(kicad_pcb
	(version 20260206)
	(generator "pcbnew")
	(generator_version "10.0")
	(general
		(thickness 1.6)
		(legacy_teardrops no)
	)
	(paper "A4")
	(layers
		(0 "F.Cu" signal "TOP")
		(4 "In1.Cu" signal "L2GND")
		(6 "In2.Cu" signal "L3")
		(8 "In3.Cu" signal "L4GND")
		(10 "In4.Cu" signal "L5")
		(12 "In5.Cu" signal "L6GND")
		(14 "In6.Cu" signal "L7VCC")
		(16 "In7.Cu" signal "L8VCC")
		(18 "In8.Cu" signal "L9GND")
		(20 "In9.Cu" signal "L10")
		(22 "In10.Cu" signal "L11GND")
		(24 "In11.Cu" signal "L12")
		(26 "In12.Cu" signal "L13GND")
		(2 "B.Cu" signal "BOTTOM")
		(9 "F.Adhes" user "F.Adhesive")
		(11 "B.Adhes" user "B.Adhesive")
		(13 "F.Paste" user "Package Geometry/Pastemask Top")
		(15 "B.Paste" user "Package Geometry/Pastemask Bottom")
		(5 "F.SilkS" user "Ref Des/Silkscreen Top")
		(7 "B.SilkS" user "Ref Des/Silkscreen Bottom")
		(1 "F.Mask" user "Board Geometry/Soldermask Top")
		(3 "B.Mask" user "Board Geometry/Soldermask Bottom")
		(17 "Dwgs.User" user "User.Drawings")
		(19 "Cmts.User" user "User.Comments")
		(21 "Eco1.User" user "User.Eco1")
		(23 "Eco2.User" user "User.Eco2")
		(25 "Edge.Cuts" user "Board Geometry/Outline")
		(27 "Margin" user)
		(31 "F.CrtYd" user "Package Geometry/Place Bound Top")
		(29 "B.CrtYd" user "Package Geometry/Place Bound Bottom")
		(35 "F.Fab" user "Ref Des/Assembly Top")
		(33 "B.Fab" user "Ref Des/Assembly Bottom")
	)
	(setup
		(pad_to_mask_clearance 0)
		(allow_soldermask_bridges_in_footprints no)
		(tenting
			(front yes)
			(back yes)
		)
		(covering
			(front no)
			(back no)
		)
		(plugging
			(front no)
			(back no)
		)
		(capping no)
		(filling no)
		(pcbplotparams
			(layerselection 0x00000000_00000000_55555555_5755f5ff)
			(plot_on_all_layers_selection 0x00000000_00000000_00000000_00000000)
			(disableapertmacros no)
			(usegerberextensions no)
			(usegerberattributes yes)
			(usegerberadvancedattributes yes)
			(creategerberjobfile yes)
			(dashed_line_dash_ratio 12)
			(dashed_line_gap_ratio 3)
			(svgprecision 4)
			(plotframeref no)
			(mode 1)
			(useauxorigin no)
			(pdf_front_fp_property_popups yes)
			(pdf_back_fp_property_popups yes)
			(pdf_metadata yes)
			(pdf_single_document no)
			(dxfpolygonmode yes)
			(dxfimperialunits yes)
			(dxfusepcbnewfont yes)
			(psnegative no)
			(psa4output no)
			(plot_black_and_white yes)
			(sketchpadsonfab no)
			(plotpadnumbers no)
			(hidednponfab no)
			(sketchdnponfab yes)
			(crossoutdnponfab yes)
			(subtractmaskfromsilk no)
			(outputformat 1)
			(mirror no)
			(drillshape 1)
			(scaleselection 1)
			(outputdirectory "")
		)
	)
	(footprint ""
		(layer "F.Cu")
		(at 22.225 -70.866)
		(property "Reference" "R1D43"
			(at 0 0 0)
			(layer "F.SilkS")
			(hide yes)
			(effects
				(font
					(size 1.27 1.27)
				)
			)
		)
		(property "Value" ""
			(at 0 0 0)
			(layer "F.Fab")
			(effects
				(font
					(size 1.27 1.27)
				)
			)
		)
		(duplicate_pad_numbers_are_jumpers no)
		(fp_poly
			(pts
				(xy -0.2794 -0.1016) (xy 0.2794 -0.1016) (xy 0.2794 0.9906) (xy -0.2794 0.9906)
			)
			(stroke
				(width 0)
				(type default)
			)
			(fill no)
			(layer "F.CrtYd")
		)
		(fp_line
			(start -0.2794 -0.1016)
			(end -0.2794 0.9906)
			(stroke
				(width 0.1)
				(type default)
			)
			(layer "F.Fab")
		)
		(fp_line
			(start -0.2794 0.9906)
			(end 0.2794 0.9906)
			(stroke
				(width 0.1)
				(type default)
			)
			(layer "F.Fab")
		)
		(fp_line
			(start 0.2794 -0.1016)
			(end -0.2794 -0.1016)
			(stroke
				(width 0.1)
				(type default)
			)
			(layer "F.Fab")
		)
		(fp_line
			(start 0.2794 0.9906)
			(end 0.2794 -0.1016)
			(stroke
				(width 0.1)
				(type default)
			)
			(layer "F.Fab")
		)
		(pad "1" smd rect
			(at 0 0)
			(size 0.508 0.508)
			(layers "F.Cu" "F.Mask" "F.Paste")
			(net "A_HSC_OV")
		)
		(pad "2" smd rect
			(at 0 0.889)
			(size 0.508 0.508)
			(layers "F.Cu" "F.Mask" "F.Paste")
			(net "AGND_HSC")
		)
		(zone
			(layer "F.Cu")
			(hatch none 0.5)
			(connect_pads
				(clearance 0)
			)
			(min_thickness 0.25)
			(keepout
				(tracks allowed)
				(vias not_allowed)
				(pads allowed)
				(copperpour not_allowed)
				(footprints allowed)
			)
			(placement
				(enabled no)
				(sheetname "")
			)
			(fill
				(thermal_gap 0.5)
				(thermal_bridge_width 0.5)
				(island_removal_mode 0)
			)
			(polygon
				(pts
					(xy 21.971 -70.612) (xy 22.479 -70.612) (xy 22.479 -70.231) (xy 21.971 -70.231)
				)
			)
		)
		(zone
			(layer "F.Cu")
			(hatch none 0.5)
			(connect_pads
				(clearance 0)
			)
			(min_thickness 0.25)
			(keepout
				(tracks not_allowed)
				(vias allowed)
				(pads allowed)
				(copperpour not_allowed)
				(footprints allowed)
			)
			(placement
				(enabled no)
				(sheetname "")
			)
			(fill
				(thermal_gap 0.5)
				(thermal_bridge_width 0.5)
				(island_removal_mode 0)
			)
			(polygon
				(pts
					(xy 21.971 -70.231) (xy 22.479 -70.231) (xy 22.479 -70.612) (xy 21.971 -70.612)
				)
			)
		)
	)
	(footprint ""
		(layer "F.Cu")
		(at 471.513916 -24.49322)
		(property "Reference" "EU8E1"
			(at -0.508 -1.49733 0)
			(unlocked yes)
			(layer "F.SilkS")
			(effects
				(font
					(size 0.7874 0.5842)
					(thickness 0.1524)
				)
			)
		)
		(property "Value" ""
			(at 0 0 0)
			(layer "F.Fab")
			(effects
				(font
					(size 1.27 1.27)
				)
			)
		)
		(duplicate_pad_numbers_are_jumpers no)
		(fp_line
			(start -0.747014 -0.78994)
			(end 2.853182 -0.78994)
			(stroke
				(width 0.1524)
				(type default)
			)
			(layer "F.SilkS")
		)
		(fp_line
			(start -0.747014 3.301492)
			(end -0.747014 -0.78994)
			(stroke
				(width 0.1524)
				(type default)
			)
			(layer "F.SilkS")
		)
		(fp_line
			(start 2.853182 -0.78994)
			(end 2.853182 3.301492)
			(stroke
				(width 0.1524)
				(type default)
			)
			(layer "F.SilkS")
		)
		(fp_circle
			(center -1.238504 -0.803148)
			(end -1.111504 -0.803148)
			(stroke
				(width 0.254)
				(type default)
			)
			(fill no)
			(layer "F.SilkS")
		)
		(fp_poly
			(pts
				(xy -0.747014 -0.78994) (xy -0.747014 4.310126) (xy 2.853182 4.310126) (xy 2.853182 -0.78994)
			)
			(stroke
				(width 0)
				(type default)
			)
			(fill no)
			(layer "F.CrtYd")
		)
		(fp_line
			(start -0.747014 -0.78994)
			(end 2.853182 -0.78994)
			(stroke
				(width 0.1)
				(type default)
			)
			(layer "F.Fab")
		)
		(fp_line
			(start -0.747014 4.310126)
			(end -0.747014 -0.78994)
			(stroke
				(width 0.1)
				(type default)
			)
			(layer "F.Fab")
		)
		(fp_line
			(start 2.853182 -0.78994)
			(end 2.853182 4.310126)
			(stroke
				(width 0.1)
				(type default)
			)
			(layer "F.Fab")
		)
		(fp_line
			(start 2.853182 4.310126)
			(end -0.747014 4.310126)
			(stroke
				(width 0.1)
				(type default)
			)
			(layer "F.Fab")
		)
		(fp_circle
			(center -1.238504 -0.803148)
			(end -1.111504 -0.803148)
			(stroke
				(width 0.254)
				(type default)
			)
			(fill no)
			(layer "F.Fab")
		)
		(pad "1" smd rect
			(at 0 0)
			(size 0.3302 0.3302)
			(layers "F.Cu" "F.Mask" "F.Paste")
			(net "VR_P3V3_STBY_UGATE")
		)
		(pad "2" smd rect
			(at 1.366774 0.002032)
			(size 1.8034 0.508)
			(layers "F.Cu" "F.Mask" "F.Paste")
			(net "VR_FET_SW_P12V_STBY_P3V3_STBY")
		)
		(pad "3" smd custom
			(at 1.053084 2.19202)
			(size 0.56515 0.56515)
			(layers "F.Cu" "F.Mask" "F.Paste")
			(net "GND")
			(options
				(clearance outline)
				(anchor circle)
			)
			(primitives
				(gr_poly
					(pts
						(xy -1.2065 0.3937) (xy -1.2065 -1.1303) (xy 1.2065 -1.1303) (xy 1.2065 1.1303) (xy -0.5969 1.1303)
						(xy -0.5969 0.3937)
					)
					(width 0)
					(fill yes)
				)
			)
		)
		(pad "4" smd rect
			(at 0 3.047238)
			(size 0.3302 0.3302)
			(layers "F.Cu" "F.Mask" "F.Paste")
			(net "VR_P3V3_STBY_LGATE")
		)
		(pad "5" smd rect
			(at 1.053084 4.02463)
			(size 3.5052 0.508)
			(layers "F.Cu" "F.Mask" "F.Paste")
			(net "VR_P3V3_STBY_PHASE")
		)
	)
	(footprint ""
		(layer "F.Cu")
		(at 449.69938 -34.7345 90)
		(property "Reference" "R25W9"
			(at 0 0 90)
			(layer "F.SilkS")
			(hide yes)
			(effects
				(font
					(size 1.27 1.27)
				)
			)
		)
		(property "Value" "*"
			(at 0.064008 -4.108196 90)
			(unlocked yes)
			(layer "F.Fab")
			(hide yes)
			(effects
				(font
					(size 1.27 1.016)
					(thickness 0.1524)
				)
			)
		)
		(property "Device Type" "120R2F-GP_RCL_GP-120R2F-GP,64.A"
			(at 0.064008 -5.632196 90)
			(unlocked yes)
			(layer "F.Fab")
			(hide yes)
			(effects
				(font
					(size 1.27 1.016)
					(thickness 0.1524)
				)
			)
		)
		(duplicate_pad_numbers_are_jumpers no)
		(fp_line
			(start 0.508 -0.9398)
			(end -0.508 -0.9398)
			(stroke
				(width 0.1524)
				(type default)
			)
			(layer "F.SilkS")
		)
		(fp_line
			(start -0.508 -0.9398)
			(end -0.508 0.9398)
			(stroke
				(width 0.1524)
				(type default)
			)
			(layer "F.SilkS")
		)
		(fp_rect
			(start -0.508 0.9398)
			(end 0.508 -0.9398)
			(stroke
				(width 0)
				(type default)
			)
			(fill no)
			(layer "F.CrtYd")
		)
		(fp_rect
			(start -0.508 0.9398)
			(end 0.508 -0.9398)
			(stroke
				(width 0)
				(type default)
			)
			(fill no)
			(layer "F.Fab")
		)
		(pad "1" smd custom
			(at 0 -0.4445 90)
			(size 0.1397 0.1397)
			(layers "F.Cu" "F.Mask" "F.Paste")
			(net "GND")
			(options
				(clearance outline)
				(anchor circle)
			)
			(primitives
				(gr_poly
					(pts
						(arc
							(start -0.1778 -0.2794)
							(mid -0.249642 -0.249642)
							(end -0.2794 -0.1778)
						)
						(arc
							(start -0.2794 0.1778)
							(mid -0.249642 0.249642)
							(end -0.1778 0.2794)
						)
						(arc
							(start 0.1778 0.2794)
							(mid 0.249642 0.249642)
							(end 0.2794 0.1778)
						)
						(arc
							(start 0.2794 -0.1778)
							(mid 0.249642 -0.249642)
							(end 0.1778 -0.2794)
						)
					)
					(width 0)
					(fill yes)
				)
			)
		)
		(pad "2" smd custom
			(at 0 0.4445 90)
			(size 0.1397 0.1397)
			(layers "F.Cu" "F.Mask" "F.Paste")
			(net "BMC_M_BA0")
			(options
				(clearance outline)
				(anchor circle)
			)
			(primitives
				(gr_poly
					(pts
						(arc
							(start -0.1778 -0.2794)
							(mid -0.249642 -0.249642)
							(end -0.2794 -0.1778)
						)
						(arc
							(start -0.2794 0.1778)
							(mid -0.249642 0.249642)
							(end -0.1778 0.2794)
						)
						(arc
							(start 0.1778 0.2794)
							(mid 0.249642 0.249642)
							(end 0.2794 0.1778)
						)
						(arc
							(start 0.2794 -0.1778)
							(mid 0.249642 -0.249642)
							(end 0.1778 -0.2794)
						)
					)
					(width 0)
					(fill yes)
				)
			)
		)
	)
	(footprint ""
		(layer "F.Cu")
		(at 265.901424 -68.412614 180)
		(property "Reference" "C5D56"
			(at 0 0 180)
			(layer "F.SilkS")
			(hide yes)
			(effects
				(font
					(size 1.27 1.27)
				)
			)
		)
		(property "Value" ""
			(at 0 0 180)
			(layer "F.Fab")
			(effects
				(font
					(size 1.27 1.27)
				)
			)
		)
		(duplicate_pad_numbers_are_jumpers no)
		(fp_poly
			(pts
				(xy -0.4953 -0.2032) (xy 0.4953 -0.2032) (xy 0.4953 1.6002) (xy -0.4953 1.6002)
			)
			(stroke
				(width 0)
				(type default)
			)
			(fill no)
			(layer "F.CrtYd")
		)
		(fp_line
			(start 0.4953 1.6002)
			(end -0.4953 1.6002)
			(stroke
				(width 0.1)
				(type default)
			)
			(layer "F.Fab")
		)
		(fp_line
			(start 0.4953 -0.2032)
			(end 0.4953 1.6002)
			(stroke
				(width 0.1)
				(type default)
			)
			(layer "F.Fab")
		)
		(fp_line
			(start -0.4953 1.6002)
			(end -0.4953 -0.2032)
			(stroke
				(width 0.1)
				(type default)
			)
			(layer "F.Fab")
		)
		(fp_line
			(start -0.4953 -0.2032)
			(end 0.4953 -0.2032)
			(stroke
				(width 0.1)
				(type default)
			)
			(layer "F.Fab")
		)
		(pad "1" smd rect
			(at 0 0 180)
			(size 0.762 0.889)
			(layers "F.Cu" "F.Mask" "F.Paste")
			(net "PVDDQ_ABC")
		)
		(pad "2" smd rect
			(at 0 1.397 180)
			(size 0.762 0.889)
			(layers "F.Cu" "F.Mask" "F.Paste")
			(net "GND")
		)
		(zone
			(layer "F.Cu")
			(hatch none 0.5)
			(connect_pads
				(clearance 0)
			)
			(min_thickness 0.25)
			(keepout
				(tracks not_allowed)
				(vias allowed)
				(pads allowed)
				(copperpour not_allowed)
				(footprints allowed)
			)
			(placement
				(enabled no)
				(sheetname "")
			)
			(fill
				(thermal_gap 0.5)
				(thermal_bridge_width 0.5)
				(island_removal_mode 0)
			)
			(polygon
				(pts
					(xy 266.282424 -68.857114) (xy 265.520424 -68.857114) (xy 265.520424 -69.365114) (xy 266.282424 -69.365114)
				)
			)
		)
	)
	(footprint ""
		(layer "F.Cu")
		(at 408.728926 -115.521486 -90)
		(property "Reference" "R8B23"
			(at 0 0 270)
			(layer "F.SilkS")
			(hide yes)
			(effects
				(font
					(size 1.27 1.27)
				)
			)
		)
		(property "Value" ""
			(at 0 0 270)
			(layer "F.Fab")
			(effects
				(font
					(size 1.27 1.27)
				)
			)
		)
		(duplicate_pad_numbers_are_jumpers no)
		(fp_poly
			(pts
				(xy -0.2794 -0.1016) (xy 0.2794 -0.1016) (xy 0.2794 0.9906) (xy -0.2794 0.9906)
			)
			(stroke
				(width 0)
				(type default)
			)
			(fill no)
			(layer "F.CrtYd")
		)
		(fp_line
			(start -0.2794 0.9906)
			(end 0.2794 0.9906)
			(stroke
				(width 0.1)
				(type default)
			)
			(layer "F.Fab")
		)
		(fp_line
			(start 0.2794 0.9906)
			(end 0.2794 -0.1016)
			(stroke
				(width 0.1)
				(type default)
			)
			(layer "F.Fab")
		)
		(fp_line
			(start -0.2794 -0.1016)
			(end -0.2794 0.9906)
			(stroke
				(width 0.1)
				(type default)
			)
			(layer "F.Fab")
		)
		(fp_line
			(start 0.2794 -0.1016)
			(end -0.2794 -0.1016)
			(stroke
				(width 0.1)
				(type default)
			)
			(layer "F.Fab")
		)
		(pad "1" smd rect
			(at 0 0 270)
			(size 0.508 0.508)
			(layers "F.Cu" "F.Mask" "F.Paste")
			(net "P3V3_STBY")
		)
		(pad "2" smd rect
			(at 0 0.889 270)
			(size 0.508 0.508)
			(layers "F.Cu" "F.Mask" "F.Paste")
			(net "FM_XRC_PRESENT_N")
		)
		(zone
			(layer "F.Cu")
			(hatch none 0.5)
			(connect_pads
				(clearance 0)
			)
			(min_thickness 0.25)
			(keepout
				(tracks not_allowed)
				(vias allowed)
				(pads allowed)
				(copperpour not_allowed)
				(footprints allowed)
			)
			(placement
				(enabled no)
				(sheetname "")
			)
			(fill
				(thermal_gap 0.5)
				(thermal_bridge_width 0.5)
				(island_removal_mode 0)
			)
			(polygon
				(pts
					(xy 408.093926 -115.775486) (xy 408.093926 -115.267486) (xy 408.474926 -115.267486) (xy 408.474926 -115.775486)
				)
			)
		)
		(zone
			(layer "F.Cu")
			(hatch none 0.5)
			(connect_pads
				(clearance 0)
			)
			(min_thickness 0.25)
			(keepout
				(tracks allowed)
				(vias not_allowed)
				(pads allowed)
				(copperpour not_allowed)
				(footprints allowed)
			)
			(placement
				(enabled no)
				(sheetname "")
			)
			(fill
				(thermal_gap 0.5)
				(thermal_bridge_width 0.5)
				(island_removal_mode 0)
			)
			(polygon
				(pts
					(xy 408.474926 -115.775486) (xy 408.474926 -115.267486) (xy 408.093926 -115.267486) (xy 408.093926 -115.775486)
				)
			)
		)
	)
	(footprint ""
		(layer "F.Cu")
		(at 453.898 -36.449)
		(property "Reference" "DS9E1"
			(at 0 0 0)
			(layer "F.SilkS")
			(hide yes)
			(effects
				(font
					(size 1.27 1.27)
				)
			)
		)
		(property "Value" ""
			(at 0 0 0)
			(layer "F.Fab")
			(effects
				(font
					(size 1.27 1.27)
				)
			)
		)
		(duplicate_pad_numbers_are_jumpers no)
		(fp_line
			(start -1.985772 0.486918)
			(end -1.50495 0.486918)
			(stroke
				(width 0.1524)
				(type default)
			)
			(layer "F.SilkS")
		)
		(fp_line
			(start -1.985772 1.319784)
			(end -1.024128 1.319784)
			(stroke
				(width 0.1524)
				(type default)
			)
			(layer "F.SilkS")
		)
		(fp_line
			(start -1.50495 -0.424688)
			(end -1.50495 0.486918)
			(stroke
				(width 0.1524)
				(type default)
			)
			(layer "F.SilkS")
		)
		(fp_line
			(start -1.50495 0.486918)
			(end -1.024128 0.486918)
			(stroke
				(width 0.1524)
				(type default)
			)
			(layer "F.SilkS")
		)
		(fp_line
			(start -1.50495 1.319784)
			(end -1.985772 0.486918)
			(stroke
				(width 0.1524)
				(type default)
			)
			(layer "F.SilkS")
		)
		(fp_line
			(start -1.50495 2.443226)
			(end -1.50495 1.319784)
			(stroke
				(width 0.1524)
				(type default)
			)
			(layer "F.SilkS")
		)
		(fp_line
			(start -1.024128 0.486918)
			(end -1.50495 1.319784)
			(stroke
				(width 0.1524)
				(type default)
			)
			(layer "F.SilkS")
		)
		(fp_poly
			(pts
				(xy 0.6223 2.032) (xy -0.6223 2.032) (xy -0.6223 0.0254) (xy 0.6223 0.0254)
			)
			(stroke
				(width 0)
				(type default)
			)
			(fill no)
			(layer "F.CrtYd")
		)
		(fp_line
			(start -1.985772 0.486918)
			(end -1.024128 0.486918)
			(stroke
				(width 0.1)
				(type default)
			)
			(layer "F.Fab")
		)
		(fp_line
			(start -1.985772 1.319784)
			(end -1.024128 1.319784)
			(stroke
				(width 0.1)
				(type default)
			)
			(layer "F.Fab")
		)
		(fp_line
			(start -1.50495 0.486918)
			(end -1.50495 -0.424688)
			(stroke
				(width 0.1)
				(type default)
			)
			(layer "F.Fab")
		)
		(fp_line
			(start -1.50495 1.319784)
			(end -1.985772 0.486918)
			(stroke
				(width 0.1)
				(type default)
			)
			(layer "F.Fab")
		)
		(fp_line
			(start -1.50495 1.319784)
			(end -1.50495 2.443226)
			(stroke
				(width 0.1)
				(type default)
			)
			(layer "F.Fab")
		)
		(fp_line
			(start -1.024128 0.486918)
			(end -1.50495 1.319784)
			(stroke
				(width 0.1)
				(type default)
			)
			(layer "F.Fab")
		)
		(fp_line
			(start -0.6223 0.0254)
			(end 0.6223 0.0254)
			(stroke
				(width 0.1)
				(type default)
			)
			(layer "F.Fab")
		)
		(fp_line
			(start -0.6223 2.032)
			(end -0.6223 0.0254)
			(stroke
				(width 0.1)
				(type default)
			)
			(layer "F.Fab")
		)
		(fp_line
			(start 0.6223 0.0254)
			(end 0.6223 2.032)
			(stroke
				(width 0.1)
				(type default)
			)
			(layer "F.Fab")
		)
		(fp_line
			(start 0.6223 2.032)
			(end -0.6223 2.032)
			(stroke
				(width 0.1)
				(type default)
			)
			(layer "F.Fab")
		)
		(pad "1" smd rect
			(at 0 0)
			(size 1.27 1.27)
			(layers "F.Cu" "F.Mask" "F.Paste")
			(net "FM_HEARTBEAT_LED_A")
		)
		(pad "2" smd rect
			(at 0 2.032)
			(size 1.27 1.27)
			(layers "F.Cu" "F.Mask" "F.Paste")
			(net "FM_HEARTBEAT_LED_K")
		)
		(zone
			(layer "F.Cu")
			(hatch none 0.5)
			(connect_pads
				(clearance 0)
			)
			(min_thickness 0.25)
			(keepout
				(tracks not_allowed)
				(vias allowed)
				(pads allowed)
				(copperpour not_allowed)
				(footprints allowed)
			)
			(placement
				(enabled no)
				(sheetname "")
			)
			(fill
				(thermal_gap 0.5)
				(thermal_bridge_width 0.5)
				(island_removal_mode 0)
			)
			(polygon
				(pts
					(xy 453.263 -35.052) (xy 454.533 -35.052) (xy 454.533 -35.814) (xy 453.263 -35.814)
				)
			)
		)
		(zone
			(layer "F.Cu")
			(hatch none 0.5)
			(connect_pads
				(clearance 0)
			)
			(min_thickness 0.25)
			(keepout
				(tracks allowed)
				(vias not_allowed)
				(pads allowed)
				(copperpour not_allowed)
				(footprints allowed)
			)
			(placement
				(enabled no)
				(sheetname "")
			)
			(fill
				(thermal_gap 0.5)
				(thermal_bridge_width 0.5)
				(island_removal_mode 0)
			)
			(polygon
				(pts
					(xy 453.263 -35.052) (xy 454.533 -35.052) (xy 454.533 -35.814) (xy 453.263 -35.814)
				)
			)
		)
	)
	(footprint ""
		(layer "F.Cu")
		(at 25.02916 -90.05824 180)
		(property "Reference" "CF9"
			(at 0 0 180)
			(layer "F.SilkS")
			(hide yes)
			(effects
				(font
					(size 1.27 1.27)
				)
			)
		)
		(property "Value" "*"
			(at 1.1811 -2.8194 180)
			(unlocked yes)
			(layer "F.Fab")
			(hide yes)
			(effects
				(font
					(size 1.27 1.016)
					(thickness 0.1524)
				)
			)
		)
		(property "Device Type" "SC22P50V2JN-4GP_SMD-BCG-SC22P5A"
			(at 1.1811 -4.3434 180)
			(unlocked yes)
			(layer "F.Fab")
			(hide yes)
			(effects
				(font
					(size 1.27 1.016)
					(thickness 0.1524)
				)
			)
		)
		(duplicate_pad_numbers_are_jumpers no)
		(fp_rect
			(start -0.4318 0.9525)
			(end 0.4318 -0.9525)
			(stroke
				(width 0)
				(type default)
			)
			(fill no)
			(layer "F.CrtYd")
		)
		(fp_rect
			(start -0.4318 0.9525)
			(end 0.4318 -0.9525)
			(stroke
				(width 0)
				(type default)
			)
			(fill no)
			(layer "F.Fab")
		)
		(pad "1" smd custom
			(at 0 -0.4445 180)
			(size 0.1524 0.1524)
			(layers "F.Cu" "F.Mask" "F.Paste")
			(net "VR_PVCCIN_CPU1_AIREF3")
			(options
				(clearance outline)
				(anchor circle)
			)
			(primitives
				(gr_poly
					(pts
						(arc
							(start 0.3048 -0.2032)
							(mid 0.275042 -0.275042)
							(end 0.2032 -0.3048)
						)
						(arc
							(start -0.2032 -0.3048)
							(mid -0.275042 -0.275042)
							(end -0.3048 -0.2032)
						)
						(arc
							(start -0.3048 0.2032)
							(mid -0.275042 0.275042)
							(end -0.2032 0.3048)
						)
						(arc
							(start 0.2032 0.3048)
							(mid 0.275042 0.275042)
							(end 0.3048 0.2032)
						)
					)
					(width 0)
					(fill yes)
				)
			)
		)
		(pad "2" smd custom
			(at 0 0.4445 180)
			(size 0.1524 0.1524)
			(layers "F.Cu" "F.Mask" "F.Paste")
			(net "ISENSE_PVCCIN_CPU1_PH3_IMON")
			(options
				(clearance outline)
				(anchor circle)
			)
			(primitives
				(gr_poly
					(pts
						(arc
							(start 0.3048 -0.2032)
							(mid 0.275042 -0.275042)
							(end 0.2032 -0.3048)
						)
						(arc
							(start -0.2032 -0.3048)
							(mid -0.275042 -0.275042)
							(end -0.3048 -0.2032)
						)
						(arc
							(start -0.3048 0.2032)
							(mid -0.275042 0.275042)
							(end -0.2032 0.3048)
						)
						(arc
							(start 0.2032 0.3048)
							(mid 0.275042 0.275042)
							(end 0.3048 0.2032)
						)
					)
					(width 0)
					(fill yes)
				)
			)
		)
	)
	(footprint ""
		(layer "F.Cu")
		(at 382.898904 -76.019406 180)
		(property "Reference" "R2T40"
			(at 0 0 180)
			(layer "F.SilkS")
			(hide yes)
			(effects
				(font
					(size 1.27 1.27)
				)
			)
		)
		(property "Value" ""
			(at 0 0 180)
			(layer "F.Fab")
			(effects
				(font
					(size 1.27 1.27)
				)
			)
		)
		(duplicate_pad_numbers_are_jumpers no)
		(fp_poly
			(pts
				(xy -0.2794 -0.1016) (xy 0.2794 -0.1016) (xy 0.2794 0.9906) (xy -0.2794 0.9906)
			)
			(stroke
				(width 0)
				(type default)
			)
			(fill no)
			(layer "F.CrtYd")
		)
		(fp_line
			(start 0.2794 0.9906)
			(end 0.2794 -0.1016)
			(stroke
				(width 0.1)
				(type default)
			)
			(layer "F.Fab")
		)
		(fp_line
			(start 0.2794 -0.1016)
			(end -0.2794 -0.1016)
			(stroke
				(width 0.1)
				(type default)
			)
			(layer "F.Fab")
		)
		(fp_line
			(start -0.2794 0.9906)
			(end 0.2794 0.9906)
			(stroke
				(width 0.1)
				(type default)
			)
			(layer "F.Fab")
		)
		(fp_line
			(start -0.2794 -0.1016)
			(end -0.2794 0.9906)
			(stroke
				(width 0.1)
				(type default)
			)
			(layer "F.Fab")
		)
		(pad "1" smd rect
			(at 0 0 180)
			(size 0.508 0.508)
			(layers "F.Cu" "F.Mask" "F.Paste")
			(net "H_CPU0_ERR2_G_N")
		)
		(pad "2" smd rect
			(at 0 0.889 180)
			(size 0.508 0.508)
			(layers "F.Cu" "F.Mask" "F.Paste")
			(net "H_CPU_ERR2_G_R_N")
		)
		(zone
			(layer "F.Cu")
			(hatch none 0.5)
			(connect_pads
				(clearance 0)
			)
			(min_thickness 0.25)
			(keepout
				(tracks not_allowed)
				(vias allowed)
				(pads allowed)
				(copperpour not_allowed)
				(footprints allowed)
			)
			(placement
				(enabled no)
				(sheetname "")
			)
			(fill
				(thermal_gap 0.5)
				(thermal_bridge_width 0.5)
				(island_removal_mode 0)
			)
			(polygon
				(pts
					(xy 383.152904 -76.654406) (xy 382.644904 -76.654406) (xy 382.644904 -76.273406) (xy 383.152904 -76.273406)
				)
			)
		)
		(zone
			(layer "F.Cu")
			(hatch none 0.5)
			(connect_pads
				(clearance 0)
			)
			(min_thickness 0.25)
			(keepout
				(tracks allowed)
				(vias not_allowed)
				(pads allowed)
				(copperpour not_allowed)
				(footprints allowed)
			)
			(placement
				(enabled no)
				(sheetname "")
			)
			(fill
				(thermal_gap 0.5)
				(thermal_bridge_width 0.5)
				(island_removal_mode 0)
			)
			(polygon
				(pts
					(xy 383.152904 -76.273406) (xy 382.644904 -76.273406) (xy 382.644904 -76.654406) (xy 383.152904 -76.654406)
				)
			)
		)
	)
	(footprint ""
		(layer "F.Cu")
		(at 401.752816 -147.928584 90)
		(property "Reference" "EU8A2"
			(at 0.228346 -5.106416 0)
			(unlocked yes)
			(layer "F.SilkS")
			(effects
				(font
					(size 0.7874 0.5842)
					(thickness 0.1524)
				)
				(justify left)
			)
		)
		(property "Value" ""
			(at 0 0 90)
			(layer "F.Fab")
			(effects
				(font
					(size 1.27 1.27)
				)
			)
		)
		(duplicate_pad_numbers_are_jumpers no)
		(fp_circle
			(center -0.835152 -0.417322)
			(end -0.835152 -0.290576)
			(stroke
				(width 0.254)
				(type default)
			)
			(fill no)
			(layer "F.SilkS")
		)
		(fp_poly
			(pts
				(xy -0.064516 -1.0922) (xy -0.064516 -0.3302) (xy 0.697484 -1.0922)
			)
			(stroke
				(width 0)
				(type default)
			)
			(fill yes)
			(layer "F.SilkS")
		)
		(fp_rect
			(start 0.597408 2.295398)
			(end 2.273808 -0.295402)
			(stroke
				(width 0)
				(type default)
			)
			(fill yes)
			(layer "F.Paste")
		)
		(fp_rect
			(start -0.064516 2.500122)
			(end 2.935478 -0.500126)
			(stroke
				(width 0)
				(type default)
			)
			(fill no)
			(layer "F.CrtYd")
		)
		(fp_line
			(start 2.935478 -0.500126)
			(end 2.935478 2.500122)
			(stroke
				(width 0.1)
				(type default)
			)
			(layer "F.Fab")
		)
		(fp_line
			(start -0.064516 -0.500126)
			(end 2.935478 -0.500126)
			(stroke
				(width 0.1)
				(type default)
			)
			(layer "F.Fab")
		)
		(fp_line
			(start 2.935478 2.500122)
			(end -0.064516 2.500122)
			(stroke
				(width 0.1)
				(type default)
			)
			(layer "F.Fab")
		)
		(fp_line
			(start -0.064516 2.500122)
			(end -0.064516 -0.500126)
			(stroke
				(width 0.1)
				(type default)
			)
			(layer "F.Fab")
		)
		(fp_circle
			(center -0.835152 -0.417322)
			(end -0.835152 -0.290576)
			(stroke
				(width 0.254)
				(type default)
			)
			(fill no)
			(layer "F.Fab")
		)
		(pad "1" smd rect
			(at 0 0 90)
			(size 0.6858 0.3048)
			(layers "F.Cu" "F.Mask" "F.Paste")
			(net "P1V8_PCH_STBY")
		)
		(pad "2" smd rect
			(at 0 0.500126 90)
			(size 0.6858 0.3048)
			(layers "F.Cu" "F.Mask" "F.Paste")
			(net "P1V8_PCH_STBY")
		)
		(pad "3" smd rect
			(at 0 0.999998 90)
			(size 0.6858 0.3048)
			(layers "F.Cu" "F.Mask" "F.Paste")
			(net "P1V8_PCH_STBY")
		)
		(pad "4" smd rect
			(at 0 1.500124 90)
			(size 0.6858 0.3048)
			(layers "F.Cu" "F.Mask" "F.Paste")
			(net "VR_P1V8_PCH_STBY_FB")
		)
		(pad "5" smd rect
			(at 0 1.999996 90)
			(size 0.6858 0.3048)
			(layers "F.Cu" "F.Mask" "F.Paste")
			(net "PWRGD_P1V8_PCH_STBY_R")
		)
		(pad "6" smd rect
			(at 2.871216 1.999996 90)
			(size 0.6858 0.3048)
			(layers "F.Cu" "F.Mask" "F.Paste")
			(net "PWRGD_P3V3_STBY")
		)
		(pad "7" smd rect
			(at 2.871216 1.500124 90)
			(size 0.6858 0.3048)
			(layers "F.Cu" "F.Mask" "F.Paste")
			(net "P3V3_STBY")
		)
		(pad "8" smd rect
			(at 2.871216 0.999998 90)
			(size 0.6858 0.3048)
			(layers "F.Cu" "F.Mask" "F.Paste")
			(net "P3V3_STBY")
		)
		(pad "9" smd rect
			(at 2.871216 0.500126 90)
			(size 0.6858 0.3048)
			(layers "F.Cu" "F.Mask" "F.Paste")
			(net "P3V3_STBY")
		)
		(pad "10" smd rect
			(at 2.871216 0 90)
			(size 0.6858 0.3048)
			(layers "F.Cu" "F.Mask" "F.Paste")
			(net "P3V3_STBY")
		)
		(pad "11" smd rect
			(at 1.435608 0.999998 90)
			(size 1.6764 2.5908)
			(layers "F.Cu" "F.Mask" "F.Paste")
			(net "GND")
		)
	)
	(footprint ""
		(layer "F.Cu")
		(at 335.292446 -129.480564)
		(property "Reference" "R7B10"
			(at 0 0 0)
			(layer "F.SilkS")
			(hide yes)
			(effects
				(font
					(size 1.27 1.27)
				)
			)
		)
		(property "Value" ""
			(at 0 0 0)
			(layer "F.Fab")
			(effects
				(font
					(size 1.27 1.27)
				)
			)
		)
		(duplicate_pad_numbers_are_jumpers no)
		(fp_poly
			(pts
				(xy -0.4953 -0.2032) (xy 0.4953 -0.2032) (xy 0.4953 1.6002) (xy -0.4953 1.6002)
			)
			(stroke
				(width 0)
				(type default)
			)
			(fill no)
			(layer "F.CrtYd")
		)
		(fp_line
			(start -0.4953 -0.2032)
			(end 0.4953 -0.2032)
			(stroke
				(width 0.1)
				(type default)
			)
			(layer "F.Fab")
		)
		(fp_line
			(start -0.4953 1.6002)
			(end -0.4953 -0.2032)
			(stroke
				(width 0.1)
				(type default)
			)
			(layer "F.Fab")
		)
		(fp_line
			(start 0.4953 -0.2032)
			(end 0.4953 1.6002)
			(stroke
				(width 0.1)
				(type default)
			)
			(layer "F.Fab")
		)
		(fp_line
			(start 0.4953 1.6002)
			(end -0.4953 1.6002)
			(stroke
				(width 0.1)
				(type default)
			)
			(layer "F.Fab")
		)
		(pad "1" smd rect
			(at 0 0)
			(size 0.762 0.889)
			(layers "F.Cu" "F.Mask" "F.Paste")
			(net "PVPP_DEF")
		)
		(pad "2" smd rect
			(at 0 1.397)
			(size 0.762 0.889)
			(layers "F.Cu" "F.Mask" "F.Paste")
			(net "GND")
		)
		(zone
			(layer "F.Cu")
			(hatch none 0.5)
			(connect_pads
				(clearance 0)
			)
			(min_thickness 0.25)
			(keepout
				(tracks not_allowed)
				(vias allowed)
				(pads allowed)
				(copperpour not_allowed)
				(footprints allowed)
			)
			(placement
				(enabled no)
				(sheetname "")
			)
			(fill
				(thermal_gap 0.5)
				(thermal_bridge_width 0.5)
				(island_removal_mode 0)
			)
			(polygon
				(pts
					(xy 334.911446 -128.528064) (xy 335.673446 -128.528064) (xy 335.673446 -129.036064) (xy 334.911446 -129.036064)
				)
			)
		)
		(zone
			(layer "F.Cu")
			(hatch none 0.5)
			(connect_pads
				(clearance 0)
			)
			(min_thickness 0.25)
			(keepout
				(tracks allowed)
				(vias not_allowed)
				(pads allowed)
				(copperpour not_allowed)
				(footprints allowed)
			)
			(placement
				(enabled no)
				(sheetname "")
			)
			(fill
				(thermal_gap 0.5)
				(thermal_bridge_width 0.5)
				(island_removal_mode 0)
			)
			(polygon
				(pts
					(xy 335.673446 -128.528064) (xy 335.673446 -129.036064) (xy 334.911446 -129.036064) (xy 334.911446 -128.528064)
				)
			)
		)
	)
	(footprint ""
		(layer "F.Cu")
		(at 490.453934 -148.717 -90)
		(property "Reference" "U9A1"
			(at -1.09855 1.85928 0)
			(unlocked yes)
			(layer "F.SilkS")
			(effects
				(font
					(size 0.7874 0.5842)
					(thickness 0.1524)
				)
				(justify left)
			)
		)
		(property "Value" ""
			(at 0 0 270)
			(layer "F.Fab")
			(effects
				(font
					(size 1.27 1.27)
				)
			)
		)
		(duplicate_pad_numbers_are_jumpers no)
		(fp_circle
			(center -0.4699 -0.8382)
			(end -0.4699 -0.9652)
			(stroke
				(width 0.254)
				(type default)
			)
			(fill no)
			(layer "F.SilkS")
		)
		(fp_poly
			(pts
				(xy 0.21463 -0.450088) (xy 1.56337 -0.450088) (xy 1.56337 1.75006) (xy 0.21463 1.75006)
			)
			(stroke
				(width 0)
				(type default)
			)
			(fill no)
			(layer "F.CrtYd")
		)
		(fp_line
			(start 0.21463 1.75006)
			(end 0.21463 -0.450088)
			(stroke
				(width 0.1)
				(type default)
			)
			(layer "F.Fab")
		)
		(fp_line
			(start 1.56337 1.75006)
			(end 0.21463 1.75006)
			(stroke
				(width 0.1)
				(type default)
			)
			(layer "F.Fab")
		)
		(fp_line
			(start 0.21463 -0.450088)
			(end 1.56337 -0.450088)
			(stroke
				(width 0.1)
				(type default)
			)
			(layer "F.Fab")
		)
		(fp_line
			(start 1.56337 -0.450088)
			(end 1.56337 1.75006)
			(stroke
				(width 0.1)
				(type default)
			)
			(layer "F.Fab")
		)
		(fp_circle
			(center -0.4699 -0.8382)
			(end -0.4699 -0.9652)
			(stroke
				(width 0.254)
				(type default)
			)
			(fill no)
			(layer "F.Fab")
		)
		(pad "1" smd rect
			(at 0 0 270)
			(size 1.016 0.381)
			(layers "F.Cu" "F.Mask" "F.Paste")
			(net "Net_6476")
		)
		(pad "2" smd rect
			(at 0 0.649986 270)
			(size 1.016 0.381)
			(layers "F.Cu" "F.Mask" "F.Paste")
			(net "SPA_5V_SIN_SW_D")
		)
		(pad "3" smd rect
			(at 0 1.299972 270)
			(size 1.016 0.381)
			(layers "F.Cu" "F.Mask" "F.Paste")
			(net "GND")
		)
		(pad "4" smd rect
			(at 1.778 1.299972 270)
			(size 1.016 0.381)
			(layers "F.Cu" "F.Mask" "F.Paste")
			(net "SPA_SIN_SW_R")
		)
		(pad "5" smd rect
			(at 1.778 0 270)
			(size 1.016 0.381)
			(layers "F.Cu" "F.Mask" "F.Paste")
			(net "P3V3_STBY")
		)
	)
	(footprint ""
		(layer "F.Cu")
		(at 318.8716 -30.585918)
		(property "Reference" "R6F6"
			(at 0 0 0)
			(layer "F.SilkS")
			(hide yes)
			(effects
				(font
					(size 1.27 1.27)
				)
			)
		)
		(property "Value" ""
			(at 0 0 0)
			(layer "F.Fab")
			(effects
				(font
					(size 1.27 1.27)
				)
			)
		)
		(duplicate_pad_numbers_are_jumpers no)
		(fp_poly
			(pts
				(xy -0.2794 -0.1016) (xy 0.2794 -0.1016) (xy 0.2794 0.9906) (xy -0.2794 0.9906)
			)
			(stroke
				(width 0)
				(type default)
			)
			(fill no)
			(layer "F.CrtYd")
		)
		(fp_line
			(start -0.2794 -0.1016)
			(end -0.2794 0.9906)
			(stroke
				(width 0.1)
				(type default)
			)
			(layer "F.Fab")
		)
		(fp_line
			(start -0.2794 0.9906)
			(end 0.2794 0.9906)
			(stroke
				(width 0.1)
				(type default)
			)
			(layer "F.Fab")
		)
		(fp_line
			(start 0.2794 -0.1016)
			(end -0.2794 -0.1016)
			(stroke
				(width 0.1)
				(type default)
			)
			(layer "F.Fab")
		)
		(fp_line
			(start 0.2794 0.9906)
			(end 0.2794 -0.1016)
			(stroke
				(width 0.1)
				(type default)
			)
			(layer "F.Fab")
		)
		(pad "1" smd rect
			(at 0 0)
			(size 0.508 0.508)
			(layers "F.Cu" "F.Mask" "F.Paste")
			(net "CLK_322M_156M_CPU0_OSC_VRM_DN")
		)
		(pad "2" smd rect
			(at 0 0.889)
			(size 0.508 0.508)
			(layers "F.Cu" "F.Mask" "F.Paste")
			(net "CLK_156M_OSC_CPU0_HFI_DN")
		)
		(zone
			(layer "F.Cu")
			(hatch none 0.5)
			(connect_pads
				(clearance 0)
			)
			(min_thickness 0.25)
			(keepout
				(tracks allowed)
				(vias not_allowed)
				(pads allowed)
				(copperpour not_allowed)
				(footprints allowed)
			)
			(placement
				(enabled no)
				(sheetname "")
			)
			(fill
				(thermal_gap 0.5)
				(thermal_bridge_width 0.5)
				(island_removal_mode 0)
			)
			(polygon
				(pts
					(xy 318.6176 -30.331918) (xy 319.1256 -30.331918) (xy 319.1256 -29.950918) (xy 318.6176 -29.950918)
				)
			)
		)
		(zone
			(layer "F.Cu")
			(hatch none 0.5)
			(connect_pads
				(clearance 0)
			)
			(min_thickness 0.25)
			(keepout
				(tracks not_allowed)
				(vias allowed)
				(pads allowed)
				(copperpour not_allowed)
				(footprints allowed)
			)
			(placement
				(enabled no)
				(sheetname "")
			)
			(fill
				(thermal_gap 0.5)
				(thermal_bridge_width 0.5)
				(island_removal_mode 0)
			)
			(polygon
				(pts
					(xy 318.6176 -29.950918) (xy 319.1256 -29.950918) (xy 319.1256 -30.331918) (xy 318.6176 -30.331918)
				)
			)
		)
	)
	(footprint ""
		(layer "F.Cu")
		(at 320.04 -130.3528 90)
		(property "Reference" "C6B2"
			(at 0 0 90)
			(layer "F.SilkS")
			(hide yes)
			(effects
				(font
					(size 1.27 1.27)
				)
			)
		)
		(property "Value" ""
			(at 0 0 90)
			(layer "F.Fab")
			(effects
				(font
					(size 1.27 1.27)
				)
			)
		)
		(duplicate_pad_numbers_are_jumpers no)
		(fp_poly
			(pts
				(xy -0.4953 -0.2032) (xy 0.4953 -0.2032) (xy 0.4953 1.6002) (xy -0.4953 1.6002)
			)
			(stroke
				(width 0)
				(type default)
			)
			(fill no)
			(layer "F.CrtYd")
		)
		(fp_line
			(start 0.4953 -0.2032)
			(end 0.4953 1.6002)
			(stroke
				(width 0.1)
				(type default)
			)
			(layer "F.Fab")
		)
		(fp_line
			(start -0.4953 -0.2032)
			(end 0.4953 -0.2032)
			(stroke
				(width 0.1)
				(type default)
			)
			(layer "F.Fab")
		)
		(fp_line
			(start 0.4953 1.6002)
			(end -0.4953 1.6002)
			(stroke
				(width 0.1)
				(type default)
			)
			(layer "F.Fab")
		)
		(fp_line
			(start -0.4953 1.6002)
			(end -0.4953 -0.2032)
			(stroke
				(width 0.1)
				(type default)
			)
			(layer "F.Fab")
		)
		(pad "1" smd rect
			(at 0 0 90)
			(size 0.762 0.889)
			(layers "F.Cu" "F.Mask" "F.Paste")
			(net "PVPP_DEF")
		)
		(pad "2" smd rect
			(at 0 1.397 90)
			(size 0.762 0.889)
			(layers "F.Cu" "F.Mask" "F.Paste")
			(net "GND")
		)
		(zone
			(layer "F.Cu")
			(hatch none 0.5)
			(connect_pads
				(clearance 0)
			)
			(min_thickness 0.25)
			(keepout
				(tracks not_allowed)
				(vias allowed)
				(pads allowed)
				(copperpour not_allowed)
				(footprints allowed)
			)
			(placement
				(enabled no)
				(sheetname "")
			)
			(fill
				(thermal_gap 0.5)
				(thermal_bridge_width 0.5)
				(island_removal_mode 0)
			)
			(polygon
				(pts
					(xy 320.4845 -129.9718) (xy 320.4845 -130.7338) (xy 320.9925 -130.7338) (xy 320.9925 -129.9718)
				)
			)
		)
	)
	(footprint ""
		(layer "F.Cu")
		(at 363.855 -140.081 90)
		(property "Reference" "R12W30"
			(at -0.8382 -0.67818 90)
			(unlocked yes)
			(layer "F.SilkS")
			(effects
				(font
					(size 0.4064 0.254)
					(thickness 0.1524)
				)
				(justify left)
			)
		)
		(property "Value" ""
			(at 0 0 90)
			(layer "F.Fab")
			(effects
				(font
					(size 1.27 1.27)
				)
			)
		)
		(duplicate_pad_numbers_are_jumpers no)
		(fp_poly
			(pts
				(xy -0.2794 -0.1016) (xy 0.2794 -0.1016) (xy 0.2794 0.9906) (xy -0.2794 0.9906)
			)
			(stroke
				(width 0)
				(type default)
			)
			(fill no)
			(layer "F.CrtYd")
		)
		(fp_line
			(start 0.2794 -0.1016)
			(end -0.2794 -0.1016)
			(stroke
				(width 0.1)
				(type default)
			)
			(layer "F.Fab")
		)
		(fp_line
			(start -0.2794 -0.1016)
			(end -0.2794 0.9906)
			(stroke
				(width 0.1)
				(type default)
			)
			(layer "F.Fab")
		)
		(fp_line
			(start 0.2794 0.9906)
			(end 0.2794 -0.1016)
			(stroke
				(width 0.1)
				(type default)
			)
			(layer "F.Fab")
		)
		(fp_line
			(start -0.2794 0.9906)
			(end 0.2794 0.9906)
			(stroke
				(width 0.1)
				(type default)
			)
			(layer "F.Fab")
		)
		(pad "1" smd rect
			(at 0 0 90)
			(size 0.508 0.508)
			(layers "F.Cu" "F.Mask" "F.Paste")
			(net "TP_PVDDQ_DEF_MP2")
		)
		(pad "2" smd rect
			(at 0 0.889 90)
			(size 0.508 0.508)
			(layers "F.Cu" "F.Mask" "F.Paste")
			(net "PWRGD_PVDDQ_DEF")
		)
		(zone
			(layer "F.Cu")
			(hatch none 0.5)
			(connect_pads
				(clearance 0)
			)
			(min_thickness 0.25)
			(keepout
				(tracks allowed)
				(vias not_allowed)
				(pads allowed)
				(copperpour not_allowed)
				(footprints allowed)
			)
			(placement
				(enabled no)
				(sheetname "")
			)
			(fill
				(thermal_gap 0.5)
				(thermal_bridge_width 0.5)
				(island_removal_mode 0)
			)
			(polygon
				(pts
					(xy 364.109 -139.827) (xy 364.109 -140.335) (xy 364.49 -140.335) (xy 364.49 -139.827)
				)
			)
		)
		(zone
			(layer "F.Cu")
			(hatch none 0.5)
			(connect_pads
				(clearance 0)
			)
			(min_thickness 0.25)
			(keepout
				(tracks not_allowed)
				(vias allowed)
				(pads allowed)
				(copperpour not_allowed)
				(footprints allowed)
			)
			(placement
				(enabled no)
				(sheetname "")
			)
			(fill
				(thermal_gap 0.5)
				(thermal_bridge_width 0.5)
				(island_removal_mode 0)
			)
			(polygon
				(pts
					(xy 364.49 -139.827) (xy 364.49 -140.335) (xy 364.109 -140.335) (xy 364.109 -139.827)
				)
			)
		)
	)
	(footprint ""
		(layer "F.Cu")
		(at 392.303 -71.0565 180)
		(property "Reference" "C7E10"
			(at 0 0 180)
			(layer "F.SilkS")
			(hide yes)
			(effects
				(font
					(size 1.27 1.27)
				)
			)
		)
		(property "Value" ""
			(at 0 0 180)
			(layer "F.Fab")
			(effects
				(font
					(size 1.27 1.27)
				)
			)
		)
		(duplicate_pad_numbers_are_jumpers no)
		(fp_poly
			(pts
				(xy 0.3048 -0.1016) (xy 0.3048 0.9906) (xy -0.3048 0.9906) (xy -0.3048 -0.1016)
			)
			(stroke
				(width 0)
				(type default)
			)
			(fill no)
			(layer "F.CrtYd")
		)
		(fp_line
			(start 0.3048 0.9906)
			(end 0.3048 -0.1016)
			(stroke
				(width 0.1)
				(type default)
			)
			(layer "F.Fab")
		)
		(fp_line
			(start 0.3048 -0.1016)
			(end -0.3048 -0.1016)
			(stroke
				(width 0.1)
				(type default)
			)
			(layer "F.Fab")
		)
		(fp_line
			(start -0.3048 0.9906)
			(end 0.3048 0.9906)
			(stroke
				(width 0.1)
				(type default)
			)
			(layer "F.Fab")
		)
		(fp_line
			(start -0.3048 -0.1016)
			(end -0.3048 0.9906)
			(stroke
				(width 0.1)
				(type default)
			)
			(layer "F.Fab")
		)
		(pad "1" smd rect
			(at 0 0 180)
			(size 0.508 0.508)
			(layers "F.Cu" "F.Mask" "F.Paste")
			(net "PWRGD_P5V_STBY_R")
		)
		(pad "2" smd rect
			(at 0 0.889 180)
			(size 0.508 0.508)
			(layers "F.Cu" "F.Mask" "F.Paste")
			(net "GND")
		)
		(zone
			(layer "F.Cu")
			(hatch none 0.5)
			(connect_pads
				(clearance 0)
			)
			(min_thickness 0.25)
			(keepout
				(tracks not_allowed)
				(vias allowed)
				(pads allowed)
				(copperpour not_allowed)
				(footprints allowed)
			)
			(placement
				(enabled no)
				(sheetname "")
			)
			(fill
				(thermal_gap 0.5)
				(thermal_bridge_width 0.5)
				(island_removal_mode 0)
			)
			(polygon
				(pts
					(xy 392.557 -71.6915) (xy 392.049 -71.6915) (xy 392.049 -71.3105) (xy 392.557 -71.3105)
				)
			)
		)
		(zone
			(layer "F.Cu")
			(hatch none 0.5)
			(connect_pads
				(clearance 0)
			)
			(min_thickness 0.25)
			(keepout
				(tracks allowed)
				(vias not_allowed)
				(pads allowed)
				(copperpour not_allowed)
				(footprints allowed)
			)
			(placement
				(enabled no)
				(sheetname "")
			)
			(fill
				(thermal_gap 0.5)
				(thermal_bridge_width 0.5)
				(island_removal_mode 0)
			)
			(polygon
				(pts
					(xy 392.557 -71.3105) (xy 392.049 -71.3105) (xy 392.049 -71.6915) (xy 392.557 -71.6915)
				)
			)
		)
	)
	(footprint ""
		(layer "F.Cu")
		(at 464.7946 -21.3233)
		(property "Reference" "R8F10"
			(at 0 0 0)
			(layer "F.SilkS")
			(hide yes)
			(effects
				(font
					(size 1.27 1.27)
				)
			)
		)
		(property "Value" ""
			(at 0 0 0)
			(layer "F.Fab")
			(effects
				(font
					(size 1.27 1.27)
				)
			)
		)
		(duplicate_pad_numbers_are_jumpers no)
		(fp_poly
			(pts
				(xy -0.2794 -0.1016) (xy 0.2794 -0.1016) (xy 0.2794 0.9906) (xy -0.2794 0.9906)
			)
			(stroke
				(width 0)
				(type default)
			)
			(fill no)
			(layer "F.CrtYd")
		)
		(fp_line
			(start -0.2794 -0.1016)
			(end -0.2794 0.9906)
			(stroke
				(width 0.1)
				(type default)
			)
			(layer "F.Fab")
		)
		(fp_line
			(start -0.2794 0.9906)
			(end 0.2794 0.9906)
			(stroke
				(width 0.1)
				(type default)
			)
			(layer "F.Fab")
		)
		(fp_line
			(start 0.2794 -0.1016)
			(end -0.2794 -0.1016)
			(stroke
				(width 0.1)
				(type default)
			)
			(layer "F.Fab")
		)
		(fp_line
			(start 0.2794 0.9906)
			(end 0.2794 -0.1016)
			(stroke
				(width 0.1)
				(type default)
			)
			(layer "F.Fab")
		)
		(pad "1" smd rect
			(at 0 0)
			(size 0.508 0.508)
			(layers "F.Cu" "F.Mask" "F.Paste")
			(net "PWRGD_P3V3_STBY_R")
		)
		(pad "2" smd rect
			(at 0 0.889)
			(size 0.508 0.508)
			(layers "F.Cu" "F.Mask" "F.Paste")
			(net "PWRGD_P3V3_STBY")
		)
		(zone
			(layer "F.Cu")
			(hatch none 0.5)
			(connect_pads
				(clearance 0)
			)
			(min_thickness 0.25)
			(keepout
				(tracks allowed)
				(vias not_allowed)
				(pads allowed)
				(copperpour not_allowed)
				(footprints allowed)
			)
			(placement
				(enabled no)
				(sheetname "")
			)
			(fill
				(thermal_gap 0.5)
				(thermal_bridge_width 0.5)
				(island_removal_mode 0)
			)
			(polygon
				(pts
					(xy 464.5406 -21.0693) (xy 465.0486 -21.0693) (xy 465.0486 -20.6883) (xy 464.5406 -20.6883)
				)
			)
		)
		(zone
			(layer "F.Cu")
			(hatch none 0.5)
			(connect_pads
				(clearance 0)
			)
			(min_thickness 0.25)
			(keepout
				(tracks not_allowed)
				(vias allowed)
				(pads allowed)
				(copperpour not_allowed)
				(footprints allowed)
			)
			(placement
				(enabled no)
				(sheetname "")
			)
			(fill
				(thermal_gap 0.5)
				(thermal_bridge_width 0.5)
				(island_removal_mode 0)
			)
			(polygon
				(pts
					(xy 464.5406 -20.6883) (xy 465.0486 -20.6883) (xy 465.0486 -21.0693) (xy 464.5406 -21.0693)
				)
			)
		)
	)
	(footprint ""
		(layer "F.Cu")
		(at 109.522768 -79.6036 180)
		(property "Reference" "C3D5"
			(at 0 0 180)
			(layer "F.SilkS")
			(hide yes)
			(effects
				(font
					(size 1.27 1.27)
				)
			)
		)
		(property "Value" ""
			(at 0 0 180)
			(layer "F.Fab")
			(effects
				(font
					(size 1.27 1.27)
				)
			)
		)
		(duplicate_pad_numbers_are_jumpers no)
		(fp_poly
			(pts
				(xy -0.4953 -0.2032) (xy 0.4953 -0.2032) (xy 0.4953 1.6002) (xy -0.4953 1.6002)
			)
			(stroke
				(width 0)
				(type default)
			)
			(fill no)
			(layer "F.CrtYd")
		)
		(fp_line
			(start 0.4953 1.6002)
			(end -0.4953 1.6002)
			(stroke
				(width 0.1)
				(type default)
			)
			(layer "F.Fab")
		)
		(fp_line
			(start 0.4953 -0.2032)
			(end 0.4953 1.6002)
			(stroke
				(width 0.1)
				(type default)
			)
			(layer "F.Fab")
		)
		(fp_line
			(start -0.4953 1.6002)
			(end -0.4953 -0.2032)
			(stroke
				(width 0.1)
				(type default)
			)
			(layer "F.Fab")
		)
		(fp_line
			(start -0.4953 -0.2032)
			(end 0.4953 -0.2032)
			(stroke
				(width 0.1)
				(type default)
			)
			(layer "F.Fab")
		)
		(pad "1" smd rect
			(at 0 0 180)
			(size 0.762 0.889)
			(layers "F.Cu" "F.Mask" "F.Paste")
			(net "PVCCMCP_CPU1")
		)
		(pad "2" smd rect
			(at 0 1.397 180)
			(size 0.762 0.889)
			(layers "F.Cu" "F.Mask" "F.Paste")
			(net "GND")
		)
		(zone
			(layer "F.Cu")
			(hatch none 0.5)
			(connect_pads
				(clearance 0)
			)
			(min_thickness 0.25)
			(keepout
				(tracks not_allowed)
				(vias allowed)
				(pads allowed)
				(copperpour not_allowed)
				(footprints allowed)
			)
			(placement
				(enabled no)
				(sheetname "")
			)
			(fill
				(thermal_gap 0.5)
				(thermal_bridge_width 0.5)
				(island_removal_mode 0)
			)
			(polygon
				(pts
					(xy 109.903768 -80.0481) (xy 109.141768 -80.0481) (xy 109.141768 -80.5561) (xy 109.903768 -80.5561)
				)
			)
		)
	)
	(footprint ""
		(layer "F.Cu")
		(at 282.030424 -71.460614 -90)
		(property "Reference" "R6D11"
			(at 0 0 270)
			(layer "F.SilkS")
			(hide yes)
			(effects
				(font
					(size 1.27 1.27)
				)
			)
		)
		(property "Value" ""
			(at 0 0 270)
			(layer "F.Fab")
			(effects
				(font
					(size 1.27 1.27)
				)
			)
		)
		(duplicate_pad_numbers_are_jumpers no)
		(fp_rect
			(start 0.2794 0.9906)
			(end -0.2794 -0.1016)
			(stroke
				(width 0)
				(type default)
			)
			(fill no)
			(layer "F.CrtYd")
		)
		(fp_line
			(start -0.2794 0.9906)
			(end 0.2794 0.9906)
			(stroke
				(width 0.1)
				(type default)
			)
			(layer "F.Fab")
		)
		(fp_line
			(start 0.2794 0.9906)
			(end 0.2794 -0.1016)
			(stroke
				(width 0.1)
				(type default)
			)
			(layer "F.Fab")
		)
		(fp_line
			(start -0.2794 -0.1016)
			(end -0.2794 0.9906)
			(stroke
				(width 0.1)
				(type default)
			)
			(layer "F.Fab")
		)
		(fp_line
			(start 0.2794 -0.1016)
			(end -0.2794 -0.1016)
			(stroke
				(width 0.1)
				(type default)
			)
			(layer "F.Fab")
		)
		(pad "1" smd rect
			(at 0 0 270)
			(size 0.508 0.508)
			(layers "F.Cu" "F.Mask" "F.Paste")
			(net "A_CPU0_UPI01_RBIAS")
		)
		(pad "2" smd rect
			(at 0 0.889 270)
			(size 0.508 0.508)
			(layers "F.Cu" "F.Mask" "F.Paste")
			(net "GND")
		)
		(zone
			(layer "F.Cu")
			(hatch none 0.5)
			(connect_pads
				(clearance 0)
			)
			(min_thickness 0.25)
			(keepout
				(tracks not_allowed)
				(vias allowed)
				(pads allowed)
				(copperpour not_allowed)
				(footprints allowed)
			)
			(placement
				(enabled no)
				(sheetname "")
			)
			(fill
				(thermal_gap 0.5)
				(thermal_bridge_width 0.5)
				(island_removal_mode 0)
			)
			(polygon
				(pts
					(xy 281.395424 -71.206614) (xy 281.776424 -71.206614) (xy 281.776424 -71.714614) (xy 281.395424 -71.714614)
				)
			)
		)
		(zone
			(layer "F.Cu")
			(hatch none 0.5)
			(connect_pads
				(clearance 0)
			)
			(min_thickness 0.25)
			(keepout
				(tracks allowed)
				(vias not_allowed)
				(pads allowed)
				(copperpour not_allowed)
				(footprints allowed)
			)
			(placement
				(enabled no)
				(sheetname "")
			)
			(fill
				(thermal_gap 0.5)
				(thermal_bridge_width 0.5)
				(island_removal_mode 0)
			)
			(polygon
				(pts
					(xy 281.395424 -71.206614) (xy 281.776424 -71.206614) (xy 281.776424 -71.714614) (xy 281.395424 -71.714614)
				)
			)
		)
	)
	(footprint ""
		(layer "F.Cu")
		(at 380.538228 -154.247596)
		(property "Reference" "C7A39"
			(at 0 0 0)
			(layer "F.SilkS")
			(hide yes)
			(effects
				(font
					(size 1.27 1.27)
				)
			)
		)
		(property "Value" ""
			(at 0 0 0)
			(layer "F.Fab")
			(effects
				(font
					(size 1.27 1.27)
				)
			)
		)
		(duplicate_pad_numbers_are_jumpers no)
		(fp_poly
			(pts
				(xy 0.3048 -0.1016) (xy 0.3048 0.9906) (xy -0.3048 0.9906) (xy -0.3048 -0.1016)
			)
			(stroke
				(width 0)
				(type default)
			)
			(fill no)
			(layer "F.CrtYd")
		)
		(fp_line
			(start -0.3048 -0.1016)
			(end -0.3048 0.9906)
			(stroke
				(width 0.1)
				(type default)
			)
			(layer "F.Fab")
		)
		(fp_line
			(start -0.3048 0.9906)
			(end 0.3048 0.9906)
			(stroke
				(width 0.1)
				(type default)
			)
			(layer "F.Fab")
		)
		(fp_line
			(start 0.3048 -0.1016)
			(end -0.3048 -0.1016)
			(stroke
				(width 0.1)
				(type default)
			)
			(layer "F.Fab")
		)
		(fp_line
			(start 0.3048 0.9906)
			(end 0.3048 -0.1016)
			(stroke
				(width 0.1)
				(type default)
			)
			(layer "F.Fab")
		)
		(pad "1" smd rect
			(at 0 0)
			(size 0.508 0.508)
			(layers "F.Cu" "F.Mask" "F.Paste")
			(net "VR_FET_SW_P12V_STBY_PVDDQ_DEF")
		)
		(pad "2" smd rect
			(at 0 0.889)
			(size 0.508 0.508)
			(layers "F.Cu" "F.Mask" "F.Paste")
			(net "GND")
		)
		(zone
			(layer "F.Cu")
			(hatch none 0.5)
			(connect_pads
				(clearance 0)
			)
			(min_thickness 0.25)
			(keepout
				(tracks allowed)
				(vias not_allowed)
				(pads allowed)
				(copperpour not_allowed)
				(footprints allowed)
			)
			(placement
				(enabled no)
				(sheetname "")
			)
			(fill
				(thermal_gap 0.5)
				(thermal_bridge_width 0.5)
				(island_removal_mode 0)
			)
			(polygon
				(pts
					(xy 380.284228 -153.993596) (xy 380.792228 -153.993596) (xy 380.792228 -153.612596) (xy 380.284228 -153.612596)
				)
			)
		)
		(zone
			(layer "F.Cu")
			(hatch none 0.5)
			(connect_pads
				(clearance 0)
			)
			(min_thickness 0.25)
			(keepout
				(tracks not_allowed)
				(vias allowed)
				(pads allowed)
				(copperpour not_allowed)
				(footprints allowed)
			)
			(placement
				(enabled no)
				(sheetname "")
			)
			(fill
				(thermal_gap 0.5)
				(thermal_bridge_width 0.5)
				(island_removal_mode 0)
			)
			(polygon
				(pts
					(xy 380.284228 -153.612596) (xy 380.792228 -153.612596) (xy 380.792228 -153.993596) (xy 380.284228 -153.993596)
				)
			)
		)
	)
	(footprint ""
		(layer "F.Cu")
		(at 266.397232 -140.208 90)
		(property "Reference" "C5A16"
			(at 1.848866 0.752348 90)
			(unlocked yes)
			(layer "F.SilkS")
			(effects
				(font
					(size 1.27 0.9652)
					(thickness 0.1524)
				)
			)
		)
		(property "Value" ""
			(at 0 0 90)
			(layer "F.Fab")
			(effects
				(font
					(size 1.27 1.27)
				)
			)
		)
		(duplicate_pad_numbers_are_jumpers no)
		(fp_rect
			(start -0.500126 1.598422)
			(end 0.500126 -0.201422)
			(stroke
				(width 0)
				(type default)
			)
			(fill no)
			(layer "F.CrtYd")
		)
		(fp_line
			(start 0.500126 -0.201422)
			(end 0.500126 1.598422)
			(stroke
				(width 0.1)
				(type default)
			)
			(layer "F.Fab")
		)
		(fp_line
			(start -0.500126 -0.201422)
			(end 0.500126 -0.201422)
			(stroke
				(width 0.1)
				(type default)
			)
			(layer "F.Fab")
		)
		(fp_line
			(start 0.500126 1.598422)
			(end -0.500126 1.598422)
			(stroke
				(width 0.1)
				(type default)
			)
			(layer "F.Fab")
		)
		(fp_line
			(start -0.500126 1.598422)
			(end -0.500126 -0.201422)
			(stroke
				(width 0.1)
				(type default)
			)
			(layer "F.Fab")
		)
		(pad "1" smd rect
			(at 0 0)
			(size 0.889 0.9906)
			(layers "F.Cu" "F.Mask" "F.Paste")
			(net "PVDDQ_DEF")
		)
		(pad "2" smd rect
			(at 0 1.397)
			(size 0.889 0.9906)
			(layers "F.Cu" "F.Mask" "F.Paste")
			(net "GND")
		)
		(zone
			(layer "F.Cu")
			(hatch none 0.5)
			(connect_pads
				(clearance 0)
			)
			(min_thickness 0.25)
			(keepout
				(tracks allowed)
				(vias not_allowed)
				(pads allowed)
				(copperpour not_allowed)
				(footprints allowed)
			)
			(placement
				(enabled no)
				(sheetname "")
			)
			(fill
				(thermal_gap 0.5)
				(thermal_bridge_width 0.5)
				(island_removal_mode 0)
			)
			(polygon
				(pts
					(xy 267.349732 -139.7127) (xy 267.349732 -140.7033) (xy 266.841732 -140.7033) (xy 266.841732 -139.7127)
				)
			)
		)
		(zone
			(layer "F.Cu")
			(hatch none 0.5)
			(connect_pads
				(clearance 0)
			)
			(min_thickness 0.25)
			(keepout
				(tracks not_allowed)
				(vias allowed)
				(pads allowed)
				(copperpour not_allowed)
				(footprints allowed)
			)
			(placement
				(enabled no)
				(sheetname "")
			)
			(fill
				(thermal_gap 0.5)
				(thermal_bridge_width 0.5)
				(island_removal_mode 0)
			)
			(polygon
				(pts
					(xy 267.349732 -139.7127) (xy 267.349732 -140.7033) (xy 266.841732 -140.7033) (xy 266.841732 -139.7127)
				)
			)
		)
	)
	(footprint ""
		(layer "F.Cu")
		(at 23.114 -79.629 -90)
		(property "Reference" "R1D27"
			(at 0 0 270)
			(layer "F.SilkS")
			(hide yes)
			(effects
				(font
					(size 1.27 1.27)
				)
			)
		)
		(property "Value" ""
			(at 0 0 270)
			(layer "F.Fab")
			(effects
				(font
					(size 1.27 1.27)
				)
			)
		)
		(duplicate_pad_numbers_are_jumpers no)
		(fp_rect
			(start -0.2794 -0.1016)
			(end 0.2794 0.9906)
			(stroke
				(width 0)
				(type default)
			)
			(fill no)
			(layer "F.CrtYd")
		)
		(fp_line
			(start -0.2794 0.9906)
			(end 0.2794 0.9906)
			(stroke
				(width 0.1)
				(type default)
			)
			(layer "F.Fab")
		)
		(fp_line
			(start 0.2794 0.9906)
			(end 0.2794 -0.1016)
			(stroke
				(width 0.1)
				(type default)
			)
			(layer "F.Fab")
		)
		(fp_line
			(start -0.2794 -0.1016)
			(end -0.2794 0.9906)
			(stroke
				(width 0.1)
				(type default)
			)
			(layer "F.Fab")
		)
		(fp_line
			(start 0.2794 -0.1016)
			(end -0.2794 -0.1016)
			(stroke
				(width 0.1)
				(type default)
			)
			(layer "F.Fab")
		)
		(pad "1" smd rect
			(at 0 0 270)
			(size 0.508 0.508)
			(layers "F.Cu" "F.Mask" "F.Paste")
			(net "A_HSC_VCAP")
		)
		(pad "2" smd rect
			(at 0 0.889 270)
			(size 0.508 0.508)
			(layers "F.Cu" "F.Mask" "F.Paste")
			(net "FM_P12V_HSC_ADR2")
		)
		(zone
			(layer "F.Cu")
			(hatch none 0.5)
			(connect_pads
				(clearance 0)
			)
			(min_thickness 0.25)
			(keepout
				(tracks not_allowed)
				(vias allowed)
				(pads allowed)
				(copperpour not_allowed)
				(footprints allowed)
			)
			(placement
				(enabled no)
				(sheetname "")
			)
			(fill
				(thermal_gap 0.5)
				(thermal_bridge_width 0.5)
				(island_removal_mode 0)
			)
			(polygon
				(pts
					(xy 22.86 -79.883) (xy 22.479 -79.883) (xy 22.479 -79.375) (xy 22.86 -79.375)
				)
			)
		)
		(zone
			(layer "F.Cu")
			(hatch none 0.5)
			(connect_pads
				(clearance 0)
			)
			(min_thickness 0.25)
			(keepout
				(tracks allowed)
				(vias not_allowed)
				(pads allowed)
				(copperpour not_allowed)
				(footprints allowed)
			)
			(placement
				(enabled no)
				(sheetname "")
			)
			(fill
				(thermal_gap 0.5)
				(thermal_bridge_width 0.5)
				(island_removal_mode 0)
			)
			(polygon
				(pts
					(xy 22.86 -79.883) (xy 22.479 -79.883) (xy 22.479 -79.375) (xy 22.86 -79.375)
				)
			)
		)
	)
	(footprint ""
		(layer "F.Cu")
		(at 339.1154 -128.3208)
		(property "Reference" "C7B9"
			(at 0 0 0)
			(layer "F.SilkS")
			(hide yes)
			(effects
				(font
					(size 1.27 1.27)
				)
			)
		)
		(property "Value" ""
			(at 0 0 0)
			(layer "F.Fab")
			(effects
				(font
					(size 1.27 1.27)
				)
			)
		)
		(duplicate_pad_numbers_are_jumpers no)
		(fp_poly
			(pts
				(xy 0.3048 -0.1016) (xy 0.3048 0.9906) (xy -0.3048 0.9906) (xy -0.3048 -0.1016)
			)
			(stroke
				(width 0)
				(type default)
			)
			(fill no)
			(layer "F.CrtYd")
		)
		(fp_line
			(start -0.3048 -0.1016)
			(end -0.3048 0.9906)
			(stroke
				(width 0.1)
				(type default)
			)
			(layer "F.Fab")
		)
		(fp_line
			(start -0.3048 0.9906)
			(end 0.3048 0.9906)
			(stroke
				(width 0.1)
				(type default)
			)
			(layer "F.Fab")
		)
		(fp_line
			(start 0.3048 -0.1016)
			(end -0.3048 -0.1016)
			(stroke
				(width 0.1)
				(type default)
			)
			(layer "F.Fab")
		)
		(fp_line
			(start 0.3048 0.9906)
			(end 0.3048 -0.1016)
			(stroke
				(width 0.1)
				(type default)
			)
			(layer "F.Fab")
		)
		(pad "1" smd rect
			(at 0 0)
			(size 0.508 0.508)
			(layers "F.Cu" "F.Mask" "F.Paste")
			(net "FM_PVPP_CPU0_EN")
		)
		(pad "2" smd rect
			(at 0 0.889)
			(size 0.508 0.508)
			(layers "F.Cu" "F.Mask" "F.Paste")
			(net "AGND_PVPP_DEF")
		)
		(zone
			(layer "F.Cu")
			(hatch none 0.5)
			(connect_pads
				(clearance 0)
			)
			(min_thickness 0.25)
			(keepout
				(tracks allowed)
				(vias not_allowed)
				(pads allowed)
				(copperpour not_allowed)
				(footprints allowed)
			)
			(placement
				(enabled no)
				(sheetname "")
			)
			(fill
				(thermal_gap 0.5)
				(thermal_bridge_width 0.5)
				(island_removal_mode 0)
			)
			(polygon
				(pts
					(xy 338.8614 -128.0668) (xy 339.3694 -128.0668) (xy 339.3694 -127.6858) (xy 338.8614 -127.6858)
				)
			)
		)
		(zone
			(layer "F.Cu")
			(hatch none 0.5)
			(connect_pads
				(clearance 0)
			)
			(min_thickness 0.25)
			(keepout
				(tracks not_allowed)
				(vias allowed)
				(pads allowed)
				(copperpour not_allowed)
				(footprints allowed)
			)
			(placement
				(enabled no)
				(sheetname "")
			)
			(fill
				(thermal_gap 0.5)
				(thermal_bridge_width 0.5)
				(island_removal_mode 0)
			)
			(polygon
				(pts
					(xy 338.8614 -127.6858) (xy 339.3694 -127.6858) (xy 339.3694 -128.0668) (xy 338.8614 -128.0668)
				)
			)
		)
	)
	(footprint ""
		(layer "F.Cu")
		(at 27.813 -3.766312)
		(property "Reference" "R1G14"
			(at 0 0 0)
			(layer "F.SilkS")
			(hide yes)
			(effects
				(font
					(size 1.27 1.27)
				)
			)
		)
		(property "Value" ""
			(at 0 0 0)
			(layer "F.Fab")
			(effects
				(font
					(size 1.27 1.27)
				)
			)
		)
		(duplicate_pad_numbers_are_jumpers no)
		(fp_poly
			(pts
				(xy -0.2794 -0.1016) (xy 0.2794 -0.1016) (xy 0.2794 0.9906) (xy -0.2794 0.9906)
			)
			(stroke
				(width 0)
				(type default)
			)
			(fill no)
			(layer "F.CrtYd")
		)
		(fp_line
			(start -0.2794 -0.1016)
			(end -0.2794 0.9906)
			(stroke
				(width 0.1)
				(type default)
			)
			(layer "F.Fab")
		)
		(fp_line
			(start -0.2794 0.9906)
			(end 0.2794 0.9906)
			(stroke
				(width 0.1)
				(type default)
			)
			(layer "F.Fab")
		)
		(fp_line
			(start 0.2794 -0.1016)
			(end -0.2794 -0.1016)
			(stroke
				(width 0.1)
				(type default)
			)
			(layer "F.Fab")
		)
		(fp_line
			(start 0.2794 0.9906)
			(end 0.2794 -0.1016)
			(stroke
				(width 0.1)
				(type default)
			)
			(layer "F.Fab")
		)
		(pad "1" smd rect
			(at 0 0)
			(size 0.508 0.508)
			(layers "F.Cu" "F.Mask" "F.Paste")
			(net "M_J_CPU_VREF")
		)
		(pad "2" smd rect
			(at 0 0.889)
			(size 0.508 0.508)
			(layers "F.Cu" "F.Mask" "F.Paste")
			(net "M_J_VREF")
		)
		(zone
			(layer "F.Cu")
			(hatch none 0.5)
			(connect_pads
				(clearance 0)
			)
			(min_thickness 0.25)
			(keepout
				(tracks allowed)
				(vias not_allowed)
				(pads allowed)
				(copperpour not_allowed)
				(footprints allowed)
			)
			(placement
				(enabled no)
				(sheetname "")
			)
			(fill
				(thermal_gap 0.5)
				(thermal_bridge_width 0.5)
				(island_removal_mode 0)
			)
			(polygon
				(pts
					(xy 27.559 -3.512312) (xy 28.067 -3.512312) (xy 28.067 -3.131312) (xy 27.559 -3.131312)
				)
			)
		)
		(zone
			(layer "F.Cu")
			(hatch none 0.5)
			(connect_pads
				(clearance 0)
			)
			(min_thickness 0.25)
			(keepout
				(tracks not_allowed)
				(vias allowed)
				(pads allowed)
				(copperpour not_allowed)
				(footprints allowed)
			)
			(placement
				(enabled no)
				(sheetname "")
			)
			(fill
				(thermal_gap 0.5)
				(thermal_bridge_width 0.5)
				(island_removal_mode 0)
			)
			(polygon
				(pts
					(xy 27.559 -3.131312) (xy 28.067 -3.131312) (xy 28.067 -3.512312) (xy 27.559 -3.512312)
				)
			)
		)
	)
	(footprint ""
		(layer "F.Cu")
		(at 365.506 -108.614972)
		(property "Reference" "Y7C1"
			(at -1.11633 2.794 90)
			(unlocked yes)
			(layer "F.SilkS")
			(effects
				(font
					(size 0.7874 0.5842)
					(thickness 0.1524)
				)
				(justify left)
			)
		)
		(property "Value" ""
			(at 0 0 0)
			(layer "F.Fab")
			(effects
				(font
					(size 1.27 1.27)
				)
			)
		)
		(duplicate_pad_numbers_are_jumpers no)
		(fp_circle
			(center -1.049782 -0.44323)
			(end -0.922782 -0.44323)
			(stroke
				(width 0.254)
				(type default)
			)
			(fill no)
			(layer "F.SilkS")
		)
		(fp_rect
			(start -0.499872 2.70002)
			(end 2.100072 -0.599948)
			(stroke
				(width 0)
				(type default)
			)
			(fill no)
			(layer "F.CrtYd")
		)
		(fp_line
			(start -0.499872 -0.599948)
			(end 2.100072 -0.599948)
			(stroke
				(width 0.1)
				(type default)
			)
			(layer "F.Fab")
		)
		(fp_line
			(start -0.499872 2.70002)
			(end -0.499872 -0.599948)
			(stroke
				(width 0.1)
				(type default)
			)
			(layer "F.Fab")
		)
		(fp_line
			(start 2.100072 -0.599948)
			(end 2.100072 2.70002)
			(stroke
				(width 0.1)
				(type default)
			)
			(layer "F.Fab")
		)
		(fp_line
			(start 2.100072 2.70002)
			(end -0.499872 2.70002)
			(stroke
				(width 0.1)
				(type default)
			)
			(layer "F.Fab")
		)
		(fp_circle
			(center -1.049782 -0.44323)
			(end -0.922782 -0.44323)
			(stroke
				(width 0.254)
				(type default)
			)
			(fill no)
			(layer "F.Fab")
		)
		(pad "1" smd rect
			(at 0 0)
			(size 1.0414 1.143)
			(layers "F.Cu" "F.Mask" "F.Paste")
			(net "XTAL_PCH_48M_IN")
		)
		(pad "2" smd rect
			(at 0 2.100072)
			(size 1.0414 1.143)
			(layers "F.Cu" "F.Mask" "F.Paste")
			(net "GND")
		)
		(pad "3" smd rect
			(at 1.6002 2.100072)
			(size 1.0414 1.143)
			(layers "F.Cu" "F.Mask" "F.Paste")
			(net "XTAL_PCH_48M_OUT")
		)
		(pad "4" smd rect
			(at 1.6002 0)
			(size 1.0414 1.143)
			(layers "F.Cu" "F.Mask" "F.Paste")
			(net "GND")
		)
	)
	(footprint ""
		(layer "F.Cu")
		(at -0.324612 -117.874034)
		(property "Reference" "R10W6"
			(at -0.8382 -0.67818 0)
			(unlocked yes)
			(layer "F.SilkS")
			(effects
				(font
					(size 0.4064 0.254)
					(thickness 0.1524)
				)
				(justify left)
			)
		)
		(property "Value" ""
			(at 0 0 0)
			(layer "F.Fab")
			(effects
				(font
					(size 1.27 1.27)
				)
			)
		)
		(duplicate_pad_numbers_are_jumpers no)
		(fp_poly
			(pts
				(xy -0.2794 -0.1016) (xy 0.2794 -0.1016) (xy 0.2794 0.9906) (xy -0.2794 0.9906)
			)
			(stroke
				(width 0)
				(type default)
			)
			(fill no)
			(layer "F.CrtYd")
		)
		(fp_line
			(start -0.2794 -0.1016)
			(end -0.2794 0.9906)
			(stroke
				(width 0.1)
				(type default)
			)
			(layer "F.Fab")
		)
		(fp_line
			(start -0.2794 0.9906)
			(end 0.2794 0.9906)
			(stroke
				(width 0.1)
				(type default)
			)
			(layer "F.Fab")
		)
		(fp_line
			(start 0.2794 -0.1016)
			(end -0.2794 -0.1016)
			(stroke
				(width 0.1)
				(type default)
			)
			(layer "F.Fab")
		)
		(fp_line
			(start 0.2794 0.9906)
			(end 0.2794 -0.1016)
			(stroke
				(width 0.1)
				(type default)
			)
			(layer "F.Fab")
		)
		(pad "1" smd rect
			(at 0 0)
			(size 0.508 0.508)
			(layers "F.Cu" "F.Mask" "F.Paste")
			(net "PUMP_TACH1")
		)
		(pad "2" smd rect
			(at 0 0.889)
			(size 0.508 0.508)
			(layers "F.Cu" "F.Mask" "F.Paste")
			(net "PUMP_TACH1_R")
		)
		(zone
			(layer "F.Cu")
			(hatch none 0.5)
			(connect_pads
				(clearance 0)
			)
			(min_thickness 0.25)
			(keepout
				(tracks allowed)
				(vias not_allowed)
				(pads allowed)
				(copperpour not_allowed)
				(footprints allowed)
			)
			(placement
				(enabled no)
				(sheetname "")
			)
			(fill
				(thermal_gap 0.5)
				(thermal_bridge_width 0.5)
				(island_removal_mode 0)
			)
			(polygon
				(pts
					(xy -0.578612 -117.620034) (xy -0.070612 -117.620034) (xy -0.070612 -117.239034) (xy -0.578612 -117.239034)
				)
			)
		)
		(zone
			(layer "F.Cu")
			(hatch none 0.5)
			(connect_pads
				(clearance 0)
			)
			(min_thickness 0.25)
			(keepout
				(tracks not_allowed)
				(vias allowed)
				(pads allowed)
				(copperpour not_allowed)
				(footprints allowed)
			)
			(placement
				(enabled no)
				(sheetname "")
			)
			(fill
				(thermal_gap 0.5)
				(thermal_bridge_width 0.5)
				(island_removal_mode 0)
			)
			(polygon
				(pts
					(xy -0.578612 -117.239034) (xy -0.070612 -117.239034) (xy -0.070612 -117.620034) (xy -0.578612 -117.620034)
				)
			)
		)
	)
	(footprint ""
		(layer "F.Cu")
		(at 490.524546 -153.68016 90)
		(property "Reference" "R9A5"
			(at 0 0 90)
			(layer "F.SilkS")
			(hide yes)
			(effects
				(font
					(size 1.27 1.27)
				)
			)
		)
		(property "Value" ""
			(at 0 0 90)
			(layer "F.Fab")
			(effects
				(font
					(size 1.27 1.27)
				)
			)
		)
		(duplicate_pad_numbers_are_jumpers no)
		(fp_poly
			(pts
				(xy -0.2794 -0.1016) (xy 0.2794 -0.1016) (xy 0.2794 0.9906) (xy -0.2794 0.9906)
			)
			(stroke
				(width 0)
				(type default)
			)
			(fill no)
			(layer "F.CrtYd")
		)
		(fp_line
			(start 0.2794 -0.1016)
			(end -0.2794 -0.1016)
			(stroke
				(width 0.1)
				(type default)
			)
			(layer "F.Fab")
		)
		(fp_line
			(start -0.2794 -0.1016)
			(end -0.2794 0.9906)
			(stroke
				(width 0.1)
				(type default)
			)
			(layer "F.Fab")
		)
		(fp_line
			(start 0.2794 0.9906)
			(end 0.2794 -0.1016)
			(stroke
				(width 0.1)
				(type default)
			)
			(layer "F.Fab")
		)
		(fp_line
			(start -0.2794 0.9906)
			(end 0.2794 0.9906)
			(stroke
				(width 0.1)
				(type default)
			)
			(layer "F.Fab")
		)
		(pad "1" smd rect
			(at 0 0 90)
			(size 0.508 0.508)
			(layers "F.Cu" "F.Mask" "F.Paste")
			(net "P5V_STBY")
		)
		(pad "2" smd rect
			(at 0 0.889 90)
			(size 0.508 0.508)
			(layers "F.Cu" "F.Mask" "F.Paste")
			(net "FM_UART_SWITCH_N")
		)
		(zone
			(layer "F.Cu")
			(hatch none 0.5)
			(connect_pads
				(clearance 0)
			)
			(min_thickness 0.25)
			(keepout
				(tracks allowed)
				(vias not_allowed)
				(pads allowed)
				(copperpour not_allowed)
				(footprints allowed)
			)
			(placement
				(enabled no)
				(sheetname "")
			)
			(fill
				(thermal_gap 0.5)
				(thermal_bridge_width 0.5)
				(island_removal_mode 0)
			)
			(polygon
				(pts
					(xy 490.778546 -153.42616) (xy 490.778546 -153.93416) (xy 491.159546 -153.93416) (xy 491.159546 -153.42616)
				)
			)
		)
		(zone
			(layer "F.Cu")
			(hatch none 0.5)
			(connect_pads
				(clearance 0)
			)
			(min_thickness 0.25)
			(keepout
				(tracks not_allowed)
				(vias allowed)
				(pads allowed)
				(copperpour not_allowed)
				(footprints allowed)
			)
			(placement
				(enabled no)
				(sheetname "")
			)
			(fill
				(thermal_gap 0.5)
				(thermal_bridge_width 0.5)
				(island_removal_mode 0)
			)
			(polygon
				(pts
					(xy 491.159546 -153.42616) (xy 491.159546 -153.93416) (xy 490.778546 -153.93416) (xy 490.778546 -153.42616)
				)
			)
		)
	)
	(footprint ""
		(layer "F.Cu")
		(at -3.175 -135.7122 -90)
		(property "Reference" "R1A3"
			(at 0 0 270)
			(layer "F.SilkS")
			(hide yes)
			(effects
				(font
					(size 1.27 1.27)
				)
			)
		)
		(property "Value" ""
			(at 0 0 270)
			(layer "F.Fab")
			(effects
				(font
					(size 1.27 1.27)
				)
			)
		)
		(duplicate_pad_numbers_are_jumpers no)
		(fp_poly
			(pts
				(xy -0.2794 -0.1016) (xy 0.2794 -0.1016) (xy 0.2794 0.9906) (xy -0.2794 0.9906)
			)
			(stroke
				(width 0)
				(type default)
			)
			(fill no)
			(layer "F.CrtYd")
		)
		(fp_line
			(start -0.2794 0.9906)
			(end 0.2794 0.9906)
			(stroke
				(width 0.1)
				(type default)
			)
			(layer "F.Fab")
		)
		(fp_line
			(start 0.2794 0.9906)
			(end 0.2794 -0.1016)
			(stroke
				(width 0.1)
				(type default)
			)
			(layer "F.Fab")
		)
		(fp_line
			(start -0.2794 -0.1016)
			(end -0.2794 0.9906)
			(stroke
				(width 0.1)
				(type default)
			)
			(layer "F.Fab")
		)
		(fp_line
			(start 0.2794 -0.1016)
			(end -0.2794 -0.1016)
			(stroke
				(width 0.1)
				(type default)
			)
			(layer "F.Fab")
		)
		(pad "1" smd rect
			(at 0 0 270)
			(size 0.508 0.508)
			(layers "F.Cu" "F.Mask" "F.Paste")
			(net "VR_PVDDQ_KLM_PH1_OCSET")
		)
		(pad "2" smd rect
			(at 0 0.889 270)
			(size 0.508 0.508)
			(layers "F.Cu" "F.Mask" "F.Paste")
			(net "GND")
		)
		(zone
			(layer "F.Cu")
			(hatch none 0.5)
			(connect_pads
				(clearance 0)
			)
			(min_thickness 0.25)
			(keepout
				(tracks not_allowed)
				(vias allowed)
				(pads allowed)
				(copperpour not_allowed)
				(footprints allowed)
			)
			(placement
				(enabled no)
				(sheetname "")
			)
			(fill
				(thermal_gap 0.5)
				(thermal_bridge_width 0.5)
				(island_removal_mode 0)
			)
			(polygon
				(pts
					(xy -3.81 -135.9662) (xy -3.81 -135.4582) (xy -3.429 -135.4582) (xy -3.429 -135.9662)
				)
			)
		)
		(zone
			(layer "F.Cu")
			(hatch none 0.5)
			(connect_pads
				(clearance 0)
			)
			(min_thickness 0.25)
			(keepout
				(tracks allowed)
				(vias not_allowed)
				(pads allowed)
				(copperpour not_allowed)
				(footprints allowed)
			)
			(placement
				(enabled no)
				(sheetname "")
			)
			(fill
				(thermal_gap 0.5)
				(thermal_bridge_width 0.5)
				(island_removal_mode 0)
			)
			(polygon
				(pts
					(xy -3.429 -135.9662) (xy -3.429 -135.4582) (xy -3.81 -135.4582) (xy -3.81 -135.9662)
				)
			)
		)
	)
	(footprint ""
		(layer "F.Cu")
		(at 194.804538 -53.48478)
		(property "Reference" "CT1"
			(at -0.762 2.26187 0)
			(unlocked yes)
			(layer "F.SilkS")
			(effects
				(font
					(size 0.7874 0.5842)
					(thickness 0.1524)
				)
				(justify left)
			)
		)
		(property "Value" ""
			(at 0 0 0)
			(layer "F.Fab")
			(effects
				(font
					(size 1.27 1.27)
				)
			)
		)
		(duplicate_pad_numbers_are_jumpers no)
		(fp_poly
			(pts
				(xy 0.3048 -0.1016) (xy 0.3048 0.9906) (xy -0.3048 0.9906) (xy -0.3048 -0.1016)
			)
			(stroke
				(width 0)
				(type default)
			)
			(fill no)
			(layer "F.CrtYd")
		)
		(fp_line
			(start -0.3048 -0.1016)
			(end -0.3048 0.9906)
			(stroke
				(width 0.1)
				(type default)
			)
			(layer "F.Fab")
		)
		(fp_line
			(start -0.3048 0.9906)
			(end 0.3048 0.9906)
			(stroke
				(width 0.1)
				(type default)
			)
			(layer "F.Fab")
		)
		(fp_line
			(start 0.3048 -0.1016)
			(end -0.3048 -0.1016)
			(stroke
				(width 0.1)
				(type default)
			)
			(layer "F.Fab")
		)
		(fp_line
			(start 0.3048 0.9906)
			(end 0.3048 -0.1016)
			(stroke
				(width 0.1)
				(type default)
			)
			(layer "F.Fab")
		)
		(pad "1" smd rect
			(at 0 0)
			(size 0.508 0.508)
			(layers "F.Cu" "F.Mask" "F.Paste")
			(net "VR_PVCCIN_CPU0_AIREF1")
		)
		(pad "2" smd rect
			(at 0 0.889)
			(size 0.508 0.508)
			(layers "F.Cu" "F.Mask" "F.Paste")
			(net "GND")
		)
		(zone
			(layer "F.Cu")
			(hatch none 0.5)
			(connect_pads
				(clearance 0)
			)
			(min_thickness 0.25)
			(keepout
				(tracks allowed)
				(vias not_allowed)
				(pads allowed)
				(copperpour not_allowed)
				(footprints allowed)
			)
			(placement
				(enabled no)
				(sheetname "")
			)
			(fill
				(thermal_gap 0.5)
				(thermal_bridge_width 0.5)
				(island_removal_mode 0)
			)
			(polygon
				(pts
					(xy 194.550538 -53.23078) (xy 195.058538 -53.23078) (xy 195.058538 -52.84978) (xy 194.550538 -52.84978)
				)
			)
		)
		(zone
			(layer "F.Cu")
			(hatch none 0.5)
			(connect_pads
				(clearance 0)
			)
			(min_thickness 0.25)
			(keepout
				(tracks not_allowed)
				(vias allowed)
				(pads allowed)
				(copperpour not_allowed)
				(footprints allowed)
			)
			(placement
				(enabled no)
				(sheetname "")
			)
			(fill
				(thermal_gap 0.5)
				(thermal_bridge_width 0.5)
				(island_removal_mode 0)
			)
			(polygon
				(pts
					(xy 194.550538 -52.84978) (xy 195.058538 -52.84978) (xy 195.058538 -53.23078) (xy 194.550538 -53.23078)
				)
			)
		)
	)
	(footprint ""
		(layer "F.Cu")
		(at 337.947 -17.272 90)
		(property "Reference" "R7G24"
			(at 0 0 90)
			(layer "F.SilkS")
			(hide yes)
			(effects
				(font
					(size 1.27 1.27)
				)
			)
		)
		(property "Value" ""
			(at 0 0 90)
			(layer "F.Fab")
			(effects
				(font
					(size 1.27 1.27)
				)
			)
		)
		(duplicate_pad_numbers_are_jumpers no)
		(fp_rect
			(start -0.2794 -0.1016)
			(end 0.2794 0.9906)
			(stroke
				(width 0)
				(type default)
			)
			(fill no)
			(layer "F.CrtYd")
		)
		(fp_line
			(start 0.2794 -0.1016)
			(end -0.2794 -0.1016)
			(stroke
				(width 0.1)
				(type default)
			)
			(layer "F.Fab")
		)
		(fp_line
			(start -0.2794 -0.1016)
			(end -0.2794 0.9906)
			(stroke
				(width 0.1)
				(type default)
			)
			(layer "F.Fab")
		)
		(fp_line
			(start 0.2794 0.9906)
			(end 0.2794 -0.1016)
			(stroke
				(width 0.1)
				(type default)
			)
			(layer "F.Fab")
		)
		(fp_line
			(start -0.2794 0.9906)
			(end 0.2794 0.9906)
			(stroke
				(width 0.1)
				(type default)
			)
			(layer "F.Fab")
		)
		(pad "1" smd rect
			(at 0 0 90)
			(size 0.508 0.508)
			(layers "F.Cu" "F.Mask" "F.Paste")
			(net "SVID_CLK1_CPU0_R")
		)
		(pad "2" smd rect
			(at 0 0.889 90)
			(size 0.508 0.508)
			(layers "F.Cu" "F.Mask" "F.Paste")
			(net "SVID_CLK_PVDDQ_ABC")
		)
		(zone
			(layer "F.Cu")
			(hatch none 0.5)
			(connect_pads
				(clearance 0)
			)
			(min_thickness 0.25)
			(keepout
				(tracks not_allowed)
				(vias allowed)
				(pads allowed)
				(copperpour not_allowed)
				(footprints allowed)
			)
			(placement
				(enabled no)
				(sheetname "")
			)
			(fill
				(thermal_gap 0.5)
				(thermal_bridge_width 0.5)
				(island_removal_mode 0)
			)
			(polygon
				(pts
					(xy 338.201 -17.018) (xy 338.582 -17.018) (xy 338.582 -17.526) (xy 338.201 -17.526)
				)
			)
		)
		(zone
			(layer "F.Cu")
			(hatch none 0.5)
			(connect_pads
				(clearance 0)
			)
			(min_thickness 0.25)
			(keepout
				(tracks allowed)
				(vias not_allowed)
				(pads allowed)
				(copperpour not_allowed)
				(footprints allowed)
			)
			(placement
				(enabled no)
				(sheetname "")
			)
			(fill
				(thermal_gap 0.5)
				(thermal_bridge_width 0.5)
				(island_removal_mode 0)
			)
			(polygon
				(pts
					(xy 338.201 -17.018) (xy 338.582 -17.018) (xy 338.582 -17.526) (xy 338.201 -17.526)
				)
			)
		)
	)
	(footprint ""
		(layer "F.Cu")
		(at 163.576 -76.708 -90)
		(property "Reference" "R4D28"
			(at 0 0 270)
			(layer "F.SilkS")
			(hide yes)
			(effects
				(font
					(size 1.27 1.27)
				)
			)
		)
		(property "Value" ""
			(at 0 0 270)
			(layer "F.Fab")
			(effects
				(font
					(size 1.27 1.27)
				)
			)
		)
		(duplicate_pad_numbers_are_jumpers no)
		(fp_poly
			(pts
				(xy -0.2794 -0.1016) (xy 0.2794 -0.1016) (xy 0.2794 0.9906) (xy -0.2794 0.9906)
			)
			(stroke
				(width 0)
				(type default)
			)
			(fill no)
			(layer "F.CrtYd")
		)
		(fp_line
			(start -0.2794 0.9906)
			(end 0.2794 0.9906)
			(stroke
				(width 0.1)
				(type default)
			)
			(layer "F.Fab")
		)
		(fp_line
			(start 0.2794 0.9906)
			(end 0.2794 -0.1016)
			(stroke
				(width 0.1)
				(type default)
			)
			(layer "F.Fab")
		)
		(fp_line
			(start -0.2794 -0.1016)
			(end -0.2794 0.9906)
			(stroke
				(width 0.1)
				(type default)
			)
			(layer "F.Fab")
		)
		(fp_line
			(start 0.2794 -0.1016)
			(end -0.2794 -0.1016)
			(stroke
				(width 0.1)
				(type default)
			)
			(layer "F.Fab")
		)
		(pad "1" smd rect
			(at 0 0 270)
			(size 0.508 0.508)
			(layers "F.Cu" "F.Mask" "F.Paste")
			(net "CLK_100M_CPU1_RC_REFCLK1_R_DN")
		)
		(pad "2" smd rect
			(at 0 0.889 270)
			(size 0.508 0.508)
			(layers "F.Cu" "F.Mask" "F.Paste")
			(net "CLK_100M_CPU1_RC_REFCLK1_DN")
		)
		(zone
			(layer "F.Cu")
			(hatch none 0.5)
			(connect_pads
				(clearance 0)
			)
			(min_thickness 0.25)
			(keepout
				(tracks not_allowed)
				(vias allowed)
				(pads allowed)
				(copperpour not_allowed)
				(footprints allowed)
			)
			(placement
				(enabled no)
				(sheetname "")
			)
			(fill
				(thermal_gap 0.5)
				(thermal_bridge_width 0.5)
				(island_removal_mode 0)
			)
			(polygon
				(pts
					(xy 162.941 -76.962) (xy 162.941 -76.454) (xy 163.322 -76.454) (xy 163.322 -76.962)
				)
			)
		)
		(zone
			(layer "F.Cu")
			(hatch none 0.5)
			(connect_pads
				(clearance 0)
			)
			(min_thickness 0.25)
			(keepout
				(tracks allowed)
				(vias not_allowed)
				(pads allowed)
				(copperpour not_allowed)
				(footprints allowed)
			)
			(placement
				(enabled no)
				(sheetname "")
			)
			(fill
				(thermal_gap 0.5)
				(thermal_bridge_width 0.5)
				(island_removal_mode 0)
			)
			(polygon
				(pts
					(xy 163.322 -76.962) (xy 163.322 -76.454) (xy 162.941 -76.454) (xy 162.941 -76.962)
				)
			)
		)
	)
	(footprint ""
		(layer "F.Cu")
		(at 415.671 -23.114)
		(property "Reference" "R1U12"
			(at 0 0 0)
			(layer "F.SilkS")
			(hide yes)
			(effects
				(font
					(size 1.27 1.27)
				)
			)
		)
		(property "Value" ""
			(at 0 0 0)
			(layer "F.Fab")
			(effects
				(font
					(size 1.27 1.27)
				)
			)
		)
		(duplicate_pad_numbers_are_jumpers no)
		(fp_poly
			(pts
				(xy -0.2794 -0.1016) (xy 0.2794 -0.1016) (xy 0.2794 0.9906) (xy -0.2794 0.9906)
			)
			(stroke
				(width 0)
				(type default)
			)
			(fill no)
			(layer "F.CrtYd")
		)
		(fp_line
			(start -0.2794 -0.1016)
			(end -0.2794 0.9906)
			(stroke
				(width 0.1)
				(type default)
			)
			(layer "F.Fab")
		)
		(fp_line
			(start -0.2794 0.9906)
			(end 0.2794 0.9906)
			(stroke
				(width 0.1)
				(type default)
			)
			(layer "F.Fab")
		)
		(fp_line
			(start 0.2794 -0.1016)
			(end -0.2794 -0.1016)
			(stroke
				(width 0.1)
				(type default)
			)
			(layer "F.Fab")
		)
		(fp_line
			(start 0.2794 0.9906)
			(end 0.2794 -0.1016)
			(stroke
				(width 0.1)
				(type default)
			)
			(layer "F.Fab")
		)
		(pad "1" smd rect
			(at 0 0)
			(size 0.508 0.508)
			(layers "F.Cu" "F.Mask" "F.Paste")
			(net "SGPIO_BMC_LD_R_N")
		)
		(pad "2" smd rect
			(at 0 0.889)
			(size 0.508 0.508)
			(layers "F.Cu" "F.Mask" "F.Paste")
			(net "SGPIO_BMC_LD_N")
		)
		(zone
			(layer "F.Cu")
			(hatch none 0.5)
			(connect_pads
				(clearance 0)
			)
			(min_thickness 0.25)
			(keepout
				(tracks allowed)
				(vias not_allowed)
				(pads allowed)
				(copperpour not_allowed)
				(footprints allowed)
			)
			(placement
				(enabled no)
				(sheetname "")
			)
			(fill
				(thermal_gap 0.5)
				(thermal_bridge_width 0.5)
				(island_removal_mode 0)
			)
			(polygon
				(pts
					(xy 415.417 -22.86) (xy 415.925 -22.86) (xy 415.925 -22.479) (xy 415.417 -22.479)
				)
			)
		)
		(zone
			(layer "F.Cu")
			(hatch none 0.5)
			(connect_pads
				(clearance 0)
			)
			(min_thickness 0.25)
			(keepout
				(tracks not_allowed)
				(vias allowed)
				(pads allowed)
				(copperpour not_allowed)
				(footprints allowed)
			)
			(placement
				(enabled no)
				(sheetname "")
			)
			(fill
				(thermal_gap 0.5)
				(thermal_bridge_width 0.5)
				(island_removal_mode 0)
			)
			(polygon
				(pts
					(xy 415.417 -22.479) (xy 415.925 -22.479) (xy 415.925 -22.86) (xy 415.417 -22.86)
				)
			)
		)
	)
	(footprint ""
		(layer "F.Cu")
		(at 477.68002 -12.474194)
		(property "Reference" "R9G22"
			(at -0.8382 -0.67818 0)
			(unlocked yes)
			(layer "F.SilkS")
			(effects
				(font
					(size 0.4064 0.254)
					(thickness 0.1524)
				)
				(justify left)
			)
		)
		(property "Value" ""
			(at 0 0 0)
			(layer "F.Fab")
			(effects
				(font
					(size 1.27 1.27)
				)
			)
		)
		(duplicate_pad_numbers_are_jumpers no)
		(fp_poly
			(pts
				(xy -0.2794 -0.1016) (xy 0.2794 -0.1016) (xy 0.2794 0.9906) (xy -0.2794 0.9906)
			)
			(stroke
				(width 0)
				(type default)
			)
			(fill no)
			(layer "F.CrtYd")
		)
		(fp_line
			(start -0.2794 -0.1016)
			(end -0.2794 0.9906)
			(stroke
				(width 0.1)
				(type default)
			)
			(layer "F.Fab")
		)
		(fp_line
			(start -0.2794 0.9906)
			(end 0.2794 0.9906)
			(stroke
				(width 0.1)
				(type default)
			)
			(layer "F.Fab")
		)
		(fp_line
			(start 0.2794 -0.1016)
			(end -0.2794 -0.1016)
			(stroke
				(width 0.1)
				(type default)
			)
			(layer "F.Fab")
		)
		(fp_line
			(start 0.2794 0.9906)
			(end 0.2794 -0.1016)
			(stroke
				(width 0.1)
				(type default)
			)
			(layer "F.Fab")
		)
		(pad "1" smd rect
			(at 0 0)
			(size 0.508 0.508)
			(layers "F.Cu" "F.Mask" "F.Paste")
			(net "NIC_MDI_SPRV_RJ45_0_DN")
		)
		(pad "2" smd rect
			(at 0 0.889)
			(size 0.508 0.508)
			(layers "F.Cu" "F.Mask" "F.Paste")
			(net "NIC_MDI_SPRV_RJ45_0_R_DN")
		)
		(zone
			(layer "F.Cu")
			(hatch none 0.5)
			(connect_pads
				(clearance 0)
			)
			(min_thickness 0.25)
			(keepout
				(tracks allowed)
				(vias not_allowed)
				(pads allowed)
				(copperpour not_allowed)
				(footprints allowed)
			)
			(placement
				(enabled no)
				(sheetname "")
			)
			(fill
				(thermal_gap 0.5)
				(thermal_bridge_width 0.5)
				(island_removal_mode 0)
			)
			(polygon
				(pts
					(xy 477.42602 -12.220194) (xy 477.93402 -12.220194) (xy 477.93402 -11.839194) (xy 477.42602 -11.839194)
				)
			)
		)
		(zone
			(layer "F.Cu")
			(hatch none 0.5)
			(connect_pads
				(clearance 0)
			)
			(min_thickness 0.25)
			(keepout
				(tracks not_allowed)
				(vias allowed)
				(pads allowed)
				(copperpour not_allowed)
				(footprints allowed)
			)
			(placement
				(enabled no)
				(sheetname "")
			)
			(fill
				(thermal_gap 0.5)
				(thermal_bridge_width 0.5)
				(island_removal_mode 0)
			)
			(polygon
				(pts
					(xy 477.42602 -11.839194) (xy 477.93402 -11.839194) (xy 477.93402 -12.220194) (xy 477.42602 -12.220194)
				)
			)
		)
	)
	(footprint ""
		(layer "F.Cu")
		(at 104.5591 -12.954 90)
		(property "Reference" "C2G6"
			(at 1.848866 0.752348 90)
			(unlocked yes)
			(layer "F.SilkS")
			(effects
				(font
					(size 1.27 0.9652)
					(thickness 0.1524)
				)
			)
		)
		(property "Value" ""
			(at 0 0 90)
			(layer "F.Fab")
			(effects
				(font
					(size 1.27 1.27)
				)
			)
		)
		(duplicate_pad_numbers_are_jumpers no)
		(fp_rect
			(start -0.500126 1.598422)
			(end 0.500126 -0.201422)
			(stroke
				(width 0)
				(type default)
			)
			(fill no)
			(layer "F.CrtYd")
		)
		(fp_line
			(start 0.500126 -0.201422)
			(end 0.500126 1.598422)
			(stroke
				(width 0.1)
				(type default)
			)
			(layer "F.Fab")
		)
		(fp_line
			(start -0.500126 -0.201422)
			(end 0.500126 -0.201422)
			(stroke
				(width 0.1)
				(type default)
			)
			(layer "F.Fab")
		)
		(fp_line
			(start 0.500126 1.598422)
			(end -0.500126 1.598422)
			(stroke
				(width 0.1)
				(type default)
			)
			(layer "F.Fab")
		)
		(fp_line
			(start -0.500126 1.598422)
			(end -0.500126 -0.201422)
			(stroke
				(width 0.1)
				(type default)
			)
			(layer "F.Fab")
		)
		(pad "1" smd rect
			(at 0 0)
			(size 0.889 0.9906)
			(layers "F.Cu" "F.Mask" "F.Paste")
			(net "PVDDQ_GHJ")
		)
		(pad "2" smd rect
			(at 0 1.397)
			(size 0.889 0.9906)
			(layers "F.Cu" "F.Mask" "F.Paste")
			(net "GND")
		)
		(zone
			(layer "F.Cu")
			(hatch none 0.5)
			(connect_pads
				(clearance 0)
			)
			(min_thickness 0.25)
			(keepout
				(tracks allowed)
				(vias not_allowed)
				(pads allowed)
				(copperpour not_allowed)
				(footprints allowed)
			)
			(placement
				(enabled no)
				(sheetname "")
			)
			(fill
				(thermal_gap 0.5)
				(thermal_bridge_width 0.5)
				(island_removal_mode 0)
			)
			(polygon
				(pts
					(xy 105.5116 -12.4587) (xy 105.5116 -13.4493) (xy 105.0036 -13.4493) (xy 105.0036 -12.4587)
				)
			)
		)
		(zone
			(layer "F.Cu")
			(hatch none 0.5)
			(connect_pads
				(clearance 0)
			)
			(min_thickness 0.25)
			(keepout
				(tracks not_allowed)
				(vias allowed)
				(pads allowed)
				(copperpour not_allowed)
				(footprints allowed)
			)
			(placement
				(enabled no)
				(sheetname "")
			)
			(fill
				(thermal_gap 0.5)
				(thermal_bridge_width 0.5)
				(island_removal_mode 0)
			)
			(polygon
				(pts
					(xy 105.5116 -12.4587) (xy 105.5116 -13.4493) (xy 105.0036 -13.4493) (xy 105.0036 -12.4587)
				)
			)
		)
	)
	(footprint ""
		(layer "F.Cu")
		(at 346.9894 -19.304 180)
		(property "Reference" "C7F15"
			(at 0 0 180)
			(layer "F.SilkS")
			(hide yes)
			(effects
				(font
					(size 1.27 1.27)
				)
			)
		)
		(property "Value" ""
			(at 0 0 180)
			(layer "F.Fab")
			(effects
				(font
					(size 1.27 1.27)
				)
			)
		)
		(duplicate_pad_numbers_are_jumpers no)
		(fp_rect
			(start 0.3048 -0.1016)
			(end -0.3048 0.9906)
			(stroke
				(width 0)
				(type default)
			)
			(fill no)
			(layer "F.CrtYd")
		)
		(fp_line
			(start 0.3048 0.9906)
			(end 0.3048 -0.1016)
			(stroke
				(width 0.1)
				(type default)
			)
			(layer "F.Fab")
		)
		(fp_line
			(start 0.3048 -0.1016)
			(end -0.3048 -0.1016)
			(stroke
				(width 0.1)
				(type default)
			)
			(layer "F.Fab")
		)
		(fp_line
			(start -0.3048 0.9906)
			(end 0.3048 0.9906)
			(stroke
				(width 0.1)
				(type default)
			)
			(layer "F.Fab")
		)
		(fp_line
			(start -0.3048 -0.1016)
			(end -0.3048 0.9906)
			(stroke
				(width 0.1)
				(type default)
			)
			(layer "F.Fab")
		)
		(pad "1" smd rect
			(at 0 0 180)
			(size 0.508 0.508)
			(layers "F.Cu" "F.Mask" "F.Paste")
			(net "VR_PVDDQ_ABC_VD12")
		)
		(pad "2" smd rect
			(at 0 0.889 180)
			(size 0.508 0.508)
			(layers "F.Cu" "F.Mask" "F.Paste")
			(net "GND")
		)
		(zone
			(layer "F.Cu")
			(hatch none 0.5)
			(connect_pads
				(clearance 0)
			)
			(min_thickness 0.25)
			(keepout
				(tracks allowed)
				(vias not_allowed)
				(pads allowed)
				(copperpour not_allowed)
				(footprints allowed)
			)
			(placement
				(enabled no)
				(sheetname "")
			)
			(fill
				(thermal_gap 0.5)
				(thermal_bridge_width 0.5)
				(island_removal_mode 0)
			)
			(polygon
				(pts
					(xy 346.7354 -19.558) (xy 347.2434 -19.558) (xy 347.2434 -19.939) (xy 346.7354 -19.939)
				)
			)
		)
		(zone
			(layer "F.Cu")
			(hatch none 0.5)
			(connect_pads
				(clearance 0)
			)
			(min_thickness 0.25)
			(keepout
				(tracks not_allowed)
				(vias allowed)
				(pads allowed)
				(copperpour not_allowed)
				(footprints allowed)
			)
			(placement
				(enabled no)
				(sheetname "")
			)
			(fill
				(thermal_gap 0.5)
				(thermal_bridge_width 0.5)
				(island_removal_mode 0)
			)
			(polygon
				(pts
					(xy 346.7354 -19.558) (xy 347.2434 -19.558) (xy 347.2434 -19.939) (xy 346.7354 -19.939)
				)
			)
		)
	)
	(footprint ""
		(layer "F.Cu")
		(at 216.911936 11.952478 -90)
		(property "Reference" "T1P4"
			(at 0 0 270)
			(layer "F.SilkS")
			(hide yes)
			(effects
				(font
					(size 1.27 1.27)
				)
			)
		)
		(property "Value" "*"
			(at -3.302 1.12395 270)
			(unlocked yes)
			(layer "F.Fab")
			(hide yes)
			(effects
				(font
					(size 0.889 0.889)
					(thickness 0.1524)
				)
			)
		)
		(property "Device Type" "TPAD-DIFF-4P-GP_DISCRET-GB3-TPA"
			(at -3.302 -0.40005 270)
			(unlocked yes)
			(layer "F.Fab")
			(hide yes)
			(effects
				(font
					(size 0.889 0.889)
					(thickness 0.1524)
				)
			)
		)
		(duplicate_pad_numbers_are_jumpers no)
		(fp_line
			(start -2.286 2.286)
			(end 2.286 2.286)
			(stroke
				(width 0.1524)
				(type default)
			)
			(layer "F.SilkS")
		)
		(fp_line
			(start 2.286 2.286)
			(end 2.286 -2.286)
			(stroke
				(width 0.1524)
				(type default)
			)
			(layer "F.SilkS")
		)
		(fp_line
			(start -2.286 -2.286)
			(end -2.286 2.286)
			(stroke
				(width 0.1524)
				(type default)
			)
			(layer "F.SilkS")
		)
		(fp_line
			(start 2.286 -2.286)
			(end -2.286 -2.286)
			(stroke
				(width 0.1524)
				(type default)
			)
			(layer "F.SilkS")
		)
		(fp_line
			(start -2.413 -2.413)
			(end -2.413 -1.143)
			(stroke
				(width 0.4064)
				(type default)
			)
			(layer "F.SilkS")
		)
		(fp_line
			(start -1.143 -2.413)
			(end -2.413 -2.413)
			(stroke
				(width 0.4064)
				(type default)
			)
			(layer "F.SilkS")
		)
		(fp_rect
			(start -2.54 2.54)
			(end 2.54 -2.54)
			(stroke
				(width 0)
				(type default)
			)
			(fill no)
			(layer "F.CrtYd")
		)
		(fp_rect
			(start -2.54 2.54)
			(end 2.54 -2.54)
			(stroke
				(width 0)
				(type default)
			)
			(fill no)
			(layer "F.Fab")
		)
		(pad "1" thru_hole circle
			(at -1.27 -1.27 270)
			(size 1.524 1.524)
			(drill 0.9144)
			(layers "*.Cu" "*.Mask")
			(remove_unused_layers no)
			(net "L10_85OHM_6INCH_DP")
			(clearance -0.0508)
			(thermal_gap 0.127)
			(padstack
				(mode front_inner_back)
				(layer "Inner"
					(shape circle)
					(size 1.1684 1.1684)
					(clearance 0.127)
				)
				(layer "B.Cu"
					(shape circle)
					(size 1.524 1.524)
					(clearance -0.0508)
				)
			)
		)
		(pad "2" thru_hole circle
			(at 1.27 -1.27 270)
			(size 1.524 1.524)
			(drill 0.9144)
			(layers "*.Cu" "*.Mask")
			(remove_unused_layers no)
			(net "L10_85OHM_6INCH_DN")
			(clearance -0.0508)
			(thermal_gap 0.127)
			(padstack
				(mode front_inner_back)
				(layer "Inner"
					(shape circle)
					(size 1.1684 1.1684)
					(clearance 0.127)
				)
				(layer "B.Cu"
					(shape circle)
					(size 1.524 1.524)
					(clearance -0.0508)
				)
			)
		)
		(pad "GND1" thru_hole rect
			(at -1.27 1.27 270)
			(size 1.524 1.524)
			(drill 0.9144)
			(layers "*.Cu" "*.Mask")
			(remove_unused_layers no)
			(net "GND")
			(clearance -0.0508)
			(thermal_gap 0.127)
			(padstack
				(mode front_inner_back)
				(layer "Inner"
					(shape circle)
					(size 1.1684 1.1684)
					(clearance 0.127)
				)
				(layer "B.Cu"
					(shape rect)
					(size 1.524 1.524)
					(clearance -0.0508)
				)
			)
		)
		(pad "GND2" thru_hole rect
			(at 1.27 1.27 270)
			(size 1.524 1.524)
			(drill 0.9144)
			(layers "*.Cu" "*.Mask")
			(remove_unused_layers no)
			(net "GND")
			(clearance -0.0508)
			(thermal_gap 0.127)
			(padstack
				(mode front_inner_back)
				(layer "Inner"
					(shape circle)
					(size 1.1684 1.1684)
					(clearance 0.127)
				)
				(layer "B.Cu"
					(shape rect)
					(size 1.524 1.524)
					(clearance -0.0508)
				)
			)
		)
	)
	(footprint ""
		(layer "F.Cu")
		(at 369.477544 -10.916158)
		(property "Reference" "C7G11"
			(at 0 0 0)
			(layer "F.SilkS")
			(hide yes)
			(effects
				(font
					(size 1.27 1.27)
				)
			)
		)
		(property "Value" ""
			(at 0 0 0)
			(layer "F.Fab")
			(effects
				(font
					(size 1.27 1.27)
				)
			)
		)
		(duplicate_pad_numbers_are_jumpers no)
		(fp_rect
			(start -0.3048 0.9906)
			(end 0.3048 -0.1016)
			(stroke
				(width 0)
				(type default)
			)
			(fill no)
			(layer "F.CrtYd")
		)
		(fp_line
			(start -0.3048 -0.1016)
			(end -0.3048 0.9906)
			(stroke
				(width 0.1)
				(type default)
			)
			(layer "F.Fab")
		)
		(fp_line
			(start -0.3048 0.9906)
			(end 0.3048 0.9906)
			(stroke
				(width 0.1)
				(type default)
			)
			(layer "F.Fab")
		)
		(fp_line
			(start 0.3048 -0.1016)
			(end -0.3048 -0.1016)
			(stroke
				(width 0.1)
				(type default)
			)
			(layer "F.Fab")
		)
		(fp_line
			(start 0.3048 0.9906)
			(end 0.3048 -0.1016)
			(stroke
				(width 0.1)
				(type default)
			)
			(layer "F.Fab")
		)
		(pad "1" smd rect
			(at 0 0)
			(size 0.508 0.508)
			(layers "F.Cu" "F.Mask" "F.Paste")
			(net "P3E_CPU0_PE2_SS_TXP<12>")
		)
		(pad "2" smd rect
			(at 0 0.889)
			(size 0.508 0.508)
			(layers "F.Cu" "F.Mask" "F.Paste")
			(net "P3E_CPU0_PE2_SS_C_TXP<12>")
		)
		(zone
			(layer "F.Cu")
			(hatch none 0.5)
			(connect_pads
				(clearance 0)
			)
			(min_thickness 0.25)
			(keepout
				(tracks allowed)
				(vias not_allowed)
				(pads allowed)
				(copperpour not_allowed)
				(footprints allowed)
			)
			(placement
				(enabled no)
				(sheetname "")
			)
			(fill
				(thermal_gap 0.5)
				(thermal_bridge_width 0.5)
				(island_removal_mode 0)
			)
			(polygon
				(pts
					(xy 369.223544 -10.281158) (xy 369.731544 -10.281158) (xy 369.731544 -10.662158) (xy 369.223544 -10.662158)
				)
			)
		)
		(zone
			(layer "F.Cu")
			(hatch none 0.5)
			(connect_pads
				(clearance 0)
			)
			(min_thickness 0.25)
			(keepout
				(tracks not_allowed)
				(vias allowed)
				(pads allowed)
				(copperpour not_allowed)
				(footprints allowed)
			)
			(placement
				(enabled no)
				(sheetname "")
			)
			(fill
				(thermal_gap 0.5)
				(thermal_bridge_width 0.5)
				(island_removal_mode 0)
			)
			(polygon
				(pts
					(xy 369.223544 -10.281158) (xy 369.731544 -10.281158) (xy 369.731544 -10.662158) (xy 369.223544 -10.662158)
				)
			)
		)
	)
	(footprint ""
		(layer "F.Cu")
		(at 385.3942 -153.67)
		(property "Reference" "EU7A2"
			(at 3.98907 0.4318 90)
			(unlocked yes)
			(layer "F.SilkS")
			(effects
				(font
					(size 0.7874 0.5842)
					(thickness 0.1524)
				)
			)
		)
		(property "Value" ""
			(at 0 0 0)
			(layer "F.Fab")
			(effects
				(font
					(size 1.27 1.27)
				)
			)
		)
		(duplicate_pad_numbers_are_jumpers no)
		(fp_line
			(start -3.0099 -3.5052)
			(end 2.9718 -3.5052)
			(stroke
				(width 0.1524)
				(type default)
			)
			(layer "F.SilkS")
		)
		(fp_line
			(start -3.0099 3.429)
			(end -3.0099 -3.5052)
			(stroke
				(width 0.1524)
				(type default)
			)
			(layer "F.SilkS")
		)
		(fp_line
			(start 2.9718 -3.5052)
			(end 2.9718 3.429)
			(stroke
				(width 0.1524)
				(type default)
			)
			(layer "F.SilkS")
		)
		(fp_line
			(start 2.9718 3.429)
			(end -3.0099 3.429)
			(stroke
				(width 0.1524)
				(type default)
			)
			(layer "F.SilkS")
		)
		(fp_circle
			(center -3.057398 -2.678684)
			(end -2.930398 -2.678684)
			(stroke
				(width 0.254)
				(type default)
			)
			(fill no)
			(layer "F.SilkS")
		)
		(fp_poly
			(pts
				(xy -2.9972 -3.4925) (xy -2.9972 -2.6924) (xy -2.1971 -3.4925)
			)
			(stroke
				(width 0)
				(type default)
			)
			(fill yes)
			(layer "F.SilkS")
		)
		(fp_poly
			(pts
				(xy -2.549906 -3.050032) (xy -2.549906 3.050032) (xy 2.549906 3.050032) (xy 2.549906 -3.050032)
			)
			(stroke
				(width 0)
				(type default)
			)
			(fill no)
			(layer "F.CrtYd")
		)
		(fp_line
			(start -2.549906 -3.050032)
			(end 2.549906 -3.050032)
			(stroke
				(width 0.1)
				(type default)
			)
			(layer "F.Fab")
		)
		(fp_line
			(start -2.549906 3.050032)
			(end -2.549906 -3.050032)
			(stroke
				(width 0.1)
				(type default)
			)
			(layer "F.Fab")
		)
		(fp_line
			(start 2.549906 -3.050032)
			(end 2.549906 3.050032)
			(stroke
				(width 0.1)
				(type default)
			)
			(layer "F.Fab")
		)
		(fp_line
			(start 2.549906 3.050032)
			(end -2.549906 3.050032)
			(stroke
				(width 0.1)
				(type default)
			)
			(layer "F.Fab")
		)
		(fp_circle
			(center -3.057398 -2.678684)
			(end -2.930398 -2.678684)
			(stroke
				(width 0.254)
				(type default)
			)
			(fill no)
			(layer "F.Fab")
		)
		(pad "1" smd rect
			(at -2.39522 -2.279904)
			(size 0.7112 0.254)
			(layers "F.Cu" "F.Mask" "F.Paste")
			(net "P1V05_PCH_STBY")
		)
		(pad "2" smd rect
			(at -2.39522 -1.83007)
			(size 0.7112 0.254)
			(layers "F.Cu" "F.Mask" "F.Paste")
			(net "GND")
		)
		(pad "3" smd rect
			(at -2.39522 -1.379982)
			(size 0.7112 0.254)
			(layers "F.Cu" "F.Mask" "F.Paste")
			(net "VR_P1V05_PCH_STBY_PH1_VCIN")
		)
		(pad "4" smd rect
			(at -2.39522 -0.929894)
			(size 0.7112 0.254)
			(layers "F.Cu" "F.Mask" "F.Paste")
			(net "P5V_STBY")
		)
		(pad "5" smd rect
			(at -2.39522 -0.48006)
			(size 0.7112 0.254)
			(layers "F.Cu" "F.Mask" "F.Paste")
			(net "GND")
		)
		(pad "6" smd rect
			(at -2.39522 -0.029972)
			(size 0.7112 0.254)
			(layers "F.Cu" "F.Mask" "F.Paste")
			(net "TP_P1V05_PCH_GL_0")
		)
		(pad "7" smd custom
			(at 0.016764 1.145032)
			(size 0.53975 0.53975)
			(layers "F.Cu" "F.Mask" "F.Paste")
			(net "GND")
			(options
				(clearance outline)
				(anchor circle)
			)
			(primitives
				(gr_poly
					(pts
						(xy -2.7051 1.0795) (xy -2.7051 -0.3683) (xy -0.9271 -0.3683) (xy -0.9271 -1.0795) (xy 2.7051 -1.0795)
						(xy 2.7051 1.0795)
					)
					(width 0)
					(fill yes)
				)
			)
		)
		(pad "10" smd rect
			(at -0.008382 2.874772)
			(size 4.3434 0.6096)
			(layers "F.Cu" "F.Mask" "F.Paste")
			(net "VR_P1V05_PCH_STBY_PH1_PHASE_SW")
		)
		(pad "25" smd rect
			(at 1.548384 -1.283208)
			(size 2.3368 2.0066)
			(layers "F.Cu" "F.Mask" "F.Paste")
			(net "VR_FET_SW_P12V_STBY_PVDDQ_DEF")
		)
		(pad "30" smd rect
			(at 2.050034 -2.895092)
			(size 0.254 0.7112)
			(layers "F.Cu" "F.Mask" "F.Paste")
			(net "VR_FET_SW_P12V_STBY_PVDDQ_DEF")
		)
		(pad "31" smd rect
			(at 1.599946 -2.895092)
			(size 0.254 0.7112)
			(layers "F.Cu" "F.Mask" "F.Paste")
			(net "Net_360")
		)
		(pad "32" smd rect
			(at 1.150112 -2.895092)
			(size 0.254 0.7112)
			(layers "F.Cu" "F.Mask" "F.Paste")
			(net "VR_P1V05_PCH_STBY_PH1_PHASE")
		)
		(pad "33" smd rect
			(at 0.700024 -2.895092)
			(size 0.254 0.7112)
			(layers "F.Cu" "F.Mask" "F.Paste")
			(net "VR_P1V05_PCH_STBY_PH1_BOOT_R")
		)
		(pad "34" smd rect
			(at 0.249936 -2.895092)
			(size 0.254 0.7112)
			(layers "F.Cu" "F.Mask" "F.Paste")
			(net "VR_P1V05_PCH_STBY_PWM1")
		)
		(pad "35" smd rect
			(at -0.199898 -2.895092)
			(size 0.254 0.7112)
			(layers "F.Cu" "F.Mask" "F.Paste")
			(net "P5V_STBY")
		)
		(pad "36" smd rect
			(at -0.649986 -2.895092)
			(size 0.254 0.7112)
			(layers "F.Cu" "F.Mask" "F.Paste")
			(net "A_TSENSE_P1V05_PCH_STBY_TMON")
		)
		(pad "37" smd rect
			(at -1.100074 -2.895092)
			(size 0.254 0.7112)
			(layers "F.Cu" "F.Mask" "F.Paste")
			(net "VR_P1V05_PCH_STBY_OCSET")
		)
		(pad "38" smd rect
			(at -1.549908 -2.895092)
			(size 0.254 0.7112)
			(layers "F.Cu" "F.Mask" "F.Paste")
			(net "ISENSE_P1V05_PCH_STBY_PH1_IMON")
		)
		(pad "39" smd rect
			(at -1.999996 -2.895092)
			(size 0.254 0.7112)
			(layers "F.Cu" "F.Mask" "F.Paste")
			(net "VR_P1V05_PCH_BIREF1")
		)
		(pad "40" smd rect
			(at -0.871728 -1.283208)
			(size 1.8034 2.0066)
			(layers "F.Cu" "F.Mask" "F.Paste")
			(net "GND")
		)
		(pad "41" smd rect
			(at -1.533906 0.247904)
			(size 0.508 0.3556)
			(layers "F.Cu" "F.Mask" "F.Paste")
			(net "TP_P1V05_PCH_GL_1")
		)
	)
	(footprint ""
		(layer "F.Cu")
		(at 397.3576 -0.2286)
		(property "Reference" "R8G15"
			(at 0 0 0)
			(layer "F.SilkS")
			(hide yes)
			(effects
				(font
					(size 1.27 1.27)
				)
			)
		)
		(property "Value" ""
			(at 0 0 0)
			(layer "F.Fab")
			(effects
				(font
					(size 1.27 1.27)
				)
			)
		)
		(duplicate_pad_numbers_are_jumpers no)
		(fp_poly
			(pts
				(xy -0.2794 -0.1016) (xy 0.2794 -0.1016) (xy 0.2794 0.9906) (xy -0.2794 0.9906)
			)
			(stroke
				(width 0)
				(type default)
			)
			(fill no)
			(layer "F.CrtYd")
		)
		(fp_line
			(start -0.2794 -0.1016)
			(end -0.2794 0.9906)
			(stroke
				(width 0.1)
				(type default)
			)
			(layer "F.Fab")
		)
		(fp_line
			(start -0.2794 0.9906)
			(end 0.2794 0.9906)
			(stroke
				(width 0.1)
				(type default)
			)
			(layer "F.Fab")
		)
		(fp_line
			(start 0.2794 -0.1016)
			(end -0.2794 -0.1016)
			(stroke
				(width 0.1)
				(type default)
			)
			(layer "F.Fab")
		)
		(fp_line
			(start 0.2794 0.9906)
			(end 0.2794 -0.1016)
			(stroke
				(width 0.1)
				(type default)
			)
			(layer "F.Fab")
		)
		(pad "1" smd rect
			(at 0 0)
			(size 0.508 0.508)
			(layers "F.Cu" "F.Mask" "F.Paste")
			(net "JTAG_PCH_GBE_CLK")
		)
		(pad "2" smd rect
			(at 0 0.889)
			(size 0.508 0.508)
			(layers "F.Cu" "F.Mask" "F.Paste")
			(net "JTAG_TCK")
		)
		(zone
			(layer "F.Cu")
			(hatch none 0.5)
			(connect_pads
				(clearance 0)
			)
			(min_thickness 0.25)
			(keepout
				(tracks allowed)
				(vias not_allowed)
				(pads allowed)
				(copperpour not_allowed)
				(footprints allowed)
			)
			(placement
				(enabled no)
				(sheetname "")
			)
			(fill
				(thermal_gap 0.5)
				(thermal_bridge_width 0.5)
				(island_removal_mode 0)
			)
			(polygon
				(pts
					(xy 397.1036 0.0254) (xy 397.6116 0.0254) (xy 397.6116 0.4064) (xy 397.1036 0.4064)
				)
			)
		)
		(zone
			(layer "F.Cu")
			(hatch none 0.5)
			(connect_pads
				(clearance 0)
			)
			(min_thickness 0.25)
			(keepout
				(tracks not_allowed)
				(vias allowed)
				(pads allowed)
				(copperpour not_allowed)
				(footprints allowed)
			)
			(placement
				(enabled no)
				(sheetname "")
			)
			(fill
				(thermal_gap 0.5)
				(thermal_bridge_width 0.5)
				(island_removal_mode 0)
			)
			(polygon
				(pts
					(xy 397.1036 0.4064) (xy 397.6116 0.4064) (xy 397.6116 0.0254) (xy 397.1036 0.0254)
				)
			)
		)
	)
	(footprint ""
		(layer "F.Cu")
		(at 23.366984 -94.938596 180)
		(property "Reference" "C1C16"
			(at 0 0 180)
			(layer "F.SilkS")
			(hide yes)
			(effects
				(font
					(size 1.27 1.27)
				)
			)
		)
		(property "Value" ""
			(at 0 0 180)
			(layer "F.Fab")
			(effects
				(font
					(size 1.27 1.27)
				)
			)
		)
		(duplicate_pad_numbers_are_jumpers no)
		(fp_rect
			(start 0.3048 -0.1016)
			(end -0.3048 0.9906)
			(stroke
				(width 0)
				(type default)
			)
			(fill no)
			(layer "F.CrtYd")
		)
		(fp_line
			(start 0.3048 0.9906)
			(end 0.3048 -0.1016)
			(stroke
				(width 0.1)
				(type default)
			)
			(layer "F.Fab")
		)
		(fp_line
			(start 0.3048 -0.1016)
			(end -0.3048 -0.1016)
			(stroke
				(width 0.1)
				(type default)
			)
			(layer "F.Fab")
		)
		(fp_line
			(start -0.3048 0.9906)
			(end 0.3048 0.9906)
			(stroke
				(width 0.1)
				(type default)
			)
			(layer "F.Fab")
		)
		(fp_line
			(start -0.3048 -0.1016)
			(end -0.3048 0.9906)
			(stroke
				(width 0.1)
				(type default)
			)
			(layer "F.Fab")
		)
		(pad "1" smd rect
			(at 0 0 180)
			(size 0.508 0.508)
			(layers "F.Cu" "F.Mask" "F.Paste")
			(net "VSENSE_PVSA_CPU1_BVSP")
		)
		(pad "2" smd rect
			(at 0 0.889 180)
			(size 0.508 0.508)
			(layers "F.Cu" "F.Mask" "F.Paste")
			(net "VSENSE_PVSA_CPU1_N")
		)
		(zone
			(layer "F.Cu")
			(hatch none 0.5)
			(connect_pads
				(clearance 0)
			)
			(min_thickness 0.25)
			(keepout
				(tracks not_allowed)
				(vias allowed)
				(pads allowed)
				(copperpour not_allowed)
				(footprints allowed)
			)
			(placement
				(enabled no)
				(sheetname "")
			)
			(fill
				(thermal_gap 0.5)
				(thermal_bridge_width 0.5)
				(island_removal_mode 0)
			)
			(polygon
				(pts
					(xy 23.112984 -95.192596) (xy 23.620984 -95.192596) (xy 23.620984 -95.573596) (xy 23.112984 -95.573596)
				)
			)
		)
		(zone
			(layer "F.Cu")
			(hatch none 0.5)
			(connect_pads
				(clearance 0)
			)
			(min_thickness 0.25)
			(keepout
				(tracks allowed)
				(vias not_allowed)
				(pads allowed)
				(copperpour not_allowed)
				(footprints allowed)
			)
			(placement
				(enabled no)
				(sheetname "")
			)
			(fill
				(thermal_gap 0.5)
				(thermal_bridge_width 0.5)
				(island_removal_mode 0)
			)
			(polygon
				(pts
					(xy 23.112984 -95.192596) (xy 23.620984 -95.192596) (xy 23.620984 -95.573596) (xy 23.112984 -95.573596)
				)
			)
		)
	)
	(footprint ""
		(layer "F.Cu")
		(at 183.261 -13.335 180)
		(property "Reference" "C4G2"
			(at 0 0 180)
			(layer "F.SilkS")
			(hide yes)
			(effects
				(font
					(size 1.27 1.27)
				)
			)
		)
		(property "Value" ""
			(at 0 0 180)
			(layer "F.Fab")
			(effects
				(font
					(size 1.27 1.27)
				)
			)
		)
		(duplicate_pad_numbers_are_jumpers no)
		(fp_poly
			(pts
				(xy -0.7239 -0.2159) (xy 0.7239 -0.2159) (xy 0.7239 1.9939) (xy -0.7239 1.9939)
			)
			(stroke
				(width 0)
				(type default)
			)
			(fill no)
			(layer "F.CrtYd")
		)
		(fp_line
			(start 0.7239 1.9939)
			(end 0.7239 -0.2159)
			(stroke
				(width 0.1)
				(type default)
			)
			(layer "F.Fab")
		)
		(fp_line
			(start 0.7239 -0.2159)
			(end -0.7239 -0.2159)
			(stroke
				(width 0.1)
				(type default)
			)
			(layer "F.Fab")
		)
		(fp_line
			(start -0.7239 1.9939)
			(end 0.7239 1.9939)
			(stroke
				(width 0.1)
				(type default)
			)
			(layer "F.Fab")
		)
		(fp_line
			(start -0.7239 -0.2159)
			(end -0.7239 1.9939)
			(stroke
				(width 0.1)
				(type default)
			)
			(layer "F.Fab")
		)
		(pad "1" smd rect
			(at 0 0 180)
			(size 1.27 1.016)
			(layers "F.Cu" "F.Mask" "F.Paste")
			(net "VR_FET_SW_P12V_STBY_PVPP_GHJ")
		)
		(pad "2" smd rect
			(at 0 1.778 180)
			(size 1.27 1.016)
			(layers "F.Cu" "F.Mask" "F.Paste")
			(net "GND")
		)
		(zone
			(layer "F.Cu")
			(hatch none 0.5)
			(connect_pads
				(clearance 0)
			)
			(min_thickness 0.25)
			(keepout
				(tracks not_allowed)
				(vias allowed)
				(pads allowed)
				(copperpour not_allowed)
				(footprints allowed)
			)
			(placement
				(enabled no)
				(sheetname "")
			)
			(fill
				(thermal_gap 0.5)
				(thermal_bridge_width 0.5)
				(island_removal_mode 0)
			)
			(polygon
				(pts
					(xy 183.896 -13.843) (xy 182.626 -13.843) (xy 182.626 -14.605) (xy 183.896 -14.605)
				)
			)
		)
	)
	(footprint ""
		(layer "F.Cu")
		(at 5.20446 -132.49402 180)
		(property "Reference" "C1B3"
			(at -0.8382 -0.67818 180)
			(unlocked yes)
			(layer "F.SilkS")
			(effects
				(font
					(size 0.4064 0.254)
					(thickness 0.1524)
				)
				(justify left)
			)
		)
		(property "Value" ""
			(at 0 0 180)
			(layer "F.Fab")
			(effects
				(font
					(size 1.27 1.27)
				)
			)
		)
		(duplicate_pad_numbers_are_jumpers no)
		(fp_poly
			(pts
				(xy 0.3048 -0.1016) (xy 0.3048 0.9906) (xy -0.3048 0.9906) (xy -0.3048 -0.1016)
			)
			(stroke
				(width 0)
				(type default)
			)
			(fill no)
			(layer "F.CrtYd")
		)
		(fp_line
			(start 0.3048 0.9906)
			(end 0.3048 -0.1016)
			(stroke
				(width 0.1)
				(type default)
			)
			(layer "F.Fab")
		)
		(fp_line
			(start 0.3048 -0.1016)
			(end -0.3048 -0.1016)
			(stroke
				(width 0.1)
				(type default)
			)
			(layer "F.Fab")
		)
		(fp_line
			(start -0.3048 0.9906)
			(end 0.3048 0.9906)
			(stroke
				(width 0.1)
				(type default)
			)
			(layer "F.Fab")
		)
		(fp_line
			(start -0.3048 -0.1016)
			(end -0.3048 0.9906)
			(stroke
				(width 0.1)
				(type default)
			)
			(layer "F.Fab")
		)
		(pad "1" smd rect
			(at 0 0 180)
			(size 0.508 0.508)
			(layers "F.Cu" "F.Mask" "F.Paste")
			(net "VR_PVDDQ_KLM_VD12")
		)
		(pad "2" smd rect
			(at 0 0.889 180)
			(size 0.508 0.508)
			(layers "F.Cu" "F.Mask" "F.Paste")
			(net "GND")
		)
		(zone
			(layer "F.Cu")
			(hatch none 0.5)
			(connect_pads
				(clearance 0)
			)
			(min_thickness 0.25)
			(keepout
				(tracks not_allowed)
				(vias allowed)
				(pads allowed)
				(copperpour not_allowed)
				(footprints allowed)
			)
			(placement
				(enabled no)
				(sheetname "")
			)
			(fill
				(thermal_gap 0.5)
				(thermal_bridge_width 0.5)
				(island_removal_mode 0)
			)
			(polygon
				(pts
					(xy 5.45846 -133.12902) (xy 4.95046 -133.12902) (xy 4.95046 -132.74802) (xy 5.45846 -132.74802)
				)
			)
		)
		(zone
			(layer "F.Cu")
			(hatch none 0.5)
			(connect_pads
				(clearance 0)
			)
			(min_thickness 0.25)
			(keepout
				(tracks allowed)
				(vias not_allowed)
				(pads allowed)
				(copperpour not_allowed)
				(footprints allowed)
			)
			(placement
				(enabled no)
				(sheetname "")
			)
			(fill
				(thermal_gap 0.5)
				(thermal_bridge_width 0.5)
				(island_removal_mode 0)
			)
			(polygon
				(pts
					(xy 5.45846 -132.74802) (xy 4.95046 -132.74802) (xy 4.95046 -133.12902) (xy 5.45846 -133.12902)
				)
			)
		)
	)
	(footprint ""
		(layer "F.Cu")
		(at 273.369024 -77.429614)
		(property "Reference" "C5D36"
			(at 0 0 0)
			(layer "F.SilkS")
			(hide yes)
			(effects
				(font
					(size 1.27 1.27)
				)
			)
		)
		(property "Value" ""
			(at 0 0 0)
			(layer "F.Fab")
			(effects
				(font
					(size 1.27 1.27)
				)
			)
		)
		(duplicate_pad_numbers_are_jumpers no)
		(fp_poly
			(pts
				(xy -0.4953 -0.2032) (xy 0.4953 -0.2032) (xy 0.4953 1.6002) (xy -0.4953 1.6002)
			)
			(stroke
				(width 0)
				(type default)
			)
			(fill no)
			(layer "F.CrtYd")
		)
		(fp_line
			(start -0.4953 -0.2032)
			(end 0.4953 -0.2032)
			(stroke
				(width 0.1)
				(type default)
			)
			(layer "F.Fab")
		)
		(fp_line
			(start -0.4953 1.6002)
			(end -0.4953 -0.2032)
			(stroke
				(width 0.1)
				(type default)
			)
			(layer "F.Fab")
		)
		(fp_line
			(start 0.4953 -0.2032)
			(end 0.4953 1.6002)
			(stroke
				(width 0.1)
				(type default)
			)
			(layer "F.Fab")
		)
		(fp_line
			(start 0.4953 1.6002)
			(end -0.4953 1.6002)
			(stroke
				(width 0.1)
				(type default)
			)
			(layer "F.Fab")
		)
		(pad "1" smd rect
			(at 0 0)
			(size 0.762 0.889)
			(layers "F.Cu" "F.Mask" "F.Paste")
			(net "PVCCMCP_CPU0")
		)
		(pad "2" smd rect
			(at 0 1.397)
			(size 0.762 0.889)
			(layers "F.Cu" "F.Mask" "F.Paste")
			(net "GND")
		)
		(zone
			(layer "F.Cu")
			(hatch none 0.5)
			(connect_pads
				(clearance 0)
			)
			(min_thickness 0.25)
			(keepout
				(tracks not_allowed)
				(vias allowed)
				(pads allowed)
				(copperpour not_allowed)
				(footprints allowed)
			)
			(placement
				(enabled no)
				(sheetname "")
			)
			(fill
				(thermal_gap 0.5)
				(thermal_bridge_width 0.5)
				(island_removal_mode 0)
			)
			(polygon
				(pts
					(xy 272.988024 -76.985114) (xy 273.750024 -76.985114) (xy 273.750024 -76.477114) (xy 272.988024 -76.477114)
				)
			)
		)
	)
	(footprint ""
		(layer "F.Cu")
		(at 179.197 -58.166 90)
		(property "Reference" "C4E22"
			(at 0 0 90)
			(layer "F.SilkS")
			(hide yes)
			(effects
				(font
					(size 1.27 1.27)
				)
			)
		)
		(property "Value" ""
			(at 0 0 90)
			(layer "F.Fab")
			(effects
				(font
					(size 1.27 1.27)
				)
			)
		)
		(duplicate_pad_numbers_are_jumpers no)
		(fp_poly
			(pts
				(xy 0.3048 -0.1016) (xy 0.3048 0.9906) (xy -0.3048 0.9906) (xy -0.3048 -0.1016)
			)
			(stroke
				(width 0)
				(type default)
			)
			(fill no)
			(layer "F.CrtYd")
		)
		(fp_line
			(start 0.3048 -0.1016)
			(end -0.3048 -0.1016)
			(stroke
				(width 0.1)
				(type default)
			)
			(layer "F.Fab")
		)
		(fp_line
			(start -0.3048 -0.1016)
			(end -0.3048 0.9906)
			(stroke
				(width 0.1)
				(type default)
			)
			(layer "F.Fab")
		)
		(fp_line
			(start 0.3048 0.9906)
			(end 0.3048 -0.1016)
			(stroke
				(width 0.1)
				(type default)
			)
			(layer "F.Fab")
		)
		(fp_line
			(start -0.3048 0.9906)
			(end 0.3048 0.9906)
			(stroke
				(width 0.1)
				(type default)
			)
			(layer "F.Fab")
		)
		(pad "1" smd rect
			(at 0 0 90)
			(size 0.508 0.508)
			(layers "F.Cu" "F.Mask" "F.Paste")
			(net "VR_PVCCIO_CPU1_PH1_VCIN")
		)
		(pad "2" smd rect
			(at 0 0.889 90)
			(size 0.508 0.508)
			(layers "F.Cu" "F.Mask" "F.Paste")
			(net "GND")
		)
		(zone
			(layer "F.Cu")
			(hatch none 0.5)
			(connect_pads
				(clearance 0)
			)
			(min_thickness 0.25)
			(keepout
				(tracks allowed)
				(vias not_allowed)
				(pads allowed)
				(copperpour not_allowed)
				(footprints allowed)
			)
			(placement
				(enabled no)
				(sheetname "")
			)
			(fill
				(thermal_gap 0.5)
				(thermal_bridge_width 0.5)
				(island_removal_mode 0)
			)
			(polygon
				(pts
					(xy 179.451 -57.912) (xy 179.451 -58.42) (xy 179.832 -58.42) (xy 179.832 -57.912)
				)
			)
		)
		(zone
			(layer "F.Cu")
			(hatch none 0.5)
			(connect_pads
				(clearance 0)
			)
			(min_thickness 0.25)
			(keepout
				(tracks not_allowed)
				(vias allowed)
				(pads allowed)
				(copperpour not_allowed)
				(footprints allowed)
			)
			(placement
				(enabled no)
				(sheetname "")
			)
			(fill
				(thermal_gap 0.5)
				(thermal_bridge_width 0.5)
				(island_removal_mode 0)
			)
			(polygon
				(pts
					(xy 179.832 -57.912) (xy 179.832 -58.42) (xy 179.451 -58.42) (xy 179.451 -57.912)
				)
			)
		)
	)
	(footprint ""
		(layer "F.Cu")
		(at 400.558 -156.718)
		(property "Reference" "R8A1"
			(at 0 0 0)
			(layer "F.SilkS")
			(hide yes)
			(effects
				(font
					(size 1.27 1.27)
				)
			)
		)
		(property "Value" ""
			(at 0 0 0)
			(layer "F.Fab")
			(effects
				(font
					(size 1.27 1.27)
				)
			)
		)
		(duplicate_pad_numbers_are_jumpers no)
		(fp_poly
			(pts
				(xy -0.2794 -0.1016) (xy 0.2794 -0.1016) (xy 0.2794 0.9906) (xy -0.2794 0.9906)
			)
			(stroke
				(width 0)
				(type default)
			)
			(fill no)
			(layer "F.CrtYd")
		)
		(fp_line
			(start -0.2794 -0.1016)
			(end -0.2794 0.9906)
			(stroke
				(width 0.1)
				(type default)
			)
			(layer "F.Fab")
		)
		(fp_line
			(start -0.2794 0.9906)
			(end 0.2794 0.9906)
			(stroke
				(width 0.1)
				(type default)
			)
			(layer "F.Fab")
		)
		(fp_line
			(start 0.2794 -0.1016)
			(end -0.2794 -0.1016)
			(stroke
				(width 0.1)
				(type default)
			)
			(layer "F.Fab")
		)
		(fp_line
			(start 0.2794 0.9906)
			(end 0.2794 -0.1016)
			(stroke
				(width 0.1)
				(type default)
			)
			(layer "F.Fab")
		)
		(pad "1" smd rect
			(at 0 0)
			(size 0.508 0.508)
			(layers "F.Cu" "F.Mask" "F.Paste")
			(net "VSENSE_PVNN_PCH_STBY_AVSP")
		)
		(pad "2" smd rect
			(at 0 0.889)
			(size 0.508 0.508)
			(layers "F.Cu" "F.Mask" "F.Paste")
			(net "VR_PVNN_PCH_AVSP")
		)
		(zone
			(layer "F.Cu")
			(hatch none 0.5)
			(connect_pads
				(clearance 0)
			)
			(min_thickness 0.25)
			(keepout
				(tracks allowed)
				(vias not_allowed)
				(pads allowed)
				(copperpour not_allowed)
				(footprints allowed)
			)
			(placement
				(enabled no)
				(sheetname "")
			)
			(fill
				(thermal_gap 0.5)
				(thermal_bridge_width 0.5)
				(island_removal_mode 0)
			)
			(polygon
				(pts
					(xy 400.304 -156.464) (xy 400.812 -156.464) (xy 400.812 -156.083) (xy 400.304 -156.083)
				)
			)
		)
		(zone
			(layer "F.Cu")
			(hatch none 0.5)
			(connect_pads
				(clearance 0)
			)
			(min_thickness 0.25)
			(keepout
				(tracks not_allowed)
				(vias allowed)
				(pads allowed)
				(copperpour not_allowed)
				(footprints allowed)
			)
			(placement
				(enabled no)
				(sheetname "")
			)
			(fill
				(thermal_gap 0.5)
				(thermal_bridge_width 0.5)
				(island_removal_mode 0)
			)
			(polygon
				(pts
					(xy 400.304 -156.083) (xy 400.812 -156.083) (xy 400.812 -156.464) (xy 400.304 -156.464)
				)
			)
		)
	)
	(footprint ""
		(layer "F.Cu")
		(at 154.305 -29.6418 90)
		(property "Reference" "R3F2"
			(at 0 0 90)
			(layer "F.SilkS")
			(hide yes)
			(effects
				(font
					(size 1.27 1.27)
				)
			)
		)
		(property "Value" ""
			(at 0 0 90)
			(layer "F.Fab")
			(effects
				(font
					(size 1.27 1.27)
				)
			)
		)
		(duplicate_pad_numbers_are_jumpers no)
		(fp_poly
			(pts
				(xy -0.2794 -0.1016) (xy 0.2794 -0.1016) (xy 0.2794 0.9906) (xy -0.2794 0.9906)
			)
			(stroke
				(width 0)
				(type default)
			)
			(fill no)
			(layer "F.CrtYd")
		)
		(fp_line
			(start 0.2794 -0.1016)
			(end -0.2794 -0.1016)
			(stroke
				(width 0.1)
				(type default)
			)
			(layer "F.Fab")
		)
		(fp_line
			(start -0.2794 -0.1016)
			(end -0.2794 0.9906)
			(stroke
				(width 0.1)
				(type default)
			)
			(layer "F.Fab")
		)
		(fp_line
			(start 0.2794 0.9906)
			(end 0.2794 -0.1016)
			(stroke
				(width 0.1)
				(type default)
			)
			(layer "F.Fab")
		)
		(fp_line
			(start -0.2794 0.9906)
			(end 0.2794 0.9906)
			(stroke
				(width 0.1)
				(type default)
			)
			(layer "F.Fab")
		)
		(pad "1" smd rect
			(at 0 0 90)
			(size 0.508 0.508)
			(layers "F.Cu" "F.Mask" "F.Paste")
			(net "CLK_156M_OSC_BRD_CPU1_DN")
		)
		(pad "2" smd rect
			(at 0 0.889 90)
			(size 0.508 0.508)
			(layers "F.Cu" "F.Mask" "F.Paste")
			(net "CLK_156M_OSC_CPU1_HFI_DN")
		)
		(zone
			(layer "F.Cu")
			(hatch none 0.5)
			(connect_pads
				(clearance 0)
			)
			(min_thickness 0.25)
			(keepout
				(tracks allowed)
				(vias not_allowed)
				(pads allowed)
				(copperpour not_allowed)
				(footprints allowed)
			)
			(placement
				(enabled no)
				(sheetname "")
			)
			(fill
				(thermal_gap 0.5)
				(thermal_bridge_width 0.5)
				(island_removal_mode 0)
			)
			(polygon
				(pts
					(xy 154.559 -29.3878) (xy 154.559 -29.8958) (xy 154.94 -29.8958) (xy 154.94 -29.3878)
				)
			)
		)
		(zone
			(layer "F.Cu")
			(hatch none 0.5)
			(connect_pads
				(clearance 0)
			)
			(min_thickness 0.25)
			(keepout
				(tracks not_allowed)
				(vias allowed)
				(pads allowed)
				(copperpour not_allowed)
				(footprints allowed)
			)
			(placement
				(enabled no)
				(sheetname "")
			)
			(fill
				(thermal_gap 0.5)
				(thermal_bridge_width 0.5)
				(island_removal_mode 0)
			)
			(polygon
				(pts
					(xy 154.94 -29.3878) (xy 154.94 -29.8958) (xy 154.559 -29.8958) (xy 154.559 -29.3878)
				)
			)
		)
	)
	(footprint ""
		(layer "F.Cu")
		(at 166.497 -3.048 180)
		(property "Reference" "C4G20"
			(at 0 0 180)
			(layer "F.SilkS")
			(hide yes)
			(effects
				(font
					(size 1.27 1.27)
				)
			)
		)
		(property "Value" ""
			(at 0 0 180)
			(layer "F.Fab")
			(effects
				(font
					(size 1.27 1.27)
				)
			)
		)
		(duplicate_pad_numbers_are_jumpers no)
		(fp_rect
			(start -0.7239 1.9939)
			(end 0.7239 -0.2159)
			(stroke
				(width 0)
				(type default)
			)
			(fill no)
			(layer "F.CrtYd")
		)
		(fp_line
			(start 0.7239 1.9939)
			(end 0.7239 -0.2159)
			(stroke
				(width 0.1)
				(type default)
			)
			(layer "F.Fab")
		)
		(fp_line
			(start 0.7239 -0.2159)
			(end -0.7239 -0.2159)
			(stroke
				(width 0.1)
				(type default)
			)
			(layer "F.Fab")
		)
		(fp_line
			(start -0.7239 1.9939)
			(end 0.7239 1.9939)
			(stroke
				(width 0.1)
				(type default)
			)
			(layer "F.Fab")
		)
		(fp_line
			(start -0.7239 -0.2159)
			(end -0.7239 1.9939)
			(stroke
				(width 0.1)
				(type default)
			)
			(layer "F.Fab")
		)
		(pad "1" smd rect
			(at 0 0 180)
			(size 1.27 1.016)
			(layers "F.Cu" "F.Mask" "F.Paste")
			(net "PVTT_GHJ")
		)
		(pad "2" smd rect
			(at 0 1.778 180)
			(size 1.27 1.016)
			(layers "F.Cu" "F.Mask" "F.Paste")
			(net "GND")
		)
		(zone
			(layer "F.Cu")
			(hatch none 0.5)
			(connect_pads
				(clearance 0)
			)
			(min_thickness 0.25)
			(keepout
				(tracks not_allowed)
				(vias allowed)
				(pads allowed)
				(copperpour not_allowed)
				(footprints allowed)
			)
			(placement
				(enabled no)
				(sheetname "")
			)
			(fill
				(thermal_gap 0.5)
				(thermal_bridge_width 0.5)
				(island_removal_mode 0)
			)
			(polygon
				(pts
					(xy 167.132 -4.318) (xy 165.862 -4.318) (xy 165.862 -3.556) (xy 167.132 -3.556)
				)
			)
		)
	)
	(footprint ""
		(layer "F.Cu")
		(at 415.7345 -110.617 -90)
		(property "Reference" "R2M3"
			(at 0 0 270)
			(layer "F.SilkS")
			(hide yes)
			(effects
				(font
					(size 1.27 1.27)
				)
			)
		)
		(property "Value" ""
			(at 0 0 270)
			(layer "F.Fab")
			(effects
				(font
					(size 1.27 1.27)
				)
			)
		)
		(duplicate_pad_numbers_are_jumpers no)
		(fp_poly
			(pts
				(xy -0.2794 -0.1016) (xy 0.2794 -0.1016) (xy 0.2794 0.9906) (xy -0.2794 0.9906)
			)
			(stroke
				(width 0)
				(type default)
			)
			(fill no)
			(layer "F.CrtYd")
		)
		(fp_line
			(start -0.2794 0.9906)
			(end 0.2794 0.9906)
			(stroke
				(width 0.1)
				(type default)
			)
			(layer "F.Fab")
		)
		(fp_line
			(start 0.2794 0.9906)
			(end 0.2794 -0.1016)
			(stroke
				(width 0.1)
				(type default)
			)
			(layer "F.Fab")
		)
		(fp_line
			(start -0.2794 -0.1016)
			(end -0.2794 0.9906)
			(stroke
				(width 0.1)
				(type default)
			)
			(layer "F.Fab")
		)
		(fp_line
			(start 0.2794 -0.1016)
			(end -0.2794 -0.1016)
			(stroke
				(width 0.1)
				(type default)
			)
			(layer "F.Fab")
		)
		(pad "1" smd rect
			(at 0 0 270)
			(size 0.508 0.508)
			(layers "F.Cu" "F.Mask" "F.Paste")
			(net "FM_PCH_PLD_DATA_R")
		)
		(pad "2" smd rect
			(at 0 0.889 270)
			(size 0.508 0.508)
			(layers "F.Cu" "F.Mask" "F.Paste")
			(net "FM_PCH_PLD_DATA")
		)
		(zone
			(layer "F.Cu")
			(hatch none 0.5)
			(connect_pads
				(clearance 0)
			)
			(min_thickness 0.25)
			(keepout
				(tracks not_allowed)
				(vias allowed)
				(pads allowed)
				(copperpour not_allowed)
				(footprints allowed)
			)
			(placement
				(enabled no)
				(sheetname "")
			)
			(fill
				(thermal_gap 0.5)
				(thermal_bridge_width 0.5)
				(island_removal_mode 0)
			)
			(polygon
				(pts
					(xy 415.0995 -110.871) (xy 415.0995 -110.363) (xy 415.4805 -110.363) (xy 415.4805 -110.871)
				)
			)
		)
		(zone
			(layer "F.Cu")
			(hatch none 0.5)
			(connect_pads
				(clearance 0)
			)
			(min_thickness 0.25)
			(keepout
				(tracks allowed)
				(vias not_allowed)
				(pads allowed)
				(copperpour not_allowed)
				(footprints allowed)
			)
			(placement
				(enabled no)
				(sheetname "")
			)
			(fill
				(thermal_gap 0.5)
				(thermal_bridge_width 0.5)
				(island_removal_mode 0)
			)
			(polygon
				(pts
					(xy 415.4805 -110.871) (xy 415.4805 -110.363) (xy 415.0995 -110.363) (xy 415.0995 -110.871)
				)
			)
		)
	)
	(footprint ""
		(layer "F.Cu")
		(at 451.85838 -38.2905 90)
		(property "Reference" "R25W49"
			(at 0 0 90)
			(layer "F.SilkS")
			(hide yes)
			(effects
				(font
					(size 1.27 1.27)
				)
			)
		)
		(property "Value" "*"
			(at 0.064008 -4.108196 90)
			(unlocked yes)
			(layer "F.Fab")
			(hide yes)
			(effects
				(font
					(size 1.27 1.016)
					(thickness 0.1524)
				)
			)
		)
		(property "Device Type" "120R2F-GP_RCL_GP-120R2F-GP,64.A"
			(at 0.064008 -5.632196 90)
			(unlocked yes)
			(layer "F.Fab")
			(hide yes)
			(effects
				(font
					(size 1.27 1.016)
					(thickness 0.1524)
				)
			)
		)
		(duplicate_pad_numbers_are_jumpers no)
		(fp_line
			(start 0.508 -0.9398)
			(end -0.508 -0.9398)
			(stroke
				(width 0.1524)
				(type default)
			)
			(layer "F.SilkS")
		)
		(fp_line
			(start -0.508 -0.9398)
			(end -0.508 0.9398)
			(stroke
				(width 0.1524)
				(type default)
			)
			(layer "F.SilkS")
		)
		(fp_rect
			(start -0.508 0.9398)
			(end 0.508 -0.9398)
			(stroke
				(width 0)
				(type default)
			)
			(fill no)
			(layer "F.CrtYd")
		)
		(fp_rect
			(start -0.508 0.9398)
			(end 0.508 -0.9398)
			(stroke
				(width 0)
				(type default)
			)
			(fill no)
			(layer "F.Fab")
		)
		(pad "1" smd custom
			(at 0 -0.4445 90)
			(size 0.1397 0.1397)
			(layers "F.Cu" "F.Mask" "F.Paste")
			(net "BMC_M_A11")
			(options
				(clearance outline)
				(anchor circle)
			)
			(primitives
				(gr_poly
					(pts
						(arc
							(start -0.1778 -0.2794)
							(mid -0.249642 -0.249642)
							(end -0.2794 -0.1778)
						)
						(arc
							(start -0.2794 0.1778)
							(mid -0.249642 0.249642)
							(end -0.1778 0.2794)
						)
						(arc
							(start 0.1778 0.2794)
							(mid 0.249642 0.249642)
							(end 0.2794 0.1778)
						)
						(arc
							(start 0.2794 -0.1778)
							(mid 0.249642 -0.249642)
							(end 0.1778 -0.2794)
						)
					)
					(width 0)
					(fill yes)
				)
			)
		)
		(pad "2" smd custom
			(at 0 0.4445 90)
			(size 0.1397 0.1397)
			(layers "F.Cu" "F.Mask" "F.Paste")
			(net "P1V2_AUX_BMC")
			(options
				(clearance outline)
				(anchor circle)
			)
			(primitives
				(gr_poly
					(pts
						(arc
							(start -0.1778 -0.2794)
							(mid -0.249642 -0.249642)
							(end -0.2794 -0.1778)
						)
						(arc
							(start -0.2794 0.1778)
							(mid -0.249642 0.249642)
							(end -0.1778 0.2794)
						)
						(arc
							(start 0.1778 0.2794)
							(mid 0.249642 0.249642)
							(end 0.2794 0.1778)
						)
						(arc
							(start 0.2794 -0.1778)
							(mid 0.249642 -0.249642)
							(end 0.1778 -0.2794)
						)
					)
					(width 0)
					(fill yes)
				)
			)
		)
	)
	(footprint ""
		(layer "F.Cu")
		(at 180.381148 -73.85685 -90)
		(property "Reference" "C4D26"
			(at 0 0 270)
			(layer "F.SilkS")
			(hide yes)
			(effects
				(font
					(size 1.27 1.27)
				)
			)
		)
		(property "Value" ""
			(at 0 0 270)
			(layer "F.Fab")
			(effects
				(font
					(size 1.27 1.27)
				)
			)
		)
		(duplicate_pad_numbers_are_jumpers no)
		(fp_rect
			(start 0.3048 -0.1016)
			(end -0.3048 0.9906)
			(stroke
				(width 0)
				(type default)
			)
			(fill no)
			(layer "F.CrtYd")
		)
		(fp_line
			(start -0.3048 0.9906)
			(end 0.3048 0.9906)
			(stroke
				(width 0.1)
				(type default)
			)
			(layer "F.Fab")
		)
		(fp_line
			(start 0.3048 0.9906)
			(end 0.3048 -0.1016)
			(stroke
				(width 0.1)
				(type default)
			)
			(layer "F.Fab")
		)
		(fp_line
			(start -0.3048 -0.1016)
			(end -0.3048 0.9906)
			(stroke
				(width 0.1)
				(type default)
			)
			(layer "F.Fab")
		)
		(fp_line
			(start 0.3048 -0.1016)
			(end -0.3048 -0.1016)
			(stroke
				(width 0.1)
				(type default)
			)
			(layer "F.Fab")
		)
		(pad "1" smd rect
			(at 0 0 270)
			(size 0.508 0.508)
			(layers "F.Cu" "F.Mask" "F.Paste")
			(net "VR_PVCCIN_CPU0_VD12")
		)
		(pad "2" smd rect
			(at 0 0.889 270)
			(size 0.508 0.508)
			(layers "F.Cu" "F.Mask" "F.Paste")
			(net "GND")
		)
		(zone
			(layer "F.Cu")
			(hatch none 0.5)
			(connect_pads
				(clearance 0)
			)
			(min_thickness 0.25)
			(keepout
				(tracks not_allowed)
				(vias allowed)
				(pads allowed)
				(copperpour not_allowed)
				(footprints allowed)
			)
			(placement
				(enabled no)
				(sheetname "")
			)
			(fill
				(thermal_gap 0.5)
				(thermal_bridge_width 0.5)
				(island_removal_mode 0)
			)
			(polygon
				(pts
					(xy 180.127148 -73.60285) (xy 180.127148 -74.11085) (xy 179.746148 -74.11085) (xy 179.746148 -73.60285)
				)
			)
		)
		(zone
			(layer "F.Cu")
			(hatch none 0.5)
			(connect_pads
				(clearance 0)
			)
			(min_thickness 0.25)
			(keepout
				(tracks allowed)
				(vias not_allowed)
				(pads allowed)
				(copperpour not_allowed)
				(footprints allowed)
			)
			(placement
				(enabled no)
				(sheetname "")
			)
			(fill
				(thermal_gap 0.5)
				(thermal_bridge_width 0.5)
				(island_removal_mode 0)
			)
			(polygon
				(pts
					(xy 180.127148 -73.60285) (xy 180.127148 -74.11085) (xy 179.746148 -74.11085) (xy 179.746148 -73.60285)
				)
			)
		)
	)
	(footprint ""
		(layer "F.Cu")
		(at 439.976006 -43.568874 180)
		(property "Reference" "R25W33"
			(at 0 0 180)
			(layer "F.SilkS")
			(hide yes)
			(effects
				(font
					(size 1.27 1.27)
				)
			)
		)
		(property "Value" "*"
			(at 0.064008 -4.108196 180)
			(unlocked yes)
			(layer "F.Fab")
			(hide yes)
			(effects
				(font
					(size 1.27 1.016)
					(thickness 0.1524)
				)
			)
		)
		(property "Device Type" "120R2F-GP_RCL_GP-120R2F-GP,64.A"
			(at 0.064008 -5.632196 180)
			(unlocked yes)
			(layer "F.Fab")
			(hide yes)
			(effects
				(font
					(size 1.27 1.016)
					(thickness 0.1524)
				)
			)
		)
		(duplicate_pad_numbers_are_jumpers no)
		(fp_line
			(start 0.508 -0.9398)
			(end -0.508 -0.9398)
			(stroke
				(width 0.1524)
				(type default)
			)
			(layer "F.SilkS")
		)
		(fp_line
			(start -0.508 -0.9398)
			(end -0.508 0.9398)
			(stroke
				(width 0.1524)
				(type default)
			)
			(layer "F.SilkS")
		)
		(fp_rect
			(start -0.508 0.9398)
			(end 0.508 -0.9398)
			(stroke
				(width 0)
				(type default)
			)
			(fill no)
			(layer "F.CrtYd")
		)
		(fp_rect
			(start -0.508 0.9398)
			(end 0.508 -0.9398)
			(stroke
				(width 0)
				(type default)
			)
			(fill no)
			(layer "F.Fab")
		)
		(pad "1" smd custom
			(at 0 -0.4445 180)
			(size 0.1397 0.1397)
			(layers "F.Cu" "F.Mask" "F.Paste")
			(net "BMC_M_CAS_N")
			(options
				(clearance outline)
				(anchor circle)
			)
			(primitives
				(gr_poly
					(pts
						(arc
							(start -0.1778 -0.2794)
							(mid -0.249642 -0.249642)
							(end -0.2794 -0.1778)
						)
						(arc
							(start -0.2794 0.1778)
							(mid -0.249642 0.249642)
							(end -0.1778 0.2794)
						)
						(arc
							(start 0.1778 0.2794)
							(mid 0.249642 0.249642)
							(end 0.2794 0.1778)
						)
						(arc
							(start 0.2794 -0.1778)
							(mid 0.249642 -0.249642)
							(end 0.1778 -0.2794)
						)
					)
					(width 0)
					(fill yes)
				)
			)
		)
		(pad "2" smd custom
			(at 0 0.4445 180)
			(size 0.1397 0.1397)
			(layers "F.Cu" "F.Mask" "F.Paste")
			(net "P1V2_AUX_BMC")
			(options
				(clearance outline)
				(anchor circle)
			)
			(primitives
				(gr_poly
					(pts
						(arc
							(start -0.1778 -0.2794)
							(mid -0.249642 -0.249642)
							(end -0.2794 -0.1778)
						)
						(arc
							(start -0.2794 0.1778)
							(mid -0.249642 0.249642)
							(end -0.1778 0.2794)
						)
						(arc
							(start 0.1778 0.2794)
							(mid 0.249642 0.249642)
							(end 0.2794 0.1778)
						)
						(arc
							(start 0.2794 -0.1778)
							(mid 0.249642 -0.249642)
							(end 0.1778 -0.2794)
						)
					)
					(width 0)
					(fill yes)
				)
			)
		)
	)
	(footprint ""
		(layer "F.Cu")
		(at 163.576 -80.518 -90)
		(property "Reference" "R4D19"
			(at 0 0 270)
			(layer "F.SilkS")
			(hide yes)
			(effects
				(font
					(size 1.27 1.27)
				)
			)
		)
		(property "Value" ""
			(at 0 0 270)
			(layer "F.Fab")
			(effects
				(font
					(size 1.27 1.27)
				)
			)
		)
		(duplicate_pad_numbers_are_jumpers no)
		(fp_poly
			(pts
				(xy -0.2794 -0.1016) (xy 0.2794 -0.1016) (xy 0.2794 0.9906) (xy -0.2794 0.9906)
			)
			(stroke
				(width 0)
				(type default)
			)
			(fill no)
			(layer "F.CrtYd")
		)
		(fp_line
			(start -0.2794 0.9906)
			(end 0.2794 0.9906)
			(stroke
				(width 0.1)
				(type default)
			)
			(layer "F.Fab")
		)
		(fp_line
			(start 0.2794 0.9906)
			(end 0.2794 -0.1016)
			(stroke
				(width 0.1)
				(type default)
			)
			(layer "F.Fab")
		)
		(fp_line
			(start -0.2794 -0.1016)
			(end -0.2794 0.9906)
			(stroke
				(width 0.1)
				(type default)
			)
			(layer "F.Fab")
		)
		(fp_line
			(start 0.2794 -0.1016)
			(end -0.2794 -0.1016)
			(stroke
				(width 0.1)
				(type default)
			)
			(layer "F.Fab")
		)
		(pad "1" smd rect
			(at 0 0 270)
			(size 0.508 0.508)
			(layers "F.Cu" "F.Mask" "F.Paste")
			(net "CLK_100M_CPU1_RC_REFCLK0_R_DP")
		)
		(pad "2" smd rect
			(at 0 0.889 270)
			(size 0.508 0.508)
			(layers "F.Cu" "F.Mask" "F.Paste")
			(net "CLK_100M_CPU1_RC_REFCLK0_DP")
		)
		(zone
			(layer "F.Cu")
			(hatch none 0.5)
			(connect_pads
				(clearance 0)
			)
			(min_thickness 0.25)
			(keepout
				(tracks not_allowed)
				(vias allowed)
				(pads allowed)
				(copperpour not_allowed)
				(footprints allowed)
			)
			(placement
				(enabled no)
				(sheetname "")
			)
			(fill
				(thermal_gap 0.5)
				(thermal_bridge_width 0.5)
				(island_removal_mode 0)
			)
			(polygon
				(pts
					(xy 162.941 -80.772) (xy 162.941 -80.264) (xy 163.322 -80.264) (xy 163.322 -80.772)
				)
			)
		)
		(zone
			(layer "F.Cu")
			(hatch none 0.5)
			(connect_pads
				(clearance 0)
			)
			(min_thickness 0.25)
			(keepout
				(tracks allowed)
				(vias not_allowed)
				(pads allowed)
				(copperpour not_allowed)
				(footprints allowed)
			)
			(placement
				(enabled no)
				(sheetname "")
			)
			(fill
				(thermal_gap 0.5)
				(thermal_bridge_width 0.5)
				(island_removal_mode 0)
			)
			(polygon
				(pts
					(xy 163.322 -80.772) (xy 163.322 -80.264) (xy 162.941 -80.264) (xy 162.941 -80.772)
				)
			)
		)
	)
	(footprint ""
		(layer "F.Cu")
		(at 171.8818 -3.175 180)
		(property "Reference" "EU4G2"
			(at 2.9718 -1.42367 0)
			(unlocked yes)
			(layer "F.SilkS")
			(effects
				(font
					(size 0.7874 0.5842)
					(thickness 0.1524)
				)
				(justify left)
			)
		)
		(property "Value" ""
			(at 0 0 180)
			(layer "F.Fab")
			(effects
				(font
					(size 1.27 1.27)
				)
			)
		)
		(duplicate_pad_numbers_are_jumpers no)
		(fp_circle
			(center -0.835152 -0.417322)
			(end -0.962152 -0.417322)
			(stroke
				(width 0.254)
				(type default)
			)
			(fill no)
			(layer "F.SilkS")
		)
		(fp_poly
			(pts
				(xy -0.064516 -1.0922) (xy -0.064516 -0.3302) (xy 0.697484 -1.0922)
			)
			(stroke
				(width 0)
				(type default)
			)
			(fill yes)
			(layer "F.SilkS")
		)
		(fp_rect
			(start 0.597408 2.295398)
			(end 2.273808 -0.295402)
			(stroke
				(width 0)
				(type default)
			)
			(fill yes)
			(layer "F.Paste")
		)
		(fp_rect
			(start -0.064516 2.500122)
			(end 2.935478 -0.500126)
			(stroke
				(width 0)
				(type default)
			)
			(fill no)
			(layer "F.CrtYd")
		)
		(fp_line
			(start 2.935478 2.500122)
			(end -0.064516 2.500122)
			(stroke
				(width 0.1)
				(type default)
			)
			(layer "F.Fab")
		)
		(fp_line
			(start 2.935478 -0.500126)
			(end 2.935478 2.500122)
			(stroke
				(width 0.1)
				(type default)
			)
			(layer "F.Fab")
		)
		(fp_line
			(start -0.064516 2.500122)
			(end -0.064516 -0.500126)
			(stroke
				(width 0.1)
				(type default)
			)
			(layer "F.Fab")
		)
		(fp_line
			(start -0.064516 -0.500126)
			(end 2.935478 -0.500126)
			(stroke
				(width 0.1)
				(type default)
			)
			(layer "F.Fab")
		)
		(fp_circle
			(center -0.835152 -0.417322)
			(end -0.962152 -0.417322)
			(stroke
				(width 0.254)
				(type default)
			)
			(fill no)
			(layer "F.Fab")
		)
		(pad "1" smd rect
			(at 0 0 180)
			(size 0.6858 0.3048)
			(layers "F.Cu" "F.Mask" "F.Paste")
			(net "VR_PVTT_GHJ_VREF")
		)
		(pad "2" smd rect
			(at 0 0.500126 180)
			(size 0.6858 0.3048)
			(layers "F.Cu" "F.Mask" "F.Paste")
			(net "VR_PVTT_GHJ_BIAS")
		)
		(pad "3" smd rect
			(at 0 0.999998 180)
			(size 0.6858 0.3048)
			(layers "F.Cu" "F.Mask" "F.Paste")
			(net "GND")
		)
		(pad "4" smd rect
			(at 0 1.500124 180)
			(size 0.6858 0.3048)
			(layers "F.Cu" "F.Mask" "F.Paste")
			(net "VSENSE_PVDDQ_GHJ_VTT")
		)
		(pad "5" smd rect
			(at 0 1.999996 180)
			(size 0.6858 0.3048)
			(layers "F.Cu" "F.Mask" "F.Paste")
			(net "PWRGD_PVTT_GHJ_CPU1_R")
		)
		(pad "6" smd rect
			(at 2.871216 1.999996 180)
			(size 0.6858 0.3048)
			(layers "F.Cu" "F.Mask" "F.Paste")
			(net "VR_PVTT_GHJ_SNS")
		)
		(pad "7" smd rect
			(at 2.871216 1.500124 180)
			(size 0.6858 0.3048)
			(layers "F.Cu" "F.Mask" "F.Paste")
			(net "FM_PVTT_GHJ_EN_R")
		)
		(pad "8" smd rect
			(at 2.871216 0.999998 180)
			(size 0.6858 0.3048)
			(layers "F.Cu" "F.Mask" "F.Paste")
			(net "GND")
		)
		(pad "9" smd rect
			(at 2.871216 0.500126 180)
			(size 0.6858 0.3048)
			(layers "F.Cu" "F.Mask" "F.Paste")
			(net "PVTT_GHJ")
		)
		(pad "10" smd rect
			(at 2.871216 0 180)
			(size 0.6858 0.3048)
			(layers "F.Cu" "F.Mask" "F.Paste")
			(net "PVDDQ_GHJ")
		)
		(pad "11" smd rect
			(at 1.435608 0.999998 180)
			(size 1.6764 2.5908)
			(layers "F.Cu" "F.Mask" "F.Paste")
			(net "GND")
		)
	)
	(footprint ""
		(layer "F.Cu")
		(at 401.55368 -28.49499 180)
		(property "Reference" "R25W148"
			(at -0.8382 -0.67818 180)
			(unlocked yes)
			(layer "F.SilkS")
			(effects
				(font
					(size 0.4064 0.254)
					(thickness 0.1524)
				)
				(justify left)
			)
		)
		(property "Value" ""
			(at 0 0 180)
			(layer "F.Fab")
			(effects
				(font
					(size 1.27 1.27)
				)
			)
		)
		(duplicate_pad_numbers_are_jumpers no)
		(fp_poly
			(pts
				(xy -0.2794 -0.1016) (xy 0.2794 -0.1016) (xy 0.2794 0.9906) (xy -0.2794 0.9906)
			)
			(stroke
				(width 0)
				(type default)
			)
			(fill no)
			(layer "F.CrtYd")
		)
		(fp_line
			(start 0.2794 0.9906)
			(end 0.2794 -0.1016)
			(stroke
				(width 0.1)
				(type default)
			)
			(layer "F.Fab")
		)
		(fp_line
			(start 0.2794 -0.1016)
			(end -0.2794 -0.1016)
			(stroke
				(width 0.1)
				(type default)
			)
			(layer "F.Fab")
		)
		(fp_line
			(start -0.2794 0.9906)
			(end 0.2794 0.9906)
			(stroke
				(width 0.1)
				(type default)
			)
			(layer "F.Fab")
		)
		(fp_line
			(start -0.2794 -0.1016)
			(end -0.2794 0.9906)
			(stroke
				(width 0.1)
				(type default)
			)
			(layer "F.Fab")
		)
		(pad "1" smd rect
			(at 0 0 180)
			(size 0.508 0.508)
			(layers "F.Cu" "F.Mask" "F.Paste")
			(net "GND")
		)
		(pad "2" smd rect
			(at 0 0.889 180)
			(size 0.508 0.508)
			(layers "F.Cu" "F.Mask" "F.Paste")
			(net "RMII_BMC_OCP_TXD1_R")
		)
		(zone
			(layer "F.Cu")
			(hatch none 0.5)
			(connect_pads
				(clearance 0)
			)
			(min_thickness 0.25)
			(keepout
				(tracks not_allowed)
				(vias allowed)
				(pads allowed)
				(copperpour not_allowed)
				(footprints allowed)
			)
			(placement
				(enabled no)
				(sheetname "")
			)
			(fill
				(thermal_gap 0.5)
				(thermal_bridge_width 0.5)
				(island_removal_mode 0)
			)
			(polygon
				(pts
					(xy 401.80768 -29.12999) (xy 401.29968 -29.12999) (xy 401.29968 -28.74899) (xy 401.80768 -28.74899)
				)
			)
		)
		(zone
			(layer "F.Cu")
			(hatch none 0.5)
			(connect_pads
				(clearance 0)
			)
			(min_thickness 0.25)
			(keepout
				(tracks allowed)
				(vias not_allowed)
				(pads allowed)
				(copperpour not_allowed)
				(footprints allowed)
			)
			(placement
				(enabled no)
				(sheetname "")
			)
			(fill
				(thermal_gap 0.5)
				(thermal_bridge_width 0.5)
				(island_removal_mode 0)
			)
			(polygon
				(pts
					(xy 401.80768 -28.74899) (xy 401.29968 -28.74899) (xy 401.29968 -29.12999) (xy 401.80768 -29.12999)
				)
			)
		)
	)
	(footprint ""
		(layer "F.Cu")
		(at 259.452872 -81.573116)
		(property "Reference" "C5D11"
			(at 0 0 0)
			(layer "F.SilkS")
			(hide yes)
			(effects
				(font
					(size 1.27 1.27)
				)
			)
		)
		(property "Value" ""
			(at 0 0 0)
			(layer "F.Fab")
			(effects
				(font
					(size 1.27 1.27)
				)
			)
		)
		(duplicate_pad_numbers_are_jumpers no)
		(fp_poly
			(pts
				(xy -0.4953 -0.2032) (xy 0.4953 -0.2032) (xy 0.4953 1.6002) (xy -0.4953 1.6002)
			)
			(stroke
				(width 0)
				(type default)
			)
			(fill no)
			(layer "F.CrtYd")
		)
		(fp_line
			(start -0.4953 -0.2032)
			(end 0.4953 -0.2032)
			(stroke
				(width 0.1)
				(type default)
			)
			(layer "F.Fab")
		)
		(fp_line
			(start -0.4953 1.6002)
			(end -0.4953 -0.2032)
			(stroke
				(width 0.1)
				(type default)
			)
			(layer "F.Fab")
		)
		(fp_line
			(start 0.4953 -0.2032)
			(end 0.4953 1.6002)
			(stroke
				(width 0.1)
				(type default)
			)
			(layer "F.Fab")
		)
		(fp_line
			(start 0.4953 1.6002)
			(end -0.4953 1.6002)
			(stroke
				(width 0.1)
				(type default)
			)
			(layer "F.Fab")
		)
		(pad "1" smd rect
			(at 0 0)
			(size 0.762 0.889)
			(layers "F.Cu" "F.Mask" "F.Paste")
			(net "PVSA_CPU0")
		)
		(pad "2" smd rect
			(at 0 1.397)
			(size 0.762 0.889)
			(layers "F.Cu" "F.Mask" "F.Paste")
			(net "GND")
		)
		(zone
			(layer "F.Cu")
			(hatch none 0.5)
			(connect_pads
				(clearance 0)
			)
			(min_thickness 0.25)
			(keepout
				(tracks not_allowed)
				(vias allowed)
				(pads allowed)
				(copperpour not_allowed)
				(footprints allowed)
			)
			(placement
				(enabled no)
				(sheetname "")
			)
			(fill
				(thermal_gap 0.5)
				(thermal_bridge_width 0.5)
				(island_removal_mode 0)
			)
			(polygon
				(pts
					(xy 259.071872 -81.128616) (xy 259.833872 -81.128616) (xy 259.833872 -80.620616) (xy 259.071872 -80.620616)
				)
			)
		)
	)
	(footprint ""
		(layer "F.Cu")
		(at 171.6532 -8.6868 90)
		(property "Reference" "R4G4"
			(at 0 0 90)
			(layer "F.SilkS")
			(hide yes)
			(effects
				(font
					(size 1.27 1.27)
				)
			)
		)
		(property "Value" ""
			(at 0 0 90)
			(layer "F.Fab")
			(effects
				(font
					(size 1.27 1.27)
				)
			)
		)
		(duplicate_pad_numbers_are_jumpers no)
		(fp_poly
			(pts
				(xy -0.2794 -0.1016) (xy 0.2794 -0.1016) (xy 0.2794 0.9906) (xy -0.2794 0.9906)
			)
			(stroke
				(width 0)
				(type default)
			)
			(fill no)
			(layer "F.CrtYd")
		)
		(fp_line
			(start 0.2794 -0.1016)
			(end -0.2794 -0.1016)
			(stroke
				(width 0.1)
				(type default)
			)
			(layer "F.Fab")
		)
		(fp_line
			(start -0.2794 -0.1016)
			(end -0.2794 0.9906)
			(stroke
				(width 0.1)
				(type default)
			)
			(layer "F.Fab")
		)
		(fp_line
			(start 0.2794 0.9906)
			(end 0.2794 -0.1016)
			(stroke
				(width 0.1)
				(type default)
			)
			(layer "F.Fab")
		)
		(fp_line
			(start -0.2794 0.9906)
			(end 0.2794 0.9906)
			(stroke
				(width 0.1)
				(type default)
			)
			(layer "F.Fab")
		)
		(pad "1" smd rect
			(at 0 0 90)
			(size 0.508 0.508)
			(layers "F.Cu" "F.Mask" "F.Paste")
			(net "FM_PVPP_CPU1_EN")
		)
		(pad "2" smd rect
			(at 0 0.889 90)
			(size 0.508 0.508)
			(layers "F.Cu" "F.Mask" "F.Paste")
			(net "FM_PVPP_PVDDQ_CPU1_EN_GHJ")
		)
		(zone
			(layer "F.Cu")
			(hatch none 0.5)
			(connect_pads
				(clearance 0)
			)
			(min_thickness 0.25)
			(keepout
				(tracks allowed)
				(vias not_allowed)
				(pads allowed)
				(copperpour not_allowed)
				(footprints allowed)
			)
			(placement
				(enabled no)
				(sheetname "")
			)
			(fill
				(thermal_gap 0.5)
				(thermal_bridge_width 0.5)
				(island_removal_mode 0)
			)
			(polygon
				(pts
					(xy 171.9072 -8.4328) (xy 171.9072 -8.9408) (xy 172.2882 -8.9408) (xy 172.2882 -8.4328)
				)
			)
		)
		(zone
			(layer "F.Cu")
			(hatch none 0.5)
			(connect_pads
				(clearance 0)
			)
			(min_thickness 0.25)
			(keepout
				(tracks not_allowed)
				(vias allowed)
				(pads allowed)
				(copperpour not_allowed)
				(footprints allowed)
			)
			(placement
				(enabled no)
				(sheetname "")
			)
			(fill
				(thermal_gap 0.5)
				(thermal_bridge_width 0.5)
				(island_removal_mode 0)
			)
			(polygon
				(pts
					(xy 172.2882 -8.4328) (xy 172.2882 -8.9408) (xy 171.9072 -8.9408) (xy 171.9072 -8.4328)
				)
			)
		)
	)
	(footprint ""
		(layer "F.Cu")
		(at 414.410652 -135.636)
		(property "Reference" "R8A14"
			(at 0 0 0)
			(layer "F.SilkS")
			(hide yes)
			(effects
				(font
					(size 1.27 1.27)
				)
			)
		)
		(property "Value" ""
			(at 0 0 0)
			(layer "F.Fab")
			(effects
				(font
					(size 1.27 1.27)
				)
			)
		)
		(duplicate_pad_numbers_are_jumpers no)
		(fp_poly
			(pts
				(xy -0.2794 -0.1016) (xy 0.2794 -0.1016) (xy 0.2794 0.9906) (xy -0.2794 0.9906)
			)
			(stroke
				(width 0)
				(type default)
			)
			(fill no)
			(layer "F.CrtYd")
		)
		(fp_line
			(start -0.2794 -0.1016)
			(end -0.2794 0.9906)
			(stroke
				(width 0.1)
				(type default)
			)
			(layer "F.Fab")
		)
		(fp_line
			(start -0.2794 0.9906)
			(end 0.2794 0.9906)
			(stroke
				(width 0.1)
				(type default)
			)
			(layer "F.Fab")
		)
		(fp_line
			(start 0.2794 -0.1016)
			(end -0.2794 -0.1016)
			(stroke
				(width 0.1)
				(type default)
			)
			(layer "F.Fab")
		)
		(fp_line
			(start 0.2794 0.9906)
			(end 0.2794 -0.1016)
			(stroke
				(width 0.1)
				(type default)
			)
			(layer "F.Fab")
		)
		(pad "1" smd rect
			(at 0 0)
			(size 0.508 0.508)
			(layers "F.Cu" "F.Mask" "F.Paste")
			(net "P1V05_PCH_STBY")
		)
		(pad "2" smd rect
			(at 0 0.889)
			(size 0.508 0.508)
			(layers "F.Cu" "F.Mask" "F.Paste")
			(net "XDP_TMS")
		)
		(zone
			(layer "F.Cu")
			(hatch none 0.5)
			(connect_pads
				(clearance 0)
			)
			(min_thickness 0.25)
			(keepout
				(tracks allowed)
				(vias not_allowed)
				(pads allowed)
				(copperpour not_allowed)
				(footprints allowed)
			)
			(placement
				(enabled no)
				(sheetname "")
			)
			(fill
				(thermal_gap 0.5)
				(thermal_bridge_width 0.5)
				(island_removal_mode 0)
			)
			(polygon
				(pts
					(xy 414.156652 -135.382) (xy 414.664652 -135.382) (xy 414.664652 -135.001) (xy 414.156652 -135.001)
				)
			)
		)
		(zone
			(layer "F.Cu")
			(hatch none 0.5)
			(connect_pads
				(clearance 0)
			)
			(min_thickness 0.25)
			(keepout
				(tracks not_allowed)
				(vias allowed)
				(pads allowed)
				(copperpour not_allowed)
				(footprints allowed)
			)
			(placement
				(enabled no)
				(sheetname "")
			)
			(fill
				(thermal_gap 0.5)
				(thermal_bridge_width 0.5)
				(island_removal_mode 0)
			)
			(polygon
				(pts
					(xy 414.156652 -135.001) (xy 414.664652 -135.001) (xy 414.664652 -135.382) (xy 414.156652 -135.382)
				)
			)
		)
	)
	(footprint ""
		(layer "F.Cu")
		(at 406.273 -128.3335)
		(property "Reference" "C8B1"
			(at 0 0 0)
			(layer "F.SilkS")
			(hide yes)
			(effects
				(font
					(size 1.27 1.27)
				)
			)
		)
		(property "Value" ""
			(at 0 0 0)
			(layer "F.Fab")
			(effects
				(font
					(size 1.27 1.27)
				)
			)
		)
		(duplicate_pad_numbers_are_jumpers no)
		(fp_poly
			(pts
				(xy -0.4953 -0.2032) (xy 0.4953 -0.2032) (xy 0.4953 1.6002) (xy -0.4953 1.6002)
			)
			(stroke
				(width 0)
				(type default)
			)
			(fill no)
			(layer "F.CrtYd")
		)
		(fp_line
			(start -0.4953 -0.2032)
			(end 0.4953 -0.2032)
			(stroke
				(width 0.1)
				(type default)
			)
			(layer "F.Fab")
		)
		(fp_line
			(start -0.4953 1.6002)
			(end -0.4953 -0.2032)
			(stroke
				(width 0.1)
				(type default)
			)
			(layer "F.Fab")
		)
		(fp_line
			(start 0.4953 -0.2032)
			(end 0.4953 1.6002)
			(stroke
				(width 0.1)
				(type default)
			)
			(layer "F.Fab")
		)
		(fp_line
			(start 0.4953 1.6002)
			(end -0.4953 1.6002)
			(stroke
				(width 0.1)
				(type default)
			)
			(layer "F.Fab")
		)
		(pad "1" smd rect
			(at 0 0)
			(size 0.762 0.889)
			(layers "F.Cu" "F.Mask" "F.Paste")
			(net "P1V8_PCH_STBY")
		)
		(pad "2" smd rect
			(at 0 1.397)
			(size 0.762 0.889)
			(layers "F.Cu" "F.Mask" "F.Paste")
			(net "GND")
		)
		(zone
			(layer "F.Cu")
			(hatch none 0.5)
			(connect_pads
				(clearance 0)
			)
			(min_thickness 0.25)
			(keepout
				(tracks not_allowed)
				(vias allowed)
				(pads allowed)
				(copperpour not_allowed)
				(footprints allowed)
			)
			(placement
				(enabled no)
				(sheetname "")
			)
			(fill
				(thermal_gap 0.5)
				(thermal_bridge_width 0.5)
				(island_removal_mode 0)
			)
			(polygon
				(pts
					(xy 405.892 -127.889) (xy 406.654 -127.889) (xy 406.654 -127.381) (xy 405.892 -127.381)
				)
			)
		)
	)
	(footprint ""
		(layer "F.Cu")
		(at 423.506646 -48.968152)
		(property "Reference" "R25W104"
			(at -0.8382 -0.67818 0)
			(unlocked yes)
			(layer "F.SilkS")
			(effects
				(font
					(size 0.4064 0.254)
					(thickness 0.1524)
				)
				(justify left)
			)
		)
		(property "Value" ""
			(at 0 0 0)
			(layer "F.Fab")
			(effects
				(font
					(size 1.27 1.27)
				)
			)
		)
		(duplicate_pad_numbers_are_jumpers no)
		(fp_poly
			(pts
				(xy -0.2794 -0.1016) (xy 0.2794 -0.1016) (xy 0.2794 0.9906) (xy -0.2794 0.9906)
			)
			(stroke
				(width 0)
				(type default)
			)
			(fill no)
			(layer "F.CrtYd")
		)
		(fp_line
			(start -0.2794 -0.1016)
			(end -0.2794 0.9906)
			(stroke
				(width 0.1)
				(type default)
			)
			(layer "F.Fab")
		)
		(fp_line
			(start -0.2794 0.9906)
			(end 0.2794 0.9906)
			(stroke
				(width 0.1)
				(type default)
			)
			(layer "F.Fab")
		)
		(fp_line
			(start 0.2794 -0.1016)
			(end -0.2794 -0.1016)
			(stroke
				(width 0.1)
				(type default)
			)
			(layer "F.Fab")
		)
		(fp_line
			(start 0.2794 0.9906)
			(end 0.2794 -0.1016)
			(stroke
				(width 0.1)
				(type default)
			)
			(layer "F.Fab")
		)
		(pad "1" smd rect
			(at 0 0)
			(size 0.508 0.508)
			(layers "F.Cu" "F.Mask" "F.Paste")
			(net "P3V3_STBY")
		)
		(pad "2" smd rect
			(at 0 0.889)
			(size 0.508 0.508)
			(layers "F.Cu" "F.Mask" "F.Paste")
			(net "BMC_STRAP_BIT27")
		)
		(zone
			(layer "F.Cu")
			(hatch none 0.5)
			(connect_pads
				(clearance 0)
			)
			(min_thickness 0.25)
			(keepout
				(tracks allowed)
				(vias not_allowed)
				(pads allowed)
				(copperpour not_allowed)
				(footprints allowed)
			)
			(placement
				(enabled no)
				(sheetname "")
			)
			(fill
				(thermal_gap 0.5)
				(thermal_bridge_width 0.5)
				(island_removal_mode 0)
			)
			(polygon
				(pts
					(xy 423.252646 -48.714152) (xy 423.760646 -48.714152) (xy 423.760646 -48.333152) (xy 423.252646 -48.333152)
				)
			)
		)
		(zone
			(layer "F.Cu")
			(hatch none 0.5)
			(connect_pads
				(clearance 0)
			)
			(min_thickness 0.25)
			(keepout
				(tracks not_allowed)
				(vias allowed)
				(pads allowed)
				(copperpour not_allowed)
				(footprints allowed)
			)
			(placement
				(enabled no)
				(sheetname "")
			)
			(fill
				(thermal_gap 0.5)
				(thermal_bridge_width 0.5)
				(island_removal_mode 0)
			)
			(polygon
				(pts
					(xy 423.252646 -48.333152) (xy 423.760646 -48.333152) (xy 423.760646 -48.714152) (xy 423.252646 -48.714152)
				)
			)
		)
	)
	(footprint ""
		(layer "F.Cu")
		(at 164.211 -68.1482 90)
		(property "Reference" "R4D54"
			(at 0 0 90)
			(layer "F.SilkS")
			(hide yes)
			(effects
				(font
					(size 1.27 1.27)
				)
			)
		)
		(property "Value" ""
			(at 0 0 90)
			(layer "F.Fab")
			(effects
				(font
					(size 1.27 1.27)
				)
			)
		)
		(duplicate_pad_numbers_are_jumpers no)
		(fp_poly
			(pts
				(xy -0.2794 -0.1016) (xy 0.2794 -0.1016) (xy 0.2794 0.9906) (xy -0.2794 0.9906)
			)
			(stroke
				(width 0)
				(type default)
			)
			(fill no)
			(layer "F.CrtYd")
		)
		(fp_line
			(start 0.2794 -0.1016)
			(end -0.2794 -0.1016)
			(stroke
				(width 0.1)
				(type default)
			)
			(layer "F.Fab")
		)
		(fp_line
			(start -0.2794 -0.1016)
			(end -0.2794 0.9906)
			(stroke
				(width 0.1)
				(type default)
			)
			(layer "F.Fab")
		)
		(fp_line
			(start 0.2794 0.9906)
			(end 0.2794 -0.1016)
			(stroke
				(width 0.1)
				(type default)
			)
			(layer "F.Fab")
		)
		(fp_line
			(start -0.2794 0.9906)
			(end 0.2794 0.9906)
			(stroke
				(width 0.1)
				(type default)
			)
			(layer "F.Fab")
		)
		(pad "1" smd rect
			(at 0 0 90)
			(size 0.508 0.508)
			(layers "F.Cu" "F.Mask" "F.Paste")
			(net "SVID_DIO0_CPU1_R")
		)
		(pad "2" smd rect
			(at 0 0.889 90)
			(size 0.508 0.508)
			(layers "F.Cu" "F.Mask" "F.Paste")
			(net "SVID_VDIO_PVCCIO_CPU1")
		)
		(zone
			(layer "F.Cu")
			(hatch none 0.5)
			(connect_pads
				(clearance 0)
			)
			(min_thickness 0.25)
			(keepout
				(tracks allowed)
				(vias not_allowed)
				(pads allowed)
				(copperpour not_allowed)
				(footprints allowed)
			)
			(placement
				(enabled no)
				(sheetname "")
			)
			(fill
				(thermal_gap 0.5)
				(thermal_bridge_width 0.5)
				(island_removal_mode 0)
			)
			(polygon
				(pts
					(xy 164.465 -67.8942) (xy 164.465 -68.4022) (xy 164.846 -68.4022) (xy 164.846 -67.8942)
				)
			)
		)
		(zone
			(layer "F.Cu")
			(hatch none 0.5)
			(connect_pads
				(clearance 0)
			)
			(min_thickness 0.25)
			(keepout
				(tracks not_allowed)
				(vias allowed)
				(pads allowed)
				(copperpour not_allowed)
				(footprints allowed)
			)
			(placement
				(enabled no)
				(sheetname "")
			)
			(fill
				(thermal_gap 0.5)
				(thermal_bridge_width 0.5)
				(island_removal_mode 0)
			)
			(polygon
				(pts
					(xy 164.846 -67.8942) (xy 164.846 -68.4022) (xy 164.465 -68.4022) (xy 164.465 -67.8942)
				)
			)
		)
	)
	(footprint ""
		(layer "F.Cu")
		(at 192.6463 -82.209132 90)
		(property "Reference" "RT28"
			(at 1.01473 0.656336 0)
			(unlocked yes)
			(layer "F.SilkS")
			(effects
				(font
					(size 0.4064 0.254)
					(thickness 0.1524)
				)
			)
		)
		(property "Value" ""
			(at 0 0 90)
			(layer "F.Fab")
			(effects
				(font
					(size 1.27 1.27)
				)
			)
		)
		(duplicate_pad_numbers_are_jumpers no)
		(fp_poly
			(pts
				(xy -0.4953 -0.2032) (xy 0.4953 -0.2032) (xy 0.4953 1.6002) (xy -0.4953 1.6002)
			)
			(stroke
				(width 0)
				(type default)
			)
			(fill no)
			(layer "F.CrtYd")
		)
		(fp_line
			(start 0.4953 -0.2032)
			(end 0.4953 1.6002)
			(stroke
				(width 0.1)
				(type default)
			)
			(layer "F.Fab")
		)
		(fp_line
			(start -0.4953 -0.2032)
			(end 0.4953 -0.2032)
			(stroke
				(width 0.1)
				(type default)
			)
			(layer "F.Fab")
		)
		(fp_line
			(start 0.4953 1.6002)
			(end -0.4953 1.6002)
			(stroke
				(width 0.1)
				(type default)
			)
			(layer "F.Fab")
		)
		(fp_line
			(start -0.4953 1.6002)
			(end -0.4953 -0.2032)
			(stroke
				(width 0.1)
				(type default)
			)
			(layer "F.Fab")
		)
		(pad "1" smd rect
			(at 0 0 90)
			(size 0.762 0.889)
			(layers "F.Cu" "F.Mask" "F.Paste")
			(net "VR_PVCCIN_CPU0_PH4_BOOT")
		)
		(pad "2" smd rect
			(at 0 1.397 90)
			(size 0.762 0.889)
			(layers "F.Cu" "F.Mask" "F.Paste")
			(net "VR_PVCCIN_CPU0_PH4_BOOT_R")
		)
		(zone
			(layer "F.Cu")
			(hatch none 0.5)
			(connect_pads
				(clearance 0)
			)
			(min_thickness 0.25)
			(keepout
				(tracks allowed)
				(vias not_allowed)
				(pads allowed)
				(copperpour not_allowed)
				(footprints allowed)
			)
			(placement
				(enabled no)
				(sheetname "")
			)
			(fill
				(thermal_gap 0.5)
				(thermal_bridge_width 0.5)
				(island_removal_mode 0)
			)
			(polygon
				(pts
					(xy 193.5988 -82.590132) (xy 193.0908 -82.590132) (xy 193.0908 -81.828132) (xy 193.5988 -81.828132)
				)
			)
		)
		(zone
			(layer "F.Cu")
			(hatch none 0.5)
			(connect_pads
				(clearance 0)
			)
			(min_thickness 0.25)
			(keepout
				(tracks not_allowed)
				(vias allowed)
				(pads allowed)
				(copperpour not_allowed)
				(footprints allowed)
			)
			(placement
				(enabled no)
				(sheetname "")
			)
			(fill
				(thermal_gap 0.5)
				(thermal_bridge_width 0.5)
				(island_removal_mode 0)
			)
			(polygon
				(pts
					(xy 193.5988 -81.828132) (xy 193.5988 -82.590132) (xy 193.0908 -82.590132) (xy 193.0908 -81.828132)
				)
			)
		)
	)
	(footprint ""
		(layer "F.Cu")
		(at 403.606 4.0894 90)
		(property "Reference" "R8G7"
			(at 0 0 90)
			(layer "F.SilkS")
			(hide yes)
			(effects
				(font
					(size 1.27 1.27)
				)
			)
		)
		(property "Value" ""
			(at 0 0 90)
			(layer "F.Fab")
			(effects
				(font
					(size 1.27 1.27)
				)
			)
		)
		(duplicate_pad_numbers_are_jumpers no)
		(fp_poly
			(pts
				(xy -0.2794 -0.1016) (xy 0.2794 -0.1016) (xy 0.2794 0.9906) (xy -0.2794 0.9906)
			)
			(stroke
				(width 0)
				(type default)
			)
			(fill no)
			(layer "F.CrtYd")
		)
		(fp_line
			(start 0.2794 -0.1016)
			(end -0.2794 -0.1016)
			(stroke
				(width 0.1)
				(type default)
			)
			(layer "F.Fab")
		)
		(fp_line
			(start -0.2794 -0.1016)
			(end -0.2794 0.9906)
			(stroke
				(width 0.1)
				(type default)
			)
			(layer "F.Fab")
		)
		(fp_line
			(start 0.2794 0.9906)
			(end 0.2794 -0.1016)
			(stroke
				(width 0.1)
				(type default)
			)
			(layer "F.Fab")
		)
		(fp_line
			(start -0.2794 0.9906)
			(end 0.2794 0.9906)
			(stroke
				(width 0.1)
				(type default)
			)
			(layer "F.Fab")
		)
		(pad "1" smd rect
			(at 0 0 90)
			(size 0.508 0.508)
			(layers "F.Cu" "F.Mask" "F.Paste")
			(net "JTAG_PLD_TDI")
		)
		(pad "2" smd rect
			(at 0 0.889 90)
			(size 0.508 0.508)
			(layers "F.Cu" "F.Mask" "F.Paste")
			(net "JTAG_PLD_TDI_MUX")
		)
		(zone
			(layer "F.Cu")
			(hatch none 0.5)
			(connect_pads
				(clearance 0)
			)
			(min_thickness 0.25)
			(keepout
				(tracks allowed)
				(vias not_allowed)
				(pads allowed)
				(copperpour not_allowed)
				(footprints allowed)
			)
			(placement
				(enabled no)
				(sheetname "")
			)
			(fill
				(thermal_gap 0.5)
				(thermal_bridge_width 0.5)
				(island_removal_mode 0)
			)
			(polygon
				(pts
					(xy 403.86 4.3434) (xy 403.86 3.8354) (xy 404.241 3.8354) (xy 404.241 4.3434)
				)
			)
		)
		(zone
			(layer "F.Cu")
			(hatch none 0.5)
			(connect_pads
				(clearance 0)
			)
			(min_thickness 0.25)
			(keepout
				(tracks not_allowed)
				(vias allowed)
				(pads allowed)
				(copperpour not_allowed)
				(footprints allowed)
			)
			(placement
				(enabled no)
				(sheetname "")
			)
			(fill
				(thermal_gap 0.5)
				(thermal_bridge_width 0.5)
				(island_removal_mode 0)
			)
			(polygon
				(pts
					(xy 404.241 4.3434) (xy 404.241 3.8354) (xy 403.86 3.8354) (xy 403.86 4.3434)
				)
			)
		)
	)
	(footprint ""
		(layer "F.Cu")
		(at 187.833 -75.057 -90)
		(property "Reference" "CF6"
			(at 0 0 270)
			(layer "F.SilkS")
			(hide yes)
			(effects
				(font
					(size 1.27 1.27)
				)
			)
		)
		(property "Value" "*"
			(at 1.1811 -2.8194 270)
			(unlocked yes)
			(layer "F.Fab")
			(hide yes)
			(effects
				(font
					(size 1.27 1.016)
					(thickness 0.1524)
				)
			)
		)
		(property "Device Type" "SC22P50V2JN-4GP_SMD-BCG-SC22P5A"
			(at 1.1811 -4.3434 270)
			(unlocked yes)
			(layer "F.Fab")
			(hide yes)
			(effects
				(font
					(size 1.27 1.016)
					(thickness 0.1524)
				)
			)
		)
		(duplicate_pad_numbers_are_jumpers no)
		(fp_rect
			(start -0.4318 0.9525)
			(end 0.4318 -0.9525)
			(stroke
				(width 0)
				(type default)
			)
			(fill no)
			(layer "F.CrtYd")
		)
		(fp_rect
			(start -0.4318 0.9525)
			(end 0.4318 -0.9525)
			(stroke
				(width 0)
				(type default)
			)
			(fill no)
			(layer "F.Fab")
		)
		(pad "1" smd custom
			(at 0 -0.4445 270)
			(size 0.1524 0.1524)
			(layers "F.Cu" "F.Mask" "F.Paste")
			(net "VR_PVSA_CPU0_BIREF1")
			(options
				(clearance outline)
				(anchor circle)
			)
			(primitives
				(gr_poly
					(pts
						(arc
							(start 0.3048 -0.2032)
							(mid 0.275042 -0.275042)
							(end 0.2032 -0.3048)
						)
						(arc
							(start -0.2032 -0.3048)
							(mid -0.275042 -0.275042)
							(end -0.3048 -0.2032)
						)
						(arc
							(start -0.3048 0.2032)
							(mid -0.275042 0.275042)
							(end -0.2032 0.3048)
						)
						(arc
							(start 0.2032 0.3048)
							(mid 0.275042 0.275042)
							(end 0.3048 0.2032)
						)
					)
					(width 0)
					(fill yes)
				)
			)
		)
		(pad "2" smd custom
			(at 0 0.4445 270)
			(size 0.1524 0.1524)
			(layers "F.Cu" "F.Mask" "F.Paste")
			(net "ISENSE_PVSA_CPU0_IMON")
			(options
				(clearance outline)
				(anchor circle)
			)
			(primitives
				(gr_poly
					(pts
						(arc
							(start 0.3048 -0.2032)
							(mid 0.275042 -0.275042)
							(end 0.2032 -0.3048)
						)
						(arc
							(start -0.2032 -0.3048)
							(mid -0.275042 -0.275042)
							(end -0.3048 -0.2032)
						)
						(arc
							(start -0.3048 0.2032)
							(mid -0.275042 0.275042)
							(end -0.2032 0.3048)
						)
						(arc
							(start 0.2032 0.3048)
							(mid 0.275042 0.275042)
							(end 0.3048 0.2032)
						)
					)
					(width 0)
					(fill yes)
				)
			)
		)
	)
	(footprint ""
		(layer "F.Cu")
		(at 265.675872 -73.318116)
		(property "Reference" "C5D45"
			(at 0 0 0)
			(layer "F.SilkS")
			(hide yes)
			(effects
				(font
					(size 1.27 1.27)
				)
			)
		)
		(property "Value" ""
			(at 0 0 0)
			(layer "F.Fab")
			(effects
				(font
					(size 1.27 1.27)
				)
			)
		)
		(duplicate_pad_numbers_are_jumpers no)
		(fp_poly
			(pts
				(xy -0.4953 -0.2032) (xy 0.4953 -0.2032) (xy 0.4953 1.6002) (xy -0.4953 1.6002)
			)
			(stroke
				(width 0)
				(type default)
			)
			(fill no)
			(layer "F.CrtYd")
		)
		(fp_line
			(start -0.4953 -0.2032)
			(end 0.4953 -0.2032)
			(stroke
				(width 0.1)
				(type default)
			)
			(layer "F.Fab")
		)
		(fp_line
			(start -0.4953 1.6002)
			(end -0.4953 -0.2032)
			(stroke
				(width 0.1)
				(type default)
			)
			(layer "F.Fab")
		)
		(fp_line
			(start 0.4953 -0.2032)
			(end 0.4953 1.6002)
			(stroke
				(width 0.1)
				(type default)
			)
			(layer "F.Fab")
		)
		(fp_line
			(start 0.4953 1.6002)
			(end -0.4953 1.6002)
			(stroke
				(width 0.1)
				(type default)
			)
			(layer "F.Fab")
		)
		(pad "1" smd rect
			(at 0 0)
			(size 0.762 0.889)
			(layers "F.Cu" "F.Mask" "F.Paste")
			(net "PVCCIN_CPU0")
		)
		(pad "2" smd rect
			(at 0 1.397)
			(size 0.762 0.889)
			(layers "F.Cu" "F.Mask" "F.Paste")
			(net "GND")
		)
		(zone
			(layer "F.Cu")
			(hatch none 0.5)
			(connect_pads
				(clearance 0)
			)
			(min_thickness 0.25)
			(keepout
				(tracks not_allowed)
				(vias allowed)
				(pads allowed)
				(copperpour not_allowed)
				(footprints allowed)
			)
			(placement
				(enabled no)
				(sheetname "")
			)
			(fill
				(thermal_gap 0.5)
				(thermal_bridge_width 0.5)
				(island_removal_mode 0)
			)
			(polygon
				(pts
					(xy 265.294872 -72.873616) (xy 266.056872 -72.873616) (xy 266.056872 -72.365616) (xy 265.294872 -72.365616)
				)
			)
		)
	)
	(footprint ""
		(layer "F.Cu")
		(at 19.220434 -2.643378 -90)
		(property "Reference" "C1G20"
			(at 0 0 270)
			(layer "F.SilkS")
			(hide yes)
			(effects
				(font
					(size 1.27 1.27)
				)
			)
		)
		(property "Value" ""
			(at 0 0 270)
			(layer "F.Fab")
			(effects
				(font
					(size 1.27 1.27)
				)
			)
		)
		(duplicate_pad_numbers_are_jumpers no)
		(fp_rect
			(start -0.7239 -0.2159)
			(end 0.7239 1.9939)
			(stroke
				(width 0)
				(type default)
			)
			(fill no)
			(layer "F.CrtYd")
		)
		(fp_line
			(start -0.7239 1.9939)
			(end 0.7239 1.9939)
			(stroke
				(width 0.1)
				(type default)
			)
			(layer "F.Fab")
		)
		(fp_line
			(start 0.7239 1.9939)
			(end 0.7239 -0.2159)
			(stroke
				(width 0.1)
				(type default)
			)
			(layer "F.Fab")
		)
		(fp_line
			(start -0.7239 -0.2159)
			(end -0.7239 1.9939)
			(stroke
				(width 0.1)
				(type default)
			)
			(layer "F.Fab")
		)
		(fp_line
			(start 0.7239 -0.2159)
			(end -0.7239 -0.2159)
			(stroke
				(width 0.1)
				(type default)
			)
			(layer "F.Fab")
		)
		(pad "1" smd rect
			(at 0 0 270)
			(size 1.27 1.016)
			(layers "F.Cu" "F.Mask" "F.Paste")
			(net "PVDDQ_GHJ")
		)
		(pad "2" smd rect
			(at 0 1.778 270)
			(size 1.27 1.016)
			(layers "F.Cu" "F.Mask" "F.Paste")
			(net "GND")
		)
		(zone
			(layer "F.Cu")
			(hatch none 0.5)
			(connect_pads
				(clearance 0)
			)
			(min_thickness 0.25)
			(keepout
				(tracks not_allowed)
				(vias allowed)
				(pads allowed)
				(copperpour not_allowed)
				(footprints allowed)
			)
			(placement
				(enabled no)
				(sheetname "")
			)
			(fill
				(thermal_gap 0.5)
				(thermal_bridge_width 0.5)
				(island_removal_mode 0)
			)
			(polygon
				(pts
					(xy 18.712434 -3.278378) (xy 17.950434 -3.278378) (xy 17.950434 -2.008378) (xy 18.712434 -2.008378)
				)
			)
		)
	)
	(footprint ""
		(layer "F.Cu")
		(at 261.9502 -79.6036 180)
		(property "Reference" "C5D14"
			(at 0 0 180)
			(layer "F.SilkS")
			(hide yes)
			(effects
				(font
					(size 1.27 1.27)
				)
			)
		)
		(property "Value" ""
			(at 0 0 180)
			(layer "F.Fab")
			(effects
				(font
					(size 1.27 1.27)
				)
			)
		)
		(duplicate_pad_numbers_are_jumpers no)
		(fp_poly
			(pts
				(xy -0.4953 -0.2032) (xy 0.4953 -0.2032) (xy 0.4953 1.6002) (xy -0.4953 1.6002)
			)
			(stroke
				(width 0)
				(type default)
			)
			(fill no)
			(layer "F.CrtYd")
		)
		(fp_line
			(start 0.4953 1.6002)
			(end -0.4953 1.6002)
			(stroke
				(width 0.1)
				(type default)
			)
			(layer "F.Fab")
		)
		(fp_line
			(start 0.4953 -0.2032)
			(end 0.4953 1.6002)
			(stroke
				(width 0.1)
				(type default)
			)
			(layer "F.Fab")
		)
		(fp_line
			(start -0.4953 1.6002)
			(end -0.4953 -0.2032)
			(stroke
				(width 0.1)
				(type default)
			)
			(layer "F.Fab")
		)
		(fp_line
			(start -0.4953 -0.2032)
			(end 0.4953 -0.2032)
			(stroke
				(width 0.1)
				(type default)
			)
			(layer "F.Fab")
		)
		(pad "1" smd rect
			(at 0 0 180)
			(size 0.762 0.889)
			(layers "F.Cu" "F.Mask" "F.Paste")
			(net "PVCCIN_CPU0")
		)
		(pad "2" smd rect
			(at 0 1.397 180)
			(size 0.762 0.889)
			(layers "F.Cu" "F.Mask" "F.Paste")
			(net "GND")
		)
		(zone
			(layer "F.Cu")
			(hatch none 0.5)
			(connect_pads
				(clearance 0)
			)
			(min_thickness 0.25)
			(keepout
				(tracks not_allowed)
				(vias allowed)
				(pads allowed)
				(copperpour not_allowed)
				(footprints allowed)
			)
			(placement
				(enabled no)
				(sheetname "")
			)
			(fill
				(thermal_gap 0.5)
				(thermal_bridge_width 0.5)
				(island_removal_mode 0)
			)
			(polygon
				(pts
					(xy 262.3312 -80.0481) (xy 261.5692 -80.0481) (xy 261.5692 -80.5561) (xy 262.3312 -80.5561)
				)
			)
		)
	)
	(footprint ""
		(layer "F.Cu")
		(at 96.94164 -73.318116)
		(property "Reference" "C2D33"
			(at 0 0 0)
			(layer "F.SilkS")
			(hide yes)
			(effects
				(font
					(size 1.27 1.27)
				)
			)
		)
		(property "Value" ""
			(at 0 0 0)
			(layer "F.Fab")
			(effects
				(font
					(size 1.27 1.27)
				)
			)
		)
		(duplicate_pad_numbers_are_jumpers no)
		(fp_poly
			(pts
				(xy -0.4953 -0.2032) (xy 0.4953 -0.2032) (xy 0.4953 1.6002) (xy -0.4953 1.6002)
			)
			(stroke
				(width 0)
				(type default)
			)
			(fill no)
			(layer "F.CrtYd")
		)
		(fp_line
			(start -0.4953 -0.2032)
			(end 0.4953 -0.2032)
			(stroke
				(width 0.1)
				(type default)
			)
			(layer "F.Fab")
		)
		(fp_line
			(start -0.4953 1.6002)
			(end -0.4953 -0.2032)
			(stroke
				(width 0.1)
				(type default)
			)
			(layer "F.Fab")
		)
		(fp_line
			(start 0.4953 -0.2032)
			(end 0.4953 1.6002)
			(stroke
				(width 0.1)
				(type default)
			)
			(layer "F.Fab")
		)
		(fp_line
			(start 0.4953 1.6002)
			(end -0.4953 1.6002)
			(stroke
				(width 0.1)
				(type default)
			)
			(layer "F.Fab")
		)
		(pad "1" smd rect
			(at 0 0)
			(size 0.762 0.889)
			(layers "F.Cu" "F.Mask" "F.Paste")
			(net "PVCCIN_CPU1")
		)
		(pad "2" smd rect
			(at 0 1.397)
			(size 0.762 0.889)
			(layers "F.Cu" "F.Mask" "F.Paste")
			(net "GND")
		)
		(zone
			(layer "F.Cu")
			(hatch none 0.5)
			(connect_pads
				(clearance 0)
			)
			(min_thickness 0.25)
			(keepout
				(tracks not_allowed)
				(vias allowed)
				(pads allowed)
				(copperpour not_allowed)
				(footprints allowed)
			)
			(placement
				(enabled no)
				(sheetname "")
			)
			(fill
				(thermal_gap 0.5)
				(thermal_bridge_width 0.5)
				(island_removal_mode 0)
			)
			(polygon
				(pts
					(xy 96.56064 -72.873616) (xy 97.32264 -72.873616) (xy 97.32264 -72.365616) (xy 96.56064 -72.365616)
				)
			)
		)
	)
	(footprint ""
		(layer "F.Cu")
		(at 193.675 -23.396194)
		(property "Reference" "R4F4"
			(at 0 0 0)
			(layer "F.SilkS")
			(hide yes)
			(effects
				(font
					(size 1.27 1.27)
				)
			)
		)
		(property "Value" ""
			(at 0 0 0)
			(layer "F.Fab")
			(effects
				(font
					(size 1.27 1.27)
				)
			)
		)
		(duplicate_pad_numbers_are_jumpers no)
		(fp_poly
			(pts
				(xy -0.2794 -0.1016) (xy 0.2794 -0.1016) (xy 0.2794 0.9906) (xy -0.2794 0.9906)
			)
			(stroke
				(width 0)
				(type default)
			)
			(fill no)
			(layer "F.CrtYd")
		)
		(fp_line
			(start -0.2794 -0.1016)
			(end -0.2794 0.9906)
			(stroke
				(width 0.1)
				(type default)
			)
			(layer "F.Fab")
		)
		(fp_line
			(start -0.2794 0.9906)
			(end 0.2794 0.9906)
			(stroke
				(width 0.1)
				(type default)
			)
			(layer "F.Fab")
		)
		(fp_line
			(start 0.2794 -0.1016)
			(end -0.2794 -0.1016)
			(stroke
				(width 0.1)
				(type default)
			)
			(layer "F.Fab")
		)
		(fp_line
			(start 0.2794 0.9906)
			(end 0.2794 -0.1016)
			(stroke
				(width 0.1)
				(type default)
			)
			(layer "F.Fab")
		)
		(pad "1" smd rect
			(at 0 0)
			(size 0.508 0.508)
			(layers "F.Cu" "F.Mask" "F.Paste")
			(net "PVDDQ_ABC")
		)
		(pad "2" smd rect
			(at 0 0.889)
			(size 0.508 0.508)
			(layers "F.Cu" "F.Mask" "F.Paste")
			(net "M_A_VREF")
		)
		(zone
			(layer "F.Cu")
			(hatch none 0.5)
			(connect_pads
				(clearance 0)
			)
			(min_thickness 0.25)
			(keepout
				(tracks allowed)
				(vias not_allowed)
				(pads allowed)
				(copperpour not_allowed)
				(footprints allowed)
			)
			(placement
				(enabled no)
				(sheetname "")
			)
			(fill
				(thermal_gap 0.5)
				(thermal_bridge_width 0.5)
				(island_removal_mode 0)
			)
			(polygon
				(pts
					(xy 193.421 -23.142194) (xy 193.929 -23.142194) (xy 193.929 -22.761194) (xy 193.421 -22.761194)
				)
			)
		)
		(zone
			(layer "F.Cu")
			(hatch none 0.5)
			(connect_pads
				(clearance 0)
			)
			(min_thickness 0.25)
			(keepout
				(tracks not_allowed)
				(vias allowed)
				(pads allowed)
				(copperpour not_allowed)
				(footprints allowed)
			)
			(placement
				(enabled no)
				(sheetname "")
			)
			(fill
				(thermal_gap 0.5)
				(thermal_bridge_width 0.5)
				(island_removal_mode 0)
			)
			(polygon
				(pts
					(xy 193.421 -22.761194) (xy 193.929 -22.761194) (xy 193.929 -23.142194) (xy 193.421 -23.142194)
				)
			)
		)
	)
	(footprint ""
		(layer "F.Cu")
		(at 386.2451 -68.8848 180)
		(property "Reference" "C7E13"
			(at 0 0 180)
			(layer "F.SilkS")
			(hide yes)
			(effects
				(font
					(size 1.27 1.27)
				)
			)
		)
		(property "Value" "*"
			(at -0.0762 -6.2357 180)
			(unlocked yes)
			(layer "F.Fab")
			(hide yes)
			(effects
				(font
					(size 1.27 1.016)
					(thickness 0.1524)
				)
			)
		)
		(property "Device Type" "SC22U16V5MX-4-GP_SMD-BCG5-SC22A"
			(at -0.0762 -8.2677 180)
			(unlocked yes)
			(layer "F.Fab")
			(hide yes)
			(effects
				(font
					(size 1.27 1.016)
					(thickness 0.1524)
				)
			)
		)
		(duplicate_pad_numbers_are_jumpers no)
		(fp_line
			(start 0.635 0)
			(end -0.635 0)
			(stroke
				(width 0.508)
				(type default)
			)
			(layer "F.SilkS")
		)
		(fp_rect
			(start -0.9652 1.778)
			(end 0.9652 -1.778)
			(stroke
				(width 0)
				(type default)
			)
			(fill no)
			(layer "F.CrtYd")
		)
		(fp_poly
			(pts
				(xy -0.9652 -1.778) (xy 0.9652 -1.778) (xy 0.9652 1.778) (xy -0.9652 1.778)
			)
			(stroke
				(width 0)
				(type default)
			)
			(fill no)
			(layer "F.Fab")
		)
		(pad "1" smd rect
			(at 0 -0.9652 180)
			(size 1.397 1.143)
			(layers "F.Cu" "F.Mask" "F.Paste")
			(net "VR_FET_SW_P5V_STBY_PVIN")
		)
		(pad "2" smd rect
			(at 0 0.9652 180)
			(size 1.397 1.143)
			(layers "F.Cu" "F.Mask" "F.Paste")
			(net "GND")
		)
	)
	(footprint ""
		(layer "F.Cu")
		(at 94.45244 -77.636116)
		(property "Reference" "C2D20"
			(at 0 0 0)
			(layer "F.SilkS")
			(hide yes)
			(effects
				(font
					(size 1.27 1.27)
				)
			)
		)
		(property "Value" ""
			(at 0 0 0)
			(layer "F.Fab")
			(effects
				(font
					(size 1.27 1.27)
				)
			)
		)
		(duplicate_pad_numbers_are_jumpers no)
		(fp_poly
			(pts
				(xy -0.4953 -0.2032) (xy 0.4953 -0.2032) (xy 0.4953 1.6002) (xy -0.4953 1.6002)
			)
			(stroke
				(width 0)
				(type default)
			)
			(fill no)
			(layer "F.CrtYd")
		)
		(fp_line
			(start -0.4953 -0.2032)
			(end 0.4953 -0.2032)
			(stroke
				(width 0.1)
				(type default)
			)
			(layer "F.Fab")
		)
		(fp_line
			(start -0.4953 1.6002)
			(end -0.4953 -0.2032)
			(stroke
				(width 0.1)
				(type default)
			)
			(layer "F.Fab")
		)
		(fp_line
			(start 0.4953 -0.2032)
			(end 0.4953 1.6002)
			(stroke
				(width 0.1)
				(type default)
			)
			(layer "F.Fab")
		)
		(fp_line
			(start 0.4953 1.6002)
			(end -0.4953 1.6002)
			(stroke
				(width 0.1)
				(type default)
			)
			(layer "F.Fab")
		)
		(pad "1" smd rect
			(at 0 0)
			(size 0.762 0.889)
			(layers "F.Cu" "F.Mask" "F.Paste")
			(net "PVCCIN_CPU1")
		)
		(pad "2" smd rect
			(at 0 1.397)
			(size 0.762 0.889)
			(layers "F.Cu" "F.Mask" "F.Paste")
			(net "GND")
		)
		(zone
			(layer "F.Cu")
			(hatch none 0.5)
			(connect_pads
				(clearance 0)
			)
			(min_thickness 0.25)
			(keepout
				(tracks not_allowed)
				(vias allowed)
				(pads allowed)
				(copperpour not_allowed)
				(footprints allowed)
			)
			(placement
				(enabled no)
				(sheetname "")
			)
			(fill
				(thermal_gap 0.5)
				(thermal_bridge_width 0.5)
				(island_removal_mode 0)
			)
			(polygon
				(pts
					(xy 94.07144 -77.191616) (xy 94.83344 -77.191616) (xy 94.83344 -76.683616) (xy 94.07144 -76.683616)
				)
			)
		)
	)
	(footprint ""
		(layer "F.Cu")
		(at 99.43084 -77.636116)
		(property "Reference" "C2D24"
			(at 0 0 0)
			(layer "F.SilkS")
			(hide yes)
			(effects
				(font
					(size 1.27 1.27)
				)
			)
		)
		(property "Value" ""
			(at 0 0 0)
			(layer "F.Fab")
			(effects
				(font
					(size 1.27 1.27)
				)
			)
		)
		(duplicate_pad_numbers_are_jumpers no)
		(fp_poly
			(pts
				(xy -0.4953 -0.2032) (xy 0.4953 -0.2032) (xy 0.4953 1.6002) (xy -0.4953 1.6002)
			)
			(stroke
				(width 0)
				(type default)
			)
			(fill no)
			(layer "F.CrtYd")
		)
		(fp_line
			(start -0.4953 -0.2032)
			(end 0.4953 -0.2032)
			(stroke
				(width 0.1)
				(type default)
			)
			(layer "F.Fab")
		)
		(fp_line
			(start -0.4953 1.6002)
			(end -0.4953 -0.2032)
			(stroke
				(width 0.1)
				(type default)
			)
			(layer "F.Fab")
		)
		(fp_line
			(start 0.4953 -0.2032)
			(end 0.4953 1.6002)
			(stroke
				(width 0.1)
				(type default)
			)
			(layer "F.Fab")
		)
		(fp_line
			(start 0.4953 1.6002)
			(end -0.4953 1.6002)
			(stroke
				(width 0.1)
				(type default)
			)
			(layer "F.Fab")
		)
		(pad "1" smd rect
			(at 0 0)
			(size 0.762 0.889)
			(layers "F.Cu" "F.Mask" "F.Paste")
			(net "PVCCIN_CPU1")
		)
		(pad "2" smd rect
			(at 0 1.397)
			(size 0.762 0.889)
			(layers "F.Cu" "F.Mask" "F.Paste")
			(net "GND")
		)
		(zone
			(layer "F.Cu")
			(hatch none 0.5)
			(connect_pads
				(clearance 0)
			)
			(min_thickness 0.25)
			(keepout
				(tracks not_allowed)
				(vias allowed)
				(pads allowed)
				(copperpour not_allowed)
				(footprints allowed)
			)
			(placement
				(enabled no)
				(sheetname "")
			)
			(fill
				(thermal_gap 0.5)
				(thermal_bridge_width 0.5)
				(island_removal_mode 0)
			)
			(polygon
				(pts
					(xy 99.04984 -77.191616) (xy 99.81184 -77.191616) (xy 99.81184 -76.683616) (xy 99.04984 -76.683616)
				)
			)
		)
	)
	(footprint ""
		(layer "F.Cu")
		(at 170.815 -70.6374 180)
		(property "Reference" "C4D31"
			(at 0 0 180)
			(layer "F.SilkS")
			(hide yes)
			(effects
				(font
					(size 1.27 1.27)
				)
			)
		)
		(property "Value" ""
			(at 0 0 180)
			(layer "F.Fab")
			(effects
				(font
					(size 1.27 1.27)
				)
			)
		)
		(duplicate_pad_numbers_are_jumpers no)
		(fp_poly
			(pts
				(xy 0.3048 -0.1016) (xy 0.3048 0.9906) (xy -0.3048 0.9906) (xy -0.3048 -0.1016)
			)
			(stroke
				(width 0)
				(type default)
			)
			(fill no)
			(layer "F.CrtYd")
		)
		(fp_line
			(start 0.3048 0.9906)
			(end 0.3048 -0.1016)
			(stroke
				(width 0.1)
				(type default)
			)
			(layer "F.Fab")
		)
		(fp_line
			(start 0.3048 -0.1016)
			(end -0.3048 -0.1016)
			(stroke
				(width 0.1)
				(type default)
			)
			(layer "F.Fab")
		)
		(fp_line
			(start -0.3048 0.9906)
			(end 0.3048 0.9906)
			(stroke
				(width 0.1)
				(type default)
			)
			(layer "F.Fab")
		)
		(fp_line
			(start -0.3048 -0.1016)
			(end -0.3048 0.9906)
			(stroke
				(width 0.1)
				(type default)
			)
			(layer "F.Fab")
		)
		(pad "1" smd rect
			(at 0 0 180)
			(size 0.508 0.508)
			(layers "F.Cu" "F.Mask" "F.Paste")
			(net "VR_PVCCIO_CPU1_VD12")
		)
		(pad "2" smd rect
			(at 0 0.889 180)
			(size 0.508 0.508)
			(layers "F.Cu" "F.Mask" "F.Paste")
			(net "GND")
		)
		(zone
			(layer "F.Cu")
			(hatch none 0.5)
			(connect_pads
				(clearance 0)
			)
			(min_thickness 0.25)
			(keepout
				(tracks not_allowed)
				(vias allowed)
				(pads allowed)
				(copperpour not_allowed)
				(footprints allowed)
			)
			(placement
				(enabled no)
				(sheetname "")
			)
			(fill
				(thermal_gap 0.5)
				(thermal_bridge_width 0.5)
				(island_removal_mode 0)
			)
			(polygon
				(pts
					(xy 171.069 -71.2724) (xy 170.561 -71.2724) (xy 170.561 -70.8914) (xy 171.069 -70.8914)
				)
			)
		)
		(zone
			(layer "F.Cu")
			(hatch none 0.5)
			(connect_pads
				(clearance 0)
			)
			(min_thickness 0.25)
			(keepout
				(tracks allowed)
				(vias not_allowed)
				(pads allowed)
				(copperpour not_allowed)
				(footprints allowed)
			)
			(placement
				(enabled no)
				(sheetname "")
			)
			(fill
				(thermal_gap 0.5)
				(thermal_bridge_width 0.5)
				(island_removal_mode 0)
			)
			(polygon
				(pts
					(xy 171.069 -70.8914) (xy 170.561 -70.8914) (xy 170.561 -71.2724) (xy 171.069 -71.2724)
				)
			)
		)
	)
	(footprint ""
		(layer "F.Cu")
		(at 390.398 -63.6905 180)
		(property "Reference" "R7F1"
			(at 0 0 180)
			(layer "F.SilkS")
			(hide yes)
			(effects
				(font
					(size 1.27 1.27)
				)
			)
		)
		(property "Value" ""
			(at 0 0 180)
			(layer "F.Fab")
			(effects
				(font
					(size 1.27 1.27)
				)
			)
		)
		(duplicate_pad_numbers_are_jumpers no)
		(fp_poly
			(pts
				(xy -0.2794 -0.1016) (xy 0.2794 -0.1016) (xy 0.2794 0.9906) (xy -0.2794 0.9906)
			)
			(stroke
				(width 0)
				(type default)
			)
			(fill no)
			(layer "F.CrtYd")
		)
		(fp_line
			(start 0.2794 0.9906)
			(end 0.2794 -0.1016)
			(stroke
				(width 0.1)
				(type default)
			)
			(layer "F.Fab")
		)
		(fp_line
			(start 0.2794 -0.1016)
			(end -0.2794 -0.1016)
			(stroke
				(width 0.1)
				(type default)
			)
			(layer "F.Fab")
		)
		(fp_line
			(start -0.2794 0.9906)
			(end 0.2794 0.9906)
			(stroke
				(width 0.1)
				(type default)
			)
			(layer "F.Fab")
		)
		(fp_line
			(start -0.2794 -0.1016)
			(end -0.2794 0.9906)
			(stroke
				(width 0.1)
				(type default)
			)
			(layer "F.Fab")
		)
		(pad "1" smd rect
			(at 0 0 180)
			(size 0.508 0.508)
			(layers "F.Cu" "F.Mask" "F.Paste")
			(net "VR_P5V_STBY_VSENSE_R")
		)
		(pad "2" smd rect
			(at 0 0.889 180)
			(size 0.508 0.508)
			(layers "F.Cu" "F.Mask" "F.Paste")
			(net "VR_P5V_STBY_VSENSE")
		)
		(zone
			(layer "F.Cu")
			(hatch none 0.5)
			(connect_pads
				(clearance 0)
			)
			(min_thickness 0.25)
			(keepout
				(tracks not_allowed)
				(vias allowed)
				(pads allowed)
				(copperpour not_allowed)
				(footprints allowed)
			)
			(placement
				(enabled no)
				(sheetname "")
			)
			(fill
				(thermal_gap 0.5)
				(thermal_bridge_width 0.5)
				(island_removal_mode 0)
			)
			(polygon
				(pts
					(xy 390.652 -64.3255) (xy 390.144 -64.3255) (xy 390.144 -63.9445) (xy 390.652 -63.9445)
				)
			)
		)
		(zone
			(layer "F.Cu")
			(hatch none 0.5)
			(connect_pads
				(clearance 0)
			)
			(min_thickness 0.25)
			(keepout
				(tracks allowed)
				(vias not_allowed)
				(pads allowed)
				(copperpour not_allowed)
				(footprints allowed)
			)
			(placement
				(enabled no)
				(sheetname "")
			)
			(fill
				(thermal_gap 0.5)
				(thermal_bridge_width 0.5)
				(island_removal_mode 0)
			)
			(polygon
				(pts
					(xy 390.652 -63.9445) (xy 390.144 -63.9445) (xy 390.144 -64.3255) (xy 390.652 -64.3255)
				)
			)
		)
	)
	(footprint ""
		(layer "F.Cu")
		(at 419.6207 -104.267 90)
		(property "Reference" "R6W26"
			(at -0.8382 -0.67818 90)
			(unlocked yes)
			(layer "F.SilkS")
			(effects
				(font
					(size 0.4064 0.254)
					(thickness 0.1524)
				)
				(justify left)
			)
		)
		(property "Value" ""
			(at 0 0 90)
			(layer "F.Fab")
			(effects
				(font
					(size 1.27 1.27)
				)
			)
		)
		(duplicate_pad_numbers_are_jumpers no)
		(fp_poly
			(pts
				(xy -0.2794 -0.1016) (xy 0.2794 -0.1016) (xy 0.2794 0.9906) (xy -0.2794 0.9906)
			)
			(stroke
				(width 0)
				(type default)
			)
			(fill no)
			(layer "F.CrtYd")
		)
		(fp_line
			(start 0.2794 -0.1016)
			(end -0.2794 -0.1016)
			(stroke
				(width 0.1)
				(type default)
			)
			(layer "F.Fab")
		)
		(fp_line
			(start -0.2794 -0.1016)
			(end -0.2794 0.9906)
			(stroke
				(width 0.1)
				(type default)
			)
			(layer "F.Fab")
		)
		(fp_line
			(start 0.2794 0.9906)
			(end 0.2794 -0.1016)
			(stroke
				(width 0.1)
				(type default)
			)
			(layer "F.Fab")
		)
		(fp_line
			(start -0.2794 0.9906)
			(end 0.2794 0.9906)
			(stroke
				(width 0.1)
				(type default)
			)
			(layer "F.Fab")
		)
		(pad "1" smd rect
			(at 0 0 90)
			(size 0.508 0.508)
			(layers "F.Cu" "F.Mask" "F.Paste")
			(net "SMB_CPU0_PE_HP_GTL_SCL")
		)
		(pad "2" smd rect
			(at 0 0.889 90)
			(size 0.508 0.508)
			(layers "F.Cu" "F.Mask" "F.Paste")
			(net "SMB_CPU0_PE_HP_GTL_R_SCL")
		)
		(zone
			(layer "F.Cu")
			(hatch none 0.5)
			(connect_pads
				(clearance 0)
			)
			(min_thickness 0.25)
			(keepout
				(tracks allowed)
				(vias not_allowed)
				(pads allowed)
				(copperpour not_allowed)
				(footprints allowed)
			)
			(placement
				(enabled no)
				(sheetname "")
			)
			(fill
				(thermal_gap 0.5)
				(thermal_bridge_width 0.5)
				(island_removal_mode 0)
			)
			(polygon
				(pts
					(xy 419.8747 -104.013) (xy 419.8747 -104.521) (xy 420.2557 -104.521) (xy 420.2557 -104.013)
				)
			)
		)
		(zone
			(layer "F.Cu")
			(hatch none 0.5)
			(connect_pads
				(clearance 0)
			)
			(min_thickness 0.25)
			(keepout
				(tracks not_allowed)
				(vias allowed)
				(pads allowed)
				(copperpour not_allowed)
				(footprints allowed)
			)
			(placement
				(enabled no)
				(sheetname "")
			)
			(fill
				(thermal_gap 0.5)
				(thermal_bridge_width 0.5)
				(island_removal_mode 0)
			)
			(polygon
				(pts
					(xy 420.2557 -104.013) (xy 420.2557 -104.521) (xy 419.8747 -104.521) (xy 419.8747 -104.013)
				)
			)
		)
	)
	(footprint ""
		(layer "F.Cu")
		(at 204.5462 -85.4456 -90)
		(property "Reference" "CT35"
			(at -0.8382 -0.67818 270)
			(unlocked yes)
			(layer "F.SilkS")
			(effects
				(font
					(size 0.4064 0.254)
					(thickness 0.1524)
				)
				(justify left)
			)
		)
		(property "Value" ""
			(at 0 0 270)
			(layer "F.Fab")
			(effects
				(font
					(size 1.27 1.27)
				)
			)
		)
		(duplicate_pad_numbers_are_jumpers no)
		(fp_poly
			(pts
				(xy 0.3048 -0.1016) (xy 0.3048 0.9906) (xy -0.3048 0.9906) (xy -0.3048 -0.1016)
			)
			(stroke
				(width 0)
				(type default)
			)
			(fill no)
			(layer "F.CrtYd")
		)
		(fp_line
			(start -0.3048 0.9906)
			(end 0.3048 0.9906)
			(stroke
				(width 0.1)
				(type default)
			)
			(layer "F.Fab")
		)
		(fp_line
			(start 0.3048 0.9906)
			(end 0.3048 -0.1016)
			(stroke
				(width 0.1)
				(type default)
			)
			(layer "F.Fab")
		)
		(fp_line
			(start -0.3048 -0.1016)
			(end -0.3048 0.9906)
			(stroke
				(width 0.1)
				(type default)
			)
			(layer "F.Fab")
		)
		(fp_line
			(start 0.3048 -0.1016)
			(end -0.3048 -0.1016)
			(stroke
				(width 0.1)
				(type default)
			)
			(layer "F.Fab")
		)
		(pad "1" smd rect
			(at 0 0 270)
			(size 0.508 0.508)
			(layers "F.Cu" "F.Mask" "F.Paste")
			(net "VR_PVCCIN_CPU0_PHASE5")
		)
		(pad "2" smd rect
			(at 0 0.889 270)
			(size 0.508 0.508)
			(layers "F.Cu" "F.Mask" "F.Paste")
			(net "VR_PVCCIN_CPU0_PHASE5_RC")
		)
		(zone
			(layer "F.Cu")
			(hatch none 0.5)
			(connect_pads
				(clearance 0)
			)
			(min_thickness 0.25)
			(keepout
				(tracks not_allowed)
				(vias allowed)
				(pads allowed)
				(copperpour not_allowed)
				(footprints allowed)
			)
			(placement
				(enabled no)
				(sheetname "")
			)
			(fill
				(thermal_gap 0.5)
				(thermal_bridge_width 0.5)
				(island_removal_mode 0)
			)
			(polygon
				(pts
					(xy 203.9112 -85.6996) (xy 203.9112 -85.1916) (xy 204.2922 -85.1916) (xy 204.2922 -85.6996)
				)
			)
		)
		(zone
			(layer "F.Cu")
			(hatch none 0.5)
			(connect_pads
				(clearance 0)
			)
			(min_thickness 0.25)
			(keepout
				(tracks allowed)
				(vias not_allowed)
				(pads allowed)
				(copperpour not_allowed)
				(footprints allowed)
			)
			(placement
				(enabled no)
				(sheetname "")
			)
			(fill
				(thermal_gap 0.5)
				(thermal_bridge_width 0.5)
				(island_removal_mode 0)
			)
			(polygon
				(pts
					(xy 204.2922 -85.6996) (xy 204.2922 -85.1916) (xy 203.9112 -85.1916) (xy 203.9112 -85.6996)
				)
			)
		)
	)
	(footprint ""
		(layer "F.Cu")
		(at 403.86 -123.7742 90)
		(property "Reference" "R8B32"
			(at 0 0 90)
			(layer "F.SilkS")
			(hide yes)
			(effects
				(font
					(size 1.27 1.27)
				)
			)
		)
		(property "Value" ""
			(at 0 0 90)
			(layer "F.Fab")
			(effects
				(font
					(size 1.27 1.27)
				)
			)
		)
		(duplicate_pad_numbers_are_jumpers no)
		(fp_poly
			(pts
				(xy -0.2794 -0.1016) (xy 0.2794 -0.1016) (xy 0.2794 0.9906) (xy -0.2794 0.9906)
			)
			(stroke
				(width 0)
				(type default)
			)
			(fill no)
			(layer "F.CrtYd")
		)
		(fp_line
			(start 0.2794 -0.1016)
			(end -0.2794 -0.1016)
			(stroke
				(width 0.1)
				(type default)
			)
			(layer "F.Fab")
		)
		(fp_line
			(start -0.2794 -0.1016)
			(end -0.2794 0.9906)
			(stroke
				(width 0.1)
				(type default)
			)
			(layer "F.Fab")
		)
		(fp_line
			(start 0.2794 0.9906)
			(end 0.2794 -0.1016)
			(stroke
				(width 0.1)
				(type default)
			)
			(layer "F.Fab")
		)
		(fp_line
			(start -0.2794 0.9906)
			(end 0.2794 0.9906)
			(stroke
				(width 0.1)
				(type default)
			)
			(layer "F.Fab")
		)
		(pad "1" smd rect
			(at 0 0 90)
			(size 0.508 0.508)
			(layers "F.Cu" "F.Mask" "F.Paste")
			(net "A_USB2_VBUS")
		)
		(pad "2" smd rect
			(at 0 0.889 90)
			(size 0.508 0.508)
			(layers "F.Cu" "F.Mask" "F.Paste")
			(net "GND")
		)
		(zone
			(layer "F.Cu")
			(hatch none 0.5)
			(connect_pads
				(clearance 0)
			)
			(min_thickness 0.25)
			(keepout
				(tracks allowed)
				(vias not_allowed)
				(pads allowed)
				(copperpour not_allowed)
				(footprints allowed)
			)
			(placement
				(enabled no)
				(sheetname "")
			)
			(fill
				(thermal_gap 0.5)
				(thermal_bridge_width 0.5)
				(island_removal_mode 0)
			)
			(polygon
				(pts
					(xy 404.114 -123.5202) (xy 404.114 -124.0282) (xy 404.495 -124.0282) (xy 404.495 -123.5202)
				)
			)
		)
		(zone
			(layer "F.Cu")
			(hatch none 0.5)
			(connect_pads
				(clearance 0)
			)
			(min_thickness 0.25)
			(keepout
				(tracks not_allowed)
				(vias allowed)
				(pads allowed)
				(copperpour not_allowed)
				(footprints allowed)
			)
			(placement
				(enabled no)
				(sheetname "")
			)
			(fill
				(thermal_gap 0.5)
				(thermal_bridge_width 0.5)
				(island_removal_mode 0)
			)
			(polygon
				(pts
					(xy 404.495 -123.5202) (xy 404.495 -124.0282) (xy 404.114 -124.0282) (xy 404.114 -123.5202)
				)
			)
		)
	)
	(footprint ""
		(layer "F.Cu")
		(at 384.048 -64.2874 180)
		(property "Reference" "FB7E1"
			(at -1.48717 0.635 270)
			(unlocked yes)
			(layer "F.SilkS")
			(effects
				(font
					(size 0.7874 0.5842)
					(thickness 0.1524)
				)
			)
		)
		(property "Value" ""
			(at 0 0 180)
			(layer "F.Fab")
			(effects
				(font
					(size 1.27 1.27)
				)
			)
		)
		(duplicate_pad_numbers_are_jumpers no)
		(fp_poly
			(pts
				(xy -0.7239 -0.26035) (xy 0.7239 -0.26035) (xy 0.7239 2.03835) (xy -0.7239 2.03835)
			)
			(stroke
				(width 0)
				(type default)
			)
			(fill no)
			(layer "F.CrtYd")
		)
		(fp_line
			(start 0.7239 2.03835)
			(end -0.7239 2.03835)
			(stroke
				(width 0.1)
				(type default)
			)
			(layer "F.Fab")
		)
		(fp_line
			(start 0.7239 -0.26035)
			(end 0.7239 2.03835)
			(stroke
				(width 0.1)
				(type default)
			)
			(layer "F.Fab")
		)
		(fp_line
			(start -0.7239 2.03835)
			(end -0.7239 -0.26035)
			(stroke
				(width 0.1)
				(type default)
			)
			(layer "F.Fab")
		)
		(fp_line
			(start -0.7239 -0.26035)
			(end 0.7239 -0.26035)
			(stroke
				(width 0.1)
				(type default)
			)
			(layer "F.Fab")
		)
		(pad "1" smd rect
			(at 0 0 180)
			(size 1.27 1.016)
			(layers "F.Cu" "F.Mask" "F.Paste")
			(net "P12V_STBY")
		)
		(pad "2" smd rect
			(at 0 1.778 180)
			(size 1.27 1.016)
			(layers "F.Cu" "F.Mask" "F.Paste")
			(net "VR_FET_SW_P5V_STBY_PVIN")
		)
		(zone
			(layer "F.Cu")
			(hatch none 0.5)
			(connect_pads
				(clearance 0)
			)
			(min_thickness 0.25)
			(keepout
				(tracks not_allowed)
				(vias allowed)
				(pads allowed)
				(copperpour not_allowed)
				(footprints allowed)
			)
			(placement
				(enabled no)
				(sheetname "")
			)
			(fill
				(thermal_gap 0.5)
				(thermal_bridge_width 0.5)
				(island_removal_mode 0)
			)
			(polygon
				(pts
					(xy 383.413 -64.7954) (xy 383.413 -65.5574) (xy 383.5019 -65.5574) (xy 384.683 -65.5574) (xy 384.683 -64.7954)
				)
			)
		)
	)
	(footprint ""
		(layer "F.Cu")
		(at 411.0355 -112.395 -90)
		(property "Reference" "R8C2"
			(at 0 0 270)
			(layer "F.SilkS")
			(hide yes)
			(effects
				(font
					(size 1.27 1.27)
				)
			)
		)
		(property "Value" ""
			(at 0 0 270)
			(layer "F.Fab")
			(effects
				(font
					(size 1.27 1.27)
				)
			)
		)
		(duplicate_pad_numbers_are_jumpers no)
		(fp_poly
			(pts
				(xy -0.2794 -0.1016) (xy 0.2794 -0.1016) (xy 0.2794 0.9906) (xy -0.2794 0.9906)
			)
			(stroke
				(width 0)
				(type default)
			)
			(fill no)
			(layer "F.CrtYd")
		)
		(fp_line
			(start -0.2794 0.9906)
			(end 0.2794 0.9906)
			(stroke
				(width 0.1)
				(type default)
			)
			(layer "F.Fab")
		)
		(fp_line
			(start 0.2794 0.9906)
			(end 0.2794 -0.1016)
			(stroke
				(width 0.1)
				(type default)
			)
			(layer "F.Fab")
		)
		(fp_line
			(start -0.2794 -0.1016)
			(end -0.2794 0.9906)
			(stroke
				(width 0.1)
				(type default)
			)
			(layer "F.Fab")
		)
		(fp_line
			(start 0.2794 -0.1016)
			(end -0.2794 -0.1016)
			(stroke
				(width 0.1)
				(type default)
			)
			(layer "F.Fab")
		)
		(pad "1" smd rect
			(at 0 0 270)
			(size 0.508 0.508)
			(layers "F.Cu" "F.Mask" "F.Paste")
			(net "P3V3_STBY")
		)
		(pad "2" smd rect
			(at 0 0.889 270)
			(size 0.508 0.508)
			(layers "F.Cu" "F.Mask" "F.Paste")
			(net "IRQ_BMC_PCH_SCI_LPC_N")
		)
		(zone
			(layer "F.Cu")
			(hatch none 0.5)
			(connect_pads
				(clearance 0)
			)
			(min_thickness 0.25)
			(keepout
				(tracks not_allowed)
				(vias allowed)
				(pads allowed)
				(copperpour not_allowed)
				(footprints allowed)
			)
			(placement
				(enabled no)
				(sheetname "")
			)
			(fill
				(thermal_gap 0.5)
				(thermal_bridge_width 0.5)
				(island_removal_mode 0)
			)
			(polygon
				(pts
					(xy 410.4005 -112.649) (xy 410.4005 -112.141) (xy 410.7815 -112.141) (xy 410.7815 -112.649)
				)
			)
		)
		(zone
			(layer "F.Cu")
			(hatch none 0.5)
			(connect_pads
				(clearance 0)
			)
			(min_thickness 0.25)
			(keepout
				(tracks allowed)
				(vias not_allowed)
				(pads allowed)
				(copperpour not_allowed)
				(footprints allowed)
			)
			(placement
				(enabled no)
				(sheetname "")
			)
			(fill
				(thermal_gap 0.5)
				(thermal_bridge_width 0.5)
				(island_removal_mode 0)
			)
			(polygon
				(pts
					(xy 410.7815 -112.649) (xy 410.7815 -112.141) (xy 410.4005 -112.141) (xy 410.4005 -112.649)
				)
			)
		)
	)
	(footprint ""
		(layer "F.Cu")
		(at 13.8938 -27.686 90)
		(property "Reference" "C1F14"
			(at 0 0 90)
			(layer "F.SilkS")
			(hide yes)
			(effects
				(font
					(size 1.27 1.27)
				)
			)
		)
		(property "Value" ""
			(at 0 0 90)
			(layer "F.Fab")
			(effects
				(font
					(size 1.27 1.27)
				)
			)
		)
		(duplicate_pad_numbers_are_jumpers no)
		(fp_rect
			(start -0.3048 -0.1016)
			(end 0.3048 0.9906)
			(stroke
				(width 0)
				(type default)
			)
			(fill no)
			(layer "F.CrtYd")
		)
		(fp_line
			(start 0.3048 -0.1016)
			(end -0.3048 -0.1016)
			(stroke
				(width 0.1)
				(type default)
			)
			(layer "F.Fab")
		)
		(fp_line
			(start -0.3048 -0.1016)
			(end -0.3048 0.9906)
			(stroke
				(width 0.1)
				(type default)
			)
			(layer "F.Fab")
		)
		(fp_line
			(start 0.3048 0.9906)
			(end 0.3048 -0.1016)
			(stroke
				(width 0.1)
				(type default)
			)
			(layer "F.Fab")
		)
		(fp_line
			(start -0.3048 0.9906)
			(end 0.3048 0.9906)
			(stroke
				(width 0.1)
				(type default)
			)
			(layer "F.Fab")
		)
		(pad "1" smd rect
			(at 0 0 90)
			(size 0.508 0.508)
			(layers "F.Cu" "F.Mask" "F.Paste")
			(net "P3E_CPU1_PE3_MP_C_TXP<2>")
		)
		(pad "2" smd rect
			(at 0 0.889 90)
			(size 0.508 0.508)
			(layers "F.Cu" "F.Mask" "F.Paste")
			(net "P3E_CPU1_PE3_MP_TXP<2>")
		)
		(zone
			(layer "F.Cu")
			(hatch none 0.5)
			(connect_pads
				(clearance 0)
			)
			(min_thickness 0.25)
			(keepout
				(tracks allowed)
				(vias not_allowed)
				(pads allowed)
				(copperpour not_allowed)
				(footprints allowed)
			)
			(placement
				(enabled no)
				(sheetname "")
			)
			(fill
				(thermal_gap 0.5)
				(thermal_bridge_width 0.5)
				(island_removal_mode 0)
			)
			(polygon
				(pts
					(xy 14.1478 -27.432) (xy 14.5288 -27.432) (xy 14.5288 -27.94) (xy 14.1478 -27.94)
				)
			)
		)
		(zone
			(layer "F.Cu")
			(hatch none 0.5)
			(connect_pads
				(clearance 0)
			)
			(min_thickness 0.25)
			(keepout
				(tracks not_allowed)
				(vias allowed)
				(pads allowed)
				(copperpour not_allowed)
				(footprints allowed)
			)
			(placement
				(enabled no)
				(sheetname "")
			)
			(fill
				(thermal_gap 0.5)
				(thermal_bridge_width 0.5)
				(island_removal_mode 0)
			)
			(polygon
				(pts
					(xy 14.1478 -27.432) (xy 14.5288 -27.432) (xy 14.5288 -27.94) (xy 14.1478 -27.94)
				)
			)
		)
	)
	(footprint ""
		(layer "F.Cu")
		(at 450.461634 -141.30909 180)
		(property "Reference" "U25W10"
			(at 2.159 -1.57988 180)
			(unlocked yes)
			(layer "F.SilkS")
			(effects
				(font
					(size 0.4064 0.254)
					(thickness 0.1524)
				)
				(justify left)
			)
		)
		(property "Value" ""
			(at 0 0 180)
			(layer "F.Fab")
			(effects
				(font
					(size 1.27 1.27)
				)
			)
		)
		(duplicate_pad_numbers_are_jumpers no)
		(fp_line
			(start 4.4323 4.52628)
			(end 1.5367 4.52628)
			(stroke
				(width 0.1524)
				(type default)
			)
			(layer "F.SilkS")
		)
		(fp_line
			(start 4.4323 -0.64008)
			(end 4.4323 4.52628)
			(stroke
				(width 0.1524)
				(type default)
			)
			(layer "F.SilkS")
		)
		(fp_line
			(start 3.302 0.49022)
			(end 3.302 -0.64008)
			(stroke
				(width 0.1524)
				(type default)
			)
			(layer "F.SilkS")
		)
		(fp_line
			(start 2.667 0.49022)
			(end 3.302 0.49022)
			(stroke
				(width 0.1524)
				(type default)
			)
			(layer "F.SilkS")
		)
		(fp_line
			(start 2.667 -0.64008)
			(end 2.667 0.49022)
			(stroke
				(width 0.1524)
				(type default)
			)
			(layer "F.SilkS")
		)
		(fp_line
			(start 1.5367 4.52628)
			(end 1.5367 -0.64008)
			(stroke
				(width 0.1524)
				(type default)
			)
			(layer "F.SilkS")
		)
		(fp_line
			(start 1.5367 -0.64008)
			(end 4.4323 -0.64008)
			(stroke
				(width 0.1524)
				(type default)
			)
			(layer "F.SilkS")
		)
		(fp_circle
			(center -1.612138 -0.684784)
			(end -1.739138 -0.684784)
			(stroke
				(width 0.254)
				(type default)
			)
			(fill no)
			(layer "F.SilkS")
		)
		(fp_poly
			(pts
				(xy 0.7366 4.54152) (xy 0.7366 -0.64008) (xy 4.7244 -0.64008) (xy 5.2324 -0.64008) (xy 5.2324 4.54152)
				(xy 4.7244 4.54152)
			)
			(stroke
				(width 0)
				(type default)
			)
			(fill no)
			(layer "F.CrtYd")
		)
		(fp_line
			(start 5.2324 4.54152)
			(end 0.7366 4.54152)
			(stroke
				(width 0.1)
				(type default)
			)
			(layer "F.Fab")
		)
		(fp_line
			(start 5.2324 -0.64008)
			(end 5.2324 4.54152)
			(stroke
				(width 0.1)
				(type default)
			)
			(layer "F.Fab")
		)
		(fp_line
			(start 3.302 0.49022)
			(end 3.302 -0.64008)
			(stroke
				(width 0.1)
				(type default)
			)
			(layer "F.Fab")
		)
		(fp_line
			(start 2.667 0.49022)
			(end 3.302 0.49022)
			(stroke
				(width 0.1)
				(type default)
			)
			(layer "F.Fab")
		)
		(fp_line
			(start 2.667 -0.64008)
			(end 2.667 0.49022)
			(stroke
				(width 0.1)
				(type default)
			)
			(layer "F.Fab")
		)
		(fp_line
			(start 0.7366 4.54152)
			(end 0.7366 -0.64008)
			(stroke
				(width 0.1)
				(type default)
			)
			(layer "F.Fab")
		)
		(fp_line
			(start 0.7366 -0.64008)
			(end 5.2324 -0.64008)
			(stroke
				(width 0.1)
				(type default)
			)
			(layer "F.Fab")
		)
		(fp_circle
			(center -1.612138 -0.684784)
			(end -1.739138 -0.684784)
			(stroke
				(width 0.254)
				(type default)
			)
			(fill no)
			(layer "F.Fab")
		)
		(pad "1" smd rect
			(at 0 0 180)
			(size 2.159 0.381)
			(layers "F.Cu" "F.Mask" "F.Paste")
			(net "PU_GTL2014_3_DIR")
		)
		(pad "2" smd rect
			(at 0 0.65024 180)
			(size 2.159 0.381)
			(layers "F.Cu" "F.Mask" "F.Paste")
			(net "XDP_PREQ_N")
		)
		(pad "3" smd rect
			(at 0 1.30048 180)
			(size 2.159 0.381)
			(layers "F.Cu" "F.Mask" "F.Paste")
			(net "XDP_CPU_PWR_DEBUG_N")
		)
		(pad "4" smd rect
			(at 0 1.95072 180)
			(size 2.159 0.381)
			(layers "F.Cu" "F.Mask" "F.Paste")
			(net "PD_GTL2014_3_VREF")
		)
		(pad "5" smd rect
			(at 0 2.60096 180)
			(size 2.159 0.381)
			(layers "F.Cu" "F.Mask" "F.Paste")
			(net "XDP_TDI_R")
		)
		(pad "6" smd rect
			(at 0 3.2512 180)
			(size 2.159 0.381)
			(layers "F.Cu" "F.Mask" "F.Paste")
			(net "XDP_TMS_R")
		)
		(pad "7" smd rect
			(at 0 3.90144 180)
			(size 2.159 0.381)
			(layers "F.Cu" "F.Mask" "F.Paste")
			(net "GND")
		)
		(pad "8" smd rect
			(at 5.969 3.90144 180)
			(size 2.159 0.381)
			(layers "F.Cu" "F.Mask" "F.Paste")
			(net "GND")
		)
		(pad "9" smd rect
			(at 5.969 3.2512 180)
			(size 2.159 0.381)
			(layers "F.Cu" "F.Mask" "F.Paste")
			(net "JTAG_BMC_BUF_TMS")
		)
		(pad "10" smd rect
			(at 5.969 2.60096 180)
			(size 2.159 0.381)
			(layers "F.Cu" "F.Mask" "F.Paste")
			(net "JTAG_BMC_BUF_TDI")
		)
		(pad "11" smd rect
			(at 5.969 1.95072 180)
			(size 2.159 0.381)
			(layers "F.Cu" "F.Mask" "F.Paste")
			(net "GND")
		)
		(pad "12" smd rect
			(at 5.969 1.30048 180)
			(size 2.159 0.381)
			(layers "F.Cu" "F.Mask" "F.Paste")
			(net "BMC_PWR_DEBUG_BUF_N")
		)
		(pad "13" smd rect
			(at 5.969 0.65024 180)
			(size 2.159 0.381)
			(layers "F.Cu" "F.Mask" "F.Paste")
			(net "BMC_PREQ_BUF_N")
		)
		(pad "14" smd rect
			(at 5.969 0 180)
			(size 2.159 0.381)
			(layers "F.Cu" "F.Mask" "F.Paste")
			(net "P3V3_STBY")
		)
	)
	(footprint ""
		(layer "F.Cu")
		(at 391.55624 -152.008586 -90)
		(property "Reference" "C8A3"
			(at 0 0 270)
			(layer "F.SilkS")
			(hide yes)
			(effects
				(font
					(size 1.27 1.27)
				)
			)
		)
		(property "Value" ""
			(at 0 0 270)
			(layer "F.Fab")
			(effects
				(font
					(size 1.27 1.27)
				)
			)
		)
		(duplicate_pad_numbers_are_jumpers no)
		(fp_poly
			(pts
				(xy 0.3048 -0.1016) (xy 0.3048 0.9906) (xy -0.3048 0.9906) (xy -0.3048 -0.1016)
			)
			(stroke
				(width 0)
				(type default)
			)
			(fill no)
			(layer "F.CrtYd")
		)
		(fp_line
			(start -0.3048 0.9906)
			(end 0.3048 0.9906)
			(stroke
				(width 0.1)
				(type default)
			)
			(layer "F.Fab")
		)
		(fp_line
			(start 0.3048 0.9906)
			(end 0.3048 -0.1016)
			(stroke
				(width 0.1)
				(type default)
			)
			(layer "F.Fab")
		)
		(fp_line
			(start -0.3048 -0.1016)
			(end -0.3048 0.9906)
			(stroke
				(width 0.1)
				(type default)
			)
			(layer "F.Fab")
		)
		(fp_line
			(start 0.3048 -0.1016)
			(end -0.3048 -0.1016)
			(stroke
				(width 0.1)
				(type default)
			)
			(layer "F.Fab")
		)
		(pad "1" smd rect
			(at 0 0 270)
			(size 0.508 0.508)
			(layers "F.Cu" "F.Mask" "F.Paste")
			(net "VR_PVNN_PCH_VINSEN")
		)
		(pad "2" smd rect
			(at 0 0.889 270)
			(size 0.508 0.508)
			(layers "F.Cu" "F.Mask" "F.Paste")
			(net "GND")
		)
		(zone
			(layer "F.Cu")
			(hatch none 0.5)
			(connect_pads
				(clearance 0)
			)
			(min_thickness 0.25)
			(keepout
				(tracks not_allowed)
				(vias allowed)
				(pads allowed)
				(copperpour not_allowed)
				(footprints allowed)
			)
			(placement
				(enabled no)
				(sheetname "")
			)
			(fill
				(thermal_gap 0.5)
				(thermal_bridge_width 0.5)
				(island_removal_mode 0)
			)
			(polygon
				(pts
					(xy 390.92124 -152.262586) (xy 390.92124 -151.754586) (xy 391.30224 -151.754586) (xy 391.30224 -152.262586)
				)
			)
		)
		(zone
			(layer "F.Cu")
			(hatch none 0.5)
			(connect_pads
				(clearance 0)
			)
			(min_thickness 0.25)
			(keepout
				(tracks allowed)
				(vias not_allowed)
				(pads allowed)
				(copperpour not_allowed)
				(footprints allowed)
			)
			(placement
				(enabled no)
				(sheetname "")
			)
			(fill
				(thermal_gap 0.5)
				(thermal_bridge_width 0.5)
				(island_removal_mode 0)
			)
			(polygon
				(pts
					(xy 391.30224 -152.262586) (xy 391.30224 -151.754586) (xy 390.92124 -151.754586) (xy 390.92124 -152.262586)
				)
			)
		)
	)
	(footprint ""
		(layer "F.Cu")
		(at 420.751 -79.614014 180)
		(property "Reference" "U8D3"
			(at 3.09753 1.21666 270)
			(unlocked yes)
			(layer "F.SilkS")
			(effects
				(font
					(size 0.7874 0.5842)
					(thickness 0.1524)
				)
				(justify left)
			)
		)
		(property "Value" ""
			(at 0 0 180)
			(layer "F.Fab")
			(effects
				(font
					(size 1.27 1.27)
				)
			)
		)
		(duplicate_pad_numbers_are_jumpers no)
		(fp_circle
			(center -0.4699 -0.8382)
			(end -0.5969 -0.8382)
			(stroke
				(width 0.254)
				(type default)
			)
			(fill no)
			(layer "F.SilkS")
		)
		(fp_poly
			(pts
				(xy 0.21463 -0.450088) (xy 1.56337 -0.450088) (xy 1.56337 1.75006) (xy 0.21463 1.75006)
			)
			(stroke
				(width 0)
				(type default)
			)
			(fill no)
			(layer "F.CrtYd")
		)
		(fp_line
			(start 1.56337 1.75006)
			(end 0.21463 1.75006)
			(stroke
				(width 0.1)
				(type default)
			)
			(layer "F.Fab")
		)
		(fp_line
			(start 1.56337 -0.450088)
			(end 1.56337 1.75006)
			(stroke
				(width 0.1)
				(type default)
			)
			(layer "F.Fab")
		)
		(fp_line
			(start 0.21463 1.75006)
			(end 0.21463 -0.450088)
			(stroke
				(width 0.1)
				(type default)
			)
			(layer "F.Fab")
		)
		(fp_line
			(start 0.21463 -0.450088)
			(end 1.56337 -0.450088)
			(stroke
				(width 0.1)
				(type default)
			)
			(layer "F.Fab")
		)
		(fp_circle
			(center -0.4699 -0.8382)
			(end -0.5969 -0.8382)
			(stroke
				(width 0.254)
				(type default)
			)
			(fill no)
			(layer "F.Fab")
		)
		(pad "1" smd rect
			(at 0 0 180)
			(size 1.016 0.381)
			(layers "F.Cu" "F.Mask" "F.Paste")
			(net "Net_6471")
		)
		(pad "2" smd rect
			(at 0 0.649986 180)
			(size 1.016 0.381)
			(layers "F.Cu" "F.Mask" "F.Paste")
			(net "IRQ_SML1_PMBUS_ALERT_BUF_N")
		)
		(pad "3" smd rect
			(at 0 1.299972 180)
			(size 1.016 0.381)
			(layers "F.Cu" "F.Mask" "F.Paste")
			(net "GND")
		)
		(pad "4" smd rect
			(at 1.778 1.299972 180)
			(size 1.016 0.381)
			(layers "F.Cu" "F.Mask" "F.Paste")
			(net "IRQ_FORCE_NM_THROTTLE_R_N")
		)
		(pad "5" smd rect
			(at 1.778 0 180)
			(size 1.016 0.381)
			(layers "F.Cu" "F.Mask" "F.Paste")
			(net "P3V3_STBY")
		)
	)
	(footprint ""
		(layer "F.Cu")
		(at 6.9342 -130.302 180)
		(property "Reference" "C1B6"
			(at -0.8382 -0.67818 180)
			(unlocked yes)
			(layer "F.SilkS")
			(effects
				(font
					(size 0.4064 0.254)
					(thickness 0.1524)
				)
				(justify left)
			)
		)
		(property "Value" ""
			(at 0 0 180)
			(layer "F.Fab")
			(effects
				(font
					(size 1.27 1.27)
				)
			)
		)
		(duplicate_pad_numbers_are_jumpers no)
		(fp_poly
			(pts
				(xy 0.3048 -0.1016) (xy 0.3048 0.9906) (xy -0.3048 0.9906) (xy -0.3048 -0.1016)
			)
			(stroke
				(width 0)
				(type default)
			)
			(fill no)
			(layer "F.CrtYd")
		)
		(fp_line
			(start 0.3048 0.9906)
			(end 0.3048 -0.1016)
			(stroke
				(width 0.1)
				(type default)
			)
			(layer "F.Fab")
		)
		(fp_line
			(start 0.3048 -0.1016)
			(end -0.3048 -0.1016)
			(stroke
				(width 0.1)
				(type default)
			)
			(layer "F.Fab")
		)
		(fp_line
			(start -0.3048 0.9906)
			(end 0.3048 0.9906)
			(stroke
				(width 0.1)
				(type default)
			)
			(layer "F.Fab")
		)
		(fp_line
			(start -0.3048 -0.1016)
			(end -0.3048 0.9906)
			(stroke
				(width 0.1)
				(type default)
			)
			(layer "F.Fab")
		)
		(pad "1" smd rect
			(at 0 0 180)
			(size 0.508 0.508)
			(layers "F.Cu" "F.Mask" "F.Paste")
			(net "VR_PVDDQ_KLM_VDD")
		)
		(pad "2" smd rect
			(at 0 0.889 180)
			(size 0.508 0.508)
			(layers "F.Cu" "F.Mask" "F.Paste")
			(net "GND")
		)
		(zone
			(layer "F.Cu")
			(hatch none 0.5)
			(connect_pads
				(clearance 0)
			)
			(min_thickness 0.25)
			(keepout
				(tracks not_allowed)
				(vias allowed)
				(pads allowed)
				(copperpour not_allowed)
				(footprints allowed)
			)
			(placement
				(enabled no)
				(sheetname "")
			)
			(fill
				(thermal_gap 0.5)
				(thermal_bridge_width 0.5)
				(island_removal_mode 0)
			)
			(polygon
				(pts
					(xy 7.1882 -130.937) (xy 6.6802 -130.937) (xy 6.6802 -130.556) (xy 7.1882 -130.556)
				)
			)
		)
		(zone
			(layer "F.Cu")
			(hatch none 0.5)
			(connect_pads
				(clearance 0)
			)
			(min_thickness 0.25)
			(keepout
				(tracks allowed)
				(vias not_allowed)
				(pads allowed)
				(copperpour not_allowed)
				(footprints allowed)
			)
			(placement
				(enabled no)
				(sheetname "")
			)
			(fill
				(thermal_gap 0.5)
				(thermal_bridge_width 0.5)
				(island_removal_mode 0)
			)
			(polygon
				(pts
					(xy 7.1882 -130.556) (xy 6.6802 -130.556) (xy 6.6802 -130.937) (xy 7.1882 -130.937)
				)
			)
		)
	)
	(footprint ""
		(layer "F.Cu")
		(at 441.119006 -41.663874 180)
		(property "Reference" "R25W5"
			(at 0 0 180)
			(layer "F.SilkS")
			(hide yes)
			(effects
				(font
					(size 1.27 1.27)
				)
			)
		)
		(property "Value" "*"
			(at 0.064008 -4.108196 180)
			(unlocked yes)
			(layer "F.Fab")
			(hide yes)
			(effects
				(font
					(size 1.27 1.016)
					(thickness 0.1524)
				)
			)
		)
		(property "Device Type" "120R2F-GP_RCL_GP-120R2F-GP,64.A"
			(at 0.064008 -5.632196 180)
			(unlocked yes)
			(layer "F.Fab")
			(hide yes)
			(effects
				(font
					(size 1.27 1.016)
					(thickness 0.1524)
				)
			)
		)
		(duplicate_pad_numbers_are_jumpers no)
		(fp_line
			(start 0.508 -0.9398)
			(end -0.508 -0.9398)
			(stroke
				(width 0.1524)
				(type default)
			)
			(layer "F.SilkS")
		)
		(fp_line
			(start -0.508 -0.9398)
			(end -0.508 0.9398)
			(stroke
				(width 0.1524)
				(type default)
			)
			(layer "F.SilkS")
		)
		(fp_rect
			(start -0.508 0.9398)
			(end 0.508 -0.9398)
			(stroke
				(width 0)
				(type default)
			)
			(fill no)
			(layer "F.CrtYd")
		)
		(fp_rect
			(start -0.508 0.9398)
			(end 0.508 -0.9398)
			(stroke
				(width 0)
				(type default)
			)
			(fill no)
			(layer "F.Fab")
		)
		(pad "1" smd custom
			(at 0 -0.4445 180)
			(size 0.1397 0.1397)
			(layers "F.Cu" "F.Mask" "F.Paste")
			(net "GND")
			(options
				(clearance outline)
				(anchor circle)
			)
			(primitives
				(gr_poly
					(pts
						(arc
							(start -0.1778 -0.2794)
							(mid -0.249642 -0.249642)
							(end -0.2794 -0.1778)
						)
						(arc
							(start -0.2794 0.1778)
							(mid -0.249642 0.249642)
							(end -0.1778 0.2794)
						)
						(arc
							(start 0.1778 0.2794)
							(mid 0.249642 0.249642)
							(end 0.2794 0.1778)
						)
						(arc
							(start 0.2794 -0.1778)
							(mid 0.249642 -0.249642)
							(end 0.1778 -0.2794)
						)
					)
					(width 0)
					(fill yes)
				)
			)
		)
		(pad "2" smd custom
			(at 0 0.4445 180)
			(size 0.1397 0.1397)
			(layers "F.Cu" "F.Mask" "F.Paste")
			(net "BMC_M_CS_N")
			(options
				(clearance outline)
				(anchor circle)
			)
			(primitives
				(gr_poly
					(pts
						(arc
							(start -0.1778 -0.2794)
							(mid -0.249642 -0.249642)
							(end -0.2794 -0.1778)
						)
						(arc
							(start -0.2794 0.1778)
							(mid -0.249642 0.249642)
							(end -0.1778 0.2794)
						)
						(arc
							(start 0.1778 0.2794)
							(mid 0.249642 0.249642)
							(end 0.2794 0.1778)
						)
						(arc
							(start 0.2794 -0.1778)
							(mid 0.249642 -0.249642)
							(end 0.1778 -0.2794)
						)
					)
					(width 0)
					(fill yes)
				)
			)
		)
	)
	(footprint ""
		(layer "F.Cu")
		(at 491.0455 -42.0624 90)
		(property "Reference" "R9E19"
			(at 0 0 90)
			(layer "F.SilkS")
			(hide yes)
			(effects
				(font
					(size 1.27 1.27)
				)
			)
		)
		(property "Value" ""
			(at 0 0 90)
			(layer "F.Fab")
			(effects
				(font
					(size 1.27 1.27)
				)
			)
		)
		(duplicate_pad_numbers_are_jumpers no)
		(fp_poly
			(pts
				(xy -0.2794 -0.1016) (xy 0.2794 -0.1016) (xy 0.2794 0.9906) (xy -0.2794 0.9906)
			)
			(stroke
				(width 0)
				(type default)
			)
			(fill no)
			(layer "F.CrtYd")
		)
		(fp_line
			(start 0.2794 -0.1016)
			(end -0.2794 -0.1016)
			(stroke
				(width 0.1)
				(type default)
			)
			(layer "F.Fab")
		)
		(fp_line
			(start -0.2794 -0.1016)
			(end -0.2794 0.9906)
			(stroke
				(width 0.1)
				(type default)
			)
			(layer "F.Fab")
		)
		(fp_line
			(start 0.2794 0.9906)
			(end 0.2794 -0.1016)
			(stroke
				(width 0.1)
				(type default)
			)
			(layer "F.Fab")
		)
		(fp_line
			(start -0.2794 0.9906)
			(end 0.2794 0.9906)
			(stroke
				(width 0.1)
				(type default)
			)
			(layer "F.Fab")
		)
		(pad "1" smd rect
			(at 0 0 90)
			(size 0.508 0.508)
			(layers "F.Cu" "F.Mask" "F.Paste")
			(net "RMII_SPRNGVLLE_BMC_PCH_RXD1_R")
		)
		(pad "2" smd rect
			(at 0 0.889 90)
			(size 0.508 0.508)
			(layers "F.Cu" "F.Mask" "F.Paste")
			(net "RMII_SPRNGVLLE_BMC_PCH_RXD1")
		)
		(zone
			(layer "F.Cu")
			(hatch none 0.5)
			(connect_pads
				(clearance 0)
			)
			(min_thickness 0.25)
			(keepout
				(tracks allowed)
				(vias not_allowed)
				(pads allowed)
				(copperpour not_allowed)
				(footprints allowed)
			)
			(placement
				(enabled no)
				(sheetname "")
			)
			(fill
				(thermal_gap 0.5)
				(thermal_bridge_width 0.5)
				(island_removal_mode 0)
			)
			(polygon
				(pts
					(xy 491.2995 -41.8084) (xy 491.2995 -42.3164) (xy 491.6805 -42.3164) (xy 491.6805 -41.8084)
				)
			)
		)
		(zone
			(layer "F.Cu")
			(hatch none 0.5)
			(connect_pads
				(clearance 0)
			)
			(min_thickness 0.25)
			(keepout
				(tracks not_allowed)
				(vias allowed)
				(pads allowed)
				(copperpour not_allowed)
				(footprints allowed)
			)
			(placement
				(enabled no)
				(sheetname "")
			)
			(fill
				(thermal_gap 0.5)
				(thermal_bridge_width 0.5)
				(island_removal_mode 0)
			)
			(polygon
				(pts
					(xy 491.6805 -41.8084) (xy 491.6805 -42.3164) (xy 491.2995 -42.3164) (xy 491.2995 -41.8084)
				)
			)
		)
	)
	(footprint ""
		(layer "F.Cu")
		(at 349.040958 -16.632428)
		(property "Reference" "C12W1"
			(at -0.8382 -0.67818 0)
			(unlocked yes)
			(layer "F.SilkS")
			(effects
				(font
					(size 0.4064 0.254)
					(thickness 0.1524)
				)
				(justify left)
			)
		)
		(property "Value" ""
			(at 0 0 0)
			(layer "F.Fab")
			(effects
				(font
					(size 1.27 1.27)
				)
			)
		)
		(duplicate_pad_numbers_are_jumpers no)
		(fp_poly
			(pts
				(xy 0.3048 -0.1016) (xy 0.3048 0.9906) (xy -0.3048 0.9906) (xy -0.3048 -0.1016)
			)
			(stroke
				(width 0)
				(type default)
			)
			(fill no)
			(layer "F.CrtYd")
		)
		(fp_line
			(start -0.3048 -0.1016)
			(end -0.3048 0.9906)
			(stroke
				(width 0.1)
				(type default)
			)
			(layer "F.Fab")
		)
		(fp_line
			(start -0.3048 0.9906)
			(end 0.3048 0.9906)
			(stroke
				(width 0.1)
				(type default)
			)
			(layer "F.Fab")
		)
		(fp_line
			(start 0.3048 -0.1016)
			(end -0.3048 -0.1016)
			(stroke
				(width 0.1)
				(type default)
			)
			(layer "F.Fab")
		)
		(fp_line
			(start 0.3048 0.9906)
			(end 0.3048 -0.1016)
			(stroke
				(width 0.1)
				(type default)
			)
			(layer "F.Fab")
		)
		(pad "1" smd rect
			(at 0 0)
			(size 0.508 0.508)
			(layers "F.Cu" "F.Mask" "F.Paste")
			(net "VR_PVDDQ_ABC_AIINSEN")
		)
		(pad "2" smd rect
			(at 0 0.889)
			(size 0.508 0.508)
			(layers "F.Cu" "F.Mask" "F.Paste")
			(net "VR_PVDDQ_ABC_VINSEN")
		)
		(zone
			(layer "F.Cu")
			(hatch none 0.5)
			(connect_pads
				(clearance 0)
			)
			(min_thickness 0.25)
			(keepout
				(tracks allowed)
				(vias not_allowed)
				(pads allowed)
				(copperpour not_allowed)
				(footprints allowed)
			)
			(placement
				(enabled no)
				(sheetname "")
			)
			(fill
				(thermal_gap 0.5)
				(thermal_bridge_width 0.5)
				(island_removal_mode 0)
			)
			(polygon
				(pts
					(xy 348.786958 -16.378428) (xy 349.294958 -16.378428) (xy 349.294958 -15.997428) (xy 348.786958 -15.997428)
				)
			)
		)
		(zone
			(layer "F.Cu")
			(hatch none 0.5)
			(connect_pads
				(clearance 0)
			)
			(min_thickness 0.25)
			(keepout
				(tracks not_allowed)
				(vias allowed)
				(pads allowed)
				(copperpour not_allowed)
				(footprints allowed)
			)
			(placement
				(enabled no)
				(sheetname "")
			)
			(fill
				(thermal_gap 0.5)
				(thermal_bridge_width 0.5)
				(island_removal_mode 0)
			)
			(polygon
				(pts
					(xy 348.786958 -15.997428) (xy 349.294958 -15.997428) (xy 349.294958 -16.378428) (xy 348.786958 -16.378428)
				)
			)
		)
	)
	(footprint ""
		(layer "F.Cu")
		(at 339.222588 -117.941598 90)
		(property "Reference" "C6B18"
			(at -0.8382 -0.67818 90)
			(unlocked yes)
			(layer "F.SilkS")
			(effects
				(font
					(size 0.4064 0.254)
					(thickness 0.1524)
				)
				(justify left)
			)
		)
		(property "Value" ""
			(at 0 0 90)
			(layer "F.Fab")
			(effects
				(font
					(size 1.27 1.27)
				)
			)
		)
		(duplicate_pad_numbers_are_jumpers no)
		(fp_poly
			(pts
				(xy 0.3048 -0.1016) (xy 0.3048 0.9906) (xy -0.3048 0.9906) (xy -0.3048 -0.1016)
			)
			(stroke
				(width 0)
				(type default)
			)
			(fill no)
			(layer "F.CrtYd")
		)
		(fp_line
			(start 0.3048 -0.1016)
			(end -0.3048 -0.1016)
			(stroke
				(width 0.1)
				(type default)
			)
			(layer "F.Fab")
		)
		(fp_line
			(start -0.3048 -0.1016)
			(end -0.3048 0.9906)
			(stroke
				(width 0.1)
				(type default)
			)
			(layer "F.Fab")
		)
		(fp_line
			(start 0.3048 0.9906)
			(end 0.3048 -0.1016)
			(stroke
				(width 0.1)
				(type default)
			)
			(layer "F.Fab")
		)
		(fp_line
			(start -0.3048 0.9906)
			(end 0.3048 0.9906)
			(stroke
				(width 0.1)
				(type default)
			)
			(layer "F.Fab")
		)
		(pad "1" smd rect
			(at 0 0 90)
			(size 0.508 0.508)
			(layers "F.Cu" "F.Mask" "F.Paste")
			(net "P3E_CPU0_PE1_PCH_TXP<9>")
		)
		(pad "2" smd rect
			(at 0 0.889 90)
			(size 0.508 0.508)
			(layers "F.Cu" "F.Mask" "F.Paste")
			(net "P3E_CPU0_PE1_PCH_C_TXP<9>")
		)
		(zone
			(layer "F.Cu")
			(hatch none 0.5)
			(connect_pads
				(clearance 0)
			)
			(min_thickness 0.25)
			(keepout
				(tracks allowed)
				(vias not_allowed)
				(pads allowed)
				(copperpour not_allowed)
				(footprints allowed)
			)
			(placement
				(enabled no)
				(sheetname "")
			)
			(fill
				(thermal_gap 0.5)
				(thermal_bridge_width 0.5)
				(island_removal_mode 0)
			)
			(polygon
				(pts
					(xy 339.476588 -117.687598) (xy 339.476588 -118.195598) (xy 339.857588 -118.195598) (xy 339.857588 -117.687598)
				)
			)
		)
		(zone
			(layer "F.Cu")
			(hatch none 0.5)
			(connect_pads
				(clearance 0)
			)
			(min_thickness 0.25)
			(keepout
				(tracks not_allowed)
				(vias allowed)
				(pads allowed)
				(copperpour not_allowed)
				(footprints allowed)
			)
			(placement
				(enabled no)
				(sheetname "")
			)
			(fill
				(thermal_gap 0.5)
				(thermal_bridge_width 0.5)
				(island_removal_mode 0)
			)
			(polygon
				(pts
					(xy 339.857588 -117.687598) (xy 339.857588 -118.195598) (xy 339.476588 -118.195598) (xy 339.476588 -117.687598)
				)
			)
		)
	)
	(footprint ""
		(layer "F.Cu")
		(at 164.084 -69.088 90)
		(property "Reference" "R4D51"
			(at 0 0 90)
			(layer "F.SilkS")
			(hide yes)
			(effects
				(font
					(size 1.27 1.27)
				)
			)
		)
		(property "Value" ""
			(at 0 0 90)
			(layer "F.Fab")
			(effects
				(font
					(size 1.27 1.27)
				)
			)
		)
		(duplicate_pad_numbers_are_jumpers no)
		(fp_poly
			(pts
				(xy -0.2794 -0.1016) (xy 0.2794 -0.1016) (xy 0.2794 0.9906) (xy -0.2794 0.9906)
			)
			(stroke
				(width 0)
				(type default)
			)
			(fill no)
			(layer "F.CrtYd")
		)
		(fp_line
			(start 0.2794 -0.1016)
			(end -0.2794 -0.1016)
			(stroke
				(width 0.1)
				(type default)
			)
			(layer "F.Fab")
		)
		(fp_line
			(start -0.2794 -0.1016)
			(end -0.2794 0.9906)
			(stroke
				(width 0.1)
				(type default)
			)
			(layer "F.Fab")
		)
		(fp_line
			(start 0.2794 0.9906)
			(end 0.2794 -0.1016)
			(stroke
				(width 0.1)
				(type default)
			)
			(layer "F.Fab")
		)
		(fp_line
			(start -0.2794 0.9906)
			(end 0.2794 0.9906)
			(stroke
				(width 0.1)
				(type default)
			)
			(layer "F.Fab")
		)
		(pad "1" smd rect
			(at 0 0 90)
			(size 0.508 0.508)
			(layers "F.Cu" "F.Mask" "F.Paste")
			(net "SVID_CLK0_CPU1_R")
		)
		(pad "2" smd rect
			(at 0 0.889 90)
			(size 0.508 0.508)
			(layers "F.Cu" "F.Mask" "F.Paste")
			(net "SVID_CLK_PVCCIO_CPU1")
		)
		(zone
			(layer "F.Cu")
			(hatch none 0.5)
			(connect_pads
				(clearance 0)
			)
			(min_thickness 0.25)
			(keepout
				(tracks allowed)
				(vias not_allowed)
				(pads allowed)
				(copperpour not_allowed)
				(footprints allowed)
			)
			(placement
				(enabled no)
				(sheetname "")
			)
			(fill
				(thermal_gap 0.5)
				(thermal_bridge_width 0.5)
				(island_removal_mode 0)
			)
			(polygon
				(pts
					(xy 164.338 -68.834) (xy 164.338 -69.342) (xy 164.719 -69.342) (xy 164.719 -68.834)
				)
			)
		)
		(zone
			(layer "F.Cu")
			(hatch none 0.5)
			(connect_pads
				(clearance 0)
			)
			(min_thickness 0.25)
			(keepout
				(tracks not_allowed)
				(vias allowed)
				(pads allowed)
				(copperpour not_allowed)
				(footprints allowed)
			)
			(placement
				(enabled no)
				(sheetname "")
			)
			(fill
				(thermal_gap 0.5)
				(thermal_bridge_width 0.5)
				(island_removal_mode 0)
			)
			(polygon
				(pts
					(xy 164.719 -68.834) (xy 164.719 -69.342) (xy 164.338 -69.342) (xy 164.338 -68.834)
				)
			)
		)
	)
	(footprint ""
		(layer "F.Cu")
		(at 476.377 -36.6395 180)
		(property "Reference" "R8G1"
			(at 0 0 180)
			(layer "F.SilkS")
			(hide yes)
			(effects
				(font
					(size 1.27 1.27)
				)
			)
		)
		(property "Value" ""
			(at 0 0 180)
			(layer "F.Fab")
			(effects
				(font
					(size 1.27 1.27)
				)
			)
		)
		(duplicate_pad_numbers_are_jumpers no)
		(fp_poly
			(pts
				(xy -0.2794 -0.1016) (xy 0.2794 -0.1016) (xy 0.2794 0.9906) (xy -0.2794 0.9906)
			)
			(stroke
				(width 0)
				(type default)
			)
			(fill no)
			(layer "F.CrtYd")
		)
		(fp_line
			(start 0.2794 0.9906)
			(end 0.2794 -0.1016)
			(stroke
				(width 0.1)
				(type default)
			)
			(layer "F.Fab")
		)
		(fp_line
			(start 0.2794 -0.1016)
			(end -0.2794 -0.1016)
			(stroke
				(width 0.1)
				(type default)
			)
			(layer "F.Fab")
		)
		(fp_line
			(start -0.2794 0.9906)
			(end 0.2794 0.9906)
			(stroke
				(width 0.1)
				(type default)
			)
			(layer "F.Fab")
		)
		(fp_line
			(start -0.2794 -0.1016)
			(end -0.2794 0.9906)
			(stroke
				(width 0.1)
				(type default)
			)
			(layer "F.Fab")
		)
		(pad "1" smd rect
			(at 0 0 180)
			(size 0.508 0.508)
			(layers "F.Cu" "F.Mask" "F.Paste")
			(net "CLK_50M_CKMNG_BMC_2_R")
		)
		(pad "2" smd rect
			(at 0 0.889 180)
			(size 0.508 0.508)
			(layers "F.Cu" "F.Mask" "F.Paste")
			(net "CLK_50M_CKMNG_BMC_2")
		)
		(zone
			(layer "F.Cu")
			(hatch none 0.5)
			(connect_pads
				(clearance 0)
			)
			(min_thickness 0.25)
			(keepout
				(tracks not_allowed)
				(vias allowed)
				(pads allowed)
				(copperpour not_allowed)
				(footprints allowed)
			)
			(placement
				(enabled no)
				(sheetname "")
			)
			(fill
				(thermal_gap 0.5)
				(thermal_bridge_width 0.5)
				(island_removal_mode 0)
			)
			(polygon
				(pts
					(xy 476.631 -37.2745) (xy 476.123 -37.2745) (xy 476.123 -36.8935) (xy 476.631 -36.8935)
				)
			)
		)
		(zone
			(layer "F.Cu")
			(hatch none 0.5)
			(connect_pads
				(clearance 0)
			)
			(min_thickness 0.25)
			(keepout
				(tracks allowed)
				(vias not_allowed)
				(pads allowed)
				(copperpour not_allowed)
				(footprints allowed)
			)
			(placement
				(enabled no)
				(sheetname "")
			)
			(fill
				(thermal_gap 0.5)
				(thermal_bridge_width 0.5)
				(island_removal_mode 0)
			)
			(polygon
				(pts
					(xy 476.631 -36.8935) (xy 476.123 -36.8935) (xy 476.123 -37.2745) (xy 476.631 -37.2745)
				)
			)
		)
	)
	(footprint ""
		(layer "F.Cu")
		(at 14.209268 -3.54203 180)
		(property "Reference" "R1G8"
			(at 0 0 180)
			(layer "F.SilkS")
			(hide yes)
			(effects
				(font
					(size 1.27 1.27)
				)
			)
		)
		(property "Value" ""
			(at 0 0 180)
			(layer "F.Fab")
			(effects
				(font
					(size 1.27 1.27)
				)
			)
		)
		(duplicate_pad_numbers_are_jumpers no)
		(fp_poly
			(pts
				(xy -0.2794 -0.1016) (xy 0.2794 -0.1016) (xy 0.2794 0.9906) (xy -0.2794 0.9906)
			)
			(stroke
				(width 0)
				(type default)
			)
			(fill no)
			(layer "F.CrtYd")
		)
		(fp_line
			(start 0.2794 0.9906)
			(end 0.2794 -0.1016)
			(stroke
				(width 0.1)
				(type default)
			)
			(layer "F.Fab")
		)
		(fp_line
			(start 0.2794 -0.1016)
			(end -0.2794 -0.1016)
			(stroke
				(width 0.1)
				(type default)
			)
			(layer "F.Fab")
		)
		(fp_line
			(start -0.2794 0.9906)
			(end 0.2794 0.9906)
			(stroke
				(width 0.1)
				(type default)
			)
			(layer "F.Fab")
		)
		(fp_line
			(start -0.2794 -0.1016)
			(end -0.2794 0.9906)
			(stroke
				(width 0.1)
				(type default)
			)
			(layer "F.Fab")
		)
		(pad "1" smd rect
			(at 0 0 180)
			(size 0.508 0.508)
			(layers "F.Cu" "F.Mask" "F.Paste")
			(net "IRQ_PVDDQ_GHJ_VRHOT_LVT3_R_N")
		)
		(pad "2" smd rect
			(at 0 0.889 180)
			(size 0.508 0.508)
			(layers "F.Cu" "F.Mask" "F.Paste")
			(net "IRQ_PVDDQ_GHJ_VRHOT_LVT3_N")
		)
		(zone
			(layer "F.Cu")
			(hatch none 0.5)
			(connect_pads
				(clearance 0)
			)
			(min_thickness 0.25)
			(keepout
				(tracks not_allowed)
				(vias allowed)
				(pads allowed)
				(copperpour not_allowed)
				(footprints allowed)
			)
			(placement
				(enabled no)
				(sheetname "")
			)
			(fill
				(thermal_gap 0.5)
				(thermal_bridge_width 0.5)
				(island_removal_mode 0)
			)
			(polygon
				(pts
					(xy 14.463268 -4.17703) (xy 13.955268 -4.17703) (xy 13.955268 -3.79603) (xy 14.463268 -3.79603)
				)
			)
		)
		(zone
			(layer "F.Cu")
			(hatch none 0.5)
			(connect_pads
				(clearance 0)
			)
			(min_thickness 0.25)
			(keepout
				(tracks allowed)
				(vias not_allowed)
				(pads allowed)
				(copperpour not_allowed)
				(footprints allowed)
			)
			(placement
				(enabled no)
				(sheetname "")
			)
			(fill
				(thermal_gap 0.5)
				(thermal_bridge_width 0.5)
				(island_removal_mode 0)
			)
			(polygon
				(pts
					(xy 14.463268 -3.79603) (xy 13.955268 -3.79603) (xy 13.955268 -4.17703) (xy 14.463268 -4.17703)
				)
			)
		)
	)
	(footprint ""
		(layer "F.Cu")
		(at 195.086986 -94.687898)
		(property "Reference" "CT60"
			(at 1.8288 -2.28473 0)
			(unlocked yes)
			(layer "F.SilkS")
			(effects
				(font
					(size 0.7874 0.5842)
					(thickness 0.1524)
				)
				(justify left)
			)
		)
		(property "Value" ""
			(at 0 0 0)
			(layer "F.Fab")
			(effects
				(font
					(size 1.27 1.27)
				)
			)
		)
		(duplicate_pad_numbers_are_jumpers no)
		(fp_poly
			(pts
				(xy 0.3048 -0.1016) (xy 0.3048 0.9906) (xy -0.3048 0.9906) (xy -0.3048 -0.1016)
			)
			(stroke
				(width 0)
				(type default)
			)
			(fill no)
			(layer "F.CrtYd")
		)
		(fp_line
			(start -0.3048 -0.1016)
			(end -0.3048 0.9906)
			(stroke
				(width 0.1)
				(type default)
			)
			(layer "F.Fab")
		)
		(fp_line
			(start -0.3048 0.9906)
			(end 0.3048 0.9906)
			(stroke
				(width 0.1)
				(type default)
			)
			(layer "F.Fab")
		)
		(fp_line
			(start 0.3048 -0.1016)
			(end -0.3048 -0.1016)
			(stroke
				(width 0.1)
				(type default)
			)
			(layer "F.Fab")
		)
		(fp_line
			(start 0.3048 0.9906)
			(end 0.3048 -0.1016)
			(stroke
				(width 0.1)
				(type default)
			)
			(layer "F.Fab")
		)
		(pad "1" smd rect
			(at 0 0)
			(size 0.508 0.508)
			(layers "F.Cu" "F.Mask" "F.Paste")
			(net "VR_PVSA_CPU0_BIREF1")
		)
		(pad "2" smd rect
			(at 0 0.889)
			(size 0.508 0.508)
			(layers "F.Cu" "F.Mask" "F.Paste")
			(net "GND")
		)
		(zone
			(layer "F.Cu")
			(hatch none 0.5)
			(connect_pads
				(clearance 0)
			)
			(min_thickness 0.25)
			(keepout
				(tracks allowed)
				(vias not_allowed)
				(pads allowed)
				(copperpour not_allowed)
				(footprints allowed)
			)
			(placement
				(enabled no)
				(sheetname "")
			)
			(fill
				(thermal_gap 0.5)
				(thermal_bridge_width 0.5)
				(island_removal_mode 0)
			)
			(polygon
				(pts
					(xy 194.832986 -94.433898) (xy 195.340986 -94.433898) (xy 195.340986 -94.052898) (xy 194.832986 -94.052898)
				)
			)
		)
		(zone
			(layer "F.Cu")
			(hatch none 0.5)
			(connect_pads
				(clearance 0)
			)
			(min_thickness 0.25)
			(keepout
				(tracks not_allowed)
				(vias allowed)
				(pads allowed)
				(copperpour not_allowed)
				(footprints allowed)
			)
			(placement
				(enabled no)
				(sheetname "")
			)
			(fill
				(thermal_gap 0.5)
				(thermal_bridge_width 0.5)
				(island_removal_mode 0)
			)
			(polygon
				(pts
					(xy 194.832986 -94.052898) (xy 195.340986 -94.052898) (xy 195.340986 -94.433898) (xy 194.832986 -94.433898)
				)
			)
		)
	)
	(footprint ""
		(layer "F.Cu")
		(at 395.351 -85.0265 180)
		(property "Reference" "R2U3"
			(at 0 0 180)
			(layer "F.SilkS")
			(hide yes)
			(effects
				(font
					(size 1.27 1.27)
				)
			)
		)
		(property "Value" ""
			(at 0 0 180)
			(layer "F.Fab")
			(effects
				(font
					(size 1.27 1.27)
				)
			)
		)
		(duplicate_pad_numbers_are_jumpers no)
		(fp_poly
			(pts
				(xy -0.2794 -0.1016) (xy 0.2794 -0.1016) (xy 0.2794 0.9906) (xy -0.2794 0.9906)
			)
			(stroke
				(width 0)
				(type default)
			)
			(fill no)
			(layer "F.CrtYd")
		)
		(fp_line
			(start 0.2794 0.9906)
			(end 0.2794 -0.1016)
			(stroke
				(width 0.1)
				(type default)
			)
			(layer "F.Fab")
		)
		(fp_line
			(start 0.2794 -0.1016)
			(end -0.2794 -0.1016)
			(stroke
				(width 0.1)
				(type default)
			)
			(layer "F.Fab")
		)
		(fp_line
			(start -0.2794 0.9906)
			(end 0.2794 0.9906)
			(stroke
				(width 0.1)
				(type default)
			)
			(layer "F.Fab")
		)
		(fp_line
			(start -0.2794 -0.1016)
			(end -0.2794 0.9906)
			(stroke
				(width 0.1)
				(type default)
			)
			(layer "F.Fab")
		)
		(pad "1" smd rect
			(at 0 0 180)
			(size 0.508 0.508)
			(layers "F.Cu" "F.Mask" "F.Paste")
			(net "P3V3_STBY")
		)
		(pad "2" smd rect
			(at 0 0.889 180)
			(size 0.508 0.508)
			(layers "F.Cu" "F.Mask" "F.Paste")
			(net "SMB_LAN_STBY_LVC3_SCL")
		)
		(zone
			(layer "F.Cu")
			(hatch none 0.5)
			(connect_pads
				(clearance 0)
			)
			(min_thickness 0.25)
			(keepout
				(tracks not_allowed)
				(vias allowed)
				(pads allowed)
				(copperpour not_allowed)
				(footprints allowed)
			)
			(placement
				(enabled no)
				(sheetname "")
			)
			(fill
				(thermal_gap 0.5)
				(thermal_bridge_width 0.5)
				(island_removal_mode 0)
			)
			(polygon
				(pts
					(xy 395.605 -85.6615) (xy 395.097 -85.6615) (xy 395.097 -85.2805) (xy 395.605 -85.2805)
				)
			)
		)
		(zone
			(layer "F.Cu")
			(hatch none 0.5)
			(connect_pads
				(clearance 0)
			)
			(min_thickness 0.25)
			(keepout
				(tracks allowed)
				(vias not_allowed)
				(pads allowed)
				(copperpour not_allowed)
				(footprints allowed)
			)
			(placement
				(enabled no)
				(sheetname "")
			)
			(fill
				(thermal_gap 0.5)
				(thermal_bridge_width 0.5)
				(island_removal_mode 0)
			)
			(polygon
				(pts
					(xy 395.605 -85.2805) (xy 395.097 -85.2805) (xy 395.097 -85.6615) (xy 395.605 -85.6615)
				)
			)
		)
	)
	(footprint ""
		(layer "F.Cu")
		(at 105.995978 -84.890102)
		(property "Reference" "C2D3"
			(at 0 0 0)
			(layer "F.SilkS")
			(hide yes)
			(effects
				(font
					(size 1.27 1.27)
				)
			)
		)
		(property "Value" ""
			(at 0 0 0)
			(layer "F.Fab")
			(effects
				(font
					(size 1.27 1.27)
				)
			)
		)
		(duplicate_pad_numbers_are_jumpers no)
		(fp_poly
			(pts
				(xy -0.4953 -0.2032) (xy 0.4953 -0.2032) (xy 0.4953 1.6002) (xy -0.4953 1.6002)
			)
			(stroke
				(width 0)
				(type default)
			)
			(fill no)
			(layer "F.CrtYd")
		)
		(fp_line
			(start -0.4953 -0.2032)
			(end 0.4953 -0.2032)
			(stroke
				(width 0.1)
				(type default)
			)
			(layer "F.Fab")
		)
		(fp_line
			(start -0.4953 1.6002)
			(end -0.4953 -0.2032)
			(stroke
				(width 0.1)
				(type default)
			)
			(layer "F.Fab")
		)
		(fp_line
			(start 0.4953 -0.2032)
			(end 0.4953 1.6002)
			(stroke
				(width 0.1)
				(type default)
			)
			(layer "F.Fab")
		)
		(fp_line
			(start 0.4953 1.6002)
			(end -0.4953 1.6002)
			(stroke
				(width 0.1)
				(type default)
			)
			(layer "F.Fab")
		)
		(pad "1" smd rect
			(at 0 0)
			(size 0.762 0.889)
			(layers "F.Cu" "F.Mask" "F.Paste")
			(net "PVDDQ_KLM")
		)
		(pad "2" smd rect
			(at 0 1.397)
			(size 0.762 0.889)
			(layers "F.Cu" "F.Mask" "F.Paste")
			(net "GND")
		)
		(zone
			(layer "F.Cu")
			(hatch none 0.5)
			(connect_pads
				(clearance 0)
			)
			(min_thickness 0.25)
			(keepout
				(tracks not_allowed)
				(vias allowed)
				(pads allowed)
				(copperpour not_allowed)
				(footprints allowed)
			)
			(placement
				(enabled no)
				(sheetname "")
			)
			(fill
				(thermal_gap 0.5)
				(thermal_bridge_width 0.5)
				(island_removal_mode 0)
			)
			(polygon
				(pts
					(xy 105.614978 -84.445602) (xy 106.376978 -84.445602) (xy 106.376978 -83.937602) (xy 105.614978 -83.937602)
				)
			)
		)
	)
	(footprint ""
		(layer "F.Cu")
		(at 25.520142 -109.542834 -90)
		(property "Reference" "C1C1"
			(at 1.397 -2.69367 90)
			(unlocked yes)
			(layer "F.SilkS")
			(effects
				(font
					(size 0.7874 0.5842)
					(thickness 0.1524)
				)
				(justify left)
			)
		)
		(property "Value" ""
			(at 0 0 270)
			(layer "F.Fab")
			(effects
				(font
					(size 1.27 1.27)
				)
			)
		)
		(duplicate_pad_numbers_are_jumpers no)
		(fp_line
			(start -3.400044 6.067044)
			(end -0.9017 6.067044)
			(stroke
				(width 0.1524)
				(type default)
			)
			(layer "F.SilkS")
		)
		(fp_line
			(start 0.9017 6.067044)
			(end 3.400044 6.067044)
			(stroke
				(width 0.1524)
				(type default)
			)
			(layer "F.SilkS")
		)
		(fp_line
			(start 3.400044 6.067044)
			(end 3.400044 0.028956)
			(stroke
				(width 0.1524)
				(type default)
			)
			(layer "F.SilkS")
		)
		(fp_line
			(start -0.9017 1.587754)
			(end -0.7239 1.587754)
			(stroke
				(width 0.1524)
				(type default)
			)
			(layer "F.SilkS")
		)
		(fp_line
			(start 0.7239 1.587754)
			(end 0.9017 1.587754)
			(stroke
				(width 0.1524)
				(type default)
			)
			(layer "F.SilkS")
		)
		(fp_line
			(start 0.9017 1.587754)
			(end 0.9017 -1.714246)
			(stroke
				(width 0.1524)
				(type default)
			)
			(layer "F.SilkS")
		)
		(fp_line
			(start -3.400044 0.028956)
			(end -3.400044 6.067044)
			(stroke
				(width 0.1524)
				(type default)
			)
			(layer "F.SilkS")
		)
		(fp_line
			(start 3.400044 0.028956)
			(end 2.638044 -0.733044)
			(stroke
				(width 0.1524)
				(type default)
			)
			(layer "F.SilkS")
		)
		(fp_line
			(start -2.638044 -0.733044)
			(end -3.400044 0.028956)
			(stroke
				(width 0.1524)
				(type default)
			)
			(layer "F.SilkS")
		)
		(fp_line
			(start -0.9017 -0.733044)
			(end -2.638044 -0.733044)
			(stroke
				(width 0.1524)
				(type default)
			)
			(layer "F.SilkS")
		)
		(fp_line
			(start 2.638044 -0.733044)
			(end 0.9017 -0.733044)
			(stroke
				(width 0.1524)
				(type default)
			)
			(layer "F.SilkS")
		)
		(fp_line
			(start -0.9017 -1.714246)
			(end -0.9017 1.587754)
			(stroke
				(width 0.1524)
				(type default)
			)
			(layer "F.SilkS")
		)
		(fp_line
			(start -0.7239 -1.714246)
			(end -0.9017 -1.714246)
			(stroke
				(width 0.1524)
				(type default)
			)
			(layer "F.SilkS")
		)
		(fp_line
			(start 0.9017 -1.714246)
			(end 0.7239 -1.714246)
			(stroke
				(width 0.1524)
				(type default)
			)
			(layer "F.SilkS")
		)
		(fp_poly
			(pts
				(xy -3.400044 6.067044) (xy 3.400044 6.067044) (xy 3.400044 0.028956) (xy 2.638044 -0.733044) (xy -2.638044 -0.733044)
				(xy -3.400044 0.028956)
			)
			(stroke
				(width 0)
				(type default)
			)
			(fill no)
			(layer "F.CrtYd")
		)
		(fp_line
			(start -3.400044 6.067044)
			(end 3.400044 6.067044)
			(stroke
				(width 0.1)
				(type default)
			)
			(layer "F.Fab")
		)
		(fp_line
			(start 3.400044 6.067044)
			(end 3.400044 0.028956)
			(stroke
				(width 0.1)
				(type default)
			)
			(layer "F.Fab")
		)
		(fp_line
			(start -3.400044 0.028956)
			(end -3.400044 6.067044)
			(stroke
				(width 0.1)
				(type default)
			)
			(layer "F.Fab")
		)
		(fp_line
			(start 3.400044 0.028956)
			(end 2.638044 -0.733044)
			(stroke
				(width 0.1)
				(type default)
			)
			(layer "F.Fab")
		)
		(fp_line
			(start -2.638044 -0.733044)
			(end -3.400044 0.028956)
			(stroke
				(width 0.1)
				(type default)
			)
			(layer "F.Fab")
		)
		(fp_line
			(start 2.638044 -0.733044)
			(end -2.638044 -0.733044)
			(stroke
				(width 0.1)
				(type default)
			)
			(layer "F.Fab")
		)
		(fp_circle
			(center 0 2.667)
			(end 0 -0.733044)
			(stroke
				(width 0.1)
				(type default)
			)
			(fill no)
			(layer "F.Fab")
		)
		(pad "1" smd rect
			(at 0 0 270)
			(size 0.7874 3.429)
			(layers "F.Cu" "F.Mask" "F.Paste")
			(net "VR_FET_SW_P12V_STBY_PVCCIN_CPU1")
		)
		(pad "2" smd rect
			(at 0 5.334 270)
			(size 0.7874 3.429)
			(layers "F.Cu" "F.Mask" "F.Paste")
			(net "GND")
		)
	)
	(footprint ""
		(layer "F.Cu")
		(at 153.4922 -149.606 -90)
		(property "Reference" "C3A3"
			(at 0 0 270)
			(layer "F.SilkS")
			(hide yes)
			(effects
				(font
					(size 1.27 1.27)
				)
			)
		)
		(property "Value" ""
			(at 0 0 270)
			(layer "F.Fab")
			(effects
				(font
					(size 1.27 1.27)
				)
			)
		)
		(duplicate_pad_numbers_are_jumpers no)
		(fp_rect
			(start -0.4953 1.6002)
			(end 0.4953 -0.2032)
			(stroke
				(width 0)
				(type default)
			)
			(fill no)
			(layer "F.CrtYd")
		)
		(fp_line
			(start -0.4953 1.6002)
			(end -0.4953 -0.2032)
			(stroke
				(width 0.1)
				(type default)
			)
			(layer "F.Fab")
		)
		(fp_line
			(start 0.4953 1.6002)
			(end -0.4953 1.6002)
			(stroke
				(width 0.1)
				(type default)
			)
			(layer "F.Fab")
		)
		(fp_line
			(start -0.4953 -0.2032)
			(end 0.4953 -0.2032)
			(stroke
				(width 0.1)
				(type default)
			)
			(layer "F.Fab")
		)
		(fp_line
			(start 0.4953 -0.2032)
			(end 0.4953 1.6002)
			(stroke
				(width 0.1)
				(type default)
			)
			(layer "F.Fab")
		)
		(pad "1" smd rect
			(at 0 0 270)
			(size 0.762 0.889)
			(layers "F.Cu" "F.Mask" "F.Paste")
			(net "PVPP_KLM")
		)
		(pad "2" smd rect
			(at 0 1.397 270)
			(size 0.762 0.889)
			(layers "F.Cu" "F.Mask" "F.Paste")
			(net "GND")
		)
		(zone
			(layer "F.Cu")
			(hatch none 0.5)
			(connect_pads
				(clearance 0)
			)
			(min_thickness 0.25)
			(keepout
				(tracks not_allowed)
				(vias allowed)
				(pads allowed)
				(copperpour not_allowed)
				(footprints allowed)
			)
			(placement
				(enabled no)
				(sheetname "")
			)
			(fill
				(thermal_gap 0.5)
				(thermal_bridge_width 0.5)
				(island_removal_mode 0)
			)
			(polygon
				(pts
					(xy 152.5397 -149.987) (xy 152.5397 -149.225) (xy 153.0477 -149.225) (xy 153.0477 -149.987)
				)
			)
		)
	)
	(footprint ""
		(layer "F.Cu")
		(at 407.40076 -57.79389)
		(property "Reference" "C8E7"
			(at 0 0 0)
			(layer "F.SilkS")
			(hide yes)
			(effects
				(font
					(size 1.27 1.27)
				)
			)
		)
		(property "Value" "*"
			(at -0.0762 -6.2357 0)
			(unlocked yes)
			(layer "F.Fab")
			(hide yes)
			(effects
				(font
					(size 1.27 1.016)
					(thickness 0.1524)
				)
			)
		)
		(property "Device Type" "SC22U16V5MX-4-GP_SMD-BCG5-SC22A"
			(at -0.0762 -8.2677 0)
			(unlocked yes)
			(layer "F.Fab")
			(hide yes)
			(effects
				(font
					(size 1.27 1.016)
					(thickness 0.1524)
				)
			)
		)
		(duplicate_pad_numbers_are_jumpers no)
		(fp_line
			(start 0.635 0)
			(end -0.635 0)
			(stroke
				(width 0.508)
				(type default)
			)
			(layer "F.SilkS")
		)
		(fp_rect
			(start -0.9652 1.778)
			(end 0.9652 -1.778)
			(stroke
				(width 0)
				(type default)
			)
			(fill no)
			(layer "F.CrtYd")
		)
		(fp_poly
			(pts
				(xy -0.9652 -1.778) (xy 0.9652 -1.778) (xy 0.9652 1.778) (xy -0.9652 1.778)
			)
			(stroke
				(width 0)
				(type default)
			)
			(fill no)
			(layer "F.Fab")
		)
		(pad "1" smd rect
			(at 0 -0.9652)
			(size 1.397 1.143)
			(layers "F.Cu" "F.Mask" "F.Paste")
			(net "P5V_STBY")
		)
		(pad "2" smd rect
			(at 0 0.9652)
			(size 1.397 1.143)
			(layers "F.Cu" "F.Mask" "F.Paste")
			(net "GND")
		)
	)
	(footprint ""
		(layer "F.Cu")
		(at 406.0825 -50.038 90)
		(property "Reference" "R8D27"
			(at 0 0 90)
			(layer "F.SilkS")
			(hide yes)
			(effects
				(font
					(size 1.27 1.27)
				)
			)
		)
		(property "Value" ""
			(at 0 0 90)
			(layer "F.Fab")
			(effects
				(font
					(size 1.27 1.27)
				)
			)
		)
		(duplicate_pad_numbers_are_jumpers no)
		(fp_poly
			(pts
				(xy -0.2794 -0.1016) (xy 0.2794 -0.1016) (xy 0.2794 0.9906) (xy -0.2794 0.9906)
			)
			(stroke
				(width 0)
				(type default)
			)
			(fill no)
			(layer "F.CrtYd")
		)
		(fp_line
			(start 0.2794 -0.1016)
			(end -0.2794 -0.1016)
			(stroke
				(width 0.1)
				(type default)
			)
			(layer "F.Fab")
		)
		(fp_line
			(start -0.2794 -0.1016)
			(end -0.2794 0.9906)
			(stroke
				(width 0.1)
				(type default)
			)
			(layer "F.Fab")
		)
		(fp_line
			(start 0.2794 0.9906)
			(end 0.2794 -0.1016)
			(stroke
				(width 0.1)
				(type default)
			)
			(layer "F.Fab")
		)
		(fp_line
			(start -0.2794 0.9906)
			(end 0.2794 0.9906)
			(stroke
				(width 0.1)
				(type default)
			)
			(layer "F.Fab")
		)
		(pad "1" smd rect
			(at 0 0 90)
			(size 0.508 0.508)
			(layers "F.Cu" "F.Mask" "F.Paste")
			(net "PD_FRU_WP")
		)
		(pad "2" smd rect
			(at 0 0.889 90)
			(size 0.508 0.508)
			(layers "F.Cu" "F.Mask" "F.Paste")
			(net "GND")
		)
		(zone
			(layer "F.Cu")
			(hatch none 0.5)
			(connect_pads
				(clearance 0)
			)
			(min_thickness 0.25)
			(keepout
				(tracks allowed)
				(vias not_allowed)
				(pads allowed)
				(copperpour not_allowed)
				(footprints allowed)
			)
			(placement
				(enabled no)
				(sheetname "")
			)
			(fill
				(thermal_gap 0.5)
				(thermal_bridge_width 0.5)
				(island_removal_mode 0)
			)
			(polygon
				(pts
					(xy 406.3365 -49.784) (xy 406.3365 -50.292) (xy 406.7175 -50.292) (xy 406.7175 -49.784)
				)
			)
		)
		(zone
			(layer "F.Cu")
			(hatch none 0.5)
			(connect_pads
				(clearance 0)
			)
			(min_thickness 0.25)
			(keepout
				(tracks not_allowed)
				(vias allowed)
				(pads allowed)
				(copperpour not_allowed)
				(footprints allowed)
			)
			(placement
				(enabled no)
				(sheetname "")
			)
			(fill
				(thermal_gap 0.5)
				(thermal_bridge_width 0.5)
				(island_removal_mode 0)
			)
			(polygon
				(pts
					(xy 406.7175 -49.784) (xy 406.7175 -50.292) (xy 406.3365 -50.292) (xy 406.3365 -49.784)
				)
			)
		)
	)
	(footprint ""
		(layer "F.Cu")
		(at -2.5146 -126.8222 -90)
		(property "Reference" "R1B11"
			(at 0 0 270)
			(layer "F.SilkS")
			(hide yes)
			(effects
				(font
					(size 1.27 1.27)
				)
			)
		)
		(property "Value" ""
			(at 0 0 270)
			(layer "F.Fab")
			(effects
				(font
					(size 1.27 1.27)
				)
			)
		)
		(duplicate_pad_numbers_are_jumpers no)
		(fp_rect
			(start 0.2794 0.9906)
			(end -0.2794 -0.1016)
			(stroke
				(width 0)
				(type default)
			)
			(fill no)
			(layer "F.CrtYd")
		)
		(fp_line
			(start -0.2794 0.9906)
			(end 0.2794 0.9906)
			(stroke
				(width 0.1)
				(type default)
			)
			(layer "F.Fab")
		)
		(fp_line
			(start 0.2794 0.9906)
			(end 0.2794 -0.1016)
			(stroke
				(width 0.1)
				(type default)
			)
			(layer "F.Fab")
		)
		(fp_line
			(start -0.2794 -0.1016)
			(end -0.2794 0.9906)
			(stroke
				(width 0.1)
				(type default)
			)
			(layer "F.Fab")
		)
		(fp_line
			(start 0.2794 -0.1016)
			(end -0.2794 -0.1016)
			(stroke
				(width 0.1)
				(type default)
			)
			(layer "F.Fab")
		)
		(pad "1" smd rect
			(at 0 0 270)
			(size 0.508 0.508)
			(layers "F.Cu" "F.Mask" "F.Paste")
			(net "SVID_ALERT_PVDDQ_KLM")
		)
		(pad "2" smd rect
			(at 0 0.889 270)
			(size 0.508 0.508)
			(layers "F.Cu" "F.Mask" "F.Paste")
			(net "SVID_ALERT1_CPU1_R_N")
		)
		(zone
			(layer "F.Cu")
			(hatch none 0.5)
			(connect_pads
				(clearance 0)
			)
			(min_thickness 0.25)
			(keepout
				(tracks not_allowed)
				(vias allowed)
				(pads allowed)
				(copperpour not_allowed)
				(footprints allowed)
			)
			(placement
				(enabled no)
				(sheetname "")
			)
			(fill
				(thermal_gap 0.5)
				(thermal_bridge_width 0.5)
				(island_removal_mode 0)
			)
			(polygon
				(pts
					(xy -3.1496 -126.5682) (xy -2.7686 -126.5682) (xy -2.7686 -127.0762) (xy -3.1496 -127.0762)
				)
			)
		)
		(zone
			(layer "F.Cu")
			(hatch none 0.5)
			(connect_pads
				(clearance 0)
			)
			(min_thickness 0.25)
			(keepout
				(tracks allowed)
				(vias not_allowed)
				(pads allowed)
				(copperpour not_allowed)
				(footprints allowed)
			)
			(placement
				(enabled no)
				(sheetname "")
			)
			(fill
				(thermal_gap 0.5)
				(thermal_bridge_width 0.5)
				(island_removal_mode 0)
			)
			(polygon
				(pts
					(xy -3.1496 -126.5682) (xy -2.7686 -126.5682) (xy -2.7686 -127.0762) (xy -3.1496 -127.0762)
				)
			)
		)
	)
	(footprint ""
		(layer "F.Cu")
		(at 192.532 -57.912 90)
		(property "Reference" "RT1"
			(at 1.01473 0.656336 0)
			(unlocked yes)
			(layer "F.SilkS")
			(effects
				(font
					(size 0.4064 0.254)
					(thickness 0.1524)
				)
			)
		)
		(property "Value" ""
			(at 0 0 90)
			(layer "F.Fab")
			(effects
				(font
					(size 1.27 1.27)
				)
			)
		)
		(duplicate_pad_numbers_are_jumpers no)
		(fp_poly
			(pts
				(xy -0.4953 -0.2032) (xy 0.4953 -0.2032) (xy 0.4953 1.6002) (xy -0.4953 1.6002)
			)
			(stroke
				(width 0)
				(type default)
			)
			(fill no)
			(layer "F.CrtYd")
		)
		(fp_line
			(start 0.4953 -0.2032)
			(end 0.4953 1.6002)
			(stroke
				(width 0.1)
				(type default)
			)
			(layer "F.Fab")
		)
		(fp_line
			(start -0.4953 -0.2032)
			(end 0.4953 -0.2032)
			(stroke
				(width 0.1)
				(type default)
			)
			(layer "F.Fab")
		)
		(fp_line
			(start 0.4953 1.6002)
			(end -0.4953 1.6002)
			(stroke
				(width 0.1)
				(type default)
			)
			(layer "F.Fab")
		)
		(fp_line
			(start -0.4953 1.6002)
			(end -0.4953 -0.2032)
			(stroke
				(width 0.1)
				(type default)
			)
			(layer "F.Fab")
		)
		(pad "1" smd rect
			(at 0 0 90)
			(size 0.762 0.889)
			(layers "F.Cu" "F.Mask" "F.Paste")
			(net "VR_PVCCIN_CPU0_PH1_BOOT")
		)
		(pad "2" smd rect
			(at 0 1.397 90)
			(size 0.762 0.889)
			(layers "F.Cu" "F.Mask" "F.Paste")
			(net "VR_PVCCIN_CPU0_PH1_BOOT_R")
		)
		(zone
			(layer "F.Cu")
			(hatch none 0.5)
			(connect_pads
				(clearance 0)
			)
			(min_thickness 0.25)
			(keepout
				(tracks allowed)
				(vias not_allowed)
				(pads allowed)
				(copperpour not_allowed)
				(footprints allowed)
			)
			(placement
				(enabled no)
				(sheetname "")
			)
			(fill
				(thermal_gap 0.5)
				(thermal_bridge_width 0.5)
				(island_removal_mode 0)
			)
			(polygon
				(pts
					(xy 193.4845 -58.293) (xy 192.9765 -58.293) (xy 192.9765 -57.531) (xy 193.4845 -57.531)
				)
			)
		)
		(zone
			(layer "F.Cu")
			(hatch none 0.5)
			(connect_pads
				(clearance 0)
			)
			(min_thickness 0.25)
			(keepout
				(tracks not_allowed)
				(vias allowed)
				(pads allowed)
				(copperpour not_allowed)
				(footprints allowed)
			)
			(placement
				(enabled no)
				(sheetname "")
			)
			(fill
				(thermal_gap 0.5)
				(thermal_bridge_width 0.5)
				(island_removal_mode 0)
			)
			(polygon
				(pts
					(xy 193.4845 -57.531) (xy 193.4845 -58.293) (xy 192.9765 -58.293) (xy 192.9765 -57.531)
				)
			)
		)
	)
	(footprint ""
		(layer "F.Cu")
		(at 362.36656 -142.045182 -90)
		(property "Reference" "RF17"
			(at -0.8382 -0.67818 270)
			(unlocked yes)
			(layer "F.SilkS")
			(effects
				(font
					(size 0.4064 0.254)
					(thickness 0.1524)
				)
				(justify left)
			)
		)
		(property "Value" ""
			(at 0 0 270)
			(layer "F.Fab")
			(effects
				(font
					(size 1.27 1.27)
				)
			)
		)
		(duplicate_pad_numbers_are_jumpers no)
		(fp_poly
			(pts
				(xy -0.2794 -0.1016) (xy 0.2794 -0.1016) (xy 0.2794 0.9906) (xy -0.2794 0.9906)
			)
			(stroke
				(width 0)
				(type default)
			)
			(fill no)
			(layer "F.CrtYd")
		)
		(fp_line
			(start -0.2794 0.9906)
			(end 0.2794 0.9906)
			(stroke
				(width 0.1)
				(type default)
			)
			(layer "F.Fab")
		)
		(fp_line
			(start 0.2794 0.9906)
			(end 0.2794 -0.1016)
			(stroke
				(width 0.1)
				(type default)
			)
			(layer "F.Fab")
		)
		(fp_line
			(start -0.2794 -0.1016)
			(end -0.2794 0.9906)
			(stroke
				(width 0.1)
				(type default)
			)
			(layer "F.Fab")
		)
		(fp_line
			(start 0.2794 -0.1016)
			(end -0.2794 -0.1016)
			(stroke
				(width 0.1)
				(type default)
			)
			(layer "F.Fab")
		)
		(pad "1" smd rect
			(at 0 0 270)
			(size 0.508 0.508)
			(layers "F.Cu" "F.Mask" "F.Paste")
			(net "VR_PVDDQ_DEF_AIREF1")
		)
		(pad "2" smd rect
			(at 0 0.889 270)
			(size 0.508 0.508)
			(layers "F.Cu" "F.Mask" "F.Paste")
			(net "ISENSE_PVDDQ_DEF_PH1_IMON")
		)
		(zone
			(layer "F.Cu")
			(hatch none 0.5)
			(connect_pads
				(clearance 0)
			)
			(min_thickness 0.25)
			(keepout
				(tracks not_allowed)
				(vias allowed)
				(pads allowed)
				(copperpour not_allowed)
				(footprints allowed)
			)
			(placement
				(enabled no)
				(sheetname "")
			)
			(fill
				(thermal_gap 0.5)
				(thermal_bridge_width 0.5)
				(island_removal_mode 0)
			)
			(polygon
				(pts
					(xy 361.73156 -142.299182) (xy 361.73156 -141.791182) (xy 362.11256 -141.791182) (xy 362.11256 -142.299182)
				)
			)
		)
		(zone
			(layer "F.Cu")
			(hatch none 0.5)
			(connect_pads
				(clearance 0)
			)
			(min_thickness 0.25)
			(keepout
				(tracks allowed)
				(vias not_allowed)
				(pads allowed)
				(copperpour not_allowed)
				(footprints allowed)
			)
			(placement
				(enabled no)
				(sheetname "")
			)
			(fill
				(thermal_gap 0.5)
				(thermal_bridge_width 0.5)
				(island_removal_mode 0)
			)
			(polygon
				(pts
					(xy 362.11256 -142.299182) (xy 362.11256 -141.791182) (xy 361.73156 -141.791182) (xy 361.73156 -142.299182)
				)
			)
		)
	)
	(footprint ""
		(layer "F.Cu")
		(at 101.92004 -77.636116)
		(property "Reference" "C2D26"
			(at 0 0 0)
			(layer "F.SilkS")
			(hide yes)
			(effects
				(font
					(size 1.27 1.27)
				)
			)
		)
		(property "Value" ""
			(at 0 0 0)
			(layer "F.Fab")
			(effects
				(font
					(size 1.27 1.27)
				)
			)
		)
		(duplicate_pad_numbers_are_jumpers no)
		(fp_poly
			(pts
				(xy -0.4953 -0.2032) (xy 0.4953 -0.2032) (xy 0.4953 1.6002) (xy -0.4953 1.6002)
			)
			(stroke
				(width 0)
				(type default)
			)
			(fill no)
			(layer "F.CrtYd")
		)
		(fp_line
			(start -0.4953 -0.2032)
			(end 0.4953 -0.2032)
			(stroke
				(width 0.1)
				(type default)
			)
			(layer "F.Fab")
		)
		(fp_line
			(start -0.4953 1.6002)
			(end -0.4953 -0.2032)
			(stroke
				(width 0.1)
				(type default)
			)
			(layer "F.Fab")
		)
		(fp_line
			(start 0.4953 -0.2032)
			(end 0.4953 1.6002)
			(stroke
				(width 0.1)
				(type default)
			)
			(layer "F.Fab")
		)
		(fp_line
			(start 0.4953 1.6002)
			(end -0.4953 1.6002)
			(stroke
				(width 0.1)
				(type default)
			)
			(layer "F.Fab")
		)
		(pad "1" smd rect
			(at 0 0)
			(size 0.762 0.889)
			(layers "F.Cu" "F.Mask" "F.Paste")
			(net "PVCCIN_CPU1")
		)
		(pad "2" smd rect
			(at 0 1.397)
			(size 0.762 0.889)
			(layers "F.Cu" "F.Mask" "F.Paste")
			(net "GND")
		)
		(zone
			(layer "F.Cu")
			(hatch none 0.5)
			(connect_pads
				(clearance 0)
			)
			(min_thickness 0.25)
			(keepout
				(tracks not_allowed)
				(vias allowed)
				(pads allowed)
				(copperpour not_allowed)
				(footprints allowed)
			)
			(placement
				(enabled no)
				(sheetname "")
			)
			(fill
				(thermal_gap 0.5)
				(thermal_bridge_width 0.5)
				(island_removal_mode 0)
			)
			(polygon
				(pts
					(xy 101.53904 -77.191616) (xy 102.30104 -77.191616) (xy 102.30104 -76.683616) (xy 101.53904 -76.683616)
				)
			)
		)
	)
	(footprint ""
		(layer "F.Cu")
		(at 394.72743 -69.65315 90)
		(property "Reference" "C8E6"
			(at 0 0 90)
			(layer "F.SilkS")
			(hide yes)
			(effects
				(font
					(size 1.27 1.27)
				)
			)
		)
		(property "Value" ""
			(at 0 0 90)
			(layer "F.Fab")
			(effects
				(font
					(size 1.27 1.27)
				)
			)
		)
		(duplicate_pad_numbers_are_jumpers no)
		(fp_poly
			(pts
				(xy -0.4953 -0.2032) (xy 0.4953 -0.2032) (xy 0.4953 1.6002) (xy -0.4953 1.6002)
			)
			(stroke
				(width 0)
				(type default)
			)
			(fill no)
			(layer "F.CrtYd")
		)
		(fp_line
			(start 0.4953 -0.2032)
			(end 0.4953 1.6002)
			(stroke
				(width 0.1)
				(type default)
			)
			(layer "F.Fab")
		)
		(fp_line
			(start -0.4953 -0.2032)
			(end 0.4953 -0.2032)
			(stroke
				(width 0.1)
				(type default)
			)
			(layer "F.Fab")
		)
		(fp_line
			(start 0.4953 1.6002)
			(end -0.4953 1.6002)
			(stroke
				(width 0.1)
				(type default)
			)
			(layer "F.Fab")
		)
		(fp_line
			(start -0.4953 1.6002)
			(end -0.4953 -0.2032)
			(stroke
				(width 0.1)
				(type default)
			)
			(layer "F.Fab")
		)
		(pad "1" smd rect
			(at 0 0 90)
			(size 0.762 0.889)
			(layers "F.Cu" "F.Mask" "F.Paste")
			(net "VR_P5V_STBY_BOOT")
		)
		(pad "2" smd rect
			(at 0 1.397 90)
			(size 0.762 0.889)
			(layers "F.Cu" "F.Mask" "F.Paste")
			(net "VR_P5V_STBY_PHASE")
		)
		(zone
			(layer "F.Cu")
			(hatch none 0.5)
			(connect_pads
				(clearance 0)
			)
			(min_thickness 0.25)
			(keepout
				(tracks not_allowed)
				(vias allowed)
				(pads allowed)
				(copperpour not_allowed)
				(footprints allowed)
			)
			(placement
				(enabled no)
				(sheetname "")
			)
			(fill
				(thermal_gap 0.5)
				(thermal_bridge_width 0.5)
				(island_removal_mode 0)
			)
			(polygon
				(pts
					(xy 395.17193 -69.27215) (xy 395.17193 -70.03415) (xy 395.67993 -70.03415) (xy 395.67993 -69.27215)
				)
			)
		)
	)
	(footprint ""
		(layer "F.Cu")
		(at 183.134 -132.207 90)
		(property "Reference" "C6M5"
			(at 1.47828 0.78994 0)
			(unlocked yes)
			(layer "F.SilkS")
			(effects
				(font
					(size 0.4064 0.254)
					(thickness 0.1524)
				)
			)
		)
		(property "Value" ""
			(at 0 0 90)
			(layer "F.Fab")
			(effects
				(font
					(size 1.27 1.27)
				)
			)
		)
		(duplicate_pad_numbers_are_jumpers no)
		(fp_poly
			(pts
				(xy -0.7239 -0.2159) (xy 0.7239 -0.2159) (xy 0.7239 1.9939) (xy -0.7239 1.9939)
			)
			(stroke
				(width 0)
				(type default)
			)
			(fill no)
			(layer "F.CrtYd")
		)
		(fp_line
			(start 0.7239 -0.2159)
			(end -0.7239 -0.2159)
			(stroke
				(width 0.1)
				(type default)
			)
			(layer "F.Fab")
		)
		(fp_line
			(start -0.7239 -0.2159)
			(end -0.7239 1.9939)
			(stroke
				(width 0.1)
				(type default)
			)
			(layer "F.Fab")
		)
		(fp_line
			(start 0.7239 1.9939)
			(end 0.7239 -0.2159)
			(stroke
				(width 0.1)
				(type default)
			)
			(layer "F.Fab")
		)
		(fp_line
			(start -0.7239 1.9939)
			(end 0.7239 1.9939)
			(stroke
				(width 0.1)
				(type default)
			)
			(layer "F.Fab")
		)
		(pad "1" smd rect
			(at 0 0 90)
			(size 1.27 1.016)
			(layers "F.Cu" "F.Mask" "F.Paste")
			(net "VR_FET_SW_P12V_STBY_PVPP_KLM")
		)
		(pad "2" smd rect
			(at 0 1.778 90)
			(size 1.27 1.016)
			(layers "F.Cu" "F.Mask" "F.Paste")
			(net "GND")
		)
		(zone
			(layer "F.Cu")
			(hatch none 0.5)
			(connect_pads
				(clearance 0)
			)
			(min_thickness 0.25)
			(keepout
				(tracks not_allowed)
				(vias allowed)
				(pads allowed)
				(copperpour not_allowed)
				(footprints allowed)
			)
			(placement
				(enabled no)
				(sheetname "")
			)
			(fill
				(thermal_gap 0.5)
				(thermal_bridge_width 0.5)
				(island_removal_mode 0)
			)
			(polygon
				(pts
					(xy 183.642 -131.572) (xy 183.642 -132.842) (xy 184.404 -132.842) (xy 184.404 -131.572)
				)
			)
		)
	)
	(footprint ""
		(layer "F.Cu")
		(at 39.330122 -106.415586 -90)
		(property "Reference" "R9N2"
			(at 0 0 270)
			(layer "F.SilkS")
			(hide yes)
			(effects
				(font
					(size 1.27 1.27)
				)
			)
		)
		(property "Value" ""
			(at 0 0 270)
			(layer "F.Fab")
			(effects
				(font
					(size 1.27 1.27)
				)
			)
		)
		(duplicate_pad_numbers_are_jumpers no)
		(fp_poly
			(pts
				(xy -0.2794 -0.1016) (xy 0.2794 -0.1016) (xy 0.2794 0.9906) (xy -0.2794 0.9906)
			)
			(stroke
				(width 0)
				(type default)
			)
			(fill no)
			(layer "F.CrtYd")
		)
		(fp_line
			(start -0.2794 0.9906)
			(end 0.2794 0.9906)
			(stroke
				(width 0.1)
				(type default)
			)
			(layer "F.Fab")
		)
		(fp_line
			(start 0.2794 0.9906)
			(end 0.2794 -0.1016)
			(stroke
				(width 0.1)
				(type default)
			)
			(layer "F.Fab")
		)
		(fp_line
			(start -0.2794 -0.1016)
			(end -0.2794 0.9906)
			(stroke
				(width 0.1)
				(type default)
			)
			(layer "F.Fab")
		)
		(fp_line
			(start 0.2794 -0.1016)
			(end -0.2794 -0.1016)
			(stroke
				(width 0.1)
				(type default)
			)
			(layer "F.Fab")
		)
		(pad "1" smd rect
			(at 0 0 270)
			(size 0.508 0.508)
			(layers "F.Cu" "F.Mask" "F.Paste")
			(net "PVCCIO_CPU1")
		)
		(pad "2" smd rect
			(at 0 0.889 270)
			(size 0.508 0.508)
			(layers "F.Cu" "F.Mask" "F.Paste")
			(net "SVID_DIO1_CPU1_R")
		)
		(zone
			(layer "F.Cu")
			(hatch none 0.5)
			(connect_pads
				(clearance 0)
			)
			(min_thickness 0.25)
			(keepout
				(tracks not_allowed)
				(vias allowed)
				(pads allowed)
				(copperpour not_allowed)
				(footprints allowed)
			)
			(placement
				(enabled no)
				(sheetname "")
			)
			(fill
				(thermal_gap 0.5)
				(thermal_bridge_width 0.5)
				(island_removal_mode 0)
			)
			(polygon
				(pts
					(xy 38.695122 -106.669586) (xy 38.695122 -106.161586) (xy 39.076122 -106.161586) (xy 39.076122 -106.669586)
				)
			)
		)
		(zone
			(layer "F.Cu")
			(hatch none 0.5)
			(connect_pads
				(clearance 0)
			)
			(min_thickness 0.25)
			(keepout
				(tracks allowed)
				(vias not_allowed)
				(pads allowed)
				(copperpour not_allowed)
				(footprints allowed)
			)
			(placement
				(enabled no)
				(sheetname "")
			)
			(fill
				(thermal_gap 0.5)
				(thermal_bridge_width 0.5)
				(island_removal_mode 0)
			)
			(polygon
				(pts
					(xy 39.076122 -106.669586) (xy 39.076122 -106.161586) (xy 38.695122 -106.161586) (xy 38.695122 -106.669586)
				)
			)
		)
	)
	(footprint ""
		(layer "F.Cu")
		(at 379.4125 -36.5506)
		(property "Reference" "R8F35"
			(at 0 0 0)
			(layer "F.SilkS")
			(hide yes)
			(effects
				(font
					(size 1.27 1.27)
				)
			)
		)
		(property "Value" ""
			(at 0 0 0)
			(layer "F.Fab")
			(effects
				(font
					(size 1.27 1.27)
				)
			)
		)
		(duplicate_pad_numbers_are_jumpers no)
		(fp_poly
			(pts
				(xy -0.2794 -0.1016) (xy 0.2794 -0.1016) (xy 0.2794 0.9906) (xy -0.2794 0.9906)
			)
			(stroke
				(width 0)
				(type default)
			)
			(fill no)
			(layer "F.CrtYd")
		)
		(fp_line
			(start -0.2794 -0.1016)
			(end -0.2794 0.9906)
			(stroke
				(width 0.1)
				(type default)
			)
			(layer "F.Fab")
		)
		(fp_line
			(start -0.2794 0.9906)
			(end 0.2794 0.9906)
			(stroke
				(width 0.1)
				(type default)
			)
			(layer "F.Fab")
		)
		(fp_line
			(start 0.2794 -0.1016)
			(end -0.2794 -0.1016)
			(stroke
				(width 0.1)
				(type default)
			)
			(layer "F.Fab")
		)
		(fp_line
			(start 0.2794 0.9906)
			(end 0.2794 -0.1016)
			(stroke
				(width 0.1)
				(type default)
			)
			(layer "F.Fab")
		)
		(pad "1" smd rect
			(at 0 0)
			(size 0.508 0.508)
			(layers "F.Cu" "F.Mask" "F.Paste")
			(net "PU_SPI_BMC_BT_WP_N")
		)
		(pad "2" smd rect
			(at 0 0.889)
			(size 0.508 0.508)
			(layers "F.Cu" "F.Mask" "F.Paste")
			(net "GND")
		)
		(zone
			(layer "F.Cu")
			(hatch none 0.5)
			(connect_pads
				(clearance 0)
			)
			(min_thickness 0.25)
			(keepout
				(tracks allowed)
				(vias not_allowed)
				(pads allowed)
				(copperpour not_allowed)
				(footprints allowed)
			)
			(placement
				(enabled no)
				(sheetname "")
			)
			(fill
				(thermal_gap 0.5)
				(thermal_bridge_width 0.5)
				(island_removal_mode 0)
			)
			(polygon
				(pts
					(xy 379.1585 -36.2966) (xy 379.6665 -36.2966) (xy 379.6665 -35.9156) (xy 379.1585 -35.9156)
				)
			)
		)
		(zone
			(layer "F.Cu")
			(hatch none 0.5)
			(connect_pads
				(clearance 0)
			)
			(min_thickness 0.25)
			(keepout
				(tracks not_allowed)
				(vias allowed)
				(pads allowed)
				(copperpour not_allowed)
				(footprints allowed)
			)
			(placement
				(enabled no)
				(sheetname "")
			)
			(fill
				(thermal_gap 0.5)
				(thermal_bridge_width 0.5)
				(island_removal_mode 0)
			)
			(polygon
				(pts
					(xy 379.1585 -35.9156) (xy 379.6665 -35.9156) (xy 379.6665 -36.2966) (xy 379.1585 -36.2966)
				)
			)
		)
	)
	(footprint ""
		(layer "F.Cu")
		(at 29.495496 -27.150822 180)
		(property "Reference" "R12W14"
			(at 1.01473 0.656336 90)
			(unlocked yes)
			(layer "F.SilkS")
			(effects
				(font
					(size 0.4064 0.254)
					(thickness 0.1524)
				)
			)
		)
		(property "Value" ""
			(at 0 0 180)
			(layer "F.Fab")
			(effects
				(font
					(size 1.27 1.27)
				)
			)
		)
		(duplicate_pad_numbers_are_jumpers no)
		(fp_poly
			(pts
				(xy -0.4953 -0.2032) (xy 0.4953 -0.2032) (xy 0.4953 1.6002) (xy -0.4953 1.6002)
			)
			(stroke
				(width 0)
				(type default)
			)
			(fill no)
			(layer "F.CrtYd")
		)
		(fp_line
			(start 0.4953 1.6002)
			(end -0.4953 1.6002)
			(stroke
				(width 0.1)
				(type default)
			)
			(layer "F.Fab")
		)
		(fp_line
			(start 0.4953 -0.2032)
			(end 0.4953 1.6002)
			(stroke
				(width 0.1)
				(type default)
			)
			(layer "F.Fab")
		)
		(fp_line
			(start -0.4953 1.6002)
			(end -0.4953 -0.2032)
			(stroke
				(width 0.1)
				(type default)
			)
			(layer "F.Fab")
		)
		(fp_line
			(start -0.4953 -0.2032)
			(end 0.4953 -0.2032)
			(stroke
				(width 0.1)
				(type default)
			)
			(layer "F.Fab")
		)
		(pad "1" smd rect
			(at 0 0 180)
			(size 0.762 0.889)
			(layers "F.Cu" "F.Mask" "F.Paste")
			(net "P12V_NVDIMM_GHJ")
		)
		(pad "2" smd rect
			(at 0 1.397 180)
			(size 0.762 0.889)
			(layers "F.Cu" "F.Mask" "F.Paste")
			(net "PWRGD_PVDDQ_GHJ_N")
		)
		(zone
			(layer "F.Cu")
			(hatch none 0.5)
			(connect_pads
				(clearance 0)
			)
			(min_thickness 0.25)
			(keepout
				(tracks allowed)
				(vias not_allowed)
				(pads allowed)
				(copperpour not_allowed)
				(footprints allowed)
			)
			(placement
				(enabled no)
				(sheetname "")
			)
			(fill
				(thermal_gap 0.5)
				(thermal_bridge_width 0.5)
				(island_removal_mode 0)
			)
			(polygon
				(pts
					(xy 29.114496 -28.103322) (xy 29.114496 -27.595322) (xy 29.876496 -27.595322) (xy 29.876496 -28.103322)
				)
			)
		)
		(zone
			(layer "F.Cu")
			(hatch none 0.5)
			(connect_pads
				(clearance 0)
			)
			(min_thickness 0.25)
			(keepout
				(tracks not_allowed)
				(vias allowed)
				(pads allowed)
				(copperpour not_allowed)
				(footprints allowed)
			)
			(placement
				(enabled no)
				(sheetname "")
			)
			(fill
				(thermal_gap 0.5)
				(thermal_bridge_width 0.5)
				(island_removal_mode 0)
			)
			(polygon
				(pts
					(xy 29.876496 -28.103322) (xy 29.114496 -28.103322) (xy 29.114496 -27.595322) (xy 29.876496 -27.595322)
				)
			)
		)
	)
	(footprint ""
		(layer "F.Cu")
		(at 28.7528 -103.7844 90)
		(property "Reference" "R1C34"
			(at 0 0 90)
			(layer "F.SilkS")
			(hide yes)
			(effects
				(font
					(size 1.27 1.27)
				)
			)
		)
		(property "Value" ""
			(at 0 0 90)
			(layer "F.Fab")
			(effects
				(font
					(size 1.27 1.27)
				)
			)
		)
		(duplicate_pad_numbers_are_jumpers no)
		(fp_poly
			(pts
				(xy -0.2794 -0.1016) (xy 0.2794 -0.1016) (xy 0.2794 0.9906) (xy -0.2794 0.9906)
			)
			(stroke
				(width 0)
				(type default)
			)
			(fill no)
			(layer "F.CrtYd")
		)
		(fp_line
			(start 0.2794 -0.1016)
			(end -0.2794 -0.1016)
			(stroke
				(width 0.1)
				(type default)
			)
			(layer "F.Fab")
		)
		(fp_line
			(start -0.2794 -0.1016)
			(end -0.2794 0.9906)
			(stroke
				(width 0.1)
				(type default)
			)
			(layer "F.Fab")
		)
		(fp_line
			(start 0.2794 0.9906)
			(end 0.2794 -0.1016)
			(stroke
				(width 0.1)
				(type default)
			)
			(layer "F.Fab")
		)
		(fp_line
			(start -0.2794 0.9906)
			(end 0.2794 0.9906)
			(stroke
				(width 0.1)
				(type default)
			)
			(layer "F.Fab")
		)
		(pad "1" smd rect
			(at 0 0 90)
			(size 0.508 0.508)
			(layers "F.Cu" "F.Mask" "F.Paste")
			(net "P3V3_STBY")
		)
		(pad "2" smd rect
			(at 0 0.889 90)
			(size 0.508 0.508)
			(layers "F.Cu" "F.Mask" "F.Paste")
			(net "PU_PIROM_CPU1_ADDR0")
		)
		(zone
			(layer "F.Cu")
			(hatch none 0.5)
			(connect_pads
				(clearance 0)
			)
			(min_thickness 0.25)
			(keepout
				(tracks allowed)
				(vias not_allowed)
				(pads allowed)
				(copperpour not_allowed)
				(footprints allowed)
			)
			(placement
				(enabled no)
				(sheetname "")
			)
			(fill
				(thermal_gap 0.5)
				(thermal_bridge_width 0.5)
				(island_removal_mode 0)
			)
			(polygon
				(pts
					(xy 29.0068 -103.5304) (xy 29.0068 -104.0384) (xy 29.3878 -104.0384) (xy 29.3878 -103.5304)
				)
			)
		)
		(zone
			(layer "F.Cu")
			(hatch none 0.5)
			(connect_pads
				(clearance 0)
			)
			(min_thickness 0.25)
			(keepout
				(tracks not_allowed)
				(vias allowed)
				(pads allowed)
				(copperpour not_allowed)
				(footprints allowed)
			)
			(placement
				(enabled no)
				(sheetname "")
			)
			(fill
				(thermal_gap 0.5)
				(thermal_bridge_width 0.5)
				(island_removal_mode 0)
			)
			(polygon
				(pts
					(xy 29.3878 -103.5304) (xy 29.3878 -104.0384) (xy 29.0068 -104.0384) (xy 29.0068 -103.5304)
				)
			)
		)
	)
	(footprint ""
		(layer "F.Cu")
		(at 388.2263 -68.8848 180)
		(property "Reference" "C22W9"
			(at 0 0 180)
			(layer "F.SilkS")
			(hide yes)
			(effects
				(font
					(size 1.27 1.27)
				)
			)
		)
		(property "Value" "*"
			(at -0.0762 -6.2357 180)
			(unlocked yes)
			(layer "F.Fab")
			(hide yes)
			(effects
				(font
					(size 1.27 1.016)
					(thickness 0.1524)
				)
			)
		)
		(property "Device Type" "SC22U16V5MX-4-GP_SMD-BCG5-SC22A"
			(at -0.0762 -8.2677 180)
			(unlocked yes)
			(layer "F.Fab")
			(hide yes)
			(effects
				(font
					(size 1.27 1.016)
					(thickness 0.1524)
				)
			)
		)
		(duplicate_pad_numbers_are_jumpers no)
		(fp_line
			(start 0.635 0)
			(end -0.635 0)
			(stroke
				(width 0.508)
				(type default)
			)
			(layer "F.SilkS")
		)
		(fp_rect
			(start -0.9652 1.778)
			(end 0.9652 -1.778)
			(stroke
				(width 0)
				(type default)
			)
			(fill no)
			(layer "F.CrtYd")
		)
		(fp_poly
			(pts
				(xy -0.9652 -1.778) (xy 0.9652 -1.778) (xy 0.9652 1.778) (xy -0.9652 1.778)
			)
			(stroke
				(width 0)
				(type default)
			)
			(fill no)
			(layer "F.Fab")
		)
		(pad "1" smd rect
			(at 0 -0.9652 180)
			(size 1.397 1.143)
			(layers "F.Cu" "F.Mask" "F.Paste")
			(net "VR_FET_SW_P5V_STBY_PVIN")
		)
		(pad "2" smd rect
			(at 0 0.9652 180)
			(size 1.397 1.143)
			(layers "F.Cu" "F.Mask" "F.Paste")
			(net "GND")
		)
	)
	(footprint ""
		(layer "F.Cu")
		(at 348.488 -104.267 180)
		(property "Reference" "C22W28"
			(at 0 0 180)
			(layer "F.SilkS")
			(hide yes)
			(effects
				(font
					(size 1.27 1.27)
				)
			)
		)
		(property "Value" "*"
			(at -0.0762 -6.2357 180)
			(unlocked yes)
			(layer "F.Fab")
			(hide yes)
			(effects
				(font
					(size 1.27 1.016)
					(thickness 0.1524)
				)
			)
		)
		(property "Device Type" "SC22U16V5MX-4-GP_SMD-BCG5-SC22A"
			(at -0.0762 -8.2677 180)
			(unlocked yes)
			(layer "F.Fab")
			(hide yes)
			(effects
				(font
					(size 1.27 1.016)
					(thickness 0.1524)
				)
			)
		)
		(duplicate_pad_numbers_are_jumpers no)
		(fp_line
			(start 0.635 0)
			(end -0.635 0)
			(stroke
				(width 0.508)
				(type default)
			)
			(layer "F.SilkS")
		)
		(fp_rect
			(start -0.9652 1.778)
			(end 0.9652 -1.778)
			(stroke
				(width 0)
				(type default)
			)
			(fill no)
			(layer "F.CrtYd")
		)
		(fp_poly
			(pts
				(xy -0.9652 -1.778) (xy 0.9652 -1.778) (xy 0.9652 1.778) (xy -0.9652 1.778)
			)
			(stroke
				(width 0)
				(type default)
			)
			(fill no)
			(layer "F.Fab")
		)
		(pad "1" smd rect
			(at 0 -0.9652 180)
			(size 1.397 1.143)
			(layers "F.Cu" "F.Mask" "F.Paste")
			(net "VR_FET_SW_P12V_STBY_PVCCIO_CPU0")
		)
		(pad "2" smd rect
			(at 0 0.9652 180)
			(size 1.397 1.143)
			(layers "F.Cu" "F.Mask" "F.Paste")
			(net "GND")
		)
	)
	(footprint ""
		(layer "F.Cu")
		(at 401.472146 -36.458652 90)
		(property "Reference" "R6W18"
			(at -0.8382 -0.67818 90)
			(unlocked yes)
			(layer "F.SilkS")
			(effects
				(font
					(size 0.4064 0.254)
					(thickness 0.1524)
				)
				(justify left)
			)
		)
		(property "Value" ""
			(at 0 0 90)
			(layer "F.Fab")
			(effects
				(font
					(size 1.27 1.27)
				)
			)
		)
		(duplicate_pad_numbers_are_jumpers no)
		(fp_poly
			(pts
				(xy -0.2794 -0.1016) (xy 0.2794 -0.1016) (xy 0.2794 0.9906) (xy -0.2794 0.9906)
			)
			(stroke
				(width 0)
				(type default)
			)
			(fill no)
			(layer "F.CrtYd")
		)
		(fp_line
			(start 0.2794 -0.1016)
			(end -0.2794 -0.1016)
			(stroke
				(width 0.1)
				(type default)
			)
			(layer "F.Fab")
		)
		(fp_line
			(start -0.2794 -0.1016)
			(end -0.2794 0.9906)
			(stroke
				(width 0.1)
				(type default)
			)
			(layer "F.Fab")
		)
		(fp_line
			(start 0.2794 0.9906)
			(end 0.2794 -0.1016)
			(stroke
				(width 0.1)
				(type default)
			)
			(layer "F.Fab")
		)
		(fp_line
			(start -0.2794 0.9906)
			(end 0.2794 0.9906)
			(stroke
				(width 0.1)
				(type default)
			)
			(layer "F.Fab")
		)
		(pad "1" smd rect
			(at 0 0 90)
			(size 0.508 0.508)
			(layers "F.Cu" "F.Mask" "F.Paste")
			(net "SMB_DEBUG_STBY_LVC3_SDA")
		)
		(pad "2" smd rect
			(at 0 0.889 90)
			(size 0.508 0.508)
			(layers "F.Cu" "F.Mask" "F.Paste")
			(net "SMB_DEBUG_STBY_LVC3_SDA_R")
		)
		(zone
			(layer "F.Cu")
			(hatch none 0.5)
			(connect_pads
				(clearance 0)
			)
			(min_thickness 0.25)
			(keepout
				(tracks allowed)
				(vias not_allowed)
				(pads allowed)
				(copperpour not_allowed)
				(footprints allowed)
			)
			(placement
				(enabled no)
				(sheetname "")
			)
			(fill
				(thermal_gap 0.5)
				(thermal_bridge_width 0.5)
				(island_removal_mode 0)
			)
			(polygon
				(pts
					(xy 401.726146 -36.204652) (xy 401.726146 -36.712652) (xy 402.107146 -36.712652) (xy 402.107146 -36.204652)
				)
			)
		)
		(zone
			(layer "F.Cu")
			(hatch none 0.5)
			(connect_pads
				(clearance 0)
			)
			(min_thickness 0.25)
			(keepout
				(tracks not_allowed)
				(vias allowed)
				(pads allowed)
				(copperpour not_allowed)
				(footprints allowed)
			)
			(placement
				(enabled no)
				(sheetname "")
			)
			(fill
				(thermal_gap 0.5)
				(thermal_bridge_width 0.5)
				(island_removal_mode 0)
			)
			(polygon
				(pts
					(xy 402.107146 -36.204652) (xy 402.107146 -36.712652) (xy 401.726146 -36.712652) (xy 401.726146 -36.204652)
				)
			)
		)
	)
	(footprint ""
		(layer "F.Cu")
		(at 436.547006 -41.663874 180)
		(property "Reference" "R25W19"
			(at 0 0 180)
			(layer "F.SilkS")
			(hide yes)
			(effects
				(font
					(size 1.27 1.27)
				)
			)
		)
		(property "Value" "*"
			(at 0.064008 -4.108196 180)
			(unlocked yes)
			(layer "F.Fab")
			(hide yes)
			(effects
				(font
					(size 1.27 1.016)
					(thickness 0.1524)
				)
			)
		)
		(property "Device Type" "120R2F-GP_RCL_GP-120R2F-GP,64.A"
			(at 0.064008 -5.632196 180)
			(unlocked yes)
			(layer "F.Fab")
			(hide yes)
			(effects
				(font
					(size 1.27 1.016)
					(thickness 0.1524)
				)
			)
		)
		(duplicate_pad_numbers_are_jumpers no)
		(fp_line
			(start 0.508 -0.9398)
			(end -0.508 -0.9398)
			(stroke
				(width 0.1524)
				(type default)
			)
			(layer "F.SilkS")
		)
		(fp_line
			(start -0.508 -0.9398)
			(end -0.508 0.9398)
			(stroke
				(width 0.1524)
				(type default)
			)
			(layer "F.SilkS")
		)
		(fp_rect
			(start -0.508 0.9398)
			(end 0.508 -0.9398)
			(stroke
				(width 0)
				(type default)
			)
			(fill no)
			(layer "F.CrtYd")
		)
		(fp_rect
			(start -0.508 0.9398)
			(end 0.508 -0.9398)
			(stroke
				(width 0)
				(type default)
			)
			(fill no)
			(layer "F.Fab")
		)
		(pad "1" smd custom
			(at 0 -0.4445 180)
			(size 0.1397 0.1397)
			(layers "F.Cu" "F.Mask" "F.Paste")
			(net "GND")
			(options
				(clearance outline)
				(anchor circle)
			)
			(primitives
				(gr_poly
					(pts
						(arc
							(start -0.1778 -0.2794)
							(mid -0.249642 -0.249642)
							(end -0.2794 -0.1778)
						)
						(arc
							(start -0.2794 0.1778)
							(mid -0.249642 0.249642)
							(end -0.1778 0.2794)
						)
						(arc
							(start 0.1778 0.2794)
							(mid 0.249642 0.249642)
							(end 0.2794 0.1778)
						)
						(arc
							(start 0.2794 -0.1778)
							(mid 0.249642 -0.249642)
							(end 0.1778 -0.2794)
						)
					)
					(width 0)
					(fill yes)
				)
			)
		)
		(pad "2" smd custom
			(at 0 0.4445 180)
			(size 0.1397 0.1397)
			(layers "F.Cu" "F.Mask" "F.Paste")
			(net "BMC_M_A7")
			(options
				(clearance outline)
				(anchor circle)
			)
			(primitives
				(gr_poly
					(pts
						(arc
							(start -0.1778 -0.2794)
							(mid -0.249642 -0.249642)
							(end -0.2794 -0.1778)
						)
						(arc
							(start -0.2794 0.1778)
							(mid -0.249642 0.249642)
							(end -0.1778 0.2794)
						)
						(arc
							(start 0.1778 0.2794)
							(mid 0.249642 0.249642)
							(end 0.2794 0.1778)
						)
						(arc
							(start 0.2794 -0.1778)
							(mid 0.249642 -0.249642)
							(end 0.1778 -0.2794)
						)
					)
					(width 0)
					(fill yes)
				)
			)
		)
	)
	(footprint ""
		(layer "F.Cu")
		(at 383.345182 -75.137518 90)
		(property "Reference" "R7E2"
			(at 0 0 90)
			(layer "F.SilkS")
			(hide yes)
			(effects
				(font
					(size 1.27 1.27)
				)
			)
		)
		(property "Value" ""
			(at 0 0 90)
			(layer "F.Fab")
			(effects
				(font
					(size 1.27 1.27)
				)
			)
		)
		(duplicate_pad_numbers_are_jumpers no)
		(fp_poly
			(pts
				(xy -0.2794 -0.1016) (xy 0.2794 -0.1016) (xy 0.2794 0.9906) (xy -0.2794 0.9906)
			)
			(stroke
				(width 0)
				(type default)
			)
			(fill no)
			(layer "F.CrtYd")
		)
		(fp_line
			(start 0.2794 -0.1016)
			(end -0.2794 -0.1016)
			(stroke
				(width 0.1)
				(type default)
			)
			(layer "F.Fab")
		)
		(fp_line
			(start -0.2794 -0.1016)
			(end -0.2794 0.9906)
			(stroke
				(width 0.1)
				(type default)
			)
			(layer "F.Fab")
		)
		(fp_line
			(start 0.2794 0.9906)
			(end 0.2794 -0.1016)
			(stroke
				(width 0.1)
				(type default)
			)
			(layer "F.Fab")
		)
		(fp_line
			(start -0.2794 0.9906)
			(end 0.2794 0.9906)
			(stroke
				(width 0.1)
				(type default)
			)
			(layer "F.Fab")
		)
		(pad "1" smd rect
			(at 0 0 90)
			(size 0.508 0.508)
			(layers "F.Cu" "F.Mask" "F.Paste")
			(net "PVCCIO_CPU0")
		)
		(pad "2" smd rect
			(at 0 0.889 90)
			(size 0.508 0.508)
			(layers "F.Cu" "F.Mask" "F.Paste")
			(net "H_CPU0_THERMTRIP_G_N")
		)
		(zone
			(layer "F.Cu")
			(hatch none 0.5)
			(connect_pads
				(clearance 0)
			)
			(min_thickness 0.25)
			(keepout
				(tracks allowed)
				(vias not_allowed)
				(pads allowed)
				(copperpour not_allowed)
				(footprints allowed)
			)
			(placement
				(enabled no)
				(sheetname "")
			)
			(fill
				(thermal_gap 0.5)
				(thermal_bridge_width 0.5)
				(island_removal_mode 0)
			)
			(polygon
				(pts
					(xy 383.599182 -74.883518) (xy 383.599182 -75.391518) (xy 383.980182 -75.391518) (xy 383.980182 -74.883518)
				)
			)
		)
		(zone
			(layer "F.Cu")
			(hatch none 0.5)
			(connect_pads
				(clearance 0)
			)
			(min_thickness 0.25)
			(keepout
				(tracks not_allowed)
				(vias allowed)
				(pads allowed)
				(copperpour not_allowed)
				(footprints allowed)
			)
			(placement
				(enabled no)
				(sheetname "")
			)
			(fill
				(thermal_gap 0.5)
				(thermal_bridge_width 0.5)
				(island_removal_mode 0)
			)
			(polygon
				(pts
					(xy 383.980182 -74.883518) (xy 383.980182 -75.391518) (xy 383.599182 -75.391518) (xy 383.599182 -74.883518)
				)
			)
		)
	)
	(footprint ""
		(layer "F.Cu")
		(at 268.50721 -84.890102)
		(property "Reference" "C5D1"
			(at 0 0 0)
			(layer "F.SilkS")
			(hide yes)
			(effects
				(font
					(size 1.27 1.27)
				)
			)
		)
		(property "Value" ""
			(at 0 0 0)
			(layer "F.Fab")
			(effects
				(font
					(size 1.27 1.27)
				)
			)
		)
		(duplicate_pad_numbers_are_jumpers no)
		(fp_poly
			(pts
				(xy -0.4953 -0.2032) (xy 0.4953 -0.2032) (xy 0.4953 1.6002) (xy -0.4953 1.6002)
			)
			(stroke
				(width 0)
				(type default)
			)
			(fill no)
			(layer "F.CrtYd")
		)
		(fp_line
			(start -0.4953 -0.2032)
			(end 0.4953 -0.2032)
			(stroke
				(width 0.1)
				(type default)
			)
			(layer "F.Fab")
		)
		(fp_line
			(start -0.4953 1.6002)
			(end -0.4953 -0.2032)
			(stroke
				(width 0.1)
				(type default)
			)
			(layer "F.Fab")
		)
		(fp_line
			(start 0.4953 -0.2032)
			(end 0.4953 1.6002)
			(stroke
				(width 0.1)
				(type default)
			)
			(layer "F.Fab")
		)
		(fp_line
			(start 0.4953 1.6002)
			(end -0.4953 1.6002)
			(stroke
				(width 0.1)
				(type default)
			)
			(layer "F.Fab")
		)
		(pad "1" smd rect
			(at 0 0)
			(size 0.762 0.889)
			(layers "F.Cu" "F.Mask" "F.Paste")
			(net "PVDDQ_DEF")
		)
		(pad "2" smd rect
			(at 0 1.397)
			(size 0.762 0.889)
			(layers "F.Cu" "F.Mask" "F.Paste")
			(net "GND")
		)
		(zone
			(layer "F.Cu")
			(hatch none 0.5)
			(connect_pads
				(clearance 0)
			)
			(min_thickness 0.25)
			(keepout
				(tracks not_allowed)
				(vias allowed)
				(pads allowed)
				(copperpour not_allowed)
				(footprints allowed)
			)
			(placement
				(enabled no)
				(sheetname "")
			)
			(fill
				(thermal_gap 0.5)
				(thermal_bridge_width 0.5)
				(island_removal_mode 0)
			)
			(polygon
				(pts
					(xy 268.12621 -84.445602) (xy 268.88821 -84.445602) (xy 268.88821 -83.937602) (xy 268.12621 -83.937602)
				)
			)
		)
	)
	(footprint ""
		(layer "F.Cu")
		(at 403.988016 -152.703784 90)
		(property "Reference" "C8A4"
			(at 0 0 90)
			(layer "F.SilkS")
			(hide yes)
			(effects
				(font
					(size 1.27 1.27)
				)
			)
		)
		(property "Value" ""
			(at 0 0 90)
			(layer "F.Fab")
			(effects
				(font
					(size 1.27 1.27)
				)
			)
		)
		(duplicate_pad_numbers_are_jumpers no)
		(fp_poly
			(pts
				(xy -0.4953 -0.2032) (xy 0.4953 -0.2032) (xy 0.4953 1.6002) (xy -0.4953 1.6002)
			)
			(stroke
				(width 0)
				(type default)
			)
			(fill no)
			(layer "F.CrtYd")
		)
		(fp_line
			(start 0.4953 -0.2032)
			(end 0.4953 1.6002)
			(stroke
				(width 0.1)
				(type default)
			)
			(layer "F.Fab")
		)
		(fp_line
			(start -0.4953 -0.2032)
			(end 0.4953 -0.2032)
			(stroke
				(width 0.1)
				(type default)
			)
			(layer "F.Fab")
		)
		(fp_line
			(start 0.4953 1.6002)
			(end -0.4953 1.6002)
			(stroke
				(width 0.1)
				(type default)
			)
			(layer "F.Fab")
		)
		(fp_line
			(start -0.4953 1.6002)
			(end -0.4953 -0.2032)
			(stroke
				(width 0.1)
				(type default)
			)
			(layer "F.Fab")
		)
		(pad "1" smd rect
			(at 0 0 90)
			(size 0.762 0.889)
			(layers "F.Cu" "F.Mask" "F.Paste")
			(net "P3V3_STBY")
		)
		(pad "2" smd rect
			(at 0 1.397 90)
			(size 0.762 0.889)
			(layers "F.Cu" "F.Mask" "F.Paste")
			(net "GND")
		)
		(zone
			(layer "F.Cu")
			(hatch none 0.5)
			(connect_pads
				(clearance 0)
			)
			(min_thickness 0.25)
			(keepout
				(tracks not_allowed)
				(vias allowed)
				(pads allowed)
				(copperpour not_allowed)
				(footprints allowed)
			)
			(placement
				(enabled no)
				(sheetname "")
			)
			(fill
				(thermal_gap 0.5)
				(thermal_bridge_width 0.5)
				(island_removal_mode 0)
			)
			(polygon
				(pts
					(xy 404.432516 -152.322784) (xy 404.432516 -153.084784) (xy 404.940516 -153.084784) (xy 404.940516 -152.322784)
				)
			)
		)
	)
	(footprint ""
		(layer "F.Cu")
		(at 184.985914 -61.976 180)
		(property "Reference" "R4E20"
			(at 0 0 180)
			(layer "F.SilkS")
			(hide yes)
			(effects
				(font
					(size 1.27 1.27)
				)
			)
		)
		(property "Value" ""
			(at 0 0 180)
			(layer "F.Fab")
			(effects
				(font
					(size 1.27 1.27)
				)
			)
		)
		(duplicate_pad_numbers_are_jumpers no)
		(fp_rect
			(start 0.2794 -0.1016)
			(end -0.2794 0.9906)
			(stroke
				(width 0)
				(type default)
			)
			(fill no)
			(layer "F.CrtYd")
		)
		(fp_line
			(start 0.2794 0.9906)
			(end 0.2794 -0.1016)
			(stroke
				(width 0.1)
				(type default)
			)
			(layer "F.Fab")
		)
		(fp_line
			(start 0.2794 -0.1016)
			(end -0.2794 -0.1016)
			(stroke
				(width 0.1)
				(type default)
			)
			(layer "F.Fab")
		)
		(fp_line
			(start -0.2794 0.9906)
			(end 0.2794 0.9906)
			(stroke
				(width 0.1)
				(type default)
			)
			(layer "F.Fab")
		)
		(fp_line
			(start -0.2794 -0.1016)
			(end -0.2794 0.9906)
			(stroke
				(width 0.1)
				(type default)
			)
			(layer "F.Fab")
		)
		(pad "1" smd rect
			(at 0 0 180)
			(size 0.508 0.508)
			(layers "F.Cu" "F.Mask" "F.Paste")
			(net "P3V3_STBY")
		)
		(pad "2" smd rect
			(at 0 0.889 180)
			(size 0.508 0.508)
			(layers "F.Cu" "F.Mask" "F.Paste")
			(net "PU_VR_PVCCIN_CPU0_FLT1_SMBALT_N")
		)
		(zone
			(layer "F.Cu")
			(hatch none 0.5)
			(connect_pads
				(clearance 0)
			)
			(min_thickness 0.25)
			(keepout
				(tracks not_allowed)
				(vias allowed)
				(pads allowed)
				(copperpour not_allowed)
				(footprints allowed)
			)
			(placement
				(enabled no)
				(sheetname "")
			)
			(fill
				(thermal_gap 0.5)
				(thermal_bridge_width 0.5)
				(island_removal_mode 0)
			)
			(polygon
				(pts
					(xy 184.731914 -62.23) (xy 185.239914 -62.23) (xy 185.239914 -62.611) (xy 184.731914 -62.611)
				)
			)
		)
		(zone
			(layer "F.Cu")
			(hatch none 0.5)
			(connect_pads
				(clearance 0)
			)
			(min_thickness 0.25)
			(keepout
				(tracks allowed)
				(vias not_allowed)
				(pads allowed)
				(copperpour not_allowed)
				(footprints allowed)
			)
			(placement
				(enabled no)
				(sheetname "")
			)
			(fill
				(thermal_gap 0.5)
				(thermal_bridge_width 0.5)
				(island_removal_mode 0)
			)
			(polygon
				(pts
					(xy 184.731914 -62.23) (xy 185.239914 -62.23) (xy 185.239914 -62.611) (xy 184.731914 -62.611)
				)
			)
		)
	)
	(footprint ""
		(layer "F.Cu")
		(at 193.929 -67.1576 90)
		(property "Reference" "C4D50"
			(at 0 0 90)
			(layer "F.SilkS")
			(hide yes)
			(effects
				(font
					(size 1.27 1.27)
				)
			)
		)
		(property "Value" ""
			(at 0 0 90)
			(layer "F.Fab")
			(effects
				(font
					(size 1.27 1.27)
				)
			)
		)
		(duplicate_pad_numbers_are_jumpers no)
		(fp_rect
			(start -0.3048 0.9906)
			(end 0.3048 -0.1016)
			(stroke
				(width 0)
				(type default)
			)
			(fill no)
			(layer "F.CrtYd")
		)
		(fp_line
			(start 0.3048 -0.1016)
			(end -0.3048 -0.1016)
			(stroke
				(width 0.1)
				(type default)
			)
			(layer "F.Fab")
		)
		(fp_line
			(start -0.3048 -0.1016)
			(end -0.3048 0.9906)
			(stroke
				(width 0.1)
				(type default)
			)
			(layer "F.Fab")
		)
		(fp_line
			(start 0.3048 0.9906)
			(end 0.3048 -0.1016)
			(stroke
				(width 0.1)
				(type default)
			)
			(layer "F.Fab")
		)
		(fp_line
			(start -0.3048 0.9906)
			(end 0.3048 0.9906)
			(stroke
				(width 0.1)
				(type default)
			)
			(layer "F.Fab")
		)
		(pad "1" smd rect
			(at 0 0 90)
			(size 0.508 0.508)
			(layers "F.Cu" "F.Mask" "F.Paste")
			(net "VR_PVCCIN_CPU0_PH2_BOOT")
		)
		(pad "2" smd rect
			(at 0 0.889 90)
			(size 0.508 0.508)
			(layers "F.Cu" "F.Mask" "F.Paste")
			(net "VR_PVCCIN_CPU0_PH2_PHASE")
		)
		(zone
			(layer "F.Cu")
			(hatch none 0.5)
			(connect_pads
				(clearance 0)
			)
			(min_thickness 0.25)
			(keepout
				(tracks not_allowed)
				(vias allowed)
				(pads allowed)
				(copperpour not_allowed)
				(footprints allowed)
			)
			(placement
				(enabled no)
				(sheetname "")
			)
			(fill
				(thermal_gap 0.5)
				(thermal_bridge_width 0.5)
				(island_removal_mode 0)
			)
			(polygon
				(pts
					(xy 194.564 -66.9036) (xy 194.564 -67.4116) (xy 194.183 -67.4116) (xy 194.183 -66.9036)
				)
			)
		)
		(zone
			(layer "F.Cu")
			(hatch none 0.5)
			(connect_pads
				(clearance 0)
			)
			(min_thickness 0.25)
			(keepout
				(tracks allowed)
				(vias not_allowed)
				(pads allowed)
				(copperpour not_allowed)
				(footprints allowed)
			)
			(placement
				(enabled no)
				(sheetname "")
			)
			(fill
				(thermal_gap 0.5)
				(thermal_bridge_width 0.5)
				(island_removal_mode 0)
			)
			(polygon
				(pts
					(xy 194.564 -66.9036) (xy 194.564 -67.4116) (xy 194.183 -67.4116) (xy 194.183 -66.9036)
				)
			)
		)
	)
	(footprint ""
		(layer "F.Cu")
		(at 402.717 -24.892)
		(property "Reference" "R25W113"
			(at -0.8382 -0.67818 0)
			(unlocked yes)
			(layer "F.SilkS")
			(effects
				(font
					(size 0.4064 0.254)
					(thickness 0.1524)
				)
				(justify left)
			)
		)
		(property "Value" ""
			(at 0 0 0)
			(layer "F.Fab")
			(effects
				(font
					(size 1.27 1.27)
				)
			)
		)
		(duplicate_pad_numbers_are_jumpers no)
		(fp_poly
			(pts
				(xy -0.2794 -0.1016) (xy 0.2794 -0.1016) (xy 0.2794 0.9906) (xy -0.2794 0.9906)
			)
			(stroke
				(width 0)
				(type default)
			)
			(fill no)
			(layer "F.CrtYd")
		)
		(fp_line
			(start -0.2794 -0.1016)
			(end -0.2794 0.9906)
			(stroke
				(width 0.1)
				(type default)
			)
			(layer "F.Fab")
		)
		(fp_line
			(start -0.2794 0.9906)
			(end 0.2794 0.9906)
			(stroke
				(width 0.1)
				(type default)
			)
			(layer "F.Fab")
		)
		(fp_line
			(start 0.2794 -0.1016)
			(end -0.2794 -0.1016)
			(stroke
				(width 0.1)
				(type default)
			)
			(layer "F.Fab")
		)
		(fp_line
			(start 0.2794 0.9906)
			(end 0.2794 -0.1016)
			(stroke
				(width 0.1)
				(type default)
			)
			(layer "F.Fab")
		)
		(pad "1" smd rect
			(at 0 0)
			(size 0.508 0.508)
			(layers "F.Cu" "F.Mask" "F.Paste")
			(net "P3V3_STBY")
		)
		(pad "2" smd rect
			(at 0 0.889)
			(size 0.508 0.508)
			(layers "F.Cu" "F.Mask" "F.Paste")
			(net "RMII_BMC_PCH_SPRNGVLLE_TXD1_R")
		)
		(zone
			(layer "F.Cu")
			(hatch none 0.5)
			(connect_pads
				(clearance 0)
			)
			(min_thickness 0.25)
			(keepout
				(tracks allowed)
				(vias not_allowed)
				(pads allowed)
				(copperpour not_allowed)
				(footprints allowed)
			)
			(placement
				(enabled no)
				(sheetname "")
			)
			(fill
				(thermal_gap 0.5)
				(thermal_bridge_width 0.5)
				(island_removal_mode 0)
			)
			(polygon
				(pts
					(xy 402.463 -24.638) (xy 402.971 -24.638) (xy 402.971 -24.257) (xy 402.463 -24.257)
				)
			)
		)
		(zone
			(layer "F.Cu")
			(hatch none 0.5)
			(connect_pads
				(clearance 0)
			)
			(min_thickness 0.25)
			(keepout
				(tracks not_allowed)
				(vias allowed)
				(pads allowed)
				(copperpour not_allowed)
				(footprints allowed)
			)
			(placement
				(enabled no)
				(sheetname "")
			)
			(fill
				(thermal_gap 0.5)
				(thermal_bridge_width 0.5)
				(island_removal_mode 0)
			)
			(polygon
				(pts
					(xy 402.463 -24.257) (xy 402.971 -24.257) (xy 402.971 -24.638) (xy 402.463 -24.638)
				)
			)
		)
	)
	(footprint ""
		(layer "F.Cu")
		(at 451.85838 -37.1475 90)
		(property "Reference" "R25W46"
			(at 0 0 90)
			(layer "F.SilkS")
			(hide yes)
			(effects
				(font
					(size 1.27 1.27)
				)
			)
		)
		(property "Value" "*"
			(at 0.064008 -4.108196 90)
			(unlocked yes)
			(layer "F.Fab")
			(hide yes)
			(effects
				(font
					(size 1.27 1.016)
					(thickness 0.1524)
				)
			)
		)
		(property "Device Type" "120R2F-GP_RCL_GP-120R2F-GP,64.A"
			(at 0.064008 -5.632196 90)
			(unlocked yes)
			(layer "F.Fab")
			(hide yes)
			(effects
				(font
					(size 1.27 1.016)
					(thickness 0.1524)
				)
			)
		)
		(duplicate_pad_numbers_are_jumpers no)
		(fp_line
			(start 0.508 -0.9398)
			(end -0.508 -0.9398)
			(stroke
				(width 0.1524)
				(type default)
			)
			(layer "F.SilkS")
		)
		(fp_line
			(start -0.508 -0.9398)
			(end -0.508 0.9398)
			(stroke
				(width 0.1524)
				(type default)
			)
			(layer "F.SilkS")
		)
		(fp_rect
			(start -0.508 0.9398)
			(end 0.508 -0.9398)
			(stroke
				(width 0)
				(type default)
			)
			(fill no)
			(layer "F.CrtYd")
		)
		(fp_rect
			(start -0.508 0.9398)
			(end 0.508 -0.9398)
			(stroke
				(width 0)
				(type default)
			)
			(fill no)
			(layer "F.Fab")
		)
		(pad "1" smd custom
			(at 0 -0.4445 90)
			(size 0.1397 0.1397)
			(layers "F.Cu" "F.Mask" "F.Paste")
			(net "BMC_M_A8")
			(options
				(clearance outline)
				(anchor circle)
			)
			(primitives
				(gr_poly
					(pts
						(arc
							(start -0.1778 -0.2794)
							(mid -0.249642 -0.249642)
							(end -0.2794 -0.1778)
						)
						(arc
							(start -0.2794 0.1778)
							(mid -0.249642 0.249642)
							(end -0.1778 0.2794)
						)
						(arc
							(start 0.1778 0.2794)
							(mid 0.249642 0.249642)
							(end 0.2794 0.1778)
						)
						(arc
							(start 0.2794 -0.1778)
							(mid 0.249642 -0.249642)
							(end 0.1778 -0.2794)
						)
					)
					(width 0)
					(fill yes)
				)
			)
		)
		(pad "2" smd custom
			(at 0 0.4445 90)
			(size 0.1397 0.1397)
			(layers "F.Cu" "F.Mask" "F.Paste")
			(net "P1V2_AUX_BMC")
			(options
				(clearance outline)
				(anchor circle)
			)
			(primitives
				(gr_poly
					(pts
						(arc
							(start -0.1778 -0.2794)
							(mid -0.249642 -0.249642)
							(end -0.2794 -0.1778)
						)
						(arc
							(start -0.2794 0.1778)
							(mid -0.249642 0.249642)
							(end -0.1778 0.2794)
						)
						(arc
							(start 0.1778 0.2794)
							(mid 0.249642 0.249642)
							(end 0.2794 0.1778)
						)
						(arc
							(start 0.2794 -0.1778)
							(mid 0.249642 -0.249642)
							(end 0.1778 -0.2794)
						)
					)
					(width 0)
					(fill yes)
				)
			)
		)
	)
	(footprint ""
		(layer "F.Cu")
		(at 33.178496 -77.605382 90)
		(property "Reference" "C1D6"
			(at 0 0 90)
			(layer "F.SilkS")
			(hide yes)
			(effects
				(font
					(size 1.27 1.27)
				)
			)
		)
		(property "Value" ""
			(at 0 0 90)
			(layer "F.Fab")
			(effects
				(font
					(size 1.27 1.27)
				)
			)
		)
		(duplicate_pad_numbers_are_jumpers no)
		(fp_rect
			(start 0.3048 0.9906)
			(end -0.3048 -0.1016)
			(stroke
				(width 0)
				(type default)
			)
			(fill no)
			(layer "F.CrtYd")
		)
		(fp_line
			(start 0.3048 -0.1016)
			(end -0.3048 -0.1016)
			(stroke
				(width 0.1)
				(type default)
			)
			(layer "F.Fab")
		)
		(fp_line
			(start -0.3048 -0.1016)
			(end -0.3048 0.9906)
			(stroke
				(width 0.1)
				(type default)
			)
			(layer "F.Fab")
		)
		(fp_line
			(start 0.3048 0.9906)
			(end 0.3048 -0.1016)
			(stroke
				(width 0.1)
				(type default)
			)
			(layer "F.Fab")
		)
		(fp_line
			(start -0.3048 0.9906)
			(end 0.3048 0.9906)
			(stroke
				(width 0.1)
				(type default)
			)
			(layer "F.Fab")
		)
		(pad "1" smd rect
			(at 0 0 90)
			(size 0.508 0.508)
			(layers "F.Cu" "F.Mask" "F.Paste")
			(net "P5V_STBY")
		)
		(pad "2" smd rect
			(at 0 0.889 90)
			(size 0.508 0.508)
			(layers "F.Cu" "F.Mask" "F.Paste")
			(net "GND")
		)
		(zone
			(layer "F.Cu")
			(hatch none 0.5)
			(connect_pads
				(clearance 0)
			)
			(min_thickness 0.25)
			(keepout
				(tracks not_allowed)
				(vias allowed)
				(pads allowed)
				(copperpour not_allowed)
				(footprints allowed)
			)
			(placement
				(enabled no)
				(sheetname "")
			)
			(fill
				(thermal_gap 0.5)
				(thermal_bridge_width 0.5)
				(island_removal_mode 0)
			)
			(polygon
				(pts
					(xy 33.813496 -77.859382) (xy 33.432496 -77.859382) (xy 33.432496 -77.351382) (xy 33.813496 -77.351382)
				)
			)
		)
		(zone
			(layer "F.Cu")
			(hatch none 0.5)
			(connect_pads
				(clearance 0)
			)
			(min_thickness 0.25)
			(keepout
				(tracks allowed)
				(vias not_allowed)
				(pads allowed)
				(copperpour not_allowed)
				(footprints allowed)
			)
			(placement
				(enabled no)
				(sheetname "")
			)
			(fill
				(thermal_gap 0.5)
				(thermal_bridge_width 0.5)
				(island_removal_mode 0)
			)
			(polygon
				(pts
					(xy 33.813496 -77.859382) (xy 33.432496 -77.859382) (xy 33.432496 -77.351382) (xy 33.813496 -77.351382)
				)
			)
		)
	)
	(footprint ""
		(layer "F.Cu")
		(at 14.732 -88.4936 -90)
		(property "Reference" "R1C30"
			(at 0 0 270)
			(layer "F.SilkS")
			(hide yes)
			(effects
				(font
					(size 1.27 1.27)
				)
			)
		)
		(property "Value" ""
			(at 0 0 270)
			(layer "F.Fab")
			(effects
				(font
					(size 1.27 1.27)
				)
			)
		)
		(duplicate_pad_numbers_are_jumpers no)
		(fp_rect
			(start 0.2794 0.9906)
			(end -0.2794 -0.1016)
			(stroke
				(width 0)
				(type default)
			)
			(fill no)
			(layer "F.CrtYd")
		)
		(fp_line
			(start -0.2794 0.9906)
			(end 0.2794 0.9906)
			(stroke
				(width 0.1)
				(type default)
			)
			(layer "F.Fab")
		)
		(fp_line
			(start 0.2794 0.9906)
			(end 0.2794 -0.1016)
			(stroke
				(width 0.1)
				(type default)
			)
			(layer "F.Fab")
		)
		(fp_line
			(start -0.2794 -0.1016)
			(end -0.2794 0.9906)
			(stroke
				(width 0.1)
				(type default)
			)
			(layer "F.Fab")
		)
		(fp_line
			(start 0.2794 -0.1016)
			(end -0.2794 -0.1016)
			(stroke
				(width 0.1)
				(type default)
			)
			(layer "F.Fab")
		)
		(pad "1" smd rect
			(at 0 0 270)
			(size 0.508 0.508)
			(layers "F.Cu" "F.Mask" "F.Paste")
			(net "VR_VRRDY_PVCCIN_CPU1")
		)
		(pad "2" smd rect
			(at 0 0.889 270)
			(size 0.508 0.508)
			(layers "F.Cu" "F.Mask" "F.Paste")
			(net "PWRGD_PVCCIN_CPU1")
		)
		(zone
			(layer "F.Cu")
			(hatch none 0.5)
			(connect_pads
				(clearance 0)
			)
			(min_thickness 0.25)
			(keepout
				(tracks not_allowed)
				(vias allowed)
				(pads allowed)
				(copperpour not_allowed)
				(footprints allowed)
			)
			(placement
				(enabled no)
				(sheetname "")
			)
			(fill
				(thermal_gap 0.5)
				(thermal_bridge_width 0.5)
				(island_removal_mode 0)
			)
			(polygon
				(pts
					(xy 14.097 -88.2396) (xy 14.478 -88.2396) (xy 14.478 -88.7476) (xy 14.097 -88.7476)
				)
			)
		)
		(zone
			(layer "F.Cu")
			(hatch none 0.5)
			(connect_pads
				(clearance 0)
			)
			(min_thickness 0.25)
			(keepout
				(tracks allowed)
				(vias not_allowed)
				(pads allowed)
				(copperpour not_allowed)
				(footprints allowed)
			)
			(placement
				(enabled no)
				(sheetname "")
			)
			(fill
				(thermal_gap 0.5)
				(thermal_bridge_width 0.5)
				(island_removal_mode 0)
			)
			(polygon
				(pts
					(xy 14.097 -88.2396) (xy 14.478 -88.2396) (xy 14.478 -88.7476) (xy 14.097 -88.7476)
				)
			)
		)
	)
	(footprint ""
		(layer "F.Cu")
		(at 3.4798 -64.77 -90)
		(property "Reference" "VR1D1"
			(at -4.06273 5.6896 0)
			(unlocked yes)
			(layer "F.SilkS")
			(effects
				(font
					(size 0.7874 0.5842)
					(thickness 0.1524)
				)
				(justify left)
			)
		)
		(property "Value" ""
			(at 0 0 270)
			(layer "F.Fab")
			(effects
				(font
					(size 1.27 1.27)
				)
			)
		)
		(duplicate_pad_numbers_are_jumpers no)
		(fp_line
			(start -3.1115 7.5946)
			(end -1.9431 7.5946)
			(stroke
				(width 0.1524)
				(type default)
			)
			(layer "F.SilkS")
		)
		(fp_line
			(start -3.1115 7.5946)
			(end -3.1115 -0.2286)
			(stroke
				(width 0.1524)
				(type default)
			)
			(layer "F.SilkS")
		)
		(fp_line
			(start 1.9431 7.5946)
			(end 3.1115 7.5946)
			(stroke
				(width 0.1524)
				(type default)
			)
			(layer "F.SilkS")
		)
		(fp_line
			(start -3.1115 -0.2286)
			(end -1.9431 -0.2286)
			(stroke
				(width 0.1524)
				(type default)
			)
			(layer "F.SilkS")
		)
		(fp_line
			(start 1.9431 -0.2286)
			(end 3.1115 -0.2286)
			(stroke
				(width 0.1524)
				(type default)
			)
			(layer "F.SilkS")
		)
		(fp_line
			(start 3.1115 -0.2286)
			(end 3.1115 7.5946)
			(stroke
				(width 0.1524)
				(type default)
			)
			(layer "F.SilkS")
		)
		(fp_circle
			(center -2.065528 -0.818388)
			(end -2.065528 -0.945388)
			(stroke
				(width 0.254)
				(type default)
			)
			(fill no)
			(layer "F.SilkS")
		)
		(fp_poly
			(pts
				(xy -3.1115 7.5946) (xy 3.1115 7.5946) (xy 3.1115 -0.2286) (xy -3.1115 -0.2286)
			)
			(stroke
				(width 0)
				(type default)
			)
			(fill no)
			(layer "F.CrtYd")
		)
		(fp_line
			(start -3.1115 7.5946)
			(end 3.1115 7.5946)
			(stroke
				(width 0.1)
				(type default)
			)
			(layer "F.Fab")
		)
		(fp_line
			(start 3.1115 7.5946)
			(end 3.1115 -0.2286)
			(stroke
				(width 0.1)
				(type default)
			)
			(layer "F.Fab")
		)
		(fp_line
			(start -3.1115 -0.2286)
			(end -3.1115 7.5946)
			(stroke
				(width 0.1)
				(type default)
			)
			(layer "F.Fab")
		)
		(fp_line
			(start 3.1115 -0.2286)
			(end -3.1115 -0.2286)
			(stroke
				(width 0.1)
				(type default)
			)
			(layer "F.Fab")
		)
		(fp_circle
			(center -2.413 -0.9906)
			(end -2.413 -1.1176)
			(stroke
				(width 0.254)
				(type default)
			)
			(fill no)
			(layer "F.Fab")
		)
		(pad "1" smd rect
			(at 0 0 270)
			(size 3.048 2.286)
			(layers "F.Cu" "F.Mask" "F.Paste")
			(net "P12V_PSU")
		)
		(pad "2" smd rect
			(at 0 7.366 270)
			(size 3.048 2.286)
			(layers "F.Cu" "F.Mask" "F.Paste")
			(net "GND")
		)
	)
	(footprint ""
		(layer "F.Cu")
		(at 381.51562 -150.965916 180)
		(property "Reference" "RT45"
			(at 0 0 180)
			(layer "F.SilkS")
			(hide yes)
			(effects
				(font
					(size 1.27 1.27)
				)
			)
		)
		(property "Value" "*"
			(at -0.0254 -2.6289 180)
			(unlocked yes)
			(layer "F.Fab")
			(hide yes)
			(effects
				(font
					(size 1.27 1.016)
					(thickness 0.1524)
				)
			)
		)
		(property "Device Type" "1R3F-GP_RCL_GP-1R3F-GP,64.1R00A"
			(at -0.0254 -4.1529 180)
			(unlocked yes)
			(layer "F.Fab")
			(hide yes)
			(effects
				(font
					(size 1.27 1.016)
					(thickness 0.1524)
				)
			)
		)
		(duplicate_pad_numbers_are_jumpers no)
		(fp_line
			(start 0.2032 0)
			(end 0.4826 0)
			(stroke
				(width 0.2032)
				(type default)
			)
			(layer "F.SilkS")
		)
		(fp_line
			(start -0.4826 0)
			(end -0.2032 0)
			(stroke
				(width 0.2032)
				(type default)
			)
			(layer "F.SilkS")
		)
		(fp_poly
			(pts
				(xy -0.5842 1.3335) (xy 0.5842 1.3335) (xy 0.5842 -1.3335) (xy -0.5842 -1.3335)
			)
			(stroke
				(width 0)
				(type default)
			)
			(fill no)
			(layer "F.CrtYd")
		)
		(fp_rect
			(start -0.5842 1.3335)
			(end 0.5842 -1.3335)
			(stroke
				(width 0)
				(type default)
			)
			(fill no)
			(layer "F.Fab")
		)
		(pad "1" smd custom
			(at 0 -0.762 180)
			(size 0.2159 0.2159)
			(layers "F.Cu" "F.Mask" "F.Paste")
			(net "VR_P1V05_PCH_STBY_PH1_SW_RC")
			(options
				(clearance outline)
				(anchor circle)
			)
			(primitives
				(gr_poly
					(pts
						(arc
							(start -0.3302 -0.4318)
							(mid -0.402042 -0.402042)
							(end -0.4318 -0.3302)
						)
						(arc
							(start -0.4318 0.3302)
							(mid -0.402042 0.402042)
							(end -0.3302 0.4318)
						)
						(arc
							(start 0.3302 0.4318)
							(mid 0.402042 0.402042)
							(end 0.4318 0.3302)
						)
						(arc
							(start 0.4318 -0.3302)
							(mid 0.402042 -0.402042)
							(end 0.3302 -0.4318)
						)
					)
					(width 0)
					(fill yes)
				)
			)
		)
		(pad "2" smd custom
			(at 0 0.762 180)
			(size 0.2159 0.2159)
			(layers "F.Cu" "F.Mask" "F.Paste")
			(net "GND")
			(options
				(clearance outline)
				(anchor circle)
			)
			(primitives
				(gr_poly
					(pts
						(arc
							(start -0.3302 -0.4318)
							(mid -0.402042 -0.402042)
							(end -0.4318 -0.3302)
						)
						(arc
							(start -0.4318 0.3302)
							(mid -0.402042 0.402042)
							(end -0.3302 0.4318)
						)
						(arc
							(start 0.3302 0.4318)
							(mid 0.402042 0.402042)
							(end 0.4318 0.3302)
						)
						(arc
							(start 0.4318 -0.3302)
							(mid 0.402042 -0.402042)
							(end 0.3302 -0.4318)
						)
					)
					(width 0)
					(fill yes)
				)
			)
		)
	)
	(footprint ""
		(layer "F.Cu")
		(at 162.687 -104.14)
		(property "Reference" "C3C2"
			(at 0 0 0)
			(layer "F.SilkS")
			(hide yes)
			(effects
				(font
					(size 1.27 1.27)
				)
			)
		)
		(property "Value" ""
			(at 0 0 0)
			(layer "F.Fab")
			(effects
				(font
					(size 1.27 1.27)
				)
			)
		)
		(duplicate_pad_numbers_are_jumpers no)
		(fp_poly
			(pts
				(xy 0.3048 -0.1016) (xy 0.3048 0.9906) (xy -0.3048 0.9906) (xy -0.3048 -0.1016)
			)
			(stroke
				(width 0)
				(type default)
			)
			(fill no)
			(layer "F.CrtYd")
		)
		(fp_line
			(start -0.3048 -0.1016)
			(end -0.3048 0.9906)
			(stroke
				(width 0.1)
				(type default)
			)
			(layer "F.Fab")
		)
		(fp_line
			(start -0.3048 0.9906)
			(end 0.3048 0.9906)
			(stroke
				(width 0.1)
				(type default)
			)
			(layer "F.Fab")
		)
		(fp_line
			(start 0.3048 -0.1016)
			(end -0.3048 -0.1016)
			(stroke
				(width 0.1)
				(type default)
			)
			(layer "F.Fab")
		)
		(fp_line
			(start 0.3048 0.9906)
			(end 0.3048 -0.1016)
			(stroke
				(width 0.1)
				(type default)
			)
			(layer "F.Fab")
		)
		(pad "1" smd rect
			(at 0 0)
			(size 0.508 0.508)
			(layers "F.Cu" "F.Mask" "F.Paste")
			(net "PVCCIOMCP_CPU1")
		)
		(pad "2" smd rect
			(at 0 0.889)
			(size 0.508 0.508)
			(layers "F.Cu" "F.Mask" "F.Paste")
			(net "GND")
		)
		(zone
			(layer "F.Cu")
			(hatch none 0.5)
			(connect_pads
				(clearance 0)
			)
			(min_thickness 0.25)
			(keepout
				(tracks allowed)
				(vias not_allowed)
				(pads allowed)
				(copperpour not_allowed)
				(footprints allowed)
			)
			(placement
				(enabled no)
				(sheetname "")
			)
			(fill
				(thermal_gap 0.5)
				(thermal_bridge_width 0.5)
				(island_removal_mode 0)
			)
			(polygon
				(pts
					(xy 162.433 -103.886) (xy 162.941 -103.886) (xy 162.941 -103.505) (xy 162.433 -103.505)
				)
			)
		)
		(zone
			(layer "F.Cu")
			(hatch none 0.5)
			(connect_pads
				(clearance 0)
			)
			(min_thickness 0.25)
			(keepout
				(tracks not_allowed)
				(vias allowed)
				(pads allowed)
				(copperpour not_allowed)
				(footprints allowed)
			)
			(placement
				(enabled no)
				(sheetname "")
			)
			(fill
				(thermal_gap 0.5)
				(thermal_bridge_width 0.5)
				(island_removal_mode 0)
			)
			(polygon
				(pts
					(xy 162.433 -103.505) (xy 162.941 -103.505) (xy 162.941 -103.886) (xy 162.433 -103.886)
				)
			)
		)
	)
	(footprint ""
		(layer "F.Cu")
		(at 88.392 -3.3528 90)
		(property "Reference" "C2G12"
			(at 1.848866 0.752348 90)
			(unlocked yes)
			(layer "F.SilkS")
			(effects
				(font
					(size 1.27 0.9652)
					(thickness 0.1524)
				)
			)
		)
		(property "Value" ""
			(at 0 0 90)
			(layer "F.Fab")
			(effects
				(font
					(size 1.27 1.27)
				)
			)
		)
		(duplicate_pad_numbers_are_jumpers no)
		(fp_rect
			(start -0.500126 1.598422)
			(end 0.500126 -0.201422)
			(stroke
				(width 0)
				(type default)
			)
			(fill no)
			(layer "F.CrtYd")
		)
		(fp_line
			(start 0.500126 -0.201422)
			(end 0.500126 1.598422)
			(stroke
				(width 0.1)
				(type default)
			)
			(layer "F.Fab")
		)
		(fp_line
			(start -0.500126 -0.201422)
			(end 0.500126 -0.201422)
			(stroke
				(width 0.1)
				(type default)
			)
			(layer "F.Fab")
		)
		(fp_line
			(start 0.500126 1.598422)
			(end -0.500126 1.598422)
			(stroke
				(width 0.1)
				(type default)
			)
			(layer "F.Fab")
		)
		(fp_line
			(start -0.500126 1.598422)
			(end -0.500126 -0.201422)
			(stroke
				(width 0.1)
				(type default)
			)
			(layer "F.Fab")
		)
		(pad "1" smd rect
			(at 0 0)
			(size 0.889 0.9906)
			(layers "F.Cu" "F.Mask" "F.Paste")
			(net "PVDDQ_GHJ")
		)
		(pad "2" smd rect
			(at 0 1.397)
			(size 0.889 0.9906)
			(layers "F.Cu" "F.Mask" "F.Paste")
			(net "GND")
		)
		(zone
			(layer "F.Cu")
			(hatch none 0.5)
			(connect_pads
				(clearance 0)
			)
			(min_thickness 0.25)
			(keepout
				(tracks allowed)
				(vias not_allowed)
				(pads allowed)
				(copperpour not_allowed)
				(footprints allowed)
			)
			(placement
				(enabled no)
				(sheetname "")
			)
			(fill
				(thermal_gap 0.5)
				(thermal_bridge_width 0.5)
				(island_removal_mode 0)
			)
			(polygon
				(pts
					(xy 89.3445 -2.8575) (xy 89.3445 -3.8481) (xy 88.8365 -3.8481) (xy 88.8365 -2.8575)
				)
			)
		)
		(zone
			(layer "F.Cu")
			(hatch none 0.5)
			(connect_pads
				(clearance 0)
			)
			(min_thickness 0.25)
			(keepout
				(tracks not_allowed)
				(vias allowed)
				(pads allowed)
				(copperpour not_allowed)
				(footprints allowed)
			)
			(placement
				(enabled no)
				(sheetname "")
			)
			(fill
				(thermal_gap 0.5)
				(thermal_bridge_width 0.5)
				(island_removal_mode 0)
			)
			(polygon
				(pts
					(xy 89.3445 -2.8575) (xy 89.3445 -3.8481) (xy 88.8365 -3.8481) (xy 88.8365 -2.8575)
				)
			)
		)
	)
	(footprint ""
		(layer "F.Cu")
		(at 178.98237 -144.159224 90)
		(property "Reference" "R4A9"
			(at 0 0 90)
			(layer "F.SilkS")
			(hide yes)
			(effects
				(font
					(size 1.27 1.27)
				)
			)
		)
		(property "Value" ""
			(at 0 0 90)
			(layer "F.Fab")
			(effects
				(font
					(size 1.27 1.27)
				)
			)
		)
		(duplicate_pad_numbers_are_jumpers no)
		(fp_poly
			(pts
				(xy -0.2794 -0.1016) (xy 0.2794 -0.1016) (xy 0.2794 0.9906) (xy -0.2794 0.9906)
			)
			(stroke
				(width 0)
				(type default)
			)
			(fill no)
			(layer "F.CrtYd")
		)
		(fp_line
			(start 0.2794 -0.1016)
			(end -0.2794 -0.1016)
			(stroke
				(width 0.1)
				(type default)
			)
			(layer "F.Fab")
		)
		(fp_line
			(start -0.2794 -0.1016)
			(end -0.2794 0.9906)
			(stroke
				(width 0.1)
				(type default)
			)
			(layer "F.Fab")
		)
		(fp_line
			(start 0.2794 0.9906)
			(end 0.2794 -0.1016)
			(stroke
				(width 0.1)
				(type default)
			)
			(layer "F.Fab")
		)
		(fp_line
			(start -0.2794 0.9906)
			(end 0.2794 0.9906)
			(stroke
				(width 0.1)
				(type default)
			)
			(layer "F.Fab")
		)
		(pad "1" smd rect
			(at 0 0 90)
			(size 0.508 0.508)
			(layers "F.Cu" "F.Mask" "F.Paste")
			(net "SMB_LAN_STBY_LVC3_SCL")
		)
		(pad "2" smd rect
			(at 0 0.889 90)
			(size 0.508 0.508)
			(layers "F.Cu" "F.Mask" "F.Paste")
			(net "SMB_PIROM_CPU0_SCL")
		)
		(zone
			(layer "F.Cu")
			(hatch none 0.5)
			(connect_pads
				(clearance 0)
			)
			(min_thickness 0.25)
			(keepout
				(tracks allowed)
				(vias not_allowed)
				(pads allowed)
				(copperpour not_allowed)
				(footprints allowed)
			)
			(placement
				(enabled no)
				(sheetname "")
			)
			(fill
				(thermal_gap 0.5)
				(thermal_bridge_width 0.5)
				(island_removal_mode 0)
			)
			(polygon
				(pts
					(xy 179.23637 -143.905224) (xy 179.23637 -144.413224) (xy 179.61737 -144.413224) (xy 179.61737 -143.905224)
				)
			)
		)
		(zone
			(layer "F.Cu")
			(hatch none 0.5)
			(connect_pads
				(clearance 0)
			)
			(min_thickness 0.25)
			(keepout
				(tracks not_allowed)
				(vias allowed)
				(pads allowed)
				(copperpour not_allowed)
				(footprints allowed)
			)
			(placement
				(enabled no)
				(sheetname "")
			)
			(fill
				(thermal_gap 0.5)
				(thermal_bridge_width 0.5)
				(island_removal_mode 0)
			)
			(polygon
				(pts
					(xy 179.61737 -143.905224) (xy 179.61737 -144.413224) (xy 179.23637 -144.413224) (xy 179.23637 -143.905224)
				)
			)
		)
	)
	(footprint ""
		(layer "F.Cu")
		(at 270.890238 -68.365116 180)
		(property "Reference" "C5D60"
			(at 0 0 180)
			(layer "F.SilkS")
			(hide yes)
			(effects
				(font
					(size 1.27 1.27)
				)
			)
		)
		(property "Value" ""
			(at 0 0 180)
			(layer "F.Fab")
			(effects
				(font
					(size 1.27 1.27)
				)
			)
		)
		(duplicate_pad_numbers_are_jumpers no)
		(fp_poly
			(pts
				(xy -0.4953 -0.2032) (xy 0.4953 -0.2032) (xy 0.4953 1.6002) (xy -0.4953 1.6002)
			)
			(stroke
				(width 0)
				(type default)
			)
			(fill no)
			(layer "F.CrtYd")
		)
		(fp_line
			(start 0.4953 1.6002)
			(end -0.4953 1.6002)
			(stroke
				(width 0.1)
				(type default)
			)
			(layer "F.Fab")
		)
		(fp_line
			(start 0.4953 -0.2032)
			(end 0.4953 1.6002)
			(stroke
				(width 0.1)
				(type default)
			)
			(layer "F.Fab")
		)
		(fp_line
			(start -0.4953 1.6002)
			(end -0.4953 -0.2032)
			(stroke
				(width 0.1)
				(type default)
			)
			(layer "F.Fab")
		)
		(fp_line
			(start -0.4953 -0.2032)
			(end 0.4953 -0.2032)
			(stroke
				(width 0.1)
				(type default)
			)
			(layer "F.Fab")
		)
		(pad "1" smd rect
			(at 0 0 180)
			(size 0.762 0.889)
			(layers "F.Cu" "F.Mask" "F.Paste")
			(net "PVDDQ_ABC")
		)
		(pad "2" smd rect
			(at 0 1.397 180)
			(size 0.762 0.889)
			(layers "F.Cu" "F.Mask" "F.Paste")
			(net "GND")
		)
		(zone
			(layer "F.Cu")
			(hatch none 0.5)
			(connect_pads
				(clearance 0)
			)
			(min_thickness 0.25)
			(keepout
				(tracks not_allowed)
				(vias allowed)
				(pads allowed)
				(copperpour not_allowed)
				(footprints allowed)
			)
			(placement
				(enabled no)
				(sheetname "")
			)
			(fill
				(thermal_gap 0.5)
				(thermal_bridge_width 0.5)
				(island_removal_mode 0)
			)
			(polygon
				(pts
					(xy 271.271238 -68.809616) (xy 270.509238 -68.809616) (xy 270.509238 -69.317616) (xy 271.271238 -69.317616)
				)
			)
		)
	)
	(footprint ""
		(layer "F.Cu")
		(at 500.199914 -124.960126 90)
		(property "Reference" "S9W1"
			(at 0 0 90)
			(layer "F.SilkS")
			(hide yes)
			(effects
				(font
					(size 1.27 1.27)
				)
			)
		)
		(property "Value" "*"
			(at -6.092952 -8.046466 90)
			(unlocked yes)
			(layer "F.Fab")
			(hide yes)
			(effects
				(font
					(size 0.889 0.889)
					(thickness 0.1524)
				)
			)
		)
		(property "Device Type" "SW-SLIDE75-GP_DISCRET-G6-SW-SLA"
			(at -6.092952 -6.522466 90)
			(unlocked yes)
			(layer "F.Fab")
			(hide yes)
			(effects
				(font
					(size 0.889 0.889)
					(thickness 0.1524)
				)
			)
		)
		(duplicate_pad_numbers_are_jumpers no)
		(fp_line
			(start -2.0701 -2.8956)
			(end -2.4511 -2.8956)
			(stroke
				(width 0.3302)
				(type default)
			)
			(layer "F.SilkS")
		)
		(fp_line
			(start 4.4069 -2.7686)
			(end 4.4069 1.7272)
			(stroke
				(width 0.1524)
				(type default)
			)
			(layer "F.SilkS")
		)
		(fp_line
			(start -4.4069 -2.7686)
			(end 4.4069 -2.7686)
			(stroke
				(width 0.1524)
				(type default)
			)
			(layer "F.SilkS")
		)
		(fp_line
			(start 4.4069 1.7272)
			(end 1.651 1.7272)
			(stroke
				(width 0.1524)
				(type default)
			)
			(layer "F.SilkS")
		)
		(fp_line
			(start 1.651 1.7272)
			(end 1.651 3.048)
			(stroke
				(width 0.1524)
				(type default)
			)
			(layer "F.SilkS")
		)
		(fp_line
			(start -1.651 1.7272)
			(end -4.4069 1.7272)
			(stroke
				(width 0.1524)
				(type default)
			)
			(layer "F.SilkS")
		)
		(fp_line
			(start -4.4069 1.7272)
			(end -4.4069 -2.7686)
			(stroke
				(width 0.1524)
				(type default)
			)
			(layer "F.SilkS")
		)
		(fp_line
			(start 1.651 3.048)
			(end -1.651 3.048)
			(stroke
				(width 0.1524)
				(type default)
			)
			(layer "F.SilkS")
		)
		(fp_line
			(start -1.651 3.048)
			(end -1.651 1.7272)
			(stroke
				(width 0.1524)
				(type default)
			)
			(layer "F.SilkS")
		)
		(fp_poly
			(pts
				(xy -2.2606 -2.8194) (xy -2.6416 -3.2004) (xy -1.8796 -3.2004)
			)
			(stroke
				(width 0)
				(type default)
			)
			(fill yes)
			(layer "F.SilkS")
		)
		(fp_poly
			(pts
				(xy -1.397 2.794) (xy -1.397 1.2954) (xy -3.8481 1.2954) (xy -3.8481 -2.2098) (xy 3.8481 -2.2098)
				(xy 3.8481 1.2954) (xy 1.397 1.2954) (xy 1.397 2.794)
			)
			(stroke
				(width 0)
				(type default)
			)
			(fill no)
			(layer "F.CrtYd")
		)
		(fp_poly
			(pts
				(xy -0.3302 3.302) (xy -0.3302 2.794) (xy -1.397 2.794) (xy -1.397 1.2954) (xy -3.8481 1.2954) (xy -3.8481 -2.2098)
				(xy 3.8481 -2.2098) (xy 3.8481 1.2954) (xy 1.397 1.2954) (xy 1.397 2.794) (xy -0.3175 2.794) (xy -0.3175 3.302)
				(xy 1.905 3.302) (xy 1.905 1.9812) (xy 4.6609 1.9812) (xy 4.6609 -3.0226) (xy -4.6609 -3.0226) (xy -4.6609 1.9812)
				(xy -1.905 1.9812) (xy -1.905 3.302)
			)
			(stroke
				(width 0)
				(type default)
			)
			(fill no)
			(layer "F.CrtYd")
		)
		(fp_poly
			(pts
				(xy -1.905 3.302) (xy -1.905 1.9812) (xy -4.6609 1.9812) (xy -4.6609 -3.0226) (xy 4.6609 -3.0226)
				(xy 4.6609 1.9812) (xy 1.905 1.9812) (xy 1.905 3.302)
			)
			(stroke
				(width 0)
				(type default)
			)
			(fill no)
			(layer "F.Fab")
		)
		(pad "" np_thru_hole circle
			(at -1.49987 0 90)
			(size 0.254 0.254)
			(drill 0.9144)
			(layers "*.Cu" "*.Mask")
			(clearance 0.6858)
			(thermal_gap 0.6858)
		)
		(pad "" np_thru_hole circle
			(at 1.49987 0 90)
			(size 0.254 0.254)
			(drill 0.9144)
			(layers "*.Cu" "*.Mask")
			(clearance 0.6858)
			(thermal_gap 0.6858)
		)
		(pad "1" smd rect
			(at -2.25044 -1.75006 90)
			(size 0.7112 1.4986)
			(layers "F.Cu" "F.Mask" "F.Paste")
			(net "Net_6516")
		)
		(pad "2" smd rect
			(at 0.75057 -1.75006 90)
			(size 0.7112 1.4986)
			(layers "F.Cu" "F.Mask" "F.Paste")
			(net "BMC_JTAG_SEL")
		)
		(pad "3" smd rect
			(at 2.25044 -1.75006 90)
			(size 0.7112 1.4986)
			(layers "F.Cu" "F.Mask" "F.Paste")
			(net "GND")
		)
		(pad "4" smd rect
			(at -3.64998 -1.056386 90)
			(size 0.9906 0.8128)
			(layers "F.Cu" "F.Mask" "F.Paste")
			(net "GND")
		)
		(pad "5" smd rect
			(at -3.64998 1.056386 90)
			(size 0.9906 0.8128)
			(layers "F.Cu" "F.Mask" "F.Paste")
			(net "GND")
		)
		(pad "6" smd rect
			(at 3.64998 -1.056386 90)
			(size 0.9906 0.8128)
			(layers "F.Cu" "F.Mask" "F.Paste")
			(net "GND")
		)
		(pad "7" smd rect
			(at 3.64998 1.056386 90)
			(size 0.9906 0.8128)
			(layers "F.Cu" "F.Mask" "F.Paste")
			(net "GND")
		)
		(zone
			(layers "F.Cu" "B.Cu" "In1.Cu" "In2.Cu" "In3.Cu" "In4.Cu" "In5.Cu" "In6.Cu"
				"In7.Cu" "In8.Cu" "In9.Cu" "In10.Cu" "In11.Cu" "In12.Cu"
			)
			(hatch none 0.5)
			(connect_pads
				(clearance 0)
			)
			(min_thickness 0.25)
			(keepout
				(tracks not_allowed)
				(vias allowed)
				(pads allowed)
				(copperpour not_allowed)
				(footprints allowed)
			)
			(placement
				(enabled no)
				(sheetname "")
			)
			(fill
				(thermal_gap 0.5)
				(thermal_bridge_width 0.5)
				(island_removal_mode 0)
			)
			(polygon
				(pts
					(arc
						(start 500.961914 -126.459996)
						(mid 499.437914 -126.459996)
						(end 500.961914 -126.459996)
					)
				)
			)
		)
		(zone
			(layers "F.Cu" "B.Cu" "In1.Cu" "In2.Cu" "In3.Cu" "In4.Cu" "In5.Cu" "In6.Cu"
				"In7.Cu" "In8.Cu" "In9.Cu" "In10.Cu" "In11.Cu" "In12.Cu"
			)
			(hatch none 0.5)
			(connect_pads
				(clearance 0)
			)
			(min_thickness 0.25)
			(keepout
				(tracks not_allowed)
				(vias allowed)
				(pads allowed)
				(copperpour not_allowed)
				(footprints allowed)
			)
			(placement
				(enabled no)
				(sheetname "")
			)
			(fill
				(thermal_gap 0.5)
				(thermal_bridge_width 0.5)
				(island_removal_mode 0)
			)
			(polygon
				(pts
					(arc
						(start 500.961914 -123.460256)
						(mid 499.437914 -123.460256)
						(end 500.961914 -123.460256)
					)
				)
			)
		)
	)
	(footprint ""
		(layer "F.Cu")
		(at 162.38728 -68.8467 180)
		(property "Reference" "R3D20"
			(at 0 0 180)
			(layer "F.SilkS")
			(hide yes)
			(effects
				(font
					(size 1.27 1.27)
				)
			)
		)
		(property "Value" ""
			(at 0 0 180)
			(layer "F.Fab")
			(effects
				(font
					(size 1.27 1.27)
				)
			)
		)
		(duplicate_pad_numbers_are_jumpers no)
		(fp_poly
			(pts
				(xy -0.2794 -0.1016) (xy 0.2794 -0.1016) (xy 0.2794 0.9906) (xy -0.2794 0.9906)
			)
			(stroke
				(width 0)
				(type default)
			)
			(fill no)
			(layer "F.CrtYd")
		)
		(fp_line
			(start 0.2794 0.9906)
			(end 0.2794 -0.1016)
			(stroke
				(width 0.1)
				(type default)
			)
			(layer "F.Fab")
		)
		(fp_line
			(start 0.2794 -0.1016)
			(end -0.2794 -0.1016)
			(stroke
				(width 0.1)
				(type default)
			)
			(layer "F.Fab")
		)
		(fp_line
			(start -0.2794 0.9906)
			(end 0.2794 0.9906)
			(stroke
				(width 0.1)
				(type default)
			)
			(layer "F.Fab")
		)
		(fp_line
			(start -0.2794 -0.1016)
			(end -0.2794 0.9906)
			(stroke
				(width 0.1)
				(type default)
			)
			(layer "F.Fab")
		)
		(pad "1" smd rect
			(at 0 0 180)
			(size 0.508 0.508)
			(layers "F.Cu" "F.Mask" "F.Paste")
			(net "PVCCIO_CPU1")
		)
		(pad "2" smd rect
			(at 0 0.889 180)
			(size 0.508 0.508)
			(layers "F.Cu" "F.Mask" "F.Paste")
			(net "RST_CPU1_G_N")
		)
		(zone
			(layer "F.Cu")
			(hatch none 0.5)
			(connect_pads
				(clearance 0)
			)
			(min_thickness 0.25)
			(keepout
				(tracks not_allowed)
				(vias allowed)
				(pads allowed)
				(copperpour not_allowed)
				(footprints allowed)
			)
			(placement
				(enabled no)
				(sheetname "")
			)
			(fill
				(thermal_gap 0.5)
				(thermal_bridge_width 0.5)
				(island_removal_mode 0)
			)
			(polygon
				(pts
					(xy 162.64128 -69.4817) (xy 162.13328 -69.4817) (xy 162.13328 -69.1007) (xy 162.64128 -69.1007)
				)
			)
		)
		(zone
			(layer "F.Cu")
			(hatch none 0.5)
			(connect_pads
				(clearance 0)
			)
			(min_thickness 0.25)
			(keepout
				(tracks allowed)
				(vias not_allowed)
				(pads allowed)
				(copperpour not_allowed)
				(footprints allowed)
			)
			(placement
				(enabled no)
				(sheetname "")
			)
			(fill
				(thermal_gap 0.5)
				(thermal_bridge_width 0.5)
				(island_removal_mode 0)
			)
			(polygon
				(pts
					(xy 162.64128 -69.1007) (xy 162.13328 -69.1007) (xy 162.13328 -69.4817) (xy 162.64128 -69.4817)
				)
			)
		)
	)
	(footprint ""
		(layer "F.Cu")
		(at 412.5468 -102.489 180)
		(property "Reference" "R2N29"
			(at 0 0 180)
			(layer "F.SilkS")
			(hide yes)
			(effects
				(font
					(size 1.27 1.27)
				)
			)
		)
		(property "Value" ""
			(at 0 0 180)
			(layer "F.Fab")
			(effects
				(font
					(size 1.27 1.27)
				)
			)
		)
		(duplicate_pad_numbers_are_jumpers no)
		(fp_poly
			(pts
				(xy -0.2794 -0.1016) (xy 0.2794 -0.1016) (xy 0.2794 0.9906) (xy -0.2794 0.9906)
			)
			(stroke
				(width 0)
				(type default)
			)
			(fill no)
			(layer "F.CrtYd")
		)
		(fp_line
			(start 0.2794 0.9906)
			(end 0.2794 -0.1016)
			(stroke
				(width 0.1)
				(type default)
			)
			(layer "F.Fab")
		)
		(fp_line
			(start 0.2794 -0.1016)
			(end -0.2794 -0.1016)
			(stroke
				(width 0.1)
				(type default)
			)
			(layer "F.Fab")
		)
		(fp_line
			(start -0.2794 0.9906)
			(end 0.2794 0.9906)
			(stroke
				(width 0.1)
				(type default)
			)
			(layer "F.Fab")
		)
		(fp_line
			(start -0.2794 -0.1016)
			(end -0.2794 0.9906)
			(stroke
				(width 0.1)
				(type default)
			)
			(layer "F.Fab")
		)
		(pad "1" smd rect
			(at 0 0 180)
			(size 0.508 0.508)
			(layers "F.Cu" "F.Mask" "F.Paste")
			(net "P3V3_STBY")
		)
		(pad "2" smd rect
			(at 0 0.889 180)
			(size 0.508 0.508)
			(layers "F.Cu" "F.Mask" "F.Paste")
			(net "FM_CPU1_RC_ERROR_N")
		)
		(zone
			(layer "F.Cu")
			(hatch none 0.5)
			(connect_pads
				(clearance 0)
			)
			(min_thickness 0.25)
			(keepout
				(tracks not_allowed)
				(vias allowed)
				(pads allowed)
				(copperpour not_allowed)
				(footprints allowed)
			)
			(placement
				(enabled no)
				(sheetname "")
			)
			(fill
				(thermal_gap 0.5)
				(thermal_bridge_width 0.5)
				(island_removal_mode 0)
			)
			(polygon
				(pts
					(xy 412.8008 -103.124) (xy 412.2928 -103.124) (xy 412.2928 -102.743) (xy 412.8008 -102.743)
				)
			)
		)
		(zone
			(layer "F.Cu")
			(hatch none 0.5)
			(connect_pads
				(clearance 0)
			)
			(min_thickness 0.25)
			(keepout
				(tracks allowed)
				(vias not_allowed)
				(pads allowed)
				(copperpour not_allowed)
				(footprints allowed)
			)
			(placement
				(enabled no)
				(sheetname "")
			)
			(fill
				(thermal_gap 0.5)
				(thermal_bridge_width 0.5)
				(island_removal_mode 0)
			)
			(polygon
				(pts
					(xy 412.8008 -102.743) (xy 412.2928 -102.743) (xy 412.2928 -103.124) (xy 412.8008 -103.124)
				)
			)
		)
	)
	(footprint ""
		(layer "F.Cu")
		(at 402.971 -22.987)
		(property "Reference" "R25W90"
			(at -0.8382 -0.67818 0)
			(unlocked yes)
			(layer "F.SilkS")
			(effects
				(font
					(size 0.4064 0.254)
					(thickness 0.1524)
				)
				(justify left)
			)
		)
		(property "Value" ""
			(at 0 0 0)
			(layer "F.Fab")
			(effects
				(font
					(size 1.27 1.27)
				)
			)
		)
		(duplicate_pad_numbers_are_jumpers no)
		(fp_poly
			(pts
				(xy -0.2794 -0.1016) (xy 0.2794 -0.1016) (xy 0.2794 0.9906) (xy -0.2794 0.9906)
			)
			(stroke
				(width 0)
				(type default)
			)
			(fill no)
			(layer "F.CrtYd")
		)
		(fp_line
			(start -0.2794 -0.1016)
			(end -0.2794 0.9906)
			(stroke
				(width 0.1)
				(type default)
			)
			(layer "F.Fab")
		)
		(fp_line
			(start -0.2794 0.9906)
			(end 0.2794 0.9906)
			(stroke
				(width 0.1)
				(type default)
			)
			(layer "F.Fab")
		)
		(fp_line
			(start 0.2794 -0.1016)
			(end -0.2794 -0.1016)
			(stroke
				(width 0.1)
				(type default)
			)
			(layer "F.Fab")
		)
		(fp_line
			(start 0.2794 0.9906)
			(end 0.2794 -0.1016)
			(stroke
				(width 0.1)
				(type default)
			)
			(layer "F.Fab")
		)
		(pad "1" smd rect
			(at 0 0)
			(size 0.508 0.508)
			(layers "F.Cu" "F.Mask" "F.Paste")
			(net "RMII_BMC_PCH_SPRNGVLLE_TXD1_R")
		)
		(pad "2" smd rect
			(at 0 0.889)
			(size 0.508 0.508)
			(layers "F.Cu" "F.Mask" "F.Paste")
			(net "RMII_BMC_PCH_SPRNGVLLE_TXD1")
		)
		(zone
			(layer "F.Cu")
			(hatch none 0.5)
			(connect_pads
				(clearance 0)
			)
			(min_thickness 0.25)
			(keepout
				(tracks allowed)
				(vias not_allowed)
				(pads allowed)
				(copperpour not_allowed)
				(footprints allowed)
			)
			(placement
				(enabled no)
				(sheetname "")
			)
			(fill
				(thermal_gap 0.5)
				(thermal_bridge_width 0.5)
				(island_removal_mode 0)
			)
			(polygon
				(pts
					(xy 402.717 -22.733) (xy 403.225 -22.733) (xy 403.225 -22.352) (xy 402.717 -22.352)
				)
			)
		)
		(zone
			(layer "F.Cu")
			(hatch none 0.5)
			(connect_pads
				(clearance 0)
			)
			(min_thickness 0.25)
			(keepout
				(tracks not_allowed)
				(vias allowed)
				(pads allowed)
				(copperpour not_allowed)
				(footprints allowed)
			)
			(placement
				(enabled no)
				(sheetname "")
			)
			(fill
				(thermal_gap 0.5)
				(thermal_bridge_width 0.5)
				(island_removal_mode 0)
			)
			(polygon
				(pts
					(xy 402.717 -22.352) (xy 403.225 -22.352) (xy 403.225 -22.733) (xy 402.717 -22.733)
				)
			)
		)
	)
	(footprint ""
		(layer "F.Cu")
		(at 372.766844 -10.916158)
		(property "Reference" "C7G14"
			(at 0 0 0)
			(layer "F.SilkS")
			(hide yes)
			(effects
				(font
					(size 1.27 1.27)
				)
			)
		)
		(property "Value" ""
			(at 0 0 0)
			(layer "F.Fab")
			(effects
				(font
					(size 1.27 1.27)
				)
			)
		)
		(duplicate_pad_numbers_are_jumpers no)
		(fp_rect
			(start -0.3048 0.9906)
			(end 0.3048 -0.1016)
			(stroke
				(width 0)
				(type default)
			)
			(fill no)
			(layer "F.CrtYd")
		)
		(fp_line
			(start -0.3048 -0.1016)
			(end -0.3048 0.9906)
			(stroke
				(width 0.1)
				(type default)
			)
			(layer "F.Fab")
		)
		(fp_line
			(start -0.3048 0.9906)
			(end 0.3048 0.9906)
			(stroke
				(width 0.1)
				(type default)
			)
			(layer "F.Fab")
		)
		(fp_line
			(start 0.3048 -0.1016)
			(end -0.3048 -0.1016)
			(stroke
				(width 0.1)
				(type default)
			)
			(layer "F.Fab")
		)
		(fp_line
			(start 0.3048 0.9906)
			(end 0.3048 -0.1016)
			(stroke
				(width 0.1)
				(type default)
			)
			(layer "F.Fab")
		)
		(pad "1" smd rect
			(at 0 0)
			(size 0.508 0.508)
			(layers "F.Cu" "F.Mask" "F.Paste")
			(net "P3E_CPU0_PE2_SS_TXP<11>")
		)
		(pad "2" smd rect
			(at 0 0.889)
			(size 0.508 0.508)
			(layers "F.Cu" "F.Mask" "F.Paste")
			(net "P3E_CPU0_PE2_SS_C_TXP<11>")
		)
		(zone
			(layer "F.Cu")
			(hatch none 0.5)
			(connect_pads
				(clearance 0)
			)
			(min_thickness 0.25)
			(keepout
				(tracks allowed)
				(vias not_allowed)
				(pads allowed)
				(copperpour not_allowed)
				(footprints allowed)
			)
			(placement
				(enabled no)
				(sheetname "")
			)
			(fill
				(thermal_gap 0.5)
				(thermal_bridge_width 0.5)
				(island_removal_mode 0)
			)
			(polygon
				(pts
					(xy 372.512844 -10.281158) (xy 373.020844 -10.281158) (xy 373.020844 -10.662158) (xy 372.512844 -10.662158)
				)
			)
		)
		(zone
			(layer "F.Cu")
			(hatch none 0.5)
			(connect_pads
				(clearance 0)
			)
			(min_thickness 0.25)
			(keepout
				(tracks not_allowed)
				(vias allowed)
				(pads allowed)
				(copperpour not_allowed)
				(footprints allowed)
			)
			(placement
				(enabled no)
				(sheetname "")
			)
			(fill
				(thermal_gap 0.5)
				(thermal_bridge_width 0.5)
				(island_removal_mode 0)
			)
			(polygon
				(pts
					(xy 372.512844 -10.281158) (xy 373.020844 -10.281158) (xy 373.020844 -10.662158) (xy 372.512844 -10.662158)
				)
			)
		)
	)
	(footprint ""
		(layer "F.Cu")
		(at 492.4806 -59.944 180)
		(property "Reference" "C30W3"
			(at 0 0 180)
			(layer "F.SilkS")
			(hide yes)
			(effects
				(font
					(size 1.27 1.27)
				)
			)
		)
		(property "Value" "*"
			(at -0.0762 -6.2357 180)
			(unlocked yes)
			(layer "F.Fab")
			(hide yes)
			(effects
				(font
					(size 1.27 1.016)
					(thickness 0.1524)
				)
			)
		)
		(property "Device Type" "SC22U16V5MX-4-GP_SMD-BCG5-SC22A"
			(at -0.0762 -8.2677 180)
			(unlocked yes)
			(layer "F.Fab")
			(hide yes)
			(effects
				(font
					(size 1.27 1.016)
					(thickness 0.1524)
				)
			)
		)
		(duplicate_pad_numbers_are_jumpers no)
		(fp_line
			(start 0.635 0)
			(end -0.635 0)
			(stroke
				(width 0.508)
				(type default)
			)
			(layer "F.SilkS")
		)
		(fp_rect
			(start -0.9652 1.778)
			(end 0.9652 -1.778)
			(stroke
				(width 0)
				(type default)
			)
			(fill no)
			(layer "F.CrtYd")
		)
		(fp_poly
			(pts
				(xy -0.9652 -1.778) (xy 0.9652 -1.778) (xy 0.9652 1.778) (xy -0.9652 1.778)
			)
			(stroke
				(width 0)
				(type default)
			)
			(fill no)
			(layer "F.Fab")
		)
		(pad "1" smd rect
			(at 0 -0.9652 180)
			(size 1.397 1.143)
			(layers "F.Cu" "F.Mask" "F.Paste")
			(net "P5V_STBY_USBC")
		)
		(pad "2" smd rect
			(at 0 0.9652 180)
			(size 1.397 1.143)
			(layers "F.Cu" "F.Mask" "F.Paste")
			(net "GND")
		)
	)
	(footprint ""
		(layer "F.Cu")
		(at -2.667 -129.3622 -90)
		(property "Reference" "R12W35"
			(at -0.8382 -0.67818 270)
			(unlocked yes)
			(layer "F.SilkS")
			(effects
				(font
					(size 0.4064 0.254)
					(thickness 0.1524)
				)
				(justify left)
			)
		)
		(property "Value" ""
			(at 0 0 270)
			(layer "F.Fab")
			(effects
				(font
					(size 1.27 1.27)
				)
			)
		)
		(duplicate_pad_numbers_are_jumpers no)
		(fp_poly
			(pts
				(xy -0.2794 -0.1016) (xy 0.2794 -0.1016) (xy 0.2794 0.9906) (xy -0.2794 0.9906)
			)
			(stroke
				(width 0)
				(type default)
			)
			(fill no)
			(layer "F.CrtYd")
		)
		(fp_line
			(start -0.2794 0.9906)
			(end 0.2794 0.9906)
			(stroke
				(width 0.1)
				(type default)
			)
			(layer "F.Fab")
		)
		(fp_line
			(start 0.2794 0.9906)
			(end 0.2794 -0.1016)
			(stroke
				(width 0.1)
				(type default)
			)
			(layer "F.Fab")
		)
		(fp_line
			(start -0.2794 -0.1016)
			(end -0.2794 0.9906)
			(stroke
				(width 0.1)
				(type default)
			)
			(layer "F.Fab")
		)
		(fp_line
			(start 0.2794 -0.1016)
			(end -0.2794 -0.1016)
			(stroke
				(width 0.1)
				(type default)
			)
			(layer "F.Fab")
		)
		(pad "1" smd rect
			(at 0 0 270)
			(size 0.508 0.508)
			(layers "F.Cu" "F.Mask" "F.Paste")
			(net "NC_PVDDQ_KLM_GP1")
		)
		(pad "2" smd rect
			(at 0 0.889 270)
			(size 0.508 0.508)
			(layers "F.Cu" "F.Mask" "F.Paste")
			(net "PWRGD_PVDDQ_KLM")
		)
		(zone
			(layer "F.Cu")
			(hatch none 0.5)
			(connect_pads
				(clearance 0)
			)
			(min_thickness 0.25)
			(keepout
				(tracks not_allowed)
				(vias allowed)
				(pads allowed)
				(copperpour not_allowed)
				(footprints allowed)
			)
			(placement
				(enabled no)
				(sheetname "")
			)
			(fill
				(thermal_gap 0.5)
				(thermal_bridge_width 0.5)
				(island_removal_mode 0)
			)
			(polygon
				(pts
					(xy -3.302 -129.6162) (xy -3.302 -129.1082) (xy -2.921 -129.1082) (xy -2.921 -129.6162)
				)
			)
		)
		(zone
			(layer "F.Cu")
			(hatch none 0.5)
			(connect_pads
				(clearance 0)
			)
			(min_thickness 0.25)
			(keepout
				(tracks allowed)
				(vias not_allowed)
				(pads allowed)
				(copperpour not_allowed)
				(footprints allowed)
			)
			(placement
				(enabled no)
				(sheetname "")
			)
			(fill
				(thermal_gap 0.5)
				(thermal_bridge_width 0.5)
				(island_removal_mode 0)
			)
			(polygon
				(pts
					(xy -2.921 -129.6162) (xy -2.921 -129.1082) (xy -3.302 -129.1082) (xy -3.302 -129.6162)
				)
			)
		)
	)
	(footprint ""
		(layer "F.Cu")
		(at -2.789682 -140.048996 90)
		(property "Reference" "C1A18"
			(at 0 0 90)
			(layer "F.SilkS")
			(hide yes)
			(effects
				(font
					(size 1.27 1.27)
				)
			)
		)
		(property "Value" ""
			(at 0 0 90)
			(layer "F.Fab")
			(effects
				(font
					(size 1.27 1.27)
				)
			)
		)
		(duplicate_pad_numbers_are_jumpers no)
		(fp_poly
			(pts
				(xy 0.3048 -0.1016) (xy 0.3048 0.9906) (xy -0.3048 0.9906) (xy -0.3048 -0.1016)
			)
			(stroke
				(width 0)
				(type default)
			)
			(fill no)
			(layer "F.CrtYd")
		)
		(fp_line
			(start 0.3048 -0.1016)
			(end -0.3048 -0.1016)
			(stroke
				(width 0.1)
				(type default)
			)
			(layer "F.Fab")
		)
		(fp_line
			(start -0.3048 -0.1016)
			(end -0.3048 0.9906)
			(stroke
				(width 0.1)
				(type default)
			)
			(layer "F.Fab")
		)
		(fp_line
			(start 0.3048 0.9906)
			(end 0.3048 -0.1016)
			(stroke
				(width 0.1)
				(type default)
			)
			(layer "F.Fab")
		)
		(fp_line
			(start -0.3048 0.9906)
			(end 0.3048 0.9906)
			(stroke
				(width 0.1)
				(type default)
			)
			(layer "F.Fab")
		)
		(pad "1" smd rect
			(at 0 0 90)
			(size 0.508 0.508)
			(layers "F.Cu" "F.Mask" "F.Paste")
			(net "VR_PVDDQ_KLM_PH1_BOOT")
		)
		(pad "2" smd rect
			(at 0 0.889 90)
			(size 0.508 0.508)
			(layers "F.Cu" "F.Mask" "F.Paste")
			(net "VR_PVDDQ_KLM_PH1_PHASE")
		)
		(zone
			(layer "F.Cu")
			(hatch none 0.5)
			(connect_pads
				(clearance 0)
			)
			(min_thickness 0.25)
			(keepout
				(tracks allowed)
				(vias not_allowed)
				(pads allowed)
				(copperpour not_allowed)
				(footprints allowed)
			)
			(placement
				(enabled no)
				(sheetname "")
			)
			(fill
				(thermal_gap 0.5)
				(thermal_bridge_width 0.5)
				(island_removal_mode 0)
			)
			(polygon
				(pts
					(xy -2.535682 -139.794996) (xy -2.535682 -140.302996) (xy -2.154682 -140.302996) (xy -2.154682 -139.794996)
				)
			)
		)
		(zone
			(layer "F.Cu")
			(hatch none 0.5)
			(connect_pads
				(clearance 0)
			)
			(min_thickness 0.25)
			(keepout
				(tracks not_allowed)
				(vias allowed)
				(pads allowed)
				(copperpour not_allowed)
				(footprints allowed)
			)
			(placement
				(enabled no)
				(sheetname "")
			)
			(fill
				(thermal_gap 0.5)
				(thermal_bridge_width 0.5)
				(island_removal_mode 0)
			)
			(polygon
				(pts
					(xy -2.154682 -139.794996) (xy -2.154682 -140.302996) (xy -2.535682 -140.302996) (xy -2.535682 -139.794996)
				)
			)
		)
	)
	(footprint ""
		(layer "F.Cu")
		(at 176.0855 -8.763 90)
		(property "Reference" "C4G6"
			(at 0 0 90)
			(layer "F.SilkS")
			(hide yes)
			(effects
				(font
					(size 1.27 1.27)
				)
			)
		)
		(property "Value" ""
			(at 0 0 90)
			(layer "F.Fab")
			(effects
				(font
					(size 1.27 1.27)
				)
			)
		)
		(duplicate_pad_numbers_are_jumpers no)
		(fp_poly
			(pts
				(xy 0.3048 -0.1016) (xy 0.3048 0.9906) (xy -0.3048 0.9906) (xy -0.3048 -0.1016)
			)
			(stroke
				(width 0)
				(type default)
			)
			(fill no)
			(layer "F.CrtYd")
		)
		(fp_line
			(start 0.3048 -0.1016)
			(end -0.3048 -0.1016)
			(stroke
				(width 0.1)
				(type default)
			)
			(layer "F.Fab")
		)
		(fp_line
			(start -0.3048 -0.1016)
			(end -0.3048 0.9906)
			(stroke
				(width 0.1)
				(type default)
			)
			(layer "F.Fab")
		)
		(fp_line
			(start 0.3048 0.9906)
			(end 0.3048 -0.1016)
			(stroke
				(width 0.1)
				(type default)
			)
			(layer "F.Fab")
		)
		(fp_line
			(start -0.3048 0.9906)
			(end 0.3048 0.9906)
			(stroke
				(width 0.1)
				(type default)
			)
			(layer "F.Fab")
		)
		(pad "1" smd rect
			(at 0 0 90)
			(size 0.508 0.508)
			(layers "F.Cu" "F.Mask" "F.Paste")
			(net "VR_FB_PVPP_GHJ")
		)
		(pad "2" smd rect
			(at 0 0.889 90)
			(size 0.508 0.508)
			(layers "F.Cu" "F.Mask" "F.Paste")
			(net "VR_COMP_PVPP_GHJ_3")
		)
		(zone
			(layer "F.Cu")
			(hatch none 0.5)
			(connect_pads
				(clearance 0)
			)
			(min_thickness 0.25)
			(keepout
				(tracks allowed)
				(vias not_allowed)
				(pads allowed)
				(copperpour not_allowed)
				(footprints allowed)
			)
			(placement
				(enabled no)
				(sheetname "")
			)
			(fill
				(thermal_gap 0.5)
				(thermal_bridge_width 0.5)
				(island_removal_mode 0)
			)
			(polygon
				(pts
					(xy 176.3395 -8.509) (xy 176.3395 -9.017) (xy 176.7205 -9.017) (xy 176.7205 -8.509)
				)
			)
		)
		(zone
			(layer "F.Cu")
			(hatch none 0.5)
			(connect_pads
				(clearance 0)
			)
			(min_thickness 0.25)
			(keepout
				(tracks not_allowed)
				(vias allowed)
				(pads allowed)
				(copperpour not_allowed)
				(footprints allowed)
			)
			(placement
				(enabled no)
				(sheetname "")
			)
			(fill
				(thermal_gap 0.5)
				(thermal_bridge_width 0.5)
				(island_removal_mode 0)
			)
			(polygon
				(pts
					(xy 176.7205 -8.509) (xy 176.7205 -9.017) (xy 176.3395 -9.017) (xy 176.3395 -8.509)
				)
			)
		)
	)
	(footprint ""
		(layer "F.Cu")
		(at 176.8856 -106.74985)
		(property "Reference" "R4C12"
			(at 0 0 0)
			(layer "F.SilkS")
			(hide yes)
			(effects
				(font
					(size 1.27 1.27)
				)
			)
		)
		(property "Value" ""
			(at 0 0 0)
			(layer "F.Fab")
			(effects
				(font
					(size 1.27 1.27)
				)
			)
		)
		(duplicate_pad_numbers_are_jumpers no)
		(fp_poly
			(pts
				(xy -0.2794 -0.1016) (xy 0.2794 -0.1016) (xy 0.2794 0.9906) (xy -0.2794 0.9906)
			)
			(stroke
				(width 0)
				(type default)
			)
			(fill no)
			(layer "F.CrtYd")
		)
		(fp_line
			(start -0.2794 -0.1016)
			(end -0.2794 0.9906)
			(stroke
				(width 0.1)
				(type default)
			)
			(layer "F.Fab")
		)
		(fp_line
			(start -0.2794 0.9906)
			(end 0.2794 0.9906)
			(stroke
				(width 0.1)
				(type default)
			)
			(layer "F.Fab")
		)
		(fp_line
			(start 0.2794 -0.1016)
			(end -0.2794 -0.1016)
			(stroke
				(width 0.1)
				(type default)
			)
			(layer "F.Fab")
		)
		(fp_line
			(start 0.2794 0.9906)
			(end 0.2794 -0.1016)
			(stroke
				(width 0.1)
				(type default)
			)
			(layer "F.Fab")
		)
		(pad "1" smd rect
			(at 0 0)
			(size 0.508 0.508)
			(layers "F.Cu" "F.Mask" "F.Paste")
			(net "VR_PVCCIOMCP_CPU1_XADDR1")
		)
		(pad "2" smd rect
			(at 0 0.889)
			(size 0.508 0.508)
			(layers "F.Cu" "F.Mask" "F.Paste")
			(net "GND")
		)
		(zone
			(layer "F.Cu")
			(hatch none 0.5)
			(connect_pads
				(clearance 0)
			)
			(min_thickness 0.25)
			(keepout
				(tracks allowed)
				(vias not_allowed)
				(pads allowed)
				(copperpour not_allowed)
				(footprints allowed)
			)
			(placement
				(enabled no)
				(sheetname "")
			)
			(fill
				(thermal_gap 0.5)
				(thermal_bridge_width 0.5)
				(island_removal_mode 0)
			)
			(polygon
				(pts
					(xy 176.6316 -106.49585) (xy 177.1396 -106.49585) (xy 177.1396 -106.11485) (xy 176.6316 -106.11485)
				)
			)
		)
		(zone
			(layer "F.Cu")
			(hatch none 0.5)
			(connect_pads
				(clearance 0)
			)
			(min_thickness 0.25)
			(keepout
				(tracks not_allowed)
				(vias allowed)
				(pads allowed)
				(copperpour not_allowed)
				(footprints allowed)
			)
			(placement
				(enabled no)
				(sheetname "")
			)
			(fill
				(thermal_gap 0.5)
				(thermal_bridge_width 0.5)
				(island_removal_mode 0)
			)
			(polygon
				(pts
					(xy 176.6316 -106.11485) (xy 177.1396 -106.11485) (xy 177.1396 -106.49585) (xy 176.6316 -106.49585)
				)
			)
		)
	)
	(footprint ""
		(layer "F.Cu")
		(at 25.7048 -50.419)
		(property "Reference" "C1E18"
			(at 4.16687 3.302 90)
			(unlocked yes)
			(layer "F.SilkS")
			(effects
				(font
					(size 0.7874 0.5842)
					(thickness 0.1524)
				)
				(justify left)
			)
		)
		(property "Value" ""
			(at 0 0 0)
			(layer "F.Fab")
			(effects
				(font
					(size 1.27 1.27)
				)
			)
		)
		(duplicate_pad_numbers_are_jumpers no)
		(fp_line
			(start -3.400044 0.028956)
			(end -3.400044 6.067044)
			(stroke
				(width 0.1524)
				(type default)
			)
			(layer "F.SilkS")
		)
		(fp_line
			(start -3.400044 6.067044)
			(end -0.9017 6.067044)
			(stroke
				(width 0.1524)
				(type default)
			)
			(layer "F.SilkS")
		)
		(fp_line
			(start -2.638044 -0.733044)
			(end -3.400044 0.028956)
			(stroke
				(width 0.1524)
				(type default)
			)
			(layer "F.SilkS")
		)
		(fp_line
			(start -0.9017 -1.714246)
			(end -0.9017 1.587754)
			(stroke
				(width 0.1524)
				(type default)
			)
			(layer "F.SilkS")
		)
		(fp_line
			(start -0.9017 -0.733044)
			(end -2.638044 -0.733044)
			(stroke
				(width 0.1524)
				(type default)
			)
			(layer "F.SilkS")
		)
		(fp_line
			(start -0.9017 1.587754)
			(end -0.7239 1.587754)
			(stroke
				(width 0.1524)
				(type default)
			)
			(layer "F.SilkS")
		)
		(fp_line
			(start -0.7239 -1.714246)
			(end -0.9017 -1.714246)
			(stroke
				(width 0.1524)
				(type default)
			)
			(layer "F.SilkS")
		)
		(fp_line
			(start 0.7239 1.587754)
			(end 0.9017 1.587754)
			(stroke
				(width 0.1524)
				(type default)
			)
			(layer "F.SilkS")
		)
		(fp_line
			(start 0.9017 -1.714246)
			(end 0.7239 -1.714246)
			(stroke
				(width 0.1524)
				(type default)
			)
			(layer "F.SilkS")
		)
		(fp_line
			(start 0.9017 1.587754)
			(end 0.9017 -1.714246)
			(stroke
				(width 0.1524)
				(type default)
			)
			(layer "F.SilkS")
		)
		(fp_line
			(start 0.9017 6.067044)
			(end 3.400044 6.067044)
			(stroke
				(width 0.1524)
				(type default)
			)
			(layer "F.SilkS")
		)
		(fp_line
			(start 2.638044 -0.733044)
			(end 0.9017 -0.733044)
			(stroke
				(width 0.1524)
				(type default)
			)
			(layer "F.SilkS")
		)
		(fp_line
			(start 3.400044 0.028956)
			(end 2.638044 -0.733044)
			(stroke
				(width 0.1524)
				(type default)
			)
			(layer "F.SilkS")
		)
		(fp_line
			(start 3.400044 6.067044)
			(end 3.400044 0.028956)
			(stroke
				(width 0.1524)
				(type default)
			)
			(layer "F.SilkS")
		)
		(fp_poly
			(pts
				(xy -3.400044 6.067044) (xy 3.400044 6.067044) (xy 3.400044 0.028956) (xy 2.638044 -0.733044) (xy -2.638044 -0.733044)
				(xy -3.400044 0.028956)
			)
			(stroke
				(width 0)
				(type default)
			)
			(fill no)
			(layer "F.CrtYd")
		)
		(fp_line
			(start -3.400044 0.028956)
			(end -3.400044 6.067044)
			(stroke
				(width 0.1)
				(type default)
			)
			(layer "F.Fab")
		)
		(fp_line
			(start -3.400044 6.067044)
			(end 3.400044 6.067044)
			(stroke
				(width 0.1)
				(type default)
			)
			(layer "F.Fab")
		)
		(fp_line
			(start -2.638044 -0.733044)
			(end -3.400044 0.028956)
			(stroke
				(width 0.1)
				(type default)
			)
			(layer "F.Fab")
		)
		(fp_line
			(start 2.638044 -0.733044)
			(end -2.638044 -0.733044)
			(stroke
				(width 0.1)
				(type default)
			)
			(layer "F.Fab")
		)
		(fp_line
			(start 3.400044 0.028956)
			(end 2.638044 -0.733044)
			(stroke
				(width 0.1)
				(type default)
			)
			(layer "F.Fab")
		)
		(fp_line
			(start 3.400044 6.067044)
			(end 3.400044 0.028956)
			(stroke
				(width 0.1)
				(type default)
			)
			(layer "F.Fab")
		)
		(fp_circle
			(center 0 2.667)
			(end 3.400044 2.667)
			(stroke
				(width 0.1)
				(type default)
			)
			(fill no)
			(layer "F.Fab")
		)
		(pad "1" smd rect
			(at 0 0)
			(size 0.7874 3.429)
			(layers "F.Cu" "F.Mask" "F.Paste")
			(net "VR_FET_SW_P12V_STBY_PVCCIN_CPU1")
		)
		(pad "2" smd rect
			(at 0 5.334)
			(size 0.7874 3.429)
			(layers "F.Cu" "F.Mask" "F.Paste")
			(net "GND")
		)
	)
	(footprint ""
		(layer "F.Cu")
		(at 258.1656 -12.9032 -90)
		(property "Reference" "C5G10"
			(at 0 0 270)
			(layer "F.SilkS")
			(hide yes)
			(effects
				(font
					(size 1.27 1.27)
				)
			)
		)
		(property "Value" ""
			(at 0 0 270)
			(layer "F.Fab")
			(effects
				(font
					(size 1.27 1.27)
				)
			)
		)
		(duplicate_pad_numbers_are_jumpers no)
		(fp_rect
			(start -0.500126 1.598422)
			(end 0.500126 -0.201422)
			(stroke
				(width 0)
				(type default)
			)
			(fill no)
			(layer "F.CrtYd")
		)
		(fp_line
			(start -0.500126 1.598422)
			(end -0.500126 -0.201422)
			(stroke
				(width 0.1)
				(type default)
			)
			(layer "F.Fab")
		)
		(fp_line
			(start 0.500126 1.598422)
			(end -0.500126 1.598422)
			(stroke
				(width 0.1)
				(type default)
			)
			(layer "F.Fab")
		)
		(fp_line
			(start -0.500126 -0.201422)
			(end 0.500126 -0.201422)
			(stroke
				(width 0.1)
				(type default)
			)
			(layer "F.Fab")
		)
		(fp_line
			(start 0.500126 -0.201422)
			(end 0.500126 1.598422)
			(stroke
				(width 0.1)
				(type default)
			)
			(layer "F.Fab")
		)
		(pad "1" smd rect
			(at 0 0 180)
			(size 0.889 0.9906)
			(layers "F.Cu" "F.Mask" "F.Paste")
			(net "PVDDQ_ABC")
		)
		(pad "2" smd rect
			(at 0 1.397 180)
			(size 0.889 0.9906)
			(layers "F.Cu" "F.Mask" "F.Paste")
			(net "GND")
		)
		(zone
			(layer "F.Cu")
			(hatch none 0.5)
			(connect_pads
				(clearance 0)
			)
			(min_thickness 0.25)
			(keepout
				(tracks not_allowed)
				(vias allowed)
				(pads allowed)
				(copperpour not_allowed)
				(footprints allowed)
			)
			(placement
				(enabled no)
				(sheetname "")
			)
			(fill
				(thermal_gap 0.5)
				(thermal_bridge_width 0.5)
				(island_removal_mode 0)
			)
			(polygon
				(pts
					(xy 257.2131 -13.3985) (xy 257.2131 -12.4079) (xy 257.7211 -12.4079) (xy 257.7211 -13.3985)
				)
			)
		)
		(zone
			(layer "F.Cu")
			(hatch none 0.5)
			(connect_pads
				(clearance 0)
			)
			(min_thickness 0.25)
			(keepout
				(tracks allowed)
				(vias not_allowed)
				(pads allowed)
				(copperpour not_allowed)
				(footprints allowed)
			)
			(placement
				(enabled no)
				(sheetname "")
			)
			(fill
				(thermal_gap 0.5)
				(thermal_bridge_width 0.5)
				(island_removal_mode 0)
			)
			(polygon
				(pts
					(xy 257.2131 -13.3985) (xy 257.2131 -12.4079) (xy 257.7211 -12.4079) (xy 257.7211 -13.3985)
				)
			)
		)
	)
	(footprint ""
		(layer "F.Cu")
		(at 172.5676 -93.3958 180)
		(property "Reference" "R4C8"
			(at 0 0 180)
			(layer "F.SilkS")
			(hide yes)
			(effects
				(font
					(size 1.27 1.27)
				)
			)
		)
		(property "Value" ""
			(at 0 0 180)
			(layer "F.Fab")
			(effects
				(font
					(size 1.27 1.27)
				)
			)
		)
		(duplicate_pad_numbers_are_jumpers no)
		(fp_poly
			(pts
				(xy -0.2794 -0.1016) (xy 0.2794 -0.1016) (xy 0.2794 0.9906) (xy -0.2794 0.9906)
			)
			(stroke
				(width 0)
				(type default)
			)
			(fill no)
			(layer "F.CrtYd")
		)
		(fp_line
			(start 0.2794 0.9906)
			(end 0.2794 -0.1016)
			(stroke
				(width 0.1)
				(type default)
			)
			(layer "F.Fab")
		)
		(fp_line
			(start 0.2794 -0.1016)
			(end -0.2794 -0.1016)
			(stroke
				(width 0.1)
				(type default)
			)
			(layer "F.Fab")
		)
		(fp_line
			(start -0.2794 0.9906)
			(end 0.2794 0.9906)
			(stroke
				(width 0.1)
				(type default)
			)
			(layer "F.Fab")
		)
		(fp_line
			(start -0.2794 -0.1016)
			(end -0.2794 0.9906)
			(stroke
				(width 0.1)
				(type default)
			)
			(layer "F.Fab")
		)
		(pad "1" smd rect
			(at 0 0 180)
			(size 0.508 0.508)
			(layers "F.Cu" "F.Mask" "F.Paste")
			(net "P3V3_STBY")
		)
		(pad "2" smd rect
			(at 0 0.889 180)
			(size 0.508 0.508)
			(layers "F.Cu" "F.Mask" "F.Paste")
			(net "PU_GTL2014_2_DIR")
		)
		(zone
			(layer "F.Cu")
			(hatch none 0.5)
			(connect_pads
				(clearance 0)
			)
			(min_thickness 0.25)
			(keepout
				(tracks not_allowed)
				(vias allowed)
				(pads allowed)
				(copperpour not_allowed)
				(footprints allowed)
			)
			(placement
				(enabled no)
				(sheetname "")
			)
			(fill
				(thermal_gap 0.5)
				(thermal_bridge_width 0.5)
				(island_removal_mode 0)
			)
			(polygon
				(pts
					(xy 172.8216 -94.0308) (xy 172.3136 -94.0308) (xy 172.3136 -93.6498) (xy 172.8216 -93.6498)
				)
			)
		)
		(zone
			(layer "F.Cu")
			(hatch none 0.5)
			(connect_pads
				(clearance 0)
			)
			(min_thickness 0.25)
			(keepout
				(tracks allowed)
				(vias not_allowed)
				(pads allowed)
				(copperpour not_allowed)
				(footprints allowed)
			)
			(placement
				(enabled no)
				(sheetname "")
			)
			(fill
				(thermal_gap 0.5)
				(thermal_bridge_width 0.5)
				(island_removal_mode 0)
			)
			(polygon
				(pts
					(xy 172.8216 -93.6498) (xy 172.3136 -93.6498) (xy 172.3136 -94.0308) (xy 172.8216 -94.0308)
				)
			)
		)
	)
	(footprint ""
		(layer "F.Cu")
		(at 384.4798 -146.574764)
		(property "Reference" "L7A4"
			(at 3.378708 -4.251706 0)
			(unlocked yes)
			(layer "F.SilkS")
			(effects
				(font
					(size 0.4064 0.254)
					(thickness 0.1524)
				)
			)
		)
		(property "Value" ""
			(at 0 0 0)
			(layer "F.Fab")
			(effects
				(font
					(size 1.27 1.27)
				)
			)
		)
		(duplicate_pad_numbers_are_jumpers no)
		(fp_line
			(start -1.1303 -3.199892)
			(end 8.3693 -3.199892)
			(stroke
				(width 0.1524)
				(type default)
			)
			(layer "F.SilkS")
		)
		(fp_line
			(start -1.1303 -1.6637)
			(end -1.1303 -3.199892)
			(stroke
				(width 0.1524)
				(type default)
			)
			(layer "F.SilkS")
		)
		(fp_line
			(start -1.1303 3.199892)
			(end -1.1303 1.6637)
			(stroke
				(width 0.1524)
				(type default)
			)
			(layer "F.SilkS")
		)
		(fp_line
			(start 8.3693 -3.199892)
			(end 8.3693 -1.6637)
			(stroke
				(width 0.1524)
				(type default)
			)
			(layer "F.SilkS")
		)
		(fp_line
			(start 8.3693 1.6637)
			(end 8.3693 3.199892)
			(stroke
				(width 0.1524)
				(type default)
			)
			(layer "F.SilkS")
		)
		(fp_line
			(start 8.3693 3.199892)
			(end -1.1303 3.199892)
			(stroke
				(width 0.1524)
				(type default)
			)
			(layer "F.SilkS")
		)
		(fp_rect
			(start -1.1303 3.199892)
			(end 8.3693 -3.199892)
			(stroke
				(width 0)
				(type default)
			)
			(fill no)
			(layer "F.CrtYd")
		)
		(fp_line
			(start -1.1303 -3.199892)
			(end 8.3693 -3.199892)
			(stroke
				(width 0.1)
				(type default)
			)
			(layer "F.Fab")
		)
		(fp_line
			(start -1.1303 3.199892)
			(end -1.1303 -3.199892)
			(stroke
				(width 0.1)
				(type default)
			)
			(layer "F.Fab")
		)
		(fp_line
			(start 8.3693 -3.199892)
			(end 8.3693 3.199892)
			(stroke
				(width 0.1)
				(type default)
			)
			(layer "F.Fab")
		)
		(fp_line
			(start 8.3693 3.199892)
			(end -1.1303 3.199892)
			(stroke
				(width 0.1)
				(type default)
			)
			(layer "F.Fab")
		)
		(pad "1" smd rect
			(at 0 0)
			(size 3.683 2.667)
			(layers "F.Cu" "F.Mask" "F.Paste")
			(net "VR_P1V05_PCH_STBY_PH1_PHASE_SW")
		)
		(pad "2" smd rect
			(at 7.239 0)
			(size 3.683 2.667)
			(layers "F.Cu" "F.Mask" "F.Paste")
			(net "P1V05_PCH_STBY")
		)
	)
	(footprint ""
		(layer "F.Cu")
		(at 201.87158 -77.47 -90)
		(property "Reference" "RT27"
			(at 0 0 270)
			(layer "F.SilkS")
			(hide yes)
			(effects
				(font
					(size 1.27 1.27)
				)
			)
		)
		(property "Value" "*"
			(at -0.0254 -2.6289 270)
			(unlocked yes)
			(layer "F.Fab")
			(hide yes)
			(effects
				(font
					(size 1.27 1.016)
					(thickness 0.1524)
				)
			)
		)
		(property "Device Type" "1R3F-GP_RCL_GP-1R3F-GP,64.1R00A"
			(at -0.0254 -4.1529 270)
			(unlocked yes)
			(layer "F.Fab")
			(hide yes)
			(effects
				(font
					(size 1.27 1.016)
					(thickness 0.1524)
				)
			)
		)
		(duplicate_pad_numbers_are_jumpers no)
		(fp_line
			(start -0.4826 0)
			(end -0.2032 0)
			(stroke
				(width 0.2032)
				(type default)
			)
			(layer "F.SilkS")
		)
		(fp_line
			(start 0.2032 0)
			(end 0.4826 0)
			(stroke
				(width 0.2032)
				(type default)
			)
			(layer "F.SilkS")
		)
		(fp_rect
			(start -0.5842 1.3335)
			(end 0.5842 -1.3335)
			(stroke
				(width 0)
				(type default)
			)
			(fill no)
			(layer "F.CrtYd")
		)
		(fp_rect
			(start -0.5842 1.3335)
			(end 0.5842 -1.3335)
			(stroke
				(width 0)
				(type default)
			)
			(fill no)
			(layer "F.Fab")
		)
		(pad "1" smd custom
			(at 0 -0.762 270)
			(size 0.2159 0.2159)
			(layers "F.Cu" "F.Mask" "F.Paste")
			(net "VR_PVCCIN_CPU0_PHASE4_RC")
			(options
				(clearance outline)
				(anchor circle)
			)
			(primitives
				(gr_poly
					(pts
						(arc
							(start -0.3302 -0.4318)
							(mid -0.402042 -0.402042)
							(end -0.4318 -0.3302)
						)
						(arc
							(start -0.4318 0.3302)
							(mid -0.402042 0.402042)
							(end -0.3302 0.4318)
						)
						(arc
							(start 0.3302 0.4318)
							(mid 0.402042 0.402042)
							(end 0.4318 0.3302)
						)
						(arc
							(start 0.4318 -0.3302)
							(mid 0.402042 -0.402042)
							(end 0.3302 -0.4318)
						)
					)
					(width 0)
					(fill yes)
				)
			)
		)
		(pad "2" smd custom
			(at 0 0.762 270)
			(size 0.2159 0.2159)
			(layers "F.Cu" "F.Mask" "F.Paste")
			(net "GND")
			(options
				(clearance outline)
				(anchor circle)
			)
			(primitives
				(gr_poly
					(pts
						(arc
							(start -0.3302 -0.4318)
							(mid -0.402042 -0.402042)
							(end -0.4318 -0.3302)
						)
						(arc
							(start -0.4318 0.3302)
							(mid -0.402042 0.402042)
							(end -0.3302 0.4318)
						)
						(arc
							(start 0.3302 0.4318)
							(mid 0.402042 0.402042)
							(end 0.4318 0.3302)
						)
						(arc
							(start 0.4318 -0.3302)
							(mid 0.402042 -0.402042)
							(end 0.3302 -0.4318)
						)
					)
					(width 0)
					(fill yes)
				)
			)
		)
	)
	(footprint ""
		(layer "F.Cu")
		(at 395.351 -88.2015)
		(property "Reference" "R2U6"
			(at 0 0 0)
			(layer "F.SilkS")
			(hide yes)
			(effects
				(font
					(size 1.27 1.27)
				)
			)
		)
		(property "Value" ""
			(at 0 0 0)
			(layer "F.Fab")
			(effects
				(font
					(size 1.27 1.27)
				)
			)
		)
		(duplicate_pad_numbers_are_jumpers no)
		(fp_poly
			(pts
				(xy -0.2794 -0.1016) (xy 0.2794 -0.1016) (xy 0.2794 0.9906) (xy -0.2794 0.9906)
			)
			(stroke
				(width 0)
				(type default)
			)
			(fill no)
			(layer "F.CrtYd")
		)
		(fp_line
			(start -0.2794 -0.1016)
			(end -0.2794 0.9906)
			(stroke
				(width 0.1)
				(type default)
			)
			(layer "F.Fab")
		)
		(fp_line
			(start -0.2794 0.9906)
			(end 0.2794 0.9906)
			(stroke
				(width 0.1)
				(type default)
			)
			(layer "F.Fab")
		)
		(fp_line
			(start 0.2794 -0.1016)
			(end -0.2794 -0.1016)
			(stroke
				(width 0.1)
				(type default)
			)
			(layer "F.Fab")
		)
		(fp_line
			(start 0.2794 0.9906)
			(end 0.2794 -0.1016)
			(stroke
				(width 0.1)
				(type default)
			)
			(layer "F.Fab")
		)
		(pad "1" smd rect
			(at 0 0)
			(size 0.508 0.508)
			(layers "F.Cu" "F.Mask" "F.Paste")
			(net "SMB_LAN_STBY_LVC3_SCL_R1")
		)
		(pad "2" smd rect
			(at 0 0.889)
			(size 0.508 0.508)
			(layers "F.Cu" "F.Mask" "F.Paste")
			(net "SMB_LAN_STBY_LVC3_SCL")
		)
		(zone
			(layer "F.Cu")
			(hatch none 0.5)
			(connect_pads
				(clearance 0)
			)
			(min_thickness 0.25)
			(keepout
				(tracks allowed)
				(vias not_allowed)
				(pads allowed)
				(copperpour not_allowed)
				(footprints allowed)
			)
			(placement
				(enabled no)
				(sheetname "")
			)
			(fill
				(thermal_gap 0.5)
				(thermal_bridge_width 0.5)
				(island_removal_mode 0)
			)
			(polygon
				(pts
					(xy 395.097 -87.9475) (xy 395.605 -87.9475) (xy 395.605 -87.5665) (xy 395.097 -87.5665)
				)
			)
		)
		(zone
			(layer "F.Cu")
			(hatch none 0.5)
			(connect_pads
				(clearance 0)
			)
			(min_thickness 0.25)
			(keepout
				(tracks not_allowed)
				(vias allowed)
				(pads allowed)
				(copperpour not_allowed)
				(footprints allowed)
			)
			(placement
				(enabled no)
				(sheetname "")
			)
			(fill
				(thermal_gap 0.5)
				(thermal_bridge_width 0.5)
				(island_removal_mode 0)
			)
			(polygon
				(pts
					(xy 395.097 -87.5665) (xy 395.605 -87.5665) (xy 395.605 -87.9475) (xy 395.097 -87.9475)
				)
			)
		)
	)
	(footprint ""
		(layer "F.Cu")
		(at 354.89769 -139.965176 -90)
		(property "Reference" "C7A29"
			(at 0 0 270)
			(layer "F.SilkS")
			(hide yes)
			(effects
				(font
					(size 1.27 1.27)
				)
			)
		)
		(property "Value" ""
			(at 0 0 270)
			(layer "F.Fab")
			(effects
				(font
					(size 1.27 1.27)
				)
			)
		)
		(duplicate_pad_numbers_are_jumpers no)
		(fp_rect
			(start 0.3048 0.9906)
			(end -0.3048 -0.1016)
			(stroke
				(width 0)
				(type default)
			)
			(fill no)
			(layer "F.CrtYd")
		)
		(fp_line
			(start -0.3048 0.9906)
			(end 0.3048 0.9906)
			(stroke
				(width 0.1)
				(type default)
			)
			(layer "F.Fab")
		)
		(fp_line
			(start 0.3048 0.9906)
			(end 0.3048 -0.1016)
			(stroke
				(width 0.1)
				(type default)
			)
			(layer "F.Fab")
		)
		(fp_line
			(start -0.3048 -0.1016)
			(end -0.3048 0.9906)
			(stroke
				(width 0.1)
				(type default)
			)
			(layer "F.Fab")
		)
		(fp_line
			(start 0.3048 -0.1016)
			(end -0.3048 -0.1016)
			(stroke
				(width 0.1)
				(type default)
			)
			(layer "F.Fab")
		)
		(pad "1" smd rect
			(at 0 0 270)
			(size 0.508 0.508)
			(layers "F.Cu" "F.Mask" "F.Paste")
			(net "A_TSENSE_PVDDQ_DEF")
		)
		(pad "2" smd rect
			(at 0 0.889 270)
			(size 0.508 0.508)
			(layers "F.Cu" "F.Mask" "F.Paste")
			(net "GND")
		)
		(zone
			(layer "F.Cu")
			(hatch none 0.5)
			(connect_pads
				(clearance 0)
			)
			(min_thickness 0.25)
			(keepout
				(tracks not_allowed)
				(vias allowed)
				(pads allowed)
				(copperpour not_allowed)
				(footprints allowed)
			)
			(placement
				(enabled no)
				(sheetname "")
			)
			(fill
				(thermal_gap 0.5)
				(thermal_bridge_width 0.5)
				(island_removal_mode 0)
			)
			(polygon
				(pts
					(xy 354.26269 -139.711176) (xy 354.64369 -139.711176) (xy 354.64369 -140.219176) (xy 354.26269 -140.219176)
				)
			)
		)
		(zone
			(layer "F.Cu")
			(hatch none 0.5)
			(connect_pads
				(clearance 0)
			)
			(min_thickness 0.25)
			(keepout
				(tracks allowed)
				(vias not_allowed)
				(pads allowed)
				(copperpour not_allowed)
				(footprints allowed)
			)
			(placement
				(enabled no)
				(sheetname "")
			)
			(fill
				(thermal_gap 0.5)
				(thermal_bridge_width 0.5)
				(island_removal_mode 0)
			)
			(polygon
				(pts
					(xy 354.26269 -139.711176) (xy 354.64369 -139.711176) (xy 354.64369 -140.219176) (xy 354.26269 -140.219176)
				)
			)
		)
	)
	(footprint ""
		(layer "F.Cu")
		(at 0.889 -134.3152 -90)
		(property "Reference" "C1B20"
			(at 0 0 270)
			(layer "F.SilkS")
			(hide yes)
			(effects
				(font
					(size 1.27 1.27)
				)
			)
		)
		(property "Value" ""
			(at 0 0 270)
			(layer "F.Fab")
			(effects
				(font
					(size 1.27 1.27)
				)
			)
		)
		(duplicate_pad_numbers_are_jumpers no)
		(fp_poly
			(pts
				(xy 0.3048 -0.1016) (xy 0.3048 0.9906) (xy -0.3048 0.9906) (xy -0.3048 -0.1016)
			)
			(stroke
				(width 0)
				(type default)
			)
			(fill no)
			(layer "F.CrtYd")
		)
		(fp_line
			(start -0.3048 0.9906)
			(end 0.3048 0.9906)
			(stroke
				(width 0.1)
				(type default)
			)
			(layer "F.Fab")
		)
		(fp_line
			(start 0.3048 0.9906)
			(end 0.3048 -0.1016)
			(stroke
				(width 0.1)
				(type default)
			)
			(layer "F.Fab")
		)
		(fp_line
			(start -0.3048 -0.1016)
			(end -0.3048 0.9906)
			(stroke
				(width 0.1)
				(type default)
			)
			(layer "F.Fab")
		)
		(fp_line
			(start 0.3048 -0.1016)
			(end -0.3048 -0.1016)
			(stroke
				(width 0.1)
				(type default)
			)
			(layer "F.Fab")
		)
		(pad "1" smd rect
			(at 0 0 270)
			(size 0.508 0.508)
			(layers "F.Cu" "F.Mask" "F.Paste")
			(net "VR_PVDDQ_KLM_PH1_VCIN")
		)
		(pad "2" smd rect
			(at 0 0.889 270)
			(size 0.508 0.508)
			(layers "F.Cu" "F.Mask" "F.Paste")
			(net "GND")
		)
		(zone
			(layer "F.Cu")
			(hatch none 0.5)
			(connect_pads
				(clearance 0)
			)
			(min_thickness 0.25)
			(keepout
				(tracks not_allowed)
				(vias allowed)
				(pads allowed)
				(copperpour not_allowed)
				(footprints allowed)
			)
			(placement
				(enabled no)
				(sheetname "")
			)
			(fill
				(thermal_gap 0.5)
				(thermal_bridge_width 0.5)
				(island_removal_mode 0)
			)
			(polygon
				(pts
					(xy 0.254 -134.5692) (xy 0.254 -134.0612) (xy 0.635 -134.0612) (xy 0.635 -134.5692)
				)
			)
		)
		(zone
			(layer "F.Cu")
			(hatch none 0.5)
			(connect_pads
				(clearance 0)
			)
			(min_thickness 0.25)
			(keepout
				(tracks allowed)
				(vias not_allowed)
				(pads allowed)
				(copperpour not_allowed)
				(footprints allowed)
			)
			(placement
				(enabled no)
				(sheetname "")
			)
			(fill
				(thermal_gap 0.5)
				(thermal_bridge_width 0.5)
				(island_removal_mode 0)
			)
			(polygon
				(pts
					(xy 0.635 -134.5692) (xy 0.635 -134.0612) (xy 0.254 -134.0612) (xy 0.254 -134.5692)
				)
			)
		)
	)
	(footprint ""
		(layer "F.Cu")
		(at 379.222 -88.2015)
		(property "Reference" "R25W69"
			(at -0.8382 -0.67818 0)
			(unlocked yes)
			(layer "F.SilkS")
			(effects
				(font
					(size 0.4064 0.254)
					(thickness 0.1524)
				)
				(justify left)
			)
		)
		(property "Value" ""
			(at 0 0 0)
			(layer "F.Fab")
			(effects
				(font
					(size 1.27 1.27)
				)
			)
		)
		(duplicate_pad_numbers_are_jumpers no)
		(fp_poly
			(pts
				(xy -0.2794 -0.1016) (xy 0.2794 -0.1016) (xy 0.2794 0.9906) (xy -0.2794 0.9906)
			)
			(stroke
				(width 0)
				(type default)
			)
			(fill no)
			(layer "F.CrtYd")
		)
		(fp_line
			(start -0.2794 -0.1016)
			(end -0.2794 0.9906)
			(stroke
				(width 0.1)
				(type default)
			)
			(layer "F.Fab")
		)
		(fp_line
			(start -0.2794 0.9906)
			(end 0.2794 0.9906)
			(stroke
				(width 0.1)
				(type default)
			)
			(layer "F.Fab")
		)
		(fp_line
			(start 0.2794 -0.1016)
			(end -0.2794 -0.1016)
			(stroke
				(width 0.1)
				(type default)
			)
			(layer "F.Fab")
		)
		(fp_line
			(start 0.2794 0.9906)
			(end 0.2794 -0.1016)
			(stroke
				(width 0.1)
				(type default)
			)
			(layer "F.Fab")
		)
		(pad "1" smd rect
			(at 0 0)
			(size 0.508 0.508)
			(layers "F.Cu" "F.Mask" "F.Paste")
			(net "LPC_LAD1_IO1")
		)
		(pad "2" smd rect
			(at 0 0.889)
			(size 0.508 0.508)
			(layers "F.Cu" "F.Mask" "F.Paste")
			(net "LPC_LAD1_IO1_R")
		)
		(zone
			(layer "F.Cu")
			(hatch none 0.5)
			(connect_pads
				(clearance 0)
			)
			(min_thickness 0.25)
			(keepout
				(tracks allowed)
				(vias not_allowed)
				(pads allowed)
				(copperpour not_allowed)
				(footprints allowed)
			)
			(placement
				(enabled no)
				(sheetname "")
			)
			(fill
				(thermal_gap 0.5)
				(thermal_bridge_width 0.5)
				(island_removal_mode 0)
			)
			(polygon
				(pts
					(xy 378.968 -87.9475) (xy 379.476 -87.9475) (xy 379.476 -87.5665) (xy 378.968 -87.5665)
				)
			)
		)
		(zone
			(layer "F.Cu")
			(hatch none 0.5)
			(connect_pads
				(clearance 0)
			)
			(min_thickness 0.25)
			(keepout
				(tracks not_allowed)
				(vias allowed)
				(pads allowed)
				(copperpour not_allowed)
				(footprints allowed)
			)
			(placement
				(enabled no)
				(sheetname "")
			)
			(fill
				(thermal_gap 0.5)
				(thermal_bridge_width 0.5)
				(island_removal_mode 0)
			)
			(polygon
				(pts
					(xy 378.968 -87.5665) (xy 379.476 -87.5665) (xy 379.476 -87.9475) (xy 378.968 -87.9475)
				)
			)
		)
	)
	(footprint ""
		(layer "F.Cu")
		(at 349.123 -12.827 90)
		(property "Reference" "R7G10"
			(at 0 0 90)
			(layer "F.SilkS")
			(hide yes)
			(effects
				(font
					(size 1.27 1.27)
				)
			)
		)
		(property "Value" ""
			(at 0 0 90)
			(layer "F.Fab")
			(effects
				(font
					(size 1.27 1.27)
				)
			)
		)
		(duplicate_pad_numbers_are_jumpers no)
		(fp_poly
			(pts
				(xy -0.2794 -0.1016) (xy 0.2794 -0.1016) (xy 0.2794 0.9906) (xy -0.2794 0.9906)
			)
			(stroke
				(width 0)
				(type default)
			)
			(fill no)
			(layer "F.CrtYd")
		)
		(fp_line
			(start 0.2794 -0.1016)
			(end -0.2794 -0.1016)
			(stroke
				(width 0.1)
				(type default)
			)
			(layer "F.Fab")
		)
		(fp_line
			(start -0.2794 -0.1016)
			(end -0.2794 0.9906)
			(stroke
				(width 0.1)
				(type default)
			)
			(layer "F.Fab")
		)
		(fp_line
			(start 0.2794 0.9906)
			(end 0.2794 -0.1016)
			(stroke
				(width 0.1)
				(type default)
			)
			(layer "F.Fab")
		)
		(fp_line
			(start -0.2794 0.9906)
			(end 0.2794 0.9906)
			(stroke
				(width 0.1)
				(type default)
			)
			(layer "F.Fab")
		)
		(pad "1" smd rect
			(at 0 0 90)
			(size 0.508 0.508)
			(layers "F.Cu" "F.Mask" "F.Paste")
			(net "VR_PVDDQ_ABC_XADDR2")
		)
		(pad "2" smd rect
			(at 0 0.889 90)
			(size 0.508 0.508)
			(layers "F.Cu" "F.Mask" "F.Paste")
			(net "GND")
		)
		(zone
			(layer "F.Cu")
			(hatch none 0.5)
			(connect_pads
				(clearance 0)
			)
			(min_thickness 0.25)
			(keepout
				(tracks allowed)
				(vias not_allowed)
				(pads allowed)
				(copperpour not_allowed)
				(footprints allowed)
			)
			(placement
				(enabled no)
				(sheetname "")
			)
			(fill
				(thermal_gap 0.5)
				(thermal_bridge_width 0.5)
				(island_removal_mode 0)
			)
			(polygon
				(pts
					(xy 349.377 -12.573) (xy 349.377 -13.081) (xy 349.758 -13.081) (xy 349.758 -12.573)
				)
			)
		)
		(zone
			(layer "F.Cu")
			(hatch none 0.5)
			(connect_pads
				(clearance 0)
			)
			(min_thickness 0.25)
			(keepout
				(tracks not_allowed)
				(vias allowed)
				(pads allowed)
				(copperpour not_allowed)
				(footprints allowed)
			)
			(placement
				(enabled no)
				(sheetname "")
			)
			(fill
				(thermal_gap 0.5)
				(thermal_bridge_width 0.5)
				(island_removal_mode 0)
			)
			(polygon
				(pts
					(xy 349.758 -12.573) (xy 349.758 -13.081) (xy 349.377 -13.081) (xy 349.377 -12.573)
				)
			)
		)
	)
	(footprint ""
		(layer "F.Cu")
		(at 413.521652 -135.636)
		(property "Reference" "R8A13"
			(at 0 0 0)
			(layer "F.SilkS")
			(hide yes)
			(effects
				(font
					(size 1.27 1.27)
				)
			)
		)
		(property "Value" ""
			(at 0 0 0)
			(layer "F.Fab")
			(effects
				(font
					(size 1.27 1.27)
				)
			)
		)
		(duplicate_pad_numbers_are_jumpers no)
		(fp_poly
			(pts
				(xy -0.2794 -0.1016) (xy 0.2794 -0.1016) (xy 0.2794 0.9906) (xy -0.2794 0.9906)
			)
			(stroke
				(width 0)
				(type default)
			)
			(fill no)
			(layer "F.CrtYd")
		)
		(fp_line
			(start -0.2794 -0.1016)
			(end -0.2794 0.9906)
			(stroke
				(width 0.1)
				(type default)
			)
			(layer "F.Fab")
		)
		(fp_line
			(start -0.2794 0.9906)
			(end 0.2794 0.9906)
			(stroke
				(width 0.1)
				(type default)
			)
			(layer "F.Fab")
		)
		(fp_line
			(start 0.2794 -0.1016)
			(end -0.2794 -0.1016)
			(stroke
				(width 0.1)
				(type default)
			)
			(layer "F.Fab")
		)
		(fp_line
			(start 0.2794 0.9906)
			(end 0.2794 -0.1016)
			(stroke
				(width 0.1)
				(type default)
			)
			(layer "F.Fab")
		)
		(pad "1" smd rect
			(at 0 0)
			(size 0.508 0.508)
			(layers "F.Cu" "F.Mask" "F.Paste")
			(net "P1V05_PCH_STBY")
		)
		(pad "2" smd rect
			(at 0 0.889)
			(size 0.508 0.508)
			(layers "F.Cu" "F.Mask" "F.Paste")
			(net "XDP_TDI")
		)
		(zone
			(layer "F.Cu")
			(hatch none 0.5)
			(connect_pads
				(clearance 0)
			)
			(min_thickness 0.25)
			(keepout
				(tracks allowed)
				(vias not_allowed)
				(pads allowed)
				(copperpour not_allowed)
				(footprints allowed)
			)
			(placement
				(enabled no)
				(sheetname "")
			)
			(fill
				(thermal_gap 0.5)
				(thermal_bridge_width 0.5)
				(island_removal_mode 0)
			)
			(polygon
				(pts
					(xy 413.267652 -135.382) (xy 413.775652 -135.382) (xy 413.775652 -135.001) (xy 413.267652 -135.001)
				)
			)
		)
		(zone
			(layer "F.Cu")
			(hatch none 0.5)
			(connect_pads
				(clearance 0)
			)
			(min_thickness 0.25)
			(keepout
				(tracks not_allowed)
				(vias allowed)
				(pads allowed)
				(copperpour not_allowed)
				(footprints allowed)
			)
			(placement
				(enabled no)
				(sheetname "")
			)
			(fill
				(thermal_gap 0.5)
				(thermal_bridge_width 0.5)
				(island_removal_mode 0)
			)
			(polygon
				(pts
					(xy 413.267652 -135.001) (xy 413.775652 -135.001) (xy 413.775652 -135.382) (xy 413.267652 -135.382)
				)
			)
		)
	)
	(footprint ""
		(layer "F.Cu")
		(at 364.617 -112.395 90)
		(property "Reference" "C7B28"
			(at 0 0 90)
			(layer "F.SilkS")
			(hide yes)
			(effects
				(font
					(size 1.27 1.27)
				)
			)
		)
		(property "Value" ""
			(at 0 0 90)
			(layer "F.Fab")
			(effects
				(font
					(size 1.27 1.27)
				)
			)
		)
		(duplicate_pad_numbers_are_jumpers no)
		(fp_poly
			(pts
				(xy 0.3048 -0.1016) (xy 0.3048 0.9906) (xy -0.3048 0.9906) (xy -0.3048 -0.1016)
			)
			(stroke
				(width 0)
				(type default)
			)
			(fill no)
			(layer "F.CrtYd")
		)
		(fp_line
			(start 0.3048 -0.1016)
			(end -0.3048 -0.1016)
			(stroke
				(width 0.1)
				(type default)
			)
			(layer "F.Fab")
		)
		(fp_line
			(start -0.3048 -0.1016)
			(end -0.3048 0.9906)
			(stroke
				(width 0.1)
				(type default)
			)
			(layer "F.Fab")
		)
		(fp_line
			(start 0.3048 0.9906)
			(end 0.3048 -0.1016)
			(stroke
				(width 0.1)
				(type default)
			)
			(layer "F.Fab")
		)
		(fp_line
			(start -0.3048 0.9906)
			(end 0.3048 0.9906)
			(stroke
				(width 0.1)
				(type default)
			)
			(layer "F.Fab")
		)
		(pad "1" smd rect
			(at 0 0 90)
			(size 0.508 0.508)
			(layers "F.Cu" "F.Mask" "F.Paste")
			(net "DMI_CPU0_PCH_TX_DP<1>")
		)
		(pad "2" smd rect
			(at 0 0.889 90)
			(size 0.508 0.508)
			(layers "F.Cu" "F.Mask" "F.Paste")
			(net "DMI_CPU0_PCH_TX_C_DP<1>")
		)
		(zone
			(layer "F.Cu")
			(hatch none 0.5)
			(connect_pads
				(clearance 0)
			)
			(min_thickness 0.25)
			(keepout
				(tracks allowed)
				(vias not_allowed)
				(pads allowed)
				(copperpour not_allowed)
				(footprints allowed)
			)
			(placement
				(enabled no)
				(sheetname "")
			)
			(fill
				(thermal_gap 0.5)
				(thermal_bridge_width 0.5)
				(island_removal_mode 0)
			)
			(polygon
				(pts
					(xy 364.871 -112.141) (xy 364.871 -112.649) (xy 365.252 -112.649) (xy 365.252 -112.141)
				)
			)
		)
		(zone
			(layer "F.Cu")
			(hatch none 0.5)
			(connect_pads
				(clearance 0)
			)
			(min_thickness 0.25)
			(keepout
				(tracks not_allowed)
				(vias allowed)
				(pads allowed)
				(copperpour not_allowed)
				(footprints allowed)
			)
			(placement
				(enabled no)
				(sheetname "")
			)
			(fill
				(thermal_gap 0.5)
				(thermal_bridge_width 0.5)
				(island_removal_mode 0)
			)
			(polygon
				(pts
					(xy 365.252 -112.141) (xy 365.252 -112.649) (xy 364.871 -112.649) (xy 364.871 -112.141)
				)
			)
		)
	)
	(footprint ""
		(layer "F.Cu")
		(at 25.0698 -77.1906 90)
		(property "Reference" "Q1D2"
			(at -4.1402 1.60147 90)
			(unlocked yes)
			(layer "F.SilkS")
			(effects
				(font
					(size 0.7874 0.5842)
					(thickness 0.1524)
				)
				(justify left)
			)
		)
		(property "Value" ""
			(at 0 0 90)
			(layer "F.Fab")
			(effects
				(font
					(size 1.27 1.27)
				)
			)
		)
		(duplicate_pad_numbers_are_jumpers no)
		(fp_line
			(start 1.778 -0.5715)
			(end 1.778 0.3175)
			(stroke
				(width 0.1524)
				(type default)
			)
			(layer "F.SilkS")
		)
		(fp_line
			(start 0.9525 -0.5715)
			(end 1.778 -0.5715)
			(stroke
				(width 0.1524)
				(type default)
			)
			(layer "F.SilkS")
		)
		(fp_line
			(start 0.381 0.635)
			(end 0.381 1.27)
			(stroke
				(width 0.1524)
				(type default)
			)
			(layer "F.SilkS")
		)
		(fp_line
			(start 1.778 2.4765)
			(end 1.778 1.5875)
			(stroke
				(width 0.1524)
				(type default)
			)
			(layer "F.SilkS")
		)
		(fp_line
			(start 0.9525 2.4765)
			(end 1.778 2.4765)
			(stroke
				(width 0.1524)
				(type default)
			)
			(layer "F.SilkS")
		)
		(fp_circle
			(center -0.9525 -0.9271)
			(end -0.9525 -0.8001)
			(stroke
				(width 0.254)
				(type default)
			)
			(fill no)
			(layer "F.SilkS")
		)
		(fp_poly
			(pts
				(xy 1.778 2.4765) (xy 0.381 2.4765) (xy 0.381 -0.5715) (xy 1.778 -0.5715)
			)
			(stroke
				(width 0)
				(type default)
			)
			(fill no)
			(layer "F.CrtYd")
		)
		(fp_line
			(start 1.778 -0.5715)
			(end 0.381 -0.5715)
			(stroke
				(width 0.1)
				(type default)
			)
			(layer "F.Fab")
		)
		(fp_line
			(start 0.381 -0.5715)
			(end 0.381 2.4765)
			(stroke
				(width 0.1)
				(type default)
			)
			(layer "F.Fab")
		)
		(fp_line
			(start 1.778 2.4765)
			(end 1.778 -0.5715)
			(stroke
				(width 0.1)
				(type default)
			)
			(layer "F.Fab")
		)
		(fp_line
			(start 0.381 2.4765)
			(end 1.778 2.4765)
			(stroke
				(width 0.1)
				(type default)
			)
			(layer "F.Fab")
		)
		(fp_circle
			(center -0.9525 -0.9271)
			(end -0.9525 -0.8001)
			(stroke
				(width 0.254)
				(type default)
			)
			(fill no)
			(layer "F.Fab")
		)
		(pad "1" smd rect
			(at 0 0 90)
			(size 1.143 0.508)
			(layers "F.Cu" "F.Mask" "F.Paste")
			(net "FM_OC_DETECT_EN_N")
		)
		(pad "2" smd rect
			(at 0 1.905 90)
			(size 1.143 0.508)
			(layers "F.Cu" "F.Mask" "F.Paste")
			(net "GND")
		)
		(pad "3" smd rect
			(at 2.159 0.9525 90)
			(size 1.143 0.508)
			(layers "F.Cu" "F.Mask" "F.Paste")
			(net "FM_OC_DETECT_EN")
		)
	)
	(footprint ""
		(layer "F.Cu")
		(at 379.725428 -154.266646)
		(property "Reference" "C7A7"
			(at 0 0 0)
			(layer "F.SilkS")
			(hide yes)
			(effects
				(font
					(size 1.27 1.27)
				)
			)
		)
		(property "Value" ""
			(at 0 0 0)
			(layer "F.Fab")
			(effects
				(font
					(size 1.27 1.27)
				)
			)
		)
		(duplicate_pad_numbers_are_jumpers no)
		(fp_poly
			(pts
				(xy 0.3048 -0.1016) (xy 0.3048 0.9906) (xy -0.3048 0.9906) (xy -0.3048 -0.1016)
			)
			(stroke
				(width 0)
				(type default)
			)
			(fill no)
			(layer "F.CrtYd")
		)
		(fp_line
			(start -0.3048 -0.1016)
			(end -0.3048 0.9906)
			(stroke
				(width 0.1)
				(type default)
			)
			(layer "F.Fab")
		)
		(fp_line
			(start -0.3048 0.9906)
			(end 0.3048 0.9906)
			(stroke
				(width 0.1)
				(type default)
			)
			(layer "F.Fab")
		)
		(fp_line
			(start 0.3048 -0.1016)
			(end -0.3048 -0.1016)
			(stroke
				(width 0.1)
				(type default)
			)
			(layer "F.Fab")
		)
		(fp_line
			(start 0.3048 0.9906)
			(end 0.3048 -0.1016)
			(stroke
				(width 0.1)
				(type default)
			)
			(layer "F.Fab")
		)
		(pad "1" smd rect
			(at 0 0)
			(size 0.508 0.508)
			(layers "F.Cu" "F.Mask" "F.Paste")
			(net "VR_FET_SW_P12V_STBY_PVDDQ_DEF")
		)
		(pad "2" smd rect
			(at 0 0.889)
			(size 0.508 0.508)
			(layers "F.Cu" "F.Mask" "F.Paste")
			(net "GND")
		)
		(zone
			(layer "F.Cu")
			(hatch none 0.5)
			(connect_pads
				(clearance 0)
			)
			(min_thickness 0.25)
			(keepout
				(tracks allowed)
				(vias not_allowed)
				(pads allowed)
				(copperpour not_allowed)
				(footprints allowed)
			)
			(placement
				(enabled no)
				(sheetname "")
			)
			(fill
				(thermal_gap 0.5)
				(thermal_bridge_width 0.5)
				(island_removal_mode 0)
			)
			(polygon
				(pts
					(xy 379.471428 -154.012646) (xy 379.979428 -154.012646) (xy 379.979428 -153.631646) (xy 379.471428 -153.631646)
				)
			)
		)
		(zone
			(layer "F.Cu")
			(hatch none 0.5)
			(connect_pads
				(clearance 0)
			)
			(min_thickness 0.25)
			(keepout
				(tracks not_allowed)
				(vias allowed)
				(pads allowed)
				(copperpour not_allowed)
				(footprints allowed)
			)
			(placement
				(enabled no)
				(sheetname "")
			)
			(fill
				(thermal_gap 0.5)
				(thermal_bridge_width 0.5)
				(island_removal_mode 0)
			)
			(polygon
				(pts
					(xy 379.471428 -153.631646) (xy 379.979428 -153.631646) (xy 379.979428 -154.012646) (xy 379.471428 -154.012646)
				)
			)
		)
	)
	(footprint ""
		(layer "F.Cu")
		(at 385.30784 -89.55532 180)
		(property "Reference" "R7W15"
			(at -0.8382 -0.67818 180)
			(unlocked yes)
			(layer "F.SilkS")
			(effects
				(font
					(size 0.4064 0.254)
					(thickness 0.1524)
				)
				(justify left)
			)
		)
		(property "Value" ""
			(at 0 0 180)
			(layer "F.Fab")
			(effects
				(font
					(size 1.27 1.27)
				)
			)
		)
		(duplicate_pad_numbers_are_jumpers no)
		(fp_poly
			(pts
				(xy -0.2794 -0.1016) (xy 0.2794 -0.1016) (xy 0.2794 0.9906) (xy -0.2794 0.9906)
			)
			(stroke
				(width 0)
				(type default)
			)
			(fill no)
			(layer "F.CrtYd")
		)
		(fp_line
			(start 0.2794 0.9906)
			(end 0.2794 -0.1016)
			(stroke
				(width 0.1)
				(type default)
			)
			(layer "F.Fab")
		)
		(fp_line
			(start 0.2794 -0.1016)
			(end -0.2794 -0.1016)
			(stroke
				(width 0.1)
				(type default)
			)
			(layer "F.Fab")
		)
		(fp_line
			(start -0.2794 0.9906)
			(end 0.2794 0.9906)
			(stroke
				(width 0.1)
				(type default)
			)
			(layer "F.Fab")
		)
		(fp_line
			(start -0.2794 -0.1016)
			(end -0.2794 0.9906)
			(stroke
				(width 0.1)
				(type default)
			)
			(layer "F.Fab")
		)
		(pad "1" smd rect
			(at 0 0 180)
			(size 0.508 0.508)
			(layers "F.Cu" "F.Mask" "F.Paste")
			(net "FM_OCP_MEZZA_PRES")
		)
		(pad "2" smd rect
			(at 0 0.889 180)
			(size 0.508 0.508)
			(layers "F.Cu" "F.Mask" "F.Paste")
			(net "FM_OCP_MEZZA_PRES_R")
		)
		(zone
			(layer "F.Cu")
			(hatch none 0.5)
			(connect_pads
				(clearance 0)
			)
			(min_thickness 0.25)
			(keepout
				(tracks not_allowed)
				(vias allowed)
				(pads allowed)
				(copperpour not_allowed)
				(footprints allowed)
			)
			(placement
				(enabled no)
				(sheetname "")
			)
			(fill
				(thermal_gap 0.5)
				(thermal_bridge_width 0.5)
				(island_removal_mode 0)
			)
			(polygon
				(pts
					(xy 385.56184 -90.19032) (xy 385.05384 -90.19032) (xy 385.05384 -89.80932) (xy 385.56184 -89.80932)
				)
			)
		)
		(zone
			(layer "F.Cu")
			(hatch none 0.5)
			(connect_pads
				(clearance 0)
			)
			(min_thickness 0.25)
			(keepout
				(tracks allowed)
				(vias not_allowed)
				(pads allowed)
				(copperpour not_allowed)
				(footprints allowed)
			)
			(placement
				(enabled no)
				(sheetname "")
			)
			(fill
				(thermal_gap 0.5)
				(thermal_bridge_width 0.5)
				(island_removal_mode 0)
			)
			(polygon
				(pts
					(xy 385.56184 -89.80932) (xy 385.05384 -89.80932) (xy 385.05384 -90.19032) (xy 385.56184 -90.19032)
				)
			)
		)
	)
	(footprint ""
		(layer "F.Cu")
		(at 345.359228 -157.1244 90)
		(property "Reference" "RT29"
			(at 0 0 90)
			(layer "F.SilkS")
			(hide yes)
			(effects
				(font
					(size 1.27 1.27)
				)
			)
		)
		(property "Value" "*"
			(at -0.0254 -2.6289 90)
			(unlocked yes)
			(layer "F.Fab")
			(hide yes)
			(effects
				(font
					(size 1.27 1.016)
					(thickness 0.1524)
				)
			)
		)
		(property "Device Type" "1R3F-GP_RCL_GP-1R3F-GP,64.1R00A"
			(at -0.0254 -4.1529 90)
			(unlocked yes)
			(layer "F.Fab")
			(hide yes)
			(effects
				(font
					(size 1.27 1.016)
					(thickness 0.1524)
				)
			)
		)
		(duplicate_pad_numbers_are_jumpers no)
		(fp_line
			(start 0.2032 0)
			(end 0.4826 0)
			(stroke
				(width 0.2032)
				(type default)
			)
			(layer "F.SilkS")
		)
		(fp_line
			(start -0.4826 0)
			(end -0.2032 0)
			(stroke
				(width 0.2032)
				(type default)
			)
			(layer "F.SilkS")
		)
		(fp_rect
			(start -0.5842 1.3335)
			(end 0.5842 -1.3335)
			(stroke
				(width 0)
				(type default)
			)
			(fill no)
			(layer "F.CrtYd")
		)
		(fp_rect
			(start -0.5842 1.3335)
			(end 0.5842 -1.3335)
			(stroke
				(width 0)
				(type default)
			)
			(fill no)
			(layer "F.Fab")
		)
		(pad "1" smd custom
			(at 0 -0.762 90)
			(size 0.2159 0.2159)
			(layers "F.Cu" "F.Mask" "F.Paste")
			(net "VR_PVDDQ_DEF_PH1_SW_RC")
			(options
				(clearance outline)
				(anchor circle)
			)
			(primitives
				(gr_poly
					(pts
						(arc
							(start -0.3302 -0.4318)
							(mid -0.402042 -0.402042)
							(end -0.4318 -0.3302)
						)
						(arc
							(start -0.4318 0.3302)
							(mid -0.402042 0.402042)
							(end -0.3302 0.4318)
						)
						(arc
							(start 0.3302 0.4318)
							(mid 0.402042 0.402042)
							(end 0.4318 0.3302)
						)
						(arc
							(start 0.4318 -0.3302)
							(mid 0.402042 -0.402042)
							(end 0.3302 -0.4318)
						)
					)
					(width 0)
					(fill yes)
				)
			)
		)
		(pad "2" smd custom
			(at 0 0.762 90)
			(size 0.2159 0.2159)
			(layers "F.Cu" "F.Mask" "F.Paste")
			(net "GND")
			(options
				(clearance outline)
				(anchor circle)
			)
			(primitives
				(gr_poly
					(pts
						(arc
							(start -0.3302 -0.4318)
							(mid -0.402042 -0.402042)
							(end -0.4318 -0.3302)
						)
						(arc
							(start -0.4318 0.3302)
							(mid -0.402042 0.402042)
							(end -0.3302 0.4318)
						)
						(arc
							(start 0.3302 0.4318)
							(mid 0.402042 0.402042)
							(end 0.4318 0.3302)
						)
						(arc
							(start 0.4318 -0.3302)
							(mid 0.402042 -0.402042)
							(end 0.3302 -0.4318)
						)
					)
					(width 0)
					(fill yes)
				)
			)
		)
	)
	(footprint ""
		(layer "F.Cu")
		(at 273.558 -69.977)
		(property "Reference" "R5D6"
			(at 0 0 0)
			(layer "F.SilkS")
			(hide yes)
			(effects
				(font
					(size 1.27 1.27)
				)
			)
		)
		(property "Value" ""
			(at 0 0 0)
			(layer "F.Fab")
			(effects
				(font
					(size 1.27 1.27)
				)
			)
		)
		(duplicate_pad_numbers_are_jumpers no)
		(fp_poly
			(pts
				(xy -0.2794 -0.1016) (xy 0.2794 -0.1016) (xy 0.2794 0.9906) (xy -0.2794 0.9906)
			)
			(stroke
				(width 0)
				(type default)
			)
			(fill no)
			(layer "F.CrtYd")
		)
		(fp_line
			(start -0.2794 -0.1016)
			(end -0.2794 0.9906)
			(stroke
				(width 0.1)
				(type default)
			)
			(layer "F.Fab")
		)
		(fp_line
			(start -0.2794 0.9906)
			(end 0.2794 0.9906)
			(stroke
				(width 0.1)
				(type default)
			)
			(layer "F.Fab")
		)
		(fp_line
			(start 0.2794 -0.1016)
			(end -0.2794 -0.1016)
			(stroke
				(width 0.1)
				(type default)
			)
			(layer "F.Fab")
		)
		(fp_line
			(start 0.2794 0.9906)
			(end 0.2794 -0.1016)
			(stroke
				(width 0.1)
				(type default)
			)
			(layer "F.Fab")
		)
		(pad "1" smd rect
			(at 0 0)
			(size 0.508 0.508)
			(layers "F.Cu" "F.Mask" "F.Paste")
			(net "PVCCIO_CPU0")
		)
		(pad "2" smd rect
			(at 0 0.889)
			(size 0.508 0.508)
			(layers "F.Cu" "F.Mask" "F.Paste")
			(net "VSENSE_PMAX_CPU0")
		)
		(zone
			(layer "F.Cu")
			(hatch none 0.5)
			(connect_pads
				(clearance 0)
			)
			(min_thickness 0.25)
			(keepout
				(tracks allowed)
				(vias not_allowed)
				(pads allowed)
				(copperpour not_allowed)
				(footprints allowed)
			)
			(placement
				(enabled no)
				(sheetname "")
			)
			(fill
				(thermal_gap 0.5)
				(thermal_bridge_width 0.5)
				(island_removal_mode 0)
			)
			(polygon
				(pts
					(xy 273.304 -69.723) (xy 273.812 -69.723) (xy 273.812 -69.342) (xy 273.304 -69.342)
				)
			)
		)
		(zone
			(layer "F.Cu")
			(hatch none 0.5)
			(connect_pads
				(clearance 0)
			)
			(min_thickness 0.25)
			(keepout
				(tracks not_allowed)
				(vias allowed)
				(pads allowed)
				(copperpour not_allowed)
				(footprints allowed)
			)
			(placement
				(enabled no)
				(sheetname "")
			)
			(fill
				(thermal_gap 0.5)
				(thermal_bridge_width 0.5)
				(island_removal_mode 0)
			)
			(polygon
				(pts
					(xy 273.304 -69.342) (xy 273.812 -69.342) (xy 273.812 -69.723) (xy 273.304 -69.723)
				)
			)
		)
	)
	(footprint ""
		(layer "F.Cu")
		(at 415.490152 -34.934652 90)
		(property "Reference" "U25W4"
			(at 0 0 90)
			(layer "F.SilkS")
			(hide yes)
			(effects
				(font
					(size 1.27 1.27)
				)
			)
		)
		(property "Value" "*"
			(at -17.0307 -8.698992 90)
			(unlocked yes)
			(layer "F.Fab")
			(hide yes)
			(effects
				(font
					(size 1.27 1.016)
					(thickness 0.1524)
				)
			)
		)
		(property "Device Type" "AST2520A1-GP-GP_ASIC2-GB1-AST2A"
			(at -17.0307 -10.222992 90)
			(unlocked yes)
			(layer "F.Fab")
			(hide yes)
			(effects
				(font
					(size 1.27 1.016)
					(thickness 0.1524)
				)
			)
		)
		(duplicate_pad_numbers_are_jumpers no)
		(fp_line
			(start -9.830308 -9.830308)
			(end -8.230108 -9.830308)
			(stroke
				(width 0.508)
				(type default)
			)
			(layer "F.SilkS")
		)
		(fp_line
			(start 9.500108 -9.500108)
			(end -9.500108 -9.500108)
			(stroke
				(width 0.1524)
				(type default)
			)
			(layer "F.SilkS")
		)
		(fp_line
			(start -9.500108 -9.500108)
			(end -9.500108 9.500108)
			(stroke
				(width 0.1524)
				(type default)
			)
			(layer "F.SilkS")
		)
		(fp_line
			(start -9.830308 -8.230108)
			(end -9.830308 -9.830308)
			(stroke
				(width 0.508)
				(type default)
			)
			(layer "F.SilkS")
		)
		(fp_line
			(start 9.500108 9.500108)
			(end 9.500108 -9.500108)
			(stroke
				(width 0.1524)
				(type default)
			)
			(layer "F.SilkS")
		)
		(fp_line
			(start -9.500108 9.500108)
			(end 9.500108 9.500108)
			(stroke
				(width 0.1524)
				(type default)
			)
			(layer "F.SilkS")
		)
		(fp_rect
			(start -9.500108 9.500108)
			(end 9.500108 -9.500108)
			(stroke
				(width 0)
				(type default)
			)
			(fill no)
			(layer "F.CrtYd")
		)
		(fp_poly
			(pts
				(xy 10.500106 -9.500108) (xy -9.500108 -9.500108) (xy -9.500108 9.500108) (xy 9.500108 9.500108)
				(xy 9.500108 -9.487408) (xy 10.500106 -9.487408) (xy 10.500106 10.500106) (xy -10.500106 10.500106)
				(xy -10.500106 -10.500106) (xy 10.500106 -10.500106)
			)
			(stroke
				(width 0)
				(type default)
			)
			(fill no)
			(layer "F.CrtYd")
		)
		(fp_rect
			(start -11.500104 11.500104)
			(end 11.500104 -11.500104)
			(stroke
				(width 0)
				(type default)
			)
			(fill no)
			(layer "F.Fab")
		)
		(pad "A1" smd circle
			(at -8.400034 -8.400034 90)
			(size 0.4064 0.4064)
			(layers "F.Cu" "F.Mask" "F.Paste")
			(net "GND")
		)
		(pad "A2" smd circle
			(at -7.599934 -8.400034 90)
			(size 0.4064 0.4064)
			(layers "F.Cu" "F.Mask" "F.Paste")
			(net "RMII_BMC_PCH_SPRNGVLLE_TXD0_R")
		)
		(pad "A3" smd circle
			(at -6.800088 -8.400034 90)
			(size 0.4064 0.4064)
			(layers "F.Cu" "F.Mask" "F.Paste")
			(net "RMII_BMC_OCP_RXD0")
		)
		(pad "A4" smd circle
			(at -5.999988 -8.400034 90)
			(size 0.3556 0.3556)
			(layers "F.Cu" "F.Mask" "F.Paste")
			(net "FM_BMC_FAULT_LED_N")
		)
		(pad "A5" smd circle
			(at -5.199888 -8.400034 90)
			(size 0.3556 0.3556)
			(layers "F.Cu" "F.Mask" "F.Paste")
			(net "RMII_BMC_OCP_TXD1_R")
		)
		(pad "A6" smd circle
			(at -4.400042 -8.400034 90)
			(size 0.3556 0.3556)
			(layers "F.Cu" "F.Mask" "F.Paste")
			(net "USB2_PCH_BMC_P5_DN")
		)
		(pad "A7" smd circle
			(at -3.599942 -8.400034 90)
			(size 0.3556 0.3556)
			(layers "F.Cu" "F.Mask" "F.Paste")
			(net "USB_PCH_BMC_P4_DP")
		)
		(pad "A8" smd circle
			(at -2.800096 -8.400034 90)
			(size 0.3556 0.3556)
			(layers "F.Cu" "F.Mask" "F.Paste")
			(net "USB_PCH_BMC_P4_DN")
		)
		(pad "A9" smd circle
			(at -1.999996 -8.400034 90)
			(size 0.3556 0.3556)
			(layers "F.Cu" "F.Mask" "F.Paste")
			(net "SMB_HOST_STBY_LVC3_SCL_R")
		)
		(pad "A10" smd circle
			(at -1.199896 -8.400034 90)
			(size 0.3556 0.3556)
			(layers "F.Cu" "F.Mask" "F.Paste")
			(net "SMB_OCP_LAN_STBY_LVC3_SDA_R")
		)
		(pad "A11" smd circle
			(at -0.40005 -8.400034 90)
			(size 0.3556 0.3556)
			(layers "F.Cu" "F.Mask" "F.Paste")
			(net "SMB_OCP_LAN_STBY_LVC3_SCL_R")
		)
		(pad "A12" smd circle
			(at 0.40005 -8.400034 90)
			(size 0.3556 0.3556)
			(layers "F.Cu" "F.Mask" "F.Paste")
			(net "SMB_DEBUG_STBY_LVC3_SDA_R")
		)
		(pad "A13" smd circle
			(at 1.199896 -8.400034 90)
			(size 0.3556 0.3556)
			(layers "F.Cu" "F.Mask" "F.Paste")
			(net "SMB_OCP_FRU_STBY_LVC3_SDA_R")
		)
		(pad "A14" smd circle
			(at 1.999996 -8.400034 90)
			(size 0.3556 0.3556)
			(layers "F.Cu" "F.Mask" "F.Paste")
			(net "SPI_BMC_DO")
		)
		(pad "A15" smd circle
			(at 2.800096 -8.400034 90)
			(size 0.3556 0.3556)
			(layers "F.Cu" "F.Mask" "F.Paste")
			(net "SPI_BMC_DI")
		)
		(pad "A16" smd circle
			(at 3.599942 -8.400034 90)
			(size 0.3556 0.3556)
			(layers "F.Cu" "F.Mask" "F.Paste")
			(net "LED_POSTCODE_6")
		)
		(pad "A17" smd circle
			(at 4.400042 -8.400034 90)
			(size 0.3556 0.3556)
			(layers "F.Cu" "F.Mask" "F.Paste")
			(net "LED_POSTCODE_4")
		)
		(pad "A18" smd circle
			(at 5.199888 -8.400034 90)
			(size 0.3556 0.3556)
			(layers "F.Cu" "F.Mask" "F.Paste")
			(net "LED_POSTCODE_0")
		)
		(pad "A19" smd circle
			(at 5.999988 -8.400034 90)
			(size 0.3556 0.3556)
			(layers "F.Cu" "F.Mask" "F.Paste")
			(net "FM_CPU_ERR2_LVT3_N")
		)
		(pad "A20" smd circle
			(at 6.800088 -8.400034 90)
			(size 0.4064 0.4064)
			(layers "F.Cu" "F.Mask" "F.Paste")
			(net "FM_CPU0_PROCHOT_LVT3_BMC_N")
		)
		(pad "A21" smd circle
			(at 7.599934 -8.400034 90)
			(size 0.4064 0.4064)
			(layers "F.Cu" "F.Mask" "F.Paste")
			(net "IRQ_PVDDQ_KLM_VRHOT_LVT3_N")
		)
		(pad "A22" smd circle
			(at 8.400034 -8.400034 90)
			(size 0.4064 0.4064)
			(layers "F.Cu" "F.Mask" "F.Paste")
			(net "GND")
		)
		(pad "AA1" smd circle
			(at -8.400034 7.599934 90)
			(size 0.4064 0.4064)
			(layers "F.Cu" "F.Mask" "F.Paste")
			(net "IRQ_BOARD_BMC_ALERT_N")
		)
		(pad "AA2" smd circle
			(at -7.599934 7.599934 90)
			(size 0.4064 0.4064)
			(layers "F.Cu" "F.Mask" "F.Paste")
			(net "FM_CPU0_THERMTRIP_LATCH_LVT3_N")
		)
		(pad "AA3" smd circle
			(at -6.800088 7.599934 90)
			(size 0.4064 0.4064)
			(layers "F.Cu" "F.Mask" "F.Paste")
			(net "FM_BIOS_SPI_BMC_CTRL")
		)
		(pad "AA4" smd circle
			(at -5.999988 7.599934 90)
			(size 0.3556 0.3556)
			(layers "F.Cu" "F.Mask" "F.Paste")
			(net "FM_XRC_PRESENT_N")
		)
		(pad "AA5" smd circle
			(at -5.199888 7.599934 90)
			(size 0.3556 0.3556)
			(layers "F.Cu" "F.Mask" "F.Paste")
			(net "FM_BOARD_SKU_ID2")
		)
		(pad "AA6" smd circle
			(at -4.400042 7.599934 90)
			(size 0.3556 0.3556)
			(layers "F.Cu" "F.Mask" "F.Paste")
			(net "BMC_M_DQ12")
		)
		(pad "AA7" smd circle
			(at -3.599942 7.599934 90)
			(size 0.3556 0.3556)
			(layers "F.Cu" "F.Mask" "F.Paste")
			(net "GND")
		)
		(pad "AA8" smd circle
			(at -2.800096 7.599934 90)
			(size 0.3556 0.3556)
			(layers "F.Cu" "F.Mask" "F.Paste")
			(net "BMC_M_DQ8")
		)
		(pad "AA9" smd circle
			(at -1.999996 7.599934 90)
			(size 0.3556 0.3556)
			(layers "F.Cu" "F.Mask" "F.Paste")
			(net "GND")
		)
		(pad "AA10" smd circle
			(at -1.199896 7.599934 90)
			(size 0.3556 0.3556)
			(layers "F.Cu" "F.Mask" "F.Paste")
			(net "BMC_M_DQ3")
		)
		(pad "AA11" smd circle
			(at -0.40005 7.599934 90)
			(size 0.3556 0.3556)
			(layers "F.Cu" "F.Mask" "F.Paste")
			(net "GND")
		)
		(pad "AA12" smd circle
			(at 0.40005 7.599934 90)
			(size 0.3556 0.3556)
			(layers "F.Cu" "F.Mask" "F.Paste")
			(net "BMC_M_CS_N")
		)
		(pad "AA13" smd circle
			(at 1.199896 7.599934 90)
			(size 0.3556 0.3556)
			(layers "F.Cu" "F.Mask" "F.Paste")
			(net "GND")
		)
		(pad "AA14" smd circle
			(at 1.999996 7.599934 90)
			(size 0.3556 0.3556)
			(layers "F.Cu" "F.Mask" "F.Paste")
			(net "BMC_M_A11")
		)
		(pad "AA15" smd circle
			(at 2.800096 7.599934 90)
			(size 0.3556 0.3556)
			(layers "F.Cu" "F.Mask" "F.Paste")
			(net "GND")
		)
		(pad "AA16" smd circle
			(at 3.599942 7.599934 90)
			(size 0.3556 0.3556)
			(layers "F.Cu" "F.Mask" "F.Paste")
			(net "BMC_M_A7")
		)
		(pad "AA17" smd circle
			(at 4.400042 7.599934 90)
			(size 0.3556 0.3556)
			(layers "F.Cu" "F.Mask" "F.Paste")
			(net "PVCCIO_CPU0_R")
		)
		(pad "AA18" smd circle
			(at 5.199888 7.599934 90)
			(size 0.3556 0.3556)
			(layers "F.Cu" "F.Mask" "F.Paste")
			(net "SPI_BMC_BT_CLK_R")
		)
		(pad "AA19" smd circle
			(at 5.999988 7.599934 90)
			(size 0.3556 0.3556)
			(layers "F.Cu" "F.Mask" "F.Paste")
			(net "SPI_BMC_BT_CS_R_N")
		)
		(pad "AA20" smd circle
			(at 6.800088 7.599934 90)
			(size 0.4064 0.4064)
			(layers "F.Cu" "F.Mask" "F.Paste")
			(net "GPIOS7")
		)
		(pad "AA21" smd circle
			(at 7.599934 7.599934 90)
			(size 0.4064 0.4064)
			(layers "F.Cu" "F.Mask" "F.Paste")
			(net "IRQ_BMC_PCH_SCI_LPC_N")
		)
		(pad "AA22" smd circle
			(at 8.400034 7.599934 90)
			(size 0.4064 0.4064)
			(layers "F.Cu" "F.Mask" "F.Paste")
			(net "FM_TPM_PRES_N")
		)
		(pad "AB1" smd circle
			(at -8.400034 8.400034 90)
			(size 0.4064 0.4064)
			(layers "F.Cu" "F.Mask" "F.Paste")
			(net "GND")
		)
		(pad "AB2" smd circle
			(at -7.599934 8.400034 90)
			(size 0.4064 0.4064)
			(layers "F.Cu" "F.Mask" "F.Paste")
			(net "FM_CPU1_RC_ERROR_N")
		)
		(pad "AB3" smd circle
			(at -6.800088 8.400034 90)
			(size 0.4064 0.4064)
			(layers "F.Cu" "F.Mask" "F.Paste")
			(net "PUMP_TACH0")
		)
		(pad "AB4" smd circle
			(at -5.999988 8.400034 90)
			(size 0.3556 0.3556)
			(layers "F.Cu" "F.Mask" "F.Paste")
			(net "FAN_TACH3")
		)
		(pad "AB5" smd circle
			(at -5.199888 8.400034 90)
			(size 0.3556 0.3556)
			(layers "F.Cu" "F.Mask" "F.Paste")
			(net "FM_BOARD_SKU_ID3")
		)
		(pad "AB6" smd circle
			(at -4.400042 8.400034 90)
			(size 0.3556 0.3556)
			(layers "F.Cu" "F.Mask" "F.Paste")
			(net "BMC_M_DQS1_DN")
		)
		(pad "AB7" smd circle
			(at -3.599942 8.400034 90)
			(size 0.3556 0.3556)
			(layers "F.Cu" "F.Mask" "F.Paste")
			(net "BMC_M_DQS1_DP")
		)
		(pad "AB8" smd circle
			(at -2.800096 8.400034 90)
			(size 0.3556 0.3556)
			(layers "F.Cu" "F.Mask" "F.Paste")
			(net "BMC_M_DM1")
		)
		(pad "AB9" smd circle
			(at -1.999996 8.400034 90)
			(size 0.3556 0.3556)
			(layers "F.Cu" "F.Mask" "F.Paste")
			(net "BMC_M_DQS0_DP")
		)
		(pad "AB10" smd circle
			(at -1.199896 8.400034 90)
			(size 0.3556 0.3556)
			(layers "F.Cu" "F.Mask" "F.Paste")
			(net "BMC_M_DQS0_DN")
		)
		(pad "AB11" smd circle
			(at -0.40005 8.400034 90)
			(size 0.3556 0.3556)
			(layers "F.Cu" "F.Mask" "F.Paste")
			(net "BMC_M_CLK_DP")
		)
		(pad "AB12" smd circle
			(at 0.40005 8.400034 90)
			(size 0.3556 0.3556)
			(layers "F.Cu" "F.Mask" "F.Paste")
			(net "BMC_M_CLK_DN")
		)
		(pad "AB13" smd circle
			(at 1.199896 8.400034 90)
			(size 0.3556 0.3556)
			(layers "F.Cu" "F.Mask" "F.Paste")
			(net "BMC_M_CAS_N")
		)
		(pad "AB14" smd circle
			(at 1.999996 8.400034 90)
			(size 0.3556 0.3556)
			(layers "F.Cu" "F.Mask" "F.Paste")
			(net "BMC_M_A1")
		)
		(pad "AB15" smd circle
			(at 2.800096 8.400034 90)
			(size 0.3556 0.3556)
			(layers "F.Cu" "F.Mask" "F.Paste")
			(net "BMC_M_A13")
		)
		(pad "AB16" smd circle
			(at 3.599942 8.400034 90)
			(size 0.3556 0.3556)
			(layers "F.Cu" "F.Mask" "F.Paste")
			(net "BMC_M_A6")
		)
		(pad "AB17" smd circle
			(at 4.400042 8.400034 90)
			(size 0.3556 0.3556)
			(layers "F.Cu" "F.Mask" "F.Paste")
			(net "BMC_M_RST_N")
		)
		(pad "AB18" smd circle
			(at 5.199888 8.400034 90)
			(size 0.3556 0.3556)
			(layers "F.Cu" "F.Mask" "F.Paste")
			(net "PECI_BMC_R")
		)
		(pad "AB19" smd circle
			(at 5.999988 8.400034 90)
			(size 0.3556 0.3556)
			(layers "F.Cu" "F.Mask" "F.Paste")
			(net "SPI_BMC_BT_CS0_N")
		)
		(pad "AB20" smd circle
			(at 6.800088 8.400034 90)
			(size 0.4064 0.4064)
			(layers "F.Cu" "F.Mask" "F.Paste")
			(net "FM_BMC_NMI_N_R")
		)
		(pad "AB21" smd circle
			(at 7.599934 8.400034 90)
			(size 0.4064 0.4064)
			(layers "F.Cu" "F.Mask" "F.Paste")
			(net "IRQ_PVDDQ_DEF_VRHOT_LVT3_N")
		)
		(pad "AB22" smd circle
			(at 8.400034 8.400034 90)
			(size 0.4064 0.4064)
			(layers "F.Cu" "F.Mask" "F.Paste")
			(net "GND")
		)
		(pad "B1" smd circle
			(at -8.400034 -7.599934 90)
			(size 0.4064 0.4064)
			(layers "F.Cu" "F.Mask" "F.Paste")
			(net "RMII_BMC_SPRNGVLLE_TXEN_R")
		)
		(pad "B2" smd circle
			(at -7.599934 -7.599934 90)
			(size 0.4064 0.4064)
			(layers "F.Cu" "F.Mask" "F.Paste")
			(net "Net_6480")
		)
		(pad "B3" smd circle
			(at -6.800088 -7.599934 90)
			(size 0.4064 0.4064)
			(layers "F.Cu" "F.Mask" "F.Paste")
			(net "RMII_BMC_PCH_SPRNGVLLE_TXD1_R")
		)
		(pad "B4" smd circle
			(at -5.999988 -7.599934 90)
			(size 0.3556 0.3556)
			(layers "F.Cu" "F.Mask" "F.Paste")
			(net "CLK_50M_CKMNG_BMC_1")
		)
		(pad "B5" smd circle
			(at -5.199888 -7.599934 90)
			(size 0.3556 0.3556)
			(layers "F.Cu" "F.Mask" "F.Paste")
			(net "Net_543")
		)
		(pad "B6" smd circle
			(at -4.400042 -7.599934 90)
			(size 0.3556 0.3556)
			(layers "F.Cu" "F.Mask" "F.Paste")
			(net "USB2_PCH_BMC_P5_DP")
		)
		(pad "B7" smd circle
			(at -3.599942 -7.599934 90)
			(size 0.3556 0.3556)
			(layers "F.Cu" "F.Mask" "F.Paste")
			(net "A_USB2BVRES")
		)
		(pad "B8" smd circle
			(at -2.800096 -7.599934 90)
			(size 0.3556 0.3556)
			(layers "F.Cu" "F.Mask" "F.Paste")
			(net "A_USB2AVRES")
		)
		(pad "B9" smd circle
			(at -1.999996 -7.599934 90)
			(size 0.3556 0.3556)
			(layers "F.Cu" "F.Mask" "F.Paste")
			(net "SMB_HOST_STBY_LVC3_SDA_R")
		)
		(pad "B10" smd circle
			(at -1.199896 -7.599934 90)
			(size 0.3556 0.3556)
			(layers "F.Cu" "F.Mask" "F.Paste")
			(net "FM_POST_CARD_PRES_BMC_N")
		)
		(pad "B11" smd circle
			(at -0.40005 -7.599934 90)
			(size 0.3556 0.3556)
			(layers "F.Cu" "F.Mask" "F.Paste")
			(net "SMB_PEHPCPU0_STBY_LVC3_R2_SDA")
		)
		(pad "B12" smd circle
			(at 0.40005 -7.599934 90)
			(size 0.3556 0.3556)
			(layers "F.Cu" "F.Mask" "F.Paste")
			(net "SMB_PEHPCPU0_STBY_LVC3_SCL")
		)
		(pad "B13" smd circle
			(at 1.199896 -7.599934 90)
			(size 0.3556 0.3556)
			(layers "F.Cu" "F.Mask" "F.Paste")
			(net "FM_BMC_CPLD_MP_RST_N")
		)
		(pad "B14" smd circle
			(at 1.999996 -7.599934 90)
			(size 0.3556 0.3556)
			(layers "F.Cu" "F.Mask" "F.Paste")
			(net "JTAG_RISER_N")
		)
		(pad "B15" smd circle
			(at 2.800096 -7.599934 90)
			(size 0.3556 0.3556)
			(layers "F.Cu" "F.Mask" "F.Paste")
			(net "SPI_BMC_CS0_N")
		)
		(pad "B16" smd circle
			(at 3.599942 -7.599934 90)
			(size 0.3556 0.3556)
			(layers "F.Cu" "F.Mask" "F.Paste")
			(net "FM_FORCE_ADR_N")
		)
		(pad "B17" smd circle
			(at 4.400042 -7.599934 90)
			(size 0.3556 0.3556)
			(layers "F.Cu" "F.Mask" "F.Paste")
			(net "LED_POSTCODE_5")
		)
		(pad "B18" smd circle
			(at 5.199888 -7.599934 90)
			(size 0.3556 0.3556)
			(layers "F.Cu" "F.Mask" "F.Paste")
			(net "LED_POSTCODE_1")
		)
		(pad "B19" smd circle
			(at 5.999988 -7.599934 90)
			(size 0.3556 0.3556)
			(layers "F.Cu" "F.Mask" "F.Paste")
			(net "FM_CPU1_PROCHOT_LVT3_BMC_N")
		)
		(pad "B20" smd circle
			(at 6.800088 -7.599934 90)
			(size 0.4064 0.4064)
			(layers "F.Cu" "F.Mask" "F.Paste")
			(net "RST_SYSTEM_BTN_R_N")
		)
		(pad "B21" smd circle
			(at 7.599934 -7.599934 90)
			(size 0.4064 0.4064)
			(layers "F.Cu" "F.Mask" "F.Paste")
			(net "IRQ_PVCCIN_CPU1_VRHOT_LVC3_N")
		)
		(pad "B22" smd circle
			(at 8.400034 -7.599934 90)
			(size 0.4064 0.4064)
			(layers "F.Cu" "F.Mask" "F.Paste")
			(net "IRQ_PVCCIN_CPU0_VRHOT_LVC3_N")
		)
		(pad "C1" smd circle
			(at -8.400034 -6.800088 90)
			(size 0.4064 0.4064)
			(layers "F.Cu" "F.Mask" "F.Paste")
			(net "FM_FAST_PROCHOT_EN_N")
		)
		(pad "C2" smd circle
			(at -7.599934 -6.800088 90)
			(size 0.4064 0.4064)
			(layers "F.Cu" "F.Mask" "F.Paste")
			(net "CLK_50M_CKMNG_BMC_2")
		)
		(pad "C3" smd circle
			(at -6.800088 -6.800088 90)
			(size 0.4064 0.4064)
			(layers "F.Cu" "F.Mask" "F.Paste")
			(net "RMII_SPRNGVLLE_BMC_PCH_RXD0")
		)
		(pad "C4" smd circle
			(at -5.999988 -6.800088 90)
			(size 0.3556 0.3556)
			(layers "F.Cu" "F.Mask" "F.Paste")
			(net "RMII_BMC_OCP_RXER")
		)
		(pad "C5" smd circle
			(at -5.199888 -6.800088 90)
			(size 0.3556 0.3556)
			(layers "F.Cu" "F.Mask" "F.Paste")
			(net "RMII_BMC_OCP_CRSDV")
		)
		(pad "C6" smd circle
			(at -4.400042 -6.800088 90)
			(size 0.3556 0.3556)
			(layers "F.Cu" "F.Mask" "F.Paste")
			(net "GND")
		)
		(pad "C7" smd circle
			(at -3.599942 -6.800088 90)
			(size 0.3556 0.3556)
			(layers "F.Cu" "F.Mask" "F.Paste")
			(net "P3V3_USB2A_ALG")
		)
		(pad "C8" smd circle
			(at -2.800096 -6.800088 90)
			(size 0.3556 0.3556)
			(layers "F.Cu" "F.Mask" "F.Paste")
			(net "JTAG_BMC_TMS")
		)
		(pad "C9" smd circle
			(at -1.999996 -6.800088 90)
			(size 0.3556 0.3556)
			(layers "F.Cu" "F.Mask" "F.Paste")
			(net "PU_JTAG_BMC_RTCK")
		)
		(pad "C10" smd circle
			(at -1.199896 -6.800088 90)
			(size 0.3556 0.3556)
			(layers "F.Cu" "F.Mask" "F.Paste")
			(net "JTAG_BMC_TCK")
		)
		(pad "C11" smd circle
			(at -0.40005 -6.800088 90)
			(size 0.3556 0.3556)
			(layers "F.Cu" "F.Mask" "F.Paste")
			(net "SMB_PEHPCPU0_STBY_LVC3_R2_SCL")
		)
		(pad "C12" smd circle
			(at 0.40005 -6.800088 90)
			(size 0.3556 0.3556)
			(layers "F.Cu" "F.Mask" "F.Paste")
			(net "SMB_DEBUG_STBY_LVC3_SCL_R")
		)
		(pad "C13" smd circle
			(at 1.199896 -6.800088 90)
			(size 0.3556 0.3556)
			(layers "F.Cu" "F.Mask" "F.Paste")
			(net "FM_BB_BMC_MP_GPIO")
		)
		(pad "C14" smd circle
			(at 1.999996 -6.800088 90)
			(size 0.3556 0.3556)
			(layers "F.Cu" "F.Mask" "F.Paste")
			(net "SMB_OCP_FRU_STBY_LVC3_SCL_R")
		)
		(pad "C15" smd circle
			(at 2.800096 -6.800088 90)
			(size 0.3556 0.3556)
			(layers "F.Cu" "F.Mask" "F.Paste")
			(net "SPI_BMC_CLK")
		)
		(pad "C16" smd circle
			(at 3.599942 -6.800088 90)
			(size 0.3556 0.3556)
			(layers "F.Cu" "F.Mask" "F.Paste")
			(net "FM_UV_ADR_TRIGGER_EN")
		)
		(pad "C17" smd circle
			(at 4.400042 -6.800088 90)
			(size 0.3556 0.3556)
			(layers "F.Cu" "F.Mask" "F.Paste")
			(net "LED_POSTCODE_3")
		)
		(pad "C18" smd circle
			(at 5.199888 -6.800088 90)
			(size 0.3556 0.3556)
			(layers "F.Cu" "F.Mask" "F.Paste")
			(net "FM_CPU0_FIVR_FAULT_LVT3_R_N")
		)
		(pad "C19" smd circle
			(at 5.999988 -6.800088 90)
			(size 0.3556 0.3556)
			(layers "F.Cu" "F.Mask" "F.Paste")
			(net "FM_PCH_BMC_THERMTRIP_N")
		)
		(pad "C20" smd circle
			(at 6.800088 -6.800088 90)
			(size 0.4064 0.4064)
			(layers "F.Cu" "F.Mask" "F.Paste")
			(net "RST_BMC_SYSRST_BTN_OUT_N")
		)
		(pad "C21" smd circle
			(at 7.599934 -6.800088 90)
			(size 0.4064 0.4064)
			(layers "F.Cu" "F.Mask" "F.Paste")
			(net "FM_CPU_ERR1_LVT3_BMC_N")
		)
		(pad "C22" smd circle
			(at 8.400034 -6.800088 90)
			(size 0.4064 0.4064)
			(layers "F.Cu" "F.Mask" "F.Paste")
			(net "CLK_24M_BMC_LPC")
		)
		(pad "D1" smd circle
			(at -8.400034 -5.999988 90)
			(size 0.3556 0.3556)
			(layers "F.Cu" "F.Mask" "F.Paste")
			(net "RMII_SPRNGVLLE_BMC_PCH_RXD1")
		)
		(pad "D2" smd circle
			(at -7.599934 -5.999988 90)
			(size 0.3556 0.3556)
			(layers "F.Cu" "F.Mask" "F.Paste")
			(net "RMII_BMC_PCH_SPRNGVLLE_CRSDV")
		)
		(pad "D3" smd circle
			(at -6.800088 -5.999988 90)
			(size 0.3556 0.3556)
			(layers "F.Cu" "F.Mask" "F.Paste")
			(net "Net_308")
		)
		(pad "D4" smd circle
			(at -5.999988 -5.999988 90)
			(size 0.3556 0.3556)
			(layers "F.Cu" "F.Mask" "F.Paste")
			(net "TP_RGMII2TXD3_GPIOU3")
		)
		(pad "D5" smd circle
			(at -5.199888 -5.999988 90)
			(size 0.3556 0.3556)
			(layers "F.Cu" "F.Mask" "F.Paste")
			(net "TP_RGMII2TXD2_GPIOU2")
		)
		(pad "D6" smd circle
			(at -4.400042 -5.999988 90)
			(size 0.3556 0.3556)
			(layers "F.Cu" "F.Mask" "F.Paste")
			(net "RMII_BMC_OCP_RXD1")
		)
		(pad "D7" smd circle
			(at -3.599942 -5.999988 90)
			(size 0.3556 0.3556)
			(layers "F.Cu" "F.Mask" "F.Paste")
			(net "TP_RGMII1TXD3_GPIOT5")
		)
		(pad "D8" smd circle
			(at -2.800096 -5.999988 90)
			(size 0.3556 0.3556)
			(layers "F.Cu" "F.Mask" "F.Paste")
			(net "FM_SLT_CFG0")
		)
		(pad "D9" smd circle
			(at -1.999996 -5.999988 90)
			(size 0.3556 0.3556)
			(layers "F.Cu" "F.Mask" "F.Paste")
			(net "SMB_PEHPCPU0_STBY_LVC3_SDA")
		)
		(pad "D10" smd circle
			(at -1.199896 -5.999988 90)
			(size 0.3556 0.3556)
			(layers "F.Cu" "F.Mask" "F.Paste")
			(net "SMB_PEHPCPU1_STBY_LVC3_SCL")
		)
		(pad "D11" smd circle
			(at -0.40005 -5.999988 90)
			(size 0.3556 0.3556)
			(layers "F.Cu" "F.Mask" "F.Paste")
			(net "JTAG_BMC_TDO")
		)
		(pad "D12" smd circle
			(at 0.40005 -5.999988 90)
			(size 0.3556 0.3556)
			(layers "F.Cu" "F.Mask" "F.Paste")
			(net "JTAG_BMC_TDI")
		)
		(pad "D13" smd circle
			(at 1.199896 -5.999988 90)
			(size 0.3556 0.3556)
			(layers "F.Cu" "F.Mask" "F.Paste")
			(net "TP_BMC_GPIOA2")
		)
		(pad "D14" smd circle
			(at 1.999996 -5.999988 90)
			(size 0.3556 0.3556)
			(layers "F.Cu" "F.Mask" "F.Paste")
			(net "FM_CPLD_BMC_PWRDN_N")
		)
		(pad "D15" smd circle
			(at 2.800096 -5.999988 90)
			(size 0.3556 0.3556)
			(layers "F.Cu" "F.Mask" "F.Paste")
			(net "IRQ_MEZZ_LAN_ALERT_N")
		)
		(pad "D16" smd circle
			(at 3.599942 -5.999988 90)
			(size 0.3556 0.3556)
			(layers "F.Cu" "F.Mask" "F.Paste")
			(net "IRQ_OOB_MGMT_RISER_ALERT_N")
		)
		(pad "D17" smd circle
			(at 4.400042 -5.999988 90)
			(size 0.3556 0.3556)
			(layers "F.Cu" "F.Mask" "F.Paste")
			(net "LED_POSTCODE_2")
		)
		(pad "D18" smd circle
			(at 5.199888 -5.999988 90)
			(size 0.3556 0.3556)
			(layers "F.Cu" "F.Mask" "F.Paste")
			(net "LED_POSTCODE_7")
		)
		(pad "D19" smd circle
			(at 5.999988 -5.999988 90)
			(size 0.3556 0.3556)
			(layers "F.Cu" "F.Mask" "F.Paste")
			(net "IRQ_BMC_PCH_NMI_STBY_N")
		)
		(pad "D20" smd circle
			(at 6.800088 -5.999988 90)
			(size 0.3556 0.3556)
			(layers "F.Cu" "F.Mask" "F.Paste")
			(net "FM_BOARD_REV_ID1")
		)
		(pad "D21" smd circle
			(at 7.599934 -5.999988 90)
			(size 0.3556 0.3556)
			(layers "F.Cu" "F.Mask" "F.Paste")
			(net "IRQ_DIMM_SAVE_LVT3_N")
		)
		(pad "D22" smd circle
			(at 8.400034 -5.999988 90)
			(size 0.3556 0.3556)
			(layers "F.Cu" "F.Mask" "F.Paste")
			(net "LPC_LAD2_IO2_R")
		)
		(pad "E1" smd circle
			(at -8.400034 -5.199888 90)
			(size 0.3556 0.3556)
			(layers "F.Cu" "F.Mask" "F.Paste")
			(net "A_P1V05_STBY_PCH_SENSOR")
		)
		(pad "E2" smd circle
			(at -7.599934 -5.199888 90)
			(size 0.3556 0.3556)
			(layers "F.Cu" "F.Mask" "F.Paste")
			(net "A_P12V_STBY_SCALED")
		)
		(pad "E3" smd circle
			(at -6.800088 -5.199888 90)
			(size 0.3556 0.3556)
			(layers "F.Cu" "F.Mask" "F.Paste")
			(net "A_P3V3_STBY_SCALED")
		)
		(pad "E4" smd circle
			(at -5.999988 -5.199888 90)
			(size 0.3556 0.3556)
			(layers "F.Cu" "F.Mask" "F.Paste")
			(net "VCCBAT_TW12")
		)
		(pad "E5" smd circle
			(at -5.199888 -5.199888 90)
			(size 0.3556 0.3556)
			(layers "F.Cu" "F.Mask" "F.Paste")
			(net "GND")
		)
		(pad "E6" smd circle
			(at -4.400042 -5.199888 90)
			(size 0.3556 0.3556)
			(layers "F.Cu" "F.Mask" "F.Paste")
			(net "RMII_BMC_PCH_SPRNGVLLE_RXER")
		)
		(pad "E7" smd circle
			(at -3.599942 -5.199888 90)
			(size 0.3556 0.3556)
			(layers "F.Cu" "F.Mask" "F.Paste")
			(net "TP_RGMII1TXD2_GPIOT4")
		)
		(pad "E8" smd circle
			(at -2.800096 -5.199888 90)
			(size 0.3556 0.3556)
			(layers "F.Cu" "F.Mask" "F.Paste")
			(net "GND")
		)
		(pad "E9" smd circle
			(at -1.999996 -5.199888 90)
			(size 0.3556 0.3556)
			(layers "F.Cu" "F.Mask" "F.Paste")
			(net "RMII_BMC_OCP_TXEN_R")
		)
		(pad "E10" smd circle
			(at -1.199896 -5.199888 90)
			(size 0.3556 0.3556)
			(layers "F.Cu" "F.Mask" "F.Paste")
			(net "FM_SLT_CFG1")
		)
		(pad "E11" smd circle
			(at -0.40005 -5.199888 90)
			(size 0.3556 0.3556)
			(layers "F.Cu" "F.Mask" "F.Paste")
			(net "JTAG_BMC_TRST_N")
		)
		(pad "E12" smd circle
			(at 0.40005 -5.199888 90)
			(size 0.3556 0.3556)
			(layers "F.Cu" "F.Mask" "F.Paste")
			(net "SMB_PEHPCPU1_STBY_LVC3_SDA")
		)
		(pad "E13" smd circle
			(at 1.199896 -5.199888 90)
			(size 0.3556 0.3556)
			(layers "F.Cu" "F.Mask" "F.Paste")
			(net "FM_BMC_SYS_THROTTLE_R_N")
		)
		(pad "E14" smd circle
			(at 1.999996 -5.199888 90)
			(size 0.3556 0.3556)
			(layers "F.Cu" "F.Mask" "F.Paste")
			(net "FM_BIOS_SMI_ACTIVE_N")
		)
		(pad "E15" smd circle
			(at 2.800096 -5.199888 90)
			(size 0.3556 0.3556)
			(layers "F.Cu" "F.Mask" "F.Paste")
			(net "FM_CPU1_FIVR_FAULT_LVT3_R_N")
		)
		(pad "E16" smd circle
			(at 3.599942 -5.199888 90)
			(size 0.3556 0.3556)
			(layers "F.Cu" "F.Mask" "F.Paste")
			(net "FM_CPU0_SKTOCC_LVT3_N")
		)
		(pad "E17" smd circle
			(at 4.400042 -5.199888 90)
			(size 0.3556 0.3556)
			(layers "F.Cu" "F.Mask" "F.Paste")
			(net "IRQ_PCH_NIC_ALERT_N")
		)
		(pad "E18" smd circle
			(at 5.199888 -5.199888 90)
			(size 0.3556 0.3556)
			(layers "F.Cu" "F.Mask" "F.Paste")
			(net "FP_NMI_BTN_N")
		)
		(pad "E19" smd circle
			(at 5.999988 -5.199888 90)
			(size 0.3556 0.3556)
			(layers "F.Cu" "F.Mask" "F.Paste")
			(net "FM_CPU_CATERR_LVT3_N")
		)
		(pad "E20" smd circle
			(at 6.800088 -5.199888 90)
			(size 0.3556 0.3556)
			(layers "F.Cu" "F.Mask" "F.Paste")
			(net "FM_BOARD_REV_ID2")
		)
		(pad "E21" smd circle
			(at 7.599934 -5.199888 90)
			(size 0.3556 0.3556)
			(layers "F.Cu" "F.Mask" "F.Paste")
			(net "FM_BOARD_REV_ID0")
		)
		(pad "E22" smd circle
			(at 8.400034 -5.199888 90)
			(size 0.3556 0.3556)
			(layers "F.Cu" "F.Mask" "F.Paste")
			(net "LPC_LAD3_IO3_R")
		)
		(pad "F1" smd circle
			(at -8.400034 -4.400042 90)
			(size 0.3556 0.3556)
			(layers "F.Cu" "F.Mask" "F.Paste")
			(net "FM_GLOBAL_RST_WARN_N_R")
		)
		(pad "F2" smd circle
			(at -7.599934 -4.400042 90)
			(size 0.3556 0.3556)
			(layers "F.Cu" "F.Mask" "F.Paste")
			(net "GND")
		)
		(pad "F3" smd circle
			(at -6.800088 -4.400042 90)
			(size 0.3556 0.3556)
			(layers "F.Cu" "F.Mask" "F.Paste")
			(net "A_PVNN_STBY_PCH_SENSOR")
		)
		(pad "F4" smd circle
			(at -5.999988 -4.400042 90)
			(size 0.3556 0.3556)
			(layers "F.Cu" "F.Mask" "F.Paste")
			(net "A_P3V3_SCALED")
		)
		(pad "F5" smd circle
			(at -5.199888 -4.400042 90)
			(size 0.3556 0.3556)
			(layers "F.Cu" "F.Mask" "F.Paste")
			(net "A_P5V_SCALED")
		)
		(pad "F6" smd circle
			(at -4.400042 -4.400042 90)
			(size 0.3556 0.3556)
			(layers "F.Cu" "F.Mask" "F.Paste")
			(net "P1V15_AUX_BMC")
		)
		(pad "F7" smd circle
			(at -3.599942 -4.400042 90)
			(size 0.3556 0.3556)
			(layers "F.Cu" "F.Mask" "F.Paste")
			(net "P3V3_STBY")
		)
		(pad "F8" smd circle
			(at -2.800096 -4.400042 90)
			(size 0.3556 0.3556)
			(layers "F.Cu" "F.Mask" "F.Paste")
			(net "P3V3_STBY")
		)
		(pad "F9" smd circle
			(at -1.999996 -4.400042 90)
			(size 0.3556 0.3556)
			(layers "F.Cu" "F.Mask" "F.Paste")
			(net "RMII_BMC_OCP_TXD0_R")
		)
		(pad "F10" smd circle
			(at -1.199896 -4.400042 90)
			(size 0.3556 0.3556)
			(layers "F.Cu" "F.Mask" "F.Paste")
			(net "P3V3_STBY")
		)
		(pad "F11" smd circle
			(at -0.40005 -4.400042 90)
			(size 0.3556 0.3556)
			(layers "F.Cu" "F.Mask" "F.Paste")
			(net "P3V3_STBY")
		)
		(pad "F12" smd circle
			(at 0.40005 -4.400042 90)
			(size 0.3556 0.3556)
			(layers "F.Cu" "F.Mask" "F.Paste")
			(net "VCC_D_3V3")
		)
		(pad "F13" smd circle
			(at 1.199896 -4.400042 90)
			(size 0.3556 0.3556)
			(layers "F.Cu" "F.Mask" "F.Paste")
			(net "VCC_D_3V3")
		)
		(pad "F14" smd circle
			(at 1.999996 -4.400042 90)
			(size 0.3556 0.3556)
			(layers "F.Cu" "F.Mask" "F.Paste")
			(net "VCC_D_3V3")
		)
		(pad "F15" smd circle
			(at 2.800096 -4.400042 90)
			(size 0.3556 0.3556)
			(layers "F.Cu" "F.Mask" "F.Paste")
			(net "VCC_D_3V3")
		)
		(pad "F16" smd circle
			(at 3.599942 -4.400042 90)
			(size 0.3556 0.3556)
			(layers "F.Cu" "F.Mask" "F.Paste")
			(net "GND")
		)
		(pad "F17" smd circle
			(at 4.400042 -4.400042 90)
			(size 0.3556 0.3556)
			(layers "F.Cu" "F.Mask" "F.Paste")
			(net "FM_BMC_PWRBTN_OUT_N")
		)
		(pad "F18" smd circle
			(at 5.199888 -4.400042 90)
			(size 0.3556 0.3556)
			(layers "F.Cu" "F.Mask" "F.Paste")
			(net "FM_PWR_BTN_R1_N")
		)
		(pad "F19" smd circle
			(at 5.999988 -4.400042 90)
			(size 0.3556 0.3556)
			(layers "F.Cu" "F.Mask" "F.Paste")
			(net "FM_BIOS_MRC_DEBUG_MSG_DIS_N")
		)
		(pad "F20" smd circle
			(at 6.800088 -4.400042 90)
			(size 0.3556 0.3556)
			(layers "F.Cu" "F.Mask" "F.Paste")
			(net "FM_SOL_UART_CH_SEL")
		)
		(pad "F21" smd circle
			(at 7.599934 -4.400042 90)
			(size 0.3556 0.3556)
			(layers "F.Cu" "F.Mask" "F.Paste")
			(net "LPC_LFRAME_N_CS0_R_N")
		)
		(pad "F22" smd circle
			(at 8.400034 -4.400042 90)
			(size 0.3556 0.3556)
			(layers "F.Cu" "F.Mask" "F.Paste")
			(net "IRQ_LPC_SERIRQ_R")
		)
		(pad "G1" smd circle
			(at -8.400034 -3.599942 90)
			(size 0.3556 0.3556)
			(layers "F.Cu" "F.Mask" "F.Paste")
			(net "H_CPU0_MEMDEF_MEMHOT_LVT3_BMC_N")
		)
		(pad "G2" smd circle
			(at -7.599934 -3.599942 90)
			(size 0.3556 0.3556)
			(layers "F.Cu" "F.Mask" "F.Paste")
			(net "GND")
		)
		(pad "G3" smd circle
			(at -6.800088 -3.599942 90)
			(size 0.3556 0.3556)
			(layers "F.Cu" "F.Mask" "F.Paste")
			(net "GND")
		)
		(pad "G4" smd circle
			(at -5.999988 -3.599942 90)
			(size 0.3556 0.3556)
			(layers "F.Cu" "F.Mask" "F.Paste")
			(net "A_P3V_BAT_SCALED")
		)
		(pad "G5" smd circle
			(at -5.199888 -3.599942 90)
			(size 0.3556 0.3556)
			(layers "F.Cu" "F.Mask" "F.Paste")
			(net "A_P5V_STBY_SCALED")
		)
		(pad "G6" smd circle
			(at -4.400042 -3.599942 90)
			(size 0.3556 0.3556)
			(layers "F.Cu" "F.Mask" "F.Paste")
			(net "GND")
		)
		(pad "G7" smd circle
			(at -3.599942 -3.599942 90)
			(size 0.3556 0.3556)
			(layers "F.Cu" "F.Mask" "F.Paste")
			(net "P1V15_AUX_BMC")
		)
		(pad "G8" smd circle
			(at -2.800096 -3.599942 90)
			(size 0.3556 0.3556)
			(layers "F.Cu" "F.Mask" "F.Paste")
			(net "P1V15_AUX_BMC")
		)
		(pad "G9" smd circle
			(at -1.999996 -3.599942 90)
			(size 0.3556 0.3556)
			(layers "F.Cu" "F.Mask" "F.Paste")
			(net "P1V15_AUX_BMC")
		)
		(pad "G10" smd circle
			(at -1.199896 -3.599942 90)
			(size 0.3556 0.3556)
			(layers "F.Cu" "F.Mask" "F.Paste")
			(net "P1V15_AUX_BMC")
		)
		(pad "G11" smd circle
			(at -0.40005 -3.599942 90)
			(size 0.3556 0.3556)
			(layers "F.Cu" "F.Mask" "F.Paste")
			(net "P1V15_AUX_BMC")
		)
		(pad "G12" smd circle
			(at 0.40005 -3.599942 90)
			(size 0.3556 0.3556)
			(layers "F.Cu" "F.Mask" "F.Paste")
			(net "P1V15_AUX_BMC")
		)
		(pad "G13" smd circle
			(at 1.199896 -3.599942 90)
			(size 0.3556 0.3556)
			(layers "F.Cu" "F.Mask" "F.Paste")
			(net "P1V15_AUX_BMC")
		)
		(pad "G14" smd circle
			(at 1.999996 -3.599942 90)
			(size 0.3556 0.3556)
			(layers "F.Cu" "F.Mask" "F.Paste")
			(net "P1V15_AUX_BMC")
		)
		(pad "G15" smd circle
			(at 2.800096 -3.599942 90)
			(size 0.3556 0.3556)
			(layers "F.Cu" "F.Mask" "F.Paste")
			(net "P1V15_AUX_BMC")
		)
		(pad "G16" smd circle
			(at 3.599942 -3.599942 90)
			(size 0.3556 0.3556)
			(layers "F.Cu" "F.Mask" "F.Paste")
			(net "VCC_D_3V3")
		)
		(pad "G17" smd circle
			(at 4.400042 -3.599942 90)
			(size 0.3556 0.3556)
			(layers "F.Cu" "F.Mask" "F.Paste")
			(net "FM_BATTERY_SENSE_EN_N")
		)
		(pad "G18" smd circle
			(at 5.199888 -3.599942 90)
			(size 0.3556 0.3556)
			(layers "F.Cu" "F.Mask" "F.Paste")
			(net "FM_CPU_ERR0_LVT3_BMC_N")
		)
		(pad "G19" smd circle
			(at 5.999988 -3.599942 90)
			(size 0.3556 0.3556)
			(layers "F.Cu" "F.Mask" "F.Paste")
			(net "GND")
		)
		(pad "G20" smd circle
			(at 6.800088 -3.599942 90)
			(size 0.3556 0.3556)
			(layers "F.Cu" "F.Mask" "F.Paste")
			(net "LPC_LAD1_IO1_R")
		)
		(pad "G21" smd circle
			(at 7.599934 -3.599942 90)
			(size 0.3556 0.3556)
			(layers "F.Cu" "F.Mask" "F.Paste")
			(net "LPC_LAD0_IO0_R")
		)
		(pad "G22" smd circle
			(at 8.400034 -3.599942 90)
			(size 0.3556 0.3556)
			(layers "F.Cu" "F.Mask" "F.Paste")
			(net "RST_BMC_LVC3_N")
		)
		(pad "H1" smd circle
			(at -8.400034 -2.800096 90)
			(size 0.3556 0.3556)
			(layers "F.Cu" "F.Mask" "F.Paste")
			(net "P3V3_STBY_BMC_ADCVREFN")
		)
		(pad "H2" smd circle
			(at -7.599934 -2.800096 90)
			(size 0.3556 0.3556)
			(layers "F.Cu" "F.Mask" "F.Paste")
			(net "P3V3_STBY_BMC_ADCVREFP")
		)
		(pad "H3" smd circle
			(at -6.800088 -2.800096 90)
			(size 0.3556 0.3556)
			(layers "F.Cu" "F.Mask" "F.Paste")
			(net "H_CPU1_MEMGHJ_MEMHOT_LVT3_BMC_N")
		)
		(pad "H4" smd circle
			(at -5.999988 -2.800096 90)
			(size 0.3556 0.3556)
			(layers "F.Cu" "F.Mask" "F.Paste")
			(net "H_CPU1_MEMKLM_MEMHOT_LVT3_BMC_N")
		)
		(pad "H5" smd circle
			(at -5.199888 -2.800096 90)
			(size 0.3556 0.3556)
			(layers "F.Cu" "F.Mask" "F.Paste")
			(net "H_CPU0_MEMABC_MEMHOT_LVT3_BMC_N")
		)
		(pad "H6" smd circle
			(at -4.400042 -2.800096 90)
			(size 0.3556 0.3556)
			(layers "F.Cu" "F.Mask" "F.Paste")
			(net "GND")
		)
		(pad "H7" smd circle
			(at -3.599942 -2.800096 90)
			(size 0.3556 0.3556)
			(layers "F.Cu" "F.Mask" "F.Paste")
			(net "VCC_VA_3V3")
		)
		(pad "H16" smd circle
			(at 3.599942 -2.800096 90)
			(size 0.3556 0.3556)
			(layers "F.Cu" "F.Mask" "F.Paste")
			(net "P1V15_AUX_BMC")
		)
		(pad "H17" smd circle
			(at 4.400042 -2.800096 90)
			(size 0.3556 0.3556)
			(layers "F.Cu" "F.Mask" "F.Paste")
			(net "VCC_D_3V3")
		)
		(pad "H18" smd circle
			(at 5.199888 -2.800096 90)
			(size 0.3556 0.3556)
			(layers "F.Cu" "F.Mask" "F.Paste")
			(net "FM_OCP_MEZZC_PRES_LVT3_BMC")
		)
		(pad "H19" smd circle
			(at 5.999988 -2.800096 90)
			(size 0.3556 0.3556)
			(layers "F.Cu" "F.Mask" "F.Paste")
			(net "FM_OCP_MEZZB_PRES_LVT3_BMC")
		)
		(pad "H20" smd circle
			(at 6.800088 -2.800096 90)
			(size 0.3556 0.3556)
			(layers "F.Cu" "F.Mask" "F.Paste")
			(net "IRQ_PVDDQ_GHJ_VRHOT_LVT3_N")
		)
		(pad "H21" smd circle
			(at 7.599934 -2.800096 90)
			(size 0.3556 0.3556)
			(layers "F.Cu" "F.Mask" "F.Paste")
			(net "IRQ_BMC_PCH_SMI_LPC_N")
		)
		(pad "H22" smd circle
			(at 8.400034 -2.800096 90)
			(size 0.3556 0.3556)
			(layers "F.Cu" "F.Mask" "F.Paste")
			(net "PWRGD_SYS_PWROK")
		)
		(pad "J1" smd circle
			(at -8.400034 -1.999996 90)
			(size 0.3556 0.3556)
			(layers "F.Cu" "F.Mask" "F.Paste")
			(net "PD_ADCREXT")
		)
		(pad "J2" smd circle
			(at -7.599934 -1.999996 90)
			(size 0.3556 0.3556)
			(layers "F.Cu" "F.Mask" "F.Paste")
			(net "BMC_VGA_BLUE")
		)
		(pad "J3" smd circle
			(at -6.800088 -1.999996 90)
			(size 0.3556 0.3556)
			(layers "F.Cu" "F.Mask" "F.Paste")
			(net "BMC_VGA_GREEN")
		)
		(pad "J4" smd circle
			(at -5.999988 -1.999996 90)
			(size 0.3556 0.3556)
			(layers "F.Cu" "F.Mask" "F.Paste")
			(net "BMC_VGA_RED")
		)
		(pad "J5" smd circle
			(at -5.199888 -1.999996 90)
			(size 0.3556 0.3556)
			(layers "F.Cu" "F.Mask" "F.Paste")
			(net "GND")
		)
		(pad "J6" smd circle
			(at -4.400042 -1.999996 90)
			(size 0.3556 0.3556)
			(layers "F.Cu" "F.Mask" "F.Paste")
			(net "VCC_ADCAV3V3")
		)
		(pad "J7" smd circle
			(at -3.599942 -1.999996 90)
			(size 0.3556 0.3556)
			(layers "F.Cu" "F.Mask" "F.Paste")
			(net "VCC_VA_3V3")
		)
		(pad "J9" smd circle
			(at -1.999996 -1.999996 90)
			(size 0.3556 0.3556)
			(layers "F.Cu" "F.Mask" "F.Paste")
			(net "GND")
		)
		(pad "J10" smd circle
			(at -1.199896 -1.999996 90)
			(size 0.3556 0.3556)
			(layers "F.Cu" "F.Mask" "F.Paste")
			(net "GND")
		)
		(pad "J11" smd circle
			(at -0.40005 -1.999996 90)
			(size 0.3556 0.3556)
			(layers "F.Cu" "F.Mask" "F.Paste")
			(net "GND")
		)
		(pad "J12" smd circle
			(at 0.40005 -1.999996 90)
			(size 0.3556 0.3556)
			(layers "F.Cu" "F.Mask" "F.Paste")
			(net "GND")
		)
		(pad "J13" smd circle
			(at 1.199896 -1.999996 90)
			(size 0.3556 0.3556)
			(layers "F.Cu" "F.Mask" "F.Paste")
			(net "GND")
		)
		(pad "J14" smd circle
			(at 1.999996 -1.999996 90)
			(size 0.3556 0.3556)
			(layers "F.Cu" "F.Mask" "F.Paste")
			(net "GND")
		)
		(pad "J16" smd circle
			(at 3.599942 -1.999996 90)
			(size 0.3556 0.3556)
			(layers "F.Cu" "F.Mask" "F.Paste")
			(net "P1V15_AUX_BMC")
		)
		(pad "J17" smd circle
			(at 4.400042 -1.999996 90)
			(size 0.3556 0.3556)
			(layers "F.Cu" "F.Mask" "F.Paste")
			(net "P3V3_STBY")
		)
		(pad "J18" smd circle
			(at 5.199888 -1.999996 90)
			(size 0.3556 0.3556)
			(layers "F.Cu" "F.Mask" "F.Paste")
			(net "SPI_BMC_BT_WP0_N")
		)
		(pad "J19" smd circle
			(at 5.999988 -1.999996 90)
			(size 0.3556 0.3556)
			(layers "F.Cu" "F.Mask" "F.Paste")
			(net "IRQ_PVDDQ_ABC_VRHOT_LVT3_N")
		)
		(pad "J20" smd circle
			(at 6.800088 -1.999996 90)
			(size 0.3556 0.3556)
			(layers "F.Cu" "F.Mask" "F.Paste")
			(net "CLK_48M_USB_BMC_R")
		)
		(pad "J21" smd circle
			(at 7.599934 -1.999996 90)
			(size 0.3556 0.3556)
			(layers "F.Cu" "F.Mask" "F.Paste")
			(net "GND")
		)
		(pad "J22" smd circle
			(at 8.400034 -1.999996 90)
			(size 0.3556 0.3556)
			(layers "F.Cu" "F.Mask" "F.Paste")
			(net "GND")
		)
		(pad "K1" smd circle
			(at -8.400034 -1.199896 90)
			(size 0.3556 0.3556)
			(layers "F.Cu" "F.Mask" "F.Paste")
			(net "UART_BMC_TXD5")
		)
		(pad "K2" smd circle
			(at -7.599934 -1.199896 90)
			(size 0.3556 0.3556)
			(layers "F.Cu" "F.Mask" "F.Paste")
			(net "UART_BMC_RXD5")
		)
		(pad "K3" smd circle
			(at -6.800088 -1.199896 90)
			(size 0.3556 0.3556)
			(layers "F.Cu" "F.Mask" "F.Paste")
			(net "PD_SP_ENTEST")
		)
		(pad "K4" smd circle
			(at -5.999988 -1.199896 90)
			(size 0.3556 0.3556)
			(layers "F.Cu" "F.Mask" "F.Paste")
			(net "A_DACRSET")
		)
		(pad "K5" smd circle
			(at -5.199888 -1.199896 90)
			(size 0.3556 0.3556)
			(layers "F.Cu" "F.Mask" "F.Paste")
			(net "VCC_DACAV3V3")
		)
		(pad "K6" smd circle
			(at -4.400042 -1.199896 90)
			(size 0.3556 0.3556)
			(layers "F.Cu" "F.Mask" "F.Paste")
			(net "VCC_DACAV3V3")
		)
		(pad "K7" smd circle
			(at -3.599942 -1.199896 90)
			(size 0.3556 0.3556)
			(layers "F.Cu" "F.Mask" "F.Paste")
			(net "VCC_D_3V3")
		)
		(pad "K9" smd circle
			(at -1.999996 -1.199896 90)
			(size 0.3556 0.3556)
			(layers "F.Cu" "F.Mask" "F.Paste")
			(net "GND")
		)
		(pad "K10" smd circle
			(at -1.199896 -1.199896 90)
			(size 0.3556 0.3556)
			(layers "F.Cu" "F.Mask" "F.Paste")
			(net "GND")
		)
		(pad "K11" smd circle
			(at -0.40005 -1.199896 90)
			(size 0.3556 0.3556)
			(layers "F.Cu" "F.Mask" "F.Paste")
			(net "GND")
		)
		(pad "K12" smd circle
			(at 0.40005 -1.199896 90)
			(size 0.3556 0.3556)
			(layers "F.Cu" "F.Mask" "F.Paste")
			(net "GND")
		)
		(pad "K13" smd circle
			(at 1.199896 -1.199896 90)
			(size 0.3556 0.3556)
			(layers "F.Cu" "F.Mask" "F.Paste")
			(net "GND")
		)
		(pad "K14" smd circle
			(at 1.999996 -1.199896 90)
			(size 0.3556 0.3556)
			(layers "F.Cu" "F.Mask" "F.Paste")
			(net "GND")
		)
		(pad "K16" smd circle
			(at 3.599942 -1.199896 90)
			(size 0.3556 0.3556)
			(layers "F.Cu" "F.Mask" "F.Paste")
			(net "GND")
		)
		(pad "K17" smd circle
			(at 4.400042 -1.199896 90)
			(size 0.3556 0.3556)
			(layers "F.Cu" "F.Mask" "F.Paste")
			(net "P3V3_STBY")
		)
		(pad "K18" smd circle
			(at 5.199888 -1.199896 90)
			(size 0.3556 0.3556)
			(layers "F.Cu" "F.Mask" "F.Paste")
			(net "H_CPU0_FAST_WAKE_LVT3_N")
		)
		(pad "K19" smd circle
			(at 5.999988 -1.199896 90)
			(size 0.3556 0.3556)
			(layers "F.Cu" "F.Mask" "F.Paste")
			(net "PWRGD_PCH_PWROK")
		)
		(pad "K20" smd circle
			(at 6.800088 -1.199896 90)
			(size 0.3556 0.3556)
			(layers "F.Cu" "F.Mask" "F.Paste")
			(net "PD_PEREXT")
		)
		(pad "K21" smd circle
			(at 7.599934 -1.199896 90)
			(size 0.3556 0.3556)
			(layers "F.Cu" "F.Mask" "F.Paste")
			(net "CLK_100M_BMC_PE_R_DP")
		)
		(pad "K22" smd circle
			(at 8.400034 -1.199896 90)
			(size 0.3556 0.3556)
			(layers "F.Cu" "F.Mask" "F.Paste")
			(net "CLK_100M_BMC_PE_R_DN")
		)
		(pad "L1" smd circle
			(at -8.400034 -0.40005 90)
			(size 0.3556 0.3556)
			(layers "F.Cu" "F.Mask" "F.Paste")
			(net "SMB_VR_STBY_LVC3_SCL_R")
		)
		(pad "L2" smd circle
			(at -7.599934 -0.40005 90)
			(size 0.3556 0.3556)
			(layers "F.Cu" "F.Mask" "F.Paste")
			(net "SGPIO_BMC_LD_R_N")
		)
		(pad "L3" smd circle
			(at -6.800088 -0.40005 90)
			(size 0.3556 0.3556)
			(layers "F.Cu" "F.Mask" "F.Paste")
			(net "SMB_SMLINK0_STBY_LVC3_SCL_R")
		)
		(pad "L4" smd circle
			(at -5.999988 -0.40005 90)
			(size 0.3556 0.3556)
			(layers "F.Cu" "F.Mask" "F.Paste")
			(net "SMB_SMLINK0_STBY_LVC3_SDA_R")
		)
		(pad "L5" smd circle
			(at -5.199888 -0.40005 90)
			(size 0.3556 0.3556)
			(layers "F.Cu" "F.Mask" "F.Paste")
			(net "VCC_A_1V1")
		)
		(pad "L6" smd circle
			(at -4.400042 -0.40005 90)
			(size 0.3556 0.3556)
			(layers "F.Cu" "F.Mask" "F.Paste")
			(net "VCC_A_1V1")
		)
		(pad "L7" smd circle
			(at -3.599942 -0.40005 90)
			(size 0.3556 0.3556)
			(layers "F.Cu" "F.Mask" "F.Paste")
			(net "P1V15_AUX_BMC")
		)
		(pad "L9" smd circle
			(at -1.999996 -0.40005 90)
			(size 0.3556 0.3556)
			(layers "F.Cu" "F.Mask" "F.Paste")
			(net "GND")
		)
		(pad "L10" smd circle
			(at -1.199896 -0.40005 90)
			(size 0.3556 0.3556)
			(layers "F.Cu" "F.Mask" "F.Paste")
			(net "GND")
		)
		(pad "L11" smd circle
			(at -0.40005 -0.40005 90)
			(size 0.3556 0.3556)
			(layers "F.Cu" "F.Mask" "F.Paste")
			(net "GND")
		)
		(pad "L12" smd circle
			(at 0.40005 -0.40005 90)
			(size 0.3556 0.3556)
			(layers "F.Cu" "F.Mask" "F.Paste")
			(net "GND")
		)
		(pad "L13" smd circle
			(at 1.199896 -0.40005 90)
			(size 0.3556 0.3556)
			(layers "F.Cu" "F.Mask" "F.Paste")
			(net "GND")
		)
		(pad "L14" smd circle
			(at 1.999996 -0.40005 90)
			(size 0.3556 0.3556)
			(layers "F.Cu" "F.Mask" "F.Paste")
			(net "GND")
		)
		(pad "L16" smd circle
			(at 3.599942 -0.40005 90)
			(size 0.3556 0.3556)
			(layers "F.Cu" "F.Mask" "F.Paste")
			(net "VCC_D_3V3")
		)
		(pad "L17" smd circle
			(at 4.400042 -0.40005 90)
			(size 0.3556 0.3556)
			(layers "F.Cu" "F.Mask" "F.Paste")
			(net "P1V15_AUX_BMC")
		)
		(pad "L18" smd circle
			(at 5.199888 -0.40005 90)
			(size 0.3556 0.3556)
			(layers "F.Cu" "F.Mask" "F.Paste")
			(net "FM_MP_PS_FAIL_N")
		)
		(pad "L19" smd circle
			(at 5.999988 -0.40005 90)
			(size 0.3556 0.3556)
			(layers "F.Cu" "F.Mask" "F.Paste")
			(net "BMC_DEBUG_EN_N")
		)
		(pad "L20" smd circle
			(at 6.800088 -0.40005 90)
			(size 0.3556 0.3556)
			(layers "F.Cu" "F.Mask" "F.Paste")
			(net "RST_PLTRST_BUF_N_R")
		)
		(pad "L21" smd circle
			(at 7.599934 -0.40005 90)
			(size 0.3556 0.3556)
			(layers "F.Cu" "F.Mask" "F.Paste")
			(net "P2E_SSB_BMC_RX_DP")
		)
		(pad "L22" smd circle
			(at 8.400034 -0.40005 90)
			(size 0.3556 0.3556)
			(layers "F.Cu" "F.Mask" "F.Paste")
			(net "P2E_SSB_BMC_RX_DN")
		)
		(pad "M1" smd circle
			(at -8.400034 0.40005 90)
			(size 0.3556 0.3556)
			(layers "F.Cu" "F.Mask" "F.Paste")
			(net "GND")
		)
		(pad "M2" smd circle
			(at -7.599934 0.40005 90)
			(size 0.3556 0.3556)
			(layers "F.Cu" "F.Mask" "F.Paste")
			(net "GND")
		)
		(pad "M3" smd circle
			(at -6.800088 0.40005 90)
			(size 0.3556 0.3556)
			(layers "F.Cu" "F.Mask" "F.Paste")
			(net "GND")
		)
		(pad "M4" smd circle
			(at -5.999988 0.40005 90)
			(size 0.3556 0.3556)
			(layers "F.Cu" "F.Mask" "F.Paste")
			(net "GND")
		)
		(pad "M5" smd circle
			(at -5.199888 0.40005 90)
			(size 0.3556 0.3556)
			(layers "F.Cu" "F.Mask" "F.Paste")
			(net "GND")
		)
		(pad "M6" smd circle
			(at -4.400042 0.40005 90)
			(size 0.3556 0.3556)
			(layers "F.Cu" "F.Mask" "F.Paste")
			(net "GND")
		)
		(pad "M7" smd circle
			(at -3.599942 0.40005 90)
			(size 0.3556 0.3556)
			(layers "F.Cu" "F.Mask" "F.Paste")
			(net "GND")
		)
		(pad "M9" smd circle
			(at -1.999996 0.40005 90)
			(size 0.3556 0.3556)
			(layers "F.Cu" "F.Mask" "F.Paste")
			(net "GND")
		)
		(pad "M10" smd circle
			(at -1.199896 0.40005 90)
			(size 0.3556 0.3556)
			(layers "F.Cu" "F.Mask" "F.Paste")
			(net "GND")
		)
		(pad "M11" smd circle
			(at -0.40005 0.40005 90)
			(size 0.3556 0.3556)
			(layers "F.Cu" "F.Mask" "F.Paste")
			(net "GND")
		)
		(pad "M12" smd circle
			(at 0.40005 0.40005 90)
			(size 0.3556 0.3556)
			(layers "F.Cu" "F.Mask" "F.Paste")
			(net "GND")
		)
		(pad "M13" smd circle
			(at 1.199896 0.40005 90)
			(size 0.3556 0.3556)
			(layers "F.Cu" "F.Mask" "F.Paste")
			(net "GND")
		)
		(pad "M14" smd circle
			(at 1.999996 0.40005 90)
			(size 0.3556 0.3556)
			(layers "F.Cu" "F.Mask" "F.Paste")
			(net "GND")
		)
		(pad "M16" smd circle
			(at 3.599942 0.40005 90)
			(size 0.3556 0.3556)
			(layers "F.Cu" "F.Mask" "F.Paste")
			(net "GND")
		)
		(pad "M17" smd circle
			(at 4.400042 0.40005 90)
			(size 0.3556 0.3556)
			(layers "F.Cu" "F.Mask" "F.Paste")
			(net "GND")
		)
		(pad "M18" smd circle
			(at 5.199888 0.40005 90)
			(size 0.3556 0.3556)
			(layers "F.Cu" "F.Mask" "F.Paste")
			(net "SMB_LAN_STBY_LVC3_SCL_R")
		)
		(pad "M19" smd circle
			(at 5.999988 0.40005 90)
			(size 0.3556 0.3556)
			(layers "F.Cu" "F.Mask" "F.Paste")
			(net "SMB_LAN_STBY_LVC3_SDA_R")
		)
		(pad "M20" smd circle
			(at 6.800088 0.40005 90)
			(size 0.3556 0.3556)
			(layers "F.Cu" "F.Mask" "F.Paste")
			(net "SMB_SLOTX24_STBY_LVC3_SCL_R")
		)
		(pad "M21" smd circle
			(at 7.599934 0.40005 90)
			(size 0.3556 0.3556)
			(layers "F.Cu" "F.Mask" "F.Paste")
			(net "P2E_SSB_BMC_TX_C_DP")
		)
		(pad "M22" smd circle
			(at 8.400034 0.40005 90)
			(size 0.3556 0.3556)
			(layers "F.Cu" "F.Mask" "F.Paste")
			(net "P2E_SSB_BMC_TX_C_DN")
		)
		(pad "N1" smd circle
			(at -8.400034 1.199896 90)
			(size 0.3556 0.3556)
			(layers "F.Cu" "F.Mask" "F.Paste")
			(net "SMB_SENSOR_BMC_STBY_LVC3_SCL")
		)
		(pad "N2" smd circle
			(at -7.599934 1.199896 90)
			(size 0.3556 0.3556)
			(layers "F.Cu" "F.Mask" "F.Paste")
			(net "SMB_VR_STBY_LVC3_SDA_R")
		)
		(pad "N3" smd circle
			(at -6.800088 1.199896 90)
			(size 0.3556 0.3556)
			(layers "F.Cu" "F.Mask" "F.Paste")
			(net "SGPIO_BMC_DOUT_R")
		)
		(pad "N4" smd circle
			(at -5.999988 1.199896 90)
			(size 0.3556 0.3556)
			(layers "F.Cu" "F.Mask" "F.Paste")
			(net "SGPIO_BMC_DIN")
		)
		(pad "N5" smd circle
			(at -5.199888 1.199896 90)
			(size 0.3556 0.3556)
			(layers "F.Cu" "F.Mask" "F.Paste")
			(net "BMC_VGA_HSYNC")
		)
		(pad "N6" smd circle
			(at -4.400042 1.199896 90)
			(size 0.3556 0.3556)
			(layers "F.Cu" "F.Mask" "F.Paste")
			(net "VCC_D_3V3")
		)
		(pad "N7" smd circle
			(at -3.599942 1.199896 90)
			(size 0.3556 0.3556)
			(layers "F.Cu" "F.Mask" "F.Paste")
			(net "P1V15_AUX_BMC")
		)
		(pad "N9" smd circle
			(at -1.999996 1.199896 90)
			(size 0.3556 0.3556)
			(layers "F.Cu" "F.Mask" "F.Paste")
			(net "GND")
		)
		(pad "N10" smd circle
			(at -1.199896 1.199896 90)
			(size 0.3556 0.3556)
			(layers "F.Cu" "F.Mask" "F.Paste")
			(net "GND")
		)
		(pad "N11" smd circle
			(at -0.40005 1.199896 90)
			(size 0.3556 0.3556)
			(layers "F.Cu" "F.Mask" "F.Paste")
			(net "GND")
		)
		(pad "N12" smd circle
			(at 0.40005 1.199896 90)
			(size 0.3556 0.3556)
			(layers "F.Cu" "F.Mask" "F.Paste")
			(net "GND")
		)
		(pad "N13" smd circle
			(at 1.199896 1.199896 90)
			(size 0.3556 0.3556)
			(layers "F.Cu" "F.Mask" "F.Paste")
			(net "GND")
		)
		(pad "N14" smd circle
			(at 1.999996 1.199896 90)
			(size 0.3556 0.3556)
			(layers "F.Cu" "F.Mask" "F.Paste")
			(net "GND")
		)
		(pad "N16" smd circle
			(at 3.599942 1.199896 90)
			(size 0.3556 0.3556)
			(layers "F.Cu" "F.Mask" "F.Paste")
			(net "P1V15_AUX_BMC")
		)
		(pad "N17" smd circle
			(at 4.400042 1.199896 90)
			(size 0.3556 0.3556)
			(layers "F.Cu" "F.Mask" "F.Paste")
			(net "VCC_D_3V3")
		)
		(pad "N18" smd circle
			(at 5.199888 1.199896 90)
			(size 0.3556 0.3556)
			(layers "F.Cu" "F.Mask" "F.Paste")
			(net "IRQ_LOM_ALERT_N")
		)
		(pad "N19" smd circle
			(at 5.999988 1.199896 90)
			(size 0.3556 0.3556)
			(layers "F.Cu" "F.Mask" "F.Paste")
			(net "IRQ_HSC_FAULT_N")
		)
		(pad "N20" smd circle
			(at 6.800088 1.199896 90)
			(size 0.3556 0.3556)
			(layers "F.Cu" "F.Mask" "F.Paste")
			(net "FM_PE_BMC_WAKE_N")
		)
		(pad "N21" smd circle
			(at 7.599934 1.199896 90)
			(size 0.3556 0.3556)
			(layers "F.Cu" "F.Mask" "F.Paste")
			(net "FM_UARTSW_LSB_N")
		)
		(pad "N22" smd circle
			(at 8.400034 1.199896 90)
			(size 0.3556 0.3556)
			(layers "F.Cu" "F.Mask" "F.Paste")
			(net "FM_UARTSW_MSB_N")
		)
		(pad "P1" smd circle
			(at -8.400034 1.999996 90)
			(size 0.3556 0.3556)
			(layers "F.Cu" "F.Mask" "F.Paste")
			(net "SMB_SENSOR_BMC_STBY_LVC3_SDA")
		)
		(pad "P2" smd circle
			(at -7.599934 1.999996 90)
			(size 0.3556 0.3556)
			(layers "F.Cu" "F.Mask" "F.Paste")
			(net "SMB_BMC_PMBUS_STBY_LVC3_SCL_R")
		)
		(pad "P3" smd circle
			(at -6.800088 1.999996 90)
			(size 0.3556 0.3556)
			(layers "F.Cu" "F.Mask" "F.Paste")
			(net "FM_PMBUS_ALERT_BUF_EN_R3_N")
		)
		(pad "P4" smd circle
			(at -5.999988 1.999996 90)
			(size 0.3556 0.3556)
			(layers "F.Cu" "F.Mask" "F.Paste")
			(net "FM_MEM_THERM_EVENT_PCH_N")
		)
		(pad "P5" smd circle
			(at -5.199888 1.999996 90)
			(size 0.3556 0.3556)
			(layers "F.Cu" "F.Mask" "F.Paste")
			(net "FM_CPU1_THERMTRIP_LATCH_LVT3_N")
		)
		(pad "P6" smd circle
			(at -4.400042 1.999996 90)
			(size 0.3556 0.3556)
			(layers "F.Cu" "F.Mask" "F.Paste")
			(net "VCC_D_3V3")
		)
		(pad "P7" smd circle
			(at -3.599942 1.999996 90)
			(size 0.3556 0.3556)
			(layers "F.Cu" "F.Mask" "F.Paste")
			(net "P1V15_AUX_BMC")
		)
		(pad "P9" smd circle
			(at -1.999996 1.999996 90)
			(size 0.3556 0.3556)
			(layers "F.Cu" "F.Mask" "F.Paste")
			(net "P1V15_AUX_BMC")
		)
		(pad "P10" smd circle
			(at -1.199896 1.999996 90)
			(size 0.3556 0.3556)
			(layers "F.Cu" "F.Mask" "F.Paste")
			(net "P1V15_AUX_BMC")
		)
		(pad "P11" smd circle
			(at -0.40005 1.999996 90)
			(size 0.3556 0.3556)
			(layers "F.Cu" "F.Mask" "F.Paste")
			(net "P1V15_AUX_BMC")
		)
		(pad "P12" smd circle
			(at 0.40005 1.999996 90)
			(size 0.3556 0.3556)
			(layers "F.Cu" "F.Mask" "F.Paste")
			(net "P1V15_AUX_BMC")
		)
		(pad "P13" smd circle
			(at 1.199896 1.999996 90)
			(size 0.3556 0.3556)
			(layers "F.Cu" "F.Mask" "F.Paste")
			(net "P1V15_AUX_BMC")
		)
		(pad "P14" smd circle
			(at 1.999996 1.999996 90)
			(size 0.3556 0.3556)
			(layers "F.Cu" "F.Mask" "F.Paste")
			(net "P1V15_AUX_BMC")
		)
		(pad "P16" smd circle
			(at 3.599942 1.999996 90)
			(size 0.3556 0.3556)
			(layers "F.Cu" "F.Mask" "F.Paste")
			(net "P1V15_AUX_BMC")
		)
		(pad "P17" smd circle
			(at 4.400042 1.999996 90)
			(size 0.3556 0.3556)
			(layers "F.Cu" "F.Mask" "F.Paste")
			(net "VCC_D_3V3")
		)
		(pad "P18" smd circle
			(at 5.199888 1.999996 90)
			(size 0.3556 0.3556)
			(layers "F.Cu" "F.Mask" "F.Paste")
			(net "HSC_SMBUS_SWITCH_EN")
		)
		(pad "P19" smd circle
			(at 5.999988 1.999996 90)
			(size 0.3556 0.3556)
			(layers "F.Cu" "F.Mask" "F.Paste")
			(net "FM_BIOS_POST_CMPLT_N")
		)
		(pad "P20" smd circle
			(at 6.800088 1.999996 90)
			(size 0.3556 0.3556)
			(layers "F.Cu" "F.Mask" "F.Paste")
			(net "SMB_SLOTX24_STBY_LVC3_SDA_R")
		)
		(pad "P21" smd circle
			(at 7.599934 1.999996 90)
			(size 0.3556 0.3556)
			(layers "F.Cu" "F.Mask" "F.Paste")
			(net "FM_BMC_ONCTL_R_N")
		)
		(pad "P22" smd circle
			(at 8.400034 1.999996 90)
			(size 0.3556 0.3556)
			(layers "F.Cu" "F.Mask" "F.Paste")
			(net "BMC_JTAG_SEL_N")
		)
		(pad "R1" smd circle
			(at -8.400034 2.800096 90)
			(size 0.3556 0.3556)
			(layers "F.Cu" "F.Mask" "F.Paste")
			(net "SMB_BMC_PMBUS_STBY_LVC3_SDA_R")
		)
		(pad "R2" smd circle
			(at -7.599934 2.800096 90)
			(size 0.3556 0.3556)
			(layers "F.Cu" "F.Mask" "F.Paste")
			(net "SGPIO_BMC_CLK_R")
		)
		(pad "R3" smd circle
			(at -6.800088 2.800096 90)
			(size 0.3556 0.3556)
			(layers "F.Cu" "F.Mask" "F.Paste")
			(net "I2C_BMC_VGA_DDC_SCL")
		)
		(pad "R4" smd circle
			(at -5.999988 2.800096 90)
			(size 0.3556 0.3556)
			(layers "F.Cu" "F.Mask" "F.Paste")
			(net "BMC_VGA_VSYNC")
		)
		(pad "R5" smd circle
			(at -5.199888 2.800096 90)
			(size 0.3556 0.3556)
			(layers "F.Cu" "F.Mask" "F.Paste")
			(net "SP2_BMC_CM_UART_TX")
		)
		(pad "R6" smd circle
			(at -4.400042 2.800096 90)
			(size 0.3556 0.3556)
			(layers "F.Cu" "F.Mask" "F.Paste")
			(net "VCC_D_3V3")
		)
		(pad "R7" smd circle
			(at -3.599942 2.800096 90)
			(size 0.3556 0.3556)
			(layers "F.Cu" "F.Mask" "F.Paste")
			(net "P1V15_AUX_BMC")
		)
		(pad "R16" smd circle
			(at 3.599942 2.800096 90)
			(size 0.3556 0.3556)
			(layers "F.Cu" "F.Mask" "F.Paste")
			(net "P1V15_AUX_BMC")
		)
		(pad "R17" smd circle
			(at 4.400042 2.800096 90)
			(size 0.3556 0.3556)
			(layers "F.Cu" "F.Mask" "F.Paste")
			(net "VCC_D_3V3")
		)
		(pad "R18" smd circle
			(at 5.199888 2.800096 90)
			(size 0.3556 0.3556)
			(layers "F.Cu" "F.Mask" "F.Paste")
			(net "IRQ_SML0_ALERT_N")
		)
		(pad "R19" smd circle
			(at 5.999988 2.800096 90)
			(size 0.3556 0.3556)
			(layers "F.Cu" "F.Mask" "F.Paste")
			(net "BMC_STRAP_BIT3")
		)
		(pad "R20" smd circle
			(at 6.800088 2.800096 90)
			(size 0.3556 0.3556)
			(layers "F.Cu" "F.Mask" "F.Paste")
			(net "Net_6481")
		)
		(pad "R21" smd circle
			(at 7.599934 2.800096 90)
			(size 0.3556 0.3556)
			(layers "F.Cu" "F.Mask" "F.Paste")
			(net "FM_SLPS4_N")
		)
		(pad "R22" smd circle
			(at 8.400034 2.800096 90)
			(size 0.3556 0.3556)
			(layers "F.Cu" "F.Mask" "F.Paste")
			(net "FM_SLPS3_N")
		)
		(pad "T1" smd circle
			(at -8.400034 3.599942 90)
			(size 0.3556 0.3556)
			(layers "F.Cu" "F.Mask" "F.Paste")
			(net "IRQ_OC_DETECT_N")
		)
		(pad "T2" smd circle
			(at -7.599934 3.599942 90)
			(size 0.3556 0.3556)
			(layers "F.Cu" "F.Mask" "F.Paste")
			(net "IRQ_UV_DETECT_N")
		)
		(pad "T3" smd circle
			(at -6.800088 3.599942 90)
			(size 0.3556 0.3556)
			(layers "F.Cu" "F.Mask" "F.Paste")
			(net "I2C_BMC_VGA_DDC_SDA")
		)
		(pad "T4" smd circle
			(at -5.999988 3.599942 90)
			(size 0.3556 0.3556)
			(layers "F.Cu" "F.Mask" "F.Paste")
			(net "FM_PWRBRK_N")
		)
		(pad "T5" smd circle
			(at -5.199888 3.599942 90)
			(size 0.3556 0.3556)
			(layers "F.Cu" "F.Mask" "F.Paste")
			(net "SP2_BMC_CM_UART_RX")
		)
		(pad "T6" smd circle
			(at -4.400042 3.599942 90)
			(size 0.3556 0.3556)
			(layers "F.Cu" "F.Mask" "F.Paste")
			(net "GND")
		)
		(pad "T7" smd circle
			(at -3.599942 3.599942 90)
			(size 0.3556 0.3556)
			(layers "F.Cu" "F.Mask" "F.Paste")
			(net "GND")
		)
		(pad "T8" smd circle
			(at -2.800096 3.599942 90)
			(size 0.3556 0.3556)
			(layers "F.Cu" "F.Mask" "F.Paste")
			(net "P1V2_AUX_BMC")
		)
		(pad "T9" smd circle
			(at -1.999996 3.599942 90)
			(size 0.3556 0.3556)
			(layers "F.Cu" "F.Mask" "F.Paste")
			(net "BMC_M_VREFCA")
		)
		(pad "T10" smd circle
			(at -1.199896 3.599942 90)
			(size 0.3556 0.3556)
			(layers "F.Cu" "F.Mask" "F.Paste")
			(net "P1V2_AUX_BMC")
		)
		(pad "T11" smd circle
			(at -0.40005 3.599942 90)
			(size 0.3556 0.3556)
			(layers "F.Cu" "F.Mask" "F.Paste")
			(net "VCC_PA_3V3")
		)
		(pad "T12" smd circle
			(at 0.40005 3.599942 90)
			(size 0.3556 0.3556)
			(layers "F.Cu" "F.Mask" "F.Paste")
			(net "P1V2_AUX_BMC")
		)
		(pad "T13" smd circle
			(at 1.199896 3.599942 90)
			(size 0.3556 0.3556)
			(layers "F.Cu" "F.Mask" "F.Paste")
			(net "P1V2_AUX_BMC")
		)
		(pad "T14" smd circle
			(at 1.999996 3.599942 90)
			(size 0.3556 0.3556)
			(layers "F.Cu" "F.Mask" "F.Paste")
			(net "P1V2_AUX_BMC")
		)
		(pad "T15" smd circle
			(at 2.800096 3.599942 90)
			(size 0.3556 0.3556)
			(layers "F.Cu" "F.Mask" "F.Paste")
			(net "VCC_D_3V3")
		)
		(pad "T16" smd circle
			(at 3.599942 3.599942 90)
			(size 0.3556 0.3556)
			(layers "F.Cu" "F.Mask" "F.Paste")
			(net "GND")
		)
		(pad "T17" smd circle
			(at 4.400042 3.599942 90)
			(size 0.3556 0.3556)
			(layers "F.Cu" "F.Mask" "F.Paste")
			(net "BMC_TCK_MUX_SEL")
		)
		(pad "T18" smd circle
			(at 5.199888 3.599942 90)
			(size 0.3556 0.3556)
			(layers "F.Cu" "F.Mask" "F.Paste")
			(net "SPI_BMC_BT_DI")
		)
		(pad "T19" smd circle
			(at 5.999988 3.599942 90)
			(size 0.3556 0.3556)
			(layers "F.Cu" "F.Mask" "F.Paste")
			(net "FM_MP_PS_REDUNDANT_LOST_N")
		)
		(pad "T20" smd circle
			(at 6.800088 3.599942 90)
			(size 0.3556 0.3556)
			(layers "F.Cu" "F.Mask" "F.Paste")
			(net "UV_HIGH_SET")
		)
		(pad "T21" smd circle
			(at 7.599934 3.599942 90)
			(size 0.3556 0.3556)
			(layers "F.Cu" "F.Mask" "F.Paste")
			(net "FM_OCP_MEZZA_PRES")
		)
		(pad "T22" smd circle
			(at 8.400034 3.599942 90)
			(size 0.3556 0.3556)
			(layers "F.Cu" "F.Mask" "F.Paste")
			(net "BMC_SELF_HW_RST")
		)
		(pad "U1" smd circle
			(at -8.400034 4.400042 90)
			(size 0.3556 0.3556)
			(layers "F.Cu" "F.Mask" "F.Paste")
			(net "FM_HSC_TIMER_EXP_N")
		)
		(pad "U2" smd circle
			(at -7.599934 4.400042 90)
			(size 0.3556 0.3556)
			(layers "F.Cu" "F.Mask" "F.Paste")
			(net "FM_BIOS_TOP_SWAP")
		)
		(pad "U3" smd circle
			(at -6.800088 4.400042 90)
			(size 0.3556 0.3556)
			(layers "F.Cu" "F.Mask" "F.Paste")
			(net "FM_CPU_MSMI_LVT3_N")
		)
		(pad "U4" smd circle
			(at -5.999988 4.400042 90)
			(size 0.3556 0.3556)
			(layers "F.Cu" "F.Mask" "F.Paste")
			(net "FAN_TACH1")
		)
		(pad "U5" smd circle
			(at -5.199888 4.400042 90)
			(size 0.3556 0.3556)
			(layers "F.Cu" "F.Mask" "F.Paste")
			(net "FAN_TACH0")
		)
		(pad "U6" smd circle
			(at -4.400042 4.400042 90)
			(size 0.3556 0.3556)
			(layers "F.Cu" "F.Mask" "F.Paste")
			(net "GND")
		)
		(pad "U7" smd circle
			(at -3.599942 4.400042 90)
			(size 0.3556 0.3556)
			(layers "F.Cu" "F.Mask" "F.Paste")
			(net "BMC_M_DQ15")
		)
		(pad "U8" smd circle
			(at -2.800096 4.400042 90)
			(size 0.3556 0.3556)
			(layers "F.Cu" "F.Mask" "F.Paste")
			(net "BMC_M_DM0")
		)
		(pad "U9" smd circle
			(at -1.999996 4.400042 90)
			(size 0.3556 0.3556)
			(layers "F.Cu" "F.Mask" "F.Paste")
			(net "BMC_M_DQ4")
		)
		(pad "U10" smd circle
			(at -1.199896 4.400042 90)
			(size 0.3556 0.3556)
			(layers "F.Cu" "F.Mask" "F.Paste")
			(net "BMC_M_DQ0")
		)
		(pad "U11" smd circle
			(at -0.40005 4.400042 90)
			(size 0.3556 0.3556)
			(layers "F.Cu" "F.Mask" "F.Paste")
			(net "GND")
		)
		(pad "U12" smd circle
			(at 0.40005 4.400042 90)
			(size 0.3556 0.3556)
			(layers "F.Cu" "F.Mask" "F.Paste")
			(net "BMC_M_BA0")
		)
		(pad "U13" smd circle
			(at 1.199896 4.400042 90)
			(size 0.3556 0.3556)
			(layers "F.Cu" "F.Mask" "F.Paste")
			(net "BMC_M_A10")
		)
		(pad "U14" smd circle
			(at 1.999996 4.400042 90)
			(size 0.3556 0.3556)
			(layers "F.Cu" "F.Mask" "F.Paste")
			(net "BMC_M_A3")
		)
		(pad "U15" smd circle
			(at 2.800096 4.400042 90)
			(size 0.3556 0.3556)
			(layers "F.Cu" "F.Mask" "F.Paste")
			(net "TP_BMC_M_A15")
		)
		(pad "U16" smd circle
			(at 3.599942 4.400042 90)
			(size 0.3556 0.3556)
			(layers "F.Cu" "F.Mask" "F.Paste")
			(net "BMC_M_MALERT_N")
		)
		(pad "U17" smd circle
			(at 4.400042 4.400042 90)
			(size 0.3556 0.3556)
			(layers "F.Cu" "F.Mask" "F.Paste")
			(net "SPI_BMC_BT_DO_R")
		)
		(pad "U18" smd circle
			(at 5.199888 4.400042 90)
			(size 0.3556 0.3556)
			(layers "F.Cu" "F.Mask" "F.Paste")
			(net "RST_BMC_SRST_N")
		)
		(pad "U19" smd circle
			(at 5.999988 4.400042 90)
			(size 0.3556 0.3556)
			(layers "F.Cu" "F.Mask" "F.Paste")
			(net "FM_BMC_READY_N")
		)
		(pad "U20" smd circle
			(at 6.800088 4.400042 90)
			(size 0.3556 0.3556)
			(layers "F.Cu" "F.Mask" "F.Paste")
			(net "BMC_STRAP_BIT5")
		)
		(pad "U21" smd circle
			(at 7.599934 4.400042 90)
			(size 0.3556 0.3556)
			(layers "F.Cu" "F.Mask" "F.Paste")
			(net "BMC_STRAP_BIT17")
		)
		(pad "U22" smd circle
			(at 8.400034 4.400042 90)
			(size 0.3556 0.3556)
			(layers "F.Cu" "F.Mask" "F.Paste")
			(net "PECI_SEL")
		)
		(pad "V1" smd circle
			(at -8.400034 5.199888 90)
			(size 0.3556 0.3556)
			(layers "F.Cu" "F.Mask" "F.Paste")
			(net "SP1_BMC_HOST_UART_TX")
		)
		(pad "V2" smd circle
			(at -7.599934 5.199888 90)
			(size 0.3556 0.3556)
			(layers "F.Cu" "F.Mask" "F.Paste")
			(net "FAN_PWM_OUT_SYS0")
		)
		(pad "V3" smd circle
			(at -6.800088 5.199888 90)
			(size 0.3556 0.3556)
			(layers "F.Cu" "F.Mask" "F.Paste")
			(net "FM_BIOS_PREFRB2_GOOD")
		)
		(pad "V4" smd circle
			(at -5.999988 5.199888 90)
			(size 0.3556 0.3556)
			(layers "F.Cu" "F.Mask" "F.Paste")
			(net "FM_BOARD_SKU_ID0")
		)
		(pad "V5" smd circle
			(at -5.199888 5.199888 90)
			(size 0.3556 0.3556)
			(layers "F.Cu" "F.Mask" "F.Paste")
			(net "FAN_TACH2")
		)
		(pad "V6" smd circle
			(at -4.400042 5.199888 90)
			(size 0.3556 0.3556)
			(layers "F.Cu" "F.Mask" "F.Paste")
			(net "BMC_RSMRST_B_N")
		)
		(pad "V7" smd circle
			(at -3.599942 5.199888 90)
			(size 0.3556 0.3556)
			(layers "F.Cu" "F.Mask" "F.Paste")
			(net "BMC_M_DQ14")
		)
		(pad "V8" smd circle
			(at -2.800096 5.199888 90)
			(size 0.3556 0.3556)
			(layers "F.Cu" "F.Mask" "F.Paste")
			(net "GND")
		)
		(pad "V9" smd circle
			(at -1.999996 5.199888 90)
			(size 0.3556 0.3556)
			(layers "F.Cu" "F.Mask" "F.Paste")
			(net "BMC_M_DQ7")
		)
		(pad "V10" smd circle
			(at -1.199896 5.199888 90)
			(size 0.3556 0.3556)
			(layers "F.Cu" "F.Mask" "F.Paste")
			(net "GND")
		)
		(pad "V11" smd circle
			(at -0.40005 5.199888 90)
			(size 0.3556 0.3556)
			(layers "F.Cu" "F.Mask" "F.Paste")
			(net "BMC_M_ODT")
		)
		(pad "V12" smd circle
			(at 0.40005 5.199888 90)
			(size 0.3556 0.3556)
			(layers "F.Cu" "F.Mask" "F.Paste")
			(net "GND")
		)
		(pad "V13" smd circle
			(at 1.199896 5.199888 90)
			(size 0.3556 0.3556)
			(layers "F.Cu" "F.Mask" "F.Paste")
			(net "BMC_M_A0")
		)
		(pad "V14" smd circle
			(at 1.999996 5.199888 90)
			(size 0.3556 0.3556)
			(layers "F.Cu" "F.Mask" "F.Paste")
			(net "GND")
		)
		(pad "V15" smd circle
			(at 2.800096 5.199888 90)
			(size 0.3556 0.3556)
			(layers "F.Cu" "F.Mask" "F.Paste")
			(net "BMC_M_A5")
		)
		(pad "V16" smd circle
			(at 3.599942 5.199888 90)
			(size 0.3556 0.3556)
			(layers "F.Cu" "F.Mask" "F.Paste")
			(net "GND")
		)
		(pad "V17" smd circle
			(at 4.400042 5.199888 90)
			(size 0.3556 0.3556)
			(layers "F.Cu" "F.Mask" "F.Paste")
			(net "P1V15_AUX_BMC")
		)
		(pad "V18" smd circle
			(at 5.199888 5.199888 90)
			(size 0.3556 0.3556)
			(layers "F.Cu" "F.Mask" "F.Paste")
			(net "RST_BMC_EXTRST_N")
		)
		(pad "V19" smd circle
			(at 5.999988 5.199888 90)
			(size 0.3556 0.3556)
			(layers "F.Cu" "F.Mask" "F.Paste")
			(net "RST_BMC_PLTRST_BUF_N")
		)
		(pad "V20" smd circle
			(at 6.800088 5.199888 90)
			(size 0.3556 0.3556)
			(layers "F.Cu" "F.Mask" "F.Paste")
			(net "FM_THROTTLE_N")
		)
		(pad "V21" smd circle
			(at 7.599934 5.199888 90)
			(size 0.3556 0.3556)
			(layers "F.Cu" "F.Mask" "F.Paste")
			(net "IRQ_SML1_PMBUS_ALERT_N")
		)
		(pad "V22" smd circle
			(at 8.400034 5.199888 90)
			(size 0.3556 0.3556)
			(layers "F.Cu" "F.Mask" "F.Paste")
			(net "BMC_STRAP_BIT20")
		)
		(pad "W1" smd circle
			(at -8.400034 5.999988 90)
			(size 0.3556 0.3556)
			(layers "F.Cu" "F.Mask" "F.Paste")
			(net "SP1_BMC_HOST_UART_RX")
		)
		(pad "W2" smd circle
			(at -7.599934 5.999988 90)
			(size 0.3556 0.3556)
			(layers "F.Cu" "F.Mask" "F.Paste")
			(net "FAN_PWM_OUT_SYS1")
		)
		(pad "W3" smd circle
			(at -6.800088 5.999988 90)
			(size 0.3556 0.3556)
			(layers "F.Cu" "F.Mask" "F.Paste")
			(net "FM_BACKUP_BIOS_SEL_N")
		)
		(pad "W4" smd circle
			(at -5.999988 5.999988 90)
			(size 0.3556 0.3556)
			(layers "F.Cu" "F.Mask" "F.Paste")
			(net "FM_XRC_READY_N")
		)
		(pad "W5" smd circle
			(at -5.199888 5.999988 90)
			(size 0.3556 0.3556)
			(layers "F.Cu" "F.Mask" "F.Paste")
			(net "FM_BOARD_SKU_ID1")
		)
		(pad "W6" smd circle
			(at -4.400042 5.999988 90)
			(size 0.3556 0.3556)
			(layers "F.Cu" "F.Mask" "F.Paste")
			(net "BMC_PWR_DEBUG_N")
		)
		(pad "W7" smd circle
			(at -3.599942 5.999988 90)
			(size 0.3556 0.3556)
			(layers "F.Cu" "F.Mask" "F.Paste")
			(net "BMC_M_DQ13")
		)
		(pad "W8" smd circle
			(at -2.800096 5.999988 90)
			(size 0.3556 0.3556)
			(layers "F.Cu" "F.Mask" "F.Paste")
			(net "BMC_M_DQ11")
		)
		(pad "W9" smd circle
			(at -1.999996 5.999988 90)
			(size 0.3556 0.3556)
			(layers "F.Cu" "F.Mask" "F.Paste")
			(net "BMC_M_DQ6")
		)
		(pad "W10" smd circle
			(at -1.199896 5.999988 90)
			(size 0.3556 0.3556)
			(layers "F.Cu" "F.Mask" "F.Paste")
			(net "BMC_M_DQ1")
		)
		(pad "W11" smd circle
			(at -0.40005 5.999988 90)
			(size 0.3556 0.3556)
			(layers "F.Cu" "F.Mask" "F.Paste")
			(net "BMC_MIOZ")
		)
		(pad "W12" smd circle
			(at 0.40005 5.999988 90)
			(size 0.3556 0.3556)
			(layers "F.Cu" "F.Mask" "F.Paste")
			(net "BMC_M_RAS_N")
		)
		(pad "W13" smd circle
			(at 1.199896 5.999988 90)
			(size 0.3556 0.3556)
			(layers "F.Cu" "F.Mask" "F.Paste")
			(net "BMC_M_BG0")
		)
		(pad "W14" smd circle
			(at 1.999996 5.999988 90)
			(size 0.3556 0.3556)
			(layers "F.Cu" "F.Mask" "F.Paste")
			(net "BMC_M_A2")
		)
		(pad "W15" smd circle
			(at 2.800096 5.999988 90)
			(size 0.3556 0.3556)
			(layers "F.Cu" "F.Mask" "F.Paste")
			(net "BMC_M_A4")
		)
		(pad "W16" smd circle
			(at 3.599942 5.999988 90)
			(size 0.3556 0.3556)
			(layers "F.Cu" "F.Mask" "F.Paste")
			(net "BMC_M_A8")
		)
		(pad "W17" smd circle
			(at 4.400042 5.999988 90)
			(size 0.3556 0.3556)
			(layers "F.Cu" "F.Mask" "F.Paste")
			(net "VCC_PA_3V3")
		)
		(pad "W18" smd circle
			(at 5.199888 5.999988 90)
			(size 0.3556 0.3556)
			(layers "F.Cu" "F.Mask" "F.Paste")
			(net "CLK_24M_25M_BMC_CLKIN")
		)
		(pad "W19" smd circle
			(at 5.999988 5.999988 90)
			(size 0.3556 0.3556)
			(layers "F.Cu" "F.Mask" "F.Paste")
			(net "XDP_PRESENT_N")
		)
		(pad "W20" smd circle
			(at 6.800088 5.999988 90)
			(size 0.3556 0.3556)
			(layers "F.Cu" "F.Mask" "F.Paste")
			(net "Net_544")
		)
		(pad "W21" smd circle
			(at 7.599934 5.999988 90)
			(size 0.3556 0.3556)
			(layers "F.Cu" "F.Mask" "F.Paste")
			(net "BMC_STRAP_BIT27")
		)
		(pad "W22" smd circle
			(at 8.400034 5.999988 90)
			(size 0.3556 0.3556)
			(layers "F.Cu" "F.Mask" "F.Paste")
			(net "BMC_STRAP_BIT18")
		)
		(pad "Y1" smd circle
			(at -8.400034 6.800088 90)
			(size 0.4064 0.4064)
			(layers "F.Cu" "F.Mask" "F.Paste")
			(net "FM_CPU0_RC_ERROR_N")
		)
		(pad "Y2" smd circle
			(at -7.599934 6.800088 90)
			(size 0.4064 0.4064)
			(layers "F.Cu" "F.Mask" "F.Paste")
			(net "FM_OC_DETECT_EN_N")
		)
		(pad "Y3" smd circle
			(at -6.800088 6.800088 90)
			(size 0.4064 0.4064)
			(layers "F.Cu" "F.Mask" "F.Paste")
			(net "PUMP_PWM_OUT")
		)
		(pad "Y4" smd circle
			(at -5.999988 6.800088 90)
			(size 0.3556 0.3556)
			(layers "F.Cu" "F.Mask" "F.Paste")
			(net "PUMP_TACH1")
		)
		(pad "Y5" smd circle
			(at -5.199888 6.800088 90)
			(size 0.3556 0.3556)
			(layers "F.Cu" "F.Mask" "F.Paste")
			(net "BMC_PREQ_N")
		)
		(pad "Y6" smd circle
			(at -4.400042 6.800088 90)
			(size 0.3556 0.3556)
			(layers "F.Cu" "F.Mask" "F.Paste")
			(net "FM_BOARD_SKU_ID4")
		)
		(pad "Y7" smd circle
			(at -3.599942 6.800088 90)
			(size 0.3556 0.3556)
			(layers "F.Cu" "F.Mask" "F.Paste")
			(net "BMC_M_DQ10")
		)
		(pad "Y8" smd circle
			(at -2.800096 6.800088 90)
			(size 0.3556 0.3556)
			(layers "F.Cu" "F.Mask" "F.Paste")
			(net "BMC_M_DQ9")
		)
		(pad "Y9" smd circle
			(at -1.999996 6.800088 90)
			(size 0.3556 0.3556)
			(layers "F.Cu" "F.Mask" "F.Paste")
			(net "BMC_M_DQ5")
		)
		(pad "Y10" smd circle
			(at -1.199896 6.800088 90)
			(size 0.3556 0.3556)
			(layers "F.Cu" "F.Mask" "F.Paste")
			(net "BMC_M_DQ2")
		)
		(pad "Y11" smd circle
			(at -0.40005 6.800088 90)
			(size 0.3556 0.3556)
			(layers "F.Cu" "F.Mask" "F.Paste")
			(net "BMC_M_CKE")
		)
		(pad "Y12" smd circle
			(at 0.40005 6.800088 90)
			(size 0.3556 0.3556)
			(layers "F.Cu" "F.Mask" "F.Paste")
			(net "BMC_M_WE_N")
		)
		(pad "Y13" smd circle
			(at 1.199896 6.800088 90)
			(size 0.3556 0.3556)
			(layers "F.Cu" "F.Mask" "F.Paste")
			(net "BMC_M_BA1")
		)
		(pad "Y14" smd circle
			(at 1.999996 6.800088 90)
			(size 0.3556 0.3556)
			(layers "F.Cu" "F.Mask" "F.Paste")
			(net "BMC_M_A12")
		)
		(pad "Y15" smd circle
			(at 2.800096 6.800088 90)
			(size 0.3556 0.3556)
			(layers "F.Cu" "F.Mask" "F.Paste")
			(net "BMC_M_MACT_N")
		)
		(pad "Y16" smd circle
			(at 3.599942 6.800088 90)
			(size 0.3556 0.3556)
			(layers "F.Cu" "F.Mask" "F.Paste")
			(net "BMC_M_A9")
		)
		(pad "Y17" smd circle
			(at 4.400042 6.800088 90)
			(size 0.3556 0.3556)
			(layers "F.Cu" "F.Mask" "F.Paste")
			(net "VCC_PA_3V3")
		)
		(pad "Y18" smd circle
			(at 5.199888 6.800088 90)
			(size 0.3556 0.3556)
			(layers "F.Cu" "F.Mask" "F.Paste")
			(net "FM_BMC_HEARTBEAT_N")
		)
		(pad "Y19" smd circle
			(at 5.999988 6.800088 90)
			(size 0.3556 0.3556)
			(layers "F.Cu" "F.Mask" "F.Paste")
			(net "BMC_PRDY_N")
		)
		(pad "Y20" smd circle
			(at 6.800088 6.800088 90)
			(size 0.4064 0.4064)
			(layers "F.Cu" "F.Mask" "F.Paste")
			(net "FM_BMC_CPLD_GPO")
		)
		(pad "Y21" smd circle
			(at 7.599934 6.800088 90)
			(size 0.4064 0.4064)
			(layers "F.Cu" "F.Mask" "F.Paste")
			(net "FM_CPU1_SKTOCC_LVT3_N")
		)
		(pad "Y22" smd circle
			(at 8.400034 6.800088 90)
			(size 0.4064 0.4064)
			(layers "F.Cu" "F.Mask" "F.Paste")
			(net "FP_PWR_ID_LED_N")
		)
	)
	(footprint ""
		(layer "F.Cu")
		(at 408.7495 -109.855 -90)
		(property "Reference" "R2N28"
			(at 0 0 270)
			(layer "F.SilkS")
			(hide yes)
			(effects
				(font
					(size 1.27 1.27)
				)
			)
		)
		(property "Value" ""
			(at 0 0 270)
			(layer "F.Fab")
			(effects
				(font
					(size 1.27 1.27)
				)
			)
		)
		(duplicate_pad_numbers_are_jumpers no)
		(fp_poly
			(pts
				(xy -0.2794 -0.1016) (xy 0.2794 -0.1016) (xy 0.2794 0.9906) (xy -0.2794 0.9906)
			)
			(stroke
				(width 0)
				(type default)
			)
			(fill no)
			(layer "F.CrtYd")
		)
		(fp_line
			(start -0.2794 0.9906)
			(end 0.2794 0.9906)
			(stroke
				(width 0.1)
				(type default)
			)
			(layer "F.Fab")
		)
		(fp_line
			(start 0.2794 0.9906)
			(end 0.2794 -0.1016)
			(stroke
				(width 0.1)
				(type default)
			)
			(layer "F.Fab")
		)
		(fp_line
			(start -0.2794 -0.1016)
			(end -0.2794 0.9906)
			(stroke
				(width 0.1)
				(type default)
			)
			(layer "F.Fab")
		)
		(fp_line
			(start 0.2794 -0.1016)
			(end -0.2794 -0.1016)
			(stroke
				(width 0.1)
				(type default)
			)
			(layer "F.Fab")
		)
		(pad "1" smd rect
			(at 0 0 270)
			(size 0.508 0.508)
			(layers "F.Cu" "F.Mask" "F.Paste")
			(net "P3V3_STBY")
		)
		(pad "2" smd rect
			(at 0 0.889 270)
			(size 0.508 0.508)
			(layers "F.Cu" "F.Mask" "F.Paste")
			(net "FM_PASSWORD_CLEAR_N")
		)
		(zone
			(layer "F.Cu")
			(hatch none 0.5)
			(connect_pads
				(clearance 0)
			)
			(min_thickness 0.25)
			(keepout
				(tracks not_allowed)
				(vias allowed)
				(pads allowed)
				(copperpour not_allowed)
				(footprints allowed)
			)
			(placement
				(enabled no)
				(sheetname "")
			)
			(fill
				(thermal_gap 0.5)
				(thermal_bridge_width 0.5)
				(island_removal_mode 0)
			)
			(polygon
				(pts
					(xy 408.1145 -110.109) (xy 408.1145 -109.601) (xy 408.4955 -109.601) (xy 408.4955 -110.109)
				)
			)
		)
		(zone
			(layer "F.Cu")
			(hatch none 0.5)
			(connect_pads
				(clearance 0)
			)
			(min_thickness 0.25)
			(keepout
				(tracks allowed)
				(vias not_allowed)
				(pads allowed)
				(copperpour not_allowed)
				(footprints allowed)
			)
			(placement
				(enabled no)
				(sheetname "")
			)
			(fill
				(thermal_gap 0.5)
				(thermal_bridge_width 0.5)
				(island_removal_mode 0)
			)
			(polygon
				(pts
					(xy 408.4955 -110.109) (xy 408.4955 -109.601) (xy 408.1145 -109.601) (xy 408.1145 -110.109)
				)
			)
		)
	)
	(footprint ""
		(layer "F.Cu")
		(at 407.8605 -108.204 90)
		(property "Reference" "R8C12"
			(at 0 0 90)
			(layer "F.SilkS")
			(hide yes)
			(effects
				(font
					(size 1.27 1.27)
				)
			)
		)
		(property "Value" ""
			(at 0 0 90)
			(layer "F.Fab")
			(effects
				(font
					(size 1.27 1.27)
				)
			)
		)
		(duplicate_pad_numbers_are_jumpers no)
		(fp_poly
			(pts
				(xy -0.2794 -0.1016) (xy 0.2794 -0.1016) (xy 0.2794 0.9906) (xy -0.2794 0.9906)
			)
			(stroke
				(width 0)
				(type default)
			)
			(fill no)
			(layer "F.CrtYd")
		)
		(fp_line
			(start 0.2794 -0.1016)
			(end -0.2794 -0.1016)
			(stroke
				(width 0.1)
				(type default)
			)
			(layer "F.Fab")
		)
		(fp_line
			(start -0.2794 -0.1016)
			(end -0.2794 0.9906)
			(stroke
				(width 0.1)
				(type default)
			)
			(layer "F.Fab")
		)
		(fp_line
			(start 0.2794 0.9906)
			(end 0.2794 -0.1016)
			(stroke
				(width 0.1)
				(type default)
			)
			(layer "F.Fab")
		)
		(fp_line
			(start -0.2794 0.9906)
			(end 0.2794 0.9906)
			(stroke
				(width 0.1)
				(type default)
			)
			(layer "F.Fab")
		)
		(pad "1" smd rect
			(at 0 0 90)
			(size 0.508 0.508)
			(layers "F.Cu" "F.Mask" "F.Paste")
			(net "SMB_SMLINK0_STBY_LVC3_SCL_R1")
		)
		(pad "2" smd rect
			(at 0 0.889 90)
			(size 0.508 0.508)
			(layers "F.Cu" "F.Mask" "F.Paste")
			(net "SMB_SMLINK0_STBY_LVC3_SCL")
		)
		(zone
			(layer "F.Cu")
			(hatch none 0.5)
			(connect_pads
				(clearance 0)
			)
			(min_thickness 0.25)
			(keepout
				(tracks allowed)
				(vias not_allowed)
				(pads allowed)
				(copperpour not_allowed)
				(footprints allowed)
			)
			(placement
				(enabled no)
				(sheetname "")
			)
			(fill
				(thermal_gap 0.5)
				(thermal_bridge_width 0.5)
				(island_removal_mode 0)
			)
			(polygon
				(pts
					(xy 408.1145 -107.95) (xy 408.1145 -108.458) (xy 408.4955 -108.458) (xy 408.4955 -107.95)
				)
			)
		)
		(zone
			(layer "F.Cu")
			(hatch none 0.5)
			(connect_pads
				(clearance 0)
			)
			(min_thickness 0.25)
			(keepout
				(tracks not_allowed)
				(vias allowed)
				(pads allowed)
				(copperpour not_allowed)
				(footprints allowed)
			)
			(placement
				(enabled no)
				(sheetname "")
			)
			(fill
				(thermal_gap 0.5)
				(thermal_bridge_width 0.5)
				(island_removal_mode 0)
			)
			(polygon
				(pts
					(xy 408.4955 -107.95) (xy 408.4955 -108.458) (xy 408.1145 -108.458) (xy 408.1145 -107.95)
				)
			)
		)
	)
	(footprint ""
		(layer "F.Cu")
		(at 7.333234 -112.123728 90)
		(property "Reference" "C1B18"
			(at 1.47828 0.78994 0)
			(unlocked yes)
			(layer "F.SilkS")
			(effects
				(font
					(size 0.4064 0.254)
					(thickness 0.1524)
				)
			)
		)
		(property "Value" ""
			(at 0 0 90)
			(layer "F.Fab")
			(effects
				(font
					(size 1.27 1.27)
				)
			)
		)
		(duplicate_pad_numbers_are_jumpers no)
		(fp_poly
			(pts
				(xy -0.7239 -0.2159) (xy 0.7239 -0.2159) (xy 0.7239 1.9939) (xy -0.7239 1.9939)
			)
			(stroke
				(width 0)
				(type default)
			)
			(fill no)
			(layer "F.CrtYd")
		)
		(fp_line
			(start 0.7239 -0.2159)
			(end -0.7239 -0.2159)
			(stroke
				(width 0.1)
				(type default)
			)
			(layer "F.Fab")
		)
		(fp_line
			(start -0.7239 -0.2159)
			(end -0.7239 1.9939)
			(stroke
				(width 0.1)
				(type default)
			)
			(layer "F.Fab")
		)
		(fp_line
			(start 0.7239 1.9939)
			(end 0.7239 -0.2159)
			(stroke
				(width 0.1)
				(type default)
			)
			(layer "F.Fab")
		)
		(fp_line
			(start -0.7239 1.9939)
			(end 0.7239 1.9939)
			(stroke
				(width 0.1)
				(type default)
			)
			(layer "F.Fab")
		)
		(pad "1" smd rect
			(at 0 0 90)
			(size 1.27 1.016)
			(layers "F.Cu" "F.Mask" "F.Paste")
			(net "P12V_FAN")
		)
		(pad "2" smd rect
			(at 0 1.778 90)
			(size 1.27 1.016)
			(layers "F.Cu" "F.Mask" "F.Paste")
			(net "GND")
		)
		(zone
			(layer "F.Cu")
			(hatch none 0.5)
			(connect_pads
				(clearance 0)
			)
			(min_thickness 0.25)
			(keepout
				(tracks not_allowed)
				(vias allowed)
				(pads allowed)
				(copperpour not_allowed)
				(footprints allowed)
			)
			(placement
				(enabled no)
				(sheetname "")
			)
			(fill
				(thermal_gap 0.5)
				(thermal_bridge_width 0.5)
				(island_removal_mode 0)
			)
			(polygon
				(pts
					(xy 7.841234 -111.488728) (xy 7.841234 -112.758728) (xy 8.603234 -112.758728) (xy 8.603234 -111.488728)
				)
			)
		)
	)
	(footprint ""
		(layer "F.Cu")
		(at 409.685236 -47.825914 180)
		(property "Reference" "R1T11"
			(at 0 0 180)
			(layer "F.SilkS")
			(hide yes)
			(effects
				(font
					(size 1.27 1.27)
				)
			)
		)
		(property "Value" ""
			(at 0 0 180)
			(layer "F.Fab")
			(effects
				(font
					(size 1.27 1.27)
				)
			)
		)
		(duplicate_pad_numbers_are_jumpers no)
		(fp_poly
			(pts
				(xy -0.2794 -0.1016) (xy 0.2794 -0.1016) (xy 0.2794 0.9906) (xy -0.2794 0.9906)
			)
			(stroke
				(width 0)
				(type default)
			)
			(fill no)
			(layer "F.CrtYd")
		)
		(fp_line
			(start 0.2794 0.9906)
			(end 0.2794 -0.1016)
			(stroke
				(width 0.1)
				(type default)
			)
			(layer "F.Fab")
		)
		(fp_line
			(start 0.2794 -0.1016)
			(end -0.2794 -0.1016)
			(stroke
				(width 0.1)
				(type default)
			)
			(layer "F.Fab")
		)
		(fp_line
			(start -0.2794 0.9906)
			(end 0.2794 0.9906)
			(stroke
				(width 0.1)
				(type default)
			)
			(layer "F.Fab")
		)
		(fp_line
			(start -0.2794 -0.1016)
			(end -0.2794 0.9906)
			(stroke
				(width 0.1)
				(type default)
			)
			(layer "F.Fab")
		)
		(pad "1" smd rect
			(at 0 0 180)
			(size 0.508 0.508)
			(layers "F.Cu" "F.Mask" "F.Paste")
			(net "FM_BOARD_REV_ID2")
		)
		(pad "2" smd rect
			(at 0 0.889 180)
			(size 0.508 0.508)
			(layers "F.Cu" "F.Mask" "F.Paste")
			(net "GND")
		)
	)
	(footprint ""
		(layer "F.Cu")
		(at 442.364876 -13.361924 90)
		(property "Reference" "R2U51"
			(at 0 0 90)
			(layer "F.SilkS")
			(hide yes)
			(effects
				(font
					(size 1.27 1.27)
				)
			)
		)
		(property "Value" ""
			(at 0 0 90)
			(layer "F.Fab")
			(effects
				(font
					(size 1.27 1.27)
				)
			)
		)
		(duplicate_pad_numbers_are_jumpers no)
		(fp_poly
			(pts
				(xy -0.2794 -0.1016) (xy 0.2794 -0.1016) (xy 0.2794 0.9906) (xy -0.2794 0.9906)
			)
			(stroke
				(width 0)
				(type default)
			)
			(fill no)
			(layer "F.CrtYd")
		)
		(fp_line
			(start 0.2794 -0.1016)
			(end -0.2794 -0.1016)
			(stroke
				(width 0.1)
				(type default)
			)
			(layer "F.Fab")
		)
		(fp_line
			(start -0.2794 -0.1016)
			(end -0.2794 0.9906)
			(stroke
				(width 0.1)
				(type default)
			)
			(layer "F.Fab")
		)
		(fp_line
			(start 0.2794 0.9906)
			(end 0.2794 -0.1016)
			(stroke
				(width 0.1)
				(type default)
			)
			(layer "F.Fab")
		)
		(fp_line
			(start -0.2794 0.9906)
			(end 0.2794 0.9906)
			(stroke
				(width 0.1)
				(type default)
			)
			(layer "F.Fab")
		)
		(pad "1" smd rect
			(at 0 0 90)
			(size 0.508 0.508)
			(layers "F.Cu" "F.Mask" "F.Paste")
			(net "H_CPU0_MEMABC_MEMHOT_G_PCH_N")
		)
		(pad "2" smd rect
			(at 0 0.889 90)
			(size 0.508 0.508)
			(layers "F.Cu" "F.Mask" "F.Paste")
			(net "H_CPU0_MEMABC_MEMHOT_G_N")
		)
		(zone
			(layer "F.Cu")
			(hatch none 0.5)
			(connect_pads
				(clearance 0)
			)
			(min_thickness 0.25)
			(keepout
				(tracks allowed)
				(vias not_allowed)
				(pads allowed)
				(copperpour not_allowed)
				(footprints allowed)
			)
			(placement
				(enabled no)
				(sheetname "")
			)
			(fill
				(thermal_gap 0.5)
				(thermal_bridge_width 0.5)
				(island_removal_mode 0)
			)
			(polygon
				(pts
					(xy 442.618876 -13.107924) (xy 442.618876 -13.615924) (xy 442.999876 -13.615924) (xy 442.999876 -13.107924)
				)
			)
		)
		(zone
			(layer "F.Cu")
			(hatch none 0.5)
			(connect_pads
				(clearance 0)
			)
			(min_thickness 0.25)
			(keepout
				(tracks not_allowed)
				(vias allowed)
				(pads allowed)
				(copperpour not_allowed)
				(footprints allowed)
			)
			(placement
				(enabled no)
				(sheetname "")
			)
			(fill
				(thermal_gap 0.5)
				(thermal_bridge_width 0.5)
				(island_removal_mode 0)
			)
			(polygon
				(pts
					(xy 442.999876 -13.107924) (xy 442.999876 -13.615924) (xy 442.618876 -13.615924) (xy 442.618876 -13.107924)
				)
			)
		)
	)
	(footprint ""
		(layer "F.Cu")
		(at 401.066 -49.0855 180)
		(property "Reference" "R7F6"
			(at 0 0 180)
			(layer "F.SilkS")
			(hide yes)
			(effects
				(font
					(size 1.27 1.27)
				)
			)
		)
		(property "Value" ""
			(at 0 0 180)
			(layer "F.Fab")
			(effects
				(font
					(size 1.27 1.27)
				)
			)
		)
		(duplicate_pad_numbers_are_jumpers no)
		(fp_poly
			(pts
				(xy -0.2794 -0.1016) (xy 0.2794 -0.1016) (xy 0.2794 0.9906) (xy -0.2794 0.9906)
			)
			(stroke
				(width 0)
				(type default)
			)
			(fill no)
			(layer "F.CrtYd")
		)
		(fp_line
			(start 0.2794 0.9906)
			(end 0.2794 -0.1016)
			(stroke
				(width 0.1)
				(type default)
			)
			(layer "F.Fab")
		)
		(fp_line
			(start 0.2794 -0.1016)
			(end -0.2794 -0.1016)
			(stroke
				(width 0.1)
				(type default)
			)
			(layer "F.Fab")
		)
		(fp_line
			(start -0.2794 0.9906)
			(end 0.2794 0.9906)
			(stroke
				(width 0.1)
				(type default)
			)
			(layer "F.Fab")
		)
		(fp_line
			(start -0.2794 -0.1016)
			(end -0.2794 0.9906)
			(stroke
				(width 0.1)
				(type default)
			)
			(layer "F.Fab")
		)
		(pad "1" smd rect
			(at 0 0 180)
			(size 0.508 0.508)
			(layers "F.Cu" "F.Mask" "F.Paste")
			(net "P3V3_STBY")
		)
		(pad "2" smd rect
			(at 0 0.889 180)
			(size 0.508 0.508)
			(layers "F.Cu" "F.Mask" "F.Paste")
			(net "PU_SPI0_RST")
		)
		(zone
			(layer "F.Cu")
			(hatch none 0.5)
			(connect_pads
				(clearance 0)
			)
			(min_thickness 0.25)
			(keepout
				(tracks not_allowed)
				(vias allowed)
				(pads allowed)
				(copperpour not_allowed)
				(footprints allowed)
			)
			(placement
				(enabled no)
				(sheetname "")
			)
			(fill
				(thermal_gap 0.5)
				(thermal_bridge_width 0.5)
				(island_removal_mode 0)
			)
			(polygon
				(pts
					(xy 401.32 -49.7205) (xy 400.812 -49.7205) (xy 400.812 -49.3395) (xy 401.32 -49.3395)
				)
			)
		)
		(zone
			(layer "F.Cu")
			(hatch none 0.5)
			(connect_pads
				(clearance 0)
			)
			(min_thickness 0.25)
			(keepout
				(tracks allowed)
				(vias not_allowed)
				(pads allowed)
				(copperpour not_allowed)
				(footprints allowed)
			)
			(placement
				(enabled no)
				(sheetname "")
			)
			(fill
				(thermal_gap 0.5)
				(thermal_bridge_width 0.5)
				(island_removal_mode 0)
			)
			(polygon
				(pts
					(xy 401.32 -49.3395) (xy 400.812 -49.3395) (xy 400.812 -49.7205) (xy 401.32 -49.7205)
				)
			)
		)
	)
	(footprint ""
		(layer "F.Cu")
		(at 170.234102 -57.812686 90)
		(property "Reference" "CT62"
			(at -0.8382 -0.67818 90)
			(unlocked yes)
			(layer "F.SilkS")
			(effects
				(font
					(size 0.4064 0.254)
					(thickness 0.1524)
				)
				(justify left)
			)
		)
		(property "Value" ""
			(at 0 0 90)
			(layer "F.Fab")
			(effects
				(font
					(size 1.27 1.27)
				)
			)
		)
		(duplicate_pad_numbers_are_jumpers no)
		(fp_poly
			(pts
				(xy 0.3048 -0.1016) (xy 0.3048 0.9906) (xy -0.3048 0.9906) (xy -0.3048 -0.1016)
			)
			(stroke
				(width 0)
				(type default)
			)
			(fill no)
			(layer "F.CrtYd")
		)
		(fp_line
			(start 0.3048 -0.1016)
			(end -0.3048 -0.1016)
			(stroke
				(width 0.1)
				(type default)
			)
			(layer "F.Fab")
		)
		(fp_line
			(start -0.3048 -0.1016)
			(end -0.3048 0.9906)
			(stroke
				(width 0.1)
				(type default)
			)
			(layer "F.Fab")
		)
		(fp_line
			(start 0.3048 0.9906)
			(end 0.3048 -0.1016)
			(stroke
				(width 0.1)
				(type default)
			)
			(layer "F.Fab")
		)
		(fp_line
			(start -0.3048 0.9906)
			(end 0.3048 0.9906)
			(stroke
				(width 0.1)
				(type default)
			)
			(layer "F.Fab")
		)
		(pad "1" smd rect
			(at 0 0 90)
			(size 0.508 0.508)
			(layers "F.Cu" "F.Mask" "F.Paste")
			(net "VR_PVCCIO_CPU1_PH1_SW")
		)
		(pad "2" smd rect
			(at 0 0.889 90)
			(size 0.508 0.508)
			(layers "F.Cu" "F.Mask" "F.Paste")
			(net "VR_PVCCIO_CPU1_PH1_SW_RC")
		)
		(zone
			(layer "F.Cu")
			(hatch none 0.5)
			(connect_pads
				(clearance 0)
			)
			(min_thickness 0.25)
			(keepout
				(tracks allowed)
				(vias not_allowed)
				(pads allowed)
				(copperpour not_allowed)
				(footprints allowed)
			)
			(placement
				(enabled no)
				(sheetname "")
			)
			(fill
				(thermal_gap 0.5)
				(thermal_bridge_width 0.5)
				(island_removal_mode 0)
			)
			(polygon
				(pts
					(xy 170.488102 -57.558686) (xy 170.488102 -58.066686) (xy 170.869102 -58.066686) (xy 170.869102 -57.558686)
				)
			)
		)
		(zone
			(layer "F.Cu")
			(hatch none 0.5)
			(connect_pads
				(clearance 0)
			)
			(min_thickness 0.25)
			(keepout
				(tracks not_allowed)
				(vias allowed)
				(pads allowed)
				(copperpour not_allowed)
				(footprints allowed)
			)
			(placement
				(enabled no)
				(sheetname "")
			)
			(fill
				(thermal_gap 0.5)
				(thermal_bridge_width 0.5)
				(island_removal_mode 0)
			)
			(polygon
				(pts
					(xy 170.869102 -57.558686) (xy 170.869102 -58.066686) (xy 170.488102 -58.066686) (xy 170.488102 -57.558686)
				)
			)
		)
	)
	(footprint ""
		(layer "F.Cu")
		(at 44.1198 -52.79898 -90)
		(property "Reference" "R1E3"
			(at 0 0 270)
			(layer "F.SilkS")
			(hide yes)
			(effects
				(font
					(size 1.27 1.27)
				)
			)
		)
		(property "Value" ""
			(at 0 0 270)
			(layer "F.Fab")
			(effects
				(font
					(size 1.27 1.27)
				)
			)
		)
		(duplicate_pad_numbers_are_jumpers no)
		(fp_poly
			(pts
				(xy -0.4953 -0.2032) (xy 0.4953 -0.2032) (xy 0.4953 1.6002) (xy -0.4953 1.6002)
			)
			(stroke
				(width 0)
				(type default)
			)
			(fill no)
			(layer "F.CrtYd")
		)
		(fp_line
			(start -0.4953 1.6002)
			(end -0.4953 -0.2032)
			(stroke
				(width 0.1)
				(type default)
			)
			(layer "F.Fab")
		)
		(fp_line
			(start 0.4953 1.6002)
			(end -0.4953 1.6002)
			(stroke
				(width 0.1)
				(type default)
			)
			(layer "F.Fab")
		)
		(fp_line
			(start -0.4953 -0.2032)
			(end 0.4953 -0.2032)
			(stroke
				(width 0.1)
				(type default)
			)
			(layer "F.Fab")
		)
		(fp_line
			(start 0.4953 -0.2032)
			(end 0.4953 1.6002)
			(stroke
				(width 0.1)
				(type default)
			)
			(layer "F.Fab")
		)
		(pad "1" smd rect
			(at 0 0 270)
			(size 0.762 0.889)
			(layers "F.Cu" "F.Mask" "F.Paste")
			(net "PVCCIN_CPU1")
		)
		(pad "2" smd rect
			(at 0 1.397 270)
			(size 0.762 0.889)
			(layers "F.Cu" "F.Mask" "F.Paste")
			(net "GND")
		)
		(zone
			(layer "F.Cu")
			(hatch none 0.5)
			(connect_pads
				(clearance 0)
			)
			(min_thickness 0.25)
			(keepout
				(tracks not_allowed)
				(vias allowed)
				(pads allowed)
				(copperpour not_allowed)
				(footprints allowed)
			)
			(placement
				(enabled no)
				(sheetname "")
			)
			(fill
				(thermal_gap 0.5)
				(thermal_bridge_width 0.5)
				(island_removal_mode 0)
			)
			(polygon
				(pts
					(xy 43.1673 -53.17998) (xy 43.1673 -52.41798) (xy 43.6753 -52.41798) (xy 43.6753 -53.17998)
				)
			)
		)
		(zone
			(layer "F.Cu")
			(hatch none 0.5)
			(connect_pads
				(clearance 0)
			)
			(min_thickness 0.25)
			(keepout
				(tracks allowed)
				(vias not_allowed)
				(pads allowed)
				(copperpour not_allowed)
				(footprints allowed)
			)
			(placement
				(enabled no)
				(sheetname "")
			)
			(fill
				(thermal_gap 0.5)
				(thermal_bridge_width 0.5)
				(island_removal_mode 0)
			)
			(polygon
				(pts
					(xy 43.1673 -52.41798) (xy 43.6753 -52.41798) (xy 43.6753 -53.17998) (xy 43.1673 -53.17998)
				)
			)
		)
	)
	(footprint ""
		(layer "F.Cu")
		(at 9.398 -68.0593 180)
		(property "Reference" "R1D46"
			(at 0 0 180)
			(layer "F.SilkS")
			(hide yes)
			(effects
				(font
					(size 1.27 1.27)
				)
			)
		)
		(property "Value" ""
			(at 0 0 180)
			(layer "F.Fab")
			(effects
				(font
					(size 1.27 1.27)
				)
			)
		)
		(duplicate_pad_numbers_are_jumpers no)
		(fp_rect
			(start 0.2794 0.9906)
			(end -0.2794 -0.1016)
			(stroke
				(width 0)
				(type default)
			)
			(fill no)
			(layer "F.CrtYd")
		)
		(fp_line
			(start 0.2794 0.9906)
			(end 0.2794 -0.1016)
			(stroke
				(width 0.1)
				(type default)
			)
			(layer "F.Fab")
		)
		(fp_line
			(start 0.2794 -0.1016)
			(end -0.2794 -0.1016)
			(stroke
				(width 0.1)
				(type default)
			)
			(layer "F.Fab")
		)
		(fp_line
			(start -0.2794 0.9906)
			(end 0.2794 0.9906)
			(stroke
				(width 0.1)
				(type default)
			)
			(layer "F.Fab")
		)
		(fp_line
			(start -0.2794 -0.1016)
			(end -0.2794 0.9906)
			(stroke
				(width 0.1)
				(type default)
			)
			(layer "F.Fab")
		)
		(pad "1" smd rect
			(at 0 0 180)
			(size 0.508 0.508)
			(layers "F.Cu" "F.Mask" "F.Paste")
			(net "P12V_HSC_SENP0")
		)
		(pad "2" smd rect
			(at 0 0.889 180)
			(size 0.508 0.508)
			(layers "F.Cu" "F.Mask" "F.Paste")
			(net "A_HSC_HSP")
		)
		(zone
			(layer "F.Cu")
			(hatch none 0.5)
			(connect_pads
				(clearance 0)
			)
			(min_thickness 0.25)
			(keepout
				(tracks not_allowed)
				(vias allowed)
				(pads allowed)
				(copperpour not_allowed)
				(footprints allowed)
			)
			(placement
				(enabled no)
				(sheetname "")
			)
			(fill
				(thermal_gap 0.5)
				(thermal_bridge_width 0.5)
				(island_removal_mode 0)
			)
			(polygon
				(pts
					(xy 9.144 -68.6943) (xy 9.144 -68.3133) (xy 9.652 -68.3133) (xy 9.652 -68.6943)
				)
			)
		)
		(zone
			(layer "F.Cu")
			(hatch none 0.5)
			(connect_pads
				(clearance 0)
			)
			(min_thickness 0.25)
			(keepout
				(tracks allowed)
				(vias not_allowed)
				(pads allowed)
				(copperpour not_allowed)
				(footprints allowed)
			)
			(placement
				(enabled no)
				(sheetname "")
			)
			(fill
				(thermal_gap 0.5)
				(thermal_bridge_width 0.5)
				(island_removal_mode 0)
			)
			(polygon
				(pts
					(xy 9.144 -68.6943) (xy 9.144 -68.3133) (xy 9.652 -68.3133) (xy 9.652 -68.6943)
				)
			)
		)
	)
	(footprint ""
		(layer "F.Cu")
		(at 25.654 -30.861 90)
		(property "Reference" "R1F1"
			(at 0 0 90)
			(layer "F.SilkS")
			(hide yes)
			(effects
				(font
					(size 1.27 1.27)
				)
			)
		)
		(property "Value" ""
			(at 0 0 90)
			(layer "F.Fab")
			(effects
				(font
					(size 1.27 1.27)
				)
			)
		)
		(duplicate_pad_numbers_are_jumpers no)
		(fp_rect
			(start 0.2794 0.9906)
			(end -0.2794 -0.1016)
			(stroke
				(width 0)
				(type default)
			)
			(fill no)
			(layer "F.CrtYd")
		)
		(fp_line
			(start 0.2794 -0.1016)
			(end -0.2794 -0.1016)
			(stroke
				(width 0.1)
				(type default)
			)
			(layer "F.Fab")
		)
		(fp_line
			(start -0.2794 -0.1016)
			(end -0.2794 0.9906)
			(stroke
				(width 0.1)
				(type default)
			)
			(layer "F.Fab")
		)
		(fp_line
			(start 0.2794 0.9906)
			(end 0.2794 -0.1016)
			(stroke
				(width 0.1)
				(type default)
			)
			(layer "F.Fab")
		)
		(fp_line
			(start -0.2794 0.9906)
			(end 0.2794 0.9906)
			(stroke
				(width 0.1)
				(type default)
			)
			(layer "F.Fab")
		)
		(pad "1" smd rect
			(at 0 0 90)
			(size 0.508 0.508)
			(layers "F.Cu" "F.Mask" "F.Paste")
			(net "P3V3_STBY")
		)
		(pad "2" smd rect
			(at 0 0.889 90)
			(size 0.508 0.508)
			(layers "F.Cu" "F.Mask" "F.Paste")
			(net "FAN_TACH0")
		)
		(zone
			(layer "F.Cu")
			(hatch none 0.5)
			(connect_pads
				(clearance 0)
			)
			(min_thickness 0.25)
			(keepout
				(tracks not_allowed)
				(vias allowed)
				(pads allowed)
				(copperpour not_allowed)
				(footprints allowed)
			)
			(placement
				(enabled no)
				(sheetname "")
			)
			(fill
				(thermal_gap 0.5)
				(thermal_bridge_width 0.5)
				(island_removal_mode 0)
			)
			(polygon
				(pts
					(xy 26.289 -31.115) (xy 25.908 -31.115) (xy 25.908 -30.607) (xy 26.289 -30.607)
				)
			)
		)
		(zone
			(layer "F.Cu")
			(hatch none 0.5)
			(connect_pads
				(clearance 0)
			)
			(min_thickness 0.25)
			(keepout
				(tracks allowed)
				(vias not_allowed)
				(pads allowed)
				(copperpour not_allowed)
				(footprints allowed)
			)
			(placement
				(enabled no)
				(sheetname "")
			)
			(fill
				(thermal_gap 0.5)
				(thermal_bridge_width 0.5)
				(island_removal_mode 0)
			)
			(polygon
				(pts
					(xy 26.289 -31.115) (xy 25.908 -31.115) (xy 25.908 -30.607) (xy 26.289 -30.607)
				)
			)
		)
	)
	(footprint ""
		(layer "F.Cu")
		(at 407.878026 -66.758566)
		(property "Reference" "R8E9"
			(at 0 0 0)
			(layer "F.SilkS")
			(hide yes)
			(effects
				(font
					(size 1.27 1.27)
				)
			)
		)
		(property "Value" ""
			(at 0 0 0)
			(layer "F.Fab")
			(effects
				(font
					(size 1.27 1.27)
				)
			)
		)
		(duplicate_pad_numbers_are_jumpers no)
		(fp_poly
			(pts
				(xy -0.2794 -0.1016) (xy 0.2794 -0.1016) (xy 0.2794 0.9906) (xy -0.2794 0.9906)
			)
			(stroke
				(width 0)
				(type default)
			)
			(fill no)
			(layer "F.CrtYd")
		)
		(pad "1" smd rect
			(at 0 0)
			(size 0.508 0.508)
			(layers "F.Cu" "F.Mask" "F.Paste")
			(net "SPI_PCH_CLK")
		)
		(pad "2" smd rect
			(at 0 0.889)
			(size 0.508 0.508)
			(layers "F.Cu" "F.Mask" "F.Paste")
			(net "SPI_PCH_TPM_CLK_R")
		)
		(zone
			(layer "F.Cu")
			(hatch none 0.5)
			(connect_pads
				(clearance 0)
			)
			(min_thickness 0.25)
			(keepout
				(tracks allowed)
				(vias not_allowed)
				(pads allowed)
				(copperpour not_allowed)
				(footprints allowed)
			)
			(placement
				(enabled no)
				(sheetname "")
			)
			(fill
				(thermal_gap 0.5)
				(thermal_bridge_width 0.5)
				(island_removal_mode 0)
			)
			(polygon
				(pts
					(xy 407.624026 -66.504566) (xy 408.132026 -66.504566) (xy 408.132026 -66.123566) (xy 407.624026 -66.123566)
				)
			)
		)
		(zone
			(layer "F.Cu")
			(hatch none 0.5)
			(connect_pads
				(clearance 0)
			)
			(min_thickness 0.25)
			(keepout
				(tracks not_allowed)
				(vias allowed)
				(pads allowed)
				(copperpour not_allowed)
				(footprints allowed)
			)
			(placement
				(enabled no)
				(sheetname "")
			)
			(fill
				(thermal_gap 0.5)
				(thermal_bridge_width 0.5)
				(island_removal_mode 0)
			)
			(polygon
				(pts
					(xy 407.624026 -66.123566) (xy 408.132026 -66.123566) (xy 408.132026 -66.504566) (xy 407.624026 -66.504566)
				)
			)
		)
	)
	(footprint ""
		(layer "F.Cu")
		(at 167.386 -120.0658 90)
		(property "Reference" "C4B14"
			(at 3.27533 5.1054 0)
			(unlocked yes)
			(layer "F.SilkS")
			(effects
				(font
					(size 0.7874 0.5842)
					(thickness 0.1524)
				)
			)
		)
		(property "Value" ""
			(at 0 0 90)
			(layer "F.Fab")
			(effects
				(font
					(size 1.27 1.27)
				)
			)
		)
		(duplicate_pad_numbers_are_jumpers no)
		(fp_line
			(start 2.504948 -1.616456)
			(end 2.504948 1.633728)
			(stroke
				(width 0.1524)
				(type default)
			)
			(layer "F.SilkS")
		)
		(fp_line
			(start 1.6002 -1.616456)
			(end 2.504948 -1.616456)
			(stroke
				(width 0.1524)
				(type default)
			)
			(layer "F.SilkS")
		)
		(fp_line
			(start -1.6002 -1.616456)
			(end -2.563114 -1.616456)
			(stroke
				(width 0.1524)
				(type default)
			)
			(layer "F.SilkS")
		)
		(fp_line
			(start -2.563114 -1.616456)
			(end -2.563114 1.633728)
			(stroke
				(width 0.1524)
				(type default)
			)
			(layer "F.SilkS")
		)
		(fp_line
			(start 2.504948 1.633728)
			(end 1.6002 1.633728)
			(stroke
				(width 0.1524)
				(type default)
			)
			(layer "F.SilkS")
		)
		(fp_line
			(start -2.563114 1.633728)
			(end -1.6002 1.633728)
			(stroke
				(width 0.1524)
				(type default)
			)
			(layer "F.SilkS")
		)
		(fp_line
			(start 2.286 7.366)
			(end 2.286 1.63195)
			(stroke
				(width 0.1524)
				(type default)
			)
			(layer "F.SilkS")
		)
		(fp_line
			(start 2.286 7.366)
			(end 1.600708 7.366)
			(stroke
				(width 0.1524)
				(type default)
			)
			(layer "F.SilkS")
		)
		(fp_line
			(start -2.286 7.366)
			(end -2.286 1.632712)
			(stroke
				(width 0.1524)
				(type default)
			)
			(layer "F.SilkS")
		)
		(fp_line
			(start -2.286 7.366)
			(end -1.60147 7.366)
			(stroke
				(width 0.1524)
				(type default)
			)
			(layer "F.SilkS")
		)
		(fp_rect
			(start -2.286 7.366)
			(end 2.286 -0.254)
			(stroke
				(width 0)
				(type default)
			)
			(fill no)
			(layer "F.CrtYd")
		)
		(fp_line
			(start 2.286 -0.254)
			(end 2.286 7.366)
			(stroke
				(width 0.1)
				(type default)
			)
			(layer "F.Fab")
		)
		(fp_line
			(start -2.286 -0.254)
			(end 2.286 -0.254)
			(stroke
				(width 0.1)
				(type default)
			)
			(layer "F.Fab")
		)
		(fp_line
			(start 2.286 7.366)
			(end -2.286 7.366)
			(stroke
				(width 0.1)
				(type default)
			)
			(layer "F.Fab")
		)
		(fp_line
			(start -2.286 7.366)
			(end -2.286 -0.254)
			(stroke
				(width 0.1)
				(type default)
			)
			(layer "F.Fab")
		)
		(pad "1" smd rect
			(at 0 0 90)
			(size 2.54 3.048)
			(layers "F.Cu" "F.Mask" "F.Paste")
			(net "P12V_STBY")
		)
		(pad "2" smd rect
			(at 0 7.112 90)
			(size 2.54 3.048)
			(layers "F.Cu" "F.Mask" "F.Paste")
			(net "GND")
		)
	)
	(footprint ""
		(layer "F.Cu")
		(at 321.16522 -119.26316 90)
		(property "Reference" "C6B12"
			(at -0.8382 -0.67818 90)
			(unlocked yes)
			(layer "F.SilkS")
			(effects
				(font
					(size 0.4064 0.254)
					(thickness 0.1524)
				)
				(justify left)
			)
		)
		(property "Value" ""
			(at 0 0 90)
			(layer "F.Fab")
			(effects
				(font
					(size 1.27 1.27)
				)
			)
		)
		(duplicate_pad_numbers_are_jumpers no)
		(fp_poly
			(pts
				(xy 0.3048 -0.1016) (xy 0.3048 0.9906) (xy -0.3048 0.9906) (xy -0.3048 -0.1016)
			)
			(stroke
				(width 0)
				(type default)
			)
			(fill no)
			(layer "F.CrtYd")
		)
		(fp_line
			(start 0.3048 -0.1016)
			(end -0.3048 -0.1016)
			(stroke
				(width 0.1)
				(type default)
			)
			(layer "F.Fab")
		)
		(fp_line
			(start -0.3048 -0.1016)
			(end -0.3048 0.9906)
			(stroke
				(width 0.1)
				(type default)
			)
			(layer "F.Fab")
		)
		(fp_line
			(start 0.3048 0.9906)
			(end 0.3048 -0.1016)
			(stroke
				(width 0.1)
				(type default)
			)
			(layer "F.Fab")
		)
		(fp_line
			(start -0.3048 0.9906)
			(end 0.3048 0.9906)
			(stroke
				(width 0.1)
				(type default)
			)
			(layer "F.Fab")
		)
		(pad "1" smd rect
			(at 0 0 90)
			(size 0.508 0.508)
			(layers "F.Cu" "F.Mask" "F.Paste")
			(net "P3E_CPU0_PE1_PCH_TXP<12>")
		)
		(pad "2" smd rect
			(at 0 0.889 90)
			(size 0.508 0.508)
			(layers "F.Cu" "F.Mask" "F.Paste")
			(net "P3E_CPU0_PE1_PCH_C_TXP<12>")
		)
		(zone
			(layer "F.Cu")
			(hatch none 0.5)
			(connect_pads
				(clearance 0)
			)
			(min_thickness 0.25)
			(keepout
				(tracks allowed)
				(vias not_allowed)
				(pads allowed)
				(copperpour not_allowed)
				(footprints allowed)
			)
			(placement
				(enabled no)
				(sheetname "")
			)
			(fill
				(thermal_gap 0.5)
				(thermal_bridge_width 0.5)
				(island_removal_mode 0)
			)
			(polygon
				(pts
					(xy 321.41922 -119.00916) (xy 321.41922 -119.51716) (xy 321.80022 -119.51716) (xy 321.80022 -119.00916)
				)
			)
		)
		(zone
			(layer "F.Cu")
			(hatch none 0.5)
			(connect_pads
				(clearance 0)
			)
			(min_thickness 0.25)
			(keepout
				(tracks not_allowed)
				(vias allowed)
				(pads allowed)
				(copperpour not_allowed)
				(footprints allowed)
			)
			(placement
				(enabled no)
				(sheetname "")
			)
			(fill
				(thermal_gap 0.5)
				(thermal_bridge_width 0.5)
				(island_removal_mode 0)
			)
			(polygon
				(pts
					(xy 321.80022 -119.00916) (xy 321.80022 -119.51716) (xy 321.41922 -119.51716) (xy 321.41922 -119.00916)
				)
			)
		)
	)
	(footprint ""
		(layer "F.Cu")
		(at 33.178496 -53.221382 90)
		(property "Reference" "C1E7"
			(at 0 0 90)
			(layer "F.SilkS")
			(hide yes)
			(effects
				(font
					(size 1.27 1.27)
				)
			)
		)
		(property "Value" ""
			(at 0 0 90)
			(layer "F.Fab")
			(effects
				(font
					(size 1.27 1.27)
				)
			)
		)
		(duplicate_pad_numbers_are_jumpers no)
		(fp_rect
			(start 0.3048 0.9906)
			(end -0.3048 -0.1016)
			(stroke
				(width 0)
				(type default)
			)
			(fill no)
			(layer "F.CrtYd")
		)
		(fp_line
			(start 0.3048 -0.1016)
			(end -0.3048 -0.1016)
			(stroke
				(width 0.1)
				(type default)
			)
			(layer "F.Fab")
		)
		(fp_line
			(start -0.3048 -0.1016)
			(end -0.3048 0.9906)
			(stroke
				(width 0.1)
				(type default)
			)
			(layer "F.Fab")
		)
		(fp_line
			(start 0.3048 0.9906)
			(end 0.3048 -0.1016)
			(stroke
				(width 0.1)
				(type default)
			)
			(layer "F.Fab")
		)
		(fp_line
			(start -0.3048 0.9906)
			(end 0.3048 0.9906)
			(stroke
				(width 0.1)
				(type default)
			)
			(layer "F.Fab")
		)
		(pad "1" smd rect
			(at 0 0 90)
			(size 0.508 0.508)
			(layers "F.Cu" "F.Mask" "F.Paste")
			(net "P5V_STBY")
		)
		(pad "2" smd rect
			(at 0 0.889 90)
			(size 0.508 0.508)
			(layers "F.Cu" "F.Mask" "F.Paste")
			(net "GND")
		)
		(zone
			(layer "F.Cu")
			(hatch none 0.5)
			(connect_pads
				(clearance 0)
			)
			(min_thickness 0.25)
			(keepout
				(tracks allowed)
				(vias not_allowed)
				(pads allowed)
				(copperpour not_allowed)
				(footprints allowed)
			)
			(placement
				(enabled no)
				(sheetname "")
			)
			(fill
				(thermal_gap 0.5)
				(thermal_bridge_width 0.5)
				(island_removal_mode 0)
			)
			(polygon
				(pts
					(xy 33.813496 -53.475382) (xy 33.432496 -53.475382) (xy 33.432496 -52.967382) (xy 33.813496 -52.967382)
				)
			)
		)
		(zone
			(layer "F.Cu")
			(hatch none 0.5)
			(connect_pads
				(clearance 0)
			)
			(min_thickness 0.25)
			(keepout
				(tracks not_allowed)
				(vias allowed)
				(pads allowed)
				(copperpour not_allowed)
				(footprints allowed)
			)
			(placement
				(enabled no)
				(sheetname "")
			)
			(fill
				(thermal_gap 0.5)
				(thermal_bridge_width 0.5)
				(island_removal_mode 0)
			)
			(polygon
				(pts
					(xy 33.813496 -53.475382) (xy 33.432496 -53.475382) (xy 33.432496 -52.967382) (xy 33.813496 -52.967382)
				)
			)
		)
	)
	(footprint ""
		(layer "F.Cu")
		(at 444.1825 -146.5834 -90)
		(property "Reference" "C25W92"
			(at -0.8382 -0.67818 270)
			(unlocked yes)
			(layer "F.SilkS")
			(effects
				(font
					(size 0.4064 0.254)
					(thickness 0.1524)
				)
				(justify left)
			)
		)
		(property "Value" ""
			(at 0 0 270)
			(layer "F.Fab")
			(effects
				(font
					(size 1.27 1.27)
				)
			)
		)
		(duplicate_pad_numbers_are_jumpers no)
		(fp_poly
			(pts
				(xy 0.3048 -0.1016) (xy 0.3048 0.9906) (xy -0.3048 0.9906) (xy -0.3048 -0.1016)
			)
			(stroke
				(width 0)
				(type default)
			)
			(fill no)
			(layer "F.CrtYd")
		)
		(fp_line
			(start -0.3048 0.9906)
			(end 0.3048 0.9906)
			(stroke
				(width 0.1)
				(type default)
			)
			(layer "F.Fab")
		)
		(fp_line
			(start 0.3048 0.9906)
			(end 0.3048 -0.1016)
			(stroke
				(width 0.1)
				(type default)
			)
			(layer "F.Fab")
		)
		(fp_line
			(start -0.3048 -0.1016)
			(end -0.3048 0.9906)
			(stroke
				(width 0.1)
				(type default)
			)
			(layer "F.Fab")
		)
		(fp_line
			(start 0.3048 -0.1016)
			(end -0.3048 -0.1016)
			(stroke
				(width 0.1)
				(type default)
			)
			(layer "F.Fab")
		)
		(pad "1" smd rect
			(at 0 0 270)
			(size 0.508 0.508)
			(layers "F.Cu" "F.Mask" "F.Paste")
			(net "P3V3_STBY")
		)
		(pad "2" smd rect
			(at 0 0.889 270)
			(size 0.508 0.508)
			(layers "F.Cu" "F.Mask" "F.Paste")
			(net "GND")
		)
		(zone
			(layer "F.Cu")
			(hatch none 0.5)
			(connect_pads
				(clearance 0)
			)
			(min_thickness 0.25)
			(keepout
				(tracks not_allowed)
				(vias allowed)
				(pads allowed)
				(copperpour not_allowed)
				(footprints allowed)
			)
			(placement
				(enabled no)
				(sheetname "")
			)
			(fill
				(thermal_gap 0.5)
				(thermal_bridge_width 0.5)
				(island_removal_mode 0)
			)
			(polygon
				(pts
					(xy 443.5475 -146.8374) (xy 443.5475 -146.3294) (xy 443.9285 -146.3294) (xy 443.9285 -146.8374)
				)
			)
		)
		(zone
			(layer "F.Cu")
			(hatch none 0.5)
			(connect_pads
				(clearance 0)
			)
			(min_thickness 0.25)
			(keepout
				(tracks allowed)
				(vias not_allowed)
				(pads allowed)
				(copperpour not_allowed)
				(footprints allowed)
			)
			(placement
				(enabled no)
				(sheetname "")
			)
			(fill
				(thermal_gap 0.5)
				(thermal_bridge_width 0.5)
				(island_removal_mode 0)
			)
			(polygon
				(pts
					(xy 443.9285 -146.8374) (xy 443.9285 -146.3294) (xy 443.5475 -146.3294) (xy 443.5475 -146.8374)
				)
			)
		)
	)
	(footprint ""
		(layer "F.Cu")
		(at 33.925002 -97.679764 90)
		(property "Reference" "EU1C1"
			(at 3.385566 -0.143002 0)
			(unlocked yes)
			(layer "F.SilkS")
			(effects
				(font
					(size 0.7874 0.5842)
					(thickness 0.1524)
				)
			)
		)
		(property "Value" ""
			(at 0 0 90)
			(layer "F.Fab")
			(effects
				(font
					(size 1.27 1.27)
				)
			)
		)
		(duplicate_pad_numbers_are_jumpers no)
		(fp_line
			(start 2.9718 -3.5052)
			(end 2.9718 3.429)
			(stroke
				(width 0.1524)
				(type default)
			)
			(layer "F.SilkS")
		)
		(fp_line
			(start -3.0099 -3.5052)
			(end 2.9718 -3.5052)
			(stroke
				(width 0.1524)
				(type default)
			)
			(layer "F.SilkS")
		)
		(fp_line
			(start 2.9718 3.429)
			(end -3.0099 3.429)
			(stroke
				(width 0.1524)
				(type default)
			)
			(layer "F.SilkS")
		)
		(fp_line
			(start -3.0099 3.429)
			(end -3.0099 -3.5052)
			(stroke
				(width 0.1524)
				(type default)
			)
			(layer "F.SilkS")
		)
		(fp_circle
			(center -3.057398 -2.678684)
			(end -3.057398 -2.551684)
			(stroke
				(width 0.254)
				(type default)
			)
			(fill no)
			(layer "F.SilkS")
		)
		(fp_poly
			(pts
				(xy -2.9972 -3.4925) (xy -2.9972 -2.6924) (xy -2.1971 -3.4925)
			)
			(stroke
				(width 0)
				(type default)
			)
			(fill yes)
			(layer "F.SilkS")
		)
		(fp_poly
			(pts
				(xy -2.549906 -3.050032) (xy -2.549906 3.050032) (xy 2.549906 3.050032) (xy 2.549906 -3.050032)
			)
			(stroke
				(width 0)
				(type default)
			)
			(fill no)
			(layer "F.CrtYd")
		)
		(fp_line
			(start 2.549906 -3.050032)
			(end 2.549906 3.050032)
			(stroke
				(width 0.1)
				(type default)
			)
			(layer "F.Fab")
		)
		(fp_line
			(start -2.549906 -3.050032)
			(end 2.549906 -3.050032)
			(stroke
				(width 0.1)
				(type default)
			)
			(layer "F.Fab")
		)
		(fp_line
			(start 2.549906 3.050032)
			(end -2.549906 3.050032)
			(stroke
				(width 0.1)
				(type default)
			)
			(layer "F.Fab")
		)
		(fp_line
			(start -2.549906 3.050032)
			(end -2.549906 -3.050032)
			(stroke
				(width 0.1)
				(type default)
			)
			(layer "F.Fab")
		)
		(fp_circle
			(center -3.057398 -2.678684)
			(end -3.057398 -2.551684)
			(stroke
				(width 0.254)
				(type default)
			)
			(fill no)
			(layer "F.Fab")
		)
		(pad "1" smd rect
			(at -2.39522 -2.279904 90)
			(size 0.7112 0.254)
			(layers "F.Cu" "F.Mask" "F.Paste")
			(net "PVSA_CPU1")
		)
		(pad "2" smd rect
			(at -2.39522 -1.83007 90)
			(size 0.7112 0.254)
			(layers "F.Cu" "F.Mask" "F.Paste")
			(net "GND")
		)
		(pad "3" smd rect
			(at -2.39522 -1.379982 90)
			(size 0.7112 0.254)
			(layers "F.Cu" "F.Mask" "F.Paste")
			(net "VR_PVSA_CPU1_VCIN")
		)
		(pad "4" smd rect
			(at -2.39522 -0.929894 90)
			(size 0.7112 0.254)
			(layers "F.Cu" "F.Mask" "F.Paste")
			(net "P5V_STBY")
		)
		(pad "5" smd rect
			(at -2.39522 -0.48006 90)
			(size 0.7112 0.254)
			(layers "F.Cu" "F.Mask" "F.Paste")
			(net "GND")
		)
		(pad "6" smd rect
			(at -2.39522 -0.029972 90)
			(size 0.7112 0.254)
			(layers "F.Cu" "F.Mask" "F.Paste")
			(net "TP_PVSA_CPU1_GL_0")
		)
		(pad "7" smd custom
			(at 0.016764 1.145032 90)
			(size 0.53975 0.53975)
			(layers "F.Cu" "F.Mask" "F.Paste")
			(net "GND")
			(options
				(clearance outline)
				(anchor circle)
			)
			(primitives
				(gr_poly
					(pts
						(xy -2.7051 1.0795) (xy -2.7051 -0.3683) (xy -0.9271 -0.3683) (xy -0.9271 -1.0795) (xy 2.7051 -1.0795)
						(xy 2.7051 1.0795)
					)
					(width 0)
					(fill yes)
				)
			)
		)
		(pad "10" smd rect
			(at -0.008382 2.874772 90)
			(size 4.3434 0.6096)
			(layers "F.Cu" "F.Mask" "F.Paste")
			(net "VR_PVSA_CPU1_PHASE_SW")
		)
		(pad "25" smd rect
			(at 1.548384 -1.283208 90)
			(size 2.3368 2.0066)
			(layers "F.Cu" "F.Mask" "F.Paste")
			(net "VR_FET_SW_P12V_STBY_PVCCIN_CPU1")
		)
		(pad "30" smd rect
			(at 2.050034 -2.895092 90)
			(size 0.254 0.7112)
			(layers "F.Cu" "F.Mask" "F.Paste")
			(net "VR_FET_SW_P12V_STBY_PVCCIN_CPU1")
		)
		(pad "31" smd rect
			(at 1.599946 -2.895092 90)
			(size 0.254 0.7112)
			(layers "F.Cu" "F.Mask" "F.Paste")
			(net "Net_295")
		)
		(pad "32" smd rect
			(at 1.150112 -2.895092 90)
			(size 0.254 0.7112)
			(layers "F.Cu" "F.Mask" "F.Paste")
			(net "VR_PVSA_CPU1_PHASE")
		)
		(pad "33" smd rect
			(at 0.700024 -2.895092 90)
			(size 0.254 0.7112)
			(layers "F.Cu" "F.Mask" "F.Paste")
			(net "VR_PVSA_CPU1_BOOT_R")
		)
		(pad "34" smd rect
			(at 0.249936 -2.895092 90)
			(size 0.254 0.7112)
			(layers "F.Cu" "F.Mask" "F.Paste")
			(net "VR_PVSA_CPU1_PWM")
		)
		(pad "35" smd rect
			(at -0.199898 -2.895092 90)
			(size 0.254 0.7112)
			(layers "F.Cu" "F.Mask" "F.Paste")
			(net "P5V_STBY")
		)
		(pad "36" smd rect
			(at -0.649986 -2.895092 90)
			(size 0.254 0.7112)
			(layers "F.Cu" "F.Mask" "F.Paste")
			(net "A_TSENSE_PVSA_CPU1")
		)
		(pad "37" smd rect
			(at -1.100074 -2.895092 90)
			(size 0.254 0.7112)
			(layers "F.Cu" "F.Mask" "F.Paste")
			(net "VR_PVSA_CPU1_OCSET")
		)
		(pad "38" smd rect
			(at -1.549908 -2.895092 90)
			(size 0.254 0.7112)
			(layers "F.Cu" "F.Mask" "F.Paste")
			(net "ISENSE_PVSA_CPU1_IMON")
		)
		(pad "39" smd rect
			(at -1.999996 -2.895092 90)
			(size 0.254 0.7112)
			(layers "F.Cu" "F.Mask" "F.Paste")
			(net "VR_PVSA_CPU1_BIREF1")
		)
		(pad "40" smd rect
			(at -0.871728 -1.283208 90)
			(size 1.8034 2.0066)
			(layers "F.Cu" "F.Mask" "F.Paste")
			(net "GND")
		)
		(pad "41" smd rect
			(at -1.533906 0.247904 90)
			(size 0.508 0.3556)
			(layers "F.Cu" "F.Mask" "F.Paste")
			(net "TP_PVSA_CPU1_GL_1")
		)
	)
	(footprint ""
		(layer "F.Cu")
		(at 414.8328 -113.2332 90)
		(property "Reference" "R2M2"
			(at 0 0 90)
			(layer "F.SilkS")
			(hide yes)
			(effects
				(font
					(size 1.27 1.27)
				)
			)
		)
		(property "Value" ""
			(at 0 0 90)
			(layer "F.Fab")
			(effects
				(font
					(size 1.27 1.27)
				)
			)
		)
		(duplicate_pad_numbers_are_jumpers no)
		(fp_poly
			(pts
				(xy -0.2794 -0.1016) (xy 0.2794 -0.1016) (xy 0.2794 0.9906) (xy -0.2794 0.9906)
			)
			(stroke
				(width 0)
				(type default)
			)
			(fill no)
			(layer "F.CrtYd")
		)
		(fp_line
			(start 0.2794 -0.1016)
			(end -0.2794 -0.1016)
			(stroke
				(width 0.1)
				(type default)
			)
			(layer "F.Fab")
		)
		(fp_line
			(start -0.2794 -0.1016)
			(end -0.2794 0.9906)
			(stroke
				(width 0.1)
				(type default)
			)
			(layer "F.Fab")
		)
		(fp_line
			(start 0.2794 0.9906)
			(end 0.2794 -0.1016)
			(stroke
				(width 0.1)
				(type default)
			)
			(layer "F.Fab")
		)
		(fp_line
			(start -0.2794 0.9906)
			(end 0.2794 0.9906)
			(stroke
				(width 0.1)
				(type default)
			)
			(layer "F.Fab")
		)
		(pad "1" smd rect
			(at 0 0 90)
			(size 0.508 0.508)
			(layers "F.Cu" "F.Mask" "F.Paste")
			(net "P3V3_STBY")
		)
		(pad "2" smd rect
			(at 0 0.889 90)
			(size 0.508 0.508)
			(layers "F.Cu" "F.Mask" "F.Paste")
			(net "FM_ADR_SMI_GPIO_N")
		)
		(zone
			(layer "F.Cu")
			(hatch none 0.5)
			(connect_pads
				(clearance 0)
			)
			(min_thickness 0.25)
			(keepout
				(tracks allowed)
				(vias not_allowed)
				(pads allowed)
				(copperpour not_allowed)
				(footprints allowed)
			)
			(placement
				(enabled no)
				(sheetname "")
			)
			(fill
				(thermal_gap 0.5)
				(thermal_bridge_width 0.5)
				(island_removal_mode 0)
			)
			(polygon
				(pts
					(xy 415.0868 -112.9792) (xy 415.0868 -113.4872) (xy 415.4678 -113.4872) (xy 415.4678 -112.9792)
				)
			)
		)
		(zone
			(layer "F.Cu")
			(hatch none 0.5)
			(connect_pads
				(clearance 0)
			)
			(min_thickness 0.25)
			(keepout
				(tracks not_allowed)
				(vias allowed)
				(pads allowed)
				(copperpour not_allowed)
				(footprints allowed)
			)
			(placement
				(enabled no)
				(sheetname "")
			)
			(fill
				(thermal_gap 0.5)
				(thermal_bridge_width 0.5)
				(island_removal_mode 0)
			)
			(polygon
				(pts
					(xy 415.4678 -112.9792) (xy 415.4678 -113.4872) (xy 415.0868 -113.4872) (xy 415.0868 -112.9792)
				)
			)
		)
	)
	(footprint ""
		(layer "F.Cu")
		(at 391.414 -71.9455)
		(property "Reference" "R7E12"
			(at 0 0 0)
			(layer "F.SilkS")
			(hide yes)
			(effects
				(font
					(size 1.27 1.27)
				)
			)
		)
		(property "Value" ""
			(at 0 0 0)
			(layer "F.Fab")
			(effects
				(font
					(size 1.27 1.27)
				)
			)
		)
		(duplicate_pad_numbers_are_jumpers no)
		(fp_poly
			(pts
				(xy -0.2794 -0.1016) (xy 0.2794 -0.1016) (xy 0.2794 0.9906) (xy -0.2794 0.9906)
			)
			(stroke
				(width 0)
				(type default)
			)
			(fill no)
			(layer "F.CrtYd")
		)
		(fp_line
			(start -0.2794 -0.1016)
			(end -0.2794 0.9906)
			(stroke
				(width 0.1)
				(type default)
			)
			(layer "F.Fab")
		)
		(fp_line
			(start -0.2794 0.9906)
			(end 0.2794 0.9906)
			(stroke
				(width 0.1)
				(type default)
			)
			(layer "F.Fab")
		)
		(fp_line
			(start 0.2794 -0.1016)
			(end -0.2794 -0.1016)
			(stroke
				(width 0.1)
				(type default)
			)
			(layer "F.Fab")
		)
		(fp_line
			(start 0.2794 0.9906)
			(end 0.2794 -0.1016)
			(stroke
				(width 0.1)
				(type default)
			)
			(layer "F.Fab")
		)
		(pad "1" smd rect
			(at 0 0)
			(size 0.508 0.508)
			(layers "F.Cu" "F.Mask" "F.Paste")
			(net "P5V_STBY")
		)
		(pad "2" smd rect
			(at 0 0.889)
			(size 0.508 0.508)
			(layers "F.Cu" "F.Mask" "F.Paste")
			(net "PWRGD_P5V_STBY_R")
		)
		(zone
			(layer "F.Cu")
			(hatch none 0.5)
			(connect_pads
				(clearance 0)
			)
			(min_thickness 0.25)
			(keepout
				(tracks allowed)
				(vias not_allowed)
				(pads allowed)
				(copperpour not_allowed)
				(footprints allowed)
			)
			(placement
				(enabled no)
				(sheetname "")
			)
			(fill
				(thermal_gap 0.5)
				(thermal_bridge_width 0.5)
				(island_removal_mode 0)
			)
			(polygon
				(pts
					(xy 391.16 -71.6915) (xy 391.668 -71.6915) (xy 391.668 -71.3105) (xy 391.16 -71.3105)
				)
			)
		)
		(zone
			(layer "F.Cu")
			(hatch none 0.5)
			(connect_pads
				(clearance 0)
			)
			(min_thickness 0.25)
			(keepout
				(tracks not_allowed)
				(vias allowed)
				(pads allowed)
				(copperpour not_allowed)
				(footprints allowed)
			)
			(placement
				(enabled no)
				(sheetname "")
			)
			(fill
				(thermal_gap 0.5)
				(thermal_bridge_width 0.5)
				(island_removal_mode 0)
			)
			(polygon
				(pts
					(xy 391.16 -71.3105) (xy 391.668 -71.3105) (xy 391.668 -71.6915) (xy 391.16 -71.6915)
				)
			)
		)
	)
	(footprint ""
		(layer "F.Cu")
		(at 496.686332 -22.354794 90)
		(property "Reference" "C7E6"
			(at 0 0 90)
			(layer "F.SilkS")
			(hide yes)
			(effects
				(font
					(size 1.27 1.27)
				)
			)
		)
		(property "Value" ""
			(at 0 0 90)
			(layer "F.Fab")
			(effects
				(font
					(size 1.27 1.27)
				)
			)
		)
		(duplicate_pad_numbers_are_jumpers no)
		(fp_rect
			(start -0.7239 1.9939)
			(end 0.7239 -0.2159)
			(stroke
				(width 0)
				(type default)
			)
			(fill no)
			(layer "F.CrtYd")
		)
		(fp_line
			(start 0.7239 -0.2159)
			(end -0.7239 -0.2159)
			(stroke
				(width 0.1)
				(type default)
			)
			(layer "F.Fab")
		)
		(fp_line
			(start -0.7239 -0.2159)
			(end -0.7239 1.9939)
			(stroke
				(width 0.1)
				(type default)
			)
			(layer "F.Fab")
		)
		(fp_line
			(start 0.7239 1.9939)
			(end 0.7239 -0.2159)
			(stroke
				(width 0.1)
				(type default)
			)
			(layer "F.Fab")
		)
		(fp_line
			(start -0.7239 1.9939)
			(end 0.7239 1.9939)
			(stroke
				(width 0.1)
				(type default)
			)
			(layer "F.Fab")
		)
		(pad "1" smd rect
			(at 0 0 90)
			(size 1.27 1.016)
			(layers "F.Cu" "F.Mask" "F.Paste")
			(net "P12V_STBY")
		)
		(pad "2" smd rect
			(at 0 1.778 90)
			(size 1.27 1.016)
			(layers "F.Cu" "F.Mask" "F.Paste")
			(net "GND")
		)
		(zone
			(layer "F.Cu")
			(hatch none 0.5)
			(connect_pads
				(clearance 0)
			)
			(min_thickness 0.25)
			(keepout
				(tracks not_allowed)
				(vias allowed)
				(pads allowed)
				(copperpour not_allowed)
				(footprints allowed)
			)
			(placement
				(enabled no)
				(sheetname "")
			)
			(fill
				(thermal_gap 0.5)
				(thermal_bridge_width 0.5)
				(island_removal_mode 0)
			)
			(polygon
				(pts
					(xy 497.956332 -21.719794) (xy 497.956332 -22.989794) (xy 497.194332 -22.989794) (xy 497.194332 -21.719794)
				)
			)
		)
	)
	(footprint ""
		(layer "F.Cu")
		(at 371.2718 -101.346)
		(property "Reference" "R7C5"
			(at 0 0 0)
			(layer "F.SilkS")
			(hide yes)
			(effects
				(font
					(size 1.27 1.27)
				)
			)
		)
		(property "Value" ""
			(at 0 0 0)
			(layer "F.Fab")
			(effects
				(font
					(size 1.27 1.27)
				)
			)
		)
		(duplicate_pad_numbers_are_jumpers no)
		(fp_poly
			(pts
				(xy -0.2794 -0.1016) (xy 0.2794 -0.1016) (xy 0.2794 0.9906) (xy -0.2794 0.9906)
			)
			(stroke
				(width 0)
				(type default)
			)
			(fill no)
			(layer "F.CrtYd")
		)
		(fp_line
			(start -0.2794 -0.1016)
			(end -0.2794 0.9906)
			(stroke
				(width 0.1)
				(type default)
			)
			(layer "F.Fab")
		)
		(fp_line
			(start -0.2794 0.9906)
			(end 0.2794 0.9906)
			(stroke
				(width 0.1)
				(type default)
			)
			(layer "F.Fab")
		)
		(fp_line
			(start 0.2794 -0.1016)
			(end -0.2794 -0.1016)
			(stroke
				(width 0.1)
				(type default)
			)
			(layer "F.Fab")
		)
		(fp_line
			(start 0.2794 0.9906)
			(end 0.2794 -0.1016)
			(stroke
				(width 0.1)
				(type default)
			)
			(layer "F.Fab")
		)
		(pad "1" smd rect
			(at 0 0)
			(size 0.508 0.508)
			(layers "F.Cu" "F.Mask" "F.Paste")
			(net "P3V3_STBY")
		)
		(pad "2" smd rect
			(at 0 0.889)
			(size 0.508 0.508)
			(layers "F.Cu" "F.Mask" "F.Paste")
			(net "FM_SINT_PRSNT_N")
		)
		(zone
			(layer "F.Cu")
			(hatch none 0.5)
			(connect_pads
				(clearance 0)
			)
			(min_thickness 0.25)
			(keepout
				(tracks allowed)
				(vias not_allowed)
				(pads allowed)
				(copperpour not_allowed)
				(footprints allowed)
			)
			(placement
				(enabled no)
				(sheetname "")
			)
			(fill
				(thermal_gap 0.5)
				(thermal_bridge_width 0.5)
				(island_removal_mode 0)
			)
			(polygon
				(pts
					(xy 371.0178 -101.092) (xy 371.5258 -101.092) (xy 371.5258 -100.711) (xy 371.0178 -100.711)
				)
			)
		)
		(zone
			(layer "F.Cu")
			(hatch none 0.5)
			(connect_pads
				(clearance 0)
			)
			(min_thickness 0.25)
			(keepout
				(tracks not_allowed)
				(vias allowed)
				(pads allowed)
				(copperpour not_allowed)
				(footprints allowed)
			)
			(placement
				(enabled no)
				(sheetname "")
			)
			(fill
				(thermal_gap 0.5)
				(thermal_bridge_width 0.5)
				(island_removal_mode 0)
			)
			(polygon
				(pts
					(xy 371.0178 -100.711) (xy 371.5258 -100.711) (xy 371.5258 -101.092) (xy 371.0178 -101.092)
				)
			)
		)
	)
	(footprint ""
		(layer "F.Cu")
		(at 490.474 -37.338 180)
		(property "Reference" "R25W126"
			(at -0.8382 -0.67818 180)
			(unlocked yes)
			(layer "F.SilkS")
			(effects
				(font
					(size 0.4064 0.254)
					(thickness 0.1524)
				)
				(justify left)
			)
		)
		(property "Value" ""
			(at 0 0 180)
			(layer "F.Fab")
			(effects
				(font
					(size 1.27 1.27)
				)
			)
		)
		(duplicate_pad_numbers_are_jumpers no)
		(fp_poly
			(pts
				(xy -0.2794 -0.1016) (xy 0.2794 -0.1016) (xy 0.2794 0.9906) (xy -0.2794 0.9906)
			)
			(stroke
				(width 0)
				(type default)
			)
			(fill no)
			(layer "F.CrtYd")
		)
		(fp_line
			(start 0.2794 0.9906)
			(end 0.2794 -0.1016)
			(stroke
				(width 0.1)
				(type default)
			)
			(layer "F.Fab")
		)
		(fp_line
			(start 0.2794 -0.1016)
			(end -0.2794 -0.1016)
			(stroke
				(width 0.1)
				(type default)
			)
			(layer "F.Fab")
		)
		(fp_line
			(start -0.2794 0.9906)
			(end 0.2794 0.9906)
			(stroke
				(width 0.1)
				(type default)
			)
			(layer "F.Fab")
		)
		(fp_line
			(start -0.2794 -0.1016)
			(end -0.2794 0.9906)
			(stroke
				(width 0.1)
				(type default)
			)
			(layer "F.Fab")
		)
		(pad "1" smd rect
			(at 0 0 180)
			(size 0.508 0.508)
			(layers "F.Cu" "F.Mask" "F.Paste")
			(net "V_IO_B_J")
		)
		(pad "2" smd rect
			(at 0 0.889 180)
			(size 0.508 0.508)
			(layers "F.Cu" "F.Mask" "F.Paste")
			(net "GND")
		)
		(zone
			(layer "F.Cu")
			(hatch none 0.5)
			(connect_pads
				(clearance 0)
			)
			(min_thickness 0.25)
			(keepout
				(tracks not_allowed)
				(vias allowed)
				(pads allowed)
				(copperpour not_allowed)
				(footprints allowed)
			)
			(placement
				(enabled no)
				(sheetname "")
			)
			(fill
				(thermal_gap 0.5)
				(thermal_bridge_width 0.5)
				(island_removal_mode 0)
			)
			(polygon
				(pts
					(xy 490.728 -37.973) (xy 490.22 -37.973) (xy 490.22 -37.592) (xy 490.728 -37.592)
				)
			)
		)
		(zone
			(layer "F.Cu")
			(hatch none 0.5)
			(connect_pads
				(clearance 0)
			)
			(min_thickness 0.25)
			(keepout
				(tracks allowed)
				(vias not_allowed)
				(pads allowed)
				(copperpour not_allowed)
				(footprints allowed)
			)
			(placement
				(enabled no)
				(sheetname "")
			)
			(fill
				(thermal_gap 0.5)
				(thermal_bridge_width 0.5)
				(island_removal_mode 0)
			)
			(polygon
				(pts
					(xy 490.728 -37.592) (xy 490.22 -37.592) (xy 490.22 -37.973) (xy 490.728 -37.973)
				)
			)
		)
	)
	(footprint ""
		(layer "F.Cu")
		(at 193.7385 -83.212432 90)
		(property "Reference" "C4D9"
			(at 0 0 90)
			(layer "F.SilkS")
			(hide yes)
			(effects
				(font
					(size 1.27 1.27)
				)
			)
		)
		(property "Value" ""
			(at 0 0 90)
			(layer "F.Fab")
			(effects
				(font
					(size 1.27 1.27)
				)
			)
		)
		(duplicate_pad_numbers_are_jumpers no)
		(fp_rect
			(start -0.3048 0.9906)
			(end 0.3048 -0.1016)
			(stroke
				(width 0)
				(type default)
			)
			(fill no)
			(layer "F.CrtYd")
		)
		(fp_line
			(start 0.3048 -0.1016)
			(end -0.3048 -0.1016)
			(stroke
				(width 0.1)
				(type default)
			)
			(layer "F.Fab")
		)
		(fp_line
			(start -0.3048 -0.1016)
			(end -0.3048 0.9906)
			(stroke
				(width 0.1)
				(type default)
			)
			(layer "F.Fab")
		)
		(fp_line
			(start 0.3048 0.9906)
			(end 0.3048 -0.1016)
			(stroke
				(width 0.1)
				(type default)
			)
			(layer "F.Fab")
		)
		(fp_line
			(start -0.3048 0.9906)
			(end 0.3048 0.9906)
			(stroke
				(width 0.1)
				(type default)
			)
			(layer "F.Fab")
		)
		(pad "1" smd rect
			(at 0 0 90)
			(size 0.508 0.508)
			(layers "F.Cu" "F.Mask" "F.Paste")
			(net "VR_PVCCIN_CPU0_PH4_BOOT")
		)
		(pad "2" smd rect
			(at 0 0.889 90)
			(size 0.508 0.508)
			(layers "F.Cu" "F.Mask" "F.Paste")
			(net "VR_PVCCIN_CPU0_PH4_PHASE")
		)
		(zone
			(layer "F.Cu")
			(hatch none 0.5)
			(connect_pads
				(clearance 0)
			)
			(min_thickness 0.25)
			(keepout
				(tracks not_allowed)
				(vias allowed)
				(pads allowed)
				(copperpour not_allowed)
				(footprints allowed)
			)
			(placement
				(enabled no)
				(sheetname "")
			)
			(fill
				(thermal_gap 0.5)
				(thermal_bridge_width 0.5)
				(island_removal_mode 0)
			)
			(polygon
				(pts
					(xy 194.3735 -82.958432) (xy 194.3735 -83.466432) (xy 193.9925 -83.466432) (xy 193.9925 -82.958432)
				)
			)
		)
		(zone
			(layer "F.Cu")
			(hatch none 0.5)
			(connect_pads
				(clearance 0)
			)
			(min_thickness 0.25)
			(keepout
				(tracks allowed)
				(vias not_allowed)
				(pads allowed)
				(copperpour not_allowed)
				(footprints allowed)
			)
			(placement
				(enabled no)
				(sheetname "")
			)
			(fill
				(thermal_gap 0.5)
				(thermal_bridge_width 0.5)
				(island_removal_mode 0)
			)
			(polygon
				(pts
					(xy 194.3735 -82.958432) (xy 194.3735 -83.466432) (xy 193.9925 -83.466432) (xy 193.9925 -82.958432)
				)
			)
		)
	)
	(footprint ""
		(layer "F.Cu")
		(at 325.0057 -29.25318)
		(property "Reference" "C6F3"
			(at 0 0 0)
			(layer "F.SilkS")
			(hide yes)
			(effects
				(font
					(size 1.27 1.27)
				)
			)
		)
		(property "Value" ""
			(at 0 0 0)
			(layer "F.Fab")
			(effects
				(font
					(size 1.27 1.27)
				)
			)
		)
		(duplicate_pad_numbers_are_jumpers no)
		(fp_poly
			(pts
				(xy 0.3048 -0.1016) (xy 0.3048 0.9906) (xy -0.3048 0.9906) (xy -0.3048 -0.1016)
			)
			(stroke
				(width 0)
				(type default)
			)
			(fill no)
			(layer "F.CrtYd")
		)
		(fp_line
			(start -0.3048 -0.1016)
			(end -0.3048 0.9906)
			(stroke
				(width 0.1)
				(type default)
			)
			(layer "F.Fab")
		)
		(fp_line
			(start -0.3048 0.9906)
			(end 0.3048 0.9906)
			(stroke
				(width 0.1)
				(type default)
			)
			(layer "F.Fab")
		)
		(fp_line
			(start 0.3048 -0.1016)
			(end -0.3048 -0.1016)
			(stroke
				(width 0.1)
				(type default)
			)
			(layer "F.Fab")
		)
		(fp_line
			(start 0.3048 0.9906)
			(end 0.3048 -0.1016)
			(stroke
				(width 0.1)
				(type default)
			)
			(layer "F.Fab")
		)
		(pad "1" smd rect
			(at 0 0)
			(size 0.508 0.508)
			(layers "F.Cu" "F.Mask" "F.Paste")
			(net "PVPP_ABC")
		)
		(pad "2" smd rect
			(at 0 0.889)
			(size 0.508 0.508)
			(layers "F.Cu" "F.Mask" "F.Paste")
			(net "GND")
		)
		(zone
			(layer "F.Cu")
			(hatch none 0.5)
			(connect_pads
				(clearance 0)
			)
			(min_thickness 0.25)
			(keepout
				(tracks allowed)
				(vias not_allowed)
				(pads allowed)
				(copperpour not_allowed)
				(footprints allowed)
			)
			(placement
				(enabled no)
				(sheetname "")
			)
			(fill
				(thermal_gap 0.5)
				(thermal_bridge_width 0.5)
				(island_removal_mode 0)
			)
			(polygon
				(pts
					(xy 324.7517 -28.99918) (xy 325.2597 -28.99918) (xy 325.2597 -28.61818) (xy 324.7517 -28.61818)
				)
			)
		)
		(zone
			(layer "F.Cu")
			(hatch none 0.5)
			(connect_pads
				(clearance 0)
			)
			(min_thickness 0.25)
			(keepout
				(tracks not_allowed)
				(vias allowed)
				(pads allowed)
				(copperpour not_allowed)
				(footprints allowed)
			)
			(placement
				(enabled no)
				(sheetname "")
			)
			(fill
				(thermal_gap 0.5)
				(thermal_bridge_width 0.5)
				(island_removal_mode 0)
			)
			(polygon
				(pts
					(xy 324.7517 -28.61818) (xy 325.2597 -28.61818) (xy 325.2597 -28.99918) (xy 324.7517 -28.99918)
				)
			)
		)
	)
	(footprint ""
		(layer "F.Cu")
		(at 153.6446 -126.7714 -90)
		(property "Reference" "C3B3"
			(at 3.10007 5.3086 0)
			(unlocked yes)
			(layer "F.SilkS")
			(effects
				(font
					(size 0.7874 0.5842)
					(thickness 0.1524)
				)
				(justify left)
			)
		)
		(property "Value" ""
			(at 0 0 270)
			(layer "F.Fab")
			(effects
				(font
					(size 1.27 1.27)
				)
			)
		)
		(duplicate_pad_numbers_are_jumpers no)
		(fp_line
			(start -2.2987 7.3533)
			(end -1.7272 7.3533)
			(stroke
				(width 0.1524)
				(type default)
			)
			(layer "F.SilkS")
		)
		(fp_line
			(start 1.7272 7.3533)
			(end 2.2987 7.3533)
			(stroke
				(width 0.1524)
				(type default)
			)
			(layer "F.SilkS")
		)
		(fp_line
			(start 2.2987 7.3533)
			(end 2.2987 -0.2413)
			(stroke
				(width 0.1524)
				(type default)
			)
			(layer "F.SilkS")
		)
		(fp_line
			(start -2.032 1.524)
			(end -1.7272 1.524)
			(stroke
				(width 0.1524)
				(type default)
			)
			(layer "F.SilkS")
		)
		(fp_line
			(start 2.032 1.524)
			(end 1.7272 1.524)
			(stroke
				(width 0.1524)
				(type default)
			)
			(layer "F.SilkS")
		)
		(fp_line
			(start -2.2987 -0.2413)
			(end -2.2987 7.3533)
			(stroke
				(width 0.1524)
				(type default)
			)
			(layer "F.SilkS")
		)
		(fp_line
			(start -2.032 -0.2413)
			(end -2.2987 -0.2413)
			(stroke
				(width 0.1524)
				(type default)
			)
			(layer "F.SilkS")
		)
		(fp_line
			(start 2.2987 -0.2413)
			(end 2.032 -0.2413)
			(stroke
				(width 0.1524)
				(type default)
			)
			(layer "F.SilkS")
		)
		(fp_line
			(start -2.032 -1.524)
			(end -2.032 1.524)
			(stroke
				(width 0.1524)
				(type default)
			)
			(layer "F.SilkS")
		)
		(fp_line
			(start -1.7272 -1.524)
			(end -2.032 -1.524)
			(stroke
				(width 0.1524)
				(type default)
			)
			(layer "F.SilkS")
		)
		(fp_line
			(start 1.7272 -1.524)
			(end 2.032 -1.524)
			(stroke
				(width 0.1524)
				(type default)
			)
			(layer "F.SilkS")
		)
		(fp_line
			(start 2.032 -1.524)
			(end 2.032 1.524)
			(stroke
				(width 0.1524)
				(type default)
			)
			(layer "F.SilkS")
		)
		(fp_poly
			(pts
				(xy -2.2987 -0.2413) (xy 2.2987 -0.2413) (xy 2.2987 7.3533) (xy -2.2987 7.3533)
			)
			(stroke
				(width 0)
				(type default)
			)
			(fill no)
			(layer "F.CrtYd")
		)
		(fp_line
			(start -2.2987 7.3533)
			(end -2.2987 -0.2413)
			(stroke
				(width 0.1)
				(type default)
			)
			(layer "F.Fab")
		)
		(fp_line
			(start 2.2987 7.3533)
			(end -2.2987 7.3533)
			(stroke
				(width 0.1)
				(type default)
			)
			(layer "F.Fab")
		)
		(fp_line
			(start -2.2987 -0.2413)
			(end 2.2987 -0.2413)
			(stroke
				(width 0.1)
				(type default)
			)
			(layer "F.Fab")
		)
		(fp_line
			(start 2.2987 -0.2413)
			(end 2.2987 7.3533)
			(stroke
				(width 0.1)
				(type default)
			)
			(layer "F.Fab")
		)
		(pad "1" smd rect
			(at 0 0 270)
			(size 2.54 3.048)
			(layers "F.Cu" "F.Mask" "F.Paste")
			(net "PVPP_KLM")
		)
		(pad "2" smd rect
			(at 0 7.112 270)
			(size 2.54 3.048)
			(layers "F.Cu" "F.Mask" "F.Paste")
			(net "GND")
		)
	)
	(footprint ""
		(layer "F.Cu")
		(at 273.37258 -84.39912 180)
		(property "Reference" "R3P29"
			(at 0 0 180)
			(layer "F.SilkS")
			(hide yes)
			(effects
				(font
					(size 1.27 1.27)
				)
			)
		)
		(property "Value" ""
			(at 0 0 180)
			(layer "F.Fab")
			(effects
				(font
					(size 1.27 1.27)
				)
			)
		)
		(duplicate_pad_numbers_are_jumpers no)
		(fp_poly
			(pts
				(xy -0.2794 -0.1016) (xy 0.2794 -0.1016) (xy 0.2794 0.9906) (xy -0.2794 0.9906)
			)
			(stroke
				(width 0)
				(type default)
			)
			(fill no)
			(layer "F.CrtYd")
		)
		(fp_line
			(start 0.2794 0.9906)
			(end 0.2794 -0.1016)
			(stroke
				(width 0.1)
				(type default)
			)
			(layer "F.Fab")
		)
		(fp_line
			(start 0.2794 -0.1016)
			(end -0.2794 -0.1016)
			(stroke
				(width 0.1)
				(type default)
			)
			(layer "F.Fab")
		)
		(fp_line
			(start -0.2794 0.9906)
			(end 0.2794 0.9906)
			(stroke
				(width 0.1)
				(type default)
			)
			(layer "F.Fab")
		)
		(fp_line
			(start -0.2794 -0.1016)
			(end -0.2794 0.9906)
			(stroke
				(width 0.1)
				(type default)
			)
			(layer "F.Fab")
		)
		(pad "1" smd rect
			(at 0 0 180)
			(size 0.508 0.508)
			(layers "F.Cu" "F.Mask" "F.Paste")
			(net "PVDDQ_DEF")
		)
		(pad "2" smd rect
			(at 0 0.889 180)
			(size 0.508 0.508)
			(layers "F.Cu" "F.Mask" "F.Paste")
			(net "PWRGD_CPU0_DRAMPWROK_DEF_G")
		)
		(zone
			(layer "F.Cu")
			(hatch none 0.5)
			(connect_pads
				(clearance 0)
			)
			(min_thickness 0.25)
			(keepout
				(tracks not_allowed)
				(vias allowed)
				(pads allowed)
				(copperpour not_allowed)
				(footprints allowed)
			)
			(placement
				(enabled no)
				(sheetname "")
			)
			(fill
				(thermal_gap 0.5)
				(thermal_bridge_width 0.5)
				(island_removal_mode 0)
			)
			(polygon
				(pts
					(xy 273.62658 -85.03412) (xy 273.11858 -85.03412) (xy 273.11858 -84.65312) (xy 273.62658 -84.65312)
				)
			)
		)
		(zone
			(layer "F.Cu")
			(hatch none 0.5)
			(connect_pads
				(clearance 0)
			)
			(min_thickness 0.25)
			(keepout
				(tracks allowed)
				(vias not_allowed)
				(pads allowed)
				(copperpour not_allowed)
				(footprints allowed)
			)
			(placement
				(enabled no)
				(sheetname "")
			)
			(fill
				(thermal_gap 0.5)
				(thermal_bridge_width 0.5)
				(island_removal_mode 0)
			)
			(polygon
				(pts
					(xy 273.62658 -84.65312) (xy 273.11858 -84.65312) (xy 273.11858 -85.03412) (xy 273.62658 -85.03412)
				)
			)
		)
	)
	(footprint ""
		(layer "F.Cu")
		(at 367.077244 -10.916158)
		(property "Reference" "C7G9"
			(at 0 0 0)
			(layer "F.SilkS")
			(hide yes)
			(effects
				(font
					(size 1.27 1.27)
				)
			)
		)
		(property "Value" ""
			(at 0 0 0)
			(layer "F.Fab")
			(effects
				(font
					(size 1.27 1.27)
				)
			)
		)
		(duplicate_pad_numbers_are_jumpers no)
		(fp_rect
			(start -0.3048 0.9906)
			(end 0.3048 -0.1016)
			(stroke
				(width 0)
				(type default)
			)
			(fill no)
			(layer "F.CrtYd")
		)
		(fp_line
			(start -0.3048 -0.1016)
			(end -0.3048 0.9906)
			(stroke
				(width 0.1)
				(type default)
			)
			(layer "F.Fab")
		)
		(fp_line
			(start -0.3048 0.9906)
			(end 0.3048 0.9906)
			(stroke
				(width 0.1)
				(type default)
			)
			(layer "F.Fab")
		)
		(fp_line
			(start 0.3048 -0.1016)
			(end -0.3048 -0.1016)
			(stroke
				(width 0.1)
				(type default)
			)
			(layer "F.Fab")
		)
		(fp_line
			(start 0.3048 0.9906)
			(end 0.3048 -0.1016)
			(stroke
				(width 0.1)
				(type default)
			)
			(layer "F.Fab")
		)
		(pad "1" smd rect
			(at 0 0)
			(size 0.508 0.508)
			(layers "F.Cu" "F.Mask" "F.Paste")
			(net "P3E_CPU0_PE2_SS_TXP<13>")
		)
		(pad "2" smd rect
			(at 0 0.889)
			(size 0.508 0.508)
			(layers "F.Cu" "F.Mask" "F.Paste")
			(net "P3E_CPU0_PE2_SS_C_TXP<13>")
		)
		(zone
			(layer "F.Cu")
			(hatch none 0.5)
			(connect_pads
				(clearance 0)
			)
			(min_thickness 0.25)
			(keepout
				(tracks allowed)
				(vias not_allowed)
				(pads allowed)
				(copperpour not_allowed)
				(footprints allowed)
			)
			(placement
				(enabled no)
				(sheetname "")
			)
			(fill
				(thermal_gap 0.5)
				(thermal_bridge_width 0.5)
				(island_removal_mode 0)
			)
			(polygon
				(pts
					(xy 366.823244 -10.281158) (xy 367.331244 -10.281158) (xy 367.331244 -10.662158) (xy 366.823244 -10.662158)
				)
			)
		)
		(zone
			(layer "F.Cu")
			(hatch none 0.5)
			(connect_pads
				(clearance 0)
			)
			(min_thickness 0.25)
			(keepout
				(tracks not_allowed)
				(vias allowed)
				(pads allowed)
				(copperpour not_allowed)
				(footprints allowed)
			)
			(placement
				(enabled no)
				(sheetname "")
			)
			(fill
				(thermal_gap 0.5)
				(thermal_bridge_width 0.5)
				(island_removal_mode 0)
			)
			(polygon
				(pts
					(xy 366.823244 -10.281158) (xy 367.331244 -10.281158) (xy 367.331244 -10.662158) (xy 366.823244 -10.662158)
				)
			)
		)
	)
	(footprint ""
		(layer "F.Cu")
		(at 398.325848 -150.071074)
		(property "Reference" "C8A9"
			(at 0 0 0)
			(layer "F.SilkS")
			(hide yes)
			(effects
				(font
					(size 1.27 1.27)
				)
			)
		)
		(property "Value" ""
			(at 0 0 0)
			(layer "F.Fab")
			(effects
				(font
					(size 1.27 1.27)
				)
			)
		)
		(duplicate_pad_numbers_are_jumpers no)
		(fp_poly
			(pts
				(xy 0.3048 -0.1016) (xy 0.3048 0.9906) (xy -0.3048 0.9906) (xy -0.3048 -0.1016)
			)
			(stroke
				(width 0)
				(type default)
			)
			(fill no)
			(layer "F.CrtYd")
		)
		(fp_line
			(start -0.3048 -0.1016)
			(end -0.3048 0.9906)
			(stroke
				(width 0.1)
				(type default)
			)
			(layer "F.Fab")
		)
		(fp_line
			(start -0.3048 0.9906)
			(end 0.3048 0.9906)
			(stroke
				(width 0.1)
				(type default)
			)
			(layer "F.Fab")
		)
		(fp_line
			(start 0.3048 -0.1016)
			(end -0.3048 -0.1016)
			(stroke
				(width 0.1)
				(type default)
			)
			(layer "F.Fab")
		)
		(fp_line
			(start 0.3048 0.9906)
			(end 0.3048 -0.1016)
			(stroke
				(width 0.1)
				(type default)
			)
			(layer "F.Fab")
		)
		(pad "1" smd rect
			(at 0 0)
			(size 0.508 0.508)
			(layers "F.Cu" "F.Mask" "F.Paste")
			(net "PWRGD_PVNN_PCH_R")
		)
		(pad "2" smd rect
			(at 0 0.889)
			(size 0.508 0.508)
			(layers "F.Cu" "F.Mask" "F.Paste")
			(net "GND")
		)
		(zone
			(layer "F.Cu")
			(hatch none 0.5)
			(connect_pads
				(clearance 0)
			)
			(min_thickness 0.25)
			(keepout
				(tracks allowed)
				(vias not_allowed)
				(pads allowed)
				(copperpour not_allowed)
				(footprints allowed)
			)
			(placement
				(enabled no)
				(sheetname "")
			)
			(fill
				(thermal_gap 0.5)
				(thermal_bridge_width 0.5)
				(island_removal_mode 0)
			)
			(polygon
				(pts
					(xy 398.071848 -149.817074) (xy 398.579848 -149.817074) (xy 398.579848 -149.436074) (xy 398.071848 -149.436074)
				)
			)
		)
		(zone
			(layer "F.Cu")
			(hatch none 0.5)
			(connect_pads
				(clearance 0)
			)
			(min_thickness 0.25)
			(keepout
				(tracks not_allowed)
				(vias allowed)
				(pads allowed)
				(copperpour not_allowed)
				(footprints allowed)
			)
			(placement
				(enabled no)
				(sheetname "")
			)
			(fill
				(thermal_gap 0.5)
				(thermal_bridge_width 0.5)
				(island_removal_mode 0)
			)
			(polygon
				(pts
					(xy 398.071848 -149.436074) (xy 398.579848 -149.436074) (xy 398.579848 -149.817074) (xy 398.071848 -149.817074)
				)
			)
		)
	)
	(footprint ""
		(layer "F.Cu")
		(at 275.7932 -79.6036 180)
		(property "Reference" "C5D23"
			(at 0 0 180)
			(layer "F.SilkS")
			(hide yes)
			(effects
				(font
					(size 1.27 1.27)
				)
			)
		)
		(property "Value" ""
			(at 0 0 180)
			(layer "F.Fab")
			(effects
				(font
					(size 1.27 1.27)
				)
			)
		)
		(duplicate_pad_numbers_are_jumpers no)
		(fp_poly
			(pts
				(xy -0.4953 -0.2032) (xy 0.4953 -0.2032) (xy 0.4953 1.6002) (xy -0.4953 1.6002)
			)
			(stroke
				(width 0)
				(type default)
			)
			(fill no)
			(layer "F.CrtYd")
		)
		(fp_line
			(start 0.4953 1.6002)
			(end -0.4953 1.6002)
			(stroke
				(width 0.1)
				(type default)
			)
			(layer "F.Fab")
		)
		(fp_line
			(start 0.4953 -0.2032)
			(end 0.4953 1.6002)
			(stroke
				(width 0.1)
				(type default)
			)
			(layer "F.Fab")
		)
		(fp_line
			(start -0.4953 1.6002)
			(end -0.4953 -0.2032)
			(stroke
				(width 0.1)
				(type default)
			)
			(layer "F.Fab")
		)
		(fp_line
			(start -0.4953 -0.2032)
			(end 0.4953 -0.2032)
			(stroke
				(width 0.1)
				(type default)
			)
			(layer "F.Fab")
		)
		(pad "1" smd rect
			(at 0 0 180)
			(size 0.762 0.889)
			(layers "F.Cu" "F.Mask" "F.Paste")
			(net "PVCCMCP_CPU0")
		)
		(pad "2" smd rect
			(at 0 1.397 180)
			(size 0.762 0.889)
			(layers "F.Cu" "F.Mask" "F.Paste")
			(net "GND")
		)
		(zone
			(layer "F.Cu")
			(hatch none 0.5)
			(connect_pads
				(clearance 0)
			)
			(min_thickness 0.25)
			(keepout
				(tracks not_allowed)
				(vias allowed)
				(pads allowed)
				(copperpour not_allowed)
				(footprints allowed)
			)
			(placement
				(enabled no)
				(sheetname "")
			)
			(fill
				(thermal_gap 0.5)
				(thermal_bridge_width 0.5)
				(island_removal_mode 0)
			)
			(polygon
				(pts
					(xy 276.1742 -80.0481) (xy 275.4122 -80.0481) (xy 275.4122 -80.5561) (xy 276.1742 -80.5561)
				)
			)
		)
	)
	(footprint ""
		(layer "F.Cu")
		(at -2.5146 -125.222)
		(property "Reference" "C1B12"
			(at 0 0 0)
			(layer "F.SilkS")
			(hide yes)
			(effects
				(font
					(size 1.27 1.27)
				)
			)
		)
		(property "Value" ""
			(at 0 0 0)
			(layer "F.Fab")
			(effects
				(font
					(size 1.27 1.27)
				)
			)
		)
		(duplicate_pad_numbers_are_jumpers no)
		(fp_rect
			(start -0.3048 0.9906)
			(end 0.3048 -0.1016)
			(stroke
				(width 0)
				(type default)
			)
			(fill no)
			(layer "F.CrtYd")
		)
		(fp_line
			(start -0.3048 -0.1016)
			(end -0.3048 0.9906)
			(stroke
				(width 0.1)
				(type default)
			)
			(layer "F.Fab")
		)
		(fp_line
			(start -0.3048 0.9906)
			(end 0.3048 0.9906)
			(stroke
				(width 0.1)
				(type default)
			)
			(layer "F.Fab")
		)
		(fp_line
			(start 0.3048 -0.1016)
			(end -0.3048 -0.1016)
			(stroke
				(width 0.1)
				(type default)
			)
			(layer "F.Fab")
		)
		(fp_line
			(start 0.3048 0.9906)
			(end 0.3048 -0.1016)
			(stroke
				(width 0.1)
				(type default)
			)
			(layer "F.Fab")
		)
		(pad "1" smd rect
			(at 0 0)
			(size 0.508 0.508)
			(layers "F.Cu" "F.Mask" "F.Paste")
			(net "VR_PVDDQ_KLM_AVSP")
		)
		(pad "2" smd rect
			(at 0 0.889)
			(size 0.508 0.508)
			(layers "F.Cu" "F.Mask" "F.Paste")
			(net "VSENSE_PVDDQ_KLM_N")
		)
		(zone
			(layer "F.Cu")
			(hatch none 0.5)
			(connect_pads
				(clearance 0)
			)
			(min_thickness 0.25)
			(keepout
				(tracks allowed)
				(vias not_allowed)
				(pads allowed)
				(copperpour not_allowed)
				(footprints allowed)
			)
			(placement
				(enabled no)
				(sheetname "")
			)
			(fill
				(thermal_gap 0.5)
				(thermal_bridge_width 0.5)
				(island_removal_mode 0)
			)
			(polygon
				(pts
					(xy -2.7686 -124.587) (xy -2.2606 -124.587) (xy -2.2606 -124.968) (xy -2.7686 -124.968)
				)
			)
		)
	)
	(footprint ""
		(layer "F.Cu")
		(at 155.194 -30.5308)
		(property "Reference" "R3F1"
			(at 0 0 0)
			(layer "F.SilkS")
			(hide yes)
			(effects
				(font
					(size 1.27 1.27)
				)
			)
		)
		(property "Value" ""
			(at 0 0 0)
			(layer "F.Fab")
			(effects
				(font
					(size 1.27 1.27)
				)
			)
		)
		(duplicate_pad_numbers_are_jumpers no)
		(fp_poly
			(pts
				(xy -0.2794 -0.1016) (xy 0.2794 -0.1016) (xy 0.2794 0.9906) (xy -0.2794 0.9906)
			)
			(stroke
				(width 0)
				(type default)
			)
			(fill no)
			(layer "F.CrtYd")
		)
		(fp_line
			(start -0.2794 -0.1016)
			(end -0.2794 0.9906)
			(stroke
				(width 0.1)
				(type default)
			)
			(layer "F.Fab")
		)
		(fp_line
			(start -0.2794 0.9906)
			(end 0.2794 0.9906)
			(stroke
				(width 0.1)
				(type default)
			)
			(layer "F.Fab")
		)
		(fp_line
			(start 0.2794 -0.1016)
			(end -0.2794 -0.1016)
			(stroke
				(width 0.1)
				(type default)
			)
			(layer "F.Fab")
		)
		(fp_line
			(start 0.2794 0.9906)
			(end 0.2794 -0.1016)
			(stroke
				(width 0.1)
				(type default)
			)
			(layer "F.Fab")
		)
		(pad "1" smd rect
			(at 0 0)
			(size 0.508 0.508)
			(layers "F.Cu" "F.Mask" "F.Paste")
			(net "CLK_322M_156M_CPU1_OSC_VRM_DN")
		)
		(pad "2" smd rect
			(at 0 0.889)
			(size 0.508 0.508)
			(layers "F.Cu" "F.Mask" "F.Paste")
			(net "CLK_156M_OSC_CPU1_HFI_DN")
		)
		(zone
			(layer "F.Cu")
			(hatch none 0.5)
			(connect_pads
				(clearance 0)
			)
			(min_thickness 0.25)
			(keepout
				(tracks allowed)
				(vias not_allowed)
				(pads allowed)
				(copperpour not_allowed)
				(footprints allowed)
			)
			(placement
				(enabled no)
				(sheetname "")
			)
			(fill
				(thermal_gap 0.5)
				(thermal_bridge_width 0.5)
				(island_removal_mode 0)
			)
			(polygon
				(pts
					(xy 154.94 -30.2768) (xy 155.448 -30.2768) (xy 155.448 -29.8958) (xy 154.94 -29.8958)
				)
			)
		)
		(zone
			(layer "F.Cu")
			(hatch none 0.5)
			(connect_pads
				(clearance 0)
			)
			(min_thickness 0.25)
			(keepout
				(tracks not_allowed)
				(vias allowed)
				(pads allowed)
				(copperpour not_allowed)
				(footprints allowed)
			)
			(placement
				(enabled no)
				(sheetname "")
			)
			(fill
				(thermal_gap 0.5)
				(thermal_bridge_width 0.5)
				(island_removal_mode 0)
			)
			(polygon
				(pts
					(xy 154.94 -29.8958) (xy 155.448 -29.8958) (xy 155.448 -30.2768) (xy 154.94 -30.2768)
				)
			)
		)
	)
	(footprint ""
		(layer "F.Cu")
		(at 198.925434 -81.423764 90)
		(property "Reference" "EU4D1"
			(at 3.334766 -1.542034 0)
			(unlocked yes)
			(layer "F.SilkS")
			(effects
				(font
					(size 0.7874 0.5842)
					(thickness 0.1524)
				)
			)
		)
		(property "Value" ""
			(at 0 0 90)
			(layer "F.Fab")
			(effects
				(font
					(size 1.27 1.27)
				)
			)
		)
		(duplicate_pad_numbers_are_jumpers no)
		(fp_line
			(start 2.9718 -3.5052)
			(end 2.9718 3.429)
			(stroke
				(width 0.1524)
				(type default)
			)
			(layer "F.SilkS")
		)
		(fp_line
			(start -3.0099 -3.5052)
			(end 2.9718 -3.5052)
			(stroke
				(width 0.1524)
				(type default)
			)
			(layer "F.SilkS")
		)
		(fp_line
			(start 2.9718 3.429)
			(end -3.0099 3.429)
			(stroke
				(width 0.1524)
				(type default)
			)
			(layer "F.SilkS")
		)
		(fp_line
			(start -3.0099 3.429)
			(end -3.0099 -3.5052)
			(stroke
				(width 0.1524)
				(type default)
			)
			(layer "F.SilkS")
		)
		(fp_circle
			(center -3.057398 -2.678684)
			(end -3.057398 -2.551684)
			(stroke
				(width 0.254)
				(type default)
			)
			(fill no)
			(layer "F.SilkS")
		)
		(fp_poly
			(pts
				(xy -2.9972 -3.4925) (xy -2.9972 -2.6924) (xy -2.1971 -3.4925)
			)
			(stroke
				(width 0)
				(type default)
			)
			(fill yes)
			(layer "F.SilkS")
		)
		(fp_poly
			(pts
				(xy -2.549906 -3.050032) (xy -2.549906 3.050032) (xy 2.549906 3.050032) (xy 2.549906 -3.050032)
			)
			(stroke
				(width 0)
				(type default)
			)
			(fill no)
			(layer "F.CrtYd")
		)
		(fp_line
			(start 2.549906 -3.050032)
			(end 2.549906 3.050032)
			(stroke
				(width 0.1)
				(type default)
			)
			(layer "F.Fab")
		)
		(fp_line
			(start -2.549906 -3.050032)
			(end 2.549906 -3.050032)
			(stroke
				(width 0.1)
				(type default)
			)
			(layer "F.Fab")
		)
		(fp_line
			(start 2.549906 3.050032)
			(end -2.549906 3.050032)
			(stroke
				(width 0.1)
				(type default)
			)
			(layer "F.Fab")
		)
		(fp_line
			(start -2.549906 3.050032)
			(end -2.549906 -3.050032)
			(stroke
				(width 0.1)
				(type default)
			)
			(layer "F.Fab")
		)
		(fp_circle
			(center -3.057398 -2.678684)
			(end -3.057398 -2.551684)
			(stroke
				(width 0.254)
				(type default)
			)
			(fill no)
			(layer "F.Fab")
		)
		(pad "1" smd rect
			(at -2.39522 -2.279904 90)
			(size 0.7112 0.254)
			(layers "F.Cu" "F.Mask" "F.Paste")
			(net "PVCCIN_CPU0")
		)
		(pad "2" smd rect
			(at -2.39522 -1.83007 90)
			(size 0.7112 0.254)
			(layers "F.Cu" "F.Mask" "F.Paste")
			(net "GND")
		)
		(pad "3" smd rect
			(at -2.39522 -1.379982 90)
			(size 0.7112 0.254)
			(layers "F.Cu" "F.Mask" "F.Paste")
			(net "VR_PVCCIN_CPU0_PH4_VCIN")
		)
		(pad "4" smd rect
			(at -2.39522 -0.929894 90)
			(size 0.7112 0.254)
			(layers "F.Cu" "F.Mask" "F.Paste")
			(net "P5V_STBY")
		)
		(pad "5" smd rect
			(at -2.39522 -0.48006 90)
			(size 0.7112 0.254)
			(layers "F.Cu" "F.Mask" "F.Paste")
			(net "GND")
		)
		(pad "6" smd rect
			(at -2.39522 -0.029972 90)
			(size 0.7112 0.254)
			(layers "F.Cu" "F.Mask" "F.Paste")
			(net "TP_PVCCIN_CPU0_PH4_GL_0")
		)
		(pad "7" smd custom
			(at 0.016764 1.145032 90)
			(size 0.53975 0.53975)
			(layers "F.Cu" "F.Mask" "F.Paste")
			(net "GND")
			(options
				(clearance outline)
				(anchor circle)
			)
			(primitives
				(gr_poly
					(pts
						(xy -2.7051 1.0795) (xy -2.7051 -0.3683) (xy -0.9271 -0.3683) (xy -0.9271 -1.0795) (xy 2.7051 -1.0795)
						(xy 2.7051 1.0795)
					)
					(width 0)
					(fill yes)
				)
			)
		)
		(pad "10" smd rect
			(at -0.008382 2.874772 90)
			(size 4.3434 0.6096)
			(layers "F.Cu" "F.Mask" "F.Paste")
			(net "VR_PVCCIN_CPU0_PHASE4")
		)
		(pad "25" smd rect
			(at 1.548384 -1.283208 90)
			(size 2.3368 2.0066)
			(layers "F.Cu" "F.Mask" "F.Paste")
			(net "VR_FET_SW_P12V_STBY_PVCCIN_CPU0")
		)
		(pad "30" smd rect
			(at 2.050034 -2.895092 90)
			(size 0.254 0.7112)
			(layers "F.Cu" "F.Mask" "F.Paste")
			(net "VR_FET_SW_P12V_STBY_PVCCIN_CPU0")
		)
		(pad "31" smd rect
			(at 1.599946 -2.895092 90)
			(size 0.254 0.7112)
			(layers "F.Cu" "F.Mask" "F.Paste")
			(net "Net_364")
		)
		(pad "32" smd rect
			(at 1.150112 -2.895092 90)
			(size 0.254 0.7112)
			(layers "F.Cu" "F.Mask" "F.Paste")
			(net "VR_PVCCIN_CPU0_PH4_PHASE")
		)
		(pad "33" smd rect
			(at 0.700024 -2.895092 90)
			(size 0.254 0.7112)
			(layers "F.Cu" "F.Mask" "F.Paste")
			(net "VR_PVCCIN_CPU0_PH4_BOOT_R")
		)
		(pad "34" smd rect
			(at 0.249936 -2.895092 90)
			(size 0.254 0.7112)
			(layers "F.Cu" "F.Mask" "F.Paste")
			(net "VR_PVCCIN_CPU0_PWM4")
		)
		(pad "35" smd rect
			(at -0.199898 -2.895092 90)
			(size 0.254 0.7112)
			(layers "F.Cu" "F.Mask" "F.Paste")
			(net "P5V_STBY")
		)
		(pad "36" smd rect
			(at -0.649986 -2.895092 90)
			(size 0.254 0.7112)
			(layers "F.Cu" "F.Mask" "F.Paste")
			(net "A_TSENSE_PVCCIN_CPU0")
		)
		(pad "37" smd rect
			(at -1.100074 -2.895092 90)
			(size 0.254 0.7112)
			(layers "F.Cu" "F.Mask" "F.Paste")
			(net "VR_PVCCIN_CPU0_PH4_OCSET")
		)
		(pad "38" smd rect
			(at -1.549908 -2.895092 90)
			(size 0.254 0.7112)
			(layers "F.Cu" "F.Mask" "F.Paste")
			(net "ISENSE_PVCCIN_CPU0_PH4_IMON")
		)
		(pad "39" smd rect
			(at -1.999996 -2.895092 90)
			(size 0.254 0.7112)
			(layers "F.Cu" "F.Mask" "F.Paste")
			(net "VR_PVCCIN_CPU0_AIREF4")
		)
		(pad "40" smd rect
			(at -0.871728 -1.283208 90)
			(size 1.8034 2.0066)
			(layers "F.Cu" "F.Mask" "F.Paste")
			(net "GND")
		)
		(pad "41" smd rect
			(at -1.533906 0.247904 90)
			(size 0.508 0.3556)
			(layers "F.Cu" "F.Mask" "F.Paste")
			(net "TP_PVCCIN_CPU0_PH4_GL_1")
		)
	)
	(footprint ""
		(layer "F.Cu")
		(at 33.229296 -61.298582 90)
		(property "Reference" "C1E25"
			(at 0 0 90)
			(layer "F.SilkS")
			(hide yes)
			(effects
				(font
					(size 1.27 1.27)
				)
			)
		)
		(property "Value" ""
			(at 0 0 90)
			(layer "F.Fab")
			(effects
				(font
					(size 1.27 1.27)
				)
			)
		)
		(duplicate_pad_numbers_are_jumpers no)
		(fp_rect
			(start 0.3048 0.9906)
			(end -0.3048 -0.1016)
			(stroke
				(width 0)
				(type default)
			)
			(fill no)
			(layer "F.CrtYd")
		)
		(fp_line
			(start 0.3048 -0.1016)
			(end -0.3048 -0.1016)
			(stroke
				(width 0.1)
				(type default)
			)
			(layer "F.Fab")
		)
		(fp_line
			(start -0.3048 -0.1016)
			(end -0.3048 0.9906)
			(stroke
				(width 0.1)
				(type default)
			)
			(layer "F.Fab")
		)
		(fp_line
			(start 0.3048 0.9906)
			(end 0.3048 -0.1016)
			(stroke
				(width 0.1)
				(type default)
			)
			(layer "F.Fab")
		)
		(fp_line
			(start -0.3048 0.9906)
			(end 0.3048 0.9906)
			(stroke
				(width 0.1)
				(type default)
			)
			(layer "F.Fab")
		)
		(pad "1" smd rect
			(at 0 0 90)
			(size 0.508 0.508)
			(layers "F.Cu" "F.Mask" "F.Paste")
			(net "P5V_STBY")
		)
		(pad "2" smd rect
			(at 0 0.889 90)
			(size 0.508 0.508)
			(layers "F.Cu" "F.Mask" "F.Paste")
			(net "GND")
		)
		(zone
			(layer "F.Cu")
			(hatch none 0.5)
			(connect_pads
				(clearance 0)
			)
			(min_thickness 0.25)
			(keepout
				(tracks not_allowed)
				(vias allowed)
				(pads allowed)
				(copperpour not_allowed)
				(footprints allowed)
			)
			(placement
				(enabled no)
				(sheetname "")
			)
			(fill
				(thermal_gap 0.5)
				(thermal_bridge_width 0.5)
				(island_removal_mode 0)
			)
			(polygon
				(pts
					(xy 33.864296 -61.552582) (xy 33.483296 -61.552582) (xy 33.483296 -61.044582) (xy 33.864296 -61.044582)
				)
			)
		)
		(zone
			(layer "F.Cu")
			(hatch none 0.5)
			(connect_pads
				(clearance 0)
			)
			(min_thickness 0.25)
			(keepout
				(tracks allowed)
				(vias not_allowed)
				(pads allowed)
				(copperpour not_allowed)
				(footprints allowed)
			)
			(placement
				(enabled no)
				(sheetname "")
			)
			(fill
				(thermal_gap 0.5)
				(thermal_bridge_width 0.5)
				(island_removal_mode 0)
			)
			(polygon
				(pts
					(xy 33.864296 -61.552582) (xy 33.483296 -61.552582) (xy 33.483296 -61.044582) (xy 33.864296 -61.044582)
				)
			)
		)
	)
	(footprint ""
		(layer "F.Cu")
		(at 364.617 -113.792 90)
		(property "Reference" "C7B26"
			(at 0 0 90)
			(layer "F.SilkS")
			(hide yes)
			(effects
				(font
					(size 1.27 1.27)
				)
			)
		)
		(property "Value" ""
			(at 0 0 90)
			(layer "F.Fab")
			(effects
				(font
					(size 1.27 1.27)
				)
			)
		)
		(duplicate_pad_numbers_are_jumpers no)
		(fp_poly
			(pts
				(xy 0.3048 -0.1016) (xy 0.3048 0.9906) (xy -0.3048 0.9906) (xy -0.3048 -0.1016)
			)
			(stroke
				(width 0)
				(type default)
			)
			(fill no)
			(layer "F.CrtYd")
		)
		(fp_line
			(start 0.3048 -0.1016)
			(end -0.3048 -0.1016)
			(stroke
				(width 0.1)
				(type default)
			)
			(layer "F.Fab")
		)
		(fp_line
			(start -0.3048 -0.1016)
			(end -0.3048 0.9906)
			(stroke
				(width 0.1)
				(type default)
			)
			(layer "F.Fab")
		)
		(fp_line
			(start 0.3048 0.9906)
			(end 0.3048 -0.1016)
			(stroke
				(width 0.1)
				(type default)
			)
			(layer "F.Fab")
		)
		(fp_line
			(start -0.3048 0.9906)
			(end 0.3048 0.9906)
			(stroke
				(width 0.1)
				(type default)
			)
			(layer "F.Fab")
		)
		(pad "1" smd rect
			(at 0 0 90)
			(size 0.508 0.508)
			(layers "F.Cu" "F.Mask" "F.Paste")
			(net "DMI_CPU0_PCH_TX_DN<3>")
		)
		(pad "2" smd rect
			(at 0 0.889 90)
			(size 0.508 0.508)
			(layers "F.Cu" "F.Mask" "F.Paste")
			(net "DMI_CPU0_PCH_TX_C_DN<3>")
		)
		(zone
			(layer "F.Cu")
			(hatch none 0.5)
			(connect_pads
				(clearance 0)
			)
			(min_thickness 0.25)
			(keepout
				(tracks allowed)
				(vias not_allowed)
				(pads allowed)
				(copperpour not_allowed)
				(footprints allowed)
			)
			(placement
				(enabled no)
				(sheetname "")
			)
			(fill
				(thermal_gap 0.5)
				(thermal_bridge_width 0.5)
				(island_removal_mode 0)
			)
			(polygon
				(pts
					(xy 364.871 -113.538) (xy 364.871 -114.046) (xy 365.252 -114.046) (xy 365.252 -113.538)
				)
			)
		)
		(zone
			(layer "F.Cu")
			(hatch none 0.5)
			(connect_pads
				(clearance 0)
			)
			(min_thickness 0.25)
			(keepout
				(tracks not_allowed)
				(vias allowed)
				(pads allowed)
				(copperpour not_allowed)
				(footprints allowed)
			)
			(placement
				(enabled no)
				(sheetname "")
			)
			(fill
				(thermal_gap 0.5)
				(thermal_bridge_width 0.5)
				(island_removal_mode 0)
			)
			(polygon
				(pts
					(xy 365.252 -113.538) (xy 365.252 -114.046) (xy 364.871 -114.046) (xy 364.871 -113.538)
				)
			)
		)
	)
	(footprint ""
		(layer "F.Cu")
		(at 169.6212 -7.1247 180)
		(property "Reference" "C4G11"
			(at 0 0 180)
			(layer "F.SilkS")
			(hide yes)
			(effects
				(font
					(size 1.27 1.27)
				)
			)
		)
		(property "Value" ""
			(at 0 0 180)
			(layer "F.Fab")
			(effects
				(font
					(size 1.27 1.27)
				)
			)
		)
		(duplicate_pad_numbers_are_jumpers no)
		(fp_poly
			(pts
				(xy 0.3048 -0.1016) (xy 0.3048 0.9906) (xy -0.3048 0.9906) (xy -0.3048 -0.1016)
			)
			(stroke
				(width 0)
				(type default)
			)
			(fill no)
			(layer "F.CrtYd")
		)
		(fp_line
			(start 0.3048 0.9906)
			(end 0.3048 -0.1016)
			(stroke
				(width 0.1)
				(type default)
			)
			(layer "F.Fab")
		)
		(fp_line
			(start 0.3048 -0.1016)
			(end -0.3048 -0.1016)
			(stroke
				(width 0.1)
				(type default)
			)
			(layer "F.Fab")
		)
		(fp_line
			(start -0.3048 0.9906)
			(end 0.3048 0.9906)
			(stroke
				(width 0.1)
				(type default)
			)
			(layer "F.Fab")
		)
		(fp_line
			(start -0.3048 -0.1016)
			(end -0.3048 0.9906)
			(stroke
				(width 0.1)
				(type default)
			)
			(layer "F.Fab")
		)
		(pad "1" smd rect
			(at 0 0 180)
			(size 0.508 0.508)
			(layers "F.Cu" "F.Mask" "F.Paste")
			(net "VR_COMP_PVPP_GHJ")
		)
		(pad "2" smd rect
			(at 0 0.889 180)
			(size 0.508 0.508)
			(layers "F.Cu" "F.Mask" "F.Paste")
			(net "VR_FB_PVPP_GHJ")
		)
		(zone
			(layer "F.Cu")
			(hatch none 0.5)
			(connect_pads
				(clearance 0)
			)
			(min_thickness 0.25)
			(keepout
				(tracks not_allowed)
				(vias allowed)
				(pads allowed)
				(copperpour not_allowed)
				(footprints allowed)
			)
			(placement
				(enabled no)
				(sheetname "")
			)
			(fill
				(thermal_gap 0.5)
				(thermal_bridge_width 0.5)
				(island_removal_mode 0)
			)
			(polygon
				(pts
					(xy 169.8752 -7.7597) (xy 169.3672 -7.7597) (xy 169.3672 -7.3787) (xy 169.8752 -7.3787)
				)
			)
		)
		(zone
			(layer "F.Cu")
			(hatch none 0.5)
			(connect_pads
				(clearance 0)
			)
			(min_thickness 0.25)
			(keepout
				(tracks allowed)
				(vias not_allowed)
				(pads allowed)
				(copperpour not_allowed)
				(footprints allowed)
			)
			(placement
				(enabled no)
				(sheetname "")
			)
			(fill
				(thermal_gap 0.5)
				(thermal_bridge_width 0.5)
				(island_removal_mode 0)
			)
			(polygon
				(pts
					(xy 169.8752 -7.3787) (xy 169.3672 -7.3787) (xy 169.3672 -7.7597) (xy 169.8752 -7.7597)
				)
			)
		)
	)
	(footprint ""
		(layer "F.Cu")
		(at 181.9656 -135.9662 180)
		(property "Reference" "C4A20"
			(at 0 0 180)
			(layer "F.SilkS")
			(hide yes)
			(effects
				(font
					(size 1.27 1.27)
				)
			)
		)
		(property "Value" ""
			(at 0 0 180)
			(layer "F.Fab")
			(effects
				(font
					(size 1.27 1.27)
				)
			)
		)
		(duplicate_pad_numbers_are_jumpers no)
		(fp_poly
			(pts
				(xy 0.3048 -0.1016) (xy 0.3048 0.9906) (xy -0.3048 0.9906) (xy -0.3048 -0.1016)
			)
			(stroke
				(width 0)
				(type default)
			)
			(fill no)
			(layer "F.CrtYd")
		)
		(fp_line
			(start 0.3048 0.9906)
			(end 0.3048 -0.1016)
			(stroke
				(width 0.1)
				(type default)
			)
			(layer "F.Fab")
		)
		(fp_line
			(start 0.3048 -0.1016)
			(end -0.3048 -0.1016)
			(stroke
				(width 0.1)
				(type default)
			)
			(layer "F.Fab")
		)
		(fp_line
			(start -0.3048 0.9906)
			(end 0.3048 0.9906)
			(stroke
				(width 0.1)
				(type default)
			)
			(layer "F.Fab")
		)
		(fp_line
			(start -0.3048 -0.1016)
			(end -0.3048 0.9906)
			(stroke
				(width 0.1)
				(type default)
			)
			(layer "F.Fab")
		)
		(pad "1" smd rect
			(at 0 0 180)
			(size 0.508 0.508)
			(layers "F.Cu" "F.Mask" "F.Paste")
			(net "VR_FET_SW_P12V_STBY_PVPP_KLM")
		)
		(pad "2" smd rect
			(at 0 0.889 180)
			(size 0.508 0.508)
			(layers "F.Cu" "F.Mask" "F.Paste")
			(net "GND")
		)
		(zone
			(layer "F.Cu")
			(hatch none 0.5)
			(connect_pads
				(clearance 0)
			)
			(min_thickness 0.25)
			(keepout
				(tracks not_allowed)
				(vias allowed)
				(pads allowed)
				(copperpour not_allowed)
				(footprints allowed)
			)
			(placement
				(enabled no)
				(sheetname "")
			)
			(fill
				(thermal_gap 0.5)
				(thermal_bridge_width 0.5)
				(island_removal_mode 0)
			)
			(polygon
				(pts
					(xy 182.2196 -136.6012) (xy 181.7116 -136.6012) (xy 181.7116 -136.2202) (xy 182.2196 -136.2202)
				)
			)
		)
		(zone
			(layer "F.Cu")
			(hatch none 0.5)
			(connect_pads
				(clearance 0)
			)
			(min_thickness 0.25)
			(keepout
				(tracks allowed)
				(vias not_allowed)
				(pads allowed)
				(copperpour not_allowed)
				(footprints allowed)
			)
			(placement
				(enabled no)
				(sheetname "")
			)
			(fill
				(thermal_gap 0.5)
				(thermal_bridge_width 0.5)
				(island_removal_mode 0)
			)
			(polygon
				(pts
					(xy 182.2196 -136.2202) (xy 181.7116 -136.2202) (xy 181.7116 -136.6012) (xy 182.2196 -136.6012)
				)
			)
		)
	)
	(footprint ""
		(layer "F.Cu")
		(at 497.05006 -57.079896 90)
		(property "Reference" "J30W1"
			(at 0 0 90)
			(layer "F.SilkS")
			(hide yes)
			(effects
				(font
					(size 1.27 1.27)
				)
			)
		)
		(property "Value" "*"
			(at 6.604 -3.1623 90)
			(unlocked yes)
			(layer "F.Fab")
			(hide yes)
			(effects
				(font
					(size 1.27 1.016)
					(thickness 0.1524)
				)
			)
		)
		(property "Device Type" "SKT-USB32-8-GP_SOCKET-G4-SKT-UA"
			(at 6.604 -4.6863 90)
			(unlocked yes)
			(layer "F.Fab")
			(hide yes)
			(effects
				(font
					(size 1.27 1.016)
					(thickness 0.1524)
				)
			)
		)
		(duplicate_pad_numbers_are_jumpers no)
		(fp_line
			(start 3.665474 -2.71526)
			(end 4.275074 -2.71526)
			(stroke
				(width 0.3048)
				(type default)
			)
			(layer "F.SilkS")
		)
		(fp_line
			(start 0.758698 -2.71526)
			(end 1.241298 -2.71526)
			(stroke
				(width 0.3048)
				(type default)
			)
			(layer "F.SilkS")
		)
		(fp_line
			(start -1.241298 -2.71526)
			(end -0.758698 -2.71526)
			(stroke
				(width 0.3048)
				(type default)
			)
			(layer "F.SilkS")
		)
		(fp_line
			(start -4.275074 -2.71526)
			(end -3.665474 -2.71526)
			(stroke
				(width 0.3048)
				(type default)
			)
			(layer "F.SilkS")
		)
		(fp_line
			(start 5.3594 -2.6162)
			(end -5.3594 -2.6162)
			(stroke
				(width 0.1524)
				(type default)
			)
			(layer "F.SilkS")
		)
		(fp_line
			(start -5.3594 -2.6162)
			(end -5.3594 7.366)
			(stroke
				(width 0.1524)
				(type default)
			)
			(layer "F.SilkS")
		)
		(fp_line
			(start 5.240274 -1.75006)
			(end 5.240274 -0.60706)
			(stroke
				(width 0.3048)
				(type default)
			)
			(layer "F.SilkS")
		)
		(fp_line
			(start -5.240274 -0.60706)
			(end -5.240274 -1.75006)
			(stroke
				(width 0.3048)
				(type default)
			)
			(layer "F.SilkS")
		)
		(fp_line
			(start 5.465318 2.716022)
			(end 5.465318 3.884422)
			(stroke
				(width 0.3048)
				(type default)
			)
			(layer "F.SilkS")
		)
		(fp_line
			(start -3.534918 2.716022)
			(end -3.534918 3.884422)
			(stroke
				(width 0.3048)
				(type default)
			)
			(layer "F.SilkS")
		)
		(fp_line
			(start 3.534918 3.884422)
			(end 3.534918 2.716022)
			(stroke
				(width 0.3048)
				(type default)
			)
			(layer "F.SilkS")
		)
		(fp_line
			(start -5.465318 3.884422)
			(end -5.465318 2.716022)
			(stroke
				(width 0.3048)
				(type default)
			)
			(layer "F.SilkS")
		)
		(fp_line
			(start 5.3594 7.366)
			(end 5.3594 -2.6162)
			(stroke
				(width 0.1524)
				(type default)
			)
			(layer "F.SilkS")
		)
		(fp_line
			(start -5.3594 7.366)
			(end 5.3594 7.366)
			(stroke
				(width 0.1524)
				(type default)
			)
			(layer "F.SilkS")
		)
		(fp_arc
			(start 4.275074 -2.71526)
			(mid 4.957573 -2.432559)
			(end 5.240274 -1.75006)
			(stroke
				(width 0.3048)
				(type default)
			)
			(layer "F.SilkS")
		)
		(fp_arc
			(start 1.241298 -2.71526)
			(mid 1.948816 -2.35599)
			(end 2.076196 -1.572768)
			(stroke
				(width 0.3048)
				(type default)
			)
			(layer "F.SilkS")
		)
		(fp_arc
			(start -0.758698 -2.71526)
			(mid -0.320687 -2.597938)
			(end 0 -2.277364)
			(stroke
				(width 0.3048)
				(type default)
			)
			(layer "F.SilkS")
		)
		(fp_arc
			(start -3.665474 -2.71526)
			(mid -3.006095 -2.455016)
			(end -2.702306 -1.814576)
			(stroke
				(width 0.3048)
				(type default)
			)
			(layer "F.SilkS")
		)
		(fp_arc
			(start 0 -2.277364)
			(mid 0.32071 -2.597898)
			(end 0.758698 -2.71526)
			(stroke
				(width 0.3048)
				(type default)
			)
			(layer "F.SilkS")
		)
		(fp_arc
			(start -5.240274 -1.75006)
			(mid -4.957573 -2.432559)
			(end -4.275074 -2.71526)
			(stroke
				(width 0.3048)
				(type default)
			)
			(layer "F.SilkS")
		)
		(fp_arc
			(start 2.70637 -1.642618)
			(mid 2.946059 -2.393384)
			(end 3.665474 -2.71526)
			(stroke
				(width 0.3048)
				(type default)
			)
			(layer "F.SilkS")
		)
		(fp_arc
			(start -2.078736 -1.580896)
			(mid -1.946295 -2.359421)
			(end -1.241298 -2.71526)
			(stroke
				(width 0.3048)
				(type default)
			)
			(layer "F.SilkS")
		)
		(fp_arc
			(start 5.240274 -0.60706)
			(mid 4.78892 0.209992)
			(end 3.85699 0.26289)
			(stroke
				(width 0.3048)
				(type default)
			)
			(layer "F.SilkS")
		)
		(fp_arc
			(start -4.015232 0.32258)
			(mid -4.858568 0.161889)
			(end -5.240274 -0.60706)
			(stroke
				(width 0.3048)
				(type default)
			)
			(layer "F.SilkS")
		)
		(fp_arc
			(start 3.756914 0.589534)
			(mid 4.197376 1.413733)
			(end 3.474974 2.0066)
			(stroke
				(width 0.3048)
				(type default)
			)
			(layer "F.SilkS")
		)
		(fp_arc
			(start -2.8829 1.708404)
			(mid -3.143508 1.927851)
			(end -3.474974 2.0066)
			(stroke
				(width 0.3048)
				(type default)
			)
			(layer "F.SilkS")
		)
		(fp_arc
			(start 3.474974 2.0066)
			(mid 3.18054 1.945172)
			(end 2.935224 1.771142)
			(stroke
				(width 0.3048)
				(type default)
			)
			(layer "F.SilkS")
		)
		(fp_arc
			(start -3.474974 2.0066)
			(mid -4.181898 1.476973)
			(end -3.87223 0.649732)
			(stroke
				(width 0.3048)
				(type default)
			)
			(layer "F.SilkS")
		)
		(fp_arc
			(start 3.534918 2.716022)
			(mid 4.500118 1.750822)
			(end 5.465318 2.716022)
			(stroke
				(width 0.3048)
				(type default)
			)
			(layer "F.SilkS")
		)
		(fp_arc
			(start -5.465318 2.716022)
			(mid -4.500118 1.750822)
			(end -3.534918 2.716022)
			(stroke
				(width 0.3048)
				(type default)
			)
			(layer "F.SilkS")
		)
		(fp_arc
			(start 5.465318 3.884422)
			(mid 4.500118 4.849622)
			(end 3.534918 3.884422)
			(stroke
				(width 0.3048)
				(type default)
			)
			(layer "F.SilkS")
		)
		(fp_arc
			(start -3.534918 3.884422)
			(mid -4.500118 4.849622)
			(end -5.465318 3.884422)
			(stroke
				(width 0.3048)
				(type default)
			)
			(layer "F.SilkS")
		)
		(fp_rect
			(start -4.6228 7.112)
			(end 4.6228 -1.8288)
			(stroke
				(width 0)
				(type default)
			)
			(fill no)
			(layer "F.CrtYd")
		)
		(fp_poly
			(pts
				(xy -5.6134 7.62) (xy -5.6134 -2.8702) (xy 5.6134 -2.8702) (xy 5.6134 -0.00635) (xy 4.6228 -0.00635)
				(xy 4.6228 -1.8288) (xy -4.6228 -1.8288) (xy -4.6228 7.112) (xy 4.6228 7.112) (xy 4.6228 0.00635)
				(xy 5.6134 0.00635) (xy 5.6134 7.62)
			)
			(stroke
				(width 0)
				(type default)
			)
			(fill no)
			(layer "F.CrtYd")
		)
		(fp_rect
			(start -5.6134 7.62)
			(end 5.6134 -2.8702)
			(stroke
				(width 0)
				(type default)
			)
			(fill no)
			(layer "F.Fab")
		)
		(pad "" np_thru_hole circle
			(at -3.350006 0 90)
			(size 0.254 0.254)
			(drill 0.762)
			(layers "*.Cu" "*.Mask")
			(clearance 0.6096)
			(thermal_gap 0.6096)
		)
		(pad "" np_thru_hole circle
			(at 3.150108 0 90)
			(size 0.254 0.254)
			(drill 0.6604)
			(layers "*.Cu" "*.Mask")
			(clearance 0.5588)
			(thermal_gap 0.5588)
		)
		(pad "A1" smd rect
			(at -2.750058 -0.8001 90)
			(size 0.3048 0.8128)
			(layers "F.Cu" "F.Mask" "F.Paste")
			(net "GND")
		)
		(pad "A2" smd rect
			(at -2.249932 -0.8001 90)
			(size 0.3048 0.8128)
			(layers "F.Cu" "F.Mask" "F.Paste")
			(net "USB3_P01_FB_TXP")
		)
		(pad "A3" smd rect
			(at -1.75006 -0.8001 90)
			(size 0.3048 0.8128)
			(layers "F.Cu" "F.Mask" "F.Paste")
			(net "USB3_P01_FB_TXN")
		)
		(pad "A4" smd rect
			(at -1.249934 -0.7493 90)
			(size 0.3048 0.7112)
			(layers "F.Cu" "F.Mask" "F.Paste")
			(net "P5V_STBY_USBC")
		)
		(pad "A5" smd rect
			(at -0.750062 -0.7493 90)
			(size 0.3048 0.7112)
			(layers "F.Cu" "F.Mask" "F.Paste")
			(net "Net_6503")
		)
		(pad "A6" smd rect
			(at -0.249936 -0.8001 90)
			(size 0.3048 0.8128)
			(layers "F.Cu" "F.Mask" "F.Paste")
			(net "Net_6499")
		)
		(pad "A7" smd rect
			(at 0.249936 -0.8001 90)
			(size 0.3048 0.8128)
			(layers "F.Cu" "F.Mask" "F.Paste")
			(net "Net_6501")
		)
		(pad "A8" smd rect
			(at 0.750062 -0.7493 90)
			(size 0.3048 0.7112)
			(layers "F.Cu" "F.Mask" "F.Paste")
			(net "Net_6495")
		)
		(pad "A9" smd rect
			(at 1.249934 -0.7493 90)
			(size 0.3048 0.7112)
			(layers "F.Cu" "F.Mask" "F.Paste")
			(net "P5V_STBY_USBC")
		)
		(pad "A10" smd rect
			(at 1.75006 -0.8001 90)
			(size 0.3048 0.8128)
			(layers "F.Cu" "F.Mask" "F.Paste")
			(net "Net_6493")
		)
		(pad "A11" smd rect
			(at 2.249932 -0.8001 90)
			(size 0.3048 0.8128)
			(layers "F.Cu" "F.Mask" "F.Paste")
			(net "Net_6492")
		)
		(pad "A12" smd custom
			(at 2.750058 -0.8001 90)
			(size 0.0762 0.0762)
			(layers "F.Cu" "F.Mask" "F.Paste")
			(net "GND")
			(options
				(clearance outline)
				(anchor circle)
			)
			(primitives
				(gr_poly
					(pts
						(xy -0.1524 0.4064) (xy -0.1524 -0.4064) (xy 0.1524 -0.4064)
						(arc
							(start 0.1524 0.284988)
							(mid 0.063554 0.338103)
							(end -0.014224 0.4064)
						)
					)
					(width 0)
					(fill yes)
				)
			)
		)
		(pad "B1" smd rect
			(at 2.724658 0.899922 90)
			(size 0.254 0.8128)
			(layers "F.Cu" "F.Mask" "F.Paste")
			(net "GND")
		)
		(pad "B2" smd rect
			(at 2.249932 0.899922 90)
			(size 0.3048 0.8128)
			(layers "F.Cu" "F.Mask" "F.Paste")
			(net "Net_380")
		)
		(pad "B3" smd rect
			(at 1.75006 0.899922 90)
			(size 0.3048 0.8128)
			(layers "F.Cu" "F.Mask" "F.Paste")
			(net "Net_381")
		)
		(pad "B4" smd rect
			(at 1.249934 0.899922 90)
			(size 0.3048 0.8128)
			(layers "F.Cu" "F.Mask" "F.Paste")
			(net "P5V_STBY_USBC")
		)
		(pad "B5" smd rect
			(at 0.750062 0.899922 90)
			(size 0.3048 0.8128)
			(layers "F.Cu" "F.Mask" "F.Paste")
			(net "Net_6502")
		)
		(pad "B6" smd rect
			(at 0.249936 0.899922 90)
			(size 0.3048 0.8128)
			(layers "F.Cu" "F.Mask" "F.Paste")
			(net "Net_6498")
		)
		(pad "B7" smd rect
			(at -0.249936 0.899922 90)
			(size 0.3048 0.8128)
			(layers "F.Cu" "F.Mask" "F.Paste")
			(net "Net_6500")
		)
		(pad "B8" smd rect
			(at -0.750062 0.899922 90)
			(size 0.3048 0.8128)
			(layers "F.Cu" "F.Mask" "F.Paste")
			(net "Net_6494")
		)
		(pad "B9" smd rect
			(at -1.249934 0.899922 90)
			(size 0.3048 0.8128)
			(layers "F.Cu" "F.Mask" "F.Paste")
			(net "P5V_STBY_USBC")
		)
		(pad "B10" smd rect
			(at -1.75006 0.899922 90)
			(size 0.3048 0.8128)
			(layers "F.Cu" "F.Mask" "F.Paste")
			(net "USB3_P01_FB_RXN")
		)
		(pad "B11" smd rect
			(at -2.249932 0.899922 90)
			(size 0.3048 0.8128)
			(layers "F.Cu" "F.Mask" "F.Paste")
			(net "USB3_P01_FB_RXP")
		)
		(pad "B12" smd rect
			(at -2.724658 0.899922 90)
			(size 0.254 0.8128)
			(layers "F.Cu" "F.Mask" "F.Paste")
			(net "GND")
		)
		(pad "PTH1" thru_hole custom
			(at -4.275074 -1.75006 90)
			(size 0.457329 0.457329)
			(drill 0.0254)
			(layers "*.Cu" "*.Mask")
			(remove_unused_layers no)
			(net "GND")
			(clearance 0.254)
			(thermal_gap 0.254)
			(options
				(clearance outline)
				(anchor circle)
			)
			(primitives
				(gr_poly
					(pts
						(arc
							(start 0.045974 1.070102)
							(mid -0.585696 1.112558)
							(end -0.9144 0.5715)
						)
						(arc
							(start -0.9144 -0.5715)
							(mid -0.735852 -1.002552)
							(end -0.3048 -1.1811)
						)
						(arc
							(start 0.3048 -1.1811)
							(mid 0.9144 -0.5715)
							(end 0.3048 0.0381)
						)
						(arc
							(start 0.3048 0.5715)
							(mid 0.301608 0.633547)
							(end 0.2921 0.694944)
						)
						(arc
							(start 0.2921 0.694944)
							(mid 0.1316 0.857963)
							(end 0.045974 1.070102)
						)
					)
					(width 0)
					(fill yes)
				)
			)
		)
		(pad "PTH2" thru_hole custom
			(at 4.275074 -1.75006 90)
			(size 0.457329 0.457329)
			(drill 0.0254)
			(layers "*.Cu" "*.Mask")
			(remove_unused_layers no)
			(net "GND")
			(clearance 0.254)
			(thermal_gap 0.254)
			(options
				(clearance outline)
				(anchor circle)
			)
			(primitives
				(gr_poly
					(pts
						(arc
							(start 0.9144 0.5715)
							(mid 0.3048 1.1811)
							(end -0.3048 0.5715)
						)
						(arc
							(start -0.3048 0.0381)
							(mid -0.9144 -0.5715)
							(end -0.3048 -1.1811)
						)
						(arc
							(start 0.3048 -1.1811)
							(mid 0.735852 -1.002552)
							(end 0.9144 -0.5715)
						)
					)
					(width 0)
					(fill yes)
				)
			)
		)
		(pad "PTH3" thru_hole oval
			(at -0.999998 -1.75006 90)
			(size 1.524 1.0414)
			(drill oval 0.8128 0.508
				(offset 0 -0.0889)
			)
			(layers "*.Cu" "*.Mask")
			(remove_unused_layers no)
			(net "GND")
			(clearance 0.1524)
			(thermal_gap 0.1524)
		)
		(pad "PTH4" thru_hole oval
			(at 0.999998 -1.75006 90)
			(size 1.524 1.0414)
			(drill oval 0.8128 0.508
				(offset 0 -0.0889)
			)
			(layers "*.Cu" "*.Mask")
			(remove_unused_layers no)
			(net "GND")
			(clearance 0.1524)
			(thermal_gap 0.1524)
		)
		(pad "PTH5" thru_hole circle
			(at -3.474974 1.27 90)
			(size 0.762 0.762)
			(drill 0.4572)
			(layers "*.Cu" "*.Mask")
			(remove_unused_layers no)
			(net "GND")
			(clearance 0.2032)
			(thermal_gap 0.2032)
		)
		(pad "PTH6" thru_hole circle
			(at 3.474974 1.27 90)
			(size 0.762 0.762)
			(drill 0.4572)
			(layers "*.Cu" "*.Mask")
			(remove_unused_layers no)
			(net "GND")
			(clearance 0.2032)
			(thermal_gap 0.2032)
		)
		(pad "PTH7" thru_hole oval
			(at -4.500118 3.50012 90)
			(size 1.2192 2.3876)
			(drill oval 0.508 1.524
				(offset 0 -0.199898)
			)
			(layers "*.Cu" "*.Mask")
			(remove_unused_layers no)
			(net "GND")
			(clearance 0.1524)
			(thermal_gap 0.1524)
		)
		(pad "PTH8" thru_hole oval
			(at 4.500118 3.50012 90)
			(size 1.2192 2.3876)
			(drill oval 0.508 1.524
				(offset 0 -0.199898)
			)
			(layers "*.Cu" "*.Mask")
			(remove_unused_layers no)
			(net "GND")
			(clearance 0.1524)
			(thermal_gap 0.1524)
		)
		(zone
			(layers "F.Cu" "B.Cu" "In1.Cu" "In2.Cu" "In3.Cu" "In4.Cu" "In5.Cu" "In6.Cu"
				"In7.Cu" "In8.Cu" "In9.Cu" "In10.Cu" "In11.Cu" "In12.Cu"
			)
			(hatch none 0.5)
			(connect_pads
				(clearance 0)
			)
			(min_thickness 0.25)
			(keepout
				(tracks not_allowed)
				(vias allowed)
				(pads allowed)
				(copperpour not_allowed)
				(footprints allowed)
			)
			(placement
				(enabled no)
				(sheetname "")
			)
			(fill
				(thermal_gap 0.5)
				(thermal_bridge_width 0.5)
				(island_removal_mode 0)
			)
			(polygon
				(pts
					(arc
						(start 497.68506 -60.230004)
						(mid 496.41506 -60.230004)
						(end 497.68506 -60.230004)
					)
				)
			)
		)
		(zone
			(layers "F.Cu" "B.Cu" "In1.Cu" "In2.Cu" "In3.Cu" "In4.Cu" "In5.Cu" "In6.Cu"
				"In7.Cu" "In8.Cu" "In9.Cu" "In10.Cu" "In11.Cu" "In12.Cu"
			)
			(hatch none 0.5)
			(connect_pads
				(clearance 0)
			)
			(min_thickness 0.25)
			(keepout
				(tracks not_allowed)
				(vias allowed)
				(pads allowed)
				(copperpour not_allowed)
				(footprints allowed)
			)
			(placement
				(enabled no)
				(sheetname "")
			)
			(fill
				(thermal_gap 0.5)
				(thermal_bridge_width 0.5)
				(island_removal_mode 0)
			)
			(polygon
				(pts
					(arc
						(start 497.73586 -53.72989)
						(mid 496.36426 -53.72989)
						(end 497.73586 -53.72989)
					)
				)
			)
		)
	)
	(footprint ""
		(layer "F.Cu")
		(at 104.99979 -76.550012 180)
		(property "Reference" "U2D1"
			(at 25.19299 30.484318 0)
			(unlocked yes)
			(layer "F.SilkS")
			(effects
				(font
					(size 0.7874 0.5842)
					(thickness 0.1524)
				)
			)
		)
		(property "Value" ""
			(at 0 0 180)
			(layer "F.Fab")
			(effects
				(font
					(size 1.27 1.27)
				)
			)
		)
		(duplicate_pad_numbers_are_jumpers no)
		(fp_line
			(start -34.147506 26.518616)
			(end -34.147506 26.519886)
			(stroke
				(width 0.1)
				(type default)
			)
			(layer "F.SilkS")
		)
		(fp_line
			(start -36.773358 14.507718)
			(end -36.773358 14.5034)
			(stroke
				(width 0.1)
				(type default)
			)
			(layer "F.SilkS")
		)
		(fp_line
			(start -37.19576 22.425914)
			(end -37.19576 22.427184)
			(stroke
				(width 0.1)
				(type default)
			)
			(layer "F.SilkS")
		)
		(fp_line
			(start -38.05047 -13.229082)
			(end -37.362892 -13.229082)
			(stroke
				(width 0.1)
				(type default)
			)
			(layer "F.SilkS")
		)
		(fp_line
			(start -38.079426 -9.269984)
			(end -38.079426 -9.27354)
			(stroke
				(width 0.1)
				(type default)
			)
			(layer "F.SilkS")
		)
		(fp_line
			(start -38.443662 -17.203166)
			(end -37.402008 -17.20342)
			(stroke
				(width 0.1)
				(type default)
			)
			(layer "F.SilkS")
		)
		(fp_line
			(start -40.971724 10.539984)
			(end -37.31641 10.539984)
			(stroke
				(width 0.1)
				(type default)
			)
			(layer "F.SilkS")
		)
		(fp_line
			(start -41.111424 6.581394)
			(end -37.311076 6.581394)
			(stroke
				(width 0.1)
				(type default)
			)
			(layer "F.SilkS")
		)
		(fp_line
			(start -41.185846 14.507718)
			(end -36.773358 14.507718)
			(stroke
				(width 0.1)
				(type default)
			)
			(layer "F.SilkS")
		)
		(fp_line
			(start -41.30675 -1.345184)
			(end -35.209988 -1.345184)
			(stroke
				(width 0.1)
				(type default)
			)
			(layer "F.SilkS")
		)
		(fp_line
			(start -41.33469 2.613406)
			(end -35.209988 2.613406)
			(stroke
				(width 0.1)
				(type default)
			)
			(layer "F.SilkS")
		)
		(fp_line
			(start -41.409112 26.518616)
			(end -34.147506 26.518616)
			(stroke
				(width 0.1)
				(type default)
			)
			(layer "F.SilkS")
		)
		(fp_line
			(start -41.632886 -13.229082)
			(end -38.05047 -13.229082)
			(stroke
				(width 0.1)
				(type default)
			)
			(layer "F.SilkS")
		)
		(fp_line
			(start -41.661842 -9.269984)
			(end -38.079426 -9.269984)
			(stroke
				(width 0.1)
				(type default)
			)
			(layer "F.SilkS")
		)
		(fp_line
			(start -41.693592 18.463514)
			(end -38.127686 18.463514)
			(stroke
				(width 0.1)
				(type default)
			)
			(layer "F.SilkS")
		)
		(fp_line
			(start -41.773094 22.425914)
			(end -37.19576 22.425914)
			(stroke
				(width 0.1)
				(type default)
			)
			(layer "F.SilkS")
		)
		(fp_line
			(start -41.78046 -5.310886)
			(end -36.942268 -5.310886)
			(stroke
				(width 0.1)
				(type default)
			)
			(layer "F.SilkS")
		)
		(fp_line
			(start -41.784016 23.911814)
			(end -36.476178 23.911814)
			(stroke
				(width 0.1)
				(type default)
			)
			(layer "F.SilkS")
		)
		(fp_line
			(start -41.811702 -25.122886)
			(end -36.071048 -25.122886)
			(stroke
				(width 0.1)
				(type default)
			)
			(layer "F.SilkS")
		)
		(fp_line
			(start -41.96842 -21.160486)
			(end -37.452808 -21.160486)
			(stroke
				(width 0.1)
				(type default)
			)
			(layer "F.SilkS")
		)
		(fp_line
			(start -42.026078 -17.203166)
			(end -38.443662 -17.203166)
			(stroke
				(width 0.1)
				(type default)
			)
			(layer "F.SilkS")
		)
		(fp_circle
			(center -48.051212 -28.315412)
			(end -48.177958 -28.315412)
			(stroke
				(width 0.254)
				(type default)
			)
			(fill no)
			(layer "F.SilkS")
		)
		(fp_poly
			(pts
				(xy -37.999924 -28.24988) (xy -0.000254 -28.24988) (xy -0.000254 -9.750298) (xy -6.460236 -9.750298)
				(xy -13.05052 -5.790184) (xy -13.05052 5.790184) (xy -6.459982 9.750298) (xy 6.459982 9.750298)
				(xy 13.05052 5.78993) (xy 13.05052 -5.790184) (xy 6.459982 -9.750298) (xy 0.000254 -9.750298) (xy 0.000254 -28.24988)
				(xy 37.999924 -28.24988)
				(arc
					(start 37.999924 14.925802)
					(mid 37.110691 16.000198)
					(end 37.999924 17.074388)
				)
				(xy 37.999924 28.24988) (xy -37.999924 28.24988)
				(arc
					(start -37.999924 17.064228)
					(mid -37.118649 16.000198)
					(end -37.999924 14.935962)
				)
			)
			(stroke
				(width 0)
				(type default)
			)
			(fill no)
			(layer "F.CrtYd")
		)
		(fp_line
			(start 37.999924 28.24988)
			(end 37.999924 17.074388)
			(stroke
				(width 0.1)
				(type default)
			)
			(layer "F.Fab")
		)
		(fp_line
			(start 37.999924 14.925802)
			(end 37.999924 -28.24988)
			(stroke
				(width 0.1)
				(type default)
			)
			(layer "F.Fab")
		)
		(fp_line
			(start 37.999924 -28.24988)
			(end -37.999924 -28.24988)
			(stroke
				(width 0.1)
				(type default)
			)
			(layer "F.Fab")
		)
		(fp_line
			(start -37.12464 15.99819)
			(end -37.124894 16.00708)
			(stroke
				(width 0.1)
				(type default)
			)
			(layer "F.Fab")
		)
		(fp_line
			(start -37.124894 16.02359)
			(end -37.125148 16.032226)
			(stroke
				(width 0.1)
				(type default)
			)
			(layer "F.Fab")
		)
		(fp_line
			(start -37.124894 16.017494)
			(end -37.124894 16.02359)
			(stroke
				(width 0.1)
				(type default)
			)
			(layer "F.Fab")
		)
		(fp_line
			(start -37.124894 16.00962)
			(end -37.124894 16.017494)
			(stroke
				(width 0.1)
				(type default)
			)
			(layer "F.Fab")
		)
		(fp_line
			(start -37.124894 16.00708)
			(end -37.124894 16.00962)
			(stroke
				(width 0.1)
				(type default)
			)
			(layer "F.Fab")
		)
		(fp_line
			(start -37.124894 15.99311)
			(end -37.12464 15.99819)
			(stroke
				(width 0.1)
				(type default)
			)
			(layer "F.Fab")
		)
		(fp_line
			(start -37.125148 16.032226)
			(end -37.125656 16.043402)
			(stroke
				(width 0.1)
				(type default)
			)
			(layer "F.Fab")
		)
		(fp_line
			(start -37.125402 15.961868)
			(end -37.124894 15.99311)
			(stroke
				(width 0.1)
				(type default)
			)
			(layer "F.Fab")
		)
		(fp_line
			(start -37.125656 16.043402)
			(end -37.126164 16.054578)
			(stroke
				(width 0.1)
				(type default)
			)
			(layer "F.Fab")
		)
		(fp_line
			(start -37.12591 15.949676)
			(end -37.125402 15.961868)
			(stroke
				(width 0.1)
				(type default)
			)
			(layer "F.Fab")
		)
		(fp_line
			(start -37.126164 16.054578)
			(end -37.126672 16.063214)
			(stroke
				(width 0.1)
				(type default)
			)
			(layer "F.Fab")
		)
		(fp_line
			(start -37.126418 15.938754)
			(end -37.12591 15.949676)
			(stroke
				(width 0.1)
				(type default)
			)
			(layer "F.Fab")
		)
		(fp_line
			(start -37.126672 16.063214)
			(end -37.12718 16.07439)
			(stroke
				(width 0.1)
				(type default)
			)
			(layer "F.Fab")
		)
		(fp_line
			(start -37.126926 15.930118)
			(end -37.126418 15.938754)
			(stroke
				(width 0.1)
				(type default)
			)
			(layer "F.Fab")
		)
		(fp_line
			(start -37.12718 16.07439)
			(end -37.127688 16.079978)
			(stroke
				(width 0.1)
				(type default)
			)
			(layer "F.Fab")
		)
		(fp_line
			(start -37.127688 16.079978)
			(end -37.128196 16.086836)
			(stroke
				(width 0.1)
				(type default)
			)
			(layer "F.Fab")
		)
		(fp_line
			(start -37.127688 15.921736)
			(end -37.126926 15.930118)
			(stroke
				(width 0.1)
				(type default)
			)
			(layer "F.Fab")
		)
		(fp_line
			(start -37.128196 16.086836)
			(end -37.128958 16.094964)
			(stroke
				(width 0.1)
				(type default)
			)
			(layer "F.Fab")
		)
		(fp_line
			(start -37.128196 15.914624)
			(end -37.127688 15.921736)
			(stroke
				(width 0.1)
				(type default)
			)
			(layer "F.Fab")
		)
		(fp_line
			(start -37.128704 15.906496)
			(end -37.128196 15.914624)
			(stroke
				(width 0.1)
				(type default)
			)
			(layer "F.Fab")
		)
		(fp_line
			(start -37.128958 16.094964)
			(end -37.129466 16.100298)
			(stroke
				(width 0.1)
				(type default)
			)
			(layer "F.Fab")
		)
		(fp_line
			(start -37.129466 16.100298)
			(end -37.130228 16.109696)
			(stroke
				(width 0.1)
				(type default)
			)
			(layer "F.Fab")
		)
		(fp_line
			(start -37.12972 15.895574)
			(end -37.128704 15.906496)
			(stroke
				(width 0.1)
				(type default)
			)
			(layer "F.Fab")
		)
		(fp_line
			(start -37.130228 16.109696)
			(end -37.13099 16.115538)
			(stroke
				(width 0.1)
				(type default)
			)
			(layer "F.Fab")
		)
		(fp_line
			(start -37.130736 15.88643)
			(end -37.12972 15.895574)
			(stroke
				(width 0.1)
				(type default)
			)
			(layer "F.Fab")
		)
		(fp_line
			(start -37.13099 16.115538)
			(end -37.131752 16.122904)
			(stroke
				(width 0.1)
				(type default)
			)
			(layer "F.Fab")
		)
		(fp_line
			(start -37.131498 15.879064)
			(end -37.130736 15.88643)
			(stroke
				(width 0.1)
				(type default)
			)
			(layer "F.Fab")
		)
		(fp_line
			(start -37.131752 16.122904)
			(end -37.13226 16.127984)
			(stroke
				(width 0.1)
				(type default)
			)
			(layer "F.Fab")
		)
		(fp_line
			(start -37.13226 16.127984)
			(end -37.133022 16.13281)
			(stroke
				(width 0.1)
				(type default)
			)
			(layer "F.Fab")
		)
		(fp_line
			(start -37.13226 15.872968)
			(end -37.131498 15.879064)
			(stroke
				(width 0.1)
				(type default)
			)
			(layer "F.Fab")
		)
		(fp_line
			(start -37.133022 16.13281)
			(end -37.134292 16.143478)
			(stroke
				(width 0.1)
				(type default)
			)
			(layer "F.Fab")
		)
		(fp_line
			(start -37.133022 15.86738)
			(end -37.13226 15.872968)
			(stroke
				(width 0.1)
				(type default)
			)
			(layer "F.Fab")
		)
		(fp_line
			(start -37.133276 15.864078)
			(end -37.133022 15.86738)
			(stroke
				(width 0.1)
				(type default)
			)
			(layer "F.Fab")
		)
		(fp_line
			(start -37.134038 15.858744)
			(end -37.133276 15.864078)
			(stroke
				(width 0.1)
				(type default)
			)
			(layer "F.Fab")
		)
		(fp_line
			(start -37.134292 16.143478)
			(end -37.1348 16.147288)
			(stroke
				(width 0.1)
				(type default)
			)
			(layer "F.Fab")
		)
		(fp_line
			(start -37.1348 16.147288)
			(end -37.135308 16.150844)
			(stroke
				(width 0.1)
				(type default)
			)
			(layer "F.Fab")
		)
		(fp_line
			(start -37.135308 16.150844)
			(end -37.13607 16.155924)
			(stroke
				(width 0.1)
				(type default)
			)
			(layer "F.Fab")
		)
		(fp_line
			(start -37.135308 15.849854)
			(end -37.134038 15.858744)
			(stroke
				(width 0.1)
				(type default)
			)
			(layer "F.Fab")
		)
		(fp_line
			(start -37.13607 16.155924)
			(end -37.137086 16.163798)
			(stroke
				(width 0.1)
				(type default)
			)
			(layer "F.Fab")
		)
		(fp_line
			(start -37.136578 15.84071)
			(end -37.135308 15.849854)
			(stroke
				(width 0.1)
				(type default)
			)
			(layer "F.Fab")
		)
		(fp_line
			(start -37.137086 16.163798)
			(end -37.137848 16.167862)
			(stroke
				(width 0.1)
				(type default)
			)
			(layer "F.Fab")
		)
		(fp_line
			(start -37.137848 16.167862)
			(end -37.138356 16.17091)
			(stroke
				(width 0.1)
				(type default)
			)
			(layer "F.Fab")
		)
		(fp_line
			(start -37.138356 16.17091)
			(end -37.13861 16.17345)
			(stroke
				(width 0.1)
				(type default)
			)
			(layer "F.Fab")
		)
		(fp_line
			(start -37.13861 16.17345)
			(end -37.139118 16.176498)
			(stroke
				(width 0.1)
				(type default)
			)
			(layer "F.Fab")
		)
		(fp_line
			(start -37.13861 15.827756)
			(end -37.136578 15.84071)
			(stroke
				(width 0.1)
				(type default)
			)
			(layer "F.Fab")
		)
		(fp_line
			(start -37.139118 16.176498)
			(end -37.139626 16.179546)
			(stroke
				(width 0.1)
				(type default)
			)
			(layer "F.Fab")
		)
		(fp_line
			(start -37.139626 16.179546)
			(end -37.140388 16.18361)
			(stroke
				(width 0.1)
				(type default)
			)
			(layer "F.Fab")
		)
		(fp_line
			(start -37.140388 16.18361)
			(end -37.140896 16.186658)
			(stroke
				(width 0.1)
				(type default)
			)
			(layer "F.Fab")
		)
		(fp_line
			(start -37.140388 15.817088)
			(end -37.13861 15.827756)
			(stroke
				(width 0.1)
				(type default)
			)
			(layer "F.Fab")
		)
		(fp_line
			(start -37.140896 16.186658)
			(end -37.141404 16.189452)
			(stroke
				(width 0.1)
				(type default)
			)
			(layer "F.Fab")
		)
		(fp_line
			(start -37.141404 16.189452)
			(end -37.141658 16.190976)
			(stroke
				(width 0.1)
				(type default)
			)
			(layer "F.Fab")
		)
		(fp_line
			(start -37.141404 15.809976)
			(end -37.140388 15.817088)
			(stroke
				(width 0.1)
				(type default)
			)
			(layer "F.Fab")
		)
		(fp_line
			(start -37.141658 16.190976)
			(end -37.142166 16.193262)
			(stroke
				(width 0.1)
				(type default)
			)
			(layer "F.Fab")
		)
		(fp_line
			(start -37.142166 16.193262)
			(end -37.142928 16.19758)
			(stroke
				(width 0.1)
				(type default)
			)
			(layer "F.Fab")
		)
		(fp_line
			(start -37.142674 15.803118)
			(end -37.141404 15.809976)
			(stroke
				(width 0.1)
				(type default)
			)
			(layer "F.Fab")
		)
		(fp_line
			(start -37.142928 16.19758)
			(end -37.143182 16.199866)
			(stroke
				(width 0.1)
				(type default)
			)
			(layer "F.Fab")
		)
		(fp_line
			(start -37.143182 16.199866)
			(end -37.144198 16.2052)
			(stroke
				(width 0.1)
				(type default)
			)
			(layer "F.Fab")
		)
		(fp_line
			(start -37.143944 15.797022)
			(end -37.142674 15.803118)
			(stroke
				(width 0.1)
				(type default)
			)
			(layer "F.Fab")
		)
		(fp_line
			(start -37.144198 16.2052)
			(end -37.14496 16.208756)
			(stroke
				(width 0.1)
				(type default)
			)
			(layer "F.Fab")
		)
		(fp_line
			(start -37.14496 16.208756)
			(end -37.148262 16.224504)
			(stroke
				(width 0.1)
				(type default)
			)
			(layer "F.Fab")
		)
		(fp_line
			(start -37.145468 15.789402)
			(end -37.143944 15.797022)
			(stroke
				(width 0.1)
				(type default)
			)
			(layer "F.Fab")
		)
		(fp_line
			(start -37.146738 15.782798)
			(end -37.145468 15.789402)
			(stroke
				(width 0.1)
				(type default)
			)
			(layer "F.Fab")
		)
		(fp_line
			(start -37.148008 15.776448)
			(end -37.146738 15.782798)
			(stroke
				(width 0.1)
				(type default)
			)
			(layer "F.Fab")
		)
		(fp_line
			(start -37.148262 16.224504)
			(end -37.149532 16.2306)
			(stroke
				(width 0.1)
				(type default)
			)
			(layer "F.Fab")
		)
		(fp_line
			(start -37.149532 16.2306)
			(end -37.151564 16.23949)
			(stroke
				(width 0.1)
				(type default)
			)
			(layer "F.Fab")
		)
		(fp_line
			(start -37.149786 15.767812)
			(end -37.148008 15.776448)
			(stroke
				(width 0.1)
				(type default)
			)
			(layer "F.Fab")
		)
		(fp_line
			(start -37.151564 16.23949)
			(end -37.152834 16.245078)
			(stroke
				(width 0.1)
				(type default)
			)
			(layer "F.Fab")
		)
		(fp_line
			(start -37.151818 15.759684)
			(end -37.149786 15.767812)
			(stroke
				(width 0.1)
				(type default)
			)
			(layer "F.Fab")
		)
		(fp_line
			(start -37.152834 16.245078)
			(end -37.153596 16.248888)
			(stroke
				(width 0.1)
				(type default)
			)
			(layer "F.Fab")
		)
		(fp_line
			(start -37.153342 15.752826)
			(end -37.151818 15.759684)
			(stroke
				(width 0.1)
				(type default)
			)
			(layer "F.Fab")
		)
		(fp_line
			(start -37.153596 16.248888)
			(end -37.15512 16.254222)
			(stroke
				(width 0.1)
				(type default)
			)
			(layer "F.Fab")
		)
		(fp_line
			(start -37.15512 16.254222)
			(end -37.15639 16.25981)
			(stroke
				(width 0.1)
				(type default)
			)
			(layer "F.Fab")
		)
		(fp_line
			(start -37.15512 15.745206)
			(end -37.153342 15.752826)
			(stroke
				(width 0.1)
				(type default)
			)
			(layer "F.Fab")
		)
		(fp_line
			(start -37.15639 16.25981)
			(end -37.157406 16.264382)
			(stroke
				(width 0.1)
				(type default)
			)
			(layer "F.Fab")
		)
		(fp_line
			(start -37.157152 15.737078)
			(end -37.15512 15.745206)
			(stroke
				(width 0.1)
				(type default)
			)
			(layer "F.Fab")
		)
		(fp_line
			(start -37.157406 16.264382)
			(end -37.158422 16.268192)
			(stroke
				(width 0.1)
				(type default)
			)
			(layer "F.Fab")
		)
		(fp_line
			(start -37.158422 16.268192)
			(end -37.159692 16.272764)
			(stroke
				(width 0.1)
				(type default)
			)
			(layer "F.Fab")
		)
		(fp_line
			(start -37.15893 15.729712)
			(end -37.157152 15.737078)
			(stroke
				(width 0.1)
				(type default)
			)
			(layer "F.Fab")
		)
		(fp_line
			(start -37.159692 16.272764)
			(end -37.161216 16.278606)
			(stroke
				(width 0.1)
				(type default)
			)
			(layer "F.Fab")
		)
		(fp_line
			(start -37.161216 16.278606)
			(end -37.162486 16.283686)
			(stroke
				(width 0.1)
				(type default)
			)
			(layer "F.Fab")
		)
		(fp_line
			(start -37.161978 15.718536)
			(end -37.15893 15.729712)
			(stroke
				(width 0.1)
				(type default)
			)
			(layer "F.Fab")
		)
		(fp_line
			(start -37.162486 16.283686)
			(end -37.164264 16.29029)
			(stroke
				(width 0.1)
				(type default)
			)
			(layer "F.Fab")
		)
		(fp_line
			(start -37.162486 15.715996)
			(end -37.161978 15.718536)
			(stroke
				(width 0.1)
				(type default)
			)
			(layer "F.Fab")
		)
		(fp_line
			(start -37.163502 15.713202)
			(end -37.162486 15.715996)
			(stroke
				(width 0.1)
				(type default)
			)
			(layer "F.Fab")
		)
		(fp_line
			(start -37.164264 16.29029)
			(end -37.166042 16.296386)
			(stroke
				(width 0.1)
				(type default)
			)
			(layer "F.Fab")
		)
		(fp_line
			(start -37.164772 15.708376)
			(end -37.163502 15.713202)
			(stroke
				(width 0.1)
				(type default)
			)
			(layer "F.Fab")
		)
		(fp_line
			(start -37.166042 16.296386)
			(end -37.16782 16.30299)
			(stroke
				(width 0.1)
				(type default)
			)
			(layer "F.Fab")
		)
		(fp_line
			(start -37.166296 15.702534)
			(end -37.164772 15.708376)
			(stroke
				(width 0.1)
				(type default)
			)
			(layer "F.Fab")
		)
		(fp_line
			(start -37.16782 16.30299)
			(end -37.170614 16.312388)
			(stroke
				(width 0.1)
				(type default)
			)
			(layer "F.Fab")
		)
		(fp_line
			(start -37.168328 15.695676)
			(end -37.166296 15.702534)
			(stroke
				(width 0.1)
				(type default)
			)
			(layer "F.Fab")
		)
		(fp_line
			(start -37.170614 16.312388)
			(end -37.172138 16.317214)
			(stroke
				(width 0.1)
				(type default)
			)
			(layer "F.Fab")
		)
		(fp_line
			(start -37.171122 15.686024)
			(end -37.168328 15.695676)
			(stroke
				(width 0.1)
				(type default)
			)
			(layer "F.Fab")
		)
		(fp_line
			(start -37.172138 16.317214)
			(end -37.173662 16.321786)
			(stroke
				(width 0.1)
				(type default)
			)
			(layer "F.Fab")
		)
		(fp_line
			(start -37.173662 16.321786)
			(end -37.174932 16.326358)
			(stroke
				(width 0.1)
				(type default)
			)
			(layer "F.Fab")
		)
		(fp_line
			(start -37.174424 15.67561)
			(end -37.171122 15.686024)
			(stroke
				(width 0.1)
				(type default)
			)
			(layer "F.Fab")
		)
		(fp_line
			(start -37.174932 16.326358)
			(end -37.17671 16.331692)
			(stroke
				(width 0.1)
				(type default)
			)
			(layer "F.Fab")
		)
		(fp_line
			(start -37.17671 16.331692)
			(end -37.178488 16.33728)
			(stroke
				(width 0.1)
				(type default)
			)
			(layer "F.Fab")
		)
		(fp_line
			(start -37.177726 15.665196)
			(end -37.174424 15.67561)
			(stroke
				(width 0.1)
				(type default)
			)
			(layer "F.Fab")
		)
		(fp_line
			(start -37.178488 16.33728)
			(end -37.182044 16.347948)
			(stroke
				(width 0.1)
				(type default)
			)
			(layer "F.Fab")
		)
		(fp_line
			(start -37.182044 16.347948)
			(end -37.183314 16.352012)
			(stroke
				(width 0.1)
				(type default)
			)
			(layer "F.Fab")
		)
		(fp_line
			(start -37.182298 15.651226)
			(end -37.177726 15.665196)
			(stroke
				(width 0.1)
				(type default)
			)
			(layer "F.Fab")
		)
		(fp_line
			(start -37.183314 16.352012)
			(end -37.184838 16.356076)
			(stroke
				(width 0.1)
				(type default)
			)
			(layer "F.Fab")
		)
		(fp_line
			(start -37.184838 16.356076)
			(end -37.186616 16.361156)
			(stroke
				(width 0.1)
				(type default)
			)
			(layer "F.Fab")
		)
		(fp_line
			(start -37.184838 15.644114)
			(end -37.182298 15.651226)
			(stroke
				(width 0.1)
				(type default)
			)
			(layer "F.Fab")
		)
		(fp_line
			(start -37.186616 16.361156)
			(end -37.187378 16.363188)
			(stroke
				(width 0.1)
				(type default)
			)
			(layer "F.Fab")
		)
		(fp_line
			(start -37.187378 16.363188)
			(end -37.188902 16.367506)
			(stroke
				(width 0.1)
				(type default)
			)
			(layer "F.Fab")
		)
		(fp_line
			(start -37.187632 15.635732)
			(end -37.184838 15.644114)
			(stroke
				(width 0.1)
				(type default)
			)
			(layer "F.Fab")
		)
		(fp_line
			(start -37.188902 16.367506)
			(end -37.19068 16.372586)
			(stroke
				(width 0.1)
				(type default)
			)
			(layer "F.Fab")
		)
		(fp_line
			(start -37.190426 15.628112)
			(end -37.187632 15.635732)
			(stroke
				(width 0.1)
				(type default)
			)
			(layer "F.Fab")
		)
		(fp_line
			(start -37.19068 16.372586)
			(end -37.192712 16.377666)
			(stroke
				(width 0.1)
				(type default)
			)
			(layer "F.Fab")
		)
		(fp_line
			(start -37.192712 16.377666)
			(end -37.194236 16.381984)
			(stroke
				(width 0.1)
				(type default)
			)
			(layer "F.Fab")
		)
		(fp_line
			(start -37.193474 15.61973)
			(end -37.190426 15.628112)
			(stroke
				(width 0.1)
				(type default)
			)
			(layer "F.Fab")
		)
		(fp_line
			(start -37.194236 16.381984)
			(end -37.196522 16.387826)
			(stroke
				(width 0.1)
				(type default)
			)
			(layer "F.Fab")
		)
		(fp_line
			(start -37.196522 16.387826)
			(end -37.1983 16.392398)
			(stroke
				(width 0.1)
				(type default)
			)
			(layer "F.Fab")
		)
		(fp_line
			(start -37.197284 15.610332)
			(end -37.193474 15.61973)
			(stroke
				(width 0.1)
				(type default)
			)
			(layer "F.Fab")
		)
		(fp_line
			(start -37.1983 16.392398)
			(end -37.199316 16.395446)
			(stroke
				(width 0.1)
				(type default)
			)
			(layer "F.Fab")
		)
		(fp_line
			(start -37.199316 16.395446)
			(end -37.200078 16.397478)
			(stroke
				(width 0.1)
				(type default)
			)
			(layer "F.Fab")
		)
		(fp_line
			(start -37.200078 16.397478)
			(end -37.203634 16.406114)
			(stroke
				(width 0.1)
				(type default)
			)
			(layer "F.Fab")
		)
		(fp_line
			(start -37.201602 15.598902)
			(end -37.197284 15.610332)
			(stroke
				(width 0.1)
				(type default)
			)
			(layer "F.Fab")
		)
		(fp_line
			(start -37.203634 16.406114)
			(end -37.205412 16.410686)
			(stroke
				(width 0.1)
				(type default)
			)
			(layer "F.Fab")
		)
		(fp_line
			(start -37.205412 16.410686)
			(end -37.20719 16.415004)
			(stroke
				(width 0.1)
				(type default)
			)
			(layer "F.Fab")
		)
		(fp_line
			(start -37.205412 15.589504)
			(end -37.201602 15.598902)
			(stroke
				(width 0.1)
				(type default)
			)
			(layer "F.Fab")
		)
		(fp_line
			(start -37.20719 16.415004)
			(end -37.209222 16.419322)
			(stroke
				(width 0.1)
				(type default)
			)
			(layer "F.Fab")
		)
		(fp_line
			(start -37.208968 15.580868)
			(end -37.205412 15.589504)
			(stroke
				(width 0.1)
				(type default)
			)
			(layer "F.Fab")
		)
		(fp_line
			(start -37.209222 16.419322)
			(end -37.210492 16.422624)
			(stroke
				(width 0.1)
				(type default)
			)
			(layer "F.Fab")
		)
		(fp_line
			(start -37.210492 16.422624)
			(end -37.211508 16.425164)
			(stroke
				(width 0.1)
				(type default)
			)
			(layer "F.Fab")
		)
		(fp_line
			(start -37.211508 16.425164)
			(end -37.212778 16.428212)
			(stroke
				(width 0.1)
				(type default)
			)
			(layer "F.Fab")
		)
		(fp_line
			(start -37.212778 16.428212)
			(end -37.215318 16.4338)
			(stroke
				(width 0.1)
				(type default)
			)
			(layer "F.Fab")
		)
		(fp_line
			(start -37.214302 15.568168)
			(end -37.208968 15.580868)
			(stroke
				(width 0.1)
				(type default)
			)
			(layer "F.Fab")
		)
		(fp_line
			(start -37.215318 16.4338)
			(end -37.216334 16.43634)
			(stroke
				(width 0.1)
				(type default)
			)
			(layer "F.Fab")
		)
		(fp_line
			(start -37.216334 16.43634)
			(end -37.217858 16.439642)
			(stroke
				(width 0.1)
				(type default)
			)
			(layer "F.Fab")
		)
		(fp_line
			(start -37.217858 16.439642)
			(end -37.21989 16.444214)
			(stroke
				(width 0.1)
				(type default)
			)
			(layer "F.Fab")
		)
		(fp_line
			(start -37.219128 15.5575)
			(end -37.214302 15.568168)
			(stroke
				(width 0.1)
				(type default)
			)
			(layer "F.Fab")
		)
		(fp_line
			(start -37.21989 16.444214)
			(end -37.222684 16.45031)
			(stroke
				(width 0.1)
				(type default)
			)
			(layer "F.Fab")
		)
		(fp_line
			(start -37.222684 16.45031)
			(end -37.225224 16.456152)
			(stroke
				(width 0.1)
				(type default)
			)
			(layer "F.Fab")
		)
		(fp_line
			(start -37.224208 15.546578)
			(end -37.219128 15.5575)
			(stroke
				(width 0.1)
				(type default)
			)
			(layer "F.Fab")
		)
		(fp_line
			(start -37.225224 16.456152)
			(end -37.226748 16.4592)
			(stroke
				(width 0.1)
				(type default)
			)
			(layer "F.Fab")
		)
		(fp_line
			(start -37.226748 16.4592)
			(end -37.228272 16.462502)
			(stroke
				(width 0.1)
				(type default)
			)
			(layer "F.Fab")
		)
		(fp_line
			(start -37.227764 15.538704)
			(end -37.224208 15.546578)
			(stroke
				(width 0.1)
				(type default)
			)
			(layer "F.Fab")
		)
		(fp_line
			(start -37.228272 16.462502)
			(end -37.23005 16.466058)
			(stroke
				(width 0.1)
				(type default)
			)
			(layer "F.Fab")
		)
		(fp_line
			(start -37.23005 16.466058)
			(end -37.23132 16.468598)
			(stroke
				(width 0.1)
				(type default)
			)
			(layer "F.Fab")
		)
		(fp_line
			(start -37.23132 16.468598)
			(end -37.23259 16.471646)
			(stroke
				(width 0.1)
				(type default)
			)
			(layer "F.Fab")
		)
		(fp_line
			(start -37.231574 15.530322)
			(end -37.227764 15.538704)
			(stroke
				(width 0.1)
				(type default)
			)
			(layer "F.Fab")
		)
		(fp_line
			(start -37.23259 16.471646)
			(end -37.23386 16.473932)
			(stroke
				(width 0.1)
				(type default)
			)
			(layer "F.Fab")
		)
		(fp_line
			(start -37.233098 15.527528)
			(end -37.231574 15.530322)
			(stroke
				(width 0.1)
				(type default)
			)
			(layer "F.Fab")
		)
		(fp_line
			(start -37.23386 16.473932)
			(end -37.238178 16.482822)
			(stroke
				(width 0.1)
				(type default)
			)
			(layer "F.Fab")
		)
		(fp_line
			(start -37.236146 15.521178)
			(end -37.233098 15.527528)
			(stroke
				(width 0.1)
				(type default)
			)
			(layer "F.Fab")
		)
		(fp_line
			(start -37.238178 16.482822)
			(end -37.240972 16.488664)
			(stroke
				(width 0.1)
				(type default)
			)
			(layer "F.Fab")
		)
		(fp_line
			(start -37.239194 15.514828)
			(end -37.236146 15.521178)
			(stroke
				(width 0.1)
				(type default)
			)
			(layer "F.Fab")
		)
		(fp_line
			(start -37.240972 16.488664)
			(end -37.242496 16.491204)
			(stroke
				(width 0.1)
				(type default)
			)
			(layer "F.Fab")
		)
		(fp_line
			(start -37.242496 16.491204)
			(end -37.244274 16.495268)
			(stroke
				(width 0.1)
				(type default)
			)
			(layer "F.Fab")
		)
		(fp_line
			(start -37.243512 15.506446)
			(end -37.239194 15.514828)
			(stroke
				(width 0.1)
				(type default)
			)
			(layer "F.Fab")
		)
		(fp_line
			(start -37.244274 16.495268)
			(end -37.247576 16.50111)
			(stroke
				(width 0.1)
				(type default)
			)
			(layer "F.Fab")
		)
		(fp_line
			(start -37.247068 15.499842)
			(end -37.243512 15.506446)
			(stroke
				(width 0.1)
				(type default)
			)
			(layer "F.Fab")
		)
		(fp_line
			(start -37.247576 16.50111)
			(end -37.249862 16.505682)
			(stroke
				(width 0.1)
				(type default)
			)
			(layer "F.Fab")
		)
		(fp_line
			(start -37.249608 15.495016)
			(end -37.247068 15.499842)
			(stroke
				(width 0.1)
				(type default)
			)
			(layer "F.Fab")
		)
		(fp_line
			(start -37.249862 16.505682)
			(end -37.251894 16.509492)
			(stroke
				(width 0.1)
				(type default)
			)
			(layer "F.Fab")
		)
		(fp_line
			(start -37.251894 16.509492)
			(end -37.254434 16.514318)
			(stroke
				(width 0.1)
				(type default)
			)
			(layer "F.Fab")
		)
		(fp_line
			(start -37.25291 15.48892)
			(end -37.249608 15.495016)
			(stroke
				(width 0.1)
				(type default)
			)
			(layer "F.Fab")
		)
		(fp_line
			(start -37.254434 16.514318)
			(end -37.257482 16.52016)
			(stroke
				(width 0.1)
				(type default)
			)
			(layer "F.Fab")
		)
		(fp_line
			(start -37.25545 15.484094)
			(end -37.25291 15.48892)
			(stroke
				(width 0.1)
				(type default)
			)
			(layer "F.Fab")
		)
		(fp_line
			(start -37.257482 16.52016)
			(end -37.258498 16.521684)
			(stroke
				(width 0.1)
				(type default)
			)
			(layer "F.Fab")
		)
		(fp_line
			(start -37.257482 15.480284)
			(end -37.25545 15.484094)
			(stroke
				(width 0.1)
				(type default)
			)
			(layer "F.Fab")
		)
		(fp_line
			(start -37.258498 16.521684)
			(end -37.259514 16.523716)
			(stroke
				(width 0.1)
				(type default)
			)
			(layer "F.Fab")
		)
		(fp_line
			(start -37.259514 16.523716)
			(end -37.261546 16.527272)
			(stroke
				(width 0.1)
				(type default)
			)
			(layer "F.Fab")
		)
		(fp_line
			(start -37.260276 15.47495)
			(end -37.257482 15.480284)
			(stroke
				(width 0.1)
				(type default)
			)
			(layer "F.Fab")
		)
		(fp_line
			(start -37.261546 16.527272)
			(end -37.263578 16.531082)
			(stroke
				(width 0.1)
				(type default)
			)
			(layer "F.Fab")
		)
		(fp_line
			(start -37.263324 15.469616)
			(end -37.260276 15.47495)
			(stroke
				(width 0.1)
				(type default)
			)
			(layer "F.Fab")
		)
		(fp_line
			(start -37.263578 16.531082)
			(end -37.266372 16.535908)
			(stroke
				(width 0.1)
				(type default)
			)
			(layer "F.Fab")
		)
		(fp_line
			(start -37.265864 15.465298)
			(end -37.263324 15.469616)
			(stroke
				(width 0.1)
				(type default)
			)
			(layer "F.Fab")
		)
		(fp_line
			(start -37.266372 16.535908)
			(end -37.267388 16.537686)
			(stroke
				(width 0.1)
				(type default)
			)
			(layer "F.Fab")
		)
		(fp_line
			(start -37.267388 16.537686)
			(end -37.269166 16.540734)
			(stroke
				(width 0.1)
				(type default)
			)
			(layer "F.Fab")
		)
		(fp_line
			(start -37.268658 15.460218)
			(end -37.265864 15.465298)
			(stroke
				(width 0.1)
				(type default)
			)
			(layer "F.Fab")
		)
		(fp_line
			(start -37.269166 16.540734)
			(end -37.274754 16.550386)
			(stroke
				(width 0.1)
				(type default)
			)
			(layer "F.Fab")
		)
		(fp_line
			(start -37.271706 15.45463)
			(end -37.268658 15.460218)
			(stroke
				(width 0.1)
				(type default)
			)
			(layer "F.Fab")
		)
		(fp_line
			(start -37.274754 16.550386)
			(end -37.279072 16.557752)
			(stroke
				(width 0.1)
				(type default)
			)
			(layer "F.Fab")
		)
		(fp_line
			(start -37.275516 15.448534)
			(end -37.271706 15.45463)
			(stroke
				(width 0.1)
				(type default)
			)
			(layer "F.Fab")
		)
		(fp_line
			(start -37.278564 15.4432)
			(end -37.275516 15.448534)
			(stroke
				(width 0.1)
				(type default)
			)
			(layer "F.Fab")
		)
		(fp_line
			(start -37.279072 16.557752)
			(end -37.283644 16.565372)
			(stroke
				(width 0.1)
				(type default)
			)
			(layer "F.Fab")
		)
		(fp_line
			(start -37.281358 15.438628)
			(end -37.278564 15.4432)
			(stroke
				(width 0.1)
				(type default)
			)
			(layer "F.Fab")
		)
		(fp_line
			(start -37.283644 16.565372)
			(end -37.286692 16.570198)
			(stroke
				(width 0.1)
				(type default)
			)
			(layer "F.Fab")
		)
		(fp_line
			(start -37.28466 15.43304)
			(end -37.281358 15.438628)
			(stroke
				(width 0.1)
				(type default)
			)
			(layer "F.Fab")
		)
		(fp_line
			(start -37.286184 15.4305)
			(end -37.28466 15.43304)
			(stroke
				(width 0.1)
				(type default)
			)
			(layer "F.Fab")
		)
		(fp_line
			(start -37.286692 16.570198)
			(end -37.289994 16.575532)
			(stroke
				(width 0.1)
				(type default)
			)
			(layer "F.Fab")
		)
		(fp_line
			(start -37.289994 16.575532)
			(end -37.292788 16.580104)
			(stroke
				(width 0.1)
				(type default)
			)
			(layer "F.Fab")
		)
		(fp_line
			(start -37.290756 15.423388)
			(end -37.286184 15.4305)
			(stroke
				(width 0.1)
				(type default)
			)
			(layer "F.Fab")
		)
		(fp_line
			(start -37.292788 16.580104)
			(end -37.295328 16.584168)
			(stroke
				(width 0.1)
				(type default)
			)
			(layer "F.Fab")
		)
		(fp_line
			(start -37.293296 15.419578)
			(end -37.290756 15.423388)
			(stroke
				(width 0.1)
				(type default)
			)
			(layer "F.Fab")
		)
		(fp_line
			(start -37.295328 16.584168)
			(end -37.300154 16.59128)
			(stroke
				(width 0.1)
				(type default)
			)
			(layer "F.Fab")
		)
		(fp_line
			(start -37.296598 15.41399)
			(end -37.293296 15.419578)
			(stroke
				(width 0.1)
				(type default)
			)
			(layer "F.Fab")
		)
		(fp_line
			(start -37.300154 16.59128)
			(end -37.304726 16.598138)
			(stroke
				(width 0.1)
				(type default)
			)
			(layer "F.Fab")
		)
		(fp_line
			(start -37.300662 15.407894)
			(end -37.296598 15.41399)
			(stroke
				(width 0.1)
				(type default)
			)
			(layer "F.Fab")
		)
		(fp_line
			(start -37.30371 15.403322)
			(end -37.300662 15.407894)
			(stroke
				(width 0.1)
				(type default)
			)
			(layer "F.Fab")
		)
		(fp_line
			(start -37.304726 16.598138)
			(end -37.309298 16.604996)
			(stroke
				(width 0.1)
				(type default)
			)
			(layer "F.Fab")
		)
		(fp_line
			(start -37.307012 15.397988)
			(end -37.30371 15.403322)
			(stroke
				(width 0.1)
				(type default)
			)
			(layer "F.Fab")
		)
		(fp_line
			(start -37.309298 16.604996)
			(end -37.314124 16.612108)
			(stroke
				(width 0.1)
				(type default)
			)
			(layer "F.Fab")
		)
		(fp_line
			(start -37.311076 15.3924)
			(end -37.307012 15.397988)
			(stroke
				(width 0.1)
				(type default)
			)
			(layer "F.Fab")
		)
		(fp_line
			(start -37.314124 16.612108)
			(end -37.317934 16.617696)
			(stroke
				(width 0.1)
				(type default)
			)
			(layer "F.Fab")
		)
		(fp_line
			(start -37.315394 15.38605)
			(end -37.311076 15.3924)
			(stroke
				(width 0.1)
				(type default)
			)
			(layer "F.Fab")
		)
		(fp_line
			(start -37.317934 16.617696)
			(end -37.324284 16.62684)
			(stroke
				(width 0.1)
				(type default)
			)
			(layer "F.Fab")
		)
		(fp_line
			(start -37.31895 15.380716)
			(end -37.315394 15.38605)
			(stroke
				(width 0.1)
				(type default)
			)
			(layer "F.Fab")
		)
		(fp_line
			(start -37.324284 16.62684)
			(end -37.330888 16.635984)
			(stroke
				(width 0.1)
				(type default)
			)
			(layer "F.Fab")
		)
		(fp_line
			(start -37.330888 16.635984)
			(end -37.33927 16.647414)
			(stroke
				(width 0.1)
				(type default)
			)
			(layer "F.Fab")
		)
		(fp_line
			(start -37.332158 15.362174)
			(end -37.31895 15.380716)
			(stroke
				(width 0.1)
				(type default)
			)
			(layer "F.Fab")
		)
		(fp_line
			(start -37.333174 15.36065)
			(end -37.332158 15.362174)
			(stroke
				(width 0.1)
				(type default)
			)
			(layer "F.Fab")
		)
		(fp_line
			(start -37.336984 15.355316)
			(end -37.333174 15.36065)
			(stroke
				(width 0.1)
				(type default)
			)
			(layer "F.Fab")
		)
		(fp_line
			(start -37.33927 16.647414)
			(end -37.350446 16.6624)
			(stroke
				(width 0.1)
				(type default)
			)
			(layer "F.Fab")
		)
		(fp_line
			(start -37.34181 15.34922)
			(end -37.336984 15.355316)
			(stroke
				(width 0.1)
				(type default)
			)
			(layer "F.Fab")
		)
		(fp_line
			(start -37.34562 15.34414)
			(end -37.34181 15.34922)
			(stroke
				(width 0.1)
				(type default)
			)
			(layer "F.Fab")
		)
		(fp_line
			(start -37.349684 15.338806)
			(end -37.34562 15.34414)
			(stroke
				(width 0.1)
				(type default)
			)
			(layer "F.Fab")
		)
		(fp_line
			(start -37.350446 16.6624)
			(end -37.353494 16.66621)
			(stroke
				(width 0.1)
				(type default)
			)
			(layer "F.Fab")
		)
		(fp_line
			(start -37.353494 16.66621)
			(end -37.358828 16.673068)
			(stroke
				(width 0.1)
				(type default)
			)
			(layer "F.Fab")
		)
		(fp_line
			(start -37.353748 15.333472)
			(end -37.349684 15.338806)
			(stroke
				(width 0.1)
				(type default)
			)
			(layer "F.Fab")
		)
		(fp_line
			(start -37.357812 15.328138)
			(end -37.353748 15.333472)
			(stroke
				(width 0.1)
				(type default)
			)
			(layer "F.Fab")
		)
		(fp_line
			(start -37.358828 16.673068)
			(end -37.362384 16.677386)
			(stroke
				(width 0.1)
				(type default)
			)
			(layer "F.Fab")
		)
		(fp_line
			(start -37.362384 16.677386)
			(end -37.36848 16.68526)
			(stroke
				(width 0.1)
				(type default)
			)
			(layer "F.Fab")
		)
		(fp_line
			(start -37.36848 16.68526)
			(end -37.374576 16.692626)
			(stroke
				(width 0.1)
				(type default)
			)
			(layer "F.Fab")
		)
		(fp_line
			(start -37.374576 16.692626)
			(end -37.383974 16.703802)
			(stroke
				(width 0.1)
				(type default)
			)
			(layer "F.Fab")
		)
		(fp_line
			(start -37.383974 16.703802)
			(end -37.39261 16.713708)
			(stroke
				(width 0.1)
				(type default)
			)
			(layer "F.Fab")
		)
		(fp_line
			(start -37.39261 16.713708)
			(end -37.4015 16.723868)
			(stroke
				(width 0.1)
				(type default)
			)
			(layer "F.Fab")
		)
		(fp_line
			(start -37.39642 15.281402)
			(end -37.357812 15.328138)
			(stroke
				(width 0.1)
				(type default)
			)
			(layer "F.Fab")
		)
		(fp_line
			(start -37.399214 15.278608)
			(end -37.39642 15.281402)
			(stroke
				(width 0.1)
				(type default)
			)
			(layer "F.Fab")
		)
		(fp_line
			(start -37.4015 16.723868)
			(end -37.41039 16.73352)
			(stroke
				(width 0.1)
				(type default)
			)
			(layer "F.Fab")
		)
		(fp_line
			(start -37.40531 15.271496)
			(end -37.399214 15.278608)
			(stroke
				(width 0.1)
				(type default)
			)
			(layer "F.Fab")
		)
		(fp_line
			(start -37.410136 15.266416)
			(end -37.40531 15.271496)
			(stroke
				(width 0.1)
				(type default)
			)
			(layer "F.Fab")
		)
		(fp_line
			(start -37.41039 16.73352)
			(end -37.419534 16.743426)
			(stroke
				(width 0.1)
				(type default)
			)
			(layer "F.Fab")
		)
		(fp_line
			(start -37.419534 16.743426)
			(end -37.427916 16.752062)
			(stroke
				(width 0.1)
				(type default)
			)
			(layer "F.Fab")
		)
		(fp_line
			(start -37.427916 16.752062)
			(end -37.430456 16.754602)
			(stroke
				(width 0.1)
				(type default)
			)
			(layer "F.Fab")
		)
		(fp_line
			(start -37.430456 16.754602)
			(end -37.434012 16.758412)
			(stroke
				(width 0.1)
				(type default)
			)
			(layer "F.Fab")
		)
		(fp_line
			(start -37.434012 16.758412)
			(end -37.444426 16.76908)
			(stroke
				(width 0.1)
				(type default)
			)
			(layer "F.Fab")
		)
		(fp_line
			(start -37.444426 16.76908)
			(end -37.451284 16.775684)
			(stroke
				(width 0.1)
				(type default)
			)
			(layer "F.Fab")
		)
		(fp_line
			(start -37.451284 16.775684)
			(end -37.457888 16.782034)
			(stroke
				(width 0.1)
				(type default)
			)
			(layer "F.Fab")
		)
		(fp_line
			(start -37.457888 16.782034)
			(end -37.466016 16.789908)
			(stroke
				(width 0.1)
				(type default)
			)
			(layer "F.Fab")
		)
		(fp_line
			(start -37.459412 15.21587)
			(end -37.410136 15.266416)
			(stroke
				(width 0.1)
				(type default)
			)
			(layer "F.Fab")
		)
		(fp_line
			(start -37.460682 15.2146)
			(end -37.459412 15.21587)
			(stroke
				(width 0.1)
				(type default)
			)
			(layer "F.Fab")
		)
		(fp_line
			(start -37.464492 15.211298)
			(end -37.460682 15.2146)
			(stroke
				(width 0.1)
				(type default)
			)
			(layer "F.Fab")
		)
		(fp_line
			(start -37.466016 16.789908)
			(end -37.472366 16.79575)
			(stroke
				(width 0.1)
				(type default)
			)
			(layer "F.Fab")
		)
		(fp_line
			(start -37.469826 15.206218)
			(end -37.464492 15.211298)
			(stroke
				(width 0.1)
				(type default)
			)
			(layer "F.Fab")
		)
		(fp_line
			(start -37.472366 16.79575)
			(end -37.479224 16.8021)
			(stroke
				(width 0.1)
				(type default)
			)
			(layer "F.Fab")
		)
		(fp_line
			(start -37.474652 15.201646)
			(end -37.469826 15.206218)
			(stroke
				(width 0.1)
				(type default)
			)
			(layer "F.Fab")
		)
		(fp_line
			(start -37.479224 16.8021)
			(end -37.488114 16.809974)
			(stroke
				(width 0.1)
				(type default)
			)
			(layer "F.Fab")
		)
		(fp_line
			(start -37.479478 15.197328)
			(end -37.474652 15.201646)
			(stroke
				(width 0.1)
				(type default)
			)
			(layer "F.Fab")
		)
		(fp_line
			(start -37.484304 15.19301)
			(end -37.479478 15.197328)
			(stroke
				(width 0.1)
				(type default)
			)
			(layer "F.Fab")
		)
		(fp_line
			(start -37.488114 16.809974)
			(end -37.492686 16.814038)
			(stroke
				(width 0.1)
				(type default)
			)
			(layer "F.Fab")
		)
		(fp_line
			(start -37.48913 15.188692)
			(end -37.484304 15.19301)
			(stroke
				(width 0.1)
				(type default)
			)
			(layer "F.Fab")
		)
		(fp_line
			(start -37.492432 15.185644)
			(end -37.48913 15.188692)
			(stroke
				(width 0.1)
				(type default)
			)
			(layer "F.Fab")
		)
		(fp_line
			(start -37.492686 16.814038)
			(end -37.49675 16.817594)
			(stroke
				(width 0.1)
				(type default)
			)
			(layer "F.Fab")
		)
		(fp_line
			(start -37.496242 15.182342)
			(end -37.492432 15.185644)
			(stroke
				(width 0.1)
				(type default)
			)
			(layer "F.Fab")
		)
		(fp_line
			(start -37.49675 16.817594)
			(end -37.502592 16.822674)
			(stroke
				(width 0.1)
				(type default)
			)
			(layer "F.Fab")
		)
		(fp_line
			(start -37.500306 15.178786)
			(end -37.496242 15.182342)
			(stroke
				(width 0.1)
				(type default)
			)
			(layer "F.Fab")
		)
		(fp_line
			(start -37.502592 16.822674)
			(end -37.511228 16.83004)
			(stroke
				(width 0.1)
				(type default)
			)
			(layer "F.Fab")
		)
		(fp_line
			(start -37.5031 15.1765)
			(end -37.500306 15.178786)
			(stroke
				(width 0.1)
				(type default)
			)
			(layer "F.Fab")
		)
		(fp_line
			(start -37.505386 15.174722)
			(end -37.5031 15.1765)
			(stroke
				(width 0.1)
				(type default)
			)
			(layer "F.Fab")
		)
		(fp_line
			(start -37.509704 15.170912)
			(end -37.505386 15.174722)
			(stroke
				(width 0.1)
				(type default)
			)
			(layer "F.Fab")
		)
		(fp_line
			(start -37.511228 16.83004)
			(end -37.516308 16.834104)
			(stroke
				(width 0.1)
				(type default)
			)
			(layer "F.Fab")
		)
		(fp_line
			(start -37.513514 15.16761)
			(end -37.509704 15.170912)
			(stroke
				(width 0.1)
				(type default)
			)
			(layer "F.Fab")
		)
		(fp_line
			(start -37.516308 16.834104)
			(end -37.520118 16.837406)
			(stroke
				(width 0.1)
				(type default)
			)
			(layer "F.Fab")
		)
		(fp_line
			(start -37.51707 15.164816)
			(end -37.513514 15.16761)
			(stroke
				(width 0.1)
				(type default)
			)
			(layer "F.Fab")
		)
		(fp_line
			(start -37.520118 16.837406)
			(end -37.525706 16.841978)
			(stroke
				(width 0.1)
				(type default)
			)
			(layer "F.Fab")
		)
		(fp_line
			(start -37.522404 15.160498)
			(end -37.51707 15.164816)
			(stroke
				(width 0.1)
				(type default)
			)
			(layer "F.Fab")
		)
		(fp_line
			(start -37.525706 16.841978)
			(end -37.531294 16.84655)
			(stroke
				(width 0.1)
				(type default)
			)
			(layer "F.Fab")
		)
		(fp_line
			(start -37.5285 15.155418)
			(end -37.522404 15.160498)
			(stroke
				(width 0.1)
				(type default)
			)
			(layer "F.Fab")
		)
		(fp_line
			(start -37.531294 16.84655)
			(end -37.536628 16.850868)
			(stroke
				(width 0.1)
				(type default)
			)
			(layer "F.Fab")
		)
		(fp_line
			(start -37.532056 15.152624)
			(end -37.5285 15.155418)
			(stroke
				(width 0.1)
				(type default)
			)
			(layer "F.Fab")
		)
		(fp_line
			(start -37.536374 15.149068)
			(end -37.532056 15.152624)
			(stroke
				(width 0.1)
				(type default)
			)
			(layer "F.Fab")
		)
		(fp_line
			(start -37.536628 16.850868)
			(end -37.540184 16.853408)
			(stroke
				(width 0.1)
				(type default)
			)
			(layer "F.Fab")
		)
		(fp_line
			(start -37.540184 16.853408)
			(end -37.543232 16.855948)
			(stroke
				(width 0.1)
				(type default)
			)
			(layer "F.Fab")
		)
		(fp_line
			(start -37.540184 15.14602)
			(end -37.536374 15.149068)
			(stroke
				(width 0.1)
				(type default)
			)
			(layer "F.Fab")
		)
		(fp_line
			(start -37.543232 16.855948)
			(end -37.547296 16.858996)
			(stroke
				(width 0.1)
				(type default)
			)
			(layer "F.Fab")
		)
		(fp_line
			(start -37.545772 15.141702)
			(end -37.540184 15.14602)
			(stroke
				(width 0.1)
				(type default)
			)
			(layer "F.Fab")
		)
		(fp_line
			(start -37.547296 16.858996)
			(end -37.551106 16.862044)
			(stroke
				(width 0.1)
				(type default)
			)
			(layer "F.Fab")
		)
		(fp_line
			(start -37.551106 16.862044)
			(end -37.554408 16.864584)
			(stroke
				(width 0.1)
				(type default)
			)
			(layer "F.Fab")
		)
		(fp_line
			(start -37.551106 15.137638)
			(end -37.545772 15.141702)
			(stroke
				(width 0.1)
				(type default)
			)
			(layer "F.Fab")
		)
		(fp_line
			(start -37.554408 16.864584)
			(end -37.559742 16.868648)
			(stroke
				(width 0.1)
				(type default)
			)
			(layer "F.Fab")
		)
		(fp_line
			(start -37.556948 15.13332)
			(end -37.551106 15.137638)
			(stroke
				(width 0.1)
				(type default)
			)
			(layer "F.Fab")
		)
		(fp_line
			(start -37.559742 16.868648)
			(end -37.564822 16.872204)
			(stroke
				(width 0.1)
				(type default)
			)
			(layer "F.Fab")
		)
		(fp_line
			(start -37.561774 15.12951)
			(end -37.556948 15.13332)
			(stroke
				(width 0.1)
				(type default)
			)
			(layer "F.Fab")
		)
		(fp_line
			(start -37.564822 16.872204)
			(end -37.568886 16.875506)
			(stroke
				(width 0.1)
				(type default)
			)
			(layer "F.Fab")
		)
		(fp_line
			(start -37.568886 16.875506)
			(end -37.574728 16.87957)
			(stroke
				(width 0.1)
				(type default)
			)
			(layer "F.Fab")
		)
		(fp_line
			(start -37.57041 15.12316)
			(end -37.561774 15.12951)
			(stroke
				(width 0.1)
				(type default)
			)
			(layer "F.Fab")
		)
		(fp_line
			(start -37.574728 16.87957)
			(end -37.581586 16.884396)
			(stroke
				(width 0.1)
				(type default)
			)
			(layer "F.Fab")
		)
		(fp_line
			(start -37.574982 15.119858)
			(end -37.57041 15.12316)
			(stroke
				(width 0.1)
				(type default)
			)
			(layer "F.Fab")
		)
		(fp_line
			(start -37.581586 16.884396)
			(end -37.586666 16.887952)
			(stroke
				(width 0.1)
				(type default)
			)
			(layer "F.Fab")
		)
		(fp_line
			(start -37.582602 15.114524)
			(end -37.574982 15.119858)
			(stroke
				(width 0.1)
				(type default)
			)
			(layer "F.Fab")
		)
		(fp_line
			(start -37.586666 16.887952)
			(end -37.592 16.891762)
			(stroke
				(width 0.1)
				(type default)
			)
			(layer "F.Fab")
		)
		(fp_line
			(start -37.588444 15.11046)
			(end -37.582602 15.114524)
			(stroke
				(width 0.1)
				(type default)
			)
			(layer "F.Fab")
		)
		(fp_line
			(start -37.592 16.891762)
			(end -37.598604 16.89608)
			(stroke
				(width 0.1)
				(type default)
			)
			(layer "F.Fab")
		)
		(fp_line
			(start -37.594794 15.106142)
			(end -37.588444 15.11046)
			(stroke
				(width 0.1)
				(type default)
			)
			(layer "F.Fab")
		)
		(fp_line
			(start -37.597842 15.10411)
			(end -37.594794 15.106142)
			(stroke
				(width 0.1)
				(type default)
			)
			(layer "F.Fab")
		)
		(fp_line
			(start -37.598604 16.89608)
			(end -37.610542 16.904208)
			(stroke
				(width 0.1)
				(type default)
			)
			(layer "F.Fab")
		)
		(fp_line
			(start -37.600636 15.102078)
			(end -37.597842 15.10411)
			(stroke
				(width 0.1)
				(type default)
			)
			(layer "F.Fab")
		)
		(fp_line
			(start -37.607748 15.097252)
			(end -37.600636 15.102078)
			(stroke
				(width 0.1)
				(type default)
			)
			(layer "F.Fab")
		)
		(fp_line
			(start -37.610542 16.904208)
			(end -37.615368 16.90751)
			(stroke
				(width 0.1)
				(type default)
			)
			(layer "F.Fab")
		)
		(fp_line
			(start -37.61105 15.09522)
			(end -37.607748 15.097252)
			(stroke
				(width 0.1)
				(type default)
			)
			(layer "F.Fab")
		)
		(fp_line
			(start -37.615368 16.90751)
			(end -37.619178 16.909796)
			(stroke
				(width 0.1)
				(type default)
			)
			(layer "F.Fab")
		)
		(fp_line
			(start -37.619178 16.909796)
			(end -37.624258 16.913098)
			(stroke
				(width 0.1)
				(type default)
			)
			(layer "F.Fab")
		)
		(fp_line
			(start -37.619178 15.089632)
			(end -37.61105 15.09522)
			(stroke
				(width 0.1)
				(type default)
			)
			(layer "F.Fab")
		)
		(fp_line
			(start -37.624258 16.913098)
			(end -37.628576 16.915892)
			(stroke
				(width 0.1)
				(type default)
			)
			(layer "F.Fab")
		)
		(fp_line
			(start -37.626544 15.08506)
			(end -37.619178 15.089632)
			(stroke
				(width 0.1)
				(type default)
			)
			(layer "F.Fab")
		)
		(fp_line
			(start -37.628576 16.915892)
			(end -37.634926 16.919956)
			(stroke
				(width 0.1)
				(type default)
			)
			(layer "F.Fab")
		)
		(fp_line
			(start -37.630608 15.08252)
			(end -37.626544 15.08506)
			(stroke
				(width 0.1)
				(type default)
			)
			(layer "F.Fab")
		)
		(fp_line
			(start -37.634926 16.919956)
			(end -37.6428 16.924782)
			(stroke
				(width 0.1)
				(type default)
			)
			(layer "F.Fab")
		)
		(fp_line
			(start -37.635434 15.079472)
			(end -37.630608 15.08252)
			(stroke
				(width 0.1)
				(type default)
			)
			(layer "F.Fab")
		)
		(fp_line
			(start -37.640006 15.076678)
			(end -37.635434 15.079472)
			(stroke
				(width 0.1)
				(type default)
			)
			(layer "F.Fab")
		)
		(fp_line
			(start -37.642292 15.075154)
			(end -37.640006 15.076678)
			(stroke
				(width 0.1)
				(type default)
			)
			(layer "F.Fab")
		)
		(fp_line
			(start -37.6428 16.924782)
			(end -37.647118 16.927576)
			(stroke
				(width 0.1)
				(type default)
			)
			(layer "F.Fab")
		)
		(fp_line
			(start -37.64534 15.073376)
			(end -37.642292 15.075154)
			(stroke
				(width 0.1)
				(type default)
			)
			(layer "F.Fab")
		)
		(fp_line
			(start -37.647118 16.927576)
			(end -37.653214 16.931132)
			(stroke
				(width 0.1)
				(type default)
			)
			(layer "F.Fab")
		)
		(fp_line
			(start -37.648134 15.071598)
			(end -37.64534 15.073376)
			(stroke
				(width 0.1)
				(type default)
			)
			(layer "F.Fab")
		)
		(fp_line
			(start -37.651944 15.069312)
			(end -37.648134 15.071598)
			(stroke
				(width 0.1)
				(type default)
			)
			(layer "F.Fab")
		)
		(fp_line
			(start -37.653214 16.931132)
			(end -37.658802 16.934434)
			(stroke
				(width 0.1)
				(type default)
			)
			(layer "F.Fab")
		)
		(fp_line
			(start -37.657024 15.066264)
			(end -37.651944 15.069312)
			(stroke
				(width 0.1)
				(type default)
			)
			(layer "F.Fab")
		)
		(fp_line
			(start -37.658802 16.934434)
			(end -37.665406 16.938498)
			(stroke
				(width 0.1)
				(type default)
			)
			(layer "F.Fab")
		)
		(fp_line
			(start -37.661596 15.063724)
			(end -37.657024 15.066264)
			(stroke
				(width 0.1)
				(type default)
			)
			(layer "F.Fab")
		)
		(fp_line
			(start -37.665406 16.938498)
			(end -37.67455 16.943578)
			(stroke
				(width 0.1)
				(type default)
			)
			(layer "F.Fab")
		)
		(fp_line
			(start -37.665406 15.061438)
			(end -37.661596 15.063724)
			(stroke
				(width 0.1)
				(type default)
			)
			(layer "F.Fab")
		)
		(fp_line
			(start -37.673026 15.05712)
			(end -37.665406 15.061438)
			(stroke
				(width 0.1)
				(type default)
			)
			(layer "F.Fab")
		)
		(fp_line
			(start -37.67455 16.943578)
			(end -37.679376 16.946372)
			(stroke
				(width 0.1)
				(type default)
			)
			(layer "F.Fab")
		)
		(fp_line
			(start -37.677344 15.05458)
			(end -37.673026 15.05712)
			(stroke
				(width 0.1)
				(type default)
			)
			(layer "F.Fab")
		)
		(fp_line
			(start -37.679376 16.946372)
			(end -37.687758 16.950944)
			(stroke
				(width 0.1)
				(type default)
			)
			(layer "F.Fab")
		)
		(fp_line
			(start -37.681662 15.052294)
			(end -37.677344 15.05458)
			(stroke
				(width 0.1)
				(type default)
			)
			(layer "F.Fab")
		)
		(fp_line
			(start -37.687758 16.950944)
			(end -37.692584 16.953484)
			(stroke
				(width 0.1)
				(type default)
			)
			(layer "F.Fab")
		)
		(fp_line
			(start -37.688774 15.04823)
			(end -37.681662 15.052294)
			(stroke
				(width 0.1)
				(type default)
			)
			(layer "F.Fab")
		)
		(fp_line
			(start -37.692584 16.953484)
			(end -37.69741 16.956278)
			(stroke
				(width 0.1)
				(type default)
			)
			(layer "F.Fab")
		)
		(fp_line
			(start -37.69741 16.956278)
			(end -37.701474 16.95831)
			(stroke
				(width 0.1)
				(type default)
			)
			(layer "F.Fab")
		)
		(fp_line
			(start -37.701474 16.95831)
			(end -37.705284 16.960342)
			(stroke
				(width 0.1)
				(type default)
			)
			(layer "F.Fab")
		)
		(fp_line
			(start -37.705284 16.960342)
			(end -37.710364 16.962882)
			(stroke
				(width 0.1)
				(type default)
			)
			(layer "F.Fab")
		)
		(fp_line
			(start -37.707824 15.038324)
			(end -37.688774 15.04823)
			(stroke
				(width 0.1)
				(type default)
			)
			(layer "F.Fab")
		)
		(fp_line
			(start -37.710364 16.962882)
			(end -37.717222 16.966438)
			(stroke
				(width 0.1)
				(type default)
			)
			(layer "F.Fab")
		)
		(fp_line
			(start -37.713412 15.035276)
			(end -37.707824 15.038324)
			(stroke
				(width 0.1)
				(type default)
			)
			(layer "F.Fab")
		)
		(fp_line
			(start -37.717222 16.966438)
			(end -37.72789 16.972026)
			(stroke
				(width 0.1)
				(type default)
			)
			(layer "F.Fab")
		)
		(fp_line
			(start -37.721286 15.031212)
			(end -37.713412 15.035276)
			(stroke
				(width 0.1)
				(type default)
			)
			(layer "F.Fab")
		)
		(fp_line
			(start -37.72789 16.972026)
			(end -37.732208 16.974058)
			(stroke
				(width 0.1)
				(type default)
			)
			(layer "F.Fab")
		)
		(fp_line
			(start -37.728906 15.027402)
			(end -37.721286 15.031212)
			(stroke
				(width 0.1)
				(type default)
			)
			(layer "F.Fab")
		)
		(fp_line
			(start -37.732208 16.974058)
			(end -37.738304 16.976852)
			(stroke
				(width 0.1)
				(type default)
			)
			(layer "F.Fab")
		)
		(fp_line
			(start -37.733986 15.024862)
			(end -37.728906 15.027402)
			(stroke
				(width 0.1)
				(type default)
			)
			(layer "F.Fab")
		)
		(fp_line
			(start -37.738304 16.976852)
			(end -37.742876 16.979138)
			(stroke
				(width 0.1)
				(type default)
			)
			(layer "F.Fab")
		)
		(fp_line
			(start -37.739574 15.022322)
			(end -37.733986 15.024862)
			(stroke
				(width 0.1)
				(type default)
			)
			(layer "F.Fab")
		)
		(fp_line
			(start -37.742876 16.979138)
			(end -37.74821 16.981678)
			(stroke
				(width 0.1)
				(type default)
			)
			(layer "F.Fab")
		)
		(fp_line
			(start -37.74567 15.019274)
			(end -37.739574 15.022322)
			(stroke
				(width 0.1)
				(type default)
			)
			(layer "F.Fab")
		)
		(fp_line
			(start -37.74821 16.981678)
			(end -37.753036 16.983964)
			(stroke
				(width 0.1)
				(type default)
			)
			(layer "F.Fab")
		)
		(fp_line
			(start -37.74948 15.017496)
			(end -37.74567 15.019274)
			(stroke
				(width 0.1)
				(type default)
			)
			(layer "F.Fab")
		)
		(fp_line
			(start -37.753036 16.983964)
			(end -37.756084 16.985488)
			(stroke
				(width 0.1)
				(type default)
			)
			(layer "F.Fab")
		)
		(fp_line
			(start -37.753798 15.015718)
			(end -37.74948 15.017496)
			(stroke
				(width 0.1)
				(type default)
			)
			(layer "F.Fab")
		)
		(fp_line
			(start -37.756084 16.985488)
			(end -37.765228 16.989552)
			(stroke
				(width 0.1)
				(type default)
			)
			(layer "F.Fab")
		)
		(fp_line
			(start -37.759894 15.01267)
			(end -37.753798 15.015718)
			(stroke
				(width 0.1)
				(type default)
			)
			(layer "F.Fab")
		)
		(fp_line
			(start -37.763196 15.0114)
			(end -37.759894 15.01267)
			(stroke
				(width 0.1)
				(type default)
			)
			(layer "F.Fab")
		)
		(fp_line
			(start -37.765228 16.989552)
			(end -37.768784 16.991076)
			(stroke
				(width 0.1)
				(type default)
			)
			(layer "F.Fab")
		)
		(fp_line
			(start -37.767006 15.009622)
			(end -37.763196 15.0114)
			(stroke
				(width 0.1)
				(type default)
			)
			(layer "F.Fab")
		)
		(fp_line
			(start -37.768784 16.991076)
			(end -37.773102 16.993108)
			(stroke
				(width 0.1)
				(type default)
			)
			(layer "F.Fab")
		)
		(fp_line
			(start -37.773102 16.993108)
			(end -37.777674 16.994886)
			(stroke
				(width 0.1)
				(type default)
			)
			(layer "F.Fab")
		)
		(fp_line
			(start -37.773102 15.006828)
			(end -37.767006 15.009622)
			(stroke
				(width 0.1)
				(type default)
			)
			(layer "F.Fab")
		)
		(fp_line
			(start -37.777674 16.994886)
			(end -37.78758 16.999204)
			(stroke
				(width 0.1)
				(type default)
			)
			(layer "F.Fab")
		)
		(fp_line
			(start -37.777674 15.004796)
			(end -37.773102 15.006828)
			(stroke
				(width 0.1)
				(type default)
			)
			(layer "F.Fab")
		)
		(fp_line
			(start -37.782754 15.002764)
			(end -37.777674 15.004796)
			(stroke
				(width 0.1)
				(type default)
			)
			(layer "F.Fab")
		)
		(fp_line
			(start -37.78758 16.999204)
			(end -37.804852 17.006316)
			(stroke
				(width 0.1)
				(type default)
			)
			(layer "F.Fab")
		)
		(fp_line
			(start -37.788088 15.000478)
			(end -37.782754 15.002764)
			(stroke
				(width 0.1)
				(type default)
			)
			(layer "F.Fab")
		)
		(fp_line
			(start -37.79647 14.996922)
			(end -37.788088 15.000478)
			(stroke
				(width 0.1)
				(type default)
			)
			(layer "F.Fab")
		)
		(fp_line
			(start -37.804852 17.006316)
			(end -37.819838 17.012158)
			(stroke
				(width 0.1)
				(type default)
			)
			(layer "F.Fab")
		)
		(fp_line
			(start -37.812218 14.990572)
			(end -37.79647 14.996922)
			(stroke
				(width 0.1)
				(type default)
			)
			(layer "F.Fab")
		)
		(fp_line
			(start -37.819838 17.012158)
			(end -37.828982 17.015714)
			(stroke
				(width 0.1)
				(type default)
			)
			(layer "F.Fab")
		)
		(fp_line
			(start -37.828982 17.015714)
			(end -37.836856 17.018508)
			(stroke
				(width 0.1)
				(type default)
			)
			(layer "F.Fab")
		)
		(fp_line
			(start -37.829998 14.983714)
			(end -37.812218 14.990572)
			(stroke
				(width 0.1)
				(type default)
			)
			(layer "F.Fab")
		)
		(fp_line
			(start -37.834824 14.98219)
			(end -37.829998 14.983714)
			(stroke
				(width 0.1)
				(type default)
			)
			(layer "F.Fab")
		)
		(fp_line
			(start -37.836348 14.981428)
			(end -37.834824 14.98219)
			(stroke
				(width 0.1)
				(type default)
			)
			(layer "F.Fab")
		)
		(fp_line
			(start -37.836856 17.018508)
			(end -37.841682 17.020286)
			(stroke
				(width 0.1)
				(type default)
			)
			(layer "F.Fab")
		)
		(fp_line
			(start -37.839904 14.980158)
			(end -37.836348 14.981428)
			(stroke
				(width 0.1)
				(type default)
			)
			(layer "F.Fab")
		)
		(fp_line
			(start -37.841682 17.020286)
			(end -37.84981 17.023334)
			(stroke
				(width 0.1)
				(type default)
			)
			(layer "F.Fab")
		)
		(fp_line
			(start -37.843206 14.978888)
			(end -37.839904 14.980158)
			(stroke
				(width 0.1)
				(type default)
			)
			(layer "F.Fab")
		)
		(fp_line
			(start -37.847778 14.977364)
			(end -37.843206 14.978888)
			(stroke
				(width 0.1)
				(type default)
			)
			(layer "F.Fab")
		)
		(fp_line
			(start -37.84981 17.023334)
			(end -37.857176 17.025874)
			(stroke
				(width 0.1)
				(type default)
			)
			(layer "F.Fab")
		)
		(fp_line
			(start -37.851334 14.976094)
			(end -37.847778 14.977364)
			(stroke
				(width 0.1)
				(type default)
			)
			(layer "F.Fab")
		)
		(fp_line
			(start -37.856414 14.974316)
			(end -37.851334 14.976094)
			(stroke
				(width 0.1)
				(type default)
			)
			(layer "F.Fab")
		)
		(fp_line
			(start -37.857176 17.025874)
			(end -37.864542 17.028414)
			(stroke
				(width 0.1)
				(type default)
			)
			(layer "F.Fab")
		)
		(fp_line
			(start -37.861748 14.972538)
			(end -37.856414 14.974316)
			(stroke
				(width 0.1)
				(type default)
			)
			(layer "F.Fab")
		)
		(fp_line
			(start -37.864542 17.028414)
			(end -37.875718 17.03197)
			(stroke
				(width 0.1)
				(type default)
			)
			(layer "F.Fab")
		)
		(fp_line
			(start -37.86632 14.971014)
			(end -37.861748 14.972538)
			(stroke
				(width 0.1)
				(type default)
			)
			(layer "F.Fab")
		)
		(fp_line
			(start -37.871146 14.96949)
			(end -37.86632 14.971014)
			(stroke
				(width 0.1)
				(type default)
			)
			(layer "F.Fab")
		)
		(fp_line
			(start -37.874702 14.96822)
			(end -37.871146 14.96949)
			(stroke
				(width 0.1)
				(type default)
			)
			(layer "F.Fab")
		)
		(fp_line
			(start -37.875718 17.03197)
			(end -37.881306 17.033748)
			(stroke
				(width 0.1)
				(type default)
			)
			(layer "F.Fab")
		)
		(fp_line
			(start -37.878258 14.967204)
			(end -37.874702 14.96822)
			(stroke
				(width 0.1)
				(type default)
			)
			(layer "F.Fab")
		)
		(fp_line
			(start -37.881052 14.966188)
			(end -37.878258 14.967204)
			(stroke
				(width 0.1)
				(type default)
			)
			(layer "F.Fab")
		)
		(fp_line
			(start -37.881306 17.033748)
			(end -37.88791 17.03578)
			(stroke
				(width 0.1)
				(type default)
			)
			(layer "F.Fab")
		)
		(fp_line
			(start -37.886894 14.96441)
			(end -37.881052 14.966188)
			(stroke
				(width 0.1)
				(type default)
			)
			(layer "F.Fab")
		)
		(fp_line
			(start -37.88791 17.03578)
			(end -37.894514 17.037812)
			(stroke
				(width 0.1)
				(type default)
			)
			(layer "F.Fab")
		)
		(fp_line
			(start -37.889942 14.963394)
			(end -37.886894 14.96441)
			(stroke
				(width 0.1)
				(type default)
			)
			(layer "F.Fab")
		)
		(fp_line
			(start -37.894514 17.037812)
			(end -37.90061 17.03959)
			(stroke
				(width 0.1)
				(type default)
			)
			(layer "F.Fab")
		)
		(fp_line
			(start -37.895022 14.96187)
			(end -37.889942 14.963394)
			(stroke
				(width 0.1)
				(type default)
			)
			(layer "F.Fab")
		)
		(fp_line
			(start -37.90061 17.03959)
			(end -37.905436 17.041114)
			(stroke
				(width 0.1)
				(type default)
			)
			(layer "F.Fab")
		)
		(fp_line
			(start -37.903404 14.95933)
			(end -37.895022 14.96187)
			(stroke
				(width 0.1)
				(type default)
			)
			(layer "F.Fab")
		)
		(fp_line
			(start -37.905436 17.041114)
			(end -37.910008 17.042384)
			(stroke
				(width 0.1)
				(type default)
			)
			(layer "F.Fab")
		)
		(fp_line
			(start -37.907468 14.958314)
			(end -37.903404 14.95933)
			(stroke
				(width 0.1)
				(type default)
			)
			(layer "F.Fab")
		)
		(fp_line
			(start -37.910008 17.042384)
			(end -37.914326 17.043654)
			(stroke
				(width 0.1)
				(type default)
			)
			(layer "F.Fab")
		)
		(fp_line
			(start -37.912294 14.95679)
			(end -37.907468 14.958314)
			(stroke
				(width 0.1)
				(type default)
			)
			(layer "F.Fab")
		)
		(fp_line
			(start -37.914326 17.043654)
			(end -37.921184 17.045686)
			(stroke
				(width 0.1)
				(type default)
			)
			(layer "F.Fab")
		)
		(fp_line
			(start -37.917882 14.955266)
			(end -37.912294 14.95679)
			(stroke
				(width 0.1)
				(type default)
			)
			(layer "F.Fab")
		)
		(fp_line
			(start -37.92093 14.954504)
			(end -37.917882 14.955266)
			(stroke
				(width 0.1)
				(type default)
			)
			(layer "F.Fab")
		)
		(fp_line
			(start -37.921184 17.045686)
			(end -37.927788 17.047464)
			(stroke
				(width 0.1)
				(type default)
			)
			(layer "F.Fab")
		)
		(fp_line
			(start -37.927788 17.047464)
			(end -37.93109 17.048226)
			(stroke
				(width 0.1)
				(type default)
			)
			(layer "F.Fab")
		)
		(fp_line
			(start -37.927788 14.952472)
			(end -37.92093 14.954504)
			(stroke
				(width 0.1)
				(type default)
			)
			(layer "F.Fab")
		)
		(fp_line
			(start -37.93109 17.048226)
			(end -37.93617 17.049496)
			(stroke
				(width 0.1)
				(type default)
			)
			(layer "F.Fab")
		)
		(fp_line
			(start -37.933884 14.950948)
			(end -37.927788 14.952472)
			(stroke
				(width 0.1)
				(type default)
			)
			(layer "F.Fab")
		)
		(fp_line
			(start -37.93617 17.049496)
			(end -37.94379 17.051528)
			(stroke
				(width 0.1)
				(type default)
			)
			(layer "F.Fab")
		)
		(fp_line
			(start -37.942012 14.948916)
			(end -37.933884 14.950948)
			(stroke
				(width 0.1)
				(type default)
			)
			(layer "F.Fab")
		)
		(fp_line
			(start -37.94379 17.051528)
			(end -37.948616 17.052798)
			(stroke
				(width 0.1)
				(type default)
			)
			(layer "F.Fab")
		)
		(fp_line
			(start -37.948616 17.052798)
			(end -37.956998 17.05483)
			(stroke
				(width 0.1)
				(type default)
			)
			(layer "F.Fab")
		)
		(fp_line
			(start -37.94887 14.947138)
			(end -37.942012 14.948916)
			(stroke
				(width 0.1)
				(type default)
			)
			(layer "F.Fab")
		)
		(fp_line
			(start -37.953188 14.946122)
			(end -37.94887 14.947138)
			(stroke
				(width 0.1)
				(type default)
			)
			(layer "F.Fab")
		)
		(fp_line
			(start -37.956998 17.05483)
			(end -37.96538 17.057116)
			(stroke
				(width 0.1)
				(type default)
			)
			(layer "F.Fab")
		)
		(fp_line
			(start -37.957506 14.945106)
			(end -37.953188 14.946122)
			(stroke
				(width 0.1)
				(type default)
			)
			(layer "F.Fab")
		)
		(fp_line
			(start -37.96538 17.057116)
			(end -37.977064 17.059402)
			(stroke
				(width 0.1)
				(type default)
			)
			(layer "F.Fab")
		)
		(fp_line
			(start -37.972492 14.94155)
			(end -37.957506 14.945106)
			(stroke
				(width 0.1)
				(type default)
			)
			(layer "F.Fab")
		)
		(fp_line
			(start -37.977064 17.059402)
			(end -37.992558 17.062704)
			(stroke
				(width 0.1)
				(type default)
			)
			(layer "F.Fab")
		)
		(fp_line
			(start -37.992558 17.062704)
			(end -37.99967 17.063974)
			(stroke
				(width 0.1)
				(type default)
			)
			(layer "F.Fab")
		)
		(fp_line
			(start -37.99967 17.063974)
			(end -37.999924 17.064228)
			(stroke
				(width 0.1)
				(type default)
			)
			(layer "F.Fab")
		)
		(fp_line
			(start -37.999924 28.24988)
			(end 37.999924 28.24988)
			(stroke
				(width 0.1)
				(type default)
			)
			(layer "F.Fab")
		)
		(fp_line
			(start -37.999924 17.064228)
			(end -37.999924 28.24988)
			(stroke
				(width 0.1)
				(type default)
			)
			(layer "F.Fab")
		)
		(fp_line
			(start -37.999924 14.935962)
			(end -37.972492 14.94155)
			(stroke
				(width 0.1)
				(type default)
			)
			(layer "F.Fab")
		)
		(fp_line
			(start -37.999924 -28.24988)
			(end -37.999924 14.935962)
			(stroke
				(width 0.1)
				(type default)
			)
			(layer "F.Fab")
		)
		(fp_arc
			(start 37.999924 17.074388)
			(mid 37.111766 16.000198)
			(end 37.999924 14.925802)
			(stroke
				(width 0.1)
				(type default)
			)
			(layer "F.Fab")
		)
		(fp_circle
			(center -48.051212 -28.315412)
			(end -48.177958 -28.315412)
			(stroke
				(width 0.254)
				(type default)
			)
			(fill no)
			(layer "F.Fab")
		)
		(fp_text user "86"
			(at 35.444684 -32.99968 180)
			(unlocked yes)
			(layer "F.SilkS")
			(effects
				(font
					(size 0.7874 0.5842)
					(thickness 0.1524)
				)
			)
		)
		(fp_text user "85"
			(at 34.602928 -32.059118 180)
			(unlocked yes)
			(layer "F.SilkS")
			(effects
				(font
					(size 0.7874 0.5842)
					(thickness 0.1524)
				)
			)
		)
		(fp_text user "84"
			(at 33.727898 -32.99968 180)
			(unlocked yes)
			(layer "F.SilkS")
			(effects
				(font
					(size 0.7874 0.5842)
					(thickness 0.1524)
				)
			)
		)
		(fp_text user "83"
			(at 32.885888 -32.059118 180)
			(unlocked yes)
			(layer "F.SilkS")
			(effects
				(font
					(size 0.7874 0.5842)
					(thickness 0.1524)
				)
			)
		)
		(fp_text user "82"
			(at 32.010858 -32.99968 180)
			(unlocked yes)
			(layer "F.SilkS")
			(effects
				(font
					(size 0.7874 0.5842)
					(thickness 0.1524)
				)
			)
		)
		(fp_text user "81"
			(at 31.168848 -32.059118 180)
			(unlocked yes)
			(layer "F.SilkS")
			(effects
				(font
					(size 0.7874 0.5842)
					(thickness 0.1524)
				)
			)
		)
		(fp_text user "80"
			(at 30.293818 -32.99968 180)
			(unlocked yes)
			(layer "F.SilkS")
			(effects
				(font
					(size 0.7874 0.5842)
					(thickness 0.1524)
				)
			)
		)
		(fp_text user "79"
			(at 29.629608 -31.424118 180)
			(unlocked yes)
			(layer "F.SilkS")
			(effects
				(font
					(size 0.7874 0.5842)
					(thickness 0.1524)
				)
			)
		)
		(fp_text user "78"
			(at 28.754578 -32.36468 180)
			(unlocked yes)
			(layer "F.SilkS")
			(effects
				(font
					(size 0.7874 0.5842)
					(thickness 0.1524)
				)
			)
		)
		(fp_text user "77"
			(at 27.912822 -31.424118 180)
			(unlocked yes)
			(layer "F.SilkS")
			(effects
				(font
					(size 0.7874 0.5842)
					(thickness 0.1524)
				)
			)
		)
		(fp_text user "76"
			(at 27.037538 -32.36468 180)
			(unlocked yes)
			(layer "F.SilkS")
			(effects
				(font
					(size 0.7874 0.5842)
					(thickness 0.1524)
				)
			)
		)
		(fp_text user "75"
			(at 26.195782 -31.424118 180)
			(unlocked yes)
			(layer "F.SilkS")
			(effects
				(font
					(size 0.7874 0.5842)
					(thickness 0.1524)
				)
			)
		)
		(fp_text user "74"
			(at 25.320498 -32.36468 180)
			(unlocked yes)
			(layer "F.SilkS")
			(effects
				(font
					(size 0.7874 0.5842)
					(thickness 0.1524)
				)
			)
		)
		(fp_text user "73"
			(at 24.478742 -31.424118 180)
			(unlocked yes)
			(layer "F.SilkS")
			(effects
				(font
					(size 0.7874 0.5842)
					(thickness 0.1524)
				)
			)
		)
		(fp_text user "72"
			(at 23.603712 -32.36468 180)
			(unlocked yes)
			(layer "F.SilkS")
			(effects
				(font
					(size 0.7874 0.5842)
					(thickness 0.1524)
				)
			)
		)
		(fp_text user "71"
			(at 22.761702 -31.424118 180)
			(unlocked yes)
			(layer "F.SilkS")
			(effects
				(font
					(size 0.7874 0.5842)
					(thickness 0.1524)
				)
			)
		)
		(fp_text user "70"
			(at 21.886672 -32.36468 180)
			(unlocked yes)
			(layer "F.SilkS")
			(effects
				(font
					(size 0.7874 0.5842)
					(thickness 0.1524)
				)
			)
		)
		(fp_text user "69"
			(at 21.044662 -31.424118 180)
			(unlocked yes)
			(layer "F.SilkS")
			(effects
				(font
					(size 0.7874 0.5842)
					(thickness 0.1524)
				)
			)
		)
		(fp_text user "68"
			(at 20.169632 -32.36468 180)
			(unlocked yes)
			(layer "F.SilkS")
			(effects
				(font
					(size 0.7874 0.5842)
					(thickness 0.1524)
				)
			)
		)
		(fp_text user "67"
			(at 19.327622 -31.424118 180)
			(unlocked yes)
			(layer "F.SilkS")
			(effects
				(font
					(size 0.7874 0.5842)
					(thickness 0.1524)
				)
			)
		)
		(fp_text user "66"
			(at 18.452592 -32.36468 180)
			(unlocked yes)
			(layer "F.SilkS")
			(effects
				(font
					(size 0.7874 0.5842)
					(thickness 0.1524)
				)
			)
		)
		(fp_text user "65"
			(at 17.610582 -31.424118 180)
			(unlocked yes)
			(layer "F.SilkS")
			(effects
				(font
					(size 0.7874 0.5842)
					(thickness 0.1524)
				)
			)
		)
		(fp_text user "64"
			(at 16.735552 -32.36468 180)
			(unlocked yes)
			(layer "F.SilkS")
			(effects
				(font
					(size 0.7874 0.5842)
					(thickness 0.1524)
				)
			)
		)
		(fp_text user "63"
			(at 15.893796 -31.424118 180)
			(unlocked yes)
			(layer "F.SilkS")
			(effects
				(font
					(size 0.7874 0.5842)
					(thickness 0.1524)
				)
			)
		)
		(fp_text user "62"
			(at 15.018512 -32.36468 180)
			(unlocked yes)
			(layer "F.SilkS")
			(effects
				(font
					(size 0.7874 0.5842)
					(thickness 0.1524)
				)
			)
		)
		(fp_text user "61"
			(at 14.176756 -31.424118 180)
			(unlocked yes)
			(layer "F.SilkS")
			(effects
				(font
					(size 0.7874 0.5842)
					(thickness 0.1524)
				)
			)
		)
		(fp_text user "60"
			(at 13.301726 -32.36468 180)
			(unlocked yes)
			(layer "F.SilkS")
			(effects
				(font
					(size 0.7874 0.5842)
					(thickness 0.1524)
				)
			)
		)
		(fp_text user "59"
			(at 12.459716 -31.424118 180)
			(unlocked yes)
			(layer "F.SilkS")
			(effects
				(font
					(size 0.7874 0.5842)
					(thickness 0.1524)
				)
			)
		)
		(fp_text user "58"
			(at 11.584686 -32.36468 180)
			(unlocked yes)
			(layer "F.SilkS")
			(effects
				(font
					(size 0.7874 0.5842)
					(thickness 0.1524)
				)
			)
		)
		(fp_text user "57"
			(at 10.742676 -31.424118 180)
			(unlocked yes)
			(layer "F.SilkS")
			(effects
				(font
					(size 0.7874 0.5842)
					(thickness 0.1524)
				)
			)
		)
		(fp_text user "56"
			(at 9.867646 -32.36468 180)
			(unlocked yes)
			(layer "F.SilkS")
			(effects
				(font
					(size 0.7874 0.5842)
					(thickness 0.1524)
				)
			)
		)
		(fp_text user "55"
			(at 9.025636 -31.424118 180)
			(unlocked yes)
			(layer "F.SilkS")
			(effects
				(font
					(size 0.7874 0.5842)
					(thickness 0.1524)
				)
			)
		)
		(fp_text user "54"
			(at 8.150606 -32.36468 180)
			(unlocked yes)
			(layer "F.SilkS")
			(effects
				(font
					(size 0.7874 0.5842)
					(thickness 0.1524)
				)
			)
		)
		(fp_text user "53"
			(at 7.308596 -31.424118 180)
			(unlocked yes)
			(layer "F.SilkS")
			(effects
				(font
					(size 0.7874 0.5842)
					(thickness 0.1524)
				)
			)
		)
		(fp_text user "52"
			(at 6.433566 -32.36468 180)
			(unlocked yes)
			(layer "F.SilkS")
			(effects
				(font
					(size 0.7874 0.5842)
					(thickness 0.1524)
				)
			)
		)
		(fp_text user "51"
			(at 5.59181 -31.424118 180)
			(unlocked yes)
			(layer "F.SilkS")
			(effects
				(font
					(size 0.7874 0.5842)
					(thickness 0.1524)
				)
			)
		)
		(fp_text user "50"
			(at 4.716526 -32.36468 180)
			(unlocked yes)
			(layer "F.SilkS")
			(effects
				(font
					(size 0.7874 0.5842)
					(thickness 0.1524)
				)
			)
		)
		(fp_text user "49"
			(at 3.87477 -31.424118 180)
			(unlocked yes)
			(layer "F.SilkS")
			(effects
				(font
					(size 0.7874 0.5842)
					(thickness 0.1524)
				)
			)
		)
		(fp_text user "48"
			(at 2.999486 -32.36468 180)
			(unlocked yes)
			(layer "F.SilkS")
			(effects
				(font
					(size 0.7874 0.5842)
					(thickness 0.1524)
				)
			)
		)
		(fp_text user "47"
			(at 2.15773 -31.424118 180)
			(unlocked yes)
			(layer "F.SilkS")
			(effects
				(font
					(size 0.7874 0.5842)
					(thickness 0.1524)
				)
			)
		)
		(fp_text user "46"
			(at 1.2827 -32.36468 180)
			(unlocked yes)
			(layer "F.SilkS")
			(effects
				(font
					(size 0.7874 0.5842)
					(thickness 0.1524)
				)
			)
		)
		(fp_text user "45"
			(at 0.44069 -31.424118 180)
			(unlocked yes)
			(layer "F.SilkS")
			(effects
				(font
					(size 0.7874 0.5842)
					(thickness 0.1524)
				)
			)
		)
		(fp_text user "44"
			(at -0.43434 -32.36468 180)
			(unlocked yes)
			(layer "F.SilkS")
			(effects
				(font
					(size 0.7874 0.5842)
					(thickness 0.1524)
				)
			)
		)
		(fp_text user "43"
			(at -1.218184 -31.335726 180)
			(unlocked yes)
			(layer "F.SilkS")
			(effects
				(font
					(size 0.7874 0.5842)
					(thickness 0.1524)
				)
			)
		)
		(fp_text user "42"
			(at -2.093214 -32.276288 180)
			(unlocked yes)
			(layer "F.SilkS")
			(effects
				(font
					(size 0.7874 0.5842)
					(thickness 0.1524)
				)
			)
		)
		(fp_text user "41"
			(at -2.935224 -31.335726 180)
			(unlocked yes)
			(layer "F.SilkS")
			(effects
				(font
					(size 0.7874 0.5842)
					(thickness 0.1524)
				)
			)
		)
		(fp_text user "40"
			(at -3.810254 -32.276288 180)
			(unlocked yes)
			(layer "F.SilkS")
			(effects
				(font
					(size 0.7874 0.5842)
					(thickness 0.1524)
				)
			)
		)
		(fp_text user "39"
			(at -4.65201 -31.335726 180)
			(unlocked yes)
			(layer "F.SilkS")
			(effects
				(font
					(size 0.7874 0.5842)
					(thickness 0.1524)
				)
			)
		)
		(fp_text user "38"
			(at -5.527294 -32.276288 180)
			(unlocked yes)
			(layer "F.SilkS")
			(effects
				(font
					(size 0.7874 0.5842)
					(thickness 0.1524)
				)
			)
		)
		(fp_text user "37"
			(at -6.36905 -31.335726 180)
			(unlocked yes)
			(layer "F.SilkS")
			(effects
				(font
					(size 0.7874 0.5842)
					(thickness 0.1524)
				)
			)
		)
		(fp_text user "36"
			(at -7.24408 -32.276288 180)
			(unlocked yes)
			(layer "F.SilkS")
			(effects
				(font
					(size 0.7874 0.5842)
					(thickness 0.1524)
				)
			)
		)
		(fp_text user "35"
			(at -8.08609 -31.335726 180)
			(unlocked yes)
			(layer "F.SilkS")
			(effects
				(font
					(size 0.7874 0.5842)
					(thickness 0.1524)
				)
			)
		)
		(fp_text user "34"
			(at -8.96112 -32.276288 180)
			(unlocked yes)
			(layer "F.SilkS")
			(effects
				(font
					(size 0.7874 0.5842)
					(thickness 0.1524)
				)
			)
		)
		(fp_text user "33"
			(at -9.80313 -31.335726 180)
			(unlocked yes)
			(layer "F.SilkS")
			(effects
				(font
					(size 0.7874 0.5842)
					(thickness 0.1524)
				)
			)
		)
		(fp_text user "32"
			(at -10.67816 -32.276288 180)
			(unlocked yes)
			(layer "F.SilkS")
			(effects
				(font
					(size 0.7874 0.5842)
					(thickness 0.1524)
				)
			)
		)
		(fp_text user "31"
			(at -11.52017 -31.335726 180)
			(unlocked yes)
			(layer "F.SilkS")
			(effects
				(font
					(size 0.7874 0.5842)
					(thickness 0.1524)
				)
			)
		)
		(fp_text user "30"
			(at -12.3952 -32.276288 180)
			(unlocked yes)
			(layer "F.SilkS")
			(effects
				(font
					(size 0.7874 0.5842)
					(thickness 0.1524)
				)
			)
		)
		(fp_text user "29"
			(at -13.23721 -31.335726 180)
			(unlocked yes)
			(layer "F.SilkS")
			(effects
				(font
					(size 0.7874 0.5842)
					(thickness 0.1524)
				)
			)
		)
		(fp_text user "28"
			(at -14.11224 -32.276288 180)
			(unlocked yes)
			(layer "F.SilkS")
			(effects
				(font
					(size 0.7874 0.5842)
					(thickness 0.1524)
				)
			)
		)
		(fp_text user "27"
			(at -14.953996 -31.335726 180)
			(unlocked yes)
			(layer "F.SilkS")
			(effects
				(font
					(size 0.7874 0.5842)
					(thickness 0.1524)
				)
			)
		)
		(fp_text user "26"
			(at -15.82928 -32.276288 180)
			(unlocked yes)
			(layer "F.SilkS")
			(effects
				(font
					(size 0.7874 0.5842)
					(thickness 0.1524)
				)
			)
		)
		(fp_text user "25"
			(at -16.671036 -31.335726 180)
			(unlocked yes)
			(layer "F.SilkS")
			(effects
				(font
					(size 0.7874 0.5842)
					(thickness 0.1524)
				)
			)
		)
		(fp_text user "24"
			(at -17.54632 -32.276288 180)
			(unlocked yes)
			(layer "F.SilkS")
			(effects
				(font
					(size 0.7874 0.5842)
					(thickness 0.1524)
				)
			)
		)
		(fp_text user "23"
			(at -18.388076 -31.335726 180)
			(unlocked yes)
			(layer "F.SilkS")
			(effects
				(font
					(size 0.7874 0.5842)
					(thickness 0.1524)
				)
			)
		)
		(fp_text user "22"
			(at -19.263106 -32.276288 180)
			(unlocked yes)
			(layer "F.SilkS")
			(effects
				(font
					(size 0.7874 0.5842)
					(thickness 0.1524)
				)
			)
		)
		(fp_text user "21"
			(at -20.105116 -31.335726 180)
			(unlocked yes)
			(layer "F.SilkS")
			(effects
				(font
					(size 0.7874 0.5842)
					(thickness 0.1524)
				)
			)
		)
		(fp_text user "20"
			(at -20.980146 -32.276288 180)
			(unlocked yes)
			(layer "F.SilkS")
			(effects
				(font
					(size 0.7874 0.5842)
					(thickness 0.1524)
				)
			)
		)
		(fp_text user "19"
			(at -21.822156 -31.335726 180)
			(unlocked yes)
			(layer "F.SilkS")
			(effects
				(font
					(size 0.7874 0.5842)
					(thickness 0.1524)
				)
			)
		)
		(fp_text user "18"
			(at -22.697186 -32.276288 180)
			(unlocked yes)
			(layer "F.SilkS")
			(effects
				(font
					(size 0.7874 0.5842)
					(thickness 0.1524)
				)
			)
		)
		(fp_text user "17"
			(at -23.539196 -31.335726 180)
			(unlocked yes)
			(layer "F.SilkS")
			(effects
				(font
					(size 0.7874 0.5842)
					(thickness 0.1524)
				)
			)
		)
		(fp_text user "16"
			(at -24.414226 -32.276288 180)
			(unlocked yes)
			(layer "F.SilkS")
			(effects
				(font
					(size 0.7874 0.5842)
					(thickness 0.1524)
				)
			)
		)
		(fp_text user "15"
			(at -25.255982 -31.335726 180)
			(unlocked yes)
			(layer "F.SilkS")
			(effects
				(font
					(size 0.7874 0.5842)
					(thickness 0.1524)
				)
			)
		)
		(fp_text user "14"
			(at -26.131266 -32.276288 180)
			(unlocked yes)
			(layer "F.SilkS")
			(effects
				(font
					(size 0.7874 0.5842)
					(thickness 0.1524)
				)
			)
		)
		(fp_text user "13"
			(at -26.973022 -31.335726 180)
			(unlocked yes)
			(layer "F.SilkS")
			(effects
				(font
					(size 0.7874 0.5842)
					(thickness 0.1524)
				)
			)
		)
		(fp_text user "12"
			(at -27.848306 -32.276288 180)
			(unlocked yes)
			(layer "F.SilkS")
			(effects
				(font
					(size 0.7874 0.5842)
					(thickness 0.1524)
				)
			)
		)
		(fp_text user "11"
			(at -28.690062 -31.335726 180)
			(unlocked yes)
			(layer "F.SilkS")
			(effects
				(font
					(size 0.7874 0.5842)
					(thickness 0.1524)
				)
			)
		)
		(fp_text user "10"
			(at -29.565092 -32.276288 180)
			(unlocked yes)
			(layer "F.SilkS")
			(effects
				(font
					(size 0.7874 0.5842)
					(thickness 0.1524)
				)
			)
		)
		(fp_text user "9"
			(at -30.407102 -31.335726 180)
			(unlocked yes)
			(layer "F.SilkS")
			(effects
				(font
					(size 0.7874 0.5842)
					(thickness 0.1524)
				)
			)
		)
		(fp_text user "8"
			(at -31.282132 -32.276288 180)
			(unlocked yes)
			(layer "F.SilkS")
			(effects
				(font
					(size 0.7874 0.5842)
					(thickness 0.1524)
				)
			)
		)
		(fp_text user "7"
			(at -31.34741 -31.209742 180)
			(unlocked yes)
			(layer "F.SilkS")
			(effects
				(font
					(size 0.7874 0.5842)
					(thickness 0.1524)
				)
			)
		)
		(fp_text user "5"
			(at -32.21101 -31.260542 180)
			(unlocked yes)
			(layer "F.SilkS")
			(effects
				(font
					(size 0.7874 0.5842)
					(thickness 0.1524)
				)
			)
		)
		(fp_text user "3"
			(at -32.99841 -31.235142 180)
			(unlocked yes)
			(layer "F.SilkS")
			(effects
				(font
					(size 0.7874 0.5842)
					(thickness 0.1524)
				)
			)
		)
		(fp_text user "6"
			(at -32.999172 -32.276288 180)
			(unlocked yes)
			(layer "F.SilkS")
			(effects
				(font
					(size 0.7874 0.5842)
					(thickness 0.1524)
				)
			)
		)
		(fp_text user "1"
			(at -33.60801 -31.209742 180)
			(unlocked yes)
			(layer "F.SilkS")
			(effects
				(font
					(size 0.7874 0.5842)
					(thickness 0.1524)
				)
			)
		)
		(fp_text user "4"
			(at -34.716212 -32.276288 180)
			(unlocked yes)
			(layer "F.SilkS")
			(effects
				(font
					(size 0.7874 0.5842)
					(thickness 0.1524)
				)
			)
		)
		(fp_text user "2"
			(at -36.433252 -32.276288 180)
			(unlocked yes)
			(layer "F.SilkS")
			(effects
				(font
					(size 0.7874 0.5842)
					(thickness 0.1524)
				)
			)
		)
		(fp_text user "EE"
			(at -42.250614 26.504646 180)
			(unlocked yes)
			(layer "F.SilkS")
			(effects
				(font
					(size 0.7874 0.5842)
					(thickness 0.1524)
				)
			)
		)
		(fp_text user "BU"
			(at -42.440606 2.597912 180)
			(unlocked yes)
			(layer "F.SilkS")
			(effects
				(font
					(size 0.7874 0.5842)
					(thickness 0.1524)
				)
			)
		)
		(fp_text user "DU"
			(at -42.618406 22.409912 180)
			(unlocked yes)
			(layer "F.SilkS")
			(effects
				(font
					(size 0.7874 0.5842)
					(thickness 0.1524)
				)
			)
		)
		(fp_text user "DJ"
			(at -42.618406 18.447512 180)
			(unlocked yes)
			(layer "F.SilkS")
			(effects
				(font
					(size 0.7874 0.5842)
					(thickness 0.1524)
				)
			)
		)
		(fp_text user "DA"
			(at -42.618406 14.485112 180)
			(unlocked yes)
			(layer "F.SilkS")
			(effects
				(font
					(size 0.7874 0.5842)
					(thickness 0.1524)
				)
			)
		)
		(fp_text user "CN"
			(at -42.618406 10.522712 180)
			(unlocked yes)
			(layer "F.SilkS")
			(effects
				(font
					(size 0.7874 0.5842)
					(thickness 0.1524)
				)
			)
		)
		(fp_text user "CE"
			(at -42.618406 6.560312 180)
			(unlocked yes)
			(layer "F.SilkS")
			(effects
				(font
					(size 0.7874 0.5842)
					(thickness 0.1524)
				)
			)
		)
		(fp_text user "BJ"
			(at -42.618406 -1.364488 180)
			(unlocked yes)
			(layer "F.SilkS")
			(effects
				(font
					(size 0.7874 0.5842)
					(thickness 0.1524)
				)
			)
		)
		(fp_text user "BA"
			(at -42.618406 -5.326888 180)
			(unlocked yes)
			(layer "F.SilkS")
			(effects
				(font
					(size 0.7874 0.5842)
					(thickness 0.1524)
				)
			)
		)
		(fp_text user "AN"
			(at -42.618406 -9.289288 180)
			(unlocked yes)
			(layer "F.SilkS")
			(effects
				(font
					(size 0.7874 0.5842)
					(thickness 0.1524)
				)
			)
		)
		(fp_text user "AE"
			(at -42.618406 -13.251688 180)
			(unlocked yes)
			(layer "F.SilkS")
			(effects
				(font
					(size 0.7874 0.5842)
					(thickness 0.1524)
				)
			)
		)
		(fp_text user "U"
			(at -42.618406 -17.214088 180)
			(unlocked yes)
			(layer "F.SilkS")
			(effects
				(font
					(size 0.7874 0.5842)
					(thickness 0.1524)
				)
			)
		)
		(fp_text user "J"
			(at -42.618406 -21.176488 180)
			(unlocked yes)
			(layer "F.SilkS")
			(effects
				(font
					(size 0.7874 0.5842)
					(thickness 0.1524)
				)
			)
		)
		(fp_text user "DY"
			(at -42.625772 23.897844 180)
			(unlocked yes)
			(layer "F.SilkS")
			(effects
				(font
					(size 0.7874 0.5842)
					(thickness 0.1524)
				)
			)
		)
		(fp_text user "A"
			(at -42.756582 -25.23617 180)
			(unlocked yes)
			(layer "F.SilkS")
			(effects
				(font
					(size 0.7874 0.5842)
					(thickness 0.1524)
				)
			)
		)
		(fp_text user "86"
			(at 37.222684 -32.23768 180)
			(unlocked yes)
			(layer "F.Fab")
			(effects
				(font
					(size 0.7874 0.5842)
					(thickness 0.1524)
				)
			)
		)
		(fp_text user "85"
			(at 36.380928 -31.297118 180)
			(unlocked yes)
			(layer "F.Fab")
			(effects
				(font
					(size 0.7874 0.5842)
					(thickness 0.1524)
				)
			)
		)
		(fp_text user "84"
			(at 35.505898 -32.23768 180)
			(unlocked yes)
			(layer "F.Fab")
			(effects
				(font
					(size 0.7874 0.5842)
					(thickness 0.1524)
				)
			)
		)
		(fp_text user "83"
			(at 34.663888 -31.297118 180)
			(unlocked yes)
			(layer "F.Fab")
			(effects
				(font
					(size 0.7874 0.5842)
					(thickness 0.1524)
				)
			)
		)
		(fp_text user "82"
			(at 33.788858 -32.23768 180)
			(unlocked yes)
			(layer "F.Fab")
			(effects
				(font
					(size 0.7874 0.5842)
					(thickness 0.1524)
				)
			)
		)
		(fp_text user "81"
			(at 32.946848 -31.297118 180)
			(unlocked yes)
			(layer "F.Fab")
			(effects
				(font
					(size 0.7874 0.5842)
					(thickness 0.1524)
				)
			)
		)
		(fp_text user "80"
			(at 32.071818 -32.23768 180)
			(unlocked yes)
			(layer "F.Fab")
			(effects
				(font
					(size 0.7874 0.5842)
					(thickness 0.1524)
				)
			)
		)
		(fp_text user "79"
			(at 31.229808 -31.297118 180)
			(unlocked yes)
			(layer "F.Fab")
			(effects
				(font
					(size 0.7874 0.5842)
					(thickness 0.1524)
				)
			)
		)
		(fp_text user "78"
			(at 30.354778 -32.23768 180)
			(unlocked yes)
			(layer "F.Fab")
			(effects
				(font
					(size 0.7874 0.5842)
					(thickness 0.1524)
				)
			)
		)
		(fp_text user "77"
			(at 29.513022 -31.297118 180)
			(unlocked yes)
			(layer "F.Fab")
			(effects
				(font
					(size 0.7874 0.5842)
					(thickness 0.1524)
				)
			)
		)
		(fp_text user "76"
			(at 28.637738 -32.23768 180)
			(unlocked yes)
			(layer "F.Fab")
			(effects
				(font
					(size 0.7874 0.5842)
					(thickness 0.1524)
				)
			)
		)
		(fp_text user "75"
			(at 27.795982 -31.297118 180)
			(unlocked yes)
			(layer "F.Fab")
			(effects
				(font
					(size 0.7874 0.5842)
					(thickness 0.1524)
				)
			)
		)
		(fp_text user "74"
			(at 26.920698 -32.23768 180)
			(unlocked yes)
			(layer "F.Fab")
			(effects
				(font
					(size 0.7874 0.5842)
					(thickness 0.1524)
				)
			)
		)
		(fp_text user "73"
			(at 26.078942 -31.297118 180)
			(unlocked yes)
			(layer "F.Fab")
			(effects
				(font
					(size 0.7874 0.5842)
					(thickness 0.1524)
				)
			)
		)
		(fp_text user "72"
			(at 25.203912 -32.23768 180)
			(unlocked yes)
			(layer "F.Fab")
			(effects
				(font
					(size 0.7874 0.5842)
					(thickness 0.1524)
				)
			)
		)
		(fp_text user "71"
			(at 24.361902 -31.297118 180)
			(unlocked yes)
			(layer "F.Fab")
			(effects
				(font
					(size 0.7874 0.5842)
					(thickness 0.1524)
				)
			)
		)
		(fp_text user "70"
			(at 23.486872 -32.23768 180)
			(unlocked yes)
			(layer "F.Fab")
			(effects
				(font
					(size 0.7874 0.5842)
					(thickness 0.1524)
				)
			)
		)
		(fp_text user "69"
			(at 22.644862 -31.297118 180)
			(unlocked yes)
			(layer "F.Fab")
			(effects
				(font
					(size 0.7874 0.5842)
					(thickness 0.1524)
				)
			)
		)
		(fp_text user "68"
			(at 21.769832 -32.23768 180)
			(unlocked yes)
			(layer "F.Fab")
			(effects
				(font
					(size 0.7874 0.5842)
					(thickness 0.1524)
				)
			)
		)
		(fp_text user "67"
			(at 20.927822 -31.297118 180)
			(unlocked yes)
			(layer "F.Fab")
			(effects
				(font
					(size 0.7874 0.5842)
					(thickness 0.1524)
				)
			)
		)
		(fp_text user "66"
			(at 20.052792 -32.23768 180)
			(unlocked yes)
			(layer "F.Fab")
			(effects
				(font
					(size 0.7874 0.5842)
					(thickness 0.1524)
				)
			)
		)
		(fp_text user "65"
			(at 19.210782 -31.297118 180)
			(unlocked yes)
			(layer "F.Fab")
			(effects
				(font
					(size 0.7874 0.5842)
					(thickness 0.1524)
				)
			)
		)
		(fp_text user "64"
			(at 18.335752 -32.23768 180)
			(unlocked yes)
			(layer "F.Fab")
			(effects
				(font
					(size 0.7874 0.5842)
					(thickness 0.1524)
				)
			)
		)
		(fp_text user "63"
			(at 17.493996 -31.297118 180)
			(unlocked yes)
			(layer "F.Fab")
			(effects
				(font
					(size 0.7874 0.5842)
					(thickness 0.1524)
				)
			)
		)
		(fp_text user "62"
			(at 16.618712 -32.23768 180)
			(unlocked yes)
			(layer "F.Fab")
			(effects
				(font
					(size 0.7874 0.5842)
					(thickness 0.1524)
				)
			)
		)
		(fp_text user "61"
			(at 15.776956 -31.297118 180)
			(unlocked yes)
			(layer "F.Fab")
			(effects
				(font
					(size 0.7874 0.5842)
					(thickness 0.1524)
				)
			)
		)
		(fp_text user "60"
			(at 14.901926 -32.23768 180)
			(unlocked yes)
			(layer "F.Fab")
			(effects
				(font
					(size 0.7874 0.5842)
					(thickness 0.1524)
				)
			)
		)
		(fp_text user "59"
			(at 14.059916 -31.297118 180)
			(unlocked yes)
			(layer "F.Fab")
			(effects
				(font
					(size 0.7874 0.5842)
					(thickness 0.1524)
				)
			)
		)
		(fp_text user "58"
			(at 13.184886 -32.23768 180)
			(unlocked yes)
			(layer "F.Fab")
			(effects
				(font
					(size 0.7874 0.5842)
					(thickness 0.1524)
				)
			)
		)
		(fp_text user "57"
			(at 12.342876 -31.297118 180)
			(unlocked yes)
			(layer "F.Fab")
			(effects
				(font
					(size 0.7874 0.5842)
					(thickness 0.1524)
				)
			)
		)
		(fp_text user "56"
			(at 11.467846 -32.23768 180)
			(unlocked yes)
			(layer "F.Fab")
			(effects
				(font
					(size 0.7874 0.5842)
					(thickness 0.1524)
				)
			)
		)
		(fp_text user "55"
			(at 10.625836 -31.297118 180)
			(unlocked yes)
			(layer "F.Fab")
			(effects
				(font
					(size 0.7874 0.5842)
					(thickness 0.1524)
				)
			)
		)
		(fp_text user "54"
			(at 9.750806 -32.23768 180)
			(unlocked yes)
			(layer "F.Fab")
			(effects
				(font
					(size 0.7874 0.5842)
					(thickness 0.1524)
				)
			)
		)
		(fp_text user "53"
			(at 8.908796 -31.297118 180)
			(unlocked yes)
			(layer "F.Fab")
			(effects
				(font
					(size 0.7874 0.5842)
					(thickness 0.1524)
				)
			)
		)
		(fp_text user "52"
			(at 8.033766 -32.23768 180)
			(unlocked yes)
			(layer "F.Fab")
			(effects
				(font
					(size 0.7874 0.5842)
					(thickness 0.1524)
				)
			)
		)
		(fp_text user "51"
			(at 7.19201 -31.297118 180)
			(unlocked yes)
			(layer "F.Fab")
			(effects
				(font
					(size 0.7874 0.5842)
					(thickness 0.1524)
				)
			)
		)
		(fp_text user "50"
			(at 6.316726 -32.23768 180)
			(unlocked yes)
			(layer "F.Fab")
			(effects
				(font
					(size 0.7874 0.5842)
					(thickness 0.1524)
				)
			)
		)
		(fp_text user "49"
			(at 5.47497 -31.297118 180)
			(unlocked yes)
			(layer "F.Fab")
			(effects
				(font
					(size 0.7874 0.5842)
					(thickness 0.1524)
				)
			)
		)
		(fp_text user "48"
			(at 4.599686 -32.23768 180)
			(unlocked yes)
			(layer "F.Fab")
			(effects
				(font
					(size 0.7874 0.5842)
					(thickness 0.1524)
				)
			)
		)
		(fp_text user "47"
			(at 3.75793 -31.297118 180)
			(unlocked yes)
			(layer "F.Fab")
			(effects
				(font
					(size 0.7874 0.5842)
					(thickness 0.1524)
				)
			)
		)
		(fp_text user "46"
			(at 2.8829 -32.23768 180)
			(unlocked yes)
			(layer "F.Fab")
			(effects
				(font
					(size 0.7874 0.5842)
					(thickness 0.1524)
				)
			)
		)
		(fp_text user "45"
			(at 2.04089 -31.297118 180)
			(unlocked yes)
			(layer "F.Fab")
			(effects
				(font
					(size 0.7874 0.5842)
					(thickness 0.1524)
				)
			)
		)
		(fp_text user "44"
			(at 1.16586 -32.23768 180)
			(unlocked yes)
			(layer "F.Fab")
			(effects
				(font
					(size 0.7874 0.5842)
					(thickness 0.1524)
				)
			)
		)
		(fp_text user "43"
			(at -1.218184 -31.335726 180)
			(unlocked yes)
			(layer "F.Fab")
			(effects
				(font
					(size 0.7874 0.5842)
					(thickness 0.1524)
				)
			)
		)
		(fp_text user "42"
			(at -2.093214 -32.276288 180)
			(unlocked yes)
			(layer "F.Fab")
			(effects
				(font
					(size 0.7874 0.5842)
					(thickness 0.1524)
				)
			)
		)
		(fp_text user "41"
			(at -2.935224 -31.335726 180)
			(unlocked yes)
			(layer "F.Fab")
			(effects
				(font
					(size 0.7874 0.5842)
					(thickness 0.1524)
				)
			)
		)
		(fp_text user "40"
			(at -3.810254 -32.276288 180)
			(unlocked yes)
			(layer "F.Fab")
			(effects
				(font
					(size 0.7874 0.5842)
					(thickness 0.1524)
				)
			)
		)
		(fp_text user "39"
			(at -4.65201 -31.335726 180)
			(unlocked yes)
			(layer "F.Fab")
			(effects
				(font
					(size 0.7874 0.5842)
					(thickness 0.1524)
				)
			)
		)
		(fp_text user "38"
			(at -5.527294 -32.276288 180)
			(unlocked yes)
			(layer "F.Fab")
			(effects
				(font
					(size 0.7874 0.5842)
					(thickness 0.1524)
				)
			)
		)
		(fp_text user "37"
			(at -6.36905 -31.335726 180)
			(unlocked yes)
			(layer "F.Fab")
			(effects
				(font
					(size 0.7874 0.5842)
					(thickness 0.1524)
				)
			)
		)
		(fp_text user "36"
			(at -7.24408 -32.276288 180)
			(unlocked yes)
			(layer "F.Fab")
			(effects
				(font
					(size 0.7874 0.5842)
					(thickness 0.1524)
				)
			)
		)
		(fp_text user "35"
			(at -8.08609 -31.335726 180)
			(unlocked yes)
			(layer "F.Fab")
			(effects
				(font
					(size 0.7874 0.5842)
					(thickness 0.1524)
				)
			)
		)
		(fp_text user "34"
			(at -8.96112 -32.276288 180)
			(unlocked yes)
			(layer "F.Fab")
			(effects
				(font
					(size 0.7874 0.5842)
					(thickness 0.1524)
				)
			)
		)
		(fp_text user "33"
			(at -9.80313 -31.335726 180)
			(unlocked yes)
			(layer "F.Fab")
			(effects
				(font
					(size 0.7874 0.5842)
					(thickness 0.1524)
				)
			)
		)
		(fp_text user "32"
			(at -10.67816 -32.276288 180)
			(unlocked yes)
			(layer "F.Fab")
			(effects
				(font
					(size 0.7874 0.5842)
					(thickness 0.1524)
				)
			)
		)
		(fp_text user "31"
			(at -11.52017 -31.335726 180)
			(unlocked yes)
			(layer "F.Fab")
			(effects
				(font
					(size 0.7874 0.5842)
					(thickness 0.1524)
				)
			)
		)
		(fp_text user "30"
			(at -12.3952 -32.276288 180)
			(unlocked yes)
			(layer "F.Fab")
			(effects
				(font
					(size 0.7874 0.5842)
					(thickness 0.1524)
				)
			)
		)
		(fp_text user "29"
			(at -13.23721 -31.335726 180)
			(unlocked yes)
			(layer "F.Fab")
			(effects
				(font
					(size 0.7874 0.5842)
					(thickness 0.1524)
				)
			)
		)
		(fp_text user "28"
			(at -14.11224 -32.276288 180)
			(unlocked yes)
			(layer "F.Fab")
			(effects
				(font
					(size 0.7874 0.5842)
					(thickness 0.1524)
				)
			)
		)
		(fp_text user "27"
			(at -14.953996 -31.335726 180)
			(unlocked yes)
			(layer "F.Fab")
			(effects
				(font
					(size 0.7874 0.5842)
					(thickness 0.1524)
				)
			)
		)
		(fp_text user "26"
			(at -15.82928 -32.276288 180)
			(unlocked yes)
			(layer "F.Fab")
			(effects
				(font
					(size 0.7874 0.5842)
					(thickness 0.1524)
				)
			)
		)
		(fp_text user "25"
			(at -16.671036 -31.335726 180)
			(unlocked yes)
			(layer "F.Fab")
			(effects
				(font
					(size 0.7874 0.5842)
					(thickness 0.1524)
				)
			)
		)
		(fp_text user "24"
			(at -17.54632 -32.276288 180)
			(unlocked yes)
			(layer "F.Fab")
			(effects
				(font
					(size 0.7874 0.5842)
					(thickness 0.1524)
				)
			)
		)
		(fp_text user "23"
			(at -18.388076 -31.335726 180)
			(unlocked yes)
			(layer "F.Fab")
			(effects
				(font
					(size 0.7874 0.5842)
					(thickness 0.1524)
				)
			)
		)
		(fp_text user "22"
			(at -19.263106 -32.276288 180)
			(unlocked yes)
			(layer "F.Fab")
			(effects
				(font
					(size 0.7874 0.5842)
					(thickness 0.1524)
				)
			)
		)
		(fp_text user "21"
			(at -20.105116 -31.335726 180)
			(unlocked yes)
			(layer "F.Fab")
			(effects
				(font
					(size 0.7874 0.5842)
					(thickness 0.1524)
				)
			)
		)
		(fp_text user "20"
			(at -20.980146 -32.276288 180)
			(unlocked yes)
			(layer "F.Fab")
			(effects
				(font
					(size 0.7874 0.5842)
					(thickness 0.1524)
				)
			)
		)
		(fp_text user "19"
			(at -21.822156 -31.335726 180)
			(unlocked yes)
			(layer "F.Fab")
			(effects
				(font
					(size 0.7874 0.5842)
					(thickness 0.1524)
				)
			)
		)
		(fp_text user "18"
			(at -22.697186 -32.276288 180)
			(unlocked yes)
			(layer "F.Fab")
			(effects
				(font
					(size 0.7874 0.5842)
					(thickness 0.1524)
				)
			)
		)
		(fp_text user "17"
			(at -23.539196 -31.335726 180)
			(unlocked yes)
			(layer "F.Fab")
			(effects
				(font
					(size 0.7874 0.5842)
					(thickness 0.1524)
				)
			)
		)
		(fp_text user "16"
			(at -24.414226 -32.276288 180)
			(unlocked yes)
			(layer "F.Fab")
			(effects
				(font
					(size 0.7874 0.5842)
					(thickness 0.1524)
				)
			)
		)
		(fp_text user "15"
			(at -25.255982 -31.335726 180)
			(unlocked yes)
			(layer "F.Fab")
			(effects
				(font
					(size 0.7874 0.5842)
					(thickness 0.1524)
				)
			)
		)
		(fp_text user "14"
			(at -26.131266 -32.276288 180)
			(unlocked yes)
			(layer "F.Fab")
			(effects
				(font
					(size 0.7874 0.5842)
					(thickness 0.1524)
				)
			)
		)
		(fp_text user "13"
			(at -26.973022 -31.335726 180)
			(unlocked yes)
			(layer "F.Fab")
			(effects
				(font
					(size 0.7874 0.5842)
					(thickness 0.1524)
				)
			)
		)
		(fp_text user "12"
			(at -27.848306 -32.276288 180)
			(unlocked yes)
			(layer "F.Fab")
			(effects
				(font
					(size 0.7874 0.5842)
					(thickness 0.1524)
				)
			)
		)
		(fp_text user "11"
			(at -28.690062 -31.335726 180)
			(unlocked yes)
			(layer "F.Fab")
			(effects
				(font
					(size 0.7874 0.5842)
					(thickness 0.1524)
				)
			)
		)
		(fp_text user "10"
			(at -29.565092 -32.276288 180)
			(unlocked yes)
			(layer "F.Fab")
			(effects
				(font
					(size 0.7874 0.5842)
					(thickness 0.1524)
				)
			)
		)
		(fp_text user "9"
			(at -30.407102 -31.335726 180)
			(unlocked yes)
			(layer "F.Fab")
			(effects
				(font
					(size 0.7874 0.5842)
					(thickness 0.1524)
				)
			)
		)
		(fp_text user "8"
			(at -31.282132 -32.276288 180)
			(unlocked yes)
			(layer "F.Fab")
			(effects
				(font
					(size 0.7874 0.5842)
					(thickness 0.1524)
				)
			)
		)
		(fp_text user "7"
			(at -32.124142 -31.335726 180)
			(unlocked yes)
			(layer "F.Fab")
			(effects
				(font
					(size 0.7874 0.5842)
					(thickness 0.1524)
				)
			)
		)
		(fp_text user "6"
			(at -32.999172 -32.276288 180)
			(unlocked yes)
			(layer "F.Fab")
			(effects
				(font
					(size 0.7874 0.5842)
					(thickness 0.1524)
				)
			)
		)
		(fp_text user "5"
			(at -33.841182 -31.335726 180)
			(unlocked yes)
			(layer "F.Fab")
			(effects
				(font
					(size 0.7874 0.5842)
					(thickness 0.1524)
				)
			)
		)
		(fp_text user "4"
			(at -34.716212 -32.276288 180)
			(unlocked yes)
			(layer "F.Fab")
			(effects
				(font
					(size 0.7874 0.5842)
					(thickness 0.1524)
				)
			)
		)
		(fp_text user "3"
			(at -35.558222 -31.335726 180)
			(unlocked yes)
			(layer "F.Fab")
			(effects
				(font
					(size 0.7874 0.5842)
					(thickness 0.1524)
				)
			)
		)
		(fp_text user "2"
			(at -36.433252 -32.276288 180)
			(unlocked yes)
			(layer "F.Fab")
			(effects
				(font
					(size 0.7874 0.5842)
					(thickness 0.1524)
				)
			)
		)
		(fp_text user "1"
			(at -37.275008 -31.335726 180)
			(unlocked yes)
			(layer "F.Fab")
			(effects
				(font
					(size 0.7874 0.5842)
					(thickness 0.1524)
				)
			)
		)
		(fp_text user "DW"
			(at -39.0652 23.349204 180)
			(unlocked yes)
			(layer "F.Fab")
			(effects
				(font
					(size 0.7874 0.5842)
					(thickness 0.1524)
				)
			)
		)
		(fp_text user "DU"
			(at -39.0652 22.358604 180)
			(unlocked yes)
			(layer "F.Fab")
			(effects
				(font
					(size 0.7874 0.5842)
					(thickness 0.1524)
				)
			)
		)
		(fp_text user "DR"
			(at -39.0652 21.368004 180)
			(unlocked yes)
			(layer "F.Fab")
			(effects
				(font
					(size 0.7874 0.5842)
					(thickness 0.1524)
				)
			)
		)
		(fp_text user "DN"
			(at -39.0652 20.377404 180)
			(unlocked yes)
			(layer "F.Fab")
			(effects
				(font
					(size 0.7874 0.5842)
					(thickness 0.1524)
				)
			)
		)
		(fp_text user "DL"
			(at -39.0652 19.386804 180)
			(unlocked yes)
			(layer "F.Fab")
			(effects
				(font
					(size 0.7874 0.5842)
					(thickness 0.1524)
				)
			)
		)
		(fp_text user "DJ"
			(at -39.0652 18.396204 180)
			(unlocked yes)
			(layer "F.Fab")
			(effects
				(font
					(size 0.7874 0.5842)
					(thickness 0.1524)
				)
			)
		)
		(fp_text user "DG"
			(at -39.0652 17.405604 180)
			(unlocked yes)
			(layer "F.Fab")
			(effects
				(font
					(size 0.7874 0.5842)
					(thickness 0.1524)
				)
			)
		)
		(fp_text user "DE"
			(at -39.0652 16.415004 180)
			(unlocked yes)
			(layer "F.Fab")
			(effects
				(font
					(size 0.7874 0.5842)
					(thickness 0.1524)
				)
			)
		)
		(fp_text user "DC"
			(at -39.0652 15.424404 180)
			(unlocked yes)
			(layer "F.Fab")
			(effects
				(font
					(size 0.7874 0.5842)
					(thickness 0.1524)
				)
			)
		)
		(fp_text user "DA"
			(at -39.0652 14.433804 180)
			(unlocked yes)
			(layer "F.Fab")
			(effects
				(font
					(size 0.7874 0.5842)
					(thickness 0.1524)
				)
			)
		)
		(fp_text user "CW"
			(at -39.0652 13.443204 180)
			(unlocked yes)
			(layer "F.Fab")
			(effects
				(font
					(size 0.7874 0.5842)
					(thickness 0.1524)
				)
			)
		)
		(fp_text user "CU"
			(at -39.0652 12.452604 180)
			(unlocked yes)
			(layer "F.Fab")
			(effects
				(font
					(size 0.7874 0.5842)
					(thickness 0.1524)
				)
			)
		)
		(fp_text user "CR"
			(at -39.0652 11.462004 180)
			(unlocked yes)
			(layer "F.Fab")
			(effects
				(font
					(size 0.7874 0.5842)
					(thickness 0.1524)
				)
			)
		)
		(fp_text user "CN"
			(at -39.0652 10.471404 180)
			(unlocked yes)
			(layer "F.Fab")
			(effects
				(font
					(size 0.7874 0.5842)
					(thickness 0.1524)
				)
			)
		)
		(fp_text user "CL"
			(at -39.0652 9.480804 180)
			(unlocked yes)
			(layer "F.Fab")
			(effects
				(font
					(size 0.7874 0.5842)
					(thickness 0.1524)
				)
			)
		)
		(fp_text user "CJ"
			(at -39.0652 8.490204 180)
			(unlocked yes)
			(layer "F.Fab")
			(effects
				(font
					(size 0.7874 0.5842)
					(thickness 0.1524)
				)
			)
		)
		(fp_text user "CG"
			(at -39.0652 7.499604 180)
			(unlocked yes)
			(layer "F.Fab")
			(effects
				(font
					(size 0.7874 0.5842)
					(thickness 0.1524)
				)
			)
		)
		(fp_text user "CE"
			(at -39.0652 6.509004 180)
			(unlocked yes)
			(layer "F.Fab")
			(effects
				(font
					(size 0.7874 0.5842)
					(thickness 0.1524)
				)
			)
		)
		(fp_text user "CC"
			(at -39.0652 5.518404 180)
			(unlocked yes)
			(layer "F.Fab")
			(effects
				(font
					(size 0.7874 0.5842)
					(thickness 0.1524)
				)
			)
		)
		(fp_text user "CA"
			(at -39.0652 4.527804 180)
			(unlocked yes)
			(layer "F.Fab")
			(effects
				(font
					(size 0.7874 0.5842)
					(thickness 0.1524)
				)
			)
		)
		(fp_text user "BW"
			(at -39.0652 3.537204 180)
			(unlocked yes)
			(layer "F.Fab")
			(effects
				(font
					(size 0.7874 0.5842)
					(thickness 0.1524)
				)
			)
		)
		(fp_text user "BU"
			(at -39.0652 2.546604 180)
			(unlocked yes)
			(layer "F.Fab")
			(effects
				(font
					(size 0.7874 0.5842)
					(thickness 0.1524)
				)
			)
		)
		(fp_text user "BR"
			(at -39.0652 1.556004 180)
			(unlocked yes)
			(layer "F.Fab")
			(effects
				(font
					(size 0.7874 0.5842)
					(thickness 0.1524)
				)
			)
		)
		(fp_text user "BN"
			(at -39.0652 0.565404 180)
			(unlocked yes)
			(layer "F.Fab")
			(effects
				(font
					(size 0.7874 0.5842)
					(thickness 0.1524)
				)
			)
		)
		(fp_text user "BL"
			(at -39.0652 -0.425196 180)
			(unlocked yes)
			(layer "F.Fab")
			(effects
				(font
					(size 0.7874 0.5842)
					(thickness 0.1524)
				)
			)
		)
		(fp_text user "BJ"
			(at -39.0652 -1.415796 180)
			(unlocked yes)
			(layer "F.Fab")
			(effects
				(font
					(size 0.7874 0.5842)
					(thickness 0.1524)
				)
			)
		)
		(fp_text user "BG"
			(at -39.0652 -2.406396 180)
			(unlocked yes)
			(layer "F.Fab")
			(effects
				(font
					(size 0.7874 0.5842)
					(thickness 0.1524)
				)
			)
		)
		(fp_text user "BE"
			(at -39.0652 -3.396996 180)
			(unlocked yes)
			(layer "F.Fab")
			(effects
				(font
					(size 0.7874 0.5842)
					(thickness 0.1524)
				)
			)
		)
		(fp_text user "BC"
			(at -39.0652 -4.387596 180)
			(unlocked yes)
			(layer "F.Fab")
			(effects
				(font
					(size 0.7874 0.5842)
					(thickness 0.1524)
				)
			)
		)
		(fp_text user "BA"
			(at -39.0652 -5.378196 180)
			(unlocked yes)
			(layer "F.Fab")
			(effects
				(font
					(size 0.7874 0.5842)
					(thickness 0.1524)
				)
			)
		)
		(fp_text user "AW"
			(at -39.0652 -6.368796 180)
			(unlocked yes)
			(layer "F.Fab")
			(effects
				(font
					(size 0.7874 0.5842)
					(thickness 0.1524)
				)
			)
		)
		(fp_text user "AU"
			(at -39.0652 -7.359396 180)
			(unlocked yes)
			(layer "F.Fab")
			(effects
				(font
					(size 0.7874 0.5842)
					(thickness 0.1524)
				)
			)
		)
		(fp_text user "AR"
			(at -39.0652 -8.349996 180)
			(unlocked yes)
			(layer "F.Fab")
			(effects
				(font
					(size 0.7874 0.5842)
					(thickness 0.1524)
				)
			)
		)
		(fp_text user "AN"
			(at -39.0652 -9.340596 180)
			(unlocked yes)
			(layer "F.Fab")
			(effects
				(font
					(size 0.7874 0.5842)
					(thickness 0.1524)
				)
			)
		)
		(fp_text user "AL"
			(at -39.0652 -10.331196 180)
			(unlocked yes)
			(layer "F.Fab")
			(effects
				(font
					(size 0.7874 0.5842)
					(thickness 0.1524)
				)
			)
		)
		(fp_text user "AJ"
			(at -39.0652 -11.321796 180)
			(unlocked yes)
			(layer "F.Fab")
			(effects
				(font
					(size 0.7874 0.5842)
					(thickness 0.1524)
				)
			)
		)
		(fp_text user "AG"
			(at -39.0652 -12.312396 180)
			(unlocked yes)
			(layer "F.Fab")
			(effects
				(font
					(size 0.7874 0.5842)
					(thickness 0.1524)
				)
			)
		)
		(fp_text user "AE"
			(at -39.0652 -13.302996 180)
			(unlocked yes)
			(layer "F.Fab")
			(effects
				(font
					(size 0.7874 0.5842)
					(thickness 0.1524)
				)
			)
		)
		(fp_text user "AC"
			(at -39.0652 -14.293596 180)
			(unlocked yes)
			(layer "F.Fab")
			(effects
				(font
					(size 0.7874 0.5842)
					(thickness 0.1524)
				)
			)
		)
		(fp_text user "AA"
			(at -39.0652 -15.284196 180)
			(unlocked yes)
			(layer "F.Fab")
			(effects
				(font
					(size 0.7874 0.5842)
					(thickness 0.1524)
				)
			)
		)
		(fp_text user "W"
			(at -39.0652 -16.274796 180)
			(unlocked yes)
			(layer "F.Fab")
			(effects
				(font
					(size 0.7874 0.5842)
					(thickness 0.1524)
				)
			)
		)
		(fp_text user "U"
			(at -39.0652 -17.265396 180)
			(unlocked yes)
			(layer "F.Fab")
			(effects
				(font
					(size 0.7874 0.5842)
					(thickness 0.1524)
				)
			)
		)
		(fp_text user "R"
			(at -39.0652 -18.255996 180)
			(unlocked yes)
			(layer "F.Fab")
			(effects
				(font
					(size 0.7874 0.5842)
					(thickness 0.1524)
				)
			)
		)
		(fp_text user "N"
			(at -39.0652 -19.246596 180)
			(unlocked yes)
			(layer "F.Fab")
			(effects
				(font
					(size 0.7874 0.5842)
					(thickness 0.1524)
				)
			)
		)
		(fp_text user "L"
			(at -39.0652 -20.237196 180)
			(unlocked yes)
			(layer "F.Fab")
			(effects
				(font
					(size 0.7874 0.5842)
					(thickness 0.1524)
				)
			)
		)
		(fp_text user "J"
			(at -39.0652 -21.227796 180)
			(unlocked yes)
			(layer "F.Fab")
			(effects
				(font
					(size 0.7874 0.5842)
					(thickness 0.1524)
				)
			)
		)
		(fp_text user "G"
			(at -39.0652 -22.218396 180)
			(unlocked yes)
			(layer "F.Fab")
			(effects
				(font
					(size 0.7874 0.5842)
					(thickness 0.1524)
				)
			)
		)
		(fp_text user "E"
			(at -39.0652 -23.208996 180)
			(unlocked yes)
			(layer "F.Fab")
			(effects
				(font
					(size 0.7874 0.5842)
					(thickness 0.1524)
				)
			)
		)
		(fp_text user "C"
			(at -39.0652 -24.199596 180)
			(unlocked yes)
			(layer "F.Fab")
			(effects
				(font
					(size 0.7874 0.5842)
					(thickness 0.1524)
				)
			)
		)
		(fp_text user "A"
			(at -39.0652 -25.190196 180)
			(unlocked yes)
			(layer "F.Fab")
			(effects
				(font
					(size 0.7874 0.5842)
					(thickness 0.1524)
				)
			)
		)
		(fp_text user "Y"
			(at -39.815008 -15.779496 180)
			(unlocked yes)
			(layer "F.Fab")
			(effects
				(font
					(size 0.7874 0.5842)
					(thickness 0.1524)
				)
			)
		)
		(fp_text user "V"
			(at -39.815008 -16.770096 180)
			(unlocked yes)
			(layer "F.Fab")
			(effects
				(font
					(size 0.7874 0.5842)
					(thickness 0.1524)
				)
			)
		)
		(fp_text user "T"
			(at -39.815008 -17.760696 180)
			(unlocked yes)
			(layer "F.Fab")
			(effects
				(font
					(size 0.7874 0.5842)
					(thickness 0.1524)
				)
			)
		)
		(fp_text user "P"
			(at -39.815008 -18.751296 180)
			(unlocked yes)
			(layer "F.Fab")
			(effects
				(font
					(size 0.7874 0.5842)
					(thickness 0.1524)
				)
			)
		)
		(fp_text user "M"
			(at -39.815008 -19.741896 180)
			(unlocked yes)
			(layer "F.Fab")
			(effects
				(font
					(size 0.7874 0.5842)
					(thickness 0.1524)
				)
			)
		)
		(fp_text user "K"
			(at -39.815008 -20.732496 180)
			(unlocked yes)
			(layer "F.Fab")
			(effects
				(font
					(size 0.7874 0.5842)
					(thickness 0.1524)
				)
			)
		)
		(fp_text user "H"
			(at -39.815008 -21.723096 180)
			(unlocked yes)
			(layer "F.Fab")
			(effects
				(font
					(size 0.7874 0.5842)
					(thickness 0.1524)
				)
			)
		)
		(fp_text user "F"
			(at -39.815008 -22.713696 180)
			(unlocked yes)
			(layer "F.Fab")
			(effects
				(font
					(size 0.7874 0.5842)
					(thickness 0.1524)
				)
			)
		)
		(fp_text user "D"
			(at -39.815008 -23.704296 180)
			(unlocked yes)
			(layer "F.Fab")
			(effects
				(font
					(size 0.7874 0.5842)
					(thickness 0.1524)
				)
			)
		)
		(fp_text user "B"
			(at -39.815008 -24.694896 180)
			(unlocked yes)
			(layer "F.Fab")
			(effects
				(font
					(size 0.7874 0.5842)
					(thickness 0.1524)
				)
			)
		)
		(fp_text user "DY"
			(at -40.462708 23.895558 180)
			(unlocked yes)
			(layer "F.Fab")
			(effects
				(font
					(size 0.7874 0.5842)
					(thickness 0.1524)
				)
			)
		)
		(fp_text user "DV"
			(at -40.462708 22.904958 180)
			(unlocked yes)
			(layer "F.Fab")
			(effects
				(font
					(size 0.7874 0.5842)
					(thickness 0.1524)
				)
			)
		)
		(fp_text user "DT"
			(at -40.462708 21.914358 180)
			(unlocked yes)
			(layer "F.Fab")
			(effects
				(font
					(size 0.7874 0.5842)
					(thickness 0.1524)
				)
			)
		)
		(fp_text user "DP"
			(at -40.462708 20.923758 180)
			(unlocked yes)
			(layer "F.Fab")
			(effects
				(font
					(size 0.7874 0.5842)
					(thickness 0.1524)
				)
			)
		)
		(fp_text user "DM"
			(at -40.462708 19.933158 180)
			(unlocked yes)
			(layer "F.Fab")
			(effects
				(font
					(size 0.7874 0.5842)
					(thickness 0.1524)
				)
			)
		)
		(fp_text user "DK"
			(at -40.462708 18.942558 180)
			(unlocked yes)
			(layer "F.Fab")
			(effects
				(font
					(size 0.7874 0.5842)
					(thickness 0.1524)
				)
			)
		)
		(fp_text user "DH"
			(at -40.462708 17.951958 180)
			(unlocked yes)
			(layer "F.Fab")
			(effects
				(font
					(size 0.7874 0.5842)
					(thickness 0.1524)
				)
			)
		)
		(fp_text user "DF"
			(at -40.462708 16.961358 180)
			(unlocked yes)
			(layer "F.Fab")
			(effects
				(font
					(size 0.7874 0.5842)
					(thickness 0.1524)
				)
			)
		)
		(fp_text user "DD"
			(at -40.462708 15.970758 180)
			(unlocked yes)
			(layer "F.Fab")
			(effects
				(font
					(size 0.7874 0.5842)
					(thickness 0.1524)
				)
			)
		)
		(fp_text user "DB"
			(at -40.462708 14.980158 180)
			(unlocked yes)
			(layer "F.Fab")
			(effects
				(font
					(size 0.7874 0.5842)
					(thickness 0.1524)
				)
			)
		)
		(fp_text user "CY"
			(at -40.462708 13.989558 180)
			(unlocked yes)
			(layer "F.Fab")
			(effects
				(font
					(size 0.7874 0.5842)
					(thickness 0.1524)
				)
			)
		)
		(fp_text user "CV"
			(at -40.462708 12.998958 180)
			(unlocked yes)
			(layer "F.Fab")
			(effects
				(font
					(size 0.7874 0.5842)
					(thickness 0.1524)
				)
			)
		)
		(fp_text user "CT"
			(at -40.462708 12.008358 180)
			(unlocked yes)
			(layer "F.Fab")
			(effects
				(font
					(size 0.7874 0.5842)
					(thickness 0.1524)
				)
			)
		)
		(fp_text user "CP"
			(at -40.462708 11.017758 180)
			(unlocked yes)
			(layer "F.Fab")
			(effects
				(font
					(size 0.7874 0.5842)
					(thickness 0.1524)
				)
			)
		)
		(fp_text user "CM"
			(at -40.462708 10.027158 180)
			(unlocked yes)
			(layer "F.Fab")
			(effects
				(font
					(size 0.7874 0.5842)
					(thickness 0.1524)
				)
			)
		)
		(fp_text user "CK"
			(at -40.462708 9.036558 180)
			(unlocked yes)
			(layer "F.Fab")
			(effects
				(font
					(size 0.7874 0.5842)
					(thickness 0.1524)
				)
			)
		)
		(fp_text user "CH"
			(at -40.462708 8.045958 180)
			(unlocked yes)
			(layer "F.Fab")
			(effects
				(font
					(size 0.7874 0.5842)
					(thickness 0.1524)
				)
			)
		)
		(fp_text user "CF"
			(at -40.462708 7.055358 180)
			(unlocked yes)
			(layer "F.Fab")
			(effects
				(font
					(size 0.7874 0.5842)
					(thickness 0.1524)
				)
			)
		)
		(fp_text user "CD"
			(at -40.462708 6.064758 180)
			(unlocked yes)
			(layer "F.Fab")
			(effects
				(font
					(size 0.7874 0.5842)
					(thickness 0.1524)
				)
			)
		)
		(fp_text user "CB"
			(at -40.462708 5.074158 180)
			(unlocked yes)
			(layer "F.Fab")
			(effects
				(font
					(size 0.7874 0.5842)
					(thickness 0.1524)
				)
			)
		)
		(fp_text user "BY"
			(at -40.462708 4.083558 180)
			(unlocked yes)
			(layer "F.Fab")
			(effects
				(font
					(size 0.7874 0.5842)
					(thickness 0.1524)
				)
			)
		)
		(fp_text user "BV"
			(at -40.462708 3.092958 180)
			(unlocked yes)
			(layer "F.Fab")
			(effects
				(font
					(size 0.7874 0.5842)
					(thickness 0.1524)
				)
			)
		)
		(fp_text user "BT"
			(at -40.462708 2.102358 180)
			(unlocked yes)
			(layer "F.Fab")
			(effects
				(font
					(size 0.7874 0.5842)
					(thickness 0.1524)
				)
			)
		)
		(fp_text user "BP"
			(at -40.462708 1.111758 180)
			(unlocked yes)
			(layer "F.Fab")
			(effects
				(font
					(size 0.7874 0.5842)
					(thickness 0.1524)
				)
			)
		)
		(fp_text user "BM"
			(at -40.462708 0.121158 180)
			(unlocked yes)
			(layer "F.Fab")
			(effects
				(font
					(size 0.7874 0.5842)
					(thickness 0.1524)
				)
			)
		)
		(fp_text user "BK"
			(at -40.462708 -0.869442 180)
			(unlocked yes)
			(layer "F.Fab")
			(effects
				(font
					(size 0.7874 0.5842)
					(thickness 0.1524)
				)
			)
		)
		(fp_text user "BH"
			(at -40.462708 -1.860042 180)
			(unlocked yes)
			(layer "F.Fab")
			(effects
				(font
					(size 0.7874 0.5842)
					(thickness 0.1524)
				)
			)
		)
		(fp_text user "BF"
			(at -40.462708 -2.850642 180)
			(unlocked yes)
			(layer "F.Fab")
			(effects
				(font
					(size 0.7874 0.5842)
					(thickness 0.1524)
				)
			)
		)
		(fp_text user "BD"
			(at -40.462708 -3.841242 180)
			(unlocked yes)
			(layer "F.Fab")
			(effects
				(font
					(size 0.7874 0.5842)
					(thickness 0.1524)
				)
			)
		)
		(fp_text user "BB"
			(at -40.462708 -4.831842 180)
			(unlocked yes)
			(layer "F.Fab")
			(effects
				(font
					(size 0.7874 0.5842)
					(thickness 0.1524)
				)
			)
		)
		(fp_text user "AY"
			(at -40.462708 -5.822442 180)
			(unlocked yes)
			(layer "F.Fab")
			(effects
				(font
					(size 0.7874 0.5842)
					(thickness 0.1524)
				)
			)
		)
		(fp_text user "AV"
			(at -40.462708 -6.813042 180)
			(unlocked yes)
			(layer "F.Fab")
			(effects
				(font
					(size 0.7874 0.5842)
					(thickness 0.1524)
				)
			)
		)
		(fp_text user "AT"
			(at -40.462708 -7.803642 180)
			(unlocked yes)
			(layer "F.Fab")
			(effects
				(font
					(size 0.7874 0.5842)
					(thickness 0.1524)
				)
			)
		)
		(fp_text user "AP"
			(at -40.462708 -8.794242 180)
			(unlocked yes)
			(layer "F.Fab")
			(effects
				(font
					(size 0.7874 0.5842)
					(thickness 0.1524)
				)
			)
		)
		(fp_text user "AM"
			(at -40.462708 -9.784842 180)
			(unlocked yes)
			(layer "F.Fab")
			(effects
				(font
					(size 0.7874 0.5842)
					(thickness 0.1524)
				)
			)
		)
		(fp_text user "AK"
			(at -40.462708 -10.775442 180)
			(unlocked yes)
			(layer "F.Fab")
			(effects
				(font
					(size 0.7874 0.5842)
					(thickness 0.1524)
				)
			)
		)
		(fp_text user "AH"
			(at -40.462708 -11.766042 180)
			(unlocked yes)
			(layer "F.Fab")
			(effects
				(font
					(size 0.7874 0.5842)
					(thickness 0.1524)
				)
			)
		)
		(fp_text user "AF"
			(at -40.462708 -12.756642 180)
			(unlocked yes)
			(layer "F.Fab")
			(effects
				(font
					(size 0.7874 0.5842)
					(thickness 0.1524)
				)
			)
		)
		(fp_text user "AD"
			(at -40.462708 -13.747242 180)
			(unlocked yes)
			(layer "F.Fab")
			(effects
				(font
					(size 0.7874 0.5842)
					(thickness 0.1524)
				)
			)
		)
		(fp_text user "AB"
			(at -40.462708 -14.737842 180)
			(unlocked yes)
			(layer "F.Fab")
			(effects
				(font
					(size 0.7874 0.5842)
					(thickness 0.1524)
				)
			)
		)
		(pad "A4" smd custom
			(at -34.675064 -25.103074 45)
			(size 0.10795 0.10795)
			(layers "F.Cu" "F.Mask" "F.Paste")
			(net "TP_CPU1_RSVD_304")
			(options
				(clearance outline)
				(anchor circle)
			)
			(primitives
				(gr_poly
					(pts
						(arc
							(start 0.2159 -0.0381)
							(mid 0 -0.254)
							(end -0.2159 -0.0381)
						)
						(arc
							(start -0.2159 0.0381)
							(mid 0 0.254)
							(end 0.2159 0.0381)
						)
					)
					(width 0)
					(fill yes)
				)
			)
		)
		(pad "A6" smd custom
			(at -32.958024 -25.103074 45)
			(size 0.10795 0.10795)
			(layers "F.Cu" "F.Mask" "F.Paste")
			(net "TP_CPU1_RSVD_303")
			(options
				(clearance outline)
				(anchor circle)
			)
			(primitives
				(gr_poly
					(pts
						(arc
							(start 0.2159 -0.0381)
							(mid 0 -0.254)
							(end -0.2159 -0.0381)
						)
						(arc
							(start -0.2159 0.0381)
							(mid 0 0.254)
							(end 0.2159 0.0381)
						)
					)
					(width 0)
					(fill yes)
				)
			)
		)
		(pad "A8" smd custom
			(at -31.240984 -25.103074)
			(size 0.10795 0.10795)
			(layers "F.Cu" "F.Mask" "F.Paste")
			(net "PVPP_GHJ")
			(options
				(clearance outline)
				(anchor circle)
			)
			(primitives
				(gr_poly
					(pts
						(arc
							(start 0.2159 -0.0381)
							(mid 0 -0.254)
							(end -0.2159 -0.0381)
						)
						(arc
							(start -0.2159 0.0381)
							(mid 0 0.254)
							(end 0.2159 0.0381)
						)
					)
					(width 0)
					(fill yes)
				)
			)
		)
		(pad "A10" smd custom
			(at -29.523944 -25.103074)
			(size 0.10795 0.10795)
			(layers "F.Cu" "F.Mask" "F.Paste")
			(net "PVPP_GHJ")
			(options
				(clearance outline)
				(anchor circle)
			)
			(primitives
				(gr_poly
					(pts
						(arc
							(start 0.2159 -0.0381)
							(mid 0 -0.254)
							(end -0.2159 -0.0381)
						)
						(arc
							(start -0.2159 0.0381)
							(mid 0 0.254)
							(end 0.2159 0.0381)
						)
					)
					(width 0)
					(fill yes)
				)
			)
		)
		(pad "A12" smd custom
			(at -27.806904 -25.103074)
			(size 0.10795 0.10795)
			(layers "F.Cu" "F.Mask" "F.Paste")
			(net "PVPP_GHJ")
			(options
				(clearance outline)
				(anchor circle)
			)
			(primitives
				(gr_poly
					(pts
						(arc
							(start 0.2159 -0.0381)
							(mid 0 -0.254)
							(end -0.2159 -0.0381)
						)
						(arc
							(start -0.2159 0.0381)
							(mid 0 0.254)
							(end 0.2159 0.0381)
						)
					)
					(width 0)
					(fill yes)
				)
			)
		)
		(pad "A14" smd custom
			(at -26.090118 -25.103074)
			(size 0.10795 0.10795)
			(layers "F.Cu" "F.Mask" "F.Paste")
			(net "P1V8_MCP_CPU1")
			(options
				(clearance outline)
				(anchor circle)
			)
			(primitives
				(gr_poly
					(pts
						(arc
							(start 0.2159 -0.0381)
							(mid 0 -0.254)
							(end -0.2159 -0.0381)
						)
						(arc
							(start -0.2159 0.0381)
							(mid 0 0.254)
							(end 0.2159 0.0381)
						)
					)
					(width 0)
					(fill yes)
				)
			)
		)
		(pad "A16" smd custom
			(at -24.373078 -25.103074)
			(size 0.10795 0.10795)
			(layers "F.Cu" "F.Mask" "F.Paste")
			(net "P1V8_MCP_CPU1")
			(options
				(clearance outline)
				(anchor circle)
			)
			(primitives
				(gr_poly
					(pts
						(arc
							(start 0.2159 -0.0381)
							(mid 0 -0.254)
							(end -0.2159 -0.0381)
						)
						(arc
							(start -0.2159 0.0381)
							(mid 0 0.254)
							(end 0.2159 0.0381)
						)
					)
					(width 0)
					(fill yes)
				)
			)
		)
		(pad "A24" smd custom
			(at -17.504918 -25.103074)
			(size 0.10795 0.10795)
			(layers "F.Cu" "F.Mask" "F.Paste")
			(net "TP_CPU1_RSVD_300")
			(options
				(clearance outline)
				(anchor circle)
			)
			(primitives
				(gr_poly
					(pts
						(arc
							(start 0.2159 -0.0381)
							(mid 0 -0.254)
							(end -0.2159 -0.0381)
						)
						(arc
							(start -0.2159 0.0381)
							(mid 0 0.254)
							(end 0.2159 0.0381)
						)
					)
					(width 0)
					(fill yes)
				)
			)
		)
		(pad "A26" smd custom
			(at -15.787878 -25.103074)
			(size 0.10795 0.10795)
			(layers "F.Cu" "F.Mask" "F.Paste")
			(net "GND")
			(options
				(clearance outline)
				(anchor circle)
			)
			(primitives
				(gr_poly
					(pts
						(arc
							(start 0.2159 -0.0381)
							(mid 0 -0.254)
							(end -0.2159 -0.0381)
						)
						(arc
							(start -0.2159 0.0381)
							(mid 0 0.254)
							(end 0.2159 0.0381)
						)
					)
					(width 0)
					(fill yes)
				)
			)
		)
		(pad "A28" smd custom
			(at -14.071092 -25.103074)
			(size 0.10795 0.10795)
			(layers "F.Cu" "F.Mask" "F.Paste")
			(net "M_H_DQS_DN<15>")
			(options
				(clearance outline)
				(anchor circle)
			)
			(primitives
				(gr_poly
					(pts
						(arc
							(start 0.2159 -0.0381)
							(mid 0 -0.254)
							(end -0.2159 -0.0381)
						)
						(arc
							(start -0.2159 0.0381)
							(mid 0 0.254)
							(end 0.2159 0.0381)
						)
					)
					(width 0)
					(fill yes)
				)
			)
		)
		(pad "A30" smd custom
			(at -12.354052 -25.103074)
			(size 0.10795 0.10795)
			(layers "F.Cu" "F.Mask" "F.Paste")
			(net "GND")
			(options
				(clearance outline)
				(anchor circle)
			)
			(primitives
				(gr_poly
					(pts
						(arc
							(start 0.2159 -0.0381)
							(mid 0 -0.254)
							(end -0.2159 -0.0381)
						)
						(arc
							(start -0.2159 0.0381)
							(mid 0 0.254)
							(end 0.2159 0.0381)
						)
					)
					(width 0)
					(fill yes)
				)
			)
		)
		(pad "A32" smd custom
			(at -10.637012 -25.103074)
			(size 0.10795 0.10795)
			(layers "F.Cu" "F.Mask" "F.Paste")
			(net "GND")
			(options
				(clearance outline)
				(anchor circle)
			)
			(primitives
				(gr_poly
					(pts
						(arc
							(start 0.2159 -0.0381)
							(mid 0 -0.254)
							(end -0.2159 -0.0381)
						)
						(arc
							(start -0.2159 0.0381)
							(mid 0 0.254)
							(end 0.2159 0.0381)
						)
					)
					(width 0)
					(fill yes)
				)
			)
		)
		(pad "A34" smd custom
			(at -8.919972 -25.103074)
			(size 0.10795 0.10795)
			(layers "F.Cu" "F.Mask" "F.Paste")
			(net "M_H_DQS_DN<14>")
			(options
				(clearance outline)
				(anchor circle)
			)
			(primitives
				(gr_poly
					(pts
						(arc
							(start 0.2159 -0.0381)
							(mid 0 -0.254)
							(end -0.2159 -0.0381)
						)
						(arc
							(start -0.2159 0.0381)
							(mid 0 0.254)
							(end 0.2159 0.0381)
						)
					)
					(width 0)
					(fill yes)
				)
			)
		)
		(pad "A36" smd custom
			(at -7.202932 -25.103074)
			(size 0.10795 0.10795)
			(layers "F.Cu" "F.Mask" "F.Paste")
			(net "GND")
			(options
				(clearance outline)
				(anchor circle)
			)
			(primitives
				(gr_poly
					(pts
						(arc
							(start 0.2159 -0.0381)
							(mid 0 -0.254)
							(end -0.2159 -0.0381)
						)
						(arc
							(start -0.2159 0.0381)
							(mid 0 0.254)
							(end 0.2159 0.0381)
						)
					)
					(width 0)
					(fill yes)
				)
			)
		)
		(pad "A38" smd custom
			(at -5.485892 -25.103074)
			(size 0.10795 0.10795)
			(layers "F.Cu" "F.Mask" "F.Paste")
			(net "GND")
			(options
				(clearance outline)
				(anchor circle)
			)
			(primitives
				(gr_poly
					(pts
						(arc
							(start 0.2159 -0.0381)
							(mid 0 -0.254)
							(end -0.2159 -0.0381)
						)
						(arc
							(start -0.2159 0.0381)
							(mid 0 0.254)
							(end 0.2159 0.0381)
						)
					)
					(width 0)
					(fill yes)
				)
			)
		)
		(pad "A40" smd custom
			(at -3.769106 -25.103074)
			(size 0.10795 0.10795)
			(layers "F.Cu" "F.Mask" "F.Paste")
			(net "M_G_DQS_DN<13>")
			(options
				(clearance outline)
				(anchor circle)
			)
			(primitives
				(gr_poly
					(pts
						(arc
							(start 0.2159 -0.0381)
							(mid 0 -0.254)
							(end -0.2159 -0.0381)
						)
						(arc
							(start -0.2159 0.0381)
							(mid 0 0.254)
							(end 0.2159 0.0381)
						)
					)
					(width 0)
					(fill yes)
				)
			)
		)
		(pad "A42" smd custom
			(at -2.052066 -25.103074 315)
			(size 0.10795 0.10795)
			(layers "F.Cu" "F.Mask" "F.Paste")
			(net "GND")
			(options
				(clearance outline)
				(anchor circle)
			)
			(primitives
				(gr_poly
					(pts
						(arc
							(start 0.2159 -0.0381)
							(mid 0 -0.254)
							(end -0.2159 -0.0381)
						)
						(arc
							(start -0.2159 0.0381)
							(mid 0 0.254)
							(end 0.2159 0.0381)
						)
					)
					(width 0)
					(fill yes)
				)
			)
		)
		(pad "AA2" smd circle
			(at -36.392104 -15.197074)
			(size 0.4318 0.4318)
			(layers "F.Cu" "F.Mask" "F.Paste")
			(net "UPI_CPU1_CPU0_P0P0_DP<4>")
		)
		(pad "AA4" smd circle
			(at -34.675064 -15.197074)
			(size 0.4318 0.4318)
			(layers "F.Cu" "F.Mask" "F.Paste")
			(net "GND")
		)
		(pad "AA6" smd circle
			(at -32.958024 -15.197074)
			(size 0.4318 0.4318)
			(layers "F.Cu" "F.Mask" "F.Paste")
			(net "UPI_CPU0_CPU1_P0P0_DP<2>")
		)
		(pad "AA8" smd circle
			(at -31.240984 -15.197074)
			(size 0.4318 0.4318)
			(layers "F.Cu" "F.Mask" "F.Paste")
			(net "UPI_CPU0_CPU1_P0P0_DN<1>")
		)
		(pad "AA10" smd circle
			(at -29.523944 -15.197074)
			(size 0.4318 0.4318)
			(layers "F.Cu" "F.Mask" "F.Paste")
			(net "PVCCIO_CPU1")
		)
		(pad "AA12" smd circle
			(at -27.806904 -15.197074)
			(size 0.4318 0.4318)
			(layers "F.Cu" "F.Mask" "F.Paste")
			(net "TP_XDP_CPU1_OBSDATA_B2_MBP4_N")
		)
		(pad "AA14" smd circle
			(at -26.090118 -15.197074)
			(size 0.4318 0.4318)
			(layers "F.Cu" "F.Mask" "F.Paste")
			(net "XDP_CPU_TCK0")
		)
		(pad "AA16" smd circle
			(at -24.373078 -15.197074)
			(size 0.4318 0.4318)
			(layers "F.Cu" "F.Mask" "F.Paste")
			(net "GND")
		)
		(pad "AA18" smd circle
			(at -22.656038 -15.197074)
			(size 0.4318 0.4318)
			(layers "F.Cu" "F.Mask" "F.Paste")
			(net "GND")
		)
		(pad "AA20" smd circle
			(at -20.938998 -15.197074)
			(size 0.4318 0.4318)
			(layers "F.Cu" "F.Mask" "F.Paste")
			(net "UPI_CPU0_CPU1_P1P1_DN<19>")
		)
		(pad "AA22" smd circle
			(at -19.221958 -15.197074)
			(size 0.4318 0.4318)
			(layers "F.Cu" "F.Mask" "F.Paste")
			(net "GND")
		)
		(pad "AA24" smd circle
			(at -17.504918 -15.197074)
			(size 0.4318 0.4318)
			(layers "F.Cu" "F.Mask" "F.Paste")
			(net "GND")
		)
		(pad "AA26" smd circle
			(at -15.787878 -15.197074)
			(size 0.4318 0.4318)
			(layers "F.Cu" "F.Mask" "F.Paste")
			(net "M_H_DQ<63>")
		)
		(pad "AA28" smd circle
			(at -14.071092 -15.197074)
			(size 0.4318 0.4318)
			(layers "F.Cu" "F.Mask" "F.Paste")
			(net "M_H_DQ<57>")
		)
		(pad "AA30" smd circle
			(at -12.354052 -15.197074)
			(size 0.4318 0.4318)
			(layers "F.Cu" "F.Mask" "F.Paste")
			(net "GND")
		)
		(pad "AA32" smd circle
			(at -10.637012 -15.197074)
			(size 0.4318 0.4318)
			(layers "F.Cu" "F.Mask" "F.Paste")
			(net "M_J_DQ<47>")
		)
		(pad "AA34" smd circle
			(at -8.919972 -15.197074)
			(size 0.4318 0.4318)
			(layers "F.Cu" "F.Mask" "F.Paste")
			(net "M_J_DQ<41>")
		)
		(pad "AA36" smd circle
			(at -7.202932 -15.197074)
			(size 0.4318 0.4318)
			(layers "F.Cu" "F.Mask" "F.Paste")
			(net "GND")
		)
		(pad "AA38" smd circle
			(at -5.485892 -15.197074)
			(size 0.4318 0.4318)
			(layers "F.Cu" "F.Mask" "F.Paste")
			(net "M_J_DQ<39>")
		)
		(pad "AA40" smd circle
			(at -3.769106 -15.197074)
			(size 0.4318 0.4318)
			(layers "F.Cu" "F.Mask" "F.Paste")
			(net "M_J_DQ<33>")
		)
		(pad "AA42" smd circle
			(at -2.052066 -15.197074)
			(size 0.4318 0.4318)
			(layers "F.Cu" "F.Mask" "F.Paste")
			(net "GND")
		)
		(pad "AA46" smd circle
			(at 2.910586 -16.997172)
			(size 0.4318 0.4318)
			(layers "F.Cu" "F.Mask" "F.Paste")
			(net "M_J_CS_N<3>")
		)
		(pad "AA48" smd circle
			(at 4.627626 -16.997172)
			(size 0.4318 0.4318)
			(layers "F.Cu" "F.Mask" "F.Paste")
			(net "M_J_ODT<1>")
		)
		(pad "AA50" smd circle
			(at 6.344412 -16.997172)
			(size 0.4318 0.4318)
			(layers "F.Cu" "F.Mask" "F.Paste")
			(net "M_J_ODT<0>")
		)
		(pad "AA52" smd circle
			(at 8.061452 -16.997172)
			(size 0.4318 0.4318)
			(layers "F.Cu" "F.Mask" "F.Paste")
			(net "M_J_MA<16>")
		)
		(pad "AA54" smd circle
			(at 9.778492 -16.997172)
			(size 0.4318 0.4318)
			(layers "F.Cu" "F.Mask" "F.Paste")
			(net "M_J_CLK_DN<0>")
		)
		(pad "AA56" smd circle
			(at 11.495532 -16.997172)
			(size 0.4318 0.4318)
			(layers "F.Cu" "F.Mask" "F.Paste")
			(net "M_J_CLK_DN<2>")
		)
		(pad "AA58" smd circle
			(at 13.212572 -16.997172)
			(size 0.4318 0.4318)
			(layers "F.Cu" "F.Mask" "F.Paste")
			(net "M_J_MA<4>")
		)
		(pad "AA60" smd circle
			(at 14.929612 -16.997172)
			(size 0.4318 0.4318)
			(layers "F.Cu" "F.Mask" "F.Paste")
			(net "M_J_BG<0>")
		)
		(pad "AA62" smd circle
			(at 16.646398 -16.997172)
			(size 0.4318 0.4318)
			(layers "F.Cu" "F.Mask" "F.Paste")
			(net "M_J_CKE<0>")
		)
		(pad "AA64" smd circle
			(at 18.363438 -16.997172)
			(size 0.4318 0.4318)
			(layers "F.Cu" "F.Mask" "F.Paste")
			(net "GND")
		)
		(pad "AA66" smd circle
			(at 20.080478 -16.997172)
			(size 0.4318 0.4318)
			(layers "F.Cu" "F.Mask" "F.Paste")
			(net "GND")
		)
		(pad "AA68" smd circle
			(at 21.797518 -16.997172)
			(size 0.4318 0.4318)
			(layers "F.Cu" "F.Mask" "F.Paste")
			(net "GND")
		)
		(pad "AA70" smd circle
			(at 23.514558 -16.997172)
			(size 0.4318 0.4318)
			(layers "F.Cu" "F.Mask" "F.Paste")
			(net "M_J_DQ<17>")
		)
		(pad "AA72" smd circle
			(at 25.231598 -16.997172)
			(size 0.4318 0.4318)
			(layers "F.Cu" "F.Mask" "F.Paste")
			(net "M_J_DQ<20>")
		)
		(pad "AA74" smd circle
			(at 26.948384 -16.997172)
			(size 0.4318 0.4318)
			(layers "F.Cu" "F.Mask" "F.Paste")
			(net "M_J_DQS_DN<1>")
		)
		(pad "AA76" smd circle
			(at 28.665424 -16.997172)
			(size 0.4318 0.4318)
			(layers "F.Cu" "F.Mask" "F.Paste")
			(net "GND")
		)
		(pad "AA78" smd circle
			(at 30.382464 -16.997172)
			(size 0.4318 0.4318)
			(layers "F.Cu" "F.Mask" "F.Paste")
			(net "GND")
		)
		(pad "AA80" smd circle
			(at 32.099504 -16.997172)
			(size 0.4318 0.4318)
			(layers "F.Cu" "F.Mask" "F.Paste")
			(net "GND")
		)
		(pad "AA82" smd circle
			(at 33.816544 -16.997172)
			(size 0.4318 0.4318)
			(layers "F.Cu" "F.Mask" "F.Paste")
			(net "GND")
		)
		(pad "AA84" smd circle
			(at 35.533584 -16.997172)
			(size 0.4318 0.4318)
			(layers "F.Cu" "F.Mask" "F.Paste")
			(net "M_G_DQ<13>")
		)
		(pad "AA86" smd custom
			(at 37.250624 -16.997172 270)
			(size 0.10795 0.10795)
			(layers "F.Cu" "F.Mask" "F.Paste")
			(net "M_G_DQ<12>")
			(options
				(clearance outline)
				(anchor circle)
			)
			(primitives
				(gr_poly
					(pts
						(arc
							(start 0.2159 -0.0381)
							(mid 0 -0.254)
							(end -0.2159 -0.0381)
						)
						(arc
							(start -0.2159 0.0381)
							(mid 0 0.254)
							(end 0.2159 0.0381)
						)
					)
					(width 0)
					(fill yes)
				)
			)
		)
		(pad "AB1" smd custom
			(at -37.250624 -14.702028 90)
			(size 0.10795 0.10795)
			(layers "F.Cu" "F.Mask" "F.Paste")
			(net "GND")
			(options
				(clearance outline)
				(anchor circle)
			)
			(primitives
				(gr_poly
					(pts
						(arc
							(start 0.2159 -0.0381)
							(mid 0 -0.254)
							(end -0.2159 -0.0381)
						)
						(arc
							(start -0.2159 0.0381)
							(mid 0 0.254)
							(end 0.2159 0.0381)
						)
					)
					(width 0)
					(fill yes)
				)
			)
		)
		(pad "AB3" smd circle
			(at -35.533584 -14.702028)
			(size 0.4318 0.4318)
			(layers "F.Cu" "F.Mask" "F.Paste")
			(net "UPI_CPU1_CPU0_P0P0_DN<4>")
		)
		(pad "AB5" smd circle
			(at -33.816544 -14.702028)
			(size 0.4318 0.4318)
			(layers "F.Cu" "F.Mask" "F.Paste")
			(net "GND")
		)
		(pad "AB7" smd circle
			(at -32.099504 -14.702028)
			(size 0.4318 0.4318)
			(layers "F.Cu" "F.Mask" "F.Paste")
			(net "UPI_CPU0_CPU1_P0P0_DN<2>")
		)
		(pad "AB9" smd circle
			(at -30.382464 -14.702028)
			(size 0.4318 0.4318)
			(layers "F.Cu" "F.Mask" "F.Paste")
			(net "UPI_CPU0_CPU1_P0P0_DN<0>")
		)
		(pad "AB11" smd circle
			(at -28.665424 -14.702028)
			(size 0.4318 0.4318)
			(layers "F.Cu" "F.Mask" "F.Paste")
			(net "GND")
		)
		(pad "AB13" smd circle
			(at -26.948384 -14.702028)
			(size 0.4318 0.4318)
			(layers "F.Cu" "F.Mask" "F.Paste")
			(net "FM_CPU1_SKTOCC_LVT3_N")
		)
		(pad "AB15" smd circle
			(at -25.231598 -14.702028)
			(size 0.4318 0.4318)
			(layers "F.Cu" "F.Mask" "F.Paste")
			(net "H_CPU1_THERMTRIP_G_N")
		)
		(pad "AB17" smd circle
			(at -23.514558 -14.702028)
			(size 0.4318 0.4318)
			(layers "F.Cu" "F.Mask" "F.Paste")
			(net "TP_CPU1_PROC_DIS_G_N")
		)
		(pad "AB19" smd circle
			(at -21.797518 -14.702028)
			(size 0.4318 0.4318)
			(layers "F.Cu" "F.Mask" "F.Paste")
			(net "UPI_CPU0_CPU1_P1P1_DP<19>")
		)
		(pad "AB21" smd circle
			(at -20.080478 -14.702028)
			(size 0.4318 0.4318)
			(layers "F.Cu" "F.Mask" "F.Paste")
			(net "GND")
		)
		(pad "AB23" smd circle
			(at -18.363438 -14.702028)
			(size 0.4318 0.4318)
			(layers "F.Cu" "F.Mask" "F.Paste")
			(net "GND")
		)
		(pad "AB25" smd circle
			(at -16.646398 -14.702028)
			(size 0.4318 0.4318)
			(layers "F.Cu" "F.Mask" "F.Paste")
			(net "GND")
		)
		(pad "AB27" smd circle
			(at -14.929612 -14.702028)
			(size 0.4318 0.4318)
			(layers "F.Cu" "F.Mask" "F.Paste")
			(net "M_H_DQS_DN<7>")
		)
		(pad "AB29" smd circle
			(at -13.212572 -14.702028)
			(size 0.4318 0.4318)
			(layers "F.Cu" "F.Mask" "F.Paste")
			(net "GND")
		)
		(pad "AB31" smd circle
			(at -11.495532 -14.702028)
			(size 0.4318 0.4318)
			(layers "F.Cu" "F.Mask" "F.Paste")
			(net "GND")
		)
		(pad "AB33" smd circle
			(at -9.778492 -14.702028)
			(size 0.4318 0.4318)
			(layers "F.Cu" "F.Mask" "F.Paste")
			(net "M_J_DQS_DN<5>")
		)
		(pad "AB35" smd circle
			(at -8.061452 -14.702028)
			(size 0.4318 0.4318)
			(layers "F.Cu" "F.Mask" "F.Paste")
			(net "GND")
		)
		(pad "AB37" smd circle
			(at -6.344412 -14.702028)
			(size 0.4318 0.4318)
			(layers "F.Cu" "F.Mask" "F.Paste")
			(net "GND")
		)
		(pad "AB39" smd circle
			(at -4.627626 -14.702028)
			(size 0.4318 0.4318)
			(layers "F.Cu" "F.Mask" "F.Paste")
			(net "M_J_DQS_DN<4>")
		)
		(pad "AB41" smd circle
			(at -2.910586 -14.702028)
			(size 0.4318 0.4318)
			(layers "F.Cu" "F.Mask" "F.Paste")
			(net "GND")
		)
		(pad "AB43" smd circle
			(at -1.193546 -14.702028)
			(size 0.4318 0.4318)
			(layers "F.Cu" "F.Mask" "F.Paste")
			(net "A_CPU1_GHJ_RCOMP1")
		)
		(pad "AB45" smd circle
			(at 2.052066 -16.502126)
			(size 0.508 0.508)
			(layers "F.Cu" "F.Mask" "F.Paste")
			(net "M_J_C<2>")
		)
		(pad "AB47" smd circle
			(at 3.769106 -16.502126)
			(size 0.4318 0.4318)
			(layers "F.Cu" "F.Mask" "F.Paste")
			(net "M_J_ODT<3>")
		)
		(pad "AB49" smd circle
			(at 5.485892 -16.502126)
			(size 0.4318 0.4318)
			(layers "F.Cu" "F.Mask" "F.Paste")
			(net "M_J_CS_N<1>")
		)
		(pad "AB51" smd circle
			(at 7.202932 -16.502126)
			(size 0.4318 0.4318)
			(layers "F.Cu" "F.Mask" "F.Paste")
			(net "M_J_CS_N<4>")
		)
		(pad "AB53" smd circle
			(at 8.919972 -16.502126)
			(size 0.4318 0.4318)
			(layers "F.Cu" "F.Mask" "F.Paste")
			(net "M_J_MA<0>")
		)
		(pad "AB55" smd circle
			(at 10.637012 -16.502126)
			(size 0.4318 0.4318)
			(layers "F.Cu" "F.Mask" "F.Paste")
			(net "M_J_CLK_DP<0>")
		)
		(pad "AB57" smd circle
			(at 12.354052 -16.502126)
			(size 0.4318 0.4318)
			(layers "F.Cu" "F.Mask" "F.Paste")
			(net "M_J_CLK_DP<2>")
		)
		(pad "AB59" smd circle
			(at 14.071092 -16.502126)
			(size 0.4318 0.4318)
			(layers "F.Cu" "F.Mask" "F.Paste")
			(net "M_J_MA<6>")
		)
		(pad "AB61" smd circle
			(at 15.787878 -16.502126)
			(size 0.4318 0.4318)
			(layers "F.Cu" "F.Mask" "F.Paste")
			(net "M_J_ACT_N")
		)
		(pad "AB63" smd circle
			(at 17.504918 -16.502126)
			(size 0.4318 0.4318)
			(layers "F.Cu" "F.Mask" "F.Paste")
			(net "M_J_CKE<3>")
		)
		(pad "AB65" smd circle
			(at 19.221958 -16.502126)
			(size 0.4318 0.4318)
			(layers "F.Cu" "F.Mask" "F.Paste")
			(net "GND")
		)
		(pad "AB67" smd circle
			(at 20.938998 -16.502126)
			(size 0.4318 0.4318)
			(layers "F.Cu" "F.Mask" "F.Paste")
			(net "M_G_DQS_DN<17>")
		)
		(pad "AB69" smd circle
			(at 22.656038 -16.502126)
			(size 0.4318 0.4318)
			(layers "F.Cu" "F.Mask" "F.Paste")
			(net "GND")
		)
		(pad "AB71" smd circle
			(at 24.373078 -16.502126)
			(size 0.4318 0.4318)
			(layers "F.Cu" "F.Mask" "F.Paste")
			(net "M_J_DQ<21>")
		)
		(pad "AB73" smd circle
			(at 26.090118 -16.502126)
			(size 0.4318 0.4318)
			(layers "F.Cu" "F.Mask" "F.Paste")
			(net "GND")
		)
		(pad "AB75" smd circle
			(at 27.806904 -16.502126)
			(size 0.4318 0.4318)
			(layers "F.Cu" "F.Mask" "F.Paste")
			(net "M_J_DQS_DP<1>")
		)
		(pad "AB77" smd circle
			(at 29.523944 -16.502126)
			(size 0.4318 0.4318)
			(layers "F.Cu" "F.Mask" "F.Paste")
			(net "M_J_DQ<14>")
		)
		(pad "AB79" smd circle
			(at 31.240984 -16.502126)
			(size 0.4318 0.4318)
			(layers "F.Cu" "F.Mask" "F.Paste")
			(net "GND")
		)
		(pad "AB81" smd circle
			(at 32.958024 -16.502126)
			(size 0.4318 0.4318)
			(layers "F.Cu" "F.Mask" "F.Paste")
			(net "M_H_DQ<11>")
		)
		(pad "AB83" smd circle
			(at 34.675064 -16.502126)
			(size 0.4318 0.4318)
			(layers "F.Cu" "F.Mask" "F.Paste")
			(net "GND")
		)
		(pad "AB85" smd circle
			(at 36.392104 -16.502126)
			(size 0.4318 0.4318)
			(layers "F.Cu" "F.Mask" "F.Paste")
			(net "GND")
		)
		(pad "AC2" smd circle
			(at -36.392104 -14.206474)
			(size 0.4318 0.4318)
			(layers "F.Cu" "F.Mask" "F.Paste")
			(net "UPI_CPU1_CPU0_P0P0_DP<5>")
		)
		(pad "AC4" smd circle
			(at -34.675064 -14.206474)
			(size 0.4318 0.4318)
			(layers "F.Cu" "F.Mask" "F.Paste")
			(net "PVCCIO_CPU1")
		)
		(pad "AC6" smd circle
			(at -32.958024 -14.206474)
			(size 0.4318 0.4318)
			(layers "F.Cu" "F.Mask" "F.Paste")
			(net "UPI_CPU0_CPU1_P0P0_DN<3>")
		)
		(pad "AC8" smd circle
			(at -31.240984 -14.206474)
			(size 0.4318 0.4318)
			(layers "F.Cu" "F.Mask" "F.Paste")
			(net "UPI_CPU0_CPU1_P0P0_DP<1>")
		)
		(pad "AC10" smd circle
			(at -29.523944 -14.206474)
			(size 0.4318 0.4318)
			(layers "F.Cu" "F.Mask" "F.Paste")
			(net "UPI_CPU0_CPU1_P0P0_DP<0>")
		)
		(pad "AC12" smd circle
			(at -27.806904 -14.206474)
			(size 0.4318 0.4318)
			(layers "F.Cu" "F.Mask" "F.Paste")
			(net "XDP_CPU_OBSFN_B1_MBP7_N")
		)
		(pad "AC14" smd circle
			(at -26.090118 -14.206474)
			(size 0.4318 0.4318)
			(layers "F.Cu" "F.Mask" "F.Paste")
			(net "XDP_CPU1_TDI")
		)
		(pad "AC16" smd circle
			(at -24.373078 -14.206474)
			(size 0.4318 0.4318)
			(layers "F.Cu" "F.Mask" "F.Paste")
			(net "H_CPU1_PROCHOT_G_N")
		)
		(pad "AC18" smd circle
			(at -22.656038 -14.206474)
			(size 0.4318 0.4318)
			(layers "F.Cu" "F.Mask" "F.Paste")
			(net "GND")
		)
		(pad "AC20" smd circle
			(at -20.938998 -14.206474)
			(size 0.4318 0.4318)
			(layers "F.Cu" "F.Mask" "F.Paste")
			(net "PVCCIO_CPU1")
		)
		(pad "AC22" smd circle
			(at -19.221958 -14.206474)
			(size 0.4318 0.4318)
			(layers "F.Cu" "F.Mask" "F.Paste")
			(net "GND")
		)
		(pad "AC24" smd circle
			(at -17.504918 -14.206474)
			(size 0.4318 0.4318)
			(layers "F.Cu" "F.Mask" "F.Paste")
			(net "M_J_DQS_DN<16>")
		)
		(pad "AC26" smd circle
			(at -15.787878 -14.206474)
			(size 0.4318 0.4318)
			(layers "F.Cu" "F.Mask" "F.Paste")
			(net "GND")
		)
		(pad "AC28" smd circle
			(at -14.071092 -14.206474)
			(size 0.4318 0.4318)
			(layers "F.Cu" "F.Mask" "F.Paste")
			(net "GND")
		)
		(pad "AC30" smd circle
			(at -12.354052 -14.206474)
			(size 0.4318 0.4318)
			(layers "F.Cu" "F.Mask" "F.Paste")
			(net "M_J_DQS_DN<15>")
		)
		(pad "AC32" smd circle
			(at -10.637012 -14.206474)
			(size 0.4318 0.4318)
			(layers "F.Cu" "F.Mask" "F.Paste")
			(net "GND")
		)
		(pad "AC34" smd circle
			(at -8.919972 -14.206474)
			(size 0.4318 0.4318)
			(layers "F.Cu" "F.Mask" "F.Paste")
			(net "GND")
		)
		(pad "AC36" smd circle
			(at -7.202932 -14.206474)
			(size 0.4318 0.4318)
			(layers "F.Cu" "F.Mask" "F.Paste")
			(net "PVCCIO_CPU1")
		)
		(pad "AC38" smd circle
			(at -5.485892 -14.206474)
			(size 0.4318 0.4318)
			(layers "F.Cu" "F.Mask" "F.Paste")
			(net "GND")
		)
		(pad "AC40" smd circle
			(at -3.769106 -14.206474)
			(size 0.4318 0.4318)
			(layers "F.Cu" "F.Mask" "F.Paste")
			(net "GND")
		)
		(pad "AC42" smd circle
			(at -2.052066 -14.206474)
			(size 0.4318 0.4318)
			(layers "F.Cu" "F.Mask" "F.Paste")
			(net "A_CPU1_GHJ_RCOMP2")
		)
		(pad "AC46" smd circle
			(at 2.910586 -16.006572)
			(size 0.4318 0.4318)
			(layers "F.Cu" "F.Mask" "F.Paste")
			(net "M_J_MA<17>")
		)
		(pad "AC48" smd circle
			(at 4.627626 -16.006572)
			(size 0.4318 0.4318)
			(layers "F.Cu" "F.Mask" "F.Paste")
			(net "GND")
		)
		(pad "AC50" smd circle
			(at 6.344412 -16.006572)
			(size 0.4318 0.4318)
			(layers "F.Cu" "F.Mask" "F.Paste")
			(net "GND")
		)
		(pad "AC52" smd circle
			(at 8.061452 -16.006572)
			(size 0.4318 0.4318)
			(layers "F.Cu" "F.Mask" "F.Paste")
			(net "GND")
		)
		(pad "AC54" smd circle
			(at 9.778492 -16.006572)
			(size 0.4318 0.4318)
			(layers "F.Cu" "F.Mask" "F.Paste")
			(net "GND")
		)
		(pad "AC56" smd circle
			(at 11.495532 -16.006572)
			(size 0.4318 0.4318)
			(layers "F.Cu" "F.Mask" "F.Paste")
			(net "GND")
		)
		(pad "AC58" smd circle
			(at 13.212572 -16.006572)
			(size 0.4318 0.4318)
			(layers "F.Cu" "F.Mask" "F.Paste")
			(net "GND")
		)
		(pad "AC60" smd circle
			(at 14.929612 -16.006572)
			(size 0.4318 0.4318)
			(layers "F.Cu" "F.Mask" "F.Paste")
			(net "GND")
		)
		(pad "AC62" smd circle
			(at 16.646398 -16.006572)
			(size 0.4318 0.4318)
			(layers "F.Cu" "F.Mask" "F.Paste")
			(net "GND")
		)
		(pad "AC64" smd circle
			(at 18.363438 -16.006572)
			(size 0.4318 0.4318)
			(layers "F.Cu" "F.Mask" "F.Paste")
			(net "GND")
		)
		(pad "AC66" smd circle
			(at 20.080478 -16.006572)
			(size 0.4318 0.4318)
			(layers "F.Cu" "F.Mask" "F.Paste")
			(net "M_G_ECC<6>")
		)
		(pad "AC68" smd circle
			(at 21.797518 -16.006572)
			(size 0.4318 0.4318)
			(layers "F.Cu" "F.Mask" "F.Paste")
			(net "M_G_ECC<0>")
		)
		(pad "AC70" smd circle
			(at 23.514558 -16.006572)
			(size 0.4318 0.4318)
			(layers "F.Cu" "F.Mask" "F.Paste")
			(net "GND")
		)
		(pad "AC72" smd circle
			(at 25.231598 -16.006572)
			(size 0.4318 0.4318)
			(layers "F.Cu" "F.Mask" "F.Paste")
			(net "GND")
		)
		(pad "AC74" smd circle
			(at 26.948384 -16.006572)
			(size 0.4318 0.4318)
			(layers "F.Cu" "F.Mask" "F.Paste")
			(net "M_J_DQ<9>")
		)
		(pad "AC76" smd circle
			(at 28.665424 -16.006572)
			(size 0.4318 0.4318)
			(layers "F.Cu" "F.Mask" "F.Paste")
			(net "M_J_DQS_DP<10>")
		)
		(pad "AC78" smd circle
			(at 30.382464 -16.006572)
			(size 0.4318 0.4318)
			(layers "F.Cu" "F.Mask" "F.Paste")
			(net "GND")
		)
		(pad "AC80" smd circle
			(at 32.099504 -16.006572)
			(size 0.4318 0.4318)
			(layers "F.Cu" "F.Mask" "F.Paste")
			(net "M_H_DQ<15>")
		)
		(pad "AC82" smd circle
			(at 33.816544 -16.006572)
			(size 0.4318 0.4318)
			(layers "F.Cu" "F.Mask" "F.Paste")
			(net "M_H_DQ<10>")
		)
		(pad "AC84" smd circle
			(at 35.533584 -16.006572)
			(size 0.4318 0.4318)
			(layers "F.Cu" "F.Mask" "F.Paste")
			(net "GND")
		)
		(pad "AC86" smd custom
			(at 37.250624 -16.006572 270)
			(size 0.10795 0.10795)
			(layers "F.Cu" "F.Mask" "F.Paste")
			(net "GND")
			(options
				(clearance outline)
				(anchor circle)
			)
			(primitives
				(gr_poly
					(pts
						(arc
							(start 0.2159 -0.0381)
							(mid 0 -0.254)
							(end -0.2159 -0.0381)
						)
						(arc
							(start -0.2159 0.0381)
							(mid 0 0.254)
							(end 0.2159 0.0381)
						)
					)
					(width 0)
					(fill yes)
				)
			)
		)
		(pad "AD1" smd custom
			(at -37.250624 -13.711428 90)
			(size 0.10795 0.10795)
			(layers "F.Cu" "F.Mask" "F.Paste")
			(net "UPI_CPU1_CPU0_P0P0_DN<5>")
			(options
				(clearance outline)
				(anchor circle)
			)
			(primitives
				(gr_poly
					(pts
						(arc
							(start 0.2159 -0.0381)
							(mid 0 -0.254)
							(end -0.2159 -0.0381)
						)
						(arc
							(start -0.2159 0.0381)
							(mid 0 0.254)
							(end 0.2159 0.0381)
						)
					)
					(width 0)
					(fill yes)
				)
			)
		)
		(pad "AD3" smd circle
			(at -35.533584 -13.711428)
			(size 0.4318 0.4318)
			(layers "F.Cu" "F.Mask" "F.Paste")
			(net "GND")
		)
		(pad "AD5" smd circle
			(at -33.816544 -13.711428)
			(size 0.4318 0.4318)
			(layers "F.Cu" "F.Mask" "F.Paste")
			(net "UPI_CPU0_CPU1_P0P0_DP<3>")
		)
		(pad "AD7" smd circle
			(at -32.099504 -13.711428)
			(size 0.4318 0.4318)
			(layers "F.Cu" "F.Mask" "F.Paste")
			(net "GND")
		)
		(pad "AD9" smd circle
			(at -30.382464 -13.711428)
			(size 0.4318 0.4318)
			(layers "F.Cu" "F.Mask" "F.Paste")
			(net "GND")
		)
		(pad "AD11" smd circle
			(at -28.665424 -13.711428)
			(size 0.4318 0.4318)
			(layers "F.Cu" "F.Mask" "F.Paste")
			(net "GND")
		)
		(pad "AD13" smd circle
			(at -26.948384 -13.711428)
			(size 0.4318 0.4318)
			(layers "F.Cu" "F.Mask" "F.Paste")
			(net "GND")
		)
		(pad "AD15" smd circle
			(at -25.231598 -13.711428)
			(size 0.4318 0.4318)
			(layers "F.Cu" "F.Mask" "F.Paste")
			(net "GND")
		)
		(pad "AD17" smd circle
			(at -23.514558 -13.711428)
			(size 0.4318 0.4318)
			(layers "F.Cu" "F.Mask" "F.Paste")
			(net "SMB_DDR_KLM_SDA_G_R")
		)
		(pad "AD19" smd circle
			(at -21.797518 -13.711428)
			(size 0.4318 0.4318)
			(layers "F.Cu" "F.Mask" "F.Paste")
			(net "GND")
		)
		(pad "AD21" smd circle
			(at -20.080478 -13.711428)
			(size 0.4318 0.4318)
			(layers "F.Cu" "F.Mask" "F.Paste")
			(net "GND")
		)
		(pad "AD23" smd circle
			(at -18.363438 -13.711428)
			(size 0.4318 0.4318)
			(layers "F.Cu" "F.Mask" "F.Paste")
			(net "M_J_DQ<62>")
		)
		(pad "AD25" smd circle
			(at -16.646398 -13.711428)
			(size 0.4318 0.4318)
			(layers "F.Cu" "F.Mask" "F.Paste")
			(net "M_J_DQ<56>")
		)
		(pad "AD27" smd circle
			(at -14.929612 -13.711428)
			(size 0.4318 0.4318)
			(layers "F.Cu" "F.Mask" "F.Paste")
			(net "GND")
		)
		(pad "AD29" smd circle
			(at -13.212572 -13.711428)
			(size 0.4318 0.4318)
			(layers "F.Cu" "F.Mask" "F.Paste")
			(net "M_J_DQ<54>")
		)
		(pad "AD31" smd circle
			(at -11.495532 -13.711428)
			(size 0.4318 0.4318)
			(layers "F.Cu" "F.Mask" "F.Paste")
			(net "M_J_DQ<48>")
		)
		(pad "AD33" smd circle
			(at -9.778492 -13.711428)
			(size 0.4318 0.4318)
			(layers "F.Cu" "F.Mask" "F.Paste")
			(net "GND")
		)
		(pad "AD35" smd circle
			(at -8.061452 -13.711428)
			(size 0.4318 0.4318)
			(layers "F.Cu" "F.Mask" "F.Paste")
			(net "PVCCIO_CPU1")
		)
		(pad "AD37" smd circle
			(at -6.344412 -13.711428)
			(size 0.4318 0.4318)
			(layers "F.Cu" "F.Mask" "F.Paste")
			(net "PVCCIO_CPU1")
		)
		(pad "AD39" smd circle
			(at -4.627626 -13.711428)
			(size 0.4318 0.4318)
			(layers "F.Cu" "F.Mask" "F.Paste")
			(net "GND")
		)
		(pad "AD41" smd circle
			(at -2.910586 -13.711428)
			(size 0.4318 0.4318)
			(layers "F.Cu" "F.Mask" "F.Paste")
			(net "VSENSE_PMAX_CPU1")
		)
		(pad "AD43" smd circle
			(at -1.193546 -13.711428)
			(size 0.4318 0.4318)
			(layers "F.Cu" "F.Mask" "F.Paste")
			(net "GND")
		)
		(pad "AD45" smd circle
			(at 2.052066 -15.511526)
			(size 0.508 0.508)
			(layers "F.Cu" "F.Mask" "F.Paste")
			(net "PVDDQ_GHJ")
		)
		(pad "AD47" smd circle
			(at 3.769106 -15.511526)
			(size 0.4318 0.4318)
			(layers "F.Cu" "F.Mask" "F.Paste")
			(net "TP_CPU1_RSVD_254")
		)
		(pad "AD49" smd circle
			(at 5.485892 -15.511526)
			(size 0.4318 0.4318)
			(layers "F.Cu" "F.Mask" "F.Paste")
			(net "TP_CPU1_RSVD_253")
		)
		(pad "AD51" smd circle
			(at 7.202932 -15.511526)
			(size 0.4318 0.4318)
			(layers "F.Cu" "F.Mask" "F.Paste")
			(net "TP_CPU1_RSVD_252")
		)
		(pad "AD53" smd circle
			(at 8.919972 -15.511526)
			(size 0.4318 0.4318)
			(layers "F.Cu" "F.Mask" "F.Paste")
			(net "M_J_MA<13>")
		)
		(pad "AD55" smd circle
			(at 10.637012 -15.511526)
			(size 0.4318 0.4318)
			(layers "F.Cu" "F.Mask" "F.Paste")
			(net "M_J_MA<10>")
		)
		(pad "AD57" smd circle
			(at 12.354052 -15.511526)
			(size 0.4318 0.4318)
			(layers "F.Cu" "F.Mask" "F.Paste")
			(net "M_J_MA<2>")
		)
		(pad "AD59" smd circle
			(at 14.071092 -15.511526)
			(size 0.4318 0.4318)
			(layers "F.Cu" "F.Mask" "F.Paste")
			(net "M_J_MA<8>")
		)
		(pad "AD61" smd circle
			(at 15.787878 -15.511526)
			(size 0.4318 0.4318)
			(layers "F.Cu" "F.Mask" "F.Paste")
			(net "M_J_ALERT_N")
		)
		(pad "AD63" smd circle
			(at 17.504918 -15.511526)
			(size 0.4318 0.4318)
			(layers "F.Cu" "F.Mask" "F.Paste")
			(net "M_J_CKE<1>")
		)
		(pad "AD65" smd circle
			(at 19.221958 -15.511526)
			(size 0.4318 0.4318)
			(layers "F.Cu" "F.Mask" "F.Paste")
			(net "M_G_ECC<2>")
		)
		(pad "AD67" smd circle
			(at 20.938998 -15.511526)
			(size 0.4318 0.4318)
			(layers "F.Cu" "F.Mask" "F.Paste")
			(net "M_G_DQS_DP<17>")
		)
		(pad "AD69" smd circle
			(at 22.656038 -15.511526)
			(size 0.4318 0.4318)
			(layers "F.Cu" "F.Mask" "F.Paste")
			(net "M_G_ECC<4>")
		)
		(pad "AD71" smd circle
			(at 24.373078 -15.511526)
			(size 0.4318 0.4318)
			(layers "F.Cu" "F.Mask" "F.Paste")
			(net "GND")
		)
		(pad "AD73" smd circle
			(at 26.090118 -15.511526)
			(size 0.4318 0.4318)
			(layers "F.Cu" "F.Mask" "F.Paste")
			(net "GND")
		)
		(pad "AD75" smd circle
			(at 27.806904 -15.511526)
			(size 0.4318 0.4318)
			(layers "F.Cu" "F.Mask" "F.Paste")
			(net "GND")
		)
		(pad "AD77" smd circle
			(at 29.523944 -15.511526)
			(size 0.4318 0.4318)
			(layers "F.Cu" "F.Mask" "F.Paste")
			(net "M_J_DQS_DN<10>")
		)
		(pad "AD79" smd circle
			(at 31.240984 -15.511526)
			(size 0.4318 0.4318)
			(layers "F.Cu" "F.Mask" "F.Paste")
			(net "M_H_DQS_DN<1>")
		)
		(pad "AD81" smd circle
			(at 32.958024 -15.511526)
			(size 0.4318 0.4318)
			(layers "F.Cu" "F.Mask" "F.Paste")
			(net "GND")
		)
		(pad "AD83" smd circle
			(at 34.675064 -15.511526)
			(size 0.4318 0.4318)
			(layers "F.Cu" "F.Mask" "F.Paste")
			(net "GND")
		)
		(pad "AD85" smd circle
			(at 36.392104 -15.511526)
			(size 0.4318 0.4318)
			(layers "F.Cu" "F.Mask" "F.Paste")
			(net "GND")
		)
		(pad "AE2" smd circle
			(at -36.392104 -13.215874)
			(size 0.4318 0.4318)
			(layers "F.Cu" "F.Mask" "F.Paste")
			(net "UPI_CPU1_CPU0_P0P0_DN<7>")
		)
		(pad "AE4" smd circle
			(at -34.675064 -13.215874)
			(size 0.4318 0.4318)
			(layers "F.Cu" "F.Mask" "F.Paste")
			(net "GND")
		)
		(pad "AE6" smd circle
			(at -32.958024 -13.215874)
			(size 0.4318 0.4318)
			(layers "F.Cu" "F.Mask" "F.Paste")
			(net "UPI_CPU0_CPU1_P0P0_DP<4>")
		)
		(pad "AE8" smd circle
			(at -31.240984 -13.215874)
			(size 0.4318 0.4318)
			(layers "F.Cu" "F.Mask" "F.Paste")
			(net "GND")
		)
		(pad "AE10" smd circle
			(at -29.523944 -13.215874)
			(size 0.4318 0.4318)
			(layers "F.Cu" "F.Mask" "F.Paste")
			(net "PVCCIO_CPU1")
		)
		(pad "AE12" smd circle
			(at -27.806904 -13.215874)
			(size 0.4318 0.4318)
			(layers "F.Cu" "F.Mask" "F.Paste")
			(net "XDP_CPU_OBSFN_B0_MBP6_N")
		)
		(pad "AE14" smd circle
			(at -26.090118 -13.215874)
			(size 0.4318 0.4318)
			(layers "F.Cu" "F.Mask" "F.Paste")
			(net "XDP_CPU1_TDO")
		)
		(pad "AE16" smd circle
			(at -24.373078 -13.215874)
			(size 0.4318 0.4318)
			(layers "F.Cu" "F.Mask" "F.Paste")
			(net "GND")
		)
		(pad "AE18" smd circle
			(at -22.656038 -13.215874)
			(size 0.4318 0.4318)
			(layers "F.Cu" "F.Mask" "F.Paste")
			(net "SMB_DDR_KLM_SCL_G_R")
		)
		(pad "AE20" smd circle
			(at -20.938998 -13.215874)
			(size 0.4318 0.4318)
			(layers "F.Cu" "F.Mask" "F.Paste")
			(net "PU_CPU1_LEGACY_SKT")
		)
		(pad "AE22" smd circle
			(at -19.221958 -13.215874)
			(size 0.4318 0.4318)
			(layers "F.Cu" "F.Mask" "F.Paste")
			(net "M_J_DQ<58>")
		)
		(pad "AE24" smd circle
			(at -17.504918 -13.215874)
			(size 0.4318 0.4318)
			(layers "F.Cu" "F.Mask" "F.Paste")
			(net "M_J_DQS_DP<16>")
		)
		(pad "AE26" smd circle
			(at -15.787878 -13.215874)
			(size 0.4318 0.4318)
			(layers "F.Cu" "F.Mask" "F.Paste")
			(net "M_J_DQ<60>")
		)
		(pad "AE28" smd circle
			(at -14.071092 -13.215874)
			(size 0.4318 0.4318)
			(layers "F.Cu" "F.Mask" "F.Paste")
			(net "M_J_DQ<50>")
		)
		(pad "AE30" smd circle
			(at -12.354052 -13.215874)
			(size 0.4318 0.4318)
			(layers "F.Cu" "F.Mask" "F.Paste")
			(net "M_J_DQS_DP<15>")
		)
		(pad "AE32" smd circle
			(at -10.637012 -13.215874)
			(size 0.4318 0.4318)
			(layers "F.Cu" "F.Mask" "F.Paste")
			(net "M_J_DQ<52>")
		)
		(pad "AE34" smd circle
			(at -8.919972 -13.215874)
			(size 0.4318 0.4318)
			(layers "F.Cu" "F.Mask" "F.Paste")
			(net "PVCCIO_CPU1")
		)
		(pad "AE36" smd circle
			(at -7.202932 -13.215874)
			(size 0.4318 0.4318)
			(layers "F.Cu" "F.Mask" "F.Paste")
			(net "PVCCIO_CPU1")
		)
		(pad "AE38" smd circle
			(at -5.485892 -13.215874)
			(size 0.4318 0.4318)
			(layers "F.Cu" "F.Mask" "F.Paste")
			(net "GND")
		)
		(pad "AE40" smd circle
			(at -3.769106 -13.215874)
			(size 0.4318 0.4318)
			(layers "F.Cu" "F.Mask" "F.Paste")
			(net "GND")
		)
		(pad "AE42" smd circle
			(at -2.052066 -13.215874)
			(size 0.4318 0.4318)
			(layers "F.Cu" "F.Mask" "F.Paste")
			(net "GND")
		)
		(pad "AE46" smd circle
			(at 2.910586 -15.015972)
			(size 0.4318 0.4318)
			(layers "F.Cu" "F.Mask" "F.Paste")
			(net "TP_CPU1_RSVD_251")
		)
		(pad "AE48" smd circle
			(at 4.627626 -15.015972)
			(size 0.4318 0.4318)
			(layers "F.Cu" "F.Mask" "F.Paste")
			(net "TP_CPU1_RSVD_250")
		)
		(pad "AE50" smd circle
			(at 6.344412 -15.015972)
			(size 0.4318 0.4318)
			(layers "F.Cu" "F.Mask" "F.Paste")
			(net "TP_CPU1_RSVD_249")
		)
		(pad "AE52" smd circle
			(at 8.061452 -15.015972)
			(size 0.4318 0.4318)
			(layers "F.Cu" "F.Mask" "F.Paste")
			(net "TP_CPU1_RSVD_248")
		)
		(pad "AE54" smd circle
			(at 9.778492 -15.015972)
			(size 0.4318 0.4318)
			(layers "F.Cu" "F.Mask" "F.Paste")
			(net "M_J_MA<15>")
		)
		(pad "AE56" smd circle
			(at 11.495532 -15.015972)
			(size 0.4318 0.4318)
			(layers "F.Cu" "F.Mask" "F.Paste")
			(net "M_J_BA<1>")
		)
		(pad "AE58" smd circle
			(at 13.212572 -15.015972)
			(size 0.4318 0.4318)
			(layers "F.Cu" "F.Mask" "F.Paste")
			(net "M_J_MA<1>")
		)
		(pad "AE60" smd circle
			(at 14.929612 -15.015972)
			(size 0.4318 0.4318)
			(layers "F.Cu" "F.Mask" "F.Paste")
			(net "M_J_MA<7>")
		)
		(pad "AE62" smd circle
			(at 16.646398 -15.015972)
			(size 0.4318 0.4318)
			(layers "F.Cu" "F.Mask" "F.Paste")
			(net "M_J_BG<1>")
		)
		(pad "AE64" smd circle
			(at 18.363438 -15.015972)
			(size 0.4318 0.4318)
			(layers "F.Cu" "F.Mask" "F.Paste")
			(net "GND")
		)
		(pad "AE66" smd circle
			(at 20.080478 -15.015972)
			(size 0.4318 0.4318)
			(layers "F.Cu" "F.Mask" "F.Paste")
			(net "GND")
		)
		(pad "AE68" smd circle
			(at 21.797518 -15.015972)
			(size 0.4318 0.4318)
			(layers "F.Cu" "F.Mask" "F.Paste")
			(net "GND")
		)
		(pad "AE70" smd circle
			(at 23.514558 -15.015972)
			(size 0.4318 0.4318)
			(layers "F.Cu" "F.Mask" "F.Paste")
			(net "GND")
		)
		(pad "AE72" smd circle
			(at 25.231598 -15.015972)
			(size 0.4318 0.4318)
			(layers "F.Cu" "F.Mask" "F.Paste")
			(net "TP_CPU1_RSVD_247")
		)
		(pad "AE74" smd circle
			(at 26.948384 -15.015972)
			(size 0.4318 0.4318)
			(layers "F.Cu" "F.Mask" "F.Paste")
			(net "M_J_DQ<13>")
		)
		(pad "AE76" smd circle
			(at 28.665424 -15.015972)
			(size 0.4318 0.4318)
			(layers "F.Cu" "F.Mask" "F.Paste")
			(net "M_J_DQ<8>")
		)
		(pad "AE78" smd circle
			(at 30.382464 -15.015972)
			(size 0.4318 0.4318)
			(layers "F.Cu" "F.Mask" "F.Paste")
			(net "GND")
		)
		(pad "AE80" smd circle
			(at 32.099504 -15.015972)
			(size 0.4318 0.4318)
			(layers "F.Cu" "F.Mask" "F.Paste")
			(net "M_H_DQS_DP<1>")
		)
		(pad "AE82" smd circle
			(at 33.816544 -15.015972)
			(size 0.4318 0.4318)
			(layers "F.Cu" "F.Mask" "F.Paste")
			(net "M_H_DQ<14>")
		)
		(pad "AE84" smd circle
			(at 35.533584 -15.015972)
			(size 0.4318 0.4318)
			(layers "F.Cu" "F.Mask" "F.Paste")
			(net "M_G_DQ<3>")
		)
		(pad "AE86" smd custom
			(at 37.250624 -15.015972 270)
			(size 0.10795 0.10795)
			(layers "F.Cu" "F.Mask" "F.Paste")
			(net "M_G_DQ<2>")
			(options
				(clearance outline)
				(anchor circle)
			)
			(primitives
				(gr_poly
					(pts
						(arc
							(start 0.2159 -0.0381)
							(mid 0 -0.254)
							(end -0.2159 -0.0381)
						)
						(arc
							(start -0.2159 0.0381)
							(mid 0 0.254)
							(end 0.2159 0.0381)
						)
					)
					(width 0)
					(fill yes)
				)
			)
		)
		(pad "AF1" smd custom
			(at -37.250624 -12.720828 90)
			(size 0.10795 0.10795)
			(layers "F.Cu" "F.Mask" "F.Paste")
			(net "GND")
			(options
				(clearance outline)
				(anchor circle)
			)
			(primitives
				(gr_poly
					(pts
						(arc
							(start 0.2159 -0.0381)
							(mid 0 -0.254)
							(end -0.2159 -0.0381)
						)
						(arc
							(start -0.2159 0.0381)
							(mid 0 0.254)
							(end 0.2159 0.0381)
						)
					)
					(width 0)
					(fill yes)
				)
			)
		)
		(pad "AF3" smd circle
			(at -35.533584 -12.720828)
			(size 0.4318 0.4318)
			(layers "F.Cu" "F.Mask" "F.Paste")
			(net "UPI_CPU1_CPU0_P0P0_DP<6>")
		)
		(pad "AF5" smd circle
			(at -33.816544 -12.720828)
			(size 0.4318 0.4318)
			(layers "F.Cu" "F.Mask" "F.Paste")
			(net "PVCCIO_CPU1")
		)
		(pad "AF7" smd circle
			(at -32.099504 -12.720828)
			(size 0.4318 0.4318)
			(layers "F.Cu" "F.Mask" "F.Paste")
			(net "UPI_CPU0_CPU1_P0P0_DN<5>")
		)
		(pad "AF9" smd circle
			(at -30.382464 -12.720828)
			(size 0.4318 0.4318)
			(layers "F.Cu" "F.Mask" "F.Paste")
			(net "GND")
		)
		(pad "AF11" smd circle
			(at -28.665424 -12.720828)
			(size 0.4318 0.4318)
			(layers "F.Cu" "F.Mask" "F.Paste")
			(net "TP_XDP_CPU1_OBSDATA_B1_MBP3_N")
		)
		(pad "AF13" smd circle
			(at -26.948384 -12.720828)
			(size 0.4318 0.4318)
			(layers "F.Cu" "F.Mask" "F.Paste")
			(net "H_CPU1_MEMKLM_MEMHOT_G_N")
		)
		(pad "AF15" smd circle
			(at -25.231598 -12.720828)
			(size 0.4318 0.4318)
			(layers "F.Cu" "F.Mask" "F.Paste")
			(net "H_CPU1_FAST_WAKE_N")
		)
		(pad "AF17" smd circle
			(at -23.514558 -12.720828)
			(size 0.4318 0.4318)
			(layers "F.Cu" "F.Mask" "F.Paste")
			(net "SMB_DDR_GHJ_SDA_G_R")
		)
		(pad "AF19" smd circle
			(at -21.797518 -12.720828)
			(size 0.4318 0.4318)
			(layers "F.Cu" "F.Mask" "F.Paste")
			(net "TP_CPU1_RSVD_246")
		)
		(pad "AF21" smd circle
			(at -20.080478 -12.720828)
			(size 0.4318 0.4318)
			(layers "F.Cu" "F.Mask" "F.Paste")
			(net "GND")
		)
		(pad "AF23" smd circle
			(at -18.363438 -12.720828)
			(size 0.4318 0.4318)
			(layers "F.Cu" "F.Mask" "F.Paste")
			(net "GND")
		)
		(pad "AF25" smd circle
			(at -16.646398 -12.720828)
			(size 0.4318 0.4318)
			(layers "F.Cu" "F.Mask" "F.Paste")
			(net "GND")
		)
		(pad "AF27" smd circle
			(at -14.929612 -12.720828)
			(size 0.4318 0.4318)
			(layers "F.Cu" "F.Mask" "F.Paste")
			(net "GND")
		)
		(pad "AF29" smd circle
			(at -13.212572 -12.720828)
			(size 0.4318 0.4318)
			(layers "F.Cu" "F.Mask" "F.Paste")
			(net "GND")
		)
		(pad "AF31" smd circle
			(at -11.495532 -12.720828)
			(size 0.4318 0.4318)
			(layers "F.Cu" "F.Mask" "F.Paste")
			(net "GND")
		)
		(pad "AF33" smd circle
			(at -9.778492 -12.720828)
			(size 0.4318 0.4318)
			(layers "F.Cu" "F.Mask" "F.Paste")
			(net "GND")
		)
		(pad "AF35" smd circle
			(at -8.061452 -12.720828)
			(size 0.4318 0.4318)
			(layers "F.Cu" "F.Mask" "F.Paste")
			(net "PVCCIO_CPU1")
		)
		(pad "AF37" smd circle
			(at -6.344412 -12.720828)
			(size 0.4318 0.4318)
			(layers "F.Cu" "F.Mask" "F.Paste")
			(net "GND")
		)
		(pad "AF39" smd circle
			(at -4.627626 -12.720828)
			(size 0.4318 0.4318)
			(layers "F.Cu" "F.Mask" "F.Paste")
			(net "GND")
		)
		(pad "AF41" smd circle
			(at -2.910586 -12.720828)
			(size 0.4318 0.4318)
			(layers "F.Cu" "F.Mask" "F.Paste")
			(net "GND")
		)
		(pad "AF43" smd circle
			(at -1.193546 -12.720828)
			(size 0.4318 0.4318)
			(layers "F.Cu" "F.Mask" "F.Paste")
			(net "PVCCIN_CPU1")
		)
		(pad "AF45" smd circle
			(at 2.052066 -14.520926)
			(size 0.508 0.508)
			(layers "F.Cu" "F.Mask" "F.Paste")
			(net "PD_CPU1_RSVD_TEST_1")
		)
		(pad "AF47" smd circle
			(at 3.769106 -14.520926)
			(size 0.4318 0.4318)
			(layers "F.Cu" "F.Mask" "F.Paste")
			(net "TP_CPU1_RSVD_245")
		)
		(pad "AF49" smd circle
			(at 5.485892 -14.520926)
			(size 0.4318 0.4318)
			(layers "F.Cu" "F.Mask" "F.Paste")
			(net "TP_CPU1_RSVD_244")
		)
		(pad "AF51" smd circle
			(at 7.202932 -14.520926)
			(size 0.4318 0.4318)
			(layers "F.Cu" "F.Mask" "F.Paste")
			(net "TP_CPU1_RSVD_243")
		)
		(pad "AF53" smd circle
			(at 8.919972 -14.520926)
			(size 0.4318 0.4318)
			(layers "F.Cu" "F.Mask" "F.Paste")
			(net "TP_CPU1_RSVD_242")
		)
		(pad "AF55" smd circle
			(at 10.637012 -14.520926)
			(size 0.4318 0.4318)
			(layers "F.Cu" "F.Mask" "F.Paste")
			(net "PVDDQ_GHJ")
		)
		(pad "AF57" smd circle
			(at 12.354052 -14.520926)
			(size 0.4318 0.4318)
			(layers "F.Cu" "F.Mask" "F.Paste")
			(net "PVDDQ_GHJ")
		)
		(pad "AF59" smd circle
			(at 14.071092 -14.520926)
			(size 0.4318 0.4318)
			(layers "F.Cu" "F.Mask" "F.Paste")
			(net "PVDDQ_GHJ")
		)
		(pad "AF61" smd circle
			(at 15.787878 -14.520926)
			(size 0.4318 0.4318)
			(layers "F.Cu" "F.Mask" "F.Paste")
			(net "PVDDQ_GHJ")
		)
		(pad "AF63" smd circle
			(at 17.504918 -14.520926)
			(size 0.4318 0.4318)
			(layers "F.Cu" "F.Mask" "F.Paste")
			(net "PVDDQ_GHJ")
		)
		(pad "AF65" smd circle
			(at 19.221958 -14.520926)
			(size 0.4318 0.4318)
			(layers "F.Cu" "F.Mask" "F.Paste")
			(net "M_G_ECC<3>")
		)
		(pad "AF67" smd circle
			(at 20.938998 -14.520926)
			(size 0.4318 0.4318)
			(layers "F.Cu" "F.Mask" "F.Paste")
			(net "M_G_DQS_DP<8>")
		)
		(pad "AF69" smd circle
			(at 22.656038 -14.520926)
			(size 0.4318 0.4318)
			(layers "F.Cu" "F.Mask" "F.Paste")
			(net "M_G_ECC<5>")
		)
		(pad "AF71" smd circle
			(at 24.373078 -14.520926)
			(size 0.4318 0.4318)
			(layers "F.Cu" "F.Mask" "F.Paste")
			(net "TP_CPU1_RSVD_241")
		)
		(pad "AF73" smd circle
			(at 26.090118 -14.520926)
			(size 0.4318 0.4318)
			(layers "F.Cu" "F.Mask" "F.Paste")
			(net "GND")
		)
		(pad "AF75" smd circle
			(at 27.806904 -14.520926)
			(size 0.4318 0.4318)
			(layers "F.Cu" "F.Mask" "F.Paste")
			(net "M_J_DQ<12>")
		)
		(pad "AF77" smd circle
			(at 29.523944 -14.520926)
			(size 0.4318 0.4318)
			(layers "F.Cu" "F.Mask" "F.Paste")
			(net "GND")
		)
		(pad "AF79" smd circle
			(at 31.240984 -14.520926)
			(size 0.4318 0.4318)
			(layers "F.Cu" "F.Mask" "F.Paste")
			(net "M_H_DQ<9>")
		)
		(pad "AF81" smd circle
			(at 32.958024 -14.520926)
			(size 0.4318 0.4318)
			(layers "F.Cu" "F.Mask" "F.Paste")
			(net "M_H_DQS_DP<10>")
		)
		(pad "AF83" smd circle
			(at 34.675064 -14.520926)
			(size 0.4318 0.4318)
			(layers "F.Cu" "F.Mask" "F.Paste")
			(net "GND")
		)
		(pad "AF85" smd circle
			(at 36.392104 -14.520926)
			(size 0.4318 0.4318)
			(layers "F.Cu" "F.Mask" "F.Paste")
			(net "GND")
		)
		(pad "AG2" smd circle
			(at -36.392104 -12.225274)
			(size 0.4318 0.4318)
			(layers "F.Cu" "F.Mask" "F.Paste")
			(net "UPI_CPU1_CPU0_P0P0_DP<7>")
		)
		(pad "AG4" smd circle
			(at -34.675064 -12.225274)
			(size 0.4318 0.4318)
			(layers "F.Cu" "F.Mask" "F.Paste")
			(net "UPI_CPU1_CPU0_P0P0_DN<6>")
		)
		(pad "AG6" smd circle
			(at -32.958024 -12.225274)
			(size 0.4318 0.4318)
			(layers "F.Cu" "F.Mask" "F.Paste")
			(net "UPI_CPU0_CPU1_P0P0_DN<4>")
		)
		(pad "AG8" smd circle
			(at -31.240984 -12.225274)
			(size 0.4318 0.4318)
			(layers "F.Cu" "F.Mask" "F.Paste")
			(net "UPI_CPU0_CPU1_P0P0_DP<5>")
		)
		(pad "AG10" smd circle
			(at -29.523944 -12.225274)
			(size 0.4318 0.4318)
			(layers "F.Cu" "F.Mask" "F.Paste")
			(net "TP_XDP_CPU1_OBSDATA_B0_MBP2_N")
		)
		(pad "AG12" smd circle
			(at -27.806904 -12.225274)
			(size 0.4318 0.4318)
			(layers "F.Cu" "F.Mask" "F.Paste")
			(net "GND")
		)
		(pad "AG14" smd circle
			(at -26.090118 -12.225274)
			(size 0.4318 0.4318)
			(layers "F.Cu" "F.Mask" "F.Paste")
			(net "GND")
		)
		(pad "AG16" smd circle
			(at -24.373078 -12.225274)
			(size 0.4318 0.4318)
			(layers "F.Cu" "F.Mask" "F.Paste")
			(net "XDP_CPU_PRDY_N")
		)
		(pad "AG18" smd circle
			(at -22.656038 -12.225274)
			(size 0.4318 0.4318)
			(layers "F.Cu" "F.Mask" "F.Paste")
			(net "GND")
		)
		(pad "AG20" smd circle
			(at -20.938998 -12.225274)
			(size 0.4318 0.4318)
			(layers "F.Cu" "F.Mask" "F.Paste")
			(net "TP_CPU1_RSVD_240")
		)
		(pad "AG22" smd circle
			(at -19.221958 -12.225274)
			(size 0.4318 0.4318)
			(layers "F.Cu" "F.Mask" "F.Paste")
			(net "M_J_DQ<59>")
		)
		(pad "AG24" smd circle
			(at -17.504918 -12.225274)
			(size 0.4318 0.4318)
			(layers "F.Cu" "F.Mask" "F.Paste")
			(net "M_J_DQS_DP<7>")
		)
		(pad "AG26" smd circle
			(at -15.787878 -12.225274)
			(size 0.4318 0.4318)
			(layers "F.Cu" "F.Mask" "F.Paste")
			(net "M_J_DQ<61>")
		)
		(pad "AG28" smd circle
			(at -14.071092 -12.225274)
			(size 0.4318 0.4318)
			(layers "F.Cu" "F.Mask" "F.Paste")
			(net "M_J_DQ<51>")
		)
		(pad "AG30" smd circle
			(at -12.354052 -12.225274)
			(size 0.4318 0.4318)
			(layers "F.Cu" "F.Mask" "F.Paste")
			(net "M_J_DQS_DP<6>")
		)
		(pad "AG32" smd circle
			(at -10.637012 -12.225274)
			(size 0.4318 0.4318)
			(layers "F.Cu" "F.Mask" "F.Paste")
			(net "M_J_DQ<53>")
		)
		(pad "AG34" smd circle
			(at -8.919972 -12.225274)
			(size 0.4318 0.4318)
			(layers "F.Cu" "F.Mask" "F.Paste")
			(net "PVCCIO_CPU1")
		)
		(pad "AG36" smd circle
			(at -7.202932 -12.225274)
			(size 0.4318 0.4318)
			(layers "F.Cu" "F.Mask" "F.Paste")
			(net "GND")
		)
		(pad "AG38" smd circle
			(at -5.485892 -12.225274)
			(size 0.4318 0.4318)
			(layers "F.Cu" "F.Mask" "F.Paste")
			(net "PVCCIN_CPU1")
		)
		(pad "AG40" smd circle
			(at -3.769106 -12.225274)
			(size 0.4318 0.4318)
			(layers "F.Cu" "F.Mask" "F.Paste")
			(net "PVCCIN_CPU1")
		)
		(pad "AG42" smd circle
			(at -2.052066 -12.225274)
			(size 0.4318 0.4318)
			(layers "F.Cu" "F.Mask" "F.Paste")
			(net "PVCCIN_CPU1")
		)
		(pad "AG46" smd circle
			(at 2.910586 -14.025372)
			(size 0.4318 0.4318)
			(layers "F.Cu" "F.Mask" "F.Paste")
			(net "PD_CPU1_RSVD_TEST_2")
		)
		(pad "AG48" smd circle
			(at 4.627626 -14.025372)
			(size 0.4318 0.4318)
			(layers "F.Cu" "F.Mask" "F.Paste")
			(net "TP_CPU1_RSVD_239")
		)
		(pad "AG50" smd circle
			(at 6.344412 -14.025372)
			(size 0.4318 0.4318)
			(layers "F.Cu" "F.Mask" "F.Paste")
			(net "TP_CPU1_RSVD_238")
		)
		(pad "AG52" smd circle
			(at 8.061452 -14.025372)
			(size 0.4318 0.4318)
			(layers "F.Cu" "F.Mask" "F.Paste")
			(net "TP_CPU1_RSVD_237")
		)
		(pad "AG54" smd circle
			(at 9.778492 -14.025372)
			(size 0.4318 0.4318)
			(layers "F.Cu" "F.Mask" "F.Paste")
			(net "TP_CPU1_RSVD_236")
		)
		(pad "AG56" smd circle
			(at 11.495532 -14.025372)
			(size 0.4318 0.4318)
			(layers "F.Cu" "F.Mask" "F.Paste")
			(net "TP_CPU1_RSVD_235")
		)
		(pad "AG58" smd circle
			(at 13.212572 -14.025372)
			(size 0.4318 0.4318)
			(layers "F.Cu" "F.Mask" "F.Paste")
			(net "M_J_MA<9>")
		)
		(pad "AG60" smd circle
			(at 14.929612 -14.025372)
			(size 0.4318 0.4318)
			(layers "F.Cu" "F.Mask" "F.Paste")
			(net "M_J_MA<11>")
		)
		(pad "AG62" smd circle
			(at 16.646398 -14.025372)
			(size 0.4318 0.4318)
			(layers "F.Cu" "F.Mask" "F.Paste")
			(net "M_J_MA<12>")
		)
		(pad "AG64" smd circle
			(at 18.363438 -14.025372)
			(size 0.4318 0.4318)
			(layers "F.Cu" "F.Mask" "F.Paste")
			(net "GND")
		)
		(pad "AG66" smd circle
			(at 20.080478 -14.025372)
			(size 0.4318 0.4318)
			(layers "F.Cu" "F.Mask" "F.Paste")
			(net "M_G_ECC<7>")
		)
		(pad "AG68" smd circle
			(at 21.797518 -14.025372)
			(size 0.4318 0.4318)
			(layers "F.Cu" "F.Mask" "F.Paste")
			(net "M_G_ECC<1>")
		)
		(pad "AG70" smd circle
			(at 23.514558 -14.025372)
			(size 0.4318 0.4318)
			(layers "F.Cu" "F.Mask" "F.Paste")
			(net "GND")
		)
		(pad "AG72" smd circle
			(at 25.231598 -14.025372)
			(size 0.4318 0.4318)
			(layers "F.Cu" "F.Mask" "F.Paste")
			(net "TP_CPU1_RSVD_234")
		)
		(pad "AG74" smd circle
			(at 26.948384 -14.025372)
			(size 0.4318 0.4318)
			(layers "F.Cu" "F.Mask" "F.Paste")
			(net "GND")
		)
		(pad "AG76" smd circle
			(at 28.665424 -14.025372)
			(size 0.4318 0.4318)
			(layers "F.Cu" "F.Mask" "F.Paste")
			(net "GND")
		)
		(pad "AG78" smd circle
			(at 30.382464 -14.025372)
			(size 0.4318 0.4318)
			(layers "F.Cu" "F.Mask" "F.Paste")
			(net "GND")
		)
		(pad "AG80" smd circle
			(at 32.099504 -14.025372)
			(size 0.4318 0.4318)
			(layers "F.Cu" "F.Mask" "F.Paste")
			(net "GND")
		)
		(pad "AG82" smd circle
			(at 33.816544 -14.025372)
			(size 0.4318 0.4318)
			(layers "F.Cu" "F.Mask" "F.Paste")
			(net "M_H_DQS_DN<10>")
		)
		(pad "AG84" smd circle
			(at 35.533584 -14.025372)
			(size 0.4318 0.4318)
			(layers "F.Cu" "F.Mask" "F.Paste")
			(net "M_G_DQ<7>")
		)
		(pad "AG86" smd custom
			(at 37.250624 -14.025372 270)
			(size 0.10795 0.10795)
			(layers "F.Cu" "F.Mask" "F.Paste")
			(net "M_G_DQ<6>")
			(options
				(clearance outline)
				(anchor circle)
			)
			(primitives
				(gr_poly
					(pts
						(arc
							(start 0.2159 -0.0381)
							(mid 0 -0.254)
							(end -0.2159 -0.0381)
						)
						(arc
							(start -0.2159 0.0381)
							(mid 0 0.254)
							(end 0.2159 0.0381)
						)
					)
					(width 0)
					(fill yes)
				)
			)
		)
		(pad "AH1" smd custom
			(at -37.250624 -11.730228 90)
			(size 0.10795 0.10795)
			(layers "F.Cu" "F.Mask" "F.Paste")
			(net "GND")
			(options
				(clearance outline)
				(anchor circle)
			)
			(primitives
				(gr_poly
					(pts
						(arc
							(start 0.2159 -0.0381)
							(mid 0 -0.254)
							(end -0.2159 -0.0381)
						)
						(arc
							(start -0.2159 0.0381)
							(mid 0 0.254)
							(end 0.2159 0.0381)
						)
					)
					(width 0)
					(fill yes)
				)
			)
		)
		(pad "AH3" smd circle
			(at -35.533584 -11.730228)
			(size 0.4318 0.4318)
			(layers "F.Cu" "F.Mask" "F.Paste")
			(net "UPI_CPU1_CPU0_P0P0_DP<8>")
		)
		(pad "AH5" smd circle
			(at -33.816544 -11.730228)
			(size 0.4318 0.4318)
			(layers "F.Cu" "F.Mask" "F.Paste")
			(net "GND")
		)
		(pad "AH7" smd circle
			(at -32.099504 -11.730228)
			(size 0.4318 0.4318)
			(layers "F.Cu" "F.Mask" "F.Paste")
			(net "UPI_CPU0_CPU1_P0P0_DN<6>")
		)
		(pad "AH9" smd circle
			(at -30.382464 -11.730228)
			(size 0.4318 0.4318)
			(layers "F.Cu" "F.Mask" "F.Paste")
			(net "PVCCIO_CPU1")
		)
		(pad "AH11" smd circle
			(at -28.665424 -11.730228)
			(size 0.4318 0.4318)
			(layers "F.Cu" "F.Mask" "F.Paste")
			(net "XDP_CPU_MBP1_N")
		)
		(pad "AH13" smd circle
			(at -26.948384 -11.730228)
			(size 0.4318 0.4318)
			(layers "F.Cu" "F.Mask" "F.Paste")
			(net "H_CPU1_MEMGHJ_MEMHOT_G_N")
		)
		(pad "AH15" smd circle
			(at -25.231598 -11.730228)
			(size 0.4318 0.4318)
			(layers "F.Cu" "F.Mask" "F.Paste")
			(net "TP_CPU1_RSVD_233")
		)
		(pad "AH19" smd circle
			(at -21.797518 -11.730228)
			(size 0.4318 0.4318)
			(layers "F.Cu" "F.Mask" "F.Paste")
			(net "TP_CPU1_RSVD_232")
		)
		(pad "AH21" smd circle
			(at -20.080478 -11.730228)
			(size 0.4318 0.4318)
			(layers "F.Cu" "F.Mask" "F.Paste")
			(net "GND")
		)
		(pad "AH23" smd circle
			(at -18.363438 -11.730228)
			(size 0.4318 0.4318)
			(layers "F.Cu" "F.Mask" "F.Paste")
			(net "M_J_DQ<63>")
		)
		(pad "AH25" smd circle
			(at -16.646398 -11.730228)
			(size 0.4318 0.4318)
			(layers "F.Cu" "F.Mask" "F.Paste")
			(net "M_J_DQ<57>")
		)
		(pad "AH27" smd circle
			(at -14.929612 -11.730228)
			(size 0.4318 0.4318)
			(layers "F.Cu" "F.Mask" "F.Paste")
			(net "GND")
		)
		(pad "AH29" smd circle
			(at -13.212572 -11.730228)
			(size 0.4318 0.4318)
			(layers "F.Cu" "F.Mask" "F.Paste")
			(net "M_J_DQ<55>")
		)
		(pad "AH31" smd circle
			(at -11.495532 -11.730228)
			(size 0.4318 0.4318)
			(layers "F.Cu" "F.Mask" "F.Paste")
			(net "M_J_DQ<49>")
		)
		(pad "AH33" smd circle
			(at -9.778492 -11.730228)
			(size 0.4318 0.4318)
			(layers "F.Cu" "F.Mask" "F.Paste")
			(net "GND")
		)
		(pad "AH35" smd circle
			(at -8.061452 -11.730228)
			(size 0.4318 0.4318)
			(layers "F.Cu" "F.Mask" "F.Paste")
			(net "GND")
		)
		(pad "AH37" smd circle
			(at -6.344412 -11.730228)
			(size 0.4318 0.4318)
			(layers "F.Cu" "F.Mask" "F.Paste")
			(net "PVCCIN_CPU1")
		)
		(pad "AH39" smd circle
			(at -4.627626 -11.730228)
			(size 0.4318 0.4318)
			(layers "F.Cu" "F.Mask" "F.Paste")
			(net "PVCCIN_CPU1")
		)
		(pad "AH41" smd circle
			(at -2.910586 -11.730228)
			(size 0.4318 0.4318)
			(layers "F.Cu" "F.Mask" "F.Paste")
			(net "PVCCIN_CPU1")
		)
		(pad "AH45" smd circle
			(at 2.052066 -13.530326)
			(size 0.508 0.508)
			(layers "F.Cu" "F.Mask" "F.Paste")
			(net "GND")
		)
		(pad "AH47" smd circle
			(at 3.769106 -13.530326)
			(size 0.4318 0.4318)
			(layers "F.Cu" "F.Mask" "F.Paste")
			(net "GND")
		)
		(pad "AH49" smd circle
			(at 5.485892 -13.530326)
			(size 0.4318 0.4318)
			(layers "F.Cu" "F.Mask" "F.Paste")
			(net "GND")
		)
		(pad "AH51" smd circle
			(at 7.202932 -13.530326)
			(size 0.4318 0.4318)
			(layers "F.Cu" "F.Mask" "F.Paste")
			(net "GND")
		)
		(pad "AH53" smd circle
			(at 8.919972 -13.530326)
			(size 0.4318 0.4318)
			(layers "F.Cu" "F.Mask" "F.Paste")
			(net "GND")
		)
		(pad "AH55" smd circle
			(at 10.637012 -13.530326)
			(size 0.4318 0.4318)
			(layers "F.Cu" "F.Mask" "F.Paste")
			(net "TP_CPU1_RSVD_231")
		)
		(pad "AH57" smd circle
			(at 12.354052 -13.530326)
			(size 0.4318 0.4318)
			(layers "F.Cu" "F.Mask" "F.Paste")
			(net "TP_CPU1_RSVD_230")
		)
		(pad "AH59" smd circle
			(at 14.071092 -13.530326)
			(size 0.4318 0.4318)
			(layers "F.Cu" "F.Mask" "F.Paste")
			(net "GND")
		)
		(pad "AH61" smd circle
			(at 15.787878 -13.530326)
			(size 0.4318 0.4318)
			(layers "F.Cu" "F.Mask" "F.Paste")
			(net "GND")
		)
		(pad "AH63" smd circle
			(at 17.504918 -13.530326)
			(size 0.4318 0.4318)
			(layers "F.Cu" "F.Mask" "F.Paste")
			(net "M_J_CPU_VREF")
		)
		(pad "AH65" smd circle
			(at 19.221958 -13.530326)
			(size 0.4318 0.4318)
			(layers "F.Cu" "F.Mask" "F.Paste")
			(net "GND")
		)
		(pad "AH67" smd circle
			(at 20.938998 -13.530326)
			(size 0.4318 0.4318)
			(layers "F.Cu" "F.Mask" "F.Paste")
			(net "M_G_DQS_DN<8>")
		)
		(pad "AH69" smd circle
			(at 22.656038 -13.530326)
			(size 0.4318 0.4318)
			(layers "F.Cu" "F.Mask" "F.Paste")
			(net "GND")
		)
		(pad "AH71" smd circle
			(at 24.373078 -13.530326)
			(size 0.4318 0.4318)
			(layers "F.Cu" "F.Mask" "F.Paste")
			(net "TP_CPU1_RSVD_229")
		)
		(pad "AH73" smd circle
			(at 26.090118 -13.530326)
			(size 0.4318 0.4318)
			(layers "F.Cu" "F.Mask" "F.Paste")
			(net "TP_CPU1_RSVD_228")
		)
		(pad "AH75" smd circle
			(at 27.806904 -13.530326)
			(size 0.4318 0.4318)
			(layers "F.Cu" "F.Mask" "F.Paste")
			(net "GND")
		)
		(pad "AH77" smd circle
			(at 29.523944 -13.530326)
			(size 0.4318 0.4318)
			(layers "F.Cu" "F.Mask" "F.Paste")
			(net "GND")
		)
		(pad "AH79" smd circle
			(at 31.240984 -13.530326)
			(size 0.4318 0.4318)
			(layers "F.Cu" "F.Mask" "F.Paste")
			(net "M_H_DQ<13>")
		)
		(pad "AH81" smd circle
			(at 32.958024 -13.530326)
			(size 0.4318 0.4318)
			(layers "F.Cu" "F.Mask" "F.Paste")
			(net "M_H_DQ<8>")
		)
		(pad "AH83" smd circle
			(at 34.675064 -13.530326)
			(size 0.4318 0.4318)
			(layers "F.Cu" "F.Mask" "F.Paste")
			(net "GND")
		)
		(pad "AH85" smd circle
			(at 36.392104 -13.530326)
			(size 0.4318 0.4318)
			(layers "F.Cu" "F.Mask" "F.Paste")
			(net "M_G_DQS_DP<0>")
		)
		(pad "AJ2" smd circle
			(at -36.392104 -11.234674)
			(size 0.4318 0.4318)
			(layers "F.Cu" "F.Mask" "F.Paste")
			(net "UPI_CPU1_CPU0_P0P0_DN<8>")
		)
		(pad "AJ4" smd circle
			(at -34.675064 -11.234674)
			(size 0.4318 0.4318)
			(layers "F.Cu" "F.Mask" "F.Paste")
			(net "GND")
		)
		(pad "AJ6" smd circle
			(at -32.958024 -11.234674)
			(size 0.4318 0.4318)
			(layers "F.Cu" "F.Mask" "F.Paste")
			(net "UPI_CPU0_CPU1_P0P0_DP<6>")
		)
		(pad "AJ8" smd circle
			(at -31.240984 -11.234674)
			(size 0.4318 0.4318)
			(layers "F.Cu" "F.Mask" "F.Paste")
			(net "GND")
		)
		(pad "AJ10" smd circle
			(at -29.523944 -11.234674)
			(size 0.4318 0.4318)
			(layers "F.Cu" "F.Mask" "F.Paste")
			(net "XDP_CPU_MBP0_N")
		)
		(pad "AJ12" smd circle
			(at -27.806904 -11.234674)
			(size 0.4318 0.4318)
			(layers "F.Cu" "F.Mask" "F.Paste")
			(net "H_CPU1_ERR0_G_N")
		)
		(pad "AJ14" smd circle
			(at -26.090118 -11.234674)
			(size 0.4318 0.4318)
			(layers "F.Cu" "F.Mask" "F.Paste")
			(net "PD_CPU1_EAR_N")
		)
		(pad "AJ18" smd circle
			(at -22.656038 -11.234674)
			(size 0.4318 0.4318)
			(layers "F.Cu" "F.Mask" "F.Paste")
			(net "SMB_DDR_GHJ_SCL_G_R")
		)
		(pad "AJ20" smd circle
			(at -20.938998 -11.234674)
			(size 0.4318 0.4318)
			(layers "F.Cu" "F.Mask" "F.Paste")
			(net "TP_CPU1_RSVD_227")
		)
		(pad "AJ22" smd circle
			(at -19.221958 -11.234674)
			(size 0.4318 0.4318)
			(layers "F.Cu" "F.Mask" "F.Paste")
			(net "GND")
		)
		(pad "AJ24" smd circle
			(at -17.504918 -11.234674)
			(size 0.4318 0.4318)
			(layers "F.Cu" "F.Mask" "F.Paste")
			(net "M_J_DQS_DN<7>")
		)
		(pad "AJ26" smd circle
			(at -15.787878 -11.234674)
			(size 0.4318 0.4318)
			(layers "F.Cu" "F.Mask" "F.Paste")
			(net "GND")
		)
		(pad "AJ28" smd circle
			(at -14.071092 -11.234674)
			(size 0.4318 0.4318)
			(layers "F.Cu" "F.Mask" "F.Paste")
			(net "GND")
		)
		(pad "AJ30" smd circle
			(at -12.354052 -11.234674)
			(size 0.4318 0.4318)
			(layers "F.Cu" "F.Mask" "F.Paste")
			(net "M_J_DQS_DN<6>")
		)
		(pad "AJ32" smd circle
			(at -10.637012 -11.234674)
			(size 0.4318 0.4318)
			(layers "F.Cu" "F.Mask" "F.Paste")
			(net "GND")
		)
		(pad "AJ34" smd circle
			(at -8.919972 -11.234674)
			(size 0.4318 0.4318)
			(layers "F.Cu" "F.Mask" "F.Paste")
			(net "GND")
		)
		(pad "AJ36" smd circle
			(at -7.202932 -11.234674)
			(size 0.4318 0.4318)
			(layers "F.Cu" "F.Mask" "F.Paste")
			(net "PVCCIN_CPU1")
		)
		(pad "AJ46" smd circle
			(at 2.910586 -13.034772)
			(size 0.4318 0.4318)
			(layers "F.Cu" "F.Mask" "F.Paste")
			(net "GND")
		)
		(pad "AJ48" smd circle
			(at 4.627626 -13.034772)
			(size 0.4318 0.4318)
			(layers "F.Cu" "F.Mask" "F.Paste")
			(net "GND")
		)
		(pad "AJ50" smd circle
			(at 6.344412 -13.034772)
			(size 0.4318 0.4318)
			(layers "F.Cu" "F.Mask" "F.Paste")
			(net "GND")
		)
		(pad "AJ52" smd circle
			(at 8.061452 -13.034772)
			(size 0.4318 0.4318)
			(layers "F.Cu" "F.Mask" "F.Paste")
			(net "GND")
		)
		(pad "AJ54" smd circle
			(at 9.778492 -13.034772)
			(size 0.4318 0.4318)
			(layers "F.Cu" "F.Mask" "F.Paste")
			(net "GND")
		)
		(pad "AJ56" smd circle
			(at 11.495532 -13.034772)
			(size 0.4318 0.4318)
			(layers "F.Cu" "F.Mask" "F.Paste")
			(net "TP_CPU1_RSVD_226")
		)
		(pad "AJ58" smd circle
			(at 13.212572 -13.034772)
			(size 0.4318 0.4318)
			(layers "F.Cu" "F.Mask" "F.Paste")
			(net "TP_CPU1_RSVD_225")
		)
		(pad "AJ60" smd circle
			(at 14.929612 -13.034772)
			(size 0.4318 0.4318)
			(layers "F.Cu" "F.Mask" "F.Paste")
			(net "TP_CPU1_RSVD_224")
		)
		(pad "AJ62" smd circle
			(at 16.646398 -13.034772)
			(size 0.4318 0.4318)
			(layers "F.Cu" "F.Mask" "F.Paste")
			(net "TP_CPU1_RSVD_223")
		)
		(pad "AJ64" smd circle
			(at 18.363438 -13.034772)
			(size 0.4318 0.4318)
			(layers "F.Cu" "F.Mask" "F.Paste")
			(net "M_G_CPU_VREF")
		)
		(pad "AJ66" smd circle
			(at 20.080478 -13.034772)
			(size 0.4318 0.4318)
			(layers "F.Cu" "F.Mask" "F.Paste")
			(net "GND")
		)
		(pad "AJ68" smd circle
			(at 21.797518 -13.034772)
			(size 0.4318 0.4318)
			(layers "F.Cu" "F.Mask" "F.Paste")
			(net "GND")
		)
		(pad "AJ70" smd circle
			(at 23.514558 -13.034772)
			(size 0.4318 0.4318)
			(layers "F.Cu" "F.Mask" "F.Paste")
			(net "TP_CPU1_RSVD_222")
		)
		(pad "AJ74" smd circle
			(at 26.948384 -13.034772)
			(size 0.4318 0.4318)
			(layers "F.Cu" "F.Mask" "F.Paste")
			(net "GND")
		)
		(pad "AJ76" smd circle
			(at 28.665424 -13.034772)
			(size 0.4318 0.4318)
			(layers "F.Cu" "F.Mask" "F.Paste")
			(net "M_J_DQ<3>")
		)
		(pad "AJ78" smd circle
			(at 30.382464 -13.034772)
			(size 0.4318 0.4318)
			(layers "F.Cu" "F.Mask" "F.Paste")
			(net "GND")
		)
		(pad "AJ80" smd circle
			(at 32.099504 -13.034772)
			(size 0.4318 0.4318)
			(layers "F.Cu" "F.Mask" "F.Paste")
			(net "M_H_DQ<12>")
		)
		(pad "AJ82" smd circle
			(at 33.816544 -13.034772)
			(size 0.4318 0.4318)
			(layers "F.Cu" "F.Mask" "F.Paste")
			(net "GND")
		)
		(pad "AJ84" smd circle
			(at 35.533584 -13.034772)
			(size 0.4318 0.4318)
			(layers "F.Cu" "F.Mask" "F.Paste")
			(net "M_G_DQS_DN<0>")
		)
		(pad "AJ86" smd custom
			(at 37.250624 -13.034772 270)
			(size 0.10795 0.10795)
			(layers "F.Cu" "F.Mask" "F.Paste")
			(net "GND")
			(options
				(clearance outline)
				(anchor circle)
			)
			(primitives
				(gr_poly
					(pts
						(arc
							(start 0.2159 -0.0381)
							(mid 0 -0.254)
							(end -0.2159 -0.0381)
						)
						(arc
							(start -0.2159 0.0381)
							(mid 0 0.254)
							(end 0.2159 0.0381)
						)
					)
					(width 0)
					(fill yes)
				)
			)
		)
		(pad "AK1" smd custom
			(at -37.250624 -10.739628 90)
			(size 0.10795 0.10795)
			(layers "F.Cu" "F.Mask" "F.Paste")
			(net "UPI_CPU1_CPU0_P0P0_DP<9>")
			(options
				(clearance outline)
				(anchor circle)
			)
			(primitives
				(gr_poly
					(pts
						(arc
							(start 0.2159 -0.0381)
							(mid 0 -0.254)
							(end -0.2159 -0.0381)
						)
						(arc
							(start -0.2159 0.0381)
							(mid 0 0.254)
							(end 0.2159 0.0381)
						)
					)
					(width 0)
					(fill yes)
				)
			)
		)
		(pad "AK3" smd circle
			(at -35.533584 -10.739628)
			(size 0.4318 0.4318)
			(layers "F.Cu" "F.Mask" "F.Paste")
			(net "UPI_CPU1_CPU0_P0P0_DN<10>")
		)
		(pad "AK5" smd circle
			(at -33.816544 -10.739628)
			(size 0.4318 0.4318)
			(layers "F.Cu" "F.Mask" "F.Paste")
			(net "UPI_CPU0_CPU1_P0P0_DN<7>")
		)
		(pad "AK7" smd circle
			(at -32.099504 -10.739628)
			(size 0.4318 0.4318)
			(layers "F.Cu" "F.Mask" "F.Paste")
			(net "UPI_CPU0_CPU1_P0P0_DP<8>")
		)
		(pad "AK9" smd circle
			(at -30.382464 -10.739628)
			(size 0.4318 0.4318)
			(layers "F.Cu" "F.Mask" "F.Paste")
			(net "GND")
		)
		(pad "AK11" smd circle
			(at -28.665424 -10.739628)
			(size 0.4318 0.4318)
			(layers "F.Cu" "F.Mask" "F.Paste")
			(net "H_CPU1_ERR1_G_N")
		)
		(pad "AK13" smd circle
			(at -26.948384 -10.739628)
			(size 0.4318 0.4318)
			(layers "F.Cu" "F.Mask" "F.Paste")
			(net "GND")
		)
		(pad "AK19" smd circle
			(at -21.797518 -10.739628)
			(size 0.4318 0.4318)
			(layers "F.Cu" "F.Mask" "F.Paste")
			(net "GND")
		)
		(pad "AK21" smd circle
			(at -20.080478 -10.739628)
			(size 0.4318 0.4318)
			(layers "F.Cu" "F.Mask" "F.Paste")
			(net "VSENSE_P1V8MCP_CPU1_SKT_VSEN")
		)
		(pad "AK23" smd circle
			(at -18.363438 -10.739628)
			(size 0.4318 0.4318)
			(layers "F.Cu" "F.Mask" "F.Paste")
			(net "GND")
		)
		(pad "AK25" smd circle
			(at -16.646398 -10.739628)
			(size 0.4318 0.4318)
			(layers "F.Cu" "F.Mask" "F.Paste")
			(net "GND")
		)
		(pad "AK27" smd circle
			(at -14.929612 -10.739628)
			(size 0.4318 0.4318)
			(layers "F.Cu" "F.Mask" "F.Paste")
			(net "CLK_322M_OSC_CPU1_RC_DP")
		)
		(pad "AK29" smd circle
			(at -13.212572 -10.739628)
			(size 0.4318 0.4318)
			(layers "F.Cu" "F.Mask" "F.Paste")
			(net "GND")
		)
		(pad "AK31" smd circle
			(at -11.495532 -10.739628)
			(size 0.4318 0.4318)
			(layers "F.Cu" "F.Mask" "F.Paste")
			(net "GND")
		)
		(pad "AK33" smd circle
			(at -9.778492 -10.739628)
			(size 0.4318 0.4318)
			(layers "F.Cu" "F.Mask" "F.Paste")
			(net "GND")
		)
		(pad "AK35" smd circle
			(at -8.061452 -10.739628)
			(size 0.4318 0.4318)
			(layers "F.Cu" "F.Mask" "F.Paste")
			(net "PVCCIN_CPU1")
		)
		(pad "AK45" smd circle
			(at 2.052066 -12.539726)
			(size 0.508 0.508)
			(layers "F.Cu" "F.Mask" "F.Paste")
			(net "PVCCIN_CPU1")
		)
		(pad "AK47" smd circle
			(at 3.769106 -12.539726)
			(size 0.4318 0.4318)
			(layers "F.Cu" "F.Mask" "F.Paste")
			(net "PVCCIN_CPU1")
		)
		(pad "AK49" smd circle
			(at 5.485892 -12.539726)
			(size 0.4318 0.4318)
			(layers "F.Cu" "F.Mask" "F.Paste")
			(net "PVCCIN_CPU1")
		)
		(pad "AK51" smd circle
			(at 7.202932 -12.539726)
			(size 0.4318 0.4318)
			(layers "F.Cu" "F.Mask" "F.Paste")
			(net "PVCCIN_CPU1")
		)
		(pad "AK53" smd circle
			(at 8.919972 -12.539726)
			(size 0.4318 0.4318)
			(layers "F.Cu" "F.Mask" "F.Paste")
			(net "PVCCIN_CPU1")
		)
		(pad "AK55" smd circle
			(at 10.637012 -12.539726)
			(size 0.4318 0.4318)
			(layers "F.Cu" "F.Mask" "F.Paste")
			(net "GND")
		)
		(pad "AK57" smd circle
			(at 12.354052 -12.539726)
			(size 0.4318 0.4318)
			(layers "F.Cu" "F.Mask" "F.Paste")
			(net "TP_CPU1_RSVD_219")
		)
		(pad "AK59" smd circle
			(at 14.071092 -12.539726)
			(size 0.4318 0.4318)
			(layers "F.Cu" "F.Mask" "F.Paste")
			(net "TP_CPU1_RSVD_218")
		)
		(pad "AK61" smd circle
			(at 15.787878 -12.539726)
			(size 0.4318 0.4318)
			(layers "F.Cu" "F.Mask" "F.Paste")
			(net "TP_CPU1_RSVD_217")
		)
		(pad "AK63" smd circle
			(at 17.504918 -12.539726)
			(size 0.4318 0.4318)
			(layers "F.Cu" "F.Mask" "F.Paste")
			(net "M_H_CPU_VREF")
		)
		(pad "AK65" smd circle
			(at 19.221958 -12.539726)
			(size 0.4318 0.4318)
			(layers "F.Cu" "F.Mask" "F.Paste")
			(net "GND")
		)
		(pad "AK67" smd circle
			(at 20.938998 -12.539726)
			(size 0.4318 0.4318)
			(layers "F.Cu" "F.Mask" "F.Paste")
			(net "GND")
		)
		(pad "AK69" smd circle
			(at 22.656038 -12.539726)
			(size 0.4318 0.4318)
			(layers "F.Cu" "F.Mask" "F.Paste")
			(net "TP_CPU1_RSVD_216")
		)
		(pad "AK73" smd circle
			(at 26.090118 -12.539726)
			(size 0.4318 0.4318)
			(layers "F.Cu" "F.Mask" "F.Paste")
			(net "GND")
		)
		(pad "AK75" smd circle
			(at 27.806904 -12.539726)
			(size 0.4318 0.4318)
			(layers "F.Cu" "F.Mask" "F.Paste")
			(net "M_J_DQ<7>")
		)
		(pad "AK77" smd circle
			(at 29.523944 -12.539726)
			(size 0.4318 0.4318)
			(layers "F.Cu" "F.Mask" "F.Paste")
			(net "M_J_DQ<2>")
		)
		(pad "AK79" smd circle
			(at 31.240984 -12.539726)
			(size 0.4318 0.4318)
			(layers "F.Cu" "F.Mask" "F.Paste")
			(net "GND")
		)
		(pad "AK81" smd circle
			(at 32.958024 -12.539726)
			(size 0.4318 0.4318)
			(layers "F.Cu" "F.Mask" "F.Paste")
			(net "GND")
		)
		(pad "AK83" smd circle
			(at 34.675064 -12.539726)
			(size 0.4318 0.4318)
			(layers "F.Cu" "F.Mask" "F.Paste")
			(net "GND")
		)
		(pad "AK85" smd circle
			(at 36.392104 -12.539726)
			(size 0.4318 0.4318)
			(layers "F.Cu" "F.Mask" "F.Paste")
			(net "GND")
		)
		(pad "AL2" smd circle
			(at -36.392104 -10.244074)
			(size 0.4318 0.4318)
			(layers "F.Cu" "F.Mask" "F.Paste")
			(net "UPI_CPU1_CPU0_P0P0_DN<9>")
		)
		(pad "AL4" smd circle
			(at -34.675064 -10.244074)
			(size 0.4318 0.4318)
			(layers "F.Cu" "F.Mask" "F.Paste")
			(net "GND")
		)
		(pad "AL6" smd circle
			(at -32.958024 -10.244074)
			(size 0.4318 0.4318)
			(layers "F.Cu" "F.Mask" "F.Paste")
			(net "UPI_CPU0_CPU1_P0P0_DP<7>")
		)
		(pad "AL8" smd circle
			(at -31.240984 -10.244074)
			(size 0.4318 0.4318)
			(layers "F.Cu" "F.Mask" "F.Paste")
			(net "UPI_CPU0_CPU1_P0P0_DN<9>")
		)
		(pad "AL10" smd circle
			(at -29.523944 -10.244074)
			(size 0.4318 0.4318)
			(layers "F.Cu" "F.Mask" "F.Paste")
			(net "GND")
		)
		(pad "AL12" smd circle
			(at -27.806904 -10.244074)
			(size 0.4318 0.4318)
			(layers "F.Cu" "F.Mask" "F.Paste")
			(net "H_CPU1_ERR2_G_N")
		)
		(pad "AL14" smd circle
			(at -26.090118 -10.244074)
			(size 0.4318 0.4318)
			(layers "F.Cu" "F.Mask" "F.Paste")
			(net "H_CPU1_CATERR_G_N")
		)
		(pad "AL18" smd circle
			(at -22.656038 -10.244074)
			(size 0.4318 0.4318)
			(layers "F.Cu" "F.Mask" "F.Paste")
			(net "SMB_CPU1_PE_HP_GTL_SDA")
		)
		(pad "AL20" smd circle
			(at -20.938998 -10.244074)
			(size 0.4318 0.4318)
			(layers "F.Cu" "F.Mask" "F.Paste")
			(net "VSENSE_P1V8MCP_CPU1_SKT_VRTN")
		)
		(pad "AL22" smd circle
			(at -19.221958 -10.244074)
			(size 0.4318 0.4318)
			(layers "F.Cu" "F.Mask" "F.Paste")
			(net "TP_CPU1_RSVD_214")
		)
		(pad "AL24" smd circle
			(at -17.504918 -10.244074)
			(size 0.4318 0.4318)
			(layers "F.Cu" "F.Mask" "F.Paste")
			(net "GND")
		)
		(pad "AL26" smd circle
			(at -15.787878 -10.244074)
			(size 0.4318 0.4318)
			(layers "F.Cu" "F.Mask" "F.Paste")
			(net "CLK_322M_OSC_CPU1_RC_DN")
		)
		(pad "AL28" smd circle
			(at -14.071092 -10.244074)
			(size 0.4318 0.4318)
			(layers "F.Cu" "F.Mask" "F.Paste")
			(net "PVCCIO_CPU1")
		)
		(pad "AL30" smd circle
			(at -12.354052 -10.244074)
			(size 0.4318 0.4318)
			(layers "F.Cu" "F.Mask" "F.Paste")
			(net "GND")
		)
		(pad "AL32" smd circle
			(at -10.637012 -10.244074)
			(size 0.4318 0.4318)
			(layers "F.Cu" "F.Mask" "F.Paste")
			(net "GND")
		)
		(pad "AL34" smd circle
			(at -8.919972 -10.244074)
			(size 0.4318 0.4318)
			(layers "F.Cu" "F.Mask" "F.Paste")
			(net "PVCCIN_CPU1")
		)
		(pad "AL46" smd circle
			(at 2.910586 -12.044172)
			(size 0.508 0.508)
			(layers "F.Cu" "F.Mask" "F.Paste")
			(net "PVCCIN_CPU1")
		)
		(pad "AL48" smd circle
			(at 4.627626 -12.044172)
			(size 0.508 0.508)
			(layers "F.Cu" "F.Mask" "F.Paste")
			(net "PVCCIN_CPU1")
		)
		(pad "AL50" smd circle
			(at 6.344412 -12.044172)
			(size 0.508 0.508)
			(layers "F.Cu" "F.Mask" "F.Paste")
			(net "PVCCIN_CPU1")
		)
		(pad "AL52" smd circle
			(at 8.061452 -12.044172)
			(size 0.508 0.508)
			(layers "F.Cu" "F.Mask" "F.Paste")
			(net "PVCCIN_CPU1")
		)
		(pad "AL54" smd circle
			(at 9.778492 -12.044172)
			(size 0.4318 0.4318)
			(layers "F.Cu" "F.Mask" "F.Paste")
			(net "PVCCIN_CPU1")
		)
		(pad "AL56" smd circle
			(at 11.495532 -12.044172)
			(size 0.4318 0.4318)
			(layers "F.Cu" "F.Mask" "F.Paste")
			(net "GND")
		)
		(pad "AL58" smd circle
			(at 13.212572 -12.044172)
			(size 0.4318 0.4318)
			(layers "F.Cu" "F.Mask" "F.Paste")
			(net "TP_CPU1_RSVD_212")
		)
		(pad "AL60" smd circle
			(at 14.929612 -12.044172)
			(size 0.4318 0.4318)
			(layers "F.Cu" "F.Mask" "F.Paste")
			(net "TP_CPU1_RSVD_211")
		)
		(pad "AL62" smd circle
			(at 16.646398 -12.044172)
			(size 0.4318 0.4318)
			(layers "F.Cu" "F.Mask" "F.Paste")
			(net "TP_CPU1_RSVD_210")
		)
		(pad "AL64" smd circle
			(at 18.363438 -12.044172)
			(size 0.4318 0.4318)
			(layers "F.Cu" "F.Mask" "F.Paste")
			(net "GND")
		)
		(pad "AL66" smd circle
			(at 20.080478 -12.044172)
			(size 0.4318 0.4318)
			(layers "F.Cu" "F.Mask" "F.Paste")
			(net "M_J_DQS_DN<12>")
		)
		(pad "AL68" smd circle
			(at 21.797518 -12.044172)
			(size 0.4318 0.4318)
			(layers "F.Cu" "F.Mask" "F.Paste")
			(net "GND")
		)
		(pad "AL74" smd circle
			(at 26.948384 -12.044172)
			(size 0.4318 0.4318)
			(layers "F.Cu" "F.Mask" "F.Paste")
			(net "M_J_DQS_DN<0>")
		)
		(pad "AL76" smd circle
			(at 28.665424 -12.044172)
			(size 0.4318 0.4318)
			(layers "F.Cu" "F.Mask" "F.Paste")
			(net "GND")
		)
		(pad "AL78" smd circle
			(at 30.382464 -12.044172)
			(size 0.4318 0.4318)
			(layers "F.Cu" "F.Mask" "F.Paste")
			(net "GND")
		)
		(pad "AL80" smd circle
			(at 32.099504 -12.044172)
			(size 0.4318 0.4318)
			(layers "F.Cu" "F.Mask" "F.Paste")
			(net "GND")
		)
		(pad "AL82" smd circle
			(at 33.816544 -12.044172)
			(size 0.4318 0.4318)
			(layers "F.Cu" "F.Mask" "F.Paste")
			(net "GND")
		)
		(pad "AL84" smd circle
			(at 35.533584 -12.044172)
			(size 0.4318 0.4318)
			(layers "F.Cu" "F.Mask" "F.Paste")
			(net "M_G_DQS_DN<9>")
		)
		(pad "AL86" smd custom
			(at 37.250624 -12.044172 270)
			(size 0.10795 0.10795)
			(layers "F.Cu" "F.Mask" "F.Paste")
			(net "GND")
			(options
				(clearance outline)
				(anchor circle)
			)
			(primitives
				(gr_poly
					(pts
						(arc
							(start 0.2159 -0.0381)
							(mid 0 -0.254)
							(end -0.2159 -0.0381)
						)
						(arc
							(start -0.2159 0.0381)
							(mid 0 0.254)
							(end 0.2159 0.0381)
						)
					)
					(width 0)
					(fill yes)
				)
			)
		)
		(pad "AM1" smd custom
			(at -37.250624 -9.749028 90)
			(size 0.10795 0.10795)
			(layers "F.Cu" "F.Mask" "F.Paste")
			(net "GND")
			(options
				(clearance outline)
				(anchor circle)
			)
			(primitives
				(gr_poly
					(pts
						(arc
							(start 0.2159 -0.0381)
							(mid 0 -0.254)
							(end -0.2159 -0.0381)
						)
						(arc
							(start -0.2159 0.0381)
							(mid 0 0.254)
							(end 0.2159 0.0381)
						)
					)
					(width 0)
					(fill yes)
				)
			)
		)
		(pad "AM3" smd circle
			(at -35.533584 -9.749028)
			(size 0.4318 0.4318)
			(layers "F.Cu" "F.Mask" "F.Paste")
			(net "UPI_CPU1_CPU0_P0P0_DP<10>")
		)
		(pad "AM5" smd circle
			(at -33.816544 -9.749028)
			(size 0.4318 0.4318)
			(layers "F.Cu" "F.Mask" "F.Paste")
			(net "PVCCIO_CPU1")
		)
		(pad "AM7" smd circle
			(at -32.099504 -9.749028)
			(size 0.4318 0.4318)
			(layers "F.Cu" "F.Mask" "F.Paste")
			(net "UPI_CPU0_CPU1_P0P0_DN<8>")
		)
		(pad "AM9" smd circle
			(at -30.382464 -9.749028)
			(size 0.4318 0.4318)
			(layers "F.Cu" "F.Mask" "F.Paste")
			(net "UPI_CPU0_CPU1_P0P0_DP<9>")
		)
		(pad "AM11" smd circle
			(at -28.665424 -9.749028)
			(size 0.4318 0.4318)
			(layers "F.Cu" "F.Mask" "F.Paste")
			(net "PU_CPU1_TSC_SYNC")
		)
		(pad "AM13" smd circle
			(at -26.948384 -9.749028)
			(size 0.4318 0.4318)
			(layers "F.Cu" "F.Mask" "F.Paste")
			(net "TP_CPU1_RSVD_TEST_3")
		)
		(pad "AM19" smd circle
			(at -21.797518 -9.749028)
			(size 0.4318 0.4318)
			(layers "F.Cu" "F.Mask" "F.Paste")
			(net "SMB_CPU1_PE_HP_GTL_SCL")
		)
		(pad "AM21" smd circle
			(at -20.080478 -9.749028)
			(size 0.4318 0.4318)
			(layers "F.Cu" "F.Mask" "F.Paste")
			(net "PVCCMCP_CPU1")
		)
		(pad "AM23" smd circle
			(at -18.363438 -9.749028)
			(size 0.4318 0.4318)
			(layers "F.Cu" "F.Mask" "F.Paste")
			(net "TP_CPU1_RSVD_208")
		)
		(pad "AM25" smd circle
			(at -16.646398 -9.749028)
			(size 0.4318 0.4318)
			(layers "F.Cu" "F.Mask" "F.Paste")
			(net "PVCCMCP_CPU1")
		)
		(pad "AM27" smd circle
			(at -14.929612 -9.749028)
			(size 0.4318 0.4318)
			(layers "F.Cu" "F.Mask" "F.Paste")
			(net "CLK_100M_CPU1_RC_REFCLK0_DP")
		)
		(pad "AM29" smd circle
			(at -13.212572 -9.749028)
			(size 0.4318 0.4318)
			(layers "F.Cu" "F.Mask" "F.Paste")
			(net "PVCCIO_CPU1")
		)
		(pad "AM31" smd circle
			(at -11.495532 -9.749028)
			(size 0.4318 0.4318)
			(layers "F.Cu" "F.Mask" "F.Paste")
			(net "GND")
		)
		(pad "AM33" smd circle
			(at -9.778492 -9.749028)
			(size 0.4318 0.4318)
			(layers "F.Cu" "F.Mask" "F.Paste")
			(net "PVCCIN_CPU1")
		)
		(pad "AM53" smd circle
			(at 8.919972 -11.549126)
			(size 0.508 0.508)
			(layers "F.Cu" "F.Mask" "F.Paste")
			(net "PVCCIN_CPU1")
		)
		(pad "AM55" smd circle
			(at 10.637012 -11.549126)
			(size 0.4318 0.4318)
			(layers "F.Cu" "F.Mask" "F.Paste")
			(net "PVCCIN_CPU1")
		)
		(pad "AM57" smd circle
			(at 12.354052 -11.549126)
			(size 0.4318 0.4318)
			(layers "F.Cu" "F.Mask" "F.Paste")
			(net "GND")
		)
		(pad "AM59" smd circle
			(at 14.071092 -11.549126)
			(size 0.4318 0.4318)
			(layers "F.Cu" "F.Mask" "F.Paste")
			(net "TP_CPU1_RSVD_205")
		)
		(pad "AM61" smd circle
			(at 15.787878 -11.549126)
			(size 0.4318 0.4318)
			(layers "F.Cu" "F.Mask" "F.Paste")
			(net "TP_CPU1_RSVD_204")
		)
		(pad "AM63" smd circle
			(at 17.504918 -11.549126)
			(size 0.4318 0.4318)
			(layers "F.Cu" "F.Mask" "F.Paste")
			(net "GND")
		)
		(pad "AM65" smd circle
			(at 19.221958 -11.549126)
			(size 0.4318 0.4318)
			(layers "F.Cu" "F.Mask" "F.Paste")
			(net "M_J_DQ<30>")
		)
		(pad "AM67" smd circle
			(at 20.938998 -11.549126)
			(size 0.4318 0.4318)
			(layers "F.Cu" "F.Mask" "F.Paste")
			(net "M_J_DQ<24>")
		)
		(pad "AM69" smd circle
			(at 22.656038 -11.549126)
			(size 0.4318 0.4318)
			(layers "F.Cu" "F.Mask" "F.Paste")
			(net "GND")
		)
		(pad "AM73" smd circle
			(at 26.090118 -11.549126)
			(size 0.4318 0.4318)
			(layers "F.Cu" "F.Mask" "F.Paste")
			(net "GND")
		)
		(pad "AM75" smd circle
			(at 27.806904 -11.549126)
			(size 0.4318 0.4318)
			(layers "F.Cu" "F.Mask" "F.Paste")
			(net "M_J_DQS_DP<0>")
		)
		(pad "AM77" smd circle
			(at 29.523944 -11.549126)
			(size 0.4318 0.4318)
			(layers "F.Cu" "F.Mask" "F.Paste")
			(net "M_J_DQ<6>")
		)
		(pad "AM79" smd circle
			(at 31.240984 -11.549126)
			(size 0.4318 0.4318)
			(layers "F.Cu" "F.Mask" "F.Paste")
			(net "GND")
		)
		(pad "AM81" smd circle
			(at 32.958024 -11.549126)
			(size 0.4318 0.4318)
			(layers "F.Cu" "F.Mask" "F.Paste")
			(net "M_H_DQ<3>")
		)
		(pad "AM83" smd circle
			(at 34.675064 -11.549126)
			(size 0.4318 0.4318)
			(layers "F.Cu" "F.Mask" "F.Paste")
			(net "GND")
		)
		(pad "AM85" smd circle
			(at 36.392104 -11.549126)
			(size 0.4318 0.4318)
			(layers "F.Cu" "F.Mask" "F.Paste")
			(net "M_G_DQS_DP<9>")
		)
		(pad "AN2" smd circle
			(at -36.392104 -9.253474)
			(size 0.4318 0.4318)
			(layers "F.Cu" "F.Mask" "F.Paste")
			(net "GND")
		)
		(pad "AN4" smd circle
			(at -34.675064 -9.253474)
			(size 0.4318 0.4318)
			(layers "F.Cu" "F.Mask" "F.Paste")
			(net "UPI_CPU1_CPU0_P0P0_DP<11>")
		)
		(pad "AN6" smd circle
			(at -32.958024 -9.253474)
			(size 0.4318 0.4318)
			(layers "F.Cu" "F.Mask" "F.Paste")
			(net "GND")
		)
		(pad "AN8" smd circle
			(at -31.240984 -9.253474)
			(size 0.4318 0.4318)
			(layers "F.Cu" "F.Mask" "F.Paste")
			(net "UPI_CPU0_CPU1_P0P0_DP<10>")
		)
		(pad "AN10" smd circle
			(at -29.523944 -9.253474)
			(size 0.4318 0.4318)
			(layers "F.Cu" "F.Mask" "F.Paste")
			(net "PVCCIO_CPU1")
		)
		(pad "AN12" smd circle
			(at -27.806904 -9.253474)
			(size 0.4318 0.4318)
			(layers "F.Cu" "F.Mask" "F.Paste")
			(net "TP_CPU1_RSVD_TEST_4")
		)
		(pad "AN14" smd circle
			(at -26.090118 -9.253474)
			(size 0.4318 0.4318)
			(layers "F.Cu" "F.Mask" "F.Paste")
			(net "TP_CPU1_RSVD_TEST_5")
		)
		(pad "AN18" smd circle
			(at -22.656038 -9.253474)
			(size 0.4318 0.4318)
			(layers "F.Cu" "F.Mask" "F.Paste")
			(net "PVCCMCP_CPU1")
		)
		(pad "AN20" smd circle
			(at -20.938998 -9.253474)
			(size 0.4318 0.4318)
			(layers "F.Cu" "F.Mask" "F.Paste")
			(net "H_CPU1_MSMI_G_N")
		)
		(pad "AN22" smd circle
			(at -19.221958 -9.253474)
			(size 0.4318 0.4318)
			(layers "F.Cu" "F.Mask" "F.Paste")
			(net "PVCCMCP_CPU1")
		)
		(pad "AN24" smd circle
			(at -17.504918 -9.253474)
			(size 0.4318 0.4318)
			(layers "F.Cu" "F.Mask" "F.Paste")
			(net "PVCCMCP_CPU1")
		)
		(pad "AN26" smd circle
			(at -15.787878 -9.253474)
			(size 0.4318 0.4318)
			(layers "F.Cu" "F.Mask" "F.Paste")
			(net "PVCCMCP_CPU1")
		)
		(pad "AN28" smd circle
			(at -14.071092 -9.253474)
			(size 0.4318 0.4318)
			(layers "F.Cu" "F.Mask" "F.Paste")
			(net "GND")
		)
		(pad "AN30" smd circle
			(at -12.354052 -9.253474)
			(size 0.4318 0.4318)
			(layers "F.Cu" "F.Mask" "F.Paste")
			(net "PWRGD_CPU1_DRAMPWROK_GHJ_G")
		)
		(pad "AN32" smd circle
			(at -10.637012 -9.253474)
			(size 0.4318 0.4318)
			(layers "F.Cu" "F.Mask" "F.Paste")
			(net "PVCCIN_CPU1")
		)
		(pad "AN54" smd circle
			(at 9.778492 -11.053572)
			(size 0.508 0.508)
			(layers "F.Cu" "F.Mask" "F.Paste")
			(net "PVCCIN_CPU1")
		)
		(pad "AN56" smd circle
			(at 11.495532 -11.053572)
			(size 0.4318 0.4318)
			(layers "F.Cu" "F.Mask" "F.Paste")
			(net "PVCCIN_CPU1")
		)
		(pad "AN58" smd circle
			(at 13.212572 -11.053572)
			(size 0.4318 0.4318)
			(layers "F.Cu" "F.Mask" "F.Paste")
			(net "GND")
		)
		(pad "AN60" smd circle
			(at 14.929612 -11.053572)
			(size 0.4318 0.4318)
			(layers "F.Cu" "F.Mask" "F.Paste")
			(net "TP_CPU1_RSVD_199")
		)
		(pad "AN62" smd circle
			(at 16.646398 -11.053572)
			(size 0.4318 0.4318)
			(layers "F.Cu" "F.Mask" "F.Paste")
			(net "TP_CPU1_RSVD_198")
		)
		(pad "AN64" smd circle
			(at 18.363438 -11.053572)
			(size 0.4318 0.4318)
			(layers "F.Cu" "F.Mask" "F.Paste")
			(net "M_J_DQ<26>")
		)
		(pad "AN66" smd circle
			(at 20.080478 -11.053572)
			(size 0.4318 0.4318)
			(layers "F.Cu" "F.Mask" "F.Paste")
			(net "M_J_DQS_DP<12>")
		)
		(pad "AN68" smd circle
			(at 21.797518 -11.053572)
			(size 0.4318 0.4318)
			(layers "F.Cu" "F.Mask" "F.Paste")
			(net "M_J_DQ<28>")
		)
		(pad "AN74" smd circle
			(at 26.948384 -11.053572)
			(size 0.4318 0.4318)
			(layers "F.Cu" "F.Mask" "F.Paste")
			(net "M_J_DQ<1>")
		)
		(pad "AN76" smd circle
			(at 28.665424 -11.053572)
			(size 0.4318 0.4318)
			(layers "F.Cu" "F.Mask" "F.Paste")
			(net "M_J_DQS_DP<9>")
		)
		(pad "AN78" smd circle
			(at 30.382464 -11.053572)
			(size 0.4318 0.4318)
			(layers "F.Cu" "F.Mask" "F.Paste")
			(net "GND")
		)
		(pad "AN80" smd circle
			(at 32.099504 -11.053572)
			(size 0.4318 0.4318)
			(layers "F.Cu" "F.Mask" "F.Paste")
			(net "M_H_DQ<7>")
		)
		(pad "AN82" smd circle
			(at 33.816544 -11.053572)
			(size 0.4318 0.4318)
			(layers "F.Cu" "F.Mask" "F.Paste")
			(net "M_H_DQ<2>")
		)
		(pad "AN84" smd circle
			(at 35.533584 -11.053572)
			(size 0.4318 0.4318)
			(layers "F.Cu" "F.Mask" "F.Paste")
			(net "M_G_DQ<1>")
		)
		(pad "AN86" smd custom
			(at 37.250624 -11.053572 270)
			(size 0.10795 0.10795)
			(layers "F.Cu" "F.Mask" "F.Paste")
			(net "M_G_DQ<0>")
			(options
				(clearance outline)
				(anchor circle)
			)
			(primitives
				(gr_poly
					(pts
						(arc
							(start 0.2159 -0.0381)
							(mid 0 -0.254)
							(end -0.2159 -0.0381)
						)
						(arc
							(start -0.2159 0.0381)
							(mid 0 0.254)
							(end 0.2159 0.0381)
						)
					)
					(width 0)
					(fill yes)
				)
			)
		)
		(pad "AP1" smd custom
			(at -37.250624 -8.758428 90)
			(size 0.10795 0.10795)
			(layers "F.Cu" "F.Mask" "F.Paste")
			(net "UPI_CPU1_CPU0_P0P0_DN<12>")
			(options
				(clearance outline)
				(anchor circle)
			)
			(primitives
				(gr_poly
					(pts
						(arc
							(start 0.2159 -0.0381)
							(mid 0 -0.254)
							(end -0.2159 -0.0381)
						)
						(arc
							(start -0.2159 0.0381)
							(mid 0 0.254)
							(end 0.2159 0.0381)
						)
					)
					(width 0)
					(fill yes)
				)
			)
		)
		(pad "AP3" smd circle
			(at -35.533584 -8.758428)
			(size 0.4318 0.4318)
			(layers "F.Cu" "F.Mask" "F.Paste")
			(net "UPI_CPU1_CPU0_P0P0_DN<11>")
		)
		(pad "AP5" smd circle
			(at -33.816544 -8.758428)
			(size 0.4318 0.4318)
			(layers "F.Cu" "F.Mask" "F.Paste")
			(net "GND")
		)
		(pad "AP7" smd circle
			(at -32.099504 -8.758428)
			(size 0.4318 0.4318)
			(layers "F.Cu" "F.Mask" "F.Paste")
			(net "UPI_CPU0_CPU1_P0P0_DN<10>")
		)
		(pad "AP9" smd circle
			(at -30.382464 -8.758428)
			(size 0.4318 0.4318)
			(layers "F.Cu" "F.Mask" "F.Paste")
			(net "GND")
		)
		(pad "AP11" smd circle
			(at -28.665424 -8.758428)
			(size 0.4318 0.4318)
			(layers "F.Cu" "F.Mask" "F.Paste")
			(net "TP_CPU1_NMI")
		)
		(pad "AP13" smd circle
			(at -26.948384 -8.758428)
			(size 0.4318 0.4318)
			(layers "F.Cu" "F.Mask" "F.Paste")
			(net "GND")
		)
		(pad "AP17" smd circle
			(at -23.514558 -8.758428)
			(size 0.4318 0.4318)
			(layers "F.Cu" "F.Mask" "F.Paste")
			(net "XDP_CPU_PWR_DEBUG_N")
		)
		(pad "AP19" smd circle
			(at -21.797518 -8.758428)
			(size 0.4318 0.4318)
			(layers "F.Cu" "F.Mask" "F.Paste")
			(net "GND")
		)
		(pad "AP21" smd circle
			(at -20.080478 -8.758428)
			(size 0.4318 0.4318)
			(layers "F.Cu" "F.Mask" "F.Paste")
			(net "RST_CPU1_G_N")
		)
		(pad "AP23" smd circle
			(at -18.363438 -8.758428)
			(size 0.4318 0.4318)
			(layers "F.Cu" "F.Mask" "F.Paste")
			(net "PVCCMCP_CPU1")
		)
		(pad "AP25" smd circle
			(at -16.646398 -8.758428)
			(size 0.4318 0.4318)
			(layers "F.Cu" "F.Mask" "F.Paste")
			(net "PVCCMCP_CPU1")
		)
		(pad "AP27" smd circle
			(at -14.929612 -8.758428)
			(size 0.4318 0.4318)
			(layers "F.Cu" "F.Mask" "F.Paste")
			(net "CLK_100M_CPU1_RC_REFCLK0_DN")
		)
		(pad "AP29" smd circle
			(at -13.212572 -8.758428)
			(size 0.4318 0.4318)
			(layers "F.Cu" "F.Mask" "F.Paste")
			(net "A_CPU1_UPI01_RBIAS")
		)
		(pad "AP31" smd circle
			(at -11.495532 -8.758428)
			(size 0.4318 0.4318)
			(layers "F.Cu" "F.Mask" "F.Paste")
			(net "GND")
		)
		(pad "AP55" smd circle
			(at 10.637012 -10.558526)
			(size 0.508 0.508)
			(layers "F.Cu" "F.Mask" "F.Paste")
			(net "PVCCIN_CPU1")
		)
		(pad "AP57" smd circle
			(at 12.354052 -10.558526)
			(size 0.4318 0.4318)
			(layers "F.Cu" "F.Mask" "F.Paste")
			(net "PVCCIN_CPU1")
		)
		(pad "AP59" smd circle
			(at 14.071092 -10.558526)
			(size 0.4318 0.4318)
			(layers "F.Cu" "F.Mask" "F.Paste")
			(net "GND")
		)
		(pad "AP61" smd circle
			(at 15.787878 -10.558526)
			(size 0.4318 0.4318)
			(layers "F.Cu" "F.Mask" "F.Paste")
			(net "TP_CPU1_RSVD_194")
		)
		(pad "AP63" smd circle
			(at 17.504918 -10.558526)
			(size 0.4318 0.4318)
			(layers "F.Cu" "F.Mask" "F.Paste")
			(net "GND")
		)
		(pad "AP65" smd circle
			(at 19.221958 -10.558526)
			(size 0.4318 0.4318)
			(layers "F.Cu" "F.Mask" "F.Paste")
			(net "GND")
		)
		(pad "AP67" smd circle
			(at 20.938998 -10.558526)
			(size 0.4318 0.4318)
			(layers "F.Cu" "F.Mask" "F.Paste")
			(net "GND")
		)
		(pad "AP69" smd circle
			(at 22.656038 -10.558526)
			(size 0.4318 0.4318)
			(layers "F.Cu" "F.Mask" "F.Paste")
			(net "GND")
		)
		(pad "AP73" smd circle
			(at 26.090118 -10.558526)
			(size 0.4318 0.4318)
			(layers "F.Cu" "F.Mask" "F.Paste")
			(net "GND")
		)
		(pad "AP75" smd circle
			(at 27.806904 -10.558526)
			(size 0.4318 0.4318)
			(layers "F.Cu" "F.Mask" "F.Paste")
			(net "GND")
		)
		(pad "AP77" smd circle
			(at 29.523944 -10.558526)
			(size 0.4318 0.4318)
			(layers "F.Cu" "F.Mask" "F.Paste")
			(net "M_J_DQS_DN<9>")
		)
		(pad "AP79" smd circle
			(at 31.240984 -10.558526)
			(size 0.4318 0.4318)
			(layers "F.Cu" "F.Mask" "F.Paste")
			(net "M_H_DQS_DN<0>")
		)
		(pad "AP81" smd circle
			(at 32.958024 -10.558526)
			(size 0.4318 0.4318)
			(layers "F.Cu" "F.Mask" "F.Paste")
			(net "GND")
		)
		(pad "AP83" smd circle
			(at 34.675064 -10.558526)
			(size 0.4318 0.4318)
			(layers "F.Cu" "F.Mask" "F.Paste")
			(net "GND")
		)
		(pad "AP85" smd circle
			(at 36.392104 -10.558526)
			(size 0.4318 0.4318)
			(layers "F.Cu" "F.Mask" "F.Paste")
			(net "GND")
		)
		(pad "AR2" smd circle
			(at -36.392104 -8.262874)
			(size 0.4318 0.4318)
			(layers "F.Cu" "F.Mask" "F.Paste")
			(net "UPI_CPU1_CPU0_P0P0_DN<13>")
		)
		(pad "AR4" smd circle
			(at -34.675064 -8.262874)
			(size 0.4318 0.4318)
			(layers "F.Cu" "F.Mask" "F.Paste")
			(net "UPI_CPU1_CPU0_P0P0_DN<14>")
		)
		(pad "AR6" smd circle
			(at -32.958024 -8.262874)
			(size 0.4318 0.4318)
			(layers "F.Cu" "F.Mask" "F.Paste")
			(net "GND")
		)
		(pad "AR8" smd circle
			(at -31.240984 -8.262874)
			(size 0.4318 0.4318)
			(layers "F.Cu" "F.Mask" "F.Paste")
			(net "UPI_CPU0_CPU1_P0P0_DP<11>")
		)
		(pad "AR10" smd circle
			(at -29.523944 -8.262874)
			(size 0.4318 0.4318)
			(layers "F.Cu" "F.Mask" "F.Paste")
			(net "GND")
		)
		(pad "AR12" smd circle
			(at -27.806904 -8.262874)
			(size 0.4318 0.4318)
			(layers "F.Cu" "F.Mask" "F.Paste")
			(net "XDP_CPU_PREQ_N")
		)
		(pad "AR14" smd circle
			(at -26.090118 -8.262874)
			(size 0.4318 0.4318)
			(layers "F.Cu" "F.Mask" "F.Paste")
			(net "H_PM_SYNC_GTL_R2")
		)
		(pad "AR16" smd circle
			(at -24.373078 -8.262874)
			(size 0.4318 0.4318)
			(layers "F.Cu" "F.Mask" "F.Paste")
			(net "TP_CPU1_TEST_6")
		)
		(pad "AR18" smd circle
			(at -22.656038 -8.262874)
			(size 0.4318 0.4318)
			(layers "F.Cu" "F.Mask" "F.Paste")
			(net "PU_CPU1_SAFE_MODE_BOOT")
		)
		(pad "AR20" smd circle
			(at -20.938998 -8.262874)
			(size 0.4318 0.4318)
			(layers "F.Cu" "F.Mask" "F.Paste")
			(net "PVCCMCP_CPU1")
		)
		(pad "AR22" smd circle
			(at -19.221958 -8.262874)
			(size 0.4318 0.4318)
			(layers "F.Cu" "F.Mask" "F.Paste")
			(net "PVCCMCP_CPU1")
		)
		(pad "AR24" smd circle
			(at -17.504918 -8.262874)
			(size 0.4318 0.4318)
			(layers "F.Cu" "F.Mask" "F.Paste")
			(net "GND")
		)
		(pad "AR26" smd circle
			(at -15.787878 -8.262874)
			(size 0.4318 0.4318)
			(layers "F.Cu" "F.Mask" "F.Paste")
			(net "PVCCMCP_CPU1")
		)
		(pad "AR28" smd circle
			(at -14.071092 -8.262874)
			(size 0.4318 0.4318)
			(layers "F.Cu" "F.Mask" "F.Paste")
			(net "PVCCIO_CPU1")
		)
		(pad "AR30" smd circle
			(at -12.354052 -8.262874)
			(size 0.4318 0.4318)
			(layers "F.Cu" "F.Mask" "F.Paste")
			(net "GND")
		)
		(pad "AR56" smd circle
			(at 11.495532 -10.062972)
			(size 0.508 0.508)
			(layers "F.Cu" "F.Mask" "F.Paste")
			(net "PVCCIN_CPU1")
		)
		(pad "AR58" smd circle
			(at 13.212572 -10.062972)
			(size 0.4318 0.4318)
			(layers "F.Cu" "F.Mask" "F.Paste")
			(net "PVCCIN_CPU1")
		)
		(pad "AR60" smd circle
			(at 14.929612 -10.062972)
			(size 0.4318 0.4318)
			(layers "F.Cu" "F.Mask" "F.Paste")
			(net "GND")
		)
		(pad "AR62" smd circle
			(at 16.646398 -10.062972)
			(size 0.4318 0.4318)
			(layers "F.Cu" "F.Mask" "F.Paste")
			(net "TP_CPU1_RSVD_190")
		)
		(pad "AR64" smd circle
			(at 18.363438 -10.062972)
			(size 0.4318 0.4318)
			(layers "F.Cu" "F.Mask" "F.Paste")
			(net "M_J_DQ<27>")
		)
		(pad "AR66" smd circle
			(at 20.080478 -10.062972)
			(size 0.4318 0.4318)
			(layers "F.Cu" "F.Mask" "F.Paste")
			(net "M_J_DQS_DP<3>")
		)
		(pad "AR68" smd circle
			(at 21.797518 -10.062972)
			(size 0.4318 0.4318)
			(layers "F.Cu" "F.Mask" "F.Paste")
			(net "M_J_DQ<29>")
		)
		(pad "AR72" smd circle
			(at 25.231598 -10.062972)
			(size 0.4318 0.4318)
			(layers "F.Cu" "F.Mask" "F.Paste")
			(net "GND")
		)
		(pad "AR74" smd circle
			(at 26.948384 -10.062972)
			(size 0.4318 0.4318)
			(layers "F.Cu" "F.Mask" "F.Paste")
			(net "M_J_DQ<5>")
		)
		(pad "AR76" smd circle
			(at 28.665424 -10.062972)
			(size 0.4318 0.4318)
			(layers "F.Cu" "F.Mask" "F.Paste")
			(net "M_J_DQ<0>")
		)
		(pad "AR78" smd circle
			(at 30.382464 -10.062972)
			(size 0.4318 0.4318)
			(layers "F.Cu" "F.Mask" "F.Paste")
			(net "GND")
		)
		(pad "AR80" smd circle
			(at 32.099504 -10.062972)
			(size 0.4318 0.4318)
			(layers "F.Cu" "F.Mask" "F.Paste")
			(net "M_H_DQS_DP<0>")
		)
		(pad "AR82" smd circle
			(at 33.816544 -10.062972)
			(size 0.4318 0.4318)
			(layers "F.Cu" "F.Mask" "F.Paste")
			(net "M_H_DQ<6>")
		)
		(pad "AR84" smd circle
			(at 35.533584 -10.062972)
			(size 0.4318 0.4318)
			(layers "F.Cu" "F.Mask" "F.Paste")
			(net "M_G_DQ<5>")
		)
		(pad "AR86" smd custom
			(at 37.250624 -10.062972 270)
			(size 0.10795 0.10795)
			(layers "F.Cu" "F.Mask" "F.Paste")
			(net "M_G_DQ<4>")
			(options
				(clearance outline)
				(anchor circle)
			)
			(primitives
				(gr_poly
					(pts
						(arc
							(start 0.2159 -0.0381)
							(mid 0 -0.254)
							(end -0.2159 -0.0381)
						)
						(arc
							(start -0.2159 0.0381)
							(mid 0 0.254)
							(end 0.2159 0.0381)
						)
					)
					(width 0)
					(fill yes)
				)
			)
		)
		(pad "AT1" smd custom
			(at -37.250624 -7.767828 90)
			(size 0.10795 0.10795)
			(layers "F.Cu" "F.Mask" "F.Paste")
			(net "UPI_CPU1_CPU0_P0P0_DP<12>")
			(options
				(clearance outline)
				(anchor circle)
			)
			(primitives
				(gr_poly
					(pts
						(arc
							(start 0.2159 -0.0381)
							(mid 0 -0.254)
							(end -0.2159 -0.0381)
						)
						(arc
							(start -0.2159 0.0381)
							(mid 0 0.254)
							(end 0.2159 0.0381)
						)
					)
					(width 0)
					(fill yes)
				)
			)
		)
		(pad "AT3" smd circle
			(at -35.533584 -7.767828)
			(size 0.4318 0.4318)
			(layers "F.Cu" "F.Mask" "F.Paste")
			(net "UPI_CPU1_CPU0_P0P0_DP<13>")
		)
		(pad "AT5" smd circle
			(at -33.816544 -7.767828)
			(size 0.4318 0.4318)
			(layers "F.Cu" "F.Mask" "F.Paste")
			(net "PVCCIO_CPU1")
		)
		(pad "AT7" smd circle
			(at -32.099504 -7.767828)
			(size 0.4318 0.4318)
			(layers "F.Cu" "F.Mask" "F.Paste")
			(net "PVCCIO_CPU1")
		)
		(pad "AT9" smd circle
			(at -30.382464 -7.767828)
			(size 0.4318 0.4318)
			(layers "F.Cu" "F.Mask" "F.Paste")
			(net "UPI_CPU0_CPU1_P0P0_DP<12>")
		)
		(pad "AT11" smd circle
			(at -28.665424 -7.767828)
			(size 0.4318 0.4318)
			(layers "F.Cu" "F.Mask" "F.Paste")
			(net "PVCCIO_CPU1")
		)
		(pad "AT13" smd circle
			(at -26.948384 -7.767828)
			(size 0.4318 0.4318)
			(layers "F.Cu" "F.Mask" "F.Paste")
			(net "TP_CPU1_RSVD_189")
		)
		(pad "AT15" smd circle
			(at -25.231598 -7.767828)
			(size 0.4318 0.4318)
			(layers "F.Cu" "F.Mask" "F.Paste")
			(net "GND")
		)
		(pad "AT17" smd circle
			(at -23.514558 -7.767828)
			(size 0.4318 0.4318)
			(layers "F.Cu" "F.Mask" "F.Paste")
			(net "GND")
		)
		(pad "AT19" smd circle
			(at -21.797518 -7.767828)
			(size 0.4318 0.4318)
			(layers "F.Cu" "F.Mask" "F.Paste")
			(net "H_PMSYNC_CLK_24M_CPU1")
		)
		(pad "AT21" smd circle
			(at -20.080478 -7.767828)
			(size 0.4318 0.4318)
			(layers "F.Cu" "F.Mask" "F.Paste")
			(net "GND")
		)
		(pad "AT23" smd circle
			(at -18.363438 -7.767828)
			(size 0.4318 0.4318)
			(layers "F.Cu" "F.Mask" "F.Paste")
			(net "PVCCMCP_CPU1")
		)
		(pad "AT25" smd circle
			(at -16.646398 -7.767828)
			(size 0.4318 0.4318)
			(layers "F.Cu" "F.Mask" "F.Paste")
			(net "PVCCMCP_CPU1")
		)
		(pad "AT27" smd circle
			(at -14.929612 -7.767828)
			(size 0.4318 0.4318)
			(layers "F.Cu" "F.Mask" "F.Paste")
			(net "GND")
		)
		(pad "AT29" smd circle
			(at -13.212572 -7.767828)
			(size 0.4318 0.4318)
			(layers "F.Cu" "F.Mask" "F.Paste")
			(net "A_CPU1_UPI01_RBIAS")
		)
		(pad "AT57" smd circle
			(at 12.354052 -9.567926)
			(size 0.508 0.508)
			(layers "F.Cu" "F.Mask" "F.Paste")
			(net "PVCCIN_CPU1")
		)
		(pad "AT59" smd circle
			(at 14.071092 -9.567926)
			(size 0.4318 0.4318)
			(layers "F.Cu" "F.Mask" "F.Paste")
			(net "PVCCIN_CPU1")
		)
		(pad "AT61" smd circle
			(at 15.787878 -9.567926)
			(size 0.4318 0.4318)
			(layers "F.Cu" "F.Mask" "F.Paste")
			(net "GND")
		)
		(pad "AT63" smd circle
			(at 17.504918 -9.567926)
			(size 0.4318 0.4318)
			(layers "F.Cu" "F.Mask" "F.Paste")
			(net "GND")
		)
		(pad "AT65" smd circle
			(at 19.221958 -9.567926)
			(size 0.4318 0.4318)
			(layers "F.Cu" "F.Mask" "F.Paste")
			(net "M_J_DQ<31>")
		)
		(pad "AT67" smd circle
			(at 20.938998 -9.567926)
			(size 0.4318 0.4318)
			(layers "F.Cu" "F.Mask" "F.Paste")
			(net "M_J_DQ<25>")
		)
		(pad "AT69" smd circle
			(at 22.656038 -9.567926)
			(size 0.4318 0.4318)
			(layers "F.Cu" "F.Mask" "F.Paste")
			(net "GND")
		)
		(pad "AT71" smd circle
			(at 24.373078 -9.567926)
			(size 0.4318 0.4318)
			(layers "F.Cu" "F.Mask" "F.Paste")
			(net "M_J_DQS_DN<17>")
		)
		(pad "AT73" smd circle
			(at 26.090118 -9.567926)
			(size 0.4318 0.4318)
			(layers "F.Cu" "F.Mask" "F.Paste")
			(net "GND")
		)
		(pad "AT75" smd circle
			(at 27.806904 -9.567926)
			(size 0.4318 0.4318)
			(layers "F.Cu" "F.Mask" "F.Paste")
			(net "M_J_DQ<4>")
		)
		(pad "AT77" smd circle
			(at 29.523944 -9.567926)
			(size 0.4318 0.4318)
			(layers "F.Cu" "F.Mask" "F.Paste")
			(net "GND")
		)
		(pad "AT79" smd circle
			(at 31.240984 -9.567926)
			(size 0.4318 0.4318)
			(layers "F.Cu" "F.Mask" "F.Paste")
			(net "M_H_DQ<1>")
		)
		(pad "AT81" smd circle
			(at 32.958024 -9.567926)
			(size 0.4318 0.4318)
			(layers "F.Cu" "F.Mask" "F.Paste")
			(net "M_H_DQS_DP<9>")
		)
		(pad "AT83" smd circle
			(at 34.675064 -9.567926)
			(size 0.4318 0.4318)
			(layers "F.Cu" "F.Mask" "F.Paste")
			(net "GND")
		)
		(pad "AT85" smd circle
			(at 36.392104 -9.567926)
			(size 0.4318 0.4318)
			(layers "F.Cu" "F.Mask" "F.Paste")
			(net "GND")
		)
		(pad "AU2" smd circle
			(at -36.392104 -7.272274)
			(size 0.4318 0.4318)
			(layers "F.Cu" "F.Mask" "F.Paste")
			(net "GND")
		)
		(pad "AU4" smd circle
			(at -34.675064 -7.272274)
			(size 0.4318 0.4318)
			(layers "F.Cu" "F.Mask" "F.Paste")
			(net "UPI_CPU1_CPU0_P0P0_DP<14>")
		)
		(pad "AU6" smd circle
			(at -32.958024 -7.272274)
			(size 0.4318 0.4318)
			(layers "F.Cu" "F.Mask" "F.Paste")
			(net "GND")
		)
		(pad "AU8" smd circle
			(at -31.240984 -7.272274)
			(size 0.4318 0.4318)
			(layers "F.Cu" "F.Mask" "F.Paste")
			(net "UPI_CPU0_CPU1_P0P0_DN<11>")
		)
		(pad "AU10" smd circle
			(at -29.523944 -7.272274)
			(size 0.4318 0.4318)
			(layers "F.Cu" "F.Mask" "F.Paste")
			(net "UPI_CPU0_CPU1_P0P0_DN<12>")
		)
		(pad "AU12" smd circle
			(at -27.806904 -7.272274)
			(size 0.4318 0.4318)
			(layers "F.Cu" "F.Mask" "F.Paste")
			(net "PECI_CPU_G")
		)
		(pad "AU14" smd circle
			(at -26.090118 -7.272274)
			(size 0.4318 0.4318)
			(layers "F.Cu" "F.Mask" "F.Paste")
			(net "H_CPU1_FIVR_FAULT_G")
		)
		(pad "AU16" smd circle
			(at -24.373078 -7.272274)
			(size 0.4318 0.4318)
			(layers "F.Cu" "F.Mask" "F.Paste")
			(net "PU_CPU1_SOCKET_ID_1")
		)
		(pad "AU18" smd circle
			(at -22.656038 -7.272274)
			(size 0.4318 0.4318)
			(layers "F.Cu" "F.Mask" "F.Paste")
			(net "TP_CPU1_TEST_7")
		)
		(pad "AU20" smd circle
			(at -20.938998 -7.272274)
			(size 0.4318 0.4318)
			(layers "F.Cu" "F.Mask" "F.Paste")
			(net "TP_CPU1_SOCKET_ID_2")
		)
		(pad "AU22" smd circle
			(at -19.221958 -7.272274)
			(size 0.4318 0.4318)
			(layers "F.Cu" "F.Mask" "F.Paste")
			(net "PU_CPU1_SOCKET_ID_0")
		)
		(pad "AU24" smd circle
			(at -17.504918 -7.272274)
			(size 0.4318 0.4318)
			(layers "F.Cu" "F.Mask" "F.Paste")
			(net "CLK_100M_CPU1_BCLK0_DN")
		)
		(pad "AU26" smd circle
			(at -15.787878 -7.272274)
			(size 0.4318 0.4318)
			(layers "F.Cu" "F.Mask" "F.Paste")
			(net "GND")
		)
		(pad "AU28" smd circle
			(at -14.071092 -7.272274)
			(size 0.4318 0.4318)
			(layers "F.Cu" "F.Mask" "F.Paste")
			(net "GND")
		)
		(pad "AU58" smd circle
			(at 13.212572 -9.072372)
			(size 0.508 0.508)
			(layers "F.Cu" "F.Mask" "F.Paste")
			(net "PVCCIN_CPU1")
		)
		(pad "AU60" smd circle
			(at 14.929612 -9.072372)
			(size 0.4318 0.4318)
			(layers "F.Cu" "F.Mask" "F.Paste")
			(net "PVCCIN_CPU1")
		)
		(pad "AU62" smd circle
			(at 16.646398 -9.072372)
			(size 0.4318 0.4318)
			(layers "F.Cu" "F.Mask" "F.Paste")
			(net "GND")
		)
		(pad "AU64" smd circle
			(at 18.363438 -9.072372)
			(size 0.4318 0.4318)
			(layers "F.Cu" "F.Mask" "F.Paste")
			(net "GND")
		)
		(pad "AU66" smd circle
			(at 20.080478 -9.072372)
			(size 0.4318 0.4318)
			(layers "F.Cu" "F.Mask" "F.Paste")
			(net "M_J_DQS_DN<3>")
		)
		(pad "AU68" smd circle
			(at 21.797518 -9.072372)
			(size 0.4318 0.4318)
			(layers "F.Cu" "F.Mask" "F.Paste")
			(net "GND")
		)
		(pad "AU70" smd circle
			(at 23.514558 -9.072372)
			(size 0.4318 0.4318)
			(layers "F.Cu" "F.Mask" "F.Paste")
			(net "M_J_ECC<6>")
		)
		(pad "AU72" smd circle
			(at 25.231598 -9.072372)
			(size 0.4318 0.4318)
			(layers "F.Cu" "F.Mask" "F.Paste")
			(net "M_J_ECC<0>")
		)
		(pad "AU74" smd circle
			(at 26.948384 -9.072372)
			(size 0.4318 0.4318)
			(layers "F.Cu" "F.Mask" "F.Paste")
			(net "GND")
		)
		(pad "AU76" smd circle
			(at 28.665424 -9.072372)
			(size 0.4318 0.4318)
			(layers "F.Cu" "F.Mask" "F.Paste")
			(net "GND")
		)
		(pad "AU78" smd circle
			(at 30.382464 -9.072372)
			(size 0.4318 0.4318)
			(layers "F.Cu" "F.Mask" "F.Paste")
			(net "GND")
		)
		(pad "AU80" smd circle
			(at 32.099504 -9.072372)
			(size 0.4318 0.4318)
			(layers "F.Cu" "F.Mask" "F.Paste")
			(net "GND")
		)
		(pad "AU82" smd circle
			(at 33.816544 -9.072372)
			(size 0.4318 0.4318)
			(layers "F.Cu" "F.Mask" "F.Paste")
			(net "M_H_DQS_DN<9>")
		)
		(pad "AU84" smd circle
			(at 35.533584 -9.072372)
			(size 0.4318 0.4318)
			(layers "F.Cu" "F.Mask" "F.Paste")
			(net "GND")
		)
		(pad "AU86" smd custom
			(at 37.250624 -9.072372 270)
			(size 0.10795 0.10795)
			(layers "F.Cu" "F.Mask" "F.Paste")
			(net "GND")
			(options
				(clearance outline)
				(anchor circle)
			)
			(primitives
				(gr_poly
					(pts
						(arc
							(start 0.2159 -0.0381)
							(mid 0 -0.254)
							(end -0.2159 -0.0381)
						)
						(arc
							(start -0.2159 0.0381)
							(mid 0 0.254)
							(end 0.2159 0.0381)
						)
					)
					(width 0)
					(fill yes)
				)
			)
		)
		(pad "AV1" smd custom
			(at -37.250624 -6.777228 90)
			(size 0.10795 0.10795)
			(layers "F.Cu" "F.Mask" "F.Paste")
			(net "GND")
			(options
				(clearance outline)
				(anchor circle)
			)
			(primitives
				(gr_poly
					(pts
						(arc
							(start 0.2159 -0.0381)
							(mid 0 -0.254)
							(end -0.2159 -0.0381)
						)
						(arc
							(start -0.2159 0.0381)
							(mid 0 0.254)
							(end 0.2159 0.0381)
						)
					)
					(width 0)
					(fill yes)
				)
			)
		)
		(pad "AV3" smd circle
			(at -35.533584 -6.777228)
			(size 0.4318 0.4318)
			(layers "F.Cu" "F.Mask" "F.Paste")
			(net "GND")
		)
		(pad "AV5" smd circle
			(at -33.816544 -6.777228)
			(size 0.4318 0.4318)
			(layers "F.Cu" "F.Mask" "F.Paste")
			(net "UPI_CPU1_CPU0_P0P0_DP<15>")
		)
		(pad "AV7" smd circle
			(at -32.099504 -6.777228)
			(size 0.4318 0.4318)
			(layers "F.Cu" "F.Mask" "F.Paste")
			(net "GND")
		)
		(pad "AV9" smd circle
			(at -30.382464 -6.777228)
			(size 0.4318 0.4318)
			(layers "F.Cu" "F.Mask" "F.Paste")
			(net "UPI_CPU0_CPU1_P0P0_DP<16>")
		)
		(pad "AV11" smd circle
			(at -28.665424 -6.777228)
			(size 0.4318 0.4318)
			(layers "F.Cu" "F.Mask" "F.Paste")
			(net "GND")
		)
		(pad "AV13" smd circle
			(at -26.948384 -6.777228)
			(size 0.4318 0.4318)
			(layers "F.Cu" "F.Mask" "F.Paste")
			(net "GND")
		)
		(pad "AV15" smd circle
			(at -25.231598 -6.777228)
			(size 0.4318 0.4318)
			(layers "F.Cu" "F.Mask" "F.Paste")
			(net "PD_CPU1_TXT_PLTEN")
		)
		(pad "AV17" smd circle
			(at -23.514558 -6.777228)
			(size 0.4318 0.4318)
			(layers "F.Cu" "F.Mask" "F.Paste")
			(net "PU_CPU1_FRMAGENT")
		)
		(pad "AV19" smd circle
			(at -21.797518 -6.777228)
			(size 0.4318 0.4318)
			(layers "F.Cu" "F.Mask" "F.Paste")
			(net "GND")
		)
		(pad "AV21" smd circle
			(at -20.080478 -6.777228)
			(size 0.4318 0.4318)
			(layers "F.Cu" "F.Mask" "F.Paste")
			(net "CPU_XDP_PRESENT_N")
		)
		(pad "AV23" smd circle
			(at -18.363438 -6.777228)
			(size 0.4318 0.4318)
			(layers "F.Cu" "F.Mask" "F.Paste")
			(net "GND")
		)
		(pad "AV25" smd circle
			(at -16.646398 -6.777228)
			(size 0.4318 0.4318)
			(layers "F.Cu" "F.Mask" "F.Paste")
			(net "GND")
		)
		(pad "AV27" smd circle
			(at -14.929612 -6.777228)
			(size 0.4318 0.4318)
			(layers "F.Cu" "F.Mask" "F.Paste")
			(net "PVCCIO_CPU1")
		)
		(pad "AV59" smd circle
			(at 14.071092 -8.577326)
			(size 0.508 0.508)
			(layers "F.Cu" "F.Mask" "F.Paste")
			(net "PVCCIN_CPU1")
		)
		(pad "AV61" smd circle
			(at 15.787878 -8.577326)
			(size 0.4318 0.4318)
			(layers "F.Cu" "F.Mask" "F.Paste")
			(net "PVCCIN_CPU1")
		)
		(pad "AV63" smd circle
			(at 17.504918 -8.577326)
			(size 0.4318 0.4318)
			(layers "F.Cu" "F.Mask" "F.Paste")
			(net "GND")
		)
		(pad "AV65" smd circle
			(at 19.221958 -8.577326)
			(size 0.4318 0.4318)
			(layers "F.Cu" "F.Mask" "F.Paste")
			(net "GND")
		)
		(pad "AV67" smd circle
			(at 20.938998 -8.577326)
			(size 0.4318 0.4318)
			(layers "F.Cu" "F.Mask" "F.Paste")
			(net "GND")
		)
		(pad "AV69" smd circle
			(at 22.656038 -8.577326)
			(size 0.4318 0.4318)
			(layers "F.Cu" "F.Mask" "F.Paste")
			(net "M_J_ECC<2>")
		)
		(pad "AV71" smd circle
			(at 24.373078 -8.577326)
			(size 0.4318 0.4318)
			(layers "F.Cu" "F.Mask" "F.Paste")
			(net "M_J_DQS_DP<17>")
		)
		(pad "AV73" smd circle
			(at 26.090118 -8.577326)
			(size 0.4318 0.4318)
			(layers "F.Cu" "F.Mask" "F.Paste")
			(net "M_J_ECC<4>")
		)
		(pad "AV75" smd circle
			(at 27.806904 -8.577326)
			(size 0.4318 0.4318)
			(layers "F.Cu" "F.Mask" "F.Paste")
			(net "GND")
		)
		(pad "AV77" smd circle
			(at 29.523944 -8.577326)
			(size 0.4318 0.4318)
			(layers "F.Cu" "F.Mask" "F.Paste")
			(net "TP_CPU1_RSVD_186")
		)
		(pad "AV79" smd circle
			(at 31.240984 -8.577326)
			(size 0.4318 0.4318)
			(layers "F.Cu" "F.Mask" "F.Paste")
			(net "M_H_DQ<5>")
		)
		(pad "AV81" smd circle
			(at 32.958024 -8.577326)
			(size 0.4318 0.4318)
			(layers "F.Cu" "F.Mask" "F.Paste")
			(net "M_H_DQ<0>")
		)
		(pad "AV83" smd circle
			(at 34.675064 -8.577326)
			(size 0.4318 0.4318)
			(layers "F.Cu" "F.Mask" "F.Paste")
			(net "GND")
		)
		(pad "AV85" smd circle
			(at 36.392104 -8.577326)
			(size 0.4318 0.4318)
			(layers "F.Cu" "F.Mask" "F.Paste")
			(net "VSENSE_VCCINR2PMAX_CPU1")
		)
		(pad "AW2" smd custom
			(at -36.392104 -6.281928 90)
			(size 0.10795 0.10795)
			(layers "F.Cu" "F.Mask" "F.Paste")
			(net "GND")
			(options
				(clearance outline)
				(anchor circle)
			)
			(primitives
				(gr_poly
					(pts
						(arc
							(start 0.2159 -0.0381)
							(mid 0 -0.254)
							(end -0.2159 -0.0381)
						)
						(arc
							(start -0.2159 0.0381)
							(mid 0 0.254)
							(end 0.2159 0.0381)
						)
					)
					(width 0)
					(fill yes)
				)
			)
		)
		(pad "AW4" smd circle
			(at -34.675064 -6.281928)
			(size 0.4318 0.4318)
			(layers "F.Cu" "F.Mask" "F.Paste")
			(net "UPI_CPU1_CPU0_P0P0_DN<15>")
		)
		(pad "AW6" smd circle
			(at -32.958024 -6.281928)
			(size 0.4318 0.4318)
			(layers "F.Cu" "F.Mask" "F.Paste")
			(net "PVCCIO_CPU1")
		)
		(pad "AW8" smd circle
			(at -31.240984 -6.281928)
			(size 0.4318 0.4318)
			(layers "F.Cu" "F.Mask" "F.Paste")
			(net "UPI_CPU0_CPU1_P0P0_DN<16>")
		)
		(pad "AW10" smd circle
			(at -29.523944 -6.281928)
			(size 0.4318 0.4318)
			(layers "F.Cu" "F.Mask" "F.Paste")
			(net "GND")
		)
		(pad "AW12" smd circle
			(at -27.806904 -6.281928)
			(size 0.4318 0.4318)
			(layers "F.Cu" "F.Mask" "F.Paste")
			(net "PD_CPU1_DMIMODE_OVERRIDE")
		)
		(pad "AW14" smd circle
			(at -26.090118 -6.281928)
			(size 0.4318 0.4318)
			(layers "F.Cu" "F.Mask" "F.Paste")
			(net "PD_CPU1_KSFC_DIS")
		)
		(pad "AW16" smd circle
			(at -24.373078 -6.281928)
			(size 0.4318 0.4318)
			(layers "F.Cu" "F.Mask" "F.Paste")
			(net "TP_CPU1_TEST_8")
		)
		(pad "AW18" smd circle
			(at -22.656038 -6.281928)
			(size 0.4318 0.4318)
			(layers "F.Cu" "F.Mask" "F.Paste")
			(net "PU_CPU1_TXT_AGENT")
		)
		(pad "AW20" smd circle
			(at -20.938998 -6.281928)
			(size 0.4318 0.4318)
			(layers "F.Cu" "F.Mask" "F.Paste")
			(net "TP_CPU1_TEST_9")
		)
		(pad "AW22" smd circle
			(at -19.221958 -6.281928)
			(size 0.4318 0.4318)
			(layers "F.Cu" "F.Mask" "F.Paste")
			(net "TP_CPU1_TEST_10")
		)
		(pad "AW24" smd circle
			(at -17.504918 -6.281928)
			(size 0.4318 0.4318)
			(layers "F.Cu" "F.Mask" "F.Paste")
			(net "CLK_100M_CPU1_BCLK0_DP")
		)
		(pad "AW26" smd circle
			(at -15.787878 -6.281928)
			(size 0.4318 0.4318)
			(layers "F.Cu" "F.Mask" "F.Paste")
			(net "PVCCIO_CPU1")
		)
		(pad "AW60" smd circle
			(at 14.929612 -8.081772)
			(size 0.508 0.508)
			(layers "F.Cu" "F.Mask" "F.Paste")
			(net "PVCCIN_CPU1")
		)
		(pad "AW62" smd circle
			(at 16.646398 -8.081772)
			(size 0.4318 0.4318)
			(layers "F.Cu" "F.Mask" "F.Paste")
			(net "GND")
		)
		(pad "AW64" smd circle
			(at 18.363438 -8.081772)
			(size 0.4318 0.4318)
			(layers "F.Cu" "F.Mask" "F.Paste")
			(net "TP_CPU1_RSVD_184")
		)
		(pad "AW66" smd circle
			(at 20.080478 -8.081772)
			(size 0.4318 0.4318)
			(layers "F.Cu" "F.Mask" "F.Paste")
			(net "GND")
		)
		(pad "AW68" smd circle
			(at 21.797518 -8.081772)
			(size 0.4318 0.4318)
			(layers "F.Cu" "F.Mask" "F.Paste")
			(net "GND")
		)
		(pad "AW70" smd circle
			(at 23.514558 -8.081772)
			(size 0.4318 0.4318)
			(layers "F.Cu" "F.Mask" "F.Paste")
			(net "GND")
		)
		(pad "AW72" smd circle
			(at 25.231598 -8.081772)
			(size 0.4318 0.4318)
			(layers "F.Cu" "F.Mask" "F.Paste")
			(net "GND")
		)
		(pad "AW74" smd circle
			(at 26.948384 -8.081772)
			(size 0.4318 0.4318)
			(layers "F.Cu" "F.Mask" "F.Paste")
			(net "GND")
		)
		(pad "AW76" smd circle
			(at 28.665424 -8.081772)
			(size 0.4318 0.4318)
			(layers "F.Cu" "F.Mask" "F.Paste")
			(net "TP_CPU1_RSVD_183")
		)
		(pad "AW78" smd circle
			(at 30.382464 -8.081772)
			(size 0.4318 0.4318)
			(layers "F.Cu" "F.Mask" "F.Paste")
			(net "GND")
		)
		(pad "AW80" smd circle
			(at 32.099504 -8.081772)
			(size 0.4318 0.4318)
			(layers "F.Cu" "F.Mask" "F.Paste")
			(net "M_H_DQ<4>")
		)
		(pad "AW82" smd circle
			(at 33.816544 -8.081772)
			(size 0.4318 0.4318)
			(layers "F.Cu" "F.Mask" "F.Paste")
			(net "GND")
		)
		(pad "AW84" smd circle
			(at 35.533584 -8.081772)
			(size 0.4318 0.4318)
			(layers "F.Cu" "F.Mask" "F.Paste")
			(net "GND")
		)
		(pad "AW86" smd custom
			(at 37.250624 -8.081772 270)
			(size 0.10795 0.10795)
			(layers "F.Cu" "F.Mask" "F.Paste")
			(net "VSENSE_VCCINR2PMAX_CPU1")
			(options
				(clearance outline)
				(anchor circle)
			)
			(primitives
				(gr_poly
					(pts
						(arc
							(start 0.2159 -0.0381)
							(mid 0 -0.254)
							(end -0.2159 -0.0381)
						)
						(arc
							(start -0.2159 0.0381)
							(mid 0 0.254)
							(end 0.2159 0.0381)
						)
					)
					(width 0)
					(fill yes)
				)
			)
		)
		(pad "AY3" smd circle
			(at -35.533584 -5.786628)
			(size 0.4318 0.4318)
			(layers "F.Cu" "F.Mask" "F.Paste")
			(net "UPI_CPU1_CPU0_P0P0_DN<16>")
		)
		(pad "AY5" smd circle
			(at -33.816544 -5.786628)
			(size 0.4318 0.4318)
			(layers "F.Cu" "F.Mask" "F.Paste")
			(net "GND")
		)
		(pad "AY7" smd circle
			(at -32.099504 -5.786628)
			(size 0.4318 0.4318)
			(layers "F.Cu" "F.Mask" "F.Paste")
			(net "UPI_CPU0_CPU1_P0P0_DP<13>")
		)
		(pad "AY9" smd circle
			(at -30.382464 -5.786628)
			(size 0.4318 0.4318)
			(layers "F.Cu" "F.Mask" "F.Paste")
			(net "UPI_CPU0_CPU1_P0P0_DN<17>")
		)
		(pad "AY11" smd circle
			(at -28.665424 -5.786628)
			(size 0.4318 0.4318)
			(layers "F.Cu" "F.Mask" "F.Paste")
			(net "PVCCIO_CPU1")
		)
		(pad "AY13" smd circle
			(at -26.948384 -5.786628)
			(size 0.4318 0.4318)
			(layers "F.Cu" "F.Mask" "F.Paste")
			(net "TP_CPU1_RSVD_TEST_11")
		)
		(pad "AY15" smd circle
			(at -25.231598 -5.786628)
			(size 0.4318 0.4318)
			(layers "F.Cu" "F.Mask" "F.Paste")
			(net "GND")
		)
		(pad "AY17" smd circle
			(at -23.514558 -5.786628)
			(size 0.4318 0.4318)
			(layers "F.Cu" "F.Mask" "F.Paste")
			(net "GND")
		)
		(pad "AY19" smd circle
			(at -21.797518 -5.786628)
			(size 0.4318 0.4318)
			(layers "F.Cu" "F.Mask" "F.Paste")
			(net "PD_CPU1_TEST12")
		)
		(pad "AY21" smd circle
			(at -20.080478 -5.786628)
			(size 0.4318 0.4318)
			(layers "F.Cu" "F.Mask" "F.Paste")
			(net "GND")
		)
		(pad "AY23" smd circle
			(at -18.363438 -5.786628)
			(size 0.4318 0.4318)
			(layers "F.Cu" "F.Mask" "F.Paste")
			(net "GND")
		)
		(pad "AY25" smd circle
			(at -16.646398 -5.786628)
			(size 0.4318 0.4318)
			(layers "F.Cu" "F.Mask" "F.Paste")
			(net "GND")
		)
		(pad "AY27" smd circle
			(at -14.929612 -5.786628)
			(size 0.4318 0.4318)
			(layers "F.Cu" "F.Mask" "F.Paste")
			(net "PVCCIO_CPU1")
		)
		(pad "AY61" smd circle
			(at 15.787878 -7.586726)
			(size 0.4318 0.4318)
			(layers "F.Cu" "F.Mask" "F.Paste")
			(net "PVCCIN_CPU1")
		)
		(pad "AY63" smd circle
			(at 17.504918 -7.586726)
			(size 0.4318 0.4318)
			(layers "F.Cu" "F.Mask" "F.Paste")
			(net "GND")
		)
		(pad "AY65" smd circle
			(at 19.221958 -7.586726)
			(size 0.4318 0.4318)
			(layers "F.Cu" "F.Mask" "F.Paste")
			(net "TP_CPU1_RSVD_182")
		)
		(pad "AY67" smd circle
			(at 20.938998 -7.586726)
			(size 0.4318 0.4318)
			(layers "F.Cu" "F.Mask" "F.Paste")
			(net "TP_CPU1_RSVD_181")
		)
		(pad "AY69" smd circle
			(at 22.656038 -7.586726)
			(size 0.4318 0.4318)
			(layers "F.Cu" "F.Mask" "F.Paste")
			(net "M_J_ECC<3>")
		)
		(pad "AY71" smd circle
			(at 24.373078 -7.586726)
			(size 0.4318 0.4318)
			(layers "F.Cu" "F.Mask" "F.Paste")
			(net "M_J_DQS_DP<8>")
		)
		(pad "AY73" smd circle
			(at 26.090118 -7.586726)
			(size 0.4318 0.4318)
			(layers "F.Cu" "F.Mask" "F.Paste")
			(net "M_J_ECC<5>")
		)
		(pad "AY75" smd circle
			(at 27.806904 -7.586726)
			(size 0.4318 0.4318)
			(layers "F.Cu" "F.Mask" "F.Paste")
			(net "TP_CPU1_RSVD_180")
		)
		(pad "AY77" smd circle
			(at 29.523944 -7.586726)
			(size 0.4318 0.4318)
			(layers "F.Cu" "F.Mask" "F.Paste")
			(net "TP_CPU1_RSVD_179")
		)
		(pad "AY79" smd circle
			(at 31.240984 -7.586726)
			(size 0.4318 0.4318)
			(layers "F.Cu" "F.Mask" "F.Paste")
			(net "GND")
		)
		(pad "AY81" smd circle
			(at 32.958024 -7.586726)
			(size 0.4318 0.4318)
			(layers "F.Cu" "F.Mask" "F.Paste")
			(net "GND")
		)
		(pad "AY83" smd circle
			(at 34.675064 -7.586726)
			(size 0.4318 0.4318)
			(layers "F.Cu" "F.Mask" "F.Paste")
			(net "TP_CPU1_RSVD_255")
		)
		(pad "AY85" smd circle
			(at 36.392104 -7.586726)
			(size 0.4318 0.4318)
			(layers "F.Cu" "F.Mask" "F.Paste")
			(net "VSENSE_PVCCIN_CPU1_SKT_VRTN")
		)
		(pad "B3" smd custom
			(at -35.533584 -24.608028 45)
			(size 0.10795 0.10795)
			(layers "F.Cu" "F.Mask" "F.Paste")
			(net "TP_CPU1_RSVD_299")
			(options
				(clearance outline)
				(anchor circle)
			)
			(primitives
				(gr_poly
					(pts
						(arc
							(start 0.2159 -0.0381)
							(mid 0 -0.254)
							(end -0.2159 -0.0381)
						)
						(arc
							(start -0.2159 0.0381)
							(mid 0 0.254)
							(end 0.2159 0.0381)
						)
					)
					(width 0)
					(fill yes)
				)
			)
		)
		(pad "B5" smd custom
			(at -33.816544 -24.608028 45)
			(size 0.10795 0.10795)
			(layers "F.Cu" "F.Mask" "F.Paste")
			(net "GND")
			(options
				(clearance outline)
				(anchor circle)
			)
			(primitives
				(gr_poly
					(pts
						(arc
							(start 0.2159 -0.0381)
							(mid 0 -0.254)
							(end -0.2159 -0.0381)
						)
						(arc
							(start -0.2159 0.0381)
							(mid 0 0.254)
							(end 0.2159 0.0381)
						)
					)
					(width 0)
					(fill yes)
				)
			)
		)
		(pad "B7" smd custom
			(at -32.099504 -24.608028)
			(size 0.10795 0.10795)
			(layers "F.Cu" "F.Mask" "F.Paste")
			(net "TP_CPU1_RSVD_298")
			(options
				(clearance outline)
				(anchor circle)
			)
			(primitives
				(gr_poly
					(pts
						(arc
							(start 0.2159 -0.0381)
							(mid 0 -0.254)
							(end -0.2159 -0.0381)
						)
						(arc
							(start -0.2159 0.0381)
							(mid 0 0.254)
							(end 0.2159 0.0381)
						)
					)
					(width 0)
					(fill yes)
				)
			)
		)
		(pad "B9" smd circle
			(at -30.382464 -24.608028)
			(size 0.4318 0.4318)
			(layers "F.Cu" "F.Mask" "F.Paste")
			(net "GND")
		)
		(pad "B11" smd circle
			(at -28.665424 -24.608028)
			(size 0.4318 0.4318)
			(layers "F.Cu" "F.Mask" "F.Paste")
			(net "PVPP_GHJ")
		)
		(pad "B13" smd circle
			(at -26.948384 -24.608028)
			(size 0.4318 0.4318)
			(layers "F.Cu" "F.Mask" "F.Paste")
			(net "P1V8_MCP_CPU1")
		)
		(pad "B15" smd circle
			(at -25.231598 -24.608028)
			(size 0.4318 0.4318)
			(layers "F.Cu" "F.Mask" "F.Paste")
			(net "P1V8_MCP_CPU1")
		)
		(pad "B17" smd custom
			(at -23.514558 -24.608028)
			(size 0.10795 0.10795)
			(layers "F.Cu" "F.Mask" "F.Paste")
			(net "P1V8_MCP_CPU1")
			(options
				(clearance outline)
				(anchor circle)
			)
			(primitives
				(gr_poly
					(pts
						(arc
							(start 0.2159 -0.0381)
							(mid 0 -0.254)
							(end -0.2159 -0.0381)
						)
						(arc
							(start -0.2159 0.0381)
							(mid 0 0.254)
							(end 0.2159 0.0381)
						)
					)
					(width 0)
					(fill yes)
				)
			)
		)
		(pad "B25" smd circle
			(at -16.646398 -24.608028)
			(size 0.4318 0.4318)
			(layers "F.Cu" "F.Mask" "F.Paste")
			(net "GND")
		)
		(pad "B27" smd circle
			(at -14.929612 -24.608028)
			(size 0.4318 0.4318)
			(layers "F.Cu" "F.Mask" "F.Paste")
			(net "M_H_DQ<54>")
		)
		(pad "B29" smd circle
			(at -13.212572 -24.608028)
			(size 0.4318 0.4318)
			(layers "F.Cu" "F.Mask" "F.Paste")
			(net "M_H_DQ<49>")
		)
		(pad "B31" smd circle
			(at -11.495532 -24.608028)
			(size 0.4318 0.4318)
			(layers "F.Cu" "F.Mask" "F.Paste")
			(net "GND")
		)
		(pad "B33" smd circle
			(at -9.778492 -24.608028)
			(size 0.4318 0.4318)
			(layers "F.Cu" "F.Mask" "F.Paste")
			(net "M_H_DQ<46>")
		)
		(pad "B35" smd circle
			(at -8.061452 -24.608028)
			(size 0.4318 0.4318)
			(layers "F.Cu" "F.Mask" "F.Paste")
			(net "M_H_DQ<41>")
		)
		(pad "B37" smd circle
			(at -6.344412 -24.608028)
			(size 0.4318 0.4318)
			(layers "F.Cu" "F.Mask" "F.Paste")
			(net "GND")
		)
		(pad "B39" smd circle
			(at -4.627626 -24.608028)
			(size 0.4318 0.4318)
			(layers "F.Cu" "F.Mask" "F.Paste")
			(net "M_G_DQ<38>")
		)
		(pad "B41" smd circle
			(at -2.910586 -24.608028)
			(size 0.4318 0.4318)
			(layers "F.Cu" "F.Mask" "F.Paste")
			(net "M_G_DQ<33>")
		)
		(pad "B43" smd custom
			(at -1.193546 -24.608028 315)
			(size 0.10795 0.10795)
			(layers "F.Cu" "F.Mask" "F.Paste")
			(net "GND")
			(options
				(clearance outline)
				(anchor circle)
			)
			(primitives
				(gr_poly
					(pts
						(arc
							(start 0.2159 -0.0381)
							(mid 0 -0.254)
							(end -0.2159 -0.0381)
						)
						(arc
							(start -0.2159 0.0381)
							(mid 0 0.254)
							(end 0.2159 0.0381)
						)
					)
					(width 0)
					(fill yes)
				)
			)
		)
		(pad "B47" smd custom
			(at 3.769106 -26.408126 45)
			(size 0.10795 0.10795)
			(layers "F.Cu" "F.Mask" "F.Paste")
			(net "PVDDQ_GHJ")
			(options
				(clearance outline)
				(anchor circle)
			)
			(primitives
				(gr_poly
					(pts
						(arc
							(start 0.2159 -0.0381)
							(mid 0 -0.254)
							(end -0.2159 -0.0381)
						)
						(arc
							(start -0.2159 0.0381)
							(mid 0 0.254)
							(end 0.2159 0.0381)
						)
					)
					(width 0)
					(fill yes)
				)
			)
		)
		(pad "B49" smd custom
			(at 5.485892 -26.408126)
			(size 0.10795 0.10795)
			(layers "F.Cu" "F.Mask" "F.Paste")
			(net "PVDDQ_GHJ")
			(options
				(clearance outline)
				(anchor circle)
			)
			(primitives
				(gr_poly
					(pts
						(arc
							(start 0.2159 -0.0381)
							(mid 0 -0.254)
							(end -0.2159 -0.0381)
						)
						(arc
							(start -0.2159 0.0381)
							(mid 0 0.254)
							(end 0.2159 0.0381)
						)
					)
					(width 0)
					(fill yes)
				)
			)
		)
		(pad "B51" smd custom
			(at 7.202932 -26.408126)
			(size 0.10795 0.10795)
			(layers "F.Cu" "F.Mask" "F.Paste")
			(net "M_G_CS_N<4>")
			(options
				(clearance outline)
				(anchor circle)
			)
			(primitives
				(gr_poly
					(pts
						(arc
							(start 0.2159 -0.0381)
							(mid 0 -0.254)
							(end -0.2159 -0.0381)
						)
						(arc
							(start -0.2159 0.0381)
							(mid 0 0.254)
							(end 0.2159 0.0381)
						)
					)
					(width 0)
					(fill yes)
				)
			)
		)
		(pad "B53" smd custom
			(at 8.919972 -26.408126)
			(size 0.10795 0.10795)
			(layers "F.Cu" "F.Mask" "F.Paste")
			(net "PVDDQ_GHJ")
			(options
				(clearance outline)
				(anchor circle)
			)
			(primitives
				(gr_poly
					(pts
						(arc
							(start 0.2159 -0.0381)
							(mid 0 -0.254)
							(end -0.2159 -0.0381)
						)
						(arc
							(start -0.2159 0.0381)
							(mid 0 0.254)
							(end 0.2159 0.0381)
						)
					)
					(width 0)
					(fill yes)
				)
			)
		)
		(pad "B55" smd custom
			(at 10.637012 -26.408126)
			(size 0.10795 0.10795)
			(layers "F.Cu" "F.Mask" "F.Paste")
			(net "M_G_CLK_DP<1>")
			(options
				(clearance outline)
				(anchor circle)
			)
			(primitives
				(gr_poly
					(pts
						(arc
							(start 0.2159 -0.0381)
							(mid 0 -0.254)
							(end -0.2159 -0.0381)
						)
						(arc
							(start -0.2159 0.0381)
							(mid 0 0.254)
							(end 0.2159 0.0381)
						)
					)
					(width 0)
					(fill yes)
				)
			)
		)
		(pad "B57" smd custom
			(at 12.354052 -26.408126)
			(size 0.10795 0.10795)
			(layers "F.Cu" "F.Mask" "F.Paste")
			(net "M_G_CLK_DP<3>")
			(options
				(clearance outline)
				(anchor circle)
			)
			(primitives
				(gr_poly
					(pts
						(arc
							(start 0.2159 -0.0381)
							(mid 0 -0.254)
							(end -0.2159 -0.0381)
						)
						(arc
							(start -0.2159 0.0381)
							(mid 0 0.254)
							(end 0.2159 0.0381)
						)
					)
					(width 0)
					(fill yes)
				)
			)
		)
		(pad "B59" smd custom
			(at 14.071092 -26.408126)
			(size 0.10795 0.10795)
			(layers "F.Cu" "F.Mask" "F.Paste")
			(net "PVDDQ_GHJ")
			(options
				(clearance outline)
				(anchor circle)
			)
			(primitives
				(gr_poly
					(pts
						(arc
							(start 0.2159 -0.0381)
							(mid 0 -0.254)
							(end -0.2159 -0.0381)
						)
						(arc
							(start -0.2159 0.0381)
							(mid 0 0.254)
							(end 0.2159 0.0381)
						)
					)
					(width 0)
					(fill yes)
				)
			)
		)
		(pad "B61" smd custom
			(at 15.787878 -26.408126)
			(size 0.10795 0.10795)
			(layers "F.Cu" "F.Mask" "F.Paste")
			(net "M_G_ALERT_N")
			(options
				(clearance outline)
				(anchor circle)
			)
			(primitives
				(gr_poly
					(pts
						(arc
							(start 0.2159 -0.0381)
							(mid 0 -0.254)
							(end -0.2159 -0.0381)
						)
						(arc
							(start -0.2159 0.0381)
							(mid 0 0.254)
							(end 0.2159 0.0381)
						)
					)
					(width 0)
					(fill yes)
				)
			)
		)
		(pad "B63" smd custom
			(at 17.504918 -26.408126)
			(size 0.10795 0.10795)
			(layers "F.Cu" "F.Mask" "F.Paste")
			(net "M_G_CKE<2>")
			(options
				(clearance outline)
				(anchor circle)
			)
			(primitives
				(gr_poly
					(pts
						(arc
							(start 0.2159 -0.0381)
							(mid 0 -0.254)
							(end -0.2159 -0.0381)
						)
						(arc
							(start -0.2159 0.0381)
							(mid 0 0.254)
							(end 0.2159 0.0381)
						)
					)
					(width 0)
					(fill yes)
				)
			)
		)
		(pad "B71" smd custom
			(at 24.373078 -26.408126)
			(size 0.10795 0.10795)
			(layers "F.Cu" "F.Mask" "F.Paste")
			(net "GND")
			(options
				(clearance outline)
				(anchor circle)
			)
			(primitives
				(gr_poly
					(pts
						(arc
							(start 0.2159 -0.0381)
							(mid 0 -0.254)
							(end -0.2159 -0.0381)
						)
						(arc
							(start -0.2159 0.0381)
							(mid 0 0.254)
							(end 0.2159 0.0381)
						)
					)
					(width 0)
					(fill yes)
				)
			)
		)
		(pad "B73" smd custom
			(at 26.090118 -26.408126)
			(size 0.10795 0.10795)
			(layers "F.Cu" "F.Mask" "F.Paste")
			(net "M_H_DQS_DN<12>")
			(options
				(clearance outline)
				(anchor circle)
			)
			(primitives
				(gr_poly
					(pts
						(arc
							(start 0.2159 -0.0381)
							(mid 0 -0.254)
							(end -0.2159 -0.0381)
						)
						(arc
							(start -0.2159 0.0381)
							(mid 0 0.254)
							(end 0.2159 0.0381)
						)
					)
					(width 0)
					(fill yes)
				)
			)
		)
		(pad "B75" smd custom
			(at 27.806904 -26.408126)
			(size 0.10795 0.10795)
			(layers "F.Cu" "F.Mask" "F.Paste")
			(net "GND")
			(options
				(clearance outline)
				(anchor circle)
			)
			(primitives
				(gr_poly
					(pts
						(arc
							(start 0.2159 -0.0381)
							(mid 0 -0.254)
							(end -0.2159 -0.0381)
						)
						(arc
							(start -0.2159 0.0381)
							(mid 0 0.254)
							(end 0.2159 0.0381)
						)
					)
					(width 0)
					(fill yes)
				)
			)
		)
		(pad "B77" smd custom
			(at 29.523944 -26.408126)
			(size 0.10795 0.10795)
			(layers "F.Cu" "F.Mask" "F.Paste")
			(net "TP_CPU1_RSVD_293")
			(options
				(clearance outline)
				(anchor circle)
			)
			(primitives
				(gr_poly
					(pts
						(arc
							(start 0.2159 -0.0381)
							(mid 0 -0.254)
							(end -0.2159 -0.0381)
						)
						(arc
							(start -0.2159 0.0381)
							(mid 0 0.254)
							(end 0.2159 0.0381)
						)
					)
					(width 0)
					(fill yes)
				)
			)
		)
		(pad "B79" smd custom
			(at 31.240984 -26.408126 315)
			(size 0.10795 0.10795)
			(layers "F.Cu" "F.Mask" "F.Paste")
			(net "GND")
			(options
				(clearance outline)
				(anchor circle)
			)
			(primitives
				(gr_poly
					(pts
						(arc
							(start 0.2159 -0.0381)
							(mid 0 -0.254)
							(end -0.2159 -0.0381)
						)
						(arc
							(start -0.2159 0.0381)
							(mid 0 0.254)
							(end 0.2159 0.0381)
						)
					)
					(width 0)
					(fill yes)
				)
			)
		)
		(pad "B81" smd custom
			(at 32.958024 -26.408126 315)
			(size 0.10795 0.10795)
			(layers "F.Cu" "F.Mask" "F.Paste")
			(net "TP_CPU1_RSVD_292")
			(options
				(clearance outline)
				(anchor circle)
			)
			(primitives
				(gr_poly
					(pts
						(arc
							(start 0.2159 -0.0381)
							(mid 0 -0.254)
							(end -0.2159 -0.0381)
						)
						(arc
							(start -0.2159 0.0381)
							(mid 0 0.254)
							(end 0.2159 0.0381)
						)
					)
					(width 0)
					(fill yes)
				)
			)
		)
		(pad "BA2" smd custom
			(at -36.392104 -5.291074 90)
			(size 0.10795 0.10795)
			(layers "F.Cu" "F.Mask" "F.Paste")
			(net "GND")
			(options
				(clearance outline)
				(anchor circle)
			)
			(primitives
				(gr_poly
					(pts
						(arc
							(start 0.2159 -0.0381)
							(mid 0 -0.254)
							(end -0.2159 -0.0381)
						)
						(arc
							(start -0.2159 0.0381)
							(mid 0 0.254)
							(end 0.2159 0.0381)
						)
					)
					(width 0)
					(fill yes)
				)
			)
		)
		(pad "BA4" smd circle
			(at -34.675064 -5.291074)
			(size 0.4318 0.4318)
			(layers "F.Cu" "F.Mask" "F.Paste")
			(net "UPI_CPU1_CPU0_P0P0_DP<16>")
		)
		(pad "BA6" smd circle
			(at -32.958024 -5.291074)
			(size 0.4318 0.4318)
			(layers "F.Cu" "F.Mask" "F.Paste")
			(net "GND")
		)
		(pad "BA8" smd circle
			(at -31.240984 -5.291074)
			(size 0.4318 0.4318)
			(layers "F.Cu" "F.Mask" "F.Paste")
			(net "UPI_CPU0_CPU1_P0P0_DN<13>")
		)
		(pad "BA10" smd circle
			(at -29.523944 -5.291074)
			(size 0.4318 0.4318)
			(layers "F.Cu" "F.Mask" "F.Paste")
			(net "UPI_CPU0_CPU1_P0P0_DN<19>")
		)
		(pad "BA12" smd circle
			(at -27.806904 -5.291074)
			(size 0.4318 0.4318)
			(layers "F.Cu" "F.Mask" "F.Paste")
			(net "GND")
		)
		(pad "BA14" smd circle
			(at -26.090118 -5.291074)
			(size 0.4318 0.4318)
			(layers "F.Cu" "F.Mask" "F.Paste")
			(net "TP_CPU1_RSVD_178")
		)
		(pad "BA16" smd circle
			(at -24.373078 -5.291074)
			(size 0.4318 0.4318)
			(layers "F.Cu" "F.Mask" "F.Paste")
			(net "TP_CPU1_RSVD_177")
		)
		(pad "BA18" smd circle
			(at -22.656038 -5.291074)
			(size 0.4318 0.4318)
			(layers "F.Cu" "F.Mask" "F.Paste")
			(net "TP_CPU1_RSVD_176")
		)
		(pad "BA20" smd circle
			(at -20.938998 -5.291074)
			(size 0.4318 0.4318)
			(layers "F.Cu" "F.Mask" "F.Paste")
			(net "PD_CPU1_BIST_ENABLE")
		)
		(pad "BA22" smd circle
			(at -19.221958 -5.291074)
			(size 0.4318 0.4318)
			(layers "F.Cu" "F.Mask" "F.Paste")
			(net "TP_CPU1_RSVD_175")
		)
		(pad "BA24" smd circle
			(at -17.504918 -5.291074)
			(size 0.4318 0.4318)
			(layers "F.Cu" "F.Mask" "F.Paste")
			(net "PVCCIO_CPU1")
		)
		(pad "BA26" smd circle
			(at -15.787878 -5.291074)
			(size 0.4318 0.4318)
			(layers "F.Cu" "F.Mask" "F.Paste")
			(net "PVCCIO_CPU1")
		)
		(pad "BA60" smd circle
			(at 14.929612 -7.091172)
			(size 0.508 0.508)
			(layers "F.Cu" "F.Mask" "F.Paste")
			(net "PVCCIN_CPU1")
		)
		(pad "BA62" smd circle
			(at 16.646398 -7.091172)
			(size 0.4318 0.4318)
			(layers "F.Cu" "F.Mask" "F.Paste")
			(net "GND")
		)
		(pad "BA64" smd circle
			(at 18.363438 -7.091172)
			(size 0.4318 0.4318)
			(layers "F.Cu" "F.Mask" "F.Paste")
			(net "TP_CPU1_RSVD_174")
		)
		(pad "BA66" smd circle
			(at 20.080478 -7.091172)
			(size 0.4318 0.4318)
			(layers "F.Cu" "F.Mask" "F.Paste")
			(net "TP_CPU1_RSVD_173")
		)
		(pad "BA68" smd circle
			(at 21.797518 -7.091172)
			(size 0.4318 0.4318)
			(layers "F.Cu" "F.Mask" "F.Paste")
			(net "GND")
		)
		(pad "BA70" smd circle
			(at 23.514558 -7.091172)
			(size 0.4318 0.4318)
			(layers "F.Cu" "F.Mask" "F.Paste")
			(net "M_J_ECC<7>")
		)
		(pad "BA72" smd circle
			(at 25.231598 -7.091172)
			(size 0.4318 0.4318)
			(layers "F.Cu" "F.Mask" "F.Paste")
			(net "M_J_ECC<1>")
		)
		(pad "BA74" smd circle
			(at 26.948384 -7.091172)
			(size 0.4318 0.4318)
			(layers "F.Cu" "F.Mask" "F.Paste")
			(net "GND")
		)
		(pad "BA76" smd circle
			(at 28.665424 -7.091172)
			(size 0.4318 0.4318)
			(layers "F.Cu" "F.Mask" "F.Paste")
			(net "TP_CPU1_RSVD_172")
		)
		(pad "BA78" smd circle
			(at 30.382464 -7.091172)
			(size 0.4318 0.4318)
			(layers "F.Cu" "F.Mask" "F.Paste")
			(net "TP_CPU1_RSVD_171")
		)
		(pad "BA80" smd circle
			(at 32.099504 -7.091172)
			(size 0.4318 0.4318)
			(layers "F.Cu" "F.Mask" "F.Paste")
			(net "GND")
		)
		(pad "BA82" smd circle
			(at 33.816544 -7.091172)
			(size 0.4318 0.4318)
			(layers "F.Cu" "F.Mask" "F.Paste")
			(net "TP_CPU1_RSVD_170")
		)
		(pad "BA84" smd circle
			(at 35.533584 -7.091172)
			(size 0.4318 0.4318)
			(layers "F.Cu" "F.Mask" "F.Paste")
			(net "GND")
		)
		(pad "BA86" smd custom
			(at 37.250624 -7.091172 270)
			(size 0.10795 0.10795)
			(layers "F.Cu" "F.Mask" "F.Paste")
			(net "VSENSE_PVCCIN_CPU1_SKT_VSEN")
			(options
				(clearance outline)
				(anchor circle)
			)
			(primitives
				(gr_poly
					(pts
						(arc
							(start 0.2159 -0.0381)
							(mid 0 -0.254)
							(end -0.2159 -0.0381)
						)
						(arc
							(start -0.2159 0.0381)
							(mid 0 0.254)
							(end 0.2159 0.0381)
						)
					)
					(width 0)
					(fill yes)
				)
			)
		)
		(pad "BB3" smd circle
			(at -35.533584 -4.796028)
			(size 0.4318 0.4318)
			(layers "F.Cu" "F.Mask" "F.Paste")
			(net "UPI_CPU1_CPU0_P0P0_DN<17>")
		)
		(pad "BB5" smd circle
			(at -33.816544 -4.796028)
			(size 0.4318 0.4318)
			(layers "F.Cu" "F.Mask" "F.Paste")
			(net "PVCCIO_CPU1")
		)
		(pad "BB7" smd circle
			(at -32.099504 -4.796028)
			(size 0.4318 0.4318)
			(layers "F.Cu" "F.Mask" "F.Paste")
			(net "UPI_CPU0_CPU1_P0P0_DN<14>")
		)
		(pad "BB9" smd circle
			(at -30.382464 -4.796028)
			(size 0.4318 0.4318)
			(layers "F.Cu" "F.Mask" "F.Paste")
			(net "UPI_CPU0_CPU1_P0P0_DP<17>")
		)
		(pad "BB11" smd circle
			(at -28.665424 -4.796028)
			(size 0.4318 0.4318)
			(layers "F.Cu" "F.Mask" "F.Paste")
			(net "UPI_CPU0_CPU1_P0P0_DP<19>")
		)
		(pad "BB13" smd circle
			(at -26.948384 -4.796028)
			(size 0.4318 0.4318)
			(layers "F.Cu" "F.Mask" "F.Paste")
			(net "TP_CPU1_RSVD_169")
		)
		(pad "BB15" smd circle
			(at -25.231598 -4.796028)
			(size 0.4318 0.4318)
			(layers "F.Cu" "F.Mask" "F.Paste")
			(net "TP_CPU1_RSVD_168")
		)
		(pad "BB17" smd circle
			(at -23.514558 -4.796028)
			(size 0.4318 0.4318)
			(layers "F.Cu" "F.Mask" "F.Paste")
			(net "TP_CPU1_RSVD_167")
		)
		(pad "BB19" smd circle
			(at -21.797518 -4.796028)
			(size 0.4318 0.4318)
			(layers "F.Cu" "F.Mask" "F.Paste")
			(net "GND")
		)
		(pad "BB21" smd circle
			(at -20.080478 -4.796028)
			(size 0.4318 0.4318)
			(layers "F.Cu" "F.Mask" "F.Paste")
			(net "TP_CPU1_RSVD_166")
		)
		(pad "BB23" smd circle
			(at -18.363438 -4.796028)
			(size 0.4318 0.4318)
			(layers "F.Cu" "F.Mask" "F.Paste")
			(net "GND")
		)
		(pad "BB25" smd circle
			(at -16.646398 -4.796028)
			(size 0.4318 0.4318)
			(layers "F.Cu" "F.Mask" "F.Paste")
			(net "CLK_100M_CPU1_RC_REFCLK1_DN")
		)
		(pad "BB27" smd circle
			(at -14.929612 -4.796028)
			(size 0.4318 0.4318)
			(layers "F.Cu" "F.Mask" "F.Paste")
			(net "PVCCIO_CPU1")
		)
		(pad "BB61" smd circle
			(at 15.787878 -6.596126)
			(size 0.4318 0.4318)
			(layers "F.Cu" "F.Mask" "F.Paste")
			(net "PVCCIN_CPU1")
		)
		(pad "BB63" smd circle
			(at 17.504918 -6.596126)
			(size 0.4318 0.4318)
			(layers "F.Cu" "F.Mask" "F.Paste")
			(net "GND")
		)
		(pad "BB65" smd circle
			(at 19.221958 -6.596126)
			(size 0.4318 0.4318)
			(layers "F.Cu" "F.Mask" "F.Paste")
			(net "TP_CPU1_RSVD_164")
		)
		(pad "BB67" smd circle
			(at 20.938998 -6.596126)
			(size 0.4318 0.4318)
			(layers "F.Cu" "F.Mask" "F.Paste")
			(net "TP_CPU1_RSVD_163")
		)
		(pad "BB69" smd circle
			(at 22.656038 -6.596126)
			(size 0.4318 0.4318)
			(layers "F.Cu" "F.Mask" "F.Paste")
			(net "GND")
		)
		(pad "BB71" smd circle
			(at 24.373078 -6.596126)
			(size 0.4318 0.4318)
			(layers "F.Cu" "F.Mask" "F.Paste")
			(net "M_J_DQS_DN<8>")
		)
		(pad "BB73" smd circle
			(at 26.090118 -6.596126)
			(size 0.4318 0.4318)
			(layers "F.Cu" "F.Mask" "F.Paste")
			(net "GND")
		)
		(pad "BB75" smd circle
			(at 27.806904 -6.596126)
			(size 0.4318 0.4318)
			(layers "F.Cu" "F.Mask" "F.Paste")
			(net "GND")
		)
		(pad "BB77" smd circle
			(at 29.523944 -6.596126)
			(size 0.4318 0.4318)
			(layers "F.Cu" "F.Mask" "F.Paste")
			(net "GND")
		)
		(pad "BB79" smd circle
			(at 31.240984 -6.596126)
			(size 0.4318 0.4318)
			(layers "F.Cu" "F.Mask" "F.Paste")
			(net "GND")
		)
		(pad "BB81" smd circle
			(at 32.958024 -6.596126)
			(size 0.4318 0.4318)
			(layers "F.Cu" "F.Mask" "F.Paste")
			(net "GND")
		)
		(pad "BB83" smd circle
			(at 34.675064 -6.596126)
			(size 0.4318 0.4318)
			(layers "F.Cu" "F.Mask" "F.Paste")
			(net "GND")
		)
		(pad "BB85" smd custom
			(at 36.392104 -6.596126 270)
			(size 0.10795 0.10795)
			(layers "F.Cu" "F.Mask" "F.Paste")
			(net "PVCCIN_CPU1")
			(options
				(clearance outline)
				(anchor circle)
			)
			(primitives
				(gr_poly
					(pts
						(arc
							(start 0.2159 -0.0381)
							(mid 0 -0.254)
							(end -0.2159 -0.0381)
						)
						(arc
							(start -0.2159 0.0381)
							(mid 0 0.254)
							(end 0.2159 0.0381)
						)
					)
					(width 0)
					(fill yes)
				)
			)
		)
		(pad "BC2" smd custom
			(at -36.392104 -4.300474 90)
			(size 0.10795 0.10795)
			(layers "F.Cu" "F.Mask" "F.Paste")
			(net "UPI_CPU1_CPU0_P0P0_DP<17>")
			(options
				(clearance outline)
				(anchor circle)
			)
			(primitives
				(gr_poly
					(pts
						(arc
							(start 0.2159 -0.0381)
							(mid 0 -0.254)
							(end -0.2159 -0.0381)
						)
						(arc
							(start -0.2159 0.0381)
							(mid 0 0.254)
							(end 0.2159 0.0381)
						)
					)
					(width 0)
					(fill yes)
				)
			)
		)
		(pad "BC4" smd circle
			(at -34.675064 -4.300474)
			(size 0.4318 0.4318)
			(layers "F.Cu" "F.Mask" "F.Paste")
			(net "GND")
		)
		(pad "BC6" smd circle
			(at -32.958024 -4.300474)
			(size 0.4318 0.4318)
			(layers "F.Cu" "F.Mask" "F.Paste")
			(net "UPI_CPU0_CPU1_P0P0_DP<14>")
		)
		(pad "BC8" smd circle
			(at -31.240984 -4.300474)
			(size 0.4318 0.4318)
			(layers "F.Cu" "F.Mask" "F.Paste")
			(net "GND")
		)
		(pad "BC10" smd circle
			(at -29.523944 -4.300474)
			(size 0.4318 0.4318)
			(layers "F.Cu" "F.Mask" "F.Paste")
			(net "UPI_CPU0_CPU1_P0P0_DN<18>")
		)
		(pad "BC12" smd circle
			(at -27.806904 -4.300474)
			(size 0.4318 0.4318)
			(layers "F.Cu" "F.Mask" "F.Paste")
			(net "GND")
		)
		(pad "BC14" smd circle
			(at -26.090118 -4.300474)
			(size 0.4318 0.4318)
			(layers "F.Cu" "F.Mask" "F.Paste")
			(net "TP_CPU1_RSVD_162")
		)
		(pad "BC16" smd circle
			(at -24.373078 -4.300474)
			(size 0.4318 0.4318)
			(layers "F.Cu" "F.Mask" "F.Paste")
			(net "GND")
		)
		(pad "BC18" smd circle
			(at -22.656038 -4.300474)
			(size 0.4318 0.4318)
			(layers "F.Cu" "F.Mask" "F.Paste")
			(net "TP_CPU1_RSVD_161")
		)
		(pad "BC20" smd circle
			(at -20.938998 -4.300474)
			(size 0.4318 0.4318)
			(layers "F.Cu" "F.Mask" "F.Paste")
			(net "TP_CPU1_RSVD_160")
		)
		(pad "BC22" smd circle
			(at -19.221958 -4.300474)
			(size 0.4318 0.4318)
			(layers "F.Cu" "F.Mask" "F.Paste")
			(net "TP_CPU1_RSVD_159")
		)
		(pad "BC24" smd circle
			(at -17.504918 -4.300474)
			(size 0.4318 0.4318)
			(layers "F.Cu" "F.Mask" "F.Paste")
			(net "PWRGD_CPU1_G")
		)
		(pad "BC26" smd circle
			(at -15.787878 -4.300474)
			(size 0.4318 0.4318)
			(layers "F.Cu" "F.Mask" "F.Paste")
			(net "PVCCIO_CPU1")
		)
		(pad "BC60" smd circle
			(at 14.929612 -6.100572)
			(size 0.508 0.508)
			(layers "F.Cu" "F.Mask" "F.Paste")
			(net "PVCCIN_CPU1")
		)
		(pad "BC62" smd circle
			(at 16.646398 -6.100572)
			(size 0.4318 0.4318)
			(layers "F.Cu" "F.Mask" "F.Paste")
			(net "PVCCIN_CPU1")
		)
		(pad "BC64" smd circle
			(at 18.363438 -6.100572)
			(size 0.4318 0.4318)
			(layers "F.Cu" "F.Mask" "F.Paste")
			(net "TP_CPU1_RSVD_158")
		)
		(pad "BC66" smd circle
			(at 20.080478 -6.100572)
			(size 0.4318 0.4318)
			(layers "F.Cu" "F.Mask" "F.Paste")
			(net "TP_CPU1_RSVD_157")
		)
		(pad "BC68" smd circle
			(at 21.797518 -6.100572)
			(size 0.4318 0.4318)
			(layers "F.Cu" "F.Mask" "F.Paste")
			(net "TP_CPU1_RSVD_156")
		)
		(pad "BC70" smd circle
			(at 23.514558 -6.100572)
			(size 0.4318 0.4318)
			(layers "F.Cu" "F.Mask" "F.Paste")
			(net "GND")
		)
		(pad "BC72" smd circle
			(at 25.231598 -6.100572)
			(size 0.4318 0.4318)
			(layers "F.Cu" "F.Mask" "F.Paste")
			(net "GND")
		)
		(pad "BC74" smd circle
			(at 26.948384 -6.100572)
			(size 0.4318 0.4318)
			(layers "F.Cu" "F.Mask" "F.Paste")
			(net "GND")
		)
		(pad "BC76" smd circle
			(at 28.665424 -6.100572)
			(size 0.4318 0.4318)
			(layers "F.Cu" "F.Mask" "F.Paste")
			(net "GND")
		)
		(pad "BC78" smd circle
			(at 30.382464 -6.100572)
			(size 0.4318 0.4318)
			(layers "F.Cu" "F.Mask" "F.Paste")
			(net "GND")
		)
		(pad "BC80" smd circle
			(at 32.099504 -6.100572)
			(size 0.4318 0.4318)
			(layers "F.Cu" "F.Mask" "F.Paste")
			(net "GND")
		)
		(pad "BC82" smd circle
			(at 33.816544 -6.100572)
			(size 0.4318 0.4318)
			(layers "F.Cu" "F.Mask" "F.Paste")
			(net "GND")
		)
		(pad "BC84" smd circle
			(at 35.533584 -6.100572)
			(size 0.4318 0.4318)
			(layers "F.Cu" "F.Mask" "F.Paste")
			(net "PVCCIN_CPU1")
		)
		(pad "BD3" smd custom
			(at -35.533584 -3.805428 90)
			(size 0.10795 0.10795)
			(layers "F.Cu" "F.Mask" "F.Paste")
			(net "UPI_CPU1_CPU0_P0P0_DP<18>")
			(options
				(clearance outline)
				(anchor circle)
			)
			(primitives
				(gr_poly
					(pts
						(arc
							(start 0.2159 -0.0381)
							(mid 0 -0.254)
							(end -0.2159 -0.0381)
						)
						(arc
							(start -0.2159 0.0381)
							(mid 0 0.254)
							(end 0.2159 0.0381)
						)
					)
					(width 0)
					(fill yes)
				)
			)
		)
		(pad "BD5" smd circle
			(at -33.816544 -3.805428)
			(size 0.4318 0.4318)
			(layers "F.Cu" "F.Mask" "F.Paste")
			(net "GND")
		)
		(pad "BD7" smd circle
			(at -32.099504 -3.805428)
			(size 0.4318 0.4318)
			(layers "F.Cu" "F.Mask" "F.Paste")
			(net "UPI_CPU0_CPU1_P0P0_DN<15>")
		)
		(pad "BD9" smd circle
			(at -30.382464 -3.805428)
			(size 0.4318 0.4318)
			(layers "F.Cu" "F.Mask" "F.Paste")
			(net "UPI_CPU0_CPU1_P0P0_DP<18>")
		)
		(pad "BD11" smd circle
			(at -28.665424 -3.805428)
			(size 0.4318 0.4318)
			(layers "F.Cu" "F.Mask" "F.Paste")
			(net "GND")
		)
		(pad "BD13" smd circle
			(at -26.948384 -3.805428)
			(size 0.4318 0.4318)
			(layers "F.Cu" "F.Mask" "F.Paste")
			(net "PVCCMCP_CPU1")
		)
		(pad "BD15" smd circle
			(at -25.231598 -3.805428)
			(size 0.4318 0.4318)
			(layers "F.Cu" "F.Mask" "F.Paste")
			(net "GND")
		)
		(pad "BD17" smd circle
			(at -23.514558 -3.805428)
			(size 0.4318 0.4318)
			(layers "F.Cu" "F.Mask" "F.Paste")
			(net "TP_CPU1_RSVD_155")
		)
		(pad "BD19" smd circle
			(at -21.797518 -3.805428)
			(size 0.4318 0.4318)
			(layers "F.Cu" "F.Mask" "F.Paste")
			(net "TP_CPU1_RSVD_154")
		)
		(pad "BD21" smd circle
			(at -20.080478 -3.805428)
			(size 0.4318 0.4318)
			(layers "F.Cu" "F.Mask" "F.Paste")
			(net "GND")
		)
		(pad "BD23" smd circle
			(at -18.363438 -3.805428)
			(size 0.4318 0.4318)
			(layers "F.Cu" "F.Mask" "F.Paste")
			(net "H_CPU1_BMCINIT")
		)
		(pad "BD25" smd circle
			(at -16.646398 -3.805428)
			(size 0.4318 0.4318)
			(layers "F.Cu" "F.Mask" "F.Paste")
			(net "CLK_100M_CPU1_RC_REFCLK1_DP")
		)
		(pad "BD27" smd circle
			(at -14.929612 -3.805428)
			(size 0.4318 0.4318)
			(layers "F.Cu" "F.Mask" "F.Paste")
			(net "GND")
		)
		(pad "BD61" smd circle
			(at 15.787878 -5.605272)
			(size 0.4318 0.4318)
			(layers "F.Cu" "F.Mask" "F.Paste")
			(net "PVCCIN_CPU1")
		)
		(pad "BD63" smd circle
			(at 17.504918 -5.605272)
			(size 0.4318 0.4318)
			(layers "F.Cu" "F.Mask" "F.Paste")
			(net "GND")
		)
		(pad "BD65" smd circle
			(at 19.221958 -5.605272)
			(size 0.4318 0.4318)
			(layers "F.Cu" "F.Mask" "F.Paste")
			(net "TP_CPU1_RSVD_152")
		)
		(pad "BD67" smd circle
			(at 20.938998 -5.605272)
			(size 0.4318 0.4318)
			(layers "F.Cu" "F.Mask" "F.Paste")
			(net "TP_CPU1_RSVD_151")
		)
		(pad "BD69" smd circle
			(at 22.656038 -5.605272)
			(size 0.4318 0.4318)
			(layers "F.Cu" "F.Mask" "F.Paste")
			(net "TP_CPU1_RSVD_150")
		)
		(pad "BD71" smd circle
			(at 24.373078 -5.605272)
			(size 0.4318 0.4318)
			(layers "F.Cu" "F.Mask" "F.Paste")
			(net "GND")
		)
		(pad "BD73" smd circle
			(at 26.090118 -5.605272)
			(size 0.4318 0.4318)
			(layers "F.Cu" "F.Mask" "F.Paste")
			(net "PVCCIN_CPU1")
		)
		(pad "BD75" smd circle
			(at 27.806904 -5.605272)
			(size 0.4318 0.4318)
			(layers "F.Cu" "F.Mask" "F.Paste")
			(net "PVCCIN_CPU1")
		)
		(pad "BD77" smd circle
			(at 29.523944 -5.605272)
			(size 0.4318 0.4318)
			(layers "F.Cu" "F.Mask" "F.Paste")
			(net "PVCCIN_CPU1")
		)
		(pad "BD79" smd circle
			(at 31.240984 -5.605272)
			(size 0.4318 0.4318)
			(layers "F.Cu" "F.Mask" "F.Paste")
			(net "PVCCIN_CPU1")
		)
		(pad "BD81" smd circle
			(at 32.958024 -5.605272)
			(size 0.4318 0.4318)
			(layers "F.Cu" "F.Mask" "F.Paste")
			(net "PVCCIN_CPU1")
		)
		(pad "BD83" smd circle
			(at 34.675064 -5.605272)
			(size 0.4318 0.4318)
			(layers "F.Cu" "F.Mask" "F.Paste")
			(net "PVCCIN_CPU1")
		)
		(pad "BD85" smd custom
			(at 36.392104 -5.605272 270)
			(size 0.10795 0.10795)
			(layers "F.Cu" "F.Mask" "F.Paste")
			(net "PVCCIN_CPU1")
			(options
				(clearance outline)
				(anchor circle)
			)
			(primitives
				(gr_poly
					(pts
						(arc
							(start 0.2159 -0.0381)
							(mid 0 -0.254)
							(end -0.2159 -0.0381)
						)
						(arc
							(start -0.2159 0.0381)
							(mid 0 0.254)
							(end 0.2159 0.0381)
						)
					)
					(width 0)
					(fill yes)
				)
			)
		)
		(pad "BE4" smd circle
			(at -34.675064 -3.309874)
			(size 0.4318 0.4318)
			(layers "F.Cu" "F.Mask" "F.Paste")
			(net "GND")
		)
		(pad "BE6" smd circle
			(at -32.958024 -3.309874)
			(size 0.4318 0.4318)
			(layers "F.Cu" "F.Mask" "F.Paste")
			(net "GND")
		)
		(pad "BE8" smd circle
			(at -31.240984 -3.309874)
			(size 0.4318 0.4318)
			(layers "F.Cu" "F.Mask" "F.Paste")
			(net "GND")
		)
		(pad "BE10" smd circle
			(at -29.523944 -3.309874)
			(size 0.4318 0.4318)
			(layers "F.Cu" "F.Mask" "F.Paste")
			(net "GND")
		)
		(pad "BE12" smd circle
			(at -27.806904 -3.309874)
			(size 0.4318 0.4318)
			(layers "F.Cu" "F.Mask" "F.Paste")
			(net "PVCCMCP_CPU1")
		)
		(pad "BE14" smd circle
			(at -26.090118 -3.309874)
			(size 0.4318 0.4318)
			(layers "F.Cu" "F.Mask" "F.Paste")
			(net "PVCCMCP_CPU1")
		)
		(pad "BE16" smd circle
			(at -24.373078 -3.309874)
			(size 0.4318 0.4318)
			(layers "F.Cu" "F.Mask" "F.Paste")
			(net "CLK_156M_OSC_CPU1_HFI_DN")
		)
		(pad "BE18" smd circle
			(at -22.656038 -3.309874)
			(size 0.4318 0.4318)
			(layers "F.Cu" "F.Mask" "F.Paste")
			(net "TP_CPU1_RSVD_149")
		)
		(pad "BE20" smd circle
			(at -20.938998 -3.309874)
			(size 0.4318 0.4318)
			(layers "F.Cu" "F.Mask" "F.Paste")
			(net "TP_CPU1_RSVD_148")
		)
		(pad "BE22" smd circle
			(at -19.221958 -3.309874)
			(size 0.4318 0.4318)
			(layers "F.Cu" "F.Mask" "F.Paste")
			(net "TP_CPU1_RSVD_147")
		)
		(pad "BE24" smd circle
			(at -17.504918 -3.309874)
			(size 0.4318 0.4318)
			(layers "F.Cu" "F.Mask" "F.Paste")
			(net "PVCCIO_CPU1")
		)
		(pad "BE26" smd circle
			(at -15.787878 -3.309874)
			(size 0.4318 0.4318)
			(layers "F.Cu" "F.Mask" "F.Paste")
			(net "GND")
		)
		(pad "BE60" smd circle
			(at 14.929612 -5.109972)
			(size 0.508 0.508)
			(layers "F.Cu" "F.Mask" "F.Paste")
			(net "PVCCIN_CPU1")
		)
		(pad "BE62" smd circle
			(at 16.646398 -5.109972)
			(size 0.4318 0.4318)
			(layers "F.Cu" "F.Mask" "F.Paste")
			(net "PVCCIN_CPU1")
		)
		(pad "BE64" smd circle
			(at 18.363438 -5.109972)
			(size 0.4318 0.4318)
			(layers "F.Cu" "F.Mask" "F.Paste")
			(net "GND")
		)
		(pad "BE66" smd circle
			(at 20.080478 -5.109972)
			(size 0.4318 0.4318)
			(layers "F.Cu" "F.Mask" "F.Paste")
			(net "GND")
		)
		(pad "BE68" smd circle
			(at 21.797518 -5.109972)
			(size 0.4318 0.4318)
			(layers "F.Cu" "F.Mask" "F.Paste")
			(net "GND")
		)
		(pad "BE70" smd circle
			(at 23.514558 -5.109972)
			(size 0.4318 0.4318)
			(layers "F.Cu" "F.Mask" "F.Paste")
			(net "GND")
		)
		(pad "BE72" smd circle
			(at 25.231598 -5.109972)
			(size 0.4318 0.4318)
			(layers "F.Cu" "F.Mask" "F.Paste")
			(net "PVCCIN_CPU1")
		)
		(pad "BE74" smd circle
			(at 26.948384 -5.109972)
			(size 0.4318 0.4318)
			(layers "F.Cu" "F.Mask" "F.Paste")
			(net "PVCCIN_CPU1")
		)
		(pad "BE76" smd circle
			(at 28.665424 -5.109972)
			(size 0.4318 0.4318)
			(layers "F.Cu" "F.Mask" "F.Paste")
			(net "PVCCIN_CPU1")
		)
		(pad "BE78" smd circle
			(at 30.382464 -5.109972)
			(size 0.4318 0.4318)
			(layers "F.Cu" "F.Mask" "F.Paste")
			(net "PVCCIN_CPU1")
		)
		(pad "BE80" smd circle
			(at 32.099504 -5.109972)
			(size 0.4318 0.4318)
			(layers "F.Cu" "F.Mask" "F.Paste")
			(net "PVCCIN_CPU1")
		)
		(pad "BE82" smd circle
			(at 33.816544 -5.109972)
			(size 0.4318 0.4318)
			(layers "F.Cu" "F.Mask" "F.Paste")
			(net "PVCCIN_CPU1")
		)
		(pad "BE84" smd circle
			(at 35.533584 -5.109972)
			(size 0.4318 0.4318)
			(layers "F.Cu" "F.Mask" "F.Paste")
			(net "PVCCIN_CPU1")
		)
		(pad "BF3" smd custom
			(at -35.533584 -2.814828 90)
			(size 0.10795 0.10795)
			(layers "F.Cu" "F.Mask" "F.Paste")
			(net "UPI_CPU1_CPU0_P0P0_DN<18>")
			(options
				(clearance outline)
				(anchor circle)
			)
			(primitives
				(gr_poly
					(pts
						(arc
							(start 0.2159 -0.0381)
							(mid 0 -0.254)
							(end -0.2159 -0.0381)
						)
						(arc
							(start -0.2159 0.0381)
							(mid 0 0.254)
							(end 0.2159 0.0381)
						)
					)
					(width 0)
					(fill yes)
				)
			)
		)
		(pad "BF5" smd circle
			(at -33.816544 -2.814828)
			(size 0.4318 0.4318)
			(layers "F.Cu" "F.Mask" "F.Paste")
			(net "VSENSE_PVCCIO_CPU1_SKT_VRTN")
		)
		(pad "BF7" smd circle
			(at -32.099504 -2.814828)
			(size 0.4318 0.4318)
			(layers "F.Cu" "F.Mask" "F.Paste")
			(net "UPI_CPU0_CPU1_P0P0_DP<15>")
		)
		(pad "BF9" smd circle
			(at -30.382464 -2.814828)
			(size 0.4318 0.4318)
			(layers "F.Cu" "F.Mask" "F.Paste")
			(net "GND")
		)
		(pad "BF11" smd circle
			(at -28.665424 -2.814828)
			(size 0.4318 0.4318)
			(layers "F.Cu" "F.Mask" "F.Paste")
			(net "PVCCMCP_CPU1")
		)
		(pad "BF13" smd circle
			(at -26.948384 -2.814828)
			(size 0.4318 0.4318)
			(layers "F.Cu" "F.Mask" "F.Paste")
			(net "PVCCMCP_CPU1")
		)
		(pad "BF15" smd circle
			(at -25.231598 -2.814828)
			(size 0.4318 0.4318)
			(layers "F.Cu" "F.Mask" "F.Paste")
			(net "GND")
		)
		(pad "BF17" smd circle
			(at -23.514558 -2.814828)
			(size 0.4318 0.4318)
			(layers "F.Cu" "F.Mask" "F.Paste")
			(net "GND")
		)
		(pad "BF19" smd circle
			(at -21.797518 -2.814828)
			(size 0.4318 0.4318)
			(layers "F.Cu" "F.Mask" "F.Paste")
			(net "GND")
		)
		(pad "BF21" smd circle
			(at -20.080478 -2.814828)
			(size 0.4318 0.4318)
			(layers "F.Cu" "F.Mask" "F.Paste")
			(net "TP_CPU1_RSVD_146")
		)
		(pad "BF23" smd circle
			(at -18.363438 -2.814828)
			(size 0.4318 0.4318)
			(layers "F.Cu" "F.Mask" "F.Paste")
			(net "PVCCIO_CPU1")
		)
		(pad "BF25" smd circle
			(at -16.646398 -2.814828)
			(size 0.4318 0.4318)
			(layers "F.Cu" "F.Mask" "F.Paste")
			(net "GND")
		)
		(pad "BF27" smd circle
			(at -14.929612 -2.814828)
			(size 0.4318 0.4318)
			(layers "F.Cu" "F.Mask" "F.Paste")
			(net "PVCCIO_CPU1")
		)
		(pad "BF61" smd circle
			(at 15.787878 -4.614926)
			(size 0.4318 0.4318)
			(layers "F.Cu" "F.Mask" "F.Paste")
			(net "PVCCIN_CPU1")
		)
		(pad "BF63" smd circle
			(at 17.504918 -4.614926)
			(size 0.4318 0.4318)
			(layers "F.Cu" "F.Mask" "F.Paste")
			(net "GND")
		)
		(pad "BF65" smd circle
			(at 19.221958 -4.614926)
			(size 0.4318 0.4318)
			(layers "F.Cu" "F.Mask" "F.Paste")
			(net "GND")
		)
		(pad "BF67" smd circle
			(at 20.938998 -4.614926)
			(size 0.4318 0.4318)
			(layers "F.Cu" "F.Mask" "F.Paste")
			(net "GND")
		)
		(pad "BF69" smd circle
			(at 22.656038 -4.614926)
			(size 0.4318 0.4318)
			(layers "F.Cu" "F.Mask" "F.Paste")
			(net "GND")
		)
		(pad "BF71" smd circle
			(at 24.373078 -4.614926)
			(size 0.4318 0.4318)
			(layers "F.Cu" "F.Mask" "F.Paste")
			(net "GND")
		)
		(pad "BF73" smd circle
			(at 26.090118 -4.614926)
			(size 0.4318 0.4318)
			(layers "F.Cu" "F.Mask" "F.Paste")
			(net "PVCCIN_CPU1")
		)
		(pad "BF75" smd circle
			(at 27.806904 -4.614926)
			(size 0.4318 0.4318)
			(layers "F.Cu" "F.Mask" "F.Paste")
			(net "PVCCIN_CPU1")
		)
		(pad "BF77" smd circle
			(at 29.523944 -4.614926)
			(size 0.4318 0.4318)
			(layers "F.Cu" "F.Mask" "F.Paste")
			(net "PVCCIN_CPU1")
		)
		(pad "BF79" smd circle
			(at 31.240984 -4.614926)
			(size 0.4318 0.4318)
			(layers "F.Cu" "F.Mask" "F.Paste")
			(net "PVCCIN_CPU1")
		)
		(pad "BF81" smd circle
			(at 32.958024 -4.614926)
			(size 0.4318 0.4318)
			(layers "F.Cu" "F.Mask" "F.Paste")
			(net "PVCCIN_CPU1")
		)
		(pad "BF83" smd circle
			(at 34.675064 -4.614926)
			(size 0.4318 0.4318)
			(layers "F.Cu" "F.Mask" "F.Paste")
			(net "PVCCIN_CPU1")
		)
		(pad "BF85" smd custom
			(at 36.392104 -4.614926 270)
			(size 0.10795 0.10795)
			(layers "F.Cu" "F.Mask" "F.Paste")
			(net "PVCCIN_CPU1")
			(options
				(clearance outline)
				(anchor circle)
			)
			(primitives
				(gr_poly
					(pts
						(arc
							(start 0.2159 -0.0381)
							(mid 0 -0.254)
							(end -0.2159 -0.0381)
						)
						(arc
							(start -0.2159 0.0381)
							(mid 0 0.254)
							(end 0.2159 0.0381)
						)
					)
					(width 0)
					(fill yes)
				)
			)
		)
		(pad "BG4" smd circle
			(at -34.675064 -2.319274)
			(size 0.4318 0.4318)
			(layers "F.Cu" "F.Mask" "F.Paste")
			(net "UPI_CPU1_CPU0_P0P0_DP<19>")
		)
		(pad "BG6" smd circle
			(at -32.958024 -2.319274)
			(size 0.4318 0.4318)
			(layers "F.Cu" "F.Mask" "F.Paste")
			(net "GND")
		)
		(pad "BG8" smd circle
			(at -31.240984 -2.319274)
			(size 0.4318 0.4318)
			(layers "F.Cu" "F.Mask" "F.Paste")
			(net "GND")
		)
		(pad "BG10" smd circle
			(at -29.523944 -2.319274)
			(size 0.4318 0.4318)
			(layers "F.Cu" "F.Mask" "F.Paste")
			(net "GND")
		)
		(pad "BG12" smd circle
			(at -27.806904 -2.319274)
			(size 0.4318 0.4318)
			(layers "F.Cu" "F.Mask" "F.Paste")
			(net "PVCCMCP_CPU1")
		)
		(pad "BG14" smd circle
			(at -26.090118 -2.319274)
			(size 0.4318 0.4318)
			(layers "F.Cu" "F.Mask" "F.Paste")
			(net "PVCCMCP_CPU1")
		)
		(pad "BG16" smd circle
			(at -24.373078 -2.319274)
			(size 0.4318 0.4318)
			(layers "F.Cu" "F.Mask" "F.Paste")
			(net "CLK_156M_OSC_CPU1_HFI_DP")
		)
		(pad "BG18" smd circle
			(at -22.656038 -2.319274)
			(size 0.4318 0.4318)
			(layers "F.Cu" "F.Mask" "F.Paste")
			(net "TP_CPU1_RSVD_145")
		)
		(pad "BG20" smd circle
			(at -20.938998 -2.319274)
			(size 0.4318 0.4318)
			(layers "F.Cu" "F.Mask" "F.Paste")
			(net "TP_CPU1_RSVD_144")
		)
		(pad "BG22" smd circle
			(at -19.221958 -2.319274)
			(size 0.4318 0.4318)
			(layers "F.Cu" "F.Mask" "F.Paste")
			(net "GND")
		)
		(pad "BG24" smd circle
			(at -17.504918 -2.319274)
			(size 0.4318 0.4318)
			(layers "F.Cu" "F.Mask" "F.Paste")
			(net "GND")
		)
		(pad "BG26" smd circle
			(at -15.787878 -2.319274)
			(size 0.4318 0.4318)
			(layers "F.Cu" "F.Mask" "F.Paste")
			(net "PVCCIO_CPU1")
		)
		(pad "BG60" smd circle
			(at 14.929612 -4.119372)
			(size 0.508 0.508)
			(layers "F.Cu" "F.Mask" "F.Paste")
			(net "PVCCIN_CPU1")
		)
		(pad "BG62" smd circle
			(at 16.646398 -4.119372)
			(size 0.4318 0.4318)
			(layers "F.Cu" "F.Mask" "F.Paste")
			(net "PVCCIN_CPU1")
		)
		(pad "BG64" smd circle
			(at 18.363438 -4.119372)
			(size 0.4318 0.4318)
			(layers "F.Cu" "F.Mask" "F.Paste")
			(net "PVCCIN_CPU1")
		)
		(pad "BG66" smd circle
			(at 20.080478 -4.119372)
			(size 0.4318 0.4318)
			(layers "F.Cu" "F.Mask" "F.Paste")
			(net "PVCCIN_CPU1")
		)
		(pad "BG68" smd circle
			(at 21.797518 -4.119372)
			(size 0.4318 0.4318)
			(layers "F.Cu" "F.Mask" "F.Paste")
			(net "PVCCIN_CPU1")
		)
		(pad "BG70" smd circle
			(at 23.514558 -4.119372)
			(size 0.4318 0.4318)
			(layers "F.Cu" "F.Mask" "F.Paste")
			(net "PVCCIN_CPU1")
		)
		(pad "BG72" smd circle
			(at 25.231598 -4.119372)
			(size 0.4318 0.4318)
			(layers "F.Cu" "F.Mask" "F.Paste")
			(net "GND")
		)
		(pad "BG74" smd circle
			(at 26.948384 -4.119372)
			(size 0.4318 0.4318)
			(layers "F.Cu" "F.Mask" "F.Paste")
			(net "GND")
		)
		(pad "BG76" smd circle
			(at 28.665424 -4.119372)
			(size 0.4318 0.4318)
			(layers "F.Cu" "F.Mask" "F.Paste")
			(net "GND")
		)
		(pad "BG78" smd circle
			(at 30.382464 -4.119372)
			(size 0.4318 0.4318)
			(layers "F.Cu" "F.Mask" "F.Paste")
			(net "GND")
		)
		(pad "BG80" smd circle
			(at 32.099504 -4.119372)
			(size 0.4318 0.4318)
			(layers "F.Cu" "F.Mask" "F.Paste")
			(net "GND")
		)
		(pad "BG82" smd circle
			(at 33.816544 -4.119372)
			(size 0.4318 0.4318)
			(layers "F.Cu" "F.Mask" "F.Paste")
			(net "GND")
		)
		(pad "BG84" smd custom
			(at 35.533584 -4.119372 270)
			(size 0.10795 0.10795)
			(layers "F.Cu" "F.Mask" "F.Paste")
			(net "PVCCIN_CPU1")
			(options
				(clearance outline)
				(anchor circle)
			)
			(primitives
				(gr_poly
					(pts
						(arc
							(start 0.2159 -0.0381)
							(mid 0 -0.254)
							(end -0.2159 -0.0381)
						)
						(arc
							(start -0.2159 0.0381)
							(mid 0 0.254)
							(end 0.2159 0.0381)
						)
					)
					(width 0)
					(fill yes)
				)
			)
		)
		(pad "BH3" smd custom
			(at -35.533584 -1.824228 90)
			(size 0.10795 0.10795)
			(layers "F.Cu" "F.Mask" "F.Paste")
			(net "UPI_CPU1_CPU0_P0P0_DN<19>")
			(options
				(clearance outline)
				(anchor circle)
			)
			(primitives
				(gr_poly
					(pts
						(arc
							(start 0.2159 -0.0381)
							(mid 0 -0.254)
							(end -0.2159 -0.0381)
						)
						(arc
							(start -0.2159 0.0381)
							(mid 0 0.254)
							(end 0.2159 0.0381)
						)
					)
					(width 0)
					(fill yes)
				)
			)
		)
		(pad "BH5" smd circle
			(at -33.816544 -1.824228)
			(size 0.4318 0.4318)
			(layers "F.Cu" "F.Mask" "F.Paste")
			(net "VSENSE_PVCCIO_CPU1_SKT_VSEN")
		)
		(pad "BH7" smd circle
			(at -32.099504 -1.824228)
			(size 0.4318 0.4318)
			(layers "F.Cu" "F.Mask" "F.Paste")
			(net "GND")
		)
		(pad "BH9" smd circle
			(at -30.382464 -1.824228)
			(size 0.4318 0.4318)
			(layers "F.Cu" "F.Mask" "F.Paste")
			(net "GND")
		)
		(pad "BH11" smd circle
			(at -28.665424 -1.824228)
			(size 0.4318 0.4318)
			(layers "F.Cu" "F.Mask" "F.Paste")
			(net "GND")
		)
		(pad "BH13" smd circle
			(at -26.948384 -1.824228)
			(size 0.4318 0.4318)
			(layers "F.Cu" "F.Mask" "F.Paste")
			(net "PVCCMCP_CPU1")
		)
		(pad "BH15" smd circle
			(at -25.231598 -1.824228)
			(size 0.4318 0.4318)
			(layers "F.Cu" "F.Mask" "F.Paste")
			(net "GND")
		)
		(pad "BH17" smd circle
			(at -23.514558 -1.824228)
			(size 0.4318 0.4318)
			(layers "F.Cu" "F.Mask" "F.Paste")
			(net "GND")
		)
		(pad "BH19" smd circle
			(at -21.797518 -1.824228)
			(size 0.4318 0.4318)
			(layers "F.Cu" "F.Mask" "F.Paste")
			(net "PVCCMCP_CPU1")
		)
		(pad "BH21" smd circle
			(at -20.080478 -1.824228)
			(size 0.4318 0.4318)
			(layers "F.Cu" "F.Mask" "F.Paste")
			(net "GND")
		)
		(pad "BH23" smd circle
			(at -18.363438 -1.824228)
			(size 0.4318 0.4318)
			(layers "F.Cu" "F.Mask" "F.Paste")
			(net "TP_CD_HFI1_CPU1_I2CDAT")
		)
		(pad "BH25" smd circle
			(at -16.646398 -1.824228)
			(size 0.4318 0.4318)
			(layers "F.Cu" "F.Mask" "F.Paste")
			(net "PVCCIO_CPU1")
		)
		(pad "BH27" smd circle
			(at -14.929612 -1.824228)
			(size 0.4318 0.4318)
			(layers "F.Cu" "F.Mask" "F.Paste")
			(net "PVCCIO_CPU1")
		)
		(pad "BH61" smd circle
			(at 15.787878 -3.624326)
			(size 0.4318 0.4318)
			(layers "F.Cu" "F.Mask" "F.Paste")
			(net "PVCCIN_CPU1")
		)
		(pad "BH63" smd circle
			(at 17.504918 -3.624326)
			(size 0.4318 0.4318)
			(layers "F.Cu" "F.Mask" "F.Paste")
			(net "PVCCIN_CPU1")
		)
		(pad "BH65" smd circle
			(at 19.221958 -3.624326)
			(size 0.4318 0.4318)
			(layers "F.Cu" "F.Mask" "F.Paste")
			(net "PVCCIN_CPU1")
		)
		(pad "BH67" smd circle
			(at 20.938998 -3.624326)
			(size 0.4318 0.4318)
			(layers "F.Cu" "F.Mask" "F.Paste")
			(net "PVCCIN_CPU1")
		)
		(pad "BH69" smd circle
			(at 22.656038 -3.624326)
			(size 0.4318 0.4318)
			(layers "F.Cu" "F.Mask" "F.Paste")
			(net "PVCCIN_CPU1")
		)
		(pad "BH71" smd circle
			(at 24.373078 -3.624326)
			(size 0.4318 0.4318)
			(layers "F.Cu" "F.Mask" "F.Paste")
			(net "PVCCIN_CPU1")
		)
		(pad "BH73" smd circle
			(at 26.090118 -3.624326)
			(size 0.4318 0.4318)
			(layers "F.Cu" "F.Mask" "F.Paste")
			(net "PVCCIN_CPU1")
		)
		(pad "BH75" smd circle
			(at 27.806904 -3.624326)
			(size 0.4318 0.4318)
			(layers "F.Cu" "F.Mask" "F.Paste")
			(net "PVCCIN_CPU1")
		)
		(pad "BH77" smd circle
			(at 29.523944 -3.624326)
			(size 0.4318 0.4318)
			(layers "F.Cu" "F.Mask" "F.Paste")
			(net "PVCCIN_CPU1")
		)
		(pad "BH79" smd circle
			(at 31.240984 -3.624326)
			(size 0.4318 0.4318)
			(layers "F.Cu" "F.Mask" "F.Paste")
			(net "PVCCIN_CPU1")
		)
		(pad "BH81" smd circle
			(at 32.958024 -3.624326)
			(size 0.4318 0.4318)
			(layers "F.Cu" "F.Mask" "F.Paste")
			(net "PVCCIN_CPU1")
		)
		(pad "BH83" smd circle
			(at 34.675064 -3.624326)
			(size 0.4318 0.4318)
			(layers "F.Cu" "F.Mask" "F.Paste")
			(net "PVCCIN_CPU1")
		)
		(pad "BJ4" smd circle
			(at -34.675064 -1.328674)
			(size 0.4318 0.4318)
			(layers "F.Cu" "F.Mask" "F.Paste")
			(net "GND")
		)
		(pad "BJ6" smd circle
			(at -32.958024 -1.328674)
			(size 0.4318 0.4318)
			(layers "F.Cu" "F.Mask" "F.Paste")
			(net "GND")
		)
		(pad "BJ8" smd circle
			(at -31.240984 -1.328674)
			(size 0.4318 0.4318)
			(layers "F.Cu" "F.Mask" "F.Paste")
			(net "TP_P3E_CPU1_PE2_RSR_RXP<14>")
		)
		(pad "BJ10" smd circle
			(at -29.523944 -1.328674)
			(size 0.4318 0.4318)
			(layers "F.Cu" "F.Mask" "F.Paste")
			(net "TP_P3E_CPU1_PE2_RSR_RXP<15>")
		)
		(pad "BJ12" smd circle
			(at -27.806904 -1.328674)
			(size 0.4318 0.4318)
			(layers "F.Cu" "F.Mask" "F.Paste")
			(net "PVCCMCP_CPU1")
		)
		(pad "BJ14" smd circle
			(at -26.090118 -1.328674)
			(size 0.4318 0.4318)
			(layers "F.Cu" "F.Mask" "F.Paste")
			(net "PVCCMCP_CPU1")
		)
		(pad "BJ16" smd circle
			(at -24.373078 -1.328674)
			(size 0.4318 0.4318)
			(layers "F.Cu" "F.Mask" "F.Paste")
			(net "PVCCMCP_CPU1")
		)
		(pad "BJ18" smd circle
			(at -22.656038 -1.328674)
			(size 0.4318 0.4318)
			(layers "F.Cu" "F.Mask" "F.Paste")
			(net "PVCCMCP_CPU1")
		)
		(pad "BJ20" smd circle
			(at -20.938998 -1.328674)
			(size 0.4318 0.4318)
			(layers "F.Cu" "F.Mask" "F.Paste")
			(net "PVCCMCP_CPU1")
		)
		(pad "BJ22" smd circle
			(at -19.221958 -1.328674)
			(size 0.4318 0.4318)
			(layers "F.Cu" "F.Mask" "F.Paste")
			(net "TP_CD_HFI1_CPU1_I2CLK")
		)
		(pad "BJ24" smd circle
			(at -17.504918 -1.328674)
			(size 0.4318 0.4318)
			(layers "F.Cu" "F.Mask" "F.Paste")
			(net "PVCCIO_CPU1")
		)
		(pad "BJ26" smd circle
			(at -15.787878 -1.328674)
			(size 0.4318 0.4318)
			(layers "F.Cu" "F.Mask" "F.Paste")
			(net "PVCCIO_CPU1")
		)
		(pad "BJ60" smd circle
			(at 14.929612 -3.128772)
			(size 0.508 0.508)
			(layers "F.Cu" "F.Mask" "F.Paste")
			(net "PVCCIN_CPU1")
		)
		(pad "BJ62" smd circle
			(at 16.646398 -3.128772)
			(size 0.4318 0.4318)
			(layers "F.Cu" "F.Mask" "F.Paste")
			(net "PVCCIN_CPU1")
		)
		(pad "BJ64" smd circle
			(at 18.363438 -3.128772)
			(size 0.4318 0.4318)
			(layers "F.Cu" "F.Mask" "F.Paste")
			(net "PVCCIN_CPU1")
		)
		(pad "BJ66" smd circle
			(at 20.080478 -3.128772)
			(size 0.4318 0.4318)
			(layers "F.Cu" "F.Mask" "F.Paste")
			(net "PVCCIN_CPU1")
		)
		(pad "BJ68" smd circle
			(at 21.797518 -3.128772)
			(size 0.4318 0.4318)
			(layers "F.Cu" "F.Mask" "F.Paste")
			(net "PVCCIN_CPU1")
		)
		(pad "BJ70" smd circle
			(at 23.514558 -3.128772)
			(size 0.4318 0.4318)
			(layers "F.Cu" "F.Mask" "F.Paste")
			(net "PVCCIN_CPU1")
		)
		(pad "BJ72" smd circle
			(at 25.231598 -3.128772)
			(size 0.4318 0.4318)
			(layers "F.Cu" "F.Mask" "F.Paste")
			(net "PVCCIN_CPU1")
		)
		(pad "BJ74" smd circle
			(at 26.948384 -3.128772)
			(size 0.4318 0.4318)
			(layers "F.Cu" "F.Mask" "F.Paste")
			(net "PVCCIN_CPU1")
		)
		(pad "BJ76" smd circle
			(at 28.665424 -3.128772)
			(size 0.4318 0.4318)
			(layers "F.Cu" "F.Mask" "F.Paste")
			(net "PVCCIN_CPU1")
		)
		(pad "BJ78" smd circle
			(at 30.382464 -3.128772)
			(size 0.4318 0.4318)
			(layers "F.Cu" "F.Mask" "F.Paste")
			(net "PVCCIN_CPU1")
		)
		(pad "BJ80" smd circle
			(at 32.099504 -3.128772)
			(size 0.4318 0.4318)
			(layers "F.Cu" "F.Mask" "F.Paste")
			(net "PVCCIN_CPU1")
		)
		(pad "BJ82" smd circle
			(at 33.816544 -3.128772)
			(size 0.4318 0.4318)
			(layers "F.Cu" "F.Mask" "F.Paste")
			(net "PVCCIN_CPU1")
		)
		(pad "BJ84" smd custom
			(at 35.533584 -3.128772 270)
			(size 0.10795 0.10795)
			(layers "F.Cu" "F.Mask" "F.Paste")
			(net "PVCCIN_CPU1")
			(options
				(clearance outline)
				(anchor circle)
			)
			(primitives
				(gr_poly
					(pts
						(arc
							(start 0.2159 -0.0381)
							(mid 0 -0.254)
							(end -0.2159 -0.0381)
						)
						(arc
							(start -0.2159 0.0381)
							(mid 0 0.254)
							(end 0.2159 0.0381)
						)
					)
					(width 0)
					(fill yes)
				)
			)
		)
		(pad "BK3" smd custom
			(at -35.533584 -0.833628 90)
			(size 0.10795 0.10795)
			(layers "F.Cu" "F.Mask" "F.Paste")
			(net "GND")
			(options
				(clearance outline)
				(anchor circle)
			)
			(primitives
				(gr_poly
					(pts
						(arc
							(start 0.2159 -0.0381)
							(mid 0 -0.254)
							(end -0.2159 -0.0381)
						)
						(arc
							(start -0.2159 0.0381)
							(mid 0 0.254)
							(end 0.2159 0.0381)
						)
					)
					(width 0)
					(fill yes)
				)
			)
		)
		(pad "BK5" smd circle
			(at -33.816544 -0.833628)
			(size 0.4318 0.4318)
			(layers "F.Cu" "F.Mask" "F.Paste")
			(net "TP_P3E_CPU1_PE2_RSR_TXP<15>")
		)
		(pad "BK7" smd circle
			(at -32.099504 -0.833628)
			(size 0.4318 0.4318)
			(layers "F.Cu" "F.Mask" "F.Paste")
			(net "GND")
		)
		(pad "BK9" smd circle
			(at -30.382464 -0.833628)
			(size 0.4318 0.4318)
			(layers "F.Cu" "F.Mask" "F.Paste")
			(net "TP_P3E_CPU1_PE2_RSR_RXN<15>")
		)
		(pad "BK11" smd circle
			(at -28.665424 -0.833628)
			(size 0.4318 0.4318)
			(layers "F.Cu" "F.Mask" "F.Paste")
			(net "GND")
		)
		(pad "BK13" smd circle
			(at -26.948384 -0.833628)
			(size 0.4318 0.4318)
			(layers "F.Cu" "F.Mask" "F.Paste")
			(net "PVCCMCP_CPU1")
		)
		(pad "BK15" smd circle
			(at -25.231598 -0.833628)
			(size 0.4318 0.4318)
			(layers "F.Cu" "F.Mask" "F.Paste")
			(net "PVCCMCP_CPU1")
		)
		(pad "BK17" smd circle
			(at -23.514558 -0.833628)
			(size 0.4318 0.4318)
			(layers "F.Cu" "F.Mask" "F.Paste")
			(net "PVCCMCP_CPU1")
		)
		(pad "BK19" smd circle
			(at -21.797518 -0.833628)
			(size 0.4318 0.4318)
			(layers "F.Cu" "F.Mask" "F.Paste")
			(net "GND")
		)
		(pad "BK21" smd circle
			(at -20.080478 -0.833628)
			(size 0.4318 0.4318)
			(layers "F.Cu" "F.Mask" "F.Paste")
			(net "TP_LED_CPU1_CD_HFI0_N")
		)
		(pad "BK23" smd circle
			(at -18.363438 -0.833628)
			(size 0.4318 0.4318)
			(layers "F.Cu" "F.Mask" "F.Paste")
			(net "TP_CD_HFI1_CPU1_RESET_N")
		)
		(pad "BK25" smd circle
			(at -16.646398 -0.833628)
			(size 0.4318 0.4318)
			(layers "F.Cu" "F.Mask" "F.Paste")
			(net "PVCCIO_CPU1")
		)
		(pad "BK27" smd circle
			(at -14.929612 -0.833628)
			(size 0.4318 0.4318)
			(layers "F.Cu" "F.Mask" "F.Paste")
			(net "PVCCIO_CPU1")
		)
		(pad "BK61" smd circle
			(at 15.787878 -2.633726)
			(size 0.4318 0.4318)
			(layers "F.Cu" "F.Mask" "F.Paste")
			(net "PVCCIN_CPU1")
		)
		(pad "BK63" smd circle
			(at 17.504918 -2.633726)
			(size 0.4318 0.4318)
			(layers "F.Cu" "F.Mask" "F.Paste")
			(net "PVCCIN_CPU1")
		)
		(pad "BK65" smd circle
			(at 19.221958 -2.633726)
			(size 0.4318 0.4318)
			(layers "F.Cu" "F.Mask" "F.Paste")
			(net "PVCCIN_CPU1")
		)
		(pad "BK67" smd circle
			(at 20.938998 -2.633726)
			(size 0.4318 0.4318)
			(layers "F.Cu" "F.Mask" "F.Paste")
			(net "PVCCIN_CPU1")
		)
		(pad "BK69" smd circle
			(at 22.656038 -2.633726)
			(size 0.4318 0.4318)
			(layers "F.Cu" "F.Mask" "F.Paste")
			(net "PVCCIN_CPU1")
		)
		(pad "BK71" smd circle
			(at 24.373078 -2.633726)
			(size 0.4318 0.4318)
			(layers "F.Cu" "F.Mask" "F.Paste")
			(net "PVCCIN_CPU1")
		)
		(pad "BK73" smd circle
			(at 26.090118 -2.633726)
			(size 0.4318 0.4318)
			(layers "F.Cu" "F.Mask" "F.Paste")
			(net "PVCCIN_CPU1")
		)
		(pad "BK75" smd circle
			(at 27.806904 -2.633726)
			(size 0.4318 0.4318)
			(layers "F.Cu" "F.Mask" "F.Paste")
			(net "PVCCIN_CPU1")
		)
		(pad "BK77" smd circle
			(at 29.523944 -2.633726)
			(size 0.4318 0.4318)
			(layers "F.Cu" "F.Mask" "F.Paste")
			(net "PVCCIN_CPU1")
		)
		(pad "BK79" smd circle
			(at 31.240984 -2.633726)
			(size 0.4318 0.4318)
			(layers "F.Cu" "F.Mask" "F.Paste")
			(net "PVCCIN_CPU1")
		)
		(pad "BK81" smd circle
			(at 32.958024 -2.633726)
			(size 0.4318 0.4318)
			(layers "F.Cu" "F.Mask" "F.Paste")
			(net "PVCCIN_CPU1")
		)
		(pad "BK83" smd circle
			(at 34.675064 -2.633726)
			(size 0.4318 0.4318)
			(layers "F.Cu" "F.Mask" "F.Paste")
			(net "PVCCIN_CPU1")
		)
		(pad "BL4" smd circle
			(at -34.675064 -0.338074)
			(size 0.4318 0.4318)
			(layers "F.Cu" "F.Mask" "F.Paste")
			(net "TP_P3E_CPU1_PE2_RSR_TXN<14>")
		)
		(pad "BL6" smd circle
			(at -32.958024 -0.338074)
			(size 0.4318 0.4318)
			(layers "F.Cu" "F.Mask" "F.Paste")
			(net "GND")
		)
		(pad "BL8" smd circle
			(at -31.240984 -0.338074)
			(size 0.4318 0.4318)
			(layers "F.Cu" "F.Mask" "F.Paste")
			(net "TP_P3E_CPU1_PE2_RSR_RXN<14>")
		)
		(pad "BL10" smd circle
			(at -29.523944 -0.338074)
			(size 0.4318 0.4318)
			(layers "F.Cu" "F.Mask" "F.Paste")
			(net "GND")
		)
		(pad "BL12" smd circle
			(at -27.806904 -0.338074)
			(size 0.4318 0.4318)
			(layers "F.Cu" "F.Mask" "F.Paste")
			(net "GND")
		)
		(pad "BL14" smd circle
			(at -26.090118 -0.338074)
			(size 0.4318 0.4318)
			(layers "F.Cu" "F.Mask" "F.Paste")
			(net "PVCCMCP_CPU1")
		)
		(pad "BL16" smd circle
			(at -24.373078 -0.338074)
			(size 0.4318 0.4318)
			(layers "F.Cu" "F.Mask" "F.Paste")
			(net "VSENSE_PVCCMCP_CPU1_SKT_VRTN")
		)
		(pad "BL18" smd circle
			(at -22.656038 -0.338074)
			(size 0.4318 0.4318)
			(layers "F.Cu" "F.Mask" "F.Paste")
			(net "PVCCIOMCP_CPU1")
		)
		(pad "BL20" smd circle
			(at -20.938998 -0.338074)
			(size 0.4318 0.4318)
			(layers "F.Cu" "F.Mask" "F.Paste")
			(net "PVCCMCP_CPU1")
		)
		(pad "BL22" smd circle
			(at -19.221958 -0.338074)
			(size 0.4318 0.4318)
			(layers "F.Cu" "F.Mask" "F.Paste")
			(net "GND")
		)
		(pad "BL24" smd circle
			(at -17.504918 -0.338074)
			(size 0.4318 0.4318)
			(layers "F.Cu" "F.Mask" "F.Paste")
			(net "GND")
		)
		(pad "BL26" smd circle
			(at -15.787878 -0.338074)
			(size 0.4318 0.4318)
			(layers "F.Cu" "F.Mask" "F.Paste")
			(net "PVCCIO_CPU1")
		)
		(pad "BL60" smd circle
			(at 14.929612 -2.138426)
			(size 0.508 0.508)
			(layers "F.Cu" "F.Mask" "F.Paste")
			(net "PVCCIN_CPU1")
		)
		(pad "BL62" smd circle
			(at 16.646398 -2.138426)
			(size 0.4318 0.4318)
			(layers "F.Cu" "F.Mask" "F.Paste")
			(net "PVCCIN_CPU1")
		)
		(pad "BL64" smd circle
			(at 18.363438 -2.138426)
			(size 0.4318 0.4318)
			(layers "F.Cu" "F.Mask" "F.Paste")
			(net "GND")
		)
		(pad "BL66" smd circle
			(at 20.080478 -2.138426)
			(size 0.4318 0.4318)
			(layers "F.Cu" "F.Mask" "F.Paste")
			(net "GND")
		)
		(pad "BL68" smd circle
			(at 21.797518 -2.138426)
			(size 0.4318 0.4318)
			(layers "F.Cu" "F.Mask" "F.Paste")
			(net "GND")
		)
		(pad "BL70" smd circle
			(at 23.514558 -2.138426)
			(size 0.4318 0.4318)
			(layers "F.Cu" "F.Mask" "F.Paste")
			(net "GND")
		)
		(pad "BL72" smd circle
			(at 25.231598 -2.138426)
			(size 0.4318 0.4318)
			(layers "F.Cu" "F.Mask" "F.Paste")
			(net "GND")
		)
		(pad "BL74" smd circle
			(at 26.948384 -2.138426)
			(size 0.4318 0.4318)
			(layers "F.Cu" "F.Mask" "F.Paste")
			(net "GND")
		)
		(pad "BL76" smd circle
			(at 28.665424 -2.138426)
			(size 0.4318 0.4318)
			(layers "F.Cu" "F.Mask" "F.Paste")
			(net "GND")
		)
		(pad "BL78" smd circle
			(at 30.382464 -2.138426)
			(size 0.4318 0.4318)
			(layers "F.Cu" "F.Mask" "F.Paste")
			(net "GND")
		)
		(pad "BL80" smd circle
			(at 32.099504 -2.138426)
			(size 0.4318 0.4318)
			(layers "F.Cu" "F.Mask" "F.Paste")
			(net "GND")
		)
		(pad "BL82" smd circle
			(at 33.816544 -2.138426)
			(size 0.4318 0.4318)
			(layers "F.Cu" "F.Mask" "F.Paste")
			(net "GND")
		)
		(pad "BL84" smd custom
			(at 35.533584 -2.138426 270)
			(size 0.10795 0.10795)
			(layers "F.Cu" "F.Mask" "F.Paste")
			(net "PVCCIN_CPU1")
			(options
				(clearance outline)
				(anchor circle)
			)
			(primitives
				(gr_poly
					(pts
						(arc
							(start 0.2159 -0.0381)
							(mid 0 -0.254)
							(end -0.2159 -0.0381)
						)
						(arc
							(start -0.2159 0.0381)
							(mid 0 0.254)
							(end 0.2159 0.0381)
						)
					)
					(width 0)
					(fill yes)
				)
			)
		)
		(pad "BM3" smd custom
			(at -35.533584 0.156972 90)
			(size 0.10795 0.10795)
			(layers "F.Cu" "F.Mask" "F.Paste")
			(net "TP_P3E_CPU1_PE2_RSR_TXP<14>")
			(options
				(clearance outline)
				(anchor circle)
			)
			(primitives
				(gr_poly
					(pts
						(arc
							(start 0.2159 -0.0381)
							(mid 0 -0.254)
							(end -0.2159 -0.0381)
						)
						(arc
							(start -0.2159 0.0381)
							(mid 0 0.254)
							(end 0.2159 0.0381)
						)
					)
					(width 0)
					(fill yes)
				)
			)
		)
		(pad "BM5" smd circle
			(at -33.816544 0.156972)
			(size 0.4318 0.4318)
			(layers "F.Cu" "F.Mask" "F.Paste")
			(net "TP_P3E_CPU1_PE2_RSR_TXN<15>")
		)
		(pad "BM7" smd circle
			(at -32.099504 0.156972)
			(size 0.4318 0.4318)
			(layers "F.Cu" "F.Mask" "F.Paste")
			(net "TP_P3E_CPU1_PE2_RSR_RXP<13>")
		)
		(pad "BM9" smd circle
			(at -30.382464 0.156972)
			(size 0.4318 0.4318)
			(layers "F.Cu" "F.Mask" "F.Paste")
			(net "GND")
		)
		(pad "BM11" smd circle
			(at -28.665424 0.156972)
			(size 0.4318 0.4318)
			(layers "F.Cu" "F.Mask" "F.Paste")
			(net "PVCCIOMCP_CPU1")
		)
		(pad "BM13" smd circle
			(at -26.948384 0.156972)
			(size 0.4318 0.4318)
			(layers "F.Cu" "F.Mask" "F.Paste")
			(net "GND")
		)
		(pad "BM15" smd circle
			(at -25.231598 0.156972)
			(size 0.4318 0.4318)
			(layers "F.Cu" "F.Mask" "F.Paste")
			(net "GND")
		)
		(pad "BM17" smd circle
			(at -23.514558 0.156972)
			(size 0.4318 0.4318)
			(layers "F.Cu" "F.Mask" "F.Paste")
			(net "PVCCIOMCP_CPU1")
		)
		(pad "BM19" smd circle
			(at -21.797518 0.156972)
			(size 0.4318 0.4318)
			(layers "F.Cu" "F.Mask" "F.Paste")
			(net "PVCCMCP_CPU1")
		)
		(pad "BM21" smd circle
			(at -20.080478 0.156972)
			(size 0.4318 0.4318)
			(layers "F.Cu" "F.Mask" "F.Paste")
			(net "TP_CD_HFI1_CPU1_INT_N")
		)
		(pad "BM23" smd circle
			(at -18.363438 0.156972)
			(size 0.4318 0.4318)
			(layers "F.Cu" "F.Mask" "F.Paste")
			(net "TP_CD_HFI1_CPU1_LED_N")
		)
		(pad "BM25" smd circle
			(at -16.646398 0.156972)
			(size 0.4318 0.4318)
			(layers "F.Cu" "F.Mask" "F.Paste")
			(net "GND")
		)
		(pad "BM27" smd circle
			(at -14.929612 0.156972)
			(size 0.4318 0.4318)
			(layers "F.Cu" "F.Mask" "F.Paste")
			(net "PVCCIO_CPU1")
		)
		(pad "BM61" smd circle
			(at 15.787878 -1.643126)
			(size 0.4318 0.4318)
			(layers "F.Cu" "F.Mask" "F.Paste")
			(net "PVCCIN_CPU1")
		)
		(pad "BM63" smd circle
			(at 17.504918 -1.643126)
			(size 0.4318 0.4318)
			(layers "F.Cu" "F.Mask" "F.Paste")
			(net "PVCCIN_CPU1")
		)
		(pad "BM65" smd circle
			(at 19.221958 -1.643126)
			(size 0.4318 0.4318)
			(layers "F.Cu" "F.Mask" "F.Paste")
			(net "PVCCIN_CPU1")
		)
		(pad "BM67" smd circle
			(at 20.938998 -1.643126)
			(size 0.4318 0.4318)
			(layers "F.Cu" "F.Mask" "F.Paste")
			(net "PVCCIN_CPU1")
		)
		(pad "BM69" smd circle
			(at 22.656038 -1.643126)
			(size 0.4318 0.4318)
			(layers "F.Cu" "F.Mask" "F.Paste")
			(net "PVCCIN_CPU1")
		)
		(pad "BM71" smd circle
			(at 24.373078 -1.643126)
			(size 0.4318 0.4318)
			(layers "F.Cu" "F.Mask" "F.Paste")
			(net "PVCCIN_CPU1")
		)
		(pad "BM73" smd circle
			(at 26.090118 -1.643126)
			(size 0.4318 0.4318)
			(layers "F.Cu" "F.Mask" "F.Paste")
			(net "PVCCIN_CPU1")
		)
		(pad "BM75" smd circle
			(at 27.806904 -1.643126)
			(size 0.4318 0.4318)
			(layers "F.Cu" "F.Mask" "F.Paste")
			(net "PVCCIN_CPU1")
		)
		(pad "BM77" smd circle
			(at 29.523944 -1.643126)
			(size 0.4318 0.4318)
			(layers "F.Cu" "F.Mask" "F.Paste")
			(net "PVCCIN_CPU1")
		)
		(pad "BM79" smd circle
			(at 31.240984 -1.643126)
			(size 0.4318 0.4318)
			(layers "F.Cu" "F.Mask" "F.Paste")
			(net "PVCCIN_CPU1")
		)
		(pad "BM81" smd circle
			(at 32.958024 -1.643126)
			(size 0.4318 0.4318)
			(layers "F.Cu" "F.Mask" "F.Paste")
			(net "PVCCIN_CPU1")
		)
		(pad "BM83" smd circle
			(at 34.675064 -1.643126)
			(size 0.4318 0.4318)
			(layers "F.Cu" "F.Mask" "F.Paste")
			(net "PVCCIN_CPU1")
		)
		(pad "BN4" smd circle
			(at -34.675064 0.652526)
			(size 0.4318 0.4318)
			(layers "F.Cu" "F.Mask" "F.Paste")
			(net "TP_P3E_CPU1_PE2_RSR_TXP<13>")
		)
		(pad "BN6" smd circle
			(at -32.958024 0.652526)
			(size 0.4318 0.4318)
			(layers "F.Cu" "F.Mask" "F.Paste")
			(net "GND")
		)
		(pad "BN8" smd circle
			(at -31.240984 0.652526)
			(size 0.4318 0.4318)
			(layers "F.Cu" "F.Mask" "F.Paste")
			(net "TP_P3E_CPU1_PE2_RSR_RXN<13>")
		)
		(pad "BN10" smd circle
			(at -29.523944 0.652526)
			(size 0.4318 0.4318)
			(layers "F.Cu" "F.Mask" "F.Paste")
			(net "GND")
		)
		(pad "BN12" smd circle
			(at -27.806904 0.652526)
			(size 0.4318 0.4318)
			(layers "F.Cu" "F.Mask" "F.Paste")
			(net "PVCCIOMCP_CPU1")
		)
		(pad "BN14" smd circle
			(at -26.090118 0.652526)
			(size 0.4318 0.4318)
			(layers "F.Cu" "F.Mask" "F.Paste")
			(net "PVCCIOMCP_CPU1")
		)
		(pad "BN16" smd circle
			(at -24.373078 0.652526)
			(size 0.4318 0.4318)
			(layers "F.Cu" "F.Mask" "F.Paste")
			(net "VSENSE_PVCCMCP_CPU1_SKT_VSEN")
		)
		(pad "BN18" smd circle
			(at -22.656038 0.652526)
			(size 0.4318 0.4318)
			(layers "F.Cu" "F.Mask" "F.Paste")
			(net "PVCCIOMCP_CPU1")
		)
		(pad "BN20" smd circle
			(at -20.938998 0.652526)
			(size 0.4318 0.4318)
			(layers "F.Cu" "F.Mask" "F.Paste")
			(net "GND")
		)
		(pad "BN22" smd circle
			(at -19.221958 0.652526)
			(size 0.4318 0.4318)
			(layers "F.Cu" "F.Mask" "F.Paste")
			(net "TP_SMB_CPU1_CD_HFI0_I2CCLK")
		)
		(pad "BN24" smd circle
			(at -17.504918 0.652526)
			(size 0.4318 0.4318)
			(layers "F.Cu" "F.Mask" "F.Paste")
			(net "TP_RST_CPU1_CD_HFI0_N")
		)
		(pad "BN26" smd circle
			(at -15.787878 0.652526)
			(size 0.4318 0.4318)
			(layers "F.Cu" "F.Mask" "F.Paste")
			(net "GND")
		)
		(pad "BN60" smd circle
			(at 14.929612 -1.147572)
			(size 0.508 0.508)
			(layers "F.Cu" "F.Mask" "F.Paste")
			(net "PVCCIN_CPU1")
		)
		(pad "BN62" smd circle
			(at 16.646398 -1.147572)
			(size 0.4318 0.4318)
			(layers "F.Cu" "F.Mask" "F.Paste")
			(net "PVCCIN_CPU1")
		)
		(pad "BN64" smd circle
			(at 18.363438 -1.147572)
			(size 0.4318 0.4318)
			(layers "F.Cu" "F.Mask" "F.Paste")
			(net "PVCCIN_CPU1")
		)
		(pad "BN66" smd circle
			(at 20.080478 -1.147572)
			(size 0.4318 0.4318)
			(layers "F.Cu" "F.Mask" "F.Paste")
			(net "PVCCIN_CPU1")
		)
		(pad "BN68" smd circle
			(at 21.797518 -1.147572)
			(size 0.4318 0.4318)
			(layers "F.Cu" "F.Mask" "F.Paste")
			(net "PVCCIN_CPU1")
		)
		(pad "BN70" smd circle
			(at 23.514558 -1.147572)
			(size 0.4318 0.4318)
			(layers "F.Cu" "F.Mask" "F.Paste")
			(net "PVCCIN_CPU1")
		)
		(pad "BN72" smd circle
			(at 25.231598 -1.147572)
			(size 0.4318 0.4318)
			(layers "F.Cu" "F.Mask" "F.Paste")
			(net "PVCCIN_CPU1")
		)
		(pad "BN74" smd circle
			(at 26.948384 -1.147572)
			(size 0.4318 0.4318)
			(layers "F.Cu" "F.Mask" "F.Paste")
			(net "PVCCIN_CPU1")
		)
		(pad "BN76" smd circle
			(at 28.665424 -1.147572)
			(size 0.4318 0.4318)
			(layers "F.Cu" "F.Mask" "F.Paste")
			(net "PVCCIN_CPU1")
		)
		(pad "BN78" smd circle
			(at 30.382464 -1.147572)
			(size 0.4318 0.4318)
			(layers "F.Cu" "F.Mask" "F.Paste")
			(net "PVCCIN_CPU1")
		)
		(pad "BN80" smd circle
			(at 32.099504 -1.147572)
			(size 0.4318 0.4318)
			(layers "F.Cu" "F.Mask" "F.Paste")
			(net "PVCCIN_CPU1")
		)
		(pad "BN82" smd circle
			(at 33.816544 -1.147572)
			(size 0.4318 0.4318)
			(layers "F.Cu" "F.Mask" "F.Paste")
			(net "PVCCIN_CPU1")
		)
		(pad "BN84" smd custom
			(at 35.533584 -1.147572 270)
			(size 0.10795 0.10795)
			(layers "F.Cu" "F.Mask" "F.Paste")
			(net "PVCCIN_CPU1")
			(options
				(clearance outline)
				(anchor circle)
			)
			(primitives
				(gr_poly
					(pts
						(arc
							(start 0.2159 -0.0381)
							(mid 0 -0.254)
							(end -0.2159 -0.0381)
						)
						(arc
							(start -0.2159 0.0381)
							(mid 0 0.254)
							(end 0.2159 0.0381)
						)
					)
					(width 0)
					(fill yes)
				)
			)
		)
		(pad "BP3" smd custom
			(at -35.533584 1.147572 90)
			(size 0.10795 0.10795)
			(layers "F.Cu" "F.Mask" "F.Paste")
			(net "GND")
			(options
				(clearance outline)
				(anchor circle)
			)
			(primitives
				(gr_poly
					(pts
						(arc
							(start 0.2159 -0.0381)
							(mid 0 -0.254)
							(end -0.2159 -0.0381)
						)
						(arc
							(start -0.2159 0.0381)
							(mid 0 0.254)
							(end 0.2159 0.0381)
						)
					)
					(width 0)
					(fill yes)
				)
			)
		)
		(pad "BP5" smd circle
			(at -33.816544 1.147572)
			(size 0.4318 0.4318)
			(layers "F.Cu" "F.Mask" "F.Paste")
			(net "TP_P3E_CPU1_PE2_RSR_TXN<13>")
		)
		(pad "BP7" smd circle
			(at -32.099504 1.147572)
			(size 0.4318 0.4318)
			(layers "F.Cu" "F.Mask" "F.Paste")
			(net "TP_P3E_CPU1_PE2_RSR_RXP<11>")
		)
		(pad "BP9" smd circle
			(at -30.382464 1.147572)
			(size 0.4318 0.4318)
			(layers "F.Cu" "F.Mask" "F.Paste")
			(net "TP_P3E_CPU1_PE2_RSR_RXP<12>")
		)
		(pad "BP11" smd circle
			(at -28.665424 1.147572)
			(size 0.4318 0.4318)
			(layers "F.Cu" "F.Mask" "F.Paste")
			(net "PVCCIOMCP_CPU1")
		)
		(pad "BP13" smd circle
			(at -26.948384 1.147572)
			(size 0.4318 0.4318)
			(layers "F.Cu" "F.Mask" "F.Paste")
			(net "PVCCIOMCP_CPU1")
		)
		(pad "BP15" smd circle
			(at -25.231598 1.147572)
			(size 0.4318 0.4318)
			(layers "F.Cu" "F.Mask" "F.Paste")
			(net "PVCCIOMCP_CPU1")
		)
		(pad "BP17" smd circle
			(at -23.514558 1.147572)
			(size 0.4318 0.4318)
			(layers "F.Cu" "F.Mask" "F.Paste")
			(net "PVCCIOMCP_CPU1")
		)
		(pad "BP19" smd circle
			(at -21.797518 1.147572)
			(size 0.4318 0.4318)
			(layers "F.Cu" "F.Mask" "F.Paste")
			(net "TP_IRQ_CPU1_CD_HFI0_N")
		)
		(pad "BP21" smd circle
			(at -20.080478 1.147572)
			(size 0.4318 0.4318)
			(layers "F.Cu" "F.Mask" "F.Paste")
			(net "PVCCMCP_CPU1")
		)
		(pad "BP23" smd circle
			(at -18.363438 1.147572)
			(size 0.4318 0.4318)
			(layers "F.Cu" "F.Mask" "F.Paste")
			(net "TP_SMB_CPU1_CD_HFI0_I2CDAT")
		)
		(pad "BP25" smd circle
			(at -16.646398 1.147572)
			(size 0.4318 0.4318)
			(layers "F.Cu" "F.Mask" "F.Paste")
			(net "PVCCIO_CPU1")
		)
		(pad "BP27" smd circle
			(at -14.929612 1.147572)
			(size 0.4318 0.4318)
			(layers "F.Cu" "F.Mask" "F.Paste")
			(net "GND")
		)
		(pad "BP61" smd circle
			(at 15.787878 -0.652526)
			(size 0.4318 0.4318)
			(layers "F.Cu" "F.Mask" "F.Paste")
			(net "PVCCIN_CPU1")
		)
		(pad "BP63" smd circle
			(at 17.504918 -0.652526)
			(size 0.4318 0.4318)
			(layers "F.Cu" "F.Mask" "F.Paste")
			(net "PVCCIN_CPU1")
		)
		(pad "BP65" smd circle
			(at 19.221958 -0.652526)
			(size 0.4318 0.4318)
			(layers "F.Cu" "F.Mask" "F.Paste")
			(net "PVCCIN_CPU1")
		)
		(pad "BP67" smd circle
			(at 20.938998 -0.652526)
			(size 0.4318 0.4318)
			(layers "F.Cu" "F.Mask" "F.Paste")
			(net "PVCCIN_CPU1")
		)
		(pad "BP69" smd circle
			(at 22.656038 -0.652526)
			(size 0.4318 0.4318)
			(layers "F.Cu" "F.Mask" "F.Paste")
			(net "PVCCIN_CPU1")
		)
		(pad "BP71" smd circle
			(at 24.373078 -0.652526)
			(size 0.4318 0.4318)
			(layers "F.Cu" "F.Mask" "F.Paste")
			(net "PVCCIN_CPU1")
		)
		(pad "BP73" smd circle
			(at 26.090118 -0.652526)
			(size 0.4318 0.4318)
			(layers "F.Cu" "F.Mask" "F.Paste")
			(net "PVCCIN_CPU1")
		)
		(pad "BP75" smd circle
			(at 27.806904 -0.652526)
			(size 0.4318 0.4318)
			(layers "F.Cu" "F.Mask" "F.Paste")
			(net "PVCCIN_CPU1")
		)
		(pad "BP77" smd circle
			(at 29.523944 -0.652526)
			(size 0.4318 0.4318)
			(layers "F.Cu" "F.Mask" "F.Paste")
			(net "PVCCIN_CPU1")
		)
		(pad "BP79" smd circle
			(at 31.240984 -0.652526)
			(size 0.4318 0.4318)
			(layers "F.Cu" "F.Mask" "F.Paste")
			(net "PVCCIN_CPU1")
		)
		(pad "BP81" smd circle
			(at 32.958024 -0.652526)
			(size 0.4318 0.4318)
			(layers "F.Cu" "F.Mask" "F.Paste")
			(net "PVCCIN_CPU1")
		)
		(pad "BP83" smd circle
			(at 34.675064 -0.652526)
			(size 0.4318 0.4318)
			(layers "F.Cu" "F.Mask" "F.Paste")
			(net "PVCCIN_CPU1")
		)
		(pad "BR4" smd circle
			(at -34.675064 1.643126)
			(size 0.4318 0.4318)
			(layers "F.Cu" "F.Mask" "F.Paste")
			(net "TP_P3E_CPU1_PE2_RSR_TXP<12>")
		)
		(pad "BR6" smd circle
			(at -32.958024 1.643126)
			(size 0.4318 0.4318)
			(layers "F.Cu" "F.Mask" "F.Paste")
			(net "GND")
		)
		(pad "BR8" smd circle
			(at -31.240984 1.643126)
			(size 0.4318 0.4318)
			(layers "F.Cu" "F.Mask" "F.Paste")
			(net "TP_P3E_CPU1_PE2_RSR_RXN<12>")
		)
		(pad "BR10" smd circle
			(at -29.523944 1.643126)
			(size 0.4318 0.4318)
			(layers "F.Cu" "F.Mask" "F.Paste")
			(net "GND")
		)
		(pad "BR12" smd circle
			(at -27.806904 1.643126)
			(size 0.4318 0.4318)
			(layers "F.Cu" "F.Mask" "F.Paste")
			(net "PVCCIOMCP_CPU1")
		)
		(pad "BR14" smd circle
			(at -26.090118 1.643126)
			(size 0.4318 0.4318)
			(layers "F.Cu" "F.Mask" "F.Paste")
			(net "PVCCIOMCP_CPU1")
		)
		(pad "BR16" smd circle
			(at -24.373078 1.643126)
			(size 0.4318 0.4318)
			(layers "F.Cu" "F.Mask" "F.Paste")
			(net "GND")
		)
		(pad "BR18" smd circle
			(at -22.656038 1.643126)
			(size 0.4318 0.4318)
			(layers "F.Cu" "F.Mask" "F.Paste")
			(net "GND")
		)
		(pad "BR20" smd circle
			(at -20.938998 1.643126)
			(size 0.4318 0.4318)
			(layers "F.Cu" "F.Mask" "F.Paste")
			(net "TP_FM_CPU1_CD_HFI0_MODPRST_N")
		)
		(pad "BR22" smd circle
			(at -19.221958 1.643126)
			(size 0.4318 0.4318)
			(layers "F.Cu" "F.Mask" "F.Paste")
			(net "PVCCMCP_CPU1")
		)
		(pad "BR24" smd circle
			(at -17.504918 1.643126)
			(size 0.4318 0.4318)
			(layers "F.Cu" "F.Mask" "F.Paste")
			(net "PVCCMCP_CPU1")
		)
		(pad "BR26" smd circle
			(at -15.787878 1.643126)
			(size 0.4318 0.4318)
			(layers "F.Cu" "F.Mask" "F.Paste")
			(net "GND")
		)
		(pad "BR60" smd circle
			(at 14.929612 -0.156972)
			(size 0.508 0.508)
			(layers "F.Cu" "F.Mask" "F.Paste")
			(net "PVCCIN_CPU1")
		)
		(pad "BR62" smd circle
			(at 16.646398 -0.156972)
			(size 0.4318 0.4318)
			(layers "F.Cu" "F.Mask" "F.Paste")
			(net "PVCCIN_CPU1")
		)
		(pad "BR64" smd circle
			(at 18.363438 -0.156972)
			(size 0.4318 0.4318)
			(layers "F.Cu" "F.Mask" "F.Paste")
			(net "GND")
		)
		(pad "BR66" smd circle
			(at 20.080478 -0.156972)
			(size 0.4318 0.4318)
			(layers "F.Cu" "F.Mask" "F.Paste")
			(net "GND")
		)
		(pad "BR68" smd circle
			(at 21.797518 -0.156972)
			(size 0.4318 0.4318)
			(layers "F.Cu" "F.Mask" "F.Paste")
			(net "GND")
		)
		(pad "BR70" smd circle
			(at 23.514558 -0.156972)
			(size 0.4318 0.4318)
			(layers "F.Cu" "F.Mask" "F.Paste")
			(net "GND")
		)
		(pad "BR72" smd circle
			(at 25.231598 -0.156972)
			(size 0.4318 0.4318)
			(layers "F.Cu" "F.Mask" "F.Paste")
			(net "GND")
		)
		(pad "BR74" smd circle
			(at 26.948384 -0.156972)
			(size 0.4318 0.4318)
			(layers "F.Cu" "F.Mask" "F.Paste")
			(net "GND")
		)
		(pad "BR76" smd circle
			(at 28.665424 -0.156972)
			(size 0.4318 0.4318)
			(layers "F.Cu" "F.Mask" "F.Paste")
			(net "GND")
		)
		(pad "BR78" smd circle
			(at 30.382464 -0.156972)
			(size 0.4318 0.4318)
			(layers "F.Cu" "F.Mask" "F.Paste")
			(net "GND")
		)
		(pad "BR80" smd circle
			(at 32.099504 -0.156972)
			(size 0.4318 0.4318)
			(layers "F.Cu" "F.Mask" "F.Paste")
			(net "GND")
		)
		(pad "BR82" smd circle
			(at 33.816544 -0.156972)
			(size 0.4318 0.4318)
			(layers "F.Cu" "F.Mask" "F.Paste")
			(net "GND")
		)
		(pad "BR84" smd custom
			(at 35.533584 -0.156972 270)
			(size 0.10795 0.10795)
			(layers "F.Cu" "F.Mask" "F.Paste")
			(net "PVCCIN_CPU1")
			(options
				(clearance outline)
				(anchor circle)
			)
			(primitives
				(gr_poly
					(pts
						(arc
							(start 0.2159 -0.0381)
							(mid 0 -0.254)
							(end -0.2159 -0.0381)
						)
						(arc
							(start -0.2159 0.0381)
							(mid 0 0.254)
							(end 0.2159 0.0381)
						)
					)
					(width 0)
					(fill yes)
				)
			)
		)
		(pad "BT3" smd custom
			(at -35.533584 2.138426 90)
			(size 0.10795 0.10795)
			(layers "F.Cu" "F.Mask" "F.Paste")
			(net "GND")
			(options
				(clearance outline)
				(anchor circle)
			)
			(primitives
				(gr_poly
					(pts
						(arc
							(start 0.2159 -0.0381)
							(mid 0 -0.254)
							(end -0.2159 -0.0381)
						)
						(arc
							(start -0.2159 0.0381)
							(mid 0 0.254)
							(end 0.2159 0.0381)
						)
					)
					(width 0)
					(fill yes)
				)
			)
		)
		(pad "BT5" smd circle
			(at -33.816544 2.138426)
			(size 0.4318 0.4318)
			(layers "F.Cu" "F.Mask" "F.Paste")
			(net "GND")
		)
		(pad "BT7" smd circle
			(at -32.099504 2.138426)
			(size 0.4318 0.4318)
			(layers "F.Cu" "F.Mask" "F.Paste")
			(net "TP_P3E_CPU1_PE2_RSR_RXN<11>")
		)
		(pad "BT9" smd circle
			(at -30.382464 2.138426)
			(size 0.4318 0.4318)
			(layers "F.Cu" "F.Mask" "F.Paste")
			(net "GND")
		)
		(pad "BT11" smd circle
			(at -28.665424 2.138426)
			(size 0.4318 0.4318)
			(layers "F.Cu" "F.Mask" "F.Paste")
			(net "PVCCIOMCP_CPU1")
		)
		(pad "BT13" smd circle
			(at -26.948384 2.138426)
			(size 0.4318 0.4318)
			(layers "F.Cu" "F.Mask" "F.Paste")
			(net "PVCCIOMCP_CPU1")
		)
		(pad "BT15" smd circle
			(at -25.231598 2.138426)
			(size 0.4318 0.4318)
			(layers "F.Cu" "F.Mask" "F.Paste")
			(net "PVCCIOMCP_CPU1")
		)
		(pad "BT17" smd circle
			(at -23.514558 2.138426)
			(size 0.4318 0.4318)
			(layers "F.Cu" "F.Mask" "F.Paste")
			(net "VSENSE_PVCCIOMCP_CPU1_SKT_VSEN")
		)
		(pad "BT19" smd circle
			(at -21.797518 2.138426)
			(size 0.4318 0.4318)
			(layers "F.Cu" "F.Mask" "F.Paste")
			(net "TP_CD_HFI1_CPU1_MODPRST_N")
		)
		(pad "BT21" smd circle
			(at -20.080478 2.138426)
			(size 0.4318 0.4318)
			(layers "F.Cu" "F.Mask" "F.Paste")
			(net "GND")
		)
		(pad "BT23" smd circle
			(at -18.363438 2.138426)
			(size 0.4318 0.4318)
			(layers "F.Cu" "F.Mask" "F.Paste")
			(net "GND")
		)
		(pad "BT25" smd circle
			(at -16.646398 2.138426)
			(size 0.4318 0.4318)
			(layers "F.Cu" "F.Mask" "F.Paste")
			(net "GND")
		)
		(pad "BT27" smd circle
			(at -14.929612 2.138426)
			(size 0.4318 0.4318)
			(layers "F.Cu" "F.Mask" "F.Paste")
			(net "P1V8_MCP_CPU1")
		)
		(pad "BT61" smd circle
			(at 15.787878 0.338074)
			(size 0.4318 0.4318)
			(layers "F.Cu" "F.Mask" "F.Paste")
			(net "PVCCIN_CPU1")
		)
		(pad "BT63" smd circle
			(at 17.504918 0.338074)
			(size 0.4318 0.4318)
			(layers "F.Cu" "F.Mask" "F.Paste")
			(net "PVCCIN_CPU1")
		)
		(pad "BT65" smd circle
			(at 19.221958 0.338074)
			(size 0.4318 0.4318)
			(layers "F.Cu" "F.Mask" "F.Paste")
			(net "PVCCIN_CPU1")
		)
		(pad "BT67" smd circle
			(at 20.938998 0.338074)
			(size 0.4318 0.4318)
			(layers "F.Cu" "F.Mask" "F.Paste")
			(net "PVCCIN_CPU1")
		)
		(pad "BT69" smd circle
			(at 22.656038 0.338074)
			(size 0.4318 0.4318)
			(layers "F.Cu" "F.Mask" "F.Paste")
			(net "PVCCIN_CPU1")
		)
		(pad "BT71" smd circle
			(at 24.373078 0.338074)
			(size 0.4318 0.4318)
			(layers "F.Cu" "F.Mask" "F.Paste")
			(net "PVCCIN_CPU1")
		)
		(pad "BT73" smd circle
			(at 26.090118 0.338074)
			(size 0.4318 0.4318)
			(layers "F.Cu" "F.Mask" "F.Paste")
			(net "PVCCIN_CPU1")
		)
		(pad "BT75" smd circle
			(at 27.806904 0.338074)
			(size 0.4318 0.4318)
			(layers "F.Cu" "F.Mask" "F.Paste")
			(net "PVCCIN_CPU1")
		)
		(pad "BT77" smd circle
			(at 29.523944 0.338074)
			(size 0.4318 0.4318)
			(layers "F.Cu" "F.Mask" "F.Paste")
			(net "PVCCIN_CPU1")
		)
		(pad "BT79" smd circle
			(at 31.240984 0.338074)
			(size 0.4318 0.4318)
			(layers "F.Cu" "F.Mask" "F.Paste")
			(net "PVCCIN_CPU1")
		)
		(pad "BT81" smd circle
			(at 32.958024 0.338074)
			(size 0.4318 0.4318)
			(layers "F.Cu" "F.Mask" "F.Paste")
			(net "PVCCIN_CPU1")
		)
		(pad "BT83" smd circle
			(at 34.675064 0.338074)
			(size 0.4318 0.4318)
			(layers "F.Cu" "F.Mask" "F.Paste")
			(net "PVCCIN_CPU1")
		)
		(pad "BU4" smd circle
			(at -34.675064 2.633726)
			(size 0.4318 0.4318)
			(layers "F.Cu" "F.Mask" "F.Paste")
			(net "TP_P3E_CPU1_PE2_RSR_TXN<12>")
		)
		(pad "BU6" smd circle
			(at -32.958024 2.633726)
			(size 0.4318 0.4318)
			(layers "F.Cu" "F.Mask" "F.Paste")
			(net "TP_P3E_CPU1_PE2_RSR_RXP<10>")
		)
		(pad "BU8" smd circle
			(at -31.240984 2.633726)
			(size 0.4318 0.4318)
			(layers "F.Cu" "F.Mask" "F.Paste")
			(net "GND")
		)
		(pad "BU10" smd circle
			(at -29.523944 2.633726)
			(size 0.4318 0.4318)
			(layers "F.Cu" "F.Mask" "F.Paste")
			(net "GND")
		)
		(pad "BU12" smd circle
			(at -27.806904 2.633726)
			(size 0.4318 0.4318)
			(layers "F.Cu" "F.Mask" "F.Paste")
			(net "PVCCIOMCP_CPU1")
		)
		(pad "BU14" smd circle
			(at -26.090118 2.633726)
			(size 0.4318 0.4318)
			(layers "F.Cu" "F.Mask" "F.Paste")
			(net "PVCCIOMCP_CPU1")
		)
		(pad "BU16" smd circle
			(at -24.373078 2.633726)
			(size 0.4318 0.4318)
			(layers "F.Cu" "F.Mask" "F.Paste")
			(net "VSENSE_PVCCIOMCP_CPU1_SKT_VRTN")
		)
		(pad "BU18" smd circle
			(at -22.656038 2.633726)
			(size 0.4318 0.4318)
			(layers "F.Cu" "F.Mask" "F.Paste")
			(net "PVCCIOMCP_CPU1")
		)
		(pad "BU20" smd circle
			(at -20.938998 2.633726)
			(size 0.4318 0.4318)
			(layers "F.Cu" "F.Mask" "F.Paste")
			(net "PVCCMCP_CPU1")
		)
		(pad "BU22" smd circle
			(at -19.221958 2.633726)
			(size 0.4318 0.4318)
			(layers "F.Cu" "F.Mask" "F.Paste")
			(net "PVCCMCP_CPU1")
		)
		(pad "BU24" smd circle
			(at -17.504918 2.633726)
			(size 0.4318 0.4318)
			(layers "F.Cu" "F.Mask" "F.Paste")
			(net "CLK_100M_CPU1_PE_REFCLK_DN")
		)
		(pad "BU26" smd circle
			(at -15.787878 2.633726)
			(size 0.4318 0.4318)
			(layers "F.Cu" "F.Mask" "F.Paste")
			(net "P1V8_MCP_CPU1")
		)
		(pad "BU60" smd circle
			(at 14.929612 0.833628)
			(size 0.508 0.508)
			(layers "F.Cu" "F.Mask" "F.Paste")
			(net "PVCCIN_CPU1")
		)
		(pad "BU62" smd circle
			(at 16.646398 0.833628)
			(size 0.4318 0.4318)
			(layers "F.Cu" "F.Mask" "F.Paste")
			(net "PVCCIN_CPU1")
		)
		(pad "BU64" smd circle
			(at 18.363438 0.833628)
			(size 0.4318 0.4318)
			(layers "F.Cu" "F.Mask" "F.Paste")
			(net "PVCCIN_CPU1")
		)
		(pad "BU66" smd circle
			(at 20.080478 0.833628)
			(size 0.4318 0.4318)
			(layers "F.Cu" "F.Mask" "F.Paste")
			(net "PVCCIN_CPU1")
		)
		(pad "BU68" smd circle
			(at 21.797518 0.833628)
			(size 0.4318 0.4318)
			(layers "F.Cu" "F.Mask" "F.Paste")
			(net "PVCCIN_CPU1")
		)
		(pad "BU70" smd circle
			(at 23.514558 0.833628)
			(size 0.4318 0.4318)
			(layers "F.Cu" "F.Mask" "F.Paste")
			(net "PVCCIN_CPU1")
		)
		(pad "BU72" smd circle
			(at 25.231598 0.833628)
			(size 0.4318 0.4318)
			(layers "F.Cu" "F.Mask" "F.Paste")
			(net "PVCCIN_CPU1")
		)
		(pad "BU74" smd circle
			(at 26.948384 0.833628)
			(size 0.4318 0.4318)
			(layers "F.Cu" "F.Mask" "F.Paste")
			(net "PVCCIN_CPU1")
		)
		(pad "BU76" smd circle
			(at 28.665424 0.833628)
			(size 0.4318 0.4318)
			(layers "F.Cu" "F.Mask" "F.Paste")
			(net "PVCCIN_CPU1")
		)
		(pad "BU78" smd circle
			(at 30.382464 0.833628)
			(size 0.4318 0.4318)
			(layers "F.Cu" "F.Mask" "F.Paste")
			(net "PVCCIN_CPU1")
		)
		(pad "BU80" smd circle
			(at 32.099504 0.833628)
			(size 0.4318 0.4318)
			(layers "F.Cu" "F.Mask" "F.Paste")
			(net "PVCCIN_CPU1")
		)
		(pad "BU82" smd circle
			(at 33.816544 0.833628)
			(size 0.4318 0.4318)
			(layers "F.Cu" "F.Mask" "F.Paste")
			(net "PVCCIN_CPU1")
		)
		(pad "BU84" smd custom
			(at 35.533584 0.833628 270)
			(size 0.10795 0.10795)
			(layers "F.Cu" "F.Mask" "F.Paste")
			(net "PVCCIN_CPU1")
			(options
				(clearance outline)
				(anchor circle)
			)
			(primitives
				(gr_poly
					(pts
						(arc
							(start 0.2159 -0.0381)
							(mid 0 -0.254)
							(end -0.2159 -0.0381)
						)
						(arc
							(start -0.2159 0.0381)
							(mid 0 0.254)
							(end 0.2159 0.0381)
						)
					)
					(width 0)
					(fill yes)
				)
			)
		)
		(pad "BV3" smd custom
			(at -35.533584 3.128772 90)
			(size 0.10795 0.10795)
			(layers "F.Cu" "F.Mask" "F.Paste")
			(net "TP_P3E_CPU1_PE2_RSR_TXP<11>")
			(options
				(clearance outline)
				(anchor circle)
			)
			(primitives
				(gr_poly
					(pts
						(arc
							(start 0.2159 -0.0381)
							(mid 0 -0.254)
							(end -0.2159 -0.0381)
						)
						(arc
							(start -0.2159 0.0381)
							(mid 0 0.254)
							(end 0.2159 0.0381)
						)
					)
					(width 0)
					(fill yes)
				)
			)
		)
		(pad "BV5" smd circle
			(at -33.816544 3.128772)
			(size 0.4318 0.4318)
			(layers "F.Cu" "F.Mask" "F.Paste")
			(net "GND")
		)
		(pad "BV7" smd circle
			(at -32.099504 3.128772)
			(size 0.4318 0.4318)
			(layers "F.Cu" "F.Mask" "F.Paste")
			(net "TP_P3E_CPU1_PE2_RSR_RXN<10>")
		)
		(pad "BV9" smd circle
			(at -30.382464 3.128772)
			(size 0.4318 0.4318)
			(layers "F.Cu" "F.Mask" "F.Paste")
			(net "TP_P3E_CPU1_PE2_RSR_RXP<8>")
		)
		(pad "BV11" smd circle
			(at -28.665424 3.128772)
			(size 0.4318 0.4318)
			(layers "F.Cu" "F.Mask" "F.Paste")
			(net "PVCCIOMCP_CPU1")
		)
		(pad "BV13" smd circle
			(at -26.948384 3.128772)
			(size 0.4318 0.4318)
			(layers "F.Cu" "F.Mask" "F.Paste")
			(net "PVCCIOMCP_CPU1")
		)
		(pad "BV15" smd circle
			(at -25.231598 3.128772)
			(size 0.4318 0.4318)
			(layers "F.Cu" "F.Mask" "F.Paste")
			(net "PVCCIOMCP_CPU1")
		)
		(pad "BV17" smd circle
			(at -23.514558 3.128772)
			(size 0.4318 0.4318)
			(layers "F.Cu" "F.Mask" "F.Paste")
			(net "GND")
		)
		(pad "BV19" smd circle
			(at -21.797518 3.128772)
			(size 0.4318 0.4318)
			(layers "F.Cu" "F.Mask" "F.Paste")
			(net "PVCCMCP_CPU1")
		)
		(pad "BV21" smd circle
			(at -20.080478 3.128772)
			(size 0.4318 0.4318)
			(layers "F.Cu" "F.Mask" "F.Paste")
			(net "PVCCMCP_CPU1")
		)
		(pad "BV23" smd circle
			(at -18.363438 3.128772)
			(size 0.4318 0.4318)
			(layers "F.Cu" "F.Mask" "F.Paste")
			(net "TP_CPU1_RSVD_124")
		)
		(pad "BV25" smd circle
			(at -16.646398 3.128772)
			(size 0.4318 0.4318)
			(layers "F.Cu" "F.Mask" "F.Paste")
			(net "GND")
		)
		(pad "BV27" smd circle
			(at -14.929612 3.128772)
			(size 0.4318 0.4318)
			(layers "F.Cu" "F.Mask" "F.Paste")
			(net "P1V8_MCP_CPU1")
		)
		(pad "BV61" smd circle
			(at 15.787878 1.328674)
			(size 0.4318 0.4318)
			(layers "F.Cu" "F.Mask" "F.Paste")
			(net "PVCCIN_CPU1")
		)
		(pad "BV63" smd circle
			(at 17.504918 1.328674)
			(size 0.4318 0.4318)
			(layers "F.Cu" "F.Mask" "F.Paste")
			(net "PVCCIN_CPU1")
		)
		(pad "BV65" smd circle
			(at 19.221958 1.328674)
			(size 0.4318 0.4318)
			(layers "F.Cu" "F.Mask" "F.Paste")
			(net "PVCCIN_CPU1")
		)
		(pad "BV67" smd circle
			(at 20.938998 1.328674)
			(size 0.4318 0.4318)
			(layers "F.Cu" "F.Mask" "F.Paste")
			(net "PVCCIN_CPU1")
		)
		(pad "BV69" smd circle
			(at 22.656038 1.328674)
			(size 0.4318 0.4318)
			(layers "F.Cu" "F.Mask" "F.Paste")
			(net "PVCCIN_CPU1")
		)
		(pad "BV71" smd circle
			(at 24.373078 1.328674)
			(size 0.4318 0.4318)
			(layers "F.Cu" "F.Mask" "F.Paste")
			(net "PVCCIN_CPU1")
		)
		(pad "BV73" smd circle
			(at 26.090118 1.328674)
			(size 0.4318 0.4318)
			(layers "F.Cu" "F.Mask" "F.Paste")
			(net "PVCCIN_CPU1")
		)
		(pad "BV75" smd circle
			(at 27.806904 1.328674)
			(size 0.4318 0.4318)
			(layers "F.Cu" "F.Mask" "F.Paste")
			(net "PVCCIN_CPU1")
		)
		(pad "BV77" smd circle
			(at 29.523944 1.328674)
			(size 0.4318 0.4318)
			(layers "F.Cu" "F.Mask" "F.Paste")
			(net "PVCCIN_CPU1")
		)
		(pad "BV79" smd circle
			(at 31.240984 1.328674)
			(size 0.4318 0.4318)
			(layers "F.Cu" "F.Mask" "F.Paste")
			(net "PVCCIN_CPU1")
		)
		(pad "BV81" smd circle
			(at 32.958024 1.328674)
			(size 0.4318 0.4318)
			(layers "F.Cu" "F.Mask" "F.Paste")
			(net "PVCCIN_CPU1")
		)
		(pad "BV83" smd circle
			(at 34.675064 1.328674)
			(size 0.4318 0.4318)
			(layers "F.Cu" "F.Mask" "F.Paste")
			(net "PVCCIN_CPU1")
		)
		(pad "BW4" smd circle
			(at -34.675064 3.624326)
			(size 0.4318 0.4318)
			(layers "F.Cu" "F.Mask" "F.Paste")
			(net "TP_P3E_CPU1_PE2_RSR_TXN<11>")
		)
		(pad "BW6" smd circle
			(at -32.958024 3.624326)
			(size 0.4318 0.4318)
			(layers "F.Cu" "F.Mask" "F.Paste")
			(net "GND")
		)
		(pad "BW8" smd circle
			(at -31.240984 3.624326)
			(size 0.4318 0.4318)
			(layers "F.Cu" "F.Mask" "F.Paste")
			(net "TP_P3E_CPU1_PE2_RSR_RXP<9>")
		)
		(pad "BW10" smd circle
			(at -29.523944 3.624326)
			(size 0.4318 0.4318)
			(layers "F.Cu" "F.Mask" "F.Paste")
			(net "TP_CPU1_RSVD_123")
		)
		(pad "BW12" smd circle
			(at -27.806904 3.624326)
			(size 0.4318 0.4318)
			(layers "F.Cu" "F.Mask" "F.Paste")
			(net "GND")
		)
		(pad "BW14" smd circle
			(at -26.090118 3.624326)
			(size 0.4318 0.4318)
			(layers "F.Cu" "F.Mask" "F.Paste")
			(net "GND")
		)
		(pad "BW16" smd circle
			(at -24.373078 3.624326)
			(size 0.4318 0.4318)
			(layers "F.Cu" "F.Mask" "F.Paste")
			(net "GND")
		)
		(pad "BW18" smd circle
			(at -22.656038 3.624326)
			(size 0.4318 0.4318)
			(layers "F.Cu" "F.Mask" "F.Paste")
			(net "GND")
		)
		(pad "BW20" smd circle
			(at -20.938998 3.624326)
			(size 0.4318 0.4318)
			(layers "F.Cu" "F.Mask" "F.Paste")
			(net "PVCCMCP_CPU1")
		)
		(pad "BW22" smd circle
			(at -19.221958 3.624326)
			(size 0.4318 0.4318)
			(layers "F.Cu" "F.Mask" "F.Paste")
			(net "TP_CPU1_RSVD_121")
		)
		(pad "BW24" smd circle
			(at -17.504918 3.624326)
			(size 0.4318 0.4318)
			(layers "F.Cu" "F.Mask" "F.Paste")
			(net "CLK_100M_CPU1_PE_REFCLK_DP")
		)
		(pad "BW26" smd circle
			(at -15.787878 3.624326)
			(size 0.4318 0.4318)
			(layers "F.Cu" "F.Mask" "F.Paste")
			(net "GND")
		)
		(pad "BW60" smd circle
			(at 14.929612 1.824228)
			(size 0.508 0.508)
			(layers "F.Cu" "F.Mask" "F.Paste")
			(net "PVCCIN_CPU1")
		)
		(pad "BW62" smd circle
			(at 16.646398 1.824228)
			(size 0.4318 0.4318)
			(layers "F.Cu" "F.Mask" "F.Paste")
			(net "PVCCIN_CPU1")
		)
		(pad "BW64" smd circle
			(at 18.363438 1.824228)
			(size 0.4318 0.4318)
			(layers "F.Cu" "F.Mask" "F.Paste")
			(net "PVCCIN_CPU1")
		)
		(pad "BW66" smd circle
			(at 20.080478 1.824228)
			(size 0.4318 0.4318)
			(layers "F.Cu" "F.Mask" "F.Paste")
			(net "PVCCIN_CPU1")
		)
		(pad "BW68" smd circle
			(at 21.797518 1.824228)
			(size 0.4318 0.4318)
			(layers "F.Cu" "F.Mask" "F.Paste")
			(net "PVCCIN_CPU1")
		)
		(pad "BW70" smd circle
			(at 23.514558 1.824228)
			(size 0.4318 0.4318)
			(layers "F.Cu" "F.Mask" "F.Paste")
			(net "PVCCIN_CPU1")
		)
		(pad "BW72" smd circle
			(at 25.231598 1.824228)
			(size 0.4318 0.4318)
			(layers "F.Cu" "F.Mask" "F.Paste")
			(net "GND")
		)
		(pad "BW74" smd circle
			(at 26.948384 1.824228)
			(size 0.4318 0.4318)
			(layers "F.Cu" "F.Mask" "F.Paste")
			(net "GND")
		)
		(pad "BW76" smd circle
			(at 28.665424 1.824228)
			(size 0.4318 0.4318)
			(layers "F.Cu" "F.Mask" "F.Paste")
			(net "GND")
		)
		(pad "BW78" smd circle
			(at 30.382464 1.824228)
			(size 0.4318 0.4318)
			(layers "F.Cu" "F.Mask" "F.Paste")
			(net "GND")
		)
		(pad "BW80" smd circle
			(at 32.099504 1.824228)
			(size 0.4318 0.4318)
			(layers "F.Cu" "F.Mask" "F.Paste")
			(net "GND")
		)
		(pad "BW82" smd circle
			(at 33.816544 1.824228)
			(size 0.4318 0.4318)
			(layers "F.Cu" "F.Mask" "F.Paste")
			(net "GND")
		)
		(pad "BW84" smd custom
			(at 35.533584 1.824228 270)
			(size 0.10795 0.10795)
			(layers "F.Cu" "F.Mask" "F.Paste")
			(net "PVCCIN_CPU1")
			(options
				(clearance outline)
				(anchor circle)
			)
			(primitives
				(gr_poly
					(pts
						(arc
							(start 0.2159 -0.0381)
							(mid 0 -0.254)
							(end -0.2159 -0.0381)
						)
						(arc
							(start -0.2159 0.0381)
							(mid 0 0.254)
							(end 0.2159 0.0381)
						)
					)
					(width 0)
					(fill yes)
				)
			)
		)
		(pad "BY3" smd custom
			(at -35.533584 4.119372 90)
			(size 0.10795 0.10795)
			(layers "F.Cu" "F.Mask" "F.Paste")
			(net "TP_P3E_CPU1_PE2_RSR_TXP<9>")
			(options
				(clearance outline)
				(anchor circle)
			)
			(primitives
				(gr_poly
					(pts
						(arc
							(start 0.2159 -0.0381)
							(mid 0 -0.254)
							(end -0.2159 -0.0381)
						)
						(arc
							(start -0.2159 0.0381)
							(mid 0 0.254)
							(end 0.2159 0.0381)
						)
					)
					(width 0)
					(fill yes)
				)
			)
		)
		(pad "BY5" smd circle
			(at -33.816544 4.119372)
			(size 0.4318 0.4318)
			(layers "F.Cu" "F.Mask" "F.Paste")
			(net "TP_P3E_CPU1_PE2_RSR_TXP<10>")
		)
		(pad "BY7" smd circle
			(at -32.099504 4.119372)
			(size 0.4318 0.4318)
			(layers "F.Cu" "F.Mask" "F.Paste")
			(net "TP_P3E_CPU1_PE2_RSR_RXN<9>")
		)
		(pad "BY9" smd circle
			(at -30.382464 4.119372)
			(size 0.4318 0.4318)
			(layers "F.Cu" "F.Mask" "F.Paste")
			(net "TP_P3E_CPU1_PE2_RSR_RXN<8>")
		)
		(pad "BY11" smd circle
			(at -28.665424 4.119372)
			(size 0.4318 0.4318)
			(layers "F.Cu" "F.Mask" "F.Paste")
			(net "GND")
		)
		(pad "BY13" smd circle
			(at -26.948384 4.119372)
			(size 0.4318 0.4318)
			(layers "F.Cu" "F.Mask" "F.Paste")
			(net "GND")
		)
		(pad "BY15" smd circle
			(at -25.231598 4.119372)
			(size 0.4318 0.4318)
			(layers "F.Cu" "F.Mask" "F.Paste")
			(net "GND")
		)
		(pad "BY17" smd circle
			(at -23.514558 4.119372)
			(size 0.4318 0.4318)
			(layers "F.Cu" "F.Mask" "F.Paste")
			(net "GND")
		)
		(pad "BY19" smd circle
			(at -21.797518 4.119372)
			(size 0.4318 0.4318)
			(layers "F.Cu" "F.Mask" "F.Paste")
			(net "PVCCMCP_CPU1")
		)
		(pad "BY21" smd circle
			(at -20.080478 4.119372)
			(size 0.4318 0.4318)
			(layers "F.Cu" "F.Mask" "F.Paste")
			(net "JTAG_MCP_CPU1_TDI")
		)
		(pad "BY23" smd circle
			(at -18.363438 4.119372)
			(size 0.4318 0.4318)
			(layers "F.Cu" "F.Mask" "F.Paste")
			(net "GND")
		)
		(pad "BY25" smd circle
			(at -16.646398 4.119372)
			(size 0.4318 0.4318)
			(layers "F.Cu" "F.Mask" "F.Paste")
			(net "TP_CPU1_RSVD_119")
		)
		(pad "BY27" smd circle
			(at -14.929612 4.119372)
			(size 0.4318 0.4318)
			(layers "F.Cu" "F.Mask" "F.Paste")
			(net "P1V8_MCP_CPU1")
		)
		(pad "BY61" smd circle
			(at 15.787878 2.319274)
			(size 0.4318 0.4318)
			(layers "F.Cu" "F.Mask" "F.Paste")
			(net "PVCCIN_CPU1")
		)
		(pad "BY63" smd circle
			(at 17.504918 2.319274)
			(size 0.4318 0.4318)
			(layers "F.Cu" "F.Mask" "F.Paste")
			(net "GND")
		)
		(pad "BY65" smd circle
			(at 19.221958 2.319274)
			(size 0.4318 0.4318)
			(layers "F.Cu" "F.Mask" "F.Paste")
			(net "GND")
		)
		(pad "BY67" smd circle
			(at 20.938998 2.319274)
			(size 0.4318 0.4318)
			(layers "F.Cu" "F.Mask" "F.Paste")
			(net "GND")
		)
		(pad "BY69" smd circle
			(at 22.656038 2.319274)
			(size 0.4318 0.4318)
			(layers "F.Cu" "F.Mask" "F.Paste")
			(net "GND")
		)
		(pad "BY71" smd circle
			(at 24.373078 2.319274)
			(size 0.4318 0.4318)
			(layers "F.Cu" "F.Mask" "F.Paste")
			(net "GND")
		)
		(pad "BY73" smd circle
			(at 26.090118 2.319274)
			(size 0.4318 0.4318)
			(layers "F.Cu" "F.Mask" "F.Paste")
			(net "PVCCIN_CPU1")
		)
		(pad "BY75" smd circle
			(at 27.806904 2.319274)
			(size 0.4318 0.4318)
			(layers "F.Cu" "F.Mask" "F.Paste")
			(net "PVCCIN_CPU1")
		)
		(pad "BY77" smd circle
			(at 29.523944 2.319274)
			(size 0.4318 0.4318)
			(layers "F.Cu" "F.Mask" "F.Paste")
			(net "PVCCIN_CPU1")
		)
		(pad "BY79" smd circle
			(at 31.240984 2.319274)
			(size 0.4318 0.4318)
			(layers "F.Cu" "F.Mask" "F.Paste")
			(net "PVCCIN_CPU1")
		)
		(pad "BY81" smd circle
			(at 32.958024 2.319274)
			(size 0.4318 0.4318)
			(layers "F.Cu" "F.Mask" "F.Paste")
			(net "PVCCIN_CPU1")
		)
		(pad "BY83" smd circle
			(at 34.675064 2.319274)
			(size 0.4318 0.4318)
			(layers "F.Cu" "F.Mask" "F.Paste")
			(net "PVCCIN_CPU1")
		)
		(pad "C4" smd custom
			(at -34.675064 -24.112474 45)
			(size 0.10795 0.10795)
			(layers "F.Cu" "F.Mask" "F.Paste")
			(net "GND")
			(options
				(clearance outline)
				(anchor circle)
			)
			(primitives
				(gr_poly
					(pts
						(arc
							(start 0.2159 -0.0381)
							(mid 0 -0.254)
							(end -0.2159 -0.0381)
						)
						(arc
							(start -0.2159 0.0381)
							(mid 0 0.254)
							(end 0.2159 0.0381)
						)
					)
					(width 0)
					(fill yes)
				)
			)
		)
		(pad "C6" smd custom
			(at -32.958024 -24.112474)
			(size 0.10795 0.10795)
			(layers "F.Cu" "F.Mask" "F.Paste")
			(net "TP_CPU1_RSVD_291")
			(options
				(clearance outline)
				(anchor circle)
			)
			(primitives
				(gr_poly
					(pts
						(arc
							(start 0.2159 -0.0381)
							(mid 0 -0.254)
							(end -0.2159 -0.0381)
						)
						(arc
							(start -0.2159 0.0381)
							(mid 0 0.254)
							(end 0.2159 0.0381)
						)
					)
					(width 0)
					(fill yes)
				)
			)
		)
		(pad "C8" smd circle
			(at -31.240984 -24.112474)
			(size 0.4318 0.4318)
			(layers "F.Cu" "F.Mask" "F.Paste")
			(net "GND")
		)
		(pad "C10" smd circle
			(at -29.523944 -24.112474)
			(size 0.4318 0.4318)
			(layers "F.Cu" "F.Mask" "F.Paste")
			(net "GND")
		)
		(pad "C12" smd circle
			(at -27.806904 -24.112474)
			(size 0.4318 0.4318)
			(layers "F.Cu" "F.Mask" "F.Paste")
			(net "GND")
		)
		(pad "C14" smd circle
			(at -26.090118 -24.112474)
			(size 0.4318 0.4318)
			(layers "F.Cu" "F.Mask" "F.Paste")
			(net "GND")
		)
		(pad "C16" smd circle
			(at -24.373078 -24.112474)
			(size 0.4318 0.4318)
			(layers "F.Cu" "F.Mask" "F.Paste")
			(net "GND")
		)
		(pad "C18" smd custom
			(at -22.656038 -24.112474)
			(size 0.10795 0.10795)
			(layers "F.Cu" "F.Mask" "F.Paste")
			(net "TP_CPU1_RSVD_290")
			(options
				(clearance outline)
				(anchor circle)
			)
			(primitives
				(gr_poly
					(pts
						(arc
							(start 0.2159 -0.0381)
							(mid 0 -0.254)
							(end -0.2159 -0.0381)
						)
						(arc
							(start -0.2159 0.0381)
							(mid 0 0.254)
							(end 0.2159 0.0381)
						)
					)
					(width 0)
					(fill yes)
				)
			)
		)
		(pad "C24" smd custom
			(at -17.504918 -24.112474)
			(size 0.10795 0.10795)
			(layers "F.Cu" "F.Mask" "F.Paste")
			(net "TP_CPU1_RSVD_289")
			(options
				(clearance outline)
				(anchor circle)
			)
			(primitives
				(gr_poly
					(pts
						(arc
							(start 0.2159 -0.0381)
							(mid 0 -0.254)
							(end -0.2159 -0.0381)
						)
						(arc
							(start -0.2159 0.0381)
							(mid 0 0.254)
							(end 0.2159 0.0381)
						)
					)
					(width 0)
					(fill yes)
				)
			)
		)
		(pad "C26" smd circle
			(at -15.787878 -24.112474)
			(size 0.4318 0.4318)
			(layers "F.Cu" "F.Mask" "F.Paste")
			(net "M_H_DQ<50>")
		)
		(pad "C28" smd circle
			(at -14.071092 -24.112474)
			(size 0.4318 0.4318)
			(layers "F.Cu" "F.Mask" "F.Paste")
			(net "M_H_DQS_DP<15>")
		)
		(pad "C30" smd circle
			(at -12.354052 -24.112474)
			(size 0.4318 0.4318)
			(layers "F.Cu" "F.Mask" "F.Paste")
			(net "M_H_DQ<48>")
		)
		(pad "C32" smd circle
			(at -10.637012 -24.112474)
			(size 0.4318 0.4318)
			(layers "F.Cu" "F.Mask" "F.Paste")
			(net "M_H_DQ<42>")
		)
		(pad "C34" smd circle
			(at -8.919972 -24.112474)
			(size 0.4318 0.4318)
			(layers "F.Cu" "F.Mask" "F.Paste")
			(net "M_H_DQS_DP<14>")
		)
		(pad "C36" smd circle
			(at -7.202932 -24.112474)
			(size 0.4318 0.4318)
			(layers "F.Cu" "F.Mask" "F.Paste")
			(net "M_H_DQ<40>")
		)
		(pad "C38" smd circle
			(at -5.485892 -24.112474)
			(size 0.4318 0.4318)
			(layers "F.Cu" "F.Mask" "F.Paste")
			(net "M_G_DQ<34>")
		)
		(pad "C40" smd circle
			(at -3.769106 -24.112474)
			(size 0.4318 0.4318)
			(layers "F.Cu" "F.Mask" "F.Paste")
			(net "M_G_DQS_DP<13>")
		)
		(pad "C42" smd circle
			(at -2.052066 -24.112474)
			(size 0.4318 0.4318)
			(layers "F.Cu" "F.Mask" "F.Paste")
			(net "M_G_DQ<32>")
		)
		(pad "C46" smd custom
			(at 2.910586 -25.912572 45)
			(size 0.10795 0.10795)
			(layers "F.Cu" "F.Mask" "F.Paste")
			(net "PVDDQ_GHJ")
			(options
				(clearance outline)
				(anchor circle)
			)
			(primitives
				(gr_poly
					(pts
						(arc
							(start 0.2159 -0.0381)
							(mid 0 -0.254)
							(end -0.2159 -0.0381)
						)
						(arc
							(start -0.2159 0.0381)
							(mid 0 0.254)
							(end 0.2159 0.0381)
						)
					)
					(width 0)
					(fill yes)
				)
			)
		)
		(pad "C48" smd circle
			(at 4.627626 -25.912572)
			(size 0.4318 0.4318)
			(layers "F.Cu" "F.Mask" "F.Paste")
			(net "M_G_ODT<1>")
		)
		(pad "C50" smd circle
			(at 6.344412 -25.912572)
			(size 0.4318 0.4318)
			(layers "F.Cu" "F.Mask" "F.Paste")
			(net "M_G_ODT<0>")
		)
		(pad "C52" smd circle
			(at 8.061452 -25.912572)
			(size 0.4318 0.4318)
			(layers "F.Cu" "F.Mask" "F.Paste")
			(net "M_G_BA<0>")
		)
		(pad "C54" smd circle
			(at 9.778492 -25.912572)
			(size 0.4318 0.4318)
			(layers "F.Cu" "F.Mask" "F.Paste")
			(net "M_G_CLK_DN<1>")
		)
		(pad "C56" smd circle
			(at 11.495532 -25.912572)
			(size 0.4318 0.4318)
			(layers "F.Cu" "F.Mask" "F.Paste")
			(net "M_G_CLK_DN<3>")
		)
		(pad "C58" smd circle
			(at 13.212572 -25.912572)
			(size 0.4318 0.4318)
			(layers "F.Cu" "F.Mask" "F.Paste")
			(net "M_G_MA<3>")
		)
		(pad "C60" smd circle
			(at 14.929612 -25.912572)
			(size 0.4318 0.4318)
			(layers "F.Cu" "F.Mask" "F.Paste")
			(net "M_G_MA<8>")
		)
		(pad "C62" smd circle
			(at 16.646398 -25.912572)
			(size 0.4318 0.4318)
			(layers "F.Cu" "F.Mask" "F.Paste")
			(net "M_G_CKE<0>")
		)
		(pad "C64" smd custom
			(at 18.363438 -25.912572)
			(size 0.10795 0.10795)
			(layers "F.Cu" "F.Mask" "F.Paste")
			(net "M_G_CKE<1>")
			(options
				(clearance outline)
				(anchor circle)
			)
			(primitives
				(gr_poly
					(pts
						(arc
							(start 0.2159 -0.0381)
							(mid 0 -0.254)
							(end -0.2159 -0.0381)
						)
						(arc
							(start -0.2159 0.0381)
							(mid 0 0.254)
							(end 0.2159 0.0381)
						)
					)
					(width 0)
					(fill yes)
				)
			)
		)
		(pad "C72" smd circle
			(at 25.231598 -25.912572)
			(size 0.4318 0.4318)
			(layers "F.Cu" "F.Mask" "F.Paste")
			(net "M_H_DQ<30>")
		)
		(pad "C74" smd circle
			(at 26.948384 -25.912572)
			(size 0.4318 0.4318)
			(layers "F.Cu" "F.Mask" "F.Paste")
			(net "M_H_DQ<25>")
		)
		(pad "C76" smd circle
			(at 28.665424 -25.912572)
			(size 0.4318 0.4318)
			(layers "F.Cu" "F.Mask" "F.Paste")
			(net "GND")
		)
		(pad "C78" smd circle
			(at 30.382464 -25.912572)
			(size 0.4318 0.4318)
			(layers "F.Cu" "F.Mask" "F.Paste")
			(net "GND")
		)
		(pad "C80" smd custom
			(at 32.099504 -25.912572 315)
			(size 0.10795 0.10795)
			(layers "F.Cu" "F.Mask" "F.Paste")
			(net "GND")
			(options
				(clearance outline)
				(anchor circle)
			)
			(primitives
				(gr_poly
					(pts
						(arc
							(start 0.2159 -0.0381)
							(mid 0 -0.254)
							(end -0.2159 -0.0381)
						)
						(arc
							(start -0.2159 0.0381)
							(mid 0 0.254)
							(end 0.2159 0.0381)
						)
					)
					(width 0)
					(fill yes)
				)
			)
		)
		(pad "C82" smd custom
			(at 33.816544 -25.912572 315)
			(size 0.10795 0.10795)
			(layers "F.Cu" "F.Mask" "F.Paste")
			(net "TP_CPU1_RSVD_288")
			(options
				(clearance outline)
				(anchor circle)
			)
			(primitives
				(gr_poly
					(pts
						(arc
							(start 0.2159 -0.0381)
							(mid 0 -0.254)
							(end -0.2159 -0.0381)
						)
						(arc
							(start -0.2159 0.0381)
							(mid 0 0.254)
							(end 0.2159 0.0381)
						)
					)
					(width 0)
					(fill yes)
				)
			)
		)
		(pad "CA2" smd custom
			(at -36.392104 4.614926 90)
			(size 0.10795 0.10795)
			(layers "F.Cu" "F.Mask" "F.Paste")
			(net "GND")
			(options
				(clearance outline)
				(anchor circle)
			)
			(primitives
				(gr_poly
					(pts
						(arc
							(start 0.2159 -0.0381)
							(mid 0 -0.254)
							(end -0.2159 -0.0381)
						)
						(arc
							(start -0.2159 0.0381)
							(mid 0 0.254)
							(end 0.2159 0.0381)
						)
					)
					(width 0)
					(fill yes)
				)
			)
		)
		(pad "CA4" smd circle
			(at -34.675064 4.614926)
			(size 0.4318 0.4318)
			(layers "F.Cu" "F.Mask" "F.Paste")
			(net "TP_P3E_CPU1_PE2_RSR_TXN<10>")
		)
		(pad "CA6" smd circle
			(at -32.958024 4.614926)
			(size 0.4318 0.4318)
			(layers "F.Cu" "F.Mask" "F.Paste")
			(net "GND")
		)
		(pad "CA8" smd circle
			(at -31.240984 4.614926)
			(size 0.4318 0.4318)
			(layers "F.Cu" "F.Mask" "F.Paste")
			(net "GND")
		)
		(pad "CA10" smd circle
			(at -29.523944 4.614926)
			(size 0.4318 0.4318)
			(layers "F.Cu" "F.Mask" "F.Paste")
			(net "GND")
		)
		(pad "CA12" smd circle
			(at -27.806904 4.614926)
			(size 0.4318 0.4318)
			(layers "F.Cu" "F.Mask" "F.Paste")
			(net "TP_CPU1_UPI2_RSVD_DP21")
		)
		(pad "CA14" smd circle
			(at -26.090118 4.614926)
			(size 0.4318 0.4318)
			(layers "F.Cu" "F.Mask" "F.Paste")
			(net "GND")
		)
		(pad "CA16" smd circle
			(at -24.373078 4.614926)
			(size 0.4318 0.4318)
			(layers "F.Cu" "F.Mask" "F.Paste")
			(net "GND")
		)
		(pad "CA18" smd circle
			(at -22.656038 4.614926)
			(size 0.4318 0.4318)
			(layers "F.Cu" "F.Mask" "F.Paste")
			(net "GND")
		)
		(pad "CA20" smd circle
			(at -20.938998 4.614926)
			(size 0.4318 0.4318)
			(layers "F.Cu" "F.Mask" "F.Paste")
			(net "GND")
		)
		(pad "CA22" smd circle
			(at -19.221958 4.614926)
			(size 0.4318 0.4318)
			(layers "F.Cu" "F.Mask" "F.Paste")
			(net "PVCCMCP_CPU1")
		)
		(pad "CA24" smd circle
			(at -17.504918 4.614926)
			(size 0.4318 0.4318)
			(layers "F.Cu" "F.Mask" "F.Paste")
			(net "TP_CPU1_RSVD_117")
		)
		(pad "CA26" smd circle
			(at -15.787878 4.614926)
			(size 0.4318 0.4318)
			(layers "F.Cu" "F.Mask" "F.Paste")
			(net "GND")
		)
		(pad "CA60" smd circle
			(at 14.929612 2.814828)
			(size 0.508 0.508)
			(layers "F.Cu" "F.Mask" "F.Paste")
			(net "PVCCIN_CPU1")
		)
		(pad "CA62" smd circle
			(at 16.646398 2.814828)
			(size 0.4318 0.4318)
			(layers "F.Cu" "F.Mask" "F.Paste")
			(net "PVCCIN_CPU1")
		)
		(pad "CA64" smd circle
			(at 18.363438 2.814828)
			(size 0.4318 0.4318)
			(layers "F.Cu" "F.Mask" "F.Paste")
			(net "GND")
		)
		(pad "CA66" smd circle
			(at 20.080478 2.814828)
			(size 0.4318 0.4318)
			(layers "F.Cu" "F.Mask" "F.Paste")
			(net "GND")
		)
		(pad "CA68" smd circle
			(at 21.797518 2.814828)
			(size 0.4318 0.4318)
			(layers "F.Cu" "F.Mask" "F.Paste")
			(net "GND")
		)
		(pad "CA70" smd circle
			(at 23.514558 2.814828)
			(size 0.4318 0.4318)
			(layers "F.Cu" "F.Mask" "F.Paste")
			(net "GND")
		)
		(pad "CA72" smd circle
			(at 25.231598 2.814828)
			(size 0.4318 0.4318)
			(layers "F.Cu" "F.Mask" "F.Paste")
			(net "PVCCIN_CPU1")
		)
		(pad "CA74" smd circle
			(at 26.948384 2.814828)
			(size 0.4318 0.4318)
			(layers "F.Cu" "F.Mask" "F.Paste")
			(net "PVCCIN_CPU1")
		)
		(pad "CA76" smd circle
			(at 28.665424 2.814828)
			(size 0.4318 0.4318)
			(layers "F.Cu" "F.Mask" "F.Paste")
			(net "PVCCIN_CPU1")
		)
		(pad "CA78" smd circle
			(at 30.382464 2.814828)
			(size 0.4318 0.4318)
			(layers "F.Cu" "F.Mask" "F.Paste")
			(net "PVCCIN_CPU1")
		)
		(pad "CA80" smd circle
			(at 32.099504 2.814828)
			(size 0.4318 0.4318)
			(layers "F.Cu" "F.Mask" "F.Paste")
			(net "PVCCIN_CPU1")
		)
		(pad "CA82" smd circle
			(at 33.816544 2.814828)
			(size 0.4318 0.4318)
			(layers "F.Cu" "F.Mask" "F.Paste")
			(net "PVCCIN_CPU1")
		)
		(pad "CA84" smd custom
			(at 35.533584 2.814828 270)
			(size 0.10795 0.10795)
			(layers "F.Cu" "F.Mask" "F.Paste")
			(net "PVCCIN_CPU1")
			(options
				(clearance outline)
				(anchor circle)
			)
			(primitives
				(gr_poly
					(pts
						(arc
							(start 0.2159 -0.0381)
							(mid 0 -0.254)
							(end -0.2159 -0.0381)
						)
						(arc
							(start -0.2159 0.0381)
							(mid 0 0.254)
							(end 0.2159 0.0381)
						)
					)
					(width 0)
					(fill yes)
				)
			)
		)
		(pad "CB3" smd circle
			(at -35.533584 5.109972)
			(size 0.4318 0.4318)
			(layers "F.Cu" "F.Mask" "F.Paste")
			(net "TP_P3E_CPU1_PE2_RSR_TXN<9>")
		)
		(pad "CB5" smd circle
			(at -33.816544 5.109972)
			(size 0.4318 0.4318)
			(layers "F.Cu" "F.Mask" "F.Paste")
			(net "TP_CPU1_RSVD_113")
		)
		(pad "CB7" smd circle
			(at -32.099504 5.109972)
			(size 0.4318 0.4318)
			(layers "F.Cu" "F.Mask" "F.Paste")
			(net "GND")
		)
		(pad "CB9" smd circle
			(at -30.382464 5.109972)
			(size 0.4318 0.4318)
			(layers "F.Cu" "F.Mask" "F.Paste")
			(net "GND")
		)
		(pad "CB11" smd circle
			(at -28.665424 5.109972)
			(size 0.4318 0.4318)
			(layers "F.Cu" "F.Mask" "F.Paste")
			(net "TP_CPU1_UPI2_RSVD_DN20")
		)
		(pad "CB13" smd circle
			(at -26.948384 5.109972)
			(size 0.4318 0.4318)
			(layers "F.Cu" "F.Mask" "F.Paste")
			(net "PVCCIO_CPU1")
		)
		(pad "CB15" smd circle
			(at -25.231598 5.109972)
			(size 0.4318 0.4318)
			(layers "F.Cu" "F.Mask" "F.Paste")
			(net "GND")
		)
		(pad "CB17" smd circle
			(at -23.514558 5.109972)
			(size 0.4318 0.4318)
			(layers "F.Cu" "F.Mask" "F.Paste")
			(net "PVCCIO_CPU1")
		)
		(pad "CB19" smd circle
			(at -21.797518 5.109972)
			(size 0.4318 0.4318)
			(layers "F.Cu" "F.Mask" "F.Paste")
			(net "PVCCMCP_CPU1")
		)
		(pad "CB21" smd circle
			(at -20.080478 5.109972)
			(size 0.4318 0.4318)
			(layers "F.Cu" "F.Mask" "F.Paste")
			(net "PVCCMCP_CPU1")
		)
		(pad "CB23" smd circle
			(at -18.363438 5.109972)
			(size 0.4318 0.4318)
			(layers "F.Cu" "F.Mask" "F.Paste")
			(net "JTAG_MCP_TCK")
		)
		(pad "CB25" smd circle
			(at -16.646398 5.109972)
			(size 0.4318 0.4318)
			(layers "F.Cu" "F.Mask" "F.Paste")
			(net "TP_CPU1_RSVD_114")
		)
		(pad "CB27" smd circle
			(at -14.929612 5.109972)
			(size 0.4318 0.4318)
			(layers "F.Cu" "F.Mask" "F.Paste")
			(net "GND")
		)
		(pad "CB61" smd circle
			(at 15.787878 3.309874)
			(size 0.4318 0.4318)
			(layers "F.Cu" "F.Mask" "F.Paste")
			(net "PVCCIN_CPU1")
		)
		(pad "CB63" smd circle
			(at 17.504918 3.309874)
			(size 0.4318 0.4318)
			(layers "F.Cu" "F.Mask" "F.Paste")
			(net "GND")
		)
		(pad "CB65" smd circle
			(at 19.221958 3.309874)
			(size 0.4318 0.4318)
			(layers "F.Cu" "F.Mask" "F.Paste")
			(net "PVSA_CPU1")
		)
		(pad "CB67" smd circle
			(at 20.938998 3.309874)
			(size 0.4318 0.4318)
			(layers "F.Cu" "F.Mask" "F.Paste")
			(net "PVSA_CPU1")
		)
		(pad "CB69" smd circle
			(at 22.656038 3.309874)
			(size 0.4318 0.4318)
			(layers "F.Cu" "F.Mask" "F.Paste")
			(net "PVSA_CPU1")
		)
		(pad "CB71" smd circle
			(at 24.373078 3.309874)
			(size 0.4318 0.4318)
			(layers "F.Cu" "F.Mask" "F.Paste")
			(net "GND")
		)
		(pad "CB73" smd circle
			(at 26.090118 3.309874)
			(size 0.4318 0.4318)
			(layers "F.Cu" "F.Mask" "F.Paste")
			(net "PVCCIN_CPU1")
		)
		(pad "CB75" smd circle
			(at 27.806904 3.309874)
			(size 0.4318 0.4318)
			(layers "F.Cu" "F.Mask" "F.Paste")
			(net "PVCCIN_CPU1")
		)
		(pad "CB77" smd circle
			(at 29.523944 3.309874)
			(size 0.4318 0.4318)
			(layers "F.Cu" "F.Mask" "F.Paste")
			(net "PVCCIN_CPU1")
		)
		(pad "CB79" smd circle
			(at 31.240984 3.309874)
			(size 0.4318 0.4318)
			(layers "F.Cu" "F.Mask" "F.Paste")
			(net "PVCCIN_CPU1")
		)
		(pad "CB81" smd circle
			(at 32.958024 3.309874)
			(size 0.4318 0.4318)
			(layers "F.Cu" "F.Mask" "F.Paste")
			(net "PVCCIN_CPU1")
		)
		(pad "CB83" smd circle
			(at 34.675064 3.309874)
			(size 0.4318 0.4318)
			(layers "F.Cu" "F.Mask" "F.Paste")
			(net "PVCCIN_CPU1")
		)
		(pad "CC2" smd custom
			(at -36.392104 5.605272 90)
			(size 0.10795 0.10795)
			(layers "F.Cu" "F.Mask" "F.Paste")
			(net "TP_P3E_CPU1_PE2_RSR_TXN<8>")
			(options
				(clearance outline)
				(anchor circle)
			)
			(primitives
				(gr_poly
					(pts
						(arc
							(start 0.2159 -0.0381)
							(mid 0 -0.254)
							(end -0.2159 -0.0381)
						)
						(arc
							(start -0.2159 0.0381)
							(mid 0 0.254)
							(end 0.2159 0.0381)
						)
					)
					(width 0)
					(fill yes)
				)
			)
		)
		(pad "CC4" smd circle
			(at -34.675064 5.605272)
			(size 0.4318 0.4318)
			(layers "F.Cu" "F.Mask" "F.Paste")
			(net "GND")
		)
		(pad "CC6" smd circle
			(at -32.958024 5.605272)
			(size 0.4318 0.4318)
			(layers "F.Cu" "F.Mask" "F.Paste")
			(net "TP_CPU1_RSVD_111")
		)
		(pad "CC8" smd circle
			(at -31.240984 5.605272)
			(size 0.4318 0.4318)
			(layers "F.Cu" "F.Mask" "F.Paste")
			(net "TP_P3E_CPU1_PE2_RSR_RXP<7>")
		)
		(pad "CC10" smd circle
			(at -29.523944 5.605272)
			(size 0.4318 0.4318)
			(layers "F.Cu" "F.Mask" "F.Paste")
			(net "TP_CPU1_UPI2_RSVD_DM21")
		)
		(pad "CC12" smd circle
			(at -27.806904 5.605272)
			(size 0.4318 0.4318)
			(layers "F.Cu" "F.Mask" "F.Paste")
			(net "TP_CPU1_UPI2_RSVD_DT21")
		)
		(pad "CC14" smd circle
			(at -26.090118 5.605272)
			(size 0.4318 0.4318)
			(layers "F.Cu" "F.Mask" "F.Paste")
			(net "GND")
		)
		(pad "CC16" smd circle
			(at -24.373078 5.605272)
			(size 0.4318 0.4318)
			(layers "F.Cu" "F.Mask" "F.Paste")
			(net "GND")
		)
		(pad "CC18" smd circle
			(at -22.656038 5.605272)
			(size 0.4318 0.4318)
			(layers "F.Cu" "F.Mask" "F.Paste")
			(net "GND")
		)
		(pad "CC20" smd circle
			(at -20.938998 5.605272)
			(size 0.4318 0.4318)
			(layers "F.Cu" "F.Mask" "F.Paste")
			(net "PVCCMCP_CPU1")
		)
		(pad "CC22" smd circle
			(at -19.221958 5.605272)
			(size 0.4318 0.4318)
			(layers "F.Cu" "F.Mask" "F.Paste")
			(net "JTAG_MCP_CPU1_TDO")
		)
		(pad "CC24" smd circle
			(at -17.504918 5.605272)
			(size 0.4318 0.4318)
			(layers "F.Cu" "F.Mask" "F.Paste")
			(net "GND")
		)
		(pad "CC26" smd circle
			(at -15.787878 5.605272)
			(size 0.4318 0.4318)
			(layers "F.Cu" "F.Mask" "F.Paste")
			(net "PVCCIO_CPU1")
		)
		(pad "CC60" smd circle
			(at 14.929612 3.805428)
			(size 0.508 0.508)
			(layers "F.Cu" "F.Mask" "F.Paste")
			(net "PVCCIN_CPU1")
		)
		(pad "CC62" smd circle
			(at 16.646398 3.805428)
			(size 0.4318 0.4318)
			(layers "F.Cu" "F.Mask" "F.Paste")
			(net "PVCCIN_CPU1")
		)
		(pad "CC64" smd circle
			(at 18.363438 3.805428)
			(size 0.4318 0.4318)
			(layers "F.Cu" "F.Mask" "F.Paste")
			(net "GND")
		)
		(pad "CC66" smd circle
			(at 20.080478 3.805428)
			(size 0.4318 0.4318)
			(layers "F.Cu" "F.Mask" "F.Paste")
			(net "PVSA_CPU1")
		)
		(pad "CC68" smd circle
			(at 21.797518 3.805428)
			(size 0.4318 0.4318)
			(layers "F.Cu" "F.Mask" "F.Paste")
			(net "PVSA_CPU1")
		)
		(pad "CC70" smd circle
			(at 23.514558 3.805428)
			(size 0.4318 0.4318)
			(layers "F.Cu" "F.Mask" "F.Paste")
			(net "PVSA_CPU1")
		)
		(pad "CC72" smd circle
			(at 25.231598 3.805428)
			(size 0.4318 0.4318)
			(layers "F.Cu" "F.Mask" "F.Paste")
			(net "GND")
		)
		(pad "CC74" smd circle
			(at 26.948384 3.805428)
			(size 0.4318 0.4318)
			(layers "F.Cu" "F.Mask" "F.Paste")
			(net "GND")
		)
		(pad "CC76" smd circle
			(at 28.665424 3.805428)
			(size 0.4318 0.4318)
			(layers "F.Cu" "F.Mask" "F.Paste")
			(net "GND")
		)
		(pad "CC78" smd circle
			(at 30.382464 3.805428)
			(size 0.4318 0.4318)
			(layers "F.Cu" "F.Mask" "F.Paste")
			(net "GND")
		)
		(pad "CC80" smd circle
			(at 32.099504 3.805428)
			(size 0.4318 0.4318)
			(layers "F.Cu" "F.Mask" "F.Paste")
			(net "GND")
		)
		(pad "CC82" smd circle
			(at 33.816544 3.805428)
			(size 0.4318 0.4318)
			(layers "F.Cu" "F.Mask" "F.Paste")
			(net "GND")
		)
		(pad "CC84" smd custom
			(at 35.533584 3.805428 270)
			(size 0.10795 0.10795)
			(layers "F.Cu" "F.Mask" "F.Paste")
			(net "PVCCIN_CPU1")
			(options
				(clearance outline)
				(anchor circle)
			)
			(primitives
				(gr_poly
					(pts
						(arc
							(start 0.2159 -0.0381)
							(mid 0 -0.254)
							(end -0.2159 -0.0381)
						)
						(arc
							(start -0.2159 0.0381)
							(mid 0 0.254)
							(end 0.2159 0.0381)
						)
					)
					(width 0)
					(fill yes)
				)
			)
		)
		(pad "CD3" smd circle
			(at -35.533584 6.100572)
			(size 0.4318 0.4318)
			(layers "F.Cu" "F.Mask" "F.Paste")
			(net "TP_P3E_CPU1_PE2_RSR_TXP<8>")
		)
		(pad "CD5" smd circle
			(at -33.816544 6.100572)
			(size 0.4318 0.4318)
			(layers "F.Cu" "F.Mask" "F.Paste")
			(net "GND")
		)
		(pad "CD7" smd circle
			(at -32.099504 6.100572)
			(size 0.4318 0.4318)
			(layers "F.Cu" "F.Mask" "F.Paste")
			(net "TP_P3E_CPU1_PE2_RSR_RXP<6>")
		)
		(pad "CD9" smd circle
			(at -30.382464 6.100572)
			(size 0.4318 0.4318)
			(layers "F.Cu" "F.Mask" "F.Paste")
			(net "PVCCIO_CPU1")
		)
		(pad "CD11" smd circle
			(at -28.665424 6.100572)
			(size 0.4318 0.4318)
			(layers "F.Cu" "F.Mask" "F.Paste")
			(net "TP_CPU1_UPI2_RSVD_DK19")
		)
		(pad "CD13" smd circle
			(at -26.948384 6.100572)
			(size 0.4318 0.4318)
			(layers "F.Cu" "F.Mask" "F.Paste")
			(net "GND")
		)
		(pad "CD15" smd circle
			(at -25.231598 6.100572)
			(size 0.4318 0.4318)
			(layers "F.Cu" "F.Mask" "F.Paste")
			(net "GND")
		)
		(pad "CD17" smd circle
			(at -23.514558 6.100572)
			(size 0.4318 0.4318)
			(layers "F.Cu" "F.Mask" "F.Paste")
			(net "GND")
		)
		(pad "CD19" smd circle
			(at -21.797518 6.100572)
			(size 0.4318 0.4318)
			(layers "F.Cu" "F.Mask" "F.Paste")
			(net "PVCCMCP_CPU1")
		)
		(pad "CD21" smd circle
			(at -20.080478 6.100572)
			(size 0.4318 0.4318)
			(layers "F.Cu" "F.Mask" "F.Paste")
			(net "PVCCMCP_CPU1")
		)
		(pad "CD23" smd circle
			(at -18.363438 6.100572)
			(size 0.4318 0.4318)
			(layers "F.Cu" "F.Mask" "F.Paste")
			(net "JTAG_MCP_TRST_N")
		)
		(pad "CD25" smd circle
			(at -16.646398 6.100572)
			(size 0.4318 0.4318)
			(layers "F.Cu" "F.Mask" "F.Paste")
			(net "TP_CPU1_RSVD_108")
		)
		(pad "CD27" smd circle
			(at -14.929612 6.100572)
			(size 0.4318 0.4318)
			(layers "F.Cu" "F.Mask" "F.Paste")
			(net "PVCCIO_CPU1")
		)
		(pad "CD61" smd circle
			(at 15.787878 4.300474)
			(size 0.4318 0.4318)
			(layers "F.Cu" "F.Mask" "F.Paste")
			(net "PVCCIN_CPU1")
		)
		(pad "CD63" smd circle
			(at 17.504918 4.300474)
			(size 0.4318 0.4318)
			(layers "F.Cu" "F.Mask" "F.Paste")
			(net "GND")
		)
		(pad "CD65" smd circle
			(at 19.221958 4.300474)
			(size 0.4318 0.4318)
			(layers "F.Cu" "F.Mask" "F.Paste")
			(net "PVSA_CPU1")
		)
		(pad "CD67" smd circle
			(at 20.938998 4.300474)
			(size 0.4318 0.4318)
			(layers "F.Cu" "F.Mask" "F.Paste")
			(net "PVSA_CPU1")
		)
		(pad "CD69" smd circle
			(at 22.656038 4.300474)
			(size 0.4318 0.4318)
			(layers "F.Cu" "F.Mask" "F.Paste")
			(net "PVSA_CPU1")
		)
		(pad "CD71" smd circle
			(at 24.373078 4.300474)
			(size 0.4318 0.4318)
			(layers "F.Cu" "F.Mask" "F.Paste")
			(net "PVSA_CPU1")
		)
		(pad "CD73" smd circle
			(at 26.090118 4.300474)
			(size 0.4318 0.4318)
			(layers "F.Cu" "F.Mask" "F.Paste")
			(net "GND")
		)
		(pad "CD75" smd circle
			(at 27.806904 4.300474)
			(size 0.4318 0.4318)
			(layers "F.Cu" "F.Mask" "F.Paste")
			(net "GND")
		)
		(pad "CD77" smd circle
			(at 29.523944 4.300474)
			(size 0.4318 0.4318)
			(layers "F.Cu" "F.Mask" "F.Paste")
			(net "GND")
		)
		(pad "CD79" smd circle
			(at 31.240984 4.300474)
			(size 0.4318 0.4318)
			(layers "F.Cu" "F.Mask" "F.Paste")
			(net "GND")
		)
		(pad "CD81" smd circle
			(at 32.958024 4.300474)
			(size 0.4318 0.4318)
			(layers "F.Cu" "F.Mask" "F.Paste")
			(net "GND")
		)
		(pad "CD83" smd circle
			(at 34.675064 4.300474)
			(size 0.4318 0.4318)
			(layers "F.Cu" "F.Mask" "F.Paste")
			(net "PVCCIN_CPU1")
		)
		(pad "CD85" smd custom
			(at 36.392104 4.300474 270)
			(size 0.10795 0.10795)
			(layers "F.Cu" "F.Mask" "F.Paste")
			(net "PVCCIN_CPU1")
			(options
				(clearance outline)
				(anchor circle)
			)
			(primitives
				(gr_poly
					(pts
						(arc
							(start 0.2159 -0.0381)
							(mid 0 -0.254)
							(end -0.2159 -0.0381)
						)
						(arc
							(start -0.2159 0.0381)
							(mid 0 0.254)
							(end 0.2159 0.0381)
						)
					)
					(width 0)
					(fill yes)
				)
			)
		)
		(pad "CE2" smd custom
			(at -36.392104 6.596126 90)
			(size 0.10795 0.10795)
			(layers "F.Cu" "F.Mask" "F.Paste")
			(net "TP_P3E_CPU1_PE2_RSR_TXP<6>")
			(options
				(clearance outline)
				(anchor circle)
			)
			(primitives
				(gr_poly
					(pts
						(arc
							(start 0.2159 -0.0381)
							(mid 0 -0.254)
							(end -0.2159 -0.0381)
						)
						(arc
							(start -0.2159 0.0381)
							(mid 0 0.254)
							(end 0.2159 0.0381)
						)
					)
					(width 0)
					(fill yes)
				)
			)
		)
		(pad "CE4" smd circle
			(at -34.675064 6.596126)
			(size 0.4318 0.4318)
			(layers "F.Cu" "F.Mask" "F.Paste")
			(net "TP_P3E_CPU1_PE2_RSR_TXP<7>")
		)
		(pad "CE6" smd circle
			(at -32.958024 6.596126)
			(size 0.4318 0.4318)
			(layers "F.Cu" "F.Mask" "F.Paste")
			(net "TP_P3E_CPU1_PE2_RSR_RXN<6>")
		)
		(pad "CE8" smd circle
			(at -31.240984 6.596126)
			(size 0.4318 0.4318)
			(layers "F.Cu" "F.Mask" "F.Paste")
			(net "TP_P3E_CPU1_PE2_RSR_RXN<7>")
		)
		(pad "CE10" smd circle
			(at -29.523944 6.596126)
			(size 0.4318 0.4318)
			(layers "F.Cu" "F.Mask" "F.Paste")
			(net "GND")
		)
		(pad "CE12" smd circle
			(at -27.806904 6.596126)
			(size 0.4318 0.4318)
			(layers "F.Cu" "F.Mask" "F.Paste")
			(net "TP_CPU1_UPI2_RSVD_DL20")
		)
		(pad "CE14" smd circle
			(at -26.090118 6.596126)
			(size 0.4318 0.4318)
			(layers "F.Cu" "F.Mask" "F.Paste")
			(net "GND")
		)
		(pad "CE16" smd circle
			(at -24.373078 6.596126)
			(size 0.4318 0.4318)
			(layers "F.Cu" "F.Mask" "F.Paste")
			(net "GND")
		)
		(pad "CE18" smd circle
			(at -22.656038 6.596126)
			(size 0.4318 0.4318)
			(layers "F.Cu" "F.Mask" "F.Paste")
			(net "PVCCIO_CPU1")
		)
		(pad "CE20" smd circle
			(at -20.938998 6.596126)
			(size 0.4318 0.4318)
			(layers "F.Cu" "F.Mask" "F.Paste")
			(net "GND")
		)
		(pad "CE22" smd circle
			(at -19.221958 6.596126)
			(size 0.4318 0.4318)
			(layers "F.Cu" "F.Mask" "F.Paste")
			(net "PVCCMCP_CPU1")
		)
		(pad "CE24" smd circle
			(at -17.504918 6.596126)
			(size 0.4318 0.4318)
			(layers "F.Cu" "F.Mask" "F.Paste")
			(net "JTAG_MCP_TMS")
		)
		(pad "CE26" smd circle
			(at -15.787878 6.596126)
			(size 0.4318 0.4318)
			(layers "F.Cu" "F.Mask" "F.Paste")
			(net "GND")
		)
		(pad "CE60" smd circle
			(at 14.929612 4.796028)
			(size 0.508 0.508)
			(layers "F.Cu" "F.Mask" "F.Paste")
			(net "PVCCIN_CPU1")
		)
		(pad "CE62" smd circle
			(at 16.646398 4.796028)
			(size 0.4318 0.4318)
			(layers "F.Cu" "F.Mask" "F.Paste")
			(net "GND")
		)
		(pad "CE64" smd circle
			(at 18.363438 4.796028)
			(size 0.4318 0.4318)
			(layers "F.Cu" "F.Mask" "F.Paste")
			(net "PVSA_CPU1")
		)
		(pad "CE66" smd circle
			(at 20.080478 4.796028)
			(size 0.4318 0.4318)
			(layers "F.Cu" "F.Mask" "F.Paste")
			(net "PVSA_CPU1")
		)
		(pad "CE68" smd circle
			(at 21.797518 4.796028)
			(size 0.4318 0.4318)
			(layers "F.Cu" "F.Mask" "F.Paste")
			(net "PVSA_CPU1")
		)
		(pad "CE70" smd circle
			(at 23.514558 4.796028)
			(size 0.4318 0.4318)
			(layers "F.Cu" "F.Mask" "F.Paste")
			(net "GND")
		)
		(pad "CE72" smd circle
			(at 25.231598 4.796028)
			(size 0.4318 0.4318)
			(layers "F.Cu" "F.Mask" "F.Paste")
			(net "PVSA_CPU1")
		)
		(pad "CE74" smd circle
			(at 26.948384 4.796028)
			(size 0.4318 0.4318)
			(layers "F.Cu" "F.Mask" "F.Paste")
			(net "PVSA_CPU1")
		)
		(pad "CE76" smd circle
			(at 28.665424 4.796028)
			(size 0.4318 0.4318)
			(layers "F.Cu" "F.Mask" "F.Paste")
			(net "VSENSE_PVSA_CPU1_SKT_VSEN")
		)
		(pad "CE78" smd circle
			(at 30.382464 4.796028)
			(size 0.4318 0.4318)
			(layers "F.Cu" "F.Mask" "F.Paste")
			(net "TP_CPU1_RSVD_106")
		)
		(pad "CE80" smd circle
			(at 32.099504 4.796028)
			(size 0.4318 0.4318)
			(layers "F.Cu" "F.Mask" "F.Paste")
			(net "TP_CPU1_RSVD_105")
		)
		(pad "CE82" smd circle
			(at 33.816544 4.796028)
			(size 0.4318 0.4318)
			(layers "F.Cu" "F.Mask" "F.Paste")
			(net "GND")
		)
		(pad "CE84" smd circle
			(at 35.533584 4.796028)
			(size 0.4318 0.4318)
			(layers "F.Cu" "F.Mask" "F.Paste")
			(net "PVCCIN_CPU1")
		)
		(pad "CF3" smd circle
			(at -35.533584 7.091172)
			(size 0.4318 0.4318)
			(layers "F.Cu" "F.Mask" "F.Paste")
			(net "TP_P3E_CPU1_PE2_RSR_TXN<7>")
		)
		(pad "CF5" smd circle
			(at -33.816544 7.091172)
			(size 0.4318 0.4318)
			(layers "F.Cu" "F.Mask" "F.Paste")
			(net "PVCCIO_CPU1")
		)
		(pad "CF7" smd circle
			(at -32.099504 7.091172)
			(size 0.4318 0.4318)
			(layers "F.Cu" "F.Mask" "F.Paste")
			(net "TP_P3E_CPU1_PE2_RSR_RXP<5>")
		)
		(pad "CF9" smd circle
			(at -30.382464 7.091172)
			(size 0.4318 0.4318)
			(layers "F.Cu" "F.Mask" "F.Paste")
			(net "GND")
		)
		(pad "CF11" smd circle
			(at -28.665424 7.091172)
			(size 0.4318 0.4318)
			(layers "F.Cu" "F.Mask" "F.Paste")
			(net "TP_CPU1_UPI2_RSVD_DJ20")
		)
		(pad "CF13" smd circle
			(at -26.948384 7.091172)
			(size 0.4318 0.4318)
			(layers "F.Cu" "F.Mask" "F.Paste")
			(net "TP_CPU1_UPI2_RSVD_DH19")
		)
		(pad "CF15" smd circle
			(at -25.231598 7.091172)
			(size 0.4318 0.4318)
			(layers "F.Cu" "F.Mask" "F.Paste")
			(net "GND")
		)
		(pad "CF17" smd circle
			(at -23.514558 7.091172)
			(size 0.4318 0.4318)
			(layers "F.Cu" "F.Mask" "F.Paste")
			(net "GND")
		)
		(pad "CF19" smd circle
			(at -21.797518 7.091172)
			(size 0.4318 0.4318)
			(layers "F.Cu" "F.Mask" "F.Paste")
			(net "PVCCMCP_CPU1")
		)
		(pad "CF21" smd circle
			(at -20.080478 7.091172)
			(size 0.4318 0.4318)
			(layers "F.Cu" "F.Mask" "F.Paste")
			(net "PVCCMCP_CPU1")
		)
		(pad "CF23" smd circle
			(at -18.363438 7.091172)
			(size 0.4318 0.4318)
			(layers "F.Cu" "F.Mask" "F.Paste")
			(net "PVCCMCP_CPU1")
		)
		(pad "CF25" smd circle
			(at -16.646398 7.091172)
			(size 0.4318 0.4318)
			(layers "F.Cu" "F.Mask" "F.Paste")
			(net "RST_CD_CPU1_POR_N")
		)
		(pad "CF27" smd circle
			(at -14.929612 7.091172)
			(size 0.4318 0.4318)
			(layers "F.Cu" "F.Mask" "F.Paste")
			(net "PVCCIO_CPU1")
		)
		(pad "CF61" smd circle
			(at 15.787878 5.291074)
			(size 0.4318 0.4318)
			(layers "F.Cu" "F.Mask" "F.Paste")
			(net "PVCCIN_CPU1")
		)
		(pad "CF63" smd circle
			(at 17.504918 5.291074)
			(size 0.4318 0.4318)
			(layers "F.Cu" "F.Mask" "F.Paste")
			(net "GND")
		)
		(pad "CF65" smd circle
			(at 19.221958 5.291074)
			(size 0.4318 0.4318)
			(layers "F.Cu" "F.Mask" "F.Paste")
			(net "PVSA_CPU1")
		)
		(pad "CF67" smd circle
			(at 20.938998 5.291074)
			(size 0.4318 0.4318)
			(layers "F.Cu" "F.Mask" "F.Paste")
			(net "PVSA_CPU1")
		)
		(pad "CF69" smd circle
			(at 22.656038 5.291074)
			(size 0.4318 0.4318)
			(layers "F.Cu" "F.Mask" "F.Paste")
			(net "GND")
		)
		(pad "CF71" smd circle
			(at 24.373078 5.291074)
			(size 0.4318 0.4318)
			(layers "F.Cu" "F.Mask" "F.Paste")
			(net "GND")
		)
		(pad "CF73" smd circle
			(at 26.090118 5.291074)
			(size 0.4318 0.4318)
			(layers "F.Cu" "F.Mask" "F.Paste")
			(net "PVSA_CPU1")
		)
		(pad "CF75" smd circle
			(at 27.806904 5.291074)
			(size 0.4318 0.4318)
			(layers "F.Cu" "F.Mask" "F.Paste")
			(net "PVSA_CPU1")
		)
		(pad "CF77" smd circle
			(at 29.523944 5.291074)
			(size 0.4318 0.4318)
			(layers "F.Cu" "F.Mask" "F.Paste")
			(net "GND")
		)
		(pad "CF79" smd circle
			(at 31.240984 5.291074)
			(size 0.4318 0.4318)
			(layers "F.Cu" "F.Mask" "F.Paste")
			(net "TP_CPU1_RSVD_101")
		)
		(pad "CF81" smd circle
			(at 32.958024 5.291074)
			(size 0.4318 0.4318)
			(layers "F.Cu" "F.Mask" "F.Paste")
			(net "TP_CPU1_RSVD_100")
		)
		(pad "CF83" smd circle
			(at 34.675064 5.291074)
			(size 0.4318 0.4318)
			(layers "F.Cu" "F.Mask" "F.Paste")
			(net "GND")
		)
		(pad "CF85" smd custom
			(at 36.392104 5.291074 270)
			(size 0.10795 0.10795)
			(layers "F.Cu" "F.Mask" "F.Paste")
			(net "PVCCIN_CPU1")
			(options
				(clearance outline)
				(anchor circle)
			)
			(primitives
				(gr_poly
					(pts
						(arc
							(start 0.2159 -0.0381)
							(mid 0 -0.254)
							(end -0.2159 -0.0381)
						)
						(arc
							(start -0.2159 0.0381)
							(mid 0 0.254)
							(end 0.2159 0.0381)
						)
					)
					(width 0)
					(fill yes)
				)
			)
		)
		(pad "CG2" smd custom
			(at -36.392104 7.586726 90)
			(size 0.10795 0.10795)
			(layers "F.Cu" "F.Mask" "F.Paste")
			(net "TP_P3E_CPU1_PE2_RSR_TXN<6>")
			(options
				(clearance outline)
				(anchor circle)
			)
			(primitives
				(gr_poly
					(pts
						(arc
							(start 0.2159 -0.0381)
							(mid 0 -0.254)
							(end -0.2159 -0.0381)
						)
						(arc
							(start -0.2159 0.0381)
							(mid 0 0.254)
							(end 0.2159 0.0381)
						)
					)
					(width 0)
					(fill yes)
				)
			)
		)
		(pad "CG4" smd circle
			(at -34.675064 7.586726)
			(size 0.4318 0.4318)
			(layers "F.Cu" "F.Mask" "F.Paste")
			(net "TP_CPU1_DMI_TX_DN0")
		)
		(pad "CG6" smd circle
			(at -32.958024 7.586726)
			(size 0.4318 0.4318)
			(layers "F.Cu" "F.Mask" "F.Paste")
			(net "GND")
		)
		(pad "CG8" smd circle
			(at -31.240984 7.586726)
			(size 0.4318 0.4318)
			(layers "F.Cu" "F.Mask" "F.Paste")
			(net "TP_P3E_CPU1_PE2_RSR_RXN<5>")
		)
		(pad "CG10" smd circle
			(at -29.523944 7.586726)
			(size 0.4318 0.4318)
			(layers "F.Cu" "F.Mask" "F.Paste")
			(net "TP_CPU1_RSVD_99")
		)
		(pad "CG12" smd circle
			(at -27.806904 7.586726)
			(size 0.4318 0.4318)
			(layers "F.Cu" "F.Mask" "F.Paste")
			(net "TP_CPU1_UPI2_RSVD_DJ18")
		)
		(pad "CG14" smd circle
			(at -26.090118 7.586726)
			(size 0.4318 0.4318)
			(layers "F.Cu" "F.Mask" "F.Paste")
			(net "PVCCIO_CPU1")
		)
		(pad "CG16" smd circle
			(at -24.373078 7.586726)
			(size 0.4318 0.4318)
			(layers "F.Cu" "F.Mask" "F.Paste")
			(net "GND")
		)
		(pad "CG18" smd circle
			(at -22.656038 7.586726)
			(size 0.4318 0.4318)
			(layers "F.Cu" "F.Mask" "F.Paste")
			(net "GND")
		)
		(pad "CG20" smd circle
			(at -20.938998 7.586726)
			(size 0.4318 0.4318)
			(layers "F.Cu" "F.Mask" "F.Paste")
			(net "PVCCMCP_CPU1")
		)
		(pad "CG22" smd circle
			(at -19.221958 7.586726)
			(size 0.4318 0.4318)
			(layers "F.Cu" "F.Mask" "F.Paste")
			(net "GND")
		)
		(pad "CG24" smd circle
			(at -17.504918 7.586726)
			(size 0.4318 0.4318)
			(layers "F.Cu" "F.Mask" "F.Paste")
			(net "TP_CPU1_RSVD_97")
		)
		(pad "CG26" smd circle
			(at -15.787878 7.586726)
			(size 0.4318 0.4318)
			(layers "F.Cu" "F.Mask" "F.Paste")
			(net "PVCCMCP_CPU1")
		)
		(pad "CG60" smd circle
			(at 14.929612 5.786628)
			(size 0.508 0.508)
			(layers "F.Cu" "F.Mask" "F.Paste")
			(net "PVCCIN_CPU1")
		)
		(pad "CG62" smd circle
			(at 16.646398 5.786628)
			(size 0.4318 0.4318)
			(layers "F.Cu" "F.Mask" "F.Paste")
			(net "GND")
		)
		(pad "CG64" smd circle
			(at 18.363438 5.786628)
			(size 0.4318 0.4318)
			(layers "F.Cu" "F.Mask" "F.Paste")
			(net "PVSA_CPU1")
		)
		(pad "CG66" smd circle
			(at 20.080478 5.786628)
			(size 0.4318 0.4318)
			(layers "F.Cu" "F.Mask" "F.Paste")
			(net "PVSA_CPU1")
		)
		(pad "CG68" smd circle
			(at 21.797518 5.786628)
			(size 0.4318 0.4318)
			(layers "F.Cu" "F.Mask" "F.Paste")
			(net "GND")
		)
		(pad "CG70" smd circle
			(at 23.514558 5.786628)
			(size 0.4318 0.4318)
			(layers "F.Cu" "F.Mask" "F.Paste")
			(net "M_M_DQS_DP<17>")
		)
		(pad "CG72" smd circle
			(at 25.231598 5.786628)
			(size 0.4318 0.4318)
			(layers "F.Cu" "F.Mask" "F.Paste")
			(net "GND")
		)
		(pad "CG74" smd circle
			(at 26.948384 5.786628)
			(size 0.4318 0.4318)
			(layers "F.Cu" "F.Mask" "F.Paste")
			(net "PVSA_CPU1")
		)
		(pad "CG76" smd circle
			(at 28.665424 5.786628)
			(size 0.4318 0.4318)
			(layers "F.Cu" "F.Mask" "F.Paste")
			(net "VSENSE_PVSA_CPU1_SKT_VRTN")
		)
		(pad "CG78" smd circle
			(at 30.382464 5.786628)
			(size 0.4318 0.4318)
			(layers "F.Cu" "F.Mask" "F.Paste")
			(net "TP_CPU1_RSVD_95")
		)
		(pad "CG80" smd circle
			(at 32.099504 5.786628)
			(size 0.4318 0.4318)
			(layers "F.Cu" "F.Mask" "F.Paste")
			(net "GND")
		)
		(pad "CG82" smd circle
			(at 33.816544 5.786628)
			(size 0.4318 0.4318)
			(layers "F.Cu" "F.Mask" "F.Paste")
			(net "TP_CPU1_RSVD_94")
		)
		(pad "CG84" smd circle
			(at 35.533584 5.786628)
			(size 0.4318 0.4318)
			(layers "F.Cu" "F.Mask" "F.Paste")
			(net "PVCCIN_CPU1")
		)
		(pad "CH1" smd custom
			(at -37.250624 8.081772 90)
			(size 0.10795 0.10795)
			(layers "F.Cu" "F.Mask" "F.Paste")
			(net "GND")
			(options
				(clearance outline)
				(anchor circle)
			)
			(primitives
				(gr_poly
					(pts
						(arc
							(start 0.2159 -0.0381)
							(mid 0 -0.254)
							(end -0.2159 -0.0381)
						)
						(arc
							(start -0.2159 0.0381)
							(mid 0 0.254)
							(end 0.2159 0.0381)
						)
					)
					(width 0)
					(fill yes)
				)
			)
		)
		(pad "CH3" smd circle
			(at -35.533584 8.081772)
			(size 0.4318 0.4318)
			(layers "F.Cu" "F.Mask" "F.Paste")
			(net "GND")
		)
		(pad "CH5" smd circle
			(at -33.816544 8.081772)
			(size 0.4318 0.4318)
			(layers "F.Cu" "F.Mask" "F.Paste")
			(net "TP_CPU1_DMI_TX_DP0")
		)
		(pad "CH7" smd circle
			(at -32.099504 8.081772)
			(size 0.4318 0.4318)
			(layers "F.Cu" "F.Mask" "F.Paste")
			(net "TP_P3E_CPU1_PE2_RSR_RXP<4>")
		)
		(pad "CH9" smd circle
			(at -30.382464 8.081772)
			(size 0.4318 0.4318)
			(layers "F.Cu" "F.Mask" "F.Paste")
			(net "PVCCIO_CPU1")
		)
		(pad "CH11" smd circle
			(at -28.665424 8.081772)
			(size 0.4318 0.4318)
			(layers "F.Cu" "F.Mask" "F.Paste")
			(net "TP_CPU1_UPI2_RSVD_DG20")
		)
		(pad "CH13" smd circle
			(at -26.948384 8.081772)
			(size 0.4318 0.4318)
			(layers "F.Cu" "F.Mask" "F.Paste")
			(net "TP_CPU1_UPI2_RSVD_DH17")
		)
		(pad "CH15" smd circle
			(at -25.231598 8.081772)
			(size 0.4318 0.4318)
			(layers "F.Cu" "F.Mask" "F.Paste")
			(net "GND")
		)
		(pad "CH17" smd circle
			(at -23.514558 8.081772)
			(size 0.4318 0.4318)
			(layers "F.Cu" "F.Mask" "F.Paste")
			(net "GND")
		)
		(pad "CH19" smd circle
			(at -21.797518 8.081772)
			(size 0.4318 0.4318)
			(layers "F.Cu" "F.Mask" "F.Paste")
			(net "GND")
		)
		(pad "CH21" smd circle
			(at -20.080478 8.081772)
			(size 0.4318 0.4318)
			(layers "F.Cu" "F.Mask" "F.Paste")
			(net "PVCCMCP_CPU1")
		)
		(pad "CH23" smd circle
			(at -18.363438 8.081772)
			(size 0.4318 0.4318)
			(layers "F.Cu" "F.Mask" "F.Paste")
			(net "PVCCMCP_CPU1")
		)
		(pad "CH25" smd circle
			(at -16.646398 8.081772)
			(size 0.4318 0.4318)
			(layers "F.Cu" "F.Mask" "F.Paste")
			(net "TP_CPU1_RSVD_91")
		)
		(pad "CH27" smd circle
			(at -14.929612 8.081772)
			(size 0.4318 0.4318)
			(layers "F.Cu" "F.Mask" "F.Paste")
			(net "PVCCIO_CPU1")
		)
		(pad "CH61" smd circle
			(at 15.787878 6.281928)
			(size 0.4318 0.4318)
			(layers "F.Cu" "F.Mask" "F.Paste")
			(net "PVCCIN_CPU1")
		)
		(pad "CH63" smd circle
			(at 17.504918 6.281928)
			(size 0.4318 0.4318)
			(layers "F.Cu" "F.Mask" "F.Paste")
			(net "GND")
		)
		(pad "CH65" smd circle
			(at 19.221958 6.281928)
			(size 0.4318 0.4318)
			(layers "F.Cu" "F.Mask" "F.Paste")
			(net "PVSA_CPU1")
		)
		(pad "CH67" smd circle
			(at 20.938998 6.281928)
			(size 0.4318 0.4318)
			(layers "F.Cu" "F.Mask" "F.Paste")
			(net "GND")
		)
		(pad "CH69" smd circle
			(at 22.656038 6.281928)
			(size 0.4318 0.4318)
			(layers "F.Cu" "F.Mask" "F.Paste")
			(net "M_M_ECC<6>")
		)
		(pad "CH71" smd circle
			(at 24.373078 6.281928)
			(size 0.4318 0.4318)
			(layers "F.Cu" "F.Mask" "F.Paste")
			(net "M_M_ECC<0>")
		)
		(pad "CH73" smd circle
			(at 26.090118 6.281928)
			(size 0.4318 0.4318)
			(layers "F.Cu" "F.Mask" "F.Paste")
			(net "GND")
		)
		(pad "CH75" smd circle
			(at 27.806904 6.281928)
			(size 0.4318 0.4318)
			(layers "F.Cu" "F.Mask" "F.Paste")
			(net "PVSA_CPU1")
		)
		(pad "CH77" smd circle
			(at 29.523944 6.281928)
			(size 0.4318 0.4318)
			(layers "F.Cu" "F.Mask" "F.Paste")
			(net "TP_CPU1_RSVD_90")
		)
		(pad "CH79" smd circle
			(at 31.240984 6.281928)
			(size 0.4318 0.4318)
			(layers "F.Cu" "F.Mask" "F.Paste")
			(net "GND")
		)
		(pad "CH81" smd circle
			(at 32.958024 6.281928)
			(size 0.4318 0.4318)
			(layers "F.Cu" "F.Mask" "F.Paste")
			(net "GND")
		)
		(pad "CH83" smd circle
			(at 34.675064 6.281928)
			(size 0.4318 0.4318)
			(layers "F.Cu" "F.Mask" "F.Paste")
			(net "GND")
		)
		(pad "CH85" smd custom
			(at 36.392104 6.281928 270)
			(size 0.10795 0.10795)
			(layers "F.Cu" "F.Mask" "F.Paste")
			(net "PVCCIN_CPU1")
			(options
				(clearance outline)
				(anchor circle)
			)
			(primitives
				(gr_poly
					(pts
						(arc
							(start 0.2159 -0.0381)
							(mid 0 -0.254)
							(end -0.2159 -0.0381)
						)
						(arc
							(start -0.2159 0.0381)
							(mid 0 0.254)
							(end 0.2159 0.0381)
						)
					)
					(width 0)
					(fill yes)
				)
			)
		)
		(pad "CJ2" smd circle
			(at -36.392104 8.577326)
			(size 0.4318 0.4318)
			(layers "F.Cu" "F.Mask" "F.Paste")
			(net "GND")
		)
		(pad "CJ4" smd circle
			(at -34.675064 8.577326)
			(size 0.4318 0.4318)
			(layers "F.Cu" "F.Mask" "F.Paste")
			(net "TP_CPU1_DMI_TX_DN1")
		)
		(pad "CJ6" smd circle
			(at -32.958024 8.577326)
			(size 0.4318 0.4318)
			(layers "F.Cu" "F.Mask" "F.Paste")
			(net "GND")
		)
		(pad "CJ8" smd circle
			(at -31.240984 8.577326)
			(size 0.4318 0.4318)
			(layers "F.Cu" "F.Mask" "F.Paste")
			(net "GND")
		)
		(pad "CJ10" smd circle
			(at -29.523944 8.577326)
			(size 0.4318 0.4318)
			(layers "F.Cu" "F.Mask" "F.Paste")
			(net "GND")
		)
		(pad "CJ12" smd circle
			(at -27.806904 8.577326)
			(size 0.4318 0.4318)
			(layers "F.Cu" "F.Mask" "F.Paste")
			(net "GND")
		)
		(pad "CJ14" smd circle
			(at -26.090118 8.577326)
			(size 0.4318 0.4318)
			(layers "F.Cu" "F.Mask" "F.Paste")
			(net "TP_CPU1_UPI2_RSVD_DK17")
		)
		(pad "CJ16" smd circle
			(at -24.373078 8.577326)
			(size 0.4318 0.4318)
			(layers "F.Cu" "F.Mask" "F.Paste")
			(net "GND")
		)
		(pad "CJ18" smd circle
			(at -22.656038 8.577326)
			(size 0.4318 0.4318)
			(layers "F.Cu" "F.Mask" "F.Paste")
			(net "GND")
		)
		(pad "CJ20" smd circle
			(at -20.938998 8.577326)
			(size 0.4318 0.4318)
			(layers "F.Cu" "F.Mask" "F.Paste")
			(net "PVCCMCP_CPU1")
		)
		(pad "CJ22" smd circle
			(at -19.221958 8.577326)
			(size 0.4318 0.4318)
			(layers "F.Cu" "F.Mask" "F.Paste")
			(net "PVCCMCP_CPU1")
		)
		(pad "CJ24" smd circle
			(at -17.504918 8.577326)
			(size 0.4318 0.4318)
			(layers "F.Cu" "F.Mask" "F.Paste")
			(net "PVCCMCP_CPU1")
		)
		(pad "CJ26" smd circle
			(at -15.787878 8.577326)
			(size 0.4318 0.4318)
			(layers "F.Cu" "F.Mask" "F.Paste")
			(net "PVCCMCP_CPU1")
		)
		(pad "CJ28" smd circle
			(at -14.071092 8.577326)
			(size 0.4318 0.4318)
			(layers "F.Cu" "F.Mask" "F.Paste")
			(net "PVCCIO_CPU1")
		)
		(pad "CJ60" smd circle
			(at 14.929612 6.777228)
			(size 0.508 0.508)
			(layers "F.Cu" "F.Mask" "F.Paste")
			(net "PVCCIN_CPU1")
		)
		(pad "CJ62" smd circle
			(at 16.646398 6.777228)
			(size 0.4318 0.4318)
			(layers "F.Cu" "F.Mask" "F.Paste")
			(net "GND")
		)
		(pad "CJ64" smd circle
			(at 18.363438 6.777228)
			(size 0.4318 0.4318)
			(layers "F.Cu" "F.Mask" "F.Paste")
			(net "PVSA_CPU1")
		)
		(pad "CJ66" smd circle
			(at 20.080478 6.777228)
			(size 0.4318 0.4318)
			(layers "F.Cu" "F.Mask" "F.Paste")
			(net "PVSA_CPU1")
		)
		(pad "CJ68" smd circle
			(at 21.797518 6.777228)
			(size 0.4318 0.4318)
			(layers "F.Cu" "F.Mask" "F.Paste")
			(net "M_M_ECC<2>")
		)
		(pad "CJ70" smd circle
			(at 23.514558 6.777228)
			(size 0.4318 0.4318)
			(layers "F.Cu" "F.Mask" "F.Paste")
			(net "M_M_DQS_DN<17>")
		)
		(pad "CJ72" smd circle
			(at 25.231598 6.777228)
			(size 0.4318 0.4318)
			(layers "F.Cu" "F.Mask" "F.Paste")
			(net "M_M_ECC<4>")
		)
		(pad "CJ74" smd circle
			(at 26.948384 6.777228)
			(size 0.4318 0.4318)
			(layers "F.Cu" "F.Mask" "F.Paste")
			(net "GND")
		)
		(pad "CJ76" smd circle
			(at 28.665424 6.777228)
			(size 0.4318 0.4318)
			(layers "F.Cu" "F.Mask" "F.Paste")
			(net "GND")
		)
		(pad "CJ78" smd circle
			(at 30.382464 6.777228)
			(size 0.4318 0.4318)
			(layers "F.Cu" "F.Mask" "F.Paste")
			(net "GND")
		)
		(pad "CJ80" smd circle
			(at 32.099504 6.777228)
			(size 0.4318 0.4318)
			(layers "F.Cu" "F.Mask" "F.Paste")
			(net "M_L_DQ<5>")
		)
		(pad "CJ82" smd circle
			(at 33.816544 6.777228)
			(size 0.4318 0.4318)
			(layers "F.Cu" "F.Mask" "F.Paste")
			(net "GND")
		)
		(pad "CJ84" smd circle
			(at 35.533584 6.777228)
			(size 0.4318 0.4318)
			(layers "F.Cu" "F.Mask" "F.Paste")
			(net "GND")
		)
		(pad "CJ86" smd custom
			(at 37.250624 6.777228 270)
			(size 0.10795 0.10795)
			(layers "F.Cu" "F.Mask" "F.Paste")
			(net "GND")
			(options
				(clearance outline)
				(anchor circle)
			)
			(primitives
				(gr_poly
					(pts
						(arc
							(start 0.2159 -0.0381)
							(mid 0 -0.254)
							(end -0.2159 -0.0381)
						)
						(arc
							(start -0.2159 0.0381)
							(mid 0 0.254)
							(end 0.2159 0.0381)
						)
					)
					(width 0)
					(fill yes)
				)
			)
		)
		(pad "CK1" smd custom
			(at -37.250624 9.072372 90)
			(size 0.10795 0.10795)
			(layers "F.Cu" "F.Mask" "F.Paste")
			(net "TP_P3E_CPU1_PE2_RSR_TXP<4>")
			(options
				(clearance outline)
				(anchor circle)
			)
			(primitives
				(gr_poly
					(pts
						(arc
							(start 0.2159 -0.0381)
							(mid 0 -0.254)
							(end -0.2159 -0.0381)
						)
						(arc
							(start -0.2159 0.0381)
							(mid 0 0.254)
							(end 0.2159 0.0381)
						)
					)
					(width 0)
					(fill yes)
				)
			)
		)
		(pad "CK3" smd circle
			(at -35.533584 9.072372)
			(size 0.4318 0.4318)
			(layers "F.Cu" "F.Mask" "F.Paste")
			(net "TP_P3E_CPU1_PE2_RSR_TXP<5>")
		)
		(pad "CK5" smd circle
			(at -33.816544 9.072372)
			(size 0.4318 0.4318)
			(layers "F.Cu" "F.Mask" "F.Paste")
			(net "PVCCIO_CPU1")
		)
		(pad "CK7" smd circle
			(at -32.099504 9.072372)
			(size 0.4318 0.4318)
			(layers "F.Cu" "F.Mask" "F.Paste")
			(net "TP_P3E_CPU1_PE2_RSR_RXN<4>")
		)
		(pad "CK9" smd circle
			(at -30.382464 9.072372)
			(size 0.4318 0.4318)
			(layers "F.Cu" "F.Mask" "F.Paste")
			(net "TP_CPU1_DMI_RX_DN0")
		)
		(pad "CK11" smd circle
			(at -28.665424 9.072372)
			(size 0.4318 0.4318)
			(layers "F.Cu" "F.Mask" "F.Paste")
			(net "GND")
		)
		(pad "CK13" smd circle
			(at -26.948384 9.072372)
			(size 0.4318 0.4318)
			(layers "F.Cu" "F.Mask" "F.Paste")
			(net "TP_CPU1_UPI2_RSVD_DF17")
		)
		(pad "CK15" smd circle
			(at -25.231598 9.072372)
			(size 0.4318 0.4318)
			(layers "F.Cu" "F.Mask" "F.Paste")
			(net "GND")
		)
		(pad "CK17" smd circle
			(at -23.514558 9.072372)
			(size 0.4318 0.4318)
			(layers "F.Cu" "F.Mask" "F.Paste")
			(net "GND")
		)
		(pad "CK19" smd circle
			(at -21.797518 9.072372)
			(size 0.4318 0.4318)
			(layers "F.Cu" "F.Mask" "F.Paste")
			(net "TP_CPU1_RSVD_85")
		)
		(pad "CK21" smd circle
			(at -20.080478 9.072372)
			(size 0.4318 0.4318)
			(layers "F.Cu" "F.Mask" "F.Paste")
			(net "GND")
		)
		(pad "CK23" smd circle
			(at -18.363438 9.072372)
			(size 0.4318 0.4318)
			(layers "F.Cu" "F.Mask" "F.Paste")
			(net "PVCCMCP_CPU1")
		)
		(pad "CK25" smd circle
			(at -16.646398 9.072372)
			(size 0.4318 0.4318)
			(layers "F.Cu" "F.Mask" "F.Paste")
			(net "PVCCMCP_CPU1")
		)
		(pad "CK27" smd circle
			(at -14.929612 9.072372)
			(size 0.4318 0.4318)
			(layers "F.Cu" "F.Mask" "F.Paste")
			(net "GND")
		)
		(pad "CK29" smd circle
			(at -13.212572 9.072372)
			(size 0.4318 0.4318)
			(layers "F.Cu" "F.Mask" "F.Paste")
			(net "A_CPU1_UPI2_RBIAS")
		)
		(pad "CK59" smd circle
			(at 14.071092 7.272274)
			(size 0.508 0.508)
			(layers "F.Cu" "F.Mask" "F.Paste")
			(net "PVCCIN_CPU1")
		)
		(pad "CK61" smd circle
			(at 15.787878 7.272274)
			(size 0.4318 0.4318)
			(layers "F.Cu" "F.Mask" "F.Paste")
			(net "PVCCIN_CPU1")
		)
		(pad "CK63" smd circle
			(at 17.504918 7.272274)
			(size 0.4318 0.4318)
			(layers "F.Cu" "F.Mask" "F.Paste")
			(net "GND")
		)
		(pad "CK65" smd circle
			(at 19.221958 7.272274)
			(size 0.4318 0.4318)
			(layers "F.Cu" "F.Mask" "F.Paste")
			(net "GND")
		)
		(pad "CK67" smd circle
			(at 20.938998 7.272274)
			(size 0.4318 0.4318)
			(layers "F.Cu" "F.Mask" "F.Paste")
			(net "GND")
		)
		(pad "CK69" smd circle
			(at 22.656038 7.272274)
			(size 0.4318 0.4318)
			(layers "F.Cu" "F.Mask" "F.Paste")
			(net "GND")
		)
		(pad "CK71" smd circle
			(at 24.373078 7.272274)
			(size 0.4318 0.4318)
			(layers "F.Cu" "F.Mask" "F.Paste")
			(net "GND")
		)
		(pad "CK73" smd circle
			(at 26.090118 7.272274)
			(size 0.4318 0.4318)
			(layers "F.Cu" "F.Mask" "F.Paste")
			(net "GND")
		)
		(pad "CK75" smd circle
			(at 27.806904 7.272274)
			(size 0.4318 0.4318)
			(layers "F.Cu" "F.Mask" "F.Paste")
			(net "GND")
		)
		(pad "CK77" smd circle
			(at 29.523944 7.272274)
			(size 0.4318 0.4318)
			(layers "F.Cu" "F.Mask" "F.Paste")
			(net "TP_CPU1_RSVD_82")
		)
		(pad "CK79" smd circle
			(at 31.240984 7.272274)
			(size 0.4318 0.4318)
			(layers "F.Cu" "F.Mask" "F.Paste")
			(net "M_L_DQ<4>")
		)
		(pad "CK81" smd circle
			(at 32.958024 7.272274)
			(size 0.4318 0.4318)
			(layers "F.Cu" "F.Mask" "F.Paste")
			(net "M_L_DQ<1>")
		)
		(pad "CK83" smd circle
			(at 34.675064 7.272274)
			(size 0.4318 0.4318)
			(layers "F.Cu" "F.Mask" "F.Paste")
			(net "GND")
		)
		(pad "CK85" smd circle
			(at 36.392104 7.272274)
			(size 0.4318 0.4318)
			(layers "F.Cu" "F.Mask" "F.Paste")
			(net "GND")
		)
		(pad "CL2" smd circle
			(at -36.392104 9.567926)
			(size 0.4318 0.4318)
			(layers "F.Cu" "F.Mask" "F.Paste")
			(net "TP_P3E_CPU1_PE2_RSR_TXN<5>")
		)
		(pad "CL4" smd circle
			(at -34.675064 9.567926)
			(size 0.4318 0.4318)
			(layers "F.Cu" "F.Mask" "F.Paste")
			(net "TP_CPU1_DMI_TX_DP1")
		)
		(pad "CL6" smd circle
			(at -32.958024 9.567926)
			(size 0.4318 0.4318)
			(layers "F.Cu" "F.Mask" "F.Paste")
			(net "TP_P3E_CPU1_PE2_RSR_RXP<3>")
		)
		(pad "CL8" smd circle
			(at -31.240984 9.567926)
			(size 0.4318 0.4318)
			(layers "F.Cu" "F.Mask" "F.Paste")
			(net "GND")
		)
		(pad "CL10" smd circle
			(at -29.523944 9.567926)
			(size 0.4318 0.4318)
			(layers "F.Cu" "F.Mask" "F.Paste")
			(net "TP_CPU1_DMI_RX_DP0")
		)
		(pad "CL12" smd circle
			(at -27.806904 9.567926)
			(size 0.4318 0.4318)
			(layers "F.Cu" "F.Mask" "F.Paste")
			(net "PVCCIO_CPU1")
		)
		(pad "CL14" smd circle
			(at -26.090118 9.567926)
			(size 0.4318 0.4318)
			(layers "F.Cu" "F.Mask" "F.Paste")
			(net "GND")
		)
		(pad "CL16" smd circle
			(at -24.373078 9.567926)
			(size 0.4318 0.4318)
			(layers "F.Cu" "F.Mask" "F.Paste")
			(net "GND")
		)
		(pad "CL18" smd circle
			(at -22.656038 9.567926)
			(size 0.4318 0.4318)
			(layers "F.Cu" "F.Mask" "F.Paste")
			(net "GND")
		)
		(pad "CL20" smd circle
			(at -20.938998 9.567926)
			(size 0.4318 0.4318)
			(layers "F.Cu" "F.Mask" "F.Paste")
			(net "PVCCIO_CPU1")
		)
		(pad "CL22" smd circle
			(at -19.221958 9.567926)
			(size 0.4318 0.4318)
			(layers "F.Cu" "F.Mask" "F.Paste")
			(net "GND")
		)
		(pad "CL24" smd circle
			(at -17.504918 9.567926)
			(size 0.4318 0.4318)
			(layers "F.Cu" "F.Mask" "F.Paste")
			(net "PVCCMCP_CPU1")
		)
		(pad "CL26" smd circle
			(at -15.787878 9.567926)
			(size 0.4318 0.4318)
			(layers "F.Cu" "F.Mask" "F.Paste")
			(net "PVCCMCP_CPU1")
		)
		(pad "CL28" smd circle
			(at -14.071092 9.567926)
			(size 0.4318 0.4318)
			(layers "F.Cu" "F.Mask" "F.Paste")
			(net "A_CPU1_UPI2_RBIAS")
		)
		(pad "CL30" smd circle
			(at -12.354052 9.567926)
			(size 0.4318 0.4318)
			(layers "F.Cu" "F.Mask" "F.Paste")
			(net "A_CPU1_PE012_RBIAS")
		)
		(pad "CL58" smd circle
			(at 13.212572 7.767828)
			(size 0.508 0.508)
			(layers "F.Cu" "F.Mask" "F.Paste")
			(net "PVCCIN_CPU1")
		)
		(pad "CL60" smd circle
			(at 14.929612 7.767828)
			(size 0.4318 0.4318)
			(layers "F.Cu" "F.Mask" "F.Paste")
			(net "PVCCIN_CPU1")
		)
		(pad "CL62" smd circle
			(at 16.646398 7.767828)
			(size 0.4318 0.4318)
			(layers "F.Cu" "F.Mask" "F.Paste")
			(net "GND")
		)
		(pad "CL64" smd circle
			(at 18.363438 7.767828)
			(size 0.4318 0.4318)
			(layers "F.Cu" "F.Mask" "F.Paste")
			(net "GND")
		)
		(pad "CL66" smd circle
			(at 20.080478 7.767828)
			(size 0.4318 0.4318)
			(layers "F.Cu" "F.Mask" "F.Paste")
			(net "GND")
		)
		(pad "CL68" smd circle
			(at 21.797518 7.767828)
			(size 0.4318 0.4318)
			(layers "F.Cu" "F.Mask" "F.Paste")
			(net "M_M_ECC<3>")
		)
		(pad "CL70" smd circle
			(at 23.514558 7.767828)
			(size 0.4318 0.4318)
			(layers "F.Cu" "F.Mask" "F.Paste")
			(net "M_M_DQS_DP<8>")
		)
		(pad "CL72" smd circle
			(at 25.231598 7.767828)
			(size 0.4318 0.4318)
			(layers "F.Cu" "F.Mask" "F.Paste")
			(net "M_M_ECC<5>")
		)
		(pad "CL74" smd circle
			(at 26.948384 7.767828)
			(size 0.4318 0.4318)
			(layers "F.Cu" "F.Mask" "F.Paste")
			(net "GND")
		)
		(pad "CL76" smd circle
			(at 28.665424 7.767828)
			(size 0.4318 0.4318)
			(layers "F.Cu" "F.Mask" "F.Paste")
			(net "GND")
		)
		(pad "CL78" smd circle
			(at 30.382464 7.767828)
			(size 0.4318 0.4318)
			(layers "F.Cu" "F.Mask" "F.Paste")
			(net "GND")
		)
		(pad "CL80" smd circle
			(at 32.099504 7.767828)
			(size 0.4318 0.4318)
			(layers "F.Cu" "F.Mask" "F.Paste")
			(net "GND")
		)
		(pad "CL82" smd circle
			(at 33.816544 7.767828)
			(size 0.4318 0.4318)
			(layers "F.Cu" "F.Mask" "F.Paste")
			(net "M_L_DQS_DN<0>")
		)
		(pad "CL84" smd circle
			(at 35.533584 7.767828)
			(size 0.4318 0.4318)
			(layers "F.Cu" "F.Mask" "F.Paste")
			(net "M_K_DQ<4>")
		)
		(pad "CL86" smd custom
			(at 37.250624 7.767828 270)
			(size 0.10795 0.10795)
			(layers "F.Cu" "F.Mask" "F.Paste")
			(net "M_K_DQ<5>")
			(options
				(clearance outline)
				(anchor circle)
			)
			(primitives
				(gr_poly
					(pts
						(arc
							(start 0.2159 -0.0381)
							(mid 0 -0.254)
							(end -0.2159 -0.0381)
						)
						(arc
							(start -0.2159 0.0381)
							(mid 0 0.254)
							(end 0.2159 0.0381)
						)
					)
					(width 0)
					(fill yes)
				)
			)
		)
		(pad "CM1" smd custom
			(at -37.250624 10.062972 90)
			(size 0.10795 0.10795)
			(layers "F.Cu" "F.Mask" "F.Paste")
			(net "TP_P3E_CPU1_PE2_RSR_TXN<4>")
			(options
				(clearance outline)
				(anchor circle)
			)
			(primitives
				(gr_poly
					(pts
						(arc
							(start 0.2159 -0.0381)
							(mid 0 -0.254)
							(end -0.2159 -0.0381)
						)
						(arc
							(start -0.2159 0.0381)
							(mid 0 0.254)
							(end 0.2159 0.0381)
						)
					)
					(width 0)
					(fill yes)
				)
			)
		)
		(pad "CM3" smd circle
			(at -35.533584 10.062972)
			(size 0.4318 0.4318)
			(layers "F.Cu" "F.Mask" "F.Paste")
			(net "TP_CPU1_DMI_TX_DP2")
		)
		(pad "CM5" smd circle
			(at -33.816544 10.062972)
			(size 0.4318 0.4318)
			(layers "F.Cu" "F.Mask" "F.Paste")
			(net "GND")
		)
		(pad "CM7" smd circle
			(at -32.099504 10.062972)
			(size 0.4318 0.4318)
			(layers "F.Cu" "F.Mask" "F.Paste")
			(net "TP_P3E_CPU1_PE2_RSR_RXN<3>")
		)
		(pad "CM9" smd circle
			(at -30.382464 10.062972)
			(size 0.4318 0.4318)
			(layers "F.Cu" "F.Mask" "F.Paste")
			(net "TP_P3E_CPU1_PE2_RSR_RXP<1>")
		)
		(pad "CM11" smd circle
			(at -28.665424 10.062972)
			(size 0.4318 0.4318)
			(layers "F.Cu" "F.Mask" "F.Paste")
			(net "TP_CPU1_DMI_RX_DN1")
		)
		(pad "CM13" smd circle
			(at -26.948384 10.062972)
			(size 0.4318 0.4318)
			(layers "F.Cu" "F.Mask" "F.Paste")
			(net "TP_CPU1_UPI2_RSVD_DG18")
		)
		(pad "CM15" smd circle
			(at -25.231598 10.062972)
			(size 0.4318 0.4318)
			(layers "F.Cu" "F.Mask" "F.Paste")
			(net "PVCCIO_CPU1")
		)
		(pad "CM19" smd circle
			(at -21.797518 10.062972)
			(size 0.4318 0.4318)
			(layers "F.Cu" "F.Mask" "F.Paste")
			(net "GND")
		)
		(pad "CM21" smd circle
			(at -20.080478 10.062972)
			(size 0.4318 0.4318)
			(layers "F.Cu" "F.Mask" "F.Paste")
			(net "GND")
		)
		(pad "CM23" smd circle
			(at -18.363438 10.062972)
			(size 0.4318 0.4318)
			(layers "F.Cu" "F.Mask" "F.Paste")
			(net "PVCCMCP_CPU1")
		)
		(pad "CM25" smd circle
			(at -16.646398 10.062972)
			(size 0.4318 0.4318)
			(layers "F.Cu" "F.Mask" "F.Paste")
			(net "PVCCMCP_CPU1")
		)
		(pad "CM27" smd circle
			(at -14.929612 10.062972)
			(size 0.4318 0.4318)
			(layers "F.Cu" "F.Mask" "F.Paste")
			(net "GND")
		)
		(pad "CM29" smd circle
			(at -13.212572 10.062972)
			(size 0.4318 0.4318)
			(layers "F.Cu" "F.Mask" "F.Paste")
			(net "GND")
		)
		(pad "CM31" smd circle
			(at -11.495532 10.062972)
			(size 0.4318 0.4318)
			(layers "F.Cu" "F.Mask" "F.Paste")
			(net "GND")
		)
		(pad "CM57" smd circle
			(at 12.354052 8.262874)
			(size 0.508 0.508)
			(layers "F.Cu" "F.Mask" "F.Paste")
			(net "PVCCIN_CPU1")
		)
		(pad "CM59" smd circle
			(at 14.071092 8.262874)
			(size 0.4318 0.4318)
			(layers "F.Cu" "F.Mask" "F.Paste")
			(net "PVCCIN_CPU1")
		)
		(pad "CM61" smd circle
			(at 15.787878 8.262874)
			(size 0.4318 0.4318)
			(layers "F.Cu" "F.Mask" "F.Paste")
			(net "GND")
		)
		(pad "CM63" smd circle
			(at 17.504918 8.262874)
			(size 0.4318 0.4318)
			(layers "F.Cu" "F.Mask" "F.Paste")
			(net "GND")
		)
		(pad "CM65" smd circle
			(at 19.221958 8.262874)
			(size 0.4318 0.4318)
			(layers "F.Cu" "F.Mask" "F.Paste")
			(net "M_M_DQS_DP<12>")
		)
		(pad "CM67" smd circle
			(at 20.938998 8.262874)
			(size 0.4318 0.4318)
			(layers "F.Cu" "F.Mask" "F.Paste")
			(net "GND")
		)
		(pad "CM69" smd circle
			(at 22.656038 8.262874)
			(size 0.4318 0.4318)
			(layers "F.Cu" "F.Mask" "F.Paste")
			(net "M_M_ECC<7>")
		)
		(pad "CM71" smd circle
			(at 24.373078 8.262874)
			(size 0.4318 0.4318)
			(layers "F.Cu" "F.Mask" "F.Paste")
			(net "M_M_ECC<1>")
		)
		(pad "CM73" smd circle
			(at 26.090118 8.262874)
			(size 0.4318 0.4318)
			(layers "F.Cu" "F.Mask" "F.Paste")
			(net "GND")
		)
		(pad "CM75" smd circle
			(at 27.806904 8.262874)
			(size 0.4318 0.4318)
			(layers "F.Cu" "F.Mask" "F.Paste")
			(net "M_M_DQ<5>")
		)
		(pad "CM77" smd circle
			(at 29.523944 8.262874)
			(size 0.4318 0.4318)
			(layers "F.Cu" "F.Mask" "F.Paste")
			(net "GND")
		)
		(pad "CM79" smd circle
			(at 31.240984 8.262874)
			(size 0.4318 0.4318)
			(layers "F.Cu" "F.Mask" "F.Paste")
			(net "M_L_DQ<0>")
		)
		(pad "CM81" smd circle
			(at 32.958024 8.262874)
			(size 0.4318 0.4318)
			(layers "F.Cu" "F.Mask" "F.Paste")
			(net "M_L_DQS_DP<0>")
		)
		(pad "CM83" smd circle
			(at 34.675064 8.262874)
			(size 0.4318 0.4318)
			(layers "F.Cu" "F.Mask" "F.Paste")
			(net "GND")
		)
		(pad "CM85" smd circle
			(at 36.392104 8.262874)
			(size 0.4318 0.4318)
			(layers "F.Cu" "F.Mask" "F.Paste")
			(net "GND")
		)
		(pad "CN2" smd circle
			(at -36.392104 10.558526)
			(size 0.4318 0.4318)
			(layers "F.Cu" "F.Mask" "F.Paste")
			(net "GND")
		)
		(pad "CN4" smd circle
			(at -34.675064 10.558526)
			(size 0.4318 0.4318)
			(layers "F.Cu" "F.Mask" "F.Paste")
			(net "TP_CPU1_DMI_TX_DN2")
		)
		(pad "CN6" smd circle
			(at -32.958024 10.558526)
			(size 0.4318 0.4318)
			(layers "F.Cu" "F.Mask" "F.Paste")
			(net "PVCCIO_CPU1")
		)
		(pad "CN8" smd circle
			(at -31.240984 10.558526)
			(size 0.4318 0.4318)
			(layers "F.Cu" "F.Mask" "F.Paste")
			(net "TP_P3E_CPU1_PE2_RSR_RXP<2>")
		)
		(pad "CN10" smd circle
			(at -29.523944 10.558526)
			(size 0.4318 0.4318)
			(layers "F.Cu" "F.Mask" "F.Paste")
			(net "TP_CPU1_DMI_RX_DP1")
		)
		(pad "CN12" smd circle
			(at -27.806904 10.558526)
			(size 0.4318 0.4318)
			(layers "F.Cu" "F.Mask" "F.Paste")
			(net "GND")
		)
		(pad "CN14" smd circle
			(at -26.090118 10.558526)
			(size 0.4318 0.4318)
			(layers "F.Cu" "F.Mask" "F.Paste")
			(net "GND")
		)
		(pad "CN18" smd circle
			(at -22.656038 10.558526)
			(size 0.4318 0.4318)
			(layers "F.Cu" "F.Mask" "F.Paste")
			(net "GND")
		)
		(pad "CN20" smd circle
			(at -20.938998 10.558526)
			(size 0.4318 0.4318)
			(layers "F.Cu" "F.Mask" "F.Paste")
			(net "GND")
		)
		(pad "CN22" smd circle
			(at -19.221958 10.558526)
			(size 0.4318 0.4318)
			(layers "F.Cu" "F.Mask" "F.Paste")
			(net "TP_CPU1_KTI2_AMONV")
		)
		(pad "CN24" smd circle
			(at -17.504918 10.558526)
			(size 0.4318 0.4318)
			(layers "F.Cu" "F.Mask" "F.Paste")
			(net "PVCCMCP_CPU1")
		)
		(pad "CN26" smd circle
			(at -15.787878 10.558526)
			(size 0.4318 0.4318)
			(layers "F.Cu" "F.Mask" "F.Paste")
			(net "GND")
		)
		(pad "CN28" smd circle
			(at -14.071092 10.558526)
			(size 0.4318 0.4318)
			(layers "F.Cu" "F.Mask" "F.Paste")
			(net "PD_CPU1_MCP01_DMON")
		)
		(pad "CN30" smd circle
			(at -12.354052 10.558526)
			(size 0.4318 0.4318)
			(layers "F.Cu" "F.Mask" "F.Paste")
			(net "A_CPU1_PE012_RBIAS")
		)
		(pad "CN32" smd circle
			(at -10.637012 10.558526)
			(size 0.4318 0.4318)
			(layers "F.Cu" "F.Mask" "F.Paste")
			(net "GND")
		)
		(pad "CN56" smd circle
			(at 11.495532 8.758428)
			(size 0.508 0.508)
			(layers "F.Cu" "F.Mask" "F.Paste")
			(net "PVCCIN_CPU1")
		)
		(pad "CN58" smd circle
			(at 13.212572 8.758428)
			(size 0.4318 0.4318)
			(layers "F.Cu" "F.Mask" "F.Paste")
			(net "PVCCIN_CPU1")
		)
		(pad "CN60" smd circle
			(at 14.929612 8.758428)
			(size 0.4318 0.4318)
			(layers "F.Cu" "F.Mask" "F.Paste")
			(net "GND")
		)
		(pad "CN62" smd circle
			(at 16.646398 8.758428)
			(size 0.4318 0.4318)
			(layers "F.Cu" "F.Mask" "F.Paste")
			(net "GND")
		)
		(pad "CN64" smd circle
			(at 18.363438 8.758428)
			(size 0.4318 0.4318)
			(layers "F.Cu" "F.Mask" "F.Paste")
			(net "M_M_DQ<30>")
		)
		(pad "CN66" smd circle
			(at 20.080478 8.758428)
			(size 0.4318 0.4318)
			(layers "F.Cu" "F.Mask" "F.Paste")
			(net "M_M_DQ<24>")
		)
		(pad "CN68" smd circle
			(at 21.797518 8.758428)
			(size 0.4318 0.4318)
			(layers "F.Cu" "F.Mask" "F.Paste")
			(net "GND")
		)
		(pad "CN70" smd circle
			(at 23.514558 8.758428)
			(size 0.4318 0.4318)
			(layers "F.Cu" "F.Mask" "F.Paste")
			(net "M_M_DQS_DN<8>")
		)
		(pad "CN74" smd circle
			(at 26.948384 8.758428)
			(size 0.4318 0.4318)
			(layers "F.Cu" "F.Mask" "F.Paste")
			(net "M_M_DQ<4>")
		)
		(pad "CN76" smd circle
			(at 28.665424 8.758428)
			(size 0.4318 0.4318)
			(layers "F.Cu" "F.Mask" "F.Paste")
			(net "M_M_DQ<1>")
		)
		(pad "CN78" smd circle
			(at 30.382464 8.758428)
			(size 0.4318 0.4318)
			(layers "F.Cu" "F.Mask" "F.Paste")
			(net "GND")
		)
		(pad "CN80" smd circle
			(at 32.099504 8.758428)
			(size 0.4318 0.4318)
			(layers "F.Cu" "F.Mask" "F.Paste")
			(net "M_L_DQS_DN<9>")
		)
		(pad "CN82" smd circle
			(at 33.816544 8.758428)
			(size 0.4318 0.4318)
			(layers "F.Cu" "F.Mask" "F.Paste")
			(net "M_L_DQ<7>")
		)
		(pad "CN84" smd circle
			(at 35.533584 8.758428)
			(size 0.4318 0.4318)
			(layers "F.Cu" "F.Mask" "F.Paste")
			(net "M_K_DQ<0>")
		)
		(pad "CN86" smd custom
			(at 37.250624 8.758428 270)
			(size 0.10795 0.10795)
			(layers "F.Cu" "F.Mask" "F.Paste")
			(net "M_K_DQ<1>")
			(options
				(clearance outline)
				(anchor circle)
			)
			(primitives
				(gr_poly
					(pts
						(arc
							(start 0.2159 -0.0381)
							(mid 0 -0.254)
							(end -0.2159 -0.0381)
						)
						(arc
							(start -0.2159 0.0381)
							(mid 0 0.254)
							(end 0.2159 0.0381)
						)
					)
					(width 0)
					(fill yes)
				)
			)
		)
		(pad "CP1" smd custom
			(at -37.250624 11.053572 90)
			(size 0.10795 0.10795)
			(layers "F.Cu" "F.Mask" "F.Paste")
			(net "GND")
			(options
				(clearance outline)
				(anchor circle)
			)
			(primitives
				(gr_poly
					(pts
						(arc
							(start 0.2159 -0.0381)
							(mid 0 -0.254)
							(end -0.2159 -0.0381)
						)
						(arc
							(start -0.2159 0.0381)
							(mid 0 0.254)
							(end 0.2159 0.0381)
						)
					)
					(width 0)
					(fill yes)
				)
			)
		)
		(pad "CP3" smd circle
			(at -35.533584 11.053572)
			(size 0.4318 0.4318)
			(layers "F.Cu" "F.Mask" "F.Paste")
			(net "TP_P3E_CPU1_PE2_RSR_TXP<3>")
		)
		(pad "CP5" smd circle
			(at -33.816544 11.053572)
			(size 0.4318 0.4318)
			(layers "F.Cu" "F.Mask" "F.Paste")
			(net "TP_CPU1_DMI_TX_DN3")
		)
		(pad "CP7" smd circle
			(at -32.099504 11.053572)
			(size 0.4318 0.4318)
			(layers "F.Cu" "F.Mask" "F.Paste")
			(net "TP_P3E_CPU1_PE2_RSR_RXN<2>")
		)
		(pad "CP9" smd circle
			(at -30.382464 11.053572)
			(size 0.4318 0.4318)
			(layers "F.Cu" "F.Mask" "F.Paste")
			(net "TP_P3E_CPU1_PE2_RSR_RXN<1>")
		)
		(pad "CP11" smd circle
			(at -28.665424 11.053572)
			(size 0.4318 0.4318)
			(layers "F.Cu" "F.Mask" "F.Paste")
			(net "TP_CPU1_DMI_RX_DP2")
		)
		(pad "CP13" smd circle
			(at -26.948384 11.053572)
			(size 0.4318 0.4318)
			(layers "F.Cu" "F.Mask" "F.Paste")
			(net "PVCCIO_CPU1")
		)
		(pad "CP19" smd circle
			(at -21.797518 11.053572)
			(size 0.4318 0.4318)
			(layers "F.Cu" "F.Mask" "F.Paste")
			(net "GND")
		)
		(pad "CP21" smd circle
			(at -20.080478 11.053572)
			(size 0.4318 0.4318)
			(layers "F.Cu" "F.Mask" "F.Paste")
			(net "GND")
		)
		(pad "CP23" smd circle
			(at -18.363438 11.053572)
			(size 0.4318 0.4318)
			(layers "F.Cu" "F.Mask" "F.Paste")
			(net "PVCCMCP_CPU1")
		)
		(pad "CP25" smd circle
			(at -16.646398 11.053572)
			(size 0.4318 0.4318)
			(layers "F.Cu" "F.Mask" "F.Paste")
			(net "GND")
		)
		(pad "CP27" smd circle
			(at -14.929612 11.053572)
			(size 0.4318 0.4318)
			(layers "F.Cu" "F.Mask" "F.Paste")
			(net "CLK_100M_CPU1_BCLK1_DP")
		)
		(pad "CP29" smd circle
			(at -13.212572 11.053572)
			(size 0.4318 0.4318)
			(layers "F.Cu" "F.Mask" "F.Paste")
			(net "A_CPU1_PE3_RBIAS")
		)
		(pad "CP31" smd circle
			(at -11.495532 11.053572)
			(size 0.4318 0.4318)
			(layers "F.Cu" "F.Mask" "F.Paste")
			(net "TP_CPU1_RSVD_73")
		)
		(pad "CP33" smd circle
			(at -9.778492 11.053572)
			(size 0.4318 0.4318)
			(layers "F.Cu" "F.Mask" "F.Paste")
			(net "PVCCIN_CPU1")
		)
		(pad "CP55" smd circle
			(at 10.637012 9.253474)
			(size 0.508 0.508)
			(layers "F.Cu" "F.Mask" "F.Paste")
			(net "PVCCIN_CPU1")
		)
		(pad "CP57" smd circle
			(at 12.354052 9.253474)
			(size 0.4318 0.4318)
			(layers "F.Cu" "F.Mask" "F.Paste")
			(net "PVCCIN_CPU1")
		)
		(pad "CP59" smd circle
			(at 14.071092 9.253474)
			(size 0.4318 0.4318)
			(layers "F.Cu" "F.Mask" "F.Paste")
			(net "GND")
		)
		(pad "CP61" smd circle
			(at 15.787878 9.253474)
			(size 0.4318 0.4318)
			(layers "F.Cu" "F.Mask" "F.Paste")
			(net "M_K_CPU_VREF")
		)
		(pad "CP63" smd circle
			(at 17.504918 9.253474)
			(size 0.4318 0.4318)
			(layers "F.Cu" "F.Mask" "F.Paste")
			(net "M_M_DQ<26>")
		)
		(pad "CP65" smd circle
			(at 19.221958 9.253474)
			(size 0.4318 0.4318)
			(layers "F.Cu" "F.Mask" "F.Paste")
			(net "M_M_DQS_DN<12>")
		)
		(pad "CP67" smd circle
			(at 20.938998 9.253474)
			(size 0.4318 0.4318)
			(layers "F.Cu" "F.Mask" "F.Paste")
			(net "M_M_DQ<28>")
		)
		(pad "CP69" smd circle
			(at 22.656038 9.253474)
			(size 0.4318 0.4318)
			(layers "F.Cu" "F.Mask" "F.Paste")
			(net "GND")
		)
		(pad "CP73" smd circle
			(at 26.090118 9.253474)
			(size 0.4318 0.4318)
			(layers "F.Cu" "F.Mask" "F.Paste")
			(net "GND")
		)
		(pad "CP75" smd circle
			(at 27.806904 9.253474)
			(size 0.4318 0.4318)
			(layers "F.Cu" "F.Mask" "F.Paste")
			(net "GND")
		)
		(pad "CP77" smd circle
			(at 29.523944 9.253474)
			(size 0.4318 0.4318)
			(layers "F.Cu" "F.Mask" "F.Paste")
			(net "M_M_DQS_DN<0>")
		)
		(pad "CP79" smd circle
			(at 31.240984 9.253474)
			(size 0.4318 0.4318)
			(layers "F.Cu" "F.Mask" "F.Paste")
			(net "M_L_DQS_DP<9>")
		)
		(pad "CP81" smd circle
			(at 32.958024 9.253474)
			(size 0.4318 0.4318)
			(layers "F.Cu" "F.Mask" "F.Paste")
			(net "GND")
		)
		(pad "CP83" smd circle
			(at 34.675064 9.253474)
			(size 0.4318 0.4318)
			(layers "F.Cu" "F.Mask" "F.Paste")
			(net "GND")
		)
		(pad "CP85" smd circle
			(at 36.392104 9.253474)
			(size 0.4318 0.4318)
			(layers "F.Cu" "F.Mask" "F.Paste")
			(net "M_K_DQS_DP<9>")
		)
		(pad "CR2" smd circle
			(at -36.392104 11.549126)
			(size 0.4318 0.4318)
			(layers "F.Cu" "F.Mask" "F.Paste")
			(net "TP_P3E_CPU1_PE2_RSR_TXP<2>")
		)
		(pad "CR4" smd circle
			(at -34.675064 11.549126)
			(size 0.4318 0.4318)
			(layers "F.Cu" "F.Mask" "F.Paste")
			(net "TP_CPU1_DMI_TX_DP3")
		)
		(pad "CR6" smd circle
			(at -32.958024 11.549126)
			(size 0.4318 0.4318)
			(layers "F.Cu" "F.Mask" "F.Paste")
			(net "GND")
		)
		(pad "CR8" smd circle
			(at -31.240984 11.549126)
			(size 0.4318 0.4318)
			(layers "F.Cu" "F.Mask" "F.Paste")
			(net "TP_P3E_CPU1_PE2_RSR_RXP<0>")
		)
		(pad "CR10" smd circle
			(at -29.523944 11.549126)
			(size 0.4318 0.4318)
			(layers "F.Cu" "F.Mask" "F.Paste")
			(net "GND")
		)
		(pad "CR12" smd circle
			(at -27.806904 11.549126)
			(size 0.4318 0.4318)
			(layers "F.Cu" "F.Mask" "F.Paste")
			(net "TP_CPU1_DMI_RX_DN2")
		)
		(pad "CR14" smd circle
			(at -26.090118 11.549126)
			(size 0.4318 0.4318)
			(layers "F.Cu" "F.Mask" "F.Paste")
			(net "TP_CPU1_UPI2_RSVD_DE16")
		)
		(pad "CR18" smd circle
			(at -22.656038 11.549126)
			(size 0.4318 0.4318)
			(layers "F.Cu" "F.Mask" "F.Paste")
			(net "GND")
		)
		(pad "CR20" smd circle
			(at -20.938998 11.549126)
			(size 0.4318 0.4318)
			(layers "F.Cu" "F.Mask" "F.Paste")
			(net "GND")
		)
		(pad "CR22" smd circle
			(at -19.221958 11.549126)
			(size 0.4318 0.4318)
			(layers "F.Cu" "F.Mask" "F.Paste")
			(net "GND")
		)
		(pad "CR24" smd circle
			(at -17.504918 11.549126)
			(size 0.4318 0.4318)
			(layers "F.Cu" "F.Mask" "F.Paste")
			(net "GND")
		)
		(pad "CR26" smd circle
			(at -15.787878 11.549126)
			(size 0.4318 0.4318)
			(layers "F.Cu" "F.Mask" "F.Paste")
			(net "CLK_100M_CPU1_BCLK1_DN")
		)
		(pad "CR28" smd circle
			(at -14.071092 11.549126)
			(size 0.4318 0.4318)
			(layers "F.Cu" "F.Mask" "F.Paste")
			(net "PWRGD_CPU1_DRAMPWROK_KLM_G")
		)
		(pad "CR30" smd circle
			(at -12.354052 11.549126)
			(size 0.4318 0.4318)
			(layers "F.Cu" "F.Mask" "F.Paste")
			(net "A_CPU1_PE3_RBIAS")
		)
		(pad "CR32" smd circle
			(at -10.637012 11.549126)
			(size 0.4318 0.4318)
			(layers "F.Cu" "F.Mask" "F.Paste")
			(net "GND")
		)
		(pad "CR34" smd circle
			(at -8.919972 11.549126)
			(size 0.4318 0.4318)
			(layers "F.Cu" "F.Mask" "F.Paste")
			(net "PVCCIN_CPU1")
		)
		(pad "CR54" smd circle
			(at 9.778492 9.749028)
			(size 0.508 0.508)
			(layers "F.Cu" "F.Mask" "F.Paste")
			(net "PVCCIN_CPU1")
		)
		(pad "CR56" smd circle
			(at 11.495532 9.749028)
			(size 0.4318 0.4318)
			(layers "F.Cu" "F.Mask" "F.Paste")
			(net "PVCCIN_CPU1")
		)
		(pad "CR58" smd circle
			(at 13.212572 9.749028)
			(size 0.4318 0.4318)
			(layers "F.Cu" "F.Mask" "F.Paste")
			(net "GND")
		)
		(pad "CR60" smd circle
			(at 14.929612 9.749028)
			(size 0.4318 0.4318)
			(layers "F.Cu" "F.Mask" "F.Paste")
			(net "TP_CPU1_RSVD_72")
		)
		(pad "CR62" smd circle
			(at 16.646398 9.749028)
			(size 0.4318 0.4318)
			(layers "F.Cu" "F.Mask" "F.Paste")
			(net "GND")
		)
		(pad "CR64" smd circle
			(at 18.363438 9.749028)
			(size 0.4318 0.4318)
			(layers "F.Cu" "F.Mask" "F.Paste")
			(net "GND")
		)
		(pad "CR66" smd circle
			(at 20.080478 9.749028)
			(size 0.4318 0.4318)
			(layers "F.Cu" "F.Mask" "F.Paste")
			(net "GND")
		)
		(pad "CR68" smd circle
			(at 21.797518 9.749028)
			(size 0.4318 0.4318)
			(layers "F.Cu" "F.Mask" "F.Paste")
			(net "GND")
		)
		(pad "CR74" smd circle
			(at 26.948384 9.749028)
			(size 0.4318 0.4318)
			(layers "F.Cu" "F.Mask" "F.Paste")
			(net "M_M_DQ<0>")
		)
		(pad "CR76" smd circle
			(at 28.665424 9.749028)
			(size 0.4318 0.4318)
			(layers "F.Cu" "F.Mask" "F.Paste")
			(net "M_M_DQS_DP<0>")
		)
		(pad "CR78" smd circle
			(at 30.382464 9.749028)
			(size 0.4318 0.4318)
			(layers "F.Cu" "F.Mask" "F.Paste")
			(net "GND")
		)
		(pad "CR80" smd circle
			(at 32.099504 9.749028)
			(size 0.4318 0.4318)
			(layers "F.Cu" "F.Mask" "F.Paste")
			(net "M_L_DQ<6>")
		)
		(pad "CR82" smd circle
			(at 33.816544 9.749028)
			(size 0.4318 0.4318)
			(layers "F.Cu" "F.Mask" "F.Paste")
			(net "M_L_DQ<3>")
		)
		(pad "CR84" smd circle
			(at 35.533584 9.749028)
			(size 0.4318 0.4318)
			(layers "F.Cu" "F.Mask" "F.Paste")
			(net "M_K_DQS_DN<9>")
		)
		(pad "CR86" smd custom
			(at 37.250624 9.749028 270)
			(size 0.10795 0.10795)
			(layers "F.Cu" "F.Mask" "F.Paste")
			(net "GND")
			(options
				(clearance outline)
				(anchor circle)
			)
			(primitives
				(gr_poly
					(pts
						(arc
							(start 0.2159 -0.0381)
							(mid 0 -0.254)
							(end -0.2159 -0.0381)
						)
						(arc
							(start -0.2159 0.0381)
							(mid 0 0.254)
							(end 0.2159 0.0381)
						)
					)
					(width 0)
					(fill yes)
				)
			)
		)
		(pad "CT1" smd custom
			(at -37.250624 12.044172 90)
			(size 0.10795 0.10795)
			(layers "F.Cu" "F.Mask" "F.Paste")
			(net "TP_P3E_CPU1_PE2_RSR_TXN<2>")
			(options
				(clearance outline)
				(anchor circle)
			)
			(primitives
				(gr_poly
					(pts
						(arc
							(start 0.2159 -0.0381)
							(mid 0 -0.254)
							(end -0.2159 -0.0381)
						)
						(arc
							(start -0.2159 0.0381)
							(mid 0 0.254)
							(end 0.2159 0.0381)
						)
					)
					(width 0)
					(fill yes)
				)
			)
		)
		(pad "CT3" smd circle
			(at -35.533584 12.044172)
			(size 0.4318 0.4318)
			(layers "F.Cu" "F.Mask" "F.Paste")
			(net "TP_P3E_CPU1_PE2_RSR_TXN<3>")
		)
		(pad "CT5" smd circle
			(at -33.816544 12.044172)
			(size 0.4318 0.4318)
			(layers "F.Cu" "F.Mask" "F.Paste")
			(net "TP_CPU1_RSVD_70")
		)
		(pad "CT7" smd circle
			(at -32.099504 12.044172)
			(size 0.4318 0.4318)
			(layers "F.Cu" "F.Mask" "F.Paste")
			(net "GND")
		)
		(pad "CT9" smd circle
			(at -30.382464 12.044172)
			(size 0.4318 0.4318)
			(layers "F.Cu" "F.Mask" "F.Paste")
			(net "TP_P3E_CPU1_PE2_RSR_RXN<0>")
		)
		(pad "CT11" smd circle
			(at -28.665424 12.044172)
			(size 0.4318 0.4318)
			(layers "F.Cu" "F.Mask" "F.Paste")
			(net "TP_CPU1_DMI_RX_DN3")
		)
		(pad "CT13" smd circle
			(at -26.948384 12.044172)
			(size 0.4318 0.4318)
			(layers "F.Cu" "F.Mask" "F.Paste")
			(net "GND")
		)
		(pad "CT19" smd circle
			(at -21.797518 12.044172)
			(size 0.4318 0.4318)
			(layers "F.Cu" "F.Mask" "F.Paste")
			(net "GND")
		)
		(pad "CT21" smd circle
			(at -20.080478 12.044172)
			(size 0.4318 0.4318)
			(layers "F.Cu" "F.Mask" "F.Paste")
			(net "GND")
		)
		(pad "CT23" smd circle
			(at -18.363438 12.044172)
			(size 0.4318 0.4318)
			(layers "F.Cu" "F.Mask" "F.Paste")
			(net "PVCCMCP_CPU1")
		)
		(pad "CT25" smd circle
			(at -16.646398 12.044172)
			(size 0.4318 0.4318)
			(layers "F.Cu" "F.Mask" "F.Paste")
			(net "CLK_100M_CPU1_BCLK2_DN")
		)
		(pad "CT27" smd circle
			(at -14.929612 12.044172)
			(size 0.4318 0.4318)
			(layers "F.Cu" "F.Mask" "F.Paste")
			(net "GND")
		)
		(pad "CT29" smd circle
			(at -13.212572 12.044172)
			(size 0.4318 0.4318)
			(layers "F.Cu" "F.Mask" "F.Paste")
			(net "GND")
		)
		(pad "CT31" smd circle
			(at -11.495532 12.044172)
			(size 0.4318 0.4318)
			(layers "F.Cu" "F.Mask" "F.Paste")
			(net "A_CPU1_MCP01_RBIAS")
		)
		(pad "CT33" smd circle
			(at -9.778492 12.044172)
			(size 0.4318 0.4318)
			(layers "F.Cu" "F.Mask" "F.Paste")
			(net "GND")
		)
		(pad "CT35" smd circle
			(at -8.061452 12.044172)
			(size 0.4318 0.4318)
			(layers "F.Cu" "F.Mask" "F.Paste")
			(net "GND")
		)
		(pad "CT37" smd circle
			(at -6.344412 12.044172)
			(size 0.4318 0.4318)
			(layers "F.Cu" "F.Mask" "F.Paste")
			(net "PVCCIN_CPU1")
		)
		(pad "CT39" smd circle
			(at -4.627626 12.044172)
			(size 0.4318 0.4318)
			(layers "F.Cu" "F.Mask" "F.Paste")
			(net "PVCCIN_CPU1")
		)
		(pad "CT41" smd circle
			(at -2.910586 12.044172)
			(size 0.4318 0.4318)
			(layers "F.Cu" "F.Mask" "F.Paste")
			(net "PVCCIN_CPU1")
		)
		(pad "CT53" smd circle
			(at 8.919972 10.244074)
			(size 0.508 0.508)
			(layers "F.Cu" "F.Mask" "F.Paste")
			(net "PVCCIN_CPU1")
		)
		(pad "CT55" smd circle
			(at 10.637012 10.244074)
			(size 0.4318 0.4318)
			(layers "F.Cu" "F.Mask" "F.Paste")
			(net "PVCCIN_CPU1")
		)
		(pad "CT57" smd circle
			(at 12.354052 10.244074)
			(size 0.4318 0.4318)
			(layers "F.Cu" "F.Mask" "F.Paste")
			(net "GND")
		)
		(pad "CT59" smd circle
			(at 14.071092 10.244074)
			(size 0.4318 0.4318)
			(layers "F.Cu" "F.Mask" "F.Paste")
			(net "SMB_PIROM_CPU1_SCL")
		)
		(pad "CT61" smd circle
			(at 15.787878 10.244074)
			(size 0.4318 0.4318)
			(layers "F.Cu" "F.Mask" "F.Paste")
			(net "M_L_CPU_VREF")
		)
		(pad "CT63" smd circle
			(at 17.504918 10.244074)
			(size 0.4318 0.4318)
			(layers "F.Cu" "F.Mask" "F.Paste")
			(net "M_M_DQ<27>")
		)
		(pad "CT65" smd circle
			(at 19.221958 10.244074)
			(size 0.4318 0.4318)
			(layers "F.Cu" "F.Mask" "F.Paste")
			(net "M_M_DQS_DP<3>")
		)
		(pad "CT67" smd circle
			(at 20.938998 10.244074)
			(size 0.4318 0.4318)
			(layers "F.Cu" "F.Mask" "F.Paste")
			(net "M_M_DQ<29>")
		)
		(pad "CT69" smd circle
			(at 22.656038 10.244074)
			(size 0.4318 0.4318)
			(layers "F.Cu" "F.Mask" "F.Paste")
			(net "TP_CPU1_RSVD_69")
		)
		(pad "CT73" smd circle
			(at 26.090118 10.244074)
			(size 0.4318 0.4318)
			(layers "F.Cu" "F.Mask" "F.Paste")
			(net "GND")
		)
		(pad "CT75" smd circle
			(at 27.806904 10.244074)
			(size 0.4318 0.4318)
			(layers "F.Cu" "F.Mask" "F.Paste")
			(net "M_M_DQS_DN<9>")
		)
		(pad "CT77" smd circle
			(at 29.523944 10.244074)
			(size 0.4318 0.4318)
			(layers "F.Cu" "F.Mask" "F.Paste")
			(net "M_M_DQ<7>")
		)
		(pad "CT79" smd circle
			(at 31.240984 10.244074)
			(size 0.4318 0.4318)
			(layers "F.Cu" "F.Mask" "F.Paste")
			(net "GND")
		)
		(pad "CT81" smd circle
			(at 32.958024 10.244074)
			(size 0.4318 0.4318)
			(layers "F.Cu" "F.Mask" "F.Paste")
			(net "M_L_DQ<2>")
		)
		(pad "CT83" smd circle
			(at 34.675064 10.244074)
			(size 0.4318 0.4318)
			(layers "F.Cu" "F.Mask" "F.Paste")
			(net "GND")
		)
		(pad "CT85" smd circle
			(at 36.392104 10.244074)
			(size 0.4318 0.4318)
			(layers "F.Cu" "F.Mask" "F.Paste")
			(net "GND")
		)
		(pad "CU2" smd circle
			(at -36.392104 12.539726)
			(size 0.4318 0.4318)
			(layers "F.Cu" "F.Mask" "F.Paste")
			(net "TP_P3E_CPU1_PE2_RSR_TXP<1>")
		)
		(pad "CU4" smd circle
			(at -34.675064 12.539726)
			(size 0.4318 0.4318)
			(layers "F.Cu" "F.Mask" "F.Paste")
			(net "GND")
		)
		(pad "CU6" smd circle
			(at -32.958024 12.539726)
			(size 0.4318 0.4318)
			(layers "F.Cu" "F.Mask" "F.Paste")
			(net "TP_CPU1_RSVD_67")
		)
		(pad "CU8" smd circle
			(at -31.240984 12.539726)
			(size 0.4318 0.4318)
			(layers "F.Cu" "F.Mask" "F.Paste")
			(net "TP_P3E_CPU1_PE1_MP_RXP<0>")
		)
		(pad "CU10" smd circle
			(at -29.523944 12.539726)
			(size 0.4318 0.4318)
			(layers "F.Cu" "F.Mask" "F.Paste")
			(net "P3E_CPU1_PE3_MP_RXP<15>")
		)
		(pad "CU12" smd circle
			(at -27.806904 12.539726)
			(size 0.4318 0.4318)
			(layers "F.Cu" "F.Mask" "F.Paste")
			(net "PVCCIO_CPU1")
		)
		(pad "CU14" smd circle
			(at -26.090118 12.539726)
			(size 0.4318 0.4318)
			(layers "F.Cu" "F.Mask" "F.Paste")
			(net "TP_CPU1_UPI2_RSVD_DD17")
		)
		(pad "CU18" smd circle
			(at -22.656038 12.539726)
			(size 0.4318 0.4318)
			(layers "F.Cu" "F.Mask" "F.Paste")
			(net "PVCCIO_CPU1")
		)
		(pad "CU20" smd circle
			(at -20.938998 12.539726)
			(size 0.4318 0.4318)
			(layers "F.Cu" "F.Mask" "F.Paste")
			(net "GND")
		)
		(pad "CU22" smd circle
			(at -19.221958 12.539726)
			(size 0.4318 0.4318)
			(layers "F.Cu" "F.Mask" "F.Paste")
			(net "GND")
		)
		(pad "CU24" smd circle
			(at -17.504918 12.539726)
			(size 0.4318 0.4318)
			(layers "F.Cu" "F.Mask" "F.Paste")
			(net "PVCCMCP_CPU1")
		)
		(pad "CU26" smd circle
			(at -15.787878 12.539726)
			(size 0.4318 0.4318)
			(layers "F.Cu" "F.Mask" "F.Paste")
			(net "CLK_100M_CPU1_BCLK2_DP")
		)
		(pad "CU28" smd circle
			(at -14.071092 12.539726)
			(size 0.4318 0.4318)
			(layers "F.Cu" "F.Mask" "F.Paste")
			(net "GND")
		)
		(pad "CU30" smd circle
			(at -12.354052 12.539726)
			(size 0.4318 0.4318)
			(layers "F.Cu" "F.Mask" "F.Paste")
			(net "GND")
		)
		(pad "CU32" smd circle
			(at -10.637012 12.539726)
			(size 0.4318 0.4318)
			(layers "F.Cu" "F.Mask" "F.Paste")
			(net "A_CPU1_MCP01_RBIAS")
		)
		(pad "CU34" smd circle
			(at -8.919972 12.539726)
			(size 0.4318 0.4318)
			(layers "F.Cu" "F.Mask" "F.Paste")
			(net "GND")
		)
		(pad "CU36" smd circle
			(at -7.202932 12.539726)
			(size 0.4318 0.4318)
			(layers "F.Cu" "F.Mask" "F.Paste")
			(net "GND")
		)
		(pad "CU38" smd circle
			(at -5.485892 12.539726)
			(size 0.4318 0.4318)
			(layers "F.Cu" "F.Mask" "F.Paste")
			(net "PVCCIN_CPU1")
		)
		(pad "CU40" smd circle
			(at -3.769106 12.539726)
			(size 0.4318 0.4318)
			(layers "F.Cu" "F.Mask" "F.Paste")
			(net "PVCCIN_CPU1")
		)
		(pad "CU42" smd circle
			(at -2.052066 12.539726)
			(size 0.4318 0.4318)
			(layers "F.Cu" "F.Mask" "F.Paste")
			(net "PVCCIN_CPU1")
		)
		(pad "CU52" smd circle
			(at 8.061452 10.739628)
			(size 0.508 0.508)
			(layers "F.Cu" "F.Mask" "F.Paste")
			(net "PVCCIN_CPU1")
		)
		(pad "CU54" smd circle
			(at 9.778492 10.739628)
			(size 0.4318 0.4318)
			(layers "F.Cu" "F.Mask" "F.Paste")
			(net "PVCCIN_CPU1")
		)
		(pad "CU56" smd circle
			(at 11.495532 10.739628)
			(size 0.4318 0.4318)
			(layers "F.Cu" "F.Mask" "F.Paste")
			(net "GND")
		)
		(pad "CU58" smd circle
			(at 13.212572 10.739628)
			(size 0.4318 0.4318)
			(layers "F.Cu" "F.Mask" "F.Paste")
			(net "PU_PIROM_CPU1_ADDR0")
		)
		(pad "CU60" smd circle
			(at 14.929612 10.739628)
			(size 0.4318 0.4318)
			(layers "F.Cu" "F.Mask" "F.Paste")
			(net "TP_CPU1_RSVD_66")
		)
		(pad "CU62" smd circle
			(at 16.646398 10.739628)
			(size 0.4318 0.4318)
			(layers "F.Cu" "F.Mask" "F.Paste")
			(net "GND")
		)
		(pad "CU64" smd circle
			(at 18.363438 10.739628)
			(size 0.4318 0.4318)
			(layers "F.Cu" "F.Mask" "F.Paste")
			(net "M_M_DQ<31>")
		)
		(pad "CU66" smd circle
			(at 20.080478 10.739628)
			(size 0.4318 0.4318)
			(layers "F.Cu" "F.Mask" "F.Paste")
			(net "M_M_DQ<25>")
		)
		(pad "CU68" smd circle
			(at 21.797518 10.739628)
			(size 0.4318 0.4318)
			(layers "F.Cu" "F.Mask" "F.Paste")
			(net "GND")
		)
		(pad "CU74" smd circle
			(at 26.948384 10.739628)
			(size 0.4318 0.4318)
			(layers "F.Cu" "F.Mask" "F.Paste")
			(net "M_M_DQS_DP<9>")
		)
		(pad "CU76" smd circle
			(at 28.665424 10.739628)
			(size 0.4318 0.4318)
			(layers "F.Cu" "F.Mask" "F.Paste")
			(net "GND")
		)
		(pad "CU78" smd circle
			(at 30.382464 10.739628)
			(size 0.4318 0.4318)
			(layers "F.Cu" "F.Mask" "F.Paste")
			(net "GND")
		)
		(pad "CU80" smd circle
			(at 32.099504 10.739628)
			(size 0.4318 0.4318)
			(layers "F.Cu" "F.Mask" "F.Paste")
			(net "GND")
		)
		(pad "CU82" smd circle
			(at 33.816544 10.739628)
			(size 0.4318 0.4318)
			(layers "F.Cu" "F.Mask" "F.Paste")
			(net "GND")
		)
		(pad "CU84" smd circle
			(at 35.533584 10.739628)
			(size 0.4318 0.4318)
			(layers "F.Cu" "F.Mask" "F.Paste")
			(net "M_K_DQS_DN<0>")
		)
		(pad "CU86" smd custom
			(at 37.250624 10.739628 270)
			(size 0.10795 0.10795)
			(layers "F.Cu" "F.Mask" "F.Paste")
			(net "GND")
			(options
				(clearance outline)
				(anchor circle)
			)
			(primitives
				(gr_poly
					(pts
						(arc
							(start 0.2159 -0.0381)
							(mid 0 -0.254)
							(end -0.2159 -0.0381)
						)
						(arc
							(start -0.2159 0.0381)
							(mid 0 0.254)
							(end 0.2159 0.0381)
						)
					)
					(width 0)
					(fill yes)
				)
			)
		)
		(pad "CV1" smd custom
			(at -37.250624 13.034772 90)
			(size 0.10795 0.10795)
			(layers "F.Cu" "F.Mask" "F.Paste")
			(net "GND")
			(options
				(clearance outline)
				(anchor circle)
			)
			(primitives
				(gr_poly
					(pts
						(arc
							(start 0.2159 -0.0381)
							(mid 0 -0.254)
							(end -0.2159 -0.0381)
						)
						(arc
							(start -0.2159 0.0381)
							(mid 0 0.254)
							(end 0.2159 0.0381)
						)
					)
					(width 0)
					(fill yes)
				)
			)
		)
		(pad "CV3" smd circle
			(at -35.533584 13.034772)
			(size 0.4318 0.4318)
			(layers "F.Cu" "F.Mask" "F.Paste")
			(net "TP_P3E_CPU1_PE2_RSR_TXN<1>")
		)
		(pad "CV5" smd circle
			(at -33.816544 13.034772)
			(size 0.4318 0.4318)
			(layers "F.Cu" "F.Mask" "F.Paste")
			(net "P3E_CPU1_PE3_MP_TXP<15>")
		)
		(pad "CV7" smd circle
			(at -32.099504 13.034772)
			(size 0.4318 0.4318)
			(layers "F.Cu" "F.Mask" "F.Paste")
			(net "PVCCIO_CPU1")
		)
		(pad "CV9" smd circle
			(at -30.382464 13.034772)
			(size 0.4318 0.4318)
			(layers "F.Cu" "F.Mask" "F.Paste")
			(net "P3E_CPU1_PE3_MP_RXN<15>")
		)
		(pad "CV11" smd circle
			(at -28.665424 13.034772)
			(size 0.4318 0.4318)
			(layers "F.Cu" "F.Mask" "F.Paste")
			(net "TP_CPU1_DMI_RX_DP3")
		)
		(pad "CV13" smd circle
			(at -26.948384 13.034772)
			(size 0.4318 0.4318)
			(layers "F.Cu" "F.Mask" "F.Paste")
			(net "TP_CPU1_UPI2_RSVD_DD15")
		)
		(pad "CV17" smd circle
			(at -23.514558 13.034772)
			(size 0.4318 0.4318)
			(layers "F.Cu" "F.Mask" "F.Paste")
			(net "GND")
		)
		(pad "CV19" smd circle
			(at -21.797518 13.034772)
			(size 0.4318 0.4318)
			(layers "F.Cu" "F.Mask" "F.Paste")
			(net "GND")
		)
		(pad "CV21" smd circle
			(at -20.080478 13.034772)
			(size 0.4318 0.4318)
			(layers "F.Cu" "F.Mask" "F.Paste")
			(net "PVCCIO_CPU1")
		)
		(pad "CV23" smd circle
			(at -18.363438 13.034772)
			(size 0.4318 0.4318)
			(layers "F.Cu" "F.Mask" "F.Paste")
			(net "PVCCMCP_CPU1")
		)
		(pad "CV25" smd circle
			(at -16.646398 13.034772)
			(size 0.4318 0.4318)
			(layers "F.Cu" "F.Mask" "F.Paste")
			(net "GND")
		)
		(pad "CV27" smd circle
			(at -14.929612 13.034772)
			(size 0.4318 0.4318)
			(layers "F.Cu" "F.Mask" "F.Paste")
			(net "GND")
		)
		(pad "CV29" smd circle
			(at -13.212572 13.034772)
			(size 0.4318 0.4318)
			(layers "F.Cu" "F.Mask" "F.Paste")
			(net "M_M_DQS_DP<16>")
		)
		(pad "CV31" smd circle
			(at -11.495532 13.034772)
			(size 0.4318 0.4318)
			(layers "F.Cu" "F.Mask" "F.Paste")
			(net "GND")
		)
		(pad "CV33" smd circle
			(at -9.778492 13.034772)
			(size 0.4318 0.4318)
			(layers "F.Cu" "F.Mask" "F.Paste")
			(net "GND")
		)
		(pad "CV35" smd circle
			(at -8.061452 13.034772)
			(size 0.4318 0.4318)
			(layers "F.Cu" "F.Mask" "F.Paste")
			(net "M_M_DQS_DP<15>")
		)
		(pad "CV37" smd circle
			(at -6.344412 13.034772)
			(size 0.4318 0.4318)
			(layers "F.Cu" "F.Mask" "F.Paste")
			(net "GND")
		)
		(pad "CV39" smd circle
			(at -4.627626 13.034772)
			(size 0.4318 0.4318)
			(layers "F.Cu" "F.Mask" "F.Paste")
			(net "GND")
		)
		(pad "CV41" smd circle
			(at -2.910586 13.034772)
			(size 0.4318 0.4318)
			(layers "F.Cu" "F.Mask" "F.Paste")
			(net "GND")
		)
		(pad "CV51" smd circle
			(at 7.202932 11.234674)
			(size 0.508 0.508)
			(layers "F.Cu" "F.Mask" "F.Paste")
			(net "PVCCIN_CPU1")
		)
		(pad "CV53" smd circle
			(at 8.919972 11.234674)
			(size 0.4318 0.4318)
			(layers "F.Cu" "F.Mask" "F.Paste")
			(net "GND")
		)
		(pad "CV55" smd circle
			(at 10.637012 11.234674)
			(size 0.4318 0.4318)
			(layers "F.Cu" "F.Mask" "F.Paste")
			(net "GND")
		)
		(pad "CV57" smd circle
			(at 12.354052 11.234674)
			(size 0.4318 0.4318)
			(layers "F.Cu" "F.Mask" "F.Paste")
			(net "PD_PIROM_CPU1_ADDR1")
		)
		(pad "CV59" smd circle
			(at 14.071092 11.234674)
			(size 0.4318 0.4318)
			(layers "F.Cu" "F.Mask" "F.Paste")
			(net "FM_CPU1_SM_WP")
		)
		(pad "CV61" smd circle
			(at 15.787878 11.234674)
			(size 0.4318 0.4318)
			(layers "F.Cu" "F.Mask" "F.Paste")
			(net "M_M_CPU_VREF")
		)
		(pad "CV63" smd circle
			(at 17.504918 11.234674)
			(size 0.4318 0.4318)
			(layers "F.Cu" "F.Mask" "F.Paste")
			(net "GND")
		)
		(pad "CV65" smd circle
			(at 19.221958 11.234674)
			(size 0.4318 0.4318)
			(layers "F.Cu" "F.Mask" "F.Paste")
			(net "M_M_DQS_DN<3>")
		)
		(pad "CV67" smd circle
			(at 20.938998 11.234674)
			(size 0.4318 0.4318)
			(layers "F.Cu" "F.Mask" "F.Paste")
			(net "GND")
		)
		(pad "CV69" smd circle
			(at 22.656038 11.234674)
			(size 0.4318 0.4318)
			(layers "F.Cu" "F.Mask" "F.Paste")
			(net "TP_CPU1_RSVD_64")
		)
		(pad "CV73" smd circle
			(at 26.090118 11.234674)
			(size 0.4318 0.4318)
			(layers "F.Cu" "F.Mask" "F.Paste")
			(net "GND")
		)
		(pad "CV75" smd circle
			(at 27.806904 11.234674)
			(size 0.4318 0.4318)
			(layers "F.Cu" "F.Mask" "F.Paste")
			(net "M_M_DQ<6>")
		)
		(pad "CV77" smd circle
			(at 29.523944 11.234674)
			(size 0.4318 0.4318)
			(layers "F.Cu" "F.Mask" "F.Paste")
			(net "M_M_DQ<3>")
		)
		(pad "CV79" smd circle
			(at 31.240984 11.234674)
			(size 0.4318 0.4318)
			(layers "F.Cu" "F.Mask" "F.Paste")
			(net "GND")
		)
		(pad "CV81" smd circle
			(at 32.958024 11.234674)
			(size 0.4318 0.4318)
			(layers "F.Cu" "F.Mask" "F.Paste")
			(net "GND")
		)
		(pad "CV83" smd circle
			(at 34.675064 11.234674)
			(size 0.4318 0.4318)
			(layers "F.Cu" "F.Mask" "F.Paste")
			(net "GND")
		)
		(pad "CV85" smd circle
			(at 36.392104 11.234674)
			(size 0.4318 0.4318)
			(layers "F.Cu" "F.Mask" "F.Paste")
			(net "M_K_DQS_DP<0>")
		)
		(pad "CW2" smd circle
			(at -36.392104 13.530326)
			(size 0.4318 0.4318)
			(layers "F.Cu" "F.Mask" "F.Paste")
			(net "TP_P3E_CPU1_PE1_MP_TXP<0>")
		)
		(pad "CW4" smd circle
			(at -34.675064 13.530326)
			(size 0.4318 0.4318)
			(layers "F.Cu" "F.Mask" "F.Paste")
			(net "TP_P3E_CPU1_PE2_RSR_TXP<0>")
		)
		(pad "CW6" smd circle
			(at -32.958024 13.530326)
			(size 0.4318 0.4318)
			(layers "F.Cu" "F.Mask" "F.Paste")
			(net "GND")
		)
		(pad "CW8" smd circle
			(at -31.240984 13.530326)
			(size 0.4318 0.4318)
			(layers "F.Cu" "F.Mask" "F.Paste")
			(net "TP_P3E_CPU1_PE1_MP_RXN<0>")
		)
		(pad "CW10" smd circle
			(at -29.523944 13.530326)
			(size 0.4318 0.4318)
			(layers "F.Cu" "F.Mask" "F.Paste")
			(net "P3E_CPU1_PE3_MP_RXP<14>")
		)
		(pad "CW12" smd circle
			(at -27.806904 13.530326)
			(size 0.4318 0.4318)
			(layers "F.Cu" "F.Mask" "F.Paste")
			(net "GND")
		)
		(pad "CW14" smd circle
			(at -26.090118 13.530326)
			(size 0.4318 0.4318)
			(layers "F.Cu" "F.Mask" "F.Paste")
			(net "TP_CPU1_UPI2_RSVD_DF15")
		)
		(pad "CW16" smd circle
			(at -24.373078 13.530326)
			(size 0.4318 0.4318)
			(layers "F.Cu" "F.Mask" "F.Paste")
			(net "TP_CPU1_UPI2_RSVD_DB15")
		)
		(pad "CW18" smd circle
			(at -22.656038 13.530326)
			(size 0.4318 0.4318)
			(layers "F.Cu" "F.Mask" "F.Paste")
			(net "GND")
		)
		(pad "CW20" smd circle
			(at -20.938998 13.530326)
			(size 0.4318 0.4318)
			(layers "F.Cu" "F.Mask" "F.Paste")
			(net "GND")
		)
		(pad "CW22" smd circle
			(at -19.221958 13.530326)
			(size 0.4318 0.4318)
			(layers "F.Cu" "F.Mask" "F.Paste")
			(net "TP_CPU1_KTI2_DFX_DN")
		)
		(pad "CW24" smd circle
			(at -17.504918 13.530326)
			(size 0.4318 0.4318)
			(layers "F.Cu" "F.Mask" "F.Paste")
			(net "PVCCMCP_CPU1")
		)
		(pad "CW26" smd circle
			(at -15.787878 13.530326)
			(size 0.4318 0.4318)
			(layers "F.Cu" "F.Mask" "F.Paste")
			(net "GND")
		)
		(pad "CW28" smd circle
			(at -14.071092 13.530326)
			(size 0.4318 0.4318)
			(layers "F.Cu" "F.Mask" "F.Paste")
			(net "M_M_DQ<62>")
		)
		(pad "CW30" smd circle
			(at -12.354052 13.530326)
			(size 0.4318 0.4318)
			(layers "F.Cu" "F.Mask" "F.Paste")
			(net "M_M_DQ<56>")
		)
		(pad "CW32" smd circle
			(at -10.637012 13.530326)
			(size 0.4318 0.4318)
			(layers "F.Cu" "F.Mask" "F.Paste")
			(net "GND")
		)
		(pad "CW34" smd circle
			(at -8.919972 13.530326)
			(size 0.4318 0.4318)
			(layers "F.Cu" "F.Mask" "F.Paste")
			(net "M_M_DQ<54>")
		)
		(pad "CW36" smd circle
			(at -7.202932 13.530326)
			(size 0.4318 0.4318)
			(layers "F.Cu" "F.Mask" "F.Paste")
			(net "M_M_DQ<48>")
		)
		(pad "CW38" smd circle
			(at -5.485892 13.530326)
			(size 0.4318 0.4318)
			(layers "F.Cu" "F.Mask" "F.Paste")
			(net "GND")
		)
		(pad "CW40" smd circle
			(at -3.769106 13.530326)
			(size 0.4318 0.4318)
			(layers "F.Cu" "F.Mask" "F.Paste")
			(net "GND")
		)
		(pad "CW42" smd circle
			(at -2.052066 13.530326)
			(size 0.4318 0.4318)
			(layers "F.Cu" "F.Mask" "F.Paste")
			(net "GND")
		)
		(pad "CW46" smd circle
			(at 2.910586 11.730228)
			(size 0.508 0.508)
			(layers "F.Cu" "F.Mask" "F.Paste")
			(net "PVCCIN_CPU1")
		)
		(pad "CW48" smd circle
			(at 4.627626 11.730228)
			(size 0.508 0.508)
			(layers "F.Cu" "F.Mask" "F.Paste")
			(net "PVCCIN_CPU1")
		)
		(pad "CW50" smd circle
			(at 6.344412 11.730228)
			(size 0.508 0.508)
			(layers "F.Cu" "F.Mask" "F.Paste")
			(net "PVCCIN_CPU1")
		)
		(pad "CW52" smd circle
			(at 8.061452 11.730228)
			(size 0.4318 0.4318)
			(layers "F.Cu" "F.Mask" "F.Paste")
			(net "GND")
		)
		(pad "CW54" smd circle
			(at 9.778492 11.730228)
			(size 0.4318 0.4318)
			(layers "F.Cu" "F.Mask" "F.Paste")
			(net "GND")
		)
		(pad "CW56" smd circle
			(at 11.495532 11.730228)
			(size 0.4318 0.4318)
			(layers "F.Cu" "F.Mask" "F.Paste")
			(net "PD_PIROM_CPU1_ADDR2")
		)
		(pad "CW58" smd circle
			(at 13.212572 11.730228)
			(size 0.4318 0.4318)
			(layers "F.Cu" "F.Mask" "F.Paste")
			(net "SMB_PIROM_CPU1_SDA")
		)
		(pad "CW60" smd circle
			(at 14.929612 11.730228)
			(size 0.4318 0.4318)
			(layers "F.Cu" "F.Mask" "F.Paste")
			(net "TP_CPU1_RSVD_61")
		)
		(pad "CW62" smd circle
			(at 16.646398 11.730228)
			(size 0.4318 0.4318)
			(layers "F.Cu" "F.Mask" "F.Paste")
			(net "TP_CPU1_RSVD_60")
		)
		(pad "CW64" smd circle
			(at 18.363438 11.730228)
			(size 0.4318 0.4318)
			(layers "F.Cu" "F.Mask" "F.Paste")
			(net "GND")
		)
		(pad "CW66" smd circle
			(at 20.080478 11.730228)
			(size 0.4318 0.4318)
			(layers "F.Cu" "F.Mask" "F.Paste")
			(net "GND")
		)
		(pad "CW68" smd circle
			(at 21.797518 11.730228)
			(size 0.4318 0.4318)
			(layers "F.Cu" "F.Mask" "F.Paste")
			(net "GND")
		)
		(pad "CW72" smd circle
			(at 25.231598 11.730228)
			(size 0.4318 0.4318)
			(layers "F.Cu" "F.Mask" "F.Paste")
			(net "FM_CPU1_PKGID1")
		)
		(pad "CW74" smd circle
			(at 26.948384 11.730228)
			(size 0.4318 0.4318)
			(layers "F.Cu" "F.Mask" "F.Paste")
			(net "GND")
		)
		(pad "CW76" smd circle
			(at 28.665424 11.730228)
			(size 0.4318 0.4318)
			(layers "F.Cu" "F.Mask" "F.Paste")
			(net "M_M_DQ<2>")
		)
		(pad "CW78" smd circle
			(at 30.382464 11.730228)
			(size 0.4318 0.4318)
			(layers "F.Cu" "F.Mask" "F.Paste")
			(net "GND")
		)
		(pad "CW80" smd circle
			(at 32.099504 11.730228)
			(size 0.4318 0.4318)
			(layers "F.Cu" "F.Mask" "F.Paste")
			(net "M_L_DQ<13>")
		)
		(pad "CW82" smd circle
			(at 33.816544 11.730228)
			(size 0.4318 0.4318)
			(layers "F.Cu" "F.Mask" "F.Paste")
			(net "GND")
		)
		(pad "CW84" smd circle
			(at 35.533584 11.730228)
			(size 0.4318 0.4318)
			(layers "F.Cu" "F.Mask" "F.Paste")
			(net "M_K_DQ<7>")
		)
		(pad "CW86" smd custom
			(at 37.250624 11.730228 270)
			(size 0.10795 0.10795)
			(layers "F.Cu" "F.Mask" "F.Paste")
			(net "M_K_DQ<6>")
			(options
				(clearance outline)
				(anchor circle)
			)
			(primitives
				(gr_poly
					(pts
						(arc
							(start 0.2159 -0.0381)
							(mid 0 -0.254)
							(end -0.2159 -0.0381)
						)
						(arc
							(start -0.2159 0.0381)
							(mid 0 0.254)
							(end 0.2159 0.0381)
						)
					)
					(width 0)
					(fill yes)
				)
			)
		)
		(pad "CY1" smd custom
			(at -37.250624 14.025372 90)
			(size 0.10795 0.10795)
			(layers "F.Cu" "F.Mask" "F.Paste")
			(net "GND")
			(options
				(clearance outline)
				(anchor circle)
			)
			(primitives
				(gr_poly
					(pts
						(arc
							(start 0.2159 -0.0381)
							(mid 0 -0.254)
							(end -0.2159 -0.0381)
						)
						(arc
							(start -0.2159 0.0381)
							(mid 0 0.254)
							(end 0.2159 0.0381)
						)
					)
					(width 0)
					(fill yes)
				)
			)
		)
		(pad "CY3" smd circle
			(at -35.533584 14.025372)
			(size 0.4318 0.4318)
			(layers "F.Cu" "F.Mask" "F.Paste")
			(net "TP_P3E_CPU1_PE2_RSR_TXN<0>")
		)
		(pad "CY5" smd circle
			(at -33.816544 14.025372)
			(size 0.4318 0.4318)
			(layers "F.Cu" "F.Mask" "F.Paste")
			(net "P3E_CPU1_PE3_MP_TXN<15>")
		)
		(pad "CY7" smd circle
			(at -32.099504 14.025372)
			(size 0.4318 0.4318)
			(layers "F.Cu" "F.Mask" "F.Paste")
			(net "TP_P3E_CPU1_PE1_MP_RXP<1>")
		)
		(pad "CY9" smd circle
			(at -30.382464 14.025372)
			(size 0.4318 0.4318)
			(layers "F.Cu" "F.Mask" "F.Paste")
			(net "GND")
		)
		(pad "CY11" smd circle
			(at -28.665424 14.025372)
			(size 0.4318 0.4318)
			(layers "F.Cu" "F.Mask" "F.Paste")
			(net "P3E_CPU1_PE3_MP_RXN<14>")
		)
		(pad "CY13" smd circle
			(at -26.948384 14.025372)
			(size 0.4318 0.4318)
			(layers "F.Cu" "F.Mask" "F.Paste")
			(net "GND")
		)
		(pad "CY15" smd circle
			(at -25.231598 14.025372)
			(size 0.4318 0.4318)
			(layers "F.Cu" "F.Mask" "F.Paste")
			(net "GND")
		)
		(pad "CY17" smd circle
			(at -23.514558 14.025372)
			(size 0.4318 0.4318)
			(layers "F.Cu" "F.Mask" "F.Paste")
			(net "PVCCIO_CPU1")
		)
		(pad "CY19" smd circle
			(at -21.797518 14.025372)
			(size 0.4318 0.4318)
			(layers "F.Cu" "F.Mask" "F.Paste")
			(net "GND")
		)
		(pad "CY21" smd circle
			(at -20.080478 14.025372)
			(size 0.4318 0.4318)
			(layers "F.Cu" "F.Mask" "F.Paste")
			(net "GND")
		)
		(pad "CY23" smd circle
			(at -18.363438 14.025372)
			(size 0.4318 0.4318)
			(layers "F.Cu" "F.Mask" "F.Paste")
			(net "TP_CPU1_RSVD_59")
		)
		(pad "CY25" smd circle
			(at -16.646398 14.025372)
			(size 0.4318 0.4318)
			(layers "F.Cu" "F.Mask" "F.Paste")
			(net "PVCCMCP_CPU1")
		)
		(pad "CY27" smd circle
			(at -14.929612 14.025372)
			(size 0.4318 0.4318)
			(layers "F.Cu" "F.Mask" "F.Paste")
			(net "M_M_DQ<58>")
		)
		(pad "CY29" smd circle
			(at -13.212572 14.025372)
			(size 0.4318 0.4318)
			(layers "F.Cu" "F.Mask" "F.Paste")
			(net "M_M_DQS_DN<16>")
		)
		(pad "CY31" smd circle
			(at -11.495532 14.025372)
			(size 0.4318 0.4318)
			(layers "F.Cu" "F.Mask" "F.Paste")
			(net "M_M_DQ<60>")
		)
		(pad "CY33" smd circle
			(at -9.778492 14.025372)
			(size 0.4318 0.4318)
			(layers "F.Cu" "F.Mask" "F.Paste")
			(net "M_M_DQ<50>")
		)
		(pad "CY35" smd circle
			(at -8.061452 14.025372)
			(size 0.4318 0.4318)
			(layers "F.Cu" "F.Mask" "F.Paste")
			(net "M_M_DQS_DN<15>")
		)
		(pad "CY37" smd circle
			(at -6.344412 14.025372)
			(size 0.4318 0.4318)
			(layers "F.Cu" "F.Mask" "F.Paste")
			(net "M_M_DQ<52>")
		)
		(pad "CY39" smd circle
			(at -4.627626 14.025372)
			(size 0.4318 0.4318)
			(layers "F.Cu" "F.Mask" "F.Paste")
			(net "TP_CPU1_RSVD_57")
		)
		(pad "CY41" smd circle
			(at -2.910586 14.025372)
			(size 0.4318 0.4318)
			(layers "F.Cu" "F.Mask" "F.Paste")
			(net "GND")
		)
		(pad "CY45" smd circle
			(at 2.052066 12.225274)
			(size 0.508 0.508)
			(layers "F.Cu" "F.Mask" "F.Paste")
			(net "GND")
		)
		(pad "CY47" smd circle
			(at 3.769106 12.225274)
			(size 0.4318 0.4318)
			(layers "F.Cu" "F.Mask" "F.Paste")
			(net "PVCCIN_CPU1")
		)
		(pad "CY49" smd circle
			(at 5.485892 12.225274)
			(size 0.4318 0.4318)
			(layers "F.Cu" "F.Mask" "F.Paste")
			(net "PVCCIN_CPU1")
		)
		(pad "CY51" smd circle
			(at 7.202932 12.225274)
			(size 0.4318 0.4318)
			(layers "F.Cu" "F.Mask" "F.Paste")
			(net "GND")
		)
		(pad "CY53" smd circle
			(at 8.919972 12.225274)
			(size 0.4318 0.4318)
			(layers "F.Cu" "F.Mask" "F.Paste")
			(net "TP_CPU1_RSVD_56")
		)
		(pad "CY55" smd circle
			(at 10.637012 12.225274)
			(size 0.4318 0.4318)
			(layers "F.Cu" "F.Mask" "F.Paste")
			(net "P3V3_STBY")
		)
		(pad "CY57" smd circle
			(at 12.354052 12.225274)
			(size 0.4318 0.4318)
			(layers "F.Cu" "F.Mask" "F.Paste")
			(net "TP_CPU1_RSVD_55")
		)
		(pad "CY59" smd circle
			(at 14.071092 12.225274)
			(size 0.4318 0.4318)
			(layers "F.Cu" "F.Mask" "F.Paste")
			(net "GND")
		)
		(pad "CY61" smd circle
			(at 15.787878 12.225274)
			(size 0.4318 0.4318)
			(layers "F.Cu" "F.Mask" "F.Paste")
			(net "GND")
		)
		(pad "CY63" smd circle
			(at 17.504918 12.225274)
			(size 0.4318 0.4318)
			(layers "F.Cu" "F.Mask" "F.Paste")
			(net "TP_CPU1_RSVD_54")
		)
		(pad "CY65" smd circle
			(at 19.221958 12.225274)
			(size 0.4318 0.4318)
			(layers "F.Cu" "F.Mask" "F.Paste")
			(net "GND")
		)
		(pad "CY67" smd circle
			(at 20.938998 12.225274)
			(size 0.4318 0.4318)
			(layers "F.Cu" "F.Mask" "F.Paste")
			(net "M_K_DQS_DP<17>")
		)
		(pad "CY69" smd circle
			(at 22.656038 12.225274)
			(size 0.4318 0.4318)
			(layers "F.Cu" "F.Mask" "F.Paste")
			(net "GND")
		)
		(pad "CY71" smd circle
			(at 24.373078 12.225274)
			(size 0.4318 0.4318)
			(layers "F.Cu" "F.Mask" "F.Paste")
			(net "FM_CPU1_PROC_ID0")
		)
		(pad "CY73" smd circle
			(at 26.090118 12.225274)
			(size 0.4318 0.4318)
			(layers "F.Cu" "F.Mask" "F.Paste")
			(net "TP_CPU1_RSVD_53")
		)
		(pad "CY75" smd circle
			(at 27.806904 12.225274)
			(size 0.4318 0.4318)
			(layers "F.Cu" "F.Mask" "F.Paste")
			(net "GND")
		)
		(pad "CY77" smd circle
			(at 29.523944 12.225274)
			(size 0.4318 0.4318)
			(layers "F.Cu" "F.Mask" "F.Paste")
			(net "GND")
		)
		(pad "CY79" smd circle
			(at 31.240984 12.225274)
			(size 0.4318 0.4318)
			(layers "F.Cu" "F.Mask" "F.Paste")
			(net "M_L_DQ<12>")
		)
		(pad "CY81" smd circle
			(at 32.958024 12.225274)
			(size 0.4318 0.4318)
			(layers "F.Cu" "F.Mask" "F.Paste")
			(net "M_L_DQ<9>")
		)
		(pad "CY83" smd circle
			(at 34.675064 12.225274)
			(size 0.4318 0.4318)
			(layers "F.Cu" "F.Mask" "F.Paste")
			(net "GND")
		)
		(pad "CY85" smd circle
			(at 36.392104 12.225274)
			(size 0.4318 0.4318)
			(layers "F.Cu" "F.Mask" "F.Paste")
			(net "GND")
		)
		(pad "D3" smd custom
			(at -35.533584 -23.617174 45)
			(size 0.10795 0.10795)
			(layers "F.Cu" "F.Mask" "F.Paste")
			(net "GND")
			(options
				(clearance outline)
				(anchor circle)
			)
			(primitives
				(gr_poly
					(pts
						(arc
							(start 0.2159 -0.0381)
							(mid 0 -0.254)
							(end -0.2159 -0.0381)
						)
						(arc
							(start -0.2159 0.0381)
							(mid 0 0.254)
							(end 0.2159 0.0381)
						)
					)
					(width 0)
					(fill yes)
				)
			)
		)
		(pad "D5" smd custom
			(at -33.816544 -23.617174 90)
			(size 0.10795 0.10795)
			(layers "F.Cu" "F.Mask" "F.Paste")
			(net "TP_CPU1_RSVD_287")
			(options
				(clearance outline)
				(anchor circle)
			)
			(primitives
				(gr_poly
					(pts
						(arc
							(start 0.2159 -0.0381)
							(mid 0 -0.254)
							(end -0.2159 -0.0381)
						)
						(arc
							(start -0.2159 0.0381)
							(mid 0 0.254)
							(end 0.2159 0.0381)
						)
					)
					(width 0)
					(fill yes)
				)
			)
		)
		(pad "D7" smd circle
			(at -32.099504 -23.617174)
			(size 0.4318 0.4318)
			(layers "F.Cu" "F.Mask" "F.Paste")
			(net "PVCCIO_CPU1")
		)
		(pad "D9" smd circle
			(at -30.382464 -23.617174)
			(size 0.4318 0.4318)
			(layers "F.Cu" "F.Mask" "F.Paste")
			(net "UPI_CPU1_CPU0_P1P1_DP<7>")
		)
		(pad "D11" smd circle
			(at -28.665424 -23.617174)
			(size 0.4318 0.4318)
			(layers "F.Cu" "F.Mask" "F.Paste")
			(net "GND")
		)
		(pad "D13" smd circle
			(at -26.948384 -23.617174)
			(size 0.4318 0.4318)
			(layers "F.Cu" "F.Mask" "F.Paste")
			(net "GND")
		)
		(pad "D15" smd circle
			(at -25.231598 -23.617174)
			(size 0.4318 0.4318)
			(layers "F.Cu" "F.Mask" "F.Paste")
			(net "UPI_CPU1_CPU0_P1P1_DN<12>")
		)
		(pad "D17" smd circle
			(at -23.514558 -23.617174)
			(size 0.4318 0.4318)
			(layers "F.Cu" "F.Mask" "F.Paste")
			(net "TP_CPU1_RSVD_286")
		)
		(pad "D25" smd circle
			(at -16.646398 -23.617174)
			(size 0.4318 0.4318)
			(layers "F.Cu" "F.Mask" "F.Paste")
			(net "GND")
		)
		(pad "D27" smd circle
			(at -14.929612 -23.617174)
			(size 0.4318 0.4318)
			(layers "F.Cu" "F.Mask" "F.Paste")
			(net "GND")
		)
		(pad "D29" smd circle
			(at -13.212572 -23.617174)
			(size 0.4318 0.4318)
			(layers "F.Cu" "F.Mask" "F.Paste")
			(net "GND")
		)
		(pad "D31" smd circle
			(at -11.495532 -23.617174)
			(size 0.4318 0.4318)
			(layers "F.Cu" "F.Mask" "F.Paste")
			(net "GND")
		)
		(pad "D33" smd circle
			(at -9.778492 -23.617174)
			(size 0.4318 0.4318)
			(layers "F.Cu" "F.Mask" "F.Paste")
			(net "GND")
		)
		(pad "D35" smd circle
			(at -8.061452 -23.617174)
			(size 0.4318 0.4318)
			(layers "F.Cu" "F.Mask" "F.Paste")
			(net "GND")
		)
		(pad "D37" smd circle
			(at -6.344412 -23.617174)
			(size 0.4318 0.4318)
			(layers "F.Cu" "F.Mask" "F.Paste")
			(net "GND")
		)
		(pad "D39" smd circle
			(at -4.627626 -23.617174)
			(size 0.4318 0.4318)
			(layers "F.Cu" "F.Mask" "F.Paste")
			(net "GND")
		)
		(pad "D41" smd circle
			(at -2.910586 -23.617174)
			(size 0.4318 0.4318)
			(layers "F.Cu" "F.Mask" "F.Paste")
			(net "GND")
		)
		(pad "D43" smd circle
			(at -1.193546 -23.617174)
			(size 0.4318 0.4318)
			(layers "F.Cu" "F.Mask" "F.Paste")
			(net "GND")
		)
		(pad "D45" smd custom
			(at 2.052066 -25.417526 45)
			(size 0.10795 0.10795)
			(layers "F.Cu" "F.Mask" "F.Paste")
			(net "PVDDQ_GHJ")
			(options
				(clearance outline)
				(anchor circle)
			)
			(primitives
				(gr_poly
					(pts
						(arc
							(start 0.2159 -0.0381)
							(mid 0 -0.254)
							(end -0.2159 -0.0381)
						)
						(arc
							(start -0.2159 0.0381)
							(mid 0 0.254)
							(end 0.2159 0.0381)
						)
					)
					(width 0)
					(fill yes)
				)
			)
		)
		(pad "D47" smd circle
			(at 3.769106 -25.417526)
			(size 0.4318 0.4318)
			(layers "F.Cu" "F.Mask" "F.Paste")
			(net "M_G_CS_N<2>")
		)
		(pad "D49" smd circle
			(at 5.485892 -25.417526)
			(size 0.4318 0.4318)
			(layers "F.Cu" "F.Mask" "F.Paste")
			(net "M_G_CS_N<5>")
		)
		(pad "D51" smd circle
			(at 7.202932 -25.417526)
			(size 0.4318 0.4318)
			(layers "F.Cu" "F.Mask" "F.Paste")
			(net "M_G_MA<16>")
		)
		(pad "D53" smd circle
			(at 8.919972 -25.417526)
			(size 0.4318 0.4318)
			(layers "F.Cu" "F.Mask" "F.Paste")
			(net "M_G_PAR")
		)
		(pad "D55" smd circle
			(at 10.637012 -25.417526)
			(size 0.4318 0.4318)
			(layers "F.Cu" "F.Mask" "F.Paste")
			(net "M_G_CLK_DP<0>")
		)
		(pad "D57" smd circle
			(at 12.354052 -25.417526)
			(size 0.4318 0.4318)
			(layers "F.Cu" "F.Mask" "F.Paste")
			(net "M_G_MA<2>")
		)
		(pad "D59" smd circle
			(at 14.071092 -25.417526)
			(size 0.4318 0.4318)
			(layers "F.Cu" "F.Mask" "F.Paste")
			(net "M_G_MA<6>")
		)
		(pad "D61" smd circle
			(at 15.787878 -25.417526)
			(size 0.4318 0.4318)
			(layers "F.Cu" "F.Mask" "F.Paste")
			(net "M_G_BG<0>")
		)
		(pad "D63" smd circle
			(at 17.504918 -25.417526)
			(size 0.4318 0.4318)
			(layers "F.Cu" "F.Mask" "F.Paste")
			(net "M_G_CKE<3>")
		)
		(pad "D65" smd custom
			(at 19.221958 -25.417526)
			(size 0.10795 0.10795)
			(layers "F.Cu" "F.Mask" "F.Paste")
			(net "TP_CPU1_RSVD_285")
			(options
				(clearance outline)
				(anchor circle)
			)
			(primitives
				(gr_poly
					(pts
						(arc
							(start 0.2159 -0.0381)
							(mid 0 -0.254)
							(end -0.2159 -0.0381)
						)
						(arc
							(start -0.2159 0.0381)
							(mid 0 0.254)
							(end 0.2159 0.0381)
						)
					)
					(width 0)
					(fill yes)
				)
			)
		)
		(pad "D71" smd custom
			(at 24.373078 -25.417526)
			(size 0.10795 0.10795)
			(layers "F.Cu" "F.Mask" "F.Paste")
			(net "M_H_DQ<26>")
			(options
				(clearance outline)
				(anchor circle)
			)
			(primitives
				(gr_poly
					(pts
						(arc
							(start 0.2159 -0.0381)
							(mid 0 -0.254)
							(end -0.2159 -0.0381)
						)
						(arc
							(start -0.2159 0.0381)
							(mid 0 0.254)
							(end 0.2159 0.0381)
						)
					)
					(width 0)
					(fill yes)
				)
			)
		)
		(pad "D73" smd circle
			(at 26.090118 -25.417526)
			(size 0.4318 0.4318)
			(layers "F.Cu" "F.Mask" "F.Paste")
			(net "M_H_DQS_DP<12>")
		)
		(pad "D75" smd circle
			(at 27.806904 -25.417526)
			(size 0.4318 0.4318)
			(layers "F.Cu" "F.Mask" "F.Paste")
			(net "M_H_DQ<24>")
		)
		(pad "D77" smd circle
			(at 29.523944 -25.417526)
			(size 0.4318 0.4318)
			(layers "F.Cu" "F.Mask" "F.Paste")
			(net "GND")
		)
		(pad "D79" smd circle
			(at 31.240984 -25.417526)
			(size 0.4318 0.4318)
			(layers "F.Cu" "F.Mask" "F.Paste")
			(net "M_H_DQS_DN<11>")
		)
		(pad "D81" smd custom
			(at 32.958024 -25.417526 315)
			(size 0.10795 0.10795)
			(layers "F.Cu" "F.Mask" "F.Paste")
			(net "GND")
			(options
				(clearance outline)
				(anchor circle)
			)
			(primitives
				(gr_poly
					(pts
						(arc
							(start 0.2159 -0.0381)
							(mid 0 -0.254)
							(end -0.2159 -0.0381)
						)
						(arc
							(start -0.2159 0.0381)
							(mid 0 0.254)
							(end 0.2159 0.0381)
						)
					)
					(width 0)
					(fill yes)
				)
			)
		)
		(pad "D83" smd custom
			(at 34.675064 -25.417526 270)
			(size 0.10795 0.10795)
			(layers "F.Cu" "F.Mask" "F.Paste")
			(net "TP_CPU1_RSVD_284")
			(options
				(clearance outline)
				(anchor circle)
			)
			(primitives
				(gr_poly
					(pts
						(arc
							(start 0.2159 -0.0381)
							(mid 0 -0.254)
							(end -0.2159 -0.0381)
						)
						(arc
							(start -0.2159 0.0381)
							(mid 0 0.254)
							(end 0.2159 0.0381)
						)
					)
					(width 0)
					(fill yes)
				)
			)
		)
		(pad "DA2" smd circle
			(at -36.392104 14.520926)
			(size 0.4318 0.4318)
			(layers "F.Cu" "F.Mask" "F.Paste")
			(net "TP_P3E_CPU1_PE1_MP_TXN<0>")
		)
		(pad "DA4" smd circle
			(at -34.675064 14.520926)
			(size 0.4318 0.4318)
			(layers "F.Cu" "F.Mask" "F.Paste")
			(net "P3E_CPU1_PE3_MP_TXP<14>")
		)
		(pad "DA6" smd circle
			(at -32.958024 14.520926)
			(size 0.4318 0.4318)
			(layers "F.Cu" "F.Mask" "F.Paste")
			(net "GND")
		)
		(pad "DA8" smd circle
			(at -31.240984 14.520926)
			(size 0.4318 0.4318)
			(layers "F.Cu" "F.Mask" "F.Paste")
			(net "TP_P3E_CPU1_PE1_MP_RXN<1>")
		)
		(pad "DA10" smd circle
			(at -29.523944 14.520926)
			(size 0.4318 0.4318)
			(layers "F.Cu" "F.Mask" "F.Paste")
			(net "TP_P3E_CPU1_PE1_MP_RXP<3>")
		)
		(pad "DA12" smd circle
			(at -27.806904 14.520926)
			(size 0.4318 0.4318)
			(layers "F.Cu" "F.Mask" "F.Paste")
			(net "P3E_CPU1_PE3_MP_RXP<13>")
		)
		(pad "DA14" smd circle
			(at -26.090118 14.520926)
			(size 0.4318 0.4318)
			(layers "F.Cu" "F.Mask" "F.Paste")
			(net "PVCCIO_CPU1")
		)
		(pad "DA16" smd circle
			(at -24.373078 14.520926)
			(size 0.4318 0.4318)
			(layers "F.Cu" "F.Mask" "F.Paste")
			(net "TP_CPU1_UPI2_RSVD_DC16")
		)
		(pad "DA18" smd circle
			(at -22.656038 14.520926)
			(size 0.4318 0.4318)
			(layers "F.Cu" "F.Mask" "F.Paste")
			(net "GND")
		)
		(pad "DA20" smd circle
			(at -20.938998 14.520926)
			(size 0.4318 0.4318)
			(layers "F.Cu" "F.Mask" "F.Paste")
			(net "GND")
		)
		(pad "DA22" smd circle
			(at -19.221958 14.520926)
			(size 0.4318 0.4318)
			(layers "F.Cu" "F.Mask" "F.Paste")
			(net "GND")
		)
		(pad "DA24" smd circle
			(at -17.504918 14.520926)
			(size 0.4318 0.4318)
			(layers "F.Cu" "F.Mask" "F.Paste")
			(net "PVCCMCP_CPU1")
		)
		(pad "DA26" smd circle
			(at -15.787878 14.520926)
			(size 0.4318 0.4318)
			(layers "F.Cu" "F.Mask" "F.Paste")
			(net "GND")
		)
		(pad "DA28" smd circle
			(at -14.071092 14.520926)
			(size 0.4318 0.4318)
			(layers "F.Cu" "F.Mask" "F.Paste")
			(net "GND")
		)
		(pad "DA30" smd circle
			(at -12.354052 14.520926)
			(size 0.4318 0.4318)
			(layers "F.Cu" "F.Mask" "F.Paste")
			(net "GND")
		)
		(pad "DA32" smd circle
			(at -10.637012 14.520926)
			(size 0.4318 0.4318)
			(layers "F.Cu" "F.Mask" "F.Paste")
			(net "GND")
		)
		(pad "DA34" smd circle
			(at -8.919972 14.520926)
			(size 0.4318 0.4318)
			(layers "F.Cu" "F.Mask" "F.Paste")
			(net "GND")
		)
		(pad "DA36" smd circle
			(at -7.202932 14.520926)
			(size 0.4318 0.4318)
			(layers "F.Cu" "F.Mask" "F.Paste")
			(net "GND")
		)
		(pad "DA38" smd circle
			(at -5.485892 14.520926)
			(size 0.4318 0.4318)
			(layers "F.Cu" "F.Mask" "F.Paste")
			(net "GND")
		)
		(pad "DA40" smd circle
			(at -3.769106 14.520926)
			(size 0.4318 0.4318)
			(layers "F.Cu" "F.Mask" "F.Paste")
			(net "TP_CPU1_RSVD_51")
		)
		(pad "DA42" smd circle
			(at -2.052066 14.520926)
			(size 0.4318 0.4318)
			(layers "F.Cu" "F.Mask" "F.Paste")
			(net "M_M_DQ<36>")
		)
		(pad "DA44" smd circle
			(at 1.193546 12.720828)
			(size 0.508 0.508)
			(layers "F.Cu" "F.Mask" "F.Paste")
			(net "GND")
		)
		(pad "DA46" smd circle
			(at 2.910586 12.720828)
			(size 0.4318 0.4318)
			(layers "F.Cu" "F.Mask" "F.Paste")
			(net "GND")
		)
		(pad "DA48" smd circle
			(at 4.627626 12.720828)
			(size 0.4318 0.4318)
			(layers "F.Cu" "F.Mask" "F.Paste")
			(net "GND")
		)
		(pad "DA50" smd circle
			(at 6.344412 12.720828)
			(size 0.4318 0.4318)
			(layers "F.Cu" "F.Mask" "F.Paste")
			(net "GND")
		)
		(pad "DA52" smd circle
			(at 8.061452 12.720828)
			(size 0.4318 0.4318)
			(layers "F.Cu" "F.Mask" "F.Paste")
			(net "TP_CPU1_RSVD_50")
		)
		(pad "DA54" smd circle
			(at 9.778492 12.720828)
			(size 0.4318 0.4318)
			(layers "F.Cu" "F.Mask" "F.Paste")
			(net "TP_CPU1_RSVD_49")
		)
		(pad "DA56" smd circle
			(at 11.495532 12.720828)
			(size 0.4318 0.4318)
			(layers "F.Cu" "F.Mask" "F.Paste")
			(net "TP_CPU1_RSVD_48")
		)
		(pad "DA58" smd circle
			(at 13.212572 12.720828)
			(size 0.4318 0.4318)
			(layers "F.Cu" "F.Mask" "F.Paste")
			(net "M_M_MA<9>")
		)
		(pad "DA60" smd circle
			(at 14.929612 12.720828)
			(size 0.4318 0.4318)
			(layers "F.Cu" "F.Mask" "F.Paste")
			(net "M_M_MA<11>")
		)
		(pad "DA62" smd circle
			(at 16.646398 12.720828)
			(size 0.4318 0.4318)
			(layers "F.Cu" "F.Mask" "F.Paste")
			(net "M_M_BG<0>")
		)
		(pad "DA64" smd circle
			(at 18.363438 12.720828)
			(size 0.4318 0.4318)
			(layers "F.Cu" "F.Mask" "F.Paste")
			(net "GND")
		)
		(pad "DA66" smd circle
			(at 20.080478 12.720828)
			(size 0.4318 0.4318)
			(layers "F.Cu" "F.Mask" "F.Paste")
			(net "M_K_ECC<6>")
		)
		(pad "DA68" smd circle
			(at 21.797518 12.720828)
			(size 0.4318 0.4318)
			(layers "F.Cu" "F.Mask" "F.Paste")
			(net "M_K_ECC<0>")
		)
		(pad "DA70" smd circle
			(at 23.514558 12.720828)
			(size 0.4318 0.4318)
			(layers "F.Cu" "F.Mask" "F.Paste")
			(net "GND")
		)
		(pad "DA72" smd circle
			(at 25.231598 12.720828)
			(size 0.4318 0.4318)
			(layers "F.Cu" "F.Mask" "F.Paste")
			(net "FM_CPU1_PKGID2")
		)
		(pad "DA74" smd circle
			(at 26.948384 12.720828)
			(size 0.4318 0.4318)
			(layers "F.Cu" "F.Mask" "F.Paste")
			(net "GND")
		)
		(pad "DA76" smd circle
			(at 28.665424 12.720828)
			(size 0.4318 0.4318)
			(layers "F.Cu" "F.Mask" "F.Paste")
			(net "GND")
		)
		(pad "DA78" smd circle
			(at 30.382464 12.720828)
			(size 0.4318 0.4318)
			(layers "F.Cu" "F.Mask" "F.Paste")
			(net "GND")
		)
		(pad "DA80" smd circle
			(at 32.099504 12.720828)
			(size 0.4318 0.4318)
			(layers "F.Cu" "F.Mask" "F.Paste")
			(net "GND")
		)
		(pad "DA82" smd circle
			(at 33.816544 12.720828)
			(size 0.4318 0.4318)
			(layers "F.Cu" "F.Mask" "F.Paste")
			(net "M_L_DQS_DN<1>")
		)
		(pad "DA84" smd circle
			(at 35.533584 12.720828)
			(size 0.4318 0.4318)
			(layers "F.Cu" "F.Mask" "F.Paste")
			(net "M_K_DQ<3>")
		)
		(pad "DA86" smd custom
			(at 37.250624 12.720828 270)
			(size 0.10795 0.10795)
			(layers "F.Cu" "F.Mask" "F.Paste")
			(net "M_K_DQ<2>")
			(options
				(clearance outline)
				(anchor circle)
			)
			(primitives
				(gr_poly
					(pts
						(arc
							(start 0.2159 -0.0381)
							(mid 0 -0.254)
							(end -0.2159 -0.0381)
						)
						(arc
							(start -0.2159 0.0381)
							(mid 0 0.254)
							(end 0.2159 0.0381)
						)
					)
					(width 0)
					(fill yes)
				)
			)
		)
		(pad "DB1" smd custom
			(at -37.250624 15.015972 90)
			(size 0.10795 0.10795)
			(layers "F.Cu" "F.Mask" "F.Paste")
			(net "TP_P3E_CPU1_PE1_MP_TXP<1>")
			(options
				(clearance outline)
				(anchor circle)
			)
			(primitives
				(gr_poly
					(pts
						(arc
							(start 0.2159 -0.0381)
							(mid 0 -0.254)
							(end -0.2159 -0.0381)
						)
						(arc
							(start -0.2159 0.0381)
							(mid 0 0.254)
							(end 0.2159 0.0381)
						)
					)
					(width 0)
					(fill yes)
				)
			)
		)
		(pad "DB3" smd circle
			(at -35.533584 15.015972)
			(size 0.4318 0.4318)
			(layers "F.Cu" "F.Mask" "F.Paste")
			(net "GND")
		)
		(pad "DB5" smd circle
			(at -33.816544 15.015972)
			(size 0.4318 0.4318)
			(layers "F.Cu" "F.Mask" "F.Paste")
			(net "P3E_CPU1_PE3_MP_TXN<14>")
		)
		(pad "DB7" smd circle
			(at -32.099504 15.015972)
			(size 0.4318 0.4318)
			(layers "F.Cu" "F.Mask" "F.Paste")
			(net "GND")
		)
		(pad "DB9" smd circle
			(at -30.382464 15.015972)
			(size 0.4318 0.4318)
			(layers "F.Cu" "F.Mask" "F.Paste")
			(net "TP_P3E_CPU1_PE1_MP_RXP<2>")
		)
		(pad "DB11" smd circle
			(at -28.665424 15.015972)
			(size 0.4318 0.4318)
			(layers "F.Cu" "F.Mask" "F.Paste")
			(net "P3E_CPU1_PE3_MP_RXN<13>")
		)
		(pad "DB13" smd circle
			(at -26.948384 15.015972)
			(size 0.4318 0.4318)
			(layers "F.Cu" "F.Mask" "F.Paste")
			(net "GND")
		)
		(pad "DB15" smd circle
			(at -25.231598 15.015972)
			(size 0.4318 0.4318)
			(layers "F.Cu" "F.Mask" "F.Paste")
			(net "TP_CPU1_UPI2_RSVD_CW16")
		)
		(pad "DB17" smd circle
			(at -23.514558 15.015972)
			(size 0.4318 0.4318)
			(layers "F.Cu" "F.Mask" "F.Paste")
			(net "GND")
		)
		(pad "DB19" smd circle
			(at -21.797518 15.015972)
			(size 0.4318 0.4318)
			(layers "F.Cu" "F.Mask" "F.Paste")
			(net "GND")
		)
		(pad "DB21" smd circle
			(at -20.080478 15.015972)
			(size 0.4318 0.4318)
			(layers "F.Cu" "F.Mask" "F.Paste")
			(net "GND")
		)
		(pad "DB23" smd circle
			(at -18.363438 15.015972)
			(size 0.4318 0.4318)
			(layers "F.Cu" "F.Mask" "F.Paste")
			(net "GND")
		)
		(pad "DB25" smd circle
			(at -16.646398 15.015972)
			(size 0.4318 0.4318)
			(layers "F.Cu" "F.Mask" "F.Paste")
			(net "GND")
		)
		(pad "DB27" smd circle
			(at -14.929612 15.015972)
			(size 0.4318 0.4318)
			(layers "F.Cu" "F.Mask" "F.Paste")
			(net "M_M_DQ<59>")
		)
		(pad "DB29" smd circle
			(at -13.212572 15.015972)
			(size 0.4318 0.4318)
			(layers "F.Cu" "F.Mask" "F.Paste")
			(net "M_M_DQS_DP<7>")
		)
		(pad "DB31" smd circle
			(at -11.495532 15.015972)
			(size 0.4318 0.4318)
			(layers "F.Cu" "F.Mask" "F.Paste")
			(net "M_M_DQ<61>")
		)
		(pad "DB33" smd circle
			(at -9.778492 15.015972)
			(size 0.4318 0.4318)
			(layers "F.Cu" "F.Mask" "F.Paste")
			(net "M_M_DQ<51>")
		)
		(pad "DB35" smd circle
			(at -8.061452 15.015972)
			(size 0.4318 0.4318)
			(layers "F.Cu" "F.Mask" "F.Paste")
			(net "M_M_DQS_DP<6>")
		)
		(pad "DB37" smd circle
			(at -6.344412 15.015972)
			(size 0.4318 0.4318)
			(layers "F.Cu" "F.Mask" "F.Paste")
			(net "M_M_DQ<53>")
		)
		(pad "DB39" smd circle
			(at -4.627626 15.015972)
			(size 0.4318 0.4318)
			(layers "F.Cu" "F.Mask" "F.Paste")
			(net "GND")
		)
		(pad "DB41" smd circle
			(at -2.910586 15.015972)
			(size 0.4318 0.4318)
			(layers "F.Cu" "F.Mask" "F.Paste")
			(net "GND")
		)
		(pad "DB45" smd circle
			(at 2.052066 13.215874)
			(size 0.4318 0.4318)
			(layers "F.Cu" "F.Mask" "F.Paste")
			(net "SVID_DIO0_CPU1")
		)
		(pad "DB47" smd circle
			(at 3.769106 13.215874)
			(size 0.4318 0.4318)
			(layers "F.Cu" "F.Mask" "F.Paste")
			(net "GND")
		)
		(pad "DB49" smd circle
			(at 5.485892 13.215874)
			(size 0.4318 0.4318)
			(layers "F.Cu" "F.Mask" "F.Paste")
			(net "GND")
		)
		(pad "DB51" smd circle
			(at 7.202932 13.215874)
			(size 0.4318 0.4318)
			(layers "F.Cu" "F.Mask" "F.Paste")
			(net "PD_CPU1_TEST13")
		)
		(pad "DB53" smd circle
			(at 8.919972 13.215874)
			(size 0.4318 0.4318)
			(layers "F.Cu" "F.Mask" "F.Paste")
			(net "PVDDQ_KLM")
		)
		(pad "DB55" smd circle
			(at 10.637012 13.215874)
			(size 0.4318 0.4318)
			(layers "F.Cu" "F.Mask" "F.Paste")
			(net "PVDDQ_KLM")
		)
		(pad "DB57" smd circle
			(at 12.354052 13.215874)
			(size 0.4318 0.4318)
			(layers "F.Cu" "F.Mask" "F.Paste")
			(net "PVDDQ_KLM")
		)
		(pad "DB59" smd circle
			(at 14.071092 13.215874)
			(size 0.4318 0.4318)
			(layers "F.Cu" "F.Mask" "F.Paste")
			(net "PVDDQ_KLM")
		)
		(pad "DB61" smd circle
			(at 15.787878 13.215874)
			(size 0.4318 0.4318)
			(layers "F.Cu" "F.Mask" "F.Paste")
			(net "PVDDQ_KLM")
		)
		(pad "DB63" smd circle
			(at 17.504918 13.215874)
			(size 0.4318 0.4318)
			(layers "F.Cu" "F.Mask" "F.Paste")
			(net "PVDDQ_KLM")
		)
		(pad "DB65" smd circle
			(at 19.221958 13.215874)
			(size 0.4318 0.4318)
			(layers "F.Cu" "F.Mask" "F.Paste")
			(net "M_K_ECC<2>")
		)
		(pad "DB67" smd circle
			(at 20.938998 13.215874)
			(size 0.4318 0.4318)
			(layers "F.Cu" "F.Mask" "F.Paste")
			(net "M_K_DQS_DN<17>")
		)
		(pad "DB69" smd circle
			(at 22.656038 13.215874)
			(size 0.4318 0.4318)
			(layers "F.Cu" "F.Mask" "F.Paste")
			(net "M_K_ECC<4>")
		)
		(pad "DB71" smd circle
			(at 24.373078 13.215874)
			(size 0.4318 0.4318)
			(layers "F.Cu" "F.Mask" "F.Paste")
			(net "FM_CPU1_PROC_ID1")
		)
		(pad "DB73" smd circle
			(at 26.090118 13.215874)
			(size 0.4318 0.4318)
			(layers "F.Cu" "F.Mask" "F.Paste")
			(net "GND")
		)
		(pad "DB75" smd circle
			(at 27.806904 13.215874)
			(size 0.4318 0.4318)
			(layers "F.Cu" "F.Mask" "F.Paste")
			(net "M_M_DQ<13>")
		)
		(pad "DB77" smd circle
			(at 29.523944 13.215874)
			(size 0.4318 0.4318)
			(layers "F.Cu" "F.Mask" "F.Paste")
			(net "GND")
		)
		(pad "DB79" smd circle
			(at 31.240984 13.215874)
			(size 0.4318 0.4318)
			(layers "F.Cu" "F.Mask" "F.Paste")
			(net "M_L_DQ<8>")
		)
		(pad "DB81" smd circle
			(at 32.958024 13.215874)
			(size 0.4318 0.4318)
			(layers "F.Cu" "F.Mask" "F.Paste")
			(net "M_L_DQS_DP<1>")
		)
		(pad "DB83" smd circle
			(at 34.675064 13.215874)
			(size 0.4318 0.4318)
			(layers "F.Cu" "F.Mask" "F.Paste")
			(net "GND")
		)
		(pad "DB85" smd circle
			(at 36.392104 13.215874)
			(size 0.4318 0.4318)
			(layers "F.Cu" "F.Mask" "F.Paste")
			(net "GND")
		)
		(pad "DC2" smd custom
			(at -36.392104 15.511526 90)
			(size 0.10795 0.10795)
			(layers "F.Cu" "F.Mask" "F.Paste")
			(net "TP_P3E_CPU1_PE1_MP_TXN<1>")
			(options
				(clearance outline)
				(anchor circle)
			)
			(primitives
				(gr_poly
					(pts
						(arc
							(start 0.2159 -0.0381)
							(mid 0 -0.254)
							(end -0.2159 -0.0381)
						)
						(arc
							(start -0.2159 0.0381)
							(mid 0 0.254)
							(end 0.2159 0.0381)
						)
					)
					(width 0)
					(fill yes)
				)
			)
		)
		(pad "DC4" smd circle
			(at -34.675064 15.511526)
			(size 0.4318 0.4318)
			(layers "F.Cu" "F.Mask" "F.Paste")
			(net "TP_P3E_CPU1_PE1_MP_TXP<3>")
		)
		(pad "DC6" smd circle
			(at -32.958024 15.511526)
			(size 0.4318 0.4318)
			(layers "F.Cu" "F.Mask" "F.Paste")
			(net "P3E_CPU1_PE3_MP_TXP<13>")
		)
		(pad "DC8" smd circle
			(at -31.240984 15.511526)
			(size 0.4318 0.4318)
			(layers "F.Cu" "F.Mask" "F.Paste")
			(net "TP_P3E_CPU1_PE1_MP_RXN<2>")
		)
		(pad "DC10" smd circle
			(at -29.523944 15.511526)
			(size 0.4318 0.4318)
			(layers "F.Cu" "F.Mask" "F.Paste")
			(net "TP_P3E_CPU1_PE1_MP_RXN<3>")
		)
		(pad "DC12" smd circle
			(at -27.806904 15.511526)
			(size 0.4318 0.4318)
			(layers "F.Cu" "F.Mask" "F.Paste")
			(net "P3E_CPU1_PE3_MP_RXN<12>")
		)
		(pad "DC14" smd circle
			(at -26.090118 15.511526)
			(size 0.4318 0.4318)
			(layers "F.Cu" "F.Mask" "F.Paste")
			(net "GND")
		)
		(pad "DC16" smd circle
			(at -24.373078 15.511526)
			(size 0.4318 0.4318)
			(layers "F.Cu" "F.Mask" "F.Paste")
			(net "TP_CPU1_UPI2_RSVD_DA16")
		)
		(pad "DC18" smd circle
			(at -22.656038 15.511526)
			(size 0.4318 0.4318)
			(layers "F.Cu" "F.Mask" "F.Paste")
			(net "PVCCIO_CPU1")
		)
		(pad "DC20" smd circle
			(at -20.938998 15.511526)
			(size 0.4318 0.4318)
			(layers "F.Cu" "F.Mask" "F.Paste")
			(net "GND")
		)
		(pad "DC22" smd circle
			(at -19.221958 15.511526)
			(size 0.4318 0.4318)
			(layers "F.Cu" "F.Mask" "F.Paste")
			(net "GND")
		)
		(pad "DC24" smd circle
			(at -17.504918 15.511526)
			(size 0.4318 0.4318)
			(layers "F.Cu" "F.Mask" "F.Paste")
			(net "GND")
		)
		(pad "DC26" smd circle
			(at -15.787878 15.511526)
			(size 0.4318 0.4318)
			(layers "F.Cu" "F.Mask" "F.Paste")
			(net "GND")
		)
		(pad "DC28" smd circle
			(at -14.071092 15.511526)
			(size 0.4318 0.4318)
			(layers "F.Cu" "F.Mask" "F.Paste")
			(net "M_M_DQ<63>")
		)
		(pad "DC30" smd circle
			(at -12.354052 15.511526)
			(size 0.4318 0.4318)
			(layers "F.Cu" "F.Mask" "F.Paste")
			(net "M_M_DQ<57>")
		)
		(pad "DC32" smd circle
			(at -10.637012 15.511526)
			(size 0.4318 0.4318)
			(layers "F.Cu" "F.Mask" "F.Paste")
			(net "GND")
		)
		(pad "DC34" smd circle
			(at -8.919972 15.511526)
			(size 0.4318 0.4318)
			(layers "F.Cu" "F.Mask" "F.Paste")
			(net "M_M_DQ<55>")
		)
		(pad "DC36" smd circle
			(at -7.202932 15.511526)
			(size 0.4318 0.4318)
			(layers "F.Cu" "F.Mask" "F.Paste")
			(net "M_M_DQ<49>")
		)
		(pad "DC38" smd circle
			(at -5.485892 15.511526)
			(size 0.4318 0.4318)
			(layers "F.Cu" "F.Mask" "F.Paste")
			(net "GND")
		)
		(pad "DC40" smd circle
			(at -3.769106 15.511526)
			(size 0.4318 0.4318)
			(layers "F.Cu" "F.Mask" "F.Paste")
			(net "M_M_DQS_DP<13>")
		)
		(pad "DC42" smd circle
			(at -2.052066 15.511526)
			(size 0.4318 0.4318)
			(layers "F.Cu" "F.Mask" "F.Paste")
			(net "GND")
		)
		(pad "DC44" smd circle
			(at 1.193546 13.711428)
			(size 0.508 0.508)
			(layers "F.Cu" "F.Mask" "F.Paste")
			(net "SVID_CLK0_CPU1")
		)
		(pad "DC46" smd circle
			(at 2.910586 13.711428)
			(size 0.4318 0.4318)
			(layers "F.Cu" "F.Mask" "F.Paste")
			(net "TP_CPU1_RSVD_47")
		)
		(pad "DC48" smd circle
			(at 4.627626 13.711428)
			(size 0.4318 0.4318)
			(layers "F.Cu" "F.Mask" "F.Paste")
			(net "A_CPU1_KLM_RCOMP0")
		)
		(pad "DC50" smd circle
			(at 6.344412 13.711428)
			(size 0.4318 0.4318)
			(layers "F.Cu" "F.Mask" "F.Paste")
			(net "PD_CPU1_TEST14")
		)
		(pad "DC52" smd circle
			(at 8.061452 13.711428)
			(size 0.4318 0.4318)
			(layers "F.Cu" "F.Mask" "F.Paste")
			(net "TP_CPU1_RSVD_46")
		)
		(pad "DC54" smd circle
			(at 9.778492 13.711428)
			(size 0.4318 0.4318)
			(layers "F.Cu" "F.Mask" "F.Paste")
			(net "M_M_MA<15>")
		)
		(pad "DC56" smd circle
			(at 11.495532 13.711428)
			(size 0.4318 0.4318)
			(layers "F.Cu" "F.Mask" "F.Paste")
			(net "M_M_BA<1>")
		)
		(pad "DC58" smd circle
			(at 13.212572 13.711428)
			(size 0.4318 0.4318)
			(layers "F.Cu" "F.Mask" "F.Paste")
			(net "M_M_MA<1>")
		)
		(pad "DC60" smd circle
			(at 14.929612 13.711428)
			(size 0.4318 0.4318)
			(layers "F.Cu" "F.Mask" "F.Paste")
			(net "M_M_MA<7>")
		)
		(pad "DC62" smd circle
			(at 16.646398 13.711428)
			(size 0.4318 0.4318)
			(layers "F.Cu" "F.Mask" "F.Paste")
			(net "M_M_ACT_N")
		)
		(pad "DC64" smd circle
			(at 18.363438 13.711428)
			(size 0.4318 0.4318)
			(layers "F.Cu" "F.Mask" "F.Paste")
			(net "GND")
		)
		(pad "DC66" smd circle
			(at 20.080478 13.711428)
			(size 0.4318 0.4318)
			(layers "F.Cu" "F.Mask" "F.Paste")
			(net "GND")
		)
		(pad "DC68" smd circle
			(at 21.797518 13.711428)
			(size 0.4318 0.4318)
			(layers "F.Cu" "F.Mask" "F.Paste")
			(net "GND")
		)
		(pad "DC70" smd circle
			(at 23.514558 13.711428)
			(size 0.4318 0.4318)
			(layers "F.Cu" "F.Mask" "F.Paste")
			(net "GND")
		)
		(pad "DC72" smd circle
			(at 25.231598 13.711428)
			(size 0.4318 0.4318)
			(layers "F.Cu" "F.Mask" "F.Paste")
			(net "FM_CPU1_PKGID0")
		)
		(pad "DC74" smd circle
			(at 26.948384 13.711428)
			(size 0.4318 0.4318)
			(layers "F.Cu" "F.Mask" "F.Paste")
			(net "M_M_DQ<12>")
		)
		(pad "DC76" smd circle
			(at 28.665424 13.711428)
			(size 0.4318 0.4318)
			(layers "F.Cu" "F.Mask" "F.Paste")
			(net "M_M_DQ<9>")
		)
		(pad "DC78" smd circle
			(at 30.382464 13.711428)
			(size 0.4318 0.4318)
			(layers "F.Cu" "F.Mask" "F.Paste")
			(net "GND")
		)
		(pad "DC80" smd circle
			(at 32.099504 13.711428)
			(size 0.4318 0.4318)
			(layers "F.Cu" "F.Mask" "F.Paste")
			(net "M_L_DQS_DN<10>")
		)
		(pad "DC82" smd circle
			(at 33.816544 13.711428)
			(size 0.4318 0.4318)
			(layers "F.Cu" "F.Mask" "F.Paste")
			(net "M_L_DQ<14>")
		)
		(pad "DC84" smd circle
			(at 35.533584 13.711428)
			(size 0.4318 0.4318)
			(layers "F.Cu" "F.Mask" "F.Paste")
			(net "GND")
		)
		(pad "DC86" smd custom
			(at 37.250624 13.711428 270)
			(size 0.10795 0.10795)
			(layers "F.Cu" "F.Mask" "F.Paste")
			(net "GND")
			(options
				(clearance outline)
				(anchor circle)
			)
			(primitives
				(gr_poly
					(pts
						(arc
							(start 0.2159 -0.0381)
							(mid 0 -0.254)
							(end -0.2159 -0.0381)
						)
						(arc
							(start -0.2159 0.0381)
							(mid 0 0.254)
							(end 0.2159 0.0381)
						)
					)
					(width 0)
					(fill yes)
				)
			)
		)
		(pad "DD3" smd circle
			(at -35.533584 16.006572)
			(size 0.4318 0.4318)
			(layers "F.Cu" "F.Mask" "F.Paste")
			(net "TP_P3E_CPU1_PE1_MP_TXP<2>")
		)
		(pad "DD5" smd circle
			(at -33.816544 16.006572)
			(size 0.4318 0.4318)
			(layers "F.Cu" "F.Mask" "F.Paste")
			(net "P3E_CPU1_PE3_MP_TXN<13>")
		)
		(pad "DD7" smd circle
			(at -32.099504 16.006572)
			(size 0.4318 0.4318)
			(layers "F.Cu" "F.Mask" "F.Paste")
			(net "PVCCIO_CPU1")
		)
		(pad "DD9" smd circle
			(at -30.382464 16.006572)
			(size 0.4318 0.4318)
			(layers "F.Cu" "F.Mask" "F.Paste")
			(net "TP_P3E_CPU1_PE1_MP_RXP<4>")
		)
		(pad "DD11" smd circle
			(at -28.665424 16.006572)
			(size 0.4318 0.4318)
			(layers "F.Cu" "F.Mask" "F.Paste")
			(net "GND")
		)
		(pad "DD13" smd circle
			(at -26.948384 16.006572)
			(size 0.4318 0.4318)
			(layers "F.Cu" "F.Mask" "F.Paste")
			(net "P3E_CPU1_PE3_MP_RXP<12>")
		)
		(pad "DD15" smd circle
			(at -25.231598 16.006572)
			(size 0.4318 0.4318)
			(layers "F.Cu" "F.Mask" "F.Paste")
			(net "TP_CPU1_UPI2_RSVD_CV13")
		)
		(pad "DD17" smd circle
			(at -23.514558 16.006572)
			(size 0.4318 0.4318)
			(layers "F.Cu" "F.Mask" "F.Paste")
			(net "TP_CPU1_UPI2_RSVD_CU14")
		)
		(pad "DD19" smd circle
			(at -21.797518 16.006572)
			(size 0.4318 0.4318)
			(layers "F.Cu" "F.Mask" "F.Paste")
			(net "GND")
		)
		(pad "DD21" smd circle
			(at -20.080478 16.006572)
			(size 0.4318 0.4318)
			(layers "F.Cu" "F.Mask" "F.Paste")
			(net "GND")
		)
		(pad "DD23" smd circle
			(at -18.363438 16.006572)
			(size 0.4318 0.4318)
			(layers "F.Cu" "F.Mask" "F.Paste")
			(net "GND")
		)
		(pad "DD25" smd circle
			(at -16.646398 16.006572)
			(size 0.4318 0.4318)
			(layers "F.Cu" "F.Mask" "F.Paste")
			(net "M_L_DQ<58>")
		)
		(pad "DD27" smd circle
			(at -14.929612 16.006572)
			(size 0.4318 0.4318)
			(layers "F.Cu" "F.Mask" "F.Paste")
			(net "GND")
		)
		(pad "DD29" smd circle
			(at -13.212572 16.006572)
			(size 0.4318 0.4318)
			(layers "F.Cu" "F.Mask" "F.Paste")
			(net "M_M_DQS_DN<7>")
		)
		(pad "DD31" smd circle
			(at -11.495532 16.006572)
			(size 0.4318 0.4318)
			(layers "F.Cu" "F.Mask" "F.Paste")
			(net "GND")
		)
		(pad "DD33" smd circle
			(at -9.778492 16.006572)
			(size 0.4318 0.4318)
			(layers "F.Cu" "F.Mask" "F.Paste")
			(net "GND")
		)
		(pad "DD35" smd circle
			(at -8.061452 16.006572)
			(size 0.4318 0.4318)
			(layers "F.Cu" "F.Mask" "F.Paste")
			(net "M_M_DQS_DN<6>")
		)
		(pad "DD37" smd circle
			(at -6.344412 16.006572)
			(size 0.4318 0.4318)
			(layers "F.Cu" "F.Mask" "F.Paste")
			(net "GND")
		)
		(pad "DD39" smd circle
			(at -4.627626 16.006572)
			(size 0.4318 0.4318)
			(layers "F.Cu" "F.Mask" "F.Paste")
			(net "M_M_DQ<38>")
		)
		(pad "DD41" smd circle
			(at -2.910586 16.006572)
			(size 0.4318 0.4318)
			(layers "F.Cu" "F.Mask" "F.Paste")
			(net "M_M_DQ<32>")
		)
		(pad "DD45" smd circle
			(at 2.052066 14.206474)
			(size 0.4318 0.4318)
			(layers "F.Cu" "F.Mask" "F.Paste")
			(net "PVDDQ_KLM")
		)
		(pad "DD47" smd circle
			(at 3.769106 14.206474)
			(size 0.4318 0.4318)
			(layers "F.Cu" "F.Mask" "F.Paste")
			(net "A_CPU1_KLM_RCOMP1")
		)
		(pad "DD49" smd circle
			(at 5.485892 14.206474)
			(size 0.4318 0.4318)
			(layers "F.Cu" "F.Mask" "F.Paste")
			(net "A_CPU1_KLM_RCOMP2")
		)
		(pad "DD51" smd circle
			(at 7.202932 14.206474)
			(size 0.4318 0.4318)
			(layers "F.Cu" "F.Mask" "F.Paste")
			(net "TP_CPU1_RSVD_45")
		)
		(pad "DD53" smd circle
			(at 8.919972 14.206474)
			(size 0.4318 0.4318)
			(layers "F.Cu" "F.Mask" "F.Paste")
			(net "M_M_MA<13>")
		)
		(pad "DD55" smd circle
			(at 10.637012 14.206474)
			(size 0.4318 0.4318)
			(layers "F.Cu" "F.Mask" "F.Paste")
			(net "M_M_MA<10>")
		)
		(pad "DD57" smd circle
			(at 12.354052 14.206474)
			(size 0.4318 0.4318)
			(layers "F.Cu" "F.Mask" "F.Paste")
			(net "M_M_MA<2>")
		)
		(pad "DD59" smd circle
			(at 14.071092 14.206474)
			(size 0.4318 0.4318)
			(layers "F.Cu" "F.Mask" "F.Paste")
			(net "M_M_MA<8>")
		)
		(pad "DD61" smd circle
			(at 15.787878 14.206474)
			(size 0.4318 0.4318)
			(layers "F.Cu" "F.Mask" "F.Paste")
			(net "M_M_ALERT_N")
		)
		(pad "DD63" smd circle
			(at 17.504918 14.206474)
			(size 0.4318 0.4318)
			(layers "F.Cu" "F.Mask" "F.Paste")
			(net "M_M_CKE<1>")
		)
		(pad "DD65" smd circle
			(at 19.221958 14.206474)
			(size 0.4318 0.4318)
			(layers "F.Cu" "F.Mask" "F.Paste")
			(net "M_K_ECC<3>")
		)
		(pad "DD67" smd circle
			(at 20.938998 14.206474)
			(size 0.4318 0.4318)
			(layers "F.Cu" "F.Mask" "F.Paste")
			(net "M_K_DQS_DP<8>")
		)
		(pad "DD69" smd circle
			(at 22.656038 14.206474)
			(size 0.4318 0.4318)
			(layers "F.Cu" "F.Mask" "F.Paste")
			(net "M_K_ECC<5>")
		)
		(pad "DD71" smd circle
			(at 24.373078 14.206474)
			(size 0.4318 0.4318)
			(layers "F.Cu" "F.Mask" "F.Paste")
			(net "GND")
		)
		(pad "DD73" smd circle
			(at 26.090118 14.206474)
			(size 0.4318 0.4318)
			(layers "F.Cu" "F.Mask" "F.Paste")
			(net "GND")
		)
		(pad "DD75" smd circle
			(at 27.806904 14.206474)
			(size 0.4318 0.4318)
			(layers "F.Cu" "F.Mask" "F.Paste")
			(net "GND")
		)
		(pad "DD77" smd circle
			(at 29.523944 14.206474)
			(size 0.4318 0.4318)
			(layers "F.Cu" "F.Mask" "F.Paste")
			(net "M_M_DQS_DN<1>")
		)
		(pad "DD79" smd circle
			(at 31.240984 14.206474)
			(size 0.4318 0.4318)
			(layers "F.Cu" "F.Mask" "F.Paste")
			(net "M_L_DQS_DP<10>")
		)
		(pad "DD81" smd circle
			(at 32.958024 14.206474)
			(size 0.4318 0.4318)
			(layers "F.Cu" "F.Mask" "F.Paste")
			(net "GND")
		)
		(pad "DD83" smd circle
			(at 34.675064 14.206474)
			(size 0.4318 0.4318)
			(layers "F.Cu" "F.Mask" "F.Paste")
			(net "GND")
		)
		(pad "DD85" smd custom
			(at 36.392104 14.206474 270)
			(size 0.10795 0.10795)
			(layers "F.Cu" "F.Mask" "F.Paste")
			(net "M_K_DQ<12>")
			(options
				(clearance outline)
				(anchor circle)
			)
			(primitives
				(gr_poly
					(pts
						(arc
							(start 0.2159 -0.0381)
							(mid 0 -0.254)
							(end -0.2159 -0.0381)
						)
						(arc
							(start -0.2159 0.0381)
							(mid 0 0.254)
							(end 0.2159 0.0381)
						)
					)
					(width 0)
					(fill yes)
				)
			)
		)
		(pad "DE2" smd custom
			(at -36.392104 16.502126 90)
			(size 0.10795 0.10795)
			(layers "F.Cu" "F.Mask" "F.Paste")
			(net "TP_P3E_CPU1_PE1_MP_TXN<2>")
			(options
				(clearance outline)
				(anchor circle)
			)
			(primitives
				(gr_poly
					(pts
						(arc
							(start 0.2159 -0.0381)
							(mid 0 -0.254)
							(end -0.2159 -0.0381)
						)
						(arc
							(start -0.2159 0.0381)
							(mid 0 0.254)
							(end 0.2159 0.0381)
						)
					)
					(width 0)
					(fill yes)
				)
			)
		)
		(pad "DE4" smd circle
			(at -34.675064 16.502126)
			(size 0.4318 0.4318)
			(layers "F.Cu" "F.Mask" "F.Paste")
			(net "TP_P3E_CPU1_PE1_MP_TXN<3>")
		)
		(pad "DE6" smd circle
			(at -32.958024 16.502126)
			(size 0.4318 0.4318)
			(layers "F.Cu" "F.Mask" "F.Paste")
			(net "GND")
		)
		(pad "DE8" smd circle
			(at -31.240984 16.502126)
			(size 0.4318 0.4318)
			(layers "F.Cu" "F.Mask" "F.Paste")
			(net "GND")
		)
		(pad "DE10" smd circle
			(at -29.523944 16.502126)
			(size 0.4318 0.4318)
			(layers "F.Cu" "F.Mask" "F.Paste")
			(net "TP_P3E_CPU1_PE1_MP_RXN<4>")
		)
		(pad "DE12" smd circle
			(at -27.806904 16.502126)
			(size 0.4318 0.4318)
			(layers "F.Cu" "F.Mask" "F.Paste")
			(net "P3E_CPU1_PE3_MP_RXP<10>")
		)
		(pad "DE14" smd circle
			(at -26.090118 16.502126)
			(size 0.4318 0.4318)
			(layers "F.Cu" "F.Mask" "F.Paste")
			(net "PVCCIO_CPU1")
		)
		(pad "DE16" smd circle
			(at -24.373078 16.502126)
			(size 0.4318 0.4318)
			(layers "F.Cu" "F.Mask" "F.Paste")
			(net "TP_CPU1_UPI2_RSVD_CR14")
		)
		(pad "DE18" smd circle
			(at -22.656038 16.502126)
			(size 0.4318 0.4318)
			(layers "F.Cu" "F.Mask" "F.Paste")
			(net "GND")
		)
		(pad "DE20" smd circle
			(at -20.938998 16.502126)
			(size 0.4318 0.4318)
			(layers "F.Cu" "F.Mask" "F.Paste")
			(net "GND")
		)
		(pad "DE22" smd circle
			(at -19.221958 16.502126)
			(size 0.4318 0.4318)
			(layers "F.Cu" "F.Mask" "F.Paste")
			(net "GND")
		)
		(pad "DE24" smd circle
			(at -17.504918 16.502126)
			(size 0.4318 0.4318)
			(layers "F.Cu" "F.Mask" "F.Paste")
			(net "GND")
		)
		(pad "DE26" smd circle
			(at -15.787878 16.502126)
			(size 0.4318 0.4318)
			(layers "F.Cu" "F.Mask" "F.Paste")
			(net "M_L_DQS_DP<16>")
		)
		(pad "DE28" smd circle
			(at -14.071092 16.502126)
			(size 0.4318 0.4318)
			(layers "F.Cu" "F.Mask" "F.Paste")
			(net "GND")
		)
		(pad "DE30" smd circle
			(at -12.354052 16.502126)
			(size 0.4318 0.4318)
			(layers "F.Cu" "F.Mask" "F.Paste")
			(net "GND")
		)
		(pad "DE32" smd circle
			(at -10.637012 16.502126)
			(size 0.4318 0.4318)
			(layers "F.Cu" "F.Mask" "F.Paste")
			(net "M_M_DQS_DP<14>")
		)
		(pad "DE34" smd circle
			(at -8.919972 16.502126)
			(size 0.4318 0.4318)
			(layers "F.Cu" "F.Mask" "F.Paste")
			(net "GND")
		)
		(pad "DE36" smd circle
			(at -7.202932 16.502126)
			(size 0.4318 0.4318)
			(layers "F.Cu" "F.Mask" "F.Paste")
			(net "GND")
		)
		(pad "DE38" smd circle
			(at -5.485892 16.502126)
			(size 0.4318 0.4318)
			(layers "F.Cu" "F.Mask" "F.Paste")
			(net "M_M_DQ<34>")
		)
		(pad "DE40" smd circle
			(at -3.769106 16.502126)
			(size 0.4318 0.4318)
			(layers "F.Cu" "F.Mask" "F.Paste")
			(net "M_M_DQS_DN<13>")
		)
		(pad "DE42" smd circle
			(at -2.052066 16.502126)
			(size 0.4318 0.4318)
			(layers "F.Cu" "F.Mask" "F.Paste")
			(net "M_M_DQ<37>")
		)
		(pad "DE44" smd circle
			(at 1.193546 14.702028)
			(size 0.508 0.508)
			(layers "F.Cu" "F.Mask" "F.Paste")
			(net "SVID_ALERT0_CPU1_N")
		)
		(pad "DE46" smd circle
			(at 2.910586 14.702028)
			(size 0.4318 0.4318)
			(layers "F.Cu" "F.Mask" "F.Paste")
			(net "M_M_MA<17>")
		)
		(pad "DE48" smd circle
			(at 4.627626 14.702028)
			(size 0.4318 0.4318)
			(layers "F.Cu" "F.Mask" "F.Paste")
			(net "GND")
		)
		(pad "DE50" smd circle
			(at 6.344412 14.702028)
			(size 0.4318 0.4318)
			(layers "F.Cu" "F.Mask" "F.Paste")
			(net "GND")
		)
		(pad "DE52" smd circle
			(at 8.061452 14.702028)
			(size 0.4318 0.4318)
			(layers "F.Cu" "F.Mask" "F.Paste")
			(net "GND")
		)
		(pad "DE54" smd circle
			(at 9.778492 14.702028)
			(size 0.4318 0.4318)
			(layers "F.Cu" "F.Mask" "F.Paste")
			(net "GND")
		)
		(pad "DE56" smd circle
			(at 11.495532 14.702028)
			(size 0.4318 0.4318)
			(layers "F.Cu" "F.Mask" "F.Paste")
			(net "GND")
		)
		(pad "DE58" smd circle
			(at 13.212572 14.702028)
			(size 0.4318 0.4318)
			(layers "F.Cu" "F.Mask" "F.Paste")
			(net "GND")
		)
		(pad "DE60" smd circle
			(at 14.929612 14.702028)
			(size 0.4318 0.4318)
			(layers "F.Cu" "F.Mask" "F.Paste")
			(net "GND")
		)
		(pad "DE62" smd circle
			(at 16.646398 14.702028)
			(size 0.4318 0.4318)
			(layers "F.Cu" "F.Mask" "F.Paste")
			(net "GND")
		)
		(pad "DE64" smd circle
			(at 18.363438 14.702028)
			(size 0.4318 0.4318)
			(layers "F.Cu" "F.Mask" "F.Paste")
			(net "GND")
		)
		(pad "DE66" smd circle
			(at 20.080478 14.702028)
			(size 0.4318 0.4318)
			(layers "F.Cu" "F.Mask" "F.Paste")
			(net "M_K_ECC<7>")
		)
		(pad "DE68" smd circle
			(at 21.797518 14.702028)
			(size 0.4318 0.4318)
			(layers "F.Cu" "F.Mask" "F.Paste")
			(net "M_K_ECC<1>")
		)
		(pad "DE70" smd circle
			(at 23.514558 14.702028)
			(size 0.4318 0.4318)
			(layers "F.Cu" "F.Mask" "F.Paste")
			(net "GND")
		)
		(pad "DE72" smd circle
			(at 25.231598 14.702028)
			(size 0.4318 0.4318)
			(layers "F.Cu" "F.Mask" "F.Paste")
			(net "GND")
		)
		(pad "DE74" smd circle
			(at 26.948384 14.702028)
			(size 0.4318 0.4318)
			(layers "F.Cu" "F.Mask" "F.Paste")
			(net "M_M_DQ<8>")
		)
		(pad "DE76" smd circle
			(at 28.665424 14.702028)
			(size 0.4318 0.4318)
			(layers "F.Cu" "F.Mask" "F.Paste")
			(net "M_M_DQS_DP<1>")
		)
		(pad "DE78" smd circle
			(at 30.382464 14.702028)
			(size 0.4318 0.4318)
			(layers "F.Cu" "F.Mask" "F.Paste")
			(net "GND")
		)
		(pad "DE80" smd circle
			(at 32.099504 14.702028)
			(size 0.4318 0.4318)
			(layers "F.Cu" "F.Mask" "F.Paste")
			(net "M_L_DQ<10>")
		)
		(pad "DE82" smd circle
			(at 33.816544 14.702028)
			(size 0.4318 0.4318)
			(layers "F.Cu" "F.Mask" "F.Paste")
			(net "M_L_DQ<15>")
		)
		(pad "DE84" smd circle
			(at 35.533584 14.702028)
			(size 0.4318 0.4318)
			(layers "F.Cu" "F.Mask" "F.Paste")
			(net "M_K_DQ<13>")
		)
		(pad "DF3" smd circle
			(at -35.533584 16.997172)
			(size 0.4318 0.4318)
			(layers "F.Cu" "F.Mask" "F.Paste")
			(net "TP_P3E_CPU1_PE1_MP_TXP<4>")
		)
		(pad "DF5" smd circle
			(at -33.816544 16.997172)
			(size 0.4318 0.4318)
			(layers "F.Cu" "F.Mask" "F.Paste")
			(net "GND")
		)
		(pad "DF7" smd circle
			(at -32.099504 16.997172)
			(size 0.4318 0.4318)
			(layers "F.Cu" "F.Mask" "F.Paste")
			(net "GND")
		)
		(pad "DF9" smd circle
			(at -30.382464 16.997172)
			(size 0.4318 0.4318)
			(layers "F.Cu" "F.Mask" "F.Paste")
			(net "TP_P3E_CPU1_PE1_MP_RXP<5>")
		)
		(pad "DF11" smd circle
			(at -28.665424 16.997172)
			(size 0.4318 0.4318)
			(layers "F.Cu" "F.Mask" "F.Paste")
			(net "P3E_CPU1_PE3_MP_RXP<11>")
		)
		(pad "DF13" smd circle
			(at -26.948384 16.997172)
			(size 0.4318 0.4318)
			(layers "F.Cu" "F.Mask" "F.Paste")
			(net "PVCCIO_CPU1")
		)
		(pad "DF15" smd circle
			(at -25.231598 16.997172)
			(size 0.4318 0.4318)
			(layers "F.Cu" "F.Mask" "F.Paste")
			(net "TP_CPU1_UPI2_RSVD_CW14")
		)
		(pad "DF17" smd circle
			(at -23.514558 16.997172)
			(size 0.4318 0.4318)
			(layers "F.Cu" "F.Mask" "F.Paste")
			(net "TP_CPU1_UPI2_RSVD_CK13")
		)
		(pad "DF19" smd circle
			(at -21.797518 16.997172)
			(size 0.4318 0.4318)
			(layers "F.Cu" "F.Mask" "F.Paste")
			(net "GND")
		)
		(pad "DF21" smd circle
			(at -20.080478 16.997172)
			(size 0.4318 0.4318)
			(layers "F.Cu" "F.Mask" "F.Paste")
			(net "PVCCIO_CPU1")
		)
		(pad "DF23" smd circle
			(at -18.363438 16.997172)
			(size 0.4318 0.4318)
			(layers "F.Cu" "F.Mask" "F.Paste")
			(net "GND")
		)
		(pad "DF25" smd circle
			(at -16.646398 16.997172)
			(size 0.4318 0.4318)
			(layers "F.Cu" "F.Mask" "F.Paste")
			(net "M_L_DQ<62>")
		)
		(pad "DF27" smd circle
			(at -14.929612 16.997172)
			(size 0.4318 0.4318)
			(layers "F.Cu" "F.Mask" "F.Paste")
			(net "M_L_DQ<56>")
		)
		(pad "DF29" smd circle
			(at -13.212572 16.997172)
			(size 0.4318 0.4318)
			(layers "F.Cu" "F.Mask" "F.Paste")
			(net "GND")
		)
		(pad "DF31" smd circle
			(at -11.495532 16.997172)
			(size 0.4318 0.4318)
			(layers "F.Cu" "F.Mask" "F.Paste")
			(net "M_M_DQ<46>")
		)
		(pad "DF33" smd circle
			(at -9.778492 16.997172)
			(size 0.4318 0.4318)
			(layers "F.Cu" "F.Mask" "F.Paste")
			(net "M_M_DQ<40>")
		)
		(pad "DF35" smd circle
			(at -8.061452 16.997172)
			(size 0.4318 0.4318)
			(layers "F.Cu" "F.Mask" "F.Paste")
			(net "GND")
		)
		(pad "DF37" smd circle
			(at -6.344412 16.997172)
			(size 0.4318 0.4318)
			(layers "F.Cu" "F.Mask" "F.Paste")
			(net "GND")
		)
		(pad "DF39" smd circle
			(at -4.627626 16.997172)
			(size 0.4318 0.4318)
			(layers "F.Cu" "F.Mask" "F.Paste")
			(net "GND")
		)
		(pad "DF41" smd circle
			(at -2.910586 16.997172)
			(size 0.4318 0.4318)
			(layers "F.Cu" "F.Mask" "F.Paste")
			(net "GND")
		)
		(pad "DF45" smd circle
			(at 2.052066 15.197074)
			(size 0.4318 0.4318)
			(layers "F.Cu" "F.Mask" "F.Paste")
			(net "M_M_C<2>")
		)
		(pad "DF47" smd circle
			(at 3.769106 15.197074)
			(size 0.4318 0.4318)
			(layers "F.Cu" "F.Mask" "F.Paste")
			(net "M_M_ODT<3>")
		)
		(pad "DF49" smd circle
			(at 5.485892 15.197074)
			(size 0.4318 0.4318)
			(layers "F.Cu" "F.Mask" "F.Paste")
			(net "M_M_CS_N<1>")
		)
		(pad "DF51" smd circle
			(at 7.202932 15.197074)
			(size 0.4318 0.4318)
			(layers "F.Cu" "F.Mask" "F.Paste")
			(net "M_M_CS_N<4>")
		)
		(pad "DF53" smd circle
			(at 8.919972 15.197074)
			(size 0.4318 0.4318)
			(layers "F.Cu" "F.Mask" "F.Paste")
			(net "M_M_MA<0>")
		)
		(pad "DF55" smd circle
			(at 10.637012 15.197074)
			(size 0.4318 0.4318)
			(layers "F.Cu" "F.Mask" "F.Paste")
			(net "M_M_CLK_DN<1>")
		)
		(pad "DF57" smd circle
			(at 12.354052 15.197074)
			(size 0.4318 0.4318)
			(layers "F.Cu" "F.Mask" "F.Paste")
			(net "M_M_CLK_DN<3>")
		)
		(pad "DF59" smd circle
			(at 14.071092 15.197074)
			(size 0.4318 0.4318)
			(layers "F.Cu" "F.Mask" "F.Paste")
			(net "M_M_MA<5>")
		)
		(pad "DF61" smd circle
			(at 15.787878 15.197074)
			(size 0.4318 0.4318)
			(layers "F.Cu" "F.Mask" "F.Paste")
			(net "M_M_BG<1>")
		)
		(pad "DF63" smd circle
			(at 17.504918 15.197074)
			(size 0.4318 0.4318)
			(layers "F.Cu" "F.Mask" "F.Paste")
			(net "M_M_CKE<3>")
		)
		(pad "DF65" smd circle
			(at 19.221958 15.197074)
			(size 0.4318 0.4318)
			(layers "F.Cu" "F.Mask" "F.Paste")
			(net "GND")
		)
		(pad "DF67" smd circle
			(at 20.938998 15.197074)
			(size 0.4318 0.4318)
			(layers "F.Cu" "F.Mask" "F.Paste")
			(net "M_K_DQS_DN<8>")
		)
		(pad "DF69" smd circle
			(at 22.656038 15.197074)
			(size 0.4318 0.4318)
			(layers "F.Cu" "F.Mask" "F.Paste")
			(net "GND")
		)
		(pad "DF71" smd circle
			(at 24.373078 15.197074)
			(size 0.4318 0.4318)
			(layers "F.Cu" "F.Mask" "F.Paste")
			(net "M_M_DQ<20>")
		)
		(pad "DF73" smd circle
			(at 26.090118 15.197074)
			(size 0.4318 0.4318)
			(layers "F.Cu" "F.Mask" "F.Paste")
			(net "GND")
		)
		(pad "DF75" smd circle
			(at 27.806904 15.197074)
			(size 0.4318 0.4318)
			(layers "F.Cu" "F.Mask" "F.Paste")
			(net "M_M_DQS_DN<10>")
		)
		(pad "DF77" smd circle
			(at 29.523944 15.197074)
			(size 0.4318 0.4318)
			(layers "F.Cu" "F.Mask" "F.Paste")
			(net "M_M_DQ<14>")
		)
		(pad "DF79" smd circle
			(at 31.240984 15.197074)
			(size 0.4318 0.4318)
			(layers "F.Cu" "F.Mask" "F.Paste")
			(net "GND")
		)
		(pad "DF81" smd circle
			(at 32.958024 15.197074)
			(size 0.4318 0.4318)
			(layers "F.Cu" "F.Mask" "F.Paste")
			(net "M_L_DQ<11>")
		)
		(pad "DF83" smd circle
			(at 34.675064 15.197074)
			(size 0.4318 0.4318)
			(layers "F.Cu" "F.Mask" "F.Paste")
			(net "GND")
		)
		(pad "DF85" smd custom
			(at 36.392104 15.197074 270)
			(size 0.10795 0.10795)
			(layers "F.Cu" "F.Mask" "F.Paste")
			(net "GND")
			(options
				(clearance outline)
				(anchor circle)
			)
			(primitives
				(gr_poly
					(pts
						(arc
							(start 0.2159 -0.0381)
							(mid 0 -0.254)
							(end -0.2159 -0.0381)
						)
						(arc
							(start -0.2159 0.0381)
							(mid 0 0.254)
							(end 0.2159 0.0381)
						)
					)
					(width 0)
					(fill yes)
				)
			)
		)
		(pad "DG2" smd custom
			(at -36.392104 17.492726 90)
			(size 0.10795 0.10795)
			(layers "F.Cu" "F.Mask" "F.Paste")
			(net "GND")
			(options
				(clearance outline)
				(anchor circle)
			)
			(primitives
				(gr_poly
					(pts
						(arc
							(start 0.2159 -0.0381)
							(mid 0 -0.254)
							(end -0.2159 -0.0381)
						)
						(arc
							(start -0.2159 0.0381)
							(mid 0 0.254)
							(end 0.2159 0.0381)
						)
					)
					(width 0)
					(fill yes)
				)
			)
		)
		(pad "DG4" smd circle
			(at -34.675064 17.492726)
			(size 0.4318 0.4318)
			(layers "F.Cu" "F.Mask" "F.Paste")
			(net "TP_P3E_CPU1_PE1_MP_TXN<4>")
		)
		(pad "DG6" smd circle
			(at -32.958024 17.492726)
			(size 0.4318 0.4318)
			(layers "F.Cu" "F.Mask" "F.Paste")
			(net "P3E_CPU1_PE3_MP_TXP<12>")
		)
		(pad "DG8" smd circle
			(at -31.240984 17.492726)
			(size 0.4318 0.4318)
			(layers "F.Cu" "F.Mask" "F.Paste")
			(net "PVCCIO_CPU1")
		)
		(pad "DG10" smd circle
			(at -29.523944 17.492726)
			(size 0.4318 0.4318)
			(layers "F.Cu" "F.Mask" "F.Paste")
			(net "P3E_CPU1_PE3_MP_RXN<11>")
		)
		(pad "DG12" smd circle
			(at -27.806904 17.492726)
			(size 0.4318 0.4318)
			(layers "F.Cu" "F.Mask" "F.Paste")
			(net "P3E_CPU1_PE3_MP_RXN<10>")
		)
		(pad "DG14" smd circle
			(at -26.090118 17.492726)
			(size 0.4318 0.4318)
			(layers "F.Cu" "F.Mask" "F.Paste")
			(net "GND")
		)
		(pad "DG16" smd circle
			(at -24.373078 17.492726)
			(size 0.4318 0.4318)
			(layers "F.Cu" "F.Mask" "F.Paste")
			(net "GND")
		)
		(pad "DG18" smd circle
			(at -22.656038 17.492726)
			(size 0.4318 0.4318)
			(layers "F.Cu" "F.Mask" "F.Paste")
			(net "TP_CPU1_UPI2_RSVD_CM13")
		)
		(pad "DG20" smd circle
			(at -20.938998 17.492726)
			(size 0.4318 0.4318)
			(layers "F.Cu" "F.Mask" "F.Paste")
			(net "TP_CPU1_UPI2_RSVD_CH11")
		)
		(pad "DG22" smd circle
			(at -19.221958 17.492726)
			(size 0.4318 0.4318)
			(layers "F.Cu" "F.Mask" "F.Paste")
			(net "GND")
		)
		(pad "DG24" smd circle
			(at -17.504918 17.492726)
			(size 0.4318 0.4318)
			(layers "F.Cu" "F.Mask" "F.Paste")
			(net "GND")
		)
		(pad "DG26" smd circle
			(at -15.787878 17.492726)
			(size 0.4318 0.4318)
			(layers "F.Cu" "F.Mask" "F.Paste")
			(net "M_L_DQS_DN<16>")
		)
		(pad "DG28" smd circle
			(at -14.071092 17.492726)
			(size 0.4318 0.4318)
			(layers "F.Cu" "F.Mask" "F.Paste")
			(net "M_L_DQ<60>")
		)
		(pad "DG30" smd circle
			(at -12.354052 17.492726)
			(size 0.4318 0.4318)
			(layers "F.Cu" "F.Mask" "F.Paste")
			(net "M_M_DQ<42>")
		)
		(pad "DG32" smd circle
			(at -10.637012 17.492726)
			(size 0.4318 0.4318)
			(layers "F.Cu" "F.Mask" "F.Paste")
			(net "M_M_DQS_DN<14>")
		)
		(pad "DG34" smd circle
			(at -8.919972 17.492726)
			(size 0.4318 0.4318)
			(layers "F.Cu" "F.Mask" "F.Paste")
			(net "M_M_DQ<44>")
		)
		(pad "DG36" smd circle
			(at -7.202932 17.492726)
			(size 0.4318 0.4318)
			(layers "F.Cu" "F.Mask" "F.Paste")
			(net "TP_CPU1_RSVD_44")
		)
		(pad "DG38" smd circle
			(at -5.485892 17.492726)
			(size 0.4318 0.4318)
			(layers "F.Cu" "F.Mask" "F.Paste")
			(net "M_M_DQ<35>")
		)
		(pad "DG40" smd circle
			(at -3.769106 17.492726)
			(size 0.4318 0.4318)
			(layers "F.Cu" "F.Mask" "F.Paste")
			(net "M_M_DQS_DN<4>")
		)
		(pad "DG42" smd circle
			(at -2.052066 17.492726)
			(size 0.4318 0.4318)
			(layers "F.Cu" "F.Mask" "F.Paste")
			(net "M_M_DQ<33>")
		)
		(pad "DG44" smd circle
			(at 1.193546 15.692628)
			(size 0.508 0.508)
			(layers "F.Cu" "F.Mask" "F.Paste")
			(net "SVID_CLK1_CPU1")
		)
		(pad "DG46" smd circle
			(at 2.910586 15.692628)
			(size 0.4318 0.4318)
			(layers "F.Cu" "F.Mask" "F.Paste")
			(net "M_M_CS_N<3>")
		)
		(pad "DG48" smd circle
			(at 4.627626 15.692628)
			(size 0.4318 0.4318)
			(layers "F.Cu" "F.Mask" "F.Paste")
			(net "M_M_ODT<1>")
		)
		(pad "DG50" smd circle
			(at 6.344412 15.692628)
			(size 0.4318 0.4318)
			(layers "F.Cu" "F.Mask" "F.Paste")
			(net "M_M_ODT<0>")
		)
		(pad "DG52" smd circle
			(at 8.061452 15.692628)
			(size 0.4318 0.4318)
			(layers "F.Cu" "F.Mask" "F.Paste")
			(net "M_M_MA<16>")
		)
		(pad "DG54" smd circle
			(at 9.778492 15.692628)
			(size 0.4318 0.4318)
			(layers "F.Cu" "F.Mask" "F.Paste")
			(net "M_M_CLK_DP<1>")
		)
		(pad "DG56" smd circle
			(at 11.495532 15.692628)
			(size 0.4318 0.4318)
			(layers "F.Cu" "F.Mask" "F.Paste")
			(net "M_M_CLK_DP<3>")
		)
		(pad "DG58" smd circle
			(at 13.212572 15.692628)
			(size 0.4318 0.4318)
			(layers "F.Cu" "F.Mask" "F.Paste")
			(net "M_M_MA<3>")
		)
		(pad "DG60" smd circle
			(at 14.929612 15.692628)
			(size 0.4318 0.4318)
			(layers "F.Cu" "F.Mask" "F.Paste")
			(net "M_M_MA<12>")
		)
		(pad "DG62" smd circle
			(at 16.646398 15.692628)
			(size 0.4318 0.4318)
			(layers "F.Cu" "F.Mask" "F.Paste")
			(net "M_M_CKE<0>")
		)
		(pad "DG64" smd circle
			(at 18.363438 15.692628)
			(size 0.4318 0.4318)
			(layers "F.Cu" "F.Mask" "F.Paste")
			(net "TP_CPU1_RSVD_43")
		)
		(pad "DG66" smd circle
			(at 20.080478 15.692628)
			(size 0.4318 0.4318)
			(layers "F.Cu" "F.Mask" "F.Paste")
			(net "GND")
		)
		(pad "DG68" smd circle
			(at 21.797518 15.692628)
			(size 0.4318 0.4318)
			(layers "F.Cu" "F.Mask" "F.Paste")
			(net "GND")
		)
		(pad "DG70" smd circle
			(at 23.514558 15.692628)
			(size 0.4318 0.4318)
			(layers "F.Cu" "F.Mask" "F.Paste")
			(net "M_M_DQ<16>")
		)
		(pad "DG72" smd circle
			(at 25.231598 15.692628)
			(size 0.4318 0.4318)
			(layers "F.Cu" "F.Mask" "F.Paste")
			(net "M_M_DQ<21>")
		)
		(pad "DG74" smd circle
			(at 26.948384 15.692628)
			(size 0.4318 0.4318)
			(layers "F.Cu" "F.Mask" "F.Paste")
			(net "M_M_DQS_DP<10>")
		)
		(pad "DG76" smd circle
			(at 28.665424 15.692628)
			(size 0.4318 0.4318)
			(layers "F.Cu" "F.Mask" "F.Paste")
			(net "GND")
		)
		(pad "DG78" smd circle
			(at 30.382464 15.692628)
			(size 0.4318 0.4318)
			(layers "F.Cu" "F.Mask" "F.Paste")
			(net "GND")
		)
		(pad "DG80" smd circle
			(at 32.099504 15.692628)
			(size 0.4318 0.4318)
			(layers "F.Cu" "F.Mask" "F.Paste")
			(net "GND")
		)
		(pad "DG82" smd circle
			(at 33.816544 15.692628)
			(size 0.4318 0.4318)
			(layers "F.Cu" "F.Mask" "F.Paste")
			(net "GND")
		)
		(pad "DG84" smd circle
			(at 35.533584 15.692628)
			(size 0.4318 0.4318)
			(layers "F.Cu" "F.Mask" "F.Paste")
			(net "M_K_DQ<8>")
		)
		(pad "DH3" smd circle
			(at -35.533584 17.988026)
			(size 0.4318 0.4318)
			(layers "F.Cu" "F.Mask" "F.Paste")
			(net "TP_P3E_CPU1_PE1_MP_TXP<5>")
		)
		(pad "DH5" smd circle
			(at -33.816544 17.988026)
			(size 0.4318 0.4318)
			(layers "F.Cu" "F.Mask" "F.Paste")
			(net "P3E_CPU1_PE3_MP_TXP<11>")
		)
		(pad "DH7" smd circle
			(at -32.099504 17.988026)
			(size 0.4318 0.4318)
			(layers "F.Cu" "F.Mask" "F.Paste")
			(net "PVCCIO_CPU1")
		)
		(pad "DH9" smd circle
			(at -30.382464 17.988026)
			(size 0.4318 0.4318)
			(layers "F.Cu" "F.Mask" "F.Paste")
			(net "TP_P3E_CPU1_PE1_MP_RXN<5>")
		)
		(pad "DH11" smd circle
			(at -28.665424 17.988026)
			(size 0.4318 0.4318)
			(layers "F.Cu" "F.Mask" "F.Paste")
			(net "P3E_CPU1_PE3_MP_RXP<9>")
		)
		(pad "DH13" smd circle
			(at -26.948384 17.988026)
			(size 0.4318 0.4318)
			(layers "F.Cu" "F.Mask" "F.Paste")
			(net "GND")
		)
		(pad "DH15" smd circle
			(at -25.231598 17.988026)
			(size 0.4318 0.4318)
			(layers "F.Cu" "F.Mask" "F.Paste")
			(net "GND")
		)
		(pad "DH17" smd circle
			(at -23.514558 17.988026)
			(size 0.4318 0.4318)
			(layers "F.Cu" "F.Mask" "F.Paste")
			(net "TP_CPU1_UPI2_RSVD_CH13")
		)
		(pad "DH19" smd circle
			(at -21.797518 17.988026)
			(size 0.4318 0.4318)
			(layers "F.Cu" "F.Mask" "F.Paste")
			(net "TP_CPU1_UPI2_RSVD_CF13")
		)
		(pad "DH21" smd circle
			(at -20.080478 17.988026)
			(size 0.4318 0.4318)
			(layers "F.Cu" "F.Mask" "F.Paste")
			(net "GND")
		)
		(pad "DH23" smd circle
			(at -18.363438 17.988026)
			(size 0.4318 0.4318)
			(layers "F.Cu" "F.Mask" "F.Paste")
			(net "GND")
		)
		(pad "DH25" smd circle
			(at -16.646398 17.988026)
			(size 0.4318 0.4318)
			(layers "F.Cu" "F.Mask" "F.Paste")
			(net "GND")
		)
		(pad "DH27" smd circle
			(at -14.929612 17.988026)
			(size 0.4318 0.4318)
			(layers "F.Cu" "F.Mask" "F.Paste")
			(net "GND")
		)
		(pad "DH29" smd circle
			(at -13.212572 17.988026)
			(size 0.4318 0.4318)
			(layers "F.Cu" "F.Mask" "F.Paste")
			(net "GND")
		)
		(pad "DH31" smd circle
			(at -11.495532 17.988026)
			(size 0.4318 0.4318)
			(layers "F.Cu" "F.Mask" "F.Paste")
			(net "GND")
		)
		(pad "DH33" smd circle
			(at -9.778492 17.988026)
			(size 0.4318 0.4318)
			(layers "F.Cu" "F.Mask" "F.Paste")
			(net "GND")
		)
		(pad "DH35" smd circle
			(at -8.061452 17.988026)
			(size 0.4318 0.4318)
			(layers "F.Cu" "F.Mask" "F.Paste")
			(net "GND")
		)
		(pad "DH37" smd circle
			(at -6.344412 17.988026)
			(size 0.4318 0.4318)
			(layers "F.Cu" "F.Mask" "F.Paste")
			(net "GND")
		)
		(pad "DH39" smd circle
			(at -4.627626 17.988026)
			(size 0.4318 0.4318)
			(layers "F.Cu" "F.Mask" "F.Paste")
			(net "M_M_DQ<39>")
		)
		(pad "DH41" smd circle
			(at -2.910586 17.988026)
			(size 0.4318 0.4318)
			(layers "F.Cu" "F.Mask" "F.Paste")
			(net "GND")
		)
		(pad "DH45" smd circle
			(at 2.052066 16.187674)
			(size 0.4318 0.4318)
			(layers "F.Cu" "F.Mask" "F.Paste")
			(net "PVDDQ_KLM")
		)
		(pad "DH47" smd circle
			(at 3.769106 16.187674)
			(size 0.4318 0.4318)
			(layers "F.Cu" "F.Mask" "F.Paste")
			(net "PVDDQ_KLM")
		)
		(pad "DH49" smd circle
			(at 5.485892 16.187674)
			(size 0.4318 0.4318)
			(layers "F.Cu" "F.Mask" "F.Paste")
			(net "PVDDQ_KLM")
		)
		(pad "DH51" smd circle
			(at 7.202932 16.187674)
			(size 0.4318 0.4318)
			(layers "F.Cu" "F.Mask" "F.Paste")
			(net "PVDDQ_KLM")
		)
		(pad "DH53" smd circle
			(at 8.919972 16.187674)
			(size 0.4318 0.4318)
			(layers "F.Cu" "F.Mask" "F.Paste")
			(net "PVDDQ_KLM")
		)
		(pad "DH55" smd circle
			(at 10.637012 16.187674)
			(size 0.4318 0.4318)
			(layers "F.Cu" "F.Mask" "F.Paste")
			(net "PVDDQ_KLM")
		)
		(pad "DH57" smd circle
			(at 12.354052 16.187674)
			(size 0.4318 0.4318)
			(layers "F.Cu" "F.Mask" "F.Paste")
			(net "PVDDQ_KLM")
		)
		(pad "DH59" smd circle
			(at 14.071092 16.187674)
			(size 0.4318 0.4318)
			(layers "F.Cu" "F.Mask" "F.Paste")
			(net "PVDDQ_KLM")
		)
		(pad "DH61" smd circle
			(at 15.787878 16.187674)
			(size 0.4318 0.4318)
			(layers "F.Cu" "F.Mask" "F.Paste")
			(net "PVDDQ_KLM")
		)
		(pad "DH63" smd circle
			(at 17.504918 16.187674)
			(size 0.4318 0.4318)
			(layers "F.Cu" "F.Mask" "F.Paste")
			(net "PVDDQ_KLM")
		)
		(pad "DH65" smd circle
			(at 19.221958 16.187674)
			(size 0.4318 0.4318)
			(layers "F.Cu" "F.Mask" "F.Paste")
			(net "TP_CPU1_RSVD_42")
		)
		(pad "DH67" smd circle
			(at 20.938998 16.187674)
			(size 0.4318 0.4318)
			(layers "F.Cu" "F.Mask" "F.Paste")
			(net "GND")
		)
		(pad "DH69" smd circle
			(at 22.656038 16.187674)
			(size 0.4318 0.4318)
			(layers "F.Cu" "F.Mask" "F.Paste")
			(net "M_M_DQS_DP<11>")
		)
		(pad "DH71" smd circle
			(at 24.373078 16.187674)
			(size 0.4318 0.4318)
			(layers "F.Cu" "F.Mask" "F.Paste")
			(net "GND")
		)
		(pad "DH73" smd circle
			(at 26.090118 16.187674)
			(size 0.4318 0.4318)
			(layers "F.Cu" "F.Mask" "F.Paste")
			(net "GND")
		)
		(pad "DH75" smd circle
			(at 27.806904 16.187674)
			(size 0.4318 0.4318)
			(layers "F.Cu" "F.Mask" "F.Paste")
			(net "M_M_DQ<10>")
		)
		(pad "DH77" smd circle
			(at 29.523944 16.187674)
			(size 0.4318 0.4318)
			(layers "F.Cu" "F.Mask" "F.Paste")
			(net "M_M_DQ<15>")
		)
		(pad "DH79" smd circle
			(at 31.240984 16.187674)
			(size 0.4318 0.4318)
			(layers "F.Cu" "F.Mask" "F.Paste")
			(net "GND")
		)
		(pad "DH81" smd circle
			(at 32.958024 16.187674)
			(size 0.4318 0.4318)
			(layers "F.Cu" "F.Mask" "F.Paste")
			(net "GND")
		)
		(pad "DH83" smd circle
			(at 34.675064 16.187674)
			(size 0.4318 0.4318)
			(layers "F.Cu" "F.Mask" "F.Paste")
			(net "GND")
		)
		(pad "DH85" smd custom
			(at 36.392104 16.187674 270)
			(size 0.10795 0.10795)
			(layers "F.Cu" "F.Mask" "F.Paste")
			(net "M_K_DQ<9>")
			(options
				(clearance outline)
				(anchor circle)
			)
			(primitives
				(gr_poly
					(pts
						(arc
							(start 0.2159 -0.0381)
							(mid 0 -0.254)
							(end -0.2159 -0.0381)
						)
						(arc
							(start -0.2159 0.0381)
							(mid 0 0.254)
							(end 0.2159 0.0381)
						)
					)
					(width 0)
					(fill yes)
				)
			)
		)
		(pad "DJ2" smd custom
			(at -36.392104 18.483072 90)
			(size 0.10795 0.10795)
			(layers "F.Cu" "F.Mask" "F.Paste")
			(net "GND")
			(options
				(clearance outline)
				(anchor circle)
			)
			(primitives
				(gr_poly
					(pts
						(arc
							(start 0.2159 -0.0381)
							(mid 0 -0.254)
							(end -0.2159 -0.0381)
						)
						(arc
							(start -0.2159 0.0381)
							(mid 0 0.254)
							(end 0.2159 0.0381)
						)
					)
					(width 0)
					(fill yes)
				)
			)
		)
		(pad "DJ4" smd circle
			(at -34.675064 18.483072)
			(size 0.4318 0.4318)
			(layers "F.Cu" "F.Mask" "F.Paste")
			(net "P3E_CPU1_PE3_MP_TXN<11>")
		)
		(pad "DJ6" smd circle
			(at -32.958024 18.483072)
			(size 0.4318 0.4318)
			(layers "F.Cu" "F.Mask" "F.Paste")
			(net "P3E_CPU1_PE3_MP_TXN<12>")
		)
		(pad "DJ8" smd circle
			(at -31.240984 18.483072)
			(size 0.4318 0.4318)
			(layers "F.Cu" "F.Mask" "F.Paste")
			(net "TP_P3E_CPU1_PE1_MP_RXP<6>")
		)
		(pad "DJ10" smd circle
			(at -29.523944 18.483072)
			(size 0.4318 0.4318)
			(layers "F.Cu" "F.Mask" "F.Paste")
			(net "GND")
		)
		(pad "DJ12" smd circle
			(at -27.806904 18.483072)
			(size 0.4318 0.4318)
			(layers "F.Cu" "F.Mask" "F.Paste")
			(net "P3E_CPU1_PE3_MP_RXN<9>")
		)
		(pad "DJ14" smd circle
			(at -26.090118 18.483072)
			(size 0.4318 0.4318)
			(layers "F.Cu" "F.Mask" "F.Paste")
			(net "P3E_CPU1_PE3_MP_RXP<7>")
		)
		(pad "DJ16" smd circle
			(at -24.373078 18.483072)
			(size 0.4318 0.4318)
			(layers "F.Cu" "F.Mask" "F.Paste")
			(net "PVCCIO_CPU1")
		)
		(pad "DJ18" smd circle
			(at -22.656038 18.483072)
			(size 0.4318 0.4318)
			(layers "F.Cu" "F.Mask" "F.Paste")
			(net "TP_CPU1_UPI2_RSVD_CG12")
		)
		(pad "DJ20" smd circle
			(at -20.938998 18.483072)
			(size 0.4318 0.4318)
			(layers "F.Cu" "F.Mask" "F.Paste")
			(net "TP_CPU1_UPI2_RSVD_CF11")
		)
		(pad "DJ22" smd circle
			(at -19.221958 18.483072)
			(size 0.4318 0.4318)
			(layers "F.Cu" "F.Mask" "F.Paste")
			(net "GND")
		)
		(pad "DJ24" smd circle
			(at -17.504918 18.483072)
			(size 0.4318 0.4318)
			(layers "F.Cu" "F.Mask" "F.Paste")
			(net "M_L_DQ<59>")
		)
		(pad "DJ26" smd circle
			(at -15.787878 18.483072)
			(size 0.4318 0.4318)
			(layers "F.Cu" "F.Mask" "F.Paste")
			(net "M_L_DQS_DP<7>")
		)
		(pad "DJ28" smd circle
			(at -14.071092 18.483072)
			(size 0.4318 0.4318)
			(layers "F.Cu" "F.Mask" "F.Paste")
			(net "M_L_DQ<61>")
		)
		(pad "DJ30" smd circle
			(at -12.354052 18.483072)
			(size 0.4318 0.4318)
			(layers "F.Cu" "F.Mask" "F.Paste")
			(net "M_M_DQ<43>")
		)
		(pad "DJ32" smd circle
			(at -10.637012 18.483072)
			(size 0.4318 0.4318)
			(layers "F.Cu" "F.Mask" "F.Paste")
			(net "M_M_DQS_DP<5>")
		)
		(pad "DJ34" smd circle
			(at -8.919972 18.483072)
			(size 0.4318 0.4318)
			(layers "F.Cu" "F.Mask" "F.Paste")
			(net "M_M_DQ<45>")
		)
		(pad "DJ36" smd circle
			(at -7.202932 18.483072)
			(size 0.4318 0.4318)
			(layers "F.Cu" "F.Mask" "F.Paste")
			(net "TP_CPU1_RSVD_41")
		)
		(pad "DJ38" smd circle
			(at -5.485892 18.483072)
			(size 0.4318 0.4318)
			(layers "F.Cu" "F.Mask" "F.Paste")
			(net "GND")
		)
		(pad "DJ40" smd circle
			(at -3.769106 18.483072)
			(size 0.4318 0.4318)
			(layers "F.Cu" "F.Mask" "F.Paste")
			(net "M_M_DQS_DP<4>")
		)
		(pad "DJ42" smd circle
			(at -2.052066 18.483072)
			(size 0.4318 0.4318)
			(layers "F.Cu" "F.Mask" "F.Paste")
			(net "GND")
		)
		(pad "DJ44" smd circle
			(at 1.193546 16.683228)
			(size 0.508 0.508)
			(layers "F.Cu" "F.Mask" "F.Paste")
			(net "SVID_DIO1_CPU1")
		)
		(pad "DJ46" smd circle
			(at 2.910586 16.683228)
			(size 0.4318 0.4318)
			(layers "F.Cu" "F.Mask" "F.Paste")
			(net "M_M_CS_N<2>")
		)
		(pad "DJ48" smd circle
			(at 4.627626 16.683228)
			(size 0.4318 0.4318)
			(layers "F.Cu" "F.Mask" "F.Paste")
			(net "M_M_CS_N<5>")
		)
		(pad "DJ50" smd circle
			(at 6.344412 16.683228)
			(size 0.4318 0.4318)
			(layers "F.Cu" "F.Mask" "F.Paste")
			(net "M_M_MA<14>")
		)
		(pad "DJ52" smd circle
			(at 8.061452 16.683228)
			(size 0.4318 0.4318)
			(layers "F.Cu" "F.Mask" "F.Paste")
			(net "M_M_BA<0>")
		)
		(pad "DJ54" smd circle
			(at 9.778492 16.683228)
			(size 0.4318 0.4318)
			(layers "F.Cu" "F.Mask" "F.Paste")
			(net "M_M_CLK_DP<0>")
		)
		(pad "DJ56" smd circle
			(at 11.495532 16.683228)
			(size 0.4318 0.4318)
			(layers "F.Cu" "F.Mask" "F.Paste")
			(net "M_M_CLK_DP<2>")
		)
		(pad "DJ58" smd circle
			(at 13.212572 16.683228)
			(size 0.4318 0.4318)
			(layers "F.Cu" "F.Mask" "F.Paste")
			(net "M_M_MA<4>")
		)
		(pad "DJ60" smd circle
			(at 14.929612 16.683228)
			(size 0.4318 0.4318)
			(layers "F.Cu" "F.Mask" "F.Paste")
			(net "M_L_MA<8>")
		)
		(pad "DJ62" smd circle
			(at 16.646398 16.683228)
			(size 0.4318 0.4318)
			(layers "F.Cu" "F.Mask" "F.Paste")
			(net "M_L_BG<0>")
		)
		(pad "DJ64" smd circle
			(at 18.363438 16.683228)
			(size 0.4318 0.4318)
			(layers "F.Cu" "F.Mask" "F.Paste")
			(net "PVDDQ_KLM")
		)
		(pad "DJ66" smd circle
			(at 20.080478 16.683228)
			(size 0.4318 0.4318)
			(layers "F.Cu" "F.Mask" "F.Paste")
			(net "TP_CPU1_RSVD_40")
		)
		(pad "DJ68" smd circle
			(at 21.797518 16.683228)
			(size 0.4318 0.4318)
			(layers "F.Cu" "F.Mask" "F.Paste")
			(net "GND")
		)
		(pad "DJ70" smd circle
			(at 23.514558 16.683228)
			(size 0.4318 0.4318)
			(layers "F.Cu" "F.Mask" "F.Paste")
			(net "M_M_DQS_DN<11>")
		)
		(pad "DJ72" smd circle
			(at 25.231598 16.683228)
			(size 0.4318 0.4318)
			(layers "F.Cu" "F.Mask" "F.Paste")
			(net "M_M_DQ<17>")
		)
		(pad "DJ74" smd circle
			(at 26.948384 16.683228)
			(size 0.4318 0.4318)
			(layers "F.Cu" "F.Mask" "F.Paste")
			(net "GND")
		)
		(pad "DJ76" smd circle
			(at 28.665424 16.683228)
			(size 0.4318 0.4318)
			(layers "F.Cu" "F.Mask" "F.Paste")
			(net "M_M_DQ<11>")
		)
		(pad "DJ78" smd circle
			(at 30.382464 16.683228)
			(size 0.4318 0.4318)
			(layers "F.Cu" "F.Mask" "F.Paste")
			(net "GND")
		)
		(pad "DJ80" smd circle
			(at 32.099504 16.683228)
			(size 0.4318 0.4318)
			(layers "F.Cu" "F.Mask" "F.Paste")
			(net "M_K_DQ<21>")
		)
		(pad "DJ82" smd circle
			(at 33.816544 16.683228)
			(size 0.4318 0.4318)
			(layers "F.Cu" "F.Mask" "F.Paste")
			(net "GND")
		)
		(pad "DJ84" smd circle
			(at 35.533584 16.683228)
			(size 0.4318 0.4318)
			(layers "F.Cu" "F.Mask" "F.Paste")
			(net "GND")
		)
		(pad "DK3" smd circle
			(at -35.533584 18.978372)
			(size 0.4318 0.4318)
			(layers "F.Cu" "F.Mask" "F.Paste")
			(net "TP_P3E_CPU1_PE1_MP_TXN<5>")
		)
		(pad "DK5" smd circle
			(at -33.816544 18.978372)
			(size 0.4318 0.4318)
			(layers "F.Cu" "F.Mask" "F.Paste")
			(net "P3E_CPU1_PE3_MP_TXP<10>")
		)
		(pad "DK7" smd circle
			(at -32.099504 18.978372)
			(size 0.4318 0.4318)
			(layers "F.Cu" "F.Mask" "F.Paste")
			(net "GND")
		)
		(pad "DK9" smd circle
			(at -30.382464 18.978372)
			(size 0.4318 0.4318)
			(layers "F.Cu" "F.Mask" "F.Paste")
			(net "TP_P3E_CPU1_PE1_MP_RXN<6>")
		)
		(pad "DK11" smd circle
			(at -28.665424 18.978372)
			(size 0.4318 0.4318)
			(layers "F.Cu" "F.Mask" "F.Paste")
			(net "TP_P3E_CPU1_PE1_RSR3_RXP<8>")
		)
		(pad "DK13" smd circle
			(at -26.948384 18.978372)
			(size 0.4318 0.4318)
			(layers "F.Cu" "F.Mask" "F.Paste")
			(net "P3E_CPU1_PE3_MP_RXP<8>")
		)
		(pad "DK15" smd circle
			(at -25.231598 18.978372)
			(size 0.4318 0.4318)
			(layers "F.Cu" "F.Mask" "F.Paste")
			(net "TP_CPU1_RSVD_39")
		)
		(pad "DK17" smd circle
			(at -23.514558 18.978372)
			(size 0.4318 0.4318)
			(layers "F.Cu" "F.Mask" "F.Paste")
			(net "TP_CPU1_UPI2_RSVD_CJ14")
		)
		(pad "DK19" smd circle
			(at -21.797518 18.978372)
			(size 0.4318 0.4318)
			(layers "F.Cu" "F.Mask" "F.Paste")
			(net "TP_CPU1_UPI2_RSVD_CD11")
		)
		(pad "DK21" smd circle
			(at -20.080478 18.978372)
			(size 0.4318 0.4318)
			(layers "F.Cu" "F.Mask" "F.Paste")
			(net "PVCCIO_CPU1")
		)
		(pad "DK23" smd circle
			(at -18.363438 18.978372)
			(size 0.4318 0.4318)
			(layers "F.Cu" "F.Mask" "F.Paste")
			(net "GND")
		)
		(pad "DK25" smd circle
			(at -16.646398 18.978372)
			(size 0.4318 0.4318)
			(layers "F.Cu" "F.Mask" "F.Paste")
			(net "M_L_DQ<63>")
		)
		(pad "DK27" smd circle
			(at -14.929612 18.978372)
			(size 0.4318 0.4318)
			(layers "F.Cu" "F.Mask" "F.Paste")
			(net "M_L_DQ<57>")
		)
		(pad "DK29" smd circle
			(at -13.212572 18.978372)
			(size 0.4318 0.4318)
			(layers "F.Cu" "F.Mask" "F.Paste")
			(net "GND")
		)
		(pad "DK31" smd circle
			(at -11.495532 18.978372)
			(size 0.4318 0.4318)
			(layers "F.Cu" "F.Mask" "F.Paste")
			(net "M_M_DQ<47>")
		)
		(pad "DK33" smd circle
			(at -9.778492 18.978372)
			(size 0.4318 0.4318)
			(layers "F.Cu" "F.Mask" "F.Paste")
			(net "M_M_DQ<41>")
		)
		(pad "DK35" smd circle
			(at -8.061452 18.978372)
			(size 0.4318 0.4318)
			(layers "F.Cu" "F.Mask" "F.Paste")
			(net "GND")
		)
		(pad "DK37" smd circle
			(at -6.344412 18.978372)
			(size 0.4318 0.4318)
			(layers "F.Cu" "F.Mask" "F.Paste")
			(net "TP_CPU1_RSVD_38")
		)
		(pad "DK39" smd circle
			(at -4.627626 18.978372)
			(size 0.4318 0.4318)
			(layers "F.Cu" "F.Mask" "F.Paste")
			(net "GND")
		)
		(pad "DK41" smd circle
			(at -2.910586 18.978372)
			(size 0.4318 0.4318)
			(layers "F.Cu" "F.Mask" "F.Paste")
			(net "GND")
		)
		(pad "DK45" smd circle
			(at 2.052066 17.178528)
			(size 0.4318 0.4318)
			(layers "F.Cu" "F.Mask" "F.Paste")
			(net "M_M_CS_N<7>")
		)
		(pad "DK47" smd circle
			(at 3.769106 17.178528)
			(size 0.4318 0.4318)
			(layers "F.Cu" "F.Mask" "F.Paste")
			(net "M_L_CS_N<3>")
		)
		(pad "DK49" smd circle
			(at 5.485892 17.178528)
			(size 0.4318 0.4318)
			(layers "F.Cu" "F.Mask" "F.Paste")
			(net "M_M_ODT<2>")
		)
		(pad "DK51" smd circle
			(at 7.202932 17.178528)
			(size 0.4318 0.4318)
			(layers "F.Cu" "F.Mask" "F.Paste")
			(net "M_M_CS_N<0>")
		)
		(pad "DK53" smd circle
			(at 8.919972 17.178528)
			(size 0.4318 0.4318)
			(layers "F.Cu" "F.Mask" "F.Paste")
			(net "M_M_PAR")
		)
		(pad "DK55" smd circle
			(at 10.637012 17.178528)
			(size 0.4318 0.4318)
			(layers "F.Cu" "F.Mask" "F.Paste")
			(net "M_M_CLK_DN<0>")
		)
		(pad "DK57" smd circle
			(at 12.354052 17.178528)
			(size 0.4318 0.4318)
			(layers "F.Cu" "F.Mask" "F.Paste")
			(net "M_M_CLK_DN<2>")
		)
		(pad "DK59" smd circle
			(at 14.071092 17.178528)
			(size 0.4318 0.4318)
			(layers "F.Cu" "F.Mask" "F.Paste")
			(net "M_M_MA<6>")
		)
		(pad "DK61" smd circle
			(at 15.787878 17.178528)
			(size 0.4318 0.4318)
			(layers "F.Cu" "F.Mask" "F.Paste")
			(net "M_L_MA<7>")
		)
		(pad "DK63" smd circle
			(at 17.504918 17.178528)
			(size 0.4318 0.4318)
			(layers "F.Cu" "F.Mask" "F.Paste")
			(net "M_M_CKE<2>")
		)
		(pad "DK65" smd circle
			(at 19.221958 17.178528)
			(size 0.4318 0.4318)
			(layers "F.Cu" "F.Mask" "F.Paste")
			(net "TP_CPU1_RSVD_37")
		)
		(pad "DK67" smd circle
			(at 20.938998 17.178528)
			(size 0.4318 0.4318)
			(layers "F.Cu" "F.Mask" "F.Paste")
			(net "TP_CPU1_RSVD_36")
		)
		(pad "DK69" smd circle
			(at 22.656038 17.178528)
			(size 0.4318 0.4318)
			(layers "F.Cu" "F.Mask" "F.Paste")
			(net "M_M_DQ<22>")
		)
		(pad "DK71" smd circle
			(at 24.373078 17.178528)
			(size 0.4318 0.4318)
			(layers "F.Cu" "F.Mask" "F.Paste")
			(net "M_M_DQS_DP<2>")
		)
		(pad "DK73" smd circle
			(at 26.090118 17.178528)
			(size 0.4318 0.4318)
			(layers "F.Cu" "F.Mask" "F.Paste")
			(net "GND")
		)
		(pad "DK75" smd circle
			(at 27.806904 17.178528)
			(size 0.4318 0.4318)
			(layers "F.Cu" "F.Mask" "F.Paste")
			(net "GND")
		)
		(pad "DK77" smd circle
			(at 29.523944 17.178528)
			(size 0.4318 0.4318)
			(layers "F.Cu" "F.Mask" "F.Paste")
			(net "GND")
		)
		(pad "DK79" smd circle
			(at 31.240984 17.178528)
			(size 0.4318 0.4318)
			(layers "F.Cu" "F.Mask" "F.Paste")
			(net "M_K_DQ<20>")
		)
		(pad "DK81" smd circle
			(at 32.958024 17.178528)
			(size 0.4318 0.4318)
			(layers "F.Cu" "F.Mask" "F.Paste")
			(net "M_K_DQ<17>")
		)
		(pad "DK83" smd circle
			(at 34.675064 17.178528)
			(size 0.4318 0.4318)
			(layers "F.Cu" "F.Mask" "F.Paste")
			(net "GND")
		)
		(pad "DK85" smd custom
			(at 36.392104 17.178528 270)
			(size 0.10795 0.10795)
			(layers "F.Cu" "F.Mask" "F.Paste")
			(net "GND")
			(options
				(clearance outline)
				(anchor circle)
			)
			(primitives
				(gr_poly
					(pts
						(arc
							(start 0.2159 -0.0381)
							(mid 0 -0.254)
							(end -0.2159 -0.0381)
						)
						(arc
							(start -0.2159 0.0381)
							(mid 0 0.254)
							(end 0.2159 0.0381)
						)
					)
					(width 0)
					(fill yes)
				)
			)
		)
		(pad "DL2" smd custom
			(at -36.392104 19.473926 90)
			(size 0.10795 0.10795)
			(layers "F.Cu" "F.Mask" "F.Paste")
			(net "TP_P3E_CPU1_PE1_MP_TXP<6>")
			(options
				(clearance outline)
				(anchor circle)
			)
			(primitives
				(gr_poly
					(pts
						(arc
							(start 0.2159 -0.0381)
							(mid 0 -0.254)
							(end -0.2159 -0.0381)
						)
						(arc
							(start -0.2159 0.0381)
							(mid 0 0.254)
							(end 0.2159 0.0381)
						)
					)
					(width 0)
					(fill yes)
				)
			)
		)
		(pad "DL4" smd circle
			(at -34.675064 19.473926)
			(size 0.4318 0.4318)
			(layers "F.Cu" "F.Mask" "F.Paste")
			(net "GND")
		)
		(pad "DL6" smd circle
			(at -32.958024 19.473926)
			(size 0.4318 0.4318)
			(layers "F.Cu" "F.Mask" "F.Paste")
			(net "P3E_CPU1_PE3_MP_TXN<10>")
		)
		(pad "DL8" smd circle
			(at -31.240984 19.473926)
			(size 0.4318 0.4318)
			(layers "F.Cu" "F.Mask" "F.Paste")
			(net "GND")
		)
		(pad "DL10" smd circle
			(at -29.523944 19.473926)
			(size 0.4318 0.4318)
			(layers "F.Cu" "F.Mask" "F.Paste")
			(net "TP_P3E_CPU1_PE1_MP_RXP<7>")
		)
		(pad "DL12" smd circle
			(at -27.806904 19.473926)
			(size 0.4318 0.4318)
			(layers "F.Cu" "F.Mask" "F.Paste")
			(net "P3E_CPU1_PE3_MP_RXN<8>")
		)
		(pad "DL14" smd circle
			(at -26.090118 19.473926)
			(size 0.4318 0.4318)
			(layers "F.Cu" "F.Mask" "F.Paste")
			(net "P3E_CPU1_PE3_MP_RXN<7>")
		)
		(pad "DL16" smd circle
			(at -24.373078 19.473926)
			(size 0.4318 0.4318)
			(layers "F.Cu" "F.Mask" "F.Paste")
			(net "GND")
		)
		(pad "DL18" smd circle
			(at -22.656038 19.473926)
			(size 0.4318 0.4318)
			(layers "F.Cu" "F.Mask" "F.Paste")
			(net "GND")
		)
		(pad "DL20" smd circle
			(at -20.938998 19.473926)
			(size 0.4318 0.4318)
			(layers "F.Cu" "F.Mask" "F.Paste")
			(net "TP_CPU1_UPI2_RSVD_CE12")
		)
		(pad "DL22" smd circle
			(at -19.221958 19.473926)
			(size 0.4318 0.4318)
			(layers "F.Cu" "F.Mask" "F.Paste")
			(net "GND")
		)
		(pad "DL24" smd circle
			(at -17.504918 19.473926)
			(size 0.4318 0.4318)
			(layers "F.Cu" "F.Mask" "F.Paste")
			(net "GND")
		)
		(pad "DL26" smd circle
			(at -15.787878 19.473926)
			(size 0.4318 0.4318)
			(layers "F.Cu" "F.Mask" "F.Paste")
			(net "M_L_DQS_DN<7>")
		)
		(pad "DL28" smd circle
			(at -14.071092 19.473926)
			(size 0.4318 0.4318)
			(layers "F.Cu" "F.Mask" "F.Paste")
			(net "GND")
		)
		(pad "DL30" smd circle
			(at -12.354052 19.473926)
			(size 0.4318 0.4318)
			(layers "F.Cu" "F.Mask" "F.Paste")
			(net "GND")
		)
		(pad "DL32" smd circle
			(at -10.637012 19.473926)
			(size 0.4318 0.4318)
			(layers "F.Cu" "F.Mask" "F.Paste")
			(net "M_M_DQS_DN<5>")
		)
		(pad "DL34" smd circle
			(at -8.919972 19.473926)
			(size 0.4318 0.4318)
			(layers "F.Cu" "F.Mask" "F.Paste")
			(net "GND")
		)
		(pad "DL36" smd circle
			(at -7.202932 19.473926)
			(size 0.4318 0.4318)
			(layers "F.Cu" "F.Mask" "F.Paste")
			(net "GND")
		)
		(pad "DL38" smd circle
			(at -5.485892 19.473926)
			(size 0.4318 0.4318)
			(layers "F.Cu" "F.Mask" "F.Paste")
			(net "TP_CPU1_RSVD_35")
		)
		(pad "DL40" smd circle
			(at -3.769106 19.473926)
			(size 0.4318 0.4318)
			(layers "F.Cu" "F.Mask" "F.Paste")
			(net "GND")
		)
		(pad "DL42" smd circle
			(at -2.052066 19.473926)
			(size 0.4318 0.4318)
			(layers "F.Cu" "F.Mask" "F.Paste")
			(net "M_L_DQ<36>")
		)
		(pad "DL44" smd circle
			(at 1.193546 17.673574)
			(size 0.508 0.508)
			(layers "F.Cu" "F.Mask" "F.Paste")
			(net "SVID_ALERT1_CPU1_N")
		)
		(pad "DL46" smd circle
			(at 2.910586 17.673574)
			(size 0.4318 0.4318)
			(layers "F.Cu" "F.Mask" "F.Paste")
			(net "PVDDQ_KLM")
		)
		(pad "DL48" smd circle
			(at 4.627626 17.673574)
			(size 0.4318 0.4318)
			(layers "F.Cu" "F.Mask" "F.Paste")
			(net "PVDDQ_KLM")
		)
		(pad "DL50" smd circle
			(at 6.344412 17.673574)
			(size 0.4318 0.4318)
			(layers "F.Cu" "F.Mask" "F.Paste")
			(net "PVDDQ_KLM")
		)
		(pad "DL52" smd circle
			(at 8.061452 17.673574)
			(size 0.4318 0.4318)
			(layers "F.Cu" "F.Mask" "F.Paste")
			(net "PVDDQ_KLM")
		)
		(pad "DL54" smd circle
			(at 9.778492 17.673574)
			(size 0.4318 0.4318)
			(layers "F.Cu" "F.Mask" "F.Paste")
			(net "PVDDQ_KLM")
		)
		(pad "DL56" smd circle
			(at 11.495532 17.673574)
			(size 0.4318 0.4318)
			(layers "F.Cu" "F.Mask" "F.Paste")
			(net "PVDDQ_KLM")
		)
		(pad "DL58" smd circle
			(at 13.212572 17.673574)
			(size 0.4318 0.4318)
			(layers "F.Cu" "F.Mask" "F.Paste")
			(net "PVDDQ_KLM")
		)
		(pad "DL60" smd circle
			(at 14.929612 17.673574)
			(size 0.4318 0.4318)
			(layers "F.Cu" "F.Mask" "F.Paste")
			(net "PVDDQ_KLM")
		)
		(pad "DL62" smd circle
			(at 16.646398 17.673574)
			(size 0.4318 0.4318)
			(layers "F.Cu" "F.Mask" "F.Paste")
			(net "PVDDQ_KLM")
		)
		(pad "DL64" smd circle
			(at 18.363438 17.673574)
			(size 0.4318 0.4318)
			(layers "F.Cu" "F.Mask" "F.Paste")
			(net "M_L_CKE<2>")
		)
		(pad "DL66" smd circle
			(at 20.080478 17.673574)
			(size 0.4318 0.4318)
			(layers "F.Cu" "F.Mask" "F.Paste")
			(net "TP_CPU1_RSVD_34")
		)
		(pad "DL68" smd circle
			(at 21.797518 17.673574)
			(size 0.4318 0.4318)
			(layers "F.Cu" "F.Mask" "F.Paste")
			(net "GND")
		)
		(pad "DL70" smd circle
			(at 23.514558 17.673574)
			(size 0.4318 0.4318)
			(layers "F.Cu" "F.Mask" "F.Paste")
			(net "GND")
		)
		(pad "DL72" smd circle
			(at 25.231598 17.673574)
			(size 0.4318 0.4318)
			(layers "F.Cu" "F.Mask" "F.Paste")
			(net "M_M_DQS_DN<2>")
		)
		(pad "DL74" smd circle
			(at 26.948384 17.673574)
			(size 0.4318 0.4318)
			(layers "F.Cu" "F.Mask" "F.Paste")
			(net "GND")
		)
		(pad "DL76" smd circle
			(at 28.665424 17.673574)
			(size 0.4318 0.4318)
			(layers "F.Cu" "F.Mask" "F.Paste")
			(net "GND")
		)
		(pad "DL78" smd circle
			(at 30.382464 17.673574)
			(size 0.4318 0.4318)
			(layers "F.Cu" "F.Mask" "F.Paste")
			(net "GND")
		)
		(pad "DL80" smd circle
			(at 32.099504 17.673574)
			(size 0.4318 0.4318)
			(layers "F.Cu" "F.Mask" "F.Paste")
			(net "GND")
		)
		(pad "DL82" smd circle
			(at 33.816544 17.673574)
			(size 0.4318 0.4318)
			(layers "F.Cu" "F.Mask" "F.Paste")
			(net "M_K_DQS_DN<2>")
		)
		(pad "DL84" smd circle
			(at 35.533584 17.673574)
			(size 0.4318 0.4318)
			(layers "F.Cu" "F.Mask" "F.Paste")
			(net "M_K_DQS_DP<10>")
		)
		(pad "DM3" smd circle
			(at -35.533584 19.968972)
			(size 0.4318 0.4318)
			(layers "F.Cu" "F.Mask" "F.Paste")
			(net "TP_P3E_CPU1_PE1_MP_TXN<6>")
		)
		(pad "DM5" smd circle
			(at -33.816544 19.968972)
			(size 0.4318 0.4318)
			(layers "F.Cu" "F.Mask" "F.Paste")
			(net "P3E_CPU1_PE3_MP_TXP<9>")
		)
		(pad "DM7" smd circle
			(at -32.099504 19.968972)
			(size 0.4318 0.4318)
			(layers "F.Cu" "F.Mask" "F.Paste")
			(net "P3E_CPU1_PE3_MP_TXN<8>")
		)
		(pad "DM9" smd circle
			(at -30.382464 19.968972)
			(size 0.4318 0.4318)
			(layers "F.Cu" "F.Mask" "F.Paste")
			(net "TP_P3E_CPU1_PE1_MP_RXN<7>")
		)
		(pad "DM11" smd circle
			(at -28.665424 19.968972)
			(size 0.4318 0.4318)
			(layers "F.Cu" "F.Mask" "F.Paste")
			(net "TP_P3E_CPU1_PE1_RSR3_RXN<8>")
		)
		(pad "DM13" smd circle
			(at -26.948384 19.968972)
			(size 0.4318 0.4318)
			(layers "F.Cu" "F.Mask" "F.Paste")
			(net "P3E_CPU1_PE3_MP_RXP<6>")
		)
		(pad "DM15" smd circle
			(at -25.231598 19.968972)
			(size 0.4318 0.4318)
			(layers "F.Cu" "F.Mask" "F.Paste")
			(net "GND")
		)
		(pad "DM17" smd circle
			(at -23.514558 19.968972)
			(size 0.4318 0.4318)
			(layers "F.Cu" "F.Mask" "F.Paste")
			(net "PVCCIO_CPU1")
		)
		(pad "DM19" smd circle
			(at -21.797518 19.968972)
			(size 0.4318 0.4318)
			(layers "F.Cu" "F.Mask" "F.Paste")
			(net "GND")
		)
		(pad "DM21" smd circle
			(at -20.080478 19.968972)
			(size 0.4318 0.4318)
			(layers "F.Cu" "F.Mask" "F.Paste")
			(net "TP_CPU1_UPI2_RSVD_CC10")
		)
		(pad "DM23" smd circle
			(at -18.363438 19.968972)
			(size 0.4318 0.4318)
			(layers "F.Cu" "F.Mask" "F.Paste")
			(net "M_K_DQS_DN<16>")
		)
		(pad "DM25" smd circle
			(at -16.646398 19.968972)
			(size 0.4318 0.4318)
			(layers "F.Cu" "F.Mask" "F.Paste")
			(net "GND")
		)
		(pad "DM27" smd circle
			(at -14.929612 19.968972)
			(size 0.4318 0.4318)
			(layers "F.Cu" "F.Mask" "F.Paste")
			(net "GND")
		)
		(pad "DM29" smd circle
			(at -13.212572 19.968972)
			(size 0.4318 0.4318)
			(layers "F.Cu" "F.Mask" "F.Paste")
			(net "M_K_DQS_DN<15>")
		)
		(pad "DM31" smd circle
			(at -11.495532 19.968972)
			(size 0.4318 0.4318)
			(layers "F.Cu" "F.Mask" "F.Paste")
			(net "GND")
		)
		(pad "DM33" smd circle
			(at -9.778492 19.968972)
			(size 0.4318 0.4318)
			(layers "F.Cu" "F.Mask" "F.Paste")
			(net "GND")
		)
		(pad "DM35" smd circle
			(at -8.061452 19.968972)
			(size 0.4318 0.4318)
			(layers "F.Cu" "F.Mask" "F.Paste")
			(net "M_K_DQS_DP<14>")
		)
		(pad "DM37" smd circle
			(at -6.344412 19.968972)
			(size 0.4318 0.4318)
			(layers "F.Cu" "F.Mask" "F.Paste")
			(net "GND")
		)
		(pad "DM39" smd circle
			(at -4.627626 19.968972)
			(size 0.4318 0.4318)
			(layers "F.Cu" "F.Mask" "F.Paste")
			(net "GND")
		)
		(pad "DM41" smd circle
			(at -2.910586 19.968972)
			(size 0.4318 0.4318)
			(layers "F.Cu" "F.Mask" "F.Paste")
			(net "M_L_DQS_DP<13>")
		)
		(pad "DM45" smd circle
			(at 2.052066 18.168874)
			(size 0.4318 0.4318)
			(layers "F.Cu" "F.Mask" "F.Paste")
			(net "M_M_CS_N<6>")
		)
		(pad "DM47" smd circle
			(at 3.769106 18.168874)
			(size 0.4318 0.4318)
			(layers "F.Cu" "F.Mask" "F.Paste")
			(net "M_L_ODT<3>")
		)
		(pad "DM49" smd circle
			(at 5.485892 18.168874)
			(size 0.4318 0.4318)
			(layers "F.Cu" "F.Mask" "F.Paste")
			(net "M_L_CS_N<5>")
		)
		(pad "DM51" smd circle
			(at 7.202932 18.168874)
			(size 0.4318 0.4318)
			(layers "F.Cu" "F.Mask" "F.Paste")
			(net "M_L_MA<14>")
		)
		(pad "DM53" smd circle
			(at 8.919972 18.168874)
			(size 0.4318 0.4318)
			(layers "F.Cu" "F.Mask" "F.Paste")
			(net "M_L_BA<0>")
		)
		(pad "DM55" smd circle
			(at 10.637012 18.168874)
			(size 0.4318 0.4318)
			(layers "F.Cu" "F.Mask" "F.Paste")
			(net "M_L_CLK_DN<0>")
		)
		(pad "DM57" smd circle
			(at 12.354052 18.168874)
			(size 0.4318 0.4318)
			(layers "F.Cu" "F.Mask" "F.Paste")
			(net "M_L_CLK_DN<2>")
		)
		(pad "DM59" smd circle
			(at 14.071092 18.168874)
			(size 0.4318 0.4318)
			(layers "F.Cu" "F.Mask" "F.Paste")
			(net "M_L_MA<6>")
		)
		(pad "DM61" smd circle
			(at 15.787878 18.168874)
			(size 0.4318 0.4318)
			(layers "F.Cu" "F.Mask" "F.Paste")
			(net "M_L_BG<1>")
		)
		(pad "DM63" smd circle
			(at 17.504918 18.168874)
			(size 0.4318 0.4318)
			(layers "F.Cu" "F.Mask" "F.Paste")
			(net "M_L_CKE<0>")
		)
		(pad "DM65" smd circle
			(at 19.221958 18.168874)
			(size 0.4318 0.4318)
			(layers "F.Cu" "F.Mask" "F.Paste")
			(net "GND")
		)
		(pad "DM67" smd circle
			(at 20.938998 18.168874)
			(size 0.4318 0.4318)
			(layers "F.Cu" "F.Mask" "F.Paste")
			(net "TP_CPU1_RSVD_33")
		)
		(pad "DM69" smd circle
			(at 22.656038 18.168874)
			(size 0.4318 0.4318)
			(layers "F.Cu" "F.Mask" "F.Paste")
			(net "M_M_DQ<18>")
		)
		(pad "DM71" smd circle
			(at 24.373078 18.168874)
			(size 0.4318 0.4318)
			(layers "F.Cu" "F.Mask" "F.Paste")
			(net "M_M_DQ<23>")
		)
		(pad "DM73" smd circle
			(at 26.090118 18.168874)
			(size 0.4318 0.4318)
			(layers "F.Cu" "F.Mask" "F.Paste")
			(net "GND")
		)
		(pad "DM75" smd circle
			(at 27.806904 18.168874)
			(size 0.4318 0.4318)
			(layers "F.Cu" "F.Mask" "F.Paste")
			(net "M_K_DQS_DP<12>")
		)
		(pad "DM77" smd circle
			(at 29.523944 18.168874)
			(size 0.4318 0.4318)
			(layers "F.Cu" "F.Mask" "F.Paste")
			(net "GND")
		)
		(pad "DM79" smd circle
			(at 31.240984 18.168874)
			(size 0.4318 0.4318)
			(layers "F.Cu" "F.Mask" "F.Paste")
			(net "M_K_DQ<16>")
		)
		(pad "DM81" smd circle
			(at 32.958024 18.168874)
			(size 0.4318 0.4318)
			(layers "F.Cu" "F.Mask" "F.Paste")
			(net "M_K_DQS_DP<2>")
		)
		(pad "DM83" smd circle
			(at 34.675064 18.168874)
			(size 0.4318 0.4318)
			(layers "F.Cu" "F.Mask" "F.Paste")
			(net "GND")
		)
		(pad "DM85" smd custom
			(at 36.392104 18.168874 270)
			(size 0.10795 0.10795)
			(layers "F.Cu" "F.Mask" "F.Paste")
			(net "M_K_DQS_DN<10>")
			(options
				(clearance outline)
				(anchor circle)
			)
			(primitives
				(gr_poly
					(pts
						(arc
							(start 0.2159 -0.0381)
							(mid 0 -0.254)
							(end -0.2159 -0.0381)
						)
						(arc
							(start -0.2159 0.0381)
							(mid 0 0.254)
							(end 0.2159 0.0381)
						)
					)
					(width 0)
					(fill yes)
				)
			)
		)
		(pad "DN2" smd custom
			(at -36.392104 20.464526 90)
			(size 0.10795 0.10795)
			(layers "F.Cu" "F.Mask" "F.Paste")
			(net "GND")
			(options
				(clearance outline)
				(anchor circle)
			)
			(primitives
				(gr_poly
					(pts
						(arc
							(start 0.2159 -0.0381)
							(mid 0 -0.254)
							(end -0.2159 -0.0381)
						)
						(arc
							(start -0.2159 0.0381)
							(mid 0 0.254)
							(end 0.2159 0.0381)
						)
					)
					(width 0)
					(fill yes)
				)
			)
		)
		(pad "DN4" smd circle
			(at -34.675064 20.464526)
			(size 0.4318 0.4318)
			(layers "F.Cu" "F.Mask" "F.Paste")
			(net "TP_P3E_CPU1_PE1_MP_TXN<7>")
		)
		(pad "DN6" smd circle
			(at -32.958024 20.464526)
			(size 0.4318 0.4318)
			(layers "F.Cu" "F.Mask" "F.Paste")
			(net "P3E_CPU1_PE3_MP_TXP<8>")
		)
		(pad "DN8" smd circle
			(at -31.240984 20.464526)
			(size 0.4318 0.4318)
			(layers "F.Cu" "F.Mask" "F.Paste")
			(net "PVCCIO_CPU1")
		)
		(pad "DN10" smd circle
			(at -29.523944 20.464526)
			(size 0.4318 0.4318)
			(layers "F.Cu" "F.Mask" "F.Paste")
			(net "TP_P3E_CPU1_PE1_RSR3_RXP<9>")
		)
		(pad "DN12" smd circle
			(at -27.806904 20.464526)
			(size 0.4318 0.4318)
			(layers "F.Cu" "F.Mask" "F.Paste")
			(net "GND")
		)
		(pad "DN14" smd circle
			(at -26.090118 20.464526)
			(size 0.4318 0.4318)
			(layers "F.Cu" "F.Mask" "F.Paste")
			(net "P3E_CPU1_PE3_MP_RXN<6>")
		)
		(pad "DN16" smd circle
			(at -24.373078 20.464526)
			(size 0.4318 0.4318)
			(layers "F.Cu" "F.Mask" "F.Paste")
			(net "P3E_CPU1_PE3_MP_RXP<4>")
		)
		(pad "DN18" smd circle
			(at -22.656038 20.464526)
			(size 0.4318 0.4318)
			(layers "F.Cu" "F.Mask" "F.Paste")
			(net "GND")
		)
		(pad "DN20" smd circle
			(at -20.938998 20.464526)
			(size 0.4318 0.4318)
			(layers "F.Cu" "F.Mask" "F.Paste")
			(net "TP_CPU1_UPI2_RSVD_CB11")
		)
		(pad "DN22" smd circle
			(at -19.221958 20.464526)
			(size 0.4318 0.4318)
			(layers "F.Cu" "F.Mask" "F.Paste")
			(net "GND")
		)
		(pad "DN24" smd circle
			(at -17.504918 20.464526)
			(size 0.4318 0.4318)
			(layers "F.Cu" "F.Mask" "F.Paste")
			(net "M_K_DQ<56>")
		)
		(pad "DN26" smd circle
			(at -15.787878 20.464526)
			(size 0.4318 0.4318)
			(layers "F.Cu" "F.Mask" "F.Paste")
			(net "GND")
		)
		(pad "DN28" smd circle
			(at -14.071092 20.464526)
			(size 0.4318 0.4318)
			(layers "F.Cu" "F.Mask" "F.Paste")
			(net "M_K_DQ<54>")
		)
		(pad "DN30" smd circle
			(at -12.354052 20.464526)
			(size 0.4318 0.4318)
			(layers "F.Cu" "F.Mask" "F.Paste")
			(net "M_K_DQ<48>")
		)
		(pad "DN32" smd circle
			(at -10.637012 20.464526)
			(size 0.4318 0.4318)
			(layers "F.Cu" "F.Mask" "F.Paste")
			(net "GND")
		)
		(pad "DN34" smd circle
			(at -8.919972 20.464526)
			(size 0.4318 0.4318)
			(layers "F.Cu" "F.Mask" "F.Paste")
			(net "M_K_DQ<46>")
		)
		(pad "DN36" smd circle
			(at -7.202932 20.464526)
			(size 0.4318 0.4318)
			(layers "F.Cu" "F.Mask" "F.Paste")
			(net "M_K_DQ<40>")
		)
		(pad "DN38" smd circle
			(at -5.485892 20.464526)
			(size 0.4318 0.4318)
			(layers "F.Cu" "F.Mask" "F.Paste")
			(net "GND")
		)
		(pad "DN40" smd circle
			(at -3.769106 20.464526)
			(size 0.4318 0.4318)
			(layers "F.Cu" "F.Mask" "F.Paste")
			(net "M_L_DQ<38>")
		)
		(pad "DN42" smd circle
			(at -2.052066 20.464526)
			(size 0.4318 0.4318)
			(layers "F.Cu" "F.Mask" "F.Paste")
			(net "M_L_DQ<37>")
		)
		(pad "DN44" smd circle
			(at 1.193546 18.664428)
			(size 0.508 0.508)
			(layers "F.Cu" "F.Mask" "F.Paste")
			(net "GND")
		)
		(pad "DN46" smd circle
			(at 2.910586 18.664428)
			(size 0.4318 0.4318)
			(layers "F.Cu" "F.Mask" "F.Paste")
			(net "M_L_CS_N<7>")
		)
		(pad "DN48" smd circle
			(at 4.627626 18.664428)
			(size 0.4318 0.4318)
			(layers "F.Cu" "F.Mask" "F.Paste")
			(net "M_L_ODT<1>")
		)
		(pad "DN50" smd circle
			(at 6.344412 18.664428)
			(size 0.4318 0.4318)
			(layers "F.Cu" "F.Mask" "F.Paste")
			(net "M_L_CS_N<1>")
		)
		(pad "DN52" smd circle
			(at 8.061452 18.664428)
			(size 0.4318 0.4318)
			(layers "F.Cu" "F.Mask" "F.Paste")
			(net "M_L_MA<16>")
		)
		(pad "DN54" smd circle
			(at 9.778492 18.664428)
			(size 0.4318 0.4318)
			(layers "F.Cu" "F.Mask" "F.Paste")
			(net "M_L_CLK_DP<0>")
		)
		(pad "DN56" smd circle
			(at 11.495532 18.664428)
			(size 0.4318 0.4318)
			(layers "F.Cu" "F.Mask" "F.Paste")
			(net "M_L_CLK_DP<2>")
		)
		(pad "DN58" smd circle
			(at 13.212572 18.664428)
			(size 0.4318 0.4318)
			(layers "F.Cu" "F.Mask" "F.Paste")
			(net "M_L_MA<5>")
		)
		(pad "DN60" smd circle
			(at 14.929612 18.664428)
			(size 0.4318 0.4318)
			(layers "F.Cu" "F.Mask" "F.Paste")
			(net "M_L_MA<12>")
		)
		(pad "DN62" smd circle
			(at 16.646398 18.664428)
			(size 0.4318 0.4318)
			(layers "F.Cu" "F.Mask" "F.Paste")
			(net "TP_CPU1_RSVD_32")
		)
		(pad "DN64" smd circle
			(at 18.363438 18.664428)
			(size 0.4318 0.4318)
			(layers "F.Cu" "F.Mask" "F.Paste")
			(net "M_L_CKE<1>")
		)
		(pad "DN66" smd circle
			(at 20.080478 18.664428)
			(size 0.4318 0.4318)
			(layers "F.Cu" "F.Mask" "F.Paste")
			(net "TP_CPU1_RSVD_31")
		)
		(pad "DN68" smd circle
			(at 21.797518 18.664428)
			(size 0.4318 0.4318)
			(layers "F.Cu" "F.Mask" "F.Paste")
			(net "GND")
		)
		(pad "DN70" smd circle
			(at 23.514558 18.664428)
			(size 0.4318 0.4318)
			(layers "F.Cu" "F.Mask" "F.Paste")
			(net "M_M_DQ<19>")
		)
		(pad "DN72" smd circle
			(at 25.231598 18.664428)
			(size 0.4318 0.4318)
			(layers "F.Cu" "F.Mask" "F.Paste")
			(net "GND")
		)
		(pad "DN74" smd circle
			(at 26.948384 18.664428)
			(size 0.4318 0.4318)
			(layers "F.Cu" "F.Mask" "F.Paste")
			(net "M_K_DQ<30>")
		)
		(pad "DN76" smd circle
			(at 28.665424 18.664428)
			(size 0.4318 0.4318)
			(layers "F.Cu" "F.Mask" "F.Paste")
			(net "M_K_DQ<24>")
		)
		(pad "DN78" smd circle
			(at 30.382464 18.664428)
			(size 0.4318 0.4318)
			(layers "F.Cu" "F.Mask" "F.Paste")
			(net "GND")
		)
		(pad "DN80" smd circle
			(at 32.099504 18.664428)
			(size 0.4318 0.4318)
			(layers "F.Cu" "F.Mask" "F.Paste")
			(net "M_K_DQS_DN<11>")
		)
		(pad "DN82" smd circle
			(at 33.816544 18.664428)
			(size 0.4318 0.4318)
			(layers "F.Cu" "F.Mask" "F.Paste")
			(net "M_K_DQ<23>")
		)
		(pad "DN84" smd circle
			(at 35.533584 18.664428)
			(size 0.4318 0.4318)
			(layers "F.Cu" "F.Mask" "F.Paste")
			(net "M_K_DQS_DN<1>")
		)
		(pad "DP3" smd circle
			(at -35.533584 20.959572)
			(size 0.4318 0.4318)
			(layers "F.Cu" "F.Mask" "F.Paste")
			(net "TP_P3E_CPU1_PE1_MP_TXP<7>")
		)
		(pad "DP5" smd circle
			(at -33.816544 20.959572)
			(size 0.4318 0.4318)
			(layers "F.Cu" "F.Mask" "F.Paste")
			(net "P3E_CPU1_PE3_MP_TXN<9>")
		)
		(pad "DP7" smd circle
			(at -32.099504 20.959572)
			(size 0.4318 0.4318)
			(layers "F.Cu" "F.Mask" "F.Paste")
			(net "P3E_CPU1_PE3_MP_TXP<7>")
		)
		(pad "DP9" smd circle
			(at -30.382464 20.959572)
			(size 0.4318 0.4318)
			(layers "F.Cu" "F.Mask" "F.Paste")
			(net "GND")
		)
		(pad "DP11" smd circle
			(at -28.665424 20.959572)
			(size 0.4318 0.4318)
			(layers "F.Cu" "F.Mask" "F.Paste")
			(net "TP_P3E_CPU1_PE1_RSR3_RXN<9>")
		)
		(pad "DP13" smd circle
			(at -26.948384 20.959572)
			(size 0.4318 0.4318)
			(layers "F.Cu" "F.Mask" "F.Paste")
			(net "TP_P3E_CPU1_PE1_RSR3_RXP<11>")
		)
		(pad "DP15" smd circle
			(at -25.231598 20.959572)
			(size 0.4318 0.4318)
			(layers "F.Cu" "F.Mask" "F.Paste")
			(net "P3E_CPU1_PE3_MP_RXP<5>")
		)
		(pad "DP17" smd circle
			(at -23.514558 20.959572)
			(size 0.4318 0.4318)
			(layers "F.Cu" "F.Mask" "F.Paste")
			(net "TP_CPU1_RSVD_30")
		)
		(pad "DP19" smd circle
			(at -21.797518 20.959572)
			(size 0.4318 0.4318)
			(layers "F.Cu" "F.Mask" "F.Paste")
			(net "PVCCIO_CPU1")
		)
		(pad "DP21" smd circle
			(at -20.080478 20.959572)
			(size 0.4318 0.4318)
			(layers "F.Cu" "F.Mask" "F.Paste")
			(net "TP_CPU1_UPI2_RSVD_CA12")
		)
		(pad "DP23" smd circle
			(at -18.363438 20.959572)
			(size 0.4318 0.4318)
			(layers "F.Cu" "F.Mask" "F.Paste")
			(net "M_K_DQS_DP<16>")
		)
		(pad "DP25" smd circle
			(at -16.646398 20.959572)
			(size 0.4318 0.4318)
			(layers "F.Cu" "F.Mask" "F.Paste")
			(net "M_K_DQ<60>")
		)
		(pad "DP27" smd circle
			(at -14.929612 20.959572)
			(size 0.4318 0.4318)
			(layers "F.Cu" "F.Mask" "F.Paste")
			(net "M_K_DQ<50>")
		)
		(pad "DP29" smd circle
			(at -13.212572 20.959572)
			(size 0.4318 0.4318)
			(layers "F.Cu" "F.Mask" "F.Paste")
			(net "M_K_DQS_DP<15>")
		)
		(pad "DP31" smd circle
			(at -11.495532 20.959572)
			(size 0.4318 0.4318)
			(layers "F.Cu" "F.Mask" "F.Paste")
			(net "M_K_DQ<52>")
		)
		(pad "DP33" smd circle
			(at -9.778492 20.959572)
			(size 0.4318 0.4318)
			(layers "F.Cu" "F.Mask" "F.Paste")
			(net "M_K_DQ<42>")
		)
		(pad "DP35" smd circle
			(at -8.061452 20.959572)
			(size 0.4318 0.4318)
			(layers "F.Cu" "F.Mask" "F.Paste")
			(net "M_K_DQS_DN<14>")
		)
		(pad "DP37" smd circle
			(at -6.344412 20.959572)
			(size 0.4318 0.4318)
			(layers "F.Cu" "F.Mask" "F.Paste")
			(net "M_K_DQ<44>")
		)
		(pad "DP39" smd circle
			(at -4.627626 20.959572)
			(size 0.4318 0.4318)
			(layers "F.Cu" "F.Mask" "F.Paste")
			(net "M_L_DQ<34>")
		)
		(pad "DP41" smd circle
			(at -2.910586 20.959572)
			(size 0.4318 0.4318)
			(layers "F.Cu" "F.Mask" "F.Paste")
			(net "M_L_DQS_DN<13>")
		)
		(pad "DP45" smd circle
			(at 2.052066 19.159474)
			(size 0.4318 0.4318)
			(layers "F.Cu" "F.Mask" "F.Paste")
			(net "GND")
		)
		(pad "DP47" smd circle
			(at 3.769106 19.159474)
			(size 0.4318 0.4318)
			(layers "F.Cu" "F.Mask" "F.Paste")
			(net "GND")
		)
		(pad "DP49" smd circle
			(at 5.485892 19.159474)
			(size 0.4318 0.4318)
			(layers "F.Cu" "F.Mask" "F.Paste")
			(net "GND")
		)
		(pad "DP51" smd circle
			(at 7.202932 19.159474)
			(size 0.4318 0.4318)
			(layers "F.Cu" "F.Mask" "F.Paste")
			(net "GND")
		)
		(pad "DP53" smd circle
			(at 8.919972 19.159474)
			(size 0.4318 0.4318)
			(layers "F.Cu" "F.Mask" "F.Paste")
			(net "GND")
		)
		(pad "DP55" smd circle
			(at 10.637012 19.159474)
			(size 0.4318 0.4318)
			(layers "F.Cu" "F.Mask" "F.Paste")
			(net "GND")
		)
		(pad "DP57" smd circle
			(at 12.354052 19.159474)
			(size 0.4318 0.4318)
			(layers "F.Cu" "F.Mask" "F.Paste")
			(net "GND")
		)
		(pad "DP59" smd circle
			(at 14.071092 19.159474)
			(size 0.4318 0.4318)
			(layers "F.Cu" "F.Mask" "F.Paste")
			(net "GND")
		)
		(pad "DP61" smd circle
			(at 15.787878 19.159474)
			(size 0.4318 0.4318)
			(layers "F.Cu" "F.Mask" "F.Paste")
			(net "GND")
		)
		(pad "DP63" smd circle
			(at 17.504918 19.159474)
			(size 0.4318 0.4318)
			(layers "F.Cu" "F.Mask" "F.Paste")
			(net "GND")
		)
		(pad "DP65" smd circle
			(at 19.221958 19.159474)
			(size 0.4318 0.4318)
			(layers "F.Cu" "F.Mask" "F.Paste")
			(net "TP_CPU1_RSVD_29")
		)
		(pad "DP67" smd circle
			(at 20.938998 19.159474)
			(size 0.4318 0.4318)
			(layers "F.Cu" "F.Mask" "F.Paste")
			(net "GND")
		)
		(pad "DP69" smd circle
			(at 22.656038 19.159474)
			(size 0.4318 0.4318)
			(layers "F.Cu" "F.Mask" "F.Paste")
			(net "GND")
		)
		(pad "DP71" smd circle
			(at 24.373078 19.159474)
			(size 0.4318 0.4318)
			(layers "F.Cu" "F.Mask" "F.Paste")
			(net "GND")
		)
		(pad "DP73" smd circle
			(at 26.090118 19.159474)
			(size 0.4318 0.4318)
			(layers "F.Cu" "F.Mask" "F.Paste")
			(net "M_K_DQ<26>")
		)
		(pad "DP75" smd circle
			(at 27.806904 19.159474)
			(size 0.4318 0.4318)
			(layers "F.Cu" "F.Mask" "F.Paste")
			(net "M_K_DQS_DN<12>")
		)
		(pad "DP77" smd circle
			(at 29.523944 19.159474)
			(size 0.4318 0.4318)
			(layers "F.Cu" "F.Mask" "F.Paste")
			(net "M_K_DQ<28>")
		)
		(pad "DP79" smd circle
			(at 31.240984 19.159474)
			(size 0.4318 0.4318)
			(layers "F.Cu" "F.Mask" "F.Paste")
			(net "M_K_DQS_DP<11>")
		)
		(pad "DP81" smd circle
			(at 32.958024 19.159474)
			(size 0.4318 0.4318)
			(layers "F.Cu" "F.Mask" "F.Paste")
			(net "GND")
		)
		(pad "DP83" smd circle
			(at 34.675064 19.159474)
			(size 0.4318 0.4318)
			(layers "F.Cu" "F.Mask" "F.Paste")
			(net "GND")
		)
		(pad "DP85" smd custom
			(at 36.392104 19.159474 270)
			(size 0.10795 0.10795)
			(layers "F.Cu" "F.Mask" "F.Paste")
			(net "M_K_DQS_DP<1>")
			(options
				(clearance outline)
				(anchor circle)
			)
			(primitives
				(gr_poly
					(pts
						(arc
							(start 0.2159 -0.0381)
							(mid 0 -0.254)
							(end -0.2159 -0.0381)
						)
						(arc
							(start -0.2159 0.0381)
							(mid 0 0.254)
							(end 0.2159 0.0381)
						)
					)
					(width 0)
					(fill yes)
				)
			)
		)
		(pad "DR2" smd custom
			(at -36.392104 21.455126 90)
			(size 0.10795 0.10795)
			(layers "F.Cu" "F.Mask" "F.Paste")
			(net "PVCCIO_CPU1")
			(options
				(clearance outline)
				(anchor circle)
			)
			(primitives
				(gr_poly
					(pts
						(arc
							(start 0.2159 -0.0381)
							(mid 0 -0.254)
							(end -0.2159 -0.0381)
						)
						(arc
							(start -0.2159 0.0381)
							(mid 0 0.254)
							(end 0.2159 0.0381)
						)
					)
					(width 0)
					(fill yes)
				)
			)
		)
		(pad "DR4" smd circle
			(at -34.675064 21.455126)
			(size 0.4318 0.4318)
			(layers "F.Cu" "F.Mask" "F.Paste")
			(net "TP_P3E_CPU1_PE1_RSR3_TXP<8>")
		)
		(pad "DR6" smd circle
			(at -32.958024 21.455126)
			(size 0.4318 0.4318)
			(layers "F.Cu" "F.Mask" "F.Paste")
			(net "GND")
		)
		(pad "DR8" smd circle
			(at -31.240984 21.455126)
			(size 0.4318 0.4318)
			(layers "F.Cu" "F.Mask" "F.Paste")
			(net "P3E_CPU1_PE3_MP_TXN<7>")
		)
		(pad "DR10" smd circle
			(at -29.523944 21.455126)
			(size 0.4318 0.4318)
			(layers "F.Cu" "F.Mask" "F.Paste")
			(net "PVCCIO_CPU1")
		)
		(pad "DR12" smd circle
			(at -27.806904 21.455126)
			(size 0.4318 0.4318)
			(layers "F.Cu" "F.Mask" "F.Paste")
			(net "TP_P3E_CPU1_PE1_RSR3_RXP<10>")
		)
		(pad "DR14" smd circle
			(at -26.090118 21.455126)
			(size 0.4318 0.4318)
			(layers "F.Cu" "F.Mask" "F.Paste")
			(net "P3E_CPU1_PE3_MP_RXN<5>")
		)
		(pad "DR16" smd circle
			(at -24.373078 21.455126)
			(size 0.4318 0.4318)
			(layers "F.Cu" "F.Mask" "F.Paste")
			(net "P3E_CPU1_PE3_MP_RXN<4>")
		)
		(pad "DR18" smd circle
			(at -22.656038 21.455126)
			(size 0.4318 0.4318)
			(layers "F.Cu" "F.Mask" "F.Paste")
			(net "P3E_CPU1_PE3_MP_RXP<3>")
		)
		(pad "DR20" smd circle
			(at -20.938998 21.455126)
			(size 0.4318 0.4318)
			(layers "F.Cu" "F.Mask" "F.Paste")
			(net "GND")
		)
		(pad "DR22" smd circle
			(at -19.221958 21.455126)
			(size 0.4318 0.4318)
			(layers "F.Cu" "F.Mask" "F.Paste")
			(net "GND")
		)
		(pad "DR24" smd circle
			(at -17.504918 21.455126)
			(size 0.4318 0.4318)
			(layers "F.Cu" "F.Mask" "F.Paste")
			(net "GND")
		)
		(pad "DR26" smd circle
			(at -15.787878 21.455126)
			(size 0.4318 0.4318)
			(layers "F.Cu" "F.Mask" "F.Paste")
			(net "GND")
		)
		(pad "DR28" smd circle
			(at -14.071092 21.455126)
			(size 0.4318 0.4318)
			(layers "F.Cu" "F.Mask" "F.Paste")
			(net "GND")
		)
		(pad "DR30" smd circle
			(at -12.354052 21.455126)
			(size 0.4318 0.4318)
			(layers "F.Cu" "F.Mask" "F.Paste")
			(net "GND")
		)
		(pad "DR32" smd circle
			(at -10.637012 21.455126)
			(size 0.4318 0.4318)
			(layers "F.Cu" "F.Mask" "F.Paste")
			(net "GND")
		)
		(pad "DR34" smd circle
			(at -8.919972 21.455126)
			(size 0.4318 0.4318)
			(layers "F.Cu" "F.Mask" "F.Paste")
			(net "GND")
		)
		(pad "DR36" smd circle
			(at -7.202932 21.455126)
			(size 0.4318 0.4318)
			(layers "F.Cu" "F.Mask" "F.Paste")
			(net "GND")
		)
		(pad "DR38" smd circle
			(at -5.485892 21.455126)
			(size 0.4318 0.4318)
			(layers "F.Cu" "F.Mask" "F.Paste")
			(net "GND")
		)
		(pad "DR40" smd circle
			(at -3.769106 21.455126)
			(size 0.4318 0.4318)
			(layers "F.Cu" "F.Mask" "F.Paste")
			(net "GND")
		)
		(pad "DR42" smd circle
			(at -2.052066 21.455126)
			(size 0.4318 0.4318)
			(layers "F.Cu" "F.Mask" "F.Paste")
			(net "GND")
		)
		(pad "DR44" smd circle
			(at 1.193546 19.655028)
			(size 0.508 0.508)
			(layers "F.Cu" "F.Mask" "F.Paste")
			(net "TP_CPU1_RSVD_28")
		)
		(pad "DR46" smd circle
			(at 2.910586 19.655028)
			(size 0.4318 0.4318)
			(layers "F.Cu" "F.Mask" "F.Paste")
			(net "M_L_CS_N<2>")
		)
		(pad "DR48" smd circle
			(at 4.627626 19.655028)
			(size 0.4318 0.4318)
			(layers "F.Cu" "F.Mask" "F.Paste")
			(net "M_L_MA<17>")
		)
		(pad "DR50" smd circle
			(at 6.344412 19.655028)
			(size 0.4318 0.4318)
			(layers "F.Cu" "F.Mask" "F.Paste")
			(net "M_L_ODT<0>")
		)
		(pad "DR52" smd circle
			(at 8.061452 19.655028)
			(size 0.4318 0.4318)
			(layers "F.Cu" "F.Mask" "F.Paste")
			(net "M_L_MA<15>")
		)
		(pad "DR54" smd circle
			(at 9.778492 19.655028)
			(size 0.4318 0.4318)
			(layers "F.Cu" "F.Mask" "F.Paste")
			(net "M_L_CLK_DN<1>")
		)
		(pad "DR56" smd circle
			(at 11.495532 19.655028)
			(size 0.4318 0.4318)
			(layers "F.Cu" "F.Mask" "F.Paste")
			(net "M_L_CLK_DP<3>")
		)
		(pad "DR58" smd circle
			(at 13.212572 19.655028)
			(size 0.4318 0.4318)
			(layers "F.Cu" "F.Mask" "F.Paste")
			(net "M_L_MA<3>")
		)
		(pad "DR60" smd circle
			(at 14.929612 19.655028)
			(size 0.4318 0.4318)
			(layers "F.Cu" "F.Mask" "F.Paste")
			(net "M_L_MA<11>")
		)
		(pad "DR62" smd circle
			(at 16.646398 19.655028)
			(size 0.4318 0.4318)
			(layers "F.Cu" "F.Mask" "F.Paste")
			(net "M_L_ACT_N")
		)
		(pad "DR64" smd circle
			(at 18.363438 19.655028)
			(size 0.4318 0.4318)
			(layers "F.Cu" "F.Mask" "F.Paste")
			(net "M_L_CKE<3>")
		)
		(pad "DR66" smd circle
			(at 20.080478 19.655028)
			(size 0.4318 0.4318)
			(layers "F.Cu" "F.Mask" "F.Paste")
			(net "GND")
		)
		(pad "DR68" smd circle
			(at 21.797518 19.655028)
			(size 0.4318 0.4318)
			(layers "F.Cu" "F.Mask" "F.Paste")
			(net "GND")
		)
		(pad "DR70" smd circle
			(at 23.514558 19.655028)
			(size 0.4318 0.4318)
			(layers "F.Cu" "F.Mask" "F.Paste")
			(net "GND")
		)
		(pad "DR72" smd circle
			(at 25.231598 19.655028)
			(size 0.4318 0.4318)
			(layers "F.Cu" "F.Mask" "F.Paste")
			(net "GND")
		)
		(pad "DR74" smd circle
			(at 26.948384 19.655028)
			(size 0.4318 0.4318)
			(layers "F.Cu" "F.Mask" "F.Paste")
			(net "GND")
		)
		(pad "DR76" smd circle
			(at 28.665424 19.655028)
			(size 0.4318 0.4318)
			(layers "F.Cu" "F.Mask" "F.Paste")
			(net "GND")
		)
		(pad "DR78" smd circle
			(at 30.382464 19.655028)
			(size 0.4318 0.4318)
			(layers "F.Cu" "F.Mask" "F.Paste")
			(net "GND")
		)
		(pad "DR80" smd circle
			(at 32.099504 19.655028)
			(size 0.4318 0.4318)
			(layers "F.Cu" "F.Mask" "F.Paste")
			(net "M_K_DQ<22>")
		)
		(pad "DR82" smd circle
			(at 33.816544 19.655028)
			(size 0.4318 0.4318)
			(layers "F.Cu" "F.Mask" "F.Paste")
			(net "M_K_DQ<19>")
		)
		(pad "DR84" smd circle
			(at 35.533584 19.655028)
			(size 0.4318 0.4318)
			(layers "F.Cu" "F.Mask" "F.Paste")
			(net "M_K_DQ<14>")
		)
		(pad "DT3" smd circle
			(at -35.533584 21.950172)
			(size 0.4318 0.4318)
			(layers "F.Cu" "F.Mask" "F.Paste")
			(net "GND")
		)
		(pad "DT5" smd circle
			(at -33.816544 21.950172)
			(size 0.4318 0.4318)
			(layers "F.Cu" "F.Mask" "F.Paste")
			(net "TP_P3E_CPU1_PE1_RSR3_TXN<8>")
		)
		(pad "DT7" smd circle
			(at -32.099504 21.950172)
			(size 0.4318 0.4318)
			(layers "F.Cu" "F.Mask" "F.Paste")
			(net "TP_P3E_CPU1_PE1_RSR3_TXP<12>")
		)
		(pad "DT9" smd circle
			(at -30.382464 21.950172)
			(size 0.4318 0.4318)
			(layers "F.Cu" "F.Mask" "F.Paste")
			(net "P3E_CPU1_PE3_MP_TXP<6>")
		)
		(pad "DT11" smd circle
			(at -28.665424 21.950172)
			(size 0.4318 0.4318)
			(layers "F.Cu" "F.Mask" "F.Paste")
			(net "TP_P3E_CPU1_PE1_RSR3_RXN<10>")
		)
		(pad "DT13" smd circle
			(at -26.948384 21.950172)
			(size 0.4318 0.4318)
			(layers "F.Cu" "F.Mask" "F.Paste")
			(net "TP_P3E_CPU1_PE1_RSR3_RXN<11>")
		)
		(pad "DT15" smd circle
			(at -25.231598 21.950172)
			(size 0.4318 0.4318)
			(layers "F.Cu" "F.Mask" "F.Paste")
			(net "TP_P3E_CPU1_PE1_RSR3_RXP<15>")
		)
		(pad "DT17" smd circle
			(at -23.514558 21.950172)
			(size 0.4318 0.4318)
			(layers "F.Cu" "F.Mask" "F.Paste")
			(net "GND")
		)
		(pad "DT19" smd circle
			(at -21.797518 21.950172)
			(size 0.4318 0.4318)
			(layers "F.Cu" "F.Mask" "F.Paste")
			(net "P3E_CPU1_PE3_MP_RXN<3>")
		)
		(pad "DT21" smd circle
			(at -20.080478 21.950172)
			(size 0.4318 0.4318)
			(layers "F.Cu" "F.Mask" "F.Paste")
			(net "TP_CPU1_UPI2_RSVD_CC12")
		)
		(pad "DT23" smd circle
			(at -18.363438 21.950172)
			(size 0.4318 0.4318)
			(layers "F.Cu" "F.Mask" "F.Paste")
			(net "M_K_DQS_DP<7>")
		)
		(pad "DT25" smd circle
			(at -16.646398 21.950172)
			(size 0.4318 0.4318)
			(layers "F.Cu" "F.Mask" "F.Paste")
			(net "M_K_DQ<61>")
		)
		(pad "DT27" smd circle
			(at -14.929612 21.950172)
			(size 0.4318 0.4318)
			(layers "F.Cu" "F.Mask" "F.Paste")
			(net "M_K_DQ<51>")
		)
		(pad "DT29" smd circle
			(at -13.212572 21.950172)
			(size 0.4318 0.4318)
			(layers "F.Cu" "F.Mask" "F.Paste")
			(net "M_K_DQS_DP<6>")
		)
		(pad "DT31" smd circle
			(at -11.495532 21.950172)
			(size 0.4318 0.4318)
			(layers "F.Cu" "F.Mask" "F.Paste")
			(net "M_K_DQ<53>")
		)
		(pad "DT33" smd circle
			(at -9.778492 21.950172)
			(size 0.4318 0.4318)
			(layers "F.Cu" "F.Mask" "F.Paste")
			(net "M_K_DQ<43>")
		)
		(pad "DT35" smd circle
			(at -8.061452 21.950172)
			(size 0.4318 0.4318)
			(layers "F.Cu" "F.Mask" "F.Paste")
			(net "M_K_DQS_DP<5>")
		)
		(pad "DT37" smd circle
			(at -6.344412 21.950172)
			(size 0.4318 0.4318)
			(layers "F.Cu" "F.Mask" "F.Paste")
			(net "M_K_DQ<45>")
		)
		(pad "DT39" smd circle
			(at -4.627626 21.950172)
			(size 0.4318 0.4318)
			(layers "F.Cu" "F.Mask" "F.Paste")
			(net "M_L_DQ<35>")
		)
		(pad "DT41" smd circle
			(at -2.910586 21.950172)
			(size 0.4318 0.4318)
			(layers "F.Cu" "F.Mask" "F.Paste")
			(net "M_L_DQS_DP<4>")
		)
		(pad "DT45" smd circle
			(at 2.052066 20.150074)
			(size 0.4318 0.4318)
			(layers "F.Cu" "F.Mask" "F.Paste")
			(net "M_L_CS_N<6>")
		)
		(pad "DT47" smd circle
			(at 3.769106 20.150074)
			(size 0.4318 0.4318)
			(layers "F.Cu" "F.Mask" "F.Paste")
			(net "M_L_C<2>")
		)
		(pad "DT49" smd circle
			(at 5.485892 20.150074)
			(size 0.4318 0.4318)
			(layers "F.Cu" "F.Mask" "F.Paste")
			(net "M_L_ODT<2>")
		)
		(pad "DT51" smd circle
			(at 7.202932 20.150074)
			(size 0.4318 0.4318)
			(layers "F.Cu" "F.Mask" "F.Paste")
			(net "M_L_MA<13>")
		)
		(pad "DT53" smd circle
			(at 8.919972 20.150074)
			(size 0.4318 0.4318)
			(layers "F.Cu" "F.Mask" "F.Paste")
			(net "M_L_CLK_DP<1>")
		)
		(pad "DT55" smd circle
			(at 10.637012 20.150074)
			(size 0.4318 0.4318)
			(layers "F.Cu" "F.Mask" "F.Paste")
			(net "M_L_MA<10>")
		)
		(pad "DT57" smd circle
			(at 12.354052 20.150074)
			(size 0.4318 0.4318)
			(layers "F.Cu" "F.Mask" "F.Paste")
			(net "M_L_CLK_DN<3>")
		)
		(pad "DT59" smd circle
			(at 14.071092 20.150074)
			(size 0.4318 0.4318)
			(layers "F.Cu" "F.Mask" "F.Paste")
			(net "M_L_MA<4>")
		)
		(pad "DT61" smd circle
			(at 15.787878 20.150074)
			(size 0.4318 0.4318)
			(layers "F.Cu" "F.Mask" "F.Paste")
			(net "M_L_ALERT_N")
		)
		(pad "DT63" smd circle
			(at 17.504918 20.150074)
			(size 0.4318 0.4318)
			(layers "F.Cu" "F.Mask" "F.Paste")
			(net "M_K_MA<12>")
		)
		(pad "DT65" smd circle
			(at 19.221958 20.150074)
			(size 0.4318 0.4318)
			(layers "F.Cu" "F.Mask" "F.Paste")
			(net "GND")
		)
		(pad "DT67" smd circle
			(at 20.938998 20.150074)
			(size 0.4318 0.4318)
			(layers "F.Cu" "F.Mask" "F.Paste")
			(net "M_L_DQS_DP<17>")
		)
		(pad "DT69" smd circle
			(at 22.656038 20.150074)
			(size 0.4318 0.4318)
			(layers "F.Cu" "F.Mask" "F.Paste")
			(net "GND")
		)
		(pad "DT71" smd circle
			(at 24.373078 20.150074)
			(size 0.4318 0.4318)
			(layers "F.Cu" "F.Mask" "F.Paste")
			(net "TP_CPU1_RSVD_27")
		)
		(pad "DT73" smd circle
			(at 26.090118 20.150074)
			(size 0.4318 0.4318)
			(layers "F.Cu" "F.Mask" "F.Paste")
			(net "M_K_DQ<27>")
		)
		(pad "DT75" smd circle
			(at 27.806904 20.150074)
			(size 0.4318 0.4318)
			(layers "F.Cu" "F.Mask" "F.Paste")
			(net "M_K_DQS_DP<3>")
		)
		(pad "DT77" smd circle
			(at 29.523944 20.150074)
			(size 0.4318 0.4318)
			(layers "F.Cu" "F.Mask" "F.Paste")
			(net "M_K_DQ<29>")
		)
		(pad "DT79" smd circle
			(at 31.240984 20.150074)
			(size 0.4318 0.4318)
			(layers "F.Cu" "F.Mask" "F.Paste")
			(net "GND")
		)
		(pad "DT81" smd circle
			(at 32.958024 20.150074)
			(size 0.4318 0.4318)
			(layers "F.Cu" "F.Mask" "F.Paste")
			(net "M_K_DQ<18>")
		)
		(pad "DT83" smd circle
			(at 34.675064 20.150074)
			(size 0.4318 0.4318)
			(layers "F.Cu" "F.Mask" "F.Paste")
			(net "GND")
		)
		(pad "DT85" smd custom
			(at 36.392104 20.150074 270)
			(size 0.10795 0.10795)
			(layers "F.Cu" "F.Mask" "F.Paste")
			(net "GND")
			(options
				(clearance outline)
				(anchor circle)
			)
			(primitives
				(gr_poly
					(pts
						(arc
							(start 0.2159 -0.0381)
							(mid 0 -0.254)
							(end -0.2159 -0.0381)
						)
						(arc
							(start -0.2159 0.0381)
							(mid 0 0.254)
							(end 0.2159 0.0381)
						)
					)
					(width 0)
					(fill yes)
				)
			)
		)
		(pad "DU2" smd custom
			(at -36.392104 22.445726 90)
			(size 0.10795 0.10795)
			(layers "F.Cu" "F.Mask" "F.Paste")
			(net "TP_P3E_CPU1_PE1_RSR3_TXP<9>")
			(options
				(clearance outline)
				(anchor circle)
			)
			(primitives
				(gr_poly
					(pts
						(arc
							(start 0.2159 -0.0381)
							(mid 0 -0.254)
							(end -0.2159 -0.0381)
						)
						(arc
							(start -0.2159 0.0381)
							(mid 0 0.254)
							(end 0.2159 0.0381)
						)
					)
					(width 0)
					(fill yes)
				)
			)
		)
		(pad "DU4" smd circle
			(at -34.675064 22.445726)
			(size 0.4318 0.4318)
			(layers "F.Cu" "F.Mask" "F.Paste")
			(net "TP_P3E_CPU1_PE1_RSR3_TXP<10>")
		)
		(pad "DU6" smd circle
			(at -32.958024 22.445726)
			(size 0.4318 0.4318)
			(layers "F.Cu" "F.Mask" "F.Paste")
			(net "TP_P3E_CPU1_PE1_RSR3_TXN<11>")
		)
		(pad "DU8" smd circle
			(at -31.240984 22.445726)
			(size 0.4318 0.4318)
			(layers "F.Cu" "F.Mask" "F.Paste")
			(net "P3E_CPU1_PE3_MP_TXN<6>")
		)
		(pad "DU10" smd circle
			(at -29.523944 22.445726)
			(size 0.4318 0.4318)
			(layers "F.Cu" "F.Mask" "F.Paste")
			(net "GND")
		)
		(pad "DU12" smd circle
			(at -27.806904 22.445726)
			(size 0.4318 0.4318)
			(layers "F.Cu" "F.Mask" "F.Paste")
			(net "TP_P3E_CPU1_PE1_RSR3_RXP<12>")
		)
		(pad "DU14" smd circle
			(at -26.090118 22.445726)
			(size 0.4318 0.4318)
			(layers "F.Cu" "F.Mask" "F.Paste")
			(net "GND")
		)
		(pad "DU16" smd circle
			(at -24.373078 22.445726)
			(size 0.4318 0.4318)
			(layers "F.Cu" "F.Mask" "F.Paste")
			(net "TP_P3E_CPU1_PE1_RSR3_RXN<15>")
		)
		(pad "DU18" smd circle
			(at -22.656038 22.445726)
			(size 0.4318 0.4318)
			(layers "F.Cu" "F.Mask" "F.Paste")
			(net "P3E_CPU1_PE3_MP_RXP<1>")
		)
		(pad "DU20" smd circle
			(at -20.938998 22.445726)
			(size 0.4318 0.4318)
			(layers "F.Cu" "F.Mask" "F.Paste")
			(net "PVCCIO_CPU1")
		)
		(pad "DU22" smd circle
			(at -19.221958 22.445726)
			(size 0.4318 0.4318)
			(layers "F.Cu" "F.Mask" "F.Paste")
			(net "GND")
		)
		(pad "DU24" smd circle
			(at -17.504918 22.445726)
			(size 0.4318 0.4318)
			(layers "F.Cu" "F.Mask" "F.Paste")
			(net "M_K_DQ<57>")
		)
		(pad "DU26" smd circle
			(at -15.787878 22.445726)
			(size 0.4318 0.4318)
			(layers "F.Cu" "F.Mask" "F.Paste")
			(net "GND")
		)
		(pad "DU28" smd circle
			(at -14.071092 22.445726)
			(size 0.4318 0.4318)
			(layers "F.Cu" "F.Mask" "F.Paste")
			(net "M_K_DQ<55>")
		)
		(pad "DU30" smd circle
			(at -12.354052 22.445726)
			(size 0.4318 0.4318)
			(layers "F.Cu" "F.Mask" "F.Paste")
			(net "M_K_DQ<49>")
		)
		(pad "DU32" smd circle
			(at -10.637012 22.445726)
			(size 0.4318 0.4318)
			(layers "F.Cu" "F.Mask" "F.Paste")
			(net "GND")
		)
		(pad "DU34" smd circle
			(at -8.919972 22.445726)
			(size 0.4318 0.4318)
			(layers "F.Cu" "F.Mask" "F.Paste")
			(net "M_K_DQ<47>")
		)
		(pad "DU36" smd circle
			(at -7.202932 22.445726)
			(size 0.4318 0.4318)
			(layers "F.Cu" "F.Mask" "F.Paste")
			(net "M_K_DQ<41>")
		)
		(pad "DU38" smd circle
			(at -5.485892 22.445726)
			(size 0.4318 0.4318)
			(layers "F.Cu" "F.Mask" "F.Paste")
			(net "GND")
		)
		(pad "DU40" smd circle
			(at -3.769106 22.445726)
			(size 0.4318 0.4318)
			(layers "F.Cu" "F.Mask" "F.Paste")
			(net "M_L_DQ<39>")
		)
		(pad "DU42" smd circle
			(at -2.052066 22.445726)
			(size 0.4318 0.4318)
			(layers "F.Cu" "F.Mask" "F.Paste")
			(net "M_L_DQ<32>")
		)
		(pad "DU44" smd circle
			(at 1.193546 20.645628)
			(size 0.508 0.508)
			(layers "F.Cu" "F.Mask" "F.Paste")
			(net "TP_CPU1_RSVD_26")
		)
		(pad "DU46" smd circle
			(at 2.910586 20.645628)
			(size 0.4318 0.4318)
			(layers "F.Cu" "F.Mask" "F.Paste")
			(net "PVDDQ_KLM")
		)
		(pad "DU48" smd circle
			(at 4.627626 20.645628)
			(size 0.4318 0.4318)
			(layers "F.Cu" "F.Mask" "F.Paste")
			(net "PVDDQ_KLM")
		)
		(pad "DU50" smd circle
			(at 6.344412 20.645628)
			(size 0.4318 0.4318)
			(layers "F.Cu" "F.Mask" "F.Paste")
			(net "PVDDQ_KLM")
		)
		(pad "DU52" smd circle
			(at 8.061452 20.645628)
			(size 0.4318 0.4318)
			(layers "F.Cu" "F.Mask" "F.Paste")
			(net "PVDDQ_KLM")
		)
		(pad "DU54" smd circle
			(at 9.778492 20.645628)
			(size 0.4318 0.4318)
			(layers "F.Cu" "F.Mask" "F.Paste")
			(net "PVDDQ_KLM")
		)
		(pad "DU56" smd circle
			(at 11.495532 20.645628)
			(size 0.4318 0.4318)
			(layers "F.Cu" "F.Mask" "F.Paste")
			(net "PVDDQ_KLM")
		)
		(pad "DU58" smd circle
			(at 13.212572 20.645628)
			(size 0.4318 0.4318)
			(layers "F.Cu" "F.Mask" "F.Paste")
			(net "PVDDQ_KLM")
		)
		(pad "DU60" smd circle
			(at 14.929612 20.645628)
			(size 0.4318 0.4318)
			(layers "F.Cu" "F.Mask" "F.Paste")
			(net "PVDDQ_KLM")
		)
		(pad "DU62" smd circle
			(at 16.646398 20.645628)
			(size 0.4318 0.4318)
			(layers "F.Cu" "F.Mask" "F.Paste")
			(net "PVDDQ_KLM")
		)
		(pad "DU64" smd circle
			(at 18.363438 20.645628)
			(size 0.4318 0.4318)
			(layers "F.Cu" "F.Mask" "F.Paste")
			(net "PVDDQ_KLM")
		)
		(pad "DU66" smd circle
			(at 20.080478 20.645628)
			(size 0.4318 0.4318)
			(layers "F.Cu" "F.Mask" "F.Paste")
			(net "M_L_ECC<6>")
		)
		(pad "DU68" smd circle
			(at 21.797518 20.645628)
			(size 0.4318 0.4318)
			(layers "F.Cu" "F.Mask" "F.Paste")
			(net "M_L_ECC<4>")
		)
		(pad "DU70" smd circle
			(at 23.514558 20.645628)
			(size 0.4318 0.4318)
			(layers "F.Cu" "F.Mask" "F.Paste")
			(net "GND")
		)
		(pad "DU72" smd circle
			(at 25.231598 20.645628)
			(size 0.4318 0.4318)
			(layers "F.Cu" "F.Mask" "F.Paste")
			(net "GND")
		)
		(pad "DU74" smd circle
			(at 26.948384 20.645628)
			(size 0.4318 0.4318)
			(layers "F.Cu" "F.Mask" "F.Paste")
			(net "M_K_DQ<31>")
		)
		(pad "DU76" smd circle
			(at 28.665424 20.645628)
			(size 0.4318 0.4318)
			(layers "F.Cu" "F.Mask" "F.Paste")
			(net "M_K_DQ<25>")
		)
		(pad "DU78" smd circle
			(at 30.382464 20.645628)
			(size 0.4318 0.4318)
			(layers "F.Cu" "F.Mask" "F.Paste")
			(net "GND")
		)
		(pad "DU80" smd circle
			(at 32.099504 20.645628)
			(size 0.4318 0.4318)
			(layers "F.Cu" "F.Mask" "F.Paste")
			(net "GND")
		)
		(pad "DU82" smd circle
			(at 33.816544 20.645628)
			(size 0.4318 0.4318)
			(layers "F.Cu" "F.Mask" "F.Paste")
			(net "GND")
		)
		(pad "DU84" smd circle
			(at 35.533584 20.645628)
			(size 0.4318 0.4318)
			(layers "F.Cu" "F.Mask" "F.Paste")
			(net "GND")
		)
		(pad "DV3" smd circle
			(at -35.533584 22.940772)
			(size 0.4318 0.4318)
			(layers "F.Cu" "F.Mask" "F.Paste")
			(net "TP_P3E_CPU1_PE1_RSR3_TXN<9>")
		)
		(pad "DV5" smd circle
			(at -33.816544 22.940772)
			(size 0.4318 0.4318)
			(layers "F.Cu" "F.Mask" "F.Paste")
			(net "TP_P3E_CPU1_PE1_RSR3_TXP<11>")
		)
		(pad "DV7" smd circle
			(at -32.099504 22.940772)
			(size 0.4318 0.4318)
			(layers "F.Cu" "F.Mask" "F.Paste")
			(net "TP_P3E_CPU1_PE1_RSR3_TXN<12>")
		)
		(pad "DV9" smd circle
			(at -30.382464 22.940772)
			(size 0.4318 0.4318)
			(layers "F.Cu" "F.Mask" "F.Paste")
			(net "P3E_CPU1_PE3_MP_TXP<5>")
		)
		(pad "DV11" smd circle
			(at -28.665424 22.940772)
			(size 0.4318 0.4318)
			(layers "F.Cu" "F.Mask" "F.Paste")
			(net "PVCCIO_CPU1")
		)
		(pad "DV13" smd circle
			(at -26.948384 22.940772)
			(size 0.4318 0.4318)
			(layers "F.Cu" "F.Mask" "F.Paste")
			(net "TP_P3E_CPU1_PE1_RSR3_RXN<12>")
		)
		(pad "DV15" smd circle
			(at -25.231598 22.940772)
			(size 0.4318 0.4318)
			(layers "F.Cu" "F.Mask" "F.Paste")
			(net "TP_P3E_CPU1_PE1_RSR3_RXP<14>")
		)
		(pad "DV17" smd circle
			(at -23.514558 22.940772)
			(size 0.4318 0.4318)
			(layers "F.Cu" "F.Mask" "F.Paste")
			(net "P3E_CPU1_PE3_MP_RXP<2>")
		)
		(pad "DV19" smd circle
			(at -21.797518 22.940772)
			(size 0.4318 0.4318)
			(layers "F.Cu" "F.Mask" "F.Paste")
			(net "GND")
		)
		(pad "DV21" smd circle
			(at -20.080478 22.940772)
			(size 0.4318 0.4318)
			(layers "F.Cu" "F.Mask" "F.Paste")
			(net "GND")
		)
		(pad "DV23" smd circle
			(at -18.363438 22.940772)
			(size 0.4318 0.4318)
			(layers "F.Cu" "F.Mask" "F.Paste")
			(net "M_K_DQS_DN<7>")
		)
		(pad "DV25" smd circle
			(at -16.646398 22.940772)
			(size 0.4318 0.4318)
			(layers "F.Cu" "F.Mask" "F.Paste")
			(net "GND")
		)
		(pad "DV27" smd circle
			(at -14.929612 22.940772)
			(size 0.4318 0.4318)
			(layers "F.Cu" "F.Mask" "F.Paste")
			(net "GND")
		)
		(pad "DV29" smd circle
			(at -13.212572 22.940772)
			(size 0.4318 0.4318)
			(layers "F.Cu" "F.Mask" "F.Paste")
			(net "M_K_DQS_DN<6>")
		)
		(pad "DV31" smd circle
			(at -11.495532 22.940772)
			(size 0.4318 0.4318)
			(layers "F.Cu" "F.Mask" "F.Paste")
			(net "GND")
		)
		(pad "DV33" smd circle
			(at -9.778492 22.940772)
			(size 0.4318 0.4318)
			(layers "F.Cu" "F.Mask" "F.Paste")
			(net "GND")
		)
		(pad "DV35" smd circle
			(at -8.061452 22.940772)
			(size 0.4318 0.4318)
			(layers "F.Cu" "F.Mask" "F.Paste")
			(net "M_K_DQS_DN<5>")
		)
		(pad "DV37" smd circle
			(at -6.344412 22.940772)
			(size 0.4318 0.4318)
			(layers "F.Cu" "F.Mask" "F.Paste")
			(net "GND")
		)
		(pad "DV39" smd circle
			(at -4.627626 22.940772)
			(size 0.4318 0.4318)
			(layers "F.Cu" "F.Mask" "F.Paste")
			(net "GND")
		)
		(pad "DV41" smd circle
			(at -2.910586 22.940772)
			(size 0.4318 0.4318)
			(layers "F.Cu" "F.Mask" "F.Paste")
			(net "M_L_DQS_DN<4>")
		)
		(pad "DV45" smd circle
			(at 2.052066 21.140674)
			(size 0.4318 0.4318)
			(layers "F.Cu" "F.Mask" "F.Paste")
			(net "M_K_CS_N<6>")
		)
		(pad "DV47" smd circle
			(at 3.769106 21.140674)
			(size 0.4318 0.4318)
			(layers "F.Cu" "F.Mask" "F.Paste")
			(net "M_K_C<2>")
		)
		(pad "DV49" smd circle
			(at 5.485892 21.140674)
			(size 0.4318 0.4318)
			(layers "F.Cu" "F.Mask" "F.Paste")
			(net "M_K_MA<15>")
		)
		(pad "DV51" smd circle
			(at 7.202932 21.140674)
			(size 0.4318 0.4318)
			(layers "F.Cu" "F.Mask" "F.Paste")
			(net "M_L_CS_N<0>")
		)
		(pad "DV53" smd circle
			(at 8.919972 21.140674)
			(size 0.4318 0.4318)
			(layers "F.Cu" "F.Mask" "F.Paste")
			(net "M_L_PAR")
		)
		(pad "DV55" smd circle
			(at 10.637012 21.140674)
			(size 0.4318 0.4318)
			(layers "F.Cu" "F.Mask" "F.Paste")
			(net "M_L_BA<1>")
		)
		(pad "DV57" smd circle
			(at 12.354052 21.140674)
			(size 0.4318 0.4318)
			(layers "F.Cu" "F.Mask" "F.Paste")
			(net "M_L_MA<2>")
		)
		(pad "DV59" smd circle
			(at 14.071092 21.140674)
			(size 0.4318 0.4318)
			(layers "F.Cu" "F.Mask" "F.Paste")
			(net "M_L_MA<9>")
		)
		(pad "DV61" smd circle
			(at 15.787878 21.140674)
			(size 0.4318 0.4318)
			(layers "F.Cu" "F.Mask" "F.Paste")
			(net "TP_CPU1_RSVD_25")
		)
		(pad "DV63" smd circle
			(at 17.504918 21.140674)
			(size 0.4318 0.4318)
			(layers "F.Cu" "F.Mask" "F.Paste")
			(net "M_KLM_RST_N")
		)
		(pad "DV65" smd circle
			(at 19.221958 21.140674)
			(size 0.4318 0.4318)
			(layers "F.Cu" "F.Mask" "F.Paste")
			(net "M_L_ECC<2>")
		)
		(pad "DV67" smd circle
			(at 20.938998 21.140674)
			(size 0.4318 0.4318)
			(layers "F.Cu" "F.Mask" "F.Paste")
			(net "M_L_DQS_DN<17>")
		)
		(pad "DV69" smd circle
			(at 22.656038 21.140674)
			(size 0.4318 0.4318)
			(layers "F.Cu" "F.Mask" "F.Paste")
			(net "M_L_ECC<5>")
		)
		(pad "DV71" smd circle
			(at 24.373078 21.140674)
			(size 0.4318 0.4318)
			(layers "F.Cu" "F.Mask" "F.Paste")
			(net "TP_CPU1_RSVD_24")
		)
		(pad "DV73" smd circle
			(at 26.090118 21.140674)
			(size 0.4318 0.4318)
			(layers "F.Cu" "F.Mask" "F.Paste")
			(net "GND")
		)
		(pad "DV75" smd circle
			(at 27.806904 21.140674)
			(size 0.4318 0.4318)
			(layers "F.Cu" "F.Mask" "F.Paste")
			(net "M_K_DQS_DN<3>")
		)
		(pad "DV77" smd circle
			(at 29.523944 21.140674)
			(size 0.4318 0.4318)
			(layers "F.Cu" "F.Mask" "F.Paste")
			(net "GND")
		)
		(pad "DV79" smd circle
			(at 31.240984 21.140674)
			(size 0.4318 0.4318)
			(layers "F.Cu" "F.Mask" "F.Paste")
			(net "M_L_DQS_DP<11>")
		)
		(pad "DV81" smd circle
			(at 32.958024 21.140674)
			(size 0.4318 0.4318)
			(layers "F.Cu" "F.Mask" "F.Paste")
			(net "GND")
		)
		(pad "DV83" smd circle
			(at 34.675064 21.140674)
			(size 0.4318 0.4318)
			(layers "F.Cu" "F.Mask" "F.Paste")
			(net "M_K_DQ<10>")
		)
		(pad "DV85" smd custom
			(at 36.392104 21.140674 270)
			(size 0.10795 0.10795)
			(layers "F.Cu" "F.Mask" "F.Paste")
			(net "M_K_DQ<15>")
			(options
				(clearance outline)
				(anchor circle)
			)
			(primitives
				(gr_poly
					(pts
						(arc
							(start 0.2159 -0.0381)
							(mid 0 -0.254)
							(end -0.2159 -0.0381)
						)
						(arc
							(start -0.2159 0.0381)
							(mid 0 0.254)
							(end 0.2159 0.0381)
						)
					)
					(width 0)
					(fill yes)
				)
			)
		)
		(pad "DW2" smd custom
			(at -36.392104 23.436326 90)
			(size 0.10795 0.10795)
			(layers "F.Cu" "F.Mask" "F.Paste")
			(net "GND")
			(options
				(clearance outline)
				(anchor circle)
			)
			(primitives
				(gr_poly
					(pts
						(arc
							(start 0.2159 -0.0381)
							(mid 0 -0.254)
							(end -0.2159 -0.0381)
						)
						(arc
							(start -0.2159 0.0381)
							(mid 0 0.254)
							(end 0.2159 0.0381)
						)
					)
					(width 0)
					(fill yes)
				)
			)
		)
		(pad "DW4" smd circle
			(at -34.675064 23.436326)
			(size 0.4318 0.4318)
			(layers "F.Cu" "F.Mask" "F.Paste")
			(net "TP_P3E_CPU1_PE1_RSR3_TXN<10>")
		)
		(pad "DW6" smd circle
			(at -32.958024 23.436326)
			(size 0.4318 0.4318)
			(layers "F.Cu" "F.Mask" "F.Paste")
			(net "TP_P3E_CPU1_PE1_RSR3_TXP<13>")
		)
		(pad "DW8" smd circle
			(at -31.240984 23.436326)
			(size 0.4318 0.4318)
			(layers "F.Cu" "F.Mask" "F.Paste")
			(net "GND")
		)
		(pad "DW10" smd circle
			(at -29.523944 23.436326)
			(size 0.4318 0.4318)
			(layers "F.Cu" "F.Mask" "F.Paste")
			(net "P3E_CPU1_PE3_MP_TXN<5>")
		)
		(pad "DW12" smd circle
			(at -27.806904 23.436326)
			(size 0.4318 0.4318)
			(layers "F.Cu" "F.Mask" "F.Paste")
			(net "GND")
		)
		(pad "DW14" smd circle
			(at -26.090118 23.436326)
			(size 0.4318 0.4318)
			(layers "F.Cu" "F.Mask" "F.Paste")
			(net "TP_P3E_CPU1_PE1_RSR3_RXN<13>")
		)
		(pad "DW16" smd circle
			(at -24.373078 23.436326)
			(size 0.4318 0.4318)
			(layers "F.Cu" "F.Mask" "F.Paste")
			(net "P3E_CPU1_PE3_MP_RXN<2>")
		)
		(pad "DW18" smd circle
			(at -22.656038 23.436326)
			(size 0.4318 0.4318)
			(layers "F.Cu" "F.Mask" "F.Paste")
			(net "P3E_CPU1_PE3_MP_RXN<1>")
		)
		(pad "DW20" smd circle
			(at -20.938998 23.436326)
			(size 0.4318 0.4318)
			(layers "F.Cu" "F.Mask" "F.Paste")
			(net "GND")
		)
		(pad "DW22" smd circle
			(at -19.221958 23.436326)
			(size 0.4318 0.4318)
			(layers "F.Cu" "F.Mask" "F.Paste")
			(net "M_K_DQ<63>")
		)
		(pad "DW24" smd circle
			(at -17.504918 23.436326)
			(size 0.4318 0.4318)
			(layers "F.Cu" "F.Mask" "F.Paste")
			(net "GND")
		)
		(pad "DW26" smd circle
			(at -15.787878 23.436326)
			(size 0.4318 0.4318)
			(layers "F.Cu" "F.Mask" "F.Paste")
			(net "M_L_DQS_DP<15>")
		)
		(pad "DW28" smd circle
			(at -14.071092 23.436326)
			(size 0.4318 0.4318)
			(layers "F.Cu" "F.Mask" "F.Paste")
			(net "GND")
		)
		(pad "DW30" smd circle
			(at -12.354052 23.436326)
			(size 0.4318 0.4318)
			(layers "F.Cu" "F.Mask" "F.Paste")
			(net "GND")
		)
		(pad "DW32" smd circle
			(at -10.637012 23.436326)
			(size 0.4318 0.4318)
			(layers "F.Cu" "F.Mask" "F.Paste")
			(net "M_L_DQS_DP<14>")
		)
		(pad "DW34" smd circle
			(at -8.919972 23.436326)
			(size 0.4318 0.4318)
			(layers "F.Cu" "F.Mask" "F.Paste")
			(net "GND")
		)
		(pad "DW36" smd circle
			(at -7.202932 23.436326)
			(size 0.4318 0.4318)
			(layers "F.Cu" "F.Mask" "F.Paste")
			(net "GND")
		)
		(pad "DW38" smd circle
			(at -5.485892 23.436326)
			(size 0.4318 0.4318)
			(layers "F.Cu" "F.Mask" "F.Paste")
			(net "M_K_DQS_DP<13>")
		)
		(pad "DW40" smd circle
			(at -3.769106 23.436326)
			(size 0.4318 0.4318)
			(layers "F.Cu" "F.Mask" "F.Paste")
			(net "GND")
		)
		(pad "DW42" smd circle
			(at -2.052066 23.436326)
			(size 0.4318 0.4318)
			(layers "F.Cu" "F.Mask" "F.Paste")
			(net "M_L_DQ<33>")
		)
		(pad "DW44" smd circle
			(at 1.193546 21.636228)
			(size 0.508 0.508)
			(layers "F.Cu" "F.Mask" "F.Paste")
			(net "TP_CPU1_RSVD_23")
		)
		(pad "DW46" smd circle
			(at 2.910586 21.636228)
			(size 0.4318 0.4318)
			(layers "F.Cu" "F.Mask" "F.Paste")
			(net "TP_CPU1_RSVD_22")
		)
		(pad "DW48" smd circle
			(at 4.627626 21.636228)
			(size 0.4318 0.4318)
			(layers "F.Cu" "F.Mask" "F.Paste")
			(net "M_K_MA<13>")
		)
		(pad "DW50" smd circle
			(at 6.344412 21.636228)
			(size 0.4318 0.4318)
			(layers "F.Cu" "F.Mask" "F.Paste")
			(net "M_L_CS_N<4>")
		)
		(pad "DW52" smd circle
			(at 8.061452 21.636228)
			(size 0.4318 0.4318)
			(layers "F.Cu" "F.Mask" "F.Paste")
			(net "M_L_MA<0>")
		)
		(pad "DW54" smd circle
			(at 9.778492 21.636228)
			(size 0.4318 0.4318)
			(layers "F.Cu" "F.Mask" "F.Paste")
			(net "M_K_MA<10>")
		)
		(pad "DW56" smd circle
			(at 11.495532 21.636228)
			(size 0.4318 0.4318)
			(layers "F.Cu" "F.Mask" "F.Paste")
			(net "M_K_CLK_DN<2>")
		)
		(pad "DW58" smd circle
			(at 13.212572 21.636228)
			(size 0.4318 0.4318)
			(layers "F.Cu" "F.Mask" "F.Paste")
			(net "M_L_MA<1>")
		)
		(pad "DW60" smd circle
			(at 14.929612 21.636228)
			(size 0.4318 0.4318)
			(layers "F.Cu" "F.Mask" "F.Paste")
			(net "M_K_ACT_N")
		)
		(pad "DW62" smd circle
			(at 16.646398 21.636228)
			(size 0.4318 0.4318)
			(layers "F.Cu" "F.Mask" "F.Paste")
			(net "M_K_BG<1>")
		)
		(pad "DW64" smd circle
			(at 18.363438 21.636228)
			(size 0.4318 0.4318)
			(layers "F.Cu" "F.Mask" "F.Paste")
			(net "GND")
		)
		(pad "DW66" smd circle
			(at 20.080478 21.636228)
			(size 0.4318 0.4318)
			(layers "F.Cu" "F.Mask" "F.Paste")
			(net "GND")
		)
		(pad "DW68" smd circle
			(at 21.797518 21.636228)
			(size 0.4318 0.4318)
			(layers "F.Cu" "F.Mask" "F.Paste")
			(net "GND")
		)
		(pad "DW70" smd circle
			(at 23.514558 21.636228)
			(size 0.4318 0.4318)
			(layers "F.Cu" "F.Mask" "F.Paste")
			(net "GND")
		)
		(pad "DW72" smd circle
			(at 25.231598 21.636228)
			(size 0.4318 0.4318)
			(layers "F.Cu" "F.Mask" "F.Paste")
			(net "GND")
		)
		(pad "DW74" smd circle
			(at 26.948384 21.636228)
			(size 0.4318 0.4318)
			(layers "F.Cu" "F.Mask" "F.Paste")
			(net "GND")
		)
		(pad "DW76" smd circle
			(at 28.665424 21.636228)
			(size 0.4318 0.4318)
			(layers "F.Cu" "F.Mask" "F.Paste")
			(net "GND")
		)
		(pad "DW78" smd circle
			(at 30.382464 21.636228)
			(size 0.4318 0.4318)
			(layers "F.Cu" "F.Mask" "F.Paste")
			(net "M_L_DQ<22>")
		)
		(pad "DW80" smd circle
			(at 32.099504 21.636228)
			(size 0.4318 0.4318)
			(layers "F.Cu" "F.Mask" "F.Paste")
			(net "M_L_DQ<16>")
		)
		(pad "DW82" smd circle
			(at 33.816544 21.636228)
			(size 0.4318 0.4318)
			(layers "F.Cu" "F.Mask" "F.Paste")
			(net "GND")
		)
		(pad "DW84" smd circle
			(at 35.533584 21.636228)
			(size 0.4318 0.4318)
			(layers "F.Cu" "F.Mask" "F.Paste")
			(net "GND")
		)
		(pad "DY3" smd custom
			(at -35.533584 23.931626 135)
			(size 0.10795 0.10795)
			(layers "F.Cu" "F.Mask" "F.Paste")
			(net "TP_CPU1_RSVD_21")
			(options
				(clearance outline)
				(anchor circle)
			)
			(primitives
				(gr_poly
					(pts
						(arc
							(start 0.2159 -0.0381)
							(mid 0 -0.254)
							(end -0.2159 -0.0381)
						)
						(arc
							(start -0.2159 0.0381)
							(mid 0 0.254)
							(end 0.2159 0.0381)
						)
					)
					(width 0)
					(fill yes)
				)
			)
		)
		(pad "DY5" smd circle
			(at -33.816544 23.931626)
			(size 0.4318 0.4318)
			(layers "F.Cu" "F.Mask" "F.Paste")
			(net "GND")
		)
		(pad "DY7" smd circle
			(at -32.099504 23.931626)
			(size 0.4318 0.4318)
			(layers "F.Cu" "F.Mask" "F.Paste")
			(net "TP_P3E_CPU1_PE1_RSR3_TXN<13>")
		)
		(pad "DY9" smd circle
			(at -30.382464 23.931626)
			(size 0.4318 0.4318)
			(layers "F.Cu" "F.Mask" "F.Paste")
			(net "P3E_CPU1_PE3_MP_TXP<4>")
		)
		(pad "DY11" smd circle
			(at -28.665424 23.931626)
			(size 0.4318 0.4318)
			(layers "F.Cu" "F.Mask" "F.Paste")
			(net "P3E_CPU1_PE3_MP_TXN<3>")
		)
		(pad "DY13" smd circle
			(at -26.948384 23.931626)
			(size 0.4318 0.4318)
			(layers "F.Cu" "F.Mask" "F.Paste")
			(net "TP_P3E_CPU1_PE1_RSR3_RXP<13>")
		)
		(pad "DY15" smd circle
			(at -25.231598 23.931626)
			(size 0.4318 0.4318)
			(layers "F.Cu" "F.Mask" "F.Paste")
			(net "TP_P3E_CPU1_PE1_RSR3_RXN<14>")
		)
		(pad "DY17" smd circle
			(at -23.514558 23.931626)
			(size 0.4318 0.4318)
			(layers "F.Cu" "F.Mask" "F.Paste")
			(net "P3E_CPU1_PE3_MP_RXP<0>")
		)
		(pad "DY19" smd circle
			(at -21.797518 23.931626)
			(size 0.4318 0.4318)
			(layers "F.Cu" "F.Mask" "F.Paste")
			(net "GND")
		)
		(pad "DY21" smd circle
			(at -20.080478 23.931626)
			(size 0.4318 0.4318)
			(layers "F.Cu" "F.Mask" "F.Paste")
			(net "M_K_DQ<58>")
		)
		(pad "DY23" smd circle
			(at -18.363438 23.931626)
			(size 0.4318 0.4318)
			(layers "F.Cu" "F.Mask" "F.Paste")
			(net "GND")
		)
		(pad "DY25" smd circle
			(at -16.646398 23.931626)
			(size 0.4318 0.4318)
			(layers "F.Cu" "F.Mask" "F.Paste")
			(net "M_L_DQ<54>")
		)
		(pad "DY27" smd circle
			(at -14.929612 23.931626)
			(size 0.4318 0.4318)
			(layers "F.Cu" "F.Mask" "F.Paste")
			(net "M_L_DQ<52>")
		)
		(pad "DY29" smd circle
			(at -13.212572 23.931626)
			(size 0.4318 0.4318)
			(layers "F.Cu" "F.Mask" "F.Paste")
			(net "GND")
		)
		(pad "DY31" smd circle
			(at -11.495532 23.931626)
			(size 0.4318 0.4318)
			(layers "F.Cu" "F.Mask" "F.Paste")
			(net "M_L_DQ<46>")
		)
		(pad "DY33" smd circle
			(at -9.778492 23.931626)
			(size 0.4318 0.4318)
			(layers "F.Cu" "F.Mask" "F.Paste")
			(net "M_L_DQ<44>")
		)
		(pad "DY35" smd circle
			(at -8.061452 23.931626)
			(size 0.4318 0.4318)
			(layers "F.Cu" "F.Mask" "F.Paste")
			(net "GND")
		)
		(pad "DY37" smd circle
			(at -6.344412 23.931626)
			(size 0.4318 0.4318)
			(layers "F.Cu" "F.Mask" "F.Paste")
			(net "M_K_DQ<38>")
		)
		(pad "DY39" smd circle
			(at -4.627626 23.931626)
			(size 0.4318 0.4318)
			(layers "F.Cu" "F.Mask" "F.Paste")
			(net "M_K_DQ<36>")
		)
		(pad "DY41" smd circle
			(at -2.910586 23.931626)
			(size 0.4318 0.4318)
			(layers "F.Cu" "F.Mask" "F.Paste")
			(net "GND")
		)
		(pad "DY45" smd circle
			(at 2.052066 22.131274)
			(size 0.4318 0.4318)
			(layers "F.Cu" "F.Mask" "F.Paste")
			(net "GND")
		)
		(pad "DY47" smd circle
			(at 3.769106 22.131274)
			(size 0.4318 0.4318)
			(layers "F.Cu" "F.Mask" "F.Paste")
			(net "GND")
		)
		(pad "DY49" smd circle
			(at 5.485892 22.131274)
			(size 0.4318 0.4318)
			(layers "F.Cu" "F.Mask" "F.Paste")
			(net "GND")
		)
		(pad "DY51" smd circle
			(at 7.202932 22.131274)
			(size 0.4318 0.4318)
			(layers "F.Cu" "F.Mask" "F.Paste")
			(net "GND")
		)
		(pad "DY53" smd circle
			(at 8.919972 22.131274)
			(size 0.4318 0.4318)
			(layers "F.Cu" "F.Mask" "F.Paste")
			(net "GND")
		)
		(pad "DY55" smd circle
			(at 10.637012 22.131274)
			(size 0.4318 0.4318)
			(layers "F.Cu" "F.Mask" "F.Paste")
			(net "GND")
		)
		(pad "DY57" smd circle
			(at 12.354052 22.131274)
			(size 0.4318 0.4318)
			(layers "F.Cu" "F.Mask" "F.Paste")
			(net "GND")
		)
		(pad "DY59" smd circle
			(at 14.071092 22.131274)
			(size 0.4318 0.4318)
			(layers "F.Cu" "F.Mask" "F.Paste")
			(net "GND")
		)
		(pad "DY61" smd circle
			(at 15.787878 22.131274)
			(size 0.4318 0.4318)
			(layers "F.Cu" "F.Mask" "F.Paste")
			(net "GND")
		)
		(pad "DY63" smd circle
			(at 17.504918 22.131274)
			(size 0.4318 0.4318)
			(layers "F.Cu" "F.Mask" "F.Paste")
			(net "GND")
		)
		(pad "DY65" smd circle
			(at 19.221958 22.131274)
			(size 0.4318 0.4318)
			(layers "F.Cu" "F.Mask" "F.Paste")
			(net "M_L_ECC<3>")
		)
		(pad "DY67" smd circle
			(at 20.938998 22.131274)
			(size 0.4318 0.4318)
			(layers "F.Cu" "F.Mask" "F.Paste")
			(net "M_L_DQS_DP<8>")
		)
		(pad "DY69" smd circle
			(at 22.656038 22.131274)
			(size 0.4318 0.4318)
			(layers "F.Cu" "F.Mask" "F.Paste")
			(net "M_L_ECC<0>")
		)
		(pad "DY71" smd circle
			(at 24.373078 22.131274)
			(size 0.4318 0.4318)
			(layers "F.Cu" "F.Mask" "F.Paste")
			(net "GND")
		)
		(pad "DY73" smd circle
			(at 26.090118 22.131274)
			(size 0.4318 0.4318)
			(layers "F.Cu" "F.Mask" "F.Paste")
			(net "M_L_DQS_DP<12>")
		)
		(pad "DY75" smd circle
			(at 27.806904 22.131274)
			(size 0.4318 0.4318)
			(layers "F.Cu" "F.Mask" "F.Paste")
			(net "GND")
		)
		(pad "DY77" smd circle
			(at 29.523944 22.131274)
			(size 0.4318 0.4318)
			(layers "F.Cu" "F.Mask" "F.Paste")
			(net "M_L_DQ<18>")
		)
		(pad "DY79" smd circle
			(at 31.240984 22.131274)
			(size 0.4318 0.4318)
			(layers "F.Cu" "F.Mask" "F.Paste")
			(net "M_L_DQS_DN<11>")
		)
		(pad "DY81" smd circle
			(at 32.958024 22.131274)
			(size 0.4318 0.4318)
			(layers "F.Cu" "F.Mask" "F.Paste")
			(net "M_L_DQ<20>")
		)
		(pad "DY83" smd circle
			(at 34.675064 22.131274)
			(size 0.4318 0.4318)
			(layers "F.Cu" "F.Mask" "F.Paste")
			(net "M_K_DQ<11>")
		)
		(pad "DY85" smd custom
			(at 36.392104 22.131274 225)
			(size 0.10795 0.10795)
			(layers "F.Cu" "F.Mask" "F.Paste")
			(net "GND")
			(options
				(clearance outline)
				(anchor circle)
			)
			(primitives
				(gr_poly
					(pts
						(arc
							(start 0.2159 -0.0381)
							(mid 0 -0.254)
							(end -0.2159 -0.0381)
						)
						(arc
							(start -0.2159 0.0381)
							(mid 0 0.254)
							(end 0.2159 0.0381)
						)
					)
					(width 0)
					(fill yes)
				)
			)
		)
		(pad "E2" smd custom
			(at -36.392104 -23.122128 45)
			(size 0.10795 0.10795)
			(layers "F.Cu" "F.Mask" "F.Paste")
			(net "TP_CPU1_RSVD_283")
			(options
				(clearance outline)
				(anchor circle)
			)
			(primitives
				(gr_poly
					(pts
						(arc
							(start 0.2159 -0.0381)
							(mid 0 -0.254)
							(end -0.2159 -0.0381)
						)
						(arc
							(start -0.2159 0.0381)
							(mid 0 0.254)
							(end 0.2159 0.0381)
						)
					)
					(width 0)
					(fill yes)
				)
			)
		)
		(pad "E4" smd custom
			(at -34.675064 -23.122128 45)
			(size 0.10795 0.10795)
			(layers "F.Cu" "F.Mask" "F.Paste")
			(net "TP_CPU1_RSVD_282")
			(options
				(clearance outline)
				(anchor circle)
			)
			(primitives
				(gr_poly
					(pts
						(arc
							(start 0.2159 -0.0381)
							(mid 0 -0.254)
							(end -0.2159 -0.0381)
						)
						(arc
							(start -0.2159 0.0381)
							(mid 0 0.254)
							(end 0.2159 0.0381)
						)
					)
					(width 0)
					(fill yes)
				)
			)
		)
		(pad "E6" smd circle
			(at -32.958024 -23.122128)
			(size 0.4318 0.4318)
			(layers "F.Cu" "F.Mask" "F.Paste")
			(net "GND")
		)
		(pad "E8" smd circle
			(at -31.240984 -23.122128)
			(size 0.4318 0.4318)
			(layers "F.Cu" "F.Mask" "F.Paste")
			(net "GND")
		)
		(pad "E10" smd circle
			(at -29.523944 -23.122128)
			(size 0.4318 0.4318)
			(layers "F.Cu" "F.Mask" "F.Paste")
			(net "UPI_CPU1_CPU0_P1P1_DN<8>")
		)
		(pad "E12" smd circle
			(at -27.806904 -23.122128)
			(size 0.4318 0.4318)
			(layers "F.Cu" "F.Mask" "F.Paste")
			(net "UPI_CPU1_CPU0_P1P1_DN<10>")
		)
		(pad "E14" smd circle
			(at -26.090118 -23.122128)
			(size 0.4318 0.4318)
			(layers "F.Cu" "F.Mask" "F.Paste")
			(net "UPI_CPU1_CPU0_P1P1_DP<12>")
		)
		(pad "E16" smd circle
			(at -24.373078 -23.122128)
			(size 0.4318 0.4318)
			(layers "F.Cu" "F.Mask" "F.Paste")
			(net "GND")
		)
		(pad "E18" smd custom
			(at -22.656038 -23.122128)
			(size 0.10795 0.10795)
			(layers "F.Cu" "F.Mask" "F.Paste")
			(net "GND")
			(options
				(clearance outline)
				(anchor circle)
			)
			(primitives
				(gr_poly
					(pts
						(arc
							(start 0.2159 -0.0381)
							(mid 0 -0.254)
							(end -0.2159 -0.0381)
						)
						(arc
							(start -0.2159 0.0381)
							(mid 0 0.254)
							(end 0.2159 0.0381)
						)
					)
					(width 0)
					(fill yes)
				)
			)
		)
		(pad "E20" smd custom
			(at -20.938998 -23.122128)
			(size 0.10795 0.10795)
			(layers "F.Cu" "F.Mask" "F.Paste")
			(net "GND")
			(options
				(clearance outline)
				(anchor circle)
			)
			(primitives
				(gr_poly
					(pts
						(arc
							(start 0.2159 -0.0381)
							(mid 0 -0.254)
							(end -0.2159 -0.0381)
						)
						(arc
							(start -0.2159 0.0381)
							(mid 0 0.254)
							(end 0.2159 0.0381)
						)
					)
					(width 0)
					(fill yes)
				)
			)
		)
		(pad "E22" smd custom
			(at -19.221958 -23.122128)
			(size 0.10795 0.10795)
			(layers "F.Cu" "F.Mask" "F.Paste")
			(net "GND")
			(options
				(clearance outline)
				(anchor circle)
			)
			(primitives
				(gr_poly
					(pts
						(arc
							(start 0.2159 -0.0381)
							(mid 0 -0.254)
							(end -0.2159 -0.0381)
						)
						(arc
							(start -0.2159 0.0381)
							(mid 0 0.254)
							(end 0.2159 0.0381)
						)
					)
					(width 0)
					(fill yes)
				)
			)
		)
		(pad "E24" smd custom
			(at -17.504918 -23.122128)
			(size 0.10795 0.10795)
			(layers "F.Cu" "F.Mask" "F.Paste")
			(net "TP_CPU1_RSVD_281")
			(options
				(clearance outline)
				(anchor circle)
			)
			(primitives
				(gr_poly
					(pts
						(arc
							(start 0.2159 -0.0381)
							(mid 0 -0.254)
							(end -0.2159 -0.0381)
						)
						(arc
							(start -0.2159 0.0381)
							(mid 0 0.254)
							(end 0.2159 0.0381)
						)
					)
					(width 0)
					(fill yes)
				)
			)
		)
		(pad "E26" smd circle
			(at -15.787878 -23.122128)
			(size 0.4318 0.4318)
			(layers "F.Cu" "F.Mask" "F.Paste")
			(net "M_H_DQ<51>")
		)
		(pad "E28" smd circle
			(at -14.071092 -23.122128)
			(size 0.4318 0.4318)
			(layers "F.Cu" "F.Mask" "F.Paste")
			(net "M_H_DQS_DP<6>")
		)
		(pad "E30" smd circle
			(at -12.354052 -23.122128)
			(size 0.4318 0.4318)
			(layers "F.Cu" "F.Mask" "F.Paste")
			(net "M_H_DQ<52>")
		)
		(pad "E32" smd circle
			(at -10.637012 -23.122128)
			(size 0.4318 0.4318)
			(layers "F.Cu" "F.Mask" "F.Paste")
			(net "M_H_DQ<43>")
		)
		(pad "E34" smd circle
			(at -8.919972 -23.122128)
			(size 0.4318 0.4318)
			(layers "F.Cu" "F.Mask" "F.Paste")
			(net "M_H_DQS_DP<5>")
		)
		(pad "E36" smd circle
			(at -7.202932 -23.122128)
			(size 0.4318 0.4318)
			(layers "F.Cu" "F.Mask" "F.Paste")
			(net "M_H_DQ<44>")
		)
		(pad "E38" smd circle
			(at -5.485892 -23.122128)
			(size 0.4318 0.4318)
			(layers "F.Cu" "F.Mask" "F.Paste")
			(net "M_G_DQ<35>")
		)
		(pad "E40" smd circle
			(at -3.769106 -23.122128)
			(size 0.4318 0.4318)
			(layers "F.Cu" "F.Mask" "F.Paste")
			(net "M_G_DQS_DP<4>")
		)
		(pad "E42" smd circle
			(at -2.052066 -23.122128)
			(size 0.4318 0.4318)
			(layers "F.Cu" "F.Mask" "F.Paste")
			(net "M_G_DQ<36>")
		)
		(pad "E46" smd circle
			(at 2.910586 -24.921972)
			(size 0.4318 0.4318)
			(layers "F.Cu" "F.Mask" "F.Paste")
			(net "PVDDQ_GHJ")
		)
		(pad "E48" smd circle
			(at 4.627626 -24.921972)
			(size 0.4318 0.4318)
			(layers "F.Cu" "F.Mask" "F.Paste")
			(net "PVDDQ_GHJ")
		)
		(pad "E50" smd circle
			(at 6.344412 -24.921972)
			(size 0.4318 0.4318)
			(layers "F.Cu" "F.Mask" "F.Paste")
			(net "PVDDQ_GHJ")
		)
		(pad "E52" smd circle
			(at 8.061452 -24.921972)
			(size 0.4318 0.4318)
			(layers "F.Cu" "F.Mask" "F.Paste")
			(net "PVDDQ_GHJ")
		)
		(pad "E54" smd circle
			(at 9.778492 -24.921972)
			(size 0.4318 0.4318)
			(layers "F.Cu" "F.Mask" "F.Paste")
			(net "PVDDQ_GHJ")
		)
		(pad "E56" smd circle
			(at 11.495532 -24.921972)
			(size 0.4318 0.4318)
			(layers "F.Cu" "F.Mask" "F.Paste")
			(net "PVDDQ_GHJ")
		)
		(pad "E58" smd circle
			(at 13.212572 -24.921972)
			(size 0.4318 0.4318)
			(layers "F.Cu" "F.Mask" "F.Paste")
			(net "PVDDQ_GHJ")
		)
		(pad "E60" smd circle
			(at 14.929612 -24.921972)
			(size 0.4318 0.4318)
			(layers "F.Cu" "F.Mask" "F.Paste")
			(net "PVDDQ_GHJ")
		)
		(pad "E62" smd circle
			(at 16.646398 -24.921972)
			(size 0.4318 0.4318)
			(layers "F.Cu" "F.Mask" "F.Paste")
			(net "PVDDQ_GHJ")
		)
		(pad "E64" smd circle
			(at 18.363438 -24.921972)
			(size 0.4318 0.4318)
			(layers "F.Cu" "F.Mask" "F.Paste")
			(net "PVDDQ_GHJ")
		)
		(pad "E66" smd custom
			(at 20.080478 -24.921972)
			(size 0.10795 0.10795)
			(layers "F.Cu" "F.Mask" "F.Paste")
			(net "GND")
			(options
				(clearance outline)
				(anchor circle)
			)
			(primitives
				(gr_poly
					(pts
						(arc
							(start 0.2159 -0.0381)
							(mid 0 -0.254)
							(end -0.2159 -0.0381)
						)
						(arc
							(start -0.2159 0.0381)
							(mid 0 0.254)
							(end 0.2159 0.0381)
						)
					)
					(width 0)
					(fill yes)
				)
			)
		)
		(pad "E72" smd circle
			(at 25.231598 -24.921972)
			(size 0.4318 0.4318)
			(layers "F.Cu" "F.Mask" "F.Paste")
			(net "GND")
		)
		(pad "E74" smd circle
			(at 26.948384 -24.921972)
			(size 0.4318 0.4318)
			(layers "F.Cu" "F.Mask" "F.Paste")
			(net "GND")
		)
		(pad "E76" smd circle
			(at 28.665424 -24.921972)
			(size 0.4318 0.4318)
			(layers "F.Cu" "F.Mask" "F.Paste")
			(net "GND")
		)
		(pad "E78" smd circle
			(at 30.382464 -24.921972)
			(size 0.4318 0.4318)
			(layers "F.Cu" "F.Mask" "F.Paste")
			(net "M_H_DQ<22>")
		)
		(pad "E80" smd circle
			(at 32.099504 -24.921972)
			(size 0.4318 0.4318)
			(layers "F.Cu" "F.Mask" "F.Paste")
			(net "M_H_DQ<16>")
		)
		(pad "E82" smd custom
			(at 33.816544 -24.921972 315)
			(size 0.10795 0.10795)
			(layers "F.Cu" "F.Mask" "F.Paste")
			(net "GND")
			(options
				(clearance outline)
				(anchor circle)
			)
			(primitives
				(gr_poly
					(pts
						(arc
							(start 0.2159 -0.0381)
							(mid 0 -0.254)
							(end -0.2159 -0.0381)
						)
						(arc
							(start -0.2159 0.0381)
							(mid 0 0.254)
							(end 0.2159 0.0381)
						)
					)
					(width 0)
					(fill yes)
				)
			)
		)
		(pad "E84" smd custom
			(at 35.533584 -24.921972 270)
			(size 0.10795 0.10795)
			(layers "F.Cu" "F.Mask" "F.Paste")
			(net "TP_CPU1_RSVD_280")
			(options
				(clearance outline)
				(anchor circle)
			)
			(primitives
				(gr_poly
					(pts
						(arc
							(start 0.2159 -0.0381)
							(mid 0 -0.254)
							(end -0.2159 -0.0381)
						)
						(arc
							(start -0.2159 0.0381)
							(mid 0 0.254)
							(end 0.2159 0.0381)
						)
					)
					(width 0)
					(fill yes)
				)
			)
		)
		(pad "EA4" smd custom
			(at -34.675064 24.426672 135)
			(size 0.10795 0.10795)
			(layers "F.Cu" "F.Mask" "F.Paste")
			(net "TP_CPU1_RSVD_20")
			(options
				(clearance outline)
				(anchor circle)
			)
			(primitives
				(gr_poly
					(pts
						(arc
							(start 0.2159 -0.0381)
							(mid 0 -0.254)
							(end -0.2159 -0.0381)
						)
						(arc
							(start -0.2159 0.0381)
							(mid 0 0.254)
							(end 0.2159 0.0381)
						)
					)
					(width 0)
					(fill yes)
				)
			)
		)
		(pad "EA6" smd circle
			(at -32.958024 24.426672)
			(size 0.4318 0.4318)
			(layers "F.Cu" "F.Mask" "F.Paste")
			(net "GND")
		)
		(pad "EA8" smd circle
			(at -31.240984 24.426672)
			(size 0.4318 0.4318)
			(layers "F.Cu" "F.Mask" "F.Paste")
			(net "TP_P3E_CPU1_PE1_RSR3_TXN<14>")
		)
		(pad "EA10" smd circle
			(at -29.523944 24.426672)
			(size 0.4318 0.4318)
			(layers "F.Cu" "F.Mask" "F.Paste")
			(net "P3E_CPU1_PE3_MP_TXP<3>")
		)
		(pad "EA12" smd circle
			(at -27.806904 24.426672)
			(size 0.4318 0.4318)
			(layers "F.Cu" "F.Mask" "F.Paste")
			(net "PVCCIO_CPU1")
		)
		(pad "EA14" smd circle
			(at -26.090118 24.426672)
			(size 0.4318 0.4318)
			(layers "F.Cu" "F.Mask" "F.Paste")
			(net "GND")
		)
		(pad "EA16" smd custom
			(at -24.373078 24.426672 180)
			(size 0.10795 0.10795)
			(layers "F.Cu" "F.Mask" "F.Paste")
			(net "GND")
			(options
				(clearance outline)
				(anchor circle)
			)
			(primitives
				(gr_poly
					(pts
						(arc
							(start 0.2159 -0.0381)
							(mid 0 -0.254)
							(end -0.2159 -0.0381)
						)
						(arc
							(start -0.2159 0.0381)
							(mid 0 0.254)
							(end 0.2159 0.0381)
						)
					)
					(width 0)
					(fill yes)
				)
			)
		)
		(pad "EA18" smd custom
			(at -22.656038 24.426672 180)
			(size 0.10795 0.10795)
			(layers "F.Cu" "F.Mask" "F.Paste")
			(net "P3E_CPU1_PE3_MP_RXN<0>")
			(options
				(clearance outline)
				(anchor circle)
			)
			(primitives
				(gr_poly
					(pts
						(arc
							(start 0.2159 -0.0381)
							(mid 0 -0.254)
							(end -0.2159 -0.0381)
						)
						(arc
							(start -0.2159 0.0381)
							(mid 0 0.254)
							(end 0.2159 0.0381)
						)
					)
					(width 0)
					(fill yes)
				)
			)
		)
		(pad "EA20" smd custom
			(at -20.938998 24.426672 120)
			(size 0.10795 0.10795)
			(layers "F.Cu" "F.Mask" "F.Paste")
			(net "GND")
			(options
				(clearance outline)
				(anchor circle)
			)
			(primitives
				(gr_poly
					(pts
						(arc
							(start 0.2159 -0.0381)
							(mid 0 -0.254)
							(end -0.2159 -0.0381)
						)
						(arc
							(start -0.2159 0.0381)
							(mid 0 0.254)
							(end 0.2159 0.0381)
						)
					)
					(width 0)
					(fill yes)
				)
			)
		)
		(pad "EA22" smd circle
			(at -19.221958 24.426672)
			(size 0.4318 0.4318)
			(layers "F.Cu" "F.Mask" "F.Paste")
			(net "GND")
		)
		(pad "EA24" smd circle
			(at -17.504918 24.426672)
			(size 0.4318 0.4318)
			(layers "F.Cu" "F.Mask" "F.Paste")
			(net "M_L_DQ<50>")
		)
		(pad "EA26" smd circle
			(at -15.787878 24.426672)
			(size 0.4318 0.4318)
			(layers "F.Cu" "F.Mask" "F.Paste")
			(net "M_L_DQS_DN<15>")
		)
		(pad "EA28" smd circle
			(at -14.071092 24.426672)
			(size 0.4318 0.4318)
			(layers "F.Cu" "F.Mask" "F.Paste")
			(net "M_L_DQ<53>")
		)
		(pad "EA30" smd circle
			(at -12.354052 24.426672)
			(size 0.4318 0.4318)
			(layers "F.Cu" "F.Mask" "F.Paste")
			(net "M_L_DQ<42>")
		)
		(pad "EA32" smd circle
			(at -10.637012 24.426672)
			(size 0.4318 0.4318)
			(layers "F.Cu" "F.Mask" "F.Paste")
			(net "M_L_DQS_DN<14>")
		)
		(pad "EA34" smd circle
			(at -8.919972 24.426672)
			(size 0.4318 0.4318)
			(layers "F.Cu" "F.Mask" "F.Paste")
			(net "M_L_DQ<45>")
		)
		(pad "EA36" smd circle
			(at -7.202932 24.426672)
			(size 0.4318 0.4318)
			(layers "F.Cu" "F.Mask" "F.Paste")
			(net "M_K_DQ<34>")
		)
		(pad "EA38" smd circle
			(at -5.485892 24.426672)
			(size 0.4318 0.4318)
			(layers "F.Cu" "F.Mask" "F.Paste")
			(net "M_K_DQS_DN<13>")
		)
		(pad "EA40" smd circle
			(at -3.769106 24.426672)
			(size 0.4318 0.4318)
			(layers "F.Cu" "F.Mask" "F.Paste")
			(net "M_K_DQ<37>")
		)
		(pad "EA42" smd circle
			(at -2.052066 24.426672)
			(size 0.4318 0.4318)
			(layers "F.Cu" "F.Mask" "F.Paste")
			(net "GND")
		)
		(pad "EA44" smd circle
			(at 1.193546 22.626828)
			(size 0.508 0.508)
			(layers "F.Cu" "F.Mask" "F.Paste")
			(net "TP_CPU1_RSVD_19")
		)
		(pad "EA46" smd circle
			(at 2.910586 22.626828)
			(size 0.4318 0.4318)
			(layers "F.Cu" "F.Mask" "F.Paste")
			(net "M_K_MA<17>")
		)
		(pad "EA48" smd circle
			(at 4.627626 22.626828)
			(size 0.4318 0.4318)
			(layers "F.Cu" "F.Mask" "F.Paste")
			(net "M_K_ODT<3>")
		)
		(pad "EA50" smd circle
			(at 6.344412 22.626828)
			(size 0.4318 0.4318)
			(layers "F.Cu" "F.Mask" "F.Paste")
			(net "M_K_ODT<2>")
		)
		(pad "EA52" smd circle
			(at 8.061452 22.626828)
			(size 0.4318 0.4318)
			(layers "F.Cu" "F.Mask" "F.Paste")
			(net "M_K_MA<16>")
		)
		(pad "EA54" smd circle
			(at 9.778492 22.626828)
			(size 0.4318 0.4318)
			(layers "F.Cu" "F.Mask" "F.Paste")
			(net "M_K_BA<1>")
		)
		(pad "EA56" smd circle
			(at 11.495532 22.626828)
			(size 0.4318 0.4318)
			(layers "F.Cu" "F.Mask" "F.Paste")
			(net "M_K_CLK_DP<2>")
		)
		(pad "EA58" smd circle
			(at 13.212572 22.626828)
			(size 0.4318 0.4318)
			(layers "F.Cu" "F.Mask" "F.Paste")
			(net "M_K_MA<5>")
		)
		(pad "EA60" smd circle
			(at 14.929612 22.626828)
			(size 0.4318 0.4318)
			(layers "F.Cu" "F.Mask" "F.Paste")
			(net "M_K_MA<7>")
		)
		(pad "EA62" smd circle
			(at 16.646398 22.626828)
			(size 0.4318 0.4318)
			(layers "F.Cu" "F.Mask" "F.Paste")
			(net "M_K_CKE<2>")
		)
		(pad "EA64" smd circle
			(at 18.363438 22.626828)
			(size 0.4318 0.4318)
			(layers "F.Cu" "F.Mask" "F.Paste")
			(net "GND")
		)
		(pad "EA66" smd circle
			(at 20.080478 22.626828)
			(size 0.4318 0.4318)
			(layers "F.Cu" "F.Mask" "F.Paste")
			(net "M_L_ECC<7>")
		)
		(pad "EA68" smd circle
			(at 21.797518 22.626828)
			(size 0.4318 0.4318)
			(layers "F.Cu" "F.Mask" "F.Paste")
			(net "M_L_ECC<1>")
		)
		(pad "EA70" smd circle
			(at 23.514558 22.626828)
			(size 0.4318 0.4318)
			(layers "F.Cu" "F.Mask" "F.Paste")
			(net "GND")
		)
		(pad "EA72" smd circle
			(at 25.231598 22.626828)
			(size 0.4318 0.4318)
			(layers "F.Cu" "F.Mask" "F.Paste")
			(net "M_L_DQ<30>")
		)
		(pad "EA74" smd circle
			(at 26.948384 22.626828)
			(size 0.4318 0.4318)
			(layers "F.Cu" "F.Mask" "F.Paste")
			(net "M_L_DQ<28>")
		)
		(pad "EA76" smd circle
			(at 28.665424 22.626828)
			(size 0.4318 0.4318)
			(layers "F.Cu" "F.Mask" "F.Paste")
			(net "GND")
		)
		(pad "EA78" smd circle
			(at 30.382464 22.626828)
			(size 0.4318 0.4318)
			(layers "F.Cu" "F.Mask" "F.Paste")
			(net "GND")
		)
		(pad "EA80" smd circle
			(at 32.099504 22.626828)
			(size 0.4318 0.4318)
			(layers "F.Cu" "F.Mask" "F.Paste")
			(net "GND")
		)
		(pad "EA82" smd circle
			(at 33.816544 22.626828)
			(size 0.4318 0.4318)
			(layers "F.Cu" "F.Mask" "F.Paste")
			(net "GND")
		)
		(pad "EA84" smd custom
			(at 35.533584 22.626828 225)
			(size 0.10795 0.10795)
			(layers "F.Cu" "F.Mask" "F.Paste")
			(net "GND")
			(options
				(clearance outline)
				(anchor circle)
			)
			(primitives
				(gr_poly
					(pts
						(arc
							(start 0.2159 -0.0381)
							(mid 0 -0.254)
							(end -0.2159 -0.0381)
						)
						(arc
							(start -0.2159 0.0381)
							(mid 0 0.254)
							(end 0.2159 0.0381)
						)
					)
					(width 0)
					(fill yes)
				)
			)
		)
		(pad "EB3" smd custom
			(at -35.533584 24.921972 135)
			(size 0.10795 0.10795)
			(layers "F.Cu" "F.Mask" "F.Paste")
			(net "TP_CPU1_RSVD_18")
			(options
				(clearance outline)
				(anchor circle)
			)
			(primitives
				(gr_poly
					(pts
						(arc
							(start 0.2159 -0.0381)
							(mid 0 -0.254)
							(end -0.2159 -0.0381)
						)
						(arc
							(start -0.2159 0.0381)
							(mid 0 0.254)
							(end 0.2159 0.0381)
						)
					)
					(width 0)
					(fill yes)
				)
			)
		)
		(pad "EB5" smd custom
			(at -33.816544 24.921972 135)
			(size 0.10795 0.10795)
			(layers "F.Cu" "F.Mask" "F.Paste")
			(net "TP_CPU1_RSVD_17")
			(options
				(clearance outline)
				(anchor circle)
			)
			(primitives
				(gr_poly
					(pts
						(arc
							(start 0.2159 -0.0381)
							(mid 0 -0.254)
							(end -0.2159 -0.0381)
						)
						(arc
							(start -0.2159 0.0381)
							(mid 0 0.254)
							(end 0.2159 0.0381)
						)
					)
					(width 0)
					(fill yes)
				)
			)
		)
		(pad "EB7" smd circle
			(at -32.099504 24.921972)
			(size 0.4318 0.4318)
			(layers "F.Cu" "F.Mask" "F.Paste")
			(net "TP_P3E_CPU1_PE1_RSR3_TXP<14>")
		)
		(pad "EB9" smd circle
			(at -30.382464 24.921972)
			(size 0.4318 0.4318)
			(layers "F.Cu" "F.Mask" "F.Paste")
			(net "P3E_CPU1_PE3_MP_TXN<4>")
		)
		(pad "EB11" smd circle
			(at -28.665424 24.921972)
			(size 0.4318 0.4318)
			(layers "F.Cu" "F.Mask" "F.Paste")
			(net "P3E_CPU1_PE3_MP_TXP<2>")
		)
		(pad "EB13" smd circle
			(at -26.948384 24.921972)
			(size 0.4318 0.4318)
			(layers "F.Cu" "F.Mask" "F.Paste")
			(net "GND")
		)
		(pad "EB15" smd circle
			(at -25.231598 24.921972)
			(size 0.4318 0.4318)
			(layers "F.Cu" "F.Mask" "F.Paste")
			(net "PVCCIO_CPU1")
		)
		(pad "EB21" smd custom
			(at -20.080478 24.921972 120)
			(size 0.10795 0.10795)
			(layers "F.Cu" "F.Mask" "F.Paste")
			(net "M_K_DQ<59>")
			(options
				(clearance outline)
				(anchor circle)
			)
			(primitives
				(gr_poly
					(pts
						(arc
							(start 0.2159 -0.0381)
							(mid 0 -0.254)
							(end -0.2159 -0.0381)
						)
						(arc
							(start -0.2159 0.0381)
							(mid 0 0.254)
							(end 0.2159 0.0381)
						)
					)
					(width 0)
					(fill yes)
				)
			)
		)
		(pad "EB23" smd circle
			(at -18.363438 24.921972)
			(size 0.4318 0.4318)
			(layers "F.Cu" "F.Mask" "F.Paste")
			(net "GND")
		)
		(pad "EB25" smd circle
			(at -16.646398 24.921972)
			(size 0.4318 0.4318)
			(layers "F.Cu" "F.Mask" "F.Paste")
			(net "GND")
		)
		(pad "EB27" smd circle
			(at -14.929612 24.921972)
			(size 0.4318 0.4318)
			(layers "F.Cu" "F.Mask" "F.Paste")
			(net "GND")
		)
		(pad "EB29" smd circle
			(at -13.212572 24.921972)
			(size 0.4318 0.4318)
			(layers "F.Cu" "F.Mask" "F.Paste")
			(net "GND")
		)
		(pad "EB31" smd circle
			(at -11.495532 24.921972)
			(size 0.4318 0.4318)
			(layers "F.Cu" "F.Mask" "F.Paste")
			(net "GND")
		)
		(pad "EB33" smd circle
			(at -9.778492 24.921972)
			(size 0.4318 0.4318)
			(layers "F.Cu" "F.Mask" "F.Paste")
			(net "GND")
		)
		(pad "EB35" smd circle
			(at -8.061452 24.921972)
			(size 0.4318 0.4318)
			(layers "F.Cu" "F.Mask" "F.Paste")
			(net "GND")
		)
		(pad "EB37" smd circle
			(at -6.344412 24.921972)
			(size 0.4318 0.4318)
			(layers "F.Cu" "F.Mask" "F.Paste")
			(net "GND")
		)
		(pad "EB39" smd circle
			(at -4.627626 24.921972)
			(size 0.4318 0.4318)
			(layers "F.Cu" "F.Mask" "F.Paste")
			(net "GND")
		)
		(pad "EB41" smd circle
			(at -2.910586 24.921972)
			(size 0.4318 0.4318)
			(layers "F.Cu" "F.Mask" "F.Paste")
			(net "GND")
		)
		(pad "EB45" smd circle
			(at 2.052066 23.122128)
			(size 0.4318 0.4318)
			(layers "F.Cu" "F.Mask" "F.Paste")
			(net "M_K_CS_N<7>")
		)
		(pad "EB47" smd circle
			(at 3.769106 23.122128)
			(size 0.4318 0.4318)
			(layers "F.Cu" "F.Mask" "F.Paste")
			(net "M_K_CS_N<3>")
		)
		(pad "EB49" smd circle
			(at 5.485892 23.122128)
			(size 0.4318 0.4318)
			(layers "F.Cu" "F.Mask" "F.Paste")
			(net "M_K_CS_N<5>")
		)
		(pad "EB51" smd circle
			(at 7.202932 23.122128)
			(size 0.4318 0.4318)
			(layers "F.Cu" "F.Mask" "F.Paste")
			(net "M_K_CS_N<4>")
		)
		(pad "EB53" smd circle
			(at 8.919972 23.122128)
			(size 0.4318 0.4318)
			(layers "F.Cu" "F.Mask" "F.Paste")
			(net "M_K_MA<0>")
		)
		(pad "EB55" smd circle
			(at 10.637012 23.122128)
			(size 0.4318 0.4318)
			(layers "F.Cu" "F.Mask" "F.Paste")
			(net "M_K_CLK_DP<0>")
		)
		(pad "EB57" smd circle
			(at 12.354052 23.122128)
			(size 0.4318 0.4318)
			(layers "F.Cu" "F.Mask" "F.Paste")
			(net "M_K_MA<3>")
		)
		(pad "EB59" smd circle
			(at 14.071092 23.122128)
			(size 0.4318 0.4318)
			(layers "F.Cu" "F.Mask" "F.Paste")
			(net "M_K_MA<8>")
		)
		(pad "EB61" smd circle
			(at 15.787878 23.122128)
			(size 0.4318 0.4318)
			(layers "F.Cu" "F.Mask" "F.Paste")
			(net "M_K_MA<11>")
		)
		(pad "EB63" smd custom
			(at 17.504918 23.122128 180)
			(size 0.10795 0.10795)
			(layers "F.Cu" "F.Mask" "F.Paste")
			(net "M_K_CKE<3>")
			(options
				(clearance outline)
				(anchor circle)
			)
			(primitives
				(gr_poly
					(pts
						(arc
							(start 0.2159 -0.0381)
							(mid 0 -0.254)
							(end -0.2159 -0.0381)
						)
						(arc
							(start -0.2159 0.0381)
							(mid 0 0.254)
							(end 0.2159 0.0381)
						)
					)
					(width 0)
					(fill yes)
				)
			)
		)
		(pad "EB65" smd custom
			(at 19.221958 23.122128 180)
			(size 0.10795 0.10795)
			(layers "F.Cu" "F.Mask" "F.Paste")
			(net "GND")
			(options
				(clearance outline)
				(anchor circle)
			)
			(primitives
				(gr_poly
					(pts
						(arc
							(start 0.2159 -0.0381)
							(mid 0 -0.254)
							(end -0.2159 -0.0381)
						)
						(arc
							(start -0.2159 0.0381)
							(mid 0 0.254)
							(end 0.2159 0.0381)
						)
					)
					(width 0)
					(fill yes)
				)
			)
		)
		(pad "EB67" smd custom
			(at 20.938998 23.122128 180)
			(size 0.10795 0.10795)
			(layers "F.Cu" "F.Mask" "F.Paste")
			(net "M_L_DQS_DN<8>")
			(options
				(clearance outline)
				(anchor circle)
			)
			(primitives
				(gr_poly
					(pts
						(arc
							(start 0.2159 -0.0381)
							(mid 0 -0.254)
							(end -0.2159 -0.0381)
						)
						(arc
							(start -0.2159 0.0381)
							(mid 0 0.254)
							(end 0.2159 0.0381)
						)
					)
					(width 0)
					(fill yes)
				)
			)
		)
		(pad "EB69" smd custom
			(at 22.656038 23.122128 180)
			(size 0.10795 0.10795)
			(layers "F.Cu" "F.Mask" "F.Paste")
			(net "GND")
			(options
				(clearance outline)
				(anchor circle)
			)
			(primitives
				(gr_poly
					(pts
						(arc
							(start 0.2159 -0.0381)
							(mid 0 -0.254)
							(end -0.2159 -0.0381)
						)
						(arc
							(start -0.2159 0.0381)
							(mid 0 0.254)
							(end 0.2159 0.0381)
						)
					)
					(width 0)
					(fill yes)
				)
			)
		)
		(pad "EB71" smd circle
			(at 24.373078 23.122128)
			(size 0.4318 0.4318)
			(layers "F.Cu" "F.Mask" "F.Paste")
			(net "M_L_DQ<26>")
		)
		(pad "EB73" smd circle
			(at 26.090118 23.122128)
			(size 0.4318 0.4318)
			(layers "F.Cu" "F.Mask" "F.Paste")
			(net "M_L_DQS_DN<12>")
		)
		(pad "EB75" smd circle
			(at 27.806904 23.122128)
			(size 0.4318 0.4318)
			(layers "F.Cu" "F.Mask" "F.Paste")
			(net "M_L_DQ<29>")
		)
		(pad "EB77" smd circle
			(at 29.523944 23.122128)
			(size 0.4318 0.4318)
			(layers "F.Cu" "F.Mask" "F.Paste")
			(net "M_L_DQ<19>")
		)
		(pad "EB79" smd circle
			(at 31.240984 23.122128)
			(size 0.4318 0.4318)
			(layers "F.Cu" "F.Mask" "F.Paste")
			(net "M_L_DQS_DP<2>")
		)
		(pad "EB81" smd circle
			(at 32.958024 23.122128)
			(size 0.4318 0.4318)
			(layers "F.Cu" "F.Mask" "F.Paste")
			(net "M_L_DQ<21>")
		)
		(pad "EB83" smd custom
			(at 34.675064 23.122128 225)
			(size 0.10795 0.10795)
			(layers "F.Cu" "F.Mask" "F.Paste")
			(net "GND")
			(options
				(clearance outline)
				(anchor circle)
			)
			(primitives
				(gr_poly
					(pts
						(arc
							(start 0.2159 -0.0381)
							(mid 0 -0.254)
							(end -0.2159 -0.0381)
						)
						(arc
							(start -0.2159 0.0381)
							(mid 0 0.254)
							(end 0.2159 0.0381)
						)
					)
					(width 0)
					(fill yes)
				)
			)
		)
		(pad "EB85" smd custom
			(at 36.392104 23.122128 270)
			(size 0.10795 0.10795)
			(layers "F.Cu" "F.Mask" "F.Paste")
			(net "TP_CPU1_RSVD_16")
			(options
				(clearance outline)
				(anchor circle)
			)
			(primitives
				(gr_poly
					(pts
						(arc
							(start 0.2159 -0.0381)
							(mid 0 -0.254)
							(end -0.2159 -0.0381)
						)
						(arc
							(start -0.2159 0.0381)
							(mid 0 0.254)
							(end 0.2159 0.0381)
						)
					)
					(width 0)
					(fill yes)
				)
			)
		)
		(pad "EC4" smd custom
			(at -34.675064 25.417526 135)
			(size 0.10795 0.10795)
			(layers "F.Cu" "F.Mask" "F.Paste")
			(net "TP_CPU1_RSVD_14")
			(options
				(clearance outline)
				(anchor circle)
			)
			(primitives
				(gr_poly
					(pts
						(arc
							(start 0.2159 -0.0381)
							(mid 0 -0.254)
							(end -0.2159 -0.0381)
						)
						(arc
							(start -0.2159 0.0381)
							(mid 0 0.254)
							(end 0.2159 0.0381)
						)
					)
					(width 0)
					(fill yes)
				)
			)
		)
		(pad "EC6" smd custom
			(at -32.958024 25.417526 135)
			(size 0.10795 0.10795)
			(layers "F.Cu" "F.Mask" "F.Paste")
			(net "GND")
			(options
				(clearance outline)
				(anchor circle)
			)
			(primitives
				(gr_poly
					(pts
						(arc
							(start 0.2159 -0.0381)
							(mid 0 -0.254)
							(end -0.2159 -0.0381)
						)
						(arc
							(start -0.2159 0.0381)
							(mid 0 0.254)
							(end 0.2159 0.0381)
						)
					)
					(width 0)
					(fill yes)
				)
			)
		)
		(pad "EC8" smd circle
			(at -31.240984 25.417526)
			(size 0.4318 0.4318)
			(layers "F.Cu" "F.Mask" "F.Paste")
			(net "TP_P3E_CPU1_PE1_RSR3_TXP<15>")
		)
		(pad "EC10" smd circle
			(at -29.523944 25.417526)
			(size 0.4318 0.4318)
			(layers "F.Cu" "F.Mask" "F.Paste")
			(net "GND")
		)
		(pad "EC12" smd circle
			(at -27.806904 25.417526)
			(size 0.4318 0.4318)
			(layers "F.Cu" "F.Mask" "F.Paste")
			(net "P3E_CPU1_PE3_MP_TXN<2>")
		)
		(pad "EC14" smd circle
			(at -26.090118 25.417526)
			(size 0.4318 0.4318)
			(layers "F.Cu" "F.Mask" "F.Paste")
			(net "P3E_CPU1_PE3_MP_TXP<0>")
		)
		(pad "EC16" smd custom
			(at -24.373078 25.417526 180)
			(size 0.10795 0.10795)
			(layers "F.Cu" "F.Mask" "F.Paste")
			(net "TP_CPU1_RSVD_15")
			(options
				(clearance outline)
				(anchor circle)
			)
			(primitives
				(gr_poly
					(pts
						(arc
							(start 0.2159 -0.0381)
							(mid 0 -0.254)
							(end -0.2159 -0.0381)
						)
						(arc
							(start -0.2159 0.0381)
							(mid 0 0.254)
							(end 0.2159 0.0381)
						)
					)
					(width 0)
					(fill yes)
				)
			)
		)
		(pad "EC22" smd custom
			(at -19.221958 25.417526 120)
			(size 0.10795 0.10795)
			(layers "F.Cu" "F.Mask" "F.Paste")
			(net "M_K_DQ<62>")
			(options
				(clearance outline)
				(anchor circle)
			)
			(primitives
				(gr_poly
					(pts
						(arc
							(start 0.2159 -0.0381)
							(mid 0 -0.254)
							(end -0.2159 -0.0381)
						)
						(arc
							(start -0.2159 0.0381)
							(mid 0 0.254)
							(end 0.2159 0.0381)
						)
					)
					(width 0)
					(fill yes)
				)
			)
		)
		(pad "EC24" smd circle
			(at -17.504918 25.417526)
			(size 0.4318 0.4318)
			(layers "F.Cu" "F.Mask" "F.Paste")
			(net "M_L_DQ<51>")
		)
		(pad "EC26" smd circle
			(at -15.787878 25.417526)
			(size 0.4318 0.4318)
			(layers "F.Cu" "F.Mask" "F.Paste")
			(net "M_L_DQS_DP<6>")
		)
		(pad "EC28" smd circle
			(at -14.071092 25.417526)
			(size 0.4318 0.4318)
			(layers "F.Cu" "F.Mask" "F.Paste")
			(net "M_L_DQ<48>")
		)
		(pad "EC30" smd circle
			(at -12.354052 25.417526)
			(size 0.4318 0.4318)
			(layers "F.Cu" "F.Mask" "F.Paste")
			(net "M_L_DQ<43>")
		)
		(pad "EC32" smd circle
			(at -10.637012 25.417526)
			(size 0.4318 0.4318)
			(layers "F.Cu" "F.Mask" "F.Paste")
			(net "M_L_DQS_DP<5>")
		)
		(pad "EC34" smd circle
			(at -8.919972 25.417526)
			(size 0.4318 0.4318)
			(layers "F.Cu" "F.Mask" "F.Paste")
			(net "M_L_DQ<40>")
		)
		(pad "EC36" smd circle
			(at -7.202932 25.417526)
			(size 0.4318 0.4318)
			(layers "F.Cu" "F.Mask" "F.Paste")
			(net "M_K_DQ<35>")
		)
		(pad "EC38" smd circle
			(at -5.485892 25.417526)
			(size 0.4318 0.4318)
			(layers "F.Cu" "F.Mask" "F.Paste")
			(net "M_K_DQS_DP<4>")
		)
		(pad "EC40" smd circle
			(at -3.769106 25.417526)
			(size 0.4318 0.4318)
			(layers "F.Cu" "F.Mask" "F.Paste")
			(net "M_K_DQ<32>")
		)
		(pad "EC42" smd custom
			(at -2.052066 25.417526 225)
			(size 0.10795 0.10795)
			(layers "F.Cu" "F.Mask" "F.Paste")
			(net "GND")
			(options
				(clearance outline)
				(anchor circle)
			)
			(primitives
				(gr_poly
					(pts
						(arc
							(start 0.2159 -0.0381)
							(mid 0 -0.254)
							(end -0.2159 -0.0381)
						)
						(arc
							(start -0.2159 0.0381)
							(mid 0 0.254)
							(end 0.2159 0.0381)
						)
					)
					(width 0)
					(fill yes)
				)
			)
		)
		(pad "EC44" smd circle
			(at 1.193546 23.617174)
			(size 0.508 0.508)
			(layers "F.Cu" "F.Mask" "F.Paste")
			(net "TP_CPU1_RSVD_13")
		)
		(pad "EC46" smd circle
			(at 2.910586 23.617174)
			(size 0.4318 0.4318)
			(layers "F.Cu" "F.Mask" "F.Paste")
			(net "PVDDQ_KLM")
		)
		(pad "EC48" smd circle
			(at 4.627626 23.617174)
			(size 0.4318 0.4318)
			(layers "F.Cu" "F.Mask" "F.Paste")
			(net "PVDDQ_KLM")
		)
		(pad "EC50" smd circle
			(at 6.344412 23.617174)
			(size 0.4318 0.4318)
			(layers "F.Cu" "F.Mask" "F.Paste")
			(net "PVDDQ_KLM")
		)
		(pad "EC52" smd circle
			(at 8.061452 23.617174)
			(size 0.4318 0.4318)
			(layers "F.Cu" "F.Mask" "F.Paste")
			(net "PVDDQ_KLM")
		)
		(pad "EC54" smd circle
			(at 9.778492 23.617174)
			(size 0.4318 0.4318)
			(layers "F.Cu" "F.Mask" "F.Paste")
			(net "PVDDQ_KLM")
		)
		(pad "EC56" smd circle
			(at 11.495532 23.617174)
			(size 0.4318 0.4318)
			(layers "F.Cu" "F.Mask" "F.Paste")
			(net "PVDDQ_KLM")
		)
		(pad "EC58" smd circle
			(at 13.212572 23.617174)
			(size 0.4318 0.4318)
			(layers "F.Cu" "F.Mask" "F.Paste")
			(net "PVDDQ_KLM")
		)
		(pad "EC60" smd circle
			(at 14.929612 23.617174)
			(size 0.4318 0.4318)
			(layers "F.Cu" "F.Mask" "F.Paste")
			(net "PVDDQ_KLM")
		)
		(pad "EC62" smd circle
			(at 16.646398 23.617174)
			(size 0.4318 0.4318)
			(layers "F.Cu" "F.Mask" "F.Paste")
			(net "PVDDQ_KLM")
		)
		(pad "EC70" smd circle
			(at 23.514558 23.617174)
			(size 0.4318 0.4318)
			(layers "F.Cu" "F.Mask" "F.Paste")
			(net "GND")
		)
		(pad "EC72" smd circle
			(at 25.231598 23.617174)
			(size 0.4318 0.4318)
			(layers "F.Cu" "F.Mask" "F.Paste")
			(net "GND")
		)
		(pad "EC74" smd circle
			(at 26.948384 23.617174)
			(size 0.4318 0.4318)
			(layers "F.Cu" "F.Mask" "F.Paste")
			(net "GND")
		)
		(pad "EC76" smd circle
			(at 28.665424 23.617174)
			(size 0.4318 0.4318)
			(layers "F.Cu" "F.Mask" "F.Paste")
			(net "GND")
		)
		(pad "EC78" smd circle
			(at 30.382464 23.617174)
			(size 0.4318 0.4318)
			(layers "F.Cu" "F.Mask" "F.Paste")
			(net "M_L_DQ<23>")
		)
		(pad "EC80" smd circle
			(at 32.099504 23.617174)
			(size 0.4318 0.4318)
			(layers "F.Cu" "F.Mask" "F.Paste")
			(net "M_L_DQ<17>")
		)
		(pad "EC82" smd custom
			(at 33.816544 23.617174 225)
			(size 0.10795 0.10795)
			(layers "F.Cu" "F.Mask" "F.Paste")
			(net "GND")
			(options
				(clearance outline)
				(anchor circle)
			)
			(primitives
				(gr_poly
					(pts
						(arc
							(start 0.2159 -0.0381)
							(mid 0 -0.254)
							(end -0.2159 -0.0381)
						)
						(arc
							(start -0.2159 0.0381)
							(mid 0 0.254)
							(end 0.2159 0.0381)
						)
					)
					(width 0)
					(fill yes)
				)
			)
		)
		(pad "EC84" smd custom
			(at 35.533584 23.617174 270)
			(size 0.10795 0.10795)
			(layers "F.Cu" "F.Mask" "F.Paste")
			(net "TP_CPU1_RSVD_12")
			(options
				(clearance outline)
				(anchor circle)
			)
			(primitives
				(gr_poly
					(pts
						(arc
							(start 0.2159 -0.0381)
							(mid 0 -0.254)
							(end -0.2159 -0.0381)
						)
						(arc
							(start -0.2159 0.0381)
							(mid 0 0.254)
							(end 0.2159 0.0381)
						)
					)
					(width 0)
					(fill yes)
				)
			)
		)
		(pad "ED5" smd custom
			(at -33.816544 25.912572 135)
			(size 0.10795 0.10795)
			(layers "F.Cu" "F.Mask" "F.Paste")
			(net "TP_CPU1_RSVD_10")
			(options
				(clearance outline)
				(anchor circle)
			)
			(primitives
				(gr_poly
					(pts
						(arc
							(start 0.2159 -0.0381)
							(mid 0 -0.254)
							(end -0.2159 -0.0381)
						)
						(arc
							(start -0.2159 0.0381)
							(mid 0 0.254)
							(end 0.2159 0.0381)
						)
					)
					(width 0)
					(fill yes)
				)
			)
		)
		(pad "ED7" smd custom
			(at -32.099504 25.912572 135)
			(size 0.10795 0.10795)
			(layers "F.Cu" "F.Mask" "F.Paste")
			(net "GND")
			(options
				(clearance outline)
				(anchor circle)
			)
			(primitives
				(gr_poly
					(pts
						(arc
							(start 0.2159 -0.0381)
							(mid 0 -0.254)
							(end -0.2159 -0.0381)
						)
						(arc
							(start -0.2159 0.0381)
							(mid 0 0.254)
							(end 0.2159 0.0381)
						)
					)
					(width 0)
					(fill yes)
				)
			)
		)
		(pad "ED9" smd circle
			(at -30.382464 25.912572)
			(size 0.4318 0.4318)
			(layers "F.Cu" "F.Mask" "F.Paste")
			(net "TP_P3E_CPU1_PE1_RSR3_TXN<15>")
		)
		(pad "ED11" smd circle
			(at -28.665424 25.912572)
			(size 0.4318 0.4318)
			(layers "F.Cu" "F.Mask" "F.Paste")
			(net "GND")
		)
		(pad "ED13" smd circle
			(at -26.948384 25.912572)
			(size 0.4318 0.4318)
			(layers "F.Cu" "F.Mask" "F.Paste")
			(net "P3E_CPU1_PE3_MP_TXP<1>")
		)
		(pad "ED15" smd circle
			(at -25.231598 25.912572)
			(size 0.4318 0.4318)
			(layers "F.Cu" "F.Mask" "F.Paste")
			(net "GND")
		)
		(pad "ED23" smd custom
			(at -18.363438 25.912572 120)
			(size 0.10795 0.10795)
			(layers "F.Cu" "F.Mask" "F.Paste")
			(net "GND")
			(options
				(clearance outline)
				(anchor circle)
			)
			(primitives
				(gr_poly
					(pts
						(arc
							(start 0.2159 -0.0381)
							(mid 0 -0.254)
							(end -0.2159 -0.0381)
						)
						(arc
							(start -0.2159 0.0381)
							(mid 0 0.254)
							(end 0.2159 0.0381)
						)
					)
					(width 0)
					(fill yes)
				)
			)
		)
		(pad "ED25" smd circle
			(at -16.646398 25.912572)
			(size 0.4318 0.4318)
			(layers "F.Cu" "F.Mask" "F.Paste")
			(net "M_L_DQ<55>")
		)
		(pad "ED27" smd circle
			(at -14.929612 25.912572)
			(size 0.4318 0.4318)
			(layers "F.Cu" "F.Mask" "F.Paste")
			(net "M_L_DQ<49>")
		)
		(pad "ED29" smd circle
			(at -13.212572 25.912572)
			(size 0.4318 0.4318)
			(layers "F.Cu" "F.Mask" "F.Paste")
			(net "GND")
		)
		(pad "ED31" smd circle
			(at -11.495532 25.912572)
			(size 0.4318 0.4318)
			(layers "F.Cu" "F.Mask" "F.Paste")
			(net "M_L_DQ<47>")
		)
		(pad "ED33" smd circle
			(at -9.778492 25.912572)
			(size 0.4318 0.4318)
			(layers "F.Cu" "F.Mask" "F.Paste")
			(net "M_L_DQ<41>")
		)
		(pad "ED35" smd circle
			(at -8.061452 25.912572)
			(size 0.4318 0.4318)
			(layers "F.Cu" "F.Mask" "F.Paste")
			(net "GND")
		)
		(pad "ED37" smd circle
			(at -6.344412 25.912572)
			(size 0.4318 0.4318)
			(layers "F.Cu" "F.Mask" "F.Paste")
			(net "M_K_DQ<39>")
		)
		(pad "ED39" smd circle
			(at -4.627626 25.912572)
			(size 0.4318 0.4318)
			(layers "F.Cu" "F.Mask" "F.Paste")
			(net "M_K_DQ<33>")
		)
		(pad "ED41" smd custom
			(at -2.910586 25.912572 225)
			(size 0.10795 0.10795)
			(layers "F.Cu" "F.Mask" "F.Paste")
			(net "GND")
			(options
				(clearance outline)
				(anchor circle)
			)
			(primitives
				(gr_poly
					(pts
						(arc
							(start 0.2159 -0.0381)
							(mid 0 -0.254)
							(end -0.2159 -0.0381)
						)
						(arc
							(start -0.2159 0.0381)
							(mid 0 0.254)
							(end 0.2159 0.0381)
						)
					)
					(width 0)
					(fill yes)
				)
			)
		)
		(pad "ED45" smd circle
			(at 2.052066 24.112474)
			(size 0.4318 0.4318)
			(layers "F.Cu" "F.Mask" "F.Paste")
			(net "TP_CPU1_RSVD_11")
		)
		(pad "ED47" smd circle
			(at 3.769106 24.112474)
			(size 0.4318 0.4318)
			(layers "F.Cu" "F.Mask" "F.Paste")
			(net "M_K_CS_N<2>")
		)
		(pad "ED49" smd circle
			(at 5.485892 24.112474)
			(size 0.4318 0.4318)
			(layers "F.Cu" "F.Mask" "F.Paste")
			(net "M_K_CS_N<1>")
		)
		(pad "ED51" smd circle
			(at 7.202932 24.112474)
			(size 0.4318 0.4318)
			(layers "F.Cu" "F.Mask" "F.Paste")
			(net "M_K_MA<14>")
		)
		(pad "ED53" smd circle
			(at 8.919972 24.112474)
			(size 0.4318 0.4318)
			(layers "F.Cu" "F.Mask" "F.Paste")
			(net "M_K_PAR")
		)
		(pad "ED55" smd circle
			(at 10.637012 24.112474)
			(size 0.4318 0.4318)
			(layers "F.Cu" "F.Mask" "F.Paste")
			(net "M_K_CLK_DN<0>")
		)
		(pad "ED57" smd circle
			(at 12.354052 24.112474)
			(size 0.4318 0.4318)
			(layers "F.Cu" "F.Mask" "F.Paste")
			(net "M_K_MA<1>")
		)
		(pad "ED59" smd circle
			(at 14.071092 24.112474)
			(size 0.4318 0.4318)
			(layers "F.Cu" "F.Mask" "F.Paste")
			(net "M_K_MA<4>")
		)
		(pad "ED61" smd circle
			(at 15.787878 24.112474)
			(size 0.4318 0.4318)
			(layers "F.Cu" "F.Mask" "F.Paste")
			(net "M_K_BG<0>")
		)
		(pad "ED63" smd custom
			(at 17.504918 24.112474 180)
			(size 0.10795 0.10795)
			(layers "F.Cu" "F.Mask" "F.Paste")
			(net "M_K_ALERT_N")
			(options
				(clearance outline)
				(anchor circle)
			)
			(primitives
				(gr_poly
					(pts
						(arc
							(start 0.2159 -0.0381)
							(mid 0 -0.254)
							(end -0.2159 -0.0381)
						)
						(arc
							(start -0.2159 0.0381)
							(mid 0 0.254)
							(end 0.2159 0.0381)
						)
					)
					(width 0)
					(fill yes)
				)
			)
		)
		(pad "ED69" smd custom
			(at 22.656038 24.112474 180)
			(size 0.10795 0.10795)
			(layers "F.Cu" "F.Mask" "F.Paste")
			(net "GND")
			(options
				(clearance outline)
				(anchor circle)
			)
			(primitives
				(gr_poly
					(pts
						(arc
							(start 0.2159 -0.0381)
							(mid 0 -0.254)
							(end -0.2159 -0.0381)
						)
						(arc
							(start -0.2159 0.0381)
							(mid 0 0.254)
							(end 0.2159 0.0381)
						)
					)
					(width 0)
					(fill yes)
				)
			)
		)
		(pad "ED71" smd circle
			(at 24.373078 24.112474)
			(size 0.4318 0.4318)
			(layers "F.Cu" "F.Mask" "F.Paste")
			(net "M_L_DQ<27>")
		)
		(pad "ED73" smd circle
			(at 26.090118 24.112474)
			(size 0.4318 0.4318)
			(layers "F.Cu" "F.Mask" "F.Paste")
			(net "M_L_DQS_DP<3>")
		)
		(pad "ED75" smd circle
			(at 27.806904 24.112474)
			(size 0.4318 0.4318)
			(layers "F.Cu" "F.Mask" "F.Paste")
			(net "M_L_DQ<24>")
		)
		(pad "ED77" smd circle
			(at 29.523944 24.112474)
			(size 0.4318 0.4318)
			(layers "F.Cu" "F.Mask" "F.Paste")
			(net "GND")
		)
		(pad "ED79" smd circle
			(at 31.240984 24.112474)
			(size 0.4318 0.4318)
			(layers "F.Cu" "F.Mask" "F.Paste")
			(net "M_L_DQS_DN<2>")
		)
		(pad "ED81" smd custom
			(at 32.958024 24.112474 225)
			(size 0.10795 0.10795)
			(layers "F.Cu" "F.Mask" "F.Paste")
			(net "GND")
			(options
				(clearance outline)
				(anchor circle)
			)
			(primitives
				(gr_poly
					(pts
						(arc
							(start 0.2159 -0.0381)
							(mid 0 -0.254)
							(end -0.2159 -0.0381)
						)
						(arc
							(start -0.2159 0.0381)
							(mid 0 0.254)
							(end 0.2159 0.0381)
						)
					)
					(width 0)
					(fill yes)
				)
			)
		)
		(pad "ED83" smd custom
			(at 34.675064 24.112474 270)
			(size 0.10795 0.10795)
			(layers "F.Cu" "F.Mask" "F.Paste")
			(net "TP_CPU1_RSVD_9")
			(options
				(clearance outline)
				(anchor circle)
			)
			(primitives
				(gr_poly
					(pts
						(arc
							(start 0.2159 -0.0381)
							(mid 0 -0.254)
							(end -0.2159 -0.0381)
						)
						(arc
							(start -0.2159 0.0381)
							(mid 0 0.254)
							(end 0.2159 0.0381)
						)
					)
					(width 0)
					(fill yes)
				)
			)
		)
		(pad "EE6" smd custom
			(at -32.958024 26.408126 135)
			(size 0.10795 0.10795)
			(layers "F.Cu" "F.Mask" "F.Paste")
			(net "TP_CPU1_RSVD_6")
			(options
				(clearance outline)
				(anchor circle)
			)
			(primitives
				(gr_poly
					(pts
						(arc
							(start 0.2159 -0.0381)
							(mid 0 -0.254)
							(end -0.2159 -0.0381)
						)
						(arc
							(start -0.2159 0.0381)
							(mid 0 0.254)
							(end 0.2159 0.0381)
						)
					)
					(width 0)
					(fill yes)
				)
			)
		)
		(pad "EE8" smd custom
			(at -31.240984 26.408126 135)
			(size 0.10795 0.10795)
			(layers "F.Cu" "F.Mask" "F.Paste")
			(net "GND")
			(options
				(clearance outline)
				(anchor circle)
			)
			(primitives
				(gr_poly
					(pts
						(arc
							(start 0.2159 -0.0381)
							(mid 0 -0.254)
							(end -0.2159 -0.0381)
						)
						(arc
							(start -0.2159 0.0381)
							(mid 0 0.254)
							(end 0.2159 0.0381)
						)
					)
					(width 0)
					(fill yes)
				)
			)
		)
		(pad "EE10" smd custom
			(at -29.523944 26.408126 180)
			(size 0.10795 0.10795)
			(layers "F.Cu" "F.Mask" "F.Paste")
			(net "PVCCIO_CPU1")
			(options
				(clearance outline)
				(anchor circle)
			)
			(primitives
				(gr_poly
					(pts
						(arc
							(start 0.2159 -0.0381)
							(mid 0 -0.254)
							(end -0.2159 -0.0381)
						)
						(arc
							(start -0.2159 0.0381)
							(mid 0 0.254)
							(end 0.2159 0.0381)
						)
					)
					(width 0)
					(fill yes)
				)
			)
		)
		(pad "EE12" smd custom
			(at -27.806904 26.408126 180)
			(size 0.10795 0.10795)
			(layers "F.Cu" "F.Mask" "F.Paste")
			(net "P3E_CPU1_PE3_MP_TXN<1>")
			(options
				(clearance outline)
				(anchor circle)
			)
			(primitives
				(gr_poly
					(pts
						(arc
							(start 0.2159 -0.0381)
							(mid 0 -0.254)
							(end -0.2159 -0.0381)
						)
						(arc
							(start -0.2159 0.0381)
							(mid 0 0.254)
							(end 0.2159 0.0381)
						)
					)
					(width 0)
					(fill yes)
				)
			)
		)
		(pad "EE14" smd custom
			(at -26.090118 26.408126 180)
			(size 0.10795 0.10795)
			(layers "F.Cu" "F.Mask" "F.Paste")
			(net "P3E_CPU1_PE3_MP_TXN<0>")
			(options
				(clearance outline)
				(anchor circle)
			)
			(primitives
				(gr_poly
					(pts
						(arc
							(start 0.2159 -0.0381)
							(mid 0 -0.254)
							(end -0.2159 -0.0381)
						)
						(arc
							(start -0.2159 0.0381)
							(mid 0 0.254)
							(end 0.2159 0.0381)
						)
					)
					(width 0)
					(fill yes)
				)
			)
		)
		(pad "EE16" smd custom
			(at -24.373078 26.408126 180)
			(size 0.10795 0.10795)
			(layers "F.Cu" "F.Mask" "F.Paste")
			(net "TP_CPU1_RSVD_8")
			(options
				(clearance outline)
				(anchor circle)
			)
			(primitives
				(gr_poly
					(pts
						(arc
							(start 0.2159 -0.0381)
							(mid 0 -0.254)
							(end -0.2159 -0.0381)
						)
						(arc
							(start -0.2159 0.0381)
							(mid 0 0.254)
							(end 0.2159 0.0381)
						)
					)
					(width 0)
					(fill yes)
				)
			)
		)
		(pad "EE24" smd custom
			(at -17.504918 26.408126 120)
			(size 0.10795 0.10795)
			(layers "F.Cu" "F.Mask" "F.Paste")
			(net "GND")
			(options
				(clearance outline)
				(anchor circle)
			)
			(primitives
				(gr_poly
					(pts
						(arc
							(start 0.2159 -0.0381)
							(mid 0 -0.254)
							(end -0.2159 -0.0381)
						)
						(arc
							(start -0.2159 0.0381)
							(mid 0 0.254)
							(end 0.2159 0.0381)
						)
					)
					(width 0)
					(fill yes)
				)
			)
		)
		(pad "EE26" smd custom
			(at -15.787878 26.408126 180)
			(size 0.10795 0.10795)
			(layers "F.Cu" "F.Mask" "F.Paste")
			(net "M_L_DQS_DN<6>")
			(options
				(clearance outline)
				(anchor circle)
			)
			(primitives
				(gr_poly
					(pts
						(arc
							(start 0.2159 -0.0381)
							(mid 0 -0.254)
							(end -0.2159 -0.0381)
						)
						(arc
							(start -0.2159 0.0381)
							(mid 0 0.254)
							(end 0.2159 0.0381)
						)
					)
					(width 0)
					(fill yes)
				)
			)
		)
		(pad "EE28" smd custom
			(at -14.071092 26.408126 180)
			(size 0.10795 0.10795)
			(layers "F.Cu" "F.Mask" "F.Paste")
			(net "GND")
			(options
				(clearance outline)
				(anchor circle)
			)
			(primitives
				(gr_poly
					(pts
						(arc
							(start 0.2159 -0.0381)
							(mid 0 -0.254)
							(end -0.2159 -0.0381)
						)
						(arc
							(start -0.2159 0.0381)
							(mid 0 0.254)
							(end 0.2159 0.0381)
						)
					)
					(width 0)
					(fill yes)
				)
			)
		)
		(pad "EE30" smd custom
			(at -12.354052 26.408126 180)
			(size 0.10795 0.10795)
			(layers "F.Cu" "F.Mask" "F.Paste")
			(net "GND")
			(options
				(clearance outline)
				(anchor circle)
			)
			(primitives
				(gr_poly
					(pts
						(arc
							(start 0.2159 -0.0381)
							(mid 0 -0.254)
							(end -0.2159 -0.0381)
						)
						(arc
							(start -0.2159 0.0381)
							(mid 0 0.254)
							(end 0.2159 0.0381)
						)
					)
					(width 0)
					(fill yes)
				)
			)
		)
		(pad "EE32" smd custom
			(at -10.637012 26.408126 180)
			(size 0.10795 0.10795)
			(layers "F.Cu" "F.Mask" "F.Paste")
			(net "M_L_DQS_DN<5>")
			(options
				(clearance outline)
				(anchor circle)
			)
			(primitives
				(gr_poly
					(pts
						(arc
							(start 0.2159 -0.0381)
							(mid 0 -0.254)
							(end -0.2159 -0.0381)
						)
						(arc
							(start -0.2159 0.0381)
							(mid 0 0.254)
							(end 0.2159 0.0381)
						)
					)
					(width 0)
					(fill yes)
				)
			)
		)
		(pad "EE34" smd custom
			(at -8.919972 26.408126 180)
			(size 0.10795 0.10795)
			(layers "F.Cu" "F.Mask" "F.Paste")
			(net "GND")
			(options
				(clearance outline)
				(anchor circle)
			)
			(primitives
				(gr_poly
					(pts
						(arc
							(start 0.2159 -0.0381)
							(mid 0 -0.254)
							(end -0.2159 -0.0381)
						)
						(arc
							(start -0.2159 0.0381)
							(mid 0 0.254)
							(end 0.2159 0.0381)
						)
					)
					(width 0)
					(fill yes)
				)
			)
		)
		(pad "EE36" smd custom
			(at -7.202932 26.408126 180)
			(size 0.10795 0.10795)
			(layers "F.Cu" "F.Mask" "F.Paste")
			(net "GND")
			(options
				(clearance outline)
				(anchor circle)
			)
			(primitives
				(gr_poly
					(pts
						(arc
							(start 0.2159 -0.0381)
							(mid 0 -0.254)
							(end -0.2159 -0.0381)
						)
						(arc
							(start -0.2159 0.0381)
							(mid 0 0.254)
							(end 0.2159 0.0381)
						)
					)
					(width 0)
					(fill yes)
				)
			)
		)
		(pad "EE38" smd custom
			(at -5.485892 26.408126 180)
			(size 0.10795 0.10795)
			(layers "F.Cu" "F.Mask" "F.Paste")
			(net "M_K_DQS_DN<4>")
			(options
				(clearance outline)
				(anchor circle)
			)
			(primitives
				(gr_poly
					(pts
						(arc
							(start 0.2159 -0.0381)
							(mid 0 -0.254)
							(end -0.2159 -0.0381)
						)
						(arc
							(start -0.2159 0.0381)
							(mid 0 0.254)
							(end 0.2159 0.0381)
						)
					)
					(width 0)
					(fill yes)
				)
			)
		)
		(pad "EE40" smd custom
			(at -3.769106 26.408126 225)
			(size 0.10795 0.10795)
			(layers "F.Cu" "F.Mask" "F.Paste")
			(net "GND")
			(options
				(clearance outline)
				(anchor circle)
			)
			(primitives
				(gr_poly
					(pts
						(arc
							(start 0.2159 -0.0381)
							(mid 0 -0.254)
							(end -0.2159 -0.0381)
						)
						(arc
							(start -0.2159 0.0381)
							(mid 0 0.254)
							(end 0.2159 0.0381)
						)
					)
					(width 0)
					(fill yes)
				)
			)
		)
		(pad "EE44" smd custom
			(at 1.193546 24.608028 135)
			(size 0.10795 0.10795)
			(layers "F.Cu" "F.Mask" "F.Paste")
			(net "PVDDQ_KLM")
			(options
				(clearance outline)
				(anchor circle)
			)
			(primitives
				(gr_poly
					(pts
						(arc
							(start 0.2159 -0.0381)
							(mid 0 -0.254)
							(end -0.2159 -0.0381)
						)
						(arc
							(start -0.2159 0.0381)
							(mid 0 0.254)
							(end 0.2159 0.0381)
						)
					)
					(width 0)
					(fill yes)
				)
			)
		)
		(pad "EE46" smd circle
			(at 2.910586 24.608028)
			(size 0.4318 0.4318)
			(layers "F.Cu" "F.Mask" "F.Paste")
			(net "TP_CPU1_RSVD_7")
		)
		(pad "EE48" smd circle
			(at 4.627626 24.608028)
			(size 0.4318 0.4318)
			(layers "F.Cu" "F.Mask" "F.Paste")
			(net "M_K_ODT<1>")
		)
		(pad "EE50" smd circle
			(at 6.344412 24.608028)
			(size 0.4318 0.4318)
			(layers "F.Cu" "F.Mask" "F.Paste")
			(net "M_K_ODT<0>")
		)
		(pad "EE52" smd circle
			(at 8.061452 24.608028)
			(size 0.4318 0.4318)
			(layers "F.Cu" "F.Mask" "F.Paste")
			(net "M_K_BA<0>")
		)
		(pad "EE54" smd circle
			(at 9.778492 24.608028)
			(size 0.4318 0.4318)
			(layers "F.Cu" "F.Mask" "F.Paste")
			(net "M_K_CLK_DP<1>")
		)
		(pad "EE56" smd circle
			(at 11.495532 24.608028)
			(size 0.4318 0.4318)
			(layers "F.Cu" "F.Mask" "F.Paste")
			(net "M_K_CLK_DP<3>")
		)
		(pad "EE58" smd circle
			(at 13.212572 24.608028)
			(size 0.4318 0.4318)
			(layers "F.Cu" "F.Mask" "F.Paste")
			(net "M_K_MA<2>")
		)
		(pad "EE60" smd circle
			(at 14.929612 24.608028)
			(size 0.4318 0.4318)
			(layers "F.Cu" "F.Mask" "F.Paste")
			(net "M_K_MA<6>")
		)
		(pad "EE62" smd circle
			(at 16.646398 24.608028)
			(size 0.4318 0.4318)
			(layers "F.Cu" "F.Mask" "F.Paste")
			(net "M_K_CKE<0>")
		)
		(pad "EE70" smd custom
			(at 23.514558 24.608028 180)
			(size 0.10795 0.10795)
			(layers "F.Cu" "F.Mask" "F.Paste")
			(net "GND")
			(options
				(clearance outline)
				(anchor circle)
			)
			(primitives
				(gr_poly
					(pts
						(arc
							(start 0.2159 -0.0381)
							(mid 0 -0.254)
							(end -0.2159 -0.0381)
						)
						(arc
							(start -0.2159 0.0381)
							(mid 0 0.254)
							(end 0.2159 0.0381)
						)
					)
					(width 0)
					(fill yes)
				)
			)
		)
		(pad "EE72" smd circle
			(at 25.231598 24.608028)
			(size 0.4318 0.4318)
			(layers "F.Cu" "F.Mask" "F.Paste")
			(net "M_L_DQ<31>")
		)
		(pad "EE74" smd circle
			(at 26.948384 24.608028)
			(size 0.4318 0.4318)
			(layers "F.Cu" "F.Mask" "F.Paste")
			(net "M_L_DQ<25>")
		)
		(pad "EE76" smd circle
			(at 28.665424 24.608028)
			(size 0.4318 0.4318)
			(layers "F.Cu" "F.Mask" "F.Paste")
			(net "GND")
		)
		(pad "EE78" smd circle
			(at 30.382464 24.608028)
			(size 0.4318 0.4318)
			(layers "F.Cu" "F.Mask" "F.Paste")
			(net "GND")
		)
		(pad "EE80" smd custom
			(at 32.099504 24.608028 225)
			(size 0.10795 0.10795)
			(layers "F.Cu" "F.Mask" "F.Paste")
			(net "GND")
			(options
				(clearance outline)
				(anchor circle)
			)
			(primitives
				(gr_poly
					(pts
						(arc
							(start 0.2159 -0.0381)
							(mid 0 -0.254)
							(end -0.2159 -0.0381)
						)
						(arc
							(start -0.2159 0.0381)
							(mid 0 0.254)
							(end 0.2159 0.0381)
						)
					)
					(width 0)
					(fill yes)
				)
			)
		)
		(pad "EE82" smd custom
			(at 33.816544 24.608028 270)
			(size 0.10795 0.10795)
			(layers "F.Cu" "F.Mask" "F.Paste")
			(net "TP_CPU1_RSVD_5")
			(options
				(clearance outline)
				(anchor circle)
			)
			(primitives
				(gr_poly
					(pts
						(arc
							(start 0.2159 -0.0381)
							(mid 0 -0.254)
							(end -0.2159 -0.0381)
						)
						(arc
							(start -0.2159 0.0381)
							(mid 0 0.254)
							(end 0.2159 0.0381)
						)
					)
					(width 0)
					(fill yes)
				)
			)
		)
		(pad "EE84" smd custom
			(at 35.533584 24.608028 270)
			(size 0.10795 0.10795)
			(layers "F.Cu" "F.Mask" "F.Paste")
			(net "TP_CPU1_RSVD_4")
			(options
				(clearance outline)
				(anchor circle)
			)
			(primitives
				(gr_poly
					(pts
						(arc
							(start 0.2159 -0.0381)
							(mid 0 -0.254)
							(end -0.2159 -0.0381)
						)
						(arc
							(start -0.2159 0.0381)
							(mid 0 0.254)
							(end 0.2159 0.0381)
						)
					)
					(width 0)
					(fill yes)
				)
			)
		)
		(pad "EF45" smd custom
			(at 2.052066 25.103074 135)
			(size 0.10795 0.10795)
			(layers "F.Cu" "F.Mask" "F.Paste")
			(net "PVDDQ_KLM")
			(options
				(clearance outline)
				(anchor circle)
			)
			(primitives
				(gr_poly
					(pts
						(arc
							(start 0.2159 -0.0381)
							(mid 0 -0.254)
							(end -0.2159 -0.0381)
						)
						(arc
							(start -0.2159 0.0381)
							(mid 0 0.254)
							(end 0.2159 0.0381)
						)
					)
					(width 0)
					(fill yes)
				)
			)
		)
		(pad "EF47" smd custom
			(at 3.769106 25.103074 180)
			(size 0.10795 0.10795)
			(layers "F.Cu" "F.Mask" "F.Paste")
			(net "TP_CPU1_RSVD_3")
			(options
				(clearance outline)
				(anchor circle)
			)
			(primitives
				(gr_poly
					(pts
						(arc
							(start 0.2159 -0.0381)
							(mid 0 -0.254)
							(end -0.2159 -0.0381)
						)
						(arc
							(start -0.2159 0.0381)
							(mid 0 0.254)
							(end 0.2159 0.0381)
						)
					)
					(width 0)
					(fill yes)
				)
			)
		)
		(pad "EF49" smd custom
			(at 5.485892 25.103074 180)
			(size 0.10795 0.10795)
			(layers "F.Cu" "F.Mask" "F.Paste")
			(net "PVDDQ_KLM")
			(options
				(clearance outline)
				(anchor circle)
			)
			(primitives
				(gr_poly
					(pts
						(arc
							(start 0.2159 -0.0381)
							(mid 0 -0.254)
							(end -0.2159 -0.0381)
						)
						(arc
							(start -0.2159 0.0381)
							(mid 0 0.254)
							(end 0.2159 0.0381)
						)
					)
					(width 0)
					(fill yes)
				)
			)
		)
		(pad "EF51" smd custom
			(at 7.202932 25.103074 180)
			(size 0.10795 0.10795)
			(layers "F.Cu" "F.Mask" "F.Paste")
			(net "M_K_CS_N<0>")
			(options
				(clearance outline)
				(anchor circle)
			)
			(primitives
				(gr_poly
					(pts
						(arc
							(start 0.2159 -0.0381)
							(mid 0 -0.254)
							(end -0.2159 -0.0381)
						)
						(arc
							(start -0.2159 0.0381)
							(mid 0 0.254)
							(end 0.2159 0.0381)
						)
					)
					(width 0)
					(fill yes)
				)
			)
		)
		(pad "EF53" smd custom
			(at 8.919972 25.103074 180)
			(size 0.10795 0.10795)
			(layers "F.Cu" "F.Mask" "F.Paste")
			(net "PVDDQ_KLM")
			(options
				(clearance outline)
				(anchor circle)
			)
			(primitives
				(gr_poly
					(pts
						(arc
							(start 0.2159 -0.0381)
							(mid 0 -0.254)
							(end -0.2159 -0.0381)
						)
						(arc
							(start -0.2159 0.0381)
							(mid 0 0.254)
							(end 0.2159 0.0381)
						)
					)
					(width 0)
					(fill yes)
				)
			)
		)
		(pad "EF55" smd custom
			(at 10.637012 25.103074 180)
			(size 0.10795 0.10795)
			(layers "F.Cu" "F.Mask" "F.Paste")
			(net "M_K_CLK_DN<1>")
			(options
				(clearance outline)
				(anchor circle)
			)
			(primitives
				(gr_poly
					(pts
						(arc
							(start 0.2159 -0.0381)
							(mid 0 -0.254)
							(end -0.2159 -0.0381)
						)
						(arc
							(start -0.2159 0.0381)
							(mid 0 0.254)
							(end 0.2159 0.0381)
						)
					)
					(width 0)
					(fill yes)
				)
			)
		)
		(pad "EF57" smd custom
			(at 12.354052 25.103074 180)
			(size 0.10795 0.10795)
			(layers "F.Cu" "F.Mask" "F.Paste")
			(net "M_K_CLK_DN<3>")
			(options
				(clearance outline)
				(anchor circle)
			)
			(primitives
				(gr_poly
					(pts
						(arc
							(start 0.2159 -0.0381)
							(mid 0 -0.254)
							(end -0.2159 -0.0381)
						)
						(arc
							(start -0.2159 0.0381)
							(mid 0 0.254)
							(end 0.2159 0.0381)
						)
					)
					(width 0)
					(fill yes)
				)
			)
		)
		(pad "EF59" smd custom
			(at 14.071092 25.103074 180)
			(size 0.10795 0.10795)
			(layers "F.Cu" "F.Mask" "F.Paste")
			(net "PVDDQ_KLM")
			(options
				(clearance outline)
				(anchor circle)
			)
			(primitives
				(gr_poly
					(pts
						(arc
							(start 0.2159 -0.0381)
							(mid 0 -0.254)
							(end -0.2159 -0.0381)
						)
						(arc
							(start -0.2159 0.0381)
							(mid 0 0.254)
							(end 0.2159 0.0381)
						)
					)
					(width 0)
					(fill yes)
				)
			)
		)
		(pad "EF61" smd custom
			(at 15.787878 25.103074 180)
			(size 0.10795 0.10795)
			(layers "F.Cu" "F.Mask" "F.Paste")
			(net "M_K_MA<9>")
			(options
				(clearance outline)
				(anchor circle)
			)
			(primitives
				(gr_poly
					(pts
						(arc
							(start 0.2159 -0.0381)
							(mid 0 -0.254)
							(end -0.2159 -0.0381)
						)
						(arc
							(start -0.2159 0.0381)
							(mid 0 0.254)
							(end 0.2159 0.0381)
						)
					)
					(width 0)
					(fill yes)
				)
			)
		)
		(pad "EF63" smd custom
			(at 17.504918 25.103074 180)
			(size 0.10795 0.10795)
			(layers "F.Cu" "F.Mask" "F.Paste")
			(net "M_K_CKE<1>")
			(options
				(clearance outline)
				(anchor circle)
			)
			(primitives
				(gr_poly
					(pts
						(arc
							(start 0.2159 -0.0381)
							(mid 0 -0.254)
							(end -0.2159 -0.0381)
						)
						(arc
							(start -0.2159 0.0381)
							(mid 0 0.254)
							(end 0.2159 0.0381)
						)
					)
					(width 0)
					(fill yes)
				)
			)
		)
		(pad "EF71" smd custom
			(at 24.373078 25.103074 180)
			(size 0.10795 0.10795)
			(layers "F.Cu" "F.Mask" "F.Paste")
			(net "GND")
			(options
				(clearance outline)
				(anchor circle)
			)
			(primitives
				(gr_poly
					(pts
						(arc
							(start 0.2159 -0.0381)
							(mid 0 -0.254)
							(end -0.2159 -0.0381)
						)
						(arc
							(start -0.2159 0.0381)
							(mid 0 0.254)
							(end 0.2159 0.0381)
						)
					)
					(width 0)
					(fill yes)
				)
			)
		)
		(pad "EF73" smd custom
			(at 26.090118 25.103074 180)
			(size 0.10795 0.10795)
			(layers "F.Cu" "F.Mask" "F.Paste")
			(net "M_L_DQS_DN<3>")
			(options
				(clearance outline)
				(anchor circle)
			)
			(primitives
				(gr_poly
					(pts
						(arc
							(start 0.2159 -0.0381)
							(mid 0 -0.254)
							(end -0.2159 -0.0381)
						)
						(arc
							(start -0.2159 0.0381)
							(mid 0 0.254)
							(end 0.2159 0.0381)
						)
					)
					(width 0)
					(fill yes)
				)
			)
		)
		(pad "EF75" smd custom
			(at 27.806904 25.103074 180)
			(size 0.10795 0.10795)
			(layers "F.Cu" "F.Mask" "F.Paste")
			(net "GND")
			(options
				(clearance outline)
				(anchor circle)
			)
			(primitives
				(gr_poly
					(pts
						(arc
							(start 0.2159 -0.0381)
							(mid 0 -0.254)
							(end -0.2159 -0.0381)
						)
						(arc
							(start -0.2159 0.0381)
							(mid 0 0.254)
							(end 0.2159 0.0381)
						)
					)
					(width 0)
					(fill yes)
				)
			)
		)
		(pad "EF77" smd custom
			(at 29.523944 25.103074 180)
			(size 0.10795 0.10795)
			(layers "F.Cu" "F.Mask" "F.Paste")
			(net "TP_CPU1_RSVD_2")
			(options
				(clearance outline)
				(anchor circle)
			)
			(primitives
				(gr_poly
					(pts
						(arc
							(start 0.2159 -0.0381)
							(mid 0 -0.254)
							(end -0.2159 -0.0381)
						)
						(arc
							(start -0.2159 0.0381)
							(mid 0 0.254)
							(end 0.2159 0.0381)
						)
					)
					(width 0)
					(fill yes)
				)
			)
		)
		(pad "EF79" smd custom
			(at 31.240984 25.103074 180)
			(size 0.10795 0.10795)
			(layers "F.Cu" "F.Mask" "F.Paste")
			(net "GND")
			(options
				(clearance outline)
				(anchor circle)
			)
			(primitives
				(gr_poly
					(pts
						(arc
							(start 0.2159 -0.0381)
							(mid 0 -0.254)
							(end -0.2159 -0.0381)
						)
						(arc
							(start -0.2159 0.0381)
							(mid 0 0.254)
							(end 0.2159 0.0381)
						)
					)
					(width 0)
					(fill yes)
				)
			)
		)
		(pad "EF81" smd custom
			(at 32.958024 25.103074 225)
			(size 0.10795 0.10795)
			(layers "F.Cu" "F.Mask" "F.Paste")
			(net "TP_CPU1_RSVD_1")
			(options
				(clearance outline)
				(anchor circle)
			)
			(primitives
				(gr_poly
					(pts
						(arc
							(start 0.2159 -0.0381)
							(mid 0 -0.254)
							(end -0.2159 -0.0381)
						)
						(arc
							(start -0.2159 0.0381)
							(mid 0 0.254)
							(end 0.2159 0.0381)
						)
					)
					(width 0)
					(fill yes)
				)
			)
		)
		(pad "EF83" smd custom
			(at 34.675064 25.103074 225)
			(size 0.10795 0.10795)
			(layers "F.Cu" "F.Mask" "F.Paste")
			(net "TP_CPU1_RSVD_0")
			(options
				(clearance outline)
				(anchor circle)
			)
			(primitives
				(gr_poly
					(pts
						(arc
							(start 0.2159 -0.0381)
							(mid 0 -0.254)
							(end -0.2159 -0.0381)
						)
						(arc
							(start -0.2159 0.0381)
							(mid 0 0.254)
							(end 0.2159 0.0381)
						)
					)
					(width 0)
					(fill yes)
				)
			)
		)
		(pad "F3" smd custom
			(at -35.533584 -22.626828 45)
			(size 0.10795 0.10795)
			(layers "F.Cu" "F.Mask" "F.Paste")
			(net "TP_CPU1_RSVD_279")
			(options
				(clearance outline)
				(anchor circle)
			)
			(primitives
				(gr_poly
					(pts
						(arc
							(start 0.2159 -0.0381)
							(mid 0 -0.254)
							(end -0.2159 -0.0381)
						)
						(arc
							(start -0.2159 0.0381)
							(mid 0 0.254)
							(end 0.2159 0.0381)
						)
					)
					(width 0)
					(fill yes)
				)
			)
		)
		(pad "F5" smd circle
			(at -33.816544 -22.626828)
			(size 0.4318 0.4318)
			(layers "F.Cu" "F.Mask" "F.Paste")
			(net "GND")
		)
		(pad "F7" smd circle
			(at -32.099504 -22.626828)
			(size 0.4318 0.4318)
			(layers "F.Cu" "F.Mask" "F.Paste")
			(net "UPI_CPU1_CPU0_P1P1_DP<4>")
		)
		(pad "F9" smd circle
			(at -30.382464 -22.626828)
			(size 0.4318 0.4318)
			(layers "F.Cu" "F.Mask" "F.Paste")
			(net "UPI_CPU1_CPU0_P1P1_DN<7>")
		)
		(pad "F11" smd circle
			(at -28.665424 -22.626828)
			(size 0.4318 0.4318)
			(layers "F.Cu" "F.Mask" "F.Paste")
			(net "UPI_CPU1_CPU0_P1P1_DP<8>")
		)
		(pad "F13" smd circle
			(at -26.948384 -22.626828)
			(size 0.4318 0.4318)
			(layers "F.Cu" "F.Mask" "F.Paste")
			(net "UPI_CPU1_CPU0_P1P1_DN<11>")
		)
		(pad "F15" smd circle
			(at -25.231598 -22.626828)
			(size 0.4318 0.4318)
			(layers "F.Cu" "F.Mask" "F.Paste")
			(net "UPI_CPU1_CPU0_P1P1_DN<13>")
		)
		(pad "F17" smd circle
			(at -23.514558 -22.626828)
			(size 0.4318 0.4318)
			(layers "F.Cu" "F.Mask" "F.Paste")
			(net "GND")
		)
		(pad "F19" smd circle
			(at -21.797518 -22.626828)
			(size 0.4318 0.4318)
			(layers "F.Cu" "F.Mask" "F.Paste")
			(net "GND")
		)
		(pad "F21" smd circle
			(at -20.080478 -22.626828)
			(size 0.4318 0.4318)
			(layers "F.Cu" "F.Mask" "F.Paste")
			(net "UPI_CPU1_CPU0_P1P1_DP<18>")
		)
		(pad "F23" smd circle
			(at -18.363438 -22.626828)
			(size 0.4318 0.4318)
			(layers "F.Cu" "F.Mask" "F.Paste")
			(net "TP_CPU1_RSVD_278")
		)
		(pad "F25" smd circle
			(at -16.646398 -22.626828)
			(size 0.4318 0.4318)
			(layers "F.Cu" "F.Mask" "F.Paste")
			(net "GND")
		)
		(pad "F27" smd circle
			(at -14.929612 -22.626828)
			(size 0.4318 0.4318)
			(layers "F.Cu" "F.Mask" "F.Paste")
			(net "M_H_DQ<55>")
		)
		(pad "F29" smd circle
			(at -13.212572 -22.626828)
			(size 0.4318 0.4318)
			(layers "F.Cu" "F.Mask" "F.Paste")
			(net "M_H_DQ<53>")
		)
		(pad "F31" smd circle
			(at -11.495532 -22.626828)
			(size 0.4318 0.4318)
			(layers "F.Cu" "F.Mask" "F.Paste")
			(net "GND")
		)
		(pad "F33" smd circle
			(at -9.778492 -22.626828)
			(size 0.4318 0.4318)
			(layers "F.Cu" "F.Mask" "F.Paste")
			(net "M_H_DQ<47>")
		)
		(pad "F35" smd circle
			(at -8.061452 -22.626828)
			(size 0.4318 0.4318)
			(layers "F.Cu" "F.Mask" "F.Paste")
			(net "M_H_DQ<45>")
		)
		(pad "F37" smd circle
			(at -6.344412 -22.626828)
			(size 0.4318 0.4318)
			(layers "F.Cu" "F.Mask" "F.Paste")
			(net "GND")
		)
		(pad "F39" smd circle
			(at -4.627626 -22.626828)
			(size 0.4318 0.4318)
			(layers "F.Cu" "F.Mask" "F.Paste")
			(net "M_G_DQ<39>")
		)
		(pad "F41" smd circle
			(at -2.910586 -22.626828)
			(size 0.4318 0.4318)
			(layers "F.Cu" "F.Mask" "F.Paste")
			(net "M_G_DQ<37>")
		)
		(pad "F43" smd circle
			(at -1.193546 -22.626828)
			(size 0.4318 0.4318)
			(layers "F.Cu" "F.Mask" "F.Paste")
			(net "GND")
		)
		(pad "F45" smd circle
			(at 2.052066 -24.426672)
			(size 0.508 0.508)
			(layers "F.Cu" "F.Mask" "F.Paste")
			(net "M_G_CS_N<6>")
		)
		(pad "F47" smd circle
			(at 3.769106 -24.426672)
			(size 0.4318 0.4318)
			(layers "F.Cu" "F.Mask" "F.Paste")
			(net "M_G_CS_N<3>")
		)
		(pad "F49" smd circle
			(at 5.485892 -24.426672)
			(size 0.4318 0.4318)
			(layers "F.Cu" "F.Mask" "F.Paste")
			(net "M_G_CS_N<1>")
		)
		(pad "F51" smd circle
			(at 7.202932 -24.426672)
			(size 0.4318 0.4318)
			(layers "F.Cu" "F.Mask" "F.Paste")
			(net "M_G_MA<14>")
		)
		(pad "F53" smd circle
			(at 8.919972 -24.426672)
			(size 0.4318 0.4318)
			(layers "F.Cu" "F.Mask" "F.Paste")
			(net "M_G_MA<0>")
		)
		(pad "F55" smd circle
			(at 10.637012 -24.426672)
			(size 0.4318 0.4318)
			(layers "F.Cu" "F.Mask" "F.Paste")
			(net "M_G_CLK_DN<0>")
		)
		(pad "F57" smd circle
			(at 12.354052 -24.426672)
			(size 0.4318 0.4318)
			(layers "F.Cu" "F.Mask" "F.Paste")
			(net "M_G_MA<1>")
		)
		(pad "F59" smd circle
			(at 14.071092 -24.426672)
			(size 0.4318 0.4318)
			(layers "F.Cu" "F.Mask" "F.Paste")
			(net "M_G_MA<5>")
		)
		(pad "F61" smd circle
			(at 15.787878 -24.426672)
			(size 0.4318 0.4318)
			(layers "F.Cu" "F.Mask" "F.Paste")
			(net "M_G_MA<9>")
		)
		(pad "F63" smd circle
			(at 17.504918 -24.426672)
			(size 0.4318 0.4318)
			(layers "F.Cu" "F.Mask" "F.Paste")
			(net "M_G_BG<1>")
		)
		(pad "F65" smd circle
			(at 19.221958 -24.426672)
			(size 0.4318 0.4318)
			(layers "F.Cu" "F.Mask" "F.Paste")
			(net "TP_CPU1_RSVD_277")
		)
		(pad "F67" smd custom
			(at 20.938998 -24.426672)
			(size 0.10795 0.10795)
			(layers "F.Cu" "F.Mask" "F.Paste")
			(net "GND")
			(options
				(clearance outline)
				(anchor circle)
			)
			(primitives
				(gr_poly
					(pts
						(arc
							(start 0.2159 -0.0381)
							(mid 0 -0.254)
							(end -0.2159 -0.0381)
						)
						(arc
							(start -0.2159 0.0381)
							(mid 0 0.254)
							(end 0.2159 0.0381)
						)
					)
					(width 0)
					(fill yes)
				)
			)
		)
		(pad "F69" smd custom
			(at 22.656038 -24.426672)
			(size 0.10795 0.10795)
			(layers "F.Cu" "F.Mask" "F.Paste")
			(net "GND")
			(options
				(clearance outline)
				(anchor circle)
			)
			(primitives
				(gr_poly
					(pts
						(arc
							(start 0.2159 -0.0381)
							(mid 0 -0.254)
							(end -0.2159 -0.0381)
						)
						(arc
							(start -0.2159 0.0381)
							(mid 0 0.254)
							(end 0.2159 0.0381)
						)
					)
					(width 0)
					(fill yes)
				)
			)
		)
		(pad "F71" smd custom
			(at 24.373078 -24.426672)
			(size 0.10795 0.10795)
			(layers "F.Cu" "F.Mask" "F.Paste")
			(net "M_H_DQ<27>")
			(options
				(clearance outline)
				(anchor circle)
			)
			(primitives
				(gr_poly
					(pts
						(arc
							(start 0.2159 -0.0381)
							(mid 0 -0.254)
							(end -0.2159 -0.0381)
						)
						(arc
							(start -0.2159 0.0381)
							(mid 0 0.254)
							(end 0.2159 0.0381)
						)
					)
					(width 0)
					(fill yes)
				)
			)
		)
		(pad "F73" smd circle
			(at 26.090118 -24.426672)
			(size 0.4318 0.4318)
			(layers "F.Cu" "F.Mask" "F.Paste")
			(net "M_H_DQS_DP<3>")
		)
		(pad "F75" smd circle
			(at 27.806904 -24.426672)
			(size 0.4318 0.4318)
			(layers "F.Cu" "F.Mask" "F.Paste")
			(net "M_H_DQ<28>")
		)
		(pad "F77" smd circle
			(at 29.523944 -24.426672)
			(size 0.4318 0.4318)
			(layers "F.Cu" "F.Mask" "F.Paste")
			(net "M_H_DQ<18>")
		)
		(pad "F79" smd circle
			(at 31.240984 -24.426672)
			(size 0.4318 0.4318)
			(layers "F.Cu" "F.Mask" "F.Paste")
			(net "M_H_DQS_DP<11>")
		)
		(pad "F81" smd circle
			(at 32.958024 -24.426672)
			(size 0.4318 0.4318)
			(layers "F.Cu" "F.Mask" "F.Paste")
			(net "M_H_DQ<20>")
		)
		(pad "F83" smd custom
			(at 34.675064 -24.426672 270)
			(size 0.10795 0.10795)
			(layers "F.Cu" "F.Mask" "F.Paste")
			(net "TP_CPU1_RSVD_276")
			(options
				(clearance outline)
				(anchor circle)
			)
			(primitives
				(gr_poly
					(pts
						(arc
							(start 0.2159 -0.0381)
							(mid 0 -0.254)
							(end -0.2159 -0.0381)
						)
						(arc
							(start -0.2159 0.0381)
							(mid 0 0.254)
							(end 0.2159 0.0381)
						)
					)
					(width 0)
					(fill yes)
				)
			)
		)
		(pad "G2" smd custom
			(at -36.392104 -22.131274 90)
			(size 0.10795 0.10795)
			(layers "F.Cu" "F.Mask" "F.Paste")
			(net "TP_CPU1_RSVD_275")
			(options
				(clearance outline)
				(anchor circle)
			)
			(primitives
				(gr_poly
					(pts
						(arc
							(start 0.2159 -0.0381)
							(mid 0 -0.254)
							(end -0.2159 -0.0381)
						)
						(arc
							(start -0.2159 0.0381)
							(mid 0 0.254)
							(end 0.2159 0.0381)
						)
					)
					(width 0)
					(fill yes)
				)
			)
		)
		(pad "G4" smd circle
			(at -34.675064 -22.131274)
			(size 0.4318 0.4318)
			(layers "F.Cu" "F.Mask" "F.Paste")
			(net "GND")
		)
		(pad "G6" smd circle
			(at -32.958024 -22.131274)
			(size 0.4318 0.4318)
			(layers "F.Cu" "F.Mask" "F.Paste")
			(net "UPI_CPU1_CPU0_P1P1_DN<4>")
		)
		(pad "G8" smd circle
			(at -31.240984 -22.131274)
			(size 0.4318 0.4318)
			(layers "F.Cu" "F.Mask" "F.Paste")
			(net "GND")
		)
		(pad "G10" smd circle
			(at -29.523944 -22.131274)
			(size 0.4318 0.4318)
			(layers "F.Cu" "F.Mask" "F.Paste")
			(net "UPI_CPU1_CPU0_P1P1_DN<9>")
		)
		(pad "G12" smd circle
			(at -27.806904 -22.131274)
			(size 0.4318 0.4318)
			(layers "F.Cu" "F.Mask" "F.Paste")
			(net "UPI_CPU1_CPU0_P1P1_DP<10>")
		)
		(pad "G14" smd circle
			(at -26.090118 -22.131274)
			(size 0.4318 0.4318)
			(layers "F.Cu" "F.Mask" "F.Paste")
			(net "UPI_CPU1_CPU0_P1P1_DP<11>")
		)
		(pad "G16" smd circle
			(at -24.373078 -22.131274)
			(size 0.4318 0.4318)
			(layers "F.Cu" "F.Mask" "F.Paste")
			(net "UPI_CPU1_CPU0_P1P1_DP<14>")
		)
		(pad "G18" smd circle
			(at -22.656038 -22.131274)
			(size 0.4318 0.4318)
			(layers "F.Cu" "F.Mask" "F.Paste")
			(net "UPI_CPU1_CPU0_P1P1_DN<16>")
		)
		(pad "G20" smd circle
			(at -20.938998 -22.131274)
			(size 0.4318 0.4318)
			(layers "F.Cu" "F.Mask" "F.Paste")
			(net "UPI_CPU1_CPU0_P1P1_DN<18>")
		)
		(pad "G22" smd circle
			(at -19.221958 -22.131274)
			(size 0.4318 0.4318)
			(layers "F.Cu" "F.Mask" "F.Paste")
			(net "GND")
		)
		(pad "G24" smd circle
			(at -17.504918 -22.131274)
			(size 0.4318 0.4318)
			(layers "F.Cu" "F.Mask" "F.Paste")
			(net "GND")
		)
		(pad "G26" smd circle
			(at -15.787878 -22.131274)
			(size 0.4318 0.4318)
			(layers "F.Cu" "F.Mask" "F.Paste")
			(net "GND")
		)
		(pad "G28" smd circle
			(at -14.071092 -22.131274)
			(size 0.4318 0.4318)
			(layers "F.Cu" "F.Mask" "F.Paste")
			(net "M_H_DQS_DN<6>")
		)
		(pad "G30" smd circle
			(at -12.354052 -22.131274)
			(size 0.4318 0.4318)
			(layers "F.Cu" "F.Mask" "F.Paste")
			(net "GND")
		)
		(pad "G32" smd circle
			(at -10.637012 -22.131274)
			(size 0.4318 0.4318)
			(layers "F.Cu" "F.Mask" "F.Paste")
			(net "GND")
		)
		(pad "G34" smd circle
			(at -8.919972 -22.131274)
			(size 0.4318 0.4318)
			(layers "F.Cu" "F.Mask" "F.Paste")
			(net "M_H_DQS_DN<5>")
		)
		(pad "G36" smd circle
			(at -7.202932 -22.131274)
			(size 0.4318 0.4318)
			(layers "F.Cu" "F.Mask" "F.Paste")
			(net "GND")
		)
		(pad "G38" smd circle
			(at -5.485892 -22.131274)
			(size 0.4318 0.4318)
			(layers "F.Cu" "F.Mask" "F.Paste")
			(net "GND")
		)
		(pad "G40" smd circle
			(at -3.769106 -22.131274)
			(size 0.4318 0.4318)
			(layers "F.Cu" "F.Mask" "F.Paste")
			(net "M_G_DQS_DN<4>")
		)
		(pad "G42" smd circle
			(at -2.052066 -22.131274)
			(size 0.4318 0.4318)
			(layers "F.Cu" "F.Mask" "F.Paste")
			(net "GND")
		)
		(pad "G46" smd circle
			(at 2.910586 -23.931626)
			(size 0.4318 0.4318)
			(layers "F.Cu" "F.Mask" "F.Paste")
			(net "M_G_C<2>")
		)
		(pad "G48" smd circle
			(at 4.627626 -23.931626)
			(size 0.4318 0.4318)
			(layers "F.Cu" "F.Mask" "F.Paste")
			(net "M_G_ODT<3>")
		)
		(pad "G50" smd circle
			(at 6.344412 -23.931626)
			(size 0.4318 0.4318)
			(layers "F.Cu" "F.Mask" "F.Paste")
			(net "M_G_ODT<2>")
		)
		(pad "G52" smd circle
			(at 8.061452 -23.931626)
			(size 0.4318 0.4318)
			(layers "F.Cu" "F.Mask" "F.Paste")
			(net "M_G_CS_N<0>")
		)
		(pad "G54" smd circle
			(at 9.778492 -23.931626)
			(size 0.4318 0.4318)
			(layers "F.Cu" "F.Mask" "F.Paste")
			(net "M_G_BA<1>")
		)
		(pad "G56" smd circle
			(at 11.495532 -23.931626)
			(size 0.4318 0.4318)
			(layers "F.Cu" "F.Mask" "F.Paste")
			(net "M_G_CLK_DP<2>")
		)
		(pad "G58" smd circle
			(at 13.212572 -23.931626)
			(size 0.4318 0.4318)
			(layers "F.Cu" "F.Mask" "F.Paste")
			(net "M_G_MA<4>")
		)
		(pad "G60" smd circle
			(at 14.929612 -23.931626)
			(size 0.4318 0.4318)
			(layers "F.Cu" "F.Mask" "F.Paste")
			(net "M_G_MA<7>")
		)
		(pad "G62" smd circle
			(at 16.646398 -23.931626)
			(size 0.4318 0.4318)
			(layers "F.Cu" "F.Mask" "F.Paste")
			(net "M_G_MA<11>")
		)
		(pad "G64" smd circle
			(at 18.363438 -23.931626)
			(size 0.4318 0.4318)
			(layers "F.Cu" "F.Mask" "F.Paste")
			(net "TP_CPU1_RSVD_274")
		)
		(pad "G66" smd circle
			(at 20.080478 -23.931626)
			(size 0.4318 0.4318)
			(layers "F.Cu" "F.Mask" "F.Paste")
			(net "GND")
		)
		(pad "G68" smd circle
			(at 21.797518 -23.931626)
			(size 0.4318 0.4318)
			(layers "F.Cu" "F.Mask" "F.Paste")
			(net "M_H_DQS_DN<17>")
		)
		(pad "G70" smd circle
			(at 23.514558 -23.931626)
			(size 0.4318 0.4318)
			(layers "F.Cu" "F.Mask" "F.Paste")
			(net "GND")
		)
		(pad "G72" smd circle
			(at 25.231598 -23.931626)
			(size 0.4318 0.4318)
			(layers "F.Cu" "F.Mask" "F.Paste")
			(net "M_H_DQ<31>")
		)
		(pad "G74" smd circle
			(at 26.948384 -23.931626)
			(size 0.4318 0.4318)
			(layers "F.Cu" "F.Mask" "F.Paste")
			(net "M_H_DQ<29>")
		)
		(pad "G76" smd circle
			(at 28.665424 -23.931626)
			(size 0.4318 0.4318)
			(layers "F.Cu" "F.Mask" "F.Paste")
			(net "GND")
		)
		(pad "G78" smd circle
			(at 30.382464 -23.931626)
			(size 0.4318 0.4318)
			(layers "F.Cu" "F.Mask" "F.Paste")
			(net "GND")
		)
		(pad "G80" smd circle
			(at 32.099504 -23.931626)
			(size 0.4318 0.4318)
			(layers "F.Cu" "F.Mask" "F.Paste")
			(net "GND")
		)
		(pad "G82" smd circle
			(at 33.816544 -23.931626)
			(size 0.4318 0.4318)
			(layers "F.Cu" "F.Mask" "F.Paste")
			(net "GND")
		)
		(pad "G84" smd custom
			(at 35.533584 -23.931626 270)
			(size 0.10795 0.10795)
			(layers "F.Cu" "F.Mask" "F.Paste")
			(net "TP_CPU1_RSVD_273")
			(options
				(clearance outline)
				(anchor circle)
			)
			(primitives
				(gr_poly
					(pts
						(arc
							(start 0.2159 -0.0381)
							(mid 0 -0.254)
							(end -0.2159 -0.0381)
						)
						(arc
							(start -0.2159 0.0381)
							(mid 0 0.254)
							(end 0.2159 0.0381)
						)
					)
					(width 0)
					(fill yes)
				)
			)
		)
		(pad "H1" smd custom
			(at -37.250624 -21.636228 90)
			(size 0.10795 0.10795)
			(layers "F.Cu" "F.Mask" "F.Paste")
			(net "TP_CPU1_RSVD_272")
			(options
				(clearance outline)
				(anchor circle)
			)
			(primitives
				(gr_poly
					(pts
						(arc
							(start 0.2159 -0.0381)
							(mid 0 -0.254)
							(end -0.2159 -0.0381)
						)
						(arc
							(start -0.2159 0.0381)
							(mid 0 0.254)
							(end 0.2159 0.0381)
						)
					)
					(width 0)
					(fill yes)
				)
			)
		)
		(pad "H3" smd circle
			(at -35.533584 -21.636228)
			(size 0.4318 0.4318)
			(layers "F.Cu" "F.Mask" "F.Paste")
			(net "GND")
		)
		(pad "H5" smd circle
			(at -33.816544 -21.636228)
			(size 0.4318 0.4318)
			(layers "F.Cu" "F.Mask" "F.Paste")
			(net "UPI_CPU1_CPU0_P1P1_DP<3>")
		)
		(pad "H7" smd circle
			(at -32.099504 -21.636228)
			(size 0.4318 0.4318)
			(layers "F.Cu" "F.Mask" "F.Paste")
			(net "UPI_CPU1_CPU0_P1P1_DN<5>")
		)
		(pad "H9" smd circle
			(at -30.382464 -21.636228)
			(size 0.4318 0.4318)
			(layers "F.Cu" "F.Mask" "F.Paste")
			(net "UPI_CPU1_CPU0_P1P1_DP<9>")
		)
		(pad "H11" smd circle
			(at -28.665424 -21.636228)
			(size 0.4318 0.4318)
			(layers "F.Cu" "F.Mask" "F.Paste")
			(net "GND")
		)
		(pad "H13" smd circle
			(at -26.948384 -21.636228)
			(size 0.4318 0.4318)
			(layers "F.Cu" "F.Mask" "F.Paste")
			(net "PVCCIO_CPU1")
		)
		(pad "H15" smd circle
			(at -25.231598 -21.636228)
			(size 0.4318 0.4318)
			(layers "F.Cu" "F.Mask" "F.Paste")
			(net "UPI_CPU1_CPU0_P1P1_DP<13>")
		)
		(pad "H17" smd circle
			(at -23.514558 -21.636228)
			(size 0.4318 0.4318)
			(layers "F.Cu" "F.Mask" "F.Paste")
			(net "UPI_CPU1_CPU0_P1P1_DN<14>")
		)
		(pad "H19" smd circle
			(at -21.797518 -21.636228)
			(size 0.4318 0.4318)
			(layers "F.Cu" "F.Mask" "F.Paste")
			(net "UPI_CPU1_CPU0_P1P1_DP<17>")
		)
		(pad "H21" smd circle
			(at -20.080478 -21.636228)
			(size 0.4318 0.4318)
			(layers "F.Cu" "F.Mask" "F.Paste")
			(net "UPI_CPU1_CPU0_P1P1_DP<19>")
		)
		(pad "H23" smd circle
			(at -18.363438 -21.636228)
			(size 0.4318 0.4318)
			(layers "F.Cu" "F.Mask" "F.Paste")
			(net "M_G_DQ<62>")
		)
		(pad "H25" smd circle
			(at -16.646398 -21.636228)
			(size 0.4318 0.4318)
			(layers "F.Cu" "F.Mask" "F.Paste")
			(net "GND")
		)
		(pad "H27" smd circle
			(at -14.929612 -21.636228)
			(size 0.4318 0.4318)
			(layers "F.Cu" "F.Mask" "F.Paste")
			(net "GND")
		)
		(pad "H29" smd circle
			(at -13.212572 -21.636228)
			(size 0.4318 0.4318)
			(layers "F.Cu" "F.Mask" "F.Paste")
			(net "GND")
		)
		(pad "H31" smd circle
			(at -11.495532 -21.636228)
			(size 0.4318 0.4318)
			(layers "F.Cu" "F.Mask" "F.Paste")
			(net "GND")
		)
		(pad "H33" smd circle
			(at -9.778492 -21.636228)
			(size 0.4318 0.4318)
			(layers "F.Cu" "F.Mask" "F.Paste")
			(net "GND")
		)
		(pad "H35" smd circle
			(at -8.061452 -21.636228)
			(size 0.4318 0.4318)
			(layers "F.Cu" "F.Mask" "F.Paste")
			(net "GND")
		)
		(pad "H37" smd circle
			(at -6.344412 -21.636228)
			(size 0.4318 0.4318)
			(layers "F.Cu" "F.Mask" "F.Paste")
			(net "GND")
		)
		(pad "H39" smd circle
			(at -4.627626 -21.636228)
			(size 0.4318 0.4318)
			(layers "F.Cu" "F.Mask" "F.Paste")
			(net "GND")
		)
		(pad "H41" smd circle
			(at -2.910586 -21.636228)
			(size 0.4318 0.4318)
			(layers "F.Cu" "F.Mask" "F.Paste")
			(net "GND")
		)
		(pad "H43" smd circle
			(at -1.193546 -21.636228)
			(size 0.4318 0.4318)
			(layers "F.Cu" "F.Mask" "F.Paste")
			(net "M_H_DQ<33>")
		)
		(pad "H45" smd circle
			(at 2.052066 -23.436326)
			(size 0.508 0.508)
			(layers "F.Cu" "F.Mask" "F.Paste")
			(net "GND")
		)
		(pad "H47" smd circle
			(at 3.769106 -23.436326)
			(size 0.4318 0.4318)
			(layers "F.Cu" "F.Mask" "F.Paste")
			(net "GND")
		)
		(pad "H49" smd circle
			(at 5.485892 -23.436326)
			(size 0.4318 0.4318)
			(layers "F.Cu" "F.Mask" "F.Paste")
			(net "GND")
		)
		(pad "H51" smd circle
			(at 7.202932 -23.436326)
			(size 0.4318 0.4318)
			(layers "F.Cu" "F.Mask" "F.Paste")
			(net "GND")
		)
		(pad "H53" smd circle
			(at 8.919972 -23.436326)
			(size 0.4318 0.4318)
			(layers "F.Cu" "F.Mask" "F.Paste")
			(net "GND")
		)
		(pad "H55" smd circle
			(at 10.637012 -23.436326)
			(size 0.4318 0.4318)
			(layers "F.Cu" "F.Mask" "F.Paste")
			(net "GND")
		)
		(pad "H57" smd circle
			(at 12.354052 -23.436326)
			(size 0.4318 0.4318)
			(layers "F.Cu" "F.Mask" "F.Paste")
			(net "GND")
		)
		(pad "H59" smd circle
			(at 14.071092 -23.436326)
			(size 0.4318 0.4318)
			(layers "F.Cu" "F.Mask" "F.Paste")
			(net "GND")
		)
		(pad "H61" smd circle
			(at 15.787878 -23.436326)
			(size 0.4318 0.4318)
			(layers "F.Cu" "F.Mask" "F.Paste")
			(net "GND")
		)
		(pad "H63" smd circle
			(at 17.504918 -23.436326)
			(size 0.4318 0.4318)
			(layers "F.Cu" "F.Mask" "F.Paste")
			(net "GND")
		)
		(pad "H65" smd circle
			(at 19.221958 -23.436326)
			(size 0.4318 0.4318)
			(layers "F.Cu" "F.Mask" "F.Paste")
			(net "GND")
		)
		(pad "H67" smd circle
			(at 20.938998 -23.436326)
			(size 0.4318 0.4318)
			(layers "F.Cu" "F.Mask" "F.Paste")
			(net "M_H_ECC<6>")
		)
		(pad "H69" smd circle
			(at 22.656038 -23.436326)
			(size 0.4318 0.4318)
			(layers "F.Cu" "F.Mask" "F.Paste")
			(net "M_H_ECC<1>")
		)
		(pad "H71" smd circle
			(at 24.373078 -23.436326)
			(size 0.4318 0.4318)
			(layers "F.Cu" "F.Mask" "F.Paste")
			(net "GND")
		)
		(pad "H73" smd circle
			(at 26.090118 -23.436326)
			(size 0.4318 0.4318)
			(layers "F.Cu" "F.Mask" "F.Paste")
			(net "M_H_DQS_DN<3>")
		)
		(pad "H75" smd circle
			(at 27.806904 -23.436326)
			(size 0.4318 0.4318)
			(layers "F.Cu" "F.Mask" "F.Paste")
			(net "GND")
		)
		(pad "H77" smd circle
			(at 29.523944 -23.436326)
			(size 0.4318 0.4318)
			(layers "F.Cu" "F.Mask" "F.Paste")
			(net "M_H_DQ<19>")
		)
		(pad "H79" smd circle
			(at 31.240984 -23.436326)
			(size 0.4318 0.4318)
			(layers "F.Cu" "F.Mask" "F.Paste")
			(net "M_H_DQS_DP<2>")
		)
		(pad "H81" smd circle
			(at 32.958024 -23.436326)
			(size 0.4318 0.4318)
			(layers "F.Cu" "F.Mask" "F.Paste")
			(net "M_H_DQ<21>")
		)
		(pad "H83" smd circle
			(at 34.675064 -23.436326)
			(size 0.4318 0.4318)
			(layers "F.Cu" "F.Mask" "F.Paste")
			(net "TP_CPU1_RSVD_271")
		)
		(pad "H85" smd custom
			(at 36.392104 -23.436326 270)
			(size 0.10795 0.10795)
			(layers "F.Cu" "F.Mask" "F.Paste")
			(net "TP_CPU1_RSVD_270")
			(options
				(clearance outline)
				(anchor circle)
			)
			(primitives
				(gr_poly
					(pts
						(arc
							(start 0.2159 -0.0381)
							(mid 0 -0.254)
							(end -0.2159 -0.0381)
						)
						(arc
							(start -0.2159 0.0381)
							(mid 0 0.254)
							(end 0.2159 0.0381)
						)
					)
					(width 0)
					(fill yes)
				)
			)
		)
		(pad "J2" smd circle
			(at -36.392104 -21.140674)
			(size 0.4318 0.4318)
			(layers "F.Cu" "F.Mask" "F.Paste")
			(net "PVCCIO_CPU1")
		)
		(pad "J4" smd circle
			(at -34.675064 -21.140674)
			(size 0.4318 0.4318)
			(layers "F.Cu" "F.Mask" "F.Paste")
			(net "GND")
		)
		(pad "J6" smd circle
			(at -32.958024 -21.140674)
			(size 0.4318 0.4318)
			(layers "F.Cu" "F.Mask" "F.Paste")
			(net "UPI_CPU1_CPU0_P1P1_DN<3>")
		)
		(pad "J8" smd circle
			(at -31.240984 -21.140674)
			(size 0.4318 0.4318)
			(layers "F.Cu" "F.Mask" "F.Paste")
			(net "UPI_CPU1_CPU0_P1P1_DN<6>")
		)
		(pad "J10" smd circle
			(at -29.523944 -21.140674)
			(size 0.4318 0.4318)
			(layers "F.Cu" "F.Mask" "F.Paste")
			(net "PVCCIO_CPU1")
		)
		(pad "J12" smd circle
			(at -27.806904 -21.140674)
			(size 0.4318 0.4318)
			(layers "F.Cu" "F.Mask" "F.Paste")
			(net "GND")
		)
		(pad "J14" smd circle
			(at -26.090118 -21.140674)
			(size 0.4318 0.4318)
			(layers "F.Cu" "F.Mask" "F.Paste")
			(net "GND")
		)
		(pad "J16" smd circle
			(at -24.373078 -21.140674)
			(size 0.4318 0.4318)
			(layers "F.Cu" "F.Mask" "F.Paste")
			(net "GND")
		)
		(pad "J18" smd circle
			(at -22.656038 -21.140674)
			(size 0.4318 0.4318)
			(layers "F.Cu" "F.Mask" "F.Paste")
			(net "UPI_CPU1_CPU0_P1P1_DP<16>")
		)
		(pad "J20" smd circle
			(at -20.938998 -21.140674)
			(size 0.4318 0.4318)
			(layers "F.Cu" "F.Mask" "F.Paste")
			(net "UPI_CPU1_CPU0_P1P1_DN<17>")
		)
		(pad "J22" smd circle
			(at -19.221958 -21.140674)
			(size 0.4318 0.4318)
			(layers "F.Cu" "F.Mask" "F.Paste")
			(net "GND")
		)
		(pad "J24" smd circle
			(at -17.504918 -21.140674)
			(size 0.4318 0.4318)
			(layers "F.Cu" "F.Mask" "F.Paste")
			(net "M_G_DQS_DN<16>")
		)
		(pad "J26" smd circle
			(at -15.787878 -21.140674)
			(size 0.4318 0.4318)
			(layers "F.Cu" "F.Mask" "F.Paste")
			(net "GND")
		)
		(pad "J28" smd circle
			(at -14.071092 -21.140674)
			(size 0.4318 0.4318)
			(layers "F.Cu" "F.Mask" "F.Paste")
			(net "GND")
		)
		(pad "J30" smd circle
			(at -12.354052 -21.140674)
			(size 0.4318 0.4318)
			(layers "F.Cu" "F.Mask" "F.Paste")
			(net "M_G_DQS_DN<15>")
		)
		(pad "J32" smd circle
			(at -10.637012 -21.140674)
			(size 0.4318 0.4318)
			(layers "F.Cu" "F.Mask" "F.Paste")
			(net "GND")
		)
		(pad "J34" smd circle
			(at -8.919972 -21.140674)
			(size 0.4318 0.4318)
			(layers "F.Cu" "F.Mask" "F.Paste")
			(net "GND")
		)
		(pad "J36" smd circle
			(at -7.202932 -21.140674)
			(size 0.4318 0.4318)
			(layers "F.Cu" "F.Mask" "F.Paste")
			(net "M_G_DQS_DN<14>")
		)
		(pad "J38" smd circle
			(at -5.485892 -21.140674)
			(size 0.4318 0.4318)
			(layers "F.Cu" "F.Mask" "F.Paste")
			(net "GND")
		)
		(pad "J40" smd circle
			(at -3.769106 -21.140674)
			(size 0.4318 0.4318)
			(layers "F.Cu" "F.Mask" "F.Paste")
			(net "GND")
		)
		(pad "J42" smd circle
			(at -2.052066 -21.140674)
			(size 0.4318 0.4318)
			(layers "F.Cu" "F.Mask" "F.Paste")
			(net "M_H_DQS_DN<13>")
		)
		(pad "J46" smd circle
			(at 2.910586 -22.940772)
			(size 0.4318 0.4318)
			(layers "F.Cu" "F.Mask" "F.Paste")
			(net "TP_CPU1_RSVD_269")
		)
		(pad "J48" smd circle
			(at 4.627626 -22.940772)
			(size 0.4318 0.4318)
			(layers "F.Cu" "F.Mask" "F.Paste")
			(net "M_G_MA<13>")
		)
		(pad "J50" smd circle
			(at 6.344412 -22.940772)
			(size 0.4318 0.4318)
			(layers "F.Cu" "F.Mask" "F.Paste")
			(net "M_H_CS_N<4>")
		)
		(pad "J52" smd circle
			(at 8.061452 -22.940772)
			(size 0.4318 0.4318)
			(layers "F.Cu" "F.Mask" "F.Paste")
			(net "M_H_MA<0>")
		)
		(pad "J54" smd circle
			(at 9.778492 -22.940772)
			(size 0.4318 0.4318)
			(layers "F.Cu" "F.Mask" "F.Paste")
			(net "M_G_MA<10>")
		)
		(pad "J56" smd circle
			(at 11.495532 -22.940772)
			(size 0.4318 0.4318)
			(layers "F.Cu" "F.Mask" "F.Paste")
			(net "M_G_CLK_DN<2>")
		)
		(pad "J58" smd circle
			(at 13.212572 -22.940772)
			(size 0.4318 0.4318)
			(layers "F.Cu" "F.Mask" "F.Paste")
			(net "M_H_MA<1>")
		)
		(pad "J60" smd circle
			(at 14.929612 -22.940772)
			(size 0.4318 0.4318)
			(layers "F.Cu" "F.Mask" "F.Paste")
			(net "M_G_ACT_N")
		)
		(pad "J62" smd circle
			(at 16.646398 -22.940772)
			(size 0.4318 0.4318)
			(layers "F.Cu" "F.Mask" "F.Paste")
			(net "TP_CPU1_RSVD_268")
		)
		(pad "J64" smd circle
			(at 18.363438 -22.940772)
			(size 0.4318 0.4318)
			(layers "F.Cu" "F.Mask" "F.Paste")
			(net "M_G_MA<12>")
		)
		(pad "J66" smd circle
			(at 20.080478 -22.940772)
			(size 0.4318 0.4318)
			(layers "F.Cu" "F.Mask" "F.Paste")
			(net "M_H_ECC<2>")
		)
		(pad "J68" smd circle
			(at 21.797518 -22.940772)
			(size 0.4318 0.4318)
			(layers "F.Cu" "F.Mask" "F.Paste")
			(net "M_H_DQS_DP<17>")
		)
		(pad "J70" smd circle
			(at 23.514558 -22.940772)
			(size 0.4318 0.4318)
			(layers "F.Cu" "F.Mask" "F.Paste")
			(net "M_H_ECC<0>")
		)
		(pad "J72" smd circle
			(at 25.231598 -22.940772)
			(size 0.4318 0.4318)
			(layers "F.Cu" "F.Mask" "F.Paste")
			(net "GND")
		)
		(pad "J74" smd circle
			(at 26.948384 -22.940772)
			(size 0.4318 0.4318)
			(layers "F.Cu" "F.Mask" "F.Paste")
			(net "GND")
		)
		(pad "J76" smd circle
			(at 28.665424 -22.940772)
			(size 0.4318 0.4318)
			(layers "F.Cu" "F.Mask" "F.Paste")
			(net "GND")
		)
		(pad "J78" smd circle
			(at 30.382464 -22.940772)
			(size 0.4318 0.4318)
			(layers "F.Cu" "F.Mask" "F.Paste")
			(net "M_H_DQ<23>")
		)
		(pad "J80" smd circle
			(at 32.099504 -22.940772)
			(size 0.4318 0.4318)
			(layers "F.Cu" "F.Mask" "F.Paste")
			(net "M_H_DQ<17>")
		)
		(pad "J82" smd circle
			(at 33.816544 -22.940772)
			(size 0.4318 0.4318)
			(layers "F.Cu" "F.Mask" "F.Paste")
			(net "GND")
		)
		(pad "J84" smd circle
			(at 35.533584 -22.940772)
			(size 0.4318 0.4318)
			(layers "F.Cu" "F.Mask" "F.Paste")
			(net "GND")
		)
		(pad "J86" smd custom
			(at 37.250624 -22.940772 270)
			(size 0.10795 0.10795)
			(layers "F.Cu" "F.Mask" "F.Paste")
			(net "GND")
			(options
				(clearance outline)
				(anchor circle)
			)
			(primitives
				(gr_poly
					(pts
						(arc
							(start 0.2159 -0.0381)
							(mid 0 -0.254)
							(end -0.2159 -0.0381)
						)
						(arc
							(start -0.2159 0.0381)
							(mid 0 0.254)
							(end 0.2159 0.0381)
						)
					)
					(width 0)
					(fill yes)
				)
			)
		)
		(pad "K1" smd custom
			(at -37.250624 -20.645628 90)
			(size 0.10795 0.10795)
			(layers "F.Cu" "F.Mask" "F.Paste")
			(net "GND")
			(options
				(clearance outline)
				(anchor circle)
			)
			(primitives
				(gr_poly
					(pts
						(arc
							(start 0.2159 -0.0381)
							(mid 0 -0.254)
							(end -0.2159 -0.0381)
						)
						(arc
							(start -0.2159 0.0381)
							(mid 0 0.254)
							(end 0.2159 0.0381)
						)
					)
					(width 0)
					(fill yes)
				)
			)
		)
		(pad "K3" smd circle
			(at -35.533584 -20.645628)
			(size 0.4318 0.4318)
			(layers "F.Cu" "F.Mask" "F.Paste")
			(net "UPI_CPU1_CPU0_P1P1_DN<1>")
		)
		(pad "K5" smd circle
			(at -33.816544 -20.645628)
			(size 0.4318 0.4318)
			(layers "F.Cu" "F.Mask" "F.Paste")
			(net "UPI_CPU1_CPU0_P1P1_DN<2>")
		)
		(pad "K7" smd circle
			(at -32.099504 -20.645628)
			(size 0.4318 0.4318)
			(layers "F.Cu" "F.Mask" "F.Paste")
			(net "UPI_CPU1_CPU0_P1P1_DP<5>")
		)
		(pad "K9" smd circle
			(at -30.382464 -20.645628)
			(size 0.4318 0.4318)
			(layers "F.Cu" "F.Mask" "F.Paste")
			(net "UPI_CPU1_CPU0_P1P1_DP<6>")
		)
		(pad "K11" smd circle
			(at -28.665424 -20.645628)
			(size 0.4318 0.4318)
			(layers "F.Cu" "F.Mask" "F.Paste")
			(net "GND")
		)
		(pad "K13" smd circle
			(at -26.948384 -20.645628)
			(size 0.4318 0.4318)
			(layers "F.Cu" "F.Mask" "F.Paste")
			(net "GND")
		)
		(pad "K15" smd circle
			(at -25.231598 -20.645628)
			(size 0.4318 0.4318)
			(layers "F.Cu" "F.Mask" "F.Paste")
			(net "PVCCIO_CPU1")
		)
		(pad "K17" smd circle
			(at -23.514558 -20.645628)
			(size 0.4318 0.4318)
			(layers "F.Cu" "F.Mask" "F.Paste")
			(net "GND")
		)
		(pad "K19" smd circle
			(at -21.797518 -20.645628)
			(size 0.4318 0.4318)
			(layers "F.Cu" "F.Mask" "F.Paste")
			(net "UPI_CPU1_CPU0_P1P1_DN<15>")
		)
		(pad "K21" smd circle
			(at -20.080478 -20.645628)
			(size 0.4318 0.4318)
			(layers "F.Cu" "F.Mask" "F.Paste")
			(net "UPI_CPU1_CPU0_P1P1_DN<19>")
		)
		(pad "K23" smd circle
			(at -18.363438 -20.645628)
			(size 0.4318 0.4318)
			(layers "F.Cu" "F.Mask" "F.Paste")
			(net "M_G_DQ<63>")
		)
		(pad "K25" smd circle
			(at -16.646398 -20.645628)
			(size 0.4318 0.4318)
			(layers "F.Cu" "F.Mask" "F.Paste")
			(net "M_G_DQ<56>")
		)
		(pad "K27" smd circle
			(at -14.929612 -20.645628)
			(size 0.4318 0.4318)
			(layers "F.Cu" "F.Mask" "F.Paste")
			(net "GND")
		)
		(pad "K29" smd circle
			(at -13.212572 -20.645628)
			(size 0.4318 0.4318)
			(layers "F.Cu" "F.Mask" "F.Paste")
			(net "M_G_DQ<54>")
		)
		(pad "K31" smd circle
			(at -11.495532 -20.645628)
			(size 0.4318 0.4318)
			(layers "F.Cu" "F.Mask" "F.Paste")
			(net "M_G_DQ<48>")
		)
		(pad "K33" smd circle
			(at -9.778492 -20.645628)
			(size 0.4318 0.4318)
			(layers "F.Cu" "F.Mask" "F.Paste")
			(net "GND")
		)
		(pad "K35" smd circle
			(at -8.061452 -20.645628)
			(size 0.4318 0.4318)
			(layers "F.Cu" "F.Mask" "F.Paste")
			(net "M_G_DQ<46>")
		)
		(pad "K37" smd circle
			(at -6.344412 -20.645628)
			(size 0.4318 0.4318)
			(layers "F.Cu" "F.Mask" "F.Paste")
			(net "M_G_DQ<40>")
		)
		(pad "K39" smd circle
			(at -4.627626 -20.645628)
			(size 0.4318 0.4318)
			(layers "F.Cu" "F.Mask" "F.Paste")
			(net "GND")
		)
		(pad "K41" smd circle
			(at -2.910586 -20.645628)
			(size 0.4318 0.4318)
			(layers "F.Cu" "F.Mask" "F.Paste")
			(net "M_H_DQ<38>")
		)
		(pad "K43" smd circle
			(at -1.193546 -20.645628)
			(size 0.4318 0.4318)
			(layers "F.Cu" "F.Mask" "F.Paste")
			(net "M_H_DQ<32>")
		)
		(pad "K45" smd circle
			(at 2.052066 -22.445726)
			(size 0.508 0.508)
			(layers "F.Cu" "F.Mask" "F.Paste")
			(net "M_G_CS_N<7>")
		)
		(pad "K47" smd circle
			(at 3.769106 -22.445726)
			(size 0.4318 0.4318)
			(layers "F.Cu" "F.Mask" "F.Paste")
			(net "M_G_MA<17>")
		)
		(pad "K49" smd circle
			(at 5.485892 -22.445726)
			(size 0.4318 0.4318)
			(layers "F.Cu" "F.Mask" "F.Paste")
			(net "M_G_MA<15>")
		)
		(pad "K51" smd circle
			(at 7.202932 -22.445726)
			(size 0.4318 0.4318)
			(layers "F.Cu" "F.Mask" "F.Paste")
			(net "M_H_CS_N<0>")
		)
		(pad "K53" smd circle
			(at 8.919972 -22.445726)
			(size 0.4318 0.4318)
			(layers "F.Cu" "F.Mask" "F.Paste")
			(net "M_H_PAR")
		)
		(pad "K55" smd circle
			(at 10.637012 -22.445726)
			(size 0.4318 0.4318)
			(layers "F.Cu" "F.Mask" "F.Paste")
			(net "M_H_BA<1>")
		)
		(pad "K57" smd circle
			(at 12.354052 -22.445726)
			(size 0.4318 0.4318)
			(layers "F.Cu" "F.Mask" "F.Paste")
			(net "M_H_MA<2>")
		)
		(pad "K59" smd circle
			(at 14.071092 -22.445726)
			(size 0.4318 0.4318)
			(layers "F.Cu" "F.Mask" "F.Paste")
			(net "M_H_MA<9>")
		)
		(pad "K61" smd circle
			(at 15.787878 -22.445726)
			(size 0.4318 0.4318)
			(layers "F.Cu" "F.Mask" "F.Paste")
			(net "TP_CPU1_RSVD_267")
		)
		(pad "K63" smd circle
			(at 17.504918 -22.445726)
			(size 0.4318 0.4318)
			(layers "F.Cu" "F.Mask" "F.Paste")
			(net "M_H_CKE<2>")
		)
		(pad "K65" smd circle
			(at 19.221958 -22.445726)
			(size 0.4318 0.4318)
			(layers "F.Cu" "F.Mask" "F.Paste")
			(net "GND")
		)
		(pad "K67" smd circle
			(at 20.938998 -22.445726)
			(size 0.4318 0.4318)
			(layers "F.Cu" "F.Mask" "F.Paste")
			(net "GND")
		)
		(pad "K69" smd circle
			(at 22.656038 -22.445726)
			(size 0.4318 0.4318)
			(layers "F.Cu" "F.Mask" "F.Paste")
			(net "GND")
		)
		(pad "K71" smd circle
			(at 24.373078 -22.445726)
			(size 0.4318 0.4318)
			(layers "F.Cu" "F.Mask" "F.Paste")
			(net "GND")
		)
		(pad "K73" smd circle
			(at 26.090118 -22.445726)
			(size 0.4318 0.4318)
			(layers "F.Cu" "F.Mask" "F.Paste")
			(net "GND")
		)
		(pad "K75" smd circle
			(at 27.806904 -22.445726)
			(size 0.4318 0.4318)
			(layers "F.Cu" "F.Mask" "F.Paste")
			(net "M_G_DQS_DN<12>")
		)
		(pad "K77" smd circle
			(at 29.523944 -22.445726)
			(size 0.4318 0.4318)
			(layers "F.Cu" "F.Mask" "F.Paste")
			(net "GND")
		)
		(pad "K79" smd circle
			(at 31.240984 -22.445726)
			(size 0.4318 0.4318)
			(layers "F.Cu" "F.Mask" "F.Paste")
			(net "M_H_DQS_DN<2>")
		)
		(pad "K81" smd circle
			(at 32.958024 -22.445726)
			(size 0.4318 0.4318)
			(layers "F.Cu" "F.Mask" "F.Paste")
			(net "GND")
		)
		(pad "K83" smd circle
			(at 34.675064 -22.445726)
			(size 0.4318 0.4318)
			(layers "F.Cu" "F.Mask" "F.Paste")
			(net "GND")
		)
		(pad "K85" smd circle
			(at 36.392104 -22.445726)
			(size 0.4318 0.4318)
			(layers "F.Cu" "F.Mask" "F.Paste")
			(net "GND")
		)
		(pad "L2" smd circle
			(at -36.392104 -20.150074)
			(size 0.4318 0.4318)
			(layers "F.Cu" "F.Mask" "F.Paste")
			(net "GND")
		)
		(pad "L4" smd circle
			(at -34.675064 -20.150074)
			(size 0.4318 0.4318)
			(layers "F.Cu" "F.Mask" "F.Paste")
			(net "UPI_CPU1_CPU0_P1P1_DP<1>")
		)
		(pad "L6" smd circle
			(at -32.958024 -20.150074)
			(size 0.4318 0.4318)
			(layers "F.Cu" "F.Mask" "F.Paste")
			(net "GND")
		)
		(pad "L8" smd circle
			(at -31.240984 -20.150074)
			(size 0.4318 0.4318)
			(layers "F.Cu" "F.Mask" "F.Paste")
			(net "GND")
		)
		(pad "L10" smd circle
			(at -29.523944 -20.150074)
			(size 0.4318 0.4318)
			(layers "F.Cu" "F.Mask" "F.Paste")
			(net "GND")
		)
		(pad "L12" smd circle
			(at -27.806904 -20.150074)
			(size 0.4318 0.4318)
			(layers "F.Cu" "F.Mask" "F.Paste")
			(net "UPI_CPU0_CPU1_P1P1_DN<7>")
		)
		(pad "L14" smd circle
			(at -26.090118 -20.150074)
			(size 0.4318 0.4318)
			(layers "F.Cu" "F.Mask" "F.Paste")
			(net "PVCCIO_CPU1")
		)
		(pad "L16" smd circle
			(at -24.373078 -20.150074)
			(size 0.4318 0.4318)
			(layers "F.Cu" "F.Mask" "F.Paste")
			(net "PVCCIO_CPU1")
		)
		(pad "L18" smd circle
			(at -22.656038 -20.150074)
			(size 0.4318 0.4318)
			(layers "F.Cu" "F.Mask" "F.Paste")
			(net "UPI_CPU1_CPU0_P1P1_DP<15>")
		)
		(pad "L20" smd circle
			(at -20.938998 -20.150074)
			(size 0.4318 0.4318)
			(layers "F.Cu" "F.Mask" "F.Paste")
			(net "GND")
		)
		(pad "L22" smd circle
			(at -19.221958 -20.150074)
			(size 0.4318 0.4318)
			(layers "F.Cu" "F.Mask" "F.Paste")
			(net "GND")
		)
		(pad "L24" smd circle
			(at -17.504918 -20.150074)
			(size 0.4318 0.4318)
			(layers "F.Cu" "F.Mask" "F.Paste")
			(net "M_G_DQS_DP<16>")
		)
		(pad "L26" smd circle
			(at -15.787878 -20.150074)
			(size 0.4318 0.4318)
			(layers "F.Cu" "F.Mask" "F.Paste")
			(net "M_G_DQ<60>")
		)
		(pad "L28" smd circle
			(at -14.071092 -20.150074)
			(size 0.4318 0.4318)
			(layers "F.Cu" "F.Mask" "F.Paste")
			(net "M_G_DQ<50>")
		)
		(pad "L30" smd circle
			(at -12.354052 -20.150074)
			(size 0.4318 0.4318)
			(layers "F.Cu" "F.Mask" "F.Paste")
			(net "M_G_DQS_DP<15>")
		)
		(pad "L32" smd circle
			(at -10.637012 -20.150074)
			(size 0.4318 0.4318)
			(layers "F.Cu" "F.Mask" "F.Paste")
			(net "M_G_DQ<52>")
		)
		(pad "L34" smd circle
			(at -8.919972 -20.150074)
			(size 0.4318 0.4318)
			(layers "F.Cu" "F.Mask" "F.Paste")
			(net "M_G_DQ<42>")
		)
		(pad "L36" smd circle
			(at -7.202932 -20.150074)
			(size 0.4318 0.4318)
			(layers "F.Cu" "F.Mask" "F.Paste")
			(net "M_G_DQS_DP<14>")
		)
		(pad "L38" smd circle
			(at -5.485892 -20.150074)
			(size 0.4318 0.4318)
			(layers "F.Cu" "F.Mask" "F.Paste")
			(net "M_G_DQ<44>")
		)
		(pad "L40" smd circle
			(at -3.769106 -20.150074)
			(size 0.4318 0.4318)
			(layers "F.Cu" "F.Mask" "F.Paste")
			(net "M_H_DQ<34>")
		)
		(pad "L42" smd circle
			(at -2.052066 -20.150074)
			(size 0.4318 0.4318)
			(layers "F.Cu" "F.Mask" "F.Paste")
			(net "M_H_DQS_DP<13>")
		)
		(pad "L46" smd circle
			(at 2.910586 -21.950172)
			(size 0.4318 0.4318)
			(layers "F.Cu" "F.Mask" "F.Paste")
			(net "PVDDQ_GHJ")
		)
		(pad "L48" smd circle
			(at 4.627626 -21.950172)
			(size 0.4318 0.4318)
			(layers "F.Cu" "F.Mask" "F.Paste")
			(net "PVDDQ_GHJ")
		)
		(pad "L50" smd circle
			(at 6.344412 -21.950172)
			(size 0.4318 0.4318)
			(layers "F.Cu" "F.Mask" "F.Paste")
			(net "PVDDQ_GHJ")
		)
		(pad "L52" smd circle
			(at 8.061452 -21.950172)
			(size 0.4318 0.4318)
			(layers "F.Cu" "F.Mask" "F.Paste")
			(net "PVDDQ_GHJ")
		)
		(pad "L54" smd circle
			(at 9.778492 -21.950172)
			(size 0.4318 0.4318)
			(layers "F.Cu" "F.Mask" "F.Paste")
			(net "PVDDQ_GHJ")
		)
		(pad "L56" smd circle
			(at 11.495532 -21.950172)
			(size 0.4318 0.4318)
			(layers "F.Cu" "F.Mask" "F.Paste")
			(net "PVDDQ_GHJ")
		)
		(pad "L58" smd circle
			(at 13.212572 -21.950172)
			(size 0.4318 0.4318)
			(layers "F.Cu" "F.Mask" "F.Paste")
			(net "PVDDQ_GHJ")
		)
		(pad "L60" smd circle
			(at 14.929612 -21.950172)
			(size 0.4318 0.4318)
			(layers "F.Cu" "F.Mask" "F.Paste")
			(net "PVDDQ_GHJ")
		)
		(pad "L62" smd circle
			(at 16.646398 -21.950172)
			(size 0.4318 0.4318)
			(layers "F.Cu" "F.Mask" "F.Paste")
			(net "PVDDQ_GHJ")
		)
		(pad "L64" smd circle
			(at 18.363438 -21.950172)
			(size 0.4318 0.4318)
			(layers "F.Cu" "F.Mask" "F.Paste")
			(net "M_H_CKE<3>")
		)
		(pad "L66" smd circle
			(at 20.080478 -21.950172)
			(size 0.4318 0.4318)
			(layers "F.Cu" "F.Mask" "F.Paste")
			(net "M_H_ECC<3>")
		)
		(pad "L68" smd circle
			(at 21.797518 -21.950172)
			(size 0.4318 0.4318)
			(layers "F.Cu" "F.Mask" "F.Paste")
			(net "M_H_DQS_DP<8>")
		)
		(pad "L70" smd circle
			(at 23.514558 -21.950172)
			(size 0.4318 0.4318)
			(layers "F.Cu" "F.Mask" "F.Paste")
			(net "M_H_ECC<4>")
		)
		(pad "L72" smd circle
			(at 25.231598 -21.950172)
			(size 0.4318 0.4318)
			(layers "F.Cu" "F.Mask" "F.Paste")
			(net "GND")
		)
		(pad "L74" smd circle
			(at 26.948384 -21.950172)
			(size 0.4318 0.4318)
			(layers "F.Cu" "F.Mask" "F.Paste")
			(net "M_G_DQ<30>")
		)
		(pad "L76" smd circle
			(at 28.665424 -21.950172)
			(size 0.4318 0.4318)
			(layers "F.Cu" "F.Mask" "F.Paste")
			(net "M_G_DQ<24>")
		)
		(pad "L78" smd circle
			(at 30.382464 -21.950172)
			(size 0.4318 0.4318)
			(layers "F.Cu" "F.Mask" "F.Paste")
			(net "GND")
		)
		(pad "L80" smd circle
			(at 32.099504 -21.950172)
			(size 0.4318 0.4318)
			(layers "F.Cu" "F.Mask" "F.Paste")
			(net "GND")
		)
		(pad "L82" smd circle
			(at 33.816544 -21.950172)
			(size 0.4318 0.4318)
			(layers "F.Cu" "F.Mask" "F.Paste")
			(net "GND")
		)
		(pad "L84" smd circle
			(at 35.533584 -21.950172)
			(size 0.4318 0.4318)
			(layers "F.Cu" "F.Mask" "F.Paste")
			(net "M_G_DQ<11>")
		)
		(pad "L86" smd custom
			(at 37.250624 -21.950172 270)
			(size 0.10795 0.10795)
			(layers "F.Cu" "F.Mask" "F.Paste")
			(net "M_G_DQ<10>")
			(options
				(clearance outline)
				(anchor circle)
			)
			(primitives
				(gr_poly
					(pts
						(arc
							(start 0.2159 -0.0381)
							(mid 0 -0.254)
							(end -0.2159 -0.0381)
						)
						(arc
							(start -0.2159 0.0381)
							(mid 0 0.254)
							(end 0.2159 0.0381)
						)
					)
					(width 0)
					(fill yes)
				)
			)
		)
		(pad "M1" smd custom
			(at -37.250624 -19.655028 90)
			(size 0.10795 0.10795)
			(layers "F.Cu" "F.Mask" "F.Paste")
			(net "UPI_CPU1_CPU0_P0P0_DN<0>")
			(options
				(clearance outline)
				(anchor circle)
			)
			(primitives
				(gr_poly
					(pts
						(arc
							(start 0.2159 -0.0381)
							(mid 0 -0.254)
							(end -0.2159 -0.0381)
						)
						(arc
							(start -0.2159 0.0381)
							(mid 0 0.254)
							(end 0.2159 0.0381)
						)
					)
					(width 0)
					(fill yes)
				)
			)
		)
		(pad "M3" smd circle
			(at -35.533584 -19.655028)
			(size 0.4318 0.4318)
			(layers "F.Cu" "F.Mask" "F.Paste")
			(net "UPI_CPU1_CPU0_P1P1_DP<0>")
		)
		(pad "M5" smd circle
			(at -33.816544 -19.655028)
			(size 0.4318 0.4318)
			(layers "F.Cu" "F.Mask" "F.Paste")
			(net "UPI_CPU1_CPU0_P1P1_DP<2>")
		)
		(pad "M7" smd circle
			(at -32.099504 -19.655028)
			(size 0.4318 0.4318)
			(layers "F.Cu" "F.Mask" "F.Paste")
			(net "PVCCIO_CPU1")
		)
		(pad "M9" smd circle
			(at -30.382464 -19.655028)
			(size 0.4318 0.4318)
			(layers "F.Cu" "F.Mask" "F.Paste")
			(net "PVCCIO_CPU1")
		)
		(pad "M11" smd circle
			(at -28.665424 -19.655028)
			(size 0.4318 0.4318)
			(layers "F.Cu" "F.Mask" "F.Paste")
			(net "PVCCIO_CPU1")
		)
		(pad "M13" smd circle
			(at -26.948384 -19.655028)
			(size 0.4318 0.4318)
			(layers "F.Cu" "F.Mask" "F.Paste")
			(net "UPI_CPU0_CPU1_P1P1_DN<8>")
		)
		(pad "M15" smd circle
			(at -25.231598 -19.655028)
			(size 0.4318 0.4318)
			(layers "F.Cu" "F.Mask" "F.Paste")
			(net "GND")
		)
		(pad "M17" smd circle
			(at -23.514558 -19.655028)
			(size 0.4318 0.4318)
			(layers "F.Cu" "F.Mask" "F.Paste")
			(net "GND")
		)
		(pad "M19" smd circle
			(at -21.797518 -19.655028)
			(size 0.4318 0.4318)
			(layers "F.Cu" "F.Mask" "F.Paste")
			(net "GND")
		)
		(pad "M21" smd circle
			(at -20.080478 -19.655028)
			(size 0.4318 0.4318)
			(layers "F.Cu" "F.Mask" "F.Paste")
			(net "PVCCIO_CPU1")
		)
		(pad "M23" smd circle
			(at -18.363438 -19.655028)
			(size 0.4318 0.4318)
			(layers "F.Cu" "F.Mask" "F.Paste")
			(net "GND")
		)
		(pad "M25" smd circle
			(at -16.646398 -19.655028)
			(size 0.4318 0.4318)
			(layers "F.Cu" "F.Mask" "F.Paste")
			(net "GND")
		)
		(pad "M27" smd circle
			(at -14.929612 -19.655028)
			(size 0.4318 0.4318)
			(layers "F.Cu" "F.Mask" "F.Paste")
			(net "GND")
		)
		(pad "M29" smd circle
			(at -13.212572 -19.655028)
			(size 0.4318 0.4318)
			(layers "F.Cu" "F.Mask" "F.Paste")
			(net "GND")
		)
		(pad "M31" smd circle
			(at -11.495532 -19.655028)
			(size 0.4318 0.4318)
			(layers "F.Cu" "F.Mask" "F.Paste")
			(net "GND")
		)
		(pad "M33" smd circle
			(at -9.778492 -19.655028)
			(size 0.4318 0.4318)
			(layers "F.Cu" "F.Mask" "F.Paste")
			(net "GND")
		)
		(pad "M35" smd circle
			(at -8.061452 -19.655028)
			(size 0.4318 0.4318)
			(layers "F.Cu" "F.Mask" "F.Paste")
			(net "GND")
		)
		(pad "M37" smd circle
			(at -6.344412 -19.655028)
			(size 0.4318 0.4318)
			(layers "F.Cu" "F.Mask" "F.Paste")
			(net "GND")
		)
		(pad "M39" smd circle
			(at -4.627626 -19.655028)
			(size 0.4318 0.4318)
			(layers "F.Cu" "F.Mask" "F.Paste")
			(net "GND")
		)
		(pad "M41" smd circle
			(at -2.910586 -19.655028)
			(size 0.4318 0.4318)
			(layers "F.Cu" "F.Mask" "F.Paste")
			(net "GND")
		)
		(pad "M43" smd circle
			(at -1.193546 -19.655028)
			(size 0.4318 0.4318)
			(layers "F.Cu" "F.Mask" "F.Paste")
			(net "GND")
		)
		(pad "M45" smd circle
			(at 2.052066 -21.455126)
			(size 0.508 0.508)
			(layers "F.Cu" "F.Mask" "F.Paste")
			(net "M_H_CS_N<6>")
		)
		(pad "M47" smd circle
			(at 3.769106 -21.455126)
			(size 0.4318 0.4318)
			(layers "F.Cu" "F.Mask" "F.Paste")
			(net "M_H_C<2>")
		)
		(pad "M49" smd circle
			(at 5.485892 -21.455126)
			(size 0.4318 0.4318)
			(layers "F.Cu" "F.Mask" "F.Paste")
			(net "M_H_ODT<2>")
		)
		(pad "M51" smd circle
			(at 7.202932 -21.455126)
			(size 0.4318 0.4318)
			(layers "F.Cu" "F.Mask" "F.Paste")
			(net "M_H_MA<13>")
		)
		(pad "M53" smd circle
			(at 8.919972 -21.455126)
			(size 0.4318 0.4318)
			(layers "F.Cu" "F.Mask" "F.Paste")
			(net "M_H_CLK_DN<0>")
		)
		(pad "M55" smd circle
			(at 10.637012 -21.455126)
			(size 0.4318 0.4318)
			(layers "F.Cu" "F.Mask" "F.Paste")
			(net "M_H_MA<10>")
		)
		(pad "M57" smd circle
			(at 12.354052 -21.455126)
			(size 0.4318 0.4318)
			(layers "F.Cu" "F.Mask" "F.Paste")
			(net "M_H_CLK_DP<2>")
		)
		(pad "M59" smd circle
			(at 14.071092 -21.455126)
			(size 0.4318 0.4318)
			(layers "F.Cu" "F.Mask" "F.Paste")
			(net "M_H_MA<4>")
		)
		(pad "M61" smd circle
			(at 15.787878 -21.455126)
			(size 0.4318 0.4318)
			(layers "F.Cu" "F.Mask" "F.Paste")
			(net "M_H_BG<0>")
		)
		(pad "M63" smd circle
			(at 17.504918 -21.455126)
			(size 0.4318 0.4318)
			(layers "F.Cu" "F.Mask" "F.Paste")
			(net "TP_CPU1_RSVD_266")
		)
		(pad "M65" smd circle
			(at 19.221958 -21.455126)
			(size 0.4318 0.4318)
			(layers "F.Cu" "F.Mask" "F.Paste")
			(net "GND")
		)
		(pad "M67" smd circle
			(at 20.938998 -21.455126)
			(size 0.4318 0.4318)
			(layers "F.Cu" "F.Mask" "F.Paste")
			(net "M_H_ECC<7>")
		)
		(pad "M69" smd circle
			(at 22.656038 -21.455126)
			(size 0.4318 0.4318)
			(layers "F.Cu" "F.Mask" "F.Paste")
			(net "M_H_ECC<5>")
		)
		(pad "M71" smd circle
			(at 24.373078 -21.455126)
			(size 0.4318 0.4318)
			(layers "F.Cu" "F.Mask" "F.Paste")
			(net "GND")
		)
		(pad "M73" smd circle
			(at 26.090118 -21.455126)
			(size 0.4318 0.4318)
			(layers "F.Cu" "F.Mask" "F.Paste")
			(net "M_G_DQ<26>")
		)
		(pad "M75" smd circle
			(at 27.806904 -21.455126)
			(size 0.4318 0.4318)
			(layers "F.Cu" "F.Mask" "F.Paste")
			(net "M_G_DQS_DP<12>")
		)
		(pad "M77" smd circle
			(at 29.523944 -21.455126)
			(size 0.4318 0.4318)
			(layers "F.Cu" "F.Mask" "F.Paste")
			(net "M_G_DQ<28>")
		)
		(pad "M79" smd circle
			(at 31.240984 -21.455126)
			(size 0.4318 0.4318)
			(layers "F.Cu" "F.Mask" "F.Paste")
			(net "GND")
		)
		(pad "M81" smd circle
			(at 32.958024 -21.455126)
			(size 0.4318 0.4318)
			(layers "F.Cu" "F.Mask" "F.Paste")
			(net "M_G_DQ<19>")
		)
		(pad "M83" smd circle
			(at 34.675064 -21.455126)
			(size 0.4318 0.4318)
			(layers "F.Cu" "F.Mask" "F.Paste")
			(net "GND")
		)
		(pad "M85" smd circle
			(at 36.392104 -21.455126)
			(size 0.4318 0.4318)
			(layers "F.Cu" "F.Mask" "F.Paste")
			(net "GND")
		)
		(pad "N2" smd circle
			(at -36.392104 -19.159474)
			(size 0.4318 0.4318)
			(layers "F.Cu" "F.Mask" "F.Paste")
			(net "UPI_CPU1_CPU0_P0P0_DP<0>")
		)
		(pad "N4" smd circle
			(at -34.675064 -19.159474)
			(size 0.4318 0.4318)
			(layers "F.Cu" "F.Mask" "F.Paste")
			(net "GND")
		)
		(pad "N6" smd circle
			(at -32.958024 -19.159474)
			(size 0.4318 0.4318)
			(layers "F.Cu" "F.Mask" "F.Paste")
			(net "GND")
		)
		(pad "N8" smd circle
			(at -31.240984 -19.159474)
			(size 0.4318 0.4318)
			(layers "F.Cu" "F.Mask" "F.Paste")
			(net "GND")
		)
		(pad "N10" smd circle
			(at -29.523944 -19.159474)
			(size 0.4318 0.4318)
			(layers "F.Cu" "F.Mask" "F.Paste")
			(net "UPI_CPU0_CPU1_P1P1_DP<4>")
		)
		(pad "N12" smd circle
			(at -27.806904 -19.159474)
			(size 0.4318 0.4318)
			(layers "F.Cu" "F.Mask" "F.Paste")
			(net "UPI_CPU0_CPU1_P1P1_DP<7>")
		)
		(pad "N14" smd circle
			(at -26.090118 -19.159474)
			(size 0.4318 0.4318)
			(layers "F.Cu" "F.Mask" "F.Paste")
			(net "UPI_CPU0_CPU1_P1P1_DP<8>")
		)
		(pad "N16" smd circle
			(at -24.373078 -19.159474)
			(size 0.4318 0.4318)
			(layers "F.Cu" "F.Mask" "F.Paste")
			(net "UPI_CPU0_CPU1_P1P1_DN<11>")
		)
		(pad "N18" smd circle
			(at -22.656038 -19.159474)
			(size 0.4318 0.4318)
			(layers "F.Cu" "F.Mask" "F.Paste")
			(net "PVCCIO_CPU1")
		)
		(pad "N20" smd circle
			(at -20.938998 -19.159474)
			(size 0.4318 0.4318)
			(layers "F.Cu" "F.Mask" "F.Paste")
			(net "GND")
		)
		(pad "N22" smd circle
			(at -19.221958 -19.159474)
			(size 0.4318 0.4318)
			(layers "F.Cu" "F.Mask" "F.Paste")
			(net "GND")
		)
		(pad "N24" smd circle
			(at -17.504918 -19.159474)
			(size 0.4318 0.4318)
			(layers "F.Cu" "F.Mask" "F.Paste")
			(net "M_G_DQS_DN<7>")
		)
		(pad "N26" smd circle
			(at -15.787878 -19.159474)
			(size 0.4318 0.4318)
			(layers "F.Cu" "F.Mask" "F.Paste")
			(net "M_G_DQ<61>")
		)
		(pad "N28" smd circle
			(at -14.071092 -19.159474)
			(size 0.4318 0.4318)
			(layers "F.Cu" "F.Mask" "F.Paste")
			(net "M_G_DQ<51>")
		)
		(pad "N30" smd circle
			(at -12.354052 -19.159474)
			(size 0.4318 0.4318)
			(layers "F.Cu" "F.Mask" "F.Paste")
			(net "M_G_DQS_DP<6>")
		)
		(pad "N32" smd circle
			(at -10.637012 -19.159474)
			(size 0.4318 0.4318)
			(layers "F.Cu" "F.Mask" "F.Paste")
			(net "M_G_DQ<53>")
		)
		(pad "N34" smd circle
			(at -8.919972 -19.159474)
			(size 0.4318 0.4318)
			(layers "F.Cu" "F.Mask" "F.Paste")
			(net "M_G_DQ<43>")
		)
		(pad "N36" smd circle
			(at -7.202932 -19.159474)
			(size 0.4318 0.4318)
			(layers "F.Cu" "F.Mask" "F.Paste")
			(net "M_G_DQS_DP<5>")
		)
		(pad "N38" smd circle
			(at -5.485892 -19.159474)
			(size 0.4318 0.4318)
			(layers "F.Cu" "F.Mask" "F.Paste")
			(net "M_G_DQ<45>")
		)
		(pad "N40" smd circle
			(at -3.769106 -19.159474)
			(size 0.4318 0.4318)
			(layers "F.Cu" "F.Mask" "F.Paste")
			(net "M_H_DQ<35>")
		)
		(pad "N42" smd circle
			(at -2.052066 -19.159474)
			(size 0.4318 0.4318)
			(layers "F.Cu" "F.Mask" "F.Paste")
			(net "M_H_DQS_DN<4>")
		)
		(pad "N46" smd circle
			(at 2.910586 -20.959572)
			(size 0.4318 0.4318)
			(layers "F.Cu" "F.Mask" "F.Paste")
			(net "M_H_CS_N<2>")
		)
		(pad "N48" smd circle
			(at 4.627626 -20.959572)
			(size 0.4318 0.4318)
			(layers "F.Cu" "F.Mask" "F.Paste")
			(net "M_H_MA<17>")
		)
		(pad "N50" smd circle
			(at 6.344412 -20.959572)
			(size 0.4318 0.4318)
			(layers "F.Cu" "F.Mask" "F.Paste")
			(net "M_H_ODT<0>")
		)
		(pad "N52" smd circle
			(at 8.061452 -20.959572)
			(size 0.4318 0.4318)
			(layers "F.Cu" "F.Mask" "F.Paste")
			(net "M_H_MA<15>")
		)
		(pad "N54" smd circle
			(at 9.778492 -20.959572)
			(size 0.4318 0.4318)
			(layers "F.Cu" "F.Mask" "F.Paste")
			(net "M_H_CLK_DP<0>")
		)
		(pad "N56" smd circle
			(at 11.495532 -20.959572)
			(size 0.4318 0.4318)
			(layers "F.Cu" "F.Mask" "F.Paste")
			(net "M_H_CLK_DN<2>")
		)
		(pad "N58" smd circle
			(at 13.212572 -20.959572)
			(size 0.4318 0.4318)
			(layers "F.Cu" "F.Mask" "F.Paste")
			(net "M_H_MA<3>")
		)
		(pad "N60" smd circle
			(at 14.929612 -20.959572)
			(size 0.4318 0.4318)
			(layers "F.Cu" "F.Mask" "F.Paste")
			(net "M_H_BG<1>")
		)
		(pad "N62" smd circle
			(at 16.646398 -20.959572)
			(size 0.4318 0.4318)
			(layers "F.Cu" "F.Mask" "F.Paste")
			(net "M_H_CKE<0>")
		)
		(pad "N64" smd circle
			(at 18.363438 -20.959572)
			(size 0.4318 0.4318)
			(layers "F.Cu" "F.Mask" "F.Paste")
			(net "PVDDQ_GHJ")
		)
		(pad "N66" smd circle
			(at 20.080478 -20.959572)
			(size 0.4318 0.4318)
			(layers "F.Cu" "F.Mask" "F.Paste")
			(net "GND")
		)
		(pad "N68" smd circle
			(at 21.797518 -20.959572)
			(size 0.4318 0.4318)
			(layers "F.Cu" "F.Mask" "F.Paste")
			(net "M_H_DQS_DN<8>")
		)
		(pad "N70" smd circle
			(at 23.514558 -20.959572)
			(size 0.4318 0.4318)
			(layers "F.Cu" "F.Mask" "F.Paste")
			(net "GND")
		)
		(pad "N72" smd circle
			(at 25.231598 -20.959572)
			(size 0.4318 0.4318)
			(layers "F.Cu" "F.Mask" "F.Paste")
			(net "GND")
		)
		(pad "N74" smd circle
			(at 26.948384 -20.959572)
			(size 0.4318 0.4318)
			(layers "F.Cu" "F.Mask" "F.Paste")
			(net "GND")
		)
		(pad "N76" smd circle
			(at 28.665424 -20.959572)
			(size 0.4318 0.4318)
			(layers "F.Cu" "F.Mask" "F.Paste")
			(net "GND")
		)
		(pad "N78" smd circle
			(at 30.382464 -20.959572)
			(size 0.4318 0.4318)
			(layers "F.Cu" "F.Mask" "F.Paste")
			(net "GND")
		)
		(pad "N80" smd circle
			(at 32.099504 -20.959572)
			(size 0.4318 0.4318)
			(layers "F.Cu" "F.Mask" "F.Paste")
			(net "M_G_DQ<23>")
		)
		(pad "N82" smd circle
			(at 33.816544 -20.959572)
			(size 0.4318 0.4318)
			(layers "F.Cu" "F.Mask" "F.Paste")
			(net "M_G_DQ<18>")
		)
		(pad "N84" smd circle
			(at 35.533584 -20.959572)
			(size 0.4318 0.4318)
			(layers "F.Cu" "F.Mask" "F.Paste")
			(net "M_G_DQ<15>")
		)
		(pad "N86" smd custom
			(at 37.250624 -20.959572 270)
			(size 0.10795 0.10795)
			(layers "F.Cu" "F.Mask" "F.Paste")
			(net "M_G_DQ<14>")
			(options
				(clearance outline)
				(anchor circle)
			)
			(primitives
				(gr_poly
					(pts
						(arc
							(start 0.2159 -0.0381)
							(mid 0 -0.254)
							(end -0.2159 -0.0381)
						)
						(arc
							(start -0.2159 0.0381)
							(mid 0 0.254)
							(end 0.2159 0.0381)
						)
					)
					(width 0)
					(fill yes)
				)
			)
		)
		(pad "P1" smd custom
			(at -37.250624 -18.664428 90)
			(size 0.10795 0.10795)
			(layers "F.Cu" "F.Mask" "F.Paste")
			(net "UPI_CPU1_CPU0_P0P0_DP<1>")
			(options
				(clearance outline)
				(anchor circle)
			)
			(primitives
				(gr_poly
					(pts
						(arc
							(start 0.2159 -0.0381)
							(mid 0 -0.254)
							(end -0.2159 -0.0381)
						)
						(arc
							(start -0.2159 0.0381)
							(mid 0 0.254)
							(end 0.2159 0.0381)
						)
					)
					(width 0)
					(fill yes)
				)
			)
		)
		(pad "P3" smd circle
			(at -35.533584 -18.664428)
			(size 0.4318 0.4318)
			(layers "F.Cu" "F.Mask" "F.Paste")
			(net "UPI_CPU1_CPU0_P1P1_DN<0>")
		)
		(pad "P5" smd circle
			(at -33.816544 -18.664428)
			(size 0.4318 0.4318)
			(layers "F.Cu" "F.Mask" "F.Paste")
			(net "PVCCIO_CPU1")
		)
		(pad "P7" smd circle
			(at -32.099504 -18.664428)
			(size 0.4318 0.4318)
			(layers "F.Cu" "F.Mask" "F.Paste")
			(net "UPI_CPU0_CPU1_P1P1_DN<1>")
		)
		(pad "P9" smd circle
			(at -30.382464 -18.664428)
			(size 0.4318 0.4318)
			(layers "F.Cu" "F.Mask" "F.Paste")
			(net "UPI_CPU0_CPU1_P1P1_DN<4>")
		)
		(pad "P11" smd circle
			(at -28.665424 -18.664428)
			(size 0.4318 0.4318)
			(layers "F.Cu" "F.Mask" "F.Paste")
			(net "GND")
		)
		(pad "P13" smd circle
			(at -26.948384 -18.664428)
			(size 0.4318 0.4318)
			(layers "F.Cu" "F.Mask" "F.Paste")
			(net "UPI_CPU0_CPU1_P1P1_DP<9>")
		)
		(pad "P15" smd circle
			(at -25.231598 -18.664428)
			(size 0.4318 0.4318)
			(layers "F.Cu" "F.Mask" "F.Paste")
			(net "GND")
		)
		(pad "P17" smd circle
			(at -23.514558 -18.664428)
			(size 0.4318 0.4318)
			(layers "F.Cu" "F.Mask" "F.Paste")
			(net "UPI_CPU0_CPU1_P1P1_DP<11>")
		)
		(pad "P19" smd circle
			(at -21.797518 -18.664428)
			(size 0.4318 0.4318)
			(layers "F.Cu" "F.Mask" "F.Paste")
			(net "UPI_CPU0_CPU1_P1P1_DP<14>")
		)
		(pad "P21" smd circle
			(at -20.080478 -18.664428)
			(size 0.4318 0.4318)
			(layers "F.Cu" "F.Mask" "F.Paste")
			(net "UPI_CPU0_CPU1_P1P1_DN<16>")
		)
		(pad "P23" smd circle
			(at -18.363438 -18.664428)
			(size 0.4318 0.4318)
			(layers "F.Cu" "F.Mask" "F.Paste")
			(net "M_G_DQ<58>")
		)
		(pad "P25" smd circle
			(at -16.646398 -18.664428)
			(size 0.4318 0.4318)
			(layers "F.Cu" "F.Mask" "F.Paste")
			(net "M_G_DQ<57>")
		)
		(pad "P27" smd circle
			(at -14.929612 -18.664428)
			(size 0.4318 0.4318)
			(layers "F.Cu" "F.Mask" "F.Paste")
			(net "GND")
		)
		(pad "P29" smd circle
			(at -13.212572 -18.664428)
			(size 0.4318 0.4318)
			(layers "F.Cu" "F.Mask" "F.Paste")
			(net "M_G_DQ<55>")
		)
		(pad "P31" smd circle
			(at -11.495532 -18.664428)
			(size 0.4318 0.4318)
			(layers "F.Cu" "F.Mask" "F.Paste")
			(net "M_G_DQ<49>")
		)
		(pad "P33" smd circle
			(at -9.778492 -18.664428)
			(size 0.4318 0.4318)
			(layers "F.Cu" "F.Mask" "F.Paste")
			(net "GND")
		)
		(pad "P35" smd circle
			(at -8.061452 -18.664428)
			(size 0.4318 0.4318)
			(layers "F.Cu" "F.Mask" "F.Paste")
			(net "M_G_DQ<47>")
		)
		(pad "P37" smd circle
			(at -6.344412 -18.664428)
			(size 0.4318 0.4318)
			(layers "F.Cu" "F.Mask" "F.Paste")
			(net "M_G_DQ<41>")
		)
		(pad "P39" smd circle
			(at -4.627626 -18.664428)
			(size 0.4318 0.4318)
			(layers "F.Cu" "F.Mask" "F.Paste")
			(net "GND")
		)
		(pad "P41" smd circle
			(at -2.910586 -18.664428)
			(size 0.4318 0.4318)
			(layers "F.Cu" "F.Mask" "F.Paste")
			(net "M_H_DQ<39>")
		)
		(pad "P43" smd circle
			(at -1.193546 -18.664428)
			(size 0.4318 0.4318)
			(layers "F.Cu" "F.Mask" "F.Paste")
			(net "M_H_DQ<36>")
		)
		(pad "P45" smd circle
			(at 2.052066 -20.464526)
			(size 0.508 0.508)
			(layers "F.Cu" "F.Mask" "F.Paste")
			(net "GND")
		)
		(pad "P47" smd circle
			(at 3.769106 -20.464526)
			(size 0.4318 0.4318)
			(layers "F.Cu" "F.Mask" "F.Paste")
			(net "GND")
		)
		(pad "P49" smd circle
			(at 5.485892 -20.464526)
			(size 0.4318 0.4318)
			(layers "F.Cu" "F.Mask" "F.Paste")
			(net "GND")
		)
		(pad "P51" smd circle
			(at 7.202932 -20.464526)
			(size 0.4318 0.4318)
			(layers "F.Cu" "F.Mask" "F.Paste")
			(net "GND")
		)
		(pad "P53" smd circle
			(at 8.919972 -20.464526)
			(size 0.4318 0.4318)
			(layers "F.Cu" "F.Mask" "F.Paste")
			(net "GND")
		)
		(pad "P55" smd circle
			(at 10.637012 -20.464526)
			(size 0.4318 0.4318)
			(layers "F.Cu" "F.Mask" "F.Paste")
			(net "GND")
		)
		(pad "P57" smd circle
			(at 12.354052 -20.464526)
			(size 0.4318 0.4318)
			(layers "F.Cu" "F.Mask" "F.Paste")
			(net "GND")
		)
		(pad "P59" smd circle
			(at 14.071092 -20.464526)
			(size 0.4318 0.4318)
			(layers "F.Cu" "F.Mask" "F.Paste")
			(net "GND")
		)
		(pad "P61" smd circle
			(at 15.787878 -20.464526)
			(size 0.4318 0.4318)
			(layers "F.Cu" "F.Mask" "F.Paste")
			(net "GND")
		)
		(pad "P63" smd circle
			(at 17.504918 -20.464526)
			(size 0.4318 0.4318)
			(layers "F.Cu" "F.Mask" "F.Paste")
			(net "GND")
		)
		(pad "P65" smd circle
			(at 19.221958 -20.464526)
			(size 0.4318 0.4318)
			(layers "F.Cu" "F.Mask" "F.Paste")
			(net "TP_CPU1_RSVD_265")
		)
		(pad "P67" smd circle
			(at 20.938998 -20.464526)
			(size 0.4318 0.4318)
			(layers "F.Cu" "F.Mask" "F.Paste")
			(net "GND")
		)
		(pad "P69" smd circle
			(at 22.656038 -20.464526)
			(size 0.4318 0.4318)
			(layers "F.Cu" "F.Mask" "F.Paste")
			(net "GND")
		)
		(pad "P71" smd circle
			(at 24.373078 -20.464526)
			(size 0.4318 0.4318)
			(layers "F.Cu" "F.Mask" "F.Paste")
			(net "GND")
		)
		(pad "P73" smd circle
			(at 26.090118 -20.464526)
			(size 0.4318 0.4318)
			(layers "F.Cu" "F.Mask" "F.Paste")
			(net "M_G_DQ<27>")
		)
		(pad "P75" smd circle
			(at 27.806904 -20.464526)
			(size 0.4318 0.4318)
			(layers "F.Cu" "F.Mask" "F.Paste")
			(net "M_G_DQS_DP<3>")
		)
		(pad "P77" smd circle
			(at 29.523944 -20.464526)
			(size 0.4318 0.4318)
			(layers "F.Cu" "F.Mask" "F.Paste")
			(net "M_G_DQ<29>")
		)
		(pad "P79" smd circle
			(at 31.240984 -20.464526)
			(size 0.4318 0.4318)
			(layers "F.Cu" "F.Mask" "F.Paste")
			(net "M_G_DQS_DN<2>")
		)
		(pad "P81" smd circle
			(at 32.958024 -20.464526)
			(size 0.4318 0.4318)
			(layers "F.Cu" "F.Mask" "F.Paste")
			(net "GND")
		)
		(pad "P83" smd circle
			(at 34.675064 -20.464526)
			(size 0.4318 0.4318)
			(layers "F.Cu" "F.Mask" "F.Paste")
			(net "GND")
		)
		(pad "P85" smd circle
			(at 36.392104 -20.464526)
			(size 0.4318 0.4318)
			(layers "F.Cu" "F.Mask" "F.Paste")
			(net "M_G_DQS_DP<1>")
		)
		(pad "R2" smd circle
			(at -36.392104 -18.168874)
			(size 0.4318 0.4318)
			(layers "F.Cu" "F.Mask" "F.Paste")
			(net "GND")
		)
		(pad "R4" smd circle
			(at -34.675064 -18.168874)
			(size 0.4318 0.4318)
			(layers "F.Cu" "F.Mask" "F.Paste")
			(net "GND")
		)
		(pad "R6" smd circle
			(at -32.958024 -18.168874)
			(size 0.4318 0.4318)
			(layers "F.Cu" "F.Mask" "F.Paste")
			(net "UPI_CPU0_CPU1_P1P1_DN<0>")
		)
		(pad "R8" smd circle
			(at -31.240984 -18.168874)
			(size 0.4318 0.4318)
			(layers "F.Cu" "F.Mask" "F.Paste")
			(net "UPI_CPU0_CPU1_P1P1_DP<3>")
		)
		(pad "R10" smd circle
			(at -29.523944 -18.168874)
			(size 0.4318 0.4318)
			(layers "F.Cu" "F.Mask" "F.Paste")
			(net "UPI_CPU0_CPU1_P1P1_DN<5>")
		)
		(pad "R12" smd circle
			(at -27.806904 -18.168874)
			(size 0.4318 0.4318)
			(layers "F.Cu" "F.Mask" "F.Paste")
			(net "UPI_CPU0_CPU1_P1P1_DN<9>")
		)
		(pad "R14" smd circle
			(at -26.090118 -18.168874)
			(size 0.4318 0.4318)
			(layers "F.Cu" "F.Mask" "F.Paste")
			(net "GND")
		)
		(pad "R16" smd circle
			(at -24.373078 -18.168874)
			(size 0.4318 0.4318)
			(layers "F.Cu" "F.Mask" "F.Paste")
			(net "UPI_CPU0_CPU1_P1P1_DN<10>")
		)
		(pad "R18" smd circle
			(at -22.656038 -18.168874)
			(size 0.4318 0.4318)
			(layers "F.Cu" "F.Mask" "F.Paste")
			(net "GND")
		)
		(pad "R20" smd circle
			(at -20.938998 -18.168874)
			(size 0.4318 0.4318)
			(layers "F.Cu" "F.Mask" "F.Paste")
			(net "UPI_CPU0_CPU1_P1P1_DN<14>")
		)
		(pad "R22" smd circle
			(at -19.221958 -18.168874)
			(size 0.4318 0.4318)
			(layers "F.Cu" "F.Mask" "F.Paste")
			(net "GND")
		)
		(pad "R24" smd circle
			(at -17.504918 -18.168874)
			(size 0.4318 0.4318)
			(layers "F.Cu" "F.Mask" "F.Paste")
			(net "M_G_DQS_DP<7>")
		)
		(pad "R26" smd circle
			(at -15.787878 -18.168874)
			(size 0.4318 0.4318)
			(layers "F.Cu" "F.Mask" "F.Paste")
			(net "GND")
		)
		(pad "R28" smd circle
			(at -14.071092 -18.168874)
			(size 0.4318 0.4318)
			(layers "F.Cu" "F.Mask" "F.Paste")
			(net "GND")
		)
		(pad "R30" smd circle
			(at -12.354052 -18.168874)
			(size 0.4318 0.4318)
			(layers "F.Cu" "F.Mask" "F.Paste")
			(net "M_G_DQS_DN<6>")
		)
		(pad "R32" smd circle
			(at -10.637012 -18.168874)
			(size 0.4318 0.4318)
			(layers "F.Cu" "F.Mask" "F.Paste")
			(net "GND")
		)
		(pad "R34" smd circle
			(at -8.919972 -18.168874)
			(size 0.4318 0.4318)
			(layers "F.Cu" "F.Mask" "F.Paste")
			(net "GND")
		)
		(pad "R36" smd circle
			(at -7.202932 -18.168874)
			(size 0.4318 0.4318)
			(layers "F.Cu" "F.Mask" "F.Paste")
			(net "M_G_DQS_DN<5>")
		)
		(pad "R38" smd circle
			(at -5.485892 -18.168874)
			(size 0.4318 0.4318)
			(layers "F.Cu" "F.Mask" "F.Paste")
			(net "GND")
		)
		(pad "R40" smd circle
			(at -3.769106 -18.168874)
			(size 0.4318 0.4318)
			(layers "F.Cu" "F.Mask" "F.Paste")
			(net "GND")
		)
		(pad "R42" smd circle
			(at -2.052066 -18.168874)
			(size 0.4318 0.4318)
			(layers "F.Cu" "F.Mask" "F.Paste")
			(net "M_H_DQS_DP<4>")
		)
		(pad "R46" smd circle
			(at 2.910586 -19.968972)
			(size 0.4318 0.4318)
			(layers "F.Cu" "F.Mask" "F.Paste")
			(net "M_H_CS_N<7>")
		)
		(pad "R48" smd circle
			(at 4.627626 -19.968972)
			(size 0.4318 0.4318)
			(layers "F.Cu" "F.Mask" "F.Paste")
			(net "M_H_ODT<1>")
		)
		(pad "R50" smd circle
			(at 6.344412 -19.968972)
			(size 0.4318 0.4318)
			(layers "F.Cu" "F.Mask" "F.Paste")
			(net "M_H_CS_N<1>")
		)
		(pad "R52" smd circle
			(at 8.061452 -19.968972)
			(size 0.4318 0.4318)
			(layers "F.Cu" "F.Mask" "F.Paste")
			(net "M_H_MA<16>")
		)
		(pad "R54" smd circle
			(at 9.778492 -19.968972)
			(size 0.4318 0.4318)
			(layers "F.Cu" "F.Mask" "F.Paste")
			(net "M_H_CLK_DN<1>")
		)
		(pad "R56" smd circle
			(at 11.495532 -19.968972)
			(size 0.4318 0.4318)
			(layers "F.Cu" "F.Mask" "F.Paste")
			(net "M_H_CLK_DN<3>")
		)
		(pad "R58" smd circle
			(at 13.212572 -19.968972)
			(size 0.4318 0.4318)
			(layers "F.Cu" "F.Mask" "F.Paste")
			(net "M_H_MA<5>")
		)
		(pad "R60" smd circle
			(at 14.929612 -19.968972)
			(size 0.4318 0.4318)
			(layers "F.Cu" "F.Mask" "F.Paste")
			(net "M_H_MA<11>")
		)
		(pad "R62" smd circle
			(at 16.646398 -19.968972)
			(size 0.4318 0.4318)
			(layers "F.Cu" "F.Mask" "F.Paste")
			(net "TP_CPU1_RSVD_264")
		)
		(pad "R64" smd circle
			(at 18.363438 -19.968972)
			(size 0.4318 0.4318)
			(layers "F.Cu" "F.Mask" "F.Paste")
			(net "M_H_CKE<1>")
		)
		(pad "R66" smd circle
			(at 20.080478 -19.968972)
			(size 0.4318 0.4318)
			(layers "F.Cu" "F.Mask" "F.Paste")
			(net "TP_CPU1_RSVD_263")
		)
		(pad "R68" smd circle
			(at 21.797518 -19.968972)
			(size 0.4318 0.4318)
			(layers "F.Cu" "F.Mask" "F.Paste")
			(net "GND")
		)
		(pad "R70" smd circle
			(at 23.514558 -19.968972)
			(size 0.4318 0.4318)
			(layers "F.Cu" "F.Mask" "F.Paste")
			(net "M_J_DQ<18>")
		)
		(pad "R72" smd circle
			(at 25.231598 -19.968972)
			(size 0.4318 0.4318)
			(layers "F.Cu" "F.Mask" "F.Paste")
			(net "GND")
		)
		(pad "R74" smd circle
			(at 26.948384 -19.968972)
			(size 0.4318 0.4318)
			(layers "F.Cu" "F.Mask" "F.Paste")
			(net "M_G_DQ<31>")
		)
		(pad "R76" smd circle
			(at 28.665424 -19.968972)
			(size 0.4318 0.4318)
			(layers "F.Cu" "F.Mask" "F.Paste")
			(net "M_G_DQ<25>")
		)
		(pad "R78" smd circle
			(at 30.382464 -19.968972)
			(size 0.4318 0.4318)
			(layers "F.Cu" "F.Mask" "F.Paste")
			(net "GND")
		)
		(pad "R80" smd circle
			(at 32.099504 -19.968972)
			(size 0.4318 0.4318)
			(layers "F.Cu" "F.Mask" "F.Paste")
			(net "M_G_DQS_DP<2>")
		)
		(pad "R82" smd circle
			(at 33.816544 -19.968972)
			(size 0.4318 0.4318)
			(layers "F.Cu" "F.Mask" "F.Paste")
			(net "M_G_DQ<22>")
		)
		(pad "R84" smd circle
			(at 35.533584 -19.968972)
			(size 0.4318 0.4318)
			(layers "F.Cu" "F.Mask" "F.Paste")
			(net "M_G_DQS_DN<1>")
		)
		(pad "R86" smd custom
			(at 37.250624 -19.968972 270)
			(size 0.10795 0.10795)
			(layers "F.Cu" "F.Mask" "F.Paste")
			(net "GND")
			(options
				(clearance outline)
				(anchor circle)
			)
			(primitives
				(gr_poly
					(pts
						(arc
							(start 0.2159 -0.0381)
							(mid 0 -0.254)
							(end -0.2159 -0.0381)
						)
						(arc
							(start -0.2159 0.0381)
							(mid 0 0.254)
							(end 0.2159 0.0381)
						)
					)
					(width 0)
					(fill yes)
				)
			)
		)
		(pad "T1" smd custom
			(at -37.250624 -17.673574 90)
			(size 0.10795 0.10795)
			(layers "F.Cu" "F.Mask" "F.Paste")
			(net "UPI_CPU1_CPU0_P0P0_DN<1>")
			(options
				(clearance outline)
				(anchor circle)
			)
			(primitives
				(gr_poly
					(pts
						(arc
							(start 0.2159 -0.0381)
							(mid 0 -0.254)
							(end -0.2159 -0.0381)
						)
						(arc
							(start -0.2159 0.0381)
							(mid 0 0.254)
							(end 0.2159 0.0381)
						)
					)
					(width 0)
					(fill yes)
				)
			)
		)
		(pad "T3" smd circle
			(at -35.533584 -17.673574)
			(size 0.4318 0.4318)
			(layers "F.Cu" "F.Mask" "F.Paste")
			(net "PVCCIO_CPU1")
		)
		(pad "T5" smd circle
			(at -33.816544 -17.673574)
			(size 0.4318 0.4318)
			(layers "F.Cu" "F.Mask" "F.Paste")
			(net "UPI_CPU0_CPU1_P1P1_DP<0>")
		)
		(pad "T7" smd circle
			(at -32.099504 -17.673574)
			(size 0.4318 0.4318)
			(layers "F.Cu" "F.Mask" "F.Paste")
			(net "UPI_CPU0_CPU1_P1P1_DP<1>")
		)
		(pad "T9" smd circle
			(at -30.382464 -17.673574)
			(size 0.4318 0.4318)
			(layers "F.Cu" "F.Mask" "F.Paste")
			(net "UPI_CPU0_CPU1_P1P1_DN<3>")
		)
		(pad "T11" smd circle
			(at -28.665424 -17.673574)
			(size 0.4318 0.4318)
			(layers "F.Cu" "F.Mask" "F.Paste")
			(net "UPI_CPU0_CPU1_P1P1_DP<6>")
		)
		(pad "T13" smd circle
			(at -26.948384 -17.673574)
			(size 0.4318 0.4318)
			(layers "F.Cu" "F.Mask" "F.Paste")
			(net "GND")
		)
		(pad "T15" smd circle
			(at -25.231598 -17.673574)
			(size 0.4318 0.4318)
			(layers "F.Cu" "F.Mask" "F.Paste")
			(net "UPI_CPU0_CPU1_P1P1_DP<10>")
		)
		(pad "T17" smd circle
			(at -23.514558 -17.673574)
			(size 0.4318 0.4318)
			(layers "F.Cu" "F.Mask" "F.Paste")
			(net "GND")
		)
		(pad "T19" smd circle
			(at -21.797518 -17.673574)
			(size 0.4318 0.4318)
			(layers "F.Cu" "F.Mask" "F.Paste")
			(net "UPI_CPU0_CPU1_P1P1_DP<15>")
		)
		(pad "T21" smd circle
			(at -20.080478 -17.673574)
			(size 0.4318 0.4318)
			(layers "F.Cu" "F.Mask" "F.Paste")
			(net "UPI_CPU0_CPU1_P1P1_DP<16>")
		)
		(pad "T23" smd circle
			(at -18.363438 -17.673574)
			(size 0.4318 0.4318)
			(layers "F.Cu" "F.Mask" "F.Paste")
			(net "M_G_DQ<59>")
		)
		(pad "T25" smd circle
			(at -16.646398 -17.673574)
			(size 0.4318 0.4318)
			(layers "F.Cu" "F.Mask" "F.Paste")
			(net "GND")
		)
		(pad "T27" smd circle
			(at -14.929612 -17.673574)
			(size 0.4318 0.4318)
			(layers "F.Cu" "F.Mask" "F.Paste")
			(net "M_H_DQS_DN<16>")
		)
		(pad "T29" smd circle
			(at -13.212572 -17.673574)
			(size 0.4318 0.4318)
			(layers "F.Cu" "F.Mask" "F.Paste")
			(net "GND")
		)
		(pad "T31" smd circle
			(at -11.495532 -17.673574)
			(size 0.4318 0.4318)
			(layers "F.Cu" "F.Mask" "F.Paste")
			(net "GND")
		)
		(pad "T33" smd circle
			(at -9.778492 -17.673574)
			(size 0.4318 0.4318)
			(layers "F.Cu" "F.Mask" "F.Paste")
			(net "M_J_DQS_DN<14>")
		)
		(pad "T35" smd circle
			(at -8.061452 -17.673574)
			(size 0.4318 0.4318)
			(layers "F.Cu" "F.Mask" "F.Paste")
			(net "GND")
		)
		(pad "T37" smd circle
			(at -6.344412 -17.673574)
			(size 0.4318 0.4318)
			(layers "F.Cu" "F.Mask" "F.Paste")
			(net "GND")
		)
		(pad "T39" smd circle
			(at -4.627626 -17.673574)
			(size 0.4318 0.4318)
			(layers "F.Cu" "F.Mask" "F.Paste")
			(net "M_J_DQS_DN<13>")
		)
		(pad "T41" smd circle
			(at -2.910586 -17.673574)
			(size 0.4318 0.4318)
			(layers "F.Cu" "F.Mask" "F.Paste")
			(net "GND")
		)
		(pad "T43" smd circle
			(at -1.193546 -17.673574)
			(size 0.4318 0.4318)
			(layers "F.Cu" "F.Mask" "F.Paste")
			(net "M_H_DQ<37>")
		)
		(pad "T45" smd circle
			(at 2.052066 -19.473926)
			(size 0.508 0.508)
			(layers "F.Cu" "F.Mask" "F.Paste")
			(net "M_J_CS_N<6>")
		)
		(pad "T47" smd circle
			(at 3.769106 -19.473926)
			(size 0.4318 0.4318)
			(layers "F.Cu" "F.Mask" "F.Paste")
			(net "M_H_ODT<3>")
		)
		(pad "T49" smd circle
			(at 5.485892 -19.473926)
			(size 0.4318 0.4318)
			(layers "F.Cu" "F.Mask" "F.Paste")
			(net "M_H_CS_N<5>")
		)
		(pad "T51" smd circle
			(at 7.202932 -19.473926)
			(size 0.4318 0.4318)
			(layers "F.Cu" "F.Mask" "F.Paste")
			(net "M_H_MA<14>")
		)
		(pad "T53" smd circle
			(at 8.919972 -19.473926)
			(size 0.4318 0.4318)
			(layers "F.Cu" "F.Mask" "F.Paste")
			(net "M_H_BA<0>")
		)
		(pad "T55" smd circle
			(at 10.637012 -19.473926)
			(size 0.4318 0.4318)
			(layers "F.Cu" "F.Mask" "F.Paste")
			(net "M_H_CLK_DP<1>")
		)
		(pad "T57" smd circle
			(at 12.354052 -19.473926)
			(size 0.4318 0.4318)
			(layers "F.Cu" "F.Mask" "F.Paste")
			(net "M_H_CLK_DP<3>")
		)
		(pad "T59" smd circle
			(at 14.071092 -19.473926)
			(size 0.4318 0.4318)
			(layers "F.Cu" "F.Mask" "F.Paste")
			(net "M_H_MA<6>")
		)
		(pad "T61" smd circle
			(at 15.787878 -19.473926)
			(size 0.4318 0.4318)
			(layers "F.Cu" "F.Mask" "F.Paste")
			(net "M_H_MA<12>")
		)
		(pad "T63" smd circle
			(at 17.504918 -19.473926)
			(size 0.4318 0.4318)
			(layers "F.Cu" "F.Mask" "F.Paste")
			(net "M_H_ACT_N")
		)
		(pad "T65" smd circle
			(at 19.221958 -19.473926)
			(size 0.4318 0.4318)
			(layers "F.Cu" "F.Mask" "F.Paste")
			(net "GND")
		)
		(pad "T67" smd circle
			(at 20.938998 -19.473926)
			(size 0.4318 0.4318)
			(layers "F.Cu" "F.Mask" "F.Paste")
			(net "TP_CPU1_RSVD_262")
		)
		(pad "T69" smd circle
			(at 22.656038 -19.473926)
			(size 0.4318 0.4318)
			(layers "F.Cu" "F.Mask" "F.Paste")
			(net "M_J_DQ<19>")
		)
		(pad "T71" smd circle
			(at 24.373078 -19.473926)
			(size 0.4318 0.4318)
			(layers "F.Cu" "F.Mask" "F.Paste")
			(net "M_J_DQ<22>")
		)
		(pad "T73" smd circle
			(at 26.090118 -19.473926)
			(size 0.4318 0.4318)
			(layers "F.Cu" "F.Mask" "F.Paste")
			(net "GND")
		)
		(pad "T75" smd circle
			(at 27.806904 -19.473926)
			(size 0.4318 0.4318)
			(layers "F.Cu" "F.Mask" "F.Paste")
			(net "M_G_DQS_DN<3>")
		)
		(pad "T77" smd circle
			(at 29.523944 -19.473926)
			(size 0.4318 0.4318)
			(layers "F.Cu" "F.Mask" "F.Paste")
			(net "GND")
		)
		(pad "T79" smd circle
			(at 31.240984 -19.473926)
			(size 0.4318 0.4318)
			(layers "F.Cu" "F.Mask" "F.Paste")
			(net "M_G_DQ<17>")
		)
		(pad "T81" smd circle
			(at 32.958024 -19.473926)
			(size 0.4318 0.4318)
			(layers "F.Cu" "F.Mask" "F.Paste")
			(net "M_G_DQS_DP<11>")
		)
		(pad "T83" smd circle
			(at 34.675064 -19.473926)
			(size 0.4318 0.4318)
			(layers "F.Cu" "F.Mask" "F.Paste")
			(net "GND")
		)
		(pad "T85" smd circle
			(at 36.392104 -19.473926)
			(size 0.4318 0.4318)
			(layers "F.Cu" "F.Mask" "F.Paste")
			(net "GND")
		)
		(pad "U2" smd circle
			(at -36.392104 -17.178528)
			(size 0.4318 0.4318)
			(layers "F.Cu" "F.Mask" "F.Paste")
			(net "GND")
		)
		(pad "U4" smd circle
			(at -34.675064 -17.178528)
			(size 0.4318 0.4318)
			(layers "F.Cu" "F.Mask" "F.Paste")
			(net "GND")
		)
		(pad "U6" smd circle
			(at -32.958024 -17.178528)
			(size 0.4318 0.4318)
			(layers "F.Cu" "F.Mask" "F.Paste")
			(net "GND")
		)
		(pad "U8" smd circle
			(at -31.240984 -17.178528)
			(size 0.4318 0.4318)
			(layers "F.Cu" "F.Mask" "F.Paste")
			(net "UPI_CPU0_CPU1_P1P1_DP<2>")
		)
		(pad "U10" smd circle
			(at -29.523944 -17.178528)
			(size 0.4318 0.4318)
			(layers "F.Cu" "F.Mask" "F.Paste")
			(net "UPI_CPU0_CPU1_P1P1_DP<5>")
		)
		(pad "U12" smd circle
			(at -27.806904 -17.178528)
			(size 0.4318 0.4318)
			(layers "F.Cu" "F.Mask" "F.Paste")
			(net "UPI_CPU0_CPU1_P1P1_DN<6>")
		)
		(pad "U14" smd circle
			(at -26.090118 -17.178528)
			(size 0.4318 0.4318)
			(layers "F.Cu" "F.Mask" "F.Paste")
			(net "PVCCIO_CPU1")
		)
		(pad "U16" smd circle
			(at -24.373078 -17.178528)
			(size 0.4318 0.4318)
			(layers "F.Cu" "F.Mask" "F.Paste")
			(net "UPI_CPU0_CPU1_P1P1_DP<12>")
		)
		(pad "U18" smd circle
			(at -22.656038 -17.178528)
			(size 0.4318 0.4318)
			(layers "F.Cu" "F.Mask" "F.Paste")
			(net "UPI_CPU0_CPU1_P1P1_DN<15>")
		)
		(pad "U20" smd circle
			(at -20.938998 -17.178528)
			(size 0.4318 0.4318)
			(layers "F.Cu" "F.Mask" "F.Paste")
			(net "GND")
		)
		(pad "U22" smd circle
			(at -19.221958 -17.178528)
			(size 0.4318 0.4318)
			(layers "F.Cu" "F.Mask" "F.Paste")
			(net "GND")
		)
		(pad "U24" smd circle
			(at -17.504918 -17.178528)
			(size 0.4318 0.4318)
			(layers "F.Cu" "F.Mask" "F.Paste")
			(net "GND")
		)
		(pad "U26" smd circle
			(at -15.787878 -17.178528)
			(size 0.4318 0.4318)
			(layers "F.Cu" "F.Mask" "F.Paste")
			(net "M_H_DQ<62>")
		)
		(pad "U28" smd circle
			(at -14.071092 -17.178528)
			(size 0.4318 0.4318)
			(layers "F.Cu" "F.Mask" "F.Paste")
			(net "M_H_DQ<56>")
		)
		(pad "U30" smd circle
			(at -12.354052 -17.178528)
			(size 0.4318 0.4318)
			(layers "F.Cu" "F.Mask" "F.Paste")
			(net "GND")
		)
		(pad "U32" smd circle
			(at -10.637012 -17.178528)
			(size 0.4318 0.4318)
			(layers "F.Cu" "F.Mask" "F.Paste")
			(net "M_J_DQ<46>")
		)
		(pad "U34" smd circle
			(at -8.919972 -17.178528)
			(size 0.4318 0.4318)
			(layers "F.Cu" "F.Mask" "F.Paste")
			(net "M_J_DQ<40>")
		)
		(pad "U36" smd circle
			(at -7.202932 -17.178528)
			(size 0.4318 0.4318)
			(layers "F.Cu" "F.Mask" "F.Paste")
			(net "GND")
		)
		(pad "U38" smd circle
			(at -5.485892 -17.178528)
			(size 0.4318 0.4318)
			(layers "F.Cu" "F.Mask" "F.Paste")
			(net "M_J_DQ<38>")
		)
		(pad "U40" smd circle
			(at -3.769106 -17.178528)
			(size 0.4318 0.4318)
			(layers "F.Cu" "F.Mask" "F.Paste")
			(net "M_J_DQ<32>")
		)
		(pad "U42" smd circle
			(at -2.052066 -17.178528)
			(size 0.4318 0.4318)
			(layers "F.Cu" "F.Mask" "F.Paste")
			(net "GND")
		)
		(pad "U46" smd circle
			(at 2.910586 -18.978372)
			(size 0.4318 0.4318)
			(layers "F.Cu" "F.Mask" "F.Paste")
			(net "PVDDQ_GHJ")
		)
		(pad "U48" smd circle
			(at 4.627626 -18.978372)
			(size 0.4318 0.4318)
			(layers "F.Cu" "F.Mask" "F.Paste")
			(net "PVDDQ_GHJ")
		)
		(pad "U50" smd circle
			(at 6.344412 -18.978372)
			(size 0.4318 0.4318)
			(layers "F.Cu" "F.Mask" "F.Paste")
			(net "PVDDQ_GHJ")
		)
		(pad "U52" smd circle
			(at 8.061452 -18.978372)
			(size 0.4318 0.4318)
			(layers "F.Cu" "F.Mask" "F.Paste")
			(net "PVDDQ_GHJ")
		)
		(pad "U54" smd circle
			(at 9.778492 -18.978372)
			(size 0.4318 0.4318)
			(layers "F.Cu" "F.Mask" "F.Paste")
			(net "PVDDQ_GHJ")
		)
		(pad "U56" smd circle
			(at 11.495532 -18.978372)
			(size 0.4318 0.4318)
			(layers "F.Cu" "F.Mask" "F.Paste")
			(net "PVDDQ_GHJ")
		)
		(pad "U58" smd circle
			(at 13.212572 -18.978372)
			(size 0.4318 0.4318)
			(layers "F.Cu" "F.Mask" "F.Paste")
			(net "PVDDQ_GHJ")
		)
		(pad "U60" smd circle
			(at 14.929612 -18.978372)
			(size 0.4318 0.4318)
			(layers "F.Cu" "F.Mask" "F.Paste")
			(net "PVDDQ_GHJ")
		)
		(pad "U62" smd circle
			(at 16.646398 -18.978372)
			(size 0.4318 0.4318)
			(layers "F.Cu" "F.Mask" "F.Paste")
			(net "PVDDQ_GHJ")
		)
		(pad "U64" smd circle
			(at 18.363438 -18.978372)
			(size 0.4318 0.4318)
			(layers "F.Cu" "F.Mask" "F.Paste")
			(net "M_GHJ_RST_N")
		)
		(pad "U66" smd circle
			(at 20.080478 -18.978372)
			(size 0.4318 0.4318)
			(layers "F.Cu" "F.Mask" "F.Paste")
			(net "TP_CPU1_RSVD_261")
		)
		(pad "U68" smd circle
			(at 21.797518 -18.978372)
			(size 0.4318 0.4318)
			(layers "F.Cu" "F.Mask" "F.Paste")
			(net "GND")
		)
		(pad "U70" smd circle
			(at 23.514558 -18.978372)
			(size 0.4318 0.4318)
			(layers "F.Cu" "F.Mask" "F.Paste")
			(net "GND")
		)
		(pad "U72" smd circle
			(at 25.231598 -18.978372)
			(size 0.4318 0.4318)
			(layers "F.Cu" "F.Mask" "F.Paste")
			(net "M_J_DQS_DN<11>")
		)
		(pad "U74" smd circle
			(at 26.948384 -18.978372)
			(size 0.4318 0.4318)
			(layers "F.Cu" "F.Mask" "F.Paste")
			(net "GND")
		)
		(pad "U76" smd circle
			(at 28.665424 -18.978372)
			(size 0.4318 0.4318)
			(layers "F.Cu" "F.Mask" "F.Paste")
			(net "GND")
		)
		(pad "U78" smd circle
			(at 30.382464 -18.978372)
			(size 0.4318 0.4318)
			(layers "F.Cu" "F.Mask" "F.Paste")
			(net "GND")
		)
		(pad "U80" smd circle
			(at 32.099504 -18.978372)
			(size 0.4318 0.4318)
			(layers "F.Cu" "F.Mask" "F.Paste")
			(net "GND")
		)
		(pad "U82" smd circle
			(at 33.816544 -18.978372)
			(size 0.4318 0.4318)
			(layers "F.Cu" "F.Mask" "F.Paste")
			(net "M_G_DQS_DN<11>")
		)
		(pad "U84" smd circle
			(at 35.533584 -18.978372)
			(size 0.4318 0.4318)
			(layers "F.Cu" "F.Mask" "F.Paste")
			(net "M_G_DQS_DN<10>")
		)
		(pad "U86" smd custom
			(at 37.250624 -18.978372 270)
			(size 0.10795 0.10795)
			(layers "F.Cu" "F.Mask" "F.Paste")
			(net "GND")
			(options
				(clearance outline)
				(anchor circle)
			)
			(primitives
				(gr_poly
					(pts
						(arc
							(start 0.2159 -0.0381)
							(mid 0 -0.254)
							(end -0.2159 -0.0381)
						)
						(arc
							(start -0.2159 0.0381)
							(mid 0 0.254)
							(end 0.2159 0.0381)
						)
					)
					(width 0)
					(fill yes)
				)
			)
		)
		(pad "V1" smd custom
			(at -37.250624 -16.683228 90)
			(size 0.10795 0.10795)
			(layers "F.Cu" "F.Mask" "F.Paste")
			(net "GND")
			(options
				(clearance outline)
				(anchor circle)
			)
			(primitives
				(gr_poly
					(pts
						(arc
							(start 0.2159 -0.0381)
							(mid 0 -0.254)
							(end -0.2159 -0.0381)
						)
						(arc
							(start -0.2159 0.0381)
							(mid 0 0.254)
							(end 0.2159 0.0381)
						)
					)
					(width 0)
					(fill yes)
				)
			)
		)
		(pad "V3" smd circle
			(at -35.533584 -16.683228)
			(size 0.4318 0.4318)
			(layers "F.Cu" "F.Mask" "F.Paste")
			(net "UPI_CPU1_CPU0_P0P0_DN<2>")
		)
		(pad "V5" smd circle
			(at -33.816544 -16.683228)
			(size 0.4318 0.4318)
			(layers "F.Cu" "F.Mask" "F.Paste")
			(net "GND")
		)
		(pad "V7" smd circle
			(at -32.099504 -16.683228)
			(size 0.4318 0.4318)
			(layers "F.Cu" "F.Mask" "F.Paste")
			(net "UPI_CPU0_CPU1_P1P1_DN<2>")
		)
		(pad "V9" smd circle
			(at -30.382464 -16.683228)
			(size 0.4318 0.4318)
			(layers "F.Cu" "F.Mask" "F.Paste")
			(net "GND")
		)
		(pad "V11" smd circle
			(at -28.665424 -16.683228)
			(size 0.4318 0.4318)
			(layers "F.Cu" "F.Mask" "F.Paste")
			(net "GND")
		)
		(pad "V13" smd circle
			(at -26.948384 -16.683228)
			(size 0.4318 0.4318)
			(layers "F.Cu" "F.Mask" "F.Paste")
			(net "GND")
		)
		(pad "V15" smd circle
			(at -25.231598 -16.683228)
			(size 0.4318 0.4318)
			(layers "F.Cu" "F.Mask" "F.Paste")
			(net "GND")
		)
		(pad "V17" smd circle
			(at -23.514558 -16.683228)
			(size 0.4318 0.4318)
			(layers "F.Cu" "F.Mask" "F.Paste")
			(net "UPI_CPU0_CPU1_P1P1_DN<13>")
		)
		(pad "V19" smd circle
			(at -21.797518 -16.683228)
			(size 0.4318 0.4318)
			(layers "F.Cu" "F.Mask" "F.Paste")
			(net "UPI_CPU0_CPU1_P1P1_DN<17>")
		)
		(pad "V21" smd circle
			(at -20.080478 -16.683228)
			(size 0.4318 0.4318)
			(layers "F.Cu" "F.Mask" "F.Paste")
			(net "GND")
		)
		(pad "V23" smd circle
			(at -18.363438 -16.683228)
			(size 0.4318 0.4318)
			(layers "F.Cu" "F.Mask" "F.Paste")
			(net "GND")
		)
		(pad "V25" smd circle
			(at -16.646398 -16.683228)
			(size 0.4318 0.4318)
			(layers "F.Cu" "F.Mask" "F.Paste")
			(net "M_H_DQ<58>")
		)
		(pad "V27" smd circle
			(at -14.929612 -16.683228)
			(size 0.4318 0.4318)
			(layers "F.Cu" "F.Mask" "F.Paste")
			(net "M_H_DQS_DP<16>")
		)
		(pad "V29" smd circle
			(at -13.212572 -16.683228)
			(size 0.4318 0.4318)
			(layers "F.Cu" "F.Mask" "F.Paste")
			(net "M_H_DQ<60>")
		)
		(pad "V31" smd circle
			(at -11.495532 -16.683228)
			(size 0.4318 0.4318)
			(layers "F.Cu" "F.Mask" "F.Paste")
			(net "M_J_DQ<42>")
		)
		(pad "V33" smd circle
			(at -9.778492 -16.683228)
			(size 0.4318 0.4318)
			(layers "F.Cu" "F.Mask" "F.Paste")
			(net "M_J_DQS_DP<14>")
		)
		(pad "V35" smd circle
			(at -8.061452 -16.683228)
			(size 0.4318 0.4318)
			(layers "F.Cu" "F.Mask" "F.Paste")
			(net "M_J_DQ<44>")
		)
		(pad "V37" smd circle
			(at -6.344412 -16.683228)
			(size 0.4318 0.4318)
			(layers "F.Cu" "F.Mask" "F.Paste")
			(net "M_J_DQ<34>")
		)
		(pad "V39" smd circle
			(at -4.627626 -16.683228)
			(size 0.4318 0.4318)
			(layers "F.Cu" "F.Mask" "F.Paste")
			(net "M_J_DQS_DP<13>")
		)
		(pad "V41" smd circle
			(at -2.910586 -16.683228)
			(size 0.4318 0.4318)
			(layers "F.Cu" "F.Mask" "F.Paste")
			(net "M_J_DQ<36>")
		)
		(pad "V43" smd circle
			(at -1.193546 -16.683228)
			(size 0.4318 0.4318)
			(layers "F.Cu" "F.Mask" "F.Paste")
			(net "GND")
		)
		(pad "V45" smd circle
			(at 2.052066 -18.483072)
			(size 0.508 0.508)
			(layers "F.Cu" "F.Mask" "F.Paste")
			(net "M_J_CS_N<7>")
		)
		(pad "V47" smd circle
			(at 3.769106 -18.483072)
			(size 0.4318 0.4318)
			(layers "F.Cu" "F.Mask" "F.Paste")
			(net "M_H_CS_N<3>")
		)
		(pad "V49" smd circle
			(at 5.485892 -18.483072)
			(size 0.4318 0.4318)
			(layers "F.Cu" "F.Mask" "F.Paste")
			(net "M_J_ODT<2>")
		)
		(pad "V51" smd circle
			(at 7.202932 -18.483072)
			(size 0.4318 0.4318)
			(layers "F.Cu" "F.Mask" "F.Paste")
			(net "M_J_CS_N<0>")
		)
		(pad "V53" smd circle
			(at 8.919972 -18.483072)
			(size 0.4318 0.4318)
			(layers "F.Cu" "F.Mask" "F.Paste")
			(net "M_J_PAR")
		)
		(pad "V55" smd circle
			(at 10.637012 -18.483072)
			(size 0.4318 0.4318)
			(layers "F.Cu" "F.Mask" "F.Paste")
			(net "M_J_CLK_DP<1>")
		)
		(pad "V57" smd circle
			(at 12.354052 -18.483072)
			(size 0.4318 0.4318)
			(layers "F.Cu" "F.Mask" "F.Paste")
			(net "M_J_CLK_DP<3>")
		)
		(pad "V59" smd circle
			(at 14.071092 -18.483072)
			(size 0.4318 0.4318)
			(layers "F.Cu" "F.Mask" "F.Paste")
			(net "M_J_MA<5>")
		)
		(pad "V61" smd circle
			(at 15.787878 -18.483072)
			(size 0.4318 0.4318)
			(layers "F.Cu" "F.Mask" "F.Paste")
			(net "M_H_MA<7>")
		)
		(pad "V63" smd circle
			(at 17.504918 -18.483072)
			(size 0.4318 0.4318)
			(layers "F.Cu" "F.Mask" "F.Paste")
			(net "M_J_CKE<2>")
		)
		(pad "V65" smd circle
			(at 19.221958 -18.483072)
			(size 0.4318 0.4318)
			(layers "F.Cu" "F.Mask" "F.Paste")
			(net "TP_CPU1_RSVD_260")
		)
		(pad "V67" smd circle
			(at 20.938998 -18.483072)
			(size 0.4318 0.4318)
			(layers "F.Cu" "F.Mask" "F.Paste")
			(net "TP_CPU1_RSVD_259")
		)
		(pad "V69" smd circle
			(at 22.656038 -18.483072)
			(size 0.4318 0.4318)
			(layers "F.Cu" "F.Mask" "F.Paste")
			(net "M_J_DQ<23>")
		)
		(pad "V71" smd circle
			(at 24.373078 -18.483072)
			(size 0.4318 0.4318)
			(layers "F.Cu" "F.Mask" "F.Paste")
			(net "M_J_DQS_DP<11>")
		)
		(pad "V73" smd circle
			(at 26.090118 -18.483072)
			(size 0.4318 0.4318)
			(layers "F.Cu" "F.Mask" "F.Paste")
			(net "GND")
		)
		(pad "V75" smd circle
			(at 27.806904 -18.483072)
			(size 0.4318 0.4318)
			(layers "F.Cu" "F.Mask" "F.Paste")
			(net "GND")
		)
		(pad "V77" smd circle
			(at 29.523944 -18.483072)
			(size 0.4318 0.4318)
			(layers "F.Cu" "F.Mask" "F.Paste")
			(net "GND")
		)
		(pad "V79" smd circle
			(at 31.240984 -18.483072)
			(size 0.4318 0.4318)
			(layers "F.Cu" "F.Mask" "F.Paste")
			(net "M_G_DQ<21>")
		)
		(pad "V81" smd circle
			(at 32.958024 -18.483072)
			(size 0.4318 0.4318)
			(layers "F.Cu" "F.Mask" "F.Paste")
			(net "M_G_DQ<16>")
		)
		(pad "V83" smd circle
			(at 34.675064 -18.483072)
			(size 0.4318 0.4318)
			(layers "F.Cu" "F.Mask" "F.Paste")
			(net "GND")
		)
		(pad "V85" smd circle
			(at 36.392104 -18.483072)
			(size 0.4318 0.4318)
			(layers "F.Cu" "F.Mask" "F.Paste")
			(net "M_G_DQS_DP<10>")
		)
		(pad "W2" smd circle
			(at -36.392104 -16.187674)
			(size 0.4318 0.4318)
			(layers "F.Cu" "F.Mask" "F.Paste")
			(net "UPI_CPU1_CPU0_P0P0_DP<3>")
		)
		(pad "W4" smd circle
			(at -34.675064 -16.187674)
			(size 0.4318 0.4318)
			(layers "F.Cu" "F.Mask" "F.Paste")
			(net "PVCCIO_CPU1")
		)
		(pad "W6" smd circle
			(at -32.958024 -16.187674)
			(size 0.4318 0.4318)
			(layers "F.Cu" "F.Mask" "F.Paste")
			(net "PVCCIO_CPU1")
		)
		(pad "W8" smd circle
			(at -31.240984 -16.187674)
			(size 0.4318 0.4318)
			(layers "F.Cu" "F.Mask" "F.Paste")
			(net "GND")
		)
		(pad "W10" smd circle
			(at -29.523944 -16.187674)
			(size 0.4318 0.4318)
			(layers "F.Cu" "F.Mask" "F.Paste")
			(net "PVCCIO_CPU1")
		)
		(pad "W12" smd circle
			(at -27.806904 -16.187674)
			(size 0.4318 0.4318)
			(layers "F.Cu" "F.Mask" "F.Paste")
			(net "GND")
		)
		(pad "W14" smd circle
			(at -26.090118 -16.187674)
			(size 0.4318 0.4318)
			(layers "F.Cu" "F.Mask" "F.Paste")
			(net "XDP_CPU_TMS")
		)
		(pad "W16" smd circle
			(at -24.373078 -16.187674)
			(size 0.4318 0.4318)
			(layers "F.Cu" "F.Mask" "F.Paste")
			(net "UPI_CPU0_CPU1_P1P1_DN<12>")
		)
		(pad "W18" smd circle
			(at -22.656038 -16.187674)
			(size 0.4318 0.4318)
			(layers "F.Cu" "F.Mask" "F.Paste")
			(net "UPI_CPU0_CPU1_P1P1_DP<13>")
		)
		(pad "W20" smd circle
			(at -20.938998 -16.187674)
			(size 0.4318 0.4318)
			(layers "F.Cu" "F.Mask" "F.Paste")
			(net "UPI_CPU0_CPU1_P1P1_DN<18>")
		)
		(pad "W22" smd circle
			(at -19.221958 -16.187674)
			(size 0.4318 0.4318)
			(layers "F.Cu" "F.Mask" "F.Paste")
			(net "GND")
		)
		(pad "W24" smd circle
			(at -17.504918 -16.187674)
			(size 0.4318 0.4318)
			(layers "F.Cu" "F.Mask" "F.Paste")
			(net "GND")
		)
		(pad "W26" smd circle
			(at -15.787878 -16.187674)
			(size 0.4318 0.4318)
			(layers "F.Cu" "F.Mask" "F.Paste")
			(net "GND")
		)
		(pad "W28" smd circle
			(at -14.071092 -16.187674)
			(size 0.4318 0.4318)
			(layers "F.Cu" "F.Mask" "F.Paste")
			(net "GND")
		)
		(pad "W30" smd circle
			(at -12.354052 -16.187674)
			(size 0.4318 0.4318)
			(layers "F.Cu" "F.Mask" "F.Paste")
			(net "GND")
		)
		(pad "W32" smd circle
			(at -10.637012 -16.187674)
			(size 0.4318 0.4318)
			(layers "F.Cu" "F.Mask" "F.Paste")
			(net "GND")
		)
		(pad "W34" smd circle
			(at -8.919972 -16.187674)
			(size 0.4318 0.4318)
			(layers "F.Cu" "F.Mask" "F.Paste")
			(net "GND")
		)
		(pad "W36" smd circle
			(at -7.202932 -16.187674)
			(size 0.4318 0.4318)
			(layers "F.Cu" "F.Mask" "F.Paste")
			(net "GND")
		)
		(pad "W38" smd circle
			(at -5.485892 -16.187674)
			(size 0.4318 0.4318)
			(layers "F.Cu" "F.Mask" "F.Paste")
			(net "GND")
		)
		(pad "W40" smd circle
			(at -3.769106 -16.187674)
			(size 0.4318 0.4318)
			(layers "F.Cu" "F.Mask" "F.Paste")
			(net "GND")
		)
		(pad "W42" smd circle
			(at -2.052066 -16.187674)
			(size 0.4318 0.4318)
			(layers "F.Cu" "F.Mask" "F.Paste")
			(net "GND")
		)
		(pad "W46" smd circle
			(at 2.910586 -17.988026)
			(size 0.4318 0.4318)
			(layers "F.Cu" "F.Mask" "F.Paste")
			(net "M_J_CS_N<2>")
		)
		(pad "W48" smd circle
			(at 4.627626 -17.988026)
			(size 0.4318 0.4318)
			(layers "F.Cu" "F.Mask" "F.Paste")
			(net "M_J_CS_N<5>")
		)
		(pad "W50" smd circle
			(at 6.344412 -17.988026)
			(size 0.4318 0.4318)
			(layers "F.Cu" "F.Mask" "F.Paste")
			(net "M_J_MA<14>")
		)
		(pad "W52" smd circle
			(at 8.061452 -17.988026)
			(size 0.4318 0.4318)
			(layers "F.Cu" "F.Mask" "F.Paste")
			(net "M_J_BA<0>")
		)
		(pad "W54" smd circle
			(at 9.778492 -17.988026)
			(size 0.4318 0.4318)
			(layers "F.Cu" "F.Mask" "F.Paste")
			(net "M_J_CLK_DN<1>")
		)
		(pad "W56" smd circle
			(at 11.495532 -17.988026)
			(size 0.4318 0.4318)
			(layers "F.Cu" "F.Mask" "F.Paste")
			(net "M_J_CLK_DN<3>")
		)
		(pad "W58" smd circle
			(at 13.212572 -17.988026)
			(size 0.4318 0.4318)
			(layers "F.Cu" "F.Mask" "F.Paste")
			(net "M_J_MA<3>")
		)
		(pad "W60" smd circle
			(at 14.929612 -17.988026)
			(size 0.4318 0.4318)
			(layers "F.Cu" "F.Mask" "F.Paste")
			(net "M_H_MA<8>")
		)
		(pad "W62" smd circle
			(at 16.646398 -17.988026)
			(size 0.4318 0.4318)
			(layers "F.Cu" "F.Mask" "F.Paste")
			(net "M_H_ALERT_N")
		)
		(pad "W64" smd circle
			(at 18.363438 -17.988026)
			(size 0.4318 0.4318)
			(layers "F.Cu" "F.Mask" "F.Paste")
			(net "PVDDQ_GHJ")
		)
		(pad "W66" smd circle
			(at 20.080478 -17.988026)
			(size 0.4318 0.4318)
			(layers "F.Cu" "F.Mask" "F.Paste")
			(net "TP_CPU1_RSVD_258")
		)
		(pad "W68" smd circle
			(at 21.797518 -17.988026)
			(size 0.4318 0.4318)
			(layers "F.Cu" "F.Mask" "F.Paste")
			(net "GND")
		)
		(pad "W70" smd circle
			(at 23.514558 -17.988026)
			(size 0.4318 0.4318)
			(layers "F.Cu" "F.Mask" "F.Paste")
			(net "M_J_DQS_DP<2>")
		)
		(pad "W72" smd circle
			(at 25.231598 -17.988026)
			(size 0.4318 0.4318)
			(layers "F.Cu" "F.Mask" "F.Paste")
			(net "M_J_DQ<16>")
		)
		(pad "W74" smd circle
			(at 26.948384 -17.988026)
			(size 0.4318 0.4318)
			(layers "F.Cu" "F.Mask" "F.Paste")
			(net "GND")
		)
		(pad "W76" smd circle
			(at 28.665424 -17.988026)
			(size 0.4318 0.4318)
			(layers "F.Cu" "F.Mask" "F.Paste")
			(net "M_J_DQ<11>")
		)
		(pad "W78" smd circle
			(at 30.382464 -17.988026)
			(size 0.4318 0.4318)
			(layers "F.Cu" "F.Mask" "F.Paste")
			(net "GND")
		)
		(pad "W80" smd circle
			(at 32.099504 -17.988026)
			(size 0.4318 0.4318)
			(layers "F.Cu" "F.Mask" "F.Paste")
			(net "M_G_DQ<20>")
		)
		(pad "W82" smd circle
			(at 33.816544 -17.988026)
			(size 0.4318 0.4318)
			(layers "F.Cu" "F.Mask" "F.Paste")
			(net "GND")
		)
		(pad "W84" smd circle
			(at 35.533584 -17.988026)
			(size 0.4318 0.4318)
			(layers "F.Cu" "F.Mask" "F.Paste")
			(net "M_G_DQ<9>")
		)
		(pad "W86" smd custom
			(at 37.250624 -17.988026 270)
			(size 0.10795 0.10795)
			(layers "F.Cu" "F.Mask" "F.Paste")
			(net "M_G_DQ<8>")
			(options
				(clearance outline)
				(anchor circle)
			)
			(primitives
				(gr_poly
					(pts
						(arc
							(start 0.2159 -0.0381)
							(mid 0 -0.254)
							(end -0.2159 -0.0381)
						)
						(arc
							(start -0.2159 0.0381)
							(mid 0 0.254)
							(end 0.2159 0.0381)
						)
					)
					(width 0)
					(fill yes)
				)
			)
		)
		(pad "Y1" smd custom
			(at -37.250624 -15.692628 90)
			(size 0.10795 0.10795)
			(layers "F.Cu" "F.Mask" "F.Paste")
			(net "UPI_CPU1_CPU0_P0P0_DN<3>")
			(options
				(clearance outline)
				(anchor circle)
			)
			(primitives
				(gr_poly
					(pts
						(arc
							(start 0.2159 -0.0381)
							(mid 0 -0.254)
							(end -0.2159 -0.0381)
						)
						(arc
							(start -0.2159 0.0381)
							(mid 0 0.254)
							(end 0.2159 0.0381)
						)
					)
					(width 0)
					(fill yes)
				)
			)
		)
		(pad "Y3" smd circle
			(at -35.533584 -15.692628)
			(size 0.4318 0.4318)
			(layers "F.Cu" "F.Mask" "F.Paste")
			(net "UPI_CPU1_CPU0_P0P0_DP<2>")
		)
		(pad "Y5" smd circle
			(at -33.816544 -15.692628)
			(size 0.4318 0.4318)
			(layers "F.Cu" "F.Mask" "F.Paste")
			(net "GND")
		)
		(pad "Y7" smd circle
			(at -32.099504 -15.692628)
			(size 0.4318 0.4318)
			(layers "F.Cu" "F.Mask" "F.Paste")
			(net "GND")
		)
		(pad "Y9" smd circle
			(at -30.382464 -15.692628)
			(size 0.4318 0.4318)
			(layers "F.Cu" "F.Mask" "F.Paste")
			(net "GND")
		)
		(pad "Y11" smd circle
			(at -28.665424 -15.692628)
			(size 0.4318 0.4318)
			(layers "F.Cu" "F.Mask" "F.Paste")
			(net "TP_XDP_CPU1_OBSDATA_B3_MBP5_N")
		)
		(pad "Y13" smd circle
			(at -26.948384 -15.692628)
			(size 0.4318 0.4318)
			(layers "F.Cu" "F.Mask" "F.Paste")
			(net "XDP_CPU_TRST_N")
		)
		(pad "Y15" smd circle
			(at -25.231598 -15.692628)
			(size 0.4318 0.4318)
			(layers "F.Cu" "F.Mask" "F.Paste")
			(net "GND")
		)
		(pad "Y17" smd circle
			(at -23.514558 -15.692628)
			(size 0.4318 0.4318)
			(layers "F.Cu" "F.Mask" "F.Paste")
			(net "GND")
		)
		(pad "Y19" smd circle
			(at -21.797518 -15.692628)
			(size 0.4318 0.4318)
			(layers "F.Cu" "F.Mask" "F.Paste")
			(net "UPI_CPU0_CPU1_P1P1_DP<17>")
		)
		(pad "Y21" smd circle
			(at -20.080478 -15.692628)
			(size 0.4318 0.4318)
			(layers "F.Cu" "F.Mask" "F.Paste")
			(net "UPI_CPU0_CPU1_P1P1_DP<18>")
		)
		(pad "Y23" smd circle
			(at -18.363438 -15.692628)
			(size 0.4318 0.4318)
			(layers "F.Cu" "F.Mask" "F.Paste")
			(net "FM_CPU1_RC_ERROR_N")
		)
		(pad "Y25" smd circle
			(at -16.646398 -15.692628)
			(size 0.4318 0.4318)
			(layers "F.Cu" "F.Mask" "F.Paste")
			(net "M_H_DQ<59>")
		)
		(pad "Y27" smd circle
			(at -14.929612 -15.692628)
			(size 0.4318 0.4318)
			(layers "F.Cu" "F.Mask" "F.Paste")
			(net "M_H_DQS_DP<7>")
		)
		(pad "Y29" smd circle
			(at -13.212572 -15.692628)
			(size 0.4318 0.4318)
			(layers "F.Cu" "F.Mask" "F.Paste")
			(net "M_H_DQ<61>")
		)
		(pad "Y31" smd circle
			(at -11.495532 -15.692628)
			(size 0.4318 0.4318)
			(layers "F.Cu" "F.Mask" "F.Paste")
			(net "M_J_DQ<43>")
		)
		(pad "Y33" smd circle
			(at -9.778492 -15.692628)
			(size 0.4318 0.4318)
			(layers "F.Cu" "F.Mask" "F.Paste")
			(net "M_J_DQS_DP<5>")
		)
		(pad "Y35" smd circle
			(at -8.061452 -15.692628)
			(size 0.4318 0.4318)
			(layers "F.Cu" "F.Mask" "F.Paste")
			(net "M_J_DQ<45>")
		)
		(pad "Y37" smd circle
			(at -6.344412 -15.692628)
			(size 0.4318 0.4318)
			(layers "F.Cu" "F.Mask" "F.Paste")
			(net "M_J_DQ<35>")
		)
		(pad "Y39" smd circle
			(at -4.627626 -15.692628)
			(size 0.4318 0.4318)
			(layers "F.Cu" "F.Mask" "F.Paste")
			(net "M_J_DQS_DP<4>")
		)
		(pad "Y41" smd circle
			(at -2.910586 -15.692628)
			(size 0.4318 0.4318)
			(layers "F.Cu" "F.Mask" "F.Paste")
			(net "M_J_DQ<37>")
		)
		(pad "Y43" smd circle
			(at -1.193546 -15.692628)
			(size 0.4318 0.4318)
			(layers "F.Cu" "F.Mask" "F.Paste")
			(net "A_CPU1_GHJ_RCOMP0")
		)
		(pad "Y45" smd circle
			(at 2.052066 -17.492726)
			(size 0.508 0.508)
			(layers "F.Cu" "F.Mask" "F.Paste")
			(net "PVDDQ_GHJ")
		)
		(pad "Y47" smd circle
			(at 3.769106 -17.492726)
			(size 0.4318 0.4318)
			(layers "F.Cu" "F.Mask" "F.Paste")
			(net "PVDDQ_GHJ")
		)
		(pad "Y49" smd circle
			(at 5.485892 -17.492726)
			(size 0.4318 0.4318)
			(layers "F.Cu" "F.Mask" "F.Paste")
			(net "PVDDQ_GHJ")
		)
		(pad "Y51" smd circle
			(at 7.202932 -17.492726)
			(size 0.4318 0.4318)
			(layers "F.Cu" "F.Mask" "F.Paste")
			(net "PVDDQ_GHJ")
		)
		(pad "Y53" smd circle
			(at 8.919972 -17.492726)
			(size 0.4318 0.4318)
			(layers "F.Cu" "F.Mask" "F.Paste")
			(net "PVDDQ_GHJ")
		)
		(pad "Y55" smd circle
			(at 10.637012 -17.492726)
			(size 0.4318 0.4318)
			(layers "F.Cu" "F.Mask" "F.Paste")
			(net "PVDDQ_GHJ")
		)
		(pad "Y57" smd circle
			(at 12.354052 -17.492726)
			(size 0.4318 0.4318)
			(layers "F.Cu" "F.Mask" "F.Paste")
			(net "PVDDQ_GHJ")
		)
		(pad "Y59" smd circle
			(at 14.071092 -17.492726)
			(size 0.4318 0.4318)
			(layers "F.Cu" "F.Mask" "F.Paste")
			(net "PVDDQ_GHJ")
		)
		(pad "Y61" smd circle
			(at 15.787878 -17.492726)
			(size 0.4318 0.4318)
			(layers "F.Cu" "F.Mask" "F.Paste")
			(net "PVDDQ_GHJ")
		)
		(pad "Y63" smd circle
			(at 17.504918 -17.492726)
			(size 0.4318 0.4318)
			(layers "F.Cu" "F.Mask" "F.Paste")
			(net "PVDDQ_GHJ")
		)
		(pad "Y65" smd circle
			(at 19.221958 -17.492726)
			(size 0.4318 0.4318)
			(layers "F.Cu" "F.Mask" "F.Paste")
			(net "TP_CPU1_RSVD_256")
		)
		(pad "Y67" smd circle
			(at 20.938998 -17.492726)
			(size 0.4318 0.4318)
			(layers "F.Cu" "F.Mask" "F.Paste")
			(net "GND")
		)
		(pad "Y69" smd circle
			(at 22.656038 -17.492726)
			(size 0.4318 0.4318)
			(layers "F.Cu" "F.Mask" "F.Paste")
			(net "M_J_DQS_DN<2>")
		)
		(pad "Y71" smd circle
			(at 24.373078 -17.492726)
			(size 0.4318 0.4318)
			(layers "F.Cu" "F.Mask" "F.Paste")
			(net "GND")
		)
		(pad "Y73" smd circle
			(at 26.090118 -17.492726)
			(size 0.4318 0.4318)
			(layers "F.Cu" "F.Mask" "F.Paste")
			(net "GND")
		)
		(pad "Y75" smd circle
			(at 27.806904 -17.492726)
			(size 0.4318 0.4318)
			(layers "F.Cu" "F.Mask" "F.Paste")
			(net "M_J_DQ<15>")
		)
		(pad "Y77" smd circle
			(at 29.523944 -17.492726)
			(size 0.4318 0.4318)
			(layers "F.Cu" "F.Mask" "F.Paste")
			(net "M_J_DQ<10>")
		)
		(pad "Y79" smd circle
			(at 31.240984 -17.492726)
			(size 0.4318 0.4318)
			(layers "F.Cu" "F.Mask" "F.Paste")
			(net "GND")
		)
		(pad "Y81" smd circle
			(at 32.958024 -17.492726)
			(size 0.4318 0.4318)
			(layers "F.Cu" "F.Mask" "F.Paste")
			(net "GND")
		)
		(pad "Y83" smd circle
			(at 34.675064 -17.492726)
			(size 0.4318 0.4318)
			(layers "F.Cu" "F.Mask" "F.Paste")
			(net "GND")
		)
		(pad "Y85" smd circle
			(at 36.392104 -17.492726)
			(size 0.4318 0.4318)
			(layers "F.Cu" "F.Mask" "F.Paste")
			(net "GND")
		)
		(zone
			(layer "F.Cu")
			(hatch none 0.5)
			(connect_pads
				(clearance 0)
			)
			(min_thickness 0.25)
			(keepout
				(tracks not_allowed)
				(vias allowed)
				(pads allowed)
				(copperpour not_allowed)
				(footprints allowed)
			)
			(placement
				(enabled no)
				(sheetname "")
			)
			(fill
				(thermal_gap 0.5)
				(thermal_bridge_width 0.5)
				(island_removal_mode 0)
			)
			(polygon
				(pts
					(arc
						(start 103.265478 -57.076086)
						(mid 102.62997 -57.076086)
						(end 103.265478 -57.076086)
					)
				)
			)
		)
		(zone
			(layer "F.Cu")
			(hatch none 0.5)
			(connect_pads
				(clearance 0)
			)
			(min_thickness 0.25)
			(keepout
				(tracks not_allowed)
				(vias allowed)
				(pads allowed)
				(copperpour not_allowed)
				(footprints allowed)
			)
			(placement
				(enabled no)
				(sheetname "")
			)
			(fill
				(thermal_gap 0.5)
				(thermal_bridge_width 0.5)
				(island_removal_mode 0)
			)
			(polygon
				(pts
					(arc
						(start 104.123744 -94.223586)
						(mid 103.488744 -94.223586)
						(end 104.123744 -94.223586)
					)
				)
			)
		)
		(zone
			(layer "F.Cu")
			(hatch none 0.5)
			(connect_pads
				(clearance 0)
			)
			(min_thickness 0.25)
			(keepout
				(tracks not_allowed)
				(vias allowed)
				(pads allowed)
				(copperpour not_allowed)
				(footprints allowed)
			)
			(placement
				(enabled no)
				(sheetname "")
			)
			(fill
				(thermal_gap 0.5)
				(thermal_bridge_width 0.5)
				(island_removal_mode 0)
			)
			(polygon
				(pts
					(arc
						(start 90.426032 -83.32724)
						(mid 89.714324 -83.32724)
						(end 90.426032 -83.32724)
					)
				)
			)
		)
		(zone
			(layer "F.Cu")
			(hatch none 0.5)
			(connect_pads
				(clearance 0)
			)
			(min_thickness 0.25)
			(keepout
				(tracks not_allowed)
				(vias allowed)
				(pads allowed)
				(copperpour not_allowed)
				(footprints allowed)
			)
			(placement
				(enabled no)
				(sheetname "")
			)
			(fill
				(thermal_gap 0.5)
				(thermal_bridge_width 0.5)
				(island_removal_mode 0)
			)
			(polygon
				(pts
					(arc
						(start 90.426032 -82.33664)
						(mid 89.714324 -82.33664)
						(end 90.426032 -82.33664)
					)
				)
			)
		)
		(zone
			(layer "F.Cu")
			(hatch none 0.5)
			(connect_pads
				(clearance 0)
			)
			(min_thickness 0.25)
			(keepout
				(tracks not_allowed)
				(vias allowed)
				(pads allowed)
				(copperpour not_allowed)
				(footprints allowed)
			)
			(placement
				(enabled no)
				(sheetname "")
			)
			(fill
				(thermal_gap 0.5)
				(thermal_bridge_width 0.5)
				(island_removal_mode 0)
			)
			(polygon
				(pts
					(arc
						(start 90.426032 -81.346294)
						(mid 89.714324 -81.346294)
						(end 90.426032 -81.346294)
					)
				)
			)
		)
		(zone
			(layer "F.Cu")
			(hatch none 0.5)
			(connect_pads
				(clearance 0)
			)
			(min_thickness 0.25)
			(keepout
				(tracks not_allowed)
				(vias allowed)
				(pads allowed)
				(copperpour not_allowed)
				(footprints allowed)
			)
			(placement
				(enabled no)
				(sheetname "")
			)
			(fill
				(thermal_gap 0.5)
				(thermal_bridge_width 0.5)
				(island_removal_mode 0)
			)
			(polygon
				(pts
					(arc
						(start 90.426032 -80.355694)
						(mid 89.714324 -80.355694)
						(end 90.426032 -80.355694)
					)
				)
			)
		)
		(zone
			(layer "F.Cu")
			(hatch none 0.5)
			(connect_pads
				(clearance 0)
			)
			(min_thickness 0.25)
			(keepout
				(tracks not_allowed)
				(vias allowed)
				(pads allowed)
				(copperpour not_allowed)
				(footprints allowed)
			)
			(placement
				(enabled no)
				(sheetname "")
			)
			(fill
				(thermal_gap 0.5)
				(thermal_bridge_width 0.5)
				(island_removal_mode 0)
			)
			(polygon
				(pts
					(arc
						(start 90.426032 -79.365094)
						(mid 89.714324 -79.365094)
						(end 90.426032 -79.365094)
					)
				)
			)
		)
		(zone
			(layer "F.Cu")
			(hatch none 0.5)
			(connect_pads
				(clearance 0)
			)
			(min_thickness 0.25)
			(keepout
				(tracks not_allowed)
				(vias allowed)
				(pads allowed)
				(copperpour not_allowed)
				(footprints allowed)
			)
			(placement
				(enabled no)
				(sheetname "")
			)
			(fill
				(thermal_gap 0.5)
				(thermal_bridge_width 0.5)
				(island_removal_mode 0)
			)
			(polygon
				(pts
					(arc
						(start 90.426032 -78.374748)
						(mid 89.714324 -78.374748)
						(end 90.426032 -78.374748)
					)
				)
			)
		)
		(zone
			(layer "F.Cu")
			(hatch none 0.5)
			(connect_pads
				(clearance 0)
			)
			(min_thickness 0.25)
			(keepout
				(tracks not_allowed)
				(vias allowed)
				(pads allowed)
				(copperpour not_allowed)
				(footprints allowed)
			)
			(placement
				(enabled no)
				(sheetname "")
			)
			(fill
				(thermal_gap 0.5)
				(thermal_bridge_width 0.5)
				(island_removal_mode 0)
			)
			(polygon
				(pts
					(arc
						(start 90.426032 -77.384148)
						(mid 89.714324 -77.384148)
						(end 90.426032 -77.384148)
					)
				)
			)
		)
		(zone
			(layer "F.Cu")
			(hatch none 0.5)
			(connect_pads
				(clearance 0)
			)
			(min_thickness 0.25)
			(keepout
				(tracks not_allowed)
				(vias allowed)
				(pads allowed)
				(copperpour not_allowed)
				(footprints allowed)
			)
			(placement
				(enabled no)
				(sheetname "")
			)
			(fill
				(thermal_gap 0.5)
				(thermal_bridge_width 0.5)
				(island_removal_mode 0)
			)
			(polygon
				(pts
					(arc
						(start 90.426032 -76.393802)
						(mid 89.714324 -76.393802)
						(end 90.426032 -76.393802)
					)
				)
			)
		)
		(zone
			(layer "F.Cu")
			(hatch none 0.5)
			(connect_pads
				(clearance 0)
			)
			(min_thickness 0.25)
			(keepout
				(tracks not_allowed)
				(vias allowed)
				(pads allowed)
				(copperpour not_allowed)
				(footprints allowed)
			)
			(placement
				(enabled no)
				(sheetname "")
			)
			(fill
				(thermal_gap 0.5)
				(thermal_bridge_width 0.5)
				(island_removal_mode 0)
			)
			(polygon
				(pts
					(arc
						(start 90.426032 -75.403202)
						(mid 89.714324 -75.403202)
						(end 90.426032 -75.403202)
					)
				)
			)
		)
		(zone
			(layer "F.Cu")
			(hatch none 0.5)
			(connect_pads
				(clearance 0)
			)
			(min_thickness 0.25)
			(keepout
				(tracks not_allowed)
				(vias allowed)
				(pads allowed)
				(copperpour not_allowed)
				(footprints allowed)
			)
			(placement
				(enabled no)
				(sheetname "")
			)
			(fill
				(thermal_gap 0.5)
				(thermal_bridge_width 0.5)
				(island_removal_mode 0)
			)
			(polygon
				(pts
					(arc
						(start 90.426032 -74.412602)
						(mid 89.714324 -74.412602)
						(end 90.426032 -74.412602)
					)
				)
			)
		)
		(zone
			(layer "F.Cu")
			(hatch none 0.5)
			(connect_pads
				(clearance 0)
			)
			(min_thickness 0.25)
			(keepout
				(tracks not_allowed)
				(vias allowed)
				(pads allowed)
				(copperpour not_allowed)
				(footprints allowed)
			)
			(placement
				(enabled no)
				(sheetname "")
			)
			(fill
				(thermal_gap 0.5)
				(thermal_bridge_width 0.5)
				(island_removal_mode 0)
			)
			(polygon
				(pts
					(arc
						(start 90.426032 -73.422256)
						(mid 89.714324 -73.422256)
						(end 90.426032 -73.422256)
					)
				)
			)
		)
		(zone
			(layer "F.Cu")
			(hatch none 0.5)
			(connect_pads
				(clearance 0)
			)
			(min_thickness 0.25)
			(keepout
				(tracks not_allowed)
				(vias allowed)
				(pads allowed)
				(copperpour not_allowed)
				(footprints allowed)
			)
			(placement
				(enabled no)
				(sheetname "")
			)
			(fill
				(thermal_gap 0.5)
				(thermal_bridge_width 0.5)
				(island_removal_mode 0)
			)
			(polygon
				(pts
					(arc
						(start 90.426032 -72.431656)
						(mid 89.714324 -72.431656)
						(end 90.426032 -72.431656)
					)
				)
			)
		)
		(zone
			(layer "F.Cu")
			(hatch none 0.5)
			(connect_pads
				(clearance 0)
			)
			(min_thickness 0.25)
			(keepout
				(tracks not_allowed)
				(vias allowed)
				(pads allowed)
				(copperpour not_allowed)
				(footprints allowed)
			)
			(placement
				(enabled no)
				(sheetname "")
			)
			(fill
				(thermal_gap 0.5)
				(thermal_bridge_width 0.5)
				(island_removal_mode 0)
			)
			(polygon
				(pts
					(arc
						(start 90.426032 -71.44131)
						(mid 89.714324 -71.44131)
						(end 90.426032 -71.44131)
					)
				)
			)
		)
		(zone
			(layer "F.Cu")
			(hatch none 0.5)
			(connect_pads
				(clearance 0)
			)
			(min_thickness 0.25)
			(keepout
				(tracks not_allowed)
				(vias allowed)
				(pads allowed)
				(copperpour not_allowed)
				(footprints allowed)
			)
			(placement
				(enabled no)
				(sheetname "")
			)
			(fill
				(thermal_gap 0.5)
				(thermal_bridge_width 0.5)
				(island_removal_mode 0)
			)
			(polygon
				(pts
					(arc
						(start 90.426032 -70.45071)
						(mid 89.714324 -70.45071)
						(end 90.426032 -70.45071)
					)
				)
			)
		)
		(zone
			(layer "F.Cu")
			(hatch none 0.5)
			(connect_pads
				(clearance 0)
			)
			(min_thickness 0.25)
			(keepout
				(tracks not_allowed)
				(vias allowed)
				(pads allowed)
				(copperpour not_allowed)
				(footprints allowed)
			)
			(placement
				(enabled no)
				(sheetname "")
			)
			(fill
				(thermal_gap 0.5)
				(thermal_bridge_width 0.5)
				(island_removal_mode 0)
			)
			(polygon
				(pts
					(arc
						(start 90.426032 -69.46011)
						(mid 89.714324 -69.46011)
						(end 90.426032 -69.46011)
					)
				)
			)
		)
		(zone
			(layer "F.Cu")
			(hatch none 0.5)
			(connect_pads
				(clearance 0)
			)
			(min_thickness 0.25)
			(keepout
				(tracks not_allowed)
				(vias allowed)
				(pads allowed)
				(copperpour not_allowed)
				(footprints allowed)
			)
			(placement
				(enabled no)
				(sheetname "")
			)
			(fill
				(thermal_gap 0.5)
				(thermal_bridge_width 0.5)
				(island_removal_mode 0)
			)
			(polygon
				(pts
					(arc
						(start 90.426032 -68.469764)
						(mid 89.714324 -68.469764)
						(end 90.426032 -68.469764)
					)
				)
			)
		)
		(zone
			(layer "F.Cu")
			(hatch none 0.5)
			(connect_pads
				(clearance 0)
			)
			(min_thickness 0.25)
			(keepout
				(tracks not_allowed)
				(vias allowed)
				(pads allowed)
				(copperpour not_allowed)
				(footprints allowed)
			)
			(placement
				(enabled no)
				(sheetname "")
			)
			(fill
				(thermal_gap 0.5)
				(thermal_bridge_width 0.5)
				(island_removal_mode 0)
			)
			(polygon
				(pts
					(arc
						(start 91.284552 -83.822286)
						(mid 90.572844 -83.822286)
						(end 91.284552 -83.822286)
					)
				)
			)
		)
		(zone
			(layer "F.Cu")
			(hatch none 0.5)
			(connect_pads
				(clearance 0)
			)
			(min_thickness 0.25)
			(keepout
				(tracks not_allowed)
				(vias allowed)
				(pads allowed)
				(copperpour not_allowed)
				(footprints allowed)
			)
			(placement
				(enabled no)
				(sheetname "")
			)
			(fill
				(thermal_gap 0.5)
				(thermal_bridge_width 0.5)
				(island_removal_mode 0)
			)
			(polygon
				(pts
					(arc
						(start 91.284552 -67.972686)
						(mid 90.572844 -67.972686)
						(end 91.284552 -67.972686)
					)
				)
			)
		)
		(zone
			(layer "F.Cu")
			(hatch none 0.5)
			(connect_pads
				(clearance 0)
			)
			(min_thickness 0.25)
			(keepout
				(tracks not_allowed)
				(vias allowed)
				(pads allowed)
				(copperpour not_allowed)
				(footprints allowed)
			)
			(placement
				(enabled no)
				(sheetname "")
			)
			(fill
				(thermal_gap 0.5)
				(thermal_bridge_width 0.5)
				(island_removal_mode 0)
			)
			(polygon
				(pts
					(arc
						(start 92.143072 -84.31784)
						(mid 91.431364 -84.31784)
						(end 92.143072 -84.31784)
					)
				)
			)
		)
		(zone
			(layer "F.Cu")
			(hatch none 0.5)
			(connect_pads
				(clearance 0)
			)
			(min_thickness 0.25)
			(keepout
				(tracks not_allowed)
				(vias allowed)
				(pads allowed)
				(copperpour not_allowed)
				(footprints allowed)
			)
			(placement
				(enabled no)
				(sheetname "")
			)
			(fill
				(thermal_gap 0.5)
				(thermal_bridge_width 0.5)
				(island_removal_mode 0)
			)
			(polygon
				(pts
					(arc
						(start 92.143072 -67.47764)
						(mid 91.431364 -67.47764)
						(end 92.143072 -67.47764)
					)
				)
			)
		)
		(zone
			(layer "F.Cu")
			(hatch none 0.5)
			(connect_pads
				(clearance 0)
			)
			(min_thickness 0.25)
			(keepout
				(tracks not_allowed)
				(vias allowed)
				(pads allowed)
				(copperpour not_allowed)
				(footprints allowed)
			)
			(placement
				(enabled no)
				(sheetname "")
			)
			(fill
				(thermal_gap 0.5)
				(thermal_bridge_width 0.5)
				(island_removal_mode 0)
			)
			(polygon
				(pts
					(arc
						(start 93.001338 -84.812886)
						(mid 92.290138 -84.812886)
						(end 93.001338 -84.812886)
					)
				)
			)
		)
		(zone
			(layer "F.Cu")
			(hatch none 0.5)
			(connect_pads
				(clearance 0)
			)
			(min_thickness 0.25)
			(keepout
				(tracks not_allowed)
				(vias allowed)
				(pads allowed)
				(copperpour not_allowed)
				(footprints allowed)
			)
			(placement
				(enabled no)
				(sheetname "")
			)
			(fill
				(thermal_gap 0.5)
				(thermal_bridge_width 0.5)
				(island_removal_mode 0)
			)
			(polygon
				(pts
					(arc
						(start 93.001338 -66.982086)
						(mid 92.290138 -66.982086)
						(end 93.001338 -66.982086)
					)
				)
			)
		)
		(zone
			(layer "F.Cu")
			(hatch none 0.5)
			(connect_pads
				(clearance 0)
			)
			(min_thickness 0.25)
			(keepout
				(tracks not_allowed)
				(vias allowed)
				(pads allowed)
				(copperpour not_allowed)
				(footprints allowed)
			)
			(placement
				(enabled no)
				(sheetname "")
			)
			(fill
				(thermal_gap 0.5)
				(thermal_bridge_width 0.5)
				(island_removal_mode 0)
			)
			(polygon
				(pts
					(arc
						(start 93.859858 -85.30844)
						(mid 93.148658 -85.30844)
						(end 93.859858 -85.30844)
					)
				)
			)
		)
		(zone
			(layer "F.Cu")
			(hatch none 0.5)
			(connect_pads
				(clearance 0)
			)
			(min_thickness 0.25)
			(keepout
				(tracks not_allowed)
				(vias allowed)
				(pads allowed)
				(copperpour not_allowed)
				(footprints allowed)
			)
			(placement
				(enabled no)
				(sheetname "")
			)
			(fill
				(thermal_gap 0.5)
				(thermal_bridge_width 0.5)
				(island_removal_mode 0)
			)
			(polygon
				(pts
					(arc
						(start 93.859858 -66.48704)
						(mid 93.148658 -66.48704)
						(end 93.859858 -66.48704)
					)
				)
			)
		)
		(zone
			(layer "F.Cu")
			(hatch none 0.5)
			(connect_pads
				(clearance 0)
			)
			(min_thickness 0.25)
			(keepout
				(tracks not_allowed)
				(vias allowed)
				(pads allowed)
				(copperpour not_allowed)
				(footprints allowed)
			)
			(placement
				(enabled no)
				(sheetname "")
			)
			(fill
				(thermal_gap 0.5)
				(thermal_bridge_width 0.5)
				(island_removal_mode 0)
			)
			(polygon
				(pts
					(arc
						(start 94.718378 -85.803486)
						(mid 94.007178 -85.803486)
						(end 94.718378 -85.803486)
					)
				)
			)
		)
		(zone
			(layer "F.Cu")
			(hatch none 0.5)
			(connect_pads
				(clearance 0)
			)
			(min_thickness 0.25)
			(keepout
				(tracks not_allowed)
				(vias allowed)
				(pads allowed)
				(copperpour not_allowed)
				(footprints allowed)
			)
			(placement
				(enabled no)
				(sheetname "")
			)
			(fill
				(thermal_gap 0.5)
				(thermal_bridge_width 0.5)
				(island_removal_mode 0)
			)
			(polygon
				(pts
					(arc
						(start 94.718378 -65.991486)
						(mid 94.007178 -65.991486)
						(end 94.718378 -65.991486)
					)
				)
			)
		)
		(zone
			(layer "F.Cu")
			(hatch none 0.5)
			(connect_pads
				(clearance 0)
			)
			(min_thickness 0.25)
			(keepout
				(tracks not_allowed)
				(vias allowed)
				(pads allowed)
				(copperpour not_allowed)
				(footprints allowed)
			)
			(placement
				(enabled no)
				(sheetname "")
			)
			(fill
				(thermal_gap 0.5)
				(thermal_bridge_width 0.5)
				(island_removal_mode 0)
			)
			(polygon
				(pts
					(arc
						(start 95.576898 -86.29904)
						(mid 94.865698 -86.29904)
						(end 95.576898 -86.29904)
					)
				)
			)
		)
		(zone
			(layer "F.Cu")
			(hatch none 0.5)
			(connect_pads
				(clearance 0)
			)
			(min_thickness 0.25)
			(keepout
				(tracks not_allowed)
				(vias allowed)
				(pads allowed)
				(copperpour not_allowed)
				(footprints allowed)
			)
			(placement
				(enabled no)
				(sheetname "")
			)
			(fill
				(thermal_gap 0.5)
				(thermal_bridge_width 0.5)
				(island_removal_mode 0)
			)
			(polygon
				(pts
					(arc
						(start 95.576898 -65.49644)
						(mid 94.865698 -65.49644)
						(end 95.576898 -65.49644)
					)
				)
			)
		)
		(zone
			(layer "F.Cu")
			(hatch none 0.5)
			(connect_pads
				(clearance 0)
			)
			(min_thickness 0.25)
			(keepout
				(tracks not_allowed)
				(vias allowed)
				(pads allowed)
				(copperpour not_allowed)
				(footprints allowed)
			)
			(placement
				(enabled no)
				(sheetname "")
			)
			(fill
				(thermal_gap 0.5)
				(thermal_bridge_width 0.5)
				(island_removal_mode 0)
			)
			(polygon
				(pts
					(arc
						(start 96.435418 -86.794086)
						(mid 95.724218 -86.794086)
						(end 96.435418 -86.794086)
					)
				)
			)
		)
		(zone
			(layer "F.Cu")
			(hatch none 0.5)
			(connect_pads
				(clearance 0)
			)
			(min_thickness 0.25)
			(keepout
				(tracks not_allowed)
				(vias allowed)
				(pads allowed)
				(copperpour not_allowed)
				(footprints allowed)
			)
			(placement
				(enabled no)
				(sheetname "")
			)
			(fill
				(thermal_gap 0.5)
				(thermal_bridge_width 0.5)
				(island_removal_mode 0)
			)
			(polygon
				(pts
					(arc
						(start 96.435418 -65.000886)
						(mid 95.724218 -65.000886)
						(end 96.435418 -65.000886)
					)
				)
			)
		)
		(zone
			(layer "F.Cu")
			(hatch none 0.5)
			(connect_pads
				(clearance 0)
			)
			(min_thickness 0.25)
			(keepout
				(tracks not_allowed)
				(vias allowed)
				(pads allowed)
				(copperpour not_allowed)
				(footprints allowed)
			)
			(placement
				(enabled no)
				(sheetname "")
			)
			(fill
				(thermal_gap 0.5)
				(thermal_bridge_width 0.5)
				(island_removal_mode 0)
			)
			(polygon
				(pts
					(arc
						(start 97.293938 -87.28964)
						(mid 96.582738 -87.28964)
						(end 97.293938 -87.28964)
					)
				)
			)
		)
		(zone
			(layer "F.Cu")
			(hatch none 0.5)
			(connect_pads
				(clearance 0)
			)
			(min_thickness 0.25)
			(keepout
				(tracks not_allowed)
				(vias allowed)
				(pads allowed)
				(copperpour not_allowed)
				(footprints allowed)
			)
			(placement
				(enabled no)
				(sheetname "")
			)
			(fill
				(thermal_gap 0.5)
				(thermal_bridge_width 0.5)
				(island_removal_mode 0)
			)
			(polygon
				(pts
					(arc
						(start 97.293938 -64.50584)
						(mid 96.582738 -64.50584)
						(end 97.293938 -64.50584)
					)
				)
			)
		)
		(zone
			(layer "F.Cu")
			(hatch none 0.5)
			(connect_pads
				(clearance 0)
			)
			(min_thickness 0.25)
			(keepout
				(tracks not_allowed)
				(vias allowed)
				(pads allowed)
				(copperpour not_allowed)
				(footprints allowed)
			)
			(placement
				(enabled no)
				(sheetname "")
			)
			(fill
				(thermal_gap 0.5)
				(thermal_bridge_width 0.5)
				(island_removal_mode 0)
			)
			(polygon
				(pts
					(arc
						(start 98.152204 -87.784686)
						(mid 97.441512 -87.784686)
						(end 98.152204 -87.784686)
					)
				)
			)
		)
		(zone
			(layer "F.Cu")
			(hatch none 0.5)
			(connect_pads
				(clearance 0)
			)
			(min_thickness 0.25)
			(keepout
				(tracks not_allowed)
				(vias allowed)
				(pads allowed)
				(copperpour not_allowed)
				(footprints allowed)
			)
			(placement
				(enabled no)
				(sheetname "")
			)
			(fill
				(thermal_gap 0.5)
				(thermal_bridge_width 0.5)
				(island_removal_mode 0)
			)
			(polygon
				(pts
					(arc
						(start 99.010724 -88.28024)
						(mid 98.300032 -88.28024)
						(end 99.010724 -88.28024)
					)
				)
			)
		)
		(zone
			(layer "F.Cu")
			(hatch none 0.5)
			(connect_pads
				(clearance 0)
			)
			(min_thickness 0.25)
			(keepout
				(tracks not_allowed)
				(vias allowed)
				(pads allowed)
				(copperpour not_allowed)
				(footprints allowed)
			)
			(placement
				(enabled no)
				(sheetname "")
			)
			(fill
				(thermal_gap 0.5)
				(thermal_bridge_width 0.5)
				(island_removal_mode 0)
			)
			(polygon
				(pts
					(arc
						(start 99.010724 -64.50584)
						(mid 98.300032 -64.50584)
						(end 99.010724 -64.50584)
					)
				)
			)
		)
		(zone
			(layer "F.Cu")
			(hatch none 0.5)
			(connect_pads
				(clearance 0)
			)
			(min_thickness 0.25)
			(keepout
				(tracks not_allowed)
				(vias allowed)
				(pads allowed)
				(copperpour not_allowed)
				(footprints allowed)
			)
			(placement
				(enabled no)
				(sheetname "")
			)
			(fill
				(thermal_gap 0.5)
				(thermal_bridge_width 0.5)
				(island_removal_mode 0)
			)
			(polygon
				(pts
					(arc
						(start 100.728018 -88.28024)
						(mid 100.01631 -88.28024)
						(end 100.728018 -88.28024)
					)
				)
			)
		)
		(zone
			(layer "F.Cu")
			(hatch none 0.5)
			(connect_pads
				(clearance 0)
			)
			(min_thickness 0.25)
			(keepout
				(tracks not_allowed)
				(vias allowed)
				(pads allowed)
				(copperpour not_allowed)
				(footprints allowed)
			)
			(placement
				(enabled no)
				(sheetname "")
			)
			(fill
				(thermal_gap 0.5)
				(thermal_bridge_width 0.5)
				(island_removal_mode 0)
			)
			(polygon
				(pts
					(arc
						(start 100.728018 -64.50584)
						(mid 100.01631 -64.50584)
						(end 100.728018 -64.50584)
					)
				)
			)
		)
		(zone
			(layer "F.Cu")
			(hatch none 0.5)
			(connect_pads
				(clearance 0)
			)
			(min_thickness 0.25)
			(keepout
				(tracks not_allowed)
				(vias allowed)
				(pads allowed)
				(copperpour not_allowed)
				(footprints allowed)
			)
			(placement
				(enabled no)
				(sheetname "")
			)
			(fill
				(thermal_gap 0.5)
				(thermal_bridge_width 0.5)
				(island_removal_mode 0)
			)
			(polygon
				(pts
					(arc
						(start 102.445058 -88.28024)
						(mid 101.73335 -88.28024)
						(end 102.445058 -88.28024)
					)
				)
			)
		)
		(zone
			(layer "F.Cu")
			(hatch none 0.5)
			(connect_pads
				(clearance 0)
			)
			(min_thickness 0.25)
			(keepout
				(tracks not_allowed)
				(vias allowed)
				(pads allowed)
				(copperpour not_allowed)
				(footprints allowed)
			)
			(placement
				(enabled no)
				(sheetname "")
			)
			(fill
				(thermal_gap 0.5)
				(thermal_bridge_width 0.5)
				(island_removal_mode 0)
			)
			(polygon
				(pts
					(arc
						(start 102.445058 -64.50584)
						(mid 101.73335 -64.50584)
						(end 102.445058 -64.50584)
					)
				)
			)
		)
		(zone
			(layer "F.Cu")
			(hatch none 0.5)
			(connect_pads
				(clearance 0)
			)
			(min_thickness 0.25)
			(keepout
				(tracks not_allowed)
				(vias allowed)
				(pads allowed)
				(copperpour not_allowed)
				(footprints allowed)
			)
			(placement
				(enabled no)
				(sheetname "")
			)
			(fill
				(thermal_gap 0.5)
				(thermal_bridge_width 0.5)
				(island_removal_mode 0)
			)
			(polygon
				(pts
					(arc
						(start 103.303578 -88.775286)
						(mid 102.59187 -88.775286)
						(end 103.303578 -88.775286)
					)
				)
			)
		)
		(zone
			(layer "F.Cu")
			(hatch none 0.5)
			(connect_pads
				(clearance 0)
			)
			(min_thickness 0.25)
			(keepout
				(tracks not_allowed)
				(vias allowed)
				(pads allowed)
				(copperpour not_allowed)
				(footprints allowed)
			)
			(placement
				(enabled no)
				(sheetname "")
			)
			(fill
				(thermal_gap 0.5)
				(thermal_bridge_width 0.5)
				(island_removal_mode 0)
			)
			(polygon
				(pts
					(arc
						(start 103.303578 -64.010286)
						(mid 102.59187 -64.010286)
						(end 103.303578 -64.010286)
					)
				)
			)
		)
		(zone
			(layer "F.Cu")
			(hatch none 0.5)
			(connect_pads
				(clearance 0)
			)
			(min_thickness 0.25)
			(keepout
				(tracks not_allowed)
				(vias allowed)
				(pads allowed)
				(copperpour not_allowed)
				(footprints allowed)
			)
			(placement
				(enabled no)
				(sheetname "")
			)
			(fill
				(thermal_gap 0.5)
				(thermal_bridge_width 0.5)
				(island_removal_mode 0)
			)
			(polygon
				(pts
					(arc
						(start 103.303578 -63.01994)
						(mid 102.59187 -63.01994)
						(end 103.303578 -63.01994)
					)
				)
			)
		)
		(zone
			(layer "F.Cu")
			(hatch none 0.5)
			(connect_pads
				(clearance 0)
			)
			(min_thickness 0.25)
			(keepout
				(tracks not_allowed)
				(vias allowed)
				(pads allowed)
				(copperpour not_allowed)
				(footprints allowed)
			)
			(placement
				(enabled no)
				(sheetname "")
			)
			(fill
				(thermal_gap 0.5)
				(thermal_bridge_width 0.5)
				(island_removal_mode 0)
			)
			(polygon
				(pts
					(arc
						(start 103.303578 -62.02934)
						(mid 102.59187 -62.02934)
						(end 103.303578 -62.02934)
					)
				)
			)
		)
		(zone
			(layer "F.Cu")
			(hatch none 0.5)
			(connect_pads
				(clearance 0)
			)
			(min_thickness 0.25)
			(keepout
				(tracks not_allowed)
				(vias allowed)
				(pads allowed)
				(copperpour not_allowed)
				(footprints allowed)
			)
			(placement
				(enabled no)
				(sheetname "")
			)
			(fill
				(thermal_gap 0.5)
				(thermal_bridge_width 0.5)
				(island_removal_mode 0)
			)
			(polygon
				(pts
					(arc
						(start 103.303578 -61.038994)
						(mid 102.59187 -61.038994)
						(end 103.303578 -61.038994)
					)
				)
			)
		)
		(zone
			(layer "F.Cu")
			(hatch none 0.5)
			(connect_pads
				(clearance 0)
			)
			(min_thickness 0.25)
			(keepout
				(tracks not_allowed)
				(vias allowed)
				(pads allowed)
				(copperpour not_allowed)
				(footprints allowed)
			)
			(placement
				(enabled no)
				(sheetname "")
			)
			(fill
				(thermal_gap 0.5)
				(thermal_bridge_width 0.5)
				(island_removal_mode 0)
			)
			(polygon
				(pts
					(arc
						(start 103.303578 -60.048394)
						(mid 102.59187 -60.048394)
						(end 103.303578 -60.048394)
					)
				)
			)
		)
		(zone
			(layer "F.Cu")
			(hatch none 0.5)
			(connect_pads
				(clearance 0)
			)
			(min_thickness 0.25)
			(keepout
				(tracks not_allowed)
				(vias allowed)
				(pads allowed)
				(copperpour not_allowed)
				(footprints allowed)
			)
			(placement
				(enabled no)
				(sheetname "")
			)
			(fill
				(thermal_gap 0.5)
				(thermal_bridge_width 0.5)
				(island_removal_mode 0)
			)
			(polygon
				(pts
					(arc
						(start 103.303578 -59.057794)
						(mid 102.59187 -59.057794)
						(end 103.303578 -59.057794)
					)
				)
			)
		)
		(zone
			(layer "F.Cu")
			(hatch none 0.5)
			(connect_pads
				(clearance 0)
			)
			(min_thickness 0.25)
			(keepout
				(tracks not_allowed)
				(vias allowed)
				(pads allowed)
				(copperpour not_allowed)
				(footprints allowed)
			)
			(placement
				(enabled no)
				(sheetname "")
			)
			(fill
				(thermal_gap 0.5)
				(thermal_bridge_width 0.5)
				(island_removal_mode 0)
			)
			(polygon
				(pts
					(arc
						(start 103.303578 -58.067448)
						(mid 102.59187 -58.067448)
						(end 103.303578 -58.067448)
					)
				)
			)
		)
		(zone
			(layer "F.Cu")
			(hatch none 0.5)
			(connect_pads
				(clearance 0)
			)
			(min_thickness 0.25)
			(keepout
				(tracks not_allowed)
				(vias allowed)
				(pads allowed)
				(copperpour not_allowed)
				(footprints allowed)
			)
			(placement
				(enabled no)
				(sheetname "")
			)
			(fill
				(thermal_gap 0.5)
				(thermal_bridge_width 0.5)
				(island_removal_mode 0)
			)
			(polygon
				(pts
					(arc
						(start 103.303578 -56.086502)
						(mid 102.59187 -56.086502)
						(end 103.303578 -56.086502)
					)
				)
			)
		)
		(zone
			(layer "F.Cu")
			(hatch none 0.5)
			(connect_pads
				(clearance 0)
			)
			(min_thickness 0.25)
			(keepout
				(tracks not_allowed)
				(vias allowed)
				(pads allowed)
				(copperpour not_allowed)
				(footprints allowed)
			)
			(placement
				(enabled no)
				(sheetname "")
			)
			(fill
				(thermal_gap 0.5)
				(thermal_bridge_width 0.5)
				(island_removal_mode 0)
			)
			(polygon
				(pts
					(arc
						(start 103.303578 -55.095902)
						(mid 102.59187 -55.095902)
						(end 103.303578 -55.095902)
					)
				)
			)
		)
		(zone
			(layer "F.Cu")
			(hatch none 0.5)
			(connect_pads
				(clearance 0)
			)
			(min_thickness 0.25)
			(keepout
				(tracks not_allowed)
				(vias allowed)
				(pads allowed)
				(copperpour not_allowed)
				(footprints allowed)
			)
			(placement
				(enabled no)
				(sheetname "")
			)
			(fill
				(thermal_gap 0.5)
				(thermal_bridge_width 0.5)
				(island_removal_mode 0)
			)
			(polygon
				(pts
					(arc
						(start 103.303578 -54.105302)
						(mid 102.59187 -54.105302)
						(end 103.303578 -54.105302)
					)
				)
			)
		)
		(zone
			(layer "F.Cu")
			(hatch none 0.5)
			(connect_pads
				(clearance 0)
			)
			(min_thickness 0.25)
			(keepout
				(tracks not_allowed)
				(vias allowed)
				(pads allowed)
				(copperpour not_allowed)
				(footprints allowed)
			)
			(placement
				(enabled no)
				(sheetname "")
			)
			(fill
				(thermal_gap 0.5)
				(thermal_bridge_width 0.5)
				(island_removal_mode 0)
			)
			(polygon
				(pts
					(arc
						(start 103.303578 -53.114956)
						(mid 102.59187 -53.114956)
						(end 103.303578 -53.114956)
					)
				)
			)
		)
		(zone
			(layer "F.Cu")
			(hatch none 0.5)
			(connect_pads
				(clearance 0)
			)
			(min_thickness 0.25)
			(keepout
				(tracks not_allowed)
				(vias allowed)
				(pads allowed)
				(copperpour not_allowed)
				(footprints allowed)
			)
			(placement
				(enabled no)
				(sheetname "")
			)
			(fill
				(thermal_gap 0.5)
				(thermal_bridge_width 0.5)
				(island_removal_mode 0)
			)
			(polygon
				(pts
					(arc
						(start 103.303578 -52.124356)
						(mid 102.59187 -52.124356)
						(end 103.303578 -52.124356)
					)
				)
			)
		)
		(zone
			(layer "F.Cu")
			(hatch none 0.5)
			(connect_pads
				(clearance 0)
			)
			(min_thickness 0.25)
			(keepout
				(tracks not_allowed)
				(vias allowed)
				(pads allowed)
				(copperpour not_allowed)
				(footprints allowed)
			)
			(placement
				(enabled no)
				(sheetname "")
			)
			(fill
				(thermal_gap 0.5)
				(thermal_bridge_width 0.5)
				(island_removal_mode 0)
			)
			(polygon
				(pts
					(arc
						(start 104.161844 -100.167186)
						(mid 103.450644 -100.167186)
						(end 104.161844 -100.167186)
					)
				)
			)
		)
		(zone
			(layer "F.Cu")
			(hatch none 0.5)
			(connect_pads
				(clearance 0)
			)
			(min_thickness 0.25)
			(keepout
				(tracks not_allowed)
				(vias allowed)
				(pads allowed)
				(copperpour not_allowed)
				(footprints allowed)
			)
			(placement
				(enabled no)
				(sheetname "")
			)
			(fill
				(thermal_gap 0.5)
				(thermal_bridge_width 0.5)
				(island_removal_mode 0)
			)
			(polygon
				(pts
					(arc
						(start 104.161844 -99.17684)
						(mid 103.450644 -99.17684)
						(end 104.161844 -99.17684)
					)
				)
			)
		)
		(zone
			(layer "F.Cu")
			(hatch none 0.5)
			(connect_pads
				(clearance 0)
			)
			(min_thickness 0.25)
			(keepout
				(tracks not_allowed)
				(vias allowed)
				(pads allowed)
				(copperpour not_allowed)
				(footprints allowed)
			)
			(placement
				(enabled no)
				(sheetname "")
			)
			(fill
				(thermal_gap 0.5)
				(thermal_bridge_width 0.5)
				(island_removal_mode 0)
			)
			(polygon
				(pts
					(arc
						(start 104.161844 -98.18624)
						(mid 103.450644 -98.18624)
						(end 104.161844 -98.18624)
					)
				)
			)
		)
		(zone
			(layer "F.Cu")
			(hatch none 0.5)
			(connect_pads
				(clearance 0)
			)
			(min_thickness 0.25)
			(keepout
				(tracks not_allowed)
				(vias allowed)
				(pads allowed)
				(copperpour not_allowed)
				(footprints allowed)
			)
			(placement
				(enabled no)
				(sheetname "")
			)
			(fill
				(thermal_gap 0.5)
				(thermal_bridge_width 0.5)
				(island_removal_mode 0)
			)
			(polygon
				(pts
					(arc
						(start 104.161844 -97.195894)
						(mid 103.450644 -97.195894)
						(end 104.161844 -97.195894)
					)
				)
			)
		)
		(zone
			(layer "F.Cu")
			(hatch none 0.5)
			(connect_pads
				(clearance 0)
			)
			(min_thickness 0.25)
			(keepout
				(tracks not_allowed)
				(vias allowed)
				(pads allowed)
				(copperpour not_allowed)
				(footprints allowed)
			)
			(placement
				(enabled no)
				(sheetname "")
			)
			(fill
				(thermal_gap 0.5)
				(thermal_bridge_width 0.5)
				(island_removal_mode 0)
			)
			(polygon
				(pts
					(arc
						(start 104.161844 -96.205294)
						(mid 103.450644 -96.205294)
						(end 104.161844 -96.205294)
					)
				)
			)
		)
		(zone
			(layer "F.Cu")
			(hatch none 0.5)
			(connect_pads
				(clearance 0)
			)
			(min_thickness 0.25)
			(keepout
				(tracks not_allowed)
				(vias allowed)
				(pads allowed)
				(copperpour not_allowed)
				(footprints allowed)
			)
			(placement
				(enabled no)
				(sheetname "")
			)
			(fill
				(thermal_gap 0.5)
				(thermal_bridge_width 0.5)
				(island_removal_mode 0)
			)
			(polygon
				(pts
					(arc
						(start 104.161844 -95.214694)
						(mid 103.450644 -95.214694)
						(end 104.161844 -95.214694)
					)
				)
			)
		)
		(zone
			(layer "F.Cu")
			(hatch none 0.5)
			(connect_pads
				(clearance 0)
			)
			(min_thickness 0.25)
			(keepout
				(tracks not_allowed)
				(vias allowed)
				(pads allowed)
				(copperpour not_allowed)
				(footprints allowed)
			)
			(placement
				(enabled no)
				(sheetname "")
			)
			(fill
				(thermal_gap 0.5)
				(thermal_bridge_width 0.5)
				(island_removal_mode 0)
			)
			(polygon
				(pts
					(arc
						(start 104.161844 -93.233748)
						(mid 103.450644 -93.233748)
						(end 104.161844 -93.233748)
					)
				)
			)
		)
		(zone
			(layer "F.Cu")
			(hatch none 0.5)
			(connect_pads
				(clearance 0)
			)
			(min_thickness 0.25)
			(keepout
				(tracks not_allowed)
				(vias allowed)
				(pads allowed)
				(copperpour not_allowed)
				(footprints allowed)
			)
			(placement
				(enabled no)
				(sheetname "")
			)
			(fill
				(thermal_gap 0.5)
				(thermal_bridge_width 0.5)
				(island_removal_mode 0)
			)
			(polygon
				(pts
					(arc
						(start 104.161844 -92.243402)
						(mid 103.450644 -92.243402)
						(end 104.161844 -92.243402)
					)
				)
			)
		)
		(zone
			(layer "F.Cu")
			(hatch none 0.5)
			(connect_pads
				(clearance 0)
			)
			(min_thickness 0.25)
			(keepout
				(tracks not_allowed)
				(vias allowed)
				(pads allowed)
				(copperpour not_allowed)
				(footprints allowed)
			)
			(placement
				(enabled no)
				(sheetname "")
			)
			(fill
				(thermal_gap 0.5)
				(thermal_bridge_width 0.5)
				(island_removal_mode 0)
			)
			(polygon
				(pts
					(arc
						(start 104.161844 -91.252802)
						(mid 103.450644 -91.252802)
						(end 104.161844 -91.252802)
					)
				)
			)
		)
		(zone
			(layer "F.Cu")
			(hatch none 0.5)
			(connect_pads
				(clearance 0)
			)
			(min_thickness 0.25)
			(keepout
				(tracks not_allowed)
				(vias allowed)
				(pads allowed)
				(copperpour not_allowed)
				(footprints allowed)
			)
			(placement
				(enabled no)
				(sheetname "")
			)
			(fill
				(thermal_gap 0.5)
				(thermal_bridge_width 0.5)
				(island_removal_mode 0)
			)
			(polygon
				(pts
					(arc
						(start 104.161844 -90.262202)
						(mid 103.450644 -90.262202)
						(end 104.161844 -90.262202)
					)
				)
			)
		)
		(zone
			(layer "F.Cu")
			(hatch none 0.5)
			(connect_pads
				(clearance 0)
			)
			(min_thickness 0.25)
			(keepout
				(tracks not_allowed)
				(vias allowed)
				(pads allowed)
				(copperpour not_allowed)
				(footprints allowed)
			)
			(placement
				(enabled no)
				(sheetname "")
			)
			(fill
				(thermal_gap 0.5)
				(thermal_bridge_width 0.5)
				(island_removal_mode 0)
			)
			(polygon
				(pts
					(arc
						(start 104.161844 -89.271856)
						(mid 103.450644 -89.271856)
						(end 104.161844 -89.271856)
					)
				)
			)
		)
		(zone
			(layer "F.Cu")
			(hatch none 0.5)
			(connect_pads
				(clearance 0)
			)
			(min_thickness 0.25)
			(keepout
				(tracks not_allowed)
				(vias allowed)
				(pads allowed)
				(copperpour not_allowed)
				(footprints allowed)
			)
			(placement
				(enabled no)
				(sheetname "")
			)
			(fill
				(thermal_gap 0.5)
				(thermal_bridge_width 0.5)
				(island_removal_mode 0)
			)
			(polygon
				(pts
					(arc
						(start 106.548936 -63.828168)
						(mid 105.837736 -63.828168)
						(end 106.548936 -63.828168)
					)
				)
			)
		)
		(zone
			(layer "F.Cu")
			(hatch none 0.5)
			(connect_pads
				(clearance 0)
			)
			(min_thickness 0.25)
			(keepout
				(tracks not_allowed)
				(vias allowed)
				(pads allowed)
				(copperpour not_allowed)
				(footprints allowed)
			)
			(placement
				(enabled no)
				(sheetname "")
			)
			(fill
				(thermal_gap 0.5)
				(thermal_bridge_width 0.5)
				(island_removal_mode 0)
			)
			(polygon
				(pts
					(arc
						(start 106.548936 -62.837822)
						(mid 105.837736 -62.837822)
						(end 106.548936 -62.837822)
					)
				)
			)
		)
		(zone
			(layer "F.Cu")
			(hatch none 0.5)
			(connect_pads
				(clearance 0)
			)
			(min_thickness 0.25)
			(keepout
				(tracks not_allowed)
				(vias allowed)
				(pads allowed)
				(copperpour not_allowed)
				(footprints allowed)
			)
			(placement
				(enabled no)
				(sheetname "")
			)
			(fill
				(thermal_gap 0.5)
				(thermal_bridge_width 0.5)
				(island_removal_mode 0)
			)
			(polygon
				(pts
					(arc
						(start 106.548936 -61.847222)
						(mid 105.837736 -61.847222)
						(end 106.548936 -61.847222)
					)
				)
			)
		)
		(zone
			(layer "F.Cu")
			(hatch none 0.5)
			(connect_pads
				(clearance 0)
			)
			(min_thickness 0.25)
			(keepout
				(tracks not_allowed)
				(vias allowed)
				(pads allowed)
				(copperpour not_allowed)
				(footprints allowed)
			)
			(placement
				(enabled no)
				(sheetname "")
			)
			(fill
				(thermal_gap 0.5)
				(thermal_bridge_width 0.5)
				(island_removal_mode 0)
			)
			(polygon
				(pts
					(arc
						(start 106.548936 -60.856622)
						(mid 105.837736 -60.856622)
						(end 106.548936 -60.856622)
					)
				)
			)
		)
		(zone
			(layer "F.Cu")
			(hatch none 0.5)
			(connect_pads
				(clearance 0)
			)
			(min_thickness 0.25)
			(keepout
				(tracks not_allowed)
				(vias allowed)
				(pads allowed)
				(copperpour not_allowed)
				(footprints allowed)
			)
			(placement
				(enabled no)
				(sheetname "")
			)
			(fill
				(thermal_gap 0.5)
				(thermal_bridge_width 0.5)
				(island_removal_mode 0)
			)
			(polygon
				(pts
					(arc
						(start 106.548936 -59.866276)
						(mid 105.837736 -59.866276)
						(end 106.548936 -59.866276)
					)
				)
			)
		)
		(zone
			(layer "F.Cu")
			(hatch none 0.5)
			(connect_pads
				(clearance 0)
			)
			(min_thickness 0.25)
			(keepout
				(tracks not_allowed)
				(vias allowed)
				(pads allowed)
				(copperpour not_allowed)
				(footprints allowed)
			)
			(placement
				(enabled no)
				(sheetname "")
			)
			(fill
				(thermal_gap 0.5)
				(thermal_bridge_width 0.5)
				(island_removal_mode 0)
			)
			(polygon
				(pts
					(arc
						(start 106.548936 -58.875676)
						(mid 105.837736 -58.875676)
						(end 106.548936 -58.875676)
					)
				)
			)
		)
		(zone
			(layer "F.Cu")
			(hatch none 0.5)
			(connect_pads
				(clearance 0)
			)
			(min_thickness 0.25)
			(keepout
				(tracks not_allowed)
				(vias allowed)
				(pads allowed)
				(copperpour not_allowed)
				(footprints allowed)
			)
			(placement
				(enabled no)
				(sheetname "")
			)
			(fill
				(thermal_gap 0.5)
				(thermal_bridge_width 0.5)
				(island_removal_mode 0)
			)
			(polygon
				(pts
					(arc
						(start 106.548936 -57.88533)
						(mid 105.837736 -57.88533)
						(end 106.548936 -57.88533)
					)
				)
			)
		)
		(zone
			(layer "F.Cu")
			(hatch none 0.5)
			(connect_pads
				(clearance 0)
			)
			(min_thickness 0.25)
			(keepout
				(tracks not_allowed)
				(vias allowed)
				(pads allowed)
				(copperpour not_allowed)
				(footprints allowed)
			)
			(placement
				(enabled no)
				(sheetname "")
			)
			(fill
				(thermal_gap 0.5)
				(thermal_bridge_width 0.5)
				(island_removal_mode 0)
			)
			(polygon
				(pts
					(arc
						(start 106.548936 -56.89473)
						(mid 105.837736 -56.89473)
						(end 106.548936 -56.89473)
					)
				)
			)
		)
		(zone
			(layer "F.Cu")
			(hatch none 0.5)
			(connect_pads
				(clearance 0)
			)
			(min_thickness 0.25)
			(keepout
				(tracks not_allowed)
				(vias allowed)
				(pads allowed)
				(copperpour not_allowed)
				(footprints allowed)
			)
			(placement
				(enabled no)
				(sheetname "")
			)
			(fill
				(thermal_gap 0.5)
				(thermal_bridge_width 0.5)
				(island_removal_mode 0)
			)
			(polygon
				(pts
					(arc
						(start 106.548936 -55.90413)
						(mid 105.837736 -55.90413)
						(end 106.548936 -55.90413)
					)
				)
			)
		)
		(zone
			(layer "F.Cu")
			(hatch none 0.5)
			(connect_pads
				(clearance 0)
			)
			(min_thickness 0.25)
			(keepout
				(tracks not_allowed)
				(vias allowed)
				(pads allowed)
				(copperpour not_allowed)
				(footprints allowed)
			)
			(placement
				(enabled no)
				(sheetname "")
			)
			(fill
				(thermal_gap 0.5)
				(thermal_bridge_width 0.5)
				(island_removal_mode 0)
			)
			(polygon
				(pts
					(arc
						(start 106.548936 -54.913784)
						(mid 105.837736 -54.913784)
						(end 106.548936 -54.913784)
					)
				)
			)
		)
		(zone
			(layer "F.Cu")
			(hatch none 0.5)
			(connect_pads
				(clearance 0)
			)
			(min_thickness 0.25)
			(keepout
				(tracks not_allowed)
				(vias allowed)
				(pads allowed)
				(copperpour not_allowed)
				(footprints allowed)
			)
			(placement
				(enabled no)
				(sheetname "")
			)
			(fill
				(thermal_gap 0.5)
				(thermal_bridge_width 0.5)
				(island_removal_mode 0)
			)
			(polygon
				(pts
					(arc
						(start 106.548936 -53.923184)
						(mid 105.837736 -53.923184)
						(end 106.548936 -53.923184)
					)
				)
			)
		)
		(zone
			(layer "F.Cu")
			(hatch none 0.5)
			(connect_pads
				(clearance 0)
			)
			(min_thickness 0.25)
			(keepout
				(tracks not_allowed)
				(vias allowed)
				(pads allowed)
				(copperpour not_allowed)
				(footprints allowed)
			)
			(placement
				(enabled no)
				(sheetname "")
			)
			(fill
				(thermal_gap 0.5)
				(thermal_bridge_width 0.5)
				(island_removal_mode 0)
			)
			(polygon
				(pts
					(arc
						(start 106.548936 -52.932838)
						(mid 105.837736 -52.932838)
						(end 106.548936 -52.932838)
					)
				)
			)
		)
		(zone
			(layer "F.Cu")
			(hatch none 0.5)
			(connect_pads
				(clearance 0)
			)
			(min_thickness 0.25)
			(keepout
				(tracks not_allowed)
				(vias allowed)
				(pads allowed)
				(copperpour not_allowed)
				(footprints allowed)
			)
			(placement
				(enabled no)
				(sheetname "")
			)
			(fill
				(thermal_gap 0.5)
				(thermal_bridge_width 0.5)
				(island_removal_mode 0)
			)
			(polygon
				(pts
					(arc
						(start 107.407202 -100.975668)
						(mid 106.69651 -100.975668)
						(end 107.407202 -100.975668)
					)
				)
			)
		)
		(zone
			(layer "F.Cu")
			(hatch none 0.5)
			(connect_pads
				(clearance 0)
			)
			(min_thickness 0.25)
			(keepout
				(tracks not_allowed)
				(vias allowed)
				(pads allowed)
				(copperpour not_allowed)
				(footprints allowed)
			)
			(placement
				(enabled no)
				(sheetname "")
			)
			(fill
				(thermal_gap 0.5)
				(thermal_bridge_width 0.5)
				(island_removal_mode 0)
			)
			(polygon
				(pts
					(arc
						(start 107.407202 -99.985068)
						(mid 106.69651 -99.985068)
						(end 107.407202 -99.985068)
					)
				)
			)
		)
		(zone
			(layer "F.Cu")
			(hatch none 0.5)
			(connect_pads
				(clearance 0)
			)
			(min_thickness 0.25)
			(keepout
				(tracks not_allowed)
				(vias allowed)
				(pads allowed)
				(copperpour not_allowed)
				(footprints allowed)
			)
			(placement
				(enabled no)
				(sheetname "")
			)
			(fill
				(thermal_gap 0.5)
				(thermal_bridge_width 0.5)
				(island_removal_mode 0)
			)
			(polygon
				(pts
					(arc
						(start 107.407202 -98.994722)
						(mid 106.69651 -98.994722)
						(end 107.407202 -98.994722)
					)
				)
			)
		)
		(zone
			(layer "F.Cu")
			(hatch none 0.5)
			(connect_pads
				(clearance 0)
			)
			(min_thickness 0.25)
			(keepout
				(tracks not_allowed)
				(vias allowed)
				(pads allowed)
				(copperpour not_allowed)
				(footprints allowed)
			)
			(placement
				(enabled no)
				(sheetname "")
			)
			(fill
				(thermal_gap 0.5)
				(thermal_bridge_width 0.5)
				(island_removal_mode 0)
			)
			(polygon
				(pts
					(arc
						(start 107.407202 -98.004122)
						(mid 106.69651 -98.004122)
						(end 107.407202 -98.004122)
					)
				)
			)
		)
		(zone
			(layer "F.Cu")
			(hatch none 0.5)
			(connect_pads
				(clearance 0)
			)
			(min_thickness 0.25)
			(keepout
				(tracks not_allowed)
				(vias allowed)
				(pads allowed)
				(copperpour not_allowed)
				(footprints allowed)
			)
			(placement
				(enabled no)
				(sheetname "")
			)
			(fill
				(thermal_gap 0.5)
				(thermal_bridge_width 0.5)
				(island_removal_mode 0)
			)
			(polygon
				(pts
					(arc
						(start 107.407202 -97.013522)
						(mid 106.69651 -97.013522)
						(end 107.407202 -97.013522)
					)
				)
			)
		)
		(zone
			(layer "F.Cu")
			(hatch none 0.5)
			(connect_pads
				(clearance 0)
			)
			(min_thickness 0.25)
			(keepout
				(tracks not_allowed)
				(vias allowed)
				(pads allowed)
				(copperpour not_allowed)
				(footprints allowed)
			)
			(placement
				(enabled no)
				(sheetname "")
			)
			(fill
				(thermal_gap 0.5)
				(thermal_bridge_width 0.5)
				(island_removal_mode 0)
			)
			(polygon
				(pts
					(arc
						(start 107.407202 -96.023176)
						(mid 106.69651 -96.023176)
						(end 107.407202 -96.023176)
					)
				)
			)
		)
		(zone
			(layer "F.Cu")
			(hatch none 0.5)
			(connect_pads
				(clearance 0)
			)
			(min_thickness 0.25)
			(keepout
				(tracks not_allowed)
				(vias allowed)
				(pads allowed)
				(copperpour not_allowed)
				(footprints allowed)
			)
			(placement
				(enabled no)
				(sheetname "")
			)
			(fill
				(thermal_gap 0.5)
				(thermal_bridge_width 0.5)
				(island_removal_mode 0)
			)
			(polygon
				(pts
					(arc
						(start 107.407202 -95.032576)
						(mid 106.69651 -95.032576)
						(end 107.407202 -95.032576)
					)
				)
			)
		)
		(zone
			(layer "F.Cu")
			(hatch none 0.5)
			(connect_pads
				(clearance 0)
			)
			(min_thickness 0.25)
			(keepout
				(tracks not_allowed)
				(vias allowed)
				(pads allowed)
				(copperpour not_allowed)
				(footprints allowed)
			)
			(placement
				(enabled no)
				(sheetname "")
			)
			(fill
				(thermal_gap 0.5)
				(thermal_bridge_width 0.5)
				(island_removal_mode 0)
			)
			(polygon
				(pts
					(arc
						(start 107.407202 -94.04223)
						(mid 106.69651 -94.04223)
						(end 107.407202 -94.04223)
					)
				)
			)
		)
		(zone
			(layer "F.Cu")
			(hatch none 0.5)
			(connect_pads
				(clearance 0)
			)
			(min_thickness 0.25)
			(keepout
				(tracks not_allowed)
				(vias allowed)
				(pads allowed)
				(copperpour not_allowed)
				(footprints allowed)
			)
			(placement
				(enabled no)
				(sheetname "")
			)
			(fill
				(thermal_gap 0.5)
				(thermal_bridge_width 0.5)
				(island_removal_mode 0)
			)
			(polygon
				(pts
					(arc
						(start 107.407202 -93.05163)
						(mid 106.69651 -93.05163)
						(end 107.407202 -93.05163)
					)
				)
			)
		)
		(zone
			(layer "F.Cu")
			(hatch none 0.5)
			(connect_pads
				(clearance 0)
			)
			(min_thickness 0.25)
			(keepout
				(tracks not_allowed)
				(vias allowed)
				(pads allowed)
				(copperpour not_allowed)
				(footprints allowed)
			)
			(placement
				(enabled no)
				(sheetname "")
			)
			(fill
				(thermal_gap 0.5)
				(thermal_bridge_width 0.5)
				(island_removal_mode 0)
			)
			(polygon
				(pts
					(arc
						(start 107.407202 -92.06103)
						(mid 106.69651 -92.06103)
						(end 107.407202 -92.06103)
					)
				)
			)
		)
		(zone
			(layer "F.Cu")
			(hatch none 0.5)
			(connect_pads
				(clearance 0)
			)
			(min_thickness 0.25)
			(keepout
				(tracks not_allowed)
				(vias allowed)
				(pads allowed)
				(copperpour not_allowed)
				(footprints allowed)
			)
			(placement
				(enabled no)
				(sheetname "")
			)
			(fill
				(thermal_gap 0.5)
				(thermal_bridge_width 0.5)
				(island_removal_mode 0)
			)
			(polygon
				(pts
					(arc
						(start 107.407202 -91.070684)
						(mid 106.69651 -91.070684)
						(end 107.407202 -91.070684)
					)
				)
			)
		)
		(zone
			(layer "F.Cu")
			(hatch none 0.5)
			(connect_pads
				(clearance 0)
			)
			(min_thickness 0.25)
			(keepout
				(tracks not_allowed)
				(vias allowed)
				(pads allowed)
				(copperpour not_allowed)
				(footprints allowed)
			)
			(placement
				(enabled no)
				(sheetname "")
			)
			(fill
				(thermal_gap 0.5)
				(thermal_bridge_width 0.5)
				(island_removal_mode 0)
			)
			(polygon
				(pts
					(arc
						(start 107.407202 -90.080084)
						(mid 106.69651 -90.080084)
						(end 107.407202 -90.080084)
					)
				)
			)
		)
		(zone
			(layer "F.Cu")
			(hatch none 0.5)
			(connect_pads
				(clearance 0)
			)
			(min_thickness 0.25)
			(keepout
				(tracks not_allowed)
				(vias allowed)
				(pads allowed)
				(copperpour not_allowed)
				(footprints allowed)
			)
			(placement
				(enabled no)
				(sheetname "")
			)
			(fill
				(thermal_gap 0.5)
				(thermal_bridge_width 0.5)
				(island_removal_mode 0)
			)
			(polygon
				(pts
					(arc
						(start 107.407202 -89.089738)
						(mid 106.69651 -89.089738)
						(end 107.407202 -89.089738)
					)
				)
			)
		)
		(zone
			(layer "F.Cu")
			(hatch none 0.5)
			(connect_pads
				(clearance 0)
			)
			(min_thickness 0.25)
			(keepout
				(tracks not_allowed)
				(vias allowed)
				(pads allowed)
				(copperpour not_allowed)
				(footprints allowed)
			)
			(placement
				(enabled no)
				(sheetname "")
			)
			(fill
				(thermal_gap 0.5)
				(thermal_bridge_width 0.5)
				(island_removal_mode 0)
			)
			(polygon
				(pts
					(arc
						(start 107.407202 -64.324738)
						(mid 106.69651 -64.324738)
						(end 107.407202 -64.324738)
					)
				)
			)
		)
		(zone
			(layer "F.Cu")
			(hatch none 0.5)
			(connect_pads
				(clearance 0)
			)
			(min_thickness 0.25)
			(keepout
				(tracks not_allowed)
				(vias allowed)
				(pads allowed)
				(copperpour not_allowed)
				(footprints allowed)
			)
			(placement
				(enabled no)
				(sheetname "")
			)
			(fill
				(thermal_gap 0.5)
				(thermal_bridge_width 0.5)
				(island_removal_mode 0)
			)
			(polygon
				(pts
					(arc
						(start 108.265722 -88.594184)
						(mid 107.55503 -88.594184)
						(end 108.265722 -88.594184)
					)
				)
			)
		)
		(zone
			(layer "F.Cu")
			(hatch none 0.5)
			(connect_pads
				(clearance 0)
			)
			(min_thickness 0.25)
			(keepout
				(tracks not_allowed)
				(vias allowed)
				(pads allowed)
				(copperpour not_allowed)
				(footprints allowed)
			)
			(placement
				(enabled no)
				(sheetname "")
			)
			(fill
				(thermal_gap 0.5)
				(thermal_bridge_width 0.5)
				(island_removal_mode 0)
			)
			(polygon
				(pts
					(arc
						(start 108.265722 -64.819784)
						(mid 107.55503 -64.819784)
						(end 108.265722 -64.819784)
					)
				)
			)
		)
		(zone
			(layer "F.Cu")
			(hatch none 0.5)
			(connect_pads
				(clearance 0)
			)
			(min_thickness 0.25)
			(keepout
				(tracks not_allowed)
				(vias allowed)
				(pads allowed)
				(copperpour not_allowed)
				(footprints allowed)
			)
			(placement
				(enabled no)
				(sheetname "")
			)
			(fill
				(thermal_gap 0.5)
				(thermal_bridge_width 0.5)
				(island_removal_mode 0)
			)
			(polygon
				(pts
					(arc
						(start 109.982762 -88.594184)
						(mid 109.27207 -88.594184)
						(end 109.982762 -88.594184)
					)
				)
			)
		)
		(zone
			(layer "F.Cu")
			(hatch none 0.5)
			(connect_pads
				(clearance 0)
			)
			(min_thickness 0.25)
			(keepout
				(tracks not_allowed)
				(vias allowed)
				(pads allowed)
				(copperpour not_allowed)
				(footprints allowed)
			)
			(placement
				(enabled no)
				(sheetname "")
			)
			(fill
				(thermal_gap 0.5)
				(thermal_bridge_width 0.5)
				(island_removal_mode 0)
			)
			(polygon
				(pts
					(arc
						(start 109.982762 -64.819784)
						(mid 109.27207 -64.819784)
						(end 109.982762 -64.819784)
					)
				)
			)
		)
		(zone
			(layer "F.Cu")
			(hatch none 0.5)
			(connect_pads
				(clearance 0)
			)
			(min_thickness 0.25)
			(keepout
				(tracks not_allowed)
				(vias allowed)
				(pads allowed)
				(copperpour not_allowed)
				(footprints allowed)
			)
			(placement
				(enabled no)
				(sheetname "")
			)
			(fill
				(thermal_gap 0.5)
				(thermal_bridge_width 0.5)
				(island_removal_mode 0)
			)
			(polygon
				(pts
					(arc
						(start 111.700056 -88.594184)
						(mid 110.988348 -88.594184)
						(end 111.700056 -88.594184)
					)
				)
			)
		)
		(zone
			(layer "F.Cu")
			(hatch none 0.5)
			(connect_pads
				(clearance 0)
			)
			(min_thickness 0.25)
			(keepout
				(tracks not_allowed)
				(vias allowed)
				(pads allowed)
				(copperpour not_allowed)
				(footprints allowed)
			)
			(placement
				(enabled no)
				(sheetname "")
			)
			(fill
				(thermal_gap 0.5)
				(thermal_bridge_width 0.5)
				(island_removal_mode 0)
			)
			(polygon
				(pts
					(arc
						(start 111.700056 -64.819784)
						(mid 110.988348 -64.819784)
						(end 111.700056 -64.819784)
					)
				)
			)
		)
		(zone
			(layer "F.Cu")
			(hatch none 0.5)
			(connect_pads
				(clearance 0)
			)
			(min_thickness 0.25)
			(keepout
				(tracks not_allowed)
				(vias allowed)
				(pads allowed)
				(copperpour not_allowed)
				(footprints allowed)
			)
			(placement
				(enabled no)
				(sheetname "")
			)
			(fill
				(thermal_gap 0.5)
				(thermal_bridge_width 0.5)
				(island_removal_mode 0)
			)
			(polygon
				(pts
					(arc
						(start 112.558576 -65.315338)
						(mid 111.846868 -65.315338)
						(end 112.558576 -65.315338)
					)
				)
			)
		)
		(zone
			(layer "F.Cu")
			(hatch none 0.5)
			(connect_pads
				(clearance 0)
			)
			(min_thickness 0.25)
			(keepout
				(tracks not_allowed)
				(vias allowed)
				(pads allowed)
				(copperpour not_allowed)
				(footprints allowed)
			)
			(placement
				(enabled no)
				(sheetname "")
			)
			(fill
				(thermal_gap 0.5)
				(thermal_bridge_width 0.5)
				(island_removal_mode 0)
			)
			(polygon
				(pts
					(arc
						(start 113.416842 -88.594184)
						(mid 112.705642 -88.594184)
						(end 113.416842 -88.594184)
					)
				)
			)
		)
		(zone
			(layer "F.Cu")
			(hatch none 0.5)
			(connect_pads
				(clearance 0)
			)
			(min_thickness 0.25)
			(keepout
				(tracks not_allowed)
				(vias allowed)
				(pads allowed)
				(copperpour not_allowed)
				(footprints allowed)
			)
			(placement
				(enabled no)
				(sheetname "")
			)
			(fill
				(thermal_gap 0.5)
				(thermal_bridge_width 0.5)
				(island_removal_mode 0)
			)
			(polygon
				(pts
					(arc
						(start 113.416842 -65.810384)
						(mid 112.705642 -65.810384)
						(end 113.416842 -65.810384)
					)
				)
			)
		)
		(zone
			(layer "F.Cu")
			(hatch none 0.5)
			(connect_pads
				(clearance 0)
			)
			(min_thickness 0.25)
			(keepout
				(tracks not_allowed)
				(vias allowed)
				(pads allowed)
				(copperpour not_allowed)
				(footprints allowed)
			)
			(placement
				(enabled no)
				(sheetname "")
			)
			(fill
				(thermal_gap 0.5)
				(thermal_bridge_width 0.5)
				(island_removal_mode 0)
			)
			(polygon
				(pts
					(arc
						(start 114.275362 -88.099138)
						(mid 113.564162 -88.099138)
						(end 114.275362 -88.099138)
					)
				)
			)
		)
		(zone
			(layer "F.Cu")
			(hatch none 0.5)
			(connect_pads
				(clearance 0)
			)
			(min_thickness 0.25)
			(keepout
				(tracks not_allowed)
				(vias allowed)
				(pads allowed)
				(copperpour not_allowed)
				(footprints allowed)
			)
			(placement
				(enabled no)
				(sheetname "")
			)
			(fill
				(thermal_gap 0.5)
				(thermal_bridge_width 0.5)
				(island_removal_mode 0)
			)
			(polygon
				(pts
					(arc
						(start 114.275362 -66.305938)
						(mid 113.564162 -66.305938)
						(end 114.275362 -66.305938)
					)
				)
			)
		)
		(zone
			(layer "F.Cu")
			(hatch none 0.5)
			(connect_pads
				(clearance 0)
			)
			(min_thickness 0.25)
			(keepout
				(tracks not_allowed)
				(vias allowed)
				(pads allowed)
				(copperpour not_allowed)
				(footprints allowed)
			)
			(placement
				(enabled no)
				(sheetname "")
			)
			(fill
				(thermal_gap 0.5)
				(thermal_bridge_width 0.5)
				(island_removal_mode 0)
			)
			(polygon
				(pts
					(arc
						(start 115.133882 -87.603584)
						(mid 114.422682 -87.603584)
						(end 115.133882 -87.603584)
					)
				)
			)
		)
		(zone
			(layer "F.Cu")
			(hatch none 0.5)
			(connect_pads
				(clearance 0)
			)
			(min_thickness 0.25)
			(keepout
				(tracks not_allowed)
				(vias allowed)
				(pads allowed)
				(copperpour not_allowed)
				(footprints allowed)
			)
			(placement
				(enabled no)
				(sheetname "")
			)
			(fill
				(thermal_gap 0.5)
				(thermal_bridge_width 0.5)
				(island_removal_mode 0)
			)
			(polygon
				(pts
					(arc
						(start 115.133882 -66.800984)
						(mid 114.422682 -66.800984)
						(end 115.133882 -66.800984)
					)
				)
			)
		)
		(zone
			(layer "F.Cu")
			(hatch none 0.5)
			(connect_pads
				(clearance 0)
			)
			(min_thickness 0.25)
			(keepout
				(tracks not_allowed)
				(vias allowed)
				(pads allowed)
				(copperpour not_allowed)
				(footprints allowed)
			)
			(placement
				(enabled no)
				(sheetname "")
			)
			(fill
				(thermal_gap 0.5)
				(thermal_bridge_width 0.5)
				(island_removal_mode 0)
			)
			(polygon
				(pts
					(arc
						(start 115.992402 -87.108538)
						(mid 115.281202 -87.108538)
						(end 115.992402 -87.108538)
					)
				)
			)
		)
		(zone
			(layer "F.Cu")
			(hatch none 0.5)
			(connect_pads
				(clearance 0)
			)
			(min_thickness 0.25)
			(keepout
				(tracks not_allowed)
				(vias allowed)
				(pads allowed)
				(copperpour not_allowed)
				(footprints allowed)
			)
			(placement
				(enabled no)
				(sheetname "")
			)
			(fill
				(thermal_gap 0.5)
				(thermal_bridge_width 0.5)
				(island_removal_mode 0)
			)
			(polygon
				(pts
					(arc
						(start 115.992402 -67.296538)
						(mid 115.281202 -67.296538)
						(end 115.992402 -67.296538)
					)
				)
			)
		)
		(zone
			(layer "F.Cu")
			(hatch none 0.5)
			(connect_pads
				(clearance 0)
			)
			(min_thickness 0.25)
			(keepout
				(tracks not_allowed)
				(vias allowed)
				(pads allowed)
				(copperpour not_allowed)
				(footprints allowed)
			)
			(placement
				(enabled no)
				(sheetname "")
			)
			(fill
				(thermal_gap 0.5)
				(thermal_bridge_width 0.5)
				(island_removal_mode 0)
			)
			(polygon
				(pts
					(arc
						(start 116.850922 -86.612984)
						(mid 116.139722 -86.612984)
						(end 116.850922 -86.612984)
					)
				)
			)
		)
		(zone
			(layer "F.Cu")
			(hatch none 0.5)
			(connect_pads
				(clearance 0)
			)
			(min_thickness 0.25)
			(keepout
				(tracks not_allowed)
				(vias allowed)
				(pads allowed)
				(copperpour not_allowed)
				(footprints allowed)
			)
			(placement
				(enabled no)
				(sheetname "")
			)
			(fill
				(thermal_gap 0.5)
				(thermal_bridge_width 0.5)
				(island_removal_mode 0)
			)
			(polygon
				(pts
					(arc
						(start 116.850922 -67.791584)
						(mid 116.139722 -67.791584)
						(end 116.850922 -67.791584)
					)
				)
			)
		)
		(zone
			(layer "F.Cu")
			(hatch none 0.5)
			(connect_pads
				(clearance 0)
			)
			(min_thickness 0.25)
			(keepout
				(tracks not_allowed)
				(vias allowed)
				(pads allowed)
				(copperpour not_allowed)
				(footprints allowed)
			)
			(placement
				(enabled no)
				(sheetname "")
			)
			(fill
				(thermal_gap 0.5)
				(thermal_bridge_width 0.5)
				(island_removal_mode 0)
			)
			(polygon
				(pts
					(arc
						(start 117.709442 -86.117938)
						(mid 116.998242 -86.117938)
						(end 117.709442 -86.117938)
					)
				)
			)
		)
		(zone
			(layer "F.Cu")
			(hatch none 0.5)
			(connect_pads
				(clearance 0)
			)
			(min_thickness 0.25)
			(keepout
				(tracks not_allowed)
				(vias allowed)
				(pads allowed)
				(copperpour not_allowed)
				(footprints allowed)
			)
			(placement
				(enabled no)
				(sheetname "")
			)
			(fill
				(thermal_gap 0.5)
				(thermal_bridge_width 0.5)
				(island_removal_mode 0)
			)
			(polygon
				(pts
					(arc
						(start 117.709442 -68.287138)
						(mid 116.998242 -68.287138)
						(end 117.709442 -68.287138)
					)
				)
			)
		)
		(zone
			(layer "F.Cu")
			(hatch none 0.5)
			(connect_pads
				(clearance 0)
			)
			(min_thickness 0.25)
			(keepout
				(tracks not_allowed)
				(vias allowed)
				(pads allowed)
				(copperpour not_allowed)
				(footprints allowed)
			)
			(placement
				(enabled no)
				(sheetname "")
			)
			(fill
				(thermal_gap 0.5)
				(thermal_bridge_width 0.5)
				(island_removal_mode 0)
			)
			(polygon
				(pts
					(arc
						(start 118.567708 -85.622384)
						(mid 117.857016 -85.622384)
						(end 118.567708 -85.622384)
					)
				)
			)
		)
		(zone
			(layer "F.Cu")
			(hatch none 0.5)
			(connect_pads
				(clearance 0)
			)
			(min_thickness 0.25)
			(keepout
				(tracks not_allowed)
				(vias allowed)
				(pads allowed)
				(copperpour not_allowed)
				(footprints allowed)
			)
			(placement
				(enabled no)
				(sheetname "")
			)
			(fill
				(thermal_gap 0.5)
				(thermal_bridge_width 0.5)
				(island_removal_mode 0)
			)
			(polygon
				(pts
					(arc
						(start 118.567708 -68.782184)
						(mid 117.857016 -68.782184)
						(end 118.567708 -68.782184)
					)
				)
			)
		)
		(zone
			(layer "F.Cu")
			(hatch none 0.5)
			(connect_pads
				(clearance 0)
			)
			(min_thickness 0.25)
			(keepout
				(tracks not_allowed)
				(vias allowed)
				(pads allowed)
				(copperpour not_allowed)
				(footprints allowed)
			)
			(placement
				(enabled no)
				(sheetname "")
			)
			(fill
				(thermal_gap 0.5)
				(thermal_bridge_width 0.5)
				(island_removal_mode 0)
			)
			(polygon
				(pts
					(arc
						(start 119.426228 -85.127338)
						(mid 118.715536 -85.127338)
						(end 119.426228 -85.127338)
					)
				)
			)
		)
		(zone
			(layer "F.Cu")
			(hatch none 0.5)
			(connect_pads
				(clearance 0)
			)
			(min_thickness 0.25)
			(keepout
				(tracks not_allowed)
				(vias allowed)
				(pads allowed)
				(copperpour not_allowed)
				(footprints allowed)
			)
			(placement
				(enabled no)
				(sheetname "")
			)
			(fill
				(thermal_gap 0.5)
				(thermal_bridge_width 0.5)
				(island_removal_mode 0)
			)
			(polygon
				(pts
					(arc
						(start 119.426228 -69.277738)
						(mid 118.715536 -69.277738)
						(end 119.426228 -69.277738)
					)
				)
			)
		)
		(zone
			(layer "F.Cu")
			(hatch none 0.5)
			(connect_pads
				(clearance 0)
			)
			(min_thickness 0.25)
			(keepout
				(tracks not_allowed)
				(vias allowed)
				(pads allowed)
				(copperpour not_allowed)
				(footprints allowed)
			)
			(placement
				(enabled no)
				(sheetname "")
			)
			(fill
				(thermal_gap 0.5)
				(thermal_bridge_width 0.5)
				(island_removal_mode 0)
			)
			(polygon
				(pts
					(arc
						(start 120.284748 -84.63026)
						(mid 119.574056 -84.63026)
						(end 120.284748 -84.63026)
					)
				)
			)
		)
		(zone
			(layer "F.Cu")
			(hatch none 0.5)
			(connect_pads
				(clearance 0)
			)
			(min_thickness 0.25)
			(keepout
				(tracks not_allowed)
				(vias allowed)
				(pads allowed)
				(copperpour not_allowed)
				(footprints allowed)
			)
			(placement
				(enabled no)
				(sheetname "")
			)
			(fill
				(thermal_gap 0.5)
				(thermal_bridge_width 0.5)
				(island_removal_mode 0)
			)
			(polygon
				(pts
					(arc
						(start 120.284748 -83.639914)
						(mid 119.574056 -83.639914)
						(end 120.284748 -83.639914)
					)
				)
			)
		)
		(zone
			(layer "F.Cu")
			(hatch none 0.5)
			(connect_pads
				(clearance 0)
			)
			(min_thickness 0.25)
			(keepout
				(tracks not_allowed)
				(vias allowed)
				(pads allowed)
				(copperpour not_allowed)
				(footprints allowed)
			)
			(placement
				(enabled no)
				(sheetname "")
			)
			(fill
				(thermal_gap 0.5)
				(thermal_bridge_width 0.5)
				(island_removal_mode 0)
			)
			(polygon
				(pts
					(arc
						(start 120.284748 -82.649314)
						(mid 119.574056 -82.649314)
						(end 120.284748 -82.649314)
					)
				)
			)
		)
		(zone
			(layer "F.Cu")
			(hatch none 0.5)
			(connect_pads
				(clearance 0)
			)
			(min_thickness 0.25)
			(keepout
				(tracks not_allowed)
				(vias allowed)
				(pads allowed)
				(copperpour not_allowed)
				(footprints allowed)
			)
			(placement
				(enabled no)
				(sheetname "")
			)
			(fill
				(thermal_gap 0.5)
				(thermal_bridge_width 0.5)
				(island_removal_mode 0)
			)
			(polygon
				(pts
					(arc
						(start 120.284748 -81.658714)
						(mid 119.574056 -81.658714)
						(end 120.284748 -81.658714)
					)
				)
			)
		)
		(zone
			(layer "F.Cu")
			(hatch none 0.5)
			(connect_pads
				(clearance 0)
			)
			(min_thickness 0.25)
			(keepout
				(tracks not_allowed)
				(vias allowed)
				(pads allowed)
				(copperpour not_allowed)
				(footprints allowed)
			)
			(placement
				(enabled no)
				(sheetname "")
			)
			(fill
				(thermal_gap 0.5)
				(thermal_bridge_width 0.5)
				(island_removal_mode 0)
			)
			(polygon
				(pts
					(arc
						(start 120.284748 -80.668368)
						(mid 119.574056 -80.668368)
						(end 120.284748 -80.668368)
					)
				)
			)
		)
		(zone
			(layer "F.Cu")
			(hatch none 0.5)
			(connect_pads
				(clearance 0)
			)
			(min_thickness 0.25)
			(keepout
				(tracks not_allowed)
				(vias allowed)
				(pads allowed)
				(copperpour not_allowed)
				(footprints allowed)
			)
			(placement
				(enabled no)
				(sheetname "")
			)
			(fill
				(thermal_gap 0.5)
				(thermal_bridge_width 0.5)
				(island_removal_mode 0)
			)
			(polygon
				(pts
					(arc
						(start 120.284748 -79.677768)
						(mid 119.574056 -79.677768)
						(end 120.284748 -79.677768)
					)
				)
			)
		)
		(zone
			(layer "F.Cu")
			(hatch none 0.5)
			(connect_pads
				(clearance 0)
			)
			(min_thickness 0.25)
			(keepout
				(tracks not_allowed)
				(vias allowed)
				(pads allowed)
				(copperpour not_allowed)
				(footprints allowed)
			)
			(placement
				(enabled no)
				(sheetname "")
			)
			(fill
				(thermal_gap 0.5)
				(thermal_bridge_width 0.5)
				(island_removal_mode 0)
			)
			(polygon
				(pts
					(arc
						(start 120.284748 -78.687422)
						(mid 119.574056 -78.687422)
						(end 120.284748 -78.687422)
					)
				)
			)
		)
		(zone
			(layer "F.Cu")
			(hatch none 0.5)
			(connect_pads
				(clearance 0)
			)
			(min_thickness 0.25)
			(keepout
				(tracks not_allowed)
				(vias allowed)
				(pads allowed)
				(copperpour not_allowed)
				(footprints allowed)
			)
			(placement
				(enabled no)
				(sheetname "")
			)
			(fill
				(thermal_gap 0.5)
				(thermal_bridge_width 0.5)
				(island_removal_mode 0)
			)
			(polygon
				(pts
					(arc
						(start 120.284748 -77.696822)
						(mid 119.574056 -77.696822)
						(end 120.284748 -77.696822)
					)
				)
			)
		)
		(zone
			(layer "F.Cu")
			(hatch none 0.5)
			(connect_pads
				(clearance 0)
			)
			(min_thickness 0.25)
			(keepout
				(tracks not_allowed)
				(vias allowed)
				(pads allowed)
				(copperpour not_allowed)
				(footprints allowed)
			)
			(placement
				(enabled no)
				(sheetname "")
			)
			(fill
				(thermal_gap 0.5)
				(thermal_bridge_width 0.5)
				(island_removal_mode 0)
			)
			(polygon
				(pts
					(arc
						(start 120.284748 -76.706222)
						(mid 119.574056 -76.706222)
						(end 120.284748 -76.706222)
					)
				)
			)
		)
		(zone
			(layer "F.Cu")
			(hatch none 0.5)
			(connect_pads
				(clearance 0)
			)
			(min_thickness 0.25)
			(keepout
				(tracks not_allowed)
				(vias allowed)
				(pads allowed)
				(copperpour not_allowed)
				(footprints allowed)
			)
			(placement
				(enabled no)
				(sheetname "")
			)
			(fill
				(thermal_gap 0.5)
				(thermal_bridge_width 0.5)
				(island_removal_mode 0)
			)
			(polygon
				(pts
					(arc
						(start 120.284748 -75.715876)
						(mid 119.574056 -75.715876)
						(end 120.284748 -75.715876)
					)
				)
			)
		)
		(zone
			(layer "F.Cu")
			(hatch none 0.5)
			(connect_pads
				(clearance 0)
			)
			(min_thickness 0.25)
			(keepout
				(tracks not_allowed)
				(vias allowed)
				(pads allowed)
				(copperpour not_allowed)
				(footprints allowed)
			)
			(placement
				(enabled no)
				(sheetname "")
			)
			(fill
				(thermal_gap 0.5)
				(thermal_bridge_width 0.5)
				(island_removal_mode 0)
			)
			(polygon
				(pts
					(arc
						(start 120.284748 -74.725276)
						(mid 119.574056 -74.725276)
						(end 120.284748 -74.725276)
					)
				)
			)
		)
		(zone
			(layer "F.Cu")
			(hatch none 0.5)
			(connect_pads
				(clearance 0)
			)
			(min_thickness 0.25)
			(keepout
				(tracks not_allowed)
				(vias allowed)
				(pads allowed)
				(copperpour not_allowed)
				(footprints allowed)
			)
			(placement
				(enabled no)
				(sheetname "")
			)
			(fill
				(thermal_gap 0.5)
				(thermal_bridge_width 0.5)
				(island_removal_mode 0)
			)
			(polygon
				(pts
					(arc
						(start 120.284748 -73.73493)
						(mid 119.574056 -73.73493)
						(end 120.284748 -73.73493)
					)
				)
			)
		)
		(zone
			(layer "F.Cu")
			(hatch none 0.5)
			(connect_pads
				(clearance 0)
			)
			(min_thickness 0.25)
			(keepout
				(tracks not_allowed)
				(vias allowed)
				(pads allowed)
				(copperpour not_allowed)
				(footprints allowed)
			)
			(placement
				(enabled no)
				(sheetname "")
			)
			(fill
				(thermal_gap 0.5)
				(thermal_bridge_width 0.5)
				(island_removal_mode 0)
			)
			(polygon
				(pts
					(arc
						(start 120.284748 -72.74433)
						(mid 119.574056 -72.74433)
						(end 120.284748 -72.74433)
					)
				)
			)
		)
		(zone
			(layer "F.Cu")
			(hatch none 0.5)
			(connect_pads
				(clearance 0)
			)
			(min_thickness 0.25)
			(keepout
				(tracks not_allowed)
				(vias allowed)
				(pads allowed)
				(copperpour not_allowed)
				(footprints allowed)
			)
			(placement
				(enabled no)
				(sheetname "")
			)
			(fill
				(thermal_gap 0.5)
				(thermal_bridge_width 0.5)
				(island_removal_mode 0)
			)
			(polygon
				(pts
					(arc
						(start 120.284748 -71.75373)
						(mid 119.574056 -71.75373)
						(end 120.284748 -71.75373)
					)
				)
			)
		)
		(zone
			(layer "F.Cu")
			(hatch none 0.5)
			(connect_pads
				(clearance 0)
			)
			(min_thickness 0.25)
			(keepout
				(tracks not_allowed)
				(vias allowed)
				(pads allowed)
				(copperpour not_allowed)
				(footprints allowed)
			)
			(placement
				(enabled no)
				(sheetname "")
			)
			(fill
				(thermal_gap 0.5)
				(thermal_bridge_width 0.5)
				(island_removal_mode 0)
			)
			(polygon
				(pts
					(arc
						(start 120.284748 -70.763384)
						(mid 119.574056 -70.763384)
						(end 120.284748 -70.763384)
					)
				)
			)
		)
		(zone
			(layer "F.Cu")
			(hatch none 0.5)
			(connect_pads
				(clearance 0)
			)
			(min_thickness 0.25)
			(keepout
				(tracks not_allowed)
				(vias allowed)
				(pads allowed)
				(copperpour not_allowed)
				(footprints allowed)
			)
			(placement
				(enabled no)
				(sheetname "")
			)
			(fill
				(thermal_gap 0.5)
				(thermal_bridge_width 0.5)
				(island_removal_mode 0)
			)
			(polygon
				(pts
					(arc
						(start 120.284748 -69.772784)
						(mid 119.574056 -69.772784)
						(end 120.284748 -69.772784)
					)
				)
			)
		)
		(zone
			(layer "F.Cu")
			(hatch none 0.5)
			(connect_pads
				(clearance 0)
			)
			(min_thickness 0.25)
			(keepout
				(tracks not_allowed)
				(vias allowed)
				(pads allowed)
				(copperpour not_allowed)
				(footprints allowed)
			)
			(placement
				(enabled no)
				(sheetname "")
			)
			(fill
				(thermal_gap 0.5)
				(thermal_bridge_width 0.5)
				(island_removal_mode 0)
			)
			(polygon
				(pts
					(xy 134.307072 -51.46929) (xy 134.306564 -51.45913) (xy 134.30631 -51.447192) (xy 134.29742 -51.447192)
					(arc
						(start 134.264654 -51.447192)
						(mid 134.256213 -51.447535)
						(end 134.24789 -51.44897)
					)
					(arc
						(start 134.24789 -51.44897)
						(mid 134.233322 -51.455209)
						(end 134.221474 -51.465734)
					)
					(arc
						(start 134.216902 -51.472338)
						(mid 134.211132 -51.485872)
						(end 134.20979 -51.500532)
					)
					(arc
						(start 134.20979 -51.500532)
						(mid 134.523253 -51.764978)
						(end 134.835138 -51.4985)
					)
					(xy 134.83463 -51.491642) (xy 134.834122 -51.487832) (xy 134.833106 -51.48453) (xy 134.831582 -51.479196)
					(xy 134.82955 -51.475132) (xy 134.824216 -51.467004) (xy 134.821676 -51.46421) (xy 134.816088 -51.458622)
					(xy 134.81431 -51.457352) (xy 134.811262 -51.454812) (xy 134.80923 -51.453796) (xy 134.807706 -51.453034)
					(xy 134.80669 -51.452526) (xy 134.804658 -51.45151) (xy 134.802626 -51.451002) (xy 134.7978 -51.449224)
					(xy 134.79145 -51.4477) (xy 134.788148 -51.447192) (xy 134.782052 -51.447192) (xy 134.776972 -51.447192)
					(xy 134.752588 -51.447192) (xy 134.738364 -51.447192)
					(arc
						(start 134.736586 -51.473354)
						(mid 134.732718 -51.496306)
						(end 134.725918 -51.518566)
					)
					(arc
						(start 134.720584 -51.533044)
						(mid 134.709363 -51.555503)
						(end 134.695184 -51.576224)
					)
					(xy 134.681976 -51.592226)
					(arc
						(start 134.655052 -51.617118)
						(mid 134.642061 -51.625458)
						(end 134.629652 -51.634644)
					)
					(arc
						(start 134.629652 -51.634644)
						(mid 134.600568 -51.648273)
						(end 134.569962 -51.658012)
					)
					(arc
						(start 134.569962 -51.658012)
						(mid 134.547032 -51.662214)
						(end 134.523734 -51.663092)
					)
					(arc
						(start 134.490206 -51.660806)
						(mid 134.458369 -51.652931)
						(end 134.427722 -51.641248)
					)
					(arc
						(start 134.427722 -51.641248)
						(mid 134.404632 -51.628376)
						(end 134.383272 -51.6128)
					)
					(arc
						(start 134.383272 -51.6128)
						(mid 134.361632 -51.591248)
						(end 134.342632 -51.567334)
					)
					(arc
						(start 134.342632 -51.567334)
						(mid 134.329643 -51.544227)
						(end 134.319264 -51.519836)
					)
					(arc
						(start 134.319264 -51.519836)
						(mid 134.313344 -51.500753)
						(end 134.309104 -51.481228)
					)
					(xy 134.308342 -51.47691)
				)
			)
		)
		(zone
			(layer "F.Cu")
			(hatch none 0.5)
			(connect_pads
				(clearance 0)
			)
			(min_thickness 0.25)
			(keepout
				(tracks not_allowed)
				(vias allowed)
				(pads allowed)
				(copperpour not_allowed)
				(footprints allowed)
			)
			(placement
				(enabled no)
				(sheetname "")
			)
			(fill
				(thermal_gap 0.5)
				(thermal_bridge_width 0.5)
				(island_removal_mode 0)
			)
			(polygon
				(pts
					(xy 68.629022 -82.056478) (xy 68.619116 -82.056986) (xy 68.607178 -82.056986) (xy 68.607178 -82.06613)
					(arc
						(start 68.607178 -82.098896)
						(mid 68.607423 -82.107324)
						(end 68.608702 -82.11566)
					)
					(arc
						(start 68.608702 -82.11566)
						(mid 68.614917 -82.130251)
						(end 68.625466 -82.142076)
					)
					(arc
						(start 68.63207 -82.146648)
						(mid 68.645604 -82.152418)
						(end 68.660264 -82.15376)
					)
					(arc
						(start 68.660264 -82.15376)
						(mid 68.92471 -81.840422)
						(end 68.658486 -81.528412)
					)
					(xy 68.651374 -81.52892) (xy 68.647818 -81.529428) (xy 68.644516 -81.530444) (xy 68.639182 -81.531968)
					(xy 68.634864 -81.534) (xy 68.62699 -81.539334) (xy 68.623942 -81.541874) (xy 68.618608 -81.547208)
					(xy 68.617338 -81.54924) (xy 68.614798 -81.552288) (xy 68.613782 -81.55432) (xy 68.612766 -81.55559)
					(xy 68.612512 -81.556606) (xy 68.612258 -81.55686) (xy 68.611496 -81.558892) (xy 68.610734 -81.560924)
					(xy 68.60921 -81.565496) (xy 68.607686 -81.5721) (xy 68.607178 -81.575402) (xy 68.607178 -81.581498)
					(xy 68.607178 -81.586578) (xy 68.607178 -81.610708) (xy 68.607178 -81.625186)
					(arc
						(start 68.633086 -81.626964)
						(mid 68.656163 -81.630828)
						(end 68.678552 -81.637632)
					)
					(arc
						(start 68.69303 -81.642966)
						(mid 68.715489 -81.654187)
						(end 68.73621 -81.668366)
					)
					(xy 68.751958 -81.681574)
					(arc
						(start 68.777104 -81.708498)
						(mid 68.78532 -81.721483)
						(end 68.794376 -81.733898)
					)
					(arc
						(start 68.794376 -81.733898)
						(mid 68.808128 -81.762975)
						(end 68.817998 -81.793588)
					)
					(arc
						(start 68.817998 -81.793588)
						(mid 68.8222 -81.816518)
						(end 68.823078 -81.839816)
					)
					(arc
						(start 68.820792 -81.873344)
						(mid 68.812809 -81.905196)
						(end 68.80098 -81.935828)
					)
					(arc
						(start 68.80098 -81.935828)
						(mid 68.788242 -81.958915)
						(end 68.772786 -81.980278)
					)
					(arc
						(start 68.772786 -81.980278)
						(mid 68.751234 -82.001918)
						(end 68.72732 -82.020918)
					)
					(arc
						(start 68.72732 -82.020918)
						(mid 68.704091 -82.033924)
						(end 68.679568 -82.044286)
					)
					(arc
						(start 68.679568 -82.044286)
						(mid 68.660485 -82.050206)
						(end 68.64096 -82.054446)
					)
					(xy 68.636896 -82.055208)
				)
			)
		)
		(zone
			(layer "F.Cu")
			(hatch none 0.5)
			(connect_pads
				(clearance 0)
			)
			(min_thickness 0.25)
			(keepout
				(tracks not_allowed)
				(vias allowed)
				(pads allowed)
				(copperpour not_allowed)
				(footprints allowed)
			)
			(placement
				(enabled no)
				(sheetname "")
			)
			(fill
				(thermal_gap 0.5)
				(thermal_bridge_width 0.5)
				(island_removal_mode 0)
			)
			(polygon
				(pts
					(xy 68.629784 -81.065878) (xy 68.619624 -81.066386) (xy 68.607686 -81.066386) (xy 68.60794 -81.07553)
					(arc
						(start 68.60794 -81.108296)
						(mid 68.608185 -81.116724)
						(end 68.609464 -81.12506)
					)
					(arc
						(start 68.609464 -81.12506)
						(mid 68.615679 -81.139651)
						(end 68.626228 -81.151476)
					)
					(arc
						(start 68.632832 -81.156048)
						(mid 68.646366 -81.161818)
						(end 68.661026 -81.16316)
					)
					(arc
						(start 68.661026 -81.16316)
						(mid 68.925472 -80.849822)
						(end 68.659248 -80.537812)
					)
					(xy 68.652136 -80.53832) (xy 68.64858 -80.538828) (xy 68.645278 -80.539844) (xy 68.63969 -80.541368)
					(xy 68.635626 -80.5434) (xy 68.627498 -80.548734) (xy 68.624704 -80.551274) (xy 68.619116 -80.556608)
					(xy 68.6181 -80.55864) (xy 68.61556 -80.561688) (xy 68.614544 -80.56372) (xy 68.613528 -80.56499)
					(xy 68.613274 -80.566006) (xy 68.61302 -80.56626) (xy 68.612004 -80.568292) (xy 68.611496 -80.570324)
					(xy 68.609718 -80.574896) (xy 68.608194 -80.5815) (xy 68.60794 -80.584802) (xy 68.607686 -80.590898)
					(xy 68.607686 -80.595978) (xy 68.60794 -80.620108) (xy 68.607686 -80.634586)
					(arc
						(start 68.633848 -80.636364)
						(mid 68.656925 -80.640228)
						(end 68.679314 -80.647032)
					)
					(arc
						(start 68.693792 -80.652366)
						(mid 68.716251 -80.663587)
						(end 68.736972 -80.677766)
					)
					(xy 68.75272 -80.690974)
					(arc
						(start 68.777612 -80.717898)
						(mid 68.785952 -80.730889)
						(end 68.795138 -80.743298)
					)
					(arc
						(start 68.795138 -80.743298)
						(mid 68.808767 -80.772382)
						(end 68.818506 -80.802988)
					)
					(arc
						(start 68.818506 -80.802988)
						(mid 68.82286 -80.825908)
						(end 68.82384 -80.849216)
					)
					(arc
						(start 68.8213 -80.882744)
						(mid 68.813453 -80.914592)
						(end 68.801742 -80.945228)
					)
					(arc
						(start 68.801742 -80.945228)
						(mid 68.78887 -80.968318)
						(end 68.773294 -80.989678)
					)
					(arc
						(start 68.773294 -80.989678)
						(mid 68.751872 -81.011315)
						(end 68.728082 -81.030318)
					)
					(arc
						(start 68.728082 -81.030318)
						(mid 68.704853 -81.043324)
						(end 68.68033 -81.053686)
					)
					(arc
						(start 68.68033 -81.053686)
						(mid 68.661247 -81.059606)
						(end 68.641722 -81.063846)
					)
					(xy 68.637658 -81.064608)
				)
			)
		)
		(zone
			(layer "F.Cu")
			(hatch none 0.5)
			(connect_pads
				(clearance 0)
			)
			(min_thickness 0.25)
			(keepout
				(tracks not_allowed)
				(vias allowed)
				(pads allowed)
				(copperpour not_allowed)
				(footprints allowed)
			)
			(placement
				(enabled no)
				(sheetname "")
			)
			(fill
				(thermal_gap 0.5)
				(thermal_bridge_width 0.5)
				(island_removal_mode 0)
			)
			(polygon
				(pts
					(xy 68.629784 -72.149716) (xy 68.619878 -72.150224) (xy 68.60794 -72.150478) (xy 68.60794 -72.159368)
					(arc
						(start 68.60794 -72.192134)
						(mid 68.608185 -72.200562)
						(end 68.609464 -72.208898)
					)
					(arc
						(start 68.609464 -72.208898)
						(mid 68.615679 -72.223489)
						(end 68.626228 -72.235314)
					)
					(arc
						(start 68.632832 -72.239886)
						(mid 68.646482 -72.245762)
						(end 68.66128 -72.246998)
					)
					(arc
						(start 68.66128 -72.246998)
						(mid 68.925726 -71.933535)
						(end 68.659248 -71.62165)
					)
					(xy 68.65239 -71.622158) (xy 68.64858 -71.622666) (xy 68.645278 -71.623936) (xy 68.639944 -71.625206)
					(xy 68.635626 -71.627238) (xy 68.627752 -71.632572) (xy 68.624704 -71.635112) (xy 68.61937 -71.6407)
					(xy 68.6181 -71.642478) (xy 68.61556 -71.645526) (xy 68.614544 -71.647558) (xy 68.613782 -71.649082)
					(xy 68.613274 -71.650098) (xy 68.61302 -71.650098) (xy 68.612258 -71.65213) (xy 68.611496 -71.654162)
					(xy 68.609972 -71.658988) (xy 68.608448 -71.665338) (xy 68.60794 -71.66864) (xy 68.60794 -71.674736)
					(xy 68.60794 -71.679816) (xy 68.60794 -71.7042) (xy 68.60794 -71.718424)
					(arc
						(start 68.634102 -71.720202)
						(mid 68.657054 -71.72407)
						(end 68.679314 -71.73087)
					)
					(arc
						(start 68.693792 -71.736204)
						(mid 68.716251 -71.747425)
						(end 68.736972 -71.761604)
					)
					(xy 68.75272 -71.774812)
					(arc
						(start 68.777866 -71.801736)
						(mid 68.786206 -71.814727)
						(end 68.795392 -71.827136)
					)
					(arc
						(start 68.795392 -71.827136)
						(mid 68.809021 -71.85622)
						(end 68.81876 -71.886826)
					)
					(arc
						(start 68.81876 -71.886826)
						(mid 68.822962 -71.909756)
						(end 68.82384 -71.933054)
					)
					(arc
						(start 68.821554 -71.966836)
						(mid 68.813685 -71.998552)
						(end 68.801996 -72.029066)
					)
					(arc
						(start 68.801996 -72.029066)
						(mid 68.789124 -72.052156)
						(end 68.773548 -72.073516)
					)
					(arc
						(start 68.773548 -72.073516)
						(mid 68.751996 -72.095156)
						(end 68.728082 -72.114156)
					)
					(arc
						(start 68.728082 -72.114156)
						(mid 68.704853 -72.127162)
						(end 68.68033 -72.137524)
					)
					(arc
						(start 68.68033 -72.137524)
						(mid 68.661247 -72.143444)
						(end 68.641722 -72.147684)
					)
					(xy 68.637658 -72.148446)
				)
			)
		)
		(zone
			(layer "F.Cu")
			(hatch none 0.5)
			(connect_pads
				(clearance 0)
			)
			(min_thickness 0.25)
			(keepout
				(tracks not_allowed)
				(vias allowed)
				(pads allowed)
				(copperpour not_allowed)
				(footprints allowed)
			)
			(placement
				(enabled no)
				(sheetname "")
			)
			(fill
				(thermal_gap 0.5)
				(thermal_bridge_width 0.5)
				(island_removal_mode 0)
			)
			(polygon
				(pts
					(xy 68.629784 -71.16064) (xy 68.619624 -71.161148) (xy 68.607686 -71.161402) (xy 68.607686 -71.170292)
					(arc
						(start 68.607686 -71.203058)
						(mid 68.608029 -71.211499)
						(end 68.609464 -71.219822)
					)
					(arc
						(start 68.609464 -71.219822)
						(mid 68.61557 -71.234379)
						(end 68.625974 -71.246238)
					)
					(arc
						(start 68.632578 -71.25081)
						(mid 68.646209 -71.25679)
						(end 68.661026 -71.258176)
					)
					(arc
						(start 68.661026 -71.258176)
						(mid 68.925934 -70.944479)
						(end 68.658994 -70.632574)
					)
					(xy 68.652136 -70.633082) (xy 68.648326 -70.63359) (xy 68.645024 -70.63486) (xy 68.63969 -70.636384)
					(xy 68.635372 -70.638416) (xy 68.627498 -70.643496) (xy 68.624704 -70.64629) (xy 68.619116 -70.651624)
					(xy 68.617846 -70.653402) (xy 68.615306 -70.65645) (xy 68.61429 -70.658482) (xy 68.613528 -70.660006)
					(xy 68.61302 -70.661022) (xy 68.612766 -70.661276) (xy 68.612004 -70.663054) (xy 68.611496 -70.665086)
					(xy 68.609718 -70.669912) (xy 68.608194 -70.676262) (xy 68.607686 -70.679564) (xy 68.607686 -70.685914)
					(xy 68.607686 -70.69074) (xy 68.607686 -70.715124) (xy 68.607686 -70.729348)
					(arc
						(start 68.633848 -70.731126)
						(mid 68.656802 -70.734988)
						(end 68.67906 -70.741794)
					)
					(arc
						(start 68.693538 -70.747128)
						(mid 68.716021 -70.758454)
						(end 68.736718 -70.772782)
					)
					(xy 68.752466 -70.785736)
					(arc
						(start 68.777612 -70.812914)
						(mid 68.785952 -70.825905)
						(end 68.795138 -70.838314)
					)
					(arc
						(start 68.795138 -70.838314)
						(mid 68.80875 -70.867274)
						(end 68.818506 -70.89775)
					)
					(arc
						(start 68.818506 -70.89775)
						(mid 68.822759 -70.920805)
						(end 68.823586 -70.944232)
					)
					(arc
						(start 68.8213 -70.97776)
						(mid 68.813431 -71.009476)
						(end 68.801742 -71.03999)
					)
					(arc
						(start 68.801742 -71.03999)
						(mid 68.788896 -71.063219)
						(end 68.773294 -71.084694)
					)
					(arc
						(start 68.773294 -71.084694)
						(mid 68.751744 -71.10622)
						(end 68.727828 -71.12508)
					)
					(arc
						(start 68.727828 -71.12508)
						(mid 68.70461 -71.138221)
						(end 68.680076 -71.148702)
					)
					(arc
						(start 68.680076 -71.148702)
						(mid 68.660989 -71.154499)
						(end 68.641468 -71.158608)
					)
					(xy 68.637404 -71.15937)
				)
			)
		)
		(zone
			(layer "F.Cu")
			(hatch none 0.5)
			(connect_pads
				(clearance 0)
			)
			(min_thickness 0.25)
			(keepout
				(tracks not_allowed)
				(vias allowed)
				(pads allowed)
				(copperpour not_allowed)
				(footprints allowed)
			)
			(placement
				(enabled no)
				(sheetname "")
			)
			(fill
				(thermal_gap 0.5)
				(thermal_bridge_width 0.5)
				(island_removal_mode 0)
			)
			(polygon
				(pts
					(xy 68.629784 -70.168516) (xy 68.619624 -70.169024) (xy 68.607686 -70.169024) (xy 68.60794 -70.177914)
					(arc
						(start 68.60794 -70.210934)
						(mid 68.608185 -70.219362)
						(end 68.609464 -70.227698)
					)
					(arc
						(start 68.609464 -70.227698)
						(mid 68.615679 -70.242289)
						(end 68.626228 -70.254114)
					)
					(arc
						(start 68.632832 -70.258686)
						(mid 68.646366 -70.264456)
						(end 68.661026 -70.265798)
					)
					(arc
						(start 68.661026 -70.265798)
						(mid 68.925935 -69.952226)
						(end 68.659248 -69.640196)
					)
					(xy 68.652136 -69.640704) (xy 68.64858 -69.641212) (xy 68.645278 -69.642482) (xy 68.63969 -69.644006)
					(xy 68.635626 -69.646038) (xy 68.627498 -69.651372) (xy 68.624704 -69.653912) (xy 68.619116 -69.659246)
					(xy 68.6181 -69.661278) (xy 68.61556 -69.664326) (xy 68.614544 -69.666104) (xy 68.613528 -69.667628)
					(xy 68.613274 -69.668644) (xy 68.61302 -69.668898) (xy 68.612004 -69.67093) (xy 68.611496 -69.672708)
					(xy 68.609718 -69.677534) (xy 68.608194 -69.684138) (xy 68.60794 -69.687186) (xy 68.607686 -69.693536)
					(xy 68.607686 -69.698616) (xy 68.60794 -69.722746) (xy 68.607686 -69.737224)
					(arc
						(start 68.633848 -69.739002)
						(mid 68.656925 -69.742866)
						(end 68.679314 -69.74967)
					)
					(arc
						(start 68.693792 -69.755004)
						(mid 68.716251 -69.766225)
						(end 68.736972 -69.780404)
					)
					(xy 68.75272 -69.793612)
					(arc
						(start 68.777612 -69.820536)
						(mid 68.785952 -69.833527)
						(end 68.795138 -69.845936)
					)
					(arc
						(start 68.795138 -69.845936)
						(mid 68.808767 -69.87502)
						(end 68.818506 -69.905626)
					)
					(arc
						(start 68.818506 -69.905626)
						(mid 68.82286 -69.928546)
						(end 68.82384 -69.951854)
					)
					(arc
						(start 68.8213 -69.985382)
						(mid 68.813453 -70.01723)
						(end 68.801742 -70.047866)
					)
					(arc
						(start 68.801742 -70.047866)
						(mid 68.78887 -70.070956)
						(end 68.773294 -70.092316)
					)
					(arc
						(start 68.773294 -70.092316)
						(mid 68.751861 -70.113822)
						(end 68.728082 -70.132702)
					)
					(arc
						(start 68.728082 -70.132702)
						(mid 68.704864 -70.145843)
						(end 68.68033 -70.156324)
					)
					(arc
						(start 68.68033 -70.156324)
						(mid 68.66125 -70.162258)
						(end 68.641722 -70.166484)
					)
					(xy 68.637658 -70.166992)
				)
			)
		)
		(zone
			(layer "F.Cu")
			(hatch none 0.5)
			(connect_pads
				(clearance 0)
			)
			(min_thickness 0.25)
			(keepout
				(tracks not_allowed)
				(vias allowed)
				(pads allowed)
				(copperpour not_allowed)
				(footprints allowed)
			)
			(placement
				(enabled no)
				(sheetname "")
			)
			(fill
				(thermal_gap 0.5)
				(thermal_bridge_width 0.5)
				(island_removal_mode 0)
			)
			(polygon
				(pts
					(xy 68.631308 -83.04657) (xy 68.621148 -83.047078) (xy 68.60921 -83.047332) (xy 68.60921 -83.056222)
					(arc
						(start 68.60921 -83.088988)
						(mid 68.609553 -83.097429)
						(end 68.610988 -83.105752)
					)
					(arc
						(start 68.610988 -83.105752)
						(mid 68.617094 -83.120309)
						(end 68.627498 -83.132168)
					)
					(arc
						(start 68.634102 -83.13674)
						(mid 68.647752 -83.142616)
						(end 68.66255 -83.143852)
					)
					(arc
						(start 68.66255 -83.143852)
						(mid 68.926996 -82.830389)
						(end 68.660518 -82.518504)
					)
					(xy 68.65366 -82.519012) (xy 68.64985 -82.51952) (xy 68.646548 -82.520536) (xy 68.641214 -82.52206)
					(xy 68.636896 -82.524092) (xy 68.629022 -82.529426) (xy 68.625974 -82.531966) (xy 68.62064 -82.5373)
					(xy 68.61937 -82.539332) (xy 68.61683 -82.54238) (xy 68.615814 -82.544412) (xy 68.615052 -82.545936)
					(xy 68.614544 -82.546698) (xy 68.61429 -82.546952) (xy 68.613528 -82.548984) (xy 68.612766 -82.551016)
					(xy 68.611242 -82.555588) (xy 68.609718 -82.562192) (xy 68.60921 -82.565494) (xy 68.60921 -82.57159)
					(xy 68.60921 -82.57667) (xy 68.60921 -82.6008) (xy 68.60921 -82.615278)
					(arc
						(start 68.635372 -82.617056)
						(mid 68.658324 -82.620924)
						(end 68.680584 -82.627724)
					)
					(arc
						(start 68.695062 -82.633058)
						(mid 68.717521 -82.644279)
						(end 68.738242 -82.658458)
					)
					(xy 68.75399 -82.671666)
					(arc
						(start 68.779136 -82.69859)
						(mid 68.787476 -82.711581)
						(end 68.796662 -82.72399)
					)
					(arc
						(start 68.796662 -82.72399)
						(mid 68.810291 -82.753074)
						(end 68.82003 -82.78368)
					)
					(arc
						(start 68.82003 -82.78368)
						(mid 68.824232 -82.80661)
						(end 68.82511 -82.829908)
					)
					(arc
						(start 68.822824 -82.863436)
						(mid 68.814949 -82.895273)
						(end 68.803266 -82.92592)
					)
					(arc
						(start 68.803266 -82.92592)
						(mid 68.790394 -82.94901)
						(end 68.774818 -82.97037)
					)
					(arc
						(start 68.774818 -82.97037)
						(mid 68.753266 -82.99201)
						(end 68.729352 -83.01101)
					)
					(arc
						(start 68.729352 -83.01101)
						(mid 68.706123 -83.024016)
						(end 68.6816 -83.034378)
					)
					(arc
						(start 68.6816 -83.034378)
						(mid 68.662517 -83.040298)
						(end 68.642992 -83.044538)
					)
					(xy 68.638928 -83.0453)
				)
			)
		)
		(zone
			(layer "F.Cu")
			(hatch none 0.5)
			(connect_pads
				(clearance 0)
			)
			(min_thickness 0.25)
			(keepout
				(tracks not_allowed)
				(vias allowed)
				(pads allowed)
				(copperpour not_allowed)
				(footprints allowed)
			)
			(placement
				(enabled no)
				(sheetname "")
			)
			(fill
				(thermal_gap 0.5)
				(thermal_bridge_width 0.5)
				(island_removal_mode 0)
			)
			(polygon
				(pts
					(xy 69.488304 -80.570324) (xy 69.478144 -80.570832) (xy 69.466206 -80.570832) (xy 69.46646 -80.579722)
					(arc
						(start 69.46646 -80.612488)
						(mid 69.466684 -80.621045)
						(end 69.467984 -80.629506)
					)
					(arc
						(start 69.467984 -80.629506)
						(mid 69.474199 -80.644097)
						(end 69.484748 -80.655922)
					)
					(arc
						(start 69.491352 -80.660494)
						(mid 69.504886 -80.666264)
						(end 69.519546 -80.667606)
					)
					(arc
						(start 69.519546 -80.667606)
						(mid 69.784455 -80.354034)
						(end 69.517768 -80.042004)
					)
					(xy 69.510656 -80.042512) (xy 69.5071 -80.04302) (xy 69.503798 -80.04429) (xy 69.49821 -80.045814)
					(xy 69.494146 -80.047846) (xy 69.486018 -80.05318) (xy 69.483224 -80.05572) (xy 69.477636 -80.061054)
					(xy 69.476366 -80.063086) (xy 69.47408 -80.066134) (xy 69.473064 -80.067912) (xy 69.472048 -80.069436)
					(xy 69.471794 -80.070452) (xy 69.47154 -80.070706) (xy 69.470524 -80.072738) (xy 69.470016 -80.074516)
					(xy 69.468238 -80.079342) (xy 69.466714 -80.085692) (xy 69.46646 -80.088994) (xy 69.466206 -80.095344)
					(xy 69.466206 -80.100424) (xy 69.46646 -80.124554) (xy 69.466206 -80.139032)
					(arc
						(start 69.492368 -80.14081)
						(mid 69.51532 -80.144678)
						(end 69.53758 -80.151478)
					)
					(arc
						(start 69.552312 -80.156812)
						(mid 69.574771 -80.168033)
						(end 69.595492 -80.182212)
					)
					(xy 69.61124 -80.19542)
					(arc
						(start 69.636132 -80.222344)
						(mid 69.644472 -80.235335)
						(end 69.653658 -80.247744)
					)
					(arc
						(start 69.653658 -80.247744)
						(mid 69.667287 -80.276828)
						(end 69.677026 -80.307434)
					)
					(arc
						(start 69.677026 -80.307434)
						(mid 69.68138 -80.330354)
						(end 69.68236 -80.353662)
					)
					(arc
						(start 69.67982 -80.38719)
						(mid 69.671945 -80.419027)
						(end 69.660262 -80.449674)
					)
					(arc
						(start 69.660262 -80.449674)
						(mid 69.64739 -80.472764)
						(end 69.631814 -80.494124)
					)
					(arc
						(start 69.631814 -80.494124)
						(mid 69.610381 -80.51563)
						(end 69.586602 -80.53451)
					)
					(arc
						(start 69.586602 -80.53451)
						(mid 69.563384 -80.547651)
						(end 69.53885 -80.558132)
					)
					(arc
						(start 69.53885 -80.558132)
						(mid 69.51977 -80.564066)
						(end 69.500242 -80.568292)
					)
					(xy 69.496178 -80.5688)
				)
			)
		)
		(zone
			(layer "F.Cu")
			(hatch none 0.5)
			(connect_pads
				(clearance 0)
			)
			(min_thickness 0.25)
			(keepout
				(tracks not_allowed)
				(vias allowed)
				(pads allowed)
				(copperpour not_allowed)
				(footprints allowed)
			)
			(placement
				(enabled no)
				(sheetname "")
			)
			(fill
				(thermal_gap 0.5)
				(thermal_bridge_width 0.5)
				(island_removal_mode 0)
			)
			(polygon
				(pts
					(xy 69.488304 -79.579724) (xy 69.478398 -79.580232) (xy 69.46646 -79.580486) (xy 69.46646 -79.589376)
					(arc
						(start 69.46646 -79.622142)
						(mid 69.466705 -79.63057)
						(end 69.467984 -79.638906)
					)
					(arc
						(start 69.467984 -79.638906)
						(mid 69.474199 -79.653497)
						(end 69.484748 -79.665322)
					)
					(arc
						(start 69.491352 -79.669894)
						(mid 69.504983 -79.675874)
						(end 69.5198 -79.67726)
					)
					(arc
						(start 69.5198 -79.67726)
						(mid 69.784708 -79.363563)
						(end 69.517768 -79.051658)
					)
					(xy 69.51091 -79.052166) (xy 69.5071 -79.052674) (xy 69.503798 -79.053944) (xy 69.498464 -79.055468)
					(xy 69.494146 -79.0575) (xy 69.486272 -79.062834) (xy 69.483224 -79.065374) (xy 69.47789 -79.070708)
					(xy 69.47662 -79.072486) (xy 69.47408 -79.075534) (xy 69.473064 -79.077566) (xy 69.472302 -79.07909)
					(xy 69.471794 -79.080106) (xy 69.47154 -79.08036) (xy 69.470778 -79.082138) (xy 69.470016 -79.08417)
					(xy 69.468492 -79.088996) (xy 69.466968 -79.095346) (xy 69.46646 -79.098648) (xy 69.46646 -79.104998)
					(xy 69.46646 -79.109824) (xy 69.46646 -79.134208) (xy 69.46646 -79.148432)
					(arc
						(start 69.492368 -79.15021)
						(mid 69.51546 -79.154178)
						(end 69.537834 -79.161132)
					)
					(arc
						(start 69.552312 -79.166212)
						(mid 69.574795 -79.177538)
						(end 69.595492 -79.191866)
					)
					(xy 69.61124 -79.20482)
					(arc
						(start 69.636386 -79.231998)
						(mid 69.644726 -79.244989)
						(end 69.653912 -79.257398)
					)
					(arc
						(start 69.653912 -79.257398)
						(mid 69.667524 -79.286358)
						(end 69.67728 -79.316834)
					)
					(arc
						(start 69.67728 -79.316834)
						(mid 69.681533 -79.339889)
						(end 69.68236 -79.363316)
					)
					(arc
						(start 69.680074 -79.396844)
						(mid 69.672199 -79.428681)
						(end 69.660516 -79.459328)
					)
					(arc
						(start 69.660516 -79.459328)
						(mid 69.647656 -79.482427)
						(end 69.632068 -79.503778)
					)
					(arc
						(start 69.632068 -79.503778)
						(mid 69.610518 -79.525304)
						(end 69.586602 -79.544164)
					)
					(arc
						(start 69.586602 -79.544164)
						(mid 69.563384 -79.557305)
						(end 69.53885 -79.567786)
					)
					(arc
						(start 69.53885 -79.567786)
						(mid 69.519763 -79.573583)
						(end 69.500242 -79.577692)
					)
					(xy 69.496178 -79.578454)
				)
			)
		)
		(zone
			(layer "F.Cu")
			(hatch none 0.5)
			(connect_pads
				(clearance 0)
			)
			(min_thickness 0.25)
			(keepout
				(tracks not_allowed)
				(vias allowed)
				(pads allowed)
				(copperpour not_allowed)
				(footprints allowed)
			)
			(placement
				(enabled no)
				(sheetname "")
			)
			(fill
				(thermal_gap 0.5)
				(thermal_bridge_width 0.5)
				(island_removal_mode 0)
			)
			(polygon
				(pts
					(xy 69.488304 -78.589632) (xy 69.478144 -78.589886) (xy 69.466206 -78.59014) (xy 69.46646 -78.59903)
					(arc
						(start 69.46646 -78.631796)
						(mid 69.466684 -78.640353)
						(end 69.467984 -78.648814)
					)
					(arc
						(start 69.467984 -78.648814)
						(mid 69.474199 -78.663405)
						(end 69.484748 -78.67523)
					)
					(arc
						(start 69.491352 -78.679802)
						(mid 69.504886 -78.685572)
						(end 69.519546 -78.686914)
					)
					(arc
						(start 69.519546 -78.686914)
						(mid 69.784455 -78.373342)
						(end 69.517768 -78.061312)
					)
					(xy 69.510656 -78.06182) (xy 69.5071 -78.062328) (xy 69.503798 -78.063598) (xy 69.49821 -78.065122)
					(xy 69.494146 -78.067154) (xy 69.486018 -78.072488) (xy 69.483224 -78.075028) (xy 69.477636 -78.080362)
					(xy 69.476366 -78.082394) (xy 69.47408 -78.085188) (xy 69.473064 -78.08722) (xy 69.472048 -78.088744)
					(xy 69.471794 -78.08976) (xy 69.47154 -78.090014) (xy 69.470524 -78.091792) (xy 69.470016 -78.093824)
					(xy 69.468238 -78.09865) (xy 69.466714 -78.105) (xy 69.46646 -78.108302) (xy 69.466206 -78.114652)
					(xy 69.466206 -78.119732) (xy 69.46646 -78.143862) (xy 69.466206 -78.158086)
					(arc
						(start 69.492368 -78.160118)
						(mid 69.51532 -78.163986)
						(end 69.53758 -78.170786)
					)
					(arc
						(start 69.552312 -78.17612)
						(mid 69.574771 -78.187341)
						(end 69.595492 -78.20152)
					)
					(xy 69.61124 -78.214728)
					(arc
						(start 69.636132 -78.241652)
						(mid 69.644472 -78.254643)
						(end 69.653658 -78.267052)
					)
					(arc
						(start 69.653658 -78.267052)
						(mid 69.66727 -78.296012)
						(end 69.677026 -78.326488)
					)
					(arc
						(start 69.677026 -78.326488)
						(mid 69.681394 -78.349534)
						(end 69.68236 -78.37297)
					)
					(arc
						(start 69.67982 -78.406498)
						(mid 69.671945 -78.438335)
						(end 69.660262 -78.468982)
					)
					(arc
						(start 69.660262 -78.468982)
						(mid 69.64739 -78.492072)
						(end 69.631814 -78.513432)
					)
					(arc
						(start 69.631814 -78.513432)
						(mid 69.610394 -78.534954)
						(end 69.586602 -78.553818)
					)
					(arc
						(start 69.586602 -78.553818)
						(mid 69.563384 -78.566959)
						(end 69.53885 -78.57744)
					)
					(arc
						(start 69.53885 -78.57744)
						(mid 69.51977 -78.583374)
						(end 69.500242 -78.5876)
					)
					(xy 69.496178 -78.588108)
				)
			)
		)
		(zone
			(layer "F.Cu")
			(hatch none 0.5)
			(connect_pads
				(clearance 0)
			)
			(min_thickness 0.25)
			(keepout
				(tracks not_allowed)
				(vias allowed)
				(pads allowed)
				(copperpour not_allowed)
				(footprints allowed)
			)
			(placement
				(enabled no)
				(sheetname "")
			)
			(fill
				(thermal_gap 0.5)
				(thermal_bridge_width 0.5)
				(island_removal_mode 0)
			)
			(polygon
				(pts
					(xy 69.488304 -77.598778) (xy 69.478144 -77.599286) (xy 69.466206 -77.599286) (xy 69.46646 -77.60843)
					(arc
						(start 69.46646 -77.641196)
						(mid 69.466705 -77.649624)
						(end 69.467984 -77.65796)
					)
					(arc
						(start 69.467984 -77.65796)
						(mid 69.474199 -77.672551)
						(end 69.484748 -77.684376)
					)
					(arc
						(start 69.491352 -77.688948)
						(mid 69.504886 -77.694718)
						(end 69.519546 -77.69606)
					)
					(arc
						(start 69.519546 -77.69606)
						(mid 69.783992 -77.382722)
						(end 69.517768 -77.070712)
					)
					(xy 69.510656 -77.07122) (xy 69.5071 -77.071728) (xy 69.503798 -77.072744) (xy 69.49821 -77.074268)
					(xy 69.494146 -77.0763) (xy 69.486018 -77.081634) (xy 69.483224 -77.084174) (xy 69.477636 -77.089508)
					(xy 69.476366 -77.09154) (xy 69.47408 -77.094588) (xy 69.473064 -77.09662) (xy 69.472048 -77.09789)
					(xy 69.471794 -77.098906) (xy 69.47154 -77.09916) (xy 69.470524 -77.101192) (xy 69.470016 -77.103224)
					(xy 69.468238 -77.107796) (xy 69.466714 -77.1144) (xy 69.46646 -77.117702) (xy 69.466206 -77.123798)
					(xy 69.466206 -77.128878) (xy 69.46646 -77.153008) (xy 69.466206 -77.167486)
					(arc
						(start 69.492368 -77.169264)
						(mid 69.51532 -77.173132)
						(end 69.53758 -77.179932)
					)
					(arc
						(start 69.552312 -77.185266)
						(mid 69.574771 -77.196487)
						(end 69.595492 -77.210666)
					)
					(xy 69.61124 -77.223874)
					(arc
						(start 69.636132 -77.250798)
						(mid 69.644472 -77.263789)
						(end 69.653658 -77.276198)
					)
					(arc
						(start 69.653658 -77.276198)
						(mid 69.667287 -77.305282)
						(end 69.677026 -77.335888)
					)
					(arc
						(start 69.677026 -77.335888)
						(mid 69.68138 -77.358808)
						(end 69.68236 -77.382116)
					)
					(arc
						(start 69.67982 -77.415644)
						(mid 69.671945 -77.447481)
						(end 69.660262 -77.478128)
					)
					(arc
						(start 69.660262 -77.478128)
						(mid 69.64739 -77.501218)
						(end 69.631814 -77.522578)
					)
					(arc
						(start 69.631814 -77.522578)
						(mid 69.610392 -77.544215)
						(end 69.586602 -77.563218)
					)
					(arc
						(start 69.586602 -77.563218)
						(mid 69.563373 -77.576224)
						(end 69.53885 -77.586586)
					)
					(arc
						(start 69.53885 -77.586586)
						(mid 69.519767 -77.592506)
						(end 69.500242 -77.596746)
					)
					(xy 69.496178 -77.597508)
				)
			)
		)
		(zone
			(layer "F.Cu")
			(hatch none 0.5)
			(connect_pads
				(clearance 0)
			)
			(min_thickness 0.25)
			(keepout
				(tracks not_allowed)
				(vias allowed)
				(pads allowed)
				(copperpour not_allowed)
				(footprints allowed)
			)
			(placement
				(enabled no)
				(sheetname "")
			)
			(fill
				(thermal_gap 0.5)
				(thermal_bridge_width 0.5)
				(island_removal_mode 0)
			)
			(polygon
				(pts
					(xy 69.488304 -76.605638) (xy 69.478398 -76.605892) (xy 69.46646 -76.606146) (xy 69.46646 -76.615036)
					(arc
						(start 69.46646 -76.647802)
						(mid 69.466684 -76.656359)
						(end 69.467984 -76.66482)
					)
					(arc
						(start 69.467984 -76.66482)
						(mid 69.474199 -76.679411)
						(end 69.484748 -76.691236)
					)
					(arc
						(start 69.491352 -76.695808)
						(mid 69.505002 -76.701684)
						(end 69.5198 -76.70292)
					)
					(arc
						(start 69.5198 -76.70292)
						(mid 69.784708 -76.389223)
						(end 69.517768 -76.077318)
					)
					(xy 69.51091 -76.077826) (xy 69.5071 -76.078334) (xy 69.503798 -76.079604) (xy 69.498464 -76.081128)
					(xy 69.494146 -76.08316) (xy 69.486272 -76.088494) (xy 69.483224 -76.091034) (xy 69.47789 -76.096368)
					(xy 69.47662 -76.0984) (xy 69.47408 -76.101194) (xy 69.473064 -76.103226) (xy 69.472302 -76.10475)
					(xy 69.471794 -76.105766) (xy 69.47154 -76.10602) (xy 69.470778 -76.107798) (xy 69.470016 -76.10983)
					(xy 69.468492 -76.114656) (xy 69.466968 -76.121006) (xy 69.46646 -76.124308) (xy 69.46646 -76.130658)
					(xy 69.46646 -76.135738) (xy 69.46646 -76.159868) (xy 69.46646 -76.174092)
					(arc
						(start 69.492368 -76.176124)
						(mid 69.515445 -76.179988)
						(end 69.537834 -76.186792)
					)
					(arc
						(start 69.552312 -76.192126)
						(mid 69.574789 -76.203321)
						(end 69.595492 -76.217526)
					)
					(xy 69.61124 -76.230734)
					(arc
						(start 69.636386 -76.257658)
						(mid 69.644726 -76.270649)
						(end 69.653912 -76.283058)
					)
					(arc
						(start 69.653912 -76.283058)
						(mid 69.667524 -76.312018)
						(end 69.67728 -76.342494)
					)
					(arc
						(start 69.67728 -76.342494)
						(mid 69.681533 -76.365549)
						(end 69.68236 -76.388976)
					)
					(arc
						(start 69.680074 -76.422504)
						(mid 69.672199 -76.454341)
						(end 69.660516 -76.484988)
					)
					(arc
						(start 69.660516 -76.484988)
						(mid 69.647644 -76.508078)
						(end 69.632068 -76.529438)
					)
					(arc
						(start 69.632068 -76.529438)
						(mid 69.610518 -76.550964)
						(end 69.586602 -76.569824)
					)
					(arc
						(start 69.586602 -76.569824)
						(mid 69.563384 -76.582965)
						(end 69.53885 -76.593446)
					)
					(arc
						(start 69.53885 -76.593446)
						(mid 69.51977 -76.59938)
						(end 69.500242 -76.603606)
					)
					(xy 69.496178 -76.604114)
				)
			)
		)
		(zone
			(layer "F.Cu")
			(hatch none 0.5)
			(connect_pads
				(clearance 0)
			)
			(min_thickness 0.25)
			(keepout
				(tracks not_allowed)
				(vias allowed)
				(pads allowed)
				(copperpour not_allowed)
				(footprints allowed)
			)
			(placement
				(enabled no)
				(sheetname "")
			)
			(fill
				(thermal_gap 0.5)
				(thermal_bridge_width 0.5)
				(island_removal_mode 0)
			)
			(polygon
				(pts
					(xy 69.488304 -75.617324) (xy 69.478144 -75.617832) (xy 69.466206 -75.618086) (xy 69.46646 -75.626976)
					(arc
						(start 69.46646 -75.659742)
						(mid 69.466705 -75.66817)
						(end 69.467984 -75.676506)
					)
					(arc
						(start 69.467984 -75.676506)
						(mid 69.474223 -75.691074)
						(end 69.484748 -75.702922)
					)
					(arc
						(start 69.491352 -75.707494)
						(mid 69.50486 -75.713442)
						(end 69.519546 -75.71486)
					)
					(arc
						(start 69.519546 -75.71486)
						(mid 69.784455 -75.401288)
						(end 69.517768 -75.089258)
					)
					(xy 69.510656 -75.089766) (xy 69.5071 -75.090274) (xy 69.503798 -75.091544) (xy 69.49821 -75.093068)
					(xy 69.494146 -75.0951) (xy 69.486018 -75.100434) (xy 69.483224 -75.102974) (xy 69.477636 -75.108308)
					(xy 69.476366 -75.110086) (xy 69.47408 -75.113134) (xy 69.473064 -75.115166) (xy 69.472048 -75.11669)
					(xy 69.471794 -75.117706) (xy 69.47154 -75.11796) (xy 69.470524 -75.119738) (xy 69.470016 -75.12177)
					(xy 69.468238 -75.126596) (xy 69.466714 -75.132946) (xy 69.46646 -75.136248) (xy 69.466206 -75.142598)
					(xy 69.466206 -75.147424) (xy 69.46646 -75.171808) (xy 69.466206 -75.186032)
					(arc
						(start 69.492368 -75.18781)
						(mid 69.515326 -75.191813)
						(end 69.53758 -75.198732)
					)
					(arc
						(start 69.552312 -75.203812)
						(mid 69.574795 -75.215138)
						(end 69.595492 -75.229466)
					)
					(xy 69.61124 -75.24242)
					(arc
						(start 69.636132 -75.269598)
						(mid 69.644472 -75.282589)
						(end 69.653658 -75.294998)
					)
					(arc
						(start 69.653658 -75.294998)
						(mid 69.66727 -75.323958)
						(end 69.677026 -75.354434)
					)
					(arc
						(start 69.677026 -75.354434)
						(mid 69.681394 -75.37748)
						(end 69.68236 -75.400916)
					)
					(arc
						(start 69.67982 -75.434444)
						(mid 69.671945 -75.466281)
						(end 69.660262 -75.496928)
					)
					(arc
						(start 69.660262 -75.496928)
						(mid 69.64739 -75.520018)
						(end 69.631814 -75.541378)
					)
					(arc
						(start 69.631814 -75.541378)
						(mid 69.610394 -75.5629)
						(end 69.586602 -75.581764)
					)
					(arc
						(start 69.586602 -75.581764)
						(mid 69.563384 -75.594905)
						(end 69.53885 -75.605386)
					)
					(arc
						(start 69.53885 -75.605386)
						(mid 69.519763 -75.611183)
						(end 69.500242 -75.615292)
					)
					(xy 69.496178 -75.616054)
				)
			)
		)
		(zone
			(layer "F.Cu")
			(hatch none 0.5)
			(connect_pads
				(clearance 0)
			)
			(min_thickness 0.25)
			(keepout
				(tracks not_allowed)
				(vias allowed)
				(pads allowed)
				(copperpour not_allowed)
				(footprints allowed)
			)
			(placement
				(enabled no)
				(sheetname "")
			)
			(fill
				(thermal_gap 0.5)
				(thermal_bridge_width 0.5)
				(island_removal_mode 0)
			)
			(polygon
				(pts
					(xy 69.488304 -74.629772) (xy 69.478144 -74.63028) (xy 69.466206 -74.630534) (xy 69.466206 -74.639424)
					(arc
						(start 69.466206 -74.67219)
						(mid 69.466549 -74.680631)
						(end 69.467984 -74.688954)
					)
					(arc
						(start 69.467984 -74.688954)
						(mid 69.47409 -74.703511)
						(end 69.484494 -74.71537)
					)
					(arc
						(start 69.491098 -74.719942)
						(mid 69.504734 -74.72589)
						(end 69.519546 -74.727308)
					)
					(arc
						(start 69.519546 -74.727308)
						(mid 69.784454 -74.413611)
						(end 69.517514 -74.101706)
					)
					(xy 69.510656 -74.102214) (xy 69.506846 -74.102722) (xy 69.503544 -74.103992) (xy 69.49821 -74.105516)
					(xy 69.493892 -74.107294) (xy 69.486018 -74.112628) (xy 69.48297 -74.115422) (xy 69.477636 -74.120756)
					(xy 69.476366 -74.122534) (xy 69.473826 -74.125582) (xy 69.47281 -74.127614) (xy 69.472048 -74.129138)
					(xy 69.47154 -74.130154) (xy 69.471286 -74.130408) (xy 69.470524 -74.132186) (xy 69.470016 -74.134218)
					(xy 69.468238 -74.139044) (xy 69.466714 -74.145394) (xy 69.466206 -74.148696) (xy 69.466206 -74.154792)
					(xy 69.466206 -74.159872) (xy 69.466206 -74.184256) (xy 69.466206 -74.19848)
					(arc
						(start 69.492368 -74.200258)
						(mid 69.51532 -74.204126)
						(end 69.53758 -74.210926)
					)
					(arc
						(start 69.552058 -74.21626)
						(mid 69.574541 -74.227586)
						(end 69.595238 -74.241914)
					)
					(xy 69.610986 -74.254868)
					(arc
						(start 69.636132 -74.281792)
						(mid 69.644472 -74.294783)
						(end 69.653658 -74.307192)
					)
					(arc
						(start 69.653658 -74.307192)
						(mid 69.667287 -74.336276)
						(end 69.677026 -74.366882)
					)
					(arc
						(start 69.677026 -74.366882)
						(mid 69.681228 -74.389812)
						(end 69.682106 -74.41311)
					)
					(arc
						(start 69.67982 -74.446892)
						(mid 69.671951 -74.478608)
						(end 69.660262 -74.509122)
					)
					(arc
						(start 69.660262 -74.509122)
						(mid 69.647416 -74.532351)
						(end 69.631814 -74.553826)
					)
					(arc
						(start 69.631814 -74.553826)
						(mid 69.610264 -74.575352)
						(end 69.586348 -74.594212)
					)
					(arc
						(start 69.586348 -74.594212)
						(mid 69.56313 -74.607353)
						(end 69.538596 -74.617834)
					)
					(arc
						(start 69.538596 -74.617834)
						(mid 69.519509 -74.623631)
						(end 69.499988 -74.62774)
					)
					(xy 69.495924 -74.628502)
				)
			)
		)
		(zone
			(layer "F.Cu")
			(hatch none 0.5)
			(connect_pads
				(clearance 0)
			)
			(min_thickness 0.25)
			(keepout
				(tracks not_allowed)
				(vias allowed)
				(pads allowed)
				(copperpour not_allowed)
				(footprints allowed)
			)
			(placement
				(enabled no)
				(sheetname "")
			)
			(fill
				(thermal_gap 0.5)
				(thermal_bridge_width 0.5)
				(island_removal_mode 0)
			)
			(polygon
				(pts
					(xy 69.488304 -73.635616) (xy 69.478144 -73.636124) (xy 69.466206 -73.636124) (xy 69.46646 -73.645014)
					(arc
						(start 69.46646 -73.678034)
						(mid 69.466705 -73.686462)
						(end 69.467984 -73.694798)
					)
					(arc
						(start 69.467984 -73.694798)
						(mid 69.474199 -73.709389)
						(end 69.484748 -73.721214)
					)
					(arc
						(start 69.491352 -73.725786)
						(mid 69.504886 -73.731556)
						(end 69.519546 -73.732898)
					)
					(arc
						(start 69.519546 -73.732898)
						(mid 69.784455 -73.419326)
						(end 69.517768 -73.107296)
					)
					(xy 69.510656 -73.107804) (xy 69.5071 -73.108312) (xy 69.503798 -73.109582) (xy 69.49821 -73.111106)
					(xy 69.494146 -73.113138) (xy 69.486018 -73.118472) (xy 69.483224 -73.121012) (xy 69.477636 -73.126346)
					(xy 69.476366 -73.128378) (xy 69.47408 -73.131426) (xy 69.473064 -73.133204) (xy 69.472048 -73.134728)
					(xy 69.471794 -73.135744) (xy 69.47154 -73.135998) (xy 69.470524 -73.13803) (xy 69.470016 -73.139808)
					(xy 69.468238 -73.144634) (xy 69.466714 -73.151238) (xy 69.46646 -73.154286) (xy 69.466206 -73.160636)
					(xy 69.466206 -73.165716) (xy 69.46646 -73.189846) (xy 69.466206 -73.204324)
					(arc
						(start 69.492368 -73.206102)
						(mid 69.51532 -73.20997)
						(end 69.53758 -73.21677)
					)
					(arc
						(start 69.552312 -73.222104)
						(mid 69.574771 -73.233325)
						(end 69.595492 -73.247504)
					)
					(xy 69.61124 -73.260712)
					(arc
						(start 69.636132 -73.287636)
						(mid 69.644472 -73.300627)
						(end 69.653658 -73.313036)
					)
					(arc
						(start 69.653658 -73.313036)
						(mid 69.667287 -73.34212)
						(end 69.677026 -73.372726)
					)
					(arc
						(start 69.677026 -73.372726)
						(mid 69.68138 -73.395646)
						(end 69.68236 -73.418954)
					)
					(arc
						(start 69.67982 -73.452482)
						(mid 69.671945 -73.484319)
						(end 69.660262 -73.514966)
					)
					(arc
						(start 69.660262 -73.514966)
						(mid 69.64739 -73.538056)
						(end 69.631814 -73.559416)
					)
					(arc
						(start 69.631814 -73.559416)
						(mid 69.610381 -73.580922)
						(end 69.586602 -73.599802)
					)
					(arc
						(start 69.586602 -73.599802)
						(mid 69.563384 -73.612943)
						(end 69.53885 -73.623424)
					)
					(arc
						(start 69.53885 -73.623424)
						(mid 69.51977 -73.629358)
						(end 69.500242 -73.633584)
					)
					(xy 69.496178 -73.634092)
				)
			)
		)
		(zone
			(layer "F.Cu")
			(hatch none 0.5)
			(connect_pads
				(clearance 0)
			)
			(min_thickness 0.25)
			(keepout
				(tracks not_allowed)
				(vias allowed)
				(pads allowed)
				(copperpour not_allowed)
				(footprints allowed)
			)
			(placement
				(enabled no)
				(sheetname "")
			)
			(fill
				(thermal_gap 0.5)
				(thermal_bridge_width 0.5)
				(island_removal_mode 0)
			)
			(polygon
				(pts
					(xy 69.488304 -72.646286) (xy 69.478398 -72.646794) (xy 69.46646 -72.647048) (xy 69.46646 -72.655938)
					(arc
						(start 69.46646 -72.688704)
						(mid 69.466705 -72.697132)
						(end 69.467984 -72.705468)
					)
					(arc
						(start 69.467984 -72.705468)
						(mid 69.474199 -72.720059)
						(end 69.484748 -72.731884)
					)
					(arc
						(start 69.491352 -72.736456)
						(mid 69.504988 -72.742404)
						(end 69.5198 -72.743822)
					)
					(arc
						(start 69.5198 -72.743822)
						(mid 69.784708 -72.430125)
						(end 69.517768 -72.11822)
					)
					(xy 69.51091 -72.118728) (xy 69.5071 -72.119236) (xy 69.503798 -72.120506) (xy 69.498464 -72.12203)
					(xy 69.494146 -72.123808) (xy 69.486272 -72.129142) (xy 69.483224 -72.131936) (xy 69.47789 -72.13727)
					(xy 69.47662 -72.139048) (xy 69.47408 -72.142096) (xy 69.473064 -72.144128) (xy 69.472302 -72.145652)
					(xy 69.471794 -72.146668) (xy 69.47154 -72.146922) (xy 69.470778 -72.1487) (xy 69.470016 -72.150732)
					(xy 69.468492 -72.155558) (xy 69.466968 -72.161908) (xy 69.46646 -72.16521) (xy 69.46646 -72.171306)
					(xy 69.46646 -72.176386) (xy 69.46646 -72.20077) (xy 69.46646 -72.214994)
					(arc
						(start 69.492368 -72.216772)
						(mid 69.515447 -72.22063)
						(end 69.537834 -72.22744)
					)
					(arc
						(start 69.552312 -72.232774)
						(mid 69.574795 -72.2441)
						(end 69.595492 -72.258428)
					)
					(xy 69.61124 -72.271382)
					(arc
						(start 69.636386 -72.298306)
						(mid 69.644715 -72.311306)
						(end 69.653912 -72.323706)
					)
					(arc
						(start 69.653912 -72.323706)
						(mid 69.667527 -72.352794)
						(end 69.67728 -72.383396)
					)
					(arc
						(start 69.67728 -72.383396)
						(mid 69.681482 -72.406326)
						(end 69.68236 -72.429624)
					)
					(arc
						(start 69.680074 -72.463406)
						(mid 69.672205 -72.495122)
						(end 69.660516 -72.525636)
					)
					(arc
						(start 69.660516 -72.525636)
						(mid 69.647644 -72.548726)
						(end 69.632068 -72.570086)
					)
					(arc
						(start 69.632068 -72.570086)
						(mid 69.610516 -72.591726)
						(end 69.586602 -72.610726)
					)
					(arc
						(start 69.586602 -72.610726)
						(mid 69.563373 -72.623732)
						(end 69.53885 -72.634094)
					)
					(arc
						(start 69.53885 -72.634094)
						(mid 69.519767 -72.640014)
						(end 69.500242 -72.644254)
					)
					(xy 69.496178 -72.645016)
				)
			)
		)
		(zone
			(layer "F.Cu")
			(hatch none 0.5)
			(connect_pads
				(clearance 0)
			)
			(min_thickness 0.25)
			(keepout
				(tracks not_allowed)
				(vias allowed)
				(pads allowed)
				(copperpour not_allowed)
				(footprints allowed)
			)
			(placement
				(enabled no)
				(sheetname "")
			)
			(fill
				(thermal_gap 0.5)
				(thermal_bridge_width 0.5)
				(island_removal_mode 0)
			)
			(polygon
				(pts
					(xy 132.590032 -51.46929) (xy 132.589524 -51.45913) (xy 132.58927 -51.447192) (xy 132.58038 -51.447192)
					(arc
						(start 132.547614 -51.447192)
						(mid 132.539173 -51.447535)
						(end 132.53085 -51.44897)
					)
					(arc
						(start 132.53085 -51.44897)
						(mid 132.516282 -51.455209)
						(end 132.504434 -51.465734)
					)
					(arc
						(start 132.499862 -51.472338)
						(mid 132.494092 -51.485872)
						(end 132.49275 -51.500532)
					)
					(arc
						(start 132.49275 -51.500532)
						(mid 132.806213 -51.764978)
						(end 133.118098 -51.4985)
					)
					(xy 133.11759 -51.491642) (xy 133.117082 -51.487832) (xy 133.116066 -51.48453) (xy 133.114542 -51.479196)
					(xy 133.11251 -51.475132) (xy 133.107176 -51.467004) (xy 133.104636 -51.46421) (xy 133.099302 -51.458622)
					(xy 133.09727 -51.457352) (xy 133.094222 -51.454812) (xy 133.09219 -51.453796) (xy 133.090666 -51.453034)
					(xy 133.089904 -51.452526) (xy 133.08965 -51.452526) (xy 133.087618 -51.45151) (xy 133.085586 -51.451002)
					(xy 133.081014 -51.449224) (xy 133.07441 -51.4477) (xy 133.071108 -51.447192) (xy 133.065012 -51.447192)
					(xy 133.059932 -51.447192) (xy 133.035802 -51.447192) (xy 133.021324 -51.447192)
					(arc
						(start 133.019546 -51.473354)
						(mid 133.015678 -51.496306)
						(end 133.008878 -51.518566)
					)
					(arc
						(start 133.003544 -51.533044)
						(mid 132.992323 -51.555503)
						(end 132.978144 -51.576224)
					)
					(xy 132.964936 -51.592226)
					(arc
						(start 132.938012 -51.617118)
						(mid 132.925021 -51.625458)
						(end 132.912612 -51.634644)
					)
					(arc
						(start 132.912612 -51.634644)
						(mid 132.883528 -51.648273)
						(end 132.852922 -51.658012)
					)
					(arc
						(start 132.852922 -51.658012)
						(mid 132.829992 -51.662214)
						(end 132.806694 -51.663092)
					)
					(arc
						(start 132.773166 -51.660806)
						(mid 132.741329 -51.652931)
						(end 132.710682 -51.641248)
					)
					(arc
						(start 132.710682 -51.641248)
						(mid 132.687592 -51.628376)
						(end 132.666232 -51.6128)
					)
					(arc
						(start 132.666232 -51.6128)
						(mid 132.644592 -51.591248)
						(end 132.625592 -51.567334)
					)
					(arc
						(start 132.625592 -51.567334)
						(mid 132.612603 -51.544227)
						(end 132.602224 -51.519836)
					)
					(arc
						(start 132.602224 -51.519836)
						(mid 132.596304 -51.500753)
						(end 132.592064 -51.481228)
					)
					(xy 132.591302 -51.47691)
				)
			)
		)
		(zone
			(layer "F.Cu")
			(hatch none 0.5)
			(connect_pads
				(clearance 0)
			)
			(min_thickness 0.25)
			(keepout
				(tracks not_allowed)
				(vias allowed)
				(pads allowed)
				(copperpour not_allowed)
				(footprints allowed)
			)
			(placement
				(enabled no)
				(sheetname "")
			)
			(fill
				(thermal_gap 0.5)
				(thermal_bridge_width 0.5)
				(island_removal_mode 0)
			)
			(polygon
				(pts
					(xy 136.024112 -51.46929) (xy 136.023604 -51.45913) (xy 136.02335 -51.447192) (xy 136.01446 -51.447192)
					(arc
						(start 135.981694 -51.447192)
						(mid 135.973253 -51.447535)
						(end 135.96493 -51.44897)
					)
					(arc
						(start 135.96493 -51.44897)
						(mid 135.950362 -51.455209)
						(end 135.938514 -51.465734)
					)
					(arc
						(start 135.933942 -51.472338)
						(mid 135.927994 -51.485846)
						(end 135.926576 -51.500532)
					)
					(arc
						(start 135.926576 -51.500532)
						(mid 136.240273 -51.76544)
						(end 136.552178 -51.4985)
					)
					(xy 136.55167 -51.491642) (xy 136.551162 -51.487832) (xy 136.549892 -51.48453) (xy 136.548368 -51.479196)
					(xy 136.54659 -51.475132) (xy 136.541256 -51.467004) (xy 136.538716 -51.46421) (xy 136.533128 -51.458622)
					(xy 136.53135 -51.457352) (xy 136.528302 -51.454812) (xy 136.52627 -51.453796) (xy 136.524746 -51.453034)
					(xy 136.52373 -51.452526) (xy 136.523476 -51.452526) (xy 136.521698 -51.45151) (xy 136.519666 -51.451002)
					(xy 136.51484 -51.449224) (xy 136.50849 -51.4477) (xy 136.505188 -51.447192) (xy 136.499092 -51.447192)
					(xy 136.494012 -51.447192) (xy 136.469628 -51.447192) (xy 136.455404 -51.447192)
					(arc
						(start 136.453626 -51.473354)
						(mid 136.449758 -51.496306)
						(end 136.442958 -51.518566)
					)
					(arc
						(start 136.437624 -51.533044)
						(mid 136.426298 -51.555527)
						(end 136.41197 -51.576224)
					)
					(xy 136.399016 -51.592226)
					(arc
						(start 136.372092 -51.617118)
						(mid 136.359101 -51.625458)
						(end 136.346692 -51.634644)
					)
					(arc
						(start 136.346692 -51.634644)
						(mid 136.317608 -51.648273)
						(end 136.287002 -51.658012)
					)
					(arc
						(start 136.287002 -51.658012)
						(mid 136.264072 -51.662214)
						(end 136.240774 -51.663092)
					)
					(arc
						(start 136.206992 -51.660806)
						(mid 136.175276 -51.652937)
						(end 136.144762 -51.641248)
					)
					(arc
						(start 136.144762 -51.641248)
						(mid 136.121672 -51.628376)
						(end 136.100312 -51.6128)
					)
					(arc
						(start 136.100312 -51.6128)
						(mid 136.078655 -51.591261)
						(end 136.059672 -51.567334)
					)
					(arc
						(start 136.059672 -51.567334)
						(mid 136.046683 -51.544227)
						(end 136.036304 -51.519836)
					)
					(arc
						(start 136.036304 -51.519836)
						(mid 136.030384 -51.500753)
						(end 136.026144 -51.481228)
					)
					(xy 136.025382 -51.47691)
				)
			)
		)
	)
	(footprint ""
		(layer "F.Cu")
		(at 9.779 -155.702)
		(property "Reference" ""
			(at 0 0 0)
			(layer "F.SilkS")
			(hide yes)
			(effects
				(font
					(size 1.27 1.27)
				)
			)
		)
		(property "Value" ""
			(at 0 0 0)
			(layer "F.Fab")
			(effects
				(font
					(size 1.27 1.27)
				)
			)
		)
		(duplicate_pad_numbers_are_jumpers no)
		(fp_poly
			(pts
				(arc
					(start 2.032 0)
					(mid -2.032 0)
					(end 2.032 0)
				)
			)
			(stroke
				(width 0)
				(type default)
			)
			(fill no)
			(layer "F.CrtYd")
		)
		(pad "1" smd circle
			(at 0 0)
			(size 1.016 1.016)
			(layers "F.Cu" "F.Mask" "F.Paste")
			(net "Net_384")
		)
		(zone
			(layer "F.Cu")
			(hatch none 0.5)
			(connect_pads
				(clearance 0)
			)
			(min_thickness 0.25)
			(keepout
				(tracks not_allowed)
				(vias allowed)
				(pads allowed)
				(copperpour not_allowed)
				(footprints allowed)
			)
			(placement
				(enabled no)
				(sheetname "")
			)
			(fill
				(thermal_gap 0.5)
				(thermal_bridge_width 0.5)
				(island_removal_mode 0)
			)
			(polygon
				(pts
					(arc
						(start 11.303 -155.702)
						(mid 8.255 -155.702)
						(end 11.303 -155.702)
					)
				)
			)
		)
		(zone
			(layers "F.Cu" "B.Cu" "In1.Cu" "In2.Cu" "In3.Cu" "In4.Cu" "In5.Cu" "In6.Cu"
				"In7.Cu" "In8.Cu" "In9.Cu" "In10.Cu" "In11.Cu" "In12.Cu"
			)
			(hatch none 0.5)
			(connect_pads
				(clearance 0)
			)
			(min_thickness 0.25)
			(keepout
				(tracks allowed)
				(vias not_allowed)
				(pads allowed)
				(copperpour not_allowed)
				(footprints allowed)
			)
			(placement
				(enabled no)
				(sheetname "")
			)
			(fill
				(thermal_gap 0.5)
				(thermal_bridge_width 0.5)
				(island_removal_mode 0)
			)
			(polygon
				(pts
					(arc
						(start 11.303 -155.702)
						(mid 8.255 -155.702)
						(end 11.303 -155.702)
					)
				)
			)
		)
	)
	(footprint ""
		(layer "F.Cu")
		(at 460.121 -1.524 -90)
		(property "Reference" "R8B26"
			(at -0.8382 -0.67818 270)
			(unlocked yes)
			(layer "F.SilkS")
			(effects
				(font
					(size 0.4064 0.254)
					(thickness 0.1524)
				)
				(justify left)
			)
		)
		(property "Value" ""
			(at 0 0 270)
			(layer "F.Fab")
			(effects
				(font
					(size 1.27 1.27)
				)
			)
		)
		(duplicate_pad_numbers_are_jumpers no)
		(fp_poly
			(pts
				(xy -0.2794 -0.1016) (xy 0.2794 -0.1016) (xy 0.2794 0.9906) (xy -0.2794 0.9906)
			)
			(stroke
				(width 0)
				(type default)
			)
			(fill no)
			(layer "F.CrtYd")
		)
		(fp_line
			(start -0.2794 0.9906)
			(end 0.2794 0.9906)
			(stroke
				(width 0.1)
				(type default)
			)
			(layer "F.Fab")
		)
		(fp_line
			(start 0.2794 0.9906)
			(end 0.2794 -0.1016)
			(stroke
				(width 0.1)
				(type default)
			)
			(layer "F.Fab")
		)
		(fp_line
			(start -0.2794 -0.1016)
			(end -0.2794 0.9906)
			(stroke
				(width 0.1)
				(type default)
			)
			(layer "F.Fab")
		)
		(fp_line
			(start 0.2794 -0.1016)
			(end -0.2794 -0.1016)
			(stroke
				(width 0.1)
				(type default)
			)
			(layer "F.Fab")
		)
		(pad "1" smd rect
			(at 0 0 270)
			(size 0.508 0.508)
			(layers "F.Cu" "F.Mask" "F.Paste")
			(net "P3V3_STBY")
		)
		(pad "2" smd rect
			(at 0 0.889 270)
			(size 0.508 0.508)
			(layers "F.Cu" "F.Mask" "F.Paste")
			(net "SMB_HOST_STBY_LVC3_SCL_R5")
		)
		(zone
			(layer "F.Cu")
			(hatch none 0.5)
			(connect_pads
				(clearance 0)
			)
			(min_thickness 0.25)
			(keepout
				(tracks not_allowed)
				(vias allowed)
				(pads allowed)
				(copperpour not_allowed)
				(footprints allowed)
			)
			(placement
				(enabled no)
				(sheetname "")
			)
			(fill
				(thermal_gap 0.5)
				(thermal_bridge_width 0.5)
				(island_removal_mode 0)
			)
			(polygon
				(pts
					(xy 459.486 -1.778) (xy 459.486 -1.27) (xy 459.867 -1.27) (xy 459.867 -1.778)
				)
			)
		)
		(zone
			(layer "F.Cu")
			(hatch none 0.5)
			(connect_pads
				(clearance 0)
			)
			(min_thickness 0.25)
			(keepout
				(tracks allowed)
				(vias not_allowed)
				(pads allowed)
				(copperpour not_allowed)
				(footprints allowed)
			)
			(placement
				(enabled no)
				(sheetname "")
			)
			(fill
				(thermal_gap 0.5)
				(thermal_bridge_width 0.5)
				(island_removal_mode 0)
			)
			(polygon
				(pts
					(xy 459.867 -1.778) (xy 459.867 -1.27) (xy 459.486 -1.27) (xy 459.486 -1.778)
				)
			)
		)
	)
	(footprint ""
		(layer "F.Cu")
		(at 500.579898 -42.61993 90)
		(property "Reference" "J25W1"
			(at 0 0 90)
			(layer "F.SilkS")
			(hide yes)
			(effects
				(font
					(size 1.27 1.27)
				)
			)
		)
		(property "Value" "*"
			(at 4.3434 -6.4643 90)
			(unlocked yes)
			(layer "F.Fab")
			(hide yes)
			(effects
				(font
					(size 1.27 1.016)
					(thickness 0.1524)
				)
			)
		)
		(property "Device Type" "SMC-CON13-GP_CONN-GC2-SMC-CON1A"
			(at 4.3434 -7.9883 90)
			(unlocked yes)
			(layer "F.Fab")
			(hide yes)
			(effects
				(font
					(size 1.27 1.016)
					(thickness 0.1524)
				)
			)
		)
		(duplicate_pad_numbers_are_jumpers no)
		(fp_line
			(start -6.6548 -5.0038)
			(end -5.7023 -5.0038)
			(stroke
				(width 0.3302)
				(type default)
			)
			(layer "F.SilkS")
		)
		(fp_line
			(start 6.5659 -4.9149)
			(end 6.5659 -3.7973)
			(stroke
				(width 0.1524)
				(type default)
			)
			(layer "F.SilkS")
		)
		(fp_line
			(start -6.5659 -4.9149)
			(end 6.5659 -4.9149)
			(stroke
				(width 0.1524)
				(type default)
			)
			(layer "F.SilkS")
		)
		(fp_line
			(start -6.6548 -3.8989)
			(end -6.6548 -5.0038)
			(stroke
				(width 0.3302)
				(type default)
			)
			(layer "F.SilkS")
		)
		(fp_line
			(start 7.9629 -3.7973)
			(end 7.9629 1.1557)
			(stroke
				(width 0.1524)
				(type default)
			)
			(layer "F.SilkS")
		)
		(fp_line
			(start 6.5659 -3.7973)
			(end 7.9629 -3.7973)
			(stroke
				(width 0.1524)
				(type default)
			)
			(layer "F.SilkS")
		)
		(fp_line
			(start -6.5659 -3.7973)
			(end -6.5659 -4.9149)
			(stroke
				(width 0.1524)
				(type default)
			)
			(layer "F.SilkS")
		)
		(fp_line
			(start -7.9629 -3.7973)
			(end -6.5659 -3.7973)
			(stroke
				(width 0.1524)
				(type default)
			)
			(layer "F.SilkS")
		)
		(fp_line
			(start 7.9629 1.1557)
			(end -7.9629 1.1557)
			(stroke
				(width 0.1524)
				(type default)
			)
			(layer "F.SilkS")
		)
		(fp_line
			(start -7.9629 1.1557)
			(end -7.9629 -3.7973)
			(stroke
				(width 0.1524)
				(type default)
			)
			(layer "F.SilkS")
		)
		(fp_poly
			(pts
				(xy -6.052312 -4.930902) (xy -5.428488 -5.554726) (xy -6.676136 -5.554726)
			)
			(stroke
				(width 0)
				(type default)
			)
			(fill yes)
			(layer "F.SilkS")
		)
		(fp_poly
			(pts
				(xy -6.69036 -2.897124) (xy -6.69036 1.1684) (xy 6.69036 1.1684) (xy 6.69036 -2.897124)
			)
			(stroke
				(width 0)
				(type default)
			)
			(fill yes)
			(layer "F.SilkS")
		)
		(fp_poly
			(pts
				(xy -7.5057 0.6985) (xy -7.5057 -3.5433) (xy -6.096 -3.5433) (xy -6.096 -4.2545) (xy 6.096 -4.2545)
				(xy 6.096 -3.5433) (xy 7.5057 -3.5433) (xy 7.5057 0.6985)
			)
			(stroke
				(width 0)
				(type default)
			)
			(fill no)
			(layer "F.CrtYd")
		)
		(fp_poly
			(pts
				(xy -8.2169 1.4097) (xy -8.2169 -4.0513) (xy -6.8199 -4.0513) (xy -6.8199 -5.1689) (xy 6.8199 -5.1689)
				(xy 6.8199 -4.0513) (xy 8.2169 -4.0513) (xy 8.2169 -0.00635) (xy 7.5057 -0.00635) (xy 7.5057 -3.5433)
				(xy 6.096 -3.5433) (xy 6.096 -4.2545) (xy -6.096 -4.2545) (xy -6.096 -3.5433) (xy -7.5057 -3.5433)
				(xy -7.5057 0.6985) (xy 7.5057 0.6985) (xy 7.5057 0.00635) (xy 8.2169 0.00635) (xy 8.2169 1.4097)
			)
			(stroke
				(width 0)
				(type default)
			)
			(fill no)
			(layer "F.CrtYd")
		)
		(fp_poly
			(pts
				(xy -8.2169 1.4097) (xy -8.2169 -4.0513) (xy -6.8199 -4.0513) (xy -6.8199 -5.1689) (xy 6.8199 -5.1689)
				(xy 6.8199 -4.0513) (xy 8.2169 -4.0513) (xy 8.2169 1.4097)
			)
			(stroke
				(width 0)
				(type default)
			)
			(fill no)
			(layer "F.Fab")
		)
		(pad "1" smd rect
			(at -5.999988 -3.875024 90)
			(size 0.6096 1.5494)
			(layers "F.Cu" "F.Mask" "F.Paste")
			(net "V_IO_R_J")
		)
		(pad "2" smd rect
			(at -4.99999 -3.875024 90)
			(size 0.6096 1.5494)
			(layers "F.Cu" "F.Mask" "F.Paste")
			(net "GND")
		)
		(pad "3" smd rect
			(at -3.999992 -3.875024 90)
			(size 0.6096 1.5494)
			(layers "F.Cu" "F.Mask" "F.Paste")
			(net "V_IO_G_J")
		)
		(pad "4" smd rect
			(at -2.999994 -3.875024 90)
			(size 0.6096 1.5494)
			(layers "F.Cu" "F.Mask" "F.Paste")
			(net "GND")
		)
		(pad "5" smd rect
			(at -1.999996 -3.875024 90)
			(size 0.6096 1.5494)
			(layers "F.Cu" "F.Mask" "F.Paste")
			(net "V_IO_B_J")
		)
		(pad "6" smd rect
			(at -0.999998 -3.875024 90)
			(size 0.6096 1.5494)
			(layers "F.Cu" "F.Mask" "F.Paste")
			(net "GND")
		)
		(pad "7" smd rect
			(at 0 -3.875024 90)
			(size 0.6096 1.5494)
			(layers "F.Cu" "F.Mask" "F.Paste")
			(net "V_IO_VSYNC_J")
		)
		(pad "8" smd rect
			(at 0.999998 -3.875024 90)
			(size 0.6096 1.5494)
			(layers "F.Cu" "F.Mask" "F.Paste")
			(net "GND")
		)
		(pad "9" smd rect
			(at 1.999996 -3.875024 90)
			(size 0.6096 1.5494)
			(layers "F.Cu" "F.Mask" "F.Paste")
			(net "V_IO_HSYNC_J")
		)
		(pad "10" smd rect
			(at 2.999994 -3.875024 90)
			(size 0.6096 1.5494)
			(layers "F.Cu" "F.Mask" "F.Paste")
			(net "GND")
		)
		(pad "11" smd rect
			(at 3.999992 -3.875024 90)
			(size 0.6096 1.5494)
			(layers "F.Cu" "F.Mask" "F.Paste")
			(net "V_IBMC_5V_DDC_SDA_J")
		)
		(pad "12" smd rect
			(at 4.99999 -3.875024 90)
			(size 0.6096 1.5494)
			(layers "F.Cu" "F.Mask" "F.Paste")
			(net "V_IBMC_5V_DDC_SCL_J")
		)
		(pad "13" smd rect
			(at 5.999988 -3.875024 90)
			(size 0.6096 1.5494)
			(layers "F.Cu" "F.Mask" "F.Paste")
			(net "P5V_VGA")
		)
		(pad "PTH1" smd rect
			(at -7.29996 0 90)
			(size 0.8128 1.8034)
			(layers "F.Cu" "F.Mask" "F.Paste")
			(net "GND")
		)
		(pad "PTH2" smd rect
			(at 7.29996 0 90)
			(size 0.8128 1.8034)
			(layers "F.Cu" "F.Mask" "F.Paste")
			(net "GND")
		)
	)
	(footprint ""
		(layer "F.Cu")
		(at 39.6748 -50.5714 90)
		(property "Reference" "R1E6"
			(at 0 0 90)
			(layer "F.SilkS")
			(hide yes)
			(effects
				(font
					(size 1.27 1.27)
				)
			)
		)
		(property "Value" ""
			(at 0 0 90)
			(layer "F.Fab")
			(effects
				(font
					(size 1.27 1.27)
				)
			)
		)
		(duplicate_pad_numbers_are_jumpers no)
		(fp_poly
			(pts
				(xy -0.2794 -0.1016) (xy 0.2794 -0.1016) (xy 0.2794 0.9906) (xy -0.2794 0.9906)
			)
			(stroke
				(width 0)
				(type default)
			)
			(fill no)
			(layer "F.CrtYd")
		)
		(fp_line
			(start 0.2794 -0.1016)
			(end -0.2794 -0.1016)
			(stroke
				(width 0.1)
				(type default)
			)
			(layer "F.Fab")
		)
		(fp_line
			(start -0.2794 -0.1016)
			(end -0.2794 0.9906)
			(stroke
				(width 0.1)
				(type default)
			)
			(layer "F.Fab")
		)
		(fp_line
			(start 0.2794 0.9906)
			(end 0.2794 -0.1016)
			(stroke
				(width 0.1)
				(type default)
			)
			(layer "F.Fab")
		)
		(fp_line
			(start -0.2794 0.9906)
			(end 0.2794 0.9906)
			(stroke
				(width 0.1)
				(type default)
			)
			(layer "F.Fab")
		)
		(pad "1" smd rect
			(at 0 0 90)
			(size 0.508 0.508)
			(layers "F.Cu" "F.Mask" "F.Paste")
			(net "VSENSE_PVCCIN_CPU1_P")
		)
		(pad "2" smd rect
			(at 0 0.889 90)
			(size 0.508 0.508)
			(layers "F.Cu" "F.Mask" "F.Paste")
			(net "VSENSE_PVCCIN_CPU1_SKT_VSEN")
		)
		(zone
			(layer "F.Cu")
			(hatch none 0.5)
			(connect_pads
				(clearance 0)
			)
			(min_thickness 0.25)
			(keepout
				(tracks allowed)
				(vias not_allowed)
				(pads allowed)
				(copperpour not_allowed)
				(footprints allowed)
			)
			(placement
				(enabled no)
				(sheetname "")
			)
			(fill
				(thermal_gap 0.5)
				(thermal_bridge_width 0.5)
				(island_removal_mode 0)
			)
			(polygon
				(pts
					(xy 39.9288 -50.3174) (xy 39.9288 -50.8254) (xy 40.3098 -50.8254) (xy 40.3098 -50.3174)
				)
			)
		)
		(zone
			(layer "F.Cu")
			(hatch none 0.5)
			(connect_pads
				(clearance 0)
			)
			(min_thickness 0.25)
			(keepout
				(tracks not_allowed)
				(vias allowed)
				(pads allowed)
				(copperpour not_allowed)
				(footprints allowed)
			)
			(placement
				(enabled no)
				(sheetname "")
			)
			(fill
				(thermal_gap 0.5)
				(thermal_bridge_width 0.5)
				(island_removal_mode 0)
			)
			(polygon
				(pts
					(xy 40.3098 -50.3174) (xy 40.3098 -50.8254) (xy 39.9288 -50.8254) (xy 39.9288 -50.3174)
				)
			)
		)
	)
	(footprint ""
		(layer "F.Cu")
		(at 335.788 -24.13 90)
		(property "Reference" "R7F13"
			(at 0 0 90)
			(layer "F.SilkS")
			(hide yes)
			(effects
				(font
					(size 1.27 1.27)
				)
			)
		)
		(property "Value" ""
			(at 0 0 90)
			(layer "F.Fab")
			(effects
				(font
					(size 1.27 1.27)
				)
			)
		)
		(duplicate_pad_numbers_are_jumpers no)
		(fp_rect
			(start -0.2794 -0.1016)
			(end 0.2794 0.9906)
			(stroke
				(width 0)
				(type default)
			)
			(fill no)
			(layer "F.CrtYd")
		)
		(fp_line
			(start 0.2794 -0.1016)
			(end -0.2794 -0.1016)
			(stroke
				(width 0.1)
				(type default)
			)
			(layer "F.Fab")
		)
		(fp_line
			(start -0.2794 -0.1016)
			(end -0.2794 0.9906)
			(stroke
				(width 0.1)
				(type default)
			)
			(layer "F.Fab")
		)
		(fp_line
			(start 0.2794 0.9906)
			(end 0.2794 -0.1016)
			(stroke
				(width 0.1)
				(type default)
			)
			(layer "F.Fab")
		)
		(fp_line
			(start -0.2794 0.9906)
			(end 0.2794 0.9906)
			(stroke
				(width 0.1)
				(type default)
			)
			(layer "F.Fab")
		)
		(pad "1" smd rect
			(at 0 0 90)
			(size 0.508 0.508)
			(layers "F.Cu" "F.Mask" "F.Paste")
			(net "VSENSE_PVPP_ABC")
		)
		(pad "2" smd rect
			(at 0 0.889 90)
			(size 0.508 0.508)
			(layers "F.Cu" "F.Mask" "F.Paste")
			(net "VR_FB_PVPP_ABC")
		)
		(zone
			(layer "F.Cu")
			(hatch none 0.5)
			(connect_pads
				(clearance 0)
			)
			(min_thickness 0.25)
			(keepout
				(tracks allowed)
				(vias not_allowed)
				(pads allowed)
				(copperpour not_allowed)
				(footprints allowed)
			)
			(placement
				(enabled no)
				(sheetname "")
			)
			(fill
				(thermal_gap 0.5)
				(thermal_bridge_width 0.5)
				(island_removal_mode 0)
			)
			(polygon
				(pts
					(xy 336.042 -23.876) (xy 336.423 -23.876) (xy 336.423 -24.384) (xy 336.042 -24.384)
				)
			)
		)
		(zone
			(layer "F.Cu")
			(hatch none 0.5)
			(connect_pads
				(clearance 0)
			)
			(min_thickness 0.25)
			(keepout
				(tracks not_allowed)
				(vias allowed)
				(pads allowed)
				(copperpour not_allowed)
				(footprints allowed)
			)
			(placement
				(enabled no)
				(sheetname "")
			)
			(fill
				(thermal_gap 0.5)
				(thermal_bridge_width 0.5)
				(island_removal_mode 0)
			)
			(polygon
				(pts
					(xy 336.042 -23.876) (xy 336.423 -23.876) (xy 336.423 -24.384) (xy 336.042 -24.384)
				)
			)
		)
	)
	(footprint ""
		(layer "F.Cu")
		(at 481.8126 -21.1582)
		(property "Reference" "C22W12"
			(at 0 0 0)
			(layer "F.SilkS")
			(hide yes)
			(effects
				(font
					(size 1.27 1.27)
				)
			)
		)
		(property "Value" "*"
			(at -0.0762 -6.2357 0)
			(unlocked yes)
			(layer "F.Fab")
			(hide yes)
			(effects
				(font
					(size 1.27 1.016)
					(thickness 0.1524)
				)
			)
		)
		(property "Device Type" "SC22U16V5MX-4-GP_SMD-BCG5-SC22A"
			(at -0.0762 -8.2677 0)
			(unlocked yes)
			(layer "F.Fab")
			(hide yes)
			(effects
				(font
					(size 1.27 1.016)
					(thickness 0.1524)
				)
			)
		)
		(duplicate_pad_numbers_are_jumpers no)
		(fp_line
			(start 0.635 0)
			(end -0.635 0)
			(stroke
				(width 0.508)
				(type default)
			)
			(layer "F.SilkS")
		)
		(fp_rect
			(start -0.9652 1.778)
			(end 0.9652 -1.778)
			(stroke
				(width 0)
				(type default)
			)
			(fill no)
			(layer "F.CrtYd")
		)
		(fp_poly
			(pts
				(xy -0.9652 -1.778) (xy 0.9652 -1.778) (xy 0.9652 1.778) (xy -0.9652 1.778)
			)
			(stroke
				(width 0)
				(type default)
			)
			(fill no)
			(layer "F.Fab")
		)
		(pad "1" smd rect
			(at 0 -0.9652)
			(size 1.397 1.143)
			(layers "F.Cu" "F.Mask" "F.Paste")
			(net "VR_FET_SW_P12V_STBY_P3V3_STBY")
		)
		(pad "2" smd rect
			(at 0 0.9652)
			(size 1.397 1.143)
			(layers "F.Cu" "F.Mask" "F.Paste")
			(net "GND")
		)
	)
	(footprint ""
		(layer "F.Cu")
		(at 402.336 -152.527 180)
		(property "Reference" "C8A6"
			(at 0 0 180)
			(layer "F.SilkS")
			(hide yes)
			(effects
				(font
					(size 1.27 1.27)
				)
			)
		)
		(property "Value" ""
			(at 0 0 180)
			(layer "F.Fab")
			(effects
				(font
					(size 1.27 1.27)
				)
			)
		)
		(duplicate_pad_numbers_are_jumpers no)
		(fp_poly
			(pts
				(xy -0.4953 -0.2032) (xy 0.4953 -0.2032) (xy 0.4953 1.6002) (xy -0.4953 1.6002)
			)
			(stroke
				(width 0)
				(type default)
			)
			(fill no)
			(layer "F.CrtYd")
		)
		(fp_line
			(start 0.4953 1.6002)
			(end -0.4953 1.6002)
			(stroke
				(width 0.1)
				(type default)
			)
			(layer "F.Fab")
		)
		(fp_line
			(start 0.4953 -0.2032)
			(end 0.4953 1.6002)
			(stroke
				(width 0.1)
				(type default)
			)
			(layer "F.Fab")
		)
		(fp_line
			(start -0.4953 1.6002)
			(end -0.4953 -0.2032)
			(stroke
				(width 0.1)
				(type default)
			)
			(layer "F.Fab")
		)
		(fp_line
			(start -0.4953 -0.2032)
			(end 0.4953 -0.2032)
			(stroke
				(width 0.1)
				(type default)
			)
			(layer "F.Fab")
		)
		(pad "1" smd rect
			(at 0 0 180)
			(size 0.762 0.889)
			(layers "F.Cu" "F.Mask" "F.Paste")
			(net "P3V3_STBY")
		)
		(pad "2" smd rect
			(at 0 1.397 180)
			(size 0.762 0.889)
			(layers "F.Cu" "F.Mask" "F.Paste")
			(net "GND")
		)
		(zone
			(layer "F.Cu")
			(hatch none 0.5)
			(connect_pads
				(clearance 0)
			)
			(min_thickness 0.25)
			(keepout
				(tracks not_allowed)
				(vias allowed)
				(pads allowed)
				(copperpour not_allowed)
				(footprints allowed)
			)
			(placement
				(enabled no)
				(sheetname "")
			)
			(fill
				(thermal_gap 0.5)
				(thermal_bridge_width 0.5)
				(island_removal_mode 0)
			)
			(polygon
				(pts
					(xy 402.717 -152.9715) (xy 401.955 -152.9715) (xy 401.955 -153.4795) (xy 402.717 -153.4795)
				)
			)
		)
	)
	(footprint ""
		(layer "F.Cu")
		(at 337.404202 -121.282968 -90)
		(property "Reference" "C834"
			(at -0.8382 -0.67818 270)
			(unlocked yes)
			(layer "F.SilkS")
			(effects
				(font
					(size 0.4064 0.254)
					(thickness 0.1524)
				)
				(justify left)
			)
		)
		(property "Value" ""
			(at 0 0 270)
			(layer "F.Fab")
			(effects
				(font
					(size 1.27 1.27)
				)
			)
		)
		(duplicate_pad_numbers_are_jumpers no)
		(fp_poly
			(pts
				(xy 0.3048 -0.1016) (xy 0.3048 0.9906) (xy -0.3048 0.9906) (xy -0.3048 -0.1016)
			)
			(stroke
				(width 0)
				(type default)
			)
			(fill no)
			(layer "F.CrtYd")
		)
		(fp_line
			(start -0.3048 0.9906)
			(end 0.3048 0.9906)
			(stroke
				(width 0.1)
				(type default)
			)
			(layer "F.Fab")
		)
		(fp_line
			(start 0.3048 0.9906)
			(end 0.3048 -0.1016)
			(stroke
				(width 0.1)
				(type default)
			)
			(layer "F.Fab")
		)
		(fp_line
			(start -0.3048 -0.1016)
			(end -0.3048 0.9906)
			(stroke
				(width 0.1)
				(type default)
			)
			(layer "F.Fab")
		)
		(fp_line
			(start 0.3048 -0.1016)
			(end -0.3048 -0.1016)
			(stroke
				(width 0.1)
				(type default)
			)
			(layer "F.Fab")
		)
		(pad "1" smd rect
			(at 0 0 270)
			(size 0.508 0.508)
			(layers "F.Cu" "F.Mask" "F.Paste")
			(net "P3E_CPU0_PE1_PCH_TXN<10>")
		)
		(pad "2" smd rect
			(at 0 0.889 270)
			(size 0.508 0.508)
			(layers "F.Cu" "F.Mask" "F.Paste")
			(net "P3E_CPU0_PE1_PCH_CON_TXN<10>")
		)
		(zone
			(layer "F.Cu")
			(hatch none 0.5)
			(connect_pads
				(clearance 0)
			)
			(min_thickness 0.25)
			(keepout
				(tracks not_allowed)
				(vias allowed)
				(pads allowed)
				(copperpour not_allowed)
				(footprints allowed)
			)
			(placement
				(enabled no)
				(sheetname "")
			)
			(fill
				(thermal_gap 0.5)
				(thermal_bridge_width 0.5)
				(island_removal_mode 0)
			)
			(polygon
				(pts
					(xy 336.769202 -121.536968) (xy 336.769202 -121.028968) (xy 337.150202 -121.028968) (xy 337.150202 -121.536968)
				)
			)
		)
		(zone
			(layer "F.Cu")
			(hatch none 0.5)
			(connect_pads
				(clearance 0)
			)
			(min_thickness 0.25)
			(keepout
				(tracks allowed)
				(vias not_allowed)
				(pads allowed)
				(copperpour not_allowed)
				(footprints allowed)
			)
			(placement
				(enabled no)
				(sheetname "")
			)
			(fill
				(thermal_gap 0.5)
				(thermal_bridge_width 0.5)
				(island_removal_mode 0)
			)
			(polygon
				(pts
					(xy 337.150202 -121.536968) (xy 337.150202 -121.028968) (xy 336.769202 -121.028968) (xy 336.769202 -121.536968)
				)
			)
		)
	)
	(footprint ""
		(layer "F.Cu")
		(at 103.506778 -84.890102)
		(property "Reference" "C2D1"
			(at 0 0 0)
			(layer "F.SilkS")
			(hide yes)
			(effects
				(font
					(size 1.27 1.27)
				)
			)
		)
		(property "Value" ""
			(at 0 0 0)
			(layer "F.Fab")
			(effects
				(font
					(size 1.27 1.27)
				)
			)
		)
		(duplicate_pad_numbers_are_jumpers no)
		(fp_poly
			(pts
				(xy -0.4953 -0.2032) (xy 0.4953 -0.2032) (xy 0.4953 1.6002) (xy -0.4953 1.6002)
			)
			(stroke
				(width 0)
				(type default)
			)
			(fill no)
			(layer "F.CrtYd")
		)
		(fp_line
			(start -0.4953 -0.2032)
			(end 0.4953 -0.2032)
			(stroke
				(width 0.1)
				(type default)
			)
			(layer "F.Fab")
		)
		(fp_line
			(start -0.4953 1.6002)
			(end -0.4953 -0.2032)
			(stroke
				(width 0.1)
				(type default)
			)
			(layer "F.Fab")
		)
		(fp_line
			(start 0.4953 -0.2032)
			(end 0.4953 1.6002)
			(stroke
				(width 0.1)
				(type default)
			)
			(layer "F.Fab")
		)
		(fp_line
			(start 0.4953 1.6002)
			(end -0.4953 1.6002)
			(stroke
				(width 0.1)
				(type default)
			)
			(layer "F.Fab")
		)
		(pad "1" smd rect
			(at 0 0)
			(size 0.762 0.889)
			(layers "F.Cu" "F.Mask" "F.Paste")
			(net "PVDDQ_KLM")
		)
		(pad "2" smd rect
			(at 0 1.397)
			(size 0.762 0.889)
			(layers "F.Cu" "F.Mask" "F.Paste")
			(net "GND")
		)
		(zone
			(layer "F.Cu")
			(hatch none 0.5)
			(connect_pads
				(clearance 0)
			)
			(min_thickness 0.25)
			(keepout
				(tracks not_allowed)
				(vias allowed)
				(pads allowed)
				(copperpour not_allowed)
				(footprints allowed)
			)
			(placement
				(enabled no)
				(sheetname "")
			)
			(fill
				(thermal_gap 0.5)
				(thermal_bridge_width 0.5)
				(island_removal_mode 0)
			)
			(polygon
				(pts
					(xy 103.125778 -84.445602) (xy 103.887778 -84.445602) (xy 103.887778 -83.937602) (xy 103.125778 -83.937602)
				)
			)
		)
	)
	(footprint ""
		(layer "F.Cu")
		(at 25.02408 -91.96832 180)
		(property "Reference" "CF10"
			(at 0 0 180)
			(layer "F.SilkS")
			(hide yes)
			(effects
				(font
					(size 1.27 1.27)
				)
			)
		)
		(property "Value" "*"
			(at 1.1811 -2.8194 180)
			(unlocked yes)
			(layer "F.Fab")
			(hide yes)
			(effects
				(font
					(size 1.27 1.016)
					(thickness 0.1524)
				)
			)
		)
		(property "Device Type" "SC22P50V2JN-4GP_SMD-BCG-SC22P5A"
			(at 1.1811 -4.3434 180)
			(unlocked yes)
			(layer "F.Fab")
			(hide yes)
			(effects
				(font
					(size 1.27 1.016)
					(thickness 0.1524)
				)
			)
		)
		(duplicate_pad_numbers_are_jumpers no)
		(fp_rect
			(start -0.4318 0.9525)
			(end 0.4318 -0.9525)
			(stroke
				(width 0)
				(type default)
			)
			(fill no)
			(layer "F.CrtYd")
		)
		(fp_rect
			(start -0.4318 0.9525)
			(end 0.4318 -0.9525)
			(stroke
				(width 0)
				(type default)
			)
			(fill no)
			(layer "F.Fab")
		)
		(pad "1" smd custom
			(at 0 -0.4445 180)
			(size 0.1524 0.1524)
			(layers "F.Cu" "F.Mask" "F.Paste")
			(net "VR_PVCCIN_CPU1_AIREF4")
			(options
				(clearance outline)
				(anchor circle)
			)
			(primitives
				(gr_poly
					(pts
						(arc
							(start 0.3048 -0.2032)
							(mid 0.275042 -0.275042)
							(end 0.2032 -0.3048)
						)
						(arc
							(start -0.2032 -0.3048)
							(mid -0.275042 -0.275042)
							(end -0.3048 -0.2032)
						)
						(arc
							(start -0.3048 0.2032)
							(mid -0.275042 0.275042)
							(end -0.2032 0.3048)
						)
						(arc
							(start 0.2032 0.3048)
							(mid 0.275042 0.275042)
							(end 0.3048 0.2032)
						)
					)
					(width 0)
					(fill yes)
				)
			)
		)
		(pad "2" smd custom
			(at 0 0.4445 180)
			(size 0.1524 0.1524)
			(layers "F.Cu" "F.Mask" "F.Paste")
			(net "ISENSE_PVCCIN_CPU1_PH4_IMON")
			(options
				(clearance outline)
				(anchor circle)
			)
			(primitives
				(gr_poly
					(pts
						(arc
							(start 0.3048 -0.2032)
							(mid 0.275042 -0.275042)
							(end 0.2032 -0.3048)
						)
						(arc
							(start -0.2032 -0.3048)
							(mid -0.275042 -0.275042)
							(end -0.3048 -0.2032)
						)
						(arc
							(start -0.3048 0.2032)
							(mid -0.275042 0.275042)
							(end -0.2032 0.3048)
						)
						(arc
							(start 0.2032 0.3048)
							(mid 0.275042 0.275042)
							(end 0.3048 0.2032)
						)
					)
					(width 0)
					(fill yes)
				)
			)
		)
	)
	(footprint ""
		(layer "F.Cu")
		(at 193.8782 -91.3892 90)
		(property "Reference" "C4C17"
			(at 0 0 90)
			(layer "F.SilkS")
			(hide yes)
			(effects
				(font
					(size 1.27 1.27)
				)
			)
		)
		(property "Value" ""
			(at 0 0 90)
			(layer "F.Fab")
			(effects
				(font
					(size 1.27 1.27)
				)
			)
		)
		(duplicate_pad_numbers_are_jumpers no)
		(fp_rect
			(start -0.3048 0.9906)
			(end 0.3048 -0.1016)
			(stroke
				(width 0)
				(type default)
			)
			(fill no)
			(layer "F.CrtYd")
		)
		(fp_line
			(start 0.3048 -0.1016)
			(end -0.3048 -0.1016)
			(stroke
				(width 0.1)
				(type default)
			)
			(layer "F.Fab")
		)
		(fp_line
			(start -0.3048 -0.1016)
			(end -0.3048 0.9906)
			(stroke
				(width 0.1)
				(type default)
			)
			(layer "F.Fab")
		)
		(fp_line
			(start 0.3048 0.9906)
			(end 0.3048 -0.1016)
			(stroke
				(width 0.1)
				(type default)
			)
			(layer "F.Fab")
		)
		(fp_line
			(start -0.3048 0.9906)
			(end 0.3048 0.9906)
			(stroke
				(width 0.1)
				(type default)
			)
			(layer "F.Fab")
		)
		(pad "1" smd rect
			(at 0 0 90)
			(size 0.508 0.508)
			(layers "F.Cu" "F.Mask" "F.Paste")
			(net "VR_PVCCIN_CPU0_PH5_BOOT")
		)
		(pad "2" smd rect
			(at 0 0.889 90)
			(size 0.508 0.508)
			(layers "F.Cu" "F.Mask" "F.Paste")
			(net "VR_PVCCIN_CPU0_PH5_PHASE")
		)
		(zone
			(layer "F.Cu")
			(hatch none 0.5)
			(connect_pads
				(clearance 0)
			)
			(min_thickness 0.25)
			(keepout
				(tracks allowed)
				(vias not_allowed)
				(pads allowed)
				(copperpour not_allowed)
				(footprints allowed)
			)
			(placement
				(enabled no)
				(sheetname "")
			)
			(fill
				(thermal_gap 0.5)
				(thermal_bridge_width 0.5)
				(island_removal_mode 0)
			)
			(polygon
				(pts
					(xy 194.5132 -91.1352) (xy 194.5132 -91.6432) (xy 194.1322 -91.6432) (xy 194.1322 -91.1352)
				)
			)
		)
		(zone
			(layer "F.Cu")
			(hatch none 0.5)
			(connect_pads
				(clearance 0)
			)
			(min_thickness 0.25)
			(keepout
				(tracks not_allowed)
				(vias allowed)
				(pads allowed)
				(copperpour not_allowed)
				(footprints allowed)
			)
			(placement
				(enabled no)
				(sheetname "")
			)
			(fill
				(thermal_gap 0.5)
				(thermal_bridge_width 0.5)
				(island_removal_mode 0)
			)
			(polygon
				(pts
					(xy 194.5132 -91.1352) (xy 194.5132 -91.6432) (xy 194.1322 -91.6432) (xy 194.1322 -91.1352)
				)
			)
		)
	)
	(footprint ""
		(layer "F.Cu")
		(at 24.03602 -91.36888 180)
		(property "Reference" "RF10"
			(at -0.8382 -0.67818 180)
			(unlocked yes)
			(layer "F.SilkS")
			(effects
				(font
					(size 0.4064 0.254)
					(thickness 0.1524)
				)
				(justify left)
			)
		)
		(property "Value" ""
			(at 0 0 180)
			(layer "F.Fab")
			(effects
				(font
					(size 1.27 1.27)
				)
			)
		)
		(duplicate_pad_numbers_are_jumpers no)
		(fp_poly
			(pts
				(xy -0.2794 -0.1016) (xy 0.2794 -0.1016) (xy 0.2794 0.9906) (xy -0.2794 0.9906)
			)
			(stroke
				(width 0)
				(type default)
			)
			(fill no)
			(layer "F.CrtYd")
		)
		(fp_line
			(start 0.2794 0.9906)
			(end 0.2794 -0.1016)
			(stroke
				(width 0.1)
				(type default)
			)
			(layer "F.Fab")
		)
		(fp_line
			(start 0.2794 -0.1016)
			(end -0.2794 -0.1016)
			(stroke
				(width 0.1)
				(type default)
			)
			(layer "F.Fab")
		)
		(fp_line
			(start -0.2794 0.9906)
			(end 0.2794 0.9906)
			(stroke
				(width 0.1)
				(type default)
			)
			(layer "F.Fab")
		)
		(fp_line
			(start -0.2794 -0.1016)
			(end -0.2794 0.9906)
			(stroke
				(width 0.1)
				(type default)
			)
			(layer "F.Fab")
		)
		(pad "1" smd rect
			(at 0 0 180)
			(size 0.508 0.508)
			(layers "F.Cu" "F.Mask" "F.Paste")
			(net "VR_PVCCIN_CPU1_AIREF4")
		)
		(pad "2" smd rect
			(at 0 0.889 180)
			(size 0.508 0.508)
			(layers "F.Cu" "F.Mask" "F.Paste")
			(net "ISENSE_PVCCIN_CPU1_PH4_IMON")
		)
		(zone
			(layer "F.Cu")
			(hatch none 0.5)
			(connect_pads
				(clearance 0)
			)
			(min_thickness 0.25)
			(keepout
				(tracks not_allowed)
				(vias allowed)
				(pads allowed)
				(copperpour not_allowed)
				(footprints allowed)
			)
			(placement
				(enabled no)
				(sheetname "")
			)
			(fill
				(thermal_gap 0.5)
				(thermal_bridge_width 0.5)
				(island_removal_mode 0)
			)
			(polygon
				(pts
					(xy 24.29002 -92.00388) (xy 23.78202 -92.00388) (xy 23.78202 -91.62288) (xy 24.29002 -91.62288)
				)
			)
		)
		(zone
			(layer "F.Cu")
			(hatch none 0.5)
			(connect_pads
				(clearance 0)
			)
			(min_thickness 0.25)
			(keepout
				(tracks allowed)
				(vias not_allowed)
				(pads allowed)
				(copperpour not_allowed)
				(footprints allowed)
			)
			(placement
				(enabled no)
				(sheetname "")
			)
			(fill
				(thermal_gap 0.5)
				(thermal_bridge_width 0.5)
				(island_removal_mode 0)
			)
			(polygon
				(pts
					(xy 24.29002 -91.62288) (xy 23.78202 -91.62288) (xy 23.78202 -92.00388) (xy 24.29002 -92.00388)
				)
			)
		)
	)
	(footprint ""
		(layer "F.Cu")
		(at 17.5768 -43.6626 90)
		(property "Reference" "R1E11"
			(at 0 0 90)
			(layer "F.SilkS")
			(hide yes)
			(effects
				(font
					(size 1.27 1.27)
				)
			)
		)
		(property "Value" ""
			(at 0 0 90)
			(layer "F.Fab")
			(effects
				(font
					(size 1.27 1.27)
				)
			)
		)
		(duplicate_pad_numbers_are_jumpers no)
		(fp_rect
			(start 0.2794 -0.1016)
			(end -0.2794 0.9906)
			(stroke
				(width 0)
				(type default)
			)
			(fill no)
			(layer "F.CrtYd")
		)
		(fp_line
			(start 0.2794 -0.1016)
			(end -0.2794 -0.1016)
			(stroke
				(width 0.1)
				(type default)
			)
			(layer "F.Fab")
		)
		(fp_line
			(start -0.2794 -0.1016)
			(end -0.2794 0.9906)
			(stroke
				(width 0.1)
				(type default)
			)
			(layer "F.Fab")
		)
		(fp_line
			(start 0.2794 0.9906)
			(end 0.2794 -0.1016)
			(stroke
				(width 0.1)
				(type default)
			)
			(layer "F.Fab")
		)
		(fp_line
			(start -0.2794 0.9906)
			(end 0.2794 0.9906)
			(stroke
				(width 0.1)
				(type default)
			)
			(layer "F.Fab")
		)
		(pad "1" smd rect
			(at 0 0 90)
			(size 0.508 0.508)
			(layers "F.Cu" "F.Mask" "F.Paste")
			(net "P3V3_STBY")
		)
		(pad "2" smd rect
			(at 0 0.889 90)
			(size 0.508 0.508)
			(layers "F.Cu" "F.Mask" "F.Paste")
			(net "FM_ENABLE_FAN_POWER")
		)
		(zone
			(layer "F.Cu")
			(hatch none 0.5)
			(connect_pads
				(clearance 0)
			)
			(min_thickness 0.25)
			(keepout
				(tracks allowed)
				(vias not_allowed)
				(pads allowed)
				(copperpour not_allowed)
				(footprints allowed)
			)
			(placement
				(enabled no)
				(sheetname "")
			)
			(fill
				(thermal_gap 0.5)
				(thermal_bridge_width 0.5)
				(island_removal_mode 0)
			)
			(polygon
				(pts
					(xy 17.8308 -43.9166) (xy 17.8308 -43.4086) (xy 18.2118 -43.4086) (xy 18.2118 -43.9166)
				)
			)
		)
		(zone
			(layer "F.Cu")
			(hatch none 0.5)
			(connect_pads
				(clearance 0)
			)
			(min_thickness 0.25)
			(keepout
				(tracks not_allowed)
				(vias allowed)
				(pads allowed)
				(copperpour not_allowed)
				(footprints allowed)
			)
			(placement
				(enabled no)
				(sheetname "")
			)
			(fill
				(thermal_gap 0.5)
				(thermal_bridge_width 0.5)
				(island_removal_mode 0)
			)
			(polygon
				(pts
					(xy 17.8308 -43.9166) (xy 17.8308 -43.4086) (xy 18.2118 -43.4086) (xy 18.2118 -43.9166)
				)
			)
		)
	)
	(footprint ""
		(layer "F.Cu")
		(at 181.763924 -153.6827 90)
		(property "Reference" "C4A1"
			(at 0 0 90)
			(layer "F.SilkS")
			(hide yes)
			(effects
				(font
					(size 1.27 1.27)
				)
			)
		)
		(property "Value" ""
			(at 0 0 90)
			(layer "F.Fab")
			(effects
				(font
					(size 1.27 1.27)
				)
			)
		)
		(duplicate_pad_numbers_are_jumpers no)
		(fp_rect
			(start 0.7239 1.9939)
			(end -0.7239 -0.2159)
			(stroke
				(width 0)
				(type default)
			)
			(fill no)
			(layer "F.CrtYd")
		)
		(fp_line
			(start 0.7239 -0.2159)
			(end -0.7239 -0.2159)
			(stroke
				(width 0.1)
				(type default)
			)
			(layer "F.Fab")
		)
		(fp_line
			(start -0.7239 -0.2159)
			(end -0.7239 1.9939)
			(stroke
				(width 0.1)
				(type default)
			)
			(layer "F.Fab")
		)
		(fp_line
			(start 0.7239 1.9939)
			(end 0.7239 -0.2159)
			(stroke
				(width 0.1)
				(type default)
			)
			(layer "F.Fab")
		)
		(fp_line
			(start -0.7239 1.9939)
			(end 0.7239 1.9939)
			(stroke
				(width 0.1)
				(type default)
			)
			(layer "F.Fab")
		)
		(pad "1" smd rect
			(at 0 0 90)
			(size 1.27 1.016)
			(layers "F.Cu" "F.Mask" "F.Paste")
			(net "PVTT_DEF")
		)
		(pad "2" smd rect
			(at 0 1.778 90)
			(size 1.27 1.016)
			(layers "F.Cu" "F.Mask" "F.Paste")
			(net "GND")
		)
		(zone
			(layer "F.Cu")
			(hatch none 0.5)
			(connect_pads
				(clearance 0)
			)
			(min_thickness 0.25)
			(keepout
				(tracks not_allowed)
				(vias allowed)
				(pads allowed)
				(copperpour not_allowed)
				(footprints allowed)
			)
			(placement
				(enabled no)
				(sheetname "")
			)
			(fill
				(thermal_gap 0.5)
				(thermal_bridge_width 0.5)
				(island_removal_mode 0)
			)
			(polygon
				(pts
					(xy 183.033924 -154.3177) (xy 182.271924 -154.3177) (xy 182.271924 -153.0477) (xy 183.033924 -153.0477)
				)
			)
		)
	)
	(footprint ""
		(layer "F.Cu")
		(at 402.66874 -33.664652 -90)
		(property "Reference" "R2U34"
			(at 0 0 270)
			(layer "F.SilkS")
			(hide yes)
			(effects
				(font
					(size 1.27 1.27)
				)
			)
		)
		(property "Value" ""
			(at 0 0 270)
			(layer "F.Fab")
			(effects
				(font
					(size 1.27 1.27)
				)
			)
		)
		(duplicate_pad_numbers_are_jumpers no)
		(fp_poly
			(pts
				(xy -0.2794 -0.1016) (xy 0.2794 -0.1016) (xy 0.2794 0.9906) (xy -0.2794 0.9906)
			)
			(stroke
				(width 0)
				(type default)
			)
			(fill no)
			(layer "F.CrtYd")
		)
		(fp_line
			(start -0.2794 0.9906)
			(end 0.2794 0.9906)
			(stroke
				(width 0.1)
				(type default)
			)
			(layer "F.Fab")
		)
		(fp_line
			(start 0.2794 0.9906)
			(end 0.2794 -0.1016)
			(stroke
				(width 0.1)
				(type default)
			)
			(layer "F.Fab")
		)
		(fp_line
			(start -0.2794 -0.1016)
			(end -0.2794 0.9906)
			(stroke
				(width 0.1)
				(type default)
			)
			(layer "F.Fab")
		)
		(fp_line
			(start 0.2794 -0.1016)
			(end -0.2794 -0.1016)
			(stroke
				(width 0.1)
				(type default)
			)
			(layer "F.Fab")
		)
		(pad "1" smd rect
			(at 0 0 270)
			(size 0.508 0.508)
			(layers "F.Cu" "F.Mask" "F.Paste")
			(net "SMB_HOST_STBY_LVC3_SCL_R")
		)
		(pad "2" smd rect
			(at 0 0.889 270)
			(size 0.508 0.508)
			(layers "F.Cu" "F.Mask" "F.Paste")
			(net "SMB_HOST_STBY_LVC3_SCL")
		)
		(zone
			(layer "F.Cu")
			(hatch none 0.5)
			(connect_pads
				(clearance 0)
			)
			(min_thickness 0.25)
			(keepout
				(tracks not_allowed)
				(vias allowed)
				(pads allowed)
				(copperpour not_allowed)
				(footprints allowed)
			)
			(placement
				(enabled no)
				(sheetname "")
			)
			(fill
				(thermal_gap 0.5)
				(thermal_bridge_width 0.5)
				(island_removal_mode 0)
			)
			(polygon
				(pts
					(xy 402.03374 -33.918652) (xy 402.03374 -33.410652) (xy 402.41474 -33.410652) (xy 402.41474 -33.918652)
				)
			)
		)
		(zone
			(layer "F.Cu")
			(hatch none 0.5)
			(connect_pads
				(clearance 0)
			)
			(min_thickness 0.25)
			(keepout
				(tracks allowed)
				(vias not_allowed)
				(pads allowed)
				(copperpour not_allowed)
				(footprints allowed)
			)
			(placement
				(enabled no)
				(sheetname "")
			)
			(fill
				(thermal_gap 0.5)
				(thermal_bridge_width 0.5)
				(island_removal_mode 0)
			)
			(polygon
				(pts
					(xy 402.41474 -33.918652) (xy 402.41474 -33.410652) (xy 402.03374 -33.410652) (xy 402.03374 -33.918652)
				)
			)
		)
	)
	(footprint ""
		(layer "F.Cu")
		(at 6.820916 -5.552948 -90)
		(property "Reference" "RT20"
			(at 0 0 270)
			(layer "F.SilkS")
			(hide yes)
			(effects
				(font
					(size 1.27 1.27)
				)
			)
		)
		(property "Value" "*"
			(at -0.0254 -2.6289 270)
			(unlocked yes)
			(layer "F.Fab")
			(hide yes)
			(effects
				(font
					(size 1.27 1.016)
					(thickness 0.1524)
				)
			)
		)
		(property "Device Type" "1R3F-GP_RCL_GP-1R3F-GP,64.1R00A"
			(at -0.0254 -4.1529 270)
			(unlocked yes)
			(layer "F.Fab")
			(hide yes)
			(effects
				(font
					(size 1.27 1.016)
					(thickness 0.1524)
				)
			)
		)
		(duplicate_pad_numbers_are_jumpers no)
		(fp_line
			(start -0.4826 0)
			(end -0.2032 0)
			(stroke
				(width 0.2032)
				(type default)
			)
			(layer "F.SilkS")
		)
		(fp_line
			(start 0.2032 0)
			(end 0.4826 0)
			(stroke
				(width 0.2032)
				(type default)
			)
			(layer "F.SilkS")
		)
		(fp_rect
			(start -0.5842 1.3335)
			(end 0.5842 -1.3335)
			(stroke
				(width 0)
				(type default)
			)
			(fill no)
			(layer "F.CrtYd")
		)
		(fp_rect
			(start -0.5842 1.3335)
			(end 0.5842 -1.3335)
			(stroke
				(width 0)
				(type default)
			)
			(fill no)
			(layer "F.Fab")
		)
		(pad "1" smd custom
			(at 0 -0.762 270)
			(size 0.2159 0.2159)
			(layers "F.Cu" "F.Mask" "F.Paste")
			(net "VR_PVDDQ_GHJ_PH1_SW_RC")
			(options
				(clearance outline)
				(anchor circle)
			)
			(primitives
				(gr_poly
					(pts
						(arc
							(start -0.3302 -0.4318)
							(mid -0.402042 -0.402042)
							(end -0.4318 -0.3302)
						)
						(arc
							(start -0.4318 0.3302)
							(mid -0.402042 0.402042)
							(end -0.3302 0.4318)
						)
						(arc
							(start 0.3302 0.4318)
							(mid 0.402042 0.402042)
							(end 0.4318 0.3302)
						)
						(arc
							(start 0.4318 -0.3302)
							(mid 0.402042 -0.402042)
							(end 0.3302 -0.4318)
						)
					)
					(width 0)
					(fill yes)
				)
			)
		)
		(pad "2" smd custom
			(at 0 0.762 270)
			(size 0.2159 0.2159)
			(layers "F.Cu" "F.Mask" "F.Paste")
			(net "GND")
			(options
				(clearance outline)
				(anchor circle)
			)
			(primitives
				(gr_poly
					(pts
						(arc
							(start -0.3302 -0.4318)
							(mid -0.402042 -0.402042)
							(end -0.4318 -0.3302)
						)
						(arc
							(start -0.4318 0.3302)
							(mid -0.402042 0.402042)
							(end -0.3302 0.4318)
						)
						(arc
							(start 0.3302 0.4318)
							(mid 0.402042 0.402042)
							(end 0.4318 0.3302)
						)
						(arc
							(start 0.4318 -0.3302)
							(mid 0.402042 -0.402042)
							(end 0.3302 -0.4318)
						)
					)
					(width 0)
					(fill yes)
				)
			)
		)
	)
	(footprint ""
		(layer "F.Cu")
		(at 472.313 -30.607 90)
		(property "Reference" "R1W22"
			(at -0.8382 -0.67818 90)
			(unlocked yes)
			(layer "F.SilkS")
			(effects
				(font
					(size 0.4064 0.254)
					(thickness 0.1524)
				)
				(justify left)
			)
		)
		(property "Value" ""
			(at 0 0 90)
			(layer "F.Fab")
			(effects
				(font
					(size 1.27 1.27)
				)
			)
		)
		(duplicate_pad_numbers_are_jumpers no)
		(fp_poly
			(pts
				(xy -0.2794 -0.1016) (xy 0.2794 -0.1016) (xy 0.2794 0.9906) (xy -0.2794 0.9906)
			)
			(stroke
				(width 0)
				(type default)
			)
			(fill no)
			(layer "F.CrtYd")
		)
		(fp_line
			(start 0.2794 -0.1016)
			(end -0.2794 -0.1016)
			(stroke
				(width 0.1)
				(type default)
			)
			(layer "F.Fab")
		)
		(fp_line
			(start -0.2794 -0.1016)
			(end -0.2794 0.9906)
			(stroke
				(width 0.1)
				(type default)
			)
			(layer "F.Fab")
		)
		(fp_line
			(start 0.2794 0.9906)
			(end 0.2794 -0.1016)
			(stroke
				(width 0.1)
				(type default)
			)
			(layer "F.Fab")
		)
		(fp_line
			(start -0.2794 0.9906)
			(end 0.2794 0.9906)
			(stroke
				(width 0.1)
				(type default)
			)
			(layer "F.Fab")
		)
		(pad "1" smd rect
			(at 0 0 90)
			(size 0.508 0.508)
			(layers "F.Cu" "F.Mask" "F.Paste")
			(net "SMB_HOST_STBY_LVC3_SCL")
		)
		(pad "2" smd rect
			(at 0 0.889 90)
			(size 0.508 0.508)
			(layers "F.Cu" "F.Mask" "F.Paste")
			(net "SMB_HOST_STBY_LVC3_SCL_R4")
		)
		(zone
			(layer "F.Cu")
			(hatch none 0.5)
			(connect_pads
				(clearance 0)
			)
			(min_thickness 0.25)
			(keepout
				(tracks allowed)
				(vias not_allowed)
				(pads allowed)
				(copperpour not_allowed)
				(footprints allowed)
			)
			(placement
				(enabled no)
				(sheetname "")
			)
			(fill
				(thermal_gap 0.5)
				(thermal_bridge_width 0.5)
				(island_removal_mode 0)
			)
			(polygon
				(pts
					(xy 472.567 -30.353) (xy 472.567 -30.861) (xy 472.948 -30.861) (xy 472.948 -30.353)
				)
			)
		)
		(zone
			(layer "F.Cu")
			(hatch none 0.5)
			(connect_pads
				(clearance 0)
			)
			(min_thickness 0.25)
			(keepout
				(tracks not_allowed)
				(vias allowed)
				(pads allowed)
				(copperpour not_allowed)
				(footprints allowed)
			)
			(placement
				(enabled no)
				(sheetname "")
			)
			(fill
				(thermal_gap 0.5)
				(thermal_bridge_width 0.5)
				(island_removal_mode 0)
			)
			(polygon
				(pts
					(xy 472.948 -30.353) (xy 472.948 -30.861) (xy 472.567 -30.861) (xy 472.567 -30.353)
				)
			)
		)
	)
	(footprint ""
		(layer "F.Cu")
		(at 408.319478 -119.051832 90)
		(property "Reference" "R1W14"
			(at -0.8382 -0.67818 90)
			(unlocked yes)
			(layer "F.SilkS")
			(effects
				(font
					(size 0.4064 0.254)
					(thickness 0.1524)
				)
				(justify left)
			)
		)
		(property "Value" ""
			(at 0 0 90)
			(layer "F.Fab")
			(effects
				(font
					(size 1.27 1.27)
				)
			)
		)
		(duplicate_pad_numbers_are_jumpers no)
		(fp_poly
			(pts
				(xy -0.2794 -0.1016) (xy 0.2794 -0.1016) (xy 0.2794 0.9906) (xy -0.2794 0.9906)
			)
			(stroke
				(width 0)
				(type default)
			)
			(fill no)
			(layer "F.CrtYd")
		)
		(fp_line
			(start 0.2794 -0.1016)
			(end -0.2794 -0.1016)
			(stroke
				(width 0.1)
				(type default)
			)
			(layer "F.Fab")
		)
		(fp_line
			(start -0.2794 -0.1016)
			(end -0.2794 0.9906)
			(stroke
				(width 0.1)
				(type default)
			)
			(layer "F.Fab")
		)
		(fp_line
			(start 0.2794 0.9906)
			(end 0.2794 -0.1016)
			(stroke
				(width 0.1)
				(type default)
			)
			(layer "F.Fab")
		)
		(fp_line
			(start -0.2794 0.9906)
			(end 0.2794 0.9906)
			(stroke
				(width 0.1)
				(type default)
			)
			(layer "F.Fab")
		)
		(pad "1" smd rect
			(at 0 0 90)
			(size 0.508 0.508)
			(layers "F.Cu" "F.Mask" "F.Paste")
			(net "USB2_PCH_BMC_P5_DP_R")
		)
		(pad "2" smd rect
			(at 0 0.889 90)
			(size 0.508 0.508)
			(layers "F.Cu" "F.Mask" "F.Paste")
			(net "USB2_PCH_BMC_P5_DP")
		)
		(zone
			(layer "F.Cu")
			(hatch none 0.5)
			(connect_pads
				(clearance 0)
			)
			(min_thickness 0.25)
			(keepout
				(tracks allowed)
				(vias not_allowed)
				(pads allowed)
				(copperpour not_allowed)
				(footprints allowed)
			)
			(placement
				(enabled no)
				(sheetname "")
			)
			(fill
				(thermal_gap 0.5)
				(thermal_bridge_width 0.5)
				(island_removal_mode 0)
			)
			(polygon
				(pts
					(xy 408.573478 -118.797832) (xy 408.573478 -119.305832) (xy 408.954478 -119.305832) (xy 408.954478 -118.797832)
				)
			)
		)
		(zone
			(layer "F.Cu")
			(hatch none 0.5)
			(connect_pads
				(clearance 0)
			)
			(min_thickness 0.25)
			(keepout
				(tracks not_allowed)
				(vias allowed)
				(pads allowed)
				(copperpour not_allowed)
				(footprints allowed)
			)
			(placement
				(enabled no)
				(sheetname "")
			)
			(fill
				(thermal_gap 0.5)
				(thermal_bridge_width 0.5)
				(island_removal_mode 0)
			)
			(polygon
				(pts
					(xy 408.954478 -118.797832) (xy 408.954478 -119.305832) (xy 408.573478 -119.305832) (xy 408.573478 -118.797832)
				)
			)
		)
	)
	(footprint ""
		(layer "F.Cu")
		(at 352.1075 -150.368 90)
		(property "Reference" "C7A11"
			(at 0 0 90)
			(layer "F.SilkS")
			(hide yes)
			(effects
				(font
					(size 1.27 1.27)
				)
			)
		)
		(property "Value" ""
			(at 0 0 90)
			(layer "F.Fab")
			(effects
				(font
					(size 1.27 1.27)
				)
			)
		)
		(duplicate_pad_numbers_are_jumpers no)
		(fp_poly
			(pts
				(xy 0.3048 -0.1016) (xy 0.3048 0.9906) (xy -0.3048 0.9906) (xy -0.3048 -0.1016)
			)
			(stroke
				(width 0)
				(type default)
			)
			(fill no)
			(layer "F.CrtYd")
		)
		(fp_line
			(start 0.3048 -0.1016)
			(end -0.3048 -0.1016)
			(stroke
				(width 0.1)
				(type default)
			)
			(layer "F.Fab")
		)
		(fp_line
			(start -0.3048 -0.1016)
			(end -0.3048 0.9906)
			(stroke
				(width 0.1)
				(type default)
			)
			(layer "F.Fab")
		)
		(fp_line
			(start 0.3048 0.9906)
			(end 0.3048 -0.1016)
			(stroke
				(width 0.1)
				(type default)
			)
			(layer "F.Fab")
		)
		(fp_line
			(start -0.3048 0.9906)
			(end 0.3048 0.9906)
			(stroke
				(width 0.1)
				(type default)
			)
			(layer "F.Fab")
		)
		(pad "1" smd rect
			(at 0 0 90)
			(size 0.508 0.508)
			(layers "F.Cu" "F.Mask" "F.Paste")
			(net "VR_FET_SW_P12V_STBY_PVDDQ_DEF")
		)
		(pad "2" smd rect
			(at 0 0.889 90)
			(size 0.508 0.508)
			(layers "F.Cu" "F.Mask" "F.Paste")
			(net "GND")
		)
		(zone
			(layer "F.Cu")
			(hatch none 0.5)
			(connect_pads
				(clearance 0)
			)
			(min_thickness 0.25)
			(keepout
				(tracks allowed)
				(vias not_allowed)
				(pads allowed)
				(copperpour not_allowed)
				(footprints allowed)
			)
			(placement
				(enabled no)
				(sheetname "")
			)
			(fill
				(thermal_gap 0.5)
				(thermal_bridge_width 0.5)
				(island_removal_mode 0)
			)
			(polygon
				(pts
					(xy 352.3615 -150.114) (xy 352.3615 -150.622) (xy 352.7425 -150.622) (xy 352.7425 -150.114)
				)
			)
		)
		(zone
			(layer "F.Cu")
			(hatch none 0.5)
			(connect_pads
				(clearance 0)
			)
			(min_thickness 0.25)
			(keepout
				(tracks not_allowed)
				(vias allowed)
				(pads allowed)
				(copperpour not_allowed)
				(footprints allowed)
			)
			(placement
				(enabled no)
				(sheetname "")
			)
			(fill
				(thermal_gap 0.5)
				(thermal_bridge_width 0.5)
				(island_removal_mode 0)
			)
			(polygon
				(pts
					(xy 352.7425 -150.114) (xy 352.7425 -150.622) (xy 352.3615 -150.622) (xy 352.3615 -150.114)
				)
			)
		)
	)
	(footprint ""
		(layer "F.Cu")
		(at 463.003392 -37.956998)
		(property "Reference" "C9F9"
			(at 0 0 0)
			(layer "F.SilkS")
			(hide yes)
			(effects
				(font
					(size 1.27 1.27)
				)
			)
		)
		(property "Value" ""
			(at 0 0 0)
			(layer "F.Fab")
			(effects
				(font
					(size 1.27 1.27)
				)
			)
		)
		(duplicate_pad_numbers_are_jumpers no)
		(fp_poly
			(pts
				(xy 0.3048 -0.1016) (xy 0.3048 0.9906) (xy -0.3048 0.9906) (xy -0.3048 -0.1016)
			)
			(stroke
				(width 0)
				(type default)
			)
			(fill no)
			(layer "F.CrtYd")
		)
		(fp_line
			(start -0.3048 -0.1016)
			(end -0.3048 0.9906)
			(stroke
				(width 0.1)
				(type default)
			)
			(layer "F.Fab")
		)
		(fp_line
			(start -0.3048 0.9906)
			(end 0.3048 0.9906)
			(stroke
				(width 0.1)
				(type default)
			)
			(layer "F.Fab")
		)
		(fp_line
			(start 0.3048 -0.1016)
			(end -0.3048 -0.1016)
			(stroke
				(width 0.1)
				(type default)
			)
			(layer "F.Fab")
		)
		(fp_line
			(start 0.3048 0.9906)
			(end 0.3048 -0.1016)
			(stroke
				(width 0.1)
				(type default)
			)
			(layer "F.Fab")
		)
		(pad "1" smd rect
			(at 0 0)
			(size 0.508 0.508)
			(layers "F.Cu" "F.Mask" "F.Paste")
			(net "PWRGD_P1V2_BMC_STBY")
		)
		(pad "2" smd rect
			(at 0 0.889)
			(size 0.508 0.508)
			(layers "F.Cu" "F.Mask" "F.Paste")
			(net "GND")
		)
		(zone
			(layer "F.Cu")
			(hatch none 0.5)
			(connect_pads
				(clearance 0)
			)
			(min_thickness 0.25)
			(keepout
				(tracks allowed)
				(vias not_allowed)
				(pads allowed)
				(copperpour not_allowed)
				(footprints allowed)
			)
			(placement
				(enabled no)
				(sheetname "")
			)
			(fill
				(thermal_gap 0.5)
				(thermal_bridge_width 0.5)
				(island_removal_mode 0)
			)
			(polygon
				(pts
					(xy 462.749392 -37.702998) (xy 463.257392 -37.702998) (xy 463.257392 -37.321998) (xy 462.749392 -37.321998)
				)
			)
		)
		(zone
			(layer "F.Cu")
			(hatch none 0.5)
			(connect_pads
				(clearance 0)
			)
			(min_thickness 0.25)
			(keepout
				(tracks not_allowed)
				(vias allowed)
				(pads allowed)
				(copperpour not_allowed)
				(footprints allowed)
			)
			(placement
				(enabled no)
				(sheetname "")
			)
			(fill
				(thermal_gap 0.5)
				(thermal_bridge_width 0.5)
				(island_removal_mode 0)
			)
			(polygon
				(pts
					(xy 462.749392 -37.321998) (xy 463.257392 -37.321998) (xy 463.257392 -37.702998) (xy 462.749392 -37.702998)
				)
			)
		)
	)
	(footprint ""
		(layer "F.Cu")
		(at 164.084 -64.9224 180)
		(property "Reference" "R4E7"
			(at 0 0 180)
			(layer "F.SilkS")
			(hide yes)
			(effects
				(font
					(size 1.27 1.27)
				)
			)
		)
		(property "Value" ""
			(at 0 0 180)
			(layer "F.Fab")
			(effects
				(font
					(size 1.27 1.27)
				)
			)
		)
		(duplicate_pad_numbers_are_jumpers no)
		(fp_poly
			(pts
				(xy -0.2794 -0.1016) (xy 0.2794 -0.1016) (xy 0.2794 0.9906) (xy -0.2794 0.9906)
			)
			(stroke
				(width 0)
				(type default)
			)
			(fill no)
			(layer "F.CrtYd")
		)
		(fp_line
			(start 0.2794 0.9906)
			(end 0.2794 -0.1016)
			(stroke
				(width 0.1)
				(type default)
			)
			(layer "F.Fab")
		)
		(fp_line
			(start 0.2794 -0.1016)
			(end -0.2794 -0.1016)
			(stroke
				(width 0.1)
				(type default)
			)
			(layer "F.Fab")
		)
		(fp_line
			(start -0.2794 0.9906)
			(end 0.2794 0.9906)
			(stroke
				(width 0.1)
				(type default)
			)
			(layer "F.Fab")
		)
		(fp_line
			(start -0.2794 -0.1016)
			(end -0.2794 0.9906)
			(stroke
				(width 0.1)
				(type default)
			)
			(layer "F.Fab")
		)
		(pad "1" smd rect
			(at 0 0 180)
			(size 0.508 0.508)
			(layers "F.Cu" "F.Mask" "F.Paste")
			(net "VSENSE_PVCCIO_CPU1_AVSP")
		)
		(pad "2" smd rect
			(at 0 0.889 180)
			(size 0.508 0.508)
			(layers "F.Cu" "F.Mask" "F.Paste")
			(net "VR_PVCCIO_CPU1_AVSP")
		)
		(zone
			(layer "F.Cu")
			(hatch none 0.5)
			(connect_pads
				(clearance 0)
			)
			(min_thickness 0.25)
			(keepout
				(tracks not_allowed)
				(vias allowed)
				(pads allowed)
				(copperpour not_allowed)
				(footprints allowed)
			)
			(placement
				(enabled no)
				(sheetname "")
			)
			(fill
				(thermal_gap 0.5)
				(thermal_bridge_width 0.5)
				(island_removal_mode 0)
			)
			(polygon
				(pts
					(xy 164.338 -65.5574) (xy 163.83 -65.5574) (xy 163.83 -65.1764) (xy 164.338 -65.1764)
				)
			)
		)
		(zone
			(layer "F.Cu")
			(hatch none 0.5)
			(connect_pads
				(clearance 0)
			)
			(min_thickness 0.25)
			(keepout
				(tracks allowed)
				(vias not_allowed)
				(pads allowed)
				(copperpour not_allowed)
				(footprints allowed)
			)
			(placement
				(enabled no)
				(sheetname "")
			)
			(fill
				(thermal_gap 0.5)
				(thermal_bridge_width 0.5)
				(island_removal_mode 0)
			)
			(polygon
				(pts
					(xy 164.338 -65.1764) (xy 163.83 -65.1764) (xy 163.83 -65.5574) (xy 164.338 -65.5574)
				)
			)
		)
	)
	(footprint ""
		(layer "F.Cu")
		(at 23.114 -74.549 -90)
		(property "Reference" "R1D37"
			(at 0 0 270)
			(layer "F.SilkS")
			(hide yes)
			(effects
				(font
					(size 1.27 1.27)
				)
			)
		)
		(property "Value" ""
			(at 0 0 270)
			(layer "F.Fab")
			(effects
				(font
					(size 1.27 1.27)
				)
			)
		)
		(duplicate_pad_numbers_are_jumpers no)
		(fp_poly
			(pts
				(xy -0.2794 -0.1016) (xy 0.2794 -0.1016) (xy 0.2794 0.9906) (xy -0.2794 0.9906)
			)
			(stroke
				(width 0)
				(type default)
			)
			(fill no)
			(layer "F.CrtYd")
		)
		(fp_line
			(start -0.2794 0.9906)
			(end 0.2794 0.9906)
			(stroke
				(width 0.1)
				(type default)
			)
			(layer "F.Fab")
		)
		(fp_line
			(start 0.2794 0.9906)
			(end 0.2794 -0.1016)
			(stroke
				(width 0.1)
				(type default)
			)
			(layer "F.Fab")
		)
		(fp_line
			(start -0.2794 -0.1016)
			(end -0.2794 0.9906)
			(stroke
				(width 0.1)
				(type default)
			)
			(layer "F.Fab")
		)
		(fp_line
			(start 0.2794 -0.1016)
			(end -0.2794 -0.1016)
			(stroke
				(width 0.1)
				(type default)
			)
			(layer "F.Fab")
		)
		(pad "1" smd rect
			(at 0 0 270)
			(size 0.508 0.508)
			(layers "F.Cu" "F.Mask" "F.Paste")
			(net "A_HSC_VCAP")
		)
		(pad "2" smd rect
			(at 0 0.889 270)
			(size 0.508 0.508)
			(layers "F.Cu" "F.Mask" "F.Paste")
			(net "A_HSC_ISET")
		)
		(zone
			(layer "F.Cu")
			(hatch none 0.5)
			(connect_pads
				(clearance 0)
			)
			(min_thickness 0.25)
			(keepout
				(tracks not_allowed)
				(vias allowed)
				(pads allowed)
				(copperpour not_allowed)
				(footprints allowed)
			)
			(placement
				(enabled no)
				(sheetname "")
			)
			(fill
				(thermal_gap 0.5)
				(thermal_bridge_width 0.5)
				(island_removal_mode 0)
			)
			(polygon
				(pts
					(xy 22.479 -74.803) (xy 22.479 -74.295) (xy 22.86 -74.295) (xy 22.86 -74.803)
				)
			)
		)
		(zone
			(layer "F.Cu")
			(hatch none 0.5)
			(connect_pads
				(clearance 0)
			)
			(min_thickness 0.25)
			(keepout
				(tracks allowed)
				(vias not_allowed)
				(pads allowed)
				(copperpour not_allowed)
				(footprints allowed)
			)
			(placement
				(enabled no)
				(sheetname "")
			)
			(fill
				(thermal_gap 0.5)
				(thermal_bridge_width 0.5)
				(island_removal_mode 0)
			)
			(polygon
				(pts
					(xy 22.86 -74.803) (xy 22.86 -74.295) (xy 22.479 -74.295) (xy 22.479 -74.803)
				)
			)
		)
	)
	(footprint ""
		(layer "F.Cu")
		(at 379.984 -88.2015)
		(property "Reference" "R3N24"
			(at 0 0 0)
			(layer "F.SilkS")
			(hide yes)
			(effects
				(font
					(size 1.27 1.27)
				)
			)
		)
		(property "Value" ""
			(at 0 0 0)
			(layer "F.Fab")
			(effects
				(font
					(size 1.27 1.27)
				)
			)
		)
		(duplicate_pad_numbers_are_jumpers no)
		(fp_poly
			(pts
				(xy -0.2794 -0.1016) (xy 0.2794 -0.1016) (xy 0.2794 0.9906) (xy -0.2794 0.9906)
			)
			(stroke
				(width 0)
				(type default)
			)
			(fill no)
			(layer "F.CrtYd")
		)
		(fp_line
			(start -0.2794 -0.1016)
			(end -0.2794 0.9906)
			(stroke
				(width 0.1)
				(type default)
			)
			(layer "F.Fab")
		)
		(fp_line
			(start -0.2794 0.9906)
			(end 0.2794 0.9906)
			(stroke
				(width 0.1)
				(type default)
			)
			(layer "F.Fab")
		)
		(fp_line
			(start 0.2794 -0.1016)
			(end -0.2794 -0.1016)
			(stroke
				(width 0.1)
				(type default)
			)
			(layer "F.Fab")
		)
		(fp_line
			(start 0.2794 0.9906)
			(end 0.2794 -0.1016)
			(stroke
				(width 0.1)
				(type default)
			)
			(layer "F.Fab")
		)
		(pad "1" smd rect
			(at 0 0)
			(size 0.508 0.508)
			(layers "F.Cu" "F.Mask" "F.Paste")
			(net "LPC_LAD2_IO2")
		)
		(pad "2" smd rect
			(at 0 0.889)
			(size 0.508 0.508)
			(layers "F.Cu" "F.Mask" "F.Paste")
			(net "LPC_LAD2_IO2_R")
		)
		(zone
			(layer "F.Cu")
			(hatch none 0.5)
			(connect_pads
				(clearance 0)
			)
			(min_thickness 0.25)
			(keepout
				(tracks allowed)
				(vias not_allowed)
				(pads allowed)
				(copperpour not_allowed)
				(footprints allowed)
			)
			(placement
				(enabled no)
				(sheetname "")
			)
			(fill
				(thermal_gap 0.5)
				(thermal_bridge_width 0.5)
				(island_removal_mode 0)
			)
			(polygon
				(pts
					(xy 379.73 -87.9475) (xy 380.238 -87.9475) (xy 380.238 -87.5665) (xy 379.73 -87.5665)
				)
			)
		)
		(zone
			(layer "F.Cu")
			(hatch none 0.5)
			(connect_pads
				(clearance 0)
			)
			(min_thickness 0.25)
			(keepout
				(tracks not_allowed)
				(vias allowed)
				(pads allowed)
				(copperpour not_allowed)
				(footprints allowed)
			)
			(placement
				(enabled no)
				(sheetname "")
			)
			(fill
				(thermal_gap 0.5)
				(thermal_bridge_width 0.5)
				(island_removal_mode 0)
			)
			(polygon
				(pts
					(xy 379.73 -87.5665) (xy 380.238 -87.5665) (xy 380.238 -87.9475) (xy 379.73 -87.9475)
				)
			)
		)
	)
	(footprint ""
		(layer "F.Cu")
		(at 198.87946 -30.861 180)
		(property "Reference" "C4F6"
			(at 0.75946 -3.83667 0)
			(unlocked yes)
			(layer "F.SilkS")
			(effects
				(font
					(size 0.7874 0.5842)
					(thickness 0.1524)
				)
			)
		)
		(property "Value" ""
			(at 0 0 180)
			(layer "F.Fab")
			(effects
				(font
					(size 1.27 1.27)
				)
			)
		)
		(duplicate_pad_numbers_are_jumpers no)
		(fp_line
			(start 5.1435 9.271)
			(end 1.4097 9.271)
			(stroke
				(width 0.1524)
				(type default)
			)
			(layer "F.SilkS")
		)
		(fp_line
			(start 5.1435 -0.127)
			(end 5.1435 9.271)
			(stroke
				(width 0.1524)
				(type default)
			)
			(layer "F.SilkS")
		)
		(fp_line
			(start 4.3815 -1.016)
			(end 5.1435 -0.127)
			(stroke
				(width 0.1524)
				(type default)
			)
			(layer "F.SilkS")
		)
		(fp_line
			(start 1.8415 2.0955)
			(end 1.4097 2.0955)
			(stroke
				(width 0.1524)
				(type default)
			)
			(layer "F.SilkS")
		)
		(fp_line
			(start 1.8415 -1.016)
			(end 4.3815 -1.016)
			(stroke
				(width 0.1524)
				(type default)
			)
			(layer "F.SilkS")
		)
		(fp_line
			(start 1.8415 -2.0955)
			(end 1.8415 2.0955)
			(stroke
				(width 0.1524)
				(type default)
			)
			(layer "F.SilkS")
		)
		(fp_line
			(start 1.4097 -2.0955)
			(end 1.8415 -2.0955)
			(stroke
				(width 0.1524)
				(type default)
			)
			(layer "F.SilkS")
		)
		(fp_line
			(start -1.4097 9.271)
			(end -5.1435 9.271)
			(stroke
				(width 0.1524)
				(type default)
			)
			(layer "F.SilkS")
		)
		(fp_line
			(start -1.4097 -2.0955)
			(end -1.8415 -2.0955)
			(stroke
				(width 0.1524)
				(type default)
			)
			(layer "F.SilkS")
		)
		(fp_line
			(start -1.8415 2.0955)
			(end -1.4097 2.0955)
			(stroke
				(width 0.1524)
				(type default)
			)
			(layer "F.SilkS")
		)
		(fp_line
			(start -1.8415 -2.0955)
			(end -1.8415 2.0955)
			(stroke
				(width 0.1524)
				(type default)
			)
			(layer "F.SilkS")
		)
		(fp_line
			(start -4.3815 -1.016)
			(end -1.8415 -1.016)
			(stroke
				(width 0.1524)
				(type default)
			)
			(layer "F.SilkS")
		)
		(fp_line
			(start -5.1435 9.271)
			(end -5.1435 -0.127)
			(stroke
				(width 0.1524)
				(type default)
			)
			(layer "F.SilkS")
		)
		(fp_line
			(start -5.1435 -0.127)
			(end -4.3815 -1.016)
			(stroke
				(width 0.1524)
				(type default)
			)
			(layer "F.SilkS")
		)
		(fp_poly
			(pts
				(xy -5.14604 -0.12954) (xy -4.38404 -1.01346) (xy 4.37896 -1.016) (xy 5.1435 -0.12954) (xy 5.14096 9.271)
				(xy -5.14604 9.27354)
			)
			(stroke
				(width 0)
				(type default)
			)
			(fill no)
			(layer "F.CrtYd")
		)
		(fp_line
			(start 5.1435 9.271)
			(end -5.1435 9.271)
			(stroke
				(width 0.1)
				(type default)
			)
			(layer "F.Fab")
		)
		(fp_line
			(start 5.1435 -0.127)
			(end 5.1435 9.271)
			(stroke
				(width 0.1)
				(type default)
			)
			(layer "F.Fab")
		)
		(fp_line
			(start 4.3815 -1.016)
			(end 5.1435 -0.127)
			(stroke
				(width 0.1)
				(type default)
			)
			(layer "F.Fab")
		)
		(fp_line
			(start -4.3815 -1.016)
			(end 4.3815 -1.016)
			(stroke
				(width 0.1)
				(type default)
			)
			(layer "F.Fab")
		)
		(fp_line
			(start -5.1435 9.271)
			(end -5.1435 -0.127)
			(stroke
				(width 0.1)
				(type default)
			)
			(layer "F.Fab")
		)
		(fp_line
			(start -5.1435 -0.127)
			(end -4.3815 -1.016)
			(stroke
				(width 0.1)
				(type default)
			)
			(layer "F.Fab")
		)
		(fp_circle
			(center 0 4.1275)
			(end -4.9911 4.1275)
			(stroke
				(width 0.1)
				(type default)
			)
			(fill no)
			(layer "F.Fab")
		)
		(pad "1" smd rect
			(at 0 0 180)
			(size 1.905 4.191)
			(layers "F.Cu" "F.Mask" "F.Paste")
			(net "P12V_STBY")
		)
		(pad "2" smd rect
			(at 0 8.255 180)
			(size 1.905 4.191)
			(layers "F.Cu" "F.Mask" "F.Paste")
			(net "GND")
		)
		(zone
			(layer "F.Cu")
			(hatch none 0.5)
			(connect_pads
				(clearance 0)
			)
			(min_thickness 0.25)
			(keepout
				(tracks allowed)
				(vias not_allowed)
				(pads allowed)
				(copperpour not_allowed)
				(footprints allowed)
			)
			(placement
				(enabled no)
				(sheetname "")
			)
			(fill
				(thermal_gap 0.5)
				(thermal_bridge_width 0.5)
				(island_removal_mode 0)
			)
			(polygon
				(pts
					(xy 204.02296 -40.132) (xy 193.73596 -40.132) (xy 193.73596 -30.734) (xy 194.49796 -29.845) (xy 203.26096 -29.845)
					(xy 204.02296 -30.734)
				)
			)
		)
	)
	(footprint ""
		(layer "F.Cu")
		(at 399.67408 -155.08986)
		(property "Reference" "R8W3"
			(at -0.8382 -0.67818 0)
			(unlocked yes)
			(layer "F.SilkS")
			(effects
				(font
					(size 0.4064 0.254)
					(thickness 0.1524)
				)
				(justify left)
			)
		)
		(property "Value" ""
			(at 0 0 0)
			(layer "F.Fab")
			(effects
				(font
					(size 1.27 1.27)
				)
			)
		)
		(duplicate_pad_numbers_are_jumpers no)
		(fp_poly
			(pts
				(xy -0.2794 -0.1016) (xy 0.2794 -0.1016) (xy 0.2794 0.9906) (xy -0.2794 0.9906)
			)
			(stroke
				(width 0)
				(type default)
			)
			(fill no)
			(layer "F.CrtYd")
		)
		(fp_line
			(start -0.2794 -0.1016)
			(end -0.2794 0.9906)
			(stroke
				(width 0.1)
				(type default)
			)
			(layer "F.Fab")
		)
		(fp_line
			(start -0.2794 0.9906)
			(end 0.2794 0.9906)
			(stroke
				(width 0.1)
				(type default)
			)
			(layer "F.Fab")
		)
		(fp_line
			(start 0.2794 -0.1016)
			(end -0.2794 -0.1016)
			(stroke
				(width 0.1)
				(type default)
			)
			(layer "F.Fab")
		)
		(fp_line
			(start 0.2794 0.9906)
			(end 0.2794 -0.1016)
			(stroke
				(width 0.1)
				(type default)
			)
			(layer "F.Fab")
		)
		(pad "1" smd rect
			(at 0 0)
			(size 0.508 0.508)
			(layers "F.Cu" "F.Mask" "F.Paste")
			(net "VR_PVNN_P1V05_PCH_VD12")
		)
		(pad "2" smd rect
			(at 0 0.889)
			(size 0.508 0.508)
			(layers "F.Cu" "F.Mask" "F.Paste")
			(net "PU_PVNN_PCH_VDIO")
		)
		(zone
			(layer "F.Cu")
			(hatch none 0.5)
			(connect_pads
				(clearance 0)
			)
			(min_thickness 0.25)
			(keepout
				(tracks allowed)
				(vias not_allowed)
				(pads allowed)
				(copperpour not_allowed)
				(footprints allowed)
			)
			(placement
				(enabled no)
				(sheetname "")
			)
			(fill
				(thermal_gap 0.5)
				(thermal_bridge_width 0.5)
				(island_removal_mode 0)
			)
			(polygon
				(pts
					(xy 399.42008 -154.83586) (xy 399.92808 -154.83586) (xy 399.92808 -154.45486) (xy 399.42008 -154.45486)
				)
			)
		)
		(zone
			(layer "F.Cu")
			(hatch none 0.5)
			(connect_pads
				(clearance 0)
			)
			(min_thickness 0.25)
			(keepout
				(tracks not_allowed)
				(vias allowed)
				(pads allowed)
				(copperpour not_allowed)
				(footprints allowed)
			)
			(placement
				(enabled no)
				(sheetname "")
			)
			(fill
				(thermal_gap 0.5)
				(thermal_bridge_width 0.5)
				(island_removal_mode 0)
			)
			(polygon
				(pts
					(xy 399.42008 -154.45486) (xy 399.92808 -154.45486) (xy 399.92808 -154.83586) (xy 399.42008 -154.83586)
				)
			)
		)
	)
	(footprint ""
		(layer "F.Cu")
		(at 192.685162 -125.774958 180)
		(property "Reference" "R4B12"
			(at 0 0 180)
			(layer "F.SilkS")
			(hide yes)
			(effects
				(font
					(size 1.27 1.27)
				)
			)
		)
		(property "Value" ""
			(at 0 0 180)
			(layer "F.Fab")
			(effects
				(font
					(size 1.27 1.27)
				)
			)
		)
		(duplicate_pad_numbers_are_jumpers no)
		(fp_line
			(start 0.9017 1.952498)
			(end 0.9017 0.853948)
			(stroke
				(width 0.1524)
				(type default)
			)
			(layer "F.SilkS")
		)
		(fp_line
			(start -0.9017 1.951736)
			(end -0.9017 0.823468)
			(stroke
				(width 0.1524)
				(type default)
			)
			(layer "F.SilkS")
		)
		(fp_rect
			(start -0.9017 3.0988)
			(end 0.9017 -0.3048)
			(stroke
				(width 0)
				(type default)
			)
			(fill no)
			(layer "F.CrtYd")
		)
		(fp_line
			(start 0.9017 3.0988)
			(end 0.9017 -0.3048)
			(stroke
				(width 0.1)
				(type default)
			)
			(layer "F.Fab")
		)
		(fp_line
			(start 0.9017 -0.3048)
			(end -0.9017 -0.3048)
			(stroke
				(width 0.1)
				(type default)
			)
			(layer "F.Fab")
		)
		(fp_line
			(start -0.9017 3.0988)
			(end 0.9017 3.0988)
			(stroke
				(width 0.1)
				(type default)
			)
			(layer "F.Fab")
		)
		(fp_line
			(start -0.9017 -0.3048)
			(end -0.9017 3.0988)
			(stroke
				(width 0.1)
				(type default)
			)
			(layer "F.Fab")
		)
		(pad "1" smd rect
			(at 0 0 180)
			(size 1.524 1.016)
			(layers "F.Cu" "F.Mask" "F.Paste")
			(net "P12V_STBY")
		)
		(pad "2" smd rect
			(at 0 2.794 180)
			(size 1.524 1.016)
			(layers "F.Cu" "F.Mask" "F.Paste")
			(net "P12V_NVDIMM_DEF")
		)
		(zone
			(layer "F.Cu")
			(hatch none 0.5)
			(connect_pads
				(clearance 0)
			)
			(min_thickness 0.25)
			(keepout
				(tracks allowed)
				(vias not_allowed)
				(pads allowed)
				(copperpour not_allowed)
				(footprints allowed)
			)
			(placement
				(enabled no)
				(sheetname "")
			)
			(fill
				(thermal_gap 0.5)
				(thermal_bridge_width 0.5)
				(island_removal_mode 0)
			)
			(polygon
				(pts
					(xy 193.447162 -128.060958) (xy 191.923162 -128.060958) (xy 191.923162 -126.282958) (xy 193.447162 -126.282958)
				)
			)
		)
	)
	(footprint ""
		(layer "F.Cu")
		(at 433.084986 -21.505672 -90)
		(property "Reference" "U10W1"
			(at -0.14986 2.621788 270)
			(unlocked yes)
			(layer "F.SilkS")
			(effects
				(font
					(size 1.27 0.964946)
					(thickness 0.000001)
				)
				(justify left)
			)
		)
		(property "Value" ""
			(at 0 0 270)
			(layer "F.Fab")
			(effects
				(font
					(size 1.27 1.27)
				)
			)
		)
		(duplicate_pad_numbers_are_jumpers no)
		(fp_circle
			(center -0.4699 -0.8382)
			(end -0.4699 -0.9652)
			(stroke
				(width 0.254)
				(type default)
			)
			(fill no)
			(layer "F.SilkS")
		)
		(fp_poly
			(pts
				(xy 0.21463 -0.450088) (xy 1.56337 -0.450088) (xy 1.56337 1.75006) (xy 0.21463 1.75006)
			)
			(stroke
				(width 0)
				(type default)
			)
			(fill no)
			(layer "F.CrtYd")
		)
		(fp_line
			(start 0.21463 1.75006)
			(end 0.21463 -0.450088)
			(stroke
				(width 0.1)
				(type default)
			)
			(layer "F.Fab")
		)
		(fp_line
			(start 1.56337 1.75006)
			(end 0.21463 1.75006)
			(stroke
				(width 0.1)
				(type default)
			)
			(layer "F.Fab")
		)
		(fp_line
			(start 0.21463 -0.450088)
			(end 1.56337 -0.450088)
			(stroke
				(width 0.1)
				(type default)
			)
			(layer "F.Fab")
		)
		(fp_line
			(start 1.56337 -0.450088)
			(end 1.56337 1.75006)
			(stroke
				(width 0.1)
				(type default)
			)
			(layer "F.Fab")
		)
		(fp_circle
			(center -0.4699 -0.8382)
			(end -0.4699 -0.9652)
			(stroke
				(width 0.254)
				(type default)
			)
			(fill no)
			(layer "F.Fab")
		)
		(pad "1" smd rect
			(at 0 0 270)
			(size 1.016 0.381)
			(layers "F.Cu" "F.Mask" "F.Paste")
			(net "Net_6482")
		)
		(pad "2" smd rect
			(at 0 0.649986 270)
			(size 1.016 0.381)
			(layers "F.Cu" "F.Mask" "F.Paste")
			(net "PUMP_PWM_OUT")
		)
		(pad "3" smd rect
			(at 0 1.299972 270)
			(size 1.016 0.381)
			(layers "F.Cu" "F.Mask" "F.Paste")
			(net "GND")
		)
		(pad "4" smd rect
			(at 1.778 1.299972 270)
			(size 1.016 0.381)
			(layers "F.Cu" "F.Mask" "F.Paste")
			(net "PUMP_PWM_OUT_BUF")
		)
		(pad "5" smd rect
			(at 1.778 0 270)
			(size 1.016 0.381)
			(layers "F.Cu" "F.Mask" "F.Paste")
			(net "P3V3_STBY")
		)
	)
	(footprint ""
		(layer "F.Cu")
		(at 339.2932 -29.6672 -90)
		(property "Reference" "L7F1"
			(at -4.08813 5.7658 0)
			(unlocked yes)
			(layer "F.SilkS")
			(effects
				(font
					(size 0.7874 0.5842)
					(thickness 0.1524)
				)
				(justify left)
			)
		)
		(property "Value" ""
			(at 0 0 270)
			(layer "F.Fab")
			(effects
				(font
					(size 1.27 1.27)
				)
			)
		)
		(duplicate_pad_numbers_are_jumpers no)
		(fp_line
			(start -3.4036 6.1341)
			(end -3.4036 -0.6731)
			(stroke
				(width 0.1524)
				(type default)
			)
			(layer "F.SilkS")
		)
		(fp_line
			(start -2.5654 6.1341)
			(end -3.4036 6.1341)
			(stroke
				(width 0.1524)
				(type default)
			)
			(layer "F.SilkS")
		)
		(fp_line
			(start 3.4036 6.1341)
			(end 2.5654 6.1341)
			(stroke
				(width 0.1524)
				(type default)
			)
			(layer "F.SilkS")
		)
		(fp_line
			(start -3.4036 -0.6731)
			(end -2.5654 -0.6731)
			(stroke
				(width 0.1524)
				(type default)
			)
			(layer "F.SilkS")
		)
		(fp_line
			(start 2.5654 -0.6731)
			(end 3.4036 -0.6731)
			(stroke
				(width 0.1524)
				(type default)
			)
			(layer "F.SilkS")
		)
		(fp_line
			(start 3.4036 -0.6731)
			(end 3.4036 6.1341)
			(stroke
				(width 0.1524)
				(type default)
			)
			(layer "F.SilkS")
		)
		(fp_rect
			(start 3.4036 6.1341)
			(end -3.4036 -0.6731)
			(stroke
				(width 0)
				(type default)
			)
			(fill no)
			(layer "F.CrtYd")
		)
		(fp_line
			(start -3.4036 6.1341)
			(end -3.4036 -0.6731)
			(stroke
				(width 0.1)
				(type default)
			)
			(layer "F.Fab")
		)
		(fp_line
			(start 3.4036 6.1341)
			(end -3.4036 6.1341)
			(stroke
				(width 0.1)
				(type default)
			)
			(layer "F.Fab")
		)
		(fp_line
			(start -3.4036 -0.6731)
			(end 3.4036 -0.6731)
			(stroke
				(width 0.1)
				(type default)
			)
			(layer "F.Fab")
		)
		(fp_line
			(start 3.4036 -0.6731)
			(end 3.4036 6.1341)
			(stroke
				(width 0.1)
				(type default)
			)
			(layer "F.Fab")
		)
		(pad "1" smd rect
			(at 0 0 270)
			(size 3.556 3.175)
			(layers "F.Cu" "F.Mask" "F.Paste")
			(net "VR_PVPP_ABC_PHASE")
		)
		(pad "2" smd rect
			(at 0 5.461 270)
			(size 3.556 3.175)
			(layers "F.Cu" "F.Mask" "F.Paste")
			(net "PVPP_ABC")
		)
	)
	(footprint ""
		(layer "F.Cu")
		(at 320.296032 -12.954 90)
		(property "Reference" "C6G2"
			(at 0 0 90)
			(layer "F.SilkS")
			(hide yes)
			(effects
				(font
					(size 1.27 1.27)
				)
			)
		)
		(property "Value" ""
			(at 0 0 90)
			(layer "F.Fab")
			(effects
				(font
					(size 1.27 1.27)
				)
			)
		)
		(duplicate_pad_numbers_are_jumpers no)
		(fp_poly
			(pts
				(xy -0.4953 -0.2032) (xy 0.4953 -0.2032) (xy 0.4953 1.6002) (xy -0.4953 1.6002)
			)
			(stroke
				(width 0)
				(type default)
			)
			(fill no)
			(layer "F.CrtYd")
		)
		(fp_line
			(start 0.4953 -0.2032)
			(end 0.4953 1.6002)
			(stroke
				(width 0.1)
				(type default)
			)
			(layer "F.Fab")
		)
		(fp_line
			(start -0.4953 -0.2032)
			(end 0.4953 -0.2032)
			(stroke
				(width 0.1)
				(type default)
			)
			(layer "F.Fab")
		)
		(fp_line
			(start 0.4953 1.6002)
			(end -0.4953 1.6002)
			(stroke
				(width 0.1)
				(type default)
			)
			(layer "F.Fab")
		)
		(fp_line
			(start -0.4953 1.6002)
			(end -0.4953 -0.2032)
			(stroke
				(width 0.1)
				(type default)
			)
			(layer "F.Fab")
		)
		(pad "1" smd rect
			(at 0 0 90)
			(size 0.762 0.889)
			(layers "F.Cu" "F.Mask" "F.Paste")
			(net "PVPP_ABC")
		)
		(pad "2" smd rect
			(at 0 1.397 90)
			(size 0.762 0.889)
			(layers "F.Cu" "F.Mask" "F.Paste")
			(net "GND")
		)
		(zone
			(layer "F.Cu")
			(hatch none 0.5)
			(connect_pads
				(clearance 0)
			)
			(min_thickness 0.25)
			(keepout
				(tracks not_allowed)
				(vias allowed)
				(pads allowed)
				(copperpour not_allowed)
				(footprints allowed)
			)
			(placement
				(enabled no)
				(sheetname "")
			)
			(fill
				(thermal_gap 0.5)
				(thermal_bridge_width 0.5)
				(island_removal_mode 0)
			)
			(polygon
				(pts
					(xy 320.740532 -12.573) (xy 320.740532 -13.335) (xy 321.248532 -13.335) (xy 321.248532 -12.573)
				)
			)
		)
	)
	(footprint ""
		(layer "F.Cu")
		(at 489.712 -50.6349)
		(property "Reference" "R9E4"
			(at 0 0 0)
			(layer "F.SilkS")
			(hide yes)
			(effects
				(font
					(size 1.27 1.27)
				)
			)
		)
		(property "Value" ""
			(at 0 0 0)
			(layer "F.Fab")
			(effects
				(font
					(size 1.27 1.27)
				)
			)
		)
		(duplicate_pad_numbers_are_jumpers no)
		(fp_poly
			(pts
				(xy -0.2794 -0.1016) (xy 0.2794 -0.1016) (xy 0.2794 0.9906) (xy -0.2794 0.9906)
			)
			(stroke
				(width 0)
				(type default)
			)
			(fill no)
			(layer "F.CrtYd")
		)
		(fp_line
			(start -0.2794 -0.1016)
			(end -0.2794 0.9906)
			(stroke
				(width 0.1)
				(type default)
			)
			(layer "F.Fab")
		)
		(fp_line
			(start -0.2794 0.9906)
			(end 0.2794 0.9906)
			(stroke
				(width 0.1)
				(type default)
			)
			(layer "F.Fab")
		)
		(fp_line
			(start 0.2794 -0.1016)
			(end -0.2794 -0.1016)
			(stroke
				(width 0.1)
				(type default)
			)
			(layer "F.Fab")
		)
		(fp_line
			(start 0.2794 0.9906)
			(end 0.2794 -0.1016)
			(stroke
				(width 0.1)
				(type default)
			)
			(layer "F.Fab")
		)
		(pad "1" smd rect
			(at 0 0)
			(size 0.508 0.508)
			(layers "F.Cu" "F.Mask" "F.Paste")
			(net "P3V3_STBY")
		)
		(pad "2" smd rect
			(at 0 0.889)
			(size 0.508 0.508)
			(layers "F.Cu" "F.Mask" "F.Paste")
			(net "RST_PLTRST_SPRV_R_N")
		)
		(zone
			(layer "F.Cu")
			(hatch none 0.5)
			(connect_pads
				(clearance 0)
			)
			(min_thickness 0.25)
			(keepout
				(tracks allowed)
				(vias not_allowed)
				(pads allowed)
				(copperpour not_allowed)
				(footprints allowed)
			)
			(placement
				(enabled no)
				(sheetname "")
			)
			(fill
				(thermal_gap 0.5)
				(thermal_bridge_width 0.5)
				(island_removal_mode 0)
			)
			(polygon
				(pts
					(xy 489.458 -50.3809) (xy 489.966 -50.3809) (xy 489.966 -49.9999) (xy 489.458 -49.9999)
				)
			)
		)
		(zone
			(layer "F.Cu")
			(hatch none 0.5)
			(connect_pads
				(clearance 0)
			)
			(min_thickness 0.25)
			(keepout
				(tracks not_allowed)
				(vias allowed)
				(pads allowed)
				(copperpour not_allowed)
				(footprints allowed)
			)
			(placement
				(enabled no)
				(sheetname "")
			)
			(fill
				(thermal_gap 0.5)
				(thermal_bridge_width 0.5)
				(island_removal_mode 0)
			)
			(polygon
				(pts
					(xy 489.458 -49.9999) (xy 489.966 -49.9999) (xy 489.966 -50.3809) (xy 489.458 -50.3809)
				)
			)
		)
	)
	(footprint ""
		(layer "F.Cu")
		(at 489.3945 -143.876268 90)
		(property "Reference" "R1L25"
			(at 0 0 90)
			(layer "F.SilkS")
			(hide yes)
			(effects
				(font
					(size 1.27 1.27)
				)
			)
		)
		(property "Value" ""
			(at 0 0 90)
			(layer "F.Fab")
			(effects
				(font
					(size 1.27 1.27)
				)
			)
		)
		(duplicate_pad_numbers_are_jumpers no)
		(fp_poly
			(pts
				(xy -0.2794 -0.1016) (xy 0.2794 -0.1016) (xy 0.2794 0.9906) (xy -0.2794 0.9906)
			)
			(stroke
				(width 0)
				(type default)
			)
			(fill no)
			(layer "F.CrtYd")
		)
		(fp_line
			(start 0.2794 -0.1016)
			(end -0.2794 -0.1016)
			(stroke
				(width 0.1)
				(type default)
			)
			(layer "F.Fab")
		)
		(fp_line
			(start -0.2794 -0.1016)
			(end -0.2794 0.9906)
			(stroke
				(width 0.1)
				(type default)
			)
			(layer "F.Fab")
		)
		(fp_line
			(start 0.2794 0.9906)
			(end 0.2794 -0.1016)
			(stroke
				(width 0.1)
				(type default)
			)
			(layer "F.Fab")
		)
		(fp_line
			(start -0.2794 0.9906)
			(end 0.2794 0.9906)
			(stroke
				(width 0.1)
				(type default)
			)
			(layer "F.Fab")
		)
		(pad "1" smd rect
			(at 0 0 90)
			(size 0.508 0.508)
			(layers "F.Cu" "F.Mask" "F.Paste")
			(net "LED_POSTCODE_2")
		)
		(pad "2" smd rect
			(at 0 0.889 90)
			(size 0.508 0.508)
			(layers "F.Cu" "F.Mask" "F.Paste")
			(net "LED_POSTCODE_2_R")
		)
		(zone
			(layer "F.Cu")
			(hatch none 0.5)
			(connect_pads
				(clearance 0)
			)
			(min_thickness 0.25)
			(keepout
				(tracks allowed)
				(vias not_allowed)
				(pads allowed)
				(copperpour not_allowed)
				(footprints allowed)
			)
			(placement
				(enabled no)
				(sheetname "")
			)
			(fill
				(thermal_gap 0.5)
				(thermal_bridge_width 0.5)
				(island_removal_mode 0)
			)
			(polygon
				(pts
					(xy 489.6485 -143.622268) (xy 489.6485 -144.130268) (xy 490.0295 -144.130268) (xy 490.0295 -143.622268)
				)
			)
		)
		(zone
			(layer "F.Cu")
			(hatch none 0.5)
			(connect_pads
				(clearance 0)
			)
			(min_thickness 0.25)
			(keepout
				(tracks not_allowed)
				(vias allowed)
				(pads allowed)
				(copperpour not_allowed)
				(footprints allowed)
			)
			(placement
				(enabled no)
				(sheetname "")
			)
			(fill
				(thermal_gap 0.5)
				(thermal_bridge_width 0.5)
				(island_removal_mode 0)
			)
			(polygon
				(pts
					(xy 490.0295 -143.622268) (xy 490.0295 -144.130268) (xy 489.6485 -144.130268) (xy 489.6485 -143.622268)
				)
			)
		)
	)
	(footprint ""
		(layer "F.Cu")
		(at 401.13966 -151.72436 -90)
		(property "Reference" "R8A5"
			(at 0 0 270)
			(layer "F.SilkS")
			(hide yes)
			(effects
				(font
					(size 1.27 1.27)
				)
			)
		)
		(property "Value" ""
			(at 0 0 270)
			(layer "F.Fab")
			(effects
				(font
					(size 1.27 1.27)
				)
			)
		)
		(duplicate_pad_numbers_are_jumpers no)
		(fp_poly
			(pts
				(xy -0.2794 -0.1016) (xy 0.2794 -0.1016) (xy 0.2794 0.9906) (xy -0.2794 0.9906)
			)
			(stroke
				(width 0)
				(type default)
			)
			(fill no)
			(layer "F.CrtYd")
		)
		(fp_line
			(start -0.2794 0.9906)
			(end 0.2794 0.9906)
			(stroke
				(width 0.1)
				(type default)
			)
			(layer "F.Fab")
		)
		(fp_line
			(start 0.2794 0.9906)
			(end 0.2794 -0.1016)
			(stroke
				(width 0.1)
				(type default)
			)
			(layer "F.Fab")
		)
		(fp_line
			(start -0.2794 -0.1016)
			(end -0.2794 0.9906)
			(stroke
				(width 0.1)
				(type default)
			)
			(layer "F.Fab")
		)
		(fp_line
			(start 0.2794 -0.1016)
			(end -0.2794 -0.1016)
			(stroke
				(width 0.1)
				(type default)
			)
			(layer "F.Fab")
		)
		(pad "1" smd rect
			(at 0 0 270)
			(size 0.508 0.508)
			(layers "F.Cu" "F.Mask" "F.Paste")
			(net "P3V3_STBY")
		)
		(pad "2" smd rect
			(at 0 0.889 270)
			(size 0.508 0.508)
			(layers "F.Cu" "F.Mask" "F.Paste")
			(net "IRQ_PVNN_PCH_VRHOT_N")
		)
		(zone
			(layer "F.Cu")
			(hatch none 0.5)
			(connect_pads
				(clearance 0)
			)
			(min_thickness 0.25)
			(keepout
				(tracks not_allowed)
				(vias allowed)
				(pads allowed)
				(copperpour not_allowed)
				(footprints allowed)
			)
			(placement
				(enabled no)
				(sheetname "")
			)
			(fill
				(thermal_gap 0.5)
				(thermal_bridge_width 0.5)
				(island_removal_mode 0)
			)
			(polygon
				(pts
					(xy 400.50466 -151.97836) (xy 400.50466 -151.47036) (xy 400.88566 -151.47036) (xy 400.88566 -151.97836)
				)
			)
		)
		(zone
			(layer "F.Cu")
			(hatch none 0.5)
			(connect_pads
				(clearance 0)
			)
			(min_thickness 0.25)
			(keepout
				(tracks allowed)
				(vias not_allowed)
				(pads allowed)
				(copperpour not_allowed)
				(footprints allowed)
			)
			(placement
				(enabled no)
				(sheetname "")
			)
			(fill
				(thermal_gap 0.5)
				(thermal_bridge_width 0.5)
				(island_removal_mode 0)
			)
			(polygon
				(pts
					(xy 400.88566 -151.97836) (xy 400.88566 -151.47036) (xy 400.50466 -151.47036) (xy 400.50466 -151.97836)
				)
			)
		)
	)
	(footprint ""
		(layer "F.Cu")
		(at 176.0728 -106.74985)
		(property "Reference" "R4C11"
			(at 0 0 0)
			(layer "F.SilkS")
			(hide yes)
			(effects
				(font
					(size 1.27 1.27)
				)
			)
		)
		(property "Value" ""
			(at 0 0 0)
			(layer "F.Fab")
			(effects
				(font
					(size 1.27 1.27)
				)
			)
		)
		(duplicate_pad_numbers_are_jumpers no)
		(fp_poly
			(pts
				(xy -0.2794 -0.1016) (xy 0.2794 -0.1016) (xy 0.2794 0.9906) (xy -0.2794 0.9906)
			)
			(stroke
				(width 0)
				(type default)
			)
			(fill no)
			(layer "F.CrtYd")
		)
		(fp_line
			(start -0.2794 -0.1016)
			(end -0.2794 0.9906)
			(stroke
				(width 0.1)
				(type default)
			)
			(layer "F.Fab")
		)
		(fp_line
			(start -0.2794 0.9906)
			(end 0.2794 0.9906)
			(stroke
				(width 0.1)
				(type default)
			)
			(layer "F.Fab")
		)
		(fp_line
			(start 0.2794 -0.1016)
			(end -0.2794 -0.1016)
			(stroke
				(width 0.1)
				(type default)
			)
			(layer "F.Fab")
		)
		(fp_line
			(start 0.2794 0.9906)
			(end 0.2794 -0.1016)
			(stroke
				(width 0.1)
				(type default)
			)
			(layer "F.Fab")
		)
		(pad "1" smd rect
			(at 0 0)
			(size 0.508 0.508)
			(layers "F.Cu" "F.Mask" "F.Paste")
			(net "VR_PVCCMCP_CPU1_XADDR2")
		)
		(pad "2" smd rect
			(at 0 0.889)
			(size 0.508 0.508)
			(layers "F.Cu" "F.Mask" "F.Paste")
			(net "GND")
		)
		(zone
			(layer "F.Cu")
			(hatch none 0.5)
			(connect_pads
				(clearance 0)
			)
			(min_thickness 0.25)
			(keepout
				(tracks allowed)
				(vias not_allowed)
				(pads allowed)
				(copperpour not_allowed)
				(footprints allowed)
			)
			(placement
				(enabled no)
				(sheetname "")
			)
			(fill
				(thermal_gap 0.5)
				(thermal_bridge_width 0.5)
				(island_removal_mode 0)
			)
			(polygon
				(pts
					(xy 175.8188 -106.49585) (xy 176.3268 -106.49585) (xy 176.3268 -106.11485) (xy 175.8188 -106.11485)
				)
			)
		)
		(zone
			(layer "F.Cu")
			(hatch none 0.5)
			(connect_pads
				(clearance 0)
			)
			(min_thickness 0.25)
			(keepout
				(tracks not_allowed)
				(vias allowed)
				(pads allowed)
				(copperpour not_allowed)
				(footprints allowed)
			)
			(placement
				(enabled no)
				(sheetname "")
			)
			(fill
				(thermal_gap 0.5)
				(thermal_bridge_width 0.5)
				(island_removal_mode 0)
			)
			(polygon
				(pts
					(xy 175.8188 -106.11485) (xy 176.3268 -106.11485) (xy 176.3268 -106.49585) (xy 175.8188 -106.49585)
				)
			)
		)
	)
	(footprint ""
		(layer "F.Cu")
		(at 167.386 -86.868 180)
		(property "Reference" "R4D3"
			(at 0 0 180)
			(layer "F.SilkS")
			(hide yes)
			(effects
				(font
					(size 1.27 1.27)
				)
			)
		)
		(property "Value" ""
			(at 0 0 180)
			(layer "F.Fab")
			(effects
				(font
					(size 1.27 1.27)
				)
			)
		)
		(duplicate_pad_numbers_are_jumpers no)
		(fp_poly
			(pts
				(xy -0.2794 -0.1016) (xy 0.2794 -0.1016) (xy 0.2794 0.9906) (xy -0.2794 0.9906)
			)
			(stroke
				(width 0)
				(type default)
			)
			(fill no)
			(layer "F.CrtYd")
		)
		(fp_line
			(start 0.2794 0.9906)
			(end 0.2794 -0.1016)
			(stroke
				(width 0.1)
				(type default)
			)
			(layer "F.Fab")
		)
		(fp_line
			(start 0.2794 -0.1016)
			(end -0.2794 -0.1016)
			(stroke
				(width 0.1)
				(type default)
			)
			(layer "F.Fab")
		)
		(fp_line
			(start -0.2794 0.9906)
			(end 0.2794 0.9906)
			(stroke
				(width 0.1)
				(type default)
			)
			(layer "F.Fab")
		)
		(fp_line
			(start -0.2794 -0.1016)
			(end -0.2794 0.9906)
			(stroke
				(width 0.1)
				(type default)
			)
			(layer "F.Fab")
		)
		(pad "1" smd rect
			(at 0 0 180)
			(size 0.508 0.508)
			(layers "F.Cu" "F.Mask" "F.Paste")
			(net "CLK_100M_CPU1_BCLK0_R_DN")
		)
		(pad "2" smd rect
			(at 0 0.889 180)
			(size 0.508 0.508)
			(layers "F.Cu" "F.Mask" "F.Paste")
			(net "CLK_100M_CPU1_BCLK0_DN")
		)
		(zone
			(layer "F.Cu")
			(hatch none 0.5)
			(connect_pads
				(clearance 0)
			)
			(min_thickness 0.25)
			(keepout
				(tracks not_allowed)
				(vias allowed)
				(pads allowed)
				(copperpour not_allowed)
				(footprints allowed)
			)
			(placement
				(enabled no)
				(sheetname "")
			)
			(fill
				(thermal_gap 0.5)
				(thermal_bridge_width 0.5)
				(island_removal_mode 0)
			)
			(polygon
				(pts
					(xy 167.64 -87.503) (xy 167.132 -87.503) (xy 167.132 -87.122) (xy 167.64 -87.122)
				)
			)
		)
		(zone
			(layer "F.Cu")
			(hatch none 0.5)
			(connect_pads
				(clearance 0)
			)
			(min_thickness 0.25)
			(keepout
				(tracks allowed)
				(vias not_allowed)
				(pads allowed)
				(copperpour not_allowed)
				(footprints allowed)
			)
			(placement
				(enabled no)
				(sheetname "")
			)
			(fill
				(thermal_gap 0.5)
				(thermal_bridge_width 0.5)
				(island_removal_mode 0)
			)
			(polygon
				(pts
					(xy 167.64 -87.122) (xy 167.132 -87.122) (xy 167.132 -87.503) (xy 167.64 -87.503)
				)
			)
		)
	)
	(footprint ""
		(layer "F.Cu")
		(at 258.208272 -81.560416)
		(property "Reference" "C5D13"
			(at 0 0 0)
			(layer "F.SilkS")
			(hide yes)
			(effects
				(font
					(size 1.27 1.27)
				)
			)
		)
		(property "Value" ""
			(at 0 0 0)
			(layer "F.Fab")
			(effects
				(font
					(size 1.27 1.27)
				)
			)
		)
		(duplicate_pad_numbers_are_jumpers no)
		(fp_poly
			(pts
				(xy -0.4953 -0.2032) (xy 0.4953 -0.2032) (xy 0.4953 1.6002) (xy -0.4953 1.6002)
			)
			(stroke
				(width 0)
				(type default)
			)
			(fill no)
			(layer "F.CrtYd")
		)
		(fp_line
			(start -0.4953 -0.2032)
			(end 0.4953 -0.2032)
			(stroke
				(width 0.1)
				(type default)
			)
			(layer "F.Fab")
		)
		(fp_line
			(start -0.4953 1.6002)
			(end -0.4953 -0.2032)
			(stroke
				(width 0.1)
				(type default)
			)
			(layer "F.Fab")
		)
		(fp_line
			(start 0.4953 -0.2032)
			(end 0.4953 1.6002)
			(stroke
				(width 0.1)
				(type default)
			)
			(layer "F.Fab")
		)
		(fp_line
			(start 0.4953 1.6002)
			(end -0.4953 1.6002)
			(stroke
				(width 0.1)
				(type default)
			)
			(layer "F.Fab")
		)
		(pad "1" smd rect
			(at 0 0)
			(size 0.762 0.889)
			(layers "F.Cu" "F.Mask" "F.Paste")
			(net "PVSA_CPU0")
		)
		(pad "2" smd rect
			(at 0 1.397)
			(size 0.762 0.889)
			(layers "F.Cu" "F.Mask" "F.Paste")
			(net "GND")
		)
		(zone
			(layer "F.Cu")
			(hatch none 0.5)
			(connect_pads
				(clearance 0)
			)
			(min_thickness 0.25)
			(keepout
				(tracks not_allowed)
				(vias allowed)
				(pads allowed)
				(copperpour not_allowed)
				(footprints allowed)
			)
			(placement
				(enabled no)
				(sheetname "")
			)
			(fill
				(thermal_gap 0.5)
				(thermal_bridge_width 0.5)
				(island_removal_mode 0)
			)
			(polygon
				(pts
					(xy 257.827272 -81.115916) (xy 258.589272 -81.115916) (xy 258.589272 -80.607916) (xy 257.827272 -80.607916)
				)
			)
		)
	)
	(footprint ""
		(layer "F.Cu")
		(at 162.871912 -63.829184)
		(property "Reference" "R3E1"
			(at 0 0 0)
			(layer "F.SilkS")
			(hide yes)
			(effects
				(font
					(size 1.27 1.27)
				)
			)
		)
		(property "Value" ""
			(at 0 0 0)
			(layer "F.Fab")
			(effects
				(font
					(size 1.27 1.27)
				)
			)
		)
		(duplicate_pad_numbers_are_jumpers no)
		(fp_poly
			(pts
				(xy -0.2794 -0.1016) (xy 0.2794 -0.1016) (xy 0.2794 0.9906) (xy -0.2794 0.9906)
			)
			(stroke
				(width 0)
				(type default)
			)
			(fill no)
			(layer "F.CrtYd")
		)
		(fp_line
			(start -0.2794 -0.1016)
			(end -0.2794 0.9906)
			(stroke
				(width 0.1)
				(type default)
			)
			(layer "F.Fab")
		)
		(fp_line
			(start -0.2794 0.9906)
			(end 0.2794 0.9906)
			(stroke
				(width 0.1)
				(type default)
			)
			(layer "F.Fab")
		)
		(fp_line
			(start 0.2794 -0.1016)
			(end -0.2794 -0.1016)
			(stroke
				(width 0.1)
				(type default)
			)
			(layer "F.Fab")
		)
		(fp_line
			(start 0.2794 0.9906)
			(end 0.2794 -0.1016)
			(stroke
				(width 0.1)
				(type default)
			)
			(layer "F.Fab")
		)
		(pad "1" smd rect
			(at 0 0)
			(size 0.508 0.508)
			(layers "F.Cu" "F.Mask" "F.Paste")
			(net "VSENSE_PVCCIO_CPU1_AVSP")
		)
		(pad "2" smd rect
			(at 0 0.889)
			(size 0.508 0.508)
			(layers "F.Cu" "F.Mask" "F.Paste")
			(net "PVCCIO_CPU1")
		)
		(zone
			(layer "F.Cu")
			(hatch none 0.5)
			(connect_pads
				(clearance 0)
			)
			(min_thickness 0.25)
			(keepout
				(tracks allowed)
				(vias not_allowed)
				(pads allowed)
				(copperpour not_allowed)
				(footprints allowed)
			)
			(placement
				(enabled no)
				(sheetname "")
			)
			(fill
				(thermal_gap 0.5)
				(thermal_bridge_width 0.5)
				(island_removal_mode 0)
			)
			(polygon
				(pts
					(xy 162.617912 -63.575184) (xy 163.125912 -63.575184) (xy 163.125912 -63.194184) (xy 162.617912 -63.194184)
				)
			)
		)
		(zone
			(layer "F.Cu")
			(hatch none 0.5)
			(connect_pads
				(clearance 0)
			)
			(min_thickness 0.25)
			(keepout
				(tracks not_allowed)
				(vias allowed)
				(pads allowed)
				(copperpour not_allowed)
				(footprints allowed)
			)
			(placement
				(enabled no)
				(sheetname "")
			)
			(fill
				(thermal_gap 0.5)
				(thermal_bridge_width 0.5)
				(island_removal_mode 0)
			)
			(polygon
				(pts
					(xy 162.617912 -63.194184) (xy 163.125912 -63.194184) (xy 163.125912 -63.575184) (xy 162.617912 -63.575184)
				)
			)
		)
	)
	(footprint ""
		(layer "F.Cu")
		(at 27.4828 -81.915 90)
		(property "Reference" "RT14"
			(at 1.01473 0.656336 0)
			(unlocked yes)
			(layer "F.SilkS")
			(effects
				(font
					(size 0.4064 0.254)
					(thickness 0.1524)
				)
			)
		)
		(property "Value" ""
			(at 0 0 90)
			(layer "F.Fab")
			(effects
				(font
					(size 1.27 1.27)
				)
			)
		)
		(duplicate_pad_numbers_are_jumpers no)
		(fp_poly
			(pts
				(xy -0.4953 -0.2032) (xy 0.4953 -0.2032) (xy 0.4953 1.6002) (xy -0.4953 1.6002)
			)
			(stroke
				(width 0)
				(type default)
			)
			(fill no)
			(layer "F.CrtYd")
		)
		(fp_line
			(start 0.4953 -0.2032)
			(end 0.4953 1.6002)
			(stroke
				(width 0.1)
				(type default)
			)
			(layer "F.Fab")
		)
		(fp_line
			(start -0.4953 -0.2032)
			(end 0.4953 -0.2032)
			(stroke
				(width 0.1)
				(type default)
			)
			(layer "F.Fab")
		)
		(fp_line
			(start 0.4953 1.6002)
			(end -0.4953 1.6002)
			(stroke
				(width 0.1)
				(type default)
			)
			(layer "F.Fab")
		)
		(fp_line
			(start -0.4953 1.6002)
			(end -0.4953 -0.2032)
			(stroke
				(width 0.1)
				(type default)
			)
			(layer "F.Fab")
		)
		(pad "1" smd rect
			(at 0 0 90)
			(size 0.762 0.889)
			(layers "F.Cu" "F.Mask" "F.Paste")
			(net "VR_PVCCIN_CPU1_PH4_BOOT")
		)
		(pad "2" smd rect
			(at 0 1.397 90)
			(size 0.762 0.889)
			(layers "F.Cu" "F.Mask" "F.Paste")
			(net "VR_PVCCIN_CPU1_PH4_BOOT_R")
		)
		(zone
			(layer "F.Cu")
			(hatch none 0.5)
			(connect_pads
				(clearance 0)
			)
			(min_thickness 0.25)
			(keepout
				(tracks allowed)
				(vias not_allowed)
				(pads allowed)
				(copperpour not_allowed)
				(footprints allowed)
			)
			(placement
				(enabled no)
				(sheetname "")
			)
			(fill
				(thermal_gap 0.5)
				(thermal_bridge_width 0.5)
				(island_removal_mode 0)
			)
			(polygon
				(pts
					(xy 28.4353 -82.296) (xy 27.9273 -82.296) (xy 27.9273 -81.534) (xy 28.4353 -81.534)
				)
			)
		)
		(zone
			(layer "F.Cu")
			(hatch none 0.5)
			(connect_pads
				(clearance 0)
			)
			(min_thickness 0.25)
			(keepout
				(tracks not_allowed)
				(vias allowed)
				(pads allowed)
				(copperpour not_allowed)
				(footprints allowed)
			)
			(placement
				(enabled no)
				(sheetname "")
			)
			(fill
				(thermal_gap 0.5)
				(thermal_bridge_width 0.5)
				(island_removal_mode 0)
			)
			(polygon
				(pts
					(xy 28.4353 -81.534) (xy 28.4353 -82.296) (xy 27.9273 -82.296) (xy 27.9273 -81.534)
				)
			)
		)
	)
	(footprint ""
		(layer "F.Cu")
		(at 479.2218 -140.8684 90)
		(property "Reference" "U9A4"
			(at 0 0 90)
			(layer "F.SilkS")
			(hide yes)
			(effects
				(font
					(size 1.27 1.27)
				)
			)
		)
		(property "Value" "*"
			(at -2.3622 -8.3185 90)
			(unlocked yes)
			(layer "F.Fab")
			(hide yes)
			(effects
				(font
					(size 1.27 1.016)
					(thickness 0.1524)
				)
			)
		)
		(property "Device Type" "TC7PZ14FU-GP_DISCRET-GA1-TC7PZA"
			(at -2.3622 -10.2235 90)
			(unlocked yes)
			(layer "F.Fab")
			(hide yes)
			(effects
				(font
					(size 1.27 1.016)
					(thickness 0.1524)
				)
			)
		)
		(duplicate_pad_numbers_are_jumpers no)
		(fp_line
			(start 1.4478 -1.7018)
			(end -1.4478 -1.7018)
			(stroke
				(width 0.1524)
				(type default)
			)
			(layer "F.SilkS")
		)
		(fp_line
			(start -1.4478 -1.7018)
			(end -1.4478 1.7018)
			(stroke
				(width 0.1524)
				(type default)
			)
			(layer "F.SilkS")
		)
		(fp_line
			(start 1.4478 1.7018)
			(end 1.4478 -1.7018)
			(stroke
				(width 0.1524)
				(type default)
			)
			(layer "F.SilkS")
		)
		(fp_line
			(start -1.4478 1.7018)
			(end 1.4478 1.7018)
			(stroke
				(width 0.1524)
				(type default)
			)
			(layer "F.SilkS")
		)
		(fp_line
			(start -0.5715 1.7907)
			(end -1.5494 1.7907)
			(stroke
				(width 0.3302)
				(type default)
			)
			(layer "F.SilkS")
		)
		(fp_line
			(start -1.5494 1.7907)
			(end -1.5494 0.8255)
			(stroke
				(width 0.3302)
				(type default)
			)
			(layer "F.SilkS")
		)
		(fp_poly
			(pts
				(xy -0.6604 1.7272) (xy -1.016 2.0828) (xy -0.3048 2.0828)
			)
			(stroke
				(width 0)
				(type default)
			)
			(fill yes)
			(layer "F.SilkS")
		)
		(fp_poly
			(pts
				(xy -1.524 -1.778) (xy 1.524 -1.778) (xy 1.524 1.778) (xy -1.524 1.778)
			)
			(stroke
				(width 0)
				(type default)
			)
			(fill no)
			(layer "F.CrtYd")
		)
		(fp_poly
			(pts
				(xy -1.524 -1.778) (xy 1.524 -1.778) (xy 1.524 1.778) (xy -1.524 1.778)
			)
			(stroke
				(width 0)
				(type default)
			)
			(fill no)
			(layer "F.Fab")
		)
		(pad "1" smd rect
			(at -0.65024 0.9398 90)
			(size 0.4064 1.016)
			(layers "F.Cu" "F.Mask" "F.Paste")
			(net "FP_PWR_BTN_R1_N")
		)
		(pad "2" smd rect
			(at 0 0.9398 90)
			(size 0.4064 1.016)
			(layers "F.Cu" "F.Mask" "F.Paste")
			(net "GND")
		)
		(pad "3" smd rect
			(at 0.65024 0.9398 90)
			(size 0.4064 1.016)
			(layers "F.Cu" "F.Mask" "F.Paste")
			(net "FP_PWR_BTN_BUF1_N")
		)
		(pad "4" smd rect
			(at 0.65024 -0.9398 90)
			(size 0.4064 1.016)
			(layers "F.Cu" "F.Mask" "F.Paste")
			(net "FM_PWR_BTN_R_N")
		)
		(pad "5" smd rect
			(at 0 -0.9398 90)
			(size 0.4064 1.016)
			(layers "F.Cu" "F.Mask" "F.Paste")
			(net "P3V3_STBY")
		)
		(pad "6" smd rect
			(at -0.65024 -0.9398 90)
			(size 0.4064 1.016)
			(layers "F.Cu" "F.Mask" "F.Paste")
			(net "FP_PWR_BTN_BUF1_N")
		)
	)
	(footprint ""
		(layer "F.Cu")
		(at 114.602768 -79.6036 180)
		(property "Reference" "C3D9"
			(at 0 0 180)
			(layer "F.SilkS")
			(hide yes)
			(effects
				(font
					(size 1.27 1.27)
				)
			)
		)
		(property "Value" ""
			(at 0 0 180)
			(layer "F.Fab")
			(effects
				(font
					(size 1.27 1.27)
				)
			)
		)
		(duplicate_pad_numbers_are_jumpers no)
		(fp_poly
			(pts
				(xy -0.4953 -0.2032) (xy 0.4953 -0.2032) (xy 0.4953 1.6002) (xy -0.4953 1.6002)
			)
			(stroke
				(width 0)
				(type default)
			)
			(fill no)
			(layer "F.CrtYd")
		)
		(fp_line
			(start 0.4953 1.6002)
			(end -0.4953 1.6002)
			(stroke
				(width 0.1)
				(type default)
			)
			(layer "F.Fab")
		)
		(fp_line
			(start 0.4953 -0.2032)
			(end 0.4953 1.6002)
			(stroke
				(width 0.1)
				(type default)
			)
			(layer "F.Fab")
		)
		(fp_line
			(start -0.4953 1.6002)
			(end -0.4953 -0.2032)
			(stroke
				(width 0.1)
				(type default)
			)
			(layer "F.Fab")
		)
		(fp_line
			(start -0.4953 -0.2032)
			(end 0.4953 -0.2032)
			(stroke
				(width 0.1)
				(type default)
			)
			(layer "F.Fab")
		)
		(pad "1" smd rect
			(at 0 0 180)
			(size 0.762 0.889)
			(layers "F.Cu" "F.Mask" "F.Paste")
			(net "PVCCIO_CPU1")
		)
		(pad "2" smd rect
			(at 0 1.397 180)
			(size 0.762 0.889)
			(layers "F.Cu" "F.Mask" "F.Paste")
			(net "GND")
		)
		(zone
			(layer "F.Cu")
			(hatch none 0.5)
			(connect_pads
				(clearance 0)
			)
			(min_thickness 0.25)
			(keepout
				(tracks not_allowed)
				(vias allowed)
				(pads allowed)
				(copperpour not_allowed)
				(footprints allowed)
			)
			(placement
				(enabled no)
				(sheetname "")
			)
			(fill
				(thermal_gap 0.5)
				(thermal_bridge_width 0.5)
				(island_removal_mode 0)
			)
			(polygon
				(pts
					(xy 114.983768 -80.0481) (xy 114.221768 -80.0481) (xy 114.221768 -80.5561) (xy 114.983768 -80.5561)
				)
			)
		)
	)
	(footprint ""
		(layer "F.Cu")
		(at 198.44131 -84.847684 90)
		(property "Reference" "C4D11"
			(at 0 0 90)
			(layer "F.SilkS")
			(hide yes)
			(effects
				(font
					(size 1.27 1.27)
				)
			)
		)
		(property "Value" ""
			(at 0 0 90)
			(layer "F.Fab")
			(effects
				(font
					(size 1.27 1.27)
				)
			)
		)
		(duplicate_pad_numbers_are_jumpers no)
		(fp_rect
			(start 0.3048 0.9906)
			(end -0.3048 -0.1016)
			(stroke
				(width 0)
				(type default)
			)
			(fill no)
			(layer "F.CrtYd")
		)
		(fp_line
			(start 0.3048 -0.1016)
			(end -0.3048 -0.1016)
			(stroke
				(width 0.1)
				(type default)
			)
			(layer "F.Fab")
		)
		(fp_line
			(start -0.3048 -0.1016)
			(end -0.3048 0.9906)
			(stroke
				(width 0.1)
				(type default)
			)
			(layer "F.Fab")
		)
		(fp_line
			(start 0.3048 0.9906)
			(end 0.3048 -0.1016)
			(stroke
				(width 0.1)
				(type default)
			)
			(layer "F.Fab")
		)
		(fp_line
			(start -0.3048 0.9906)
			(end 0.3048 0.9906)
			(stroke
				(width 0.1)
				(type default)
			)
			(layer "F.Fab")
		)
		(pad "1" smd rect
			(at 0 0 90)
			(size 0.508 0.508)
			(layers "F.Cu" "F.Mask" "F.Paste")
			(net "VR_FET_SW_P12V_STBY_PVCCIN_CPU0")
		)
		(pad "2" smd rect
			(at 0 0.889 90)
			(size 0.508 0.508)
			(layers "F.Cu" "F.Mask" "F.Paste")
			(net "GND")
		)
		(zone
			(layer "F.Cu")
			(hatch none 0.5)
			(connect_pads
				(clearance 0)
			)
			(min_thickness 0.25)
			(keepout
				(tracks not_allowed)
				(vias allowed)
				(pads allowed)
				(copperpour not_allowed)
				(footprints allowed)
			)
			(placement
				(enabled no)
				(sheetname "")
			)
			(fill
				(thermal_gap 0.5)
				(thermal_bridge_width 0.5)
				(island_removal_mode 0)
			)
			(polygon
				(pts
					(xy 199.07631 -85.101684) (xy 198.69531 -85.101684) (xy 198.69531 -84.593684) (xy 199.07631 -84.593684)
				)
			)
		)
		(zone
			(layer "F.Cu")
			(hatch none 0.5)
			(connect_pads
				(clearance 0)
			)
			(min_thickness 0.25)
			(keepout
				(tracks allowed)
				(vias not_allowed)
				(pads allowed)
				(copperpour not_allowed)
				(footprints allowed)
			)
			(placement
				(enabled no)
				(sheetname "")
			)
			(fill
				(thermal_gap 0.5)
				(thermal_bridge_width 0.5)
				(island_removal_mode 0)
			)
			(polygon
				(pts
					(xy 199.07631 -85.101684) (xy 198.69531 -85.101684) (xy 198.69531 -84.593684) (xy 199.07631 -84.593684)
				)
			)
		)
	)
	(footprint ""
		(layer "F.Cu")
		(at 12.347702 4.098798 -90)
		(property "Reference" "C12W3"
			(at -0.8382 -0.67818 270)
			(unlocked yes)
			(layer "F.SilkS")
			(effects
				(font
					(size 0.4064 0.254)
					(thickness 0.1524)
				)
				(justify left)
			)
		)
		(property "Value" ""
			(at 0 0 270)
			(layer "F.Fab")
			(effects
				(font
					(size 1.27 1.27)
				)
			)
		)
		(duplicate_pad_numbers_are_jumpers no)
		(fp_poly
			(pts
				(xy 0.3048 -0.1016) (xy 0.3048 0.9906) (xy -0.3048 0.9906) (xy -0.3048 -0.1016)
			)
			(stroke
				(width 0)
				(type default)
			)
			(fill no)
			(layer "F.CrtYd")
		)
		(fp_line
			(start -0.3048 0.9906)
			(end 0.3048 0.9906)
			(stroke
				(width 0.1)
				(type default)
			)
			(layer "F.Fab")
		)
		(fp_line
			(start 0.3048 0.9906)
			(end 0.3048 -0.1016)
			(stroke
				(width 0.1)
				(type default)
			)
			(layer "F.Fab")
		)
		(fp_line
			(start -0.3048 -0.1016)
			(end -0.3048 0.9906)
			(stroke
				(width 0.1)
				(type default)
			)
			(layer "F.Fab")
		)
		(fp_line
			(start 0.3048 -0.1016)
			(end -0.3048 -0.1016)
			(stroke
				(width 0.1)
				(type default)
			)
			(layer "F.Fab")
		)
		(pad "1" smd rect
			(at 0 0 270)
			(size 0.508 0.508)
			(layers "F.Cu" "F.Mask" "F.Paste")
			(net "VR_PVDDQ_GHJ_AIINSEN")
		)
		(pad "2" smd rect
			(at 0 0.889 270)
			(size 0.508 0.508)
			(layers "F.Cu" "F.Mask" "F.Paste")
			(net "VR_PVDDQ_GHJ_VINSEN")
		)
		(zone
			(layer "F.Cu")
			(hatch none 0.5)
			(connect_pads
				(clearance 0)
			)
			(min_thickness 0.25)
			(keepout
				(tracks not_allowed)
				(vias allowed)
				(pads allowed)
				(copperpour not_allowed)
				(footprints allowed)
			)
			(placement
				(enabled no)
				(sheetname "")
			)
			(fill
				(thermal_gap 0.5)
				(thermal_bridge_width 0.5)
				(island_removal_mode 0)
			)
			(polygon
				(pts
					(xy 11.712702 3.844798) (xy 11.712702 4.352798) (xy 12.093702 4.352798) (xy 12.093702 3.844798)
				)
			)
		)
		(zone
			(layer "F.Cu")
			(hatch none 0.5)
			(connect_pads
				(clearance 0)
			)
			(min_thickness 0.25)
			(keepout
				(tracks allowed)
				(vias not_allowed)
				(pads allowed)
				(copperpour not_allowed)
				(footprints allowed)
			)
			(placement
				(enabled no)
				(sheetname "")
			)
			(fill
				(thermal_gap 0.5)
				(thermal_bridge_width 0.5)
				(island_removal_mode 0)
			)
			(polygon
				(pts
					(xy 12.093702 3.844798) (xy 12.093702 4.352798) (xy 11.712702 4.352798) (xy 11.712702 3.844798)
				)
			)
		)
	)
	(footprint ""
		(layer "F.Cu")
		(at 188.73978 -72.644 180)
		(property "Reference" "C4D29"
			(at 0 0 180)
			(layer "F.SilkS")
			(hide yes)
			(effects
				(font
					(size 1.27 1.27)
				)
			)
		)
		(property "Value" ""
			(at 0 0 180)
			(layer "F.Fab")
			(effects
				(font
					(size 1.27 1.27)
				)
			)
		)
		(duplicate_pad_numbers_are_jumpers no)
		(fp_rect
			(start 0.3048 -0.1016)
			(end -0.3048 0.9906)
			(stroke
				(width 0)
				(type default)
			)
			(fill no)
			(layer "F.CrtYd")
		)
		(fp_line
			(start 0.3048 0.9906)
			(end 0.3048 -0.1016)
			(stroke
				(width 0.1)
				(type default)
			)
			(layer "F.Fab")
		)
		(fp_line
			(start 0.3048 -0.1016)
			(end -0.3048 -0.1016)
			(stroke
				(width 0.1)
				(type default)
			)
			(layer "F.Fab")
		)
		(fp_line
			(start -0.3048 0.9906)
			(end 0.3048 0.9906)
			(stroke
				(width 0.1)
				(type default)
			)
			(layer "F.Fab")
		)
		(fp_line
			(start -0.3048 -0.1016)
			(end -0.3048 0.9906)
			(stroke
				(width 0.1)
				(type default)
			)
			(layer "F.Fab")
		)
		(pad "1" smd rect
			(at 0 0 180)
			(size 0.508 0.508)
			(layers "F.Cu" "F.Mask" "F.Paste")
			(net "VSENSE_PVSA_CPU0_BVSP")
		)
		(pad "2" smd rect
			(at 0 0.889 180)
			(size 0.508 0.508)
			(layers "F.Cu" "F.Mask" "F.Paste")
			(net "VSENSE_PVSA_CPU0_N")
		)
		(zone
			(layer "F.Cu")
			(hatch none 0.5)
			(connect_pads
				(clearance 0)
			)
			(min_thickness 0.25)
			(keepout
				(tracks allowed)
				(vias not_allowed)
				(pads allowed)
				(copperpour not_allowed)
				(footprints allowed)
			)
			(placement
				(enabled no)
				(sheetname "")
			)
			(fill
				(thermal_gap 0.5)
				(thermal_bridge_width 0.5)
				(island_removal_mode 0)
			)
			(polygon
				(pts
					(xy 188.48578 -72.898) (xy 188.99378 -72.898) (xy 188.99378 -73.279) (xy 188.48578 -73.279)
				)
			)
		)
		(zone
			(layer "F.Cu")
			(hatch none 0.5)
			(connect_pads
				(clearance 0)
			)
			(min_thickness 0.25)
			(keepout
				(tracks not_allowed)
				(vias allowed)
				(pads allowed)
				(copperpour not_allowed)
				(footprints allowed)
			)
			(placement
				(enabled no)
				(sheetname "")
			)
			(fill
				(thermal_gap 0.5)
				(thermal_bridge_width 0.5)
				(island_removal_mode 0)
			)
			(polygon
				(pts
					(xy 188.48578 -72.898) (xy 188.99378 -72.898) (xy 188.99378 -73.279) (xy 188.48578 -73.279)
				)
			)
		)
	)
	(footprint ""
		(layer "F.Cu")
		(at 171.99991 1.999996 90)
		(property "Reference" "TH4G1"
			(at 4.640326 3.13309 0)
			(unlocked yes)
			(layer "F.SilkS")
			(effects
				(font
					(size 0.7874 0.5842)
					(thickness 0.1524)
				)
				(justify left)
			)
		)
		(property "Value" ""
			(at 0 0 90)
			(layer "F.Fab")
			(effects
				(font
					(size 1.27 1.27)
				)
			)
		)
		(duplicate_pad_numbers_are_jumpers no)
		(fp_poly
			(pts
				(arc
					(start 3.0226 0.68834)
					(mid 3.042235 0.827855)
					(end 3.099562 0.956564)
				)
				(arc
					(start 3.099562 0.956564)
					(mid 4.012804 3.550073)
					(end 3.042158 6.12267)
				)
				(arc
					(start 3.042158 6.12267)
					(mid 0 7.518589)
					(end -3.042158 6.12267)
				)
				(arc
					(start -3.042158 6.12267)
					(mid -4.012854 3.55061)
					(end -3.100324 0.957326)
				)
				(arc
					(start -3.100324 0.957326)
					(mid -3.042498 0.827518)
					(end -3.0226 0.686816)
				)
				(arc
					(start -3.0226 -0.000254)
					(mid -2.137121 -2.137227)
					(end 0 -3.022346)
				)
				(arc
					(start 0 -3.022346)
					(mid 2.137227 -2.136973)
					(end 3.0226 0.000254)
				)
			)
			(stroke
				(width 0)
				(type default)
			)
			(fill no)
			(layer "F.CrtYd")
		)
		(pad "1" thru_hole custom
			(at 0 0 90)
			(size 2.00667 2.00667)
			(drill 0.3048)
			(layers "*.Cu" "*.Mask")
			(remove_unused_layers no)
			(net "GND")
			(clearance -0.889)
			(options
				(clearance outline)
				(anchor circle)
			)
			(primitives
				(gr_poly
					(pts
						(arc
							(start 3.042158 3.874516)
							(mid 0 5.270435)
							(end -3.042158 3.874516)
						)
						(arc
							(start -3.042158 3.874516)
							(mid -4.012854 1.302456)
							(end -3.100324 -1.290828)
						)
						(arc
							(start -3.100324 -1.290828)
							(mid -3.042498 -1.420636)
							(end -3.0226 -1.561338)
						)
						(arc
							(start -3.0226 -2.248408)
							(mid -2.137121 -4.385381)
							(end 0 -5.2705)
						)
						(arc
							(start 0 -5.2705)
							(mid 2.137227 -4.385127)
							(end 3.0226 -2.2479)
						)
						(arc
							(start 3.0226 -1.55956)
							(mid 3.04227 -1.420177)
							(end 3.099562 -1.29159)
						)
						(arc
							(start 3.099562 -1.29159)
							(mid 4.012804 1.301919)
							(end 3.042158 3.874516)
						)
					)
					(width 0)
					(fill yes)
				)
			)
		)
	)
	(footprint ""
		(layer "F.Cu")
		(at 352.9838 -30.353)
		(property "Reference" "FB7F1"
			(at 0 0 0)
			(layer "F.SilkS")
			(hide yes)
			(effects
				(font
					(size 1.27 1.27)
				)
			)
		)
		(property "Value" ""
			(at 0 0 0)
			(layer "F.Fab")
			(effects
				(font
					(size 1.27 1.27)
				)
			)
		)
		(duplicate_pad_numbers_are_jumpers no)
		(fp_rect
			(start -0.7239 2.03835)
			(end 0.7239 -0.26035)
			(stroke
				(width 0)
				(type default)
			)
			(fill no)
			(layer "F.CrtYd")
		)
		(fp_line
			(start -0.7239 -0.26035)
			(end 0.7239 -0.26035)
			(stroke
				(width 0.1)
				(type default)
			)
			(layer "F.Fab")
		)
		(fp_line
			(start -0.7239 2.03835)
			(end -0.7239 -0.26035)
			(stroke
				(width 0.1)
				(type default)
			)
			(layer "F.Fab")
		)
		(fp_line
			(start 0.7239 -0.26035)
			(end 0.7239 2.03835)
			(stroke
				(width 0.1)
				(type default)
			)
			(layer "F.Fab")
		)
		(fp_line
			(start 0.7239 2.03835)
			(end -0.7239 2.03835)
			(stroke
				(width 0.1)
				(type default)
			)
			(layer "F.Fab")
		)
		(pad "1" smd rect
			(at 0 0)
			(size 1.27 1.016)
			(layers "F.Cu" "F.Mask" "F.Paste")
			(net "P12V_STBY")
		)
		(pad "2" smd rect
			(at 0 1.778)
			(size 1.27 1.016)
			(layers "F.Cu" "F.Mask" "F.Paste")
			(net "VR_FET_SW_P12V_STBY_PVPP_ABC")
		)
		(zone
			(layer "F.Cu")
			(hatch none 0.5)
			(connect_pads
				(clearance 0)
			)
			(min_thickness 0.25)
			(keepout
				(tracks not_allowed)
				(vias allowed)
				(pads allowed)
				(copperpour not_allowed)
				(footprints allowed)
			)
			(placement
				(enabled no)
				(sheetname "")
			)
			(fill
				(thermal_gap 0.5)
				(thermal_bridge_width 0.5)
				(island_removal_mode 0)
			)
			(polygon
				(pts
					(xy 353.6188 -29.845) (xy 353.6188 -29.083) (xy 353.5299 -29.083) (xy 352.3488 -29.083) (xy 352.3488 -29.845)
				)
			)
		)
	)
	(footprint ""
		(layer "F.Cu")
		(at 375.92 -88.2015)
		(property "Reference" "R7C16"
			(at 0 0 0)
			(layer "F.SilkS")
			(hide yes)
			(effects
				(font
					(size 1.27 1.27)
				)
			)
		)
		(property "Value" ""
			(at 0 0 0)
			(layer "F.Fab")
			(effects
				(font
					(size 1.27 1.27)
				)
			)
		)
		(duplicate_pad_numbers_are_jumpers no)
		(fp_poly
			(pts
				(xy -0.2794 -0.1016) (xy 0.2794 -0.1016) (xy 0.2794 0.9906) (xy -0.2794 0.9906)
			)
			(stroke
				(width 0)
				(type default)
			)
			(fill no)
			(layer "F.CrtYd")
		)
		(fp_line
			(start -0.2794 -0.1016)
			(end -0.2794 0.9906)
			(stroke
				(width 0.1)
				(type default)
			)
			(layer "F.Fab")
		)
		(fp_line
			(start -0.2794 0.9906)
			(end 0.2794 0.9906)
			(stroke
				(width 0.1)
				(type default)
			)
			(layer "F.Fab")
		)
		(fp_line
			(start 0.2794 -0.1016)
			(end -0.2794 -0.1016)
			(stroke
				(width 0.1)
				(type default)
			)
			(layer "F.Fab")
		)
		(fp_line
			(start 0.2794 0.9906)
			(end 0.2794 -0.1016)
			(stroke
				(width 0.1)
				(type default)
			)
			(layer "F.Fab")
		)
		(pad "1" smd rect
			(at 0 0)
			(size 0.508 0.508)
			(layers "F.Cu" "F.Mask" "F.Paste")
			(net "SPI_PCH_CS0_R_N")
		)
		(pad "2" smd rect
			(at 0 0.889)
			(size 0.508 0.508)
			(layers "F.Cu" "F.Mask" "F.Paste")
			(net "SPI_PCH_CS0_N")
		)
		(zone
			(layer "F.Cu")
			(hatch none 0.5)
			(connect_pads
				(clearance 0)
			)
			(min_thickness 0.25)
			(keepout
				(tracks allowed)
				(vias not_allowed)
				(pads allowed)
				(copperpour not_allowed)
				(footprints allowed)
			)
			(placement
				(enabled no)
				(sheetname "")
			)
			(fill
				(thermal_gap 0.5)
				(thermal_bridge_width 0.5)
				(island_removal_mode 0)
			)
			(polygon
				(pts
					(xy 375.666 -87.9475) (xy 376.174 -87.9475) (xy 376.174 -87.5665) (xy 375.666 -87.5665)
				)
			)
		)
		(zone
			(layer "F.Cu")
			(hatch none 0.5)
			(connect_pads
				(clearance 0)
			)
			(min_thickness 0.25)
			(keepout
				(tracks not_allowed)
				(vias allowed)
				(pads allowed)
				(copperpour not_allowed)
				(footprints allowed)
			)
			(placement
				(enabled no)
				(sheetname "")
			)
			(fill
				(thermal_gap 0.5)
				(thermal_bridge_width 0.5)
				(island_removal_mode 0)
			)
			(polygon
				(pts
					(xy 375.666 -87.5665) (xy 376.174 -87.5665) (xy 376.174 -87.9475) (xy 375.666 -87.9475)
				)
			)
		)
	)
	(footprint ""
		(layer "F.Cu")
		(at 446.532 -12.954 90)
		(property "Reference" "U25W9"
			(at -0.14986 2.621788 90)
			(unlocked yes)
			(layer "F.SilkS")
			(effects
				(font
					(size 1.27 0.964946)
					(thickness 0.000001)
				)
				(justify left)
			)
		)
		(property "Value" ""
			(at 0 0 90)
			(layer "F.Fab")
			(effects
				(font
					(size 1.27 1.27)
				)
			)
		)
		(duplicate_pad_numbers_are_jumpers no)
		(fp_circle
			(center -0.4699 -0.8382)
			(end -0.4699 -0.7112)
			(stroke
				(width 0.254)
				(type default)
			)
			(fill no)
			(layer "F.SilkS")
		)
		(fp_poly
			(pts
				(xy 0.21463 -0.450088) (xy 1.56337 -0.450088) (xy 1.56337 1.75006) (xy 0.21463 1.75006)
			)
			(stroke
				(width 0)
				(type default)
			)
			(fill no)
			(layer "F.CrtYd")
		)
		(fp_line
			(start 1.56337 -0.450088)
			(end 1.56337 1.75006)
			(stroke
				(width 0.1)
				(type default)
			)
			(layer "F.Fab")
		)
		(fp_line
			(start 0.21463 -0.450088)
			(end 1.56337 -0.450088)
			(stroke
				(width 0.1)
				(type default)
			)
			(layer "F.Fab")
		)
		(fp_line
			(start 1.56337 1.75006)
			(end 0.21463 1.75006)
			(stroke
				(width 0.1)
				(type default)
			)
			(layer "F.Fab")
		)
		(fp_line
			(start 0.21463 1.75006)
			(end 0.21463 -0.450088)
			(stroke
				(width 0.1)
				(type default)
			)
			(layer "F.Fab")
		)
		(fp_circle
			(center -0.4699 -0.8382)
			(end -0.4699 -0.7112)
			(stroke
				(width 0.254)
				(type default)
			)
			(fill no)
			(layer "F.Fab")
		)
		(pad "1" smd rect
			(at 0 0 90)
			(size 1.016 0.381)
			(layers "F.Cu" "F.Mask" "F.Paste")
			(net "Net_6489")
		)
		(pad "2" smd rect
			(at 0 0.649986 90)
			(size 1.016 0.381)
			(layers "F.Cu" "F.Mask" "F.Paste")
			(net "PWRGD_DSW_PWROK")
		)
		(pad "3" smd rect
			(at 0 1.299972 90)
			(size 1.016 0.381)
			(layers "F.Cu" "F.Mask" "F.Paste")
			(net "GND")
		)
		(pad "4" smd rect
			(at 1.778 1.299972 90)
			(size 1.016 0.381)
			(layers "F.Cu" "F.Mask" "F.Paste")
			(net "RST_BMC_SRST_N")
		)
		(pad "5" smd rect
			(at 1.778 0 90)
			(size 1.016 0.381)
			(layers "F.Cu" "F.Mask" "F.Paste")
			(net "P3V3_STBY")
		)
	)
	(footprint ""
		(layer "F.Cu")
		(at 435.49062 -131.3053 -90)
		(property "Reference" "EU8B1"
			(at 3.04419 3.01244 0)
			(unlocked yes)
			(layer "F.SilkS")
			(effects
				(font
					(size 0.7874 0.5842)
					(thickness 0.1524)
				)
				(justify left)
			)
		)
		(property "Value" ""
			(at 0 0 270)
			(layer "F.Fab")
			(effects
				(font
					(size 1.27 1.27)
				)
			)
		)
		(duplicate_pad_numbers_are_jumpers no)
		(fp_circle
			(center -0.702056 -0.595376)
			(end -0.702056 -0.722376)
			(stroke
				(width 0.254)
				(type default)
			)
			(fill no)
			(layer "F.SilkS")
		)
		(fp_rect
			(start 0.5842 1.549908)
			(end 1.4732 -0.050292)
			(stroke
				(width 0)
				(type default)
			)
			(fill yes)
			(layer "F.Paste")
		)
		(fp_poly
			(pts
				(xy -0.021336 1.799844) (xy 2.078736 1.799844) (xy 2.078736 -0.300228) (xy -0.021336 -0.300228)
			)
			(stroke
				(width 0)
				(type default)
			)
			(fill no)
			(layer "F.CrtYd")
		)
		(fp_line
			(start -0.021336 1.799844)
			(end -0.021336 -0.300228)
			(stroke
				(width 0.1)
				(type default)
			)
			(layer "F.Fab")
		)
		(fp_line
			(start 2.078736 1.799844)
			(end -0.021336 1.799844)
			(stroke
				(width 0.1)
				(type default)
			)
			(layer "F.Fab")
		)
		(fp_line
			(start -0.021336 -0.300228)
			(end 2.078736 -0.300228)
			(stroke
				(width 0.1)
				(type default)
			)
			(layer "F.Fab")
		)
		(fp_line
			(start 2.078736 -0.300228)
			(end 2.078736 1.799844)
			(stroke
				(width 0.1)
				(type default)
			)
			(layer "F.Fab")
		)
		(fp_circle
			(center -0.702056 -0.595376)
			(end -0.702056 -0.722376)
			(stroke
				(width 0.254)
				(type default)
			)
			(fill no)
			(layer "F.Fab")
		)
		(pad "1" smd rect
			(at 0 0 270)
			(size 0.6604 0.3048)
			(layers "F.Cu" "F.Mask" "F.Paste")
			(net "P5V_STBY")
		)
		(pad "2" smd rect
			(at 0 0.499872 270)
			(size 0.6604 0.3048)
			(layers "F.Cu" "F.Mask" "F.Paste")
			(net "FM_CTNR_PS_ON")
		)
		(pad "3" smd rect
			(at 0 0.999744 270)
			(size 0.6604 0.3048)
			(layers "F.Cu" "F.Mask" "F.Paste")
			(net "P5V_STBY")
		)
		(pad "4" smd rect
			(at 0 1.499616 270)
			(size 0.6604 0.3048)
			(layers "F.Cu" "F.Mask" "F.Paste")
			(net "GND")
		)
		(pad "5" smd rect
			(at 2.0574 1.499616 270)
			(size 0.6604 0.3048)
			(layers "F.Cu" "F.Mask" "F.Paste")
			(net "P5V_STBY")
		)
		(pad "6" smd rect
			(at 2.0574 0.999744 270)
			(size 0.6604 0.3048)
			(layers "F.Cu" "F.Mask" "F.Paste")
			(net "P5V")
		)
		(pad "7" smd rect
			(at 2.0574 0.499872 270)
			(size 0.6604 0.3048)
			(layers "F.Cu" "F.Mask" "F.Paste")
			(net "P5V_SWITCH_G")
		)
		(pad "8" smd rect
			(at 2.0574 0 270)
			(size 0.6604 0.3048)
			(layers "F.Cu" "F.Mask" "F.Paste")
			(net "TP_SLG55021_P5V_8")
		)
		(pad "9" smd rect
			(at 1.0287 0.749808 270)
			(size 0.889 1.6002)
			(layers "F.Cu" "F.Mask" "F.Paste")
			(net "GND")
		)
	)
	(footprint ""
		(layer "F.Cu")
		(at 378.218192 -54.643528 90)
		(property "Reference" "C8E18"
			(at 0 0 90)
			(layer "F.SilkS")
			(hide yes)
			(effects
				(font
					(size 1.27 1.27)
				)
			)
		)
		(property "Value" ""
			(at 0 0 90)
			(layer "F.Fab")
			(effects
				(font
					(size 1.27 1.27)
				)
			)
		)
		(duplicate_pad_numbers_are_jumpers no)
		(fp_poly
			(pts
				(xy 0.3048 -0.1016) (xy 0.3048 0.9906) (xy -0.3048 0.9906) (xy -0.3048 -0.1016)
			)
			(stroke
				(width 0)
				(type default)
			)
			(fill no)
			(layer "F.CrtYd")
		)
		(fp_line
			(start 0.3048 -0.1016)
			(end -0.3048 -0.1016)
			(stroke
				(width 0.1)
				(type default)
			)
			(layer "F.Fab")
		)
		(fp_line
			(start -0.3048 -0.1016)
			(end -0.3048 0.9906)
			(stroke
				(width 0.1)
				(type default)
			)
			(layer "F.Fab")
		)
		(fp_line
			(start 0.3048 0.9906)
			(end 0.3048 -0.1016)
			(stroke
				(width 0.1)
				(type default)
			)
			(layer "F.Fab")
		)
		(fp_line
			(start -0.3048 0.9906)
			(end 0.3048 0.9906)
			(stroke
				(width 0.1)
				(type default)
			)
			(layer "F.Fab")
		)
		(pad "1" smd rect
			(at 0 0 90)
			(size 0.508 0.508)
			(layers "F.Cu" "F.Mask" "F.Paste")
			(net "P3V3_STBY")
		)
		(pad "2" smd rect
			(at 0 0.889 90)
			(size 0.508 0.508)
			(layers "F.Cu" "F.Mask" "F.Paste")
			(net "GND")
		)
		(zone
			(layer "F.Cu")
			(hatch none 0.5)
			(connect_pads
				(clearance 0)
			)
			(min_thickness 0.25)
			(keepout
				(tracks allowed)
				(vias not_allowed)
				(pads allowed)
				(copperpour not_allowed)
				(footprints allowed)
			)
			(placement
				(enabled no)
				(sheetname "")
			)
			(fill
				(thermal_gap 0.5)
				(thermal_bridge_width 0.5)
				(island_removal_mode 0)
			)
			(polygon
				(pts
					(xy 378.472192 -54.389528) (xy 378.472192 -54.897528) (xy 378.853192 -54.897528) (xy 378.853192 -54.389528)
				)
			)
		)
		(zone
			(layer "F.Cu")
			(hatch none 0.5)
			(connect_pads
				(clearance 0)
			)
			(min_thickness 0.25)
			(keepout
				(tracks not_allowed)
				(vias allowed)
				(pads allowed)
				(copperpour not_allowed)
				(footprints allowed)
			)
			(placement
				(enabled no)
				(sheetname "")
			)
			(fill
				(thermal_gap 0.5)
				(thermal_bridge_width 0.5)
				(island_removal_mode 0)
			)
			(polygon
				(pts
					(xy 378.853192 -54.389528) (xy 378.853192 -54.897528) (xy 378.472192 -54.897528) (xy 378.472192 -54.389528)
				)
			)
		)
	)
	(footprint ""
		(layer "F.Cu")
		(at 248.8565 -12.954 -90)
		(property "Reference" "C5G2"
			(at 1.848866 0.752348 270)
			(unlocked yes)
			(layer "F.SilkS")
			(effects
				(font
					(size 1.27 0.9652)
					(thickness 0.1524)
				)
			)
		)
		(property "Value" ""
			(at 0 0 270)
			(layer "F.Fab")
			(effects
				(font
					(size 1.27 1.27)
				)
			)
		)
		(duplicate_pad_numbers_are_jumpers no)
		(fp_rect
			(start -0.500126 1.598422)
			(end 0.500126 -0.201422)
			(stroke
				(width 0)
				(type default)
			)
			(fill no)
			(layer "F.CrtYd")
		)
		(fp_line
			(start -0.500126 1.598422)
			(end -0.500126 -0.201422)
			(stroke
				(width 0.1)
				(type default)
			)
			(layer "F.Fab")
		)
		(fp_line
			(start 0.500126 1.598422)
			(end -0.500126 1.598422)
			(stroke
				(width 0.1)
				(type default)
			)
			(layer "F.Fab")
		)
		(fp_line
			(start -0.500126 -0.201422)
			(end 0.500126 -0.201422)
			(stroke
				(width 0.1)
				(type default)
			)
			(layer "F.Fab")
		)
		(fp_line
			(start 0.500126 -0.201422)
			(end 0.500126 1.598422)
			(stroke
				(width 0.1)
				(type default)
			)
			(layer "F.Fab")
		)
		(pad "1" smd rect
			(at 0 0 180)
			(size 0.889 0.9906)
			(layers "F.Cu" "F.Mask" "F.Paste")
			(net "PVDDQ_ABC")
		)
		(pad "2" smd rect
			(at 0 1.397 180)
			(size 0.889 0.9906)
			(layers "F.Cu" "F.Mask" "F.Paste")
			(net "GND")
		)
		(zone
			(layer "F.Cu")
			(hatch none 0.5)
			(connect_pads
				(clearance 0)
			)
			(min_thickness 0.25)
			(keepout
				(tracks not_allowed)
				(vias allowed)
				(pads allowed)
				(copperpour not_allowed)
				(footprints allowed)
			)
			(placement
				(enabled no)
				(sheetname "")
			)
			(fill
				(thermal_gap 0.5)
				(thermal_bridge_width 0.5)
				(island_removal_mode 0)
			)
			(polygon
				(pts
					(xy 247.904 -13.4493) (xy 247.904 -12.4587) (xy 248.412 -12.4587) (xy 248.412 -13.4493)
				)
			)
		)
		(zone
			(layer "F.Cu")
			(hatch none 0.5)
			(connect_pads
				(clearance 0)
			)
			(min_thickness 0.25)
			(keepout
				(tracks allowed)
				(vias not_allowed)
				(pads allowed)
				(copperpour not_allowed)
				(footprints allowed)
			)
			(placement
				(enabled no)
				(sheetname "")
			)
			(fill
				(thermal_gap 0.5)
				(thermal_bridge_width 0.5)
				(island_removal_mode 0)
			)
			(polygon
				(pts
					(xy 247.904 -13.4493) (xy 247.904 -12.4587) (xy 248.412 -12.4587) (xy 248.412 -13.4493)
				)
			)
		)
	)
	(footprint ""
		(layer "F.Cu")
		(at 418.7952 -91.7829 -90)
		(property "Reference" "C8C15"
			(at 0 0 270)
			(layer "F.SilkS")
			(hide yes)
			(effects
				(font
					(size 1.27 1.27)
				)
			)
		)
		(property "Value" ""
			(at 0 0 270)
			(layer "F.Fab")
			(effects
				(font
					(size 1.27 1.27)
				)
			)
		)
		(duplicate_pad_numbers_are_jumpers no)
		(fp_poly
			(pts
				(xy 0.3048 -0.1016) (xy 0.3048 0.9906) (xy -0.3048 0.9906) (xy -0.3048 -0.1016)
			)
			(stroke
				(width 0)
				(type default)
			)
			(fill no)
			(layer "F.CrtYd")
		)
		(fp_line
			(start -0.3048 0.9906)
			(end 0.3048 0.9906)
			(stroke
				(width 0.1)
				(type default)
			)
			(layer "F.Fab")
		)
		(fp_line
			(start 0.3048 0.9906)
			(end 0.3048 -0.1016)
			(stroke
				(width 0.1)
				(type default)
			)
			(layer "F.Fab")
		)
		(fp_line
			(start -0.3048 -0.1016)
			(end -0.3048 0.9906)
			(stroke
				(width 0.1)
				(type default)
			)
			(layer "F.Fab")
		)
		(fp_line
			(start 0.3048 -0.1016)
			(end -0.3048 -0.1016)
			(stroke
				(width 0.1)
				(type default)
			)
			(layer "F.Fab")
		)
		(pad "1" smd rect
			(at 0 0 270)
			(size 0.508 0.508)
			(layers "F.Cu" "F.Mask" "F.Paste")
			(net "KR_P0_OCP_RX_DP")
		)
		(pad "2" smd rect
			(at 0 0.889 270)
			(size 0.508 0.508)
			(layers "F.Cu" "F.Mask" "F.Paste")
			(net "KR_P0_OCP_RX_C_DP")
		)
		(zone
			(layer "F.Cu")
			(hatch none 0.5)
			(connect_pads
				(clearance 0)
			)
			(min_thickness 0.25)
			(keepout
				(tracks not_allowed)
				(vias allowed)
				(pads allowed)
				(copperpour not_allowed)
				(footprints allowed)
			)
			(placement
				(enabled no)
				(sheetname "")
			)
			(fill
				(thermal_gap 0.5)
				(thermal_bridge_width 0.5)
				(island_removal_mode 0)
			)
			(polygon
				(pts
					(xy 418.1602 -92.0369) (xy 418.1602 -91.5289) (xy 418.5412 -91.5289) (xy 418.5412 -92.0369)
				)
			)
		)
		(zone
			(layer "F.Cu")
			(hatch none 0.5)
			(connect_pads
				(clearance 0)
			)
			(min_thickness 0.25)
			(keepout
				(tracks allowed)
				(vias not_allowed)
				(pads allowed)
				(copperpour not_allowed)
				(footprints allowed)
			)
			(placement
				(enabled no)
				(sheetname "")
			)
			(fill
				(thermal_gap 0.5)
				(thermal_bridge_width 0.5)
				(island_removal_mode 0)
			)
			(polygon
				(pts
					(xy 418.5412 -92.0369) (xy 418.5412 -91.5289) (xy 418.1602 -91.5289) (xy 418.1602 -92.0369)
				)
			)
		)
	)
	(footprint ""
		(layer "F.Cu")
		(at 19.431 -92.456)
		(property "Reference" "EU1C2"
			(at -7.8232 -3.45313 0)
			(unlocked yes)
			(layer "F.SilkS")
			(effects
				(font
					(size 0.7874 0.5842)
					(thickness 0.1524)
				)
				(justify left)
			)
		)
		(property "Value" ""
			(at 0 0 0)
			(layer "F.Fab")
			(effects
				(font
					(size 1.27 1.27)
				)
			)
		)
		(duplicate_pad_numbers_are_jumpers no)
		(fp_line
			(start -3.5052 -3.5052)
			(end 3.5052 -3.5052)
			(stroke
				(width 0.1524)
				(type default)
			)
			(layer "F.SilkS")
		)
		(fp_line
			(start -3.5052 3.5052)
			(end -3.5052 -3.5052)
			(stroke
				(width 0.1524)
				(type default)
			)
			(layer "F.SilkS")
		)
		(fp_line
			(start -2.999994 -2.999994)
			(end -2.750058 -2.999994)
			(stroke
				(width 0.1524)
				(type default)
			)
			(layer "F.SilkS")
		)
		(fp_line
			(start -2.999994 -2.750058)
			(end -2.999994 -2.999994)
			(stroke
				(width 0.1524)
				(type default)
			)
			(layer "F.SilkS")
		)
		(fp_line
			(start -2.999994 2.999994)
			(end -2.999994 2.750058)
			(stroke
				(width 0.1524)
				(type default)
			)
			(layer "F.SilkS")
		)
		(fp_line
			(start -2.750058 2.999994)
			(end -2.999994 2.999994)
			(stroke
				(width 0.1524)
				(type default)
			)
			(layer "F.SilkS")
		)
		(fp_line
			(start 2.750058 -2.999994)
			(end 2.999994 -2.999994)
			(stroke
				(width 0.1524)
				(type default)
			)
			(layer "F.SilkS")
		)
		(fp_line
			(start 2.999994 -2.999994)
			(end 2.999994 -2.750058)
			(stroke
				(width 0.1524)
				(type default)
			)
			(layer "F.SilkS")
		)
		(fp_line
			(start 2.999994 2.750058)
			(end 2.999994 2.999994)
			(stroke
				(width 0.1524)
				(type default)
			)
			(layer "F.SilkS")
		)
		(fp_line
			(start 2.999994 2.999994)
			(end 2.750058 2.999994)
			(stroke
				(width 0.1524)
				(type default)
			)
			(layer "F.SilkS")
		)
		(fp_line
			(start 3.5052 -3.5052)
			(end 3.5052 3.5052)
			(stroke
				(width 0.1524)
				(type default)
			)
			(layer "F.SilkS")
		)
		(fp_line
			(start 3.5052 3.5052)
			(end -3.5052 3.5052)
			(stroke
				(width 0.1524)
				(type default)
			)
			(layer "F.SilkS")
		)
		(fp_circle
			(center -3.752088 -2.214626)
			(end -3.625088 -2.214626)
			(stroke
				(width 0.254)
				(type default)
			)
			(fill no)
			(layer "F.SilkS")
		)
		(fp_poly
			(pts
				(xy -3.5052 -3.5052) (xy -3.5052 -2.3368) (xy -2.3368 -3.5052)
			)
			(stroke
				(width 0)
				(type default)
			)
			(fill yes)
			(layer "F.SilkS")
		)
		(fp_rect
			(start -1.8034 1.8034)
			(end 1.8034 -1.8034)
			(stroke
				(width 0)
				(type default)
			)
			(fill yes)
			(layer "F.Paste")
		)
		(fp_rect
			(start -2.999994 2.999994)
			(end 2.999994 -2.999994)
			(stroke
				(width 0)
				(type default)
			)
			(fill no)
			(layer "F.CrtYd")
		)
		(fp_line
			(start -2.999994 -2.999994)
			(end 2.999994 -2.999994)
			(stroke
				(width 0.1)
				(type default)
			)
			(layer "F.Fab")
		)
		(fp_line
			(start -2.999994 2.999994)
			(end -2.999994 -2.999994)
			(stroke
				(width 0.1)
				(type default)
			)
			(layer "F.Fab")
		)
		(fp_line
			(start 2.999994 -2.999994)
			(end 2.999994 2.999994)
			(stroke
				(width 0.1)
				(type default)
			)
			(layer "F.Fab")
		)
		(fp_line
			(start 2.999994 2.999994)
			(end -2.999994 2.999994)
			(stroke
				(width 0.1)
				(type default)
			)
			(layer "F.Fab")
		)
		(fp_circle
			(center -3.752088 -2.214626)
			(end -3.625088 -2.214626)
			(stroke
				(width 0.254)
				(type default)
			)
			(fill no)
			(layer "F.Fab")
		)
		(pad "1" smd custom
			(at -2.8956 -2.199894)
			(size 0.0508 0.0508)
			(layers "F.Cu" "F.Mask" "F.Paste")
			(net "VR_PVSA_CPU1_PWM")
			(options
				(clearance outline)
				(anchor circle)
			)
			(primitives
				(gr_poly
					(pts
						(arc
							(start 0.254 -0.1016)
							(mid 0.3556 0)
							(end 0.254 0.1016)
						)
						(xy -0.3556 0.1016) (xy -0.3556 -0.1016)
					)
					(width 0)
					(fill yes)
				)
			)
		)
		(pad "2" smd custom
			(at -2.8956 -1.800098)
			(size 0.0508 0.0508)
			(layers "F.Cu" "F.Mask" "F.Paste")
			(net "Net_277")
			(options
				(clearance outline)
				(anchor circle)
			)
			(primitives
				(gr_poly
					(pts
						(arc
							(start 0.254 -0.1016)
							(mid 0.3556 0)
							(end 0.254 0.1016)
						)
						(xy -0.3556 0.1016) (xy -0.3556 -0.1016)
					)
					(width 0)
					(fill yes)
				)
			)
		)
		(pad "3" smd custom
			(at -2.8956 -1.400048)
			(size 0.0508 0.0508)
			(layers "F.Cu" "F.Mask" "F.Paste")
			(net "VR_PVCCIN_CPU1_PWM5")
			(options
				(clearance outline)
				(anchor circle)
			)
			(primitives
				(gr_poly
					(pts
						(arc
							(start 0.254 -0.1016)
							(mid 0.3556 0)
							(end 0.254 0.1016)
						)
						(xy -0.3556 0.1016) (xy -0.3556 -0.1016)
					)
					(width 0)
					(fill yes)
				)
			)
		)
		(pad "4" smd custom
			(at -2.8956 -0.999998)
			(size 0.0508 0.0508)
			(layers "F.Cu" "F.Mask" "F.Paste")
			(net "VR_PVCCIN_CPU1_PWM4")
			(options
				(clearance outline)
				(anchor circle)
			)
			(primitives
				(gr_poly
					(pts
						(arc
							(start 0.254 -0.1016)
							(mid 0.3556 0)
							(end 0.254 0.1016)
						)
						(xy -0.3556 0.1016) (xy -0.3556 -0.1016)
					)
					(width 0)
					(fill yes)
				)
			)
		)
		(pad "5" smd custom
			(at -2.8956 -0.599948)
			(size 0.0508 0.0508)
			(layers "F.Cu" "F.Mask" "F.Paste")
			(net "VR_PVCCIN_CPU1_PWM3")
			(options
				(clearance outline)
				(anchor circle)
			)
			(primitives
				(gr_poly
					(pts
						(arc
							(start 0.254 -0.1016)
							(mid 0.3556 0)
							(end 0.254 0.1016)
						)
						(xy -0.3556 0.1016) (xy -0.3556 -0.1016)
					)
					(width 0)
					(fill yes)
				)
			)
		)
		(pad "6" smd custom
			(at -2.8956 -0.199898)
			(size 0.0508 0.0508)
			(layers "F.Cu" "F.Mask" "F.Paste")
			(net "VR_PVCCIN_CPU1_PWM2")
			(options
				(clearance outline)
				(anchor circle)
			)
			(primitives
				(gr_poly
					(pts
						(arc
							(start 0.254 -0.1016)
							(mid 0.3556 0)
							(end 0.254 0.1016)
						)
						(xy -0.3556 0.1016) (xy -0.3556 -0.1016)
					)
					(width 0)
					(fill yes)
				)
			)
		)
		(pad "7" smd custom
			(at -2.8956 0.199898)
			(size 0.0508 0.0508)
			(layers "F.Cu" "F.Mask" "F.Paste")
			(net "VR_PVCCIN_CPU1_PWM1")
			(options
				(clearance outline)
				(anchor circle)
			)
			(primitives
				(gr_poly
					(pts
						(arc
							(start 0.254 -0.1016)
							(mid 0.3556 0)
							(end 0.254 0.1016)
						)
						(xy -0.3556 0.1016) (xy -0.3556 -0.1016)
					)
					(width 0)
					(fill yes)
				)
			)
		)
		(pad "8" smd custom
			(at -2.8956 0.599948)
			(size 0.0508 0.0508)
			(layers "F.Cu" "F.Mask" "F.Paste")
			(net "SMB_VR_STBY_LVC3_SDA")
			(options
				(clearance outline)
				(anchor circle)
			)
			(primitives
				(gr_poly
					(pts
						(arc
							(start 0.254 -0.1016)
							(mid 0.3556 0)
							(end 0.254 0.1016)
						)
						(xy -0.3556 0.1016) (xy -0.3556 -0.1016)
					)
					(width 0)
					(fill yes)
				)
			)
		)
		(pad "9" smd custom
			(at -2.8956 0.999998)
			(size 0.0508 0.0508)
			(layers "F.Cu" "F.Mask" "F.Paste")
			(net "SMB_VR_STBY_LVC3_SCL")
			(options
				(clearance outline)
				(anchor circle)
			)
			(primitives
				(gr_poly
					(pts
						(arc
							(start 0.254 -0.1016)
							(mid 0.3556 0)
							(end 0.254 0.1016)
						)
						(xy -0.3556 0.1016) (xy -0.3556 -0.1016)
					)
					(width 0)
					(fill yes)
				)
			)
		)
		(pad "10" smd custom
			(at -2.8956 1.400048)
			(size 0.0508 0.0508)
			(layers "F.Cu" "F.Mask" "F.Paste")
			(net "Net_278")
			(options
				(clearance outline)
				(anchor circle)
			)
			(primitives
				(gr_poly
					(pts
						(arc
							(start 0.254 -0.1016)
							(mid 0.3556 0)
							(end 0.254 0.1016)
						)
						(xy -0.3556 0.1016) (xy -0.3556 -0.1016)
					)
					(width 0)
					(fill yes)
				)
			)
		)
		(pad "11" smd custom
			(at -2.8956 1.800098)
			(size 0.0508 0.0508)
			(layers "F.Cu" "F.Mask" "F.Paste")
			(net "VR_VRRDY_PVCCIN_CPU1")
			(options
				(clearance outline)
				(anchor circle)
			)
			(primitives
				(gr_poly
					(pts
						(arc
							(start 0.254 -0.1016)
							(mid 0.3556 0)
							(end 0.254 0.1016)
						)
						(xy -0.3556 0.1016) (xy -0.3556 -0.1016)
					)
					(width 0)
					(fill yes)
				)
			)
		)
		(pad "12" smd custom
			(at -2.8956 2.199894)
			(size 0.0508 0.0508)
			(layers "F.Cu" "F.Mask" "F.Paste")
			(net "VR_PVCCIN_CPU1_VREN")
			(options
				(clearance outline)
				(anchor circle)
			)
			(primitives
				(gr_poly
					(pts
						(arc
							(start 0.254 -0.1016)
							(mid 0.3556 0)
							(end 0.254 0.1016)
						)
						(xy -0.3556 0.1016) (xy -0.3556 -0.1016)
					)
					(width 0)
					(fill yes)
				)
			)
		)
		(pad "13" smd custom
			(at -2.199894 2.8956)
			(size 0.0508 0.0508)
			(layers "F.Cu" "F.Mask" "F.Paste")
			(net "IRQ_PVCCIN_CPU1_VRHOT_LVC3_R_N")
			(options
				(clearance outline)
				(anchor circle)
			)
			(primitives
				(gr_poly
					(pts
						(arc
							(start -0.1016 -0.254)
							(mid 0 -0.3556)
							(end 0.1016 -0.254)
						)
						(xy 0.1016 0.3556) (xy -0.1016 0.3556)
					)
					(width 0)
					(fill yes)
				)
			)
		)
		(pad "14" smd custom
			(at -1.800098 2.8956)
			(size 0.0508 0.0508)
			(layers "F.Cu" "F.Mask" "F.Paste")
			(net "FM_PVCCIN_CPU1_PWR_IN_ALERT_N")
			(options
				(clearance outline)
				(anchor circle)
			)
			(primitives
				(gr_poly
					(pts
						(arc
							(start -0.1016 -0.254)
							(mid 0 -0.3556)
							(end 0.1016 -0.254)
						)
						(xy 0.1016 0.3556) (xy -0.1016 0.3556)
					)
					(width 0)
					(fill yes)
				)
			)
		)
		(pad "15" smd custom
			(at -1.400048 2.8956)
			(size 0.0508 0.0508)
			(layers "F.Cu" "F.Mask" "F.Paste")
			(net "PWRGD_PVSA_CPU1_R")
			(options
				(clearance outline)
				(anchor circle)
			)
			(primitives
				(gr_poly
					(pts
						(arc
							(start -0.1016 -0.254)
							(mid 0 -0.3556)
							(end 0.1016 -0.254)
						)
						(xy 0.1016 0.3556) (xy -0.1016 0.3556)
					)
					(width 0)
					(fill yes)
				)
			)
		)
		(pad "16" smd custom
			(at -0.999998 2.8956)
			(size 0.0508 0.0508)
			(layers "F.Cu" "F.Mask" "F.Paste")
			(net "Net_220")
			(options
				(clearance outline)
				(anchor circle)
			)
			(primitives
				(gr_poly
					(pts
						(arc
							(start -0.1016 -0.254)
							(mid 0 -0.3556)
							(end 0.1016 -0.254)
						)
						(xy 0.1016 0.3556) (xy -0.1016 0.3556)
					)
					(width 0)
					(fill yes)
				)
			)
		)
		(pad "17" smd custom
			(at -0.599948 2.8956)
			(size 0.0508 0.0508)
			(layers "F.Cu" "F.Mask" "F.Paste")
			(net "SVID_VCLK_PVCCIN_CPU1")
			(options
				(clearance outline)
				(anchor circle)
			)
			(primitives
				(gr_poly
					(pts
						(arc
							(start -0.1016 -0.254)
							(mid 0 -0.3556)
							(end 0.1016 -0.254)
						)
						(xy 0.1016 0.3556) (xy -0.1016 0.3556)
					)
					(width 0)
					(fill yes)
				)
			)
		)
		(pad "18" smd custom
			(at -0.199898 2.8956)
			(size 0.0508 0.0508)
			(layers "F.Cu" "F.Mask" "F.Paste")
			(net "SVID_VDIO_PVCCIN_CPU1")
			(options
				(clearance outline)
				(anchor circle)
			)
			(primitives
				(gr_poly
					(pts
						(arc
							(start -0.1016 -0.254)
							(mid 0 -0.3556)
							(end 0.1016 -0.254)
						)
						(xy 0.1016 0.3556) (xy -0.1016 0.3556)
					)
					(width 0)
					(fill yes)
				)
			)
		)
		(pad "19" smd custom
			(at 0.199898 2.8956)
			(size 0.0508 0.0508)
			(layers "F.Cu" "F.Mask" "F.Paste")
			(net "SVID_VALERT_VCCIN_CPU1")
			(options
				(clearance outline)
				(anchor circle)
			)
			(primitives
				(gr_poly
					(pts
						(arc
							(start -0.1016 -0.254)
							(mid 0 -0.3556)
							(end 0.1016 -0.254)
						)
						(xy 0.1016 0.3556) (xy -0.1016 0.3556)
					)
					(width 0)
					(fill yes)
				)
			)
		)
		(pad "20" smd custom
			(at 0.599948 2.8956)
			(size 0.0508 0.0508)
			(layers "F.Cu" "F.Mask" "F.Paste")
			(net "PU_VR_PVCCIN_CPU1_FLT1_SMBALT_N")
			(options
				(clearance outline)
				(anchor circle)
			)
			(primitives
				(gr_poly
					(pts
						(arc
							(start -0.1016 -0.254)
							(mid 0 -0.3556)
							(end 0.1016 -0.254)
						)
						(xy 0.1016 0.3556) (xy -0.1016 0.3556)
					)
					(width 0)
					(fill yes)
				)
			)
		)
		(pad "21" smd custom
			(at 0.999998 2.8956)
			(size 0.0508 0.0508)
			(layers "F.Cu" "F.Mask" "F.Paste")
			(net "VSENSE_PVCCIN_CPU1_AVSP")
			(options
				(clearance outline)
				(anchor circle)
			)
			(primitives
				(gr_poly
					(pts
						(arc
							(start -0.1016 -0.254)
							(mid 0 -0.3556)
							(end 0.1016 -0.254)
						)
						(xy 0.1016 0.3556) (xy -0.1016 0.3556)
					)
					(width 0)
					(fill yes)
				)
			)
		)
		(pad "22" smd custom
			(at 1.400048 2.8956)
			(size 0.0508 0.0508)
			(layers "F.Cu" "F.Mask" "F.Paste")
			(net "VSENSE_PVCCIN_CPU1_N")
			(options
				(clearance outline)
				(anchor circle)
			)
			(primitives
				(gr_poly
					(pts
						(arc
							(start -0.1016 -0.254)
							(mid 0 -0.3556)
							(end 0.1016 -0.254)
						)
						(xy 0.1016 0.3556) (xy -0.1016 0.3556)
					)
					(width 0)
					(fill yes)
				)
			)
		)
		(pad "23" smd custom
			(at 1.800098 2.8956)
			(size 0.0508 0.0508)
			(layers "F.Cu" "F.Mask" "F.Paste")
			(net "VR_PVCCIN_CPU1_AIREF1")
			(options
				(clearance outline)
				(anchor circle)
			)
			(primitives
				(gr_poly
					(pts
						(arc
							(start -0.1016 -0.254)
							(mid 0 -0.3556)
							(end 0.1016 -0.254)
						)
						(xy 0.1016 0.3556) (xy -0.1016 0.3556)
					)
					(width 0)
					(fill yes)
				)
			)
		)
		(pad "24" smd custom
			(at 2.199894 2.8956)
			(size 0.0508 0.0508)
			(layers "F.Cu" "F.Mask" "F.Paste")
			(net "ISENSE_PVCCIN_CPU1_PH1_IMON")
			(options
				(clearance outline)
				(anchor circle)
			)
			(primitives
				(gr_poly
					(pts
						(arc
							(start -0.1016 -0.254)
							(mid 0 -0.3556)
							(end 0.1016 -0.254)
						)
						(xy 0.1016 0.3556) (xy -0.1016 0.3556)
					)
					(width 0)
					(fill yes)
				)
			)
		)
		(pad "25" smd custom
			(at 2.8956 2.199894)
			(size 0.0508 0.0508)
			(layers "F.Cu" "F.Mask" "F.Paste")
			(net "VR_PVCCIN_CPU1_AIREF2")
			(options
				(clearance outline)
				(anchor circle)
			)
			(primitives
				(gr_poly
					(pts
						(arc
							(start -0.254 0.1016)
							(mid -0.3556 0)
							(end -0.254 -0.1016)
						)
						(xy 0.3556 -0.1016) (xy 0.3556 0.1016)
					)
					(width 0)
					(fill yes)
				)
			)
		)
		(pad "26" smd custom
			(at 2.8956 1.800098)
			(size 0.0508 0.0508)
			(layers "F.Cu" "F.Mask" "F.Paste")
			(net "ISENSE_PVCCIN_CPU1_PH2_IMON")
			(options
				(clearance outline)
				(anchor circle)
			)
			(primitives
				(gr_poly
					(pts
						(arc
							(start -0.254 0.1016)
							(mid -0.3556 0)
							(end -0.254 -0.1016)
						)
						(xy 0.3556 -0.1016) (xy 0.3556 0.1016)
					)
					(width 0)
					(fill yes)
				)
			)
		)
		(pad "27" smd custom
			(at 2.8956 1.400048)
			(size 0.0508 0.0508)
			(layers "F.Cu" "F.Mask" "F.Paste")
			(net "VR_PVCCIN_CPU1_AIREF3")
			(options
				(clearance outline)
				(anchor circle)
			)
			(primitives
				(gr_poly
					(pts
						(arc
							(start -0.254 0.1016)
							(mid -0.3556 0)
							(end -0.254 -0.1016)
						)
						(xy 0.3556 -0.1016) (xy 0.3556 0.1016)
					)
					(width 0)
					(fill yes)
				)
			)
		)
		(pad "28" smd custom
			(at 2.8956 0.999998)
			(size 0.0508 0.0508)
			(layers "F.Cu" "F.Mask" "F.Paste")
			(net "ISENSE_PVCCIN_CPU1_PH3_IMON")
			(options
				(clearance outline)
				(anchor circle)
			)
			(primitives
				(gr_poly
					(pts
						(arc
							(start -0.254 0.1016)
							(mid -0.3556 0)
							(end -0.254 -0.1016)
						)
						(xy 0.3556 -0.1016) (xy 0.3556 0.1016)
					)
					(width 0)
					(fill yes)
				)
			)
		)
		(pad "29" smd custom
			(at 2.8956 0.599948)
			(size 0.0508 0.0508)
			(layers "F.Cu" "F.Mask" "F.Paste")
			(net "VR_PVCCIN_CPU1_AIREF4")
			(options
				(clearance outline)
				(anchor circle)
			)
			(primitives
				(gr_poly
					(pts
						(arc
							(start -0.254 0.1016)
							(mid -0.3556 0)
							(end -0.254 -0.1016)
						)
						(xy 0.3556 -0.1016) (xy 0.3556 0.1016)
					)
					(width 0)
					(fill yes)
				)
			)
		)
		(pad "30" smd custom
			(at 2.8956 0.199898)
			(size 0.0508 0.0508)
			(layers "F.Cu" "F.Mask" "F.Paste")
			(net "ISENSE_PVCCIN_CPU1_PH4_IMON")
			(options
				(clearance outline)
				(anchor circle)
			)
			(primitives
				(gr_poly
					(pts
						(arc
							(start -0.254 0.1016)
							(mid -0.3556 0)
							(end -0.254 -0.1016)
						)
						(xy 0.3556 -0.1016) (xy 0.3556 0.1016)
					)
					(width 0)
					(fill yes)
				)
			)
		)
		(pad "31" smd custom
			(at 2.8956 -0.199898)
			(size 0.0508 0.0508)
			(layers "F.Cu" "F.Mask" "F.Paste")
			(net "VR_PVCCIN_CPU1_AIREF5")
			(options
				(clearance outline)
				(anchor circle)
			)
			(primitives
				(gr_poly
					(pts
						(arc
							(start -0.254 0.1016)
							(mid -0.3556 0)
							(end -0.254 -0.1016)
						)
						(xy 0.3556 -0.1016) (xy 0.3556 0.1016)
					)
					(width 0)
					(fill yes)
				)
			)
		)
		(pad "32" smd custom
			(at 2.8956 -0.599948)
			(size 0.0508 0.0508)
			(layers "F.Cu" "F.Mask" "F.Paste")
			(net "ISENSE_PVCCIN_CPU1_PH5_IMON")
			(options
				(clearance outline)
				(anchor circle)
			)
			(primitives
				(gr_poly
					(pts
						(arc
							(start -0.254 0.1016)
							(mid -0.3556 0)
							(end -0.254 -0.1016)
						)
						(xy 0.3556 -0.1016) (xy 0.3556 0.1016)
					)
					(width 0)
					(fill yes)
				)
			)
		)
		(pad "33" smd custom
			(at 2.8956 -0.999998)
			(size 0.0508 0.0508)
			(layers "F.Cu" "F.Mask" "F.Paste")
			(net "Net_276")
			(options
				(clearance outline)
				(anchor circle)
			)
			(primitives
				(gr_poly
					(pts
						(arc
							(start -0.254 0.1016)
							(mid -0.3556 0)
							(end -0.254 -0.1016)
						)
						(xy 0.3556 -0.1016) (xy 0.3556 0.1016)
					)
					(width 0)
					(fill yes)
				)
			)
		)
		(pad "34" smd custom
			(at 2.8956 -1.400048)
			(size 0.0508 0.0508)
			(layers "F.Cu" "F.Mask" "F.Paste")
			(net "Net_291")
			(options
				(clearance outline)
				(anchor circle)
			)
			(primitives
				(gr_poly
					(pts
						(arc
							(start -0.254 0.1016)
							(mid -0.3556 0)
							(end -0.254 -0.1016)
						)
						(xy 0.3556 -0.1016) (xy 0.3556 0.1016)
					)
					(width 0)
					(fill yes)
				)
			)
		)
		(pad "35" smd custom
			(at 2.8956 -1.800098)
			(size 0.0508 0.0508)
			(layers "F.Cu" "F.Mask" "F.Paste")
			(net "VSENSE_PVSA_CPU1_BVSP")
			(options
				(clearance outline)
				(anchor circle)
			)
			(primitives
				(gr_poly
					(pts
						(arc
							(start -0.254 0.1016)
							(mid -0.3556 0)
							(end -0.254 -0.1016)
						)
						(xy 0.3556 -0.1016) (xy 0.3556 0.1016)
					)
					(width 0)
					(fill yes)
				)
			)
		)
		(pad "36" smd custom
			(at 2.8956 -2.199894)
			(size 0.0508 0.0508)
			(layers "F.Cu" "F.Mask" "F.Paste")
			(net "VSENSE_PVSA_CPU1_N")
			(options
				(clearance outline)
				(anchor circle)
			)
			(primitives
				(gr_poly
					(pts
						(arc
							(start -0.254 0.1016)
							(mid -0.3556 0)
							(end -0.254 -0.1016)
						)
						(xy 0.3556 -0.1016) (xy 0.3556 0.1016)
					)
					(width 0)
					(fill yes)
				)
			)
		)
		(pad "37" smd custom
			(at 2.199894 -2.8956)
			(size 0.0508 0.0508)
			(layers "F.Cu" "F.Mask" "F.Paste")
			(net "VR_PVSA_CPU1_BIREF1")
			(options
				(clearance outline)
				(anchor circle)
			)
			(primitives
				(gr_poly
					(pts
						(arc
							(start 0.1016 0.254)
							(mid 0 0.3556)
							(end -0.1016 0.254)
						)
						(xy -0.1016 -0.3556) (xy 0.1016 -0.3556)
					)
					(width 0)
					(fill yes)
				)
			)
		)
		(pad "38" smd custom
			(at 1.800098 -2.8956)
			(size 0.0508 0.0508)
			(layers "F.Cu" "F.Mask" "F.Paste")
			(net "ISENSE_PVSA_CPU1_IMON")
			(options
				(clearance outline)
				(anchor circle)
			)
			(primitives
				(gr_poly
					(pts
						(arc
							(start 0.1016 0.254)
							(mid 0 0.3556)
							(end -0.1016 0.254)
						)
						(xy -0.1016 -0.3556) (xy 0.1016 -0.3556)
					)
					(width 0)
					(fill yes)
				)
			)
		)
		(pad "39" smd custom
			(at 1.400048 -2.8956)
			(size 0.0508 0.0508)
			(layers "F.Cu" "F.Mask" "F.Paste")
			(net "PU_VR_PVCCIN_CPU1_IMON")
			(options
				(clearance outline)
				(anchor circle)
			)
			(primitives
				(gr_poly
					(pts
						(arc
							(start 0.1016 0.254)
							(mid 0 0.3556)
							(end -0.1016 0.254)
						)
						(xy -0.1016 -0.3556) (xy 0.1016 -0.3556)
					)
					(width 0)
					(fill yes)
				)
			)
		)
		(pad "40" smd custom
			(at 0.999998 -2.8956)
			(size 0.0508 0.0508)
			(layers "F.Cu" "F.Mask" "F.Paste")
			(net "Net_293")
			(options
				(clearance outline)
				(anchor circle)
			)
			(primitives
				(gr_poly
					(pts
						(arc
							(start 0.1016 0.254)
							(mid 0 0.3556)
							(end -0.1016 0.254)
						)
						(xy -0.1016 -0.3556) (xy 0.1016 -0.3556)
					)
					(width 0)
					(fill yes)
				)
			)
		)
		(pad "41" smd custom
			(at 0.599948 -2.8956)
			(size 0.0508 0.0508)
			(layers "F.Cu" "F.Mask" "F.Paste")
			(net "VR_PVCCIN_CPU1_XADDR2")
			(options
				(clearance outline)
				(anchor circle)
			)
			(primitives
				(gr_poly
					(pts
						(arc
							(start 0.1016 0.254)
							(mid 0 0.3556)
							(end -0.1016 0.254)
						)
						(xy -0.1016 -0.3556) (xy 0.1016 -0.3556)
					)
					(width 0)
					(fill yes)
				)
			)
		)
		(pad "42" smd custom
			(at 0.199898 -2.8956)
			(size 0.0508 0.0508)
			(layers "F.Cu" "F.Mask" "F.Paste")
			(net "A_TSENSE_PVSA_CPU1")
			(options
				(clearance outline)
				(anchor circle)
			)
			(primitives
				(gr_poly
					(pts
						(arc
							(start 0.1016 0.254)
							(mid 0 0.3556)
							(end -0.1016 0.254)
						)
						(xy -0.1016 -0.3556) (xy 0.1016 -0.3556)
					)
					(width 0)
					(fill yes)
				)
			)
		)
		(pad "43" smd custom
			(at -0.199898 -2.8956)
			(size 0.0508 0.0508)
			(layers "F.Cu" "F.Mask" "F.Paste")
			(net "A_TSENSE_PVCCIN_CPU1")
			(options
				(clearance outline)
				(anchor circle)
			)
			(primitives
				(gr_poly
					(pts
						(arc
							(start 0.1016 0.254)
							(mid 0 0.3556)
							(end -0.1016 0.254)
						)
						(xy -0.1016 -0.3556) (xy 0.1016 -0.3556)
					)
					(width 0)
					(fill yes)
				)
			)
		)
		(pad "44" smd custom
			(at -0.599948 -2.8956)
			(size 0.0508 0.0508)
			(layers "F.Cu" "F.Mask" "F.Paste")
			(net "VR_PVCCIN_CPU1_XADDR1")
			(options
				(clearance outline)
				(anchor circle)
			)
			(primitives
				(gr_poly
					(pts
						(arc
							(start 0.1016 0.254)
							(mid 0 0.3556)
							(end -0.1016 0.254)
						)
						(xy -0.1016 -0.3556) (xy 0.1016 -0.3556)
					)
					(width 0)
					(fill yes)
				)
			)
		)
		(pad "45" smd custom
			(at -0.999998 -2.8956)
			(size 0.0508 0.0508)
			(layers "F.Cu" "F.Mask" "F.Paste")
			(net "VR_PVCCIN_CPU1_AVINSEN")
			(options
				(clearance outline)
				(anchor circle)
			)
			(primitives
				(gr_poly
					(pts
						(arc
							(start 0.1016 0.254)
							(mid 0 0.3556)
							(end -0.1016 0.254)
						)
						(xy -0.1016 -0.3556) (xy 0.1016 -0.3556)
					)
					(width 0)
					(fill yes)
				)
			)
		)
		(pad "46" smd custom
			(at -1.400048 -2.8956)
			(size 0.0508 0.0508)
			(layers "F.Cu" "F.Mask" "F.Paste")
			(net "Net_218")
			(options
				(clearance outline)
				(anchor circle)
			)
			(primitives
				(gr_poly
					(pts
						(arc
							(start 0.1016 0.254)
							(mid 0 0.3556)
							(end -0.1016 0.254)
						)
						(xy -0.1016 -0.3556) (xy 0.1016 -0.3556)
					)
					(width 0)
					(fill yes)
				)
			)
		)
		(pad "47" smd custom
			(at -1.800098 -2.8956)
			(size 0.0508 0.0508)
			(layers "F.Cu" "F.Mask" "F.Paste")
			(net "VR_PVCCIN_CPU1_VDD")
			(options
				(clearance outline)
				(anchor circle)
			)
			(primitives
				(gr_poly
					(pts
						(arc
							(start 0.1016 0.254)
							(mid 0 0.3556)
							(end -0.1016 0.254)
						)
						(xy -0.1016 -0.3556) (xy 0.1016 -0.3556)
					)
					(width 0)
					(fill yes)
				)
			)
		)
		(pad "48" smd custom
			(at -2.199894 -2.8956)
			(size 0.0508 0.0508)
			(layers "F.Cu" "F.Mask" "F.Paste")
			(net "VR_PVCCIN_CPU1_VD12")
			(options
				(clearance outline)
				(anchor circle)
			)
			(primitives
				(gr_poly
					(pts
						(arc
							(start 0.1016 0.254)
							(mid 0 0.3556)
							(end -0.1016 0.254)
						)
						(xy -0.1016 -0.3556) (xy 0.1016 -0.3556)
					)
					(width 0)
					(fill yes)
				)
			)
		)
		(pad "49" smd rect
			(at 0 0)
			(size 3.6068 3.6068)
			(layers "F.Cu" "F.Mask" "F.Paste")
			(net "GND")
		)
		(zone
			(layer "F.Cu")
			(hatch none 0.5)
			(connect_pads
				(clearance 0)
			)
			(min_thickness 0.25)
			(keepout
				(tracks allowed)
				(vias not_allowed)
				(pads allowed)
				(copperpour not_allowed)
				(footprints allowed)
			)
			(placement
				(enabled no)
				(sheetname "")
			)
			(fill
				(thermal_gap 0.5)
				(thermal_bridge_width 0.5)
				(island_removal_mode 0)
			)
			(polygon
				(pts
					(xy 16.892778 -94.993714) (xy 16.892778 -90.853514) (xy 17.624044 -90.853514) (xy 17.624044 -90.854022)
					(xy 17.6276 -90.854022) (xy 17.6276 -94.2594) (xy 21.2344 -94.2594) (xy 21.2344 -90.6526) (xy 17.6276 -90.6526)
					(xy 17.6276 -90.853768) (xy 17.624298 -90.853768) (xy 17.624298 -90.853006) (xy 16.892778 -90.853006)
					(xy 16.892778 -89.917016) (xy 21.970238 -89.917016) (xy 21.970238 -94.993714)
				)
			)
		)
		(zone
			(layer "F.Cu")
			(hatch none 0.5)
			(connect_pads
				(clearance 0)
			)
			(min_thickness 0.25)
			(keepout
				(tracks not_allowed)
				(vias allowed)
				(pads allowed)
				(copperpour not_allowed)
				(footprints allowed)
			)
			(placement
				(enabled no)
				(sheetname "")
			)
			(fill
				(thermal_gap 0.5)
				(thermal_bridge_width 0.5)
				(island_removal_mode 0)
			)
			(polygon
				(pts
					(xy 16.892778 -94.993714) (xy 16.892778 -90.853514) (xy 17.624044 -90.853514) (xy 17.624044 -90.854022)
					(xy 17.6276 -90.854022) (xy 17.6276 -94.2594) (xy 21.2344 -94.2594) (xy 21.2344 -90.6526) (xy 17.6276 -90.6526)
					(xy 17.6276 -90.853768) (xy 17.624298 -90.853768) (xy 17.624298 -90.853006) (xy 16.892778 -90.853006)
					(xy 16.892778 -89.917016) (xy 21.970238 -89.917016) (xy 21.970238 -94.993714)
				)
			)
		)
	)
	(footprint ""
		(layer "F.Cu")
		(at 383.14757 -78.902814 90)
		(property "Reference" "R7D28"
			(at 0 0 90)
			(layer "F.SilkS")
			(hide yes)
			(effects
				(font
					(size 1.27 1.27)
				)
			)
		)
		(property "Value" ""
			(at 0 0 90)
			(layer "F.Fab")
			(effects
				(font
					(size 1.27 1.27)
				)
			)
		)
		(duplicate_pad_numbers_are_jumpers no)
		(fp_poly
			(pts
				(xy -0.2794 -0.1016) (xy 0.2794 -0.1016) (xy 0.2794 0.9906) (xy -0.2794 0.9906)
			)
			(stroke
				(width 0)
				(type default)
			)
			(fill no)
			(layer "F.CrtYd")
		)
		(fp_line
			(start 0.2794 -0.1016)
			(end -0.2794 -0.1016)
			(stroke
				(width 0.1)
				(type default)
			)
			(layer "F.Fab")
		)
		(fp_line
			(start -0.2794 -0.1016)
			(end -0.2794 0.9906)
			(stroke
				(width 0.1)
				(type default)
			)
			(layer "F.Fab")
		)
		(fp_line
			(start 0.2794 0.9906)
			(end 0.2794 -0.1016)
			(stroke
				(width 0.1)
				(type default)
			)
			(layer "F.Fab")
		)
		(fp_line
			(start -0.2794 0.9906)
			(end 0.2794 0.9906)
			(stroke
				(width 0.1)
				(type default)
			)
			(layer "F.Fab")
		)
		(pad "1" smd rect
			(at 0 0 90)
			(size 0.508 0.508)
			(layers "F.Cu" "F.Mask" "F.Paste")
			(net "H_CPU1_MSMI_G_N")
		)
		(pad "2" smd rect
			(at 0 0.889 90)
			(size 0.508 0.508)
			(layers "F.Cu" "F.Mask" "F.Paste")
			(net "H_CPU_MSMI_G_N")
		)
		(zone
			(layer "F.Cu")
			(hatch none 0.5)
			(connect_pads
				(clearance 0)
			)
			(min_thickness 0.25)
			(keepout
				(tracks allowed)
				(vias not_allowed)
				(pads allowed)
				(copperpour not_allowed)
				(footprints allowed)
			)
			(placement
				(enabled no)
				(sheetname "")
			)
			(fill
				(thermal_gap 0.5)
				(thermal_bridge_width 0.5)
				(island_removal_mode 0)
			)
			(polygon
				(pts
					(xy 383.40157 -78.648814) (xy 383.40157 -79.156814) (xy 383.78257 -79.156814) (xy 383.78257 -78.648814)
				)
			)
		)
		(zone
			(layer "F.Cu")
			(hatch none 0.5)
			(connect_pads
				(clearance 0)
			)
			(min_thickness 0.25)
			(keepout
				(tracks not_allowed)
				(vias allowed)
				(pads allowed)
				(copperpour not_allowed)
				(footprints allowed)
			)
			(placement
				(enabled no)
				(sheetname "")
			)
			(fill
				(thermal_gap 0.5)
				(thermal_bridge_width 0.5)
				(island_removal_mode 0)
			)
			(polygon
				(pts
					(xy 383.78257 -78.648814) (xy 383.78257 -79.156814) (xy 383.40157 -79.156814) (xy 383.40157 -78.648814)
				)
			)
		)
	)
	(footprint ""
		(layer "F.Cu")
		(at 438.912 -20.828)
		(property "Reference" "CR10W1"
			(at 1.06934 -0.39116 270)
			(unlocked yes)
			(layer "F.SilkS")
			(effects
				(font
					(size 0.4064 0.254)
					(thickness 0.1524)
				)
				(justify left)
			)
		)
		(property "Value" ""
			(at 0 0 0)
			(layer "F.Fab")
			(effects
				(font
					(size 1.27 1.27)
				)
			)
		)
		(duplicate_pad_numbers_are_jumpers no)
		(fp_line
			(start -1.3843 0.038862)
			(end -0.903478 -0.794004)
			(stroke
				(width 0.1524)
				(type default)
			)
			(layer "F.SilkS")
		)
		(fp_line
			(start -0.903478 -1.917446)
			(end -0.903478 -0.794004)
			(stroke
				(width 0.1524)
				(type default)
			)
			(layer "F.SilkS")
		)
		(fp_line
			(start -0.903478 -0.794004)
			(end -0.422656 0.038862)
			(stroke
				(width 0.1524)
				(type default)
			)
			(layer "F.SilkS")
		)
		(fp_line
			(start -0.903478 0.038862)
			(end -1.3843 0.038862)
			(stroke
				(width 0.1524)
				(type default)
			)
			(layer "F.SilkS")
		)
		(fp_line
			(start -0.903478 0.950468)
			(end -0.903478 0.038862)
			(stroke
				(width 0.1524)
				(type default)
			)
			(layer "F.SilkS")
		)
		(fp_line
			(start -0.422656 -0.794004)
			(end -1.3843 -0.794004)
			(stroke
				(width 0.1524)
				(type default)
			)
			(layer "F.SilkS")
		)
		(fp_line
			(start -0.422656 0.038862)
			(end -0.903478 0.038862)
			(stroke
				(width 0.1524)
				(type default)
			)
			(layer "F.SilkS")
		)
		(fp_poly
			(pts
				(xy -0.67437 0.24384) (xy -0.67437 2.04216) (xy 0.67437 2.04216) (xy 0.67437 0.24384)
			)
			(stroke
				(width 0)
				(type default)
			)
			(fill no)
			(layer "F.CrtYd")
		)
		(fp_line
			(start -1.3843 0.038862)
			(end -0.903478 -0.794004)
			(stroke
				(width 0.1)
				(type default)
			)
			(layer "F.Fab")
		)
		(fp_line
			(start -0.903478 -0.794004)
			(end -0.903478 -1.917446)
			(stroke
				(width 0.1)
				(type default)
			)
			(layer "F.Fab")
		)
		(fp_line
			(start -0.903478 -0.794004)
			(end -0.422656 0.038862)
			(stroke
				(width 0.1)
				(type default)
			)
			(layer "F.Fab")
		)
		(fp_line
			(start -0.903478 0.038862)
			(end -0.903478 0.950468)
			(stroke
				(width 0.1)
				(type default)
			)
			(layer "F.Fab")
		)
		(fp_line
			(start -0.67437 0.24384)
			(end -0.67437 2.04216)
			(stroke
				(width 0.1)
				(type default)
			)
			(layer "F.Fab")
		)
		(fp_line
			(start -0.67437 2.04216)
			(end 0.67437 2.04216)
			(stroke
				(width 0.1)
				(type default)
			)
			(layer "F.Fab")
		)
		(fp_line
			(start -0.422656 -0.794004)
			(end -1.3843 -0.794004)
			(stroke
				(width 0.1)
				(type default)
			)
			(layer "F.Fab")
		)
		(fp_line
			(start -0.422656 0.038862)
			(end -1.3843 0.038862)
			(stroke
				(width 0.1)
				(type default)
			)
			(layer "F.Fab")
		)
		(fp_line
			(start 0.67437 0.24384)
			(end -0.67437 0.24384)
			(stroke
				(width 0.1)
				(type default)
			)
			(layer "F.Fab")
		)
		(fp_line
			(start 0.67437 2.04216)
			(end 0.67437 0.24384)
			(stroke
				(width 0.1)
				(type default)
			)
			(layer "F.Fab")
		)
		(pad "1" smd rect
			(at 0 0)
			(size 0.4064 1.016)
			(layers "F.Cu" "F.Mask" "F.Paste")
			(net "PUMP_TACH_D")
		)
		(pad "2" smd rect
			(at 0 2.286)
			(size 0.4064 1.016)
			(layers "F.Cu" "F.Mask" "F.Paste")
			(net "PUMP_TACH_R")
		)
	)
	(footprint ""
		(layer "F.Cu")
		(at 243.735606 -26.591006 -45)
		(property "Reference" "C5F1"
			(at 0 0 315)
			(layer "F.SilkS")
			(hide yes)
			(effects
				(font
					(size 1.27 1.27)
				)
			)
		)
		(property "Value" ""
			(at 0 0 315)
			(layer "F.Fab")
			(effects
				(font
					(size 1.27 1.27)
				)
			)
		)
		(duplicate_pad_numbers_are_jumpers no)
		(fp_poly
			(pts
				(xy -0.500021 -0.201359) (xy 0.500231 -0.201359) (xy 0.500231 1.598486) (xy -0.500021 1.598486)
			)
			(stroke
				(width 0)
				(type default)
			)
			(fill no)
			(layer "F.CrtYd")
		)
		(fp_line
			(start -0.500021 1.598486)
			(end -0.5002 -0.201337)
			(stroke
				(width 0.1)
				(type default)
			)
			(layer "F.Fab")
		)
		(fp_line
			(start 0.500021 1.598486)
			(end -0.500021 1.598486)
			(stroke
				(width 0.1)
				(type default)
			)
			(layer "F.Fab")
		)
		(fp_line
			(start -0.5002 -0.201337)
			(end 0.5002 -0.201337)
			(stroke
				(width 0.1)
				(type default)
			)
			(layer "F.Fab")
		)
		(fp_line
			(start 0.5002 -0.201337)
			(end 0.500021 1.598486)
			(stroke
				(width 0.1)
				(type default)
			)
			(layer "F.Fab")
		)
		(pad "1" smd rect
			(at 0 0 225)
			(size 0.889 0.9906)
			(layers "F.Cu" "F.Mask" "F.Paste")
			(net "PVDDQ_ABC")
		)
		(pad "2" smd rect
			(at 0 1.397 225)
			(size 0.889 0.9906)
			(layers "F.Cu" "F.Mask" "F.Paste")
			(net "GND")
		)
		(zone
			(layer "F.Cu")
			(hatch none 0.5)
			(connect_pads
				(clearance 0)
			)
			(min_thickness 0.25)
			(keepout
				(tracks not_allowed)
				(vias allowed)
				(pads allowed)
				(copperpour not_allowed)
				(footprints allowed)
			)
			(placement
				(enabled no)
				(sheetname "")
			)
			(fill
				(thermal_gap 0.5)
				(thermal_bridge_width 0.5)
				(island_removal_mode 0)
			)
			(polygon
				(pts
					(xy 242.711732 -26.267664) (xy 243.412192 -25.567204) (xy 243.771402 -25.926414) (xy 243.070942 -26.626874)
				)
			)
		)
		(zone
			(layer "F.Cu")
			(hatch none 0.5)
			(connect_pads
				(clearance 0)
			)
			(min_thickness 0.25)
			(keepout
				(tracks allowed)
				(vias not_allowed)
				(pads allowed)
				(copperpour not_allowed)
				(footprints allowed)
			)
			(placement
				(enabled no)
				(sheetname "")
			)
			(fill
				(thermal_gap 0.5)
				(thermal_bridge_width 0.5)
				(island_removal_mode 0)
			)
			(polygon
				(pts
					(xy 242.711732 -26.267664) (xy 243.412192 -25.567204) (xy 243.771402 -25.926414) (xy 243.070942 -26.626874)
				)
			)
		)
	)
	(footprint ""
		(layer "F.Cu")
		(at 94.343728 -13.004292 90)
		(property "Reference" "C2G7"
			(at 0 0 90)
			(layer "F.SilkS")
			(hide yes)
			(effects
				(font
					(size 1.27 1.27)
				)
			)
		)
		(property "Value" ""
			(at 0 0 90)
			(layer "F.Fab")
			(effects
				(font
					(size 1.27 1.27)
				)
			)
		)
		(duplicate_pad_numbers_are_jumpers no)
		(fp_poly
			(pts
				(xy -0.7239 -0.2159) (xy 0.7239 -0.2159) (xy 0.7239 1.9939) (xy -0.7239 1.9939)
			)
			(stroke
				(width 0)
				(type default)
			)
			(fill no)
			(layer "F.CrtYd")
		)
		(fp_line
			(start 0.7239 -0.2159)
			(end -0.7239 -0.2159)
			(stroke
				(width 0.1)
				(type default)
			)
			(layer "F.Fab")
		)
		(fp_line
			(start -0.7239 -0.2159)
			(end -0.7239 1.9939)
			(stroke
				(width 0.1)
				(type default)
			)
			(layer "F.Fab")
		)
		(fp_line
			(start 0.7239 1.9939)
			(end 0.7239 -0.2159)
			(stroke
				(width 0.1)
				(type default)
			)
			(layer "F.Fab")
		)
		(fp_line
			(start -0.7239 1.9939)
			(end 0.7239 1.9939)
			(stroke
				(width 0.1)
				(type default)
			)
			(layer "F.Fab")
		)
		(pad "1" smd rect
			(at 0 0 90)
			(size 1.27 1.016)
			(layers "F.Cu" "F.Mask" "F.Paste")
			(net "PVDDQ_GHJ")
		)
		(pad "2" smd rect
			(at 0 1.778 90)
			(size 1.27 1.016)
			(layers "F.Cu" "F.Mask" "F.Paste")
			(net "GND")
		)
		(zone
			(layer "F.Cu")
			(hatch none 0.5)
			(connect_pads
				(clearance 0)
			)
			(min_thickness 0.25)
			(keepout
				(tracks not_allowed)
				(vias allowed)
				(pads allowed)
				(copperpour not_allowed)
				(footprints allowed)
			)
			(placement
				(enabled no)
				(sheetname "")
			)
			(fill
				(thermal_gap 0.5)
				(thermal_bridge_width 0.5)
				(island_removal_mode 0)
			)
			(polygon
				(pts
					(xy 94.851728 -12.369292) (xy 94.851728 -13.639292) (xy 95.613728 -13.639292) (xy 95.613728 -12.369292)
				)
			)
		)
	)
	(footprint ""
		(layer "F.Cu")
		(at 490.2581 -45.9994 90)
		(property "Reference" "R9E9"
			(at 0 0 90)
			(layer "F.SilkS")
			(hide yes)
			(effects
				(font
					(size 1.27 1.27)
				)
			)
		)
		(property "Value" ""
			(at 0 0 90)
			(layer "F.Fab")
			(effects
				(font
					(size 1.27 1.27)
				)
			)
		)
		(duplicate_pad_numbers_are_jumpers no)
		(fp_poly
			(pts
				(xy -0.2794 -0.1016) (xy 0.2794 -0.1016) (xy 0.2794 0.9906) (xy -0.2794 0.9906)
			)
			(stroke
				(width 0)
				(type default)
			)
			(fill no)
			(layer "F.CrtYd")
		)
		(fp_line
			(start 0.2794 -0.1016)
			(end -0.2794 -0.1016)
			(stroke
				(width 0.1)
				(type default)
			)
			(layer "F.Fab")
		)
		(fp_line
			(start -0.2794 -0.1016)
			(end -0.2794 0.9906)
			(stroke
				(width 0.1)
				(type default)
			)
			(layer "F.Fab")
		)
		(fp_line
			(start 0.2794 0.9906)
			(end 0.2794 -0.1016)
			(stroke
				(width 0.1)
				(type default)
			)
			(layer "F.Fab")
		)
		(fp_line
			(start -0.2794 0.9906)
			(end 0.2794 0.9906)
			(stroke
				(width 0.1)
				(type default)
			)
			(layer "F.Fab")
		)
		(pad "1" smd rect
			(at 0 0 90)
			(size 0.508 0.508)
			(layers "F.Cu" "F.Mask" "F.Paste")
			(net "SPI_NIC_MOSI_R")
		)
		(pad "2" smd rect
			(at 0 0.889 90)
			(size 0.508 0.508)
			(layers "F.Cu" "F.Mask" "F.Paste")
			(net "SPI_NIC_MOSI")
		)
		(zone
			(layer "F.Cu")
			(hatch none 0.5)
			(connect_pads
				(clearance 0)
			)
			(min_thickness 0.25)
			(keepout
				(tracks allowed)
				(vias not_allowed)
				(pads allowed)
				(copperpour not_allowed)
				(footprints allowed)
			)
			(placement
				(enabled no)
				(sheetname "")
			)
			(fill
				(thermal_gap 0.5)
				(thermal_bridge_width 0.5)
				(island_removal_mode 0)
			)
			(polygon
				(pts
					(xy 490.5121 -45.7454) (xy 490.5121 -46.2534) (xy 490.8931 -46.2534) (xy 490.8931 -45.7454)
				)
			)
		)
		(zone
			(layer "F.Cu")
			(hatch none 0.5)
			(connect_pads
				(clearance 0)
			)
			(min_thickness 0.25)
			(keepout
				(tracks not_allowed)
				(vias allowed)
				(pads allowed)
				(copperpour not_allowed)
				(footprints allowed)
			)
			(placement
				(enabled no)
				(sheetname "")
			)
			(fill
				(thermal_gap 0.5)
				(thermal_bridge_width 0.5)
				(island_removal_mode 0)
			)
			(polygon
				(pts
					(xy 490.8931 -45.7454) (xy 490.8931 -46.2534) (xy 490.5121 -46.2534) (xy 490.5121 -45.7454)
				)
			)
		)
	)
	(footprint ""
		(layer "F.Cu")
		(at 155.575 -149.606 90)
		(property "Reference" "C3A4"
			(at 0 0 90)
			(layer "F.SilkS")
			(hide yes)
			(effects
				(font
					(size 1.27 1.27)
				)
			)
		)
		(property "Value" ""
			(at 0 0 90)
			(layer "F.Fab")
			(effects
				(font
					(size 1.27 1.27)
				)
			)
		)
		(duplicate_pad_numbers_are_jumpers no)
		(fp_rect
			(start -0.4953 1.6002)
			(end 0.4953 -0.2032)
			(stroke
				(width 0)
				(type default)
			)
			(fill no)
			(layer "F.CrtYd")
		)
		(fp_line
			(start 0.4953 -0.2032)
			(end 0.4953 1.6002)
			(stroke
				(width 0.1)
				(type default)
			)
			(layer "F.Fab")
		)
		(fp_line
			(start -0.4953 -0.2032)
			(end 0.4953 -0.2032)
			(stroke
				(width 0.1)
				(type default)
			)
			(layer "F.Fab")
		)
		(fp_line
			(start 0.4953 1.6002)
			(end -0.4953 1.6002)
			(stroke
				(width 0.1)
				(type default)
			)
			(layer "F.Fab")
		)
		(fp_line
			(start -0.4953 1.6002)
			(end -0.4953 -0.2032)
			(stroke
				(width 0.1)
				(type default)
			)
			(layer "F.Fab")
		)
		(pad "1" smd rect
			(at 0 0 90)
			(size 0.762 0.889)
			(layers "F.Cu" "F.Mask" "F.Paste")
			(net "PVPP_KLM")
		)
		(pad "2" smd rect
			(at 0 1.397 90)
			(size 0.762 0.889)
			(layers "F.Cu" "F.Mask" "F.Paste")
			(net "GND")
		)
		(zone
			(layer "F.Cu")
			(hatch none 0.5)
			(connect_pads
				(clearance 0)
			)
			(min_thickness 0.25)
			(keepout
				(tracks not_allowed)
				(vias allowed)
				(pads allowed)
				(copperpour not_allowed)
				(footprints allowed)
			)
			(placement
				(enabled no)
				(sheetname "")
			)
			(fill
				(thermal_gap 0.5)
				(thermal_bridge_width 0.5)
				(island_removal_mode 0)
			)
			(polygon
				(pts
					(xy 156.5275 -149.225) (xy 156.5275 -149.987) (xy 156.0195 -149.987) (xy 156.0195 -149.225)
				)
			)
		)
	)
	(footprint ""
		(layer "F.Cu")
		(at 415.29 -101.2698 90)
		(property "Reference" "R1W30"
			(at -0.8382 -0.67818 90)
			(unlocked yes)
			(layer "F.SilkS")
			(effects
				(font
					(size 0.4064 0.254)
					(thickness 0.1524)
				)
				(justify left)
			)
		)
		(property "Value" ""
			(at 0 0 90)
			(layer "F.Fab")
			(effects
				(font
					(size 1.27 1.27)
				)
			)
		)
		(duplicate_pad_numbers_are_jumpers no)
		(fp_poly
			(pts
				(xy -0.2794 -0.1016) (xy 0.2794 -0.1016) (xy 0.2794 0.9906) (xy -0.2794 0.9906)
			)
			(stroke
				(width 0)
				(type default)
			)
			(fill no)
			(layer "F.CrtYd")
		)
		(fp_line
			(start 0.2794 -0.1016)
			(end -0.2794 -0.1016)
			(stroke
				(width 0.1)
				(type default)
			)
			(layer "F.Fab")
		)
		(fp_line
			(start -0.2794 -0.1016)
			(end -0.2794 0.9906)
			(stroke
				(width 0.1)
				(type default)
			)
			(layer "F.Fab")
		)
		(fp_line
			(start 0.2794 0.9906)
			(end 0.2794 -0.1016)
			(stroke
				(width 0.1)
				(type default)
			)
			(layer "F.Fab")
		)
		(fp_line
			(start -0.2794 0.9906)
			(end 0.2794 0.9906)
			(stroke
				(width 0.1)
				(type default)
			)
			(layer "F.Fab")
		)
		(pad "1" smd rect
			(at 0 0 90)
			(size 0.508 0.508)
			(layers "F.Cu" "F.Mask" "F.Paste")
			(net "RST_BMC_SYSRST_BTN_OUT_B_N")
		)
		(pad "2" smd rect
			(at 0 0.889 90)
			(size 0.508 0.508)
			(layers "F.Cu" "F.Mask" "F.Paste")
			(net "RST_SYSTEM_BTN_BUF_N")
		)
		(zone
			(layer "F.Cu")
			(hatch none 0.5)
			(connect_pads
				(clearance 0)
			)
			(min_thickness 0.25)
			(keepout
				(tracks allowed)
				(vias not_allowed)
				(pads allowed)
				(copperpour not_allowed)
				(footprints allowed)
			)
			(placement
				(enabled no)
				(sheetname "")
			)
			(fill
				(thermal_gap 0.5)
				(thermal_bridge_width 0.5)
				(island_removal_mode 0)
			)
			(polygon
				(pts
					(xy 415.544 -101.0158) (xy 415.544 -101.5238) (xy 415.925 -101.5238) (xy 415.925 -101.0158)
				)
			)
		)
		(zone
			(layer "F.Cu")
			(hatch none 0.5)
			(connect_pads
				(clearance 0)
			)
			(min_thickness 0.25)
			(keepout
				(tracks not_allowed)
				(vias allowed)
				(pads allowed)
				(copperpour not_allowed)
				(footprints allowed)
			)
			(placement
				(enabled no)
				(sheetname "")
			)
			(fill
				(thermal_gap 0.5)
				(thermal_bridge_width 0.5)
				(island_removal_mode 0)
			)
			(polygon
				(pts
					(xy 415.925 -101.0158) (xy 415.925 -101.5238) (xy 415.544 -101.5238) (xy 415.544 -101.0158)
				)
			)
		)
	)
	(footprint ""
		(layer "F.Cu")
		(at 352.9965 -151.257 -90)
		(property "Reference" "C7A12"
			(at 0 0 270)
			(layer "F.SilkS")
			(hide yes)
			(effects
				(font
					(size 1.27 1.27)
				)
			)
		)
		(property "Value" ""
			(at 0 0 270)
			(layer "F.Fab")
			(effects
				(font
					(size 1.27 1.27)
				)
			)
		)
		(duplicate_pad_numbers_are_jumpers no)
		(fp_poly
			(pts
				(xy 0.3048 -0.1016) (xy 0.3048 0.9906) (xy -0.3048 0.9906) (xy -0.3048 -0.1016)
			)
			(stroke
				(width 0)
				(type default)
			)
			(fill no)
			(layer "F.CrtYd")
		)
		(fp_line
			(start -0.3048 0.9906)
			(end 0.3048 0.9906)
			(stroke
				(width 0.1)
				(type default)
			)
			(layer "F.Fab")
		)
		(fp_line
			(start 0.3048 0.9906)
			(end 0.3048 -0.1016)
			(stroke
				(width 0.1)
				(type default)
			)
			(layer "F.Fab")
		)
		(fp_line
			(start -0.3048 -0.1016)
			(end -0.3048 0.9906)
			(stroke
				(width 0.1)
				(type default)
			)
			(layer "F.Fab")
		)
		(fp_line
			(start 0.3048 -0.1016)
			(end -0.3048 -0.1016)
			(stroke
				(width 0.1)
				(type default)
			)
			(layer "F.Fab")
		)
		(pad "1" smd rect
			(at 0 0 270)
			(size 0.508 0.508)
			(layers "F.Cu" "F.Mask" "F.Paste")
			(net "VR_PVDDQ_DEF_PH1_BOOT")
		)
		(pad "2" smd rect
			(at 0 0.889 270)
			(size 0.508 0.508)
			(layers "F.Cu" "F.Mask" "F.Paste")
			(net "VR_PVDDQ_DEF_PH1_PHASE")
		)
		(zone
			(layer "F.Cu")
			(hatch none 0.5)
			(connect_pads
				(clearance 0)
			)
			(min_thickness 0.25)
			(keepout
				(tracks not_allowed)
				(vias allowed)
				(pads allowed)
				(copperpour not_allowed)
				(footprints allowed)
			)
			(placement
				(enabled no)
				(sheetname "")
			)
			(fill
				(thermal_gap 0.5)
				(thermal_bridge_width 0.5)
				(island_removal_mode 0)
			)
			(polygon
				(pts
					(xy 352.3615 -151.511) (xy 352.3615 -151.003) (xy 352.7425 -151.003) (xy 352.7425 -151.511)
				)
			)
		)
		(zone
			(layer "F.Cu")
			(hatch none 0.5)
			(connect_pads
				(clearance 0)
			)
			(min_thickness 0.25)
			(keepout
				(tracks allowed)
				(vias not_allowed)
				(pads allowed)
				(copperpour not_allowed)
				(footprints allowed)
			)
			(placement
				(enabled no)
				(sheetname "")
			)
			(fill
				(thermal_gap 0.5)
				(thermal_bridge_width 0.5)
				(island_removal_mode 0)
			)
			(polygon
				(pts
					(xy 352.7425 -151.511) (xy 352.7425 -151.003) (xy 352.3615 -151.003) (xy 352.3615 -151.511)
				)
			)
		)
	)
	(footprint ""
		(layer "F.Cu")
		(at 253.392432 -140.208 90)
		(property "Reference" "C5A14"
			(at 1.848866 0.752348 90)
			(unlocked yes)
			(layer "F.SilkS")
			(effects
				(font
					(size 1.27 0.9652)
					(thickness 0.1524)
				)
			)
		)
		(property "Value" ""
			(at 0 0 90)
			(layer "F.Fab")
			(effects
				(font
					(size 1.27 1.27)
				)
			)
		)
		(duplicate_pad_numbers_are_jumpers no)
		(fp_rect
			(start -0.500126 1.598422)
			(end 0.500126 -0.201422)
			(stroke
				(width 0)
				(type default)
			)
			(fill no)
			(layer "F.CrtYd")
		)
		(fp_line
			(start 0.500126 -0.201422)
			(end 0.500126 1.598422)
			(stroke
				(width 0.1)
				(type default)
			)
			(layer "F.Fab")
		)
		(fp_line
			(start -0.500126 -0.201422)
			(end 0.500126 -0.201422)
			(stroke
				(width 0.1)
				(type default)
			)
			(layer "F.Fab")
		)
		(fp_line
			(start 0.500126 1.598422)
			(end -0.500126 1.598422)
			(stroke
				(width 0.1)
				(type default)
			)
			(layer "F.Fab")
		)
		(fp_line
			(start -0.500126 1.598422)
			(end -0.500126 -0.201422)
			(stroke
				(width 0.1)
				(type default)
			)
			(layer "F.Fab")
		)
		(pad "1" smd rect
			(at 0 0)
			(size 0.889 0.9906)
			(layers "F.Cu" "F.Mask" "F.Paste")
			(net "PVDDQ_DEF")
		)
		(pad "2" smd rect
			(at 0 1.397)
			(size 0.889 0.9906)
			(layers "F.Cu" "F.Mask" "F.Paste")
			(net "GND")
		)
		(zone
			(layer "F.Cu")
			(hatch none 0.5)
			(connect_pads
				(clearance 0)
			)
			(min_thickness 0.25)
			(keepout
				(tracks allowed)
				(vias not_allowed)
				(pads allowed)
				(copperpour not_allowed)
				(footprints allowed)
			)
			(placement
				(enabled no)
				(sheetname "")
			)
			(fill
				(thermal_gap 0.5)
				(thermal_bridge_width 0.5)
				(island_removal_mode 0)
			)
			(polygon
				(pts
					(xy 254.344932 -139.7127) (xy 254.344932 -140.7033) (xy 253.836932 -140.7033) (xy 253.836932 -139.7127)
				)
			)
		)
		(zone
			(layer "F.Cu")
			(hatch none 0.5)
			(connect_pads
				(clearance 0)
			)
			(min_thickness 0.25)
			(keepout
				(tracks not_allowed)
				(vias allowed)
				(pads allowed)
				(copperpour not_allowed)
				(footprints allowed)
			)
			(placement
				(enabled no)
				(sheetname "")
			)
			(fill
				(thermal_gap 0.5)
				(thermal_bridge_width 0.5)
				(island_removal_mode 0)
			)
			(polygon
				(pts
					(xy 254.344932 -139.7127) (xy 254.344932 -140.7033) (xy 253.836932 -140.7033) (xy 253.836932 -139.7127)
				)
			)
		)
	)
	(footprint ""
		(layer "F.Cu")
		(at 427.56836 -45.872654)
		(property "Reference" "R25W78"
			(at -0.8382 -0.67818 0)
			(unlocked yes)
			(layer "F.SilkS")
			(effects
				(font
					(size 0.4064 0.254)
					(thickness 0.1524)
				)
				(justify left)
			)
		)
		(property "Value" ""
			(at 0 0 0)
			(layer "F.Fab")
			(effects
				(font
					(size 1.27 1.27)
				)
			)
		)
		(duplicate_pad_numbers_are_jumpers no)
		(fp_poly
			(pts
				(xy -0.2794 -0.1016) (xy 0.2794 -0.1016) (xy 0.2794 0.9906) (xy -0.2794 0.9906)
			)
			(stroke
				(width 0)
				(type default)
			)
			(fill no)
			(layer "F.CrtYd")
		)
		(fp_line
			(start -0.2794 -0.1016)
			(end -0.2794 0.9906)
			(stroke
				(width 0.1)
				(type default)
			)
			(layer "F.Fab")
		)
		(fp_line
			(start -0.2794 0.9906)
			(end 0.2794 0.9906)
			(stroke
				(width 0.1)
				(type default)
			)
			(layer "F.Fab")
		)
		(fp_line
			(start 0.2794 -0.1016)
			(end -0.2794 -0.1016)
			(stroke
				(width 0.1)
				(type default)
			)
			(layer "F.Fab")
		)
		(fp_line
			(start 0.2794 0.9906)
			(end 0.2794 -0.1016)
			(stroke
				(width 0.1)
				(type default)
			)
			(layer "F.Fab")
		)
		(pad "1" smd rect
			(at 0 0)
			(size 0.508 0.508)
			(layers "F.Cu" "F.Mask" "F.Paste")
			(net "SPI_BMC_BT_CS_R_N")
		)
		(pad "2" smd rect
			(at 0 0.889)
			(size 0.508 0.508)
			(layers "F.Cu" "F.Mask" "F.Paste")
			(net "SPI_BMC_BT_CS_N")
		)
		(zone
			(layer "F.Cu")
			(hatch none 0.5)
			(connect_pads
				(clearance 0)
			)
			(min_thickness 0.25)
			(keepout
				(tracks allowed)
				(vias not_allowed)
				(pads allowed)
				(copperpour not_allowed)
				(footprints allowed)
			)
			(placement
				(enabled no)
				(sheetname "")
			)
			(fill
				(thermal_gap 0.5)
				(thermal_bridge_width 0.5)
				(island_removal_mode 0)
			)
			(polygon
				(pts
					(xy 427.31436 -45.618654) (xy 427.82236 -45.618654) (xy 427.82236 -45.237654) (xy 427.31436 -45.237654)
				)
			)
		)
		(zone
			(layer "F.Cu")
			(hatch none 0.5)
			(connect_pads
				(clearance 0)
			)
			(min_thickness 0.25)
			(keepout
				(tracks not_allowed)
				(vias allowed)
				(pads allowed)
				(copperpour not_allowed)
				(footprints allowed)
			)
			(placement
				(enabled no)
				(sheetname "")
			)
			(fill
				(thermal_gap 0.5)
				(thermal_bridge_width 0.5)
				(island_removal_mode 0)
			)
			(polygon
				(pts
					(xy 427.31436 -45.237654) (xy 427.82236 -45.237654) (xy 427.82236 -45.618654) (xy 427.31436 -45.618654)
				)
			)
		)
	)
	(footprint ""
		(layer "F.Cu")
		(at 468.112856 -25.762204 180)
		(property "Reference" "R8E35"
			(at 0 0 180)
			(layer "F.SilkS")
			(hide yes)
			(effects
				(font
					(size 1.27 1.27)
				)
			)
		)
		(property "Value" ""
			(at 0 0 180)
			(layer "F.Fab")
			(effects
				(font
					(size 1.27 1.27)
				)
			)
		)
		(duplicate_pad_numbers_are_jumpers no)
		(fp_rect
			(start 0.2794 -0.1016)
			(end -0.2794 0.9906)
			(stroke
				(width 0)
				(type default)
			)
			(fill no)
			(layer "F.CrtYd")
		)
		(fp_line
			(start 0.2794 0.9906)
			(end 0.2794 -0.1016)
			(stroke
				(width 0.1)
				(type default)
			)
			(layer "F.Fab")
		)
		(fp_line
			(start 0.2794 -0.1016)
			(end -0.2794 -0.1016)
			(stroke
				(width 0.1)
				(type default)
			)
			(layer "F.Fab")
		)
		(fp_line
			(start -0.2794 0.9906)
			(end 0.2794 0.9906)
			(stroke
				(width 0.1)
				(type default)
			)
			(layer "F.Fab")
		)
		(fp_line
			(start -0.2794 -0.1016)
			(end -0.2794 0.9906)
			(stroke
				(width 0.1)
				(type default)
			)
			(layer "F.Fab")
		)
		(pad "1" smd rect
			(at 0 0 180)
			(size 0.508 0.508)
			(layers "F.Cu" "F.Mask" "F.Paste")
			(net "VR_P3V3_STBY_BOOT")
		)
		(pad "2" smd rect
			(at 0 0.889 180)
			(size 0.508 0.508)
			(layers "F.Cu" "F.Mask" "F.Paste")
			(net "VR_P3V3_STBY_BOOT_R")
		)
		(zone
			(layer "F.Cu")
			(hatch none 0.5)
			(connect_pads
				(clearance 0)
			)
			(min_thickness 0.25)
			(keepout
				(tracks not_allowed)
				(vias allowed)
				(pads allowed)
				(copperpour not_allowed)
				(footprints allowed)
			)
			(placement
				(enabled no)
				(sheetname "")
			)
			(fill
				(thermal_gap 0.5)
				(thermal_bridge_width 0.5)
				(island_removal_mode 0)
			)
			(polygon
				(pts
					(xy 467.858856 -26.016204) (xy 468.366856 -26.016204) (xy 468.366856 -26.397204) (xy 467.858856 -26.397204)
				)
			)
		)
		(zone
			(layer "F.Cu")
			(hatch none 0.5)
			(connect_pads
				(clearance 0)
			)
			(min_thickness 0.25)
			(keepout
				(tracks allowed)
				(vias not_allowed)
				(pads allowed)
				(copperpour not_allowed)
				(footprints allowed)
			)
			(placement
				(enabled no)
				(sheetname "")
			)
			(fill
				(thermal_gap 0.5)
				(thermal_bridge_width 0.5)
				(island_removal_mode 0)
			)
			(polygon
				(pts
					(xy 467.858856 -26.016204) (xy 468.366856 -26.016204) (xy 468.366856 -26.397204) (xy 467.858856 -26.397204)
				)
			)
		)
	)
	(footprint ""
		(layer "F.Cu")
		(at 35.9664 -77.7494 -90)
		(property "Reference" "RT13"
			(at 0 0 270)
			(layer "F.SilkS")
			(hide yes)
			(effects
				(font
					(size 1.27 1.27)
				)
			)
		)
		(property "Value" "*"
			(at -0.0254 -2.6289 270)
			(unlocked yes)
			(layer "F.Fab")
			(hide yes)
			(effects
				(font
					(size 1.27 1.016)
					(thickness 0.1524)
				)
			)
		)
		(property "Device Type" "1R3F-GP_RCL_GP-1R3F-GP,64.1R00A"
			(at -0.0254 -4.1529 270)
			(unlocked yes)
			(layer "F.Fab")
			(hide yes)
			(effects
				(font
					(size 1.27 1.016)
					(thickness 0.1524)
				)
			)
		)
		(duplicate_pad_numbers_are_jumpers no)
		(fp_line
			(start -0.4826 0)
			(end -0.2032 0)
			(stroke
				(width 0.2032)
				(type default)
			)
			(layer "F.SilkS")
		)
		(fp_line
			(start 0.2032 0)
			(end 0.4826 0)
			(stroke
				(width 0.2032)
				(type default)
			)
			(layer "F.SilkS")
		)
		(fp_rect
			(start -0.5842 1.3335)
			(end 0.5842 -1.3335)
			(stroke
				(width 0)
				(type default)
			)
			(fill no)
			(layer "F.CrtYd")
		)
		(fp_rect
			(start -0.5842 1.3335)
			(end 0.5842 -1.3335)
			(stroke
				(width 0)
				(type default)
			)
			(fill no)
			(layer "F.Fab")
		)
		(pad "1" smd custom
			(at 0 -0.762 270)
			(size 0.2159 0.2159)
			(layers "F.Cu" "F.Mask" "F.Paste")
			(net "VR_PVCCIN_CPU1_PHASE4_RC")
			(options
				(clearance outline)
				(anchor circle)
			)
			(primitives
				(gr_poly
					(pts
						(arc
							(start -0.3302 -0.4318)
							(mid -0.402042 -0.402042)
							(end -0.4318 -0.3302)
						)
						(arc
							(start -0.4318 0.3302)
							(mid -0.402042 0.402042)
							(end -0.3302 0.4318)
						)
						(arc
							(start 0.3302 0.4318)
							(mid 0.402042 0.402042)
							(end 0.4318 0.3302)
						)
						(arc
							(start 0.4318 -0.3302)
							(mid 0.402042 -0.402042)
							(end 0.3302 -0.4318)
						)
					)
					(width 0)
					(fill yes)
				)
			)
		)
		(pad "2" smd custom
			(at 0 0.762 270)
			(size 0.2159 0.2159)
			(layers "F.Cu" "F.Mask" "F.Paste")
			(net "GND")
			(options
				(clearance outline)
				(anchor circle)
			)
			(primitives
				(gr_poly
					(pts
						(arc
							(start -0.3302 -0.4318)
							(mid -0.402042 -0.402042)
							(end -0.4318 -0.3302)
						)
						(arc
							(start -0.4318 0.3302)
							(mid -0.402042 0.402042)
							(end -0.3302 0.4318)
						)
						(arc
							(start 0.3302 0.4318)
							(mid 0.402042 0.402042)
							(end 0.4318 0.3302)
						)
						(arc
							(start 0.4318 -0.3302)
							(mid 0.402042 -0.402042)
							(end 0.3302 -0.4318)
						)
					)
					(width 0)
					(fill yes)
				)
			)
		)
	)
	(footprint ""
		(layer "F.Cu")
		(at 104.5591 -3.3528 90)
		(property "Reference" "C2G14"
			(at 1.848866 0.752348 90)
			(unlocked yes)
			(layer "F.SilkS")
			(effects
				(font
					(size 1.27 0.9652)
					(thickness 0.1524)
				)
			)
		)
		(property "Value" ""
			(at 0 0 90)
			(layer "F.Fab")
			(effects
				(font
					(size 1.27 1.27)
				)
			)
		)
		(duplicate_pad_numbers_are_jumpers no)
		(fp_rect
			(start -0.500126 1.598422)
			(end 0.500126 -0.201422)
			(stroke
				(width 0)
				(type default)
			)
			(fill no)
			(layer "F.CrtYd")
		)
		(fp_line
			(start 0.500126 -0.201422)
			(end 0.500126 1.598422)
			(stroke
				(width 0.1)
				(type default)
			)
			(layer "F.Fab")
		)
		(fp_line
			(start -0.500126 -0.201422)
			(end 0.500126 -0.201422)
			(stroke
				(width 0.1)
				(type default)
			)
			(layer "F.Fab")
		)
		(fp_line
			(start 0.500126 1.598422)
			(end -0.500126 1.598422)
			(stroke
				(width 0.1)
				(type default)
			)
			(layer "F.Fab")
		)
		(fp_line
			(start -0.500126 1.598422)
			(end -0.500126 -0.201422)
			(stroke
				(width 0.1)
				(type default)
			)
			(layer "F.Fab")
		)
		(pad "1" smd rect
			(at 0 0)
			(size 0.889 0.9906)
			(layers "F.Cu" "F.Mask" "F.Paste")
			(net "PVDDQ_GHJ")
		)
		(pad "2" smd rect
			(at 0 1.397)
			(size 0.889 0.9906)
			(layers "F.Cu" "F.Mask" "F.Paste")
			(net "GND")
		)
		(zone
			(layer "F.Cu")
			(hatch none 0.5)
			(connect_pads
				(clearance 0)
			)
			(min_thickness 0.25)
			(keepout
				(tracks allowed)
				(vias not_allowed)
				(pads allowed)
				(copperpour not_allowed)
				(footprints allowed)
			)
			(placement
				(enabled no)
				(sheetname "")
			)
			(fill
				(thermal_gap 0.5)
				(thermal_bridge_width 0.5)
				(island_removal_mode 0)
			)
			(polygon
				(pts
					(xy 105.5116 -2.8575) (xy 105.5116 -3.8481) (xy 105.0036 -3.8481) (xy 105.0036 -2.8575)
				)
			)
		)
		(zone
			(layer "F.Cu")
			(hatch none 0.5)
			(connect_pads
				(clearance 0)
			)
			(min_thickness 0.25)
			(keepout
				(tracks not_allowed)
				(vias allowed)
				(pads allowed)
				(copperpour not_allowed)
				(footprints allowed)
			)
			(placement
				(enabled no)
				(sheetname "")
			)
			(fill
				(thermal_gap 0.5)
				(thermal_bridge_width 0.5)
				(island_removal_mode 0)
			)
			(polygon
				(pts
					(xy 105.5116 -2.8575) (xy 105.5116 -3.8481) (xy 105.0036 -3.8481) (xy 105.0036 -2.8575)
				)
			)
		)
	)
	(footprint ""
		(layer "F.Cu")
		(at 363.7788 -133.9977)
		(property "Reference" "R7B1"
			(at 0 0 0)
			(layer "F.SilkS")
			(hide yes)
			(effects
				(font
					(size 1.27 1.27)
				)
			)
		)
		(property "Value" ""
			(at 0 0 0)
			(layer "F.Fab")
			(effects
				(font
					(size 1.27 1.27)
				)
			)
		)
		(duplicate_pad_numbers_are_jumpers no)
		(fp_poly
			(pts
				(xy -0.2794 -0.1016) (xy 0.2794 -0.1016) (xy 0.2794 0.9906) (xy -0.2794 0.9906)
			)
			(stroke
				(width 0)
				(type default)
			)
			(fill no)
			(layer "F.CrtYd")
		)
		(fp_line
			(start -0.2794 -0.1016)
			(end -0.2794 0.9906)
			(stroke
				(width 0.1)
				(type default)
			)
			(layer "F.Fab")
		)
		(fp_line
			(start -0.2794 0.9906)
			(end 0.2794 0.9906)
			(stroke
				(width 0.1)
				(type default)
			)
			(layer "F.Fab")
		)
		(fp_line
			(start 0.2794 -0.1016)
			(end -0.2794 -0.1016)
			(stroke
				(width 0.1)
				(type default)
			)
			(layer "F.Fab")
		)
		(fp_line
			(start 0.2794 0.9906)
			(end 0.2794 -0.1016)
			(stroke
				(width 0.1)
				(type default)
			)
			(layer "F.Fab")
		)
		(pad "1" smd rect
			(at 0 0)
			(size 0.508 0.508)
			(layers "F.Cu" "F.Mask" "F.Paste")
			(net "IRQ_PVDDQ_DEF_VRHOT_LVT3_R_N")
		)
		(pad "2" smd rect
			(at 0 0.889)
			(size 0.508 0.508)
			(layers "F.Cu" "F.Mask" "F.Paste")
			(net "IRQ_PVDDQ_DEF_VRHOT_LVT3_N")
		)
		(zone
			(layer "F.Cu")
			(hatch none 0.5)
			(connect_pads
				(clearance 0)
			)
			(min_thickness 0.25)
			(keepout
				(tracks allowed)
				(vias not_allowed)
				(pads allowed)
				(copperpour not_allowed)
				(footprints allowed)
			)
			(placement
				(enabled no)
				(sheetname "")
			)
			(fill
				(thermal_gap 0.5)
				(thermal_bridge_width 0.5)
				(island_removal_mode 0)
			)
			(polygon
				(pts
					(xy 363.5248 -133.7437) (xy 364.0328 -133.7437) (xy 364.0328 -133.3627) (xy 363.5248 -133.3627)
				)
			)
		)
		(zone
			(layer "F.Cu")
			(hatch none 0.5)
			(connect_pads
				(clearance 0)
			)
			(min_thickness 0.25)
			(keepout
				(tracks not_allowed)
				(vias allowed)
				(pads allowed)
				(copperpour not_allowed)
				(footprints allowed)
			)
			(placement
				(enabled no)
				(sheetname "")
			)
			(fill
				(thermal_gap 0.5)
				(thermal_bridge_width 0.5)
				(island_removal_mode 0)
			)
			(polygon
				(pts
					(xy 363.5248 -133.3627) (xy 364.0328 -133.3627) (xy 364.0328 -133.7437) (xy 363.5248 -133.7437)
				)
			)
		)
	)
	(footprint ""
		(layer "F.Cu")
		(at 478.0026 -22.4028)
		(property "Reference" "C8E11"
			(at 0 0 0)
			(layer "F.SilkS")
			(hide yes)
			(effects
				(font
					(size 1.27 1.27)
				)
			)
		)
		(property "Value" "*"
			(at -0.0762 -6.2357 0)
			(unlocked yes)
			(layer "F.Fab")
			(hide yes)
			(effects
				(font
					(size 1.27 1.016)
					(thickness 0.1524)
				)
			)
		)
		(property "Device Type" "SC22U16V5MX-4-GP_SMD-BCG5-SC22A"
			(at -0.0762 -8.2677 0)
			(unlocked yes)
			(layer "F.Fab")
			(hide yes)
			(effects
				(font
					(size 1.27 1.016)
					(thickness 0.1524)
				)
			)
		)
		(duplicate_pad_numbers_are_jumpers no)
		(fp_line
			(start 0.635 0)
			(end -0.635 0)
			(stroke
				(width 0.508)
				(type default)
			)
			(layer "F.SilkS")
		)
		(fp_rect
			(start -0.9652 1.778)
			(end 0.9652 -1.778)
			(stroke
				(width 0)
				(type default)
			)
			(fill no)
			(layer "F.CrtYd")
		)
		(fp_poly
			(pts
				(xy -0.9652 -1.778) (xy 0.9652 -1.778) (xy 0.9652 1.778) (xy -0.9652 1.778)
			)
			(stroke
				(width 0)
				(type default)
			)
			(fill no)
			(layer "F.Fab")
		)
		(pad "1" smd rect
			(at 0 -0.9652)
			(size 1.397 1.143)
			(layers "F.Cu" "F.Mask" "F.Paste")
			(net "VR_FET_SW_P12V_STBY_P3V3_STBY")
		)
		(pad "2" smd rect
			(at 0 0.9652)
			(size 1.397 1.143)
			(layers "F.Cu" "F.Mask" "F.Paste")
			(net "GND")
		)
	)
	(footprint ""
		(layer "F.Cu")
		(at 204.6224 -69.342 -90)
		(property "Reference" "CT38"
			(at -0.8382 -0.67818 270)
			(unlocked yes)
			(layer "F.SilkS")
			(effects
				(font
					(size 0.4064 0.254)
					(thickness 0.1524)
				)
				(justify left)
			)
		)
		(property "Value" ""
			(at 0 0 270)
			(layer "F.Fab")
			(effects
				(font
					(size 1.27 1.27)
				)
			)
		)
		(duplicate_pad_numbers_are_jumpers no)
		(fp_poly
			(pts
				(xy 0.3048 -0.1016) (xy 0.3048 0.9906) (xy -0.3048 0.9906) (xy -0.3048 -0.1016)
			)
			(stroke
				(width 0)
				(type default)
			)
			(fill no)
			(layer "F.CrtYd")
		)
		(fp_line
			(start -0.3048 0.9906)
			(end 0.3048 0.9906)
			(stroke
				(width 0.1)
				(type default)
			)
			(layer "F.Fab")
		)
		(fp_line
			(start 0.3048 0.9906)
			(end 0.3048 -0.1016)
			(stroke
				(width 0.1)
				(type default)
			)
			(layer "F.Fab")
		)
		(fp_line
			(start -0.3048 -0.1016)
			(end -0.3048 0.9906)
			(stroke
				(width 0.1)
				(type default)
			)
			(layer "F.Fab")
		)
		(fp_line
			(start 0.3048 -0.1016)
			(end -0.3048 -0.1016)
			(stroke
				(width 0.1)
				(type default)
			)
			(layer "F.Fab")
		)
		(pad "1" smd rect
			(at 0 0 270)
			(size 0.508 0.508)
			(layers "F.Cu" "F.Mask" "F.Paste")
			(net "VR_PVCCIN_CPU0_PHASE3")
		)
		(pad "2" smd rect
			(at 0 0.889 270)
			(size 0.508 0.508)
			(layers "F.Cu" "F.Mask" "F.Paste")
			(net "VR_PVCCIN_CPU0_PHASE3_RC")
		)
		(zone
			(layer "F.Cu")
			(hatch none 0.5)
			(connect_pads
				(clearance 0)
			)
			(min_thickness 0.25)
			(keepout
				(tracks not_allowed)
				(vias allowed)
				(pads allowed)
				(copperpour not_allowed)
				(footprints allowed)
			)
			(placement
				(enabled no)
				(sheetname "")
			)
			(fill
				(thermal_gap 0.5)
				(thermal_bridge_width 0.5)
				(island_removal_mode 0)
			)
			(polygon
				(pts
					(xy 203.9874 -69.596) (xy 203.9874 -69.088) (xy 204.3684 -69.088) (xy 204.3684 -69.596)
				)
			)
		)
		(zone
			(layer "F.Cu")
			(hatch none 0.5)
			(connect_pads
				(clearance 0)
			)
			(min_thickness 0.25)
			(keepout
				(tracks allowed)
				(vias not_allowed)
				(pads allowed)
				(copperpour not_allowed)
				(footprints allowed)
			)
			(placement
				(enabled no)
				(sheetname "")
			)
			(fill
				(thermal_gap 0.5)
				(thermal_bridge_width 0.5)
				(island_removal_mode 0)
			)
			(polygon
				(pts
					(xy 204.3684 -69.596) (xy 204.3684 -69.088) (xy 203.9874 -69.088) (xy 203.9874 -69.596)
				)
			)
		)
	)
	(footprint ""
		(layer "F.Cu")
		(at 40.60825 -103.491284 90)
		(property "Reference" "R1C5"
			(at 0 0 90)
			(layer "F.SilkS")
			(hide yes)
			(effects
				(font
					(size 1.27 1.27)
				)
			)
		)
		(property "Value" ""
			(at 0 0 90)
			(layer "F.Fab")
			(effects
				(font
					(size 1.27 1.27)
				)
			)
		)
		(duplicate_pad_numbers_are_jumpers no)
		(fp_poly
			(pts
				(xy -0.2794 -0.1016) (xy 0.2794 -0.1016) (xy 0.2794 0.9906) (xy -0.2794 0.9906)
			)
			(stroke
				(width 0)
				(type default)
			)
			(fill no)
			(layer "F.CrtYd")
		)
		(fp_line
			(start 0.2794 -0.1016)
			(end -0.2794 -0.1016)
			(stroke
				(width 0.1)
				(type default)
			)
			(layer "F.Fab")
		)
		(fp_line
			(start -0.2794 -0.1016)
			(end -0.2794 0.9906)
			(stroke
				(width 0.1)
				(type default)
			)
			(layer "F.Fab")
		)
		(fp_line
			(start 0.2794 0.9906)
			(end 0.2794 -0.1016)
			(stroke
				(width 0.1)
				(type default)
			)
			(layer "F.Fab")
		)
		(fp_line
			(start -0.2794 0.9906)
			(end 0.2794 0.9906)
			(stroke
				(width 0.1)
				(type default)
			)
			(layer "F.Fab")
		)
		(pad "1" smd rect
			(at 0 0 90)
			(size 0.508 0.508)
			(layers "F.Cu" "F.Mask" "F.Paste")
			(net "VSENSE_PVSA_CPU1_N")
		)
		(pad "2" smd rect
			(at 0 0.889 90)
			(size 0.508 0.508)
			(layers "F.Cu" "F.Mask" "F.Paste")
			(net "VSENSE_PVSA_CPU1_SKT_VRTN")
		)
		(zone
			(layer "F.Cu")
			(hatch none 0.5)
			(connect_pads
				(clearance 0)
			)
			(min_thickness 0.25)
			(keepout
				(tracks allowed)
				(vias not_allowed)
				(pads allowed)
				(copperpour not_allowed)
				(footprints allowed)
			)
			(placement
				(enabled no)
				(sheetname "")
			)
			(fill
				(thermal_gap 0.5)
				(thermal_bridge_width 0.5)
				(island_removal_mode 0)
			)
			(polygon
				(pts
					(xy 40.86225 -103.237284) (xy 40.86225 -103.745284) (xy 41.24325 -103.745284) (xy 41.24325 -103.237284)
				)
			)
		)
		(zone
			(layer "F.Cu")
			(hatch none 0.5)
			(connect_pads
				(clearance 0)
			)
			(min_thickness 0.25)
			(keepout
				(tracks not_allowed)
				(vias allowed)
				(pads allowed)
				(copperpour not_allowed)
				(footprints allowed)
			)
			(placement
				(enabled no)
				(sheetname "")
			)
			(fill
				(thermal_gap 0.5)
				(thermal_bridge_width 0.5)
				(island_removal_mode 0)
			)
			(polygon
				(pts
					(xy 41.24325 -103.237284) (xy 41.24325 -103.745284) (xy 40.86225 -103.745284) (xy 40.86225 -103.237284)
				)
			)
		)
	)
	(footprint ""
		(layer "F.Cu")
		(at 34.417 13.2715 -90)
		(property "Reference" "T1P36"
			(at 0 0 270)
			(layer "F.SilkS")
			(hide yes)
			(effects
				(font
					(size 1.27 1.27)
				)
			)
		)
		(property "Value" "*"
			(at 0 -3.44805 270)
			(unlocked yes)
			(layer "F.Fab")
			(hide yes)
			(effects
				(font
					(size 0.889 0.889)
					(thickness 0.1524)
				)
			)
		)
		(property "Device Type" "TPAD-SE-2P-GP_DISCRET-GA1-TPADA"
			(at 0 -4.97205 270)
			(unlocked yes)
			(layer "F.Fab")
			(hide yes)
			(effects
				(font
					(size 0.889 0.889)
					(thickness 0.1524)
				)
			)
		)
		(duplicate_pad_numbers_are_jumpers no)
		(fp_line
			(start -1.016 2.286)
			(end -1.016 -2.286)
			(stroke
				(width 0.1524)
				(type default)
			)
			(layer "F.SilkS")
		)
		(fp_line
			(start 1.016 2.286)
			(end -1.016 2.286)
			(stroke
				(width 0.1524)
				(type default)
			)
			(layer "F.SilkS")
		)
		(fp_line
			(start -1.016 -2.286)
			(end 1.016 -2.286)
			(stroke
				(width 0.1524)
				(type default)
			)
			(layer "F.SilkS")
		)
		(fp_line
			(start 1.016 -2.286)
			(end 1.016 2.286)
			(stroke
				(width 0.1524)
				(type default)
			)
			(layer "F.SilkS")
		)
		(fp_rect
			(start -1.27 2.54)
			(end 1.27 -2.54)
			(stroke
				(width 0)
				(type default)
			)
			(fill no)
			(layer "F.CrtYd")
		)
		(fp_rect
			(start -1.27 2.54)
			(end 1.27 -2.54)
			(stroke
				(width 0)
				(type default)
			)
			(fill no)
			(layer "F.Fab")
		)
		(pad "1" thru_hole circle
			(at 0 -1.27 270)
			(size 1.524 1.524)
			(drill 0.9144)
			(layers "*.Cu" "*.Mask")
			(remove_unused_layers no)
			(net "L14_50OHM_6INCH")
			(clearance -0.0508)
			(thermal_gap 0.127)
			(padstack
				(mode front_inner_back)
				(layer "Inner"
					(shape circle)
					(size 1.1684 1.1684)
					(clearance 0.127)
				)
				(layer "B.Cu"
					(shape circle)
					(size 1.524 1.524)
					(clearance -0.0508)
				)
			)
		)
		(pad "GND1" thru_hole rect
			(at 0 1.27 270)
			(size 1.524 1.524)
			(drill 0.9144)
			(layers "*.Cu" "*.Mask")
			(remove_unused_layers no)
			(net "GND")
			(clearance -0.0508)
			(thermal_gap 0.127)
			(padstack
				(mode front_inner_back)
				(layer "Inner"
					(shape circle)
					(size 1.1684 1.1684)
					(clearance 0.127)
				)
				(layer "B.Cu"
					(shape rect)
					(size 1.524 1.524)
					(clearance -0.0508)
				)
			)
		)
	)
	(footprint ""
		(layer "F.Cu")
		(at 116.2812 -74.5998 90)
		(property "Reference" "R3D31"
			(at 0 0 90)
			(layer "F.SilkS")
			(hide yes)
			(effects
				(font
					(size 1.27 1.27)
				)
			)
		)
		(property "Value" ""
			(at 0 0 90)
			(layer "F.Fab")
			(effects
				(font
					(size 1.27 1.27)
				)
			)
		)
		(duplicate_pad_numbers_are_jumpers no)
		(fp_poly
			(pts
				(xy -0.2794 -0.1016) (xy 0.2794 -0.1016) (xy 0.2794 0.9906) (xy -0.2794 0.9906)
			)
			(stroke
				(width 0)
				(type default)
			)
			(fill no)
			(layer "F.CrtYd")
		)
		(fp_line
			(start 0.2794 -0.1016)
			(end -0.2794 -0.1016)
			(stroke
				(width 0.1)
				(type default)
			)
			(layer "F.Fab")
		)
		(fp_line
			(start -0.2794 -0.1016)
			(end -0.2794 0.9906)
			(stroke
				(width 0.1)
				(type default)
			)
			(layer "F.Fab")
		)
		(fp_line
			(start 0.2794 0.9906)
			(end 0.2794 -0.1016)
			(stroke
				(width 0.1)
				(type default)
			)
			(layer "F.Fab")
		)
		(fp_line
			(start -0.2794 0.9906)
			(end 0.2794 0.9906)
			(stroke
				(width 0.1)
				(type default)
			)
			(layer "F.Fab")
		)
		(pad "1" smd rect
			(at 0 0 90)
			(size 0.508 0.508)
			(layers "F.Cu" "F.Mask" "F.Paste")
			(net "FM_CPU_BMC_INIT")
		)
		(pad "2" smd rect
			(at 0 0.889 90)
			(size 0.508 0.508)
			(layers "F.Cu" "F.Mask" "F.Paste")
			(net "H_CPU1_BMCINIT")
		)
		(zone
			(layer "F.Cu")
			(hatch none 0.5)
			(connect_pads
				(clearance 0)
			)
			(min_thickness 0.25)
			(keepout
				(tracks allowed)
				(vias not_allowed)
				(pads allowed)
				(copperpour not_allowed)
				(footprints allowed)
			)
			(placement
				(enabled no)
				(sheetname "")
			)
			(fill
				(thermal_gap 0.5)
				(thermal_bridge_width 0.5)
				(island_removal_mode 0)
			)
			(polygon
				(pts
					(xy 116.5352 -74.3458) (xy 116.5352 -74.8538) (xy 116.9162 -74.8538) (xy 116.9162 -74.3458)
				)
			)
		)
		(zone
			(layer "F.Cu")
			(hatch none 0.5)
			(connect_pads
				(clearance 0)
			)
			(min_thickness 0.25)
			(keepout
				(tracks not_allowed)
				(vias allowed)
				(pads allowed)
				(copperpour not_allowed)
				(footprints allowed)
			)
			(placement
				(enabled no)
				(sheetname "")
			)
			(fill
				(thermal_gap 0.5)
				(thermal_bridge_width 0.5)
				(island_removal_mode 0)
			)
			(polygon
				(pts
					(xy 116.9162 -74.3458) (xy 116.9162 -74.8538) (xy 116.5352 -74.8538) (xy 116.5352 -74.3458)
				)
			)
		)
	)
	(footprint ""
		(layer "F.Cu")
		(at 281.178 -72.263 90)
		(property "Reference" "R6D10"
			(at 0 0 90)
			(layer "F.SilkS")
			(hide yes)
			(effects
				(font
					(size 1.27 1.27)
				)
			)
		)
		(property "Value" ""
			(at 0 0 90)
			(layer "F.Fab")
			(effects
				(font
					(size 1.27 1.27)
				)
			)
		)
		(duplicate_pad_numbers_are_jumpers no)
		(fp_rect
			(start -0.2794 -0.1016)
			(end 0.2794 0.9906)
			(stroke
				(width 0)
				(type default)
			)
			(fill no)
			(layer "F.CrtYd")
		)
		(fp_line
			(start 0.2794 -0.1016)
			(end -0.2794 -0.1016)
			(stroke
				(width 0.1)
				(type default)
			)
			(layer "F.Fab")
		)
		(fp_line
			(start -0.2794 -0.1016)
			(end -0.2794 0.9906)
			(stroke
				(width 0.1)
				(type default)
			)
			(layer "F.Fab")
		)
		(fp_line
			(start 0.2794 0.9906)
			(end 0.2794 -0.1016)
			(stroke
				(width 0.1)
				(type default)
			)
			(layer "F.Fab")
		)
		(fp_line
			(start -0.2794 0.9906)
			(end 0.2794 0.9906)
			(stroke
				(width 0.1)
				(type default)
			)
			(layer "F.Fab")
		)
		(pad "1" smd rect
			(at 0 0 90)
			(size 0.508 0.508)
			(layers "F.Cu" "F.Mask" "F.Paste")
			(net "PVCCIO_CPU0")
		)
		(pad "2" smd rect
			(at 0 0.889 90)
			(size 0.508 0.508)
			(layers "F.Cu" "F.Mask" "F.Paste")
			(net "PU_CPU0_SOCKET_ID_1")
		)
		(zone
			(layer "F.Cu")
			(hatch none 0.5)
			(connect_pads
				(clearance 0)
			)
			(min_thickness 0.25)
			(keepout
				(tracks not_allowed)
				(vias allowed)
				(pads allowed)
				(copperpour not_allowed)
				(footprints allowed)
			)
			(placement
				(enabled no)
				(sheetname "")
			)
			(fill
				(thermal_gap 0.5)
				(thermal_bridge_width 0.5)
				(island_removal_mode 0)
			)
			(polygon
				(pts
					(xy 281.432 -72.009) (xy 281.813 -72.009) (xy 281.813 -72.517) (xy 281.432 -72.517)
				)
			)
		)
		(zone
			(layer "F.Cu")
			(hatch none 0.5)
			(connect_pads
				(clearance 0)
			)
			(min_thickness 0.25)
			(keepout
				(tracks allowed)
				(vias not_allowed)
				(pads allowed)
				(copperpour not_allowed)
				(footprints allowed)
			)
			(placement
				(enabled no)
				(sheetname "")
			)
			(fill
				(thermal_gap 0.5)
				(thermal_bridge_width 0.5)
				(island_removal_mode 0)
			)
			(polygon
				(pts
					(xy 281.432 -72.009) (xy 281.813 -72.009) (xy 281.813 -72.517) (xy 281.432 -72.517)
				)
			)
		)
	)
	(footprint ""
		(layer "F.Cu")
		(at 340.872064 -5.746496 180)
		(property "Reference" "L7G1"
			(at 3.378708 -4.251706 180)
			(unlocked yes)
			(layer "F.SilkS")
			(effects
				(font
					(size 0.4064 0.254)
					(thickness 0.1524)
				)
			)
		)
		(property "Value" ""
			(at 0 0 180)
			(layer "F.Fab")
			(effects
				(font
					(size 1.27 1.27)
				)
			)
		)
		(duplicate_pad_numbers_are_jumpers no)
		(fp_line
			(start 8.3693 3.199892)
			(end -1.1303 3.199892)
			(stroke
				(width 0.1524)
				(type default)
			)
			(layer "F.SilkS")
		)
		(fp_line
			(start 8.3693 1.6637)
			(end 8.3693 3.199892)
			(stroke
				(width 0.1524)
				(type default)
			)
			(layer "F.SilkS")
		)
		(fp_line
			(start 8.3693 -3.199892)
			(end 8.3693 -1.6637)
			(stroke
				(width 0.1524)
				(type default)
			)
			(layer "F.SilkS")
		)
		(fp_line
			(start -1.1303 3.199892)
			(end -1.1303 1.6637)
			(stroke
				(width 0.1524)
				(type default)
			)
			(layer "F.SilkS")
		)
		(fp_line
			(start -1.1303 -1.6637)
			(end -1.1303 -3.199892)
			(stroke
				(width 0.1524)
				(type default)
			)
			(layer "F.SilkS")
		)
		(fp_line
			(start -1.1303 -3.199892)
			(end 8.3693 -3.199892)
			(stroke
				(width 0.1524)
				(type default)
			)
			(layer "F.SilkS")
		)
		(fp_rect
			(start -1.1303 3.199892)
			(end 8.3693 -3.199892)
			(stroke
				(width 0)
				(type default)
			)
			(fill no)
			(layer "F.CrtYd")
		)
		(fp_line
			(start 8.3693 3.199892)
			(end -1.1303 3.199892)
			(stroke
				(width 0.1)
				(type default)
			)
			(layer "F.Fab")
		)
		(fp_line
			(start 8.3693 -3.199892)
			(end 8.3693 3.199892)
			(stroke
				(width 0.1)
				(type default)
			)
			(layer "F.Fab")
		)
		(fp_line
			(start -1.1303 3.199892)
			(end -1.1303 -3.199892)
			(stroke
				(width 0.1)
				(type default)
			)
			(layer "F.Fab")
		)
		(fp_line
			(start -1.1303 -3.199892)
			(end 8.3693 -3.199892)
			(stroke
				(width 0.1)
				(type default)
			)
			(layer "F.Fab")
		)
		(pad "1" smd rect
			(at 0 0 180)
			(size 3.683 2.667)
			(layers "F.Cu" "F.Mask" "F.Paste")
			(net "VR_PVDDQ_ABC_PH1_SW")
		)
		(pad "2" smd rect
			(at 7.239 0 180)
			(size 3.683 2.667)
			(layers "F.Cu" "F.Mask" "F.Paste")
			(net "PVDDQ_ABC")
		)
	)
	(footprint ""
		(layer "F.Cu")
		(at 489.204 -137.16 90)
		(property "Reference" "Q9A3"
			(at -0.88265 0.0254 0)
			(unlocked yes)
			(layer "F.SilkS")
			(effects
				(font
					(size 0.7874 0.5842)
					(thickness 0.1524)
				)
				(justify left)
			)
		)
		(property "Value" ""
			(at 0 0 90)
			(layer "F.Fab")
			(effects
				(font
					(size 1.27 1.27)
				)
			)
		)
		(duplicate_pad_numbers_are_jumpers no)
		(fp_line
			(start 1.778 -0.5715)
			(end 1.778 0.3175)
			(stroke
				(width 0.1524)
				(type default)
			)
			(layer "F.SilkS")
		)
		(fp_line
			(start 0.9525 -0.5715)
			(end 1.778 -0.5715)
			(stroke
				(width 0.1524)
				(type default)
			)
			(layer "F.SilkS")
		)
		(fp_line
			(start 0.381 0.635)
			(end 0.381 1.27)
			(stroke
				(width 0.1524)
				(type default)
			)
			(layer "F.SilkS")
		)
		(fp_line
			(start 1.778 2.4765)
			(end 1.778 1.5875)
			(stroke
				(width 0.1524)
				(type default)
			)
			(layer "F.SilkS")
		)
		(fp_line
			(start 0.9525 2.4765)
			(end 1.778 2.4765)
			(stroke
				(width 0.1524)
				(type default)
			)
			(layer "F.SilkS")
		)
		(fp_circle
			(center -0.9525 -0.9271)
			(end -0.9525 -0.8001)
			(stroke
				(width 0.254)
				(type default)
			)
			(fill no)
			(layer "F.SilkS")
		)
		(fp_poly
			(pts
				(xy 1.778 2.4765) (xy 0.381 2.4765) (xy 0.381 -0.5715) (xy 1.778 -0.5715)
			)
			(stroke
				(width 0)
				(type default)
			)
			(fill no)
			(layer "F.CrtYd")
		)
		(fp_line
			(start 1.778 -0.5715)
			(end 0.381 -0.5715)
			(stroke
				(width 0.1)
				(type default)
			)
			(layer "F.Fab")
		)
		(fp_line
			(start 0.381 -0.5715)
			(end 0.381 2.4765)
			(stroke
				(width 0.1)
				(type default)
			)
			(layer "F.Fab")
		)
		(fp_line
			(start 1.778 2.4765)
			(end 1.778 -0.5715)
			(stroke
				(width 0.1)
				(type default)
			)
			(layer "F.Fab")
		)
		(fp_line
			(start 0.381 2.4765)
			(end 1.778 2.4765)
			(stroke
				(width 0.1)
				(type default)
			)
			(layer "F.Fab")
		)
		(fp_circle
			(center -0.9525 -0.9271)
			(end -0.9525 -0.8001)
			(stroke
				(width 0.254)
				(type default)
			)
			(fill no)
			(layer "F.Fab")
		)
		(pad "1" smd rect
			(at 0 0 90)
			(size 1.143 0.508)
			(layers "F.Cu" "F.Mask" "F.Paste")
			(net "FM_BIOS_TOP_SWAP_SPKR")
		)
		(pad "2" smd rect
			(at 0 1.905 90)
			(size 1.143 0.508)
			(layers "F.Cu" "F.Mask" "F.Paste")
			(net "GND")
		)
		(pad "3" smd rect
			(at 2.159 0.9525 90)
			(size 1.143 0.508)
			(layers "F.Cu" "F.Mask" "F.Paste")
			(net "FM_SPEAKER_PCH_N")
		)
	)
	(footprint ""
		(layer "F.Cu")
		(at 32.289496 -77.351382 -90)
		(property "Reference" "C1D7"
			(at 0 0 270)
			(layer "F.SilkS")
			(hide yes)
			(effects
				(font
					(size 1.27 1.27)
				)
			)
		)
		(property "Value" ""
			(at 0 0 270)
			(layer "F.Fab")
			(effects
				(font
					(size 1.27 1.27)
				)
			)
		)
		(duplicate_pad_numbers_are_jumpers no)
		(fp_rect
			(start 0.3048 0.9906)
			(end -0.3048 -0.1016)
			(stroke
				(width 0)
				(type default)
			)
			(fill no)
			(layer "F.CrtYd")
		)
		(fp_line
			(start -0.3048 0.9906)
			(end 0.3048 0.9906)
			(stroke
				(width 0.1)
				(type default)
			)
			(layer "F.Fab")
		)
		(fp_line
			(start 0.3048 0.9906)
			(end 0.3048 -0.1016)
			(stroke
				(width 0.1)
				(type default)
			)
			(layer "F.Fab")
		)
		(fp_line
			(start -0.3048 -0.1016)
			(end -0.3048 0.9906)
			(stroke
				(width 0.1)
				(type default)
			)
			(layer "F.Fab")
		)
		(fp_line
			(start 0.3048 -0.1016)
			(end -0.3048 -0.1016)
			(stroke
				(width 0.1)
				(type default)
			)
			(layer "F.Fab")
		)
		(pad "1" smd rect
			(at 0 0 270)
			(size 0.508 0.508)
			(layers "F.Cu" "F.Mask" "F.Paste")
			(net "VR_PVCCIN_CPU1_PH4_VCIN")
		)
		(pad "2" smd rect
			(at 0 0.889 270)
			(size 0.508 0.508)
			(layers "F.Cu" "F.Mask" "F.Paste")
			(net "GND")
		)
		(zone
			(layer "F.Cu")
			(hatch none 0.5)
			(connect_pads
				(clearance 0)
			)
			(min_thickness 0.25)
			(keepout
				(tracks not_allowed)
				(vias allowed)
				(pads allowed)
				(copperpour not_allowed)
				(footprints allowed)
			)
			(placement
				(enabled no)
				(sheetname "")
			)
			(fill
				(thermal_gap 0.5)
				(thermal_bridge_width 0.5)
				(island_removal_mode 0)
			)
			(polygon
				(pts
					(xy 31.654496 -77.097382) (xy 32.035496 -77.097382) (xy 32.035496 -77.605382) (xy 31.654496 -77.605382)
				)
			)
		)
		(zone
			(layer "F.Cu")
			(hatch none 0.5)
			(connect_pads
				(clearance 0)
			)
			(min_thickness 0.25)
			(keepout
				(tracks allowed)
				(vias not_allowed)
				(pads allowed)
				(copperpour not_allowed)
				(footprints allowed)
			)
			(placement
				(enabled no)
				(sheetname "")
			)
			(fill
				(thermal_gap 0.5)
				(thermal_bridge_width 0.5)
				(island_removal_mode 0)
			)
			(polygon
				(pts
					(xy 31.654496 -77.097382) (xy 32.035496 -77.097382) (xy 32.035496 -77.605382) (xy 31.654496 -77.605382)
				)
			)
		)
	)
	(footprint ""
		(layer "F.Cu")
		(at 439.456322 -151.064468 180)
		(property "Reference" "U25W12"
			(at -1.743964 -3.834638 180)
			(unlocked yes)
			(layer "F.SilkS")
			(effects
				(font
					(size 3.048 1.524)
					(thickness 0.000001)
				)
				(justify left)
			)
		)
		(property "Value" ""
			(at 0 0 180)
			(layer "F.Fab")
			(effects
				(font
					(size 1.27 1.27)
				)
			)
		)
		(duplicate_pad_numbers_are_jumpers no)
		(fp_circle
			(center -2.347468 -1.283462)
			(end -2.474468 -1.283462)
			(stroke
				(width 0.254)
				(type default)
			)
			(fill no)
			(layer "F.SilkS")
		)
		(fp_rect
			(start -0.9144 0.9144)
			(end 0.9144 -0.9144)
			(stroke
				(width 0)
				(type default)
			)
			(fill yes)
			(layer "F.Paste")
		)
		(fp_rect
			(start -1.82499 1.82499)
			(end 1.82499 -1.82499)
			(stroke
				(width 0)
				(type default)
			)
			(fill no)
			(layer "F.CrtYd")
		)
		(fp_line
			(start 1.82499 1.82499)
			(end -1.82499 1.82499)
			(stroke
				(width 0.1)
				(type default)
			)
			(layer "F.Fab")
		)
		(fp_line
			(start 1.82499 -1.82499)
			(end 1.82499 1.82499)
			(stroke
				(width 0.1)
				(type default)
			)
			(layer "F.Fab")
		)
		(fp_line
			(start -1.82499 1.82499)
			(end -1.82499 -1.82499)
			(stroke
				(width 0.1)
				(type default)
			)
			(layer "F.Fab")
		)
		(fp_line
			(start -1.82499 -1.82499)
			(end 1.82499 -1.82499)
			(stroke
				(width 0.1)
				(type default)
			)
			(layer "F.Fab")
		)
		(fp_circle
			(center -1.17856 -2.466086)
			(end -1.30556 -2.466086)
			(stroke
				(width 0.254)
				(type default)
			)
			(fill no)
			(layer "F.Fab")
		)
		(pad "1" smd custom
			(at -0.750062 -1.549908 180)
			(size 0.0762 0.0762)
			(layers "F.Cu" "F.Mask" "F.Paste")
			(net "BMC_JTAG_SEL_BUF")
			(options
				(clearance outline)
				(anchor circle)
			)
			(primitives
				(gr_poly
					(pts
						(xy 0.1524 -0.381)
						(arc
							(start 0.1524 0.2286)
							(mid 0 0.381)
							(end -0.1524 0.2286)
						)
						(xy -0.1524 -0.381)
					)
					(width 0)
					(fill yes)
				)
			)
		)
		(pad "2" smd custom
			(at -1.549908 -0.999998 180)
			(size 0.0762 0.0762)
			(layers "F.Cu" "F.Mask" "F.Paste")
			(net "BMC_PREQ_N")
			(options
				(clearance outline)
				(anchor circle)
			)
			(primitives
				(gr_poly
					(pts
						(xy -0.381 -0.1524)
						(arc
							(start 0.2286 -0.1524)
							(mid 0.381 0)
							(end 0.2286 0.1524)
						)
						(xy -0.381 0.1524)
					)
					(width 0)
					(fill yes)
				)
			)
		)
		(pad "3" smd custom
			(at -1.549908 -0.500126 180)
			(size 0.0762 0.0762)
			(layers "F.Cu" "F.Mask" "F.Paste")
			(net "BMC_PREQ_BUF_N")
			(options
				(clearance outline)
				(anchor circle)
			)
			(primitives
				(gr_poly
					(pts
						(xy -0.381 -0.1524)
						(arc
							(start 0.2286 -0.1524)
							(mid 0.381 0)
							(end 0.2286 0.1524)
						)
						(xy -0.381 0.1524)
					)
					(width 0)
					(fill yes)
				)
			)
		)
		(pad "4" smd custom
			(at -1.549908 0 180)
			(size 0.0762 0.0762)
			(layers "F.Cu" "F.Mask" "F.Paste")
			(net "JTAG_BMC_TCK0")
			(options
				(clearance outline)
				(anchor circle)
			)
			(primitives
				(gr_poly
					(pts
						(xy -0.381 -0.1524)
						(arc
							(start 0.2286 -0.1524)
							(mid 0.381 0)
							(end 0.2286 0.1524)
						)
						(xy -0.381 0.1524)
					)
					(width 0)
					(fill yes)
				)
			)
		)
		(pad "5" smd custom
			(at -1.549908 0.500126 180)
			(size 0.0762 0.0762)
			(layers "F.Cu" "F.Mask" "F.Paste")
			(net "P1V05_PCH_STBY")
			(options
				(clearance outline)
				(anchor circle)
			)
			(primitives
				(gr_poly
					(pts
						(xy -0.381 -0.1524)
						(arc
							(start 0.2286 -0.1524)
							(mid 0.381 0)
							(end 0.2286 0.1524)
						)
						(xy -0.381 0.1524)
					)
					(width 0)
					(fill yes)
				)
			)
		)
		(pad "6" smd custom
			(at -1.549908 0.999998 180)
			(size 0.0762 0.0762)
			(layers "F.Cu" "F.Mask" "F.Paste")
			(net "XDP_CPU_TCK0_R")
			(options
				(clearance outline)
				(anchor circle)
			)
			(primitives
				(gr_poly
					(pts
						(xy -0.381 -0.1524)
						(arc
							(start 0.2286 -0.1524)
							(mid 0.381 0)
							(end 0.2286 0.1524)
						)
						(xy -0.381 0.1524)
					)
					(width 0)
					(fill yes)
				)
			)
		)
		(pad "7" smd custom
			(at -0.750062 1.549908 180)
			(size 0.0762 0.0762)
			(layers "F.Cu" "F.Mask" "F.Paste")
			(net "GND")
			(options
				(clearance outline)
				(anchor circle)
			)
			(primitives
				(gr_poly
					(pts
						(xy -0.1524 0.381)
						(arc
							(start -0.1524 -0.2286)
							(mid 0 -0.381)
							(end 0.1524 -0.2286)
						)
						(xy 0.1524 0.381)
					)
					(width 0)
					(fill yes)
				)
			)
		)
		(pad "8" smd custom
			(at 0.769874 1.549908 180)
			(size 0.0762 0.0762)
			(layers "F.Cu" "F.Mask" "F.Paste")
			(net "XDP_PCH_TCK1_R")
			(options
				(clearance outline)
				(anchor circle)
			)
			(primitives
				(gr_poly
					(pts
						(xy -0.1524 0.381)
						(arc
							(start -0.1524 -0.2286)
							(mid 0 -0.381)
							(end 0.1524 -0.2286)
						)
						(xy 0.1524 0.381)
					)
					(width 0)
					(fill yes)
				)
			)
		)
		(pad "9" smd custom
			(at 1.549908 0.999998 180)
			(size 0.0762 0.0762)
			(layers "F.Cu" "F.Mask" "F.Paste")
			(net "P1V05_PCH_STBY")
			(options
				(clearance outline)
				(anchor circle)
			)
			(primitives
				(gr_poly
					(pts
						(xy 0.381 0.1524)
						(arc
							(start -0.2286 0.1524)
							(mid -0.381 0)
							(end -0.2286 -0.1524)
						)
						(xy 0.381 -0.1524)
					)
					(width 0)
					(fill yes)
				)
			)
		)
		(pad "10" smd custom
			(at 1.549908 0.500126 180)
			(size 0.0762 0.0762)
			(layers "F.Cu" "F.Mask" "F.Paste")
			(net "JTAG_BMC_TCK1")
			(options
				(clearance outline)
				(anchor circle)
			)
			(primitives
				(gr_poly
					(pts
						(xy 0.381 0.1524)
						(arc
							(start -0.2286 0.1524)
							(mid -0.381 0)
							(end -0.2286 -0.1524)
						)
						(xy 0.381 -0.1524)
					)
					(width 0)
					(fill yes)
				)
			)
		)
		(pad "11" smd custom
			(at 1.549908 0 180)
			(size 0.0762 0.0762)
			(layers "F.Cu" "F.Mask" "F.Paste")
			(net "XDP_TRST_R_N")
			(options
				(clearance outline)
				(anchor circle)
			)
			(primitives
				(gr_poly
					(pts
						(xy 0.381 0.1524)
						(arc
							(start -0.2286 0.1524)
							(mid -0.381 0)
							(end -0.2286 -0.1524)
						)
						(xy 0.381 -0.1524)
					)
					(width 0)
					(fill yes)
				)
			)
		)
		(pad "12" smd custom
			(at 1.549908 -0.500126 180)
			(size 0.0762 0.0762)
			(layers "F.Cu" "F.Mask" "F.Paste")
			(net "P1V05_PCH_STBY")
			(options
				(clearance outline)
				(anchor circle)
			)
			(primitives
				(gr_poly
					(pts
						(xy 0.381 0.1524)
						(arc
							(start -0.2286 0.1524)
							(mid -0.381 0)
							(end -0.2286 -0.1524)
						)
						(xy 0.381 -0.1524)
					)
					(width 0)
					(fill yes)
				)
			)
		)
		(pad "13" smd custom
			(at 1.549908 -0.999998 180)
			(size 0.0762 0.0762)
			(layers "F.Cu" "F.Mask" "F.Paste")
			(net "JTAG_BMC_TRST_BUF_N")
			(options
				(clearance outline)
				(anchor circle)
			)
			(primitives
				(gr_poly
					(pts
						(xy 0.381 0.1524)
						(arc
							(start -0.2286 0.1524)
							(mid -0.381 0)
							(end -0.2286 -0.1524)
						)
						(xy 0.381 -0.1524)
					)
					(width 0)
					(fill yes)
				)
			)
		)
		(pad "14" smd custom
			(at 0.750062 -1.549908 180)
			(size 0.0762 0.0762)
			(layers "F.Cu" "F.Mask" "F.Paste")
			(net "P3V3_STBY")
			(options
				(clearance outline)
				(anchor circle)
			)
			(primitives
				(gr_poly
					(pts
						(xy 0.1524 -0.381)
						(arc
							(start 0.1524 0.2286)
							(mid 0 0.381)
							(end -0.1524 0.2286)
						)
						(xy -0.1524 -0.381)
					)
					(width 0)
					(fill yes)
				)
			)
		)
		(pad "15" smd rect
			(at 0 0 180)
			(size 1.8288 1.8288)
			(layers "F.Cu" "F.Mask" "F.Paste")
			(net "GND")
		)
	)
	(footprint ""
		(layer "F.Cu")
		(at 153.4922 -140.0048 -90)
		(property "Reference" "C3A7"
			(at 0 0 270)
			(layer "F.SilkS")
			(hide yes)
			(effects
				(font
					(size 1.27 1.27)
				)
			)
		)
		(property "Value" ""
			(at 0 0 270)
			(layer "F.Fab")
			(effects
				(font
					(size 1.27 1.27)
				)
			)
		)
		(duplicate_pad_numbers_are_jumpers no)
		(fp_rect
			(start -0.4953 1.6002)
			(end 0.4953 -0.2032)
			(stroke
				(width 0)
				(type default)
			)
			(fill no)
			(layer "F.CrtYd")
		)
		(fp_line
			(start -0.4953 1.6002)
			(end -0.4953 -0.2032)
			(stroke
				(width 0.1)
				(type default)
			)
			(layer "F.Fab")
		)
		(fp_line
			(start 0.4953 1.6002)
			(end -0.4953 1.6002)
			(stroke
				(width 0.1)
				(type default)
			)
			(layer "F.Fab")
		)
		(fp_line
			(start -0.4953 -0.2032)
			(end 0.4953 -0.2032)
			(stroke
				(width 0.1)
				(type default)
			)
			(layer "F.Fab")
		)
		(fp_line
			(start 0.4953 -0.2032)
			(end 0.4953 1.6002)
			(stroke
				(width 0.1)
				(type default)
			)
			(layer "F.Fab")
		)
		(pad "1" smd rect
			(at 0 0 270)
			(size 0.762 0.889)
			(layers "F.Cu" "F.Mask" "F.Paste")
			(net "PVPP_KLM")
		)
		(pad "2" smd rect
			(at 0 1.397 270)
			(size 0.762 0.889)
			(layers "F.Cu" "F.Mask" "F.Paste")
			(net "GND")
		)
		(zone
			(layer "F.Cu")
			(hatch none 0.5)
			(connect_pads
				(clearance 0)
			)
			(min_thickness 0.25)
			(keepout
				(tracks not_allowed)
				(vias allowed)
				(pads allowed)
				(copperpour not_allowed)
				(footprints allowed)
			)
			(placement
				(enabled no)
				(sheetname "")
			)
			(fill
				(thermal_gap 0.5)
				(thermal_bridge_width 0.5)
				(island_removal_mode 0)
			)
			(polygon
				(pts
					(xy 152.5397 -140.3858) (xy 152.5397 -139.6238) (xy 153.0477 -139.6238) (xy 153.0477 -140.3858)
				)
			)
		)
	)
	(footprint ""
		(layer "F.Cu")
		(at 12.446 -102.0064)
		(property "Reference" "R1C31"
			(at 0 0 0)
			(layer "F.SilkS")
			(hide yes)
			(effects
				(font
					(size 1.27 1.27)
				)
			)
		)
		(property "Value" ""
			(at 0 0 0)
			(layer "F.Fab")
			(effects
				(font
					(size 1.27 1.27)
				)
			)
		)
		(duplicate_pad_numbers_are_jumpers no)
		(fp_poly
			(pts
				(xy -0.2794 -0.1016) (xy 0.2794 -0.1016) (xy 0.2794 0.9906) (xy -0.2794 0.9906)
			)
			(stroke
				(width 0)
				(type default)
			)
			(fill no)
			(layer "F.CrtYd")
		)
		(fp_line
			(start -0.2794 -0.1016)
			(end -0.2794 0.9906)
			(stroke
				(width 0.1)
				(type default)
			)
			(layer "F.Fab")
		)
		(fp_line
			(start -0.2794 0.9906)
			(end 0.2794 0.9906)
			(stroke
				(width 0.1)
				(type default)
			)
			(layer "F.Fab")
		)
		(fp_line
			(start 0.2794 -0.1016)
			(end -0.2794 -0.1016)
			(stroke
				(width 0.1)
				(type default)
			)
			(layer "F.Fab")
		)
		(fp_line
			(start 0.2794 0.9906)
			(end 0.2794 -0.1016)
			(stroke
				(width 0.1)
				(type default)
			)
			(layer "F.Fab")
		)
		(pad "1" smd rect
			(at 0 0)
			(size 0.508 0.508)
			(layers "F.Cu" "F.Mask" "F.Paste")
			(net "FM_XRC_READY_N")
		)
		(pad "2" smd rect
			(at 0 0.889)
			(size 0.508 0.508)
			(layers "F.Cu" "F.Mask" "F.Paste")
			(net "FAN_TACH0_R")
		)
		(zone
			(layer "F.Cu")
			(hatch none 0.5)
			(connect_pads
				(clearance 0)
			)
			(min_thickness 0.25)
			(keepout
				(tracks allowed)
				(vias not_allowed)
				(pads allowed)
				(copperpour not_allowed)
				(footprints allowed)
			)
			(placement
				(enabled no)
				(sheetname "")
			)
			(fill
				(thermal_gap 0.5)
				(thermal_bridge_width 0.5)
				(island_removal_mode 0)
			)
			(polygon
				(pts
					(xy 12.192 -101.7524) (xy 12.7 -101.7524) (xy 12.7 -101.3714) (xy 12.192 -101.3714)
				)
			)
		)
		(zone
			(layer "F.Cu")
			(hatch none 0.5)
			(connect_pads
				(clearance 0)
			)
			(min_thickness 0.25)
			(keepout
				(tracks not_allowed)
				(vias allowed)
				(pads allowed)
				(copperpour not_allowed)
				(footprints allowed)
			)
			(placement
				(enabled no)
				(sheetname "")
			)
			(fill
				(thermal_gap 0.5)
				(thermal_bridge_width 0.5)
				(island_removal_mode 0)
			)
			(polygon
				(pts
					(xy 12.192 -101.3714) (xy 12.7 -101.3714) (xy 12.7 -101.7524) (xy 12.192 -101.7524)
				)
			)
		)
	)
	(footprint ""
		(layer "F.Cu")
		(at 26.2255 -66.46672 180)
		(property "Reference" "R1D51"
			(at 0 0 180)
			(layer "F.SilkS")
			(hide yes)
			(effects
				(font
					(size 1.27 1.27)
				)
			)
		)
		(property "Value" ""
			(at 0 0 180)
			(layer "F.Fab")
			(effects
				(font
					(size 1.27 1.27)
				)
			)
		)
		(duplicate_pad_numbers_are_jumpers no)
		(fp_poly
			(pts
				(xy -0.2794 -0.1016) (xy 0.2794 -0.1016) (xy 0.2794 0.9906) (xy -0.2794 0.9906)
			)
			(stroke
				(width 0)
				(type default)
			)
			(fill no)
			(layer "F.CrtYd")
		)
		(fp_line
			(start 0.2794 0.9906)
			(end 0.2794 -0.1016)
			(stroke
				(width 0.1)
				(type default)
			)
			(layer "F.Fab")
		)
		(fp_line
			(start 0.2794 -0.1016)
			(end -0.2794 -0.1016)
			(stroke
				(width 0.1)
				(type default)
			)
			(layer "F.Fab")
		)
		(fp_line
			(start -0.2794 0.9906)
			(end 0.2794 0.9906)
			(stroke
				(width 0.1)
				(type default)
			)
			(layer "F.Fab")
		)
		(fp_line
			(start -0.2794 -0.1016)
			(end -0.2794 0.9906)
			(stroke
				(width 0.1)
				(type default)
			)
			(layer "F.Fab")
		)
		(pad "1" smd rect
			(at 0 0 180)
			(size 0.508 0.508)
			(layers "F.Cu" "F.Mask" "F.Paste")
			(net "A_HSC_C")
		)
		(pad "2" smd rect
			(at 0 0.889 180)
			(size 0.508 0.508)
			(layers "F.Cu" "F.Mask" "F.Paste")
			(net "A_HSC_GATE")
		)
		(zone
			(layer "F.Cu")
			(hatch none 0.5)
			(connect_pads
				(clearance 0)
			)
			(min_thickness 0.25)
			(keepout
				(tracks not_allowed)
				(vias allowed)
				(pads allowed)
				(copperpour not_allowed)
				(footprints allowed)
			)
			(placement
				(enabled no)
				(sheetname "")
			)
			(fill
				(thermal_gap 0.5)
				(thermal_bridge_width 0.5)
				(island_removal_mode 0)
			)
			(polygon
				(pts
					(xy 26.4795 -67.10172) (xy 25.9715 -67.10172) (xy 25.9715 -66.72072) (xy 26.4795 -66.72072)
				)
			)
		)
		(zone
			(layer "F.Cu")
			(hatch none 0.5)
			(connect_pads
				(clearance 0)
			)
			(min_thickness 0.25)
			(keepout
				(tracks allowed)
				(vias not_allowed)
				(pads allowed)
				(copperpour not_allowed)
				(footprints allowed)
			)
			(placement
				(enabled no)
				(sheetname "")
			)
			(fill
				(thermal_gap 0.5)
				(thermal_bridge_width 0.5)
				(island_removal_mode 0)
			)
			(polygon
				(pts
					(xy 26.4795 -66.72072) (xy 25.9715 -66.72072) (xy 25.9715 -67.10172) (xy 26.4795 -67.10172)
				)
			)
		)
	)
	(footprint ""
		(layer "F.Cu")
		(at 381.4572 -141.7447 90)
		(property "Reference" "C3M6"
			(at 0 0 90)
			(layer "F.SilkS")
			(hide yes)
			(effects
				(font
					(size 1.27 1.27)
				)
			)
		)
		(property "Value" ""
			(at 0 0 90)
			(layer "F.Fab")
			(effects
				(font
					(size 1.27 1.27)
				)
			)
		)
		(duplicate_pad_numbers_are_jumpers no)
		(fp_rect
			(start -0.4953 -0.2032)
			(end 0.4953 1.6002)
			(stroke
				(width 0)
				(type default)
			)
			(fill no)
			(layer "F.CrtYd")
		)
		(fp_line
			(start 0.4953 -0.2032)
			(end 0.4953 1.6002)
			(stroke
				(width 0.1)
				(type default)
			)
			(layer "F.Fab")
		)
		(fp_line
			(start -0.4953 -0.2032)
			(end 0.4953 -0.2032)
			(stroke
				(width 0.1)
				(type default)
			)
			(layer "F.Fab")
		)
		(fp_line
			(start 0.4953 1.6002)
			(end -0.4953 1.6002)
			(stroke
				(width 0.1)
				(type default)
			)
			(layer "F.Fab")
		)
		(fp_line
			(start -0.4953 1.6002)
			(end -0.4953 -0.2032)
			(stroke
				(width 0.1)
				(type default)
			)
			(layer "F.Fab")
		)
		(pad "1" smd rect
			(at 0 0 90)
			(size 0.762 0.889)
			(layers "F.Cu" "F.Mask" "F.Paste")
			(net "PVNN_PCH_STBY")
		)
		(pad "2" smd rect
			(at 0 1.397 90)
			(size 0.762 0.889)
			(layers "F.Cu" "F.Mask" "F.Paste")
			(net "GND")
		)
		(zone
			(layer "F.Cu")
			(hatch none 0.5)
			(connect_pads
				(clearance 0)
			)
			(min_thickness 0.25)
			(keepout
				(tracks not_allowed)
				(vias allowed)
				(pads allowed)
				(copperpour not_allowed)
				(footprints allowed)
			)
			(placement
				(enabled no)
				(sheetname "")
			)
			(fill
				(thermal_gap 0.5)
				(thermal_bridge_width 0.5)
				(island_removal_mode 0)
			)
			(polygon
				(pts
					(xy 381.9017 -141.3637) (xy 382.4097 -141.3637) (xy 382.4097 -142.1257) (xy 381.9017 -142.1257)
				)
			)
		)
	)
	(footprint ""
		(layer "F.Cu")
		(at 471.000074 1.999996 90)
		(property "Reference" "TH9G1"
			(at 4.640326 1.820926 0)
			(unlocked yes)
			(layer "F.SilkS")
			(effects
				(font
					(size 0.7874 0.5842)
					(thickness 0.1524)
				)
				(justify left)
			)
		)
		(property "Value" ""
			(at 0 0 90)
			(layer "F.Fab")
			(effects
				(font
					(size 1.27 1.27)
				)
			)
		)
		(duplicate_pad_numbers_are_jumpers no)
		(fp_poly
			(pts
				(arc
					(start 3.0226 0.68834)
					(mid 3.042235 0.827855)
					(end 3.099562 0.956564)
				)
				(arc
					(start 3.099562 0.956564)
					(mid 4.012804 3.550073)
					(end 3.042158 6.12267)
				)
				(arc
					(start 3.042158 6.12267)
					(mid 0 7.518589)
					(end -3.042158 6.12267)
				)
				(arc
					(start -3.042158 6.12267)
					(mid -4.012854 3.55061)
					(end -3.100324 0.957326)
				)
				(arc
					(start -3.100324 0.957326)
					(mid -3.042498 0.827518)
					(end -3.0226 0.686816)
				)
				(arc
					(start -3.0226 -0.000254)
					(mid -2.137121 -2.137227)
					(end 0 -3.022346)
				)
				(arc
					(start 0 -3.022346)
					(mid 2.137227 -2.136973)
					(end 3.0226 0.000254)
				)
			)
			(stroke
				(width 0)
				(type default)
			)
			(fill no)
			(layer "F.CrtYd")
		)
		(pad "1" thru_hole custom
			(at 0 0 90)
			(size 2.00667 2.00667)
			(drill 0.3048)
			(layers "*.Cu" "*.Mask")
			(remove_unused_layers no)
			(net "GND")
			(clearance -0.889)
			(options
				(clearance outline)
				(anchor circle)
			)
			(primitives
				(gr_poly
					(pts
						(arc
							(start 3.042158 3.874516)
							(mid 0 5.270435)
							(end -3.042158 3.874516)
						)
						(arc
							(start -3.042158 3.874516)
							(mid -4.012854 1.302456)
							(end -3.100324 -1.290828)
						)
						(arc
							(start -3.100324 -1.290828)
							(mid -3.042498 -1.420636)
							(end -3.0226 -1.561338)
						)
						(arc
							(start -3.0226 -2.248408)
							(mid -2.137121 -4.385381)
							(end 0 -5.2705)
						)
						(arc
							(start 0 -5.2705)
							(mid 2.137227 -4.385127)
							(end 3.0226 -2.2479)
						)
						(arc
							(start 3.0226 -1.55956)
							(mid 3.04227 -1.420177)
							(end 3.099562 -1.29159)
						)
						(arc
							(start 3.099562 -1.29159)
							(mid 4.012804 1.301919)
							(end 3.042158 3.874516)
						)
					)
					(width 0)
					(fill yes)
				)
			)
		)
	)
	(footprint ""
		(layer "F.Cu")
		(at 273.2532 -79.6036 180)
		(property "Reference" "C5D21"
			(at 0 0 180)
			(layer "F.SilkS")
			(hide yes)
			(effects
				(font
					(size 1.27 1.27)
				)
			)
		)
		(property "Value" ""
			(at 0 0 180)
			(layer "F.Fab")
			(effects
				(font
					(size 1.27 1.27)
				)
			)
		)
		(duplicate_pad_numbers_are_jumpers no)
		(fp_poly
			(pts
				(xy -0.4953 -0.2032) (xy 0.4953 -0.2032) (xy 0.4953 1.6002) (xy -0.4953 1.6002)
			)
			(stroke
				(width 0)
				(type default)
			)
			(fill no)
			(layer "F.CrtYd")
		)
		(fp_line
			(start 0.4953 1.6002)
			(end -0.4953 1.6002)
			(stroke
				(width 0.1)
				(type default)
			)
			(layer "F.Fab")
		)
		(fp_line
			(start 0.4953 -0.2032)
			(end 0.4953 1.6002)
			(stroke
				(width 0.1)
				(type default)
			)
			(layer "F.Fab")
		)
		(fp_line
			(start -0.4953 1.6002)
			(end -0.4953 -0.2032)
			(stroke
				(width 0.1)
				(type default)
			)
			(layer "F.Fab")
		)
		(fp_line
			(start -0.4953 -0.2032)
			(end 0.4953 -0.2032)
			(stroke
				(width 0.1)
				(type default)
			)
			(layer "F.Fab")
		)
		(pad "1" smd rect
			(at 0 0 180)
			(size 0.762 0.889)
			(layers "F.Cu" "F.Mask" "F.Paste")
			(net "PVCCMCP_CPU0")
		)
		(pad "2" smd rect
			(at 0 1.397 180)
			(size 0.762 0.889)
			(layers "F.Cu" "F.Mask" "F.Paste")
			(net "GND")
		)
		(zone
			(layer "F.Cu")
			(hatch none 0.5)
			(connect_pads
				(clearance 0)
			)
			(min_thickness 0.25)
			(keepout
				(tracks not_allowed)
				(vias allowed)
				(pads allowed)
				(copperpour not_allowed)
				(footprints allowed)
			)
			(placement
				(enabled no)
				(sheetname "")
			)
			(fill
				(thermal_gap 0.5)
				(thermal_bridge_width 0.5)
				(island_removal_mode 0)
			)
			(polygon
				(pts
					(xy 273.6342 -80.0481) (xy 272.8722 -80.0481) (xy 272.8722 -80.5561) (xy 273.6342 -80.5561)
				)
			)
		)
	)
	(footprint ""
		(layer "F.Cu")
		(at 405.231092 -10.917936)
		(property "Reference" "C8G5"
			(at 0 0 0)
			(layer "F.SilkS")
			(hide yes)
			(effects
				(font
					(size 1.27 1.27)
				)
			)
		)
		(property "Value" ""
			(at 0 0 0)
			(layer "F.Fab")
			(effects
				(font
					(size 1.27 1.27)
				)
			)
		)
		(duplicate_pad_numbers_are_jumpers no)
		(fp_rect
			(start -0.3048 0.9906)
			(end 0.3048 -0.1016)
			(stroke
				(width 0)
				(type default)
			)
			(fill no)
			(layer "F.CrtYd")
		)
		(fp_line
			(start -0.3048 -0.1016)
			(end -0.3048 0.9906)
			(stroke
				(width 0.1)
				(type default)
			)
			(layer "F.Fab")
		)
		(fp_line
			(start -0.3048 0.9906)
			(end 0.3048 0.9906)
			(stroke
				(width 0.1)
				(type default)
			)
			(layer "F.Fab")
		)
		(fp_line
			(start 0.3048 -0.1016)
			(end -0.3048 -0.1016)
			(stroke
				(width 0.1)
				(type default)
			)
			(layer "F.Fab")
		)
		(fp_line
			(start 0.3048 0.9906)
			(end 0.3048 -0.1016)
			(stroke
				(width 0.1)
				(type default)
			)
			(layer "F.Fab")
		)
		(pad "1" smd rect
			(at 0 0)
			(size 0.508 0.508)
			(layers "F.Cu" "F.Mask" "F.Paste")
			(net "P3E_CPU0_PE2_SS_TXP<2>")
		)
		(pad "2" smd rect
			(at 0 0.889)
			(size 0.508 0.508)
			(layers "F.Cu" "F.Mask" "F.Paste")
			(net "P3E_CPU0_PE2_SS_C_TXP<2>")
		)
		(zone
			(layer "F.Cu")
			(hatch none 0.5)
			(connect_pads
				(clearance 0)
			)
			(min_thickness 0.25)
			(keepout
				(tracks allowed)
				(vias not_allowed)
				(pads allowed)
				(copperpour not_allowed)
				(footprints allowed)
			)
			(placement
				(enabled no)
				(sheetname "")
			)
			(fill
				(thermal_gap 0.5)
				(thermal_bridge_width 0.5)
				(island_removal_mode 0)
			)
			(polygon
				(pts
					(xy 404.977092 -10.282936) (xy 405.485092 -10.282936) (xy 405.485092 -10.663936) (xy 404.977092 -10.663936)
				)
			)
		)
		(zone
			(layer "F.Cu")
			(hatch none 0.5)
			(connect_pads
				(clearance 0)
			)
			(min_thickness 0.25)
			(keepout
				(tracks not_allowed)
				(vias allowed)
				(pads allowed)
				(copperpour not_allowed)
				(footprints allowed)
			)
			(placement
				(enabled no)
				(sheetname "")
			)
			(fill
				(thermal_gap 0.5)
				(thermal_bridge_width 0.5)
				(island_removal_mode 0)
			)
			(polygon
				(pts
					(xy 404.977092 -10.282936) (xy 405.485092 -10.282936) (xy 405.485092 -10.663936) (xy 404.977092 -10.663936)
				)
			)
		)
	)
	(footprint ""
		(layer "F.Cu")
		(at 214.503 -63.11392)
		(property "Reference" "C4E3"
			(at 0 0 0)
			(layer "F.SilkS")
			(hide yes)
			(effects
				(font
					(size 1.27 1.27)
				)
			)
		)
		(property "Value" ""
			(at 0 0 0)
			(layer "F.Fab")
			(effects
				(font
					(size 1.27 1.27)
				)
			)
		)
		(duplicate_pad_numbers_are_jumpers no)
		(fp_poly
			(pts
				(xy -0.4953 -0.2032) (xy 0.4953 -0.2032) (xy 0.4953 1.6002) (xy -0.4953 1.6002)
			)
			(stroke
				(width 0)
				(type default)
			)
			(fill no)
			(layer "F.CrtYd")
		)
		(fp_line
			(start -0.4953 -0.2032)
			(end 0.4953 -0.2032)
			(stroke
				(width 0.1)
				(type default)
			)
			(layer "F.Fab")
		)
		(fp_line
			(start -0.4953 1.6002)
			(end -0.4953 -0.2032)
			(stroke
				(width 0.1)
				(type default)
			)
			(layer "F.Fab")
		)
		(fp_line
			(start 0.4953 -0.2032)
			(end 0.4953 1.6002)
			(stroke
				(width 0.1)
				(type default)
			)
			(layer "F.Fab")
		)
		(fp_line
			(start 0.4953 1.6002)
			(end -0.4953 1.6002)
			(stroke
				(width 0.1)
				(type default)
			)
			(layer "F.Fab")
		)
		(pad "1" smd rect
			(at 0 0)
			(size 0.762 0.889)
			(layers "F.Cu" "F.Mask" "F.Paste")
			(net "PVCCIN_CPU0")
		)
		(pad "2" smd rect
			(at 0 1.397)
			(size 0.762 0.889)
			(layers "F.Cu" "F.Mask" "F.Paste")
			(net "GND")
		)
		(zone
			(layer "F.Cu")
			(hatch none 0.5)
			(connect_pads
				(clearance 0)
			)
			(min_thickness 0.25)
			(keepout
				(tracks not_allowed)
				(vias allowed)
				(pads allowed)
				(copperpour not_allowed)
				(footprints allowed)
			)
			(placement
				(enabled no)
				(sheetname "")
			)
			(fill
				(thermal_gap 0.5)
				(thermal_bridge_width 0.5)
				(island_removal_mode 0)
			)
			(polygon
				(pts
					(xy 214.122 -62.66942) (xy 214.884 -62.66942) (xy 214.884 -62.16142) (xy 214.122 -62.16142)
				)
			)
		)
	)
	(footprint ""
		(layer "F.Cu")
		(at -1.59639 -150.10511 -90)
		(property "Reference" "C1A9"
			(at 0 0 270)
			(layer "F.SilkS")
			(hide yes)
			(effects
				(font
					(size 1.27 1.27)
				)
			)
		)
		(property "Value" ""
			(at 0 0 270)
			(layer "F.Fab")
			(effects
				(font
					(size 1.27 1.27)
				)
			)
		)
		(duplicate_pad_numbers_are_jumpers no)
		(fp_poly
			(pts
				(xy 0.3048 -0.1016) (xy 0.3048 0.9906) (xy -0.3048 0.9906) (xy -0.3048 -0.1016)
			)
			(stroke
				(width 0)
				(type default)
			)
			(fill no)
			(layer "F.CrtYd")
		)
		(fp_line
			(start -0.3048 0.9906)
			(end 0.3048 0.9906)
			(stroke
				(width 0.1)
				(type default)
			)
			(layer "F.Fab")
		)
		(fp_line
			(start 0.3048 0.9906)
			(end 0.3048 -0.1016)
			(stroke
				(width 0.1)
				(type default)
			)
			(layer "F.Fab")
		)
		(fp_line
			(start -0.3048 -0.1016)
			(end -0.3048 0.9906)
			(stroke
				(width 0.1)
				(type default)
			)
			(layer "F.Fab")
		)
		(fp_line
			(start 0.3048 -0.1016)
			(end -0.3048 -0.1016)
			(stroke
				(width 0.1)
				(type default)
			)
			(layer "F.Fab")
		)
		(pad "1" smd rect
			(at 0 0 270)
			(size 0.508 0.508)
			(layers "F.Cu" "F.Mask" "F.Paste")
			(net "VR_FET_SW_P12V_STBY_PVDDQ_KLM")
		)
		(pad "2" smd rect
			(at 0 0.889 270)
			(size 0.508 0.508)
			(layers "F.Cu" "F.Mask" "F.Paste")
			(net "GND")
		)
		(zone
			(layer "F.Cu")
			(hatch none 0.5)
			(connect_pads
				(clearance 0)
			)
			(min_thickness 0.25)
			(keepout
				(tracks not_allowed)
				(vias allowed)
				(pads allowed)
				(copperpour not_allowed)
				(footprints allowed)
			)
			(placement
				(enabled no)
				(sheetname "")
			)
			(fill
				(thermal_gap 0.5)
				(thermal_bridge_width 0.5)
				(island_removal_mode 0)
			)
			(polygon
				(pts
					(xy -2.23139 -150.35911) (xy -2.23139 -149.85111) (xy -1.85039 -149.85111) (xy -1.85039 -150.35911)
				)
			)
		)
		(zone
			(layer "F.Cu")
			(hatch none 0.5)
			(connect_pads
				(clearance 0)
			)
			(min_thickness 0.25)
			(keepout
				(tracks allowed)
				(vias not_allowed)
				(pads allowed)
				(copperpour not_allowed)
				(footprints allowed)
			)
			(placement
				(enabled no)
				(sheetname "")
			)
			(fill
				(thermal_gap 0.5)
				(thermal_bridge_width 0.5)
				(island_removal_mode 0)
			)
			(polygon
				(pts
					(xy -1.85039 -150.35911) (xy -1.85039 -149.85111) (xy -2.23139 -149.85111) (xy -2.23139 -150.35911)
				)
			)
		)
	)
	(footprint ""
		(layer "F.Cu")
		(at 104.645206 -68.365116 180)
		(property "Reference" "C2D46"
			(at 0 0 180)
			(layer "F.SilkS")
			(hide yes)
			(effects
				(font
					(size 1.27 1.27)
				)
			)
		)
		(property "Value" ""
			(at 0 0 180)
			(layer "F.Fab")
			(effects
				(font
					(size 1.27 1.27)
				)
			)
		)
		(duplicate_pad_numbers_are_jumpers no)
		(fp_poly
			(pts
				(xy -0.4953 -0.2032) (xy 0.4953 -0.2032) (xy 0.4953 1.6002) (xy -0.4953 1.6002)
			)
			(stroke
				(width 0)
				(type default)
			)
			(fill no)
			(layer "F.CrtYd")
		)
		(fp_line
			(start 0.4953 1.6002)
			(end -0.4953 1.6002)
			(stroke
				(width 0.1)
				(type default)
			)
			(layer "F.Fab")
		)
		(fp_line
			(start 0.4953 -0.2032)
			(end 0.4953 1.6002)
			(stroke
				(width 0.1)
				(type default)
			)
			(layer "F.Fab")
		)
		(fp_line
			(start -0.4953 1.6002)
			(end -0.4953 -0.2032)
			(stroke
				(width 0.1)
				(type default)
			)
			(layer "F.Fab")
		)
		(fp_line
			(start -0.4953 -0.2032)
			(end 0.4953 -0.2032)
			(stroke
				(width 0.1)
				(type default)
			)
			(layer "F.Fab")
		)
		(pad "1" smd rect
			(at 0 0 180)
			(size 0.762 0.889)
			(layers "F.Cu" "F.Mask" "F.Paste")
			(net "PVDDQ_GHJ")
		)
		(pad "2" smd rect
			(at 0 1.397 180)
			(size 0.762 0.889)
			(layers "F.Cu" "F.Mask" "F.Paste")
			(net "GND")
		)
		(zone
			(layer "F.Cu")
			(hatch none 0.5)
			(connect_pads
				(clearance 0)
			)
			(min_thickness 0.25)
			(keepout
				(tracks not_allowed)
				(vias allowed)
				(pads allowed)
				(copperpour not_allowed)
				(footprints allowed)
			)
			(placement
				(enabled no)
				(sheetname "")
			)
			(fill
				(thermal_gap 0.5)
				(thermal_bridge_width 0.5)
				(island_removal_mode 0)
			)
			(polygon
				(pts
					(xy 105.026206 -68.809616) (xy 104.264206 -68.809616) (xy 104.264206 -69.317616) (xy 105.026206 -69.317616)
				)
			)
		)
	)
	(footprint ""
		(layer "F.Cu")
		(at 446.73012 -24.47798)
		(property "Reference" "C25W15"
			(at -0.8382 -0.67818 0)
			(unlocked yes)
			(layer "F.SilkS")
			(effects
				(font
					(size 0.4064 0.254)
					(thickness 0.1524)
				)
				(justify left)
			)
		)
		(property "Value" ""
			(at 0 0 0)
			(layer "F.Fab")
			(effects
				(font
					(size 1.27 1.27)
				)
			)
		)
		(duplicate_pad_numbers_are_jumpers no)
		(fp_poly
			(pts
				(xy 0.3048 -0.1016) (xy 0.3048 0.9906) (xy -0.3048 0.9906) (xy -0.3048 -0.1016)
			)
			(stroke
				(width 0)
				(type default)
			)
			(fill no)
			(layer "F.CrtYd")
		)
		(fp_line
			(start -0.3048 -0.1016)
			(end -0.3048 0.9906)
			(stroke
				(width 0.1)
				(type default)
			)
			(layer "F.Fab")
		)
		(fp_line
			(start -0.3048 0.9906)
			(end 0.3048 0.9906)
			(stroke
				(width 0.1)
				(type default)
			)
			(layer "F.Fab")
		)
		(fp_line
			(start 0.3048 -0.1016)
			(end -0.3048 -0.1016)
			(stroke
				(width 0.1)
				(type default)
			)
			(layer "F.Fab")
		)
		(fp_line
			(start 0.3048 0.9906)
			(end 0.3048 -0.1016)
			(stroke
				(width 0.1)
				(type default)
			)
			(layer "F.Fab")
		)
		(pad "1" smd rect
			(at 0 0)
			(size 0.508 0.508)
			(layers "F.Cu" "F.Mask" "F.Paste")
			(net "P2V5_AUX_BMC")
		)
		(pad "2" smd rect
			(at 0 0.889)
			(size 0.508 0.508)
			(layers "F.Cu" "F.Mask" "F.Paste")
			(net "GND")
		)
		(zone
			(layer "F.Cu")
			(hatch none 0.5)
			(connect_pads
				(clearance 0)
			)
			(min_thickness 0.25)
			(keepout
				(tracks allowed)
				(vias not_allowed)
				(pads allowed)
				(copperpour not_allowed)
				(footprints allowed)
			)
			(placement
				(enabled no)
				(sheetname "")
			)
			(fill
				(thermal_gap 0.5)
				(thermal_bridge_width 0.5)
				(island_removal_mode 0)
			)
			(polygon
				(pts
					(xy 446.47612 -24.22398) (xy 446.98412 -24.22398) (xy 446.98412 -23.84298) (xy 446.47612 -23.84298)
				)
			)
		)
		(zone
			(layer "F.Cu")
			(hatch none 0.5)
			(connect_pads
				(clearance 0)
			)
			(min_thickness 0.25)
			(keepout
				(tracks not_allowed)
				(vias allowed)
				(pads allowed)
				(copperpour not_allowed)
				(footprints allowed)
			)
			(placement
				(enabled no)
				(sheetname "")
			)
			(fill
				(thermal_gap 0.5)
				(thermal_bridge_width 0.5)
				(island_removal_mode 0)
			)
			(polygon
				(pts
					(xy 446.47612 -23.84298) (xy 446.98412 -23.84298) (xy 446.98412 -24.22398) (xy 446.47612 -24.22398)
				)
			)
		)
	)
	(footprint ""
		(layer "F.Cu")
		(at 330.962 -153.543)
		(property "Reference" "C6A1"
			(at 0 0 0)
			(layer "F.SilkS")
			(hide yes)
			(effects
				(font
					(size 1.27 1.27)
				)
			)
		)
		(property "Value" ""
			(at 0 0 0)
			(layer "F.Fab")
			(effects
				(font
					(size 1.27 1.27)
				)
			)
		)
		(duplicate_pad_numbers_are_jumpers no)
		(fp_rect
			(start -0.7239 1.9939)
			(end 0.7239 -0.2159)
			(stroke
				(width 0)
				(type default)
			)
			(fill no)
			(layer "F.CrtYd")
		)
		(fp_line
			(start -0.7239 -0.2159)
			(end -0.7239 1.9939)
			(stroke
				(width 0.1)
				(type default)
			)
			(layer "F.Fab")
		)
		(fp_line
			(start -0.7239 1.9939)
			(end 0.7239 1.9939)
			(stroke
				(width 0.1)
				(type default)
			)
			(layer "F.Fab")
		)
		(fp_line
			(start 0.7239 -0.2159)
			(end -0.7239 -0.2159)
			(stroke
				(width 0.1)
				(type default)
			)
			(layer "F.Fab")
		)
		(fp_line
			(start 0.7239 1.9939)
			(end 0.7239 -0.2159)
			(stroke
				(width 0.1)
				(type default)
			)
			(layer "F.Fab")
		)
		(pad "1" smd rect
			(at 0 0)
			(size 1.27 1.016)
			(layers "F.Cu" "F.Mask" "F.Paste")
			(net "PVDDQ_DEF")
		)
		(pad "2" smd rect
			(at 0 1.778)
			(size 1.27 1.016)
			(layers "F.Cu" "F.Mask" "F.Paste")
			(net "GND")
		)
		(zone
			(layer "F.Cu")
			(hatch none 0.5)
			(connect_pads
				(clearance 0)
			)
			(min_thickness 0.25)
			(keepout
				(tracks not_allowed)
				(vias allowed)
				(pads allowed)
				(copperpour not_allowed)
				(footprints allowed)
			)
			(placement
				(enabled no)
				(sheetname "")
			)
			(fill
				(thermal_gap 0.5)
				(thermal_bridge_width 0.5)
				(island_removal_mode 0)
			)
			(polygon
				(pts
					(xy 330.327 -152.273) (xy 331.597 -152.273) (xy 331.597 -153.035) (xy 330.327 -153.035)
				)
			)
		)
	)
	(footprint ""
		(layer "F.Cu")
		(at 352.24593 -25.676606 90)
		(property "Reference" "C7F7"
			(at 0 0 90)
			(layer "F.SilkS")
			(hide yes)
			(effects
				(font
					(size 1.27 1.27)
				)
			)
		)
		(property "Value" "*"
			(at -0.0762 -6.2357 90)
			(unlocked yes)
			(layer "F.Fab")
			(hide yes)
			(effects
				(font
					(size 1.27 1.016)
					(thickness 0.1524)
				)
			)
		)
		(property "Device Type" "SC22U16V5MX-4-GP_SMD-BCG5-SC22A"
			(at -0.0762 -8.2677 90)
			(unlocked yes)
			(layer "F.Fab")
			(hide yes)
			(effects
				(font
					(size 1.27 1.016)
					(thickness 0.1524)
				)
			)
		)
		(duplicate_pad_numbers_are_jumpers no)
		(fp_line
			(start 0.635 0)
			(end -0.635 0)
			(stroke
				(width 0.508)
				(type default)
			)
			(layer "F.SilkS")
		)
		(fp_rect
			(start -0.9652 1.778)
			(end 0.9652 -1.778)
			(stroke
				(width 0)
				(type default)
			)
			(fill no)
			(layer "F.CrtYd")
		)
		(fp_poly
			(pts
				(xy -0.9652 -1.778) (xy 0.9652 -1.778) (xy 0.9652 1.778) (xy -0.9652 1.778)
			)
			(stroke
				(width 0)
				(type default)
			)
			(fill no)
			(layer "F.Fab")
		)
		(pad "1" smd rect
			(at 0 -0.9652 90)
			(size 1.397 1.143)
			(layers "F.Cu" "F.Mask" "F.Paste")
			(net "VR_FET_SW_P12V_STBY_PVPP_ABC")
		)
		(pad "2" smd rect
			(at 0 0.9652 90)
			(size 1.397 1.143)
			(layers "F.Cu" "F.Mask" "F.Paste")
			(net "GND")
		)
	)
	(footprint ""
		(layer "F.Cu")
		(at 8.509 -147.32)
		(property "Reference" "L1A1"
			(at 3.378708 -4.251706 0)
			(unlocked yes)
			(layer "F.SilkS")
			(effects
				(font
					(size 0.4064 0.254)
					(thickness 0.1524)
				)
			)
		)
		(property "Value" ""
			(at 0 0 0)
			(layer "F.Fab")
			(effects
				(font
					(size 1.27 1.27)
				)
			)
		)
		(duplicate_pad_numbers_are_jumpers no)
		(fp_line
			(start -1.1303 -3.199892)
			(end 8.3693 -3.199892)
			(stroke
				(width 0.1524)
				(type default)
			)
			(layer "F.SilkS")
		)
		(fp_line
			(start -1.1303 -1.6637)
			(end -1.1303 -3.199892)
			(stroke
				(width 0.1524)
				(type default)
			)
			(layer "F.SilkS")
		)
		(fp_line
			(start -1.1303 3.199892)
			(end -1.1303 1.6637)
			(stroke
				(width 0.1524)
				(type default)
			)
			(layer "F.SilkS")
		)
		(fp_line
			(start 8.3693 -3.199892)
			(end 8.3693 -1.6637)
			(stroke
				(width 0.1524)
				(type default)
			)
			(layer "F.SilkS")
		)
		(fp_line
			(start 8.3693 1.6637)
			(end 8.3693 3.199892)
			(stroke
				(width 0.1524)
				(type default)
			)
			(layer "F.SilkS")
		)
		(fp_line
			(start 8.3693 3.199892)
			(end -1.1303 3.199892)
			(stroke
				(width 0.1524)
				(type default)
			)
			(layer "F.SilkS")
		)
		(fp_rect
			(start -1.1303 3.199892)
			(end 8.3693 -3.199892)
			(stroke
				(width 0)
				(type default)
			)
			(fill no)
			(layer "F.CrtYd")
		)
		(fp_line
			(start -1.1303 -3.199892)
			(end 8.3693 -3.199892)
			(stroke
				(width 0.1)
				(type default)
			)
			(layer "F.Fab")
		)
		(fp_line
			(start -1.1303 3.199892)
			(end -1.1303 -3.199892)
			(stroke
				(width 0.1)
				(type default)
			)
			(layer "F.Fab")
		)
		(fp_line
			(start 8.3693 -3.199892)
			(end 8.3693 3.199892)
			(stroke
				(width 0.1)
				(type default)
			)
			(layer "F.Fab")
		)
		(fp_line
			(start 8.3693 3.199892)
			(end -1.1303 3.199892)
			(stroke
				(width 0.1)
				(type default)
			)
			(layer "F.Fab")
		)
		(pad "1" smd rect
			(at 0 0)
			(size 3.683 2.667)
			(layers "F.Cu" "F.Mask" "F.Paste")
			(net "VR_PVDDQ_KLM_PH2_SW")
		)
		(pad "2" smd rect
			(at 7.239 0)
			(size 3.683 2.667)
			(layers "F.Cu" "F.Mask" "F.Paste")
			(net "PVDDQ_KLM")
		)
	)
	(footprint ""
		(layer "F.Cu")
		(at 189.484 -56.642)
		(property "Reference" "C4E16"
			(at -4.16433 4.064 90)
			(unlocked yes)
			(layer "F.SilkS")
			(effects
				(font
					(size 0.7874 0.5842)
					(thickness 0.1524)
				)
				(justify left)
			)
		)
		(property "Value" ""
			(at 0 0 0)
			(layer "F.Fab")
			(effects
				(font
					(size 1.27 1.27)
				)
			)
		)
		(duplicate_pad_numbers_are_jumpers no)
		(fp_line
			(start -3.400044 0.028956)
			(end -3.400044 6.06679)
			(stroke
				(width 0.1524)
				(type default)
			)
			(layer "F.SilkS")
		)
		(fp_line
			(start -3.400044 6.06679)
			(end -0.9017 6.06679)
			(stroke
				(width 0.1524)
				(type default)
			)
			(layer "F.SilkS")
		)
		(fp_line
			(start -2.638044 -0.733044)
			(end -3.400044 0.028956)
			(stroke
				(width 0.1524)
				(type default)
			)
			(layer "F.SilkS")
		)
		(fp_line
			(start -0.9017 -1.714246)
			(end -0.9017 1.587754)
			(stroke
				(width 0.1524)
				(type default)
			)
			(layer "F.SilkS")
		)
		(fp_line
			(start -0.9017 -0.733044)
			(end -2.638044 -0.733044)
			(stroke
				(width 0.1524)
				(type default)
			)
			(layer "F.SilkS")
		)
		(fp_line
			(start -0.9017 1.587754)
			(end -0.7239 1.587754)
			(stroke
				(width 0.1524)
				(type default)
			)
			(layer "F.SilkS")
		)
		(fp_line
			(start -0.7239 -1.714246)
			(end -0.9017 -1.714246)
			(stroke
				(width 0.1524)
				(type default)
			)
			(layer "F.SilkS")
		)
		(fp_line
			(start 0.7239 1.587754)
			(end 0.9017 1.587754)
			(stroke
				(width 0.1524)
				(type default)
			)
			(layer "F.SilkS")
		)
		(fp_line
			(start 0.9017 -1.714246)
			(end 0.7239 -1.714246)
			(stroke
				(width 0.1524)
				(type default)
			)
			(layer "F.SilkS")
		)
		(fp_line
			(start 0.9017 1.587754)
			(end 0.9017 -1.714246)
			(stroke
				(width 0.1524)
				(type default)
			)
			(layer "F.SilkS")
		)
		(fp_line
			(start 0.9017 6.06679)
			(end 3.400044 6.06679)
			(stroke
				(width 0.1524)
				(type default)
			)
			(layer "F.SilkS")
		)
		(fp_line
			(start 2.638044 -0.733044)
			(end 0.9017 -0.733044)
			(stroke
				(width 0.1524)
				(type default)
			)
			(layer "F.SilkS")
		)
		(fp_line
			(start 3.400044 0.028956)
			(end 2.638044 -0.733044)
			(stroke
				(width 0.1524)
				(type default)
			)
			(layer "F.SilkS")
		)
		(fp_line
			(start 3.400044 6.06679)
			(end 3.400044 0.028956)
			(stroke
				(width 0.1524)
				(type default)
			)
			(layer "F.SilkS")
		)
		(fp_poly
			(pts
				(xy -3.400044 6.06679) (xy 3.400044 6.06679) (xy 3.400044 0.028956) (xy 2.638044 -0.733044) (xy -2.638044 -0.733044)
				(xy -3.400044 0.028956)
			)
			(stroke
				(width 0)
				(type default)
			)
			(fill no)
			(layer "F.CrtYd")
		)
		(fp_line
			(start -3.400044 0.028956)
			(end -3.400044 6.06679)
			(stroke
				(width 0.1)
				(type default)
			)
			(layer "F.Fab")
		)
		(fp_line
			(start -3.400044 6.06679)
			(end 3.400044 6.06679)
			(stroke
				(width 0.1)
				(type default)
			)
			(layer "F.Fab")
		)
		(fp_line
			(start -2.638044 -0.733044)
			(end -3.400044 0.028956)
			(stroke
				(width 0.1)
				(type default)
			)
			(layer "F.Fab")
		)
		(fp_line
			(start 2.638044 -0.733044)
			(end -2.638044 -0.733044)
			(stroke
				(width 0.1)
				(type default)
			)
			(layer "F.Fab")
		)
		(fp_line
			(start 3.400044 0.028956)
			(end 2.638044 -0.733044)
			(stroke
				(width 0.1)
				(type default)
			)
			(layer "F.Fab")
		)
		(fp_line
			(start 3.400044 6.06679)
			(end 3.400044 0.028956)
			(stroke
				(width 0.1)
				(type default)
			)
			(layer "F.Fab")
		)
		(fp_circle
			(center 0 2.667)
			(end 3.400044 2.667)
			(stroke
				(width 0.1)
				(type default)
			)
			(fill no)
			(layer "F.Fab")
		)
		(pad "1" smd rect
			(at 0 0)
			(size 0.7874 3.429)
			(layers "F.Cu" "F.Mask" "F.Paste")
			(net "VR_FET_SW_P12V_STBY_PVCCIN_CPU0")
		)
		(pad "2" smd rect
			(at 0 5.334)
			(size 0.7874 3.429)
			(layers "F.Cu" "F.Mask" "F.Paste")
			(net "GND")
		)
	)
	(footprint ""
		(layer "F.Cu")
		(at -2.5146 -127.7112 -90)
		(property "Reference" "R1B10"
			(at 0 0 270)
			(layer "F.SilkS")
			(hide yes)
			(effects
				(font
					(size 1.27 1.27)
				)
			)
		)
		(property "Value" ""
			(at 0 0 270)
			(layer "F.Fab")
			(effects
				(font
					(size 1.27 1.27)
				)
			)
		)
		(duplicate_pad_numbers_are_jumpers no)
		(fp_rect
			(start 0.2794 0.9906)
			(end -0.2794 -0.1016)
			(stroke
				(width 0)
				(type default)
			)
			(fill no)
			(layer "F.CrtYd")
		)
		(fp_line
			(start -0.2794 0.9906)
			(end 0.2794 0.9906)
			(stroke
				(width 0.1)
				(type default)
			)
			(layer "F.Fab")
		)
		(fp_line
			(start 0.2794 0.9906)
			(end 0.2794 -0.1016)
			(stroke
				(width 0.1)
				(type default)
			)
			(layer "F.Fab")
		)
		(fp_line
			(start -0.2794 -0.1016)
			(end -0.2794 0.9906)
			(stroke
				(width 0.1)
				(type default)
			)
			(layer "F.Fab")
		)
		(fp_line
			(start 0.2794 -0.1016)
			(end -0.2794 -0.1016)
			(stroke
				(width 0.1)
				(type default)
			)
			(layer "F.Fab")
		)
		(pad "1" smd rect
			(at 0 0 270)
			(size 0.508 0.508)
			(layers "F.Cu" "F.Mask" "F.Paste")
			(net "SVID_VDIO_PVDDQ_KLM")
		)
		(pad "2" smd rect
			(at 0 0.889 270)
			(size 0.508 0.508)
			(layers "F.Cu" "F.Mask" "F.Paste")
			(net "SVID_DIO1_CPU1_R")
		)
		(zone
			(layer "F.Cu")
			(hatch none 0.5)
			(connect_pads
				(clearance 0)
			)
			(min_thickness 0.25)
			(keepout
				(tracks allowed)
				(vias not_allowed)
				(pads allowed)
				(copperpour not_allowed)
				(footprints allowed)
			)
			(placement
				(enabled no)
				(sheetname "")
			)
			(fill
				(thermal_gap 0.5)
				(thermal_bridge_width 0.5)
				(island_removal_mode 0)
			)
			(polygon
				(pts
					(xy -3.1496 -127.4572) (xy -2.7686 -127.4572) (xy -2.7686 -127.9652) (xy -3.1496 -127.9652)
				)
			)
		)
		(zone
			(layer "F.Cu")
			(hatch none 0.5)
			(connect_pads
				(clearance 0)
			)
			(min_thickness 0.25)
			(keepout
				(tracks not_allowed)
				(vias allowed)
				(pads allowed)
				(copperpour not_allowed)
				(footprints allowed)
			)
			(placement
				(enabled no)
				(sheetname "")
			)
			(fill
				(thermal_gap 0.5)
				(thermal_bridge_width 0.5)
				(island_removal_mode 0)
			)
			(polygon
				(pts
					(xy -3.1496 -127.4572) (xy -2.7686 -127.4572) (xy -2.7686 -127.9652) (xy -3.1496 -127.9652)
				)
			)
		)
	)
	(footprint ""
		(layer "F.Cu")
		(at 272.861532 -149.8092 90)
		(property "Reference" "C5A8"
			(at 1.848866 0.752348 90)
			(unlocked yes)
			(layer "F.SilkS")
			(effects
				(font
					(size 1.27 0.9652)
					(thickness 0.1524)
				)
			)
		)
		(property "Value" ""
			(at 0 0 90)
			(layer "F.Fab")
			(effects
				(font
					(size 1.27 1.27)
				)
			)
		)
		(duplicate_pad_numbers_are_jumpers no)
		(fp_rect
			(start -0.500126 1.598422)
			(end 0.500126 -0.201422)
			(stroke
				(width 0)
				(type default)
			)
			(fill no)
			(layer "F.CrtYd")
		)
		(fp_line
			(start 0.500126 -0.201422)
			(end 0.500126 1.598422)
			(stroke
				(width 0.1)
				(type default)
			)
			(layer "F.Fab")
		)
		(fp_line
			(start -0.500126 -0.201422)
			(end 0.500126 -0.201422)
			(stroke
				(width 0.1)
				(type default)
			)
			(layer "F.Fab")
		)
		(fp_line
			(start 0.500126 1.598422)
			(end -0.500126 1.598422)
			(stroke
				(width 0.1)
				(type default)
			)
			(layer "F.Fab")
		)
		(fp_line
			(start -0.500126 1.598422)
			(end -0.500126 -0.201422)
			(stroke
				(width 0.1)
				(type default)
			)
			(layer "F.Fab")
		)
		(pad "1" smd rect
			(at 0 0)
			(size 0.889 0.9906)
			(layers "F.Cu" "F.Mask" "F.Paste")
			(net "PVDDQ_DEF")
		)
		(pad "2" smd rect
			(at 0 1.397)
			(size 0.889 0.9906)
			(layers "F.Cu" "F.Mask" "F.Paste")
			(net "GND")
		)
		(zone
			(layer "F.Cu")
			(hatch none 0.5)
			(connect_pads
				(clearance 0)
			)
			(min_thickness 0.25)
			(keepout
				(tracks allowed)
				(vias not_allowed)
				(pads allowed)
				(copperpour not_allowed)
				(footprints allowed)
			)
			(placement
				(enabled no)
				(sheetname "")
			)
			(fill
				(thermal_gap 0.5)
				(thermal_bridge_width 0.5)
				(island_removal_mode 0)
			)
			(polygon
				(pts
					(xy 273.814032 -149.3139) (xy 273.814032 -150.3045) (xy 273.306032 -150.3045) (xy 273.306032 -149.3139)
				)
			)
		)
		(zone
			(layer "F.Cu")
			(hatch none 0.5)
			(connect_pads
				(clearance 0)
			)
			(min_thickness 0.25)
			(keepout
				(tracks not_allowed)
				(vias allowed)
				(pads allowed)
				(copperpour not_allowed)
				(footprints allowed)
			)
			(placement
				(enabled no)
				(sheetname "")
			)
			(fill
				(thermal_gap 0.5)
				(thermal_bridge_width 0.5)
				(island_removal_mode 0)
			)
			(polygon
				(pts
					(xy 273.814032 -149.3139) (xy 273.814032 -150.3045) (xy 273.306032 -150.3045) (xy 273.306032 -149.3139)
				)
			)
		)
	)
	(footprint ""
		(layer "F.Cu")
		(at 201.396346 -52.7304 -90)
		(property "Reference" "RT2"
			(at 0 0 270)
			(layer "F.SilkS")
			(hide yes)
			(effects
				(font
					(size 1.27 1.27)
				)
			)
		)
		(property "Value" "*"
			(at -0.0254 -2.6289 270)
			(unlocked yes)
			(layer "F.Fab")
			(hide yes)
			(effects
				(font
					(size 1.27 1.016)
					(thickness 0.1524)
				)
			)
		)
		(property "Device Type" "1R3F-GP_RCL_GP-1R3F-GP,64.1R00A"
			(at -0.0254 -4.1529 270)
			(unlocked yes)
			(layer "F.Fab")
			(hide yes)
			(effects
				(font
					(size 1.27 1.016)
					(thickness 0.1524)
				)
			)
		)
		(duplicate_pad_numbers_are_jumpers no)
		(fp_line
			(start -0.4826 0)
			(end -0.2032 0)
			(stroke
				(width 0.2032)
				(type default)
			)
			(layer "F.SilkS")
		)
		(fp_line
			(start 0.2032 0)
			(end 0.4826 0)
			(stroke
				(width 0.2032)
				(type default)
			)
			(layer "F.SilkS")
		)
		(fp_rect
			(start -0.5842 1.3335)
			(end 0.5842 -1.3335)
			(stroke
				(width 0)
				(type default)
			)
			(fill no)
			(layer "F.CrtYd")
		)
		(fp_rect
			(start -0.5842 1.3335)
			(end 0.5842 -1.3335)
			(stroke
				(width 0)
				(type default)
			)
			(fill no)
			(layer "F.Fab")
		)
		(pad "1" smd custom
			(at 0 -0.762 270)
			(size 0.2159 0.2159)
			(layers "F.Cu" "F.Mask" "F.Paste")
			(net "VR_PVCCIN_CPU0_PHASE1_RC")
			(options
				(clearance outline)
				(anchor circle)
			)
			(primitives
				(gr_poly
					(pts
						(arc
							(start -0.3302 -0.4318)
							(mid -0.402042 -0.402042)
							(end -0.4318 -0.3302)
						)
						(arc
							(start -0.4318 0.3302)
							(mid -0.402042 0.402042)
							(end -0.3302 0.4318)
						)
						(arc
							(start 0.3302 0.4318)
							(mid 0.402042 0.402042)
							(end 0.4318 0.3302)
						)
						(arc
							(start 0.4318 -0.3302)
							(mid 0.402042 -0.402042)
							(end 0.3302 -0.4318)
						)
					)
					(width 0)
					(fill yes)
				)
			)
		)
		(pad "2" smd custom
			(at 0 0.762 270)
			(size 0.2159 0.2159)
			(layers "F.Cu" "F.Mask" "F.Paste")
			(net "GND")
			(options
				(clearance outline)
				(anchor circle)
			)
			(primitives
				(gr_poly
					(pts
						(arc
							(start -0.3302 -0.4318)
							(mid -0.402042 -0.402042)
							(end -0.4318 -0.3302)
						)
						(arc
							(start -0.4318 0.3302)
							(mid -0.402042 0.402042)
							(end -0.3302 0.4318)
						)
						(arc
							(start 0.3302 0.4318)
							(mid 0.402042 0.402042)
							(end 0.4318 0.3302)
						)
						(arc
							(start 0.4318 -0.3302)
							(mid 0.402042 -0.402042)
							(end 0.3302 -0.4318)
						)
					)
					(width 0)
					(fill yes)
				)
			)
		)
	)
	(footprint ""
		(layer "F.Cu")
		(at 22.225 -72.4662 90)
		(property "Reference" "R1D40"
			(at 0 0 90)
			(layer "F.SilkS")
			(hide yes)
			(effects
				(font
					(size 1.27 1.27)
				)
			)
		)
		(property "Value" ""
			(at 0 0 90)
			(layer "F.Fab")
			(effects
				(font
					(size 1.27 1.27)
				)
			)
		)
		(duplicate_pad_numbers_are_jumpers no)
		(fp_poly
			(pts
				(xy -0.2794 -0.1016) (xy 0.2794 -0.1016) (xy 0.2794 0.9906) (xy -0.2794 0.9906)
			)
			(stroke
				(width 0)
				(type default)
			)
			(fill no)
			(layer "F.CrtYd")
		)
		(fp_line
			(start 0.2794 -0.1016)
			(end -0.2794 -0.1016)
			(stroke
				(width 0.1)
				(type default)
			)
			(layer "F.Fab")
		)
		(fp_line
			(start -0.2794 -0.1016)
			(end -0.2794 0.9906)
			(stroke
				(width 0.1)
				(type default)
			)
			(layer "F.Fab")
		)
		(fp_line
			(start 0.2794 0.9906)
			(end 0.2794 -0.1016)
			(stroke
				(width 0.1)
				(type default)
			)
			(layer "F.Fab")
		)
		(fp_line
			(start -0.2794 0.9906)
			(end 0.2794 0.9906)
			(stroke
				(width 0.1)
				(type default)
			)
			(layer "F.Fab")
		)
		(pad "1" smd rect
			(at 0 0 90)
			(size 0.508 0.508)
			(layers "F.Cu" "F.Mask" "F.Paste")
			(net "A_HSC_PSET")
		)
		(pad "2" smd rect
			(at 0 0.889 90)
			(size 0.508 0.508)
			(layers "F.Cu" "F.Mask" "F.Paste")
			(net "AGND_HSC")
		)
		(zone
			(layer "F.Cu")
			(hatch none 0.5)
			(connect_pads
				(clearance 0)
			)
			(min_thickness 0.25)
			(keepout
				(tracks allowed)
				(vias not_allowed)
				(pads allowed)
				(copperpour not_allowed)
				(footprints allowed)
			)
			(placement
				(enabled no)
				(sheetname "")
			)
			(fill
				(thermal_gap 0.5)
				(thermal_bridge_width 0.5)
				(island_removal_mode 0)
			)
			(polygon
				(pts
					(xy 22.479 -72.2122) (xy 22.479 -72.7202) (xy 22.86 -72.7202) (xy 22.86 -72.2122)
				)
			)
		)
		(zone
			(layer "F.Cu")
			(hatch none 0.5)
			(connect_pads
				(clearance 0)
			)
			(min_thickness 0.25)
			(keepout
				(tracks not_allowed)
				(vias allowed)
				(pads allowed)
				(copperpour not_allowed)
				(footprints allowed)
			)
			(placement
				(enabled no)
				(sheetname "")
			)
			(fill
				(thermal_gap 0.5)
				(thermal_bridge_width 0.5)
				(island_removal_mode 0)
			)
			(polygon
				(pts
					(xy 22.86 -72.2122) (xy 22.86 -72.7202) (xy 22.479 -72.7202) (xy 22.479 -72.2122)
				)
			)
		)
	)
	(footprint ""
		(layer "F.Cu")
		(at 454.025 -150.241 180)
		(property "Reference" "R9A4"
			(at 0 0 180)
			(layer "F.SilkS")
			(hide yes)
			(effects
				(font
					(size 1.27 1.27)
				)
			)
		)
		(property "Value" ""
			(at 0 0 180)
			(layer "F.Fab")
			(effects
				(font
					(size 1.27 1.27)
				)
			)
		)
		(duplicate_pad_numbers_are_jumpers no)
		(fp_poly
			(pts
				(xy -0.2794 -0.1016) (xy 0.2794 -0.1016) (xy 0.2794 0.9906) (xy -0.2794 0.9906)
			)
			(stroke
				(width 0)
				(type default)
			)
			(fill no)
			(layer "F.CrtYd")
		)
		(fp_line
			(start 0.2794 0.9906)
			(end 0.2794 -0.1016)
			(stroke
				(width 0.1)
				(type default)
			)
			(layer "F.Fab")
		)
		(fp_line
			(start 0.2794 -0.1016)
			(end -0.2794 -0.1016)
			(stroke
				(width 0.1)
				(type default)
			)
			(layer "F.Fab")
		)
		(fp_line
			(start -0.2794 0.9906)
			(end 0.2794 0.9906)
			(stroke
				(width 0.1)
				(type default)
			)
			(layer "F.Fab")
		)
		(fp_line
			(start -0.2794 -0.1016)
			(end -0.2794 0.9906)
			(stroke
				(width 0.1)
				(type default)
			)
			(layer "F.Fab")
		)
		(pad "1" smd rect
			(at 0 0 180)
			(size 0.508 0.508)
			(layers "F.Cu" "F.Mask" "F.Paste")
			(net "CPU_XDP_PRESENT_N")
		)
		(pad "2" smd rect
			(at 0 0.889 180)
			(size 0.508 0.508)
			(layers "F.Cu" "F.Mask" "F.Paste")
			(net "PVCCIO_CPU0")
		)
		(zone
			(layer "F.Cu")
			(hatch none 0.5)
			(connect_pads
				(clearance 0)
			)
			(min_thickness 0.25)
			(keepout
				(tracks not_allowed)
				(vias allowed)
				(pads allowed)
				(copperpour not_allowed)
				(footprints allowed)
			)
			(placement
				(enabled no)
				(sheetname "")
			)
			(fill
				(thermal_gap 0.5)
				(thermal_bridge_width 0.5)
				(island_removal_mode 0)
			)
			(polygon
				(pts
					(xy 454.279 -150.876) (xy 453.771 -150.876) (xy 453.771 -150.495) (xy 454.279 -150.495)
				)
			)
		)
		(zone
			(layer "F.Cu")
			(hatch none 0.5)
			(connect_pads
				(clearance 0)
			)
			(min_thickness 0.25)
			(keepout
				(tracks allowed)
				(vias not_allowed)
				(pads allowed)
				(copperpour not_allowed)
				(footprints allowed)
			)
			(placement
				(enabled no)
				(sheetname "")
			)
			(fill
				(thermal_gap 0.5)
				(thermal_bridge_width 0.5)
				(island_removal_mode 0)
			)
			(polygon
				(pts
					(xy 454.279 -150.495) (xy 453.771 -150.495) (xy 453.771 -150.876) (xy 454.279 -150.876)
				)
			)
		)
	)
	(footprint ""
		(layer "F.Cu")
		(at 443.289944 -153.225246 90)
		(property "Reference" "FB25W1"
			(at 0 0 90)
			(layer "F.SilkS")
			(hide yes)
			(effects
				(font
					(size 1.27 1.27)
				)
			)
		)
		(property "Value" "*"
			(at -0.0127 -7.01675 90)
			(unlocked yes)
			(layer "F.Fab")
			(hide yes)
			(effects
				(font
					(size 0.889 0.889)
					(thickness 0.1524)
				)
			)
		)
		(property "Device Type" "BLM15AG121SN-1GP_DISCRET-G-BLMA"
			(at -0.0127 -8.54075 90)
			(unlocked yes)
			(layer "F.Fab")
			(hide yes)
			(effects
				(font
					(size 0.889 0.889)
					(thickness 0.1524)
				)
			)
		)
		(duplicate_pad_numbers_are_jumpers no)
		(fp_line
			(start 0.508 -0.9398)
			(end -0.508 -0.9398)
			(stroke
				(width 0.1524)
				(type default)
			)
			(layer "F.SilkS")
		)
		(fp_line
			(start -0.508 -0.9398)
			(end -0.508 0.9398)
			(stroke
				(width 0.1524)
				(type default)
			)
			(layer "F.SilkS")
		)
		(fp_line
			(start -0.508 0.9398)
			(end -0.508 0.8636)
			(stroke
				(width 0.1524)
				(type default)
			)
			(layer "F.SilkS")
		)
		(fp_rect
			(start -0.508 0.9398)
			(end 0.508 -0.9398)
			(stroke
				(width 0)
				(type default)
			)
			(fill no)
			(layer "F.CrtYd")
		)
		(fp_rect
			(start -0.508 0.9398)
			(end 0.508 -0.9398)
			(stroke
				(width 0)
				(type default)
			)
			(fill no)
			(layer "F.Fab")
		)
		(pad "1" smd custom
			(at 0 -0.4445 90)
			(size 0.1397 0.1397)
			(layers "F.Cu" "F.Mask" "F.Paste")
			(net "XDP_CPU_TCK0_R")
			(options
				(clearance outline)
				(anchor circle)
			)
			(primitives
				(gr_poly
					(pts
						(arc
							(start -0.1778 -0.2794)
							(mid -0.249642 -0.249642)
							(end -0.2794 -0.1778)
						)
						(arc
							(start -0.2794 0.1778)
							(mid -0.249642 0.249642)
							(end -0.1778 0.2794)
						)
						(arc
							(start 0.1778 0.2794)
							(mid 0.249642 0.249642)
							(end 0.2794 0.1778)
						)
						(arc
							(start 0.2794 -0.1778)
							(mid 0.249642 -0.249642)
							(end 0.1778 -0.2794)
						)
					)
					(width 0)
					(fill yes)
				)
			)
		)
		(pad "2" smd custom
			(at 0 0.4445 90)
			(size 0.1397 0.1397)
			(layers "F.Cu" "F.Mask" "F.Paste")
			(net "XDP_CPU_TCK0")
			(options
				(clearance outline)
				(anchor circle)
			)
			(primitives
				(gr_poly
					(pts
						(arc
							(start -0.1778 -0.2794)
							(mid -0.249642 -0.249642)
							(end -0.2794 -0.1778)
						)
						(arc
							(start -0.2794 0.1778)
							(mid -0.249642 0.249642)
							(end -0.1778 0.2794)
						)
						(arc
							(start 0.1778 0.2794)
							(mid 0.249642 0.249642)
							(end 0.2794 0.1778)
						)
						(arc
							(start 0.2794 -0.1778)
							(mid 0.249642 -0.249642)
							(end 0.1778 -0.2794)
						)
					)
					(width 0)
					(fill yes)
				)
			)
		)
	)
	(footprint ""
		(layer "F.Cu")
		(at 379.5522 -158.0896)
		(property "Reference" "C7A43"
			(at 0 0 0)
			(layer "F.SilkS")
			(hide yes)
			(effects
				(font
					(size 1.27 1.27)
				)
			)
		)
		(property "Value" ""
			(at 0 0 0)
			(layer "F.Fab")
			(effects
				(font
					(size 1.27 1.27)
				)
			)
		)
		(duplicate_pad_numbers_are_jumpers no)
		(fp_poly
			(pts
				(xy 0.3048 -0.1016) (xy 0.3048 0.9906) (xy -0.3048 0.9906) (xy -0.3048 -0.1016)
			)
			(stroke
				(width 0)
				(type default)
			)
			(fill no)
			(layer "F.CrtYd")
		)
		(fp_line
			(start -0.3048 -0.1016)
			(end -0.3048 0.9906)
			(stroke
				(width 0.1)
				(type default)
			)
			(layer "F.Fab")
		)
		(fp_line
			(start -0.3048 0.9906)
			(end 0.3048 0.9906)
			(stroke
				(width 0.1)
				(type default)
			)
			(layer "F.Fab")
		)
		(fp_line
			(start 0.3048 -0.1016)
			(end -0.3048 -0.1016)
			(stroke
				(width 0.1)
				(type default)
			)
			(layer "F.Fab")
		)
		(fp_line
			(start 0.3048 0.9906)
			(end 0.3048 -0.1016)
			(stroke
				(width 0.1)
				(type default)
			)
			(layer "F.Fab")
		)
		(pad "1" smd rect
			(at 0 0)
			(size 0.508 0.508)
			(layers "F.Cu" "F.Mask" "F.Paste")
			(net "VR_PVNN_PCH_PH1_BOOT")
		)
		(pad "2" smd rect
			(at 0 0.889)
			(size 0.508 0.508)
			(layers "F.Cu" "F.Mask" "F.Paste")
			(net "VR_PVNN_PCH_PH1_PHASE")
		)
		(zone
			(layer "F.Cu")
			(hatch none 0.5)
			(connect_pads
				(clearance 0)
			)
			(min_thickness 0.25)
			(keepout
				(tracks allowed)
				(vias not_allowed)
				(pads allowed)
				(copperpour not_allowed)
				(footprints allowed)
			)
			(placement
				(enabled no)
				(sheetname "")
			)
			(fill
				(thermal_gap 0.5)
				(thermal_bridge_width 0.5)
				(island_removal_mode 0)
			)
			(polygon
				(pts
					(xy 379.2982 -157.8356) (xy 379.8062 -157.8356) (xy 379.8062 -157.4546) (xy 379.2982 -157.4546)
				)
			)
		)
		(zone
			(layer "F.Cu")
			(hatch none 0.5)
			(connect_pads
				(clearance 0)
			)
			(min_thickness 0.25)
			(keepout
				(tracks not_allowed)
				(vias allowed)
				(pads allowed)
				(copperpour not_allowed)
				(footprints allowed)
			)
			(placement
				(enabled no)
				(sheetname "")
			)
			(fill
				(thermal_gap 0.5)
				(thermal_bridge_width 0.5)
				(island_removal_mode 0)
			)
			(polygon
				(pts
					(xy 379.2982 -157.4546) (xy 379.8062 -157.4546) (xy 379.8062 -157.8356) (xy 379.2982 -157.8356)
				)
			)
		)
	)
	(footprint ""
		(layer "F.Cu")
		(at 107.8611 -3.3528 90)
		(property "Reference" "C3G5"
			(at 1.848866 0.752348 90)
			(unlocked yes)
			(layer "F.SilkS")
			(effects
				(font
					(size 1.27 0.9652)
					(thickness 0.1524)
				)
			)
		)
		(property "Value" ""
			(at 0 0 90)
			(layer "F.Fab")
			(effects
				(font
					(size 1.27 1.27)
				)
			)
		)
		(duplicate_pad_numbers_are_jumpers no)
		(fp_rect
			(start -0.500126 1.598422)
			(end 0.500126 -0.201422)
			(stroke
				(width 0)
				(type default)
			)
			(fill no)
			(layer "F.CrtYd")
		)
		(fp_line
			(start 0.500126 -0.201422)
			(end 0.500126 1.598422)
			(stroke
				(width 0.1)
				(type default)
			)
			(layer "F.Fab")
		)
		(fp_line
			(start -0.500126 -0.201422)
			(end 0.500126 -0.201422)
			(stroke
				(width 0.1)
				(type default)
			)
			(layer "F.Fab")
		)
		(fp_line
			(start 0.500126 1.598422)
			(end -0.500126 1.598422)
			(stroke
				(width 0.1)
				(type default)
			)
			(layer "F.Fab")
		)
		(fp_line
			(start -0.500126 1.598422)
			(end -0.500126 -0.201422)
			(stroke
				(width 0.1)
				(type default)
			)
			(layer "F.Fab")
		)
		(pad "1" smd rect
			(at 0 0)
			(size 0.889 0.9906)
			(layers "F.Cu" "F.Mask" "F.Paste")
			(net "PVDDQ_GHJ")
		)
		(pad "2" smd rect
			(at 0 1.397)
			(size 0.889 0.9906)
			(layers "F.Cu" "F.Mask" "F.Paste")
			(net "GND")
		)
		(zone
			(layer "F.Cu")
			(hatch none 0.5)
			(connect_pads
				(clearance 0)
			)
			(min_thickness 0.25)
			(keepout
				(tracks not_allowed)
				(vias allowed)
				(pads allowed)
				(copperpour not_allowed)
				(footprints allowed)
			)
			(placement
				(enabled no)
				(sheetname "")
			)
			(fill
				(thermal_gap 0.5)
				(thermal_bridge_width 0.5)
				(island_removal_mode 0)
			)
			(polygon
				(pts
					(xy 108.8136 -2.8575) (xy 108.8136 -3.8481) (xy 108.3056 -3.8481) (xy 108.3056 -2.8575)
				)
			)
		)
		(zone
			(layer "F.Cu")
			(hatch none 0.5)
			(connect_pads
				(clearance 0)
			)
			(min_thickness 0.25)
			(keepout
				(tracks allowed)
				(vias not_allowed)
				(pads allowed)
				(copperpour not_allowed)
				(footprints allowed)
			)
			(placement
				(enabled no)
				(sheetname "")
			)
			(fill
				(thermal_gap 0.5)
				(thermal_bridge_width 0.5)
				(island_removal_mode 0)
			)
			(polygon
				(pts
					(xy 108.8136 -2.8575) (xy 108.8136 -3.8481) (xy 108.3056 -3.8481) (xy 108.3056 -2.8575)
				)
			)
		)
	)
	(footprint ""
		(layer "F.Cu")
		(at 422.2877 -104.267 -90)
		(property "Reference" "R6W27"
			(at -0.8382 -0.67818 270)
			(unlocked yes)
			(layer "F.SilkS")
			(effects
				(font
					(size 0.4064 0.254)
					(thickness 0.1524)
				)
				(justify left)
			)
		)
		(property "Value" ""
			(at 0 0 270)
			(layer "F.Fab")
			(effects
				(font
					(size 1.27 1.27)
				)
			)
		)
		(duplicate_pad_numbers_are_jumpers no)
		(fp_poly
			(pts
				(xy -0.2794 -0.1016) (xy 0.2794 -0.1016) (xy 0.2794 0.9906) (xy -0.2794 0.9906)
			)
			(stroke
				(width 0)
				(type default)
			)
			(fill no)
			(layer "F.CrtYd")
		)
		(fp_line
			(start -0.2794 0.9906)
			(end 0.2794 0.9906)
			(stroke
				(width 0.1)
				(type default)
			)
			(layer "F.Fab")
		)
		(fp_line
			(start 0.2794 0.9906)
			(end 0.2794 -0.1016)
			(stroke
				(width 0.1)
				(type default)
			)
			(layer "F.Fab")
		)
		(fp_line
			(start -0.2794 -0.1016)
			(end -0.2794 0.9906)
			(stroke
				(width 0.1)
				(type default)
			)
			(layer "F.Fab")
		)
		(fp_line
			(start 0.2794 -0.1016)
			(end -0.2794 -0.1016)
			(stroke
				(width 0.1)
				(type default)
			)
			(layer "F.Fab")
		)
		(pad "1" smd rect
			(at 0 0 270)
			(size 0.508 0.508)
			(layers "F.Cu" "F.Mask" "F.Paste")
			(net "SMB_CPU0_PE_HP_GTL_SDA")
		)
		(pad "2" smd rect
			(at 0 0.889 270)
			(size 0.508 0.508)
			(layers "F.Cu" "F.Mask" "F.Paste")
			(net "SMB_CPU0_PE_HP_GTL_R_SDA")
		)
		(zone
			(layer "F.Cu")
			(hatch none 0.5)
			(connect_pads
				(clearance 0)
			)
			(min_thickness 0.25)
			(keepout
				(tracks not_allowed)
				(vias allowed)
				(pads allowed)
				(copperpour not_allowed)
				(footprints allowed)
			)
			(placement
				(enabled no)
				(sheetname "")
			)
			(fill
				(thermal_gap 0.5)
				(thermal_bridge_width 0.5)
				(island_removal_mode 0)
			)
			(polygon
				(pts
					(xy 421.6527 -104.521) (xy 421.6527 -104.013) (xy 422.0337 -104.013) (xy 422.0337 -104.521)
				)
			)
		)
		(zone
			(layer "F.Cu")
			(hatch none 0.5)
			(connect_pads
				(clearance 0)
			)
			(min_thickness 0.25)
			(keepout
				(tracks allowed)
				(vias not_allowed)
				(pads allowed)
				(copperpour not_allowed)
				(footprints allowed)
			)
			(placement
				(enabled no)
				(sheetname "")
			)
			(fill
				(thermal_gap 0.5)
				(thermal_bridge_width 0.5)
				(island_removal_mode 0)
			)
			(polygon
				(pts
					(xy 422.0337 -104.521) (xy 422.0337 -104.013) (xy 421.6527 -104.013) (xy 421.6527 -104.521)
				)
			)
		)
	)
	(footprint ""
		(layer "F.Cu")
		(at 99.453192 -69.885814 -90)
		(property "Reference" "C2D41"
			(at 0 0 270)
			(layer "F.SilkS")
			(hide yes)
			(effects
				(font
					(size 1.27 1.27)
				)
			)
		)
		(property "Value" ""
			(at 0 0 270)
			(layer "F.Fab")
			(effects
				(font
					(size 1.27 1.27)
				)
			)
		)
		(duplicate_pad_numbers_are_jumpers no)
		(fp_poly
			(pts
				(xy -0.4953 -0.2032) (xy 0.4953 -0.2032) (xy 0.4953 1.6002) (xy -0.4953 1.6002)
			)
			(stroke
				(width 0)
				(type default)
			)
			(fill no)
			(layer "F.CrtYd")
		)
		(fp_line
			(start -0.4953 1.6002)
			(end -0.4953 -0.2032)
			(stroke
				(width 0.1)
				(type default)
			)
			(layer "F.Fab")
		)
		(fp_line
			(start 0.4953 1.6002)
			(end -0.4953 1.6002)
			(stroke
				(width 0.1)
				(type default)
			)
			(layer "F.Fab")
		)
		(fp_line
			(start -0.4953 -0.2032)
			(end 0.4953 -0.2032)
			(stroke
				(width 0.1)
				(type default)
			)
			(layer "F.Fab")
		)
		(fp_line
			(start 0.4953 -0.2032)
			(end 0.4953 1.6002)
			(stroke
				(width 0.1)
				(type default)
			)
			(layer "F.Fab")
		)
		(pad "1" smd rect
			(at 0 0 270)
			(size 0.762 0.889)
			(layers "F.Cu" "F.Mask" "F.Paste")
			(net "PVDDQ_GHJ")
		)
		(pad "2" smd rect
			(at 0 1.397 270)
			(size 0.762 0.889)
			(layers "F.Cu" "F.Mask" "F.Paste")
			(net "GND")
		)
		(zone
			(layer "F.Cu")
			(hatch none 0.5)
			(connect_pads
				(clearance 0)
			)
			(min_thickness 0.25)
			(keepout
				(tracks not_allowed)
				(vias allowed)
				(pads allowed)
				(copperpour not_allowed)
				(footprints allowed)
			)
			(placement
				(enabled no)
				(sheetname "")
			)
			(fill
				(thermal_gap 0.5)
				(thermal_bridge_width 0.5)
				(island_removal_mode 0)
			)
			(polygon
				(pts
					(xy 99.008692 -70.266814) (xy 99.008692 -69.504814) (xy 98.500692 -69.504814) (xy 98.500692 -70.266814)
				)
			)
		)
	)
	(footprint ""
		(layer "F.Cu")
		(at 155.0416 -130.3528 90)
		(property "Reference" "C3B2"
			(at 0 0 90)
			(layer "F.SilkS")
			(hide yes)
			(effects
				(font
					(size 1.27 1.27)
				)
			)
		)
		(property "Value" ""
			(at 0 0 90)
			(layer "F.Fab")
			(effects
				(font
					(size 1.27 1.27)
				)
			)
		)
		(duplicate_pad_numbers_are_jumpers no)
		(fp_rect
			(start -0.4953 1.6002)
			(end 0.4953 -0.2032)
			(stroke
				(width 0)
				(type default)
			)
			(fill no)
			(layer "F.CrtYd")
		)
		(fp_line
			(start 0.4953 -0.2032)
			(end 0.4953 1.6002)
			(stroke
				(width 0.1)
				(type default)
			)
			(layer "F.Fab")
		)
		(fp_line
			(start -0.4953 -0.2032)
			(end 0.4953 -0.2032)
			(stroke
				(width 0.1)
				(type default)
			)
			(layer "F.Fab")
		)
		(fp_line
			(start 0.4953 1.6002)
			(end -0.4953 1.6002)
			(stroke
				(width 0.1)
				(type default)
			)
			(layer "F.Fab")
		)
		(fp_line
			(start -0.4953 1.6002)
			(end -0.4953 -0.2032)
			(stroke
				(width 0.1)
				(type default)
			)
			(layer "F.Fab")
		)
		(pad "1" smd rect
			(at 0 0 90)
			(size 0.762 0.889)
			(layers "F.Cu" "F.Mask" "F.Paste")
			(net "PVPP_KLM")
		)
		(pad "2" smd rect
			(at 0 1.397 90)
			(size 0.762 0.889)
			(layers "F.Cu" "F.Mask" "F.Paste")
			(net "GND")
		)
		(zone
			(layer "F.Cu")
			(hatch none 0.5)
			(connect_pads
				(clearance 0)
			)
			(min_thickness 0.25)
			(keepout
				(tracks not_allowed)
				(vias allowed)
				(pads allowed)
				(copperpour not_allowed)
				(footprints allowed)
			)
			(placement
				(enabled no)
				(sheetname "")
			)
			(fill
				(thermal_gap 0.5)
				(thermal_bridge_width 0.5)
				(island_removal_mode 0)
			)
			(polygon
				(pts
					(xy 155.9941 -129.9718) (xy 155.9941 -130.7338) (xy 155.4861 -130.7338) (xy 155.4861 -129.9718)
				)
			)
		)
	)
	(footprint ""
		(layer "F.Cu")
		(at 14.529816 -2.086864 -90)
		(property "Reference" "R1G16"
			(at 0 0 270)
			(layer "F.SilkS")
			(hide yes)
			(effects
				(font
					(size 1.27 1.27)
				)
			)
		)
		(property "Value" ""
			(at 0 0 270)
			(layer "F.Fab")
			(effects
				(font
					(size 1.27 1.27)
				)
			)
		)
		(duplicate_pad_numbers_are_jumpers no)
		(fp_rect
			(start -0.2794 0.9906)
			(end 0.2794 -0.1016)
			(stroke
				(width 0)
				(type default)
			)
			(fill no)
			(layer "F.CrtYd")
		)
		(fp_line
			(start -0.2794 0.9906)
			(end 0.2794 0.9906)
			(stroke
				(width 0.1)
				(type default)
			)
			(layer "F.Fab")
		)
		(fp_line
			(start 0.2794 0.9906)
			(end 0.2794 -0.1016)
			(stroke
				(width 0.1)
				(type default)
			)
			(layer "F.Fab")
		)
		(fp_line
			(start -0.2794 -0.1016)
			(end -0.2794 0.9906)
			(stroke
				(width 0.1)
				(type default)
			)
			(layer "F.Fab")
		)
		(fp_line
			(start 0.2794 -0.1016)
			(end -0.2794 -0.1016)
			(stroke
				(width 0.1)
				(type default)
			)
			(layer "F.Fab")
		)
		(pad "1" smd rect
			(at 0 0 270)
			(size 0.508 0.508)
			(layers "F.Cu" "F.Mask" "F.Paste")
			(net "P3V3_STBY")
		)
		(pad "2" smd rect
			(at 0 0.889 270)
			(size 0.508 0.508)
			(layers "F.Cu" "F.Mask" "F.Paste")
			(net "PWRGD_PVDDQ_GHJ_R")
		)
		(zone
			(layer "F.Cu")
			(hatch none 0.5)
			(connect_pads
				(clearance 0)
			)
			(min_thickness 0.25)
			(keepout
				(tracks allowed)
				(vias not_allowed)
				(pads allowed)
				(copperpour not_allowed)
				(footprints allowed)
			)
			(placement
				(enabled no)
				(sheetname "")
			)
			(fill
				(thermal_gap 0.5)
				(thermal_bridge_width 0.5)
				(island_removal_mode 0)
			)
			(polygon
				(pts
					(xy 13.894816 -2.340864) (xy 13.894816 -1.832864) (xy 14.275816 -1.832864) (xy 14.275816 -2.340864)
				)
			)
		)
		(zone
			(layer "F.Cu")
			(hatch none 0.5)
			(connect_pads
				(clearance 0)
			)
			(min_thickness 0.25)
			(keepout
				(tracks not_allowed)
				(vias allowed)
				(pads allowed)
				(copperpour not_allowed)
				(footprints allowed)
			)
			(placement
				(enabled no)
				(sheetname "")
			)
			(fill
				(thermal_gap 0.5)
				(thermal_bridge_width 0.5)
				(island_removal_mode 0)
			)
			(polygon
				(pts
					(xy 13.894816 -2.340864) (xy 13.894816 -1.832864) (xy 14.275816 -1.832864) (xy 14.275816 -2.340864)
				)
			)
		)
	)
	(footprint ""
		(layer "F.Cu")
		(at 396.494 -66.1416 -90)
		(property "Reference" "R8E33"
			(at 0 0 270)
			(layer "F.SilkS")
			(hide yes)
			(effects
				(font
					(size 1.27 1.27)
				)
			)
		)
		(property "Value" ""
			(at 0 0 270)
			(layer "F.Fab")
			(effects
				(font
					(size 1.27 1.27)
				)
			)
		)
		(duplicate_pad_numbers_are_jumpers no)
		(fp_poly
			(pts
				(xy -0.2794 -0.1016) (xy 0.2794 -0.1016) (xy 0.2794 0.9906) (xy -0.2794 0.9906)
			)
			(stroke
				(width 0)
				(type default)
			)
			(fill no)
			(layer "F.CrtYd")
		)
		(fp_line
			(start -0.2794 0.9906)
			(end 0.2794 0.9906)
			(stroke
				(width 0.1)
				(type default)
			)
			(layer "F.Fab")
		)
		(fp_line
			(start 0.2794 0.9906)
			(end 0.2794 -0.1016)
			(stroke
				(width 0.1)
				(type default)
			)
			(layer "F.Fab")
		)
		(fp_line
			(start -0.2794 -0.1016)
			(end -0.2794 0.9906)
			(stroke
				(width 0.1)
				(type default)
			)
			(layer "F.Fab")
		)
		(fp_line
			(start 0.2794 -0.1016)
			(end -0.2794 -0.1016)
			(stroke
				(width 0.1)
				(type default)
			)
			(layer "F.Fab")
		)
		(pad "1" smd rect
			(at 0 0 270)
			(size 0.508 0.508)
			(layers "F.Cu" "F.Mask" "F.Paste")
			(net "PWRGD_P12V_HSC_DLY")
		)
		(pad "2" smd rect
			(at 0 0.889 270)
			(size 0.508 0.508)
			(layers "F.Cu" "F.Mask" "F.Paste")
			(net "VR_P5V_STBY_EN")
		)
		(zone
			(layer "F.Cu")
			(hatch none 0.5)
			(connect_pads
				(clearance 0)
			)
			(min_thickness 0.25)
			(keepout
				(tracks not_allowed)
				(vias allowed)
				(pads allowed)
				(copperpour not_allowed)
				(footprints allowed)
			)
			(placement
				(enabled no)
				(sheetname "")
			)
			(fill
				(thermal_gap 0.5)
				(thermal_bridge_width 0.5)
				(island_removal_mode 0)
			)
			(polygon
				(pts
					(xy 395.859 -66.3956) (xy 395.859 -65.8876) (xy 396.24 -65.8876) (xy 396.24 -66.3956)
				)
			)
		)
		(zone
			(layer "F.Cu")
			(hatch none 0.5)
			(connect_pads
				(clearance 0)
			)
			(min_thickness 0.25)
			(keepout
				(tracks allowed)
				(vias not_allowed)
				(pads allowed)
				(copperpour not_allowed)
				(footprints allowed)
			)
			(placement
				(enabled no)
				(sheetname "")
			)
			(fill
				(thermal_gap 0.5)
				(thermal_bridge_width 0.5)
				(island_removal_mode 0)
			)
			(polygon
				(pts
					(xy 396.24 -66.3956) (xy 396.24 -65.8876) (xy 395.859 -65.8876) (xy 395.859 -66.3956)
				)
			)
		)
	)
	(footprint ""
		(layer "F.Cu")
		(at 174.5996 -5.461 -90)
		(property "Reference" "R4G17"
			(at 0 0 270)
			(layer "F.SilkS")
			(hide yes)
			(effects
				(font
					(size 1.27 1.27)
				)
			)
		)
		(property "Value" ""
			(at 0 0 270)
			(layer "F.Fab")
			(effects
				(font
					(size 1.27 1.27)
				)
			)
		)
		(duplicate_pad_numbers_are_jumpers no)
		(fp_rect
			(start 0.2794 -0.1016)
			(end -0.2794 0.9906)
			(stroke
				(width 0)
				(type default)
			)
			(fill no)
			(layer "F.CrtYd")
		)
		(fp_line
			(start -0.2794 0.9906)
			(end 0.2794 0.9906)
			(stroke
				(width 0.1)
				(type default)
			)
			(layer "F.Fab")
		)
		(fp_line
			(start 0.2794 0.9906)
			(end 0.2794 -0.1016)
			(stroke
				(width 0.1)
				(type default)
			)
			(layer "F.Fab")
		)
		(fp_line
			(start -0.2794 -0.1016)
			(end -0.2794 0.9906)
			(stroke
				(width 0.1)
				(type default)
			)
			(layer "F.Fab")
		)
		(fp_line
			(start 0.2794 -0.1016)
			(end -0.2794 -0.1016)
			(stroke
				(width 0.1)
				(type default)
			)
			(layer "F.Fab")
		)
		(pad "1" smd rect
			(at 0 0 270)
			(size 0.508 0.508)
			(layers "F.Cu" "F.Mask" "F.Paste")
			(net "P3V3")
		)
		(pad "2" smd rect
			(at 0 0.889 270)
			(size 0.508 0.508)
			(layers "F.Cu" "F.Mask" "F.Paste")
			(net "PWRGD_PVTT_GHJ_CPU1_R")
		)
		(zone
			(layer "F.Cu")
			(hatch none 0.5)
			(connect_pads
				(clearance 0)
			)
			(min_thickness 0.25)
			(keepout
				(tracks allowed)
				(vias not_allowed)
				(pads allowed)
				(copperpour not_allowed)
				(footprints allowed)
			)
			(placement
				(enabled no)
				(sheetname "")
			)
			(fill
				(thermal_gap 0.5)
				(thermal_bridge_width 0.5)
				(island_removal_mode 0)
			)
			(polygon
				(pts
					(xy 174.3456 -5.207) (xy 174.3456 -5.715) (xy 173.9646 -5.715) (xy 173.9646 -5.207)
				)
			)
		)
		(zone
			(layer "F.Cu")
			(hatch none 0.5)
			(connect_pads
				(clearance 0)
			)
			(min_thickness 0.25)
			(keepout
				(tracks not_allowed)
				(vias allowed)
				(pads allowed)
				(copperpour not_allowed)
				(footprints allowed)
			)
			(placement
				(enabled no)
				(sheetname "")
			)
			(fill
				(thermal_gap 0.5)
				(thermal_bridge_width 0.5)
				(island_removal_mode 0)
			)
			(polygon
				(pts
					(xy 174.3456 -5.207) (xy 174.3456 -5.715) (xy 173.9646 -5.715) (xy 173.9646 -5.207)
				)
			)
		)
	)
	(footprint ""
		(layer "F.Cu")
		(at 411.80893 -134.699248 180)
		(property "Reference" "R8B2"
			(at 0 0 180)
			(layer "F.SilkS")
			(hide yes)
			(effects
				(font
					(size 1.27 1.27)
				)
			)
		)
		(property "Value" ""
			(at 0 0 180)
			(layer "F.Fab")
			(effects
				(font
					(size 1.27 1.27)
				)
			)
		)
		(duplicate_pad_numbers_are_jumpers no)
		(fp_poly
			(pts
				(xy -0.2794 -0.1016) (xy 0.2794 -0.1016) (xy 0.2794 0.9906) (xy -0.2794 0.9906)
			)
			(stroke
				(width 0)
				(type default)
			)
			(fill no)
			(layer "F.CrtYd")
		)
		(fp_line
			(start 0.2794 0.9906)
			(end 0.2794 -0.1016)
			(stroke
				(width 0.1)
				(type default)
			)
			(layer "F.Fab")
		)
		(fp_line
			(start 0.2794 -0.1016)
			(end -0.2794 -0.1016)
			(stroke
				(width 0.1)
				(type default)
			)
			(layer "F.Fab")
		)
		(fp_line
			(start -0.2794 0.9906)
			(end 0.2794 0.9906)
			(stroke
				(width 0.1)
				(type default)
			)
			(layer "F.Fab")
		)
		(fp_line
			(start -0.2794 -0.1016)
			(end -0.2794 0.9906)
			(stroke
				(width 0.1)
				(type default)
			)
			(layer "F.Fab")
		)
		(pad "1" smd rect
			(at 0 0 180)
			(size 0.508 0.508)
			(layers "F.Cu" "F.Mask" "F.Paste")
			(net "XDP_TRST_N")
		)
		(pad "2" smd rect
			(at 0 0.889 180)
			(size 0.508 0.508)
			(layers "F.Cu" "F.Mask" "F.Paste")
			(net "GND")
		)
		(zone
			(layer "F.Cu")
			(hatch none 0.5)
			(connect_pads
				(clearance 0)
			)
			(min_thickness 0.25)
			(keepout
				(tracks not_allowed)
				(vias allowed)
				(pads allowed)
				(copperpour not_allowed)
				(footprints allowed)
			)
			(placement
				(enabled no)
				(sheetname "")
			)
			(fill
				(thermal_gap 0.5)
				(thermal_bridge_width 0.5)
				(island_removal_mode 0)
			)
			(polygon
				(pts
					(xy 412.06293 -135.334248) (xy 411.55493 -135.334248) (xy 411.55493 -134.953248) (xy 412.06293 -134.953248)
				)
			)
		)
		(zone
			(layer "F.Cu")
			(hatch none 0.5)
			(connect_pads
				(clearance 0)
			)
			(min_thickness 0.25)
			(keepout
				(tracks allowed)
				(vias not_allowed)
				(pads allowed)
				(copperpour not_allowed)
				(footprints allowed)
			)
			(placement
				(enabled no)
				(sheetname "")
			)
			(fill
				(thermal_gap 0.5)
				(thermal_bridge_width 0.5)
				(island_removal_mode 0)
			)
			(polygon
				(pts
					(xy 412.06293 -134.953248) (xy 411.55493 -134.953248) (xy 411.55493 -135.334248) (xy 412.06293 -135.334248)
				)
			)
		)
	)
	(footprint ""
		(layer "F.Cu")
		(at 103.16464 -73.318116)
		(property "Reference" "C2D38"
			(at 0 0 0)
			(layer "F.SilkS")
			(hide yes)
			(effects
				(font
					(size 1.27 1.27)
				)
			)
		)
		(property "Value" ""
			(at 0 0 0)
			(layer "F.Fab")
			(effects
				(font
					(size 1.27 1.27)
				)
			)
		)
		(duplicate_pad_numbers_are_jumpers no)
		(fp_poly
			(pts
				(xy -0.4953 -0.2032) (xy 0.4953 -0.2032) (xy 0.4953 1.6002) (xy -0.4953 1.6002)
			)
			(stroke
				(width 0)
				(type default)
			)
			(fill no)
			(layer "F.CrtYd")
		)
		(fp_line
			(start -0.4953 -0.2032)
			(end 0.4953 -0.2032)
			(stroke
				(width 0.1)
				(type default)
			)
			(layer "F.Fab")
		)
		(fp_line
			(start -0.4953 1.6002)
			(end -0.4953 -0.2032)
			(stroke
				(width 0.1)
				(type default)
			)
			(layer "F.Fab")
		)
		(fp_line
			(start 0.4953 -0.2032)
			(end 0.4953 1.6002)
			(stroke
				(width 0.1)
				(type default)
			)
			(layer "F.Fab")
		)
		(fp_line
			(start 0.4953 1.6002)
			(end -0.4953 1.6002)
			(stroke
				(width 0.1)
				(type default)
			)
			(layer "F.Fab")
		)
		(pad "1" smd rect
			(at 0 0)
			(size 0.762 0.889)
			(layers "F.Cu" "F.Mask" "F.Paste")
			(net "PVCCIN_CPU1")
		)
		(pad "2" smd rect
			(at 0 1.397)
			(size 0.762 0.889)
			(layers "F.Cu" "F.Mask" "F.Paste")
			(net "GND")
		)
		(zone
			(layer "F.Cu")
			(hatch none 0.5)
			(connect_pads
				(clearance 0)
			)
			(min_thickness 0.25)
			(keepout
				(tracks not_allowed)
				(vias allowed)
				(pads allowed)
				(copperpour not_allowed)
				(footprints allowed)
			)
			(placement
				(enabled no)
				(sheetname "")
			)
			(fill
				(thermal_gap 0.5)
				(thermal_bridge_width 0.5)
				(island_removal_mode 0)
			)
			(polygon
				(pts
					(xy 102.78364 -72.873616) (xy 103.54564 -72.873616) (xy 103.54564 -72.365616) (xy 102.78364 -72.365616)
				)
			)
		)
	)
	(footprint ""
		(layer "F.Cu")
		(at 348.6658 -101.3714 90)
		(property "Reference" "C7C17"
			(at 0 0 90)
			(layer "F.SilkS")
			(hide yes)
			(effects
				(font
					(size 1.27 1.27)
				)
			)
		)
		(property "Value" ""
			(at 0 0 90)
			(layer "F.Fab")
			(effects
				(font
					(size 1.27 1.27)
				)
			)
		)
		(duplicate_pad_numbers_are_jumpers no)
		(fp_poly
			(pts
				(xy 0.3048 -0.1016) (xy 0.3048 0.9906) (xy -0.3048 0.9906) (xy -0.3048 -0.1016)
			)
			(stroke
				(width 0)
				(type default)
			)
			(fill no)
			(layer "F.CrtYd")
		)
		(fp_line
			(start 0.3048 -0.1016)
			(end -0.3048 -0.1016)
			(stroke
				(width 0.1)
				(type default)
			)
			(layer "F.Fab")
		)
		(fp_line
			(start -0.3048 -0.1016)
			(end -0.3048 0.9906)
			(stroke
				(width 0.1)
				(type default)
			)
			(layer "F.Fab")
		)
		(fp_line
			(start 0.3048 0.9906)
			(end 0.3048 -0.1016)
			(stroke
				(width 0.1)
				(type default)
			)
			(layer "F.Fab")
		)
		(fp_line
			(start -0.3048 0.9906)
			(end 0.3048 0.9906)
			(stroke
				(width 0.1)
				(type default)
			)
			(layer "F.Fab")
		)
		(pad "1" smd rect
			(at 0 0 90)
			(size 0.508 0.508)
			(layers "F.Cu" "F.Mask" "F.Paste")
			(net "VR_PVCCIO_CPU0_PH1_VCIN")
		)
		(pad "2" smd rect
			(at 0 0.889 90)
			(size 0.508 0.508)
			(layers "F.Cu" "F.Mask" "F.Paste")
			(net "GND")
		)
		(zone
			(layer "F.Cu")
			(hatch none 0.5)
			(connect_pads
				(clearance 0)
			)
			(min_thickness 0.25)
			(keepout
				(tracks allowed)
				(vias not_allowed)
				(pads allowed)
				(copperpour not_allowed)
				(footprints allowed)
			)
			(placement
				(enabled no)
				(sheetname "")
			)
			(fill
				(thermal_gap 0.5)
				(thermal_bridge_width 0.5)
				(island_removal_mode 0)
			)
			(polygon
				(pts
					(xy 348.9198 -101.1174) (xy 348.9198 -101.6254) (xy 349.3008 -101.6254) (xy 349.3008 -101.1174)
				)
			)
		)
		(zone
			(layer "F.Cu")
			(hatch none 0.5)
			(connect_pads
				(clearance 0)
			)
			(min_thickness 0.25)
			(keepout
				(tracks not_allowed)
				(vias allowed)
				(pads allowed)
				(copperpour not_allowed)
				(footprints allowed)
			)
			(placement
				(enabled no)
				(sheetname "")
			)
			(fill
				(thermal_gap 0.5)
				(thermal_bridge_width 0.5)
				(island_removal_mode 0)
			)
			(polygon
				(pts
					(xy 349.3008 -101.1174) (xy 349.3008 -101.6254) (xy 348.9198 -101.6254) (xy 348.9198 -101.1174)
				)
			)
		)
	)
	(footprint ""
		(layer "F.Cu")
		(at 316.73038 -34.936938 90)
		(property "Reference" "R6W29"
			(at -0.8382 -0.67818 90)
			(unlocked yes)
			(layer "F.SilkS")
			(effects
				(font
					(size 0.4064 0.254)
					(thickness 0.1524)
				)
				(justify left)
			)
		)
		(property "Value" ""
			(at 0 0 90)
			(layer "F.Fab")
			(effects
				(font
					(size 1.27 1.27)
				)
			)
		)
		(duplicate_pad_numbers_are_jumpers no)
		(fp_poly
			(pts
				(xy -0.2794 -0.1016) (xy 0.2794 -0.1016) (xy 0.2794 0.9906) (xy -0.2794 0.9906)
			)
			(stroke
				(width 0)
				(type default)
			)
			(fill no)
			(layer "F.CrtYd")
		)
		(fp_line
			(start 0.2794 -0.1016)
			(end -0.2794 -0.1016)
			(stroke
				(width 0.1)
				(type default)
			)
			(layer "F.Fab")
		)
		(fp_line
			(start -0.2794 -0.1016)
			(end -0.2794 0.9906)
			(stroke
				(width 0.1)
				(type default)
			)
			(layer "F.Fab")
		)
		(fp_line
			(start 0.2794 0.9906)
			(end 0.2794 -0.1016)
			(stroke
				(width 0.1)
				(type default)
			)
			(layer "F.Fab")
		)
		(fp_line
			(start -0.2794 0.9906)
			(end 0.2794 0.9906)
			(stroke
				(width 0.1)
				(type default)
			)
			(layer "F.Fab")
		)
		(pad "1" smd rect
			(at 0 0 90)
			(size 0.508 0.508)
			(layers "F.Cu" "F.Mask" "F.Paste")
			(net "PVPP_ABC")
		)
		(pad "2" smd rect
			(at 0 0.889 90)
			(size 0.508 0.508)
			(layers "F.Cu" "F.Mask" "F.Paste")
			(net "FM_ADR_COMPLETE_CPU1_N")
		)
		(zone
			(layer "F.Cu")
			(hatch none 0.5)
			(connect_pads
				(clearance 0)
			)
			(min_thickness 0.25)
			(keepout
				(tracks allowed)
				(vias not_allowed)
				(pads allowed)
				(copperpour not_allowed)
				(footprints allowed)
			)
			(placement
				(enabled no)
				(sheetname "")
			)
			(fill
				(thermal_gap 0.5)
				(thermal_bridge_width 0.5)
				(island_removal_mode 0)
			)
			(polygon
				(pts
					(xy 316.98438 -34.682938) (xy 316.98438 -35.190938) (xy 317.36538 -35.190938) (xy 317.36538 -34.682938)
				)
			)
		)
		(zone
			(layer "F.Cu")
			(hatch none 0.5)
			(connect_pads
				(clearance 0)
			)
			(min_thickness 0.25)
			(keepout
				(tracks not_allowed)
				(vias allowed)
				(pads allowed)
				(copperpour not_allowed)
				(footprints allowed)
			)
			(placement
				(enabled no)
				(sheetname "")
			)
			(fill
				(thermal_gap 0.5)
				(thermal_bridge_width 0.5)
				(island_removal_mode 0)
			)
			(polygon
				(pts
					(xy 317.36538 -34.682938) (xy 317.36538 -35.190938) (xy 316.98438 -35.190938) (xy 316.98438 -34.682938)
				)
			)
		)
	)
	(footprint ""
		(layer "F.Cu")
		(at 182.3466 -79.4258)
		(property "Reference" "R4D27"
			(at 0 0 0)
			(layer "F.SilkS")
			(hide yes)
			(effects
				(font
					(size 1.27 1.27)
				)
			)
		)
		(property "Value" ""
			(at 0 0 0)
			(layer "F.Fab")
			(effects
				(font
					(size 1.27 1.27)
				)
			)
		)
		(duplicate_pad_numbers_are_jumpers no)
		(fp_rect
			(start -0.2794 -0.1016)
			(end 0.2794 0.9906)
			(stroke
				(width 0)
				(type default)
			)
			(fill no)
			(layer "F.CrtYd")
		)
		(fp_line
			(start -0.2794 -0.1016)
			(end -0.2794 0.9906)
			(stroke
				(width 0.1)
				(type default)
			)
			(layer "F.Fab")
		)
		(fp_line
			(start -0.2794 0.9906)
			(end 0.2794 0.9906)
			(stroke
				(width 0.1)
				(type default)
			)
			(layer "F.Fab")
		)
		(fp_line
			(start 0.2794 -0.1016)
			(end -0.2794 -0.1016)
			(stroke
				(width 0.1)
				(type default)
			)
			(layer "F.Fab")
		)
		(fp_line
			(start 0.2794 0.9906)
			(end 0.2794 -0.1016)
			(stroke
				(width 0.1)
				(type default)
			)
			(layer "F.Fab")
		)
		(pad "1" smd rect
			(at 0 0)
			(size 0.508 0.508)
			(layers "F.Cu" "F.Mask" "F.Paste")
			(net "VR_FET_SW_P12V_STBY_PVCCIN_CPU0")
		)
		(pad "2" smd rect
			(at 0 0.889)
			(size 0.508 0.508)
			(layers "F.Cu" "F.Mask" "F.Paste")
			(net "VR_PVCCIN_CPU0_AVINSEN")
		)
		(zone
			(layer "F.Cu")
			(hatch none 0.5)
			(connect_pads
				(clearance 0)
			)
			(min_thickness 0.25)
			(keepout
				(tracks allowed)
				(vias not_allowed)
				(pads allowed)
				(copperpour not_allowed)
				(footprints allowed)
			)
			(placement
				(enabled no)
				(sheetname "")
			)
			(fill
				(thermal_gap 0.5)
				(thermal_bridge_width 0.5)
				(island_removal_mode 0)
			)
			(polygon
				(pts
					(xy 182.0926 -79.1718) (xy 182.0926 -78.7908) (xy 182.6006 -78.7908) (xy 182.6006 -79.1718)
				)
			)
		)
		(zone
			(layer "F.Cu")
			(hatch none 0.5)
			(connect_pads
				(clearance 0)
			)
			(min_thickness 0.25)
			(keepout
				(tracks not_allowed)
				(vias allowed)
				(pads allowed)
				(copperpour not_allowed)
				(footprints allowed)
			)
			(placement
				(enabled no)
				(sheetname "")
			)
			(fill
				(thermal_gap 0.5)
				(thermal_bridge_width 0.5)
				(island_removal_mode 0)
			)
			(polygon
				(pts
					(xy 182.0926 -79.1718) (xy 182.0926 -78.7908) (xy 182.6006 -78.7908) (xy 182.6006 -79.1718)
				)
			)
		)
	)
	(footprint ""
		(layer "F.Cu")
		(at 406.107646 -22.171152 180)
		(property "Reference" "R25W79"
			(at -0.8382 -0.67818 180)
			(unlocked yes)
			(layer "F.SilkS")
			(effects
				(font
					(size 0.4064 0.254)
					(thickness 0.1524)
				)
				(justify left)
			)
		)
		(property "Value" ""
			(at 0 0 180)
			(layer "F.Fab")
			(effects
				(font
					(size 1.27 1.27)
				)
			)
		)
		(duplicate_pad_numbers_are_jumpers no)
		(fp_poly
			(pts
				(xy -0.2794 -0.1016) (xy 0.2794 -0.1016) (xy 0.2794 0.9906) (xy -0.2794 0.9906)
			)
			(stroke
				(width 0)
				(type default)
			)
			(fill no)
			(layer "F.CrtYd")
		)
		(fp_line
			(start 0.2794 0.9906)
			(end 0.2794 -0.1016)
			(stroke
				(width 0.1)
				(type default)
			)
			(layer "F.Fab")
		)
		(fp_line
			(start 0.2794 -0.1016)
			(end -0.2794 -0.1016)
			(stroke
				(width 0.1)
				(type default)
			)
			(layer "F.Fab")
		)
		(fp_line
			(start -0.2794 0.9906)
			(end 0.2794 0.9906)
			(stroke
				(width 0.1)
				(type default)
			)
			(layer "F.Fab")
		)
		(fp_line
			(start -0.2794 -0.1016)
			(end -0.2794 0.9906)
			(stroke
				(width 0.1)
				(type default)
			)
			(layer "F.Fab")
		)
		(pad "1" smd rect
			(at 0 0 180)
			(size 0.508 0.508)
			(layers "F.Cu" "F.Mask" "F.Paste")
			(net "P3V3_STBY")
		)
		(pad "2" smd rect
			(at 0 0.889 180)
			(size 0.508 0.508)
			(layers "F.Cu" "F.Mask" "F.Paste")
			(net "RMII_SPRNGVLLE_BMC_PCH_RXD0")
		)
		(zone
			(layer "F.Cu")
			(hatch none 0.5)
			(connect_pads
				(clearance 0)
			)
			(min_thickness 0.25)
			(keepout
				(tracks not_allowed)
				(vias allowed)
				(pads allowed)
				(copperpour not_allowed)
				(footprints allowed)
			)
			(placement
				(enabled no)
				(sheetname "")
			)
			(fill
				(thermal_gap 0.5)
				(thermal_bridge_width 0.5)
				(island_removal_mode 0)
			)
			(polygon
				(pts
					(xy 406.361646 -22.806152) (xy 405.853646 -22.806152) (xy 405.853646 -22.425152) (xy 406.361646 -22.425152)
				)
			)
		)
		(zone
			(layer "F.Cu")
			(hatch none 0.5)
			(connect_pads
				(clearance 0)
			)
			(min_thickness 0.25)
			(keepout
				(tracks allowed)
				(vias not_allowed)
				(pads allowed)
				(copperpour not_allowed)
				(footprints allowed)
			)
			(placement
				(enabled no)
				(sheetname "")
			)
			(fill
				(thermal_gap 0.5)
				(thermal_bridge_width 0.5)
				(island_removal_mode 0)
			)
			(polygon
				(pts
					(xy 406.361646 -22.425152) (xy 405.853646 -22.425152) (xy 405.853646 -22.806152) (xy 406.361646 -22.806152)
				)
			)
		)
	)
	(footprint ""
		(layer "F.Cu")
		(at 20.6121 -86.0298 90)
		(property "Reference" "R1D10"
			(at 0 0 90)
			(layer "F.SilkS")
			(hide yes)
			(effects
				(font
					(size 1.27 1.27)
				)
			)
		)
		(property "Value" ""
			(at 0 0 90)
			(layer "F.Fab")
			(effects
				(font
					(size 1.27 1.27)
				)
			)
		)
		(duplicate_pad_numbers_are_jumpers no)
		(fp_poly
			(pts
				(xy -0.2794 -0.1016) (xy 0.2794 -0.1016) (xy 0.2794 0.9906) (xy -0.2794 0.9906)
			)
			(stroke
				(width 0)
				(type default)
			)
			(fill no)
			(layer "F.CrtYd")
		)
		(fp_line
			(start 0.2794 -0.1016)
			(end -0.2794 -0.1016)
			(stroke
				(width 0.1)
				(type default)
			)
			(layer "F.Fab")
		)
		(fp_line
			(start -0.2794 -0.1016)
			(end -0.2794 0.9906)
			(stroke
				(width 0.1)
				(type default)
			)
			(layer "F.Fab")
		)
		(fp_line
			(start 0.2794 0.9906)
			(end 0.2794 -0.1016)
			(stroke
				(width 0.1)
				(type default)
			)
			(layer "F.Fab")
		)
		(fp_line
			(start -0.2794 0.9906)
			(end 0.2794 0.9906)
			(stroke
				(width 0.1)
				(type default)
			)
			(layer "F.Fab")
		)
		(pad "1" smd rect
			(at 0 0 90)
			(size 0.508 0.508)
			(layers "F.Cu" "F.Mask" "F.Paste")
			(net "P3V3_STBY")
		)
		(pad "2" smd rect
			(at 0 0.889 90)
			(size 0.508 0.508)
			(layers "F.Cu" "F.Mask" "F.Paste")
			(net "A_HSC_LOW_GATE")
		)
		(zone
			(layer "F.Cu")
			(hatch none 0.5)
			(connect_pads
				(clearance 0)
			)
			(min_thickness 0.25)
			(keepout
				(tracks allowed)
				(vias not_allowed)
				(pads allowed)
				(copperpour not_allowed)
				(footprints allowed)
			)
			(placement
				(enabled no)
				(sheetname "")
			)
			(fill
				(thermal_gap 0.5)
				(thermal_bridge_width 0.5)
				(island_removal_mode 0)
			)
			(polygon
				(pts
					(xy 20.8661 -85.7758) (xy 20.8661 -86.2838) (xy 21.2471 -86.2838) (xy 21.2471 -85.7758)
				)
			)
		)
		(zone
			(layer "F.Cu")
			(hatch none 0.5)
			(connect_pads
				(clearance 0)
			)
			(min_thickness 0.25)
			(keepout
				(tracks not_allowed)
				(vias allowed)
				(pads allowed)
				(copperpour not_allowed)
				(footprints allowed)
			)
			(placement
				(enabled no)
				(sheetname "")
			)
			(fill
				(thermal_gap 0.5)
				(thermal_bridge_width 0.5)
				(island_removal_mode 0)
			)
			(polygon
				(pts
					(xy 21.2471 -85.7758) (xy 21.2471 -86.2838) (xy 20.8661 -86.2838) (xy 20.8661 -85.7758)
				)
			)
		)
	)
	(footprint ""
		(layer "F.Cu")
		(at 116.3066 -73.025 90)
		(property "Reference" "R3D16"
			(at 0 0 90)
			(layer "F.SilkS")
			(hide yes)
			(effects
				(font
					(size 1.27 1.27)
				)
			)
		)
		(property "Value" ""
			(at 0 0 90)
			(layer "F.Fab")
			(effects
				(font
					(size 1.27 1.27)
				)
			)
		)
		(duplicate_pad_numbers_are_jumpers no)
		(fp_poly
			(pts
				(xy -0.2794 -0.1016) (xy 0.2794 -0.1016) (xy 0.2794 0.9906) (xy -0.2794 0.9906)
			)
			(stroke
				(width 0)
				(type default)
			)
			(fill no)
			(layer "F.CrtYd")
		)
		(fp_line
			(start 0.2794 -0.1016)
			(end -0.2794 -0.1016)
			(stroke
				(width 0.1)
				(type default)
			)
			(layer "F.Fab")
		)
		(fp_line
			(start -0.2794 -0.1016)
			(end -0.2794 0.9906)
			(stroke
				(width 0.1)
				(type default)
			)
			(layer "F.Fab")
		)
		(fp_line
			(start 0.2794 0.9906)
			(end 0.2794 -0.1016)
			(stroke
				(width 0.1)
				(type default)
			)
			(layer "F.Fab")
		)
		(fp_line
			(start -0.2794 0.9906)
			(end 0.2794 0.9906)
			(stroke
				(width 0.1)
				(type default)
			)
			(layer "F.Fab")
		)
		(pad "1" smd rect
			(at 0 0 90)
			(size 0.508 0.508)
			(layers "F.Cu" "F.Mask" "F.Paste")
			(net "PVCCIO_CPU1")
		)
		(pad "2" smd rect
			(at 0 0.889 90)
			(size 0.508 0.508)
			(layers "F.Cu" "F.Mask" "F.Paste")
			(net "H_CPU1_BMCINIT")
		)
		(zone
			(layer "F.Cu")
			(hatch none 0.5)
			(connect_pads
				(clearance 0)
			)
			(min_thickness 0.25)
			(keepout
				(tracks allowed)
				(vias not_allowed)
				(pads allowed)
				(copperpour not_allowed)
				(footprints allowed)
			)
			(placement
				(enabled no)
				(sheetname "")
			)
			(fill
				(thermal_gap 0.5)
				(thermal_bridge_width 0.5)
				(island_removal_mode 0)
			)
			(polygon
				(pts
					(xy 116.5606 -72.771) (xy 116.5606 -73.279) (xy 116.9416 -73.279) (xy 116.9416 -72.771)
				)
			)
		)
		(zone
			(layer "F.Cu")
			(hatch none 0.5)
			(connect_pads
				(clearance 0)
			)
			(min_thickness 0.25)
			(keepout
				(tracks not_allowed)
				(vias allowed)
				(pads allowed)
				(copperpour not_allowed)
				(footprints allowed)
			)
			(placement
				(enabled no)
				(sheetname "")
			)
			(fill
				(thermal_gap 0.5)
				(thermal_bridge_width 0.5)
				(island_removal_mode 0)
			)
			(polygon
				(pts
					(xy 116.9416 -72.771) (xy 116.9416 -73.279) (xy 116.5606 -73.279) (xy 116.5606 -72.771)
				)
			)
		)
	)
	(footprint ""
		(layer "F.Cu")
		(at 29.083 -76.454 -90)
		(property "Reference" "C1D23"
			(at 0 0 270)
			(layer "F.SilkS")
			(hide yes)
			(effects
				(font
					(size 1.27 1.27)
				)
			)
		)
		(property "Value" ""
			(at 0 0 270)
			(layer "F.Fab")
			(effects
				(font
					(size 1.27 1.27)
				)
			)
		)
		(duplicate_pad_numbers_are_jumpers no)
		(fp_rect
			(start 0.3048 -0.1016)
			(end -0.3048 0.9906)
			(stroke
				(width 0)
				(type default)
			)
			(fill no)
			(layer "F.CrtYd")
		)
		(fp_line
			(start -0.3048 0.9906)
			(end 0.3048 0.9906)
			(stroke
				(width 0.1)
				(type default)
			)
			(layer "F.Fab")
		)
		(fp_line
			(start 0.3048 0.9906)
			(end 0.3048 -0.1016)
			(stroke
				(width 0.1)
				(type default)
			)
			(layer "F.Fab")
		)
		(fp_line
			(start -0.3048 -0.1016)
			(end -0.3048 0.9906)
			(stroke
				(width 0.1)
				(type default)
			)
			(layer "F.Fab")
		)
		(fp_line
			(start 0.3048 -0.1016)
			(end -0.3048 -0.1016)
			(stroke
				(width 0.1)
				(type default)
			)
			(layer "F.Fab")
		)
		(pad "1" smd rect
			(at 0 0 270)
			(size 0.508 0.508)
			(layers "F.Cu" "F.Mask" "F.Paste")
			(net "VR_FET_SW_P12V_STBY_PVCCIN_CPU1")
		)
		(pad "2" smd rect
			(at 0 0.889 270)
			(size 0.508 0.508)
			(layers "F.Cu" "F.Mask" "F.Paste")
			(net "GND")
		)
		(zone
			(layer "F.Cu")
			(hatch none 0.5)
			(connect_pads
				(clearance 0)
			)
			(min_thickness 0.25)
			(keepout
				(tracks allowed)
				(vias not_allowed)
				(pads allowed)
				(copperpour not_allowed)
				(footprints allowed)
			)
			(placement
				(enabled no)
				(sheetname "")
			)
			(fill
				(thermal_gap 0.5)
				(thermal_bridge_width 0.5)
				(island_removal_mode 0)
			)
			(polygon
				(pts
					(xy 28.829 -76.2) (xy 28.829 -76.708) (xy 28.448 -76.708) (xy 28.448 -76.2)
				)
			)
		)
		(zone
			(layer "F.Cu")
			(hatch none 0.5)
			(connect_pads
				(clearance 0)
			)
			(min_thickness 0.25)
			(keepout
				(tracks not_allowed)
				(vias allowed)
				(pads allowed)
				(copperpour not_allowed)
				(footprints allowed)
			)
			(placement
				(enabled no)
				(sheetname "")
			)
			(fill
				(thermal_gap 0.5)
				(thermal_bridge_width 0.5)
				(island_removal_mode 0)
			)
			(polygon
				(pts
					(xy 28.829 -76.2) (xy 28.829 -76.708) (xy 28.448 -76.708) (xy 28.448 -76.2)
				)
			)
		)
	)
	(footprint ""
		(layer "F.Cu")
		(at 467.106 -129.413 180)
		(property "Reference" "R9B13"
			(at 0 0 180)
			(layer "F.SilkS")
			(hide yes)
			(effects
				(font
					(size 1.27 1.27)
				)
			)
		)
		(property "Value" ""
			(at 0 0 180)
			(layer "F.Fab")
			(effects
				(font
					(size 1.27 1.27)
				)
			)
		)
		(duplicate_pad_numbers_are_jumpers no)
		(fp_poly
			(pts
				(xy -0.2794 -0.1016) (xy 0.2794 -0.1016) (xy 0.2794 0.9906) (xy -0.2794 0.9906)
			)
			(stroke
				(width 0)
				(type default)
			)
			(fill no)
			(layer "F.CrtYd")
		)
		(fp_line
			(start 0.2794 0.9906)
			(end 0.2794 -0.1016)
			(stroke
				(width 0.1)
				(type default)
			)
			(layer "F.Fab")
		)
		(fp_line
			(start 0.2794 -0.1016)
			(end -0.2794 -0.1016)
			(stroke
				(width 0.1)
				(type default)
			)
			(layer "F.Fab")
		)
		(fp_line
			(start -0.2794 0.9906)
			(end 0.2794 0.9906)
			(stroke
				(width 0.1)
				(type default)
			)
			(layer "F.Fab")
		)
		(fp_line
			(start -0.2794 -0.1016)
			(end -0.2794 0.9906)
			(stroke
				(width 0.1)
				(type default)
			)
			(layer "F.Fab")
		)
		(pad "1" smd rect
			(at 0 0 180)
			(size 0.508 0.508)
			(layers "F.Cu" "F.Mask" "F.Paste")
			(net "JTAG_MCP_TMS")
		)
		(pad "2" smd rect
			(at 0 0.889 180)
			(size 0.508 0.508)
			(layers "F.Cu" "F.Mask" "F.Paste")
			(net "JTAG_MCP_TMS_R")
		)
		(zone
			(layer "F.Cu")
			(hatch none 0.5)
			(connect_pads
				(clearance 0)
			)
			(min_thickness 0.25)
			(keepout
				(tracks not_allowed)
				(vias allowed)
				(pads allowed)
				(copperpour not_allowed)
				(footprints allowed)
			)
			(placement
				(enabled no)
				(sheetname "")
			)
			(fill
				(thermal_gap 0.5)
				(thermal_bridge_width 0.5)
				(island_removal_mode 0)
			)
			(polygon
				(pts
					(xy 467.36 -130.048) (xy 466.852 -130.048) (xy 466.852 -129.667) (xy 467.36 -129.667)
				)
			)
		)
		(zone
			(layer "F.Cu")
			(hatch none 0.5)
			(connect_pads
				(clearance 0)
			)
			(min_thickness 0.25)
			(keepout
				(tracks allowed)
				(vias not_allowed)
				(pads allowed)
				(copperpour not_allowed)
				(footprints allowed)
			)
			(placement
				(enabled no)
				(sheetname "")
			)
			(fill
				(thermal_gap 0.5)
				(thermal_bridge_width 0.5)
				(island_removal_mode 0)
			)
			(polygon
				(pts
					(xy 467.36 -129.667) (xy 466.852 -129.667) (xy 466.852 -130.048) (xy 467.36 -130.048)
				)
			)
		)
	)
	(footprint ""
		(layer "F.Cu")
		(at 260.697472 -77.636116)
		(property "Reference" "C5D26"
			(at 0 0 0)
			(layer "F.SilkS")
			(hide yes)
			(effects
				(font
					(size 1.27 1.27)
				)
			)
		)
		(property "Value" ""
			(at 0 0 0)
			(layer "F.Fab")
			(effects
				(font
					(size 1.27 1.27)
				)
			)
		)
		(duplicate_pad_numbers_are_jumpers no)
		(fp_poly
			(pts
				(xy -0.4953 -0.2032) (xy 0.4953 -0.2032) (xy 0.4953 1.6002) (xy -0.4953 1.6002)
			)
			(stroke
				(width 0)
				(type default)
			)
			(fill no)
			(layer "F.CrtYd")
		)
		(fp_line
			(start -0.4953 -0.2032)
			(end 0.4953 -0.2032)
			(stroke
				(width 0.1)
				(type default)
			)
			(layer "F.Fab")
		)
		(fp_line
			(start -0.4953 1.6002)
			(end -0.4953 -0.2032)
			(stroke
				(width 0.1)
				(type default)
			)
			(layer "F.Fab")
		)
		(fp_line
			(start 0.4953 -0.2032)
			(end 0.4953 1.6002)
			(stroke
				(width 0.1)
				(type default)
			)
			(layer "F.Fab")
		)
		(fp_line
			(start 0.4953 1.6002)
			(end -0.4953 1.6002)
			(stroke
				(width 0.1)
				(type default)
			)
			(layer "F.Fab")
		)
		(pad "1" smd rect
			(at 0 0)
			(size 0.762 0.889)
			(layers "F.Cu" "F.Mask" "F.Paste")
			(net "PVCCIN_CPU0")
		)
		(pad "2" smd rect
			(at 0 1.397)
			(size 0.762 0.889)
			(layers "F.Cu" "F.Mask" "F.Paste")
			(net "GND")
		)
		(zone
			(layer "F.Cu")
			(hatch none 0.5)
			(connect_pads
				(clearance 0)
			)
			(min_thickness 0.25)
			(keepout
				(tracks not_allowed)
				(vias allowed)
				(pads allowed)
				(copperpour not_allowed)
				(footprints allowed)
			)
			(placement
				(enabled no)
				(sheetname "")
			)
			(fill
				(thermal_gap 0.5)
				(thermal_bridge_width 0.5)
				(island_removal_mode 0)
			)
			(polygon
				(pts
					(xy 260.316472 -77.191616) (xy 261.078472 -77.191616) (xy 261.078472 -76.683616) (xy 260.316472 -76.683616)
				)
			)
		)
	)
	(footprint ""
		(layer "F.Cu")
		(at 18.288 -100.33)
		(property "Reference" "R1C13"
			(at 0 0 0)
			(layer "F.SilkS")
			(hide yes)
			(effects
				(font
					(size 1.27 1.27)
				)
			)
		)
		(property "Value" ""
			(at 0 0 0)
			(layer "F.Fab")
			(effects
				(font
					(size 1.27 1.27)
				)
			)
		)
		(duplicate_pad_numbers_are_jumpers no)
		(fp_rect
			(start -0.2794 -0.1016)
			(end 0.2794 0.9906)
			(stroke
				(width 0)
				(type default)
			)
			(fill no)
			(layer "F.CrtYd")
		)
		(fp_line
			(start -0.2794 -0.1016)
			(end -0.2794 0.9906)
			(stroke
				(width 0.1)
				(type default)
			)
			(layer "F.Fab")
		)
		(fp_line
			(start -0.2794 0.9906)
			(end 0.2794 0.9906)
			(stroke
				(width 0.1)
				(type default)
			)
			(layer "F.Fab")
		)
		(fp_line
			(start 0.2794 -0.1016)
			(end -0.2794 -0.1016)
			(stroke
				(width 0.1)
				(type default)
			)
			(layer "F.Fab")
		)
		(fp_line
			(start 0.2794 0.9906)
			(end 0.2794 -0.1016)
			(stroke
				(width 0.1)
				(type default)
			)
			(layer "F.Fab")
		)
		(pad "1" smd rect
			(at 0 0)
			(size 0.508 0.508)
			(layers "F.Cu" "F.Mask" "F.Paste")
			(net "VR_FET_SW_P12V_STBY_PVCCIN_CPU1")
		)
		(pad "2" smd rect
			(at 0 0.889)
			(size 0.508 0.508)
			(layers "F.Cu" "F.Mask" "F.Paste")
			(net "VR_PVCCIN_CPU1_AVINSEN")
		)
		(zone
			(layer "F.Cu")
			(hatch none 0.5)
			(connect_pads
				(clearance 0)
			)
			(min_thickness 0.25)
			(keepout
				(tracks not_allowed)
				(vias allowed)
				(pads allowed)
				(copperpour not_allowed)
				(footprints allowed)
			)
			(placement
				(enabled no)
				(sheetname "")
			)
			(fill
				(thermal_gap 0.5)
				(thermal_bridge_width 0.5)
				(island_removal_mode 0)
			)
			(polygon
				(pts
					(xy 18.034 -100.076) (xy 18.034 -99.695) (xy 18.542 -99.695) (xy 18.542 -100.076)
				)
			)
		)
		(zone
			(layer "F.Cu")
			(hatch none 0.5)
			(connect_pads
				(clearance 0)
			)
			(min_thickness 0.25)
			(keepout
				(tracks allowed)
				(vias not_allowed)
				(pads allowed)
				(copperpour not_allowed)
				(footprints allowed)
			)
			(placement
				(enabled no)
				(sheetname "")
			)
			(fill
				(thermal_gap 0.5)
				(thermal_bridge_width 0.5)
				(island_removal_mode 0)
			)
			(polygon
				(pts
					(xy 18.034 -100.076) (xy 18.034 -99.695) (xy 18.542 -99.695) (xy 18.542 -100.076)
				)
			)
		)
	)
	(footprint ""
		(layer "F.Cu")
		(at 95.69704 -73.318116)
		(property "Reference" "C2D32"
			(at 0 0 0)
			(layer "F.SilkS")
			(hide yes)
			(effects
				(font
					(size 1.27 1.27)
				)
			)
		)
		(property "Value" ""
			(at 0 0 0)
			(layer "F.Fab")
			(effects
				(font
					(size 1.27 1.27)
				)
			)
		)
		(duplicate_pad_numbers_are_jumpers no)
		(fp_poly
			(pts
				(xy -0.4953 -0.2032) (xy 0.4953 -0.2032) (xy 0.4953 1.6002) (xy -0.4953 1.6002)
			)
			(stroke
				(width 0)
				(type default)
			)
			(fill no)
			(layer "F.CrtYd")
		)
		(fp_line
			(start -0.4953 -0.2032)
			(end 0.4953 -0.2032)
			(stroke
				(width 0.1)
				(type default)
			)
			(layer "F.Fab")
		)
		(fp_line
			(start -0.4953 1.6002)
			(end -0.4953 -0.2032)
			(stroke
				(width 0.1)
				(type default)
			)
			(layer "F.Fab")
		)
		(fp_line
			(start 0.4953 -0.2032)
			(end 0.4953 1.6002)
			(stroke
				(width 0.1)
				(type default)
			)
			(layer "F.Fab")
		)
		(fp_line
			(start 0.4953 1.6002)
			(end -0.4953 1.6002)
			(stroke
				(width 0.1)
				(type default)
			)
			(layer "F.Fab")
		)
		(pad "1" smd rect
			(at 0 0)
			(size 0.762 0.889)
			(layers "F.Cu" "F.Mask" "F.Paste")
			(net "PVCCIN_CPU1")
		)
		(pad "2" smd rect
			(at 0 1.397)
			(size 0.762 0.889)
			(layers "F.Cu" "F.Mask" "F.Paste")
			(net "GND")
		)
		(zone
			(layer "F.Cu")
			(hatch none 0.5)
			(connect_pads
				(clearance 0)
			)
			(min_thickness 0.25)
			(keepout
				(tracks not_allowed)
				(vias allowed)
				(pads allowed)
				(copperpour not_allowed)
				(footprints allowed)
			)
			(placement
				(enabled no)
				(sheetname "")
			)
			(fill
				(thermal_gap 0.5)
				(thermal_bridge_width 0.5)
				(island_removal_mode 0)
			)
			(polygon
				(pts
					(xy 95.31604 -72.873616) (xy 96.07804 -72.873616) (xy 96.07804 -72.365616) (xy 95.31604 -72.365616)
				)
			)
		)
	)
	(footprint ""
		(layer "F.Cu")
		(at 26.924 -3.766312)
		(property "Reference" "C1G18"
			(at 0 0 0)
			(layer "F.SilkS")
			(hide yes)
			(effects
				(font
					(size 1.27 1.27)
				)
			)
		)
		(property "Value" ""
			(at 0 0 0)
			(layer "F.Fab")
			(effects
				(font
					(size 1.27 1.27)
				)
			)
		)
		(duplicate_pad_numbers_are_jumpers no)
		(fp_poly
			(pts
				(xy 0.3048 -0.1016) (xy 0.3048 0.9906) (xy -0.3048 0.9906) (xy -0.3048 -0.1016)
			)
			(stroke
				(width 0)
				(type default)
			)
			(fill no)
			(layer "F.CrtYd")
		)
		(fp_line
			(start -0.3048 -0.1016)
			(end -0.3048 0.9906)
			(stroke
				(width 0.1)
				(type default)
			)
			(layer "F.Fab")
		)
		(fp_line
			(start -0.3048 0.9906)
			(end 0.3048 0.9906)
			(stroke
				(width 0.1)
				(type default)
			)
			(layer "F.Fab")
		)
		(fp_line
			(start 0.3048 -0.1016)
			(end -0.3048 -0.1016)
			(stroke
				(width 0.1)
				(type default)
			)
			(layer "F.Fab")
		)
		(fp_line
			(start 0.3048 0.9906)
			(end 0.3048 -0.1016)
			(stroke
				(width 0.1)
				(type default)
			)
			(layer "F.Fab")
		)
		(pad "1" smd rect
			(at 0 0)
			(size 0.508 0.508)
			(layers "F.Cu" "F.Mask" "F.Paste")
			(net "M_J_CPU_VREF")
		)
		(pad "2" smd rect
			(at 0 0.889)
			(size 0.508 0.508)
			(layers "F.Cu" "F.Mask" "F.Paste")
			(net "GND")
		)
		(zone
			(layer "F.Cu")
			(hatch none 0.5)
			(connect_pads
				(clearance 0)
			)
			(min_thickness 0.25)
			(keepout
				(tracks allowed)
				(vias not_allowed)
				(pads allowed)
				(copperpour not_allowed)
				(footprints allowed)
			)
			(placement
				(enabled no)
				(sheetname "")
			)
			(fill
				(thermal_gap 0.5)
				(thermal_bridge_width 0.5)
				(island_removal_mode 0)
			)
			(polygon
				(pts
					(xy 26.67 -3.512312) (xy 27.178 -3.512312) (xy 27.178 -3.131312) (xy 26.67 -3.131312)
				)
			)
		)
		(zone
			(layer "F.Cu")
			(hatch none 0.5)
			(connect_pads
				(clearance 0)
			)
			(min_thickness 0.25)
			(keepout
				(tracks not_allowed)
				(vias allowed)
				(pads allowed)
				(copperpour not_allowed)
				(footprints allowed)
			)
			(placement
				(enabled no)
				(sheetname "")
			)
			(fill
				(thermal_gap 0.5)
				(thermal_bridge_width 0.5)
				(island_removal_mode 0)
			)
			(polygon
				(pts
					(xy 26.67 -3.131312) (xy 27.178 -3.131312) (xy 27.178 -3.512312) (xy 26.67 -3.512312)
				)
			)
		)
	)
	(footprint ""
		(layer "F.Cu")
		(at 32.289496 -61.095382 -90)
		(property "Reference" "C1E24"
			(at 0 0 270)
			(layer "F.SilkS")
			(hide yes)
			(effects
				(font
					(size 1.27 1.27)
				)
			)
		)
		(property "Value" ""
			(at 0 0 270)
			(layer "F.Fab")
			(effects
				(font
					(size 1.27 1.27)
				)
			)
		)
		(duplicate_pad_numbers_are_jumpers no)
		(fp_rect
			(start 0.3048 0.9906)
			(end -0.3048 -0.1016)
			(stroke
				(width 0)
				(type default)
			)
			(fill no)
			(layer "F.CrtYd")
		)
		(fp_line
			(start -0.3048 0.9906)
			(end 0.3048 0.9906)
			(stroke
				(width 0.1)
				(type default)
			)
			(layer "F.Fab")
		)
		(fp_line
			(start 0.3048 0.9906)
			(end 0.3048 -0.1016)
			(stroke
				(width 0.1)
				(type default)
			)
			(layer "F.Fab")
		)
		(fp_line
			(start -0.3048 -0.1016)
			(end -0.3048 0.9906)
			(stroke
				(width 0.1)
				(type default)
			)
			(layer "F.Fab")
		)
		(fp_line
			(start 0.3048 -0.1016)
			(end -0.3048 -0.1016)
			(stroke
				(width 0.1)
				(type default)
			)
			(layer "F.Fab")
		)
		(pad "1" smd rect
			(at 0 0 270)
			(size 0.508 0.508)
			(layers "F.Cu" "F.Mask" "F.Paste")
			(net "VR_PVCCIN_CPU1_PH2_VCIN")
		)
		(pad "2" smd rect
			(at 0 0.889 270)
			(size 0.508 0.508)
			(layers "F.Cu" "F.Mask" "F.Paste")
			(net "GND")
		)
		(zone
			(layer "F.Cu")
			(hatch none 0.5)
			(connect_pads
				(clearance 0)
			)
			(min_thickness 0.25)
			(keepout
				(tracks not_allowed)
				(vias allowed)
				(pads allowed)
				(copperpour not_allowed)
				(footprints allowed)
			)
			(placement
				(enabled no)
				(sheetname "")
			)
			(fill
				(thermal_gap 0.5)
				(thermal_bridge_width 0.5)
				(island_removal_mode 0)
			)
			(polygon
				(pts
					(xy 31.654496 -60.841382) (xy 32.035496 -60.841382) (xy 32.035496 -61.349382) (xy 31.654496 -61.349382)
				)
			)
		)
		(zone
			(layer "F.Cu")
			(hatch none 0.5)
			(connect_pads
				(clearance 0)
			)
			(min_thickness 0.25)
			(keepout
				(tracks allowed)
				(vias not_allowed)
				(pads allowed)
				(copperpour not_allowed)
				(footprints allowed)
			)
			(placement
				(enabled no)
				(sheetname "")
			)
			(fill
				(thermal_gap 0.5)
				(thermal_bridge_width 0.5)
				(island_removal_mode 0)
			)
			(polygon
				(pts
					(xy 31.654496 -60.841382) (xy 32.035496 -60.841382) (xy 32.035496 -61.349382) (xy 31.654496 -61.349382)
				)
			)
		)
	)
	(footprint ""
		(layer "F.Cu")
		(at 185.928 -100.838 90)
		(property "Reference" "L4C1"
			(at 0 0 90)
			(layer "F.SilkS")
			(hide yes)
			(effects
				(font
					(size 1.27 1.27)
				)
			)
		)
		(property "Value" "*"
			(at 4.9784 -0.6477 90)
			(unlocked yes)
			(layer "F.Fab")
			(hide yes)
			(effects
				(font
					(size 1.27 1.016)
					(thickness 0.1524)
				)
			)
		)
		(property "Device Type" "IND-80NH-1-GP_DISCRET-GC2-IND-A"
			(at 4.9784 -2.1717 90)
			(unlocked yes)
			(layer "F.Fab")
			(hide yes)
			(effects
				(font
					(size 1.27 1.016)
					(thickness 0.1524)
				)
			)
		)
		(duplicate_pad_numbers_are_jumpers no)
		(fp_line
			(start 2.8575 -3.4544)
			(end 2.8575 3.4544)
			(stroke
				(width 0.1524)
				(type default)
			)
			(layer "F.SilkS")
		)
		(fp_line
			(start -2.8575 -3.4544)
			(end 2.8575 -3.4544)
			(stroke
				(width 0.1524)
				(type default)
			)
			(layer "F.SilkS")
		)
		(fp_line
			(start 2.8575 3.4544)
			(end -2.8575 3.4544)
			(stroke
				(width 0.1524)
				(type default)
			)
			(layer "F.SilkS")
		)
		(fp_line
			(start -2.8575 3.4544)
			(end -2.8575 -3.4544)
			(stroke
				(width 0.1524)
				(type default)
			)
			(layer "F.SilkS")
		)
		(fp_rect
			(start -2.6035 2.6035)
			(end 2.6035 -2.6035)
			(stroke
				(width 0)
				(type default)
			)
			(fill no)
			(layer "F.CrtYd")
		)
		(fp_poly
			(pts
				(xy -3.1115 3.5306) (xy -3.1115 2.6035) (xy 2.6035 2.6035) (xy 2.6035 -2.6035) (xy -2.6035 -2.6035)
				(xy -2.6035 2.5908) (xy -3.1115 2.5908) (xy -3.1115 -3.5306) (xy 3.1115 -3.5306) (xy 3.1115 3.5306)
			)
			(stroke
				(width 0)
				(type default)
			)
			(fill no)
			(layer "F.CrtYd")
		)
		(fp_rect
			(start -3.1115 3.5306)
			(end 3.1115 -3.5306)
			(stroke
				(width 0)
				(type default)
			)
			(fill no)
			(layer "F.Fab")
		)
		(pad "1" smd rect
			(at 0 -2.395982 90)
			(size 2.2606 1.6002)
			(layers "F.Cu" "F.Mask" "F.Paste")
			(net "P12V_STBY")
		)
		(pad "2" smd rect
			(at 0 2.395982 90)
			(size 2.2606 1.6002)
			(layers "F.Cu" "F.Mask" "F.Paste")
			(net "VR_FET_SW_P12V_STBY_PVCCIN_CPU0")
		)
	)
	(footprint ""
		(layer "F.Cu")
		(at 275.909024 -77.429614)
		(property "Reference" "C5D38"
			(at 0 0 0)
			(layer "F.SilkS")
			(hide yes)
			(effects
				(font
					(size 1.27 1.27)
				)
			)
		)
		(property "Value" ""
			(at 0 0 0)
			(layer "F.Fab")
			(effects
				(font
					(size 1.27 1.27)
				)
			)
		)
		(duplicate_pad_numbers_are_jumpers no)
		(fp_poly
			(pts
				(xy -0.4953 -0.2032) (xy 0.4953 -0.2032) (xy 0.4953 1.6002) (xy -0.4953 1.6002)
			)
			(stroke
				(width 0)
				(type default)
			)
			(fill no)
			(layer "F.CrtYd")
		)
		(fp_line
			(start -0.4953 -0.2032)
			(end 0.4953 -0.2032)
			(stroke
				(width 0.1)
				(type default)
			)
			(layer "F.Fab")
		)
		(fp_line
			(start -0.4953 1.6002)
			(end -0.4953 -0.2032)
			(stroke
				(width 0.1)
				(type default)
			)
			(layer "F.Fab")
		)
		(fp_line
			(start 0.4953 -0.2032)
			(end 0.4953 1.6002)
			(stroke
				(width 0.1)
				(type default)
			)
			(layer "F.Fab")
		)
		(fp_line
			(start 0.4953 1.6002)
			(end -0.4953 1.6002)
			(stroke
				(width 0.1)
				(type default)
			)
			(layer "F.Fab")
		)
		(pad "1" smd rect
			(at 0 0)
			(size 0.762 0.889)
			(layers "F.Cu" "F.Mask" "F.Paste")
			(net "PVCCMCP_CPU0")
		)
		(pad "2" smd rect
			(at 0 1.397)
			(size 0.762 0.889)
			(layers "F.Cu" "F.Mask" "F.Paste")
			(net "GND")
		)
		(zone
			(layer "F.Cu")
			(hatch none 0.5)
			(connect_pads
				(clearance 0)
			)
			(min_thickness 0.25)
			(keepout
				(tracks not_allowed)
				(vias allowed)
				(pads allowed)
				(copperpour not_allowed)
				(footprints allowed)
			)
			(placement
				(enabled no)
				(sheetname "")
			)
			(fill
				(thermal_gap 0.5)
				(thermal_bridge_width 0.5)
				(island_removal_mode 0)
			)
			(polygon
				(pts
					(xy 275.528024 -76.985114) (xy 276.290024 -76.985114) (xy 276.290024 -76.477114) (xy 275.528024 -76.477114)
				)
			)
		)
	)
	(footprint ""
		(layer "F.Cu")
		(at 49.4284 -93.7514)
		(property "Reference" "C1C19"
			(at 0 0 0)
			(layer "F.SilkS")
			(hide yes)
			(effects
				(font
					(size 1.27 1.27)
				)
			)
		)
		(property "Value" ""
			(at 0 0 0)
			(layer "F.Fab")
			(effects
				(font
					(size 1.27 1.27)
				)
			)
		)
		(duplicate_pad_numbers_are_jumpers no)
		(fp_poly
			(pts
				(xy -0.4953 -0.2032) (xy 0.4953 -0.2032) (xy 0.4953 1.6002) (xy -0.4953 1.6002)
			)
			(stroke
				(width 0)
				(type default)
			)
			(fill no)
			(layer "F.CrtYd")
		)
		(fp_line
			(start -0.4953 -0.2032)
			(end 0.4953 -0.2032)
			(stroke
				(width 0.1)
				(type default)
			)
			(layer "F.Fab")
		)
		(fp_line
			(start -0.4953 1.6002)
			(end -0.4953 -0.2032)
			(stroke
				(width 0.1)
				(type default)
			)
			(layer "F.Fab")
		)
		(fp_line
			(start 0.4953 -0.2032)
			(end 0.4953 1.6002)
			(stroke
				(width 0.1)
				(type default)
			)
			(layer "F.Fab")
		)
		(fp_line
			(start 0.4953 1.6002)
			(end -0.4953 1.6002)
			(stroke
				(width 0.1)
				(type default)
			)
			(layer "F.Fab")
		)
		(pad "1" smd rect
			(at 0 0)
			(size 0.762 0.889)
			(layers "F.Cu" "F.Mask" "F.Paste")
			(net "PVSA_CPU1")
		)
		(pad "2" smd rect
			(at 0 1.397)
			(size 0.762 0.889)
			(layers "F.Cu" "F.Mask" "F.Paste")
			(net "GND")
		)
		(zone
			(layer "F.Cu")
			(hatch none 0.5)
			(connect_pads
				(clearance 0)
			)
			(min_thickness 0.25)
			(keepout
				(tracks not_allowed)
				(vias allowed)
				(pads allowed)
				(copperpour not_allowed)
				(footprints allowed)
			)
			(placement
				(enabled no)
				(sheetname "")
			)
			(fill
				(thermal_gap 0.5)
				(thermal_bridge_width 0.5)
				(island_removal_mode 0)
			)
			(polygon
				(pts
					(xy 49.0474 -93.3069) (xy 49.8094 -93.3069) (xy 49.8094 -92.7989) (xy 49.0474 -92.7989)
				)
			)
		)
	)
	(footprint ""
		(layer "F.Cu")
		(at 169.1894 -66.802 -90)
		(property "Reference" "EU4D5"
			(at 0.6096 -3.60807 90)
			(unlocked yes)
			(layer "F.SilkS")
			(effects
				(font
					(size 0.7874 0.5842)
					(thickness 0.1524)
				)
				(justify left)
			)
		)
		(property "Value" ""
			(at 0 0 270)
			(layer "F.Fab")
			(effects
				(font
					(size 1.27 1.27)
				)
			)
		)
		(duplicate_pad_numbers_are_jumpers no)
		(fp_line
			(start -3.0607 3.0607)
			(end -3.0607 -3.0607)
			(stroke
				(width 0.1524)
				(type default)
			)
			(layer "F.SilkS")
		)
		(fp_line
			(start 3.0607 3.0607)
			(end -3.0607 3.0607)
			(stroke
				(width 0.1524)
				(type default)
			)
			(layer "F.SilkS")
		)
		(fp_line
			(start -2.549906 2.549906)
			(end -2.549906 2.267204)
			(stroke
				(width 0.1524)
				(type default)
			)
			(layer "F.SilkS")
		)
		(fp_line
			(start -2.277618 2.549906)
			(end -2.549906 2.549906)
			(stroke
				(width 0.1524)
				(type default)
			)
			(layer "F.SilkS")
		)
		(fp_line
			(start 2.549906 2.549906)
			(end 2.249678 2.549906)
			(stroke
				(width 0.1524)
				(type default)
			)
			(layer "F.SilkS")
		)
		(fp_line
			(start 2.549906 2.233422)
			(end 2.549906 2.549906)
			(stroke
				(width 0.1524)
				(type default)
			)
			(layer "F.SilkS")
		)
		(fp_line
			(start -2.549906 -2.29362)
			(end -2.549906 -2.549906)
			(stroke
				(width 0.1524)
				(type default)
			)
			(layer "F.SilkS")
		)
		(fp_line
			(start -2.549906 -2.549906)
			(end -2.249678 -2.549906)
			(stroke
				(width 0.1524)
				(type default)
			)
			(layer "F.SilkS")
		)
		(fp_line
			(start 2.245614 -2.549906)
			(end 2.549906 -2.549906)
			(stroke
				(width 0.1524)
				(type default)
			)
			(layer "F.SilkS")
		)
		(fp_line
			(start 2.549906 -2.549906)
			(end 2.549906 -2.258314)
			(stroke
				(width 0.1524)
				(type default)
			)
			(layer "F.SilkS")
		)
		(fp_line
			(start -3.0607 -3.0607)
			(end 3.0607 -3.0607)
			(stroke
				(width 0.1524)
				(type default)
			)
			(layer "F.SilkS")
		)
		(fp_line
			(start 3.0607 -3.0607)
			(end 3.0607 3.0607)
			(stroke
				(width 0.1524)
				(type default)
			)
			(layer "F.SilkS")
		)
		(fp_circle
			(center -3.237738 -2.256536)
			(end -3.237738 -2.383536)
			(stroke
				(width 0.254)
				(type default)
			)
			(fill no)
			(layer "F.SilkS")
		)
		(fp_poly
			(pts
				(xy -3.0607 -3.0607) (xy -3.0607 -2.0193) (xy -2.0193 -3.0607)
			)
			(stroke
				(width 0)
				(type default)
			)
			(fill yes)
			(layer "F.SilkS")
		)
		(fp_rect
			(start -1.8415 1.8415)
			(end 1.8415 -1.8415)
			(stroke
				(width 0)
				(type default)
			)
			(fill yes)
			(layer "F.Paste")
		)
		(fp_rect
			(start -2.549906 2.549906)
			(end 2.549906 -2.549906)
			(stroke
				(width 0)
				(type default)
			)
			(fill no)
			(layer "F.CrtYd")
		)
		(fp_line
			(start -2.549906 2.549906)
			(end -2.549906 -2.549906)
			(stroke
				(width 0.1)
				(type default)
			)
			(layer "F.Fab")
		)
		(fp_line
			(start 2.549906 2.549906)
			(end -2.549906 2.549906)
			(stroke
				(width 0.1)
				(type default)
			)
			(layer "F.Fab")
		)
		(fp_line
			(start -2.549906 -2.549906)
			(end 2.549906 -2.549906)
			(stroke
				(width 0.1)
				(type default)
			)
			(layer "F.Fab")
		)
		(fp_line
			(start 2.549906 -2.549906)
			(end 2.549906 2.549906)
			(stroke
				(width 0.1)
				(type default)
			)
			(layer "F.Fab")
		)
		(fp_circle
			(center -3.237738 -2.256536)
			(end -3.237738 -2.383536)
			(stroke
				(width 0.254)
				(type default)
			)
			(fill no)
			(layer "F.Fab")
		)
		(pad "1" smd custom
			(at -2.4511 -1.800098 270)
			(size 0.0508 0.0508)
			(layers "F.Cu" "F.Mask" "F.Paste")
			(net "Net_336")
			(options
				(clearance outline)
				(anchor circle)
			)
			(primitives
				(gr_poly
					(pts
						(arc
							(start 0.254 -0.1016)
							(mid 0.3556 0)
							(end 0.254 0.1016)
						)
						(xy -0.3556 0.1016) (xy -0.3556 -0.1016)
					)
					(width 0)
					(fill yes)
				)
			)
		)
		(pad "2" smd custom
			(at -2.4511 -1.400048 270)
			(size 0.0508 0.0508)
			(layers "F.Cu" "F.Mask" "F.Paste")
			(net "Net_337")
			(options
				(clearance outline)
				(anchor circle)
			)
			(primitives
				(gr_poly
					(pts
						(arc
							(start 0.254 -0.1016)
							(mid 0.3556 0)
							(end 0.254 0.1016)
						)
						(xy -0.3556 0.1016) (xy -0.3556 -0.1016)
					)
					(width 0)
					(fill yes)
				)
			)
		)
		(pad "3" smd custom
			(at -2.4511 -0.999998 270)
			(size 0.0508 0.0508)
			(layers "F.Cu" "F.Mask" "F.Paste")
			(net "Net_279")
			(options
				(clearance outline)
				(anchor circle)
			)
			(primitives
				(gr_poly
					(pts
						(arc
							(start 0.254 -0.1016)
							(mid 0.3556 0)
							(end 0.254 0.1016)
						)
						(xy -0.3556 0.1016) (xy -0.3556 -0.1016)
					)
					(width 0)
					(fill yes)
				)
			)
		)
		(pad "4" smd custom
			(at -2.4511 -0.599948 270)
			(size 0.0508 0.0508)
			(layers "F.Cu" "F.Mask" "F.Paste")
			(net "Net_338")
			(options
				(clearance outline)
				(anchor circle)
			)
			(primitives
				(gr_poly
					(pts
						(arc
							(start 0.254 -0.1016)
							(mid 0.3556 0)
							(end 0.254 0.1016)
						)
						(xy -0.3556 0.1016) (xy -0.3556 -0.1016)
					)
					(width 0)
					(fill yes)
				)
			)
		)
		(pad "5" smd custom
			(at -2.4511 -0.199898 270)
			(size 0.0508 0.0508)
			(layers "F.Cu" "F.Mask" "F.Paste")
			(net "VR_PVCCIO_CPU1_PWM1")
			(options
				(clearance outline)
				(anchor circle)
			)
			(primitives
				(gr_poly
					(pts
						(arc
							(start 0.254 -0.1016)
							(mid 0.3556 0)
							(end 0.254 0.1016)
						)
						(xy -0.3556 0.1016) (xy -0.3556 -0.1016)
					)
					(width 0)
					(fill yes)
				)
			)
		)
		(pad "6" smd custom
			(at -2.4511 0.199898 270)
			(size 0.0508 0.0508)
			(layers "F.Cu" "F.Mask" "F.Paste")
			(net "SMB_VR_STBY_LVC3_SDA")
			(options
				(clearance outline)
				(anchor circle)
			)
			(primitives
				(gr_poly
					(pts
						(arc
							(start 0.254 -0.1016)
							(mid 0.3556 0)
							(end 0.254 0.1016)
						)
						(xy -0.3556 0.1016) (xy -0.3556 -0.1016)
					)
					(width 0)
					(fill yes)
				)
			)
		)
		(pad "7" smd custom
			(at -2.4511 0.599948 270)
			(size 0.0508 0.0508)
			(layers "F.Cu" "F.Mask" "F.Paste")
			(net "SMB_VR_STBY_LVC3_SCL")
			(options
				(clearance outline)
				(anchor circle)
			)
			(primitives
				(gr_poly
					(pts
						(arc
							(start 0.254 -0.1016)
							(mid 0.3556 0)
							(end 0.254 0.1016)
						)
						(xy -0.3556 0.1016) (xy -0.3556 -0.1016)
					)
					(width 0)
					(fill yes)
				)
			)
		)
		(pad "8" smd custom
			(at -2.4511 0.999998 270)
			(size 0.0508 0.0508)
			(layers "F.Cu" "F.Mask" "F.Paste")
			(net "Net_280")
			(options
				(clearance outline)
				(anchor circle)
			)
			(primitives
				(gr_poly
					(pts
						(arc
							(start 0.254 -0.1016)
							(mid 0.3556 0)
							(end 0.254 0.1016)
						)
						(xy -0.3556 0.1016) (xy -0.3556 -0.1016)
					)
					(width 0)
					(fill yes)
				)
			)
		)
		(pad "9" smd custom
			(at -2.4511 1.400048 270)
			(size 0.0508 0.0508)
			(layers "F.Cu" "F.Mask" "F.Paste")
			(net "PWRGD_PVCCIO_CPU1_R")
			(options
				(clearance outline)
				(anchor circle)
			)
			(primitives
				(gr_poly
					(pts
						(arc
							(start 0.254 -0.1016)
							(mid 0.3556 0)
							(end 0.254 0.1016)
						)
						(xy -0.3556 0.1016) (xy -0.3556 -0.1016)
					)
					(width 0)
					(fill yes)
				)
			)
		)
		(pad "10" smd custom
			(at -2.4511 1.800098 270)
			(size 0.0508 0.0508)
			(layers "F.Cu" "F.Mask" "F.Paste")
			(net "VR_PVCCIO_CPU1_EN")
			(options
				(clearance outline)
				(anchor circle)
			)
			(primitives
				(gr_poly
					(pts
						(arc
							(start 0.254 -0.1016)
							(mid 0.3556 0)
							(end 0.254 0.1016)
						)
						(xy -0.3556 0.1016) (xy -0.3556 -0.1016)
					)
					(width 0)
					(fill yes)
				)
			)
		)
		(pad "11" smd custom
			(at -1.800098 2.4511 270)
			(size 0.0508 0.0508)
			(layers "F.Cu" "F.Mask" "F.Paste")
			(net "IRQ_PVCCIO_CPU1_VRHOT_N")
			(options
				(clearance outline)
				(anchor circle)
			)
			(primitives
				(gr_poly
					(pts
						(arc
							(start -0.1016 -0.254)
							(mid 0 -0.3556)
							(end 0.1016 -0.254)
						)
						(xy 0.1016 0.3556) (xy -0.1016 0.3556)
					)
					(width 0)
					(fill yes)
				)
			)
		)
		(pad "12" smd custom
			(at -1.400048 2.4511 270)
			(size 0.0508 0.0508)
			(layers "F.Cu" "F.Mask" "F.Paste")
			(net "Net_264")
			(options
				(clearance outline)
				(anchor circle)
			)
			(primitives
				(gr_poly
					(pts
						(arc
							(start -0.1016 -0.254)
							(mid 0 -0.3556)
							(end 0.1016 -0.254)
						)
						(xy 0.1016 0.3556) (xy -0.1016 0.3556)
					)
					(width 0)
					(fill yes)
				)
			)
		)
		(pad "13" smd custom
			(at -0.999998 2.4511 270)
			(size 0.0508 0.0508)
			(layers "F.Cu" "F.Mask" "F.Paste")
			(net "Net_262")
			(options
				(clearance outline)
				(anchor circle)
			)
			(primitives
				(gr_poly
					(pts
						(arc
							(start -0.1016 -0.254)
							(mid 0 -0.3556)
							(end 0.1016 -0.254)
						)
						(xy 0.1016 0.3556) (xy -0.1016 0.3556)
					)
					(width 0)
					(fill yes)
				)
			)
		)
		(pad "14" smd custom
			(at -0.599948 2.4511 270)
			(size 0.0508 0.0508)
			(layers "F.Cu" "F.Mask" "F.Paste")
			(net "Net_263")
			(options
				(clearance outline)
				(anchor circle)
			)
			(primitives
				(gr_poly
					(pts
						(arc
							(start -0.1016 -0.254)
							(mid 0 -0.3556)
							(end 0.1016 -0.254)
						)
						(xy 0.1016 0.3556) (xy -0.1016 0.3556)
					)
					(width 0)
					(fill yes)
				)
			)
		)
		(pad "15" smd custom
			(at -0.199898 2.4511 270)
			(size 0.0508 0.0508)
			(layers "F.Cu" "F.Mask" "F.Paste")
			(net "SVID_CLK_PVCCIO_CPU1")
			(options
				(clearance outline)
				(anchor circle)
			)
			(primitives
				(gr_poly
					(pts
						(arc
							(start -0.1016 -0.254)
							(mid 0 -0.3556)
							(end 0.1016 -0.254)
						)
						(xy 0.1016 0.3556) (xy -0.1016 0.3556)
					)
					(width 0)
					(fill yes)
				)
			)
		)
		(pad "16" smd custom
			(at 0.199898 2.4511 270)
			(size 0.0508 0.0508)
			(layers "F.Cu" "F.Mask" "F.Paste")
			(net "SVID_VDIO_PVCCIO_CPU1")
			(options
				(clearance outline)
				(anchor circle)
			)
			(primitives
				(gr_poly
					(pts
						(arc
							(start -0.1016 -0.254)
							(mid 0 -0.3556)
							(end 0.1016 -0.254)
						)
						(xy 0.1016 0.3556) (xy -0.1016 0.3556)
					)
					(width 0)
					(fill yes)
				)
			)
		)
		(pad "17" smd custom
			(at 0.599948 2.4511 270)
			(size 0.0508 0.0508)
			(layers "F.Cu" "F.Mask" "F.Paste")
			(net "SVID_ALERT_PVCCIO_CPU1")
			(options
				(clearance outline)
				(anchor circle)
			)
			(primitives
				(gr_poly
					(pts
						(arc
							(start -0.1016 -0.254)
							(mid 0 -0.3556)
							(end 0.1016 -0.254)
						)
						(xy 0.1016 0.3556) (xy -0.1016 0.3556)
					)
					(width 0)
					(fill yes)
				)
			)
		)
		(pad "18" smd custom
			(at 0.999998 2.4511 270)
			(size 0.0508 0.0508)
			(layers "F.Cu" "F.Mask" "F.Paste")
			(net "Net_302")
			(options
				(clearance outline)
				(anchor circle)
			)
			(primitives
				(gr_poly
					(pts
						(arc
							(start -0.1016 -0.254)
							(mid 0 -0.3556)
							(end 0.1016 -0.254)
						)
						(xy 0.1016 0.3556) (xy -0.1016 0.3556)
					)
					(width 0)
					(fill yes)
				)
			)
		)
		(pad "19" smd custom
			(at 1.400048 2.4511 270)
			(size 0.0508 0.0508)
			(layers "F.Cu" "F.Mask" "F.Paste")
			(net "VR_PVCCIO_CPU1_AVSP")
			(options
				(clearance outline)
				(anchor circle)
			)
			(primitives
				(gr_poly
					(pts
						(arc
							(start -0.1016 -0.254)
							(mid 0 -0.3556)
							(end 0.1016 -0.254)
						)
						(xy 0.1016 0.3556) (xy -0.1016 0.3556)
					)
					(width 0)
					(fill yes)
				)
			)
		)
		(pad "20" smd custom
			(at 1.800098 2.4511 270)
			(size 0.0508 0.0508)
			(layers "F.Cu" "F.Mask" "F.Paste")
			(net "VSENSE_PVCCIO_CPU1_AVSN")
			(options
				(clearance outline)
				(anchor circle)
			)
			(primitives
				(gr_poly
					(pts
						(arc
							(start -0.1016 -0.254)
							(mid 0 -0.3556)
							(end 0.1016 -0.254)
						)
						(xy 0.1016 0.3556) (xy -0.1016 0.3556)
					)
					(width 0)
					(fill yes)
				)
			)
		)
		(pad "21" smd custom
			(at 2.4511 1.800098 270)
			(size 0.0508 0.0508)
			(layers "F.Cu" "F.Mask" "F.Paste")
			(net "VR_PVCCIO_CPU1_AIREF1")
			(options
				(clearance outline)
				(anchor circle)
			)
			(primitives
				(gr_poly
					(pts
						(arc
							(start -0.254 0.1016)
							(mid -0.3556 0)
							(end -0.254 -0.1016)
						)
						(xy 0.3556 -0.1016) (xy 0.3556 0.1016)
					)
					(width 0)
					(fill yes)
				)
			)
		)
		(pad "22" smd custom
			(at 2.4511 1.400048 270)
			(size 0.0508 0.0508)
			(layers "F.Cu" "F.Mask" "F.Paste")
			(net "ISENSE_PVCCIO_CPU1_PH1_IMON")
			(options
				(clearance outline)
				(anchor circle)
			)
			(primitives
				(gr_poly
					(pts
						(arc
							(start -0.254 0.1016)
							(mid -0.3556 0)
							(end -0.254 -0.1016)
						)
						(xy 0.3556 -0.1016) (xy 0.3556 0.1016)
					)
					(width 0)
					(fill yes)
				)
			)
		)
		(pad "23" smd custom
			(at 2.4511 0.999998 270)
			(size 0.0508 0.0508)
			(layers "F.Cu" "F.Mask" "F.Paste")
			(net "GND")
			(options
				(clearance outline)
				(anchor circle)
			)
			(primitives
				(gr_poly
					(pts
						(arc
							(start -0.254 0.1016)
							(mid -0.3556 0)
							(end -0.254 -0.1016)
						)
						(xy 0.3556 -0.1016) (xy 0.3556 0.1016)
					)
					(width 0)
					(fill yes)
				)
			)
		)
		(pad "24" smd custom
			(at 2.4511 0.599948 270)
			(size 0.0508 0.0508)
			(layers "F.Cu" "F.Mask" "F.Paste")
			(net "Net_339")
			(options
				(clearance outline)
				(anchor circle)
			)
			(primitives
				(gr_poly
					(pts
						(arc
							(start -0.254 0.1016)
							(mid -0.3556 0)
							(end -0.254 -0.1016)
						)
						(xy 0.3556 -0.1016) (xy 0.3556 0.1016)
					)
					(width 0)
					(fill yes)
				)
			)
		)
		(pad "25" smd custom
			(at 2.4511 0.199898 270)
			(size 0.0508 0.0508)
			(layers "F.Cu" "F.Mask" "F.Paste")
			(net "Net_258")
			(options
				(clearance outline)
				(anchor circle)
			)
			(primitives
				(gr_poly
					(pts
						(arc
							(start -0.254 0.1016)
							(mid -0.3556 0)
							(end -0.254 -0.1016)
						)
						(xy 0.3556 -0.1016) (xy 0.3556 0.1016)
					)
					(width 0)
					(fill yes)
				)
			)
		)
		(pad "26" smd custom
			(at 2.4511 -0.199898 270)
			(size 0.0508 0.0508)
			(layers "F.Cu" "F.Mask" "F.Paste")
			(net "GND")
			(options
				(clearance outline)
				(anchor circle)
			)
			(primitives
				(gr_poly
					(pts
						(arc
							(start -0.254 0.1016)
							(mid -0.3556 0)
							(end -0.254 -0.1016)
						)
						(xy 0.3556 -0.1016) (xy 0.3556 0.1016)
					)
					(width 0)
					(fill yes)
				)
			)
		)
		(pad "27" smd custom
			(at 2.4511 -0.599948 270)
			(size 0.0508 0.0508)
			(layers "F.Cu" "F.Mask" "F.Paste")
			(net "GND")
			(options
				(clearance outline)
				(anchor circle)
			)
			(primitives
				(gr_poly
					(pts
						(arc
							(start -0.254 0.1016)
							(mid -0.3556 0)
							(end -0.254 -0.1016)
						)
						(xy 0.3556 -0.1016) (xy 0.3556 0.1016)
					)
					(width 0)
					(fill yes)
				)
			)
		)
		(pad "28" smd custom
			(at 2.4511 -0.999998 270)
			(size 0.0508 0.0508)
			(layers "F.Cu" "F.Mask" "F.Paste")
			(net "Net_340")
			(options
				(clearance outline)
				(anchor circle)
			)
			(primitives
				(gr_poly
					(pts
						(arc
							(start -0.254 0.1016)
							(mid -0.3556 0)
							(end -0.254 -0.1016)
						)
						(xy 0.3556 -0.1016) (xy 0.3556 0.1016)
					)
					(width 0)
					(fill yes)
				)
			)
		)
		(pad "29" smd custom
			(at 2.4511 -1.400048 270)
			(size 0.0508 0.0508)
			(layers "F.Cu" "F.Mask" "F.Paste")
			(net "Net_261")
			(options
				(clearance outline)
				(anchor circle)
			)
			(primitives
				(gr_poly
					(pts
						(arc
							(start -0.254 0.1016)
							(mid -0.3556 0)
							(end -0.254 -0.1016)
						)
						(xy 0.3556 -0.1016) (xy 0.3556 0.1016)
					)
					(width 0)
					(fill yes)
				)
			)
		)
		(pad "30" smd custom
			(at 2.4511 -1.800098 270)
			(size 0.0508 0.0508)
			(layers "F.Cu" "F.Mask" "F.Paste")
			(net "Net_260")
			(options
				(clearance outline)
				(anchor circle)
			)
			(primitives
				(gr_poly
					(pts
						(arc
							(start -0.254 0.1016)
							(mid -0.3556 0)
							(end -0.254 -0.1016)
						)
						(xy 0.3556 -0.1016) (xy 0.3556 0.1016)
					)
					(width 0)
					(fill yes)
				)
			)
		)
		(pad "31" smd custom
			(at 1.800098 -2.4511 270)
			(size 0.0508 0.0508)
			(layers "F.Cu" "F.Mask" "F.Paste")
			(net "Net_303")
			(options
				(clearance outline)
				(anchor circle)
			)
			(primitives
				(gr_poly
					(pts
						(arc
							(start 0.1016 0.254)
							(mid 0 0.3556)
							(end -0.1016 0.254)
						)
						(xy -0.1016 -0.3556) (xy 0.1016 -0.3556)
					)
					(width 0)
					(fill yes)
				)
			)
		)
		(pad "32" smd custom
			(at 1.400048 -2.4511 270)
			(size 0.0508 0.0508)
			(layers "F.Cu" "F.Mask" "F.Paste")
			(net "PU_VR_PVCCIO_CPU1_FAULT1")
			(options
				(clearance outline)
				(anchor circle)
			)
			(primitives
				(gr_poly
					(pts
						(arc
							(start 0.1016 0.254)
							(mid 0 0.3556)
							(end -0.1016 0.254)
						)
						(xy -0.1016 -0.3556) (xy 0.1016 -0.3556)
					)
					(width 0)
					(fill yes)
				)
			)
		)
		(pad "33" smd custom
			(at 0.999998 -2.4511 270)
			(size 0.0508 0.0508)
			(layers "F.Cu" "F.Mask" "F.Paste")
			(net "VR_PVCCIO_CPU1_XADDR2")
			(options
				(clearance outline)
				(anchor circle)
			)
			(primitives
				(gr_poly
					(pts
						(arc
							(start 0.1016 0.254)
							(mid 0 0.3556)
							(end -0.1016 0.254)
						)
						(xy -0.1016 -0.3556) (xy 0.1016 -0.3556)
					)
					(width 0)
					(fill yes)
				)
			)
		)
		(pad "34" smd custom
			(at 0.599948 -2.4511 270)
			(size 0.0508 0.0508)
			(layers "F.Cu" "F.Mask" "F.Paste")
			(net "Net_259")
			(options
				(clearance outline)
				(anchor circle)
			)
			(primitives
				(gr_poly
					(pts
						(arc
							(start 0.1016 0.254)
							(mid 0 0.3556)
							(end -0.1016 0.254)
						)
						(xy -0.1016 -0.3556) (xy 0.1016 -0.3556)
					)
					(width 0)
					(fill yes)
				)
			)
		)
		(pad "35" smd custom
			(at 0.199898 -2.4511 270)
			(size 0.0508 0.0508)
			(layers "F.Cu" "F.Mask" "F.Paste")
			(net "A_TSENSE_PVCCIO_CPU1")
			(options
				(clearance outline)
				(anchor circle)
			)
			(primitives
				(gr_poly
					(pts
						(arc
							(start 0.1016 0.254)
							(mid 0 0.3556)
							(end -0.1016 0.254)
						)
						(xy -0.1016 -0.3556) (xy 0.1016 -0.3556)
					)
					(width 0)
					(fill yes)
				)
			)
		)
		(pad "36" smd custom
			(at -0.199898 -2.4511 270)
			(size 0.0508 0.0508)
			(layers "F.Cu" "F.Mask" "F.Paste")
			(net "VR_PVCCIO_CPU1_XADDR1")
			(options
				(clearance outline)
				(anchor circle)
			)
			(primitives
				(gr_poly
					(pts
						(arc
							(start 0.1016 0.254)
							(mid 0 0.3556)
							(end -0.1016 0.254)
						)
						(xy -0.1016 -0.3556) (xy 0.1016 -0.3556)
					)
					(width 0)
					(fill yes)
				)
			)
		)
		(pad "37" smd custom
			(at -0.599948 -2.4511 270)
			(size 0.0508 0.0508)
			(layers "F.Cu" "F.Mask" "F.Paste")
			(net "VR_PVCCIO_CPU1_VINSEN")
			(options
				(clearance outline)
				(anchor circle)
			)
			(primitives
				(gr_poly
					(pts
						(arc
							(start 0.1016 0.254)
							(mid 0 0.3556)
							(end -0.1016 0.254)
						)
						(xy -0.1016 -0.3556) (xy 0.1016 -0.3556)
					)
					(width 0)
					(fill yes)
				)
			)
		)
		(pad "38" smd custom
			(at -0.999998 -2.4511 270)
			(size 0.0508 0.0508)
			(layers "F.Cu" "F.Mask" "F.Paste")
			(net "Net_266")
			(options
				(clearance outline)
				(anchor circle)
			)
			(primitives
				(gr_poly
					(pts
						(arc
							(start 0.1016 0.254)
							(mid 0 0.3556)
							(end -0.1016 0.254)
						)
						(xy -0.1016 -0.3556) (xy 0.1016 -0.3556)
					)
					(width 0)
					(fill yes)
				)
			)
		)
		(pad "39" smd custom
			(at -1.400048 -2.4511 270)
			(size 0.0508 0.0508)
			(layers "F.Cu" "F.Mask" "F.Paste")
			(net "VR_PVCCIO_CPU1_VDD")
			(options
				(clearance outline)
				(anchor circle)
			)
			(primitives
				(gr_poly
					(pts
						(arc
							(start 0.1016 0.254)
							(mid 0 0.3556)
							(end -0.1016 0.254)
						)
						(xy -0.1016 -0.3556) (xy 0.1016 -0.3556)
					)
					(width 0)
					(fill yes)
				)
			)
		)
		(pad "40" smd custom
			(at -1.800098 -2.4511 270)
			(size 0.0508 0.0508)
			(layers "F.Cu" "F.Mask" "F.Paste")
			(net "VR_PVCCIO_CPU1_VD12")
			(options
				(clearance outline)
				(anchor circle)
			)
			(primitives
				(gr_poly
					(pts
						(arc
							(start 0.1016 0.254)
							(mid 0 0.3556)
							(end -0.1016 0.254)
						)
						(xy -0.1016 -0.3556) (xy 0.1016 -0.3556)
					)
					(width 0)
					(fill yes)
				)
			)
		)
		(pad "41" smd rect
			(at 0 0 270)
			(size 3.683 3.683)
			(layers "F.Cu" "F.Mask" "F.Paste")
			(net "GND")
		)
		(zone
			(layer "F.Cu")
			(hatch none 0.5)
			(connect_pads
				(clearance 0)
			)
			(min_thickness 0.25)
			(keepout
				(tracks allowed)
				(vias not_allowed)
				(pads allowed)
				(copperpour not_allowed)
				(footprints allowed)
			)
			(placement
				(enabled no)
				(sheetname "")
			)
			(fill
				(thermal_gap 0.5)
				(thermal_bridge_width 0.5)
				(island_removal_mode 0)
			)
			(polygon
				(pts
					(xy 167.0939 -68.8975) (xy 167.55491 -68.8975) (xy 167.55491 -68.6435) (xy 167.3479 -68.6435) (xy 167.3479 -64.9605)
					(xy 171.0309 -64.9605) (xy 171.0309 -68.6435) (xy 167.556942 -68.6435) (xy 167.556942 -68.8975)
					(xy 171.2849 -68.8975) (xy 171.2849 -64.7065) (xy 167.0939 -64.7065)
				)
			)
		)
		(zone
			(layer "F.Cu")
			(hatch none 0.5)
			(connect_pads
				(clearance 0)
			)
			(min_thickness 0.25)
			(keepout
				(tracks not_allowed)
				(vias allowed)
				(pads allowed)
				(copperpour not_allowed)
				(footprints allowed)
			)
			(placement
				(enabled no)
				(sheetname "")
			)
			(fill
				(thermal_gap 0.5)
				(thermal_bridge_width 0.5)
				(island_removal_mode 0)
			)
			(polygon
				(pts
					(xy 167.0939 -68.8975) (xy 167.55491 -68.8975) (xy 167.55491 -68.6435) (xy 167.3479 -68.6435) (xy 167.3479 -64.9605)
					(xy 171.0309 -64.9605) (xy 171.0309 -68.6435) (xy 167.556942 -68.6435) (xy 167.556942 -68.8975)
					(xy 171.2849 -68.8975) (xy 171.2849 -64.7065) (xy 167.0939 -64.7065)
				)
			)
		)
	)
	(footprint ""
		(layer "F.Cu")
		(at 26.289 -81.026 180)
		(property "Reference" "R1D22"
			(at 0 0 180)
			(layer "F.SilkS")
			(hide yes)
			(effects
				(font
					(size 1.27 1.27)
				)
			)
		)
		(property "Value" ""
			(at 0 0 180)
			(layer "F.Fab")
			(effects
				(font
					(size 1.27 1.27)
				)
			)
		)
		(duplicate_pad_numbers_are_jumpers no)
		(fp_poly
			(pts
				(xy -0.2794 -0.1016) (xy 0.2794 -0.1016) (xy 0.2794 0.9906) (xy -0.2794 0.9906)
			)
			(stroke
				(width 0)
				(type default)
			)
			(fill no)
			(layer "F.CrtYd")
		)
		(fp_line
			(start 0.2794 0.9906)
			(end 0.2794 -0.1016)
			(stroke
				(width 0.1)
				(type default)
			)
			(layer "F.Fab")
		)
		(fp_line
			(start 0.2794 -0.1016)
			(end -0.2794 -0.1016)
			(stroke
				(width 0.1)
				(type default)
			)
			(layer "F.Fab")
		)
		(fp_line
			(start -0.2794 0.9906)
			(end 0.2794 0.9906)
			(stroke
				(width 0.1)
				(type default)
			)
			(layer "F.Fab")
		)
		(fp_line
			(start -0.2794 -0.1016)
			(end -0.2794 0.9906)
			(stroke
				(width 0.1)
				(type default)
			)
			(layer "F.Fab")
		)
		(pad "1" smd rect
			(at 0 0 180)
			(size 0.508 0.508)
			(layers "F.Cu" "F.Mask" "F.Paste")
			(net "P3V3_STBY")
		)
		(pad "2" smd rect
			(at 0 0.889 180)
			(size 0.508 0.508)
			(layers "F.Cu" "F.Mask" "F.Paste")
			(net "FM_OC_DETECT_N")
		)
		(zone
			(layer "F.Cu")
			(hatch none 0.5)
			(connect_pads
				(clearance 0)
			)
			(min_thickness 0.25)
			(keepout
				(tracks not_allowed)
				(vias allowed)
				(pads allowed)
				(copperpour not_allowed)
				(footprints allowed)
			)
			(placement
				(enabled no)
				(sheetname "")
			)
			(fill
				(thermal_gap 0.5)
				(thermal_bridge_width 0.5)
				(island_removal_mode 0)
			)
			(polygon
				(pts
					(xy 26.543 -81.661) (xy 26.035 -81.661) (xy 26.035 -81.28) (xy 26.543 -81.28)
				)
			)
		)
		(zone
			(layer "F.Cu")
			(hatch none 0.5)
			(connect_pads
				(clearance 0)
			)
			(min_thickness 0.25)
			(keepout
				(tracks allowed)
				(vias not_allowed)
				(pads allowed)
				(copperpour not_allowed)
				(footprints allowed)
			)
			(placement
				(enabled no)
				(sheetname "")
			)
			(fill
				(thermal_gap 0.5)
				(thermal_bridge_width 0.5)
				(island_removal_mode 0)
			)
			(polygon
				(pts
					(xy 26.543 -81.28) (xy 26.035 -81.28) (xy 26.035 -81.661) (xy 26.543 -81.661)
				)
			)
		)
	)
	(footprint ""
		(layer "F.Cu")
		(at 400.430492 -10.917936)
		(property "Reference" "C8G1"
			(at 0 0 0)
			(layer "F.SilkS")
			(hide yes)
			(effects
				(font
					(size 1.27 1.27)
				)
			)
		)
		(property "Value" ""
			(at 0 0 0)
			(layer "F.Fab")
			(effects
				(font
					(size 1.27 1.27)
				)
			)
		)
		(duplicate_pad_numbers_are_jumpers no)
		(fp_rect
			(start -0.3048 0.9906)
			(end 0.3048 -0.1016)
			(stroke
				(width 0)
				(type default)
			)
			(fill no)
			(layer "F.CrtYd")
		)
		(fp_line
			(start -0.3048 -0.1016)
			(end -0.3048 0.9906)
			(stroke
				(width 0.1)
				(type default)
			)
			(layer "F.Fab")
		)
		(fp_line
			(start -0.3048 0.9906)
			(end 0.3048 0.9906)
			(stroke
				(width 0.1)
				(type default)
			)
			(layer "F.Fab")
		)
		(fp_line
			(start 0.3048 -0.1016)
			(end -0.3048 -0.1016)
			(stroke
				(width 0.1)
				(type default)
			)
			(layer "F.Fab")
		)
		(fp_line
			(start 0.3048 0.9906)
			(end 0.3048 -0.1016)
			(stroke
				(width 0.1)
				(type default)
			)
			(layer "F.Fab")
		)
		(pad "1" smd rect
			(at 0 0)
			(size 0.508 0.508)
			(layers "F.Cu" "F.Mask" "F.Paste")
			(net "P3E_CPU0_PE2_SS_TXP<4>")
		)
		(pad "2" smd rect
			(at 0 0.889)
			(size 0.508 0.508)
			(layers "F.Cu" "F.Mask" "F.Paste")
			(net "P3E_CPU0_PE2_SS_C_TXP<4>")
		)
		(zone
			(layer "F.Cu")
			(hatch none 0.5)
			(connect_pads
				(clearance 0)
			)
			(min_thickness 0.25)
			(keepout
				(tracks allowed)
				(vias not_allowed)
				(pads allowed)
				(copperpour not_allowed)
				(footprints allowed)
			)
			(placement
				(enabled no)
				(sheetname "")
			)
			(fill
				(thermal_gap 0.5)
				(thermal_bridge_width 0.5)
				(island_removal_mode 0)
			)
			(polygon
				(pts
					(xy 400.176492 -10.282936) (xy 400.684492 -10.282936) (xy 400.684492 -10.663936) (xy 400.176492 -10.663936)
				)
			)
		)
		(zone
			(layer "F.Cu")
			(hatch none 0.5)
			(connect_pads
				(clearance 0)
			)
			(min_thickness 0.25)
			(keepout
				(tracks not_allowed)
				(vias allowed)
				(pads allowed)
				(copperpour not_allowed)
				(footprints allowed)
			)
			(placement
				(enabled no)
				(sheetname "")
			)
			(fill
				(thermal_gap 0.5)
				(thermal_bridge_width 0.5)
				(island_removal_mode 0)
			)
			(polygon
				(pts
					(xy 400.176492 -10.282936) (xy 400.684492 -10.282936) (xy 400.684492 -10.663936) (xy 400.176492 -10.663936)
				)
			)
		)
	)
	(footprint ""
		(layer "F.Cu")
		(at -1.033526 -124.073666 90)
		(property "Reference" "RF21"
			(at -0.8382 -0.67818 90)
			(unlocked yes)
			(layer "F.SilkS")
			(effects
				(font
					(size 0.4064 0.254)
					(thickness 0.1524)
				)
				(justify left)
			)
		)
		(property "Value" ""
			(at 0 0 90)
			(layer "F.Fab")
			(effects
				(font
					(size 1.27 1.27)
				)
			)
		)
		(duplicate_pad_numbers_are_jumpers no)
		(fp_poly
			(pts
				(xy -0.2794 -0.1016) (xy 0.2794 -0.1016) (xy 0.2794 0.9906) (xy -0.2794 0.9906)
			)
			(stroke
				(width 0)
				(type default)
			)
			(fill no)
			(layer "F.CrtYd")
		)
		(fp_line
			(start 0.2794 -0.1016)
			(end -0.2794 -0.1016)
			(stroke
				(width 0.1)
				(type default)
			)
			(layer "F.Fab")
		)
		(fp_line
			(start -0.2794 -0.1016)
			(end -0.2794 0.9906)
			(stroke
				(width 0.1)
				(type default)
			)
			(layer "F.Fab")
		)
		(fp_line
			(start 0.2794 0.9906)
			(end 0.2794 -0.1016)
			(stroke
				(width 0.1)
				(type default)
			)
			(layer "F.Fab")
		)
		(fp_line
			(start -0.2794 0.9906)
			(end 0.2794 0.9906)
			(stroke
				(width 0.1)
				(type default)
			)
			(layer "F.Fab")
		)
		(pad "1" smd rect
			(at 0 0 90)
			(size 0.508 0.508)
			(layers "F.Cu" "F.Mask" "F.Paste")
			(net "VR_PVDDQ_KLM_AIREF1")
		)
		(pad "2" smd rect
			(at 0 0.889 90)
			(size 0.508 0.508)
			(layers "F.Cu" "F.Mask" "F.Paste")
			(net "ISENSE_PVDDQ_KLM_PH1_IMON")
		)
		(zone
			(layer "F.Cu")
			(hatch none 0.5)
			(connect_pads
				(clearance 0)
			)
			(min_thickness 0.25)
			(keepout
				(tracks allowed)
				(vias not_allowed)
				(pads allowed)
				(copperpour not_allowed)
				(footprints allowed)
			)
			(placement
				(enabled no)
				(sheetname "")
			)
			(fill
				(thermal_gap 0.5)
				(thermal_bridge_width 0.5)
				(island_removal_mode 0)
			)
			(polygon
				(pts
					(xy -0.779526 -123.819666) (xy -0.779526 -124.327666) (xy -0.398526 -124.327666) (xy -0.398526 -123.819666)
				)
			)
		)
		(zone
			(layer "F.Cu")
			(hatch none 0.5)
			(connect_pads
				(clearance 0)
			)
			(min_thickness 0.25)
			(keepout
				(tracks not_allowed)
				(vias allowed)
				(pads allowed)
				(copperpour not_allowed)
				(footprints allowed)
			)
			(placement
				(enabled no)
				(sheetname "")
			)
			(fill
				(thermal_gap 0.5)
				(thermal_bridge_width 0.5)
				(island_removal_mode 0)
			)
			(polygon
				(pts
					(xy -0.398526 -123.819666) (xy -0.398526 -124.327666) (xy -0.779526 -124.327666) (xy -0.779526 -123.819666)
				)
			)
		)
	)
	(footprint ""
		(layer "F.Cu")
		(at 2.397506 -138.184382 90)
		(property "Reference" "EU1A2"
			(at 3.495548 -1.432306 0)
			(unlocked yes)
			(layer "F.SilkS")
			(effects
				(font
					(size 0.7874 0.5842)
					(thickness 0.1524)
				)
			)
		)
		(property "Value" ""
			(at 0 0 90)
			(layer "F.Fab")
			(effects
				(font
					(size 1.27 1.27)
				)
			)
		)
		(duplicate_pad_numbers_are_jumpers no)
		(fp_line
			(start 2.9718 -3.5052)
			(end 2.9718 3.429)
			(stroke
				(width 0.1524)
				(type default)
			)
			(layer "F.SilkS")
		)
		(fp_line
			(start -3.0099 -3.5052)
			(end 2.9718 -3.5052)
			(stroke
				(width 0.1524)
				(type default)
			)
			(layer "F.SilkS")
		)
		(fp_line
			(start 2.9718 3.429)
			(end -3.0099 3.429)
			(stroke
				(width 0.1524)
				(type default)
			)
			(layer "F.SilkS")
		)
		(fp_line
			(start -3.0099 3.429)
			(end -3.0099 -3.5052)
			(stroke
				(width 0.1524)
				(type default)
			)
			(layer "F.SilkS")
		)
		(fp_circle
			(center -3.057398 -2.678684)
			(end -3.057398 -2.551684)
			(stroke
				(width 0.254)
				(type default)
			)
			(fill no)
			(layer "F.SilkS")
		)
		(fp_poly
			(pts
				(xy -2.9972 -3.4925) (xy -2.9972 -2.6924) (xy -2.1971 -3.4925)
			)
			(stroke
				(width 0)
				(type default)
			)
			(fill yes)
			(layer "F.SilkS")
		)
		(fp_poly
			(pts
				(xy -2.549906 -3.050032) (xy -2.549906 3.050032) (xy 2.549906 3.050032) (xy 2.549906 -3.050032)
			)
			(stroke
				(width 0)
				(type default)
			)
			(fill no)
			(layer "F.CrtYd")
		)
		(fp_line
			(start 2.549906 -3.050032)
			(end 2.549906 3.050032)
			(stroke
				(width 0.1)
				(type default)
			)
			(layer "F.Fab")
		)
		(fp_line
			(start -2.549906 -3.050032)
			(end 2.549906 -3.050032)
			(stroke
				(width 0.1)
				(type default)
			)
			(layer "F.Fab")
		)
		(fp_line
			(start 2.549906 3.050032)
			(end -2.549906 3.050032)
			(stroke
				(width 0.1)
				(type default)
			)
			(layer "F.Fab")
		)
		(fp_line
			(start -2.549906 3.050032)
			(end -2.549906 -3.050032)
			(stroke
				(width 0.1)
				(type default)
			)
			(layer "F.Fab")
		)
		(fp_circle
			(center -3.057398 -2.678684)
			(end -3.057398 -2.551684)
			(stroke
				(width 0.254)
				(type default)
			)
			(fill no)
			(layer "F.Fab")
		)
		(pad "1" smd rect
			(at -2.39522 -2.279904 90)
			(size 0.7112 0.254)
			(layers "F.Cu" "F.Mask" "F.Paste")
			(net "PVDDQ_KLM")
		)
		(pad "2" smd rect
			(at -2.39522 -1.83007 90)
			(size 0.7112 0.254)
			(layers "F.Cu" "F.Mask" "F.Paste")
			(net "GND")
		)
		(pad "3" smd rect
			(at -2.39522 -1.379982 90)
			(size 0.7112 0.254)
			(layers "F.Cu" "F.Mask" "F.Paste")
			(net "VR_PVDDQ_KLM_PH1_VCIN")
		)
		(pad "4" smd rect
			(at -2.39522 -0.929894 90)
			(size 0.7112 0.254)
			(layers "F.Cu" "F.Mask" "F.Paste")
			(net "P5V_STBY")
		)
		(pad "5" smd rect
			(at -2.39522 -0.48006 90)
			(size 0.7112 0.254)
			(layers "F.Cu" "F.Mask" "F.Paste")
			(net "GND")
		)
		(pad "6" smd rect
			(at -2.39522 -0.029972 90)
			(size 0.7112 0.254)
			(layers "F.Cu" "F.Mask" "F.Paste")
			(net "TP_PVDDQ_KLM_PH1_GL_0")
		)
		(pad "7" smd custom
			(at 0.016764 1.145032 90)
			(size 0.53975 0.53975)
			(layers "F.Cu" "F.Mask" "F.Paste")
			(net "GND")
			(options
				(clearance outline)
				(anchor circle)
			)
			(primitives
				(gr_poly
					(pts
						(xy -2.7051 1.0795) (xy -2.7051 -0.3683) (xy -0.9271 -0.3683) (xy -0.9271 -1.0795) (xy 2.7051 -1.0795)
						(xy 2.7051 1.0795)
					)
					(width 0)
					(fill yes)
				)
			)
		)
		(pad "10" smd rect
			(at -0.008382 2.874772 90)
			(size 4.3434 0.6096)
			(layers "F.Cu" "F.Mask" "F.Paste")
			(net "VR_PVDDQ_KLM_PH1_SW")
		)
		(pad "25" smd rect
			(at 1.548384 -1.283208 90)
			(size 2.3368 2.0066)
			(layers "F.Cu" "F.Mask" "F.Paste")
			(net "VR_FET_SW_P12V_STBY_PVDDQ_KLM")
		)
		(pad "30" smd rect
			(at 2.050034 -2.895092 90)
			(size 0.254 0.7112)
			(layers "F.Cu" "F.Mask" "F.Paste")
			(net "VR_FET_SW_P12V_STBY_PVDDQ_KLM")
		)
		(pad "31" smd rect
			(at 1.599946 -2.895092 90)
			(size 0.254 0.7112)
			(layers "F.Cu" "F.Mask" "F.Paste")
			(net "Net_372")
		)
		(pad "32" smd rect
			(at 1.150112 -2.895092 90)
			(size 0.254 0.7112)
			(layers "F.Cu" "F.Mask" "F.Paste")
			(net "VR_PVDDQ_KLM_PH1_PHASE")
		)
		(pad "33" smd rect
			(at 0.700024 -2.895092 90)
			(size 0.254 0.7112)
			(layers "F.Cu" "F.Mask" "F.Paste")
			(net "VR_PVDDQ_KLM_PH1_BOOT_R")
		)
		(pad "34" smd rect
			(at 0.249936 -2.895092 90)
			(size 0.254 0.7112)
			(layers "F.Cu" "F.Mask" "F.Paste")
			(net "VR_PVDDQ_KLM_PWM1")
		)
		(pad "35" smd rect
			(at -0.199898 -2.895092 90)
			(size 0.254 0.7112)
			(layers "F.Cu" "F.Mask" "F.Paste")
			(net "P5V_STBY")
		)
		(pad "36" smd rect
			(at -0.649986 -2.895092 90)
			(size 0.254 0.7112)
			(layers "F.Cu" "F.Mask" "F.Paste")
			(net "A_TSENSE_PVDDQ_KLM")
		)
		(pad "37" smd rect
			(at -1.100074 -2.895092 90)
			(size 0.254 0.7112)
			(layers "F.Cu" "F.Mask" "F.Paste")
			(net "VR_PVDDQ_KLM_PH1_OCSET")
		)
		(pad "38" smd rect
			(at -1.549908 -2.895092 90)
			(size 0.254 0.7112)
			(layers "F.Cu" "F.Mask" "F.Paste")
			(net "ISENSE_PVDDQ_KLM_PH1_IMON")
		)
		(pad "39" smd rect
			(at -1.999996 -2.895092 90)
			(size 0.254 0.7112)
			(layers "F.Cu" "F.Mask" "F.Paste")
			(net "VR_PVDDQ_KLM_AIREF1")
		)
		(pad "40" smd rect
			(at -0.871728 -1.283208 90)
			(size 1.8034 2.0066)
			(layers "F.Cu" "F.Mask" "F.Paste")
			(net "GND")
		)
		(pad "41" smd rect
			(at -1.533906 0.247904 90)
			(size 0.508 0.3556)
			(layers "F.Cu" "F.Mask" "F.Paste")
			(net "TP_PVDDQ_KLM_PH1_GL_1")
		)
	)
	(footprint ""
		(layer "F.Cu")
		(at 19.558 -70.866)
		(property "Reference" "C1D26"
			(at 0 0 0)
			(layer "F.SilkS")
			(hide yes)
			(effects
				(font
					(size 1.27 1.27)
				)
			)
		)
		(property "Value" ""
			(at 0 0 0)
			(layer "F.Fab")
			(effects
				(font
					(size 1.27 1.27)
				)
			)
		)
		(duplicate_pad_numbers_are_jumpers no)
		(fp_poly
			(pts
				(xy 0.3048 -0.1016) (xy 0.3048 0.9906) (xy -0.3048 0.9906) (xy -0.3048 -0.1016)
			)
			(stroke
				(width 0)
				(type default)
			)
			(fill no)
			(layer "F.CrtYd")
		)
		(fp_line
			(start -0.3048 -0.1016)
			(end -0.3048 0.9906)
			(stroke
				(width 0.1)
				(type default)
			)
			(layer "F.Fab")
		)
		(fp_line
			(start -0.3048 0.9906)
			(end 0.3048 0.9906)
			(stroke
				(width 0.1)
				(type default)
			)
			(layer "F.Fab")
		)
		(fp_line
			(start 0.3048 -0.1016)
			(end -0.3048 -0.1016)
			(stroke
				(width 0.1)
				(type default)
			)
			(layer "F.Fab")
		)
		(fp_line
			(start 0.3048 0.9906)
			(end 0.3048 -0.1016)
			(stroke
				(width 0.1)
				(type default)
			)
			(layer "F.Fab")
		)
		(pad "1" smd rect
			(at 0 0)
			(size 0.508 0.508)
			(layers "F.Cu" "F.Mask" "F.Paste")
			(net "A_HSC_UV")
		)
		(pad "2" smd rect
			(at 0 0.889)
			(size 0.508 0.508)
			(layers "F.Cu" "F.Mask" "F.Paste")
			(net "AGND_HSC")
		)
		(zone
			(layer "F.Cu")
			(hatch none 0.5)
			(connect_pads
				(clearance 0)
			)
			(min_thickness 0.25)
			(keepout
				(tracks allowed)
				(vias not_allowed)
				(pads allowed)
				(copperpour not_allowed)
				(footprints allowed)
			)
			(placement
				(enabled no)
				(sheetname "")
			)
			(fill
				(thermal_gap 0.5)
				(thermal_bridge_width 0.5)
				(island_removal_mode 0)
			)
			(polygon
				(pts
					(xy 19.304 -70.612) (xy 19.812 -70.612) (xy 19.812 -70.231) (xy 19.304 -70.231)
				)
			)
		)
		(zone
			(layer "F.Cu")
			(hatch none 0.5)
			(connect_pads
				(clearance 0)
			)
			(min_thickness 0.25)
			(keepout
				(tracks not_allowed)
				(vias allowed)
				(pads allowed)
				(copperpour not_allowed)
				(footprints allowed)
			)
			(placement
				(enabled no)
				(sheetname "")
			)
			(fill
				(thermal_gap 0.5)
				(thermal_bridge_width 0.5)
				(island_removal_mode 0)
			)
			(polygon
				(pts
					(xy 19.304 -70.231) (xy 19.812 -70.231) (xy 19.812 -70.612) (xy 19.304 -70.612)
				)
			)
		)
	)
	(footprint ""
		(layer "F.Cu")
		(at 477.978724 -150.256494)
		(property "Reference" "R1L2"
			(at 0 0 0)
			(layer "F.SilkS")
			(hide yes)
			(effects
				(font
					(size 1.27 1.27)
				)
			)
		)
		(property "Value" ""
			(at 0 0 0)
			(layer "F.Fab")
			(effects
				(font
					(size 1.27 1.27)
				)
			)
		)
		(duplicate_pad_numbers_are_jumpers no)
		(fp_poly
			(pts
				(xy -0.2794 -0.1016) (xy 0.2794 -0.1016) (xy 0.2794 0.9906) (xy -0.2794 0.9906)
			)
			(stroke
				(width 0)
				(type default)
			)
			(fill no)
			(layer "F.CrtYd")
		)
		(fp_line
			(start -0.2794 -0.1016)
			(end -0.2794 0.9906)
			(stroke
				(width 0.1)
				(type default)
			)
			(layer "F.Fab")
		)
		(fp_line
			(start -0.2794 0.9906)
			(end 0.2794 0.9906)
			(stroke
				(width 0.1)
				(type default)
			)
			(layer "F.Fab")
		)
		(fp_line
			(start 0.2794 -0.1016)
			(end -0.2794 -0.1016)
			(stroke
				(width 0.1)
				(type default)
			)
			(layer "F.Fab")
		)
		(fp_line
			(start 0.2794 0.9906)
			(end 0.2794 -0.1016)
			(stroke
				(width 0.1)
				(type default)
			)
			(layer "F.Fab")
		)
		(pad "1" smd rect
			(at 0 0)
			(size 0.508 0.508)
			(layers "F.Cu" "F.Mask" "F.Paste")
			(net "FM_CPLD_DBG_PWR_EN_N")
		)
		(pad "2" smd rect
			(at 0 0.889)
			(size 0.508 0.508)
			(layers "F.Cu" "F.Mask" "F.Paste")
			(net "FM_CPLD_DBG_PWR_EN_R_N")
		)
		(zone
			(layer "F.Cu")
			(hatch none 0.5)
			(connect_pads
				(clearance 0)
			)
			(min_thickness 0.25)
			(keepout
				(tracks allowed)
				(vias not_allowed)
				(pads allowed)
				(copperpour not_allowed)
				(footprints allowed)
			)
			(placement
				(enabled no)
				(sheetname "")
			)
			(fill
				(thermal_gap 0.5)
				(thermal_bridge_width 0.5)
				(island_removal_mode 0)
			)
			(polygon
				(pts
					(xy 477.724724 -150.002494) (xy 478.232724 -150.002494) (xy 478.232724 -149.621494) (xy 477.724724 -149.621494)
				)
			)
		)
		(zone
			(layer "F.Cu")
			(hatch none 0.5)
			(connect_pads
				(clearance 0)
			)
			(min_thickness 0.25)
			(keepout
				(tracks not_allowed)
				(vias allowed)
				(pads allowed)
				(copperpour not_allowed)
				(footprints allowed)
			)
			(placement
				(enabled no)
				(sheetname "")
			)
			(fill
				(thermal_gap 0.5)
				(thermal_bridge_width 0.5)
				(island_removal_mode 0)
			)
			(polygon
				(pts
					(xy 477.724724 -149.621494) (xy 478.232724 -149.621494) (xy 478.232724 -150.002494) (xy 477.724724 -150.002494)
				)
			)
		)
	)
	(footprint ""
		(layer "F.Cu")
		(at 29.699458 -133.0706 90)
		(property "Reference" "J1B1"
			(at -4.960112 38.372542 0)
			(unlocked yes)
			(layer "F.SilkS")
			(effects
				(font
					(size 0.7874 0.5842)
					(thickness 0.1524)
				)
				(justify left)
			)
		)
		(property "Value" ""
			(at 0 0 90)
			(layer "F.Fab")
			(effects
				(font
					(size 1.27 1.27)
				)
			)
		)
		(duplicate_pad_numbers_are_jumpers no)
		(fp_line
			(start 5.5499 -7.675118)
			(end 5.5499 -1.480058)
			(stroke
				(width 0.1524)
				(type default)
			)
			(layer "F.SilkS")
		)
		(fp_line
			(start -0.94996 -7.675118)
			(end 5.5499 -7.675118)
			(stroke
				(width 0.1524)
				(type default)
			)
			(layer "F.SilkS")
		)
		(fp_line
			(start -0.94996 -1.480058)
			(end -0.94996 -7.675118)
			(stroke
				(width 0.1524)
				(type default)
			)
			(layer "F.SilkS")
		)
		(fp_line
			(start 5.5499 128.130046)
			(end 5.5499 134.325106)
			(stroke
				(width 0.1524)
				(type default)
			)
			(layer "F.SilkS")
		)
		(fp_line
			(start 5.5499 134.325106)
			(end -0.94996 134.325106)
			(stroke
				(width 0.1524)
				(type default)
			)
			(layer "F.SilkS")
		)
		(fp_line
			(start -0.94996 134.325106)
			(end -0.94996 128.130046)
			(stroke
				(width 0.1524)
				(type default)
			)
			(layer "F.SilkS")
		)
		(fp_poly
			(pts
				(xy -2.984246 -0.461264) (xy -2.984246 0.554736) (xy -1.714246 0.046736)
			)
			(stroke
				(width 0)
				(type default)
			)
			(fill yes)
			(layer "F.SilkS")
		)
		(fp_poly
			(pts
				(xy -0.94996 -7.675118) (xy -0.94996 134.325106) (xy 5.5499 134.325106) (xy 5.5499 -7.675118)
			)
			(stroke
				(width 0)
				(type default)
			)
			(fill no)
			(layer "F.CrtYd")
		)
		(fp_line
			(start 5.5499 -7.675118)
			(end 5.5499 134.325106)
			(stroke
				(width 0.1)
				(type default)
			)
			(layer "F.Fab")
		)
		(fp_line
			(start -0.94996 -7.675118)
			(end 5.5499 -7.675118)
			(stroke
				(width 0.1)
				(type default)
			)
			(layer "F.Fab")
		)
		(fp_line
			(start 5.5499 134.325106)
			(end -0.94996 134.325106)
			(stroke
				(width 0.1)
				(type default)
			)
			(layer "F.Fab")
		)
		(fp_line
			(start -0.94996 134.325106)
			(end -0.94996 -7.675118)
			(stroke
				(width 0.1)
				(type default)
			)
			(layer "F.Fab")
		)
		(fp_poly
			(pts
				(xy -2.984246 -0.461264) (xy -2.984246 0.554736) (xy -1.714246 0.046736)
			)
			(stroke
				(width 0)
				(type default)
			)
			(fill yes)
			(layer "F.Fab")
		)
		(fp_text user "145"
			(at 6.066028 -0.773938 0)
			(unlocked yes)
			(layer "F.SilkS")
			(effects
				(font
					(size 0.7874 0.5842)
					(thickness 0.1524)
				)
				(justify left)
			)
		)
		(fp_text user "77"
			(at -2.216912 63.899542 0)
			(unlocked yes)
			(layer "F.SilkS")
			(effects
				(font
					(size 0.7874 0.5842)
					(thickness 0.1524)
				)
				(justify left)
			)
		)
		(fp_text user "221"
			(at 5.555488 65.296542 0)
			(unlocked yes)
			(layer "F.SilkS")
			(effects
				(font
					(size 0.7874 0.5842)
					(thickness 0.1524)
				)
				(justify left)
			)
		)
		(fp_text user "222"
			(at 6.02488 69.83984 0)
			(unlocked yes)
			(layer "F.SilkS")
			(effects
				(font
					(size 0.7874 0.5842)
					(thickness 0.1524)
				)
				(justify left)
			)
		)
		(fp_text user "78"
			(at -1.810512 69.995542 0)
			(unlocked yes)
			(layer "F.SilkS")
			(effects
				(font
					(size 0.7874 0.5842)
					(thickness 0.1524)
				)
				(justify left)
			)
		)
		(fp_text user "144"
			(at -1.708912 127.653542 0)
			(unlocked yes)
			(layer "F.SilkS")
			(effects
				(font
					(size 0.7874 0.5842)
					(thickness 0.1524)
				)
				(justify left)
			)
		)
		(fp_text user "288"
			(at 6.444488 128.288542 0)
			(unlocked yes)
			(layer "F.SilkS")
			(effects
				(font
					(size 0.7874 0.5842)
					(thickness 0.1524)
				)
				(justify left)
			)
		)
		(fp_text user "145"
			(at 2.8829 -1.597152 90)
			(unlocked yes)
			(layer "F.Fab")
			(effects
				(font
					(size 0.7874 0.5842)
					(thickness 0.1524)
				)
				(justify left)
			)
		)
		(fp_text user "221"
			(at 2.5019 65.712848 90)
			(unlocked yes)
			(layer "F.Fab")
			(effects
				(font
					(size 0.7874 0.5842)
					(thickness 0.1524)
				)
				(justify left)
			)
		)
		(fp_text user "77"
			(at -0.361442 65.831212 90)
			(unlocked yes)
			(layer "F.Fab")
			(effects
				(font
					(size 0.7874 0.5842)
					(thickness 0.1524)
				)
				(justify left)
			)
		)
		(fp_text user "222"
			(at 4.562094 67.773042 0)
			(unlocked yes)
			(layer "F.Fab")
			(effects
				(font
					(size 0.7874 0.5842)
					(thickness 0.1524)
				)
				(justify left)
			)
		)
		(fp_text user "78"
			(at -0.7874 69.395848 90)
			(unlocked yes)
			(layer "F.Fab")
			(effects
				(font
					(size 0.7874 0.5842)
					(thickness 0.1524)
				)
				(justify left)
			)
		)
		(fp_text user "288"
			(at 3.448558 128.061212 90)
			(unlocked yes)
			(layer "F.Fab")
			(effects
				(font
					(size 0.7874 0.5842)
					(thickness 0.1524)
				)
				(justify left)
			)
		)
		(fp_text user "144"
			(at -0.361442 128.061212 90)
			(unlocked yes)
			(layer "F.Fab")
			(effects
				(font
					(size 0.7874 0.5842)
					(thickness 0.1524)
				)
				(justify left)
			)
		)
		(pad "" thru_hole circle
			(at 2.29997 -5.649976 90)
			(size 2.8194 2.8194)
			(drill 2.4384)
			(layers "*.Cu" "*.Mask")
			(remove_unused_layers no)
			(clearance 0.127)
			(thermal_gap 0.127)
		)
		(pad "" thru_hole oval
			(at 2.29997 68.90004 90)
			(size 2.8194 1.5748)
			(drill oval 2.4384 1.1938)
			(layers "*.Cu" "*.Mask")
			(remove_unused_layers no)
			(clearance 0.127)
			(thermal_gap 0.127)
		)
		(pad "" thru_hole circle
			(at 2.29997 132.299964 90)
			(size 2.8194 2.8194)
			(drill 2.4384)
			(layers "*.Cu" "*.Mask")
			(remove_unused_layers no)
			(clearance 0.127)
			(thermal_gap 0.127)
		)
		(pad "1" smd rect
			(at 0 0 90)
			(size 1.8034 0.508)
			(layers "F.Cu" "F.Mask" "F.Paste")
			(net "P12V_NVDIMM_KLM")
		)
		(pad "2" smd rect
			(at 0 0.849884 90)
			(size 1.8034 0.508)
			(layers "F.Cu" "F.Mask" "F.Paste")
			(net "GND")
		)
		(pad "3" smd rect
			(at 0 1.700022 90)
			(size 1.8034 0.508)
			(layers "F.Cu" "F.Mask" "F.Paste")
			(net "M_K_DQ<5>")
		)
		(pad "4" smd rect
			(at 0 2.549906 90)
			(size 1.8034 0.508)
			(layers "F.Cu" "F.Mask" "F.Paste")
			(net "GND")
		)
		(pad "5" smd rect
			(at 0 3.400044 90)
			(size 1.8034 0.508)
			(layers "F.Cu" "F.Mask" "F.Paste")
			(net "M_K_DQ<1>")
		)
		(pad "6" smd rect
			(at 0 4.249928 90)
			(size 1.8034 0.508)
			(layers "F.Cu" "F.Mask" "F.Paste")
			(net "GND")
		)
		(pad "7" smd rect
			(at 0 5.100066 90)
			(size 1.8034 0.508)
			(layers "F.Cu" "F.Mask" "F.Paste")
			(net "M_K_DQS_DP<9>")
		)
		(pad "8" smd rect
			(at 0 5.94995 90)
			(size 1.8034 0.508)
			(layers "F.Cu" "F.Mask" "F.Paste")
			(net "M_K_DQS_DN<9>")
		)
		(pad "9" smd rect
			(at 0 6.800088 90)
			(size 1.8034 0.508)
			(layers "F.Cu" "F.Mask" "F.Paste")
			(net "GND")
		)
		(pad "10" smd rect
			(at 0 7.649972 90)
			(size 1.8034 0.508)
			(layers "F.Cu" "F.Mask" "F.Paste")
			(net "M_K_DQ<7>")
		)
		(pad "11" smd rect
			(at 0 8.50011 90)
			(size 1.8034 0.508)
			(layers "F.Cu" "F.Mask" "F.Paste")
			(net "GND")
		)
		(pad "12" smd rect
			(at 0 9.349994 90)
			(size 1.8034 0.508)
			(layers "F.Cu" "F.Mask" "F.Paste")
			(net "M_K_DQ<3>")
		)
		(pad "13" smd rect
			(at 0 10.199878 90)
			(size 1.8034 0.508)
			(layers "F.Cu" "F.Mask" "F.Paste")
			(net "GND")
		)
		(pad "14" smd rect
			(at 0 11.050016 90)
			(size 1.8034 0.508)
			(layers "F.Cu" "F.Mask" "F.Paste")
			(net "M_K_DQ<13>")
		)
		(pad "15" smd rect
			(at 0 11.8999 90)
			(size 1.8034 0.508)
			(layers "F.Cu" "F.Mask" "F.Paste")
			(net "GND")
		)
		(pad "16" smd rect
			(at 0 12.750038 90)
			(size 1.8034 0.508)
			(layers "F.Cu" "F.Mask" "F.Paste")
			(net "M_K_DQ<9>")
		)
		(pad "17" smd rect
			(at 0 13.599922 90)
			(size 1.8034 0.508)
			(layers "F.Cu" "F.Mask" "F.Paste")
			(net "GND")
		)
		(pad "18" smd rect
			(at 0 14.45006 90)
			(size 1.8034 0.508)
			(layers "F.Cu" "F.Mask" "F.Paste")
			(net "M_K_DQS_DP<10>")
		)
		(pad "19" smd rect
			(at 0 15.299944 90)
			(size 1.8034 0.508)
			(layers "F.Cu" "F.Mask" "F.Paste")
			(net "M_K_DQS_DN<10>")
		)
		(pad "20" smd rect
			(at 0 16.150082 90)
			(size 1.8034 0.508)
			(layers "F.Cu" "F.Mask" "F.Paste")
			(net "GND")
		)
		(pad "21" smd rect
			(at 0 16.999966 90)
			(size 1.8034 0.508)
			(layers "F.Cu" "F.Mask" "F.Paste")
			(net "M_K_DQ<15>")
		)
		(pad "22" smd rect
			(at 0 17.850104 90)
			(size 1.8034 0.508)
			(layers "F.Cu" "F.Mask" "F.Paste")
			(net "GND")
		)
		(pad "23" smd rect
			(at 0 18.699988 90)
			(size 1.8034 0.508)
			(layers "F.Cu" "F.Mask" "F.Paste")
			(net "M_K_DQ<11>")
		)
		(pad "24" smd rect
			(at 0 19.550126 90)
			(size 1.8034 0.508)
			(layers "F.Cu" "F.Mask" "F.Paste")
			(net "GND")
		)
		(pad "25" smd rect
			(at 0 20.40001 90)
			(size 1.8034 0.508)
			(layers "F.Cu" "F.Mask" "F.Paste")
			(net "M_K_DQ<21>")
		)
		(pad "26" smd rect
			(at 0 21.249894 90)
			(size 1.8034 0.508)
			(layers "F.Cu" "F.Mask" "F.Paste")
			(net "GND")
		)
		(pad "27" smd rect
			(at 0 22.100032 90)
			(size 1.8034 0.508)
			(layers "F.Cu" "F.Mask" "F.Paste")
			(net "M_K_DQ<17>")
		)
		(pad "28" smd rect
			(at 0 22.949916 90)
			(size 1.8034 0.508)
			(layers "F.Cu" "F.Mask" "F.Paste")
			(net "GND")
		)
		(pad "29" smd rect
			(at 0 23.800054 90)
			(size 1.8034 0.508)
			(layers "F.Cu" "F.Mask" "F.Paste")
			(net "M_K_DQS_DP<11>")
		)
		(pad "30" smd rect
			(at 0 24.649938 90)
			(size 1.8034 0.508)
			(layers "F.Cu" "F.Mask" "F.Paste")
			(net "M_K_DQS_DN<11>")
		)
		(pad "31" smd rect
			(at 0 25.500076 90)
			(size 1.8034 0.508)
			(layers "F.Cu" "F.Mask" "F.Paste")
			(net "GND")
		)
		(pad "32" smd rect
			(at 0 26.34996 90)
			(size 1.8034 0.508)
			(layers "F.Cu" "F.Mask" "F.Paste")
			(net "M_K_DQ<23>")
		)
		(pad "33" smd rect
			(at 0 27.200098 90)
			(size 1.8034 0.508)
			(layers "F.Cu" "F.Mask" "F.Paste")
			(net "GND")
		)
		(pad "34" smd rect
			(at 0 28.049982 90)
			(size 1.8034 0.508)
			(layers "F.Cu" "F.Mask" "F.Paste")
			(net "M_K_DQ<19>")
		)
		(pad "35" smd rect
			(at 0 28.90012 90)
			(size 1.8034 0.508)
			(layers "F.Cu" "F.Mask" "F.Paste")
			(net "GND")
		)
		(pad "36" smd rect
			(at 0 29.750004 90)
			(size 1.8034 0.508)
			(layers "F.Cu" "F.Mask" "F.Paste")
			(net "M_K_DQ<29>")
		)
		(pad "37" smd rect
			(at 0 30.599888 90)
			(size 1.8034 0.508)
			(layers "F.Cu" "F.Mask" "F.Paste")
			(net "GND")
		)
		(pad "38" smd rect
			(at 0 31.450026 90)
			(size 1.8034 0.508)
			(layers "F.Cu" "F.Mask" "F.Paste")
			(net "M_K_DQ<25>")
		)
		(pad "39" smd rect
			(at 0 32.29991 90)
			(size 1.8034 0.508)
			(layers "F.Cu" "F.Mask" "F.Paste")
			(net "GND")
		)
		(pad "40" smd rect
			(at 0 33.150048 90)
			(size 1.8034 0.508)
			(layers "F.Cu" "F.Mask" "F.Paste")
			(net "M_K_DQS_DP<12>")
		)
		(pad "41" smd rect
			(at 0 33.999932 90)
			(size 1.8034 0.508)
			(layers "F.Cu" "F.Mask" "F.Paste")
			(net "M_K_DQS_DN<12>")
		)
		(pad "42" smd rect
			(at 0 34.85007 90)
			(size 1.8034 0.508)
			(layers "F.Cu" "F.Mask" "F.Paste")
			(net "GND")
		)
		(pad "43" smd rect
			(at 0 35.699954 90)
			(size 1.8034 0.508)
			(layers "F.Cu" "F.Mask" "F.Paste")
			(net "M_K_DQ<31>")
		)
		(pad "44" smd rect
			(at 0 36.550092 90)
			(size 1.8034 0.508)
			(layers "F.Cu" "F.Mask" "F.Paste")
			(net "GND")
		)
		(pad "45" smd rect
			(at 0 37.399976 90)
			(size 1.8034 0.508)
			(layers "F.Cu" "F.Mask" "F.Paste")
			(net "M_K_DQ<27>")
		)
		(pad "46" smd rect
			(at 0 38.250114 90)
			(size 1.8034 0.508)
			(layers "F.Cu" "F.Mask" "F.Paste")
			(net "GND")
		)
		(pad "47" smd rect
			(at 0 39.099998 90)
			(size 1.8034 0.508)
			(layers "F.Cu" "F.Mask" "F.Paste")
			(net "M_K_ECC<5>")
		)
		(pad "48" smd rect
			(at 0 39.949882 90)
			(size 1.8034 0.508)
			(layers "F.Cu" "F.Mask" "F.Paste")
			(net "GND")
		)
		(pad "49" smd rect
			(at 0 40.80002 90)
			(size 1.8034 0.508)
			(layers "F.Cu" "F.Mask" "F.Paste")
			(net "M_K_ECC<1>")
		)
		(pad "50" smd rect
			(at 0 41.649904 90)
			(size 1.8034 0.508)
			(layers "F.Cu" "F.Mask" "F.Paste")
			(net "GND")
		)
		(pad "51" smd rect
			(at 0 42.500042 90)
			(size 1.8034 0.508)
			(layers "F.Cu" "F.Mask" "F.Paste")
			(net "M_K_DQS_DP<17>")
		)
		(pad "52" smd rect
			(at 0 43.349926 90)
			(size 1.8034 0.508)
			(layers "F.Cu" "F.Mask" "F.Paste")
			(net "M_K_DQS_DN<17>")
		)
		(pad "53" smd rect
			(at 0 44.200064 90)
			(size 1.8034 0.508)
			(layers "F.Cu" "F.Mask" "F.Paste")
			(net "GND")
		)
		(pad "54" smd rect
			(at 0 45.049948 90)
			(size 1.8034 0.508)
			(layers "F.Cu" "F.Mask" "F.Paste")
			(net "M_K_ECC<7>")
		)
		(pad "55" smd rect
			(at 0 45.900086 90)
			(size 1.8034 0.508)
			(layers "F.Cu" "F.Mask" "F.Paste")
			(net "GND")
		)
		(pad "56" smd rect
			(at 0 46.74997 90)
			(size 1.8034 0.508)
			(layers "F.Cu" "F.Mask" "F.Paste")
			(net "M_K_ECC<3>")
		)
		(pad "57" smd rect
			(at 0 47.600108 90)
			(size 1.8034 0.508)
			(layers "F.Cu" "F.Mask" "F.Paste")
			(net "GND")
		)
		(pad "58" smd rect
			(at 0 48.449992 90)
			(size 1.8034 0.508)
			(layers "F.Cu" "F.Mask" "F.Paste")
			(net "M_KLM_RST_N")
		)
		(pad "59" smd rect
			(at 0 49.299876 90)
			(size 1.8034 0.508)
			(layers "F.Cu" "F.Mask" "F.Paste")
			(net "PVDDQ_KLM")
		)
		(pad "60" smd rect
			(at 0 50.150014 90)
			(size 1.8034 0.508)
			(layers "F.Cu" "F.Mask" "F.Paste")
			(net "M_K_CKE<0>")
		)
		(pad "61" smd rect
			(at 0 50.999898 90)
			(size 1.8034 0.508)
			(layers "F.Cu" "F.Mask" "F.Paste")
			(net "PVDDQ_KLM")
		)
		(pad "62" smd rect
			(at 0 51.850036 90)
			(size 1.8034 0.508)
			(layers "F.Cu" "F.Mask" "F.Paste")
			(net "M_K_ACT_N")
		)
		(pad "63" smd rect
			(at 0 52.69992 90)
			(size 1.8034 0.508)
			(layers "F.Cu" "F.Mask" "F.Paste")
			(net "M_K_BG<0>")
		)
		(pad "64" smd rect
			(at 0 53.550058 90)
			(size 1.8034 0.508)
			(layers "F.Cu" "F.Mask" "F.Paste")
			(net "PVDDQ_KLM")
		)
		(pad "65" smd rect
			(at 0 54.399942 90)
			(size 1.8034 0.508)
			(layers "F.Cu" "F.Mask" "F.Paste")
			(net "M_K_MA<12>")
		)
		(pad "66" smd rect
			(at 0 55.25008 90)
			(size 1.8034 0.508)
			(layers "F.Cu" "F.Mask" "F.Paste")
			(net "M_K_MA<9>")
		)
		(pad "67" smd rect
			(at 0 56.099964 90)
			(size 1.8034 0.508)
			(layers "F.Cu" "F.Mask" "F.Paste")
			(net "PVDDQ_KLM")
		)
		(pad "68" smd rect
			(at 0 56.950102 90)
			(size 1.8034 0.508)
			(layers "F.Cu" "F.Mask" "F.Paste")
			(net "M_K_MA<8>")
		)
		(pad "69" smd rect
			(at 0 57.799986 90)
			(size 1.8034 0.508)
			(layers "F.Cu" "F.Mask" "F.Paste")
			(net "M_K_MA<6>")
		)
		(pad "70" smd rect
			(at 0 58.650124 90)
			(size 1.8034 0.508)
			(layers "F.Cu" "F.Mask" "F.Paste")
			(net "PVDDQ_KLM")
		)
		(pad "71" smd rect
			(at 0 59.500008 90)
			(size 1.8034 0.508)
			(layers "F.Cu" "F.Mask" "F.Paste")
			(net "M_K_MA<3>")
		)
		(pad "72" smd rect
			(at 0 60.349892 90)
			(size 1.8034 0.508)
			(layers "F.Cu" "F.Mask" "F.Paste")
			(net "M_K_MA<1>")
		)
		(pad "73" smd rect
			(at 0 61.20003 90)
			(size 1.8034 0.508)
			(layers "F.Cu" "F.Mask" "F.Paste")
			(net "PVDDQ_KLM")
		)
		(pad "74" smd rect
			(at 0 62.049914 90)
			(size 1.8034 0.508)
			(layers "F.Cu" "F.Mask" "F.Paste")
			(net "M_K_CLK_DP<0>")
		)
		(pad "75" smd rect
			(at 0 62.900052 90)
			(size 1.8034 0.508)
			(layers "F.Cu" "F.Mask" "F.Paste")
			(net "M_K_CLK_DN<0>")
		)
		(pad "76" smd rect
			(at 0 63.749936 90)
			(size 1.8034 0.508)
			(layers "F.Cu" "F.Mask" "F.Paste")
			(net "PVDDQ_KLM")
		)
		(pad "77" smd rect
			(at 0 64.600074 90)
			(size 1.8034 0.508)
			(layers "F.Cu" "F.Mask" "F.Paste")
			(net "PVTT_KLM")
		)
		(pad "78" smd rect
			(at 0 70.550024 90)
			(size 1.8034 0.508)
			(layers "F.Cu" "F.Mask" "F.Paste")
			(net "FM_DIMM_EVENT_COD_N")
		)
		(pad "79" smd rect
			(at 0 71.399908 90)
			(size 1.8034 0.508)
			(layers "F.Cu" "F.Mask" "F.Paste")
			(net "M_K_MA<0>")
		)
		(pad "80" smd rect
			(at 0 72.250046 90)
			(size 1.8034 0.508)
			(layers "F.Cu" "F.Mask" "F.Paste")
			(net "PVDDQ_KLM")
		)
		(pad "81" smd rect
			(at 0 73.09993 90)
			(size 1.8034 0.508)
			(layers "F.Cu" "F.Mask" "F.Paste")
			(net "M_K_BA<0>")
		)
		(pad "82" smd rect
			(at 0 73.950068 90)
			(size 1.8034 0.508)
			(layers "F.Cu" "F.Mask" "F.Paste")
			(net "M_K_MA<16>")
		)
		(pad "83" smd rect
			(at 0 74.799952 90)
			(size 1.8034 0.508)
			(layers "F.Cu" "F.Mask" "F.Paste")
			(net "PVDDQ_KLM")
		)
		(pad "84" smd rect
			(at 0 75.65009 90)
			(size 1.8034 0.508)
			(layers "F.Cu" "F.Mask" "F.Paste")
			(net "M_K_CS_N<0>")
		)
		(pad "85" smd rect
			(at 0 76.499974 90)
			(size 1.8034 0.508)
			(layers "F.Cu" "F.Mask" "F.Paste")
			(net "PVDDQ_KLM")
		)
		(pad "86" smd rect
			(at 0 77.350112 90)
			(size 1.8034 0.508)
			(layers "F.Cu" "F.Mask" "F.Paste")
			(net "M_K_MA<15>")
		)
		(pad "87" smd rect
			(at 0 78.199996 90)
			(size 1.8034 0.508)
			(layers "F.Cu" "F.Mask" "F.Paste")
			(net "M_K_ODT<0>")
		)
		(pad "88" smd rect
			(at 0 79.04988 90)
			(size 1.8034 0.508)
			(layers "F.Cu" "F.Mask" "F.Paste")
			(net "PVDDQ_KLM")
		)
		(pad "89" smd rect
			(at 0 79.900018 90)
			(size 1.8034 0.508)
			(layers "F.Cu" "F.Mask" "F.Paste")
			(net "M_K_CS_N<1>")
		)
		(pad "90" smd rect
			(at 0 80.749902 90)
			(size 1.8034 0.508)
			(layers "F.Cu" "F.Mask" "F.Paste")
			(net "PVDDQ_KLM")
		)
		(pad "91" smd rect
			(at 0 81.60004 90)
			(size 1.8034 0.508)
			(layers "F.Cu" "F.Mask" "F.Paste")
			(net "M_K_ODT<1>")
		)
		(pad "92" smd rect
			(at 0 82.449924 90)
			(size 1.8034 0.508)
			(layers "F.Cu" "F.Mask" "F.Paste")
			(net "PVDDQ_KLM")
		)
		(pad "93" smd rect
			(at 0 83.300062 90)
			(size 1.8034 0.508)
			(layers "F.Cu" "F.Mask" "F.Paste")
			(net "M_K_CS_N<2>")
		)
		(pad "94" smd rect
			(at 0 84.149946 90)
			(size 1.8034 0.508)
			(layers "F.Cu" "F.Mask" "F.Paste")
			(net "GND")
		)
		(pad "95" smd rect
			(at 0 85.000084 90)
			(size 1.8034 0.508)
			(layers "F.Cu" "F.Mask" "F.Paste")
			(net "M_K_DQ<37>")
		)
		(pad "96" smd rect
			(at 0 85.849968 90)
			(size 1.8034 0.508)
			(layers "F.Cu" "F.Mask" "F.Paste")
			(net "GND")
		)
		(pad "97" smd rect
			(at 0 86.700106 90)
			(size 1.8034 0.508)
			(layers "F.Cu" "F.Mask" "F.Paste")
			(net "M_K_DQ<33>")
		)
		(pad "98" smd rect
			(at 0 87.54999 90)
			(size 1.8034 0.508)
			(layers "F.Cu" "F.Mask" "F.Paste")
			(net "GND")
		)
		(pad "99" smd rect
			(at 0 88.399874 90)
			(size 1.8034 0.508)
			(layers "F.Cu" "F.Mask" "F.Paste")
			(net "M_K_DQS_DP<13>")
		)
		(pad "100" smd rect
			(at 0 89.250012 90)
			(size 1.8034 0.508)
			(layers "F.Cu" "F.Mask" "F.Paste")
			(net "M_K_DQS_DN<13>")
		)
		(pad "101" smd rect
			(at 0 90.099896 90)
			(size 1.8034 0.508)
			(layers "F.Cu" "F.Mask" "F.Paste")
			(net "GND")
		)
		(pad "102" smd rect
			(at 0 90.950034 90)
			(size 1.8034 0.508)
			(layers "F.Cu" "F.Mask" "F.Paste")
			(net "M_K_DQ<39>")
		)
		(pad "103" smd rect
			(at 0 91.799918 90)
			(size 1.8034 0.508)
			(layers "F.Cu" "F.Mask" "F.Paste")
			(net "GND")
		)
		(pad "104" smd rect
			(at 0 92.650056 90)
			(size 1.8034 0.508)
			(layers "F.Cu" "F.Mask" "F.Paste")
			(net "M_K_DQ<35>")
		)
		(pad "105" smd rect
			(at 0 93.49994 90)
			(size 1.8034 0.508)
			(layers "F.Cu" "F.Mask" "F.Paste")
			(net "GND")
		)
		(pad "106" smd rect
			(at 0 94.350078 90)
			(size 1.8034 0.508)
			(layers "F.Cu" "F.Mask" "F.Paste")
			(net "M_K_DQ<45>")
		)
		(pad "107" smd rect
			(at 0 95.199962 90)
			(size 1.8034 0.508)
			(layers "F.Cu" "F.Mask" "F.Paste")
			(net "GND")
		)
		(pad "108" smd rect
			(at 0 96.0501 90)
			(size 1.8034 0.508)
			(layers "F.Cu" "F.Mask" "F.Paste")
			(net "M_K_DQ<41>")
		)
		(pad "109" smd rect
			(at 0 96.899984 90)
			(size 1.8034 0.508)
			(layers "F.Cu" "F.Mask" "F.Paste")
			(net "GND")
		)
		(pad "110" smd rect
			(at 0 97.750122 90)
			(size 1.8034 0.508)
			(layers "F.Cu" "F.Mask" "F.Paste")
			(net "M_K_DQS_DP<14>")
		)
		(pad "111" smd rect
			(at 0 98.600006 90)
			(size 1.8034 0.508)
			(layers "F.Cu" "F.Mask" "F.Paste")
			(net "M_K_DQS_DN<14>")
		)
		(pad "112" smd rect
			(at 0 99.44989 90)
			(size 1.8034 0.508)
			(layers "F.Cu" "F.Mask" "F.Paste")
			(net "GND")
		)
		(pad "113" smd rect
			(at 0 100.300028 90)
			(size 1.8034 0.508)
			(layers "F.Cu" "F.Mask" "F.Paste")
			(net "M_K_DQ<47>")
		)
		(pad "114" smd rect
			(at 0 101.149912 90)
			(size 1.8034 0.508)
			(layers "F.Cu" "F.Mask" "F.Paste")
			(net "GND")
		)
		(pad "115" smd rect
			(at 0 102.00005 90)
			(size 1.8034 0.508)
			(layers "F.Cu" "F.Mask" "F.Paste")
			(net "M_K_DQ<43>")
		)
		(pad "116" smd rect
			(at 0 102.849934 90)
			(size 1.8034 0.508)
			(layers "F.Cu" "F.Mask" "F.Paste")
			(net "GND")
		)
		(pad "117" smd rect
			(at 0 103.700072 90)
			(size 1.8034 0.508)
			(layers "F.Cu" "F.Mask" "F.Paste")
			(net "M_K_DQ<53>")
		)
		(pad "118" smd rect
			(at 0 104.549956 90)
			(size 1.8034 0.508)
			(layers "F.Cu" "F.Mask" "F.Paste")
			(net "GND")
		)
		(pad "119" smd rect
			(at 0 105.400094 90)
			(size 1.8034 0.508)
			(layers "F.Cu" "F.Mask" "F.Paste")
			(net "M_K_DQ<49>")
		)
		(pad "120" smd rect
			(at 0 106.249978 90)
			(size 1.8034 0.508)
			(layers "F.Cu" "F.Mask" "F.Paste")
			(net "GND")
		)
		(pad "121" smd rect
			(at 0 107.100116 90)
			(size 1.8034 0.508)
			(layers "F.Cu" "F.Mask" "F.Paste")
			(net "M_K_DQS_DP<15>")
		)
		(pad "122" smd rect
			(at 0 107.95 90)
			(size 1.8034 0.508)
			(layers "F.Cu" "F.Mask" "F.Paste")
			(net "M_K_DQS_DN<15>")
		)
		(pad "123" smd rect
			(at 0 108.799884 90)
			(size 1.8034 0.508)
			(layers "F.Cu" "F.Mask" "F.Paste")
			(net "GND")
		)
		(pad "124" smd rect
			(at 0 109.650022 90)
			(size 1.8034 0.508)
			(layers "F.Cu" "F.Mask" "F.Paste")
			(net "M_K_DQ<55>")
		)
		(pad "125" smd rect
			(at 0 110.499906 90)
			(size 1.8034 0.508)
			(layers "F.Cu" "F.Mask" "F.Paste")
			(net "GND")
		)
		(pad "126" smd rect
			(at 0 111.350044 90)
			(size 1.8034 0.508)
			(layers "F.Cu" "F.Mask" "F.Paste")
			(net "M_K_DQ<51>")
		)
		(pad "127" smd rect
			(at 0 112.199928 90)
			(size 1.8034 0.508)
			(layers "F.Cu" "F.Mask" "F.Paste")
			(net "GND")
		)
		(pad "128" smd rect
			(at 0 113.050066 90)
			(size 1.8034 0.508)
			(layers "F.Cu" "F.Mask" "F.Paste")
			(net "M_K_DQ<61>")
		)
		(pad "129" smd rect
			(at 0 113.89995 90)
			(size 1.8034 0.508)
			(layers "F.Cu" "F.Mask" "F.Paste")
			(net "GND")
		)
		(pad "130" smd rect
			(at 0 114.750088 90)
			(size 1.8034 0.508)
			(layers "F.Cu" "F.Mask" "F.Paste")
			(net "M_K_DQ<57>")
		)
		(pad "131" smd rect
			(at 0 115.599972 90)
			(size 1.8034 0.508)
			(layers "F.Cu" "F.Mask" "F.Paste")
			(net "GND")
		)
		(pad "132" smd rect
			(at 0 116.45011 90)
			(size 1.8034 0.508)
			(layers "F.Cu" "F.Mask" "F.Paste")
			(net "M_K_DQS_DP<16>")
		)
		(pad "133" smd rect
			(at 0 117.299994 90)
			(size 1.8034 0.508)
			(layers "F.Cu" "F.Mask" "F.Paste")
			(net "M_K_DQS_DN<16>")
		)
		(pad "134" smd rect
			(at 0 118.149878 90)
			(size 1.8034 0.508)
			(layers "F.Cu" "F.Mask" "F.Paste")
			(net "GND")
		)
		(pad "135" smd rect
			(at 0 119.000016 90)
			(size 1.8034 0.508)
			(layers "F.Cu" "F.Mask" "F.Paste")
			(net "M_K_DQ<63>")
		)
		(pad "136" smd rect
			(at 0 119.8499 90)
			(size 1.8034 0.508)
			(layers "F.Cu" "F.Mask" "F.Paste")
			(net "GND")
		)
		(pad "137" smd rect
			(at 0 120.700038 90)
			(size 1.8034 0.508)
			(layers "F.Cu" "F.Mask" "F.Paste")
			(net "M_K_DQ<59>")
		)
		(pad "138" smd rect
			(at 0 121.549922 90)
			(size 1.8034 0.508)
			(layers "F.Cu" "F.Mask" "F.Paste")
			(net "GND")
		)
		(pad "139" smd rect
			(at 0 122.40006 90)
			(size 1.8034 0.508)
			(layers "F.Cu" "F.Mask" "F.Paste")
			(net "GND")
		)
		(pad "140" smd rect
			(at 0 123.249944 90)
			(size 1.8034 0.508)
			(layers "F.Cu" "F.Mask" "F.Paste")
			(net "GND")
		)
		(pad "141" smd rect
			(at 0 124.100082 90)
			(size 1.8034 0.508)
			(layers "F.Cu" "F.Mask" "F.Paste")
			(net "SMB_DDR_KLM_VPP_SCL")
		)
		(pad "142" smd rect
			(at 0 124.949966 90)
			(size 1.8034 0.508)
			(layers "F.Cu" "F.Mask" "F.Paste")
			(net "PVPP_KLM")
		)
		(pad "143" smd rect
			(at 0 125.800104 90)
			(size 1.8034 0.508)
			(layers "F.Cu" "F.Mask" "F.Paste")
			(net "PVPP_KLM")
		)
		(pad "144" smd rect
			(at 0 126.649988 90)
			(size 1.8034 0.508)
			(layers "F.Cu" "F.Mask" "F.Paste")
			(net "TP_CH_K_DIMM_K0_RFU_2")
		)
		(pad "145" smd rect
			(at 4.59994 0 90)
			(size 1.8034 0.508)
			(layers "F.Cu" "F.Mask" "F.Paste")
			(net "P12V_NVDIMM_KLM")
		)
		(pad "146" smd rect
			(at 4.59994 0.849884 90)
			(size 1.8034 0.508)
			(layers "F.Cu" "F.Mask" "F.Paste")
			(net "M_K_VREF")
		)
		(pad "147" smd rect
			(at 4.59994 1.700022 90)
			(size 1.8034 0.508)
			(layers "F.Cu" "F.Mask" "F.Paste")
			(net "GND")
		)
		(pad "148" smd rect
			(at 4.59994 2.549906 90)
			(size 1.8034 0.508)
			(layers "F.Cu" "F.Mask" "F.Paste")
			(net "M_K_DQ<4>")
		)
		(pad "149" smd rect
			(at 4.59994 3.400044 90)
			(size 1.8034 0.508)
			(layers "F.Cu" "F.Mask" "F.Paste")
			(net "GND")
		)
		(pad "150" smd rect
			(at 4.59994 4.249928 90)
			(size 1.8034 0.508)
			(layers "F.Cu" "F.Mask" "F.Paste")
			(net "M_K_DQ<0>")
		)
		(pad "151" smd rect
			(at 4.59994 5.100066 90)
			(size 1.8034 0.508)
			(layers "F.Cu" "F.Mask" "F.Paste")
			(net "GND")
		)
		(pad "152" smd rect
			(at 4.59994 5.94995 90)
			(size 1.8034 0.508)
			(layers "F.Cu" "F.Mask" "F.Paste")
			(net "M_K_DQS_DN<0>")
		)
		(pad "153" smd rect
			(at 4.59994 6.800088 90)
			(size 1.8034 0.508)
			(layers "F.Cu" "F.Mask" "F.Paste")
			(net "M_K_DQS_DP<0>")
		)
		(pad "154" smd rect
			(at 4.59994 7.649972 90)
			(size 1.8034 0.508)
			(layers "F.Cu" "F.Mask" "F.Paste")
			(net "GND")
		)
		(pad "155" smd rect
			(at 4.59994 8.50011 90)
			(size 1.8034 0.508)
			(layers "F.Cu" "F.Mask" "F.Paste")
			(net "M_K_DQ<6>")
		)
		(pad "156" smd rect
			(at 4.59994 9.349994 90)
			(size 1.8034 0.508)
			(layers "F.Cu" "F.Mask" "F.Paste")
			(net "GND")
		)
		(pad "157" smd rect
			(at 4.59994 10.199878 90)
			(size 1.8034 0.508)
			(layers "F.Cu" "F.Mask" "F.Paste")
			(net "M_K_DQ<2>")
		)
		(pad "158" smd rect
			(at 4.59994 11.050016 90)
			(size 1.8034 0.508)
			(layers "F.Cu" "F.Mask" "F.Paste")
			(net "GND")
		)
		(pad "159" smd rect
			(at 4.59994 11.8999 90)
			(size 1.8034 0.508)
			(layers "F.Cu" "F.Mask" "F.Paste")
			(net "M_K_DQ<12>")
		)
		(pad "160" smd rect
			(at 4.59994 12.750038 90)
			(size 1.8034 0.508)
			(layers "F.Cu" "F.Mask" "F.Paste")
			(net "GND")
		)
		(pad "161" smd rect
			(at 4.59994 13.599922 90)
			(size 1.8034 0.508)
			(layers "F.Cu" "F.Mask" "F.Paste")
			(net "M_K_DQ<8>")
		)
		(pad "162" smd rect
			(at 4.59994 14.45006 90)
			(size 1.8034 0.508)
			(layers "F.Cu" "F.Mask" "F.Paste")
			(net "GND")
		)
		(pad "163" smd rect
			(at 4.59994 15.299944 90)
			(size 1.8034 0.508)
			(layers "F.Cu" "F.Mask" "F.Paste")
			(net "M_K_DQS_DN<1>")
		)
		(pad "164" smd rect
			(at 4.59994 16.150082 90)
			(size 1.8034 0.508)
			(layers "F.Cu" "F.Mask" "F.Paste")
			(net "M_K_DQS_DP<1>")
		)
		(pad "165" smd rect
			(at 4.59994 16.999966 90)
			(size 1.8034 0.508)
			(layers "F.Cu" "F.Mask" "F.Paste")
			(net "GND")
		)
		(pad "166" smd rect
			(at 4.59994 17.850104 90)
			(size 1.8034 0.508)
			(layers "F.Cu" "F.Mask" "F.Paste")
			(net "M_K_DQ<14>")
		)
		(pad "167" smd rect
			(at 4.59994 18.699988 90)
			(size 1.8034 0.508)
			(layers "F.Cu" "F.Mask" "F.Paste")
			(net "GND")
		)
		(pad "168" smd rect
			(at 4.59994 19.550126 90)
			(size 1.8034 0.508)
			(layers "F.Cu" "F.Mask" "F.Paste")
			(net "M_K_DQ<10>")
		)
		(pad "169" smd rect
			(at 4.59994 20.40001 90)
			(size 1.8034 0.508)
			(layers "F.Cu" "F.Mask" "F.Paste")
			(net "GND")
		)
		(pad "170" smd rect
			(at 4.59994 21.249894 90)
			(size 1.8034 0.508)
			(layers "F.Cu" "F.Mask" "F.Paste")
			(net "M_K_DQ<20>")
		)
		(pad "171" smd rect
			(at 4.59994 22.100032 90)
			(size 1.8034 0.508)
			(layers "F.Cu" "F.Mask" "F.Paste")
			(net "GND")
		)
		(pad "172" smd rect
			(at 4.59994 22.949916 90)
			(size 1.8034 0.508)
			(layers "F.Cu" "F.Mask" "F.Paste")
			(net "M_K_DQ<16>")
		)
		(pad "173" smd rect
			(at 4.59994 23.800054 90)
			(size 1.8034 0.508)
			(layers "F.Cu" "F.Mask" "F.Paste")
			(net "GND")
		)
		(pad "174" smd rect
			(at 4.59994 24.649938 90)
			(size 1.8034 0.508)
			(layers "F.Cu" "F.Mask" "F.Paste")
			(net "M_K_DQS_DN<2>")
		)
		(pad "175" smd rect
			(at 4.59994 25.500076 90)
			(size 1.8034 0.508)
			(layers "F.Cu" "F.Mask" "F.Paste")
			(net "M_K_DQS_DP<2>")
		)
		(pad "176" smd rect
			(at 4.59994 26.34996 90)
			(size 1.8034 0.508)
			(layers "F.Cu" "F.Mask" "F.Paste")
			(net "GND")
		)
		(pad "177" smd rect
			(at 4.59994 27.200098 90)
			(size 1.8034 0.508)
			(layers "F.Cu" "F.Mask" "F.Paste")
			(net "M_K_DQ<22>")
		)
		(pad "178" smd rect
			(at 4.59994 28.049982 90)
			(size 1.8034 0.508)
			(layers "F.Cu" "F.Mask" "F.Paste")
			(net "GND")
		)
		(pad "179" smd rect
			(at 4.59994 28.90012 90)
			(size 1.8034 0.508)
			(layers "F.Cu" "F.Mask" "F.Paste")
			(net "M_K_DQ<18>")
		)
		(pad "180" smd rect
			(at 4.59994 29.750004 90)
			(size 1.8034 0.508)
			(layers "F.Cu" "F.Mask" "F.Paste")
			(net "GND")
		)
		(pad "181" smd rect
			(at 4.59994 30.599888 90)
			(size 1.8034 0.508)
			(layers "F.Cu" "F.Mask" "F.Paste")
			(net "M_K_DQ<28>")
		)
		(pad "182" smd rect
			(at 4.59994 31.450026 90)
			(size 1.8034 0.508)
			(layers "F.Cu" "F.Mask" "F.Paste")
			(net "GND")
		)
		(pad "183" smd rect
			(at 4.59994 32.29991 90)
			(size 1.8034 0.508)
			(layers "F.Cu" "F.Mask" "F.Paste")
			(net "M_K_DQ<24>")
		)
		(pad "184" smd rect
			(at 4.59994 33.150048 90)
			(size 1.8034 0.508)
			(layers "F.Cu" "F.Mask" "F.Paste")
			(net "GND")
		)
		(pad "185" smd rect
			(at 4.59994 33.999932 90)
			(size 1.8034 0.508)
			(layers "F.Cu" "F.Mask" "F.Paste")
			(net "M_K_DQS_DN<3>")
		)
		(pad "186" smd rect
			(at 4.59994 34.85007 90)
			(size 1.8034 0.508)
			(layers "F.Cu" "F.Mask" "F.Paste")
			(net "M_K_DQS_DP<3>")
		)
		(pad "187" smd rect
			(at 4.59994 35.699954 90)
			(size 1.8034 0.508)
			(layers "F.Cu" "F.Mask" "F.Paste")
			(net "GND")
		)
		(pad "188" smd rect
			(at 4.59994 36.550092 90)
			(size 1.8034 0.508)
			(layers "F.Cu" "F.Mask" "F.Paste")
			(net "M_K_DQ<30>")
		)
		(pad "189" smd rect
			(at 4.59994 37.399976 90)
			(size 1.8034 0.508)
			(layers "F.Cu" "F.Mask" "F.Paste")
			(net "GND")
		)
		(pad "190" smd rect
			(at 4.59994 38.250114 90)
			(size 1.8034 0.508)
			(layers "F.Cu" "F.Mask" "F.Paste")
			(net "M_K_DQ<26>")
		)
		(pad "191" smd rect
			(at 4.59994 39.099998 90)
			(size 1.8034 0.508)
			(layers "F.Cu" "F.Mask" "F.Paste")
			(net "GND")
		)
		(pad "192" smd rect
			(at 4.59994 39.949882 90)
			(size 1.8034 0.508)
			(layers "F.Cu" "F.Mask" "F.Paste")
			(net "M_K_ECC<4>")
		)
		(pad "193" smd rect
			(at 4.59994 40.80002 90)
			(size 1.8034 0.508)
			(layers "F.Cu" "F.Mask" "F.Paste")
			(net "GND")
		)
		(pad "194" smd rect
			(at 4.59994 41.649904 90)
			(size 1.8034 0.508)
			(layers "F.Cu" "F.Mask" "F.Paste")
			(net "M_K_ECC<0>")
		)
		(pad "195" smd rect
			(at 4.59994 42.500042 90)
			(size 1.8034 0.508)
			(layers "F.Cu" "F.Mask" "F.Paste")
			(net "GND")
		)
		(pad "196" smd rect
			(at 4.59994 43.349926 90)
			(size 1.8034 0.508)
			(layers "F.Cu" "F.Mask" "F.Paste")
			(net "M_K_DQS_DN<8>")
		)
		(pad "197" smd rect
			(at 4.59994 44.200064 90)
			(size 1.8034 0.508)
			(layers "F.Cu" "F.Mask" "F.Paste")
			(net "M_K_DQS_DP<8>")
		)
		(pad "198" smd rect
			(at 4.59994 45.049948 90)
			(size 1.8034 0.508)
			(layers "F.Cu" "F.Mask" "F.Paste")
			(net "GND")
		)
		(pad "199" smd rect
			(at 4.59994 45.900086 90)
			(size 1.8034 0.508)
			(layers "F.Cu" "F.Mask" "F.Paste")
			(net "M_K_ECC<6>")
		)
		(pad "200" smd rect
			(at 4.59994 46.74997 90)
			(size 1.8034 0.508)
			(layers "F.Cu" "F.Mask" "F.Paste")
			(net "GND")
		)
		(pad "201" smd rect
			(at 4.59994 47.600108 90)
			(size 1.8034 0.508)
			(layers "F.Cu" "F.Mask" "F.Paste")
			(net "M_K_ECC<2>")
		)
		(pad "202" smd rect
			(at 4.59994 48.449992 90)
			(size 1.8034 0.508)
			(layers "F.Cu" "F.Mask" "F.Paste")
			(net "GND")
		)
		(pad "203" smd rect
			(at 4.59994 49.299876 90)
			(size 1.8034 0.508)
			(layers "F.Cu" "F.Mask" "F.Paste")
			(net "M_K_CKE<1>")
		)
		(pad "204" smd rect
			(at 4.59994 50.150014 90)
			(size 1.8034 0.508)
			(layers "F.Cu" "F.Mask" "F.Paste")
			(net "PVDDQ_KLM")
		)
		(pad "205" smd rect
			(at 4.59994 50.999898 90)
			(size 1.8034 0.508)
			(layers "F.Cu" "F.Mask" "F.Paste")
			(net "TP_CH_K_DIMM_K0_RFU_0")
		)
		(pad "206" smd rect
			(at 4.59994 51.850036 90)
			(size 1.8034 0.508)
			(layers "F.Cu" "F.Mask" "F.Paste")
			(net "PVDDQ_KLM")
		)
		(pad "207" smd rect
			(at 4.59994 52.69992 90)
			(size 1.8034 0.508)
			(layers "F.Cu" "F.Mask" "F.Paste")
			(net "M_K_BG<1>")
		)
		(pad "208" smd rect
			(at 4.59994 53.550058 90)
			(size 1.8034 0.508)
			(layers "F.Cu" "F.Mask" "F.Paste")
			(net "M_K_ALERT_N")
		)
		(pad "209" smd rect
			(at 4.59994 54.399942 90)
			(size 1.8034 0.508)
			(layers "F.Cu" "F.Mask" "F.Paste")
			(net "PVDDQ_KLM")
		)
		(pad "210" smd rect
			(at 4.59994 55.25008 90)
			(size 1.8034 0.508)
			(layers "F.Cu" "F.Mask" "F.Paste")
			(net "M_K_MA<11>")
		)
		(pad "211" smd rect
			(at 4.59994 56.099964 90)
			(size 1.8034 0.508)
			(layers "F.Cu" "F.Mask" "F.Paste")
			(net "M_K_MA<7>")
		)
		(pad "212" smd rect
			(at 4.59994 56.950102 90)
			(size 1.8034 0.508)
			(layers "F.Cu" "F.Mask" "F.Paste")
			(net "PVDDQ_KLM")
		)
		(pad "213" smd rect
			(at 4.59994 57.799986 90)
			(size 1.8034 0.508)
			(layers "F.Cu" "F.Mask" "F.Paste")
			(net "M_K_MA<5>")
		)
		(pad "214" smd rect
			(at 4.59994 58.650124 90)
			(size 1.8034 0.508)
			(layers "F.Cu" "F.Mask" "F.Paste")
			(net "M_K_MA<4>")
		)
		(pad "215" smd rect
			(at 4.59994 59.500008 90)
			(size 1.8034 0.508)
			(layers "F.Cu" "F.Mask" "F.Paste")
			(net "PVDDQ_KLM")
		)
		(pad "216" smd rect
			(at 4.59994 60.349892 90)
			(size 1.8034 0.508)
			(layers "F.Cu" "F.Mask" "F.Paste")
			(net "M_K_MA<2>")
		)
		(pad "217" smd rect
			(at 4.59994 61.20003 90)
			(size 1.8034 0.508)
			(layers "F.Cu" "F.Mask" "F.Paste")
			(net "PVDDQ_KLM")
		)
		(pad "218" smd rect
			(at 4.59994 62.049914 90)
			(size 1.8034 0.508)
			(layers "F.Cu" "F.Mask" "F.Paste")
			(net "M_K_CLK_DP<1>")
		)
		(pad "219" smd rect
			(at 4.59994 62.900052 90)
			(size 1.8034 0.508)
			(layers "F.Cu" "F.Mask" "F.Paste")
			(net "M_K_CLK_DN<1>")
		)
		(pad "220" smd rect
			(at 4.59994 63.749936 90)
			(size 1.8034 0.508)
			(layers "F.Cu" "F.Mask" "F.Paste")
			(net "PVDDQ_KLM")
		)
		(pad "221" smd rect
			(at 4.59994 64.600074 90)
			(size 1.8034 0.508)
			(layers "F.Cu" "F.Mask" "F.Paste")
			(net "PVTT_KLM")
		)
		(pad "222" smd rect
			(at 4.59994 70.550024 90)
			(size 1.8034 0.508)
			(layers "F.Cu" "F.Mask" "F.Paste")
			(net "M_K_PAR")
		)
		(pad "223" smd rect
			(at 4.59994 71.399908 90)
			(size 1.8034 0.508)
			(layers "F.Cu" "F.Mask" "F.Paste")
			(net "PVDDQ_KLM")
		)
		(pad "224" smd rect
			(at 4.59994 72.250046 90)
			(size 1.8034 0.508)
			(layers "F.Cu" "F.Mask" "F.Paste")
			(net "M_K_BA<1>")
		)
		(pad "225" smd rect
			(at 4.59994 73.09993 90)
			(size 1.8034 0.508)
			(layers "F.Cu" "F.Mask" "F.Paste")
			(net "M_K_MA<10>")
		)
		(pad "226" smd rect
			(at 4.59994 73.950068 90)
			(size 1.8034 0.508)
			(layers "F.Cu" "F.Mask" "F.Paste")
			(net "PVDDQ_KLM")
		)
		(pad "227" smd rect
			(at 4.59994 74.799952 90)
			(size 1.8034 0.508)
			(layers "F.Cu" "F.Mask" "F.Paste")
			(net "TP_CH_K_DIMM_K0_RFU_1")
		)
		(pad "228" smd rect
			(at 4.59994 75.65009 90)
			(size 1.8034 0.508)
			(layers "F.Cu" "F.Mask" "F.Paste")
			(net "M_K_MA<14>")
		)
		(pad "229" smd rect
			(at 4.59994 76.499974 90)
			(size 1.8034 0.508)
			(layers "F.Cu" "F.Mask" "F.Paste")
			(net "PVDDQ_KLM")
		)
		(pad "230" smd rect
			(at 4.59994 77.350112 90)
			(size 1.8034 0.508)
			(layers "F.Cu" "F.Mask" "F.Paste")
			(net "FM_ADR_COMPLETE_KLM_N")
		)
		(pad "231" smd rect
			(at 4.59994 78.199996 90)
			(size 1.8034 0.508)
			(layers "F.Cu" "F.Mask" "F.Paste")
			(net "PVDDQ_KLM")
		)
		(pad "232" smd rect
			(at 4.59994 79.04988 90)
			(size 1.8034 0.508)
			(layers "F.Cu" "F.Mask" "F.Paste")
			(net "M_K_MA<13>")
		)
		(pad "233" smd rect
			(at 4.59994 79.900018 90)
			(size 1.8034 0.508)
			(layers "F.Cu" "F.Mask" "F.Paste")
			(net "PVDDQ_KLM")
		)
		(pad "234" smd rect
			(at 4.59994 80.749902 90)
			(size 1.8034 0.508)
			(layers "F.Cu" "F.Mask" "F.Paste")
			(net "M_K_MA<17>")
		)
		(pad "235" smd rect
			(at 4.59994 81.60004 90)
			(size 1.8034 0.508)
			(layers "F.Cu" "F.Mask" "F.Paste")
			(net "M_K_C<2>")
		)
		(pad "236" smd rect
			(at 4.59994 82.449924 90)
			(size 1.8034 0.508)
			(layers "F.Cu" "F.Mask" "F.Paste")
			(net "PVDDQ_KLM")
		)
		(pad "237" smd rect
			(at 4.59994 83.300062 90)
			(size 1.8034 0.508)
			(layers "F.Cu" "F.Mask" "F.Paste")
			(net "M_K_CS_N<3>")
		)
		(pad "238" smd rect
			(at 4.59994 84.149946 90)
			(size 1.8034 0.508)
			(layers "F.Cu" "F.Mask" "F.Paste")
			(net "GND")
		)
		(pad "239" smd rect
			(at 4.59994 85.000084 90)
			(size 1.8034 0.508)
			(layers "F.Cu" "F.Mask" "F.Paste")
			(net "GND")
		)
		(pad "240" smd rect
			(at 4.59994 85.849968 90)
			(size 1.8034 0.508)
			(layers "F.Cu" "F.Mask" "F.Paste")
			(net "M_K_DQ<36>")
		)
		(pad "241" smd rect
			(at 4.59994 86.700106 90)
			(size 1.8034 0.508)
			(layers "F.Cu" "F.Mask" "F.Paste")
			(net "GND")
		)
		(pad "242" smd rect
			(at 4.59994 87.54999 90)
			(size 1.8034 0.508)
			(layers "F.Cu" "F.Mask" "F.Paste")
			(net "M_K_DQ<32>")
		)
		(pad "243" smd rect
			(at 4.59994 88.399874 90)
			(size 1.8034 0.508)
			(layers "F.Cu" "F.Mask" "F.Paste")
			(net "GND")
		)
		(pad "244" smd rect
			(at 4.59994 89.250012 90)
			(size 1.8034 0.508)
			(layers "F.Cu" "F.Mask" "F.Paste")
			(net "M_K_DQS_DN<4>")
		)
		(pad "245" smd rect
			(at 4.59994 90.099896 90)
			(size 1.8034 0.508)
			(layers "F.Cu" "F.Mask" "F.Paste")
			(net "M_K_DQS_DP<4>")
		)
		(pad "246" smd rect
			(at 4.59994 90.950034 90)
			(size 1.8034 0.508)
			(layers "F.Cu" "F.Mask" "F.Paste")
			(net "GND")
		)
		(pad "247" smd rect
			(at 4.59994 91.799918 90)
			(size 1.8034 0.508)
			(layers "F.Cu" "F.Mask" "F.Paste")
			(net "M_K_DQ<38>")
		)
		(pad "248" smd rect
			(at 4.59994 92.650056 90)
			(size 1.8034 0.508)
			(layers "F.Cu" "F.Mask" "F.Paste")
			(net "GND")
		)
		(pad "249" smd rect
			(at 4.59994 93.49994 90)
			(size 1.8034 0.508)
			(layers "F.Cu" "F.Mask" "F.Paste")
			(net "M_K_DQ<34>")
		)
		(pad "250" smd rect
			(at 4.59994 94.350078 90)
			(size 1.8034 0.508)
			(layers "F.Cu" "F.Mask" "F.Paste")
			(net "GND")
		)
		(pad "251" smd rect
			(at 4.59994 95.199962 90)
			(size 1.8034 0.508)
			(layers "F.Cu" "F.Mask" "F.Paste")
			(net "M_K_DQ<44>")
		)
		(pad "252" smd rect
			(at 4.59994 96.0501 90)
			(size 1.8034 0.508)
			(layers "F.Cu" "F.Mask" "F.Paste")
			(net "GND")
		)
		(pad "253" smd rect
			(at 4.59994 96.899984 90)
			(size 1.8034 0.508)
			(layers "F.Cu" "F.Mask" "F.Paste")
			(net "M_K_DQ<40>")
		)
		(pad "254" smd rect
			(at 4.59994 97.750122 90)
			(size 1.8034 0.508)
			(layers "F.Cu" "F.Mask" "F.Paste")
			(net "GND")
		)
		(pad "255" smd rect
			(at 4.59994 98.600006 90)
			(size 1.8034 0.508)
			(layers "F.Cu" "F.Mask" "F.Paste")
			(net "M_K_DQS_DN<5>")
		)
		(pad "256" smd rect
			(at 4.59994 99.44989 90)
			(size 1.8034 0.508)
			(layers "F.Cu" "F.Mask" "F.Paste")
			(net "M_K_DQS_DP<5>")
		)
		(pad "257" smd rect
			(at 4.59994 100.300028 90)
			(size 1.8034 0.508)
			(layers "F.Cu" "F.Mask" "F.Paste")
			(net "GND")
		)
		(pad "258" smd rect
			(at 4.59994 101.149912 90)
			(size 1.8034 0.508)
			(layers "F.Cu" "F.Mask" "F.Paste")
			(net "M_K_DQ<46>")
		)
		(pad "259" smd rect
			(at 4.59994 102.00005 90)
			(size 1.8034 0.508)
			(layers "F.Cu" "F.Mask" "F.Paste")
			(net "GND")
		)
		(pad "260" smd rect
			(at 4.59994 102.849934 90)
			(size 1.8034 0.508)
			(layers "F.Cu" "F.Mask" "F.Paste")
			(net "M_K_DQ<42>")
		)
		(pad "261" smd rect
			(at 4.59994 103.700072 90)
			(size 1.8034 0.508)
			(layers "F.Cu" "F.Mask" "F.Paste")
			(net "GND")
		)
		(pad "262" smd rect
			(at 4.59994 104.549956 90)
			(size 1.8034 0.508)
			(layers "F.Cu" "F.Mask" "F.Paste")
			(net "M_K_DQ<52>")
		)
		(pad "263" smd rect
			(at 4.59994 105.400094 90)
			(size 1.8034 0.508)
			(layers "F.Cu" "F.Mask" "F.Paste")
			(net "GND")
		)
		(pad "264" smd rect
			(at 4.59994 106.249978 90)
			(size 1.8034 0.508)
			(layers "F.Cu" "F.Mask" "F.Paste")
			(net "M_K_DQ<48>")
		)
		(pad "265" smd rect
			(at 4.59994 107.100116 90)
			(size 1.8034 0.508)
			(layers "F.Cu" "F.Mask" "F.Paste")
			(net "GND")
		)
		(pad "266" smd rect
			(at 4.59994 107.95 90)
			(size 1.8034 0.508)
			(layers "F.Cu" "F.Mask" "F.Paste")
			(net "M_K_DQS_DN<6>")
		)
		(pad "267" smd rect
			(at 4.59994 108.799884 90)
			(size 1.8034 0.508)
			(layers "F.Cu" "F.Mask" "F.Paste")
			(net "M_K_DQS_DP<6>")
		)
		(pad "268" smd rect
			(at 4.59994 109.650022 90)
			(size 1.8034 0.508)
			(layers "F.Cu" "F.Mask" "F.Paste")
			(net "GND")
		)
		(pad "269" smd rect
			(at 4.59994 110.499906 90)
			(size 1.8034 0.508)
			(layers "F.Cu" "F.Mask" "F.Paste")
			(net "M_K_DQ<54>")
		)
		(pad "270" smd rect
			(at 4.59994 111.350044 90)
			(size 1.8034 0.508)
			(layers "F.Cu" "F.Mask" "F.Paste")
			(net "GND")
		)
		(pad "271" smd rect
			(at 4.59994 112.199928 90)
			(size 1.8034 0.508)
			(layers "F.Cu" "F.Mask" "F.Paste")
			(net "M_K_DQ<50>")
		)
		(pad "272" smd rect
			(at 4.59994 113.050066 90)
			(size 1.8034 0.508)
			(layers "F.Cu" "F.Mask" "F.Paste")
			(net "GND")
		)
		(pad "273" smd rect
			(at 4.59994 113.89995 90)
			(size 1.8034 0.508)
			(layers "F.Cu" "F.Mask" "F.Paste")
			(net "M_K_DQ<60>")
		)
		(pad "274" smd rect
			(at 4.59994 114.750088 90)
			(size 1.8034 0.508)
			(layers "F.Cu" "F.Mask" "F.Paste")
			(net "GND")
		)
		(pad "275" smd rect
			(at 4.59994 115.599972 90)
			(size 1.8034 0.508)
			(layers "F.Cu" "F.Mask" "F.Paste")
			(net "M_K_DQ<56>")
		)
		(pad "276" smd rect
			(at 4.59994 116.45011 90)
			(size 1.8034 0.508)
			(layers "F.Cu" "F.Mask" "F.Paste")
			(net "GND")
		)
		(pad "277" smd rect
			(at 4.59994 117.299994 90)
			(size 1.8034 0.508)
			(layers "F.Cu" "F.Mask" "F.Paste")
			(net "M_K_DQS_DN<7>")
		)
		(pad "278" smd rect
			(at 4.59994 118.149878 90)
			(size 1.8034 0.508)
			(layers "F.Cu" "F.Mask" "F.Paste")
			(net "M_K_DQS_DP<7>")
		)
		(pad "279" smd rect
			(at 4.59994 119.000016 90)
			(size 1.8034 0.508)
			(layers "F.Cu" "F.Mask" "F.Paste")
			(net "GND")
		)
		(pad "280" smd rect
			(at 4.59994 119.8499 90)
			(size 1.8034 0.508)
			(layers "F.Cu" "F.Mask" "F.Paste")
			(net "M_K_DQ<62>")
		)
		(pad "281" smd rect
			(at 4.59994 120.700038 90)
			(size 1.8034 0.508)
			(layers "F.Cu" "F.Mask" "F.Paste")
			(net "GND")
		)
		(pad "282" smd rect
			(at 4.59994 121.549922 90)
			(size 1.8034 0.508)
			(layers "F.Cu" "F.Mask" "F.Paste")
			(net "M_K_DQ<58>")
		)
		(pad "283" smd rect
			(at 4.59994 122.40006 90)
			(size 1.8034 0.508)
			(layers "F.Cu" "F.Mask" "F.Paste")
			(net "GND")
		)
		(pad "284" smd rect
			(at 4.59994 123.249944 90)
			(size 1.8034 0.508)
			(layers "F.Cu" "F.Mask" "F.Paste")
			(net "PVPP_KLM")
		)
		(pad "285" smd rect
			(at 4.59994 124.100082 90)
			(size 1.8034 0.508)
			(layers "F.Cu" "F.Mask" "F.Paste")
			(net "SMB_DDR_KLM_VPP_SDA")
		)
		(pad "286" smd rect
			(at 4.59994 124.949966 90)
			(size 1.8034 0.508)
			(layers "F.Cu" "F.Mask" "F.Paste")
			(net "PVPP_KLM")
		)
		(pad "287" smd rect
			(at 4.59994 125.800104 90)
			(size 1.8034 0.508)
			(layers "F.Cu" "F.Mask" "F.Paste")
			(net "PVPP_KLM")
		)
		(pad "288" smd rect
			(at 4.59994 126.649988 90)
			(size 1.8034 0.508)
			(layers "F.Cu" "F.Mask" "F.Paste")
			(net "PVPP_KLM")
		)
	)
	(footprint ""
		(layer "F.Cu")
		(at 388.0104 -0.254)
		(property "Reference" "R8G8"
			(at 0 0 0)
			(layer "F.SilkS")
			(hide yes)
			(effects
				(font
					(size 1.27 1.27)
				)
			)
		)
		(property "Value" ""
			(at 0 0 0)
			(layer "F.Fab")
			(effects
				(font
					(size 1.27 1.27)
				)
			)
		)
		(duplicate_pad_numbers_are_jumpers no)
		(fp_poly
			(pts
				(xy -0.2794 -0.1016) (xy 0.2794 -0.1016) (xy 0.2794 0.9906) (xy -0.2794 0.9906)
			)
			(stroke
				(width 0)
				(type default)
			)
			(fill no)
			(layer "F.CrtYd")
		)
		(fp_line
			(start -0.2794 -0.1016)
			(end -0.2794 0.9906)
			(stroke
				(width 0.1)
				(type default)
			)
			(layer "F.Fab")
		)
		(fp_line
			(start -0.2794 0.9906)
			(end 0.2794 0.9906)
			(stroke
				(width 0.1)
				(type default)
			)
			(layer "F.Fab")
		)
		(fp_line
			(start 0.2794 -0.1016)
			(end -0.2794 -0.1016)
			(stroke
				(width 0.1)
				(type default)
			)
			(layer "F.Fab")
		)
		(fp_line
			(start 0.2794 0.9906)
			(end 0.2794 -0.1016)
			(stroke
				(width 0.1)
				(type default)
			)
			(layer "F.Fab")
		)
		(pad "1" smd rect
			(at 0 0)
			(size 0.508 0.508)
			(layers "F.Cu" "F.Mask" "F.Paste")
			(net "JTAG_BMC_TDI")
		)
		(pad "2" smd rect
			(at 0 0.889)
			(size 0.508 0.508)
			(layers "F.Cu" "F.Mask" "F.Paste")
			(net "JTAG_TDI")
		)
		(zone
			(layer "F.Cu")
			(hatch none 0.5)
			(connect_pads
				(clearance 0)
			)
			(min_thickness 0.25)
			(keepout
				(tracks allowed)
				(vias not_allowed)
				(pads allowed)
				(copperpour not_allowed)
				(footprints allowed)
			)
			(placement
				(enabled no)
				(sheetname "")
			)
			(fill
				(thermal_gap 0.5)
				(thermal_bridge_width 0.5)
				(island_removal_mode 0)
			)
			(polygon
				(pts
					(xy 387.7564 0) (xy 388.2644 0) (xy 388.2644 0.381) (xy 387.7564 0.381)
				)
			)
		)
		(zone
			(layer "F.Cu")
			(hatch none 0.5)
			(connect_pads
				(clearance 0)
			)
			(min_thickness 0.25)
			(keepout
				(tracks not_allowed)
				(vias allowed)
				(pads allowed)
				(copperpour not_allowed)
				(footprints allowed)
			)
			(placement
				(enabled no)
				(sheetname "")
			)
			(fill
				(thermal_gap 0.5)
				(thermal_bridge_width 0.5)
				(island_removal_mode 0)
			)
			(polygon
				(pts
					(xy 387.7564 0.381) (xy 388.2644 0.381) (xy 388.2644 0) (xy 387.7564 0)
				)
			)
		)
	)
	(footprint ""
		(layer "F.Cu")
		(at 441.404756 -147.621244 90)
		(property "Reference" "C25W101"
			(at -0.8382 -0.67818 90)
			(unlocked yes)
			(layer "F.SilkS")
			(effects
				(font
					(size 0.4064 0.254)
					(thickness 0.1524)
				)
				(justify left)
			)
		)
		(property "Value" ""
			(at 0 0 90)
			(layer "F.Fab")
			(effects
				(font
					(size 1.27 1.27)
				)
			)
		)
		(duplicate_pad_numbers_are_jumpers no)
		(fp_poly
			(pts
				(xy 0.3048 -0.1016) (xy 0.3048 0.9906) (xy -0.3048 0.9906) (xy -0.3048 -0.1016)
			)
			(stroke
				(width 0)
				(type default)
			)
			(fill no)
			(layer "F.CrtYd")
		)
		(fp_line
			(start 0.3048 -0.1016)
			(end -0.3048 -0.1016)
			(stroke
				(width 0.1)
				(type default)
			)
			(layer "F.Fab")
		)
		(fp_line
			(start -0.3048 -0.1016)
			(end -0.3048 0.9906)
			(stroke
				(width 0.1)
				(type default)
			)
			(layer "F.Fab")
		)
		(fp_line
			(start 0.3048 0.9906)
			(end 0.3048 -0.1016)
			(stroke
				(width 0.1)
				(type default)
			)
			(layer "F.Fab")
		)
		(fp_line
			(start -0.3048 0.9906)
			(end 0.3048 0.9906)
			(stroke
				(width 0.1)
				(type default)
			)
			(layer "F.Fab")
		)
		(pad "1" smd rect
			(at 0 0 90)
			(size 0.508 0.508)
			(layers "F.Cu" "F.Mask" "F.Paste")
			(net "P3V3_STBY")
		)
		(pad "2" smd rect
			(at 0 0.889 90)
			(size 0.508 0.508)
			(layers "F.Cu" "F.Mask" "F.Paste")
			(net "GND")
		)
		(zone
			(layer "F.Cu")
			(hatch none 0.5)
			(connect_pads
				(clearance 0)
			)
			(min_thickness 0.25)
			(keepout
				(tracks allowed)
				(vias not_allowed)
				(pads allowed)
				(copperpour not_allowed)
				(footprints allowed)
			)
			(placement
				(enabled no)
				(sheetname "")
			)
			(fill
				(thermal_gap 0.5)
				(thermal_bridge_width 0.5)
				(island_removal_mode 0)
			)
			(polygon
				(pts
					(xy 441.658756 -147.367244) (xy 441.658756 -147.875244) (xy 442.039756 -147.875244) (xy 442.039756 -147.367244)
				)
			)
		)
		(zone
			(layer "F.Cu")
			(hatch none 0.5)
			(connect_pads
				(clearance 0)
			)
			(min_thickness 0.25)
			(keepout
				(tracks not_allowed)
				(vias allowed)
				(pads allowed)
				(copperpour not_allowed)
				(footprints allowed)
			)
			(placement
				(enabled no)
				(sheetname "")
			)
			(fill
				(thermal_gap 0.5)
				(thermal_bridge_width 0.5)
				(island_removal_mode 0)
			)
			(polygon
				(pts
					(xy 442.039756 -147.367244) (xy 442.039756 -147.875244) (xy 441.658756 -147.875244) (xy 441.658756 -147.367244)
				)
			)
		)
	)
	(footprint ""
		(layer "F.Cu")
		(at 182.626 -84.1248)
		(property "Reference" ""
			(at 0 0 0)
			(layer "F.SilkS")
			(hide yes)
			(effects
				(font
					(size 1.27 1.27)
				)
			)
		)
		(property "Value" ""
			(at 0 0 0)
			(layer "F.Fab")
			(effects
				(font
					(size 1.27 1.27)
				)
			)
		)
		(duplicate_pad_numbers_are_jumpers no)
		(fp_poly
			(pts
				(arc
					(start 2.032 0)
					(mid -2.032 0)
					(end 2.032 0)
				)
			)
			(stroke
				(width 0)
				(type default)
			)
			(fill no)
			(layer "F.CrtYd")
		)
		(pad "1" smd circle
			(at 0 0)
			(size 1.016 1.016)
			(layers "F.Cu" "F.Mask" "F.Paste")
			(net "Net_393")
		)
		(zone
			(layer "F.Cu")
			(hatch none 0.5)
			(connect_pads
				(clearance 0)
			)
			(min_thickness 0.25)
			(keepout
				(tracks not_allowed)
				(vias allowed)
				(pads allowed)
				(copperpour not_allowed)
				(footprints allowed)
			)
			(placement
				(enabled no)
				(sheetname "")
			)
			(fill
				(thermal_gap 0.5)
				(thermal_bridge_width 0.5)
				(island_removal_mode 0)
			)
			(polygon
				(pts
					(arc
						(start 184.15 -84.1248)
						(mid 181.102 -84.1248)
						(end 184.15 -84.1248)
					)
				)
			)
		)
		(zone
			(layers "F.Cu" "B.Cu" "In1.Cu" "In2.Cu" "In3.Cu" "In4.Cu" "In5.Cu" "In6.Cu"
				"In7.Cu" "In8.Cu" "In9.Cu" "In10.Cu" "In11.Cu" "In12.Cu"
			)
			(hatch none 0.5)
			(connect_pads
				(clearance 0)
			)
			(min_thickness 0.25)
			(keepout
				(tracks allowed)
				(vias not_allowed)
				(pads allowed)
				(copperpour not_allowed)
				(footprints allowed)
			)
			(placement
				(enabled no)
				(sheetname "")
			)
			(fill
				(thermal_gap 0.5)
				(thermal_bridge_width 0.5)
				(island_removal_mode 0)
			)
			(polygon
				(pts
					(arc
						(start 184.15 -84.1248)
						(mid 181.102 -84.1248)
						(end 184.15 -84.1248)
					)
				)
			)
		)
	)
	(footprint ""
		(layer "F.Cu")
		(at 487.39679 -58.51144)
		(property "Reference" "F30W1"
			(at 0 0 0)
			(layer "F.SilkS")
			(hide yes)
			(effects
				(font
					(size 1.27 1.27)
				)
			)
		)
		(property "Value" "*"
			(at -2.3241 1.30175 0)
			(unlocked yes)
			(layer "F.Fab")
			(hide yes)
			(effects
				(font
					(size 0.889 0.889)
					(thickness 0.1524)
				)
			)
		)
		(property "Device Type" "POLYSW-1D1A6V-2-GP-U_DISCRET-GA"
			(at -2.3241 -0.22225 0)
			(unlocked yes)
			(layer "F.Fab")
			(hide yes)
			(effects
				(font
					(size 0.889 0.889)
					(thickness 0.1524)
				)
			)
		)
		(duplicate_pad_numbers_are_jumpers no)
		(fp_line
			(start -1.2065 -2.2479)
			(end -1.2065 2.2479)
			(stroke
				(width 0.1524)
				(type default)
			)
			(layer "F.SilkS")
		)
		(fp_line
			(start -1.2065 2.2479)
			(end 1.2065 2.2479)
			(stroke
				(width 0.1524)
				(type default)
			)
			(layer "F.SilkS")
		)
		(fp_line
			(start 1.2065 -2.2479)
			(end -1.2065 -2.2479)
			(stroke
				(width 0.1524)
				(type default)
			)
			(layer "F.SilkS")
		)
		(fp_line
			(start 1.2065 2.2479)
			(end 1.2065 -2.2479)
			(stroke
				(width 0.1524)
				(type default)
			)
			(layer "F.SilkS")
		)
		(fp_rect
			(start -0.8255 1.6002)
			(end 0.8255 -1.6002)
			(stroke
				(width 0)
				(type default)
			)
			(fill no)
			(layer "F.CrtYd")
		)
		(fp_poly
			(pts
				(xy -1.4605 2.3241) (xy -1.4605 -2.3241) (xy 1.4605 -2.3241) (xy 1.4605 1.59512) (xy 0.8255 1.59512)
				(xy 0.8255 -1.6002) (xy -0.8255 -1.6002) (xy -0.8255 1.6002) (xy 1.4605 1.6002) (xy 1.4605 2.3241)
			)
			(stroke
				(width 0)
				(type default)
			)
			(fill no)
			(layer "F.CrtYd")
		)
		(fp_rect
			(start -1.4605 2.3241)
			(end 1.4605 -2.3241)
			(stroke
				(width 0)
				(type default)
			)
			(fill no)
			(layer "F.Fab")
		)
		(pad "1" smd rect
			(at 0 -1.417574)
			(size 1.905 1.143)
			(layers "F.Cu" "F.Mask" "F.Paste")
			(net "P5V_STBY")
		)
		(pad "2" smd rect
			(at 0 1.417574)
			(size 1.905 1.143)
			(layers "F.Cu" "F.Mask" "F.Paste")
			(net "P5V_STBY_USBC")
		)
	)
	(footprint ""
		(layer "F.Cu")
		(at 339.222588 -119.211598 -90)
		(property "Reference" "C844"
			(at -0.8382 -0.67818 270)
			(unlocked yes)
			(layer "F.SilkS")
			(effects
				(font
					(size 0.4064 0.254)
					(thickness 0.1524)
				)
				(justify left)
			)
		)
		(property "Value" ""
			(at 0 0 270)
			(layer "F.Fab")
			(effects
				(font
					(size 1.27 1.27)
				)
			)
		)
		(duplicate_pad_numbers_are_jumpers no)
		(fp_poly
			(pts
				(xy 0.3048 -0.1016) (xy 0.3048 0.9906) (xy -0.3048 0.9906) (xy -0.3048 -0.1016)
			)
			(stroke
				(width 0)
				(type default)
			)
			(fill no)
			(layer "F.CrtYd")
		)
		(fp_line
			(start -0.3048 0.9906)
			(end 0.3048 0.9906)
			(stroke
				(width 0.1)
				(type default)
			)
			(layer "F.Fab")
		)
		(fp_line
			(start 0.3048 0.9906)
			(end 0.3048 -0.1016)
			(stroke
				(width 0.1)
				(type default)
			)
			(layer "F.Fab")
		)
		(fp_line
			(start -0.3048 -0.1016)
			(end -0.3048 0.9906)
			(stroke
				(width 0.1)
				(type default)
			)
			(layer "F.Fab")
		)
		(fp_line
			(start 0.3048 -0.1016)
			(end -0.3048 -0.1016)
			(stroke
				(width 0.1)
				(type default)
			)
			(layer "F.Fab")
		)
		(pad "1" smd rect
			(at 0 0 270)
			(size 0.508 0.508)
			(layers "F.Cu" "F.Mask" "F.Paste")
			(net "P3E_CPU0_PE1_PCH_TXN<9>")
		)
		(pad "2" smd rect
			(at 0 0.889 270)
			(size 0.508 0.508)
			(layers "F.Cu" "F.Mask" "F.Paste")
			(net "P3E_CPU0_PE1_PCH_CON_TXN<9>")
		)
		(zone
			(layer "F.Cu")
			(hatch none 0.5)
			(connect_pads
				(clearance 0)
			)
			(min_thickness 0.25)
			(keepout
				(tracks not_allowed)
				(vias allowed)
				(pads allowed)
				(copperpour not_allowed)
				(footprints allowed)
			)
			(placement
				(enabled no)
				(sheetname "")
			)
			(fill
				(thermal_gap 0.5)
				(thermal_bridge_width 0.5)
				(island_removal_mode 0)
			)
			(polygon
				(pts
					(xy 338.587588 -119.465598) (xy 338.587588 -118.957598) (xy 338.968588 -118.957598) (xy 338.968588 -119.465598)
				)
			)
		)
		(zone
			(layer "F.Cu")
			(hatch none 0.5)
			(connect_pads
				(clearance 0)
			)
			(min_thickness 0.25)
			(keepout
				(tracks allowed)
				(vias not_allowed)
				(pads allowed)
				(copperpour not_allowed)
				(footprints allowed)
			)
			(placement
				(enabled no)
				(sheetname "")
			)
			(fill
				(thermal_gap 0.5)
				(thermal_bridge_width 0.5)
				(island_removal_mode 0)
			)
			(polygon
				(pts
					(xy 338.968588 -119.465598) (xy 338.968588 -118.957598) (xy 338.587588 -118.957598) (xy 338.587588 -119.465598)
				)
			)
		)
	)
	(footprint ""
		(layer "F.Cu")
		(at 185.886598 -126.97333 90)
		(property "Reference" "Q12W2"
			(at 0 0 90)
			(layer "F.SilkS")
			(hide yes)
			(effects
				(font
					(size 1.27 1.27)
				)
			)
		)
		(property "Value" "*"
			(at -4.572 -7.6835 90)
			(unlocked yes)
			(layer "F.Fab")
			(hide yes)
			(effects
				(font
					(size 1.27 1.016)
					(thickness 0.1524)
				)
			)
		)
		(property "Device Type" "BSL308C-H6327-GP_DISCRET-GB1-BA"
			(at -4.572 -9.2075 90)
			(unlocked yes)
			(layer "F.Fab")
			(hide yes)
			(effects
				(font
					(size 1.27 1.016)
					(thickness 0.1524)
				)
			)
		)
		(duplicate_pad_numbers_are_jumpers no)
		(fp_line
			(start 1.102868 -0.081534)
			(end 1.102868 0.081534)
			(stroke
				(width 0.1524)
				(type default)
			)
			(layer "F.SilkS")
		)
		(fp_line
			(start -1.8796 -0.081534)
			(end 1.102868 -0.081534)
			(stroke
				(width 0.1524)
				(type default)
			)
			(layer "F.SilkS")
		)
		(fp_line
			(start -1.8796 -0.081534)
			(end -1.524 0)
			(stroke
				(width 0.1524)
				(type default)
			)
			(layer "F.SilkS")
		)
		(fp_line
			(start -1.524 0)
			(end -1.8796 0.081534)
			(stroke
				(width 0.1524)
				(type default)
			)
			(layer "F.SilkS")
		)
		(fp_line
			(start 1.102868 0.081534)
			(end -1.8796 0.081534)
			(stroke
				(width 0.1524)
				(type default)
			)
			(layer "F.SilkS")
		)
		(fp_line
			(start -1.8796 0.081534)
			(end -1.8796 -0.081534)
			(stroke
				(width 0.1524)
				(type default)
			)
			(layer "F.SilkS")
		)
		(fp_line
			(start -1.7018 0.3048)
			(end -1.7018 1.8796)
			(stroke
				(width 0.508)
				(type default)
			)
			(layer "F.SilkS")
		)
		(fp_poly
			(pts
				(xy -1.179068 0.081534) (xy -1.179068 -0.081534) (xy 1.102868 -0.081534) (xy 1.102868 0.081534)
			)
			(stroke
				(width 0)
				(type default)
			)
			(fill yes)
			(layer "F.SilkS")
		)
		(fp_poly
			(pts
				(xy -1.4478 1.2446) (xy 1.4478 1.2446) (xy 1.4478 -1.2446) (xy -1.4478 -1.2446)
			)
			(stroke
				(width 0)
				(type default)
			)
			(fill no)
			(layer "F.CrtYd")
		)
		(fp_poly
			(pts
				(xy -1.4478 -1.23952) (xy -1.9558 -1.23952) (xy -1.9558 2.1336) (xy 1.9558 2.1336) (xy 1.9558 -2.1336)
				(xy -1.9558 -2.1336) (xy -1.9558 -1.2446) (xy 1.4478 -1.2446) (xy 1.4478 1.2446) (xy -1.4478 1.2446)
			)
			(stroke
				(width 0)
				(type default)
			)
			(fill no)
			(layer "F.CrtYd")
		)
		(fp_rect
			(start -1.9558 2.1336)
			(end 1.9558 -2.1336)
			(stroke
				(width 0)
				(type default)
			)
			(fill no)
			(layer "F.Fab")
		)
		(pad "1" smd rect
			(at -0.950468 0.995934 90)
			(size 0.4572 1.27)
			(layers "F.Cu" "F.Mask" "F.Paste")
			(net "PWRGD_PVDDQ_DEF")
		)
		(pad "2" smd rect
			(at 0 0.995934 90)
			(size 0.4572 1.27)
			(layers "F.Cu" "F.Mask" "F.Paste")
			(net "P12V_NVDIMM_DEF")
		)
		(pad "3" smd rect
			(at 0.950468 0.995934 90)
			(size 0.4572 1.27)
			(layers "F.Cu" "F.Mask" "F.Paste")
			(net "PWRGD_PVDDQ_DEF_N")
		)
		(pad "4" smd rect
			(at 0.950468 -0.995934 90)
			(size 0.4572 1.27)
			(layers "F.Cu" "F.Mask" "F.Paste")
			(net "P12V_NVDIMM_DEF_D")
		)
		(pad "5" smd rect
			(at 0 -0.995934 90)
			(size 0.4572 1.27)
			(layers "F.Cu" "F.Mask" "F.Paste")
			(net "GND")
		)
		(pad "6" smd rect
			(at -0.950468 -0.995934 90)
			(size 0.4572 1.27)
			(layers "F.Cu" "F.Mask" "F.Paste")
			(net "PWRGD_PVDDQ_DEF_N")
		)
	)
	(footprint ""
		(layer "F.Cu")
		(at 194.142614 -61.732668)
		(property "Reference" "CT6"
			(at -0.48387 -4.9022 270)
			(unlocked yes)
			(layer "F.SilkS")
			(effects
				(font
					(size 0.7874 0.5842)
					(thickness 0.1524)
				)
				(justify left)
			)
		)
		(property "Value" ""
			(at 0 0 0)
			(layer "F.Fab")
			(effects
				(font
					(size 1.27 1.27)
				)
			)
		)
		(duplicate_pad_numbers_are_jumpers no)
		(fp_poly
			(pts
				(xy 0.3048 -0.1016) (xy 0.3048 0.9906) (xy -0.3048 0.9906) (xy -0.3048 -0.1016)
			)
			(stroke
				(width 0)
				(type default)
			)
			(fill no)
			(layer "F.CrtYd")
		)
		(fp_line
			(start -0.3048 -0.1016)
			(end -0.3048 0.9906)
			(stroke
				(width 0.1)
				(type default)
			)
			(layer "F.Fab")
		)
		(fp_line
			(start -0.3048 0.9906)
			(end 0.3048 0.9906)
			(stroke
				(width 0.1)
				(type default)
			)
			(layer "F.Fab")
		)
		(fp_line
			(start 0.3048 -0.1016)
			(end -0.3048 -0.1016)
			(stroke
				(width 0.1)
				(type default)
			)
			(layer "F.Fab")
		)
		(fp_line
			(start 0.3048 0.9906)
			(end 0.3048 -0.1016)
			(stroke
				(width 0.1)
				(type default)
			)
			(layer "F.Fab")
		)
		(pad "1" smd rect
			(at 0 0)
			(size 0.508 0.508)
			(layers "F.Cu" "F.Mask" "F.Paste")
			(net "VR_PVCCIN_CPU0_AIREF2")
		)
		(pad "2" smd rect
			(at 0 0.889)
			(size 0.508 0.508)
			(layers "F.Cu" "F.Mask" "F.Paste")
			(net "GND")
		)
		(zone
			(layer "F.Cu")
			(hatch none 0.5)
			(connect_pads
				(clearance 0)
			)
			(min_thickness 0.25)
			(keepout
				(tracks allowed)
				(vias not_allowed)
				(pads allowed)
				(copperpour not_allowed)
				(footprints allowed)
			)
			(placement
				(enabled no)
				(sheetname "")
			)
			(fill
				(thermal_gap 0.5)
				(thermal_bridge_width 0.5)
				(island_removal_mode 0)
			)
			(polygon
				(pts
					(xy 193.888614 -61.478668) (xy 194.396614 -61.478668) (xy 194.396614 -61.097668) (xy 193.888614 -61.097668)
				)
			)
		)
		(zone
			(layer "F.Cu")
			(hatch none 0.5)
			(connect_pads
				(clearance 0)
			)
			(min_thickness 0.25)
			(keepout
				(tracks not_allowed)
				(vias allowed)
				(pads allowed)
				(copperpour not_allowed)
				(footprints allowed)
			)
			(placement
				(enabled no)
				(sheetname "")
			)
			(fill
				(thermal_gap 0.5)
				(thermal_bridge_width 0.5)
				(island_removal_mode 0)
			)
			(polygon
				(pts
					(xy 193.888614 -61.097668) (xy 194.396614 -61.097668) (xy 194.396614 -61.478668) (xy 193.888614 -61.478668)
				)
			)
		)
	)
	(footprint ""
		(layer "F.Cu")
		(at 385.8768 -51.6128 180)
		(property "Reference" "R7F29"
			(at 0 0 180)
			(layer "F.SilkS")
			(hide yes)
			(effects
				(font
					(size 1.27 1.27)
				)
			)
		)
		(property "Value" ""
			(at 0 0 180)
			(layer "F.Fab")
			(effects
				(font
					(size 1.27 1.27)
				)
			)
		)
		(duplicate_pad_numbers_are_jumpers no)
		(fp_poly
			(pts
				(xy -0.2794 -0.1016) (xy 0.2794 -0.1016) (xy 0.2794 0.9906) (xy -0.2794 0.9906)
			)
			(stroke
				(width 0)
				(type default)
			)
			(fill no)
			(layer "F.CrtYd")
		)
		(fp_line
			(start 0.2794 0.9906)
			(end 0.2794 -0.1016)
			(stroke
				(width 0.1)
				(type default)
			)
			(layer "F.Fab")
		)
		(fp_line
			(start 0.2794 -0.1016)
			(end -0.2794 -0.1016)
			(stroke
				(width 0.1)
				(type default)
			)
			(layer "F.Fab")
		)
		(fp_line
			(start -0.2794 0.9906)
			(end 0.2794 0.9906)
			(stroke
				(width 0.1)
				(type default)
			)
			(layer "F.Fab")
		)
		(fp_line
			(start -0.2794 -0.1016)
			(end -0.2794 0.9906)
			(stroke
				(width 0.1)
				(type default)
			)
			(layer "F.Fab")
		)
		(pad "1" smd rect
			(at 0 0 180)
			(size 0.508 0.508)
			(layers "F.Cu" "F.Mask" "F.Paste")
			(net "SPI_SWITCH_MOSI")
		)
		(pad "2" smd rect
			(at 0 0.889 180)
			(size 0.508 0.508)
			(layers "F.Cu" "F.Mask" "F.Paste")
			(net "SPI_SWITCH_MOSI_R0")
		)
		(zone
			(layer "F.Cu")
			(hatch none 0.5)
			(connect_pads
				(clearance 0)
			)
			(min_thickness 0.25)
			(keepout
				(tracks not_allowed)
				(vias allowed)
				(pads allowed)
				(copperpour not_allowed)
				(footprints allowed)
			)
			(placement
				(enabled no)
				(sheetname "")
			)
			(fill
				(thermal_gap 0.5)
				(thermal_bridge_width 0.5)
				(island_removal_mode 0)
			)
			(polygon
				(pts
					(xy 386.1308 -52.2478) (xy 385.6228 -52.2478) (xy 385.6228 -51.8668) (xy 386.1308 -51.8668)
				)
			)
		)
		(zone
			(layer "F.Cu")
			(hatch none 0.5)
			(connect_pads
				(clearance 0)
			)
			(min_thickness 0.25)
			(keepout
				(tracks allowed)
				(vias not_allowed)
				(pads allowed)
				(copperpour not_allowed)
				(footprints allowed)
			)
			(placement
				(enabled no)
				(sheetname "")
			)
			(fill
				(thermal_gap 0.5)
				(thermal_bridge_width 0.5)
				(island_removal_mode 0)
			)
			(polygon
				(pts
					(xy 386.1308 -51.8668) (xy 385.6228 -51.8668) (xy 385.6228 -52.2478) (xy 386.1308 -52.2478)
				)
			)
		)
	)
	(footprint ""
		(layer "F.Cu")
		(at 370.366544 -10.916158)
		(property "Reference" "C7G12"
			(at 0 0 0)
			(layer "F.SilkS")
			(hide yes)
			(effects
				(font
					(size 1.27 1.27)
				)
			)
		)
		(property "Value" ""
			(at 0 0 0)
			(layer "F.Fab")
			(effects
				(font
					(size 1.27 1.27)
				)
			)
		)
		(duplicate_pad_numbers_are_jumpers no)
		(fp_rect
			(start -0.3048 0.9906)
			(end 0.3048 -0.1016)
			(stroke
				(width 0)
				(type default)
			)
			(fill no)
			(layer "F.CrtYd")
		)
		(fp_line
			(start -0.3048 -0.1016)
			(end -0.3048 0.9906)
			(stroke
				(width 0.1)
				(type default)
			)
			(layer "F.Fab")
		)
		(fp_line
			(start -0.3048 0.9906)
			(end 0.3048 0.9906)
			(stroke
				(width 0.1)
				(type default)
			)
			(layer "F.Fab")
		)
		(fp_line
			(start 0.3048 -0.1016)
			(end -0.3048 -0.1016)
			(stroke
				(width 0.1)
				(type default)
			)
			(layer "F.Fab")
		)
		(fp_line
			(start 0.3048 0.9906)
			(end 0.3048 -0.1016)
			(stroke
				(width 0.1)
				(type default)
			)
			(layer "F.Fab")
		)
		(pad "1" smd rect
			(at 0 0)
			(size 0.508 0.508)
			(layers "F.Cu" "F.Mask" "F.Paste")
			(net "P3E_CPU0_PE2_SS_TXN<12>")
		)
		(pad "2" smd rect
			(at 0 0.889)
			(size 0.508 0.508)
			(layers "F.Cu" "F.Mask" "F.Paste")
			(net "P3E_CPU0_PE2_SS_C_TXN<12>")
		)
		(zone
			(layer "F.Cu")
			(hatch none 0.5)
			(connect_pads
				(clearance 0)
			)
			(min_thickness 0.25)
			(keepout
				(tracks not_allowed)
				(vias allowed)
				(pads allowed)
				(copperpour not_allowed)
				(footprints allowed)
			)
			(placement
				(enabled no)
				(sheetname "")
			)
			(fill
				(thermal_gap 0.5)
				(thermal_bridge_width 0.5)
				(island_removal_mode 0)
			)
			(polygon
				(pts
					(xy 370.112544 -10.281158) (xy 370.620544 -10.281158) (xy 370.620544 -10.662158) (xy 370.112544 -10.662158)
				)
			)
		)
		(zone
			(layer "F.Cu")
			(hatch none 0.5)
			(connect_pads
				(clearance 0)
			)
			(min_thickness 0.25)
			(keepout
				(tracks allowed)
				(vias not_allowed)
				(pads allowed)
				(copperpour not_allowed)
				(footprints allowed)
			)
			(placement
				(enabled no)
				(sheetname "")
			)
			(fill
				(thermal_gap 0.5)
				(thermal_bridge_width 0.5)
				(island_removal_mode 0)
			)
			(polygon
				(pts
					(xy 370.112544 -10.281158) (xy 370.620544 -10.281158) (xy 370.620544 -10.662158) (xy 370.112544 -10.662158)
				)
			)
		)
	)
	(footprint ""
		(layer "F.Cu")
		(at 405.283416 -147.420584 90)
		(property "Reference" "R8A11"
			(at 0 0 90)
			(layer "F.SilkS")
			(hide yes)
			(effects
				(font
					(size 1.27 1.27)
				)
			)
		)
		(property "Value" ""
			(at 0 0 90)
			(layer "F.Fab")
			(effects
				(font
					(size 1.27 1.27)
				)
			)
		)
		(duplicate_pad_numbers_are_jumpers no)
		(fp_poly
			(pts
				(xy -0.2794 -0.1016) (xy 0.2794 -0.1016) (xy 0.2794 0.9906) (xy -0.2794 0.9906)
			)
			(stroke
				(width 0)
				(type default)
			)
			(fill no)
			(layer "F.CrtYd")
		)
		(fp_line
			(start 0.2794 -0.1016)
			(end -0.2794 -0.1016)
			(stroke
				(width 0.1)
				(type default)
			)
			(layer "F.Fab")
		)
		(fp_line
			(start -0.2794 -0.1016)
			(end -0.2794 0.9906)
			(stroke
				(width 0.1)
				(type default)
			)
			(layer "F.Fab")
		)
		(fp_line
			(start 0.2794 0.9906)
			(end 0.2794 -0.1016)
			(stroke
				(width 0.1)
				(type default)
			)
			(layer "F.Fab")
		)
		(fp_line
			(start -0.2794 0.9906)
			(end 0.2794 0.9906)
			(stroke
				(width 0.1)
				(type default)
			)
			(layer "F.Fab")
		)
		(pad "1" smd rect
			(at 0 0 90)
			(size 0.508 0.508)
			(layers "F.Cu" "F.Mask" "F.Paste")
			(net "PWRGD_P1V8_PCH_STBY_R")
		)
		(pad "2" smd rect
			(at 0 0.889 90)
			(size 0.508 0.508)
			(layers "F.Cu" "F.Mask" "F.Paste")
			(net "PWRGD_P1V8_PCH_STBY")
		)
		(zone
			(layer "F.Cu")
			(hatch none 0.5)
			(connect_pads
				(clearance 0)
			)
			(min_thickness 0.25)
			(keepout
				(tracks allowed)
				(vias not_allowed)
				(pads allowed)
				(copperpour not_allowed)
				(footprints allowed)
			)
			(placement
				(enabled no)
				(sheetname "")
			)
			(fill
				(thermal_gap 0.5)
				(thermal_bridge_width 0.5)
				(island_removal_mode 0)
			)
			(polygon
				(pts
					(xy 405.537416 -147.166584) (xy 405.537416 -147.674584) (xy 405.918416 -147.674584) (xy 405.918416 -147.166584)
				)
			)
		)
		(zone
			(layer "F.Cu")
			(hatch none 0.5)
			(connect_pads
				(clearance 0)
			)
			(min_thickness 0.25)
			(keepout
				(tracks not_allowed)
				(vias allowed)
				(pads allowed)
				(copperpour not_allowed)
				(footprints allowed)
			)
			(placement
				(enabled no)
				(sheetname "")
			)
			(fill
				(thermal_gap 0.5)
				(thermal_bridge_width 0.5)
				(island_removal_mode 0)
			)
			(polygon
				(pts
					(xy 405.918416 -147.166584) (xy 405.918416 -147.674584) (xy 405.537416 -147.674584) (xy 405.537416 -147.166584)
				)
			)
		)
	)
	(footprint ""
		(layer "F.Cu")
		(at 393.916408 -61.773308 180)
		(property "Reference" "R8E37"
			(at 0 0 180)
			(layer "F.SilkS")
			(hide yes)
			(effects
				(font
					(size 1.27 1.27)
				)
			)
		)
		(property "Value" ""
			(at 0 0 180)
			(layer "F.Fab")
			(effects
				(font
					(size 1.27 1.27)
				)
			)
		)
		(duplicate_pad_numbers_are_jumpers no)
		(fp_poly
			(pts
				(xy -0.2794 -0.1016) (xy 0.2794 -0.1016) (xy 0.2794 0.9906) (xy -0.2794 0.9906)
			)
			(stroke
				(width 0)
				(type default)
			)
			(fill no)
			(layer "F.CrtYd")
		)
		(fp_line
			(start 0.2794 0.9906)
			(end 0.2794 -0.1016)
			(stroke
				(width 0.1)
				(type default)
			)
			(layer "F.Fab")
		)
		(fp_line
			(start 0.2794 -0.1016)
			(end -0.2794 -0.1016)
			(stroke
				(width 0.1)
				(type default)
			)
			(layer "F.Fab")
		)
		(fp_line
			(start -0.2794 0.9906)
			(end 0.2794 0.9906)
			(stroke
				(width 0.1)
				(type default)
			)
			(layer "F.Fab")
		)
		(fp_line
			(start -0.2794 -0.1016)
			(end -0.2794 0.9906)
			(stroke
				(width 0.1)
				(type default)
			)
			(layer "F.Fab")
		)
		(pad "1" smd rect
			(at 0 0 180)
			(size 0.508 0.508)
			(layers "F.Cu" "F.Mask" "F.Paste")
			(net "VR_P5V_STBY_VSENSE_R")
		)
		(pad "2" smd rect
			(at 0 0.889 180)
			(size 0.508 0.508)
			(layers "F.Cu" "F.Mask" "F.Paste")
			(net "P5V_STBY")
		)
		(zone
			(layer "F.Cu")
			(hatch none 0.5)
			(connect_pads
				(clearance 0)
			)
			(min_thickness 0.25)
			(keepout
				(tracks not_allowed)
				(vias allowed)
				(pads allowed)
				(copperpour not_allowed)
				(footprints allowed)
			)
			(placement
				(enabled no)
				(sheetname "")
			)
			(fill
				(thermal_gap 0.5)
				(thermal_bridge_width 0.5)
				(island_removal_mode 0)
			)
			(polygon
				(pts
					(xy 394.170408 -62.408308) (xy 393.662408 -62.408308) (xy 393.662408 -62.027308) (xy 394.170408 -62.027308)
				)
			)
		)
		(zone
			(layer "F.Cu")
			(hatch none 0.5)
			(connect_pads
				(clearance 0)
			)
			(min_thickness 0.25)
			(keepout
				(tracks allowed)
				(vias not_allowed)
				(pads allowed)
				(copperpour not_allowed)
				(footprints allowed)
			)
			(placement
				(enabled no)
				(sheetname "")
			)
			(fill
				(thermal_gap 0.5)
				(thermal_bridge_width 0.5)
				(island_removal_mode 0)
			)
			(polygon
				(pts
					(xy 394.170408 -62.027308) (xy 393.662408 -62.027308) (xy 393.662408 -62.408308) (xy 394.170408 -62.408308)
				)
			)
		)
	)
	(footprint ""
		(layer "F.Cu")
		(at 456.5015 -24.8412 -90)
		(property "Reference" "C1W7"
			(at 0.97536 0.76708 180)
			(unlocked yes)
			(layer "F.SilkS")
			(effects
				(font
					(size 0.4064 0.254)
					(thickness 0.1524)
				)
			)
		)
		(property "Value" ""
			(at 0 0 270)
			(layer "F.Fab")
			(effects
				(font
					(size 1.27 1.27)
				)
			)
		)
		(duplicate_pad_numbers_are_jumpers no)
		(fp_poly
			(pts
				(xy -0.4953 -0.2032) (xy 0.4953 -0.2032) (xy 0.4953 1.6002) (xy -0.4953 1.6002)
			)
			(stroke
				(width 0)
				(type default)
			)
			(fill no)
			(layer "F.CrtYd")
		)
		(fp_line
			(start -0.4953 1.6002)
			(end -0.4953 -0.2032)
			(stroke
				(width 0.1)
				(type default)
			)
			(layer "F.Fab")
		)
		(fp_line
			(start 0.4953 1.6002)
			(end -0.4953 1.6002)
			(stroke
				(width 0.1)
				(type default)
			)
			(layer "F.Fab")
		)
		(fp_line
			(start -0.4953 -0.2032)
			(end 0.4953 -0.2032)
			(stroke
				(width 0.1)
				(type default)
			)
			(layer "F.Fab")
		)
		(fp_line
			(start 0.4953 -0.2032)
			(end 0.4953 1.6002)
			(stroke
				(width 0.1)
				(type default)
			)
			(layer "F.Fab")
		)
		(pad "1" smd rect
			(at 0 0 270)
			(size 0.762 0.889)
			(layers "F.Cu" "F.Mask" "F.Paste")
			(net "P3V3_STBY")
		)
		(pad "2" smd rect
			(at 0 1.397 270)
			(size 0.762 0.889)
			(layers "F.Cu" "F.Mask" "F.Paste")
			(net "GND")
		)
		(zone
			(layer "F.Cu")
			(hatch none 0.5)
			(connect_pads
				(clearance 0)
			)
			(min_thickness 0.25)
			(keepout
				(tracks not_allowed)
				(vias allowed)
				(pads allowed)
				(copperpour not_allowed)
				(footprints allowed)
			)
			(placement
				(enabled no)
				(sheetname "")
			)
			(fill
				(thermal_gap 0.5)
				(thermal_bridge_width 0.5)
				(island_removal_mode 0)
			)
			(polygon
				(pts
					(xy 456.057 -25.2222) (xy 456.057 -24.4602) (xy 455.549 -24.4602) (xy 455.549 -25.2222)
				)
			)
		)
	)
	(footprint ""
		(layer "F.Cu")
		(at 390.652 -87.3125 180)
		(property "Reference" "R2P1"
			(at 0 0 180)
			(layer "F.SilkS")
			(hide yes)
			(effects
				(font
					(size 1.27 1.27)
				)
			)
		)
		(property "Value" ""
			(at 0 0 180)
			(layer "F.Fab")
			(effects
				(font
					(size 1.27 1.27)
				)
			)
		)
		(duplicate_pad_numbers_are_jumpers no)
		(fp_poly
			(pts
				(xy -0.2794 -0.1016) (xy 0.2794 -0.1016) (xy 0.2794 0.9906) (xy -0.2794 0.9906)
			)
			(stroke
				(width 0)
				(type default)
			)
			(fill no)
			(layer "F.CrtYd")
		)
		(fp_line
			(start 0.2794 0.9906)
			(end 0.2794 -0.1016)
			(stroke
				(width 0.1)
				(type default)
			)
			(layer "F.Fab")
		)
		(fp_line
			(start 0.2794 -0.1016)
			(end -0.2794 -0.1016)
			(stroke
				(width 0.1)
				(type default)
			)
			(layer "F.Fab")
		)
		(fp_line
			(start -0.2794 0.9906)
			(end 0.2794 0.9906)
			(stroke
				(width 0.1)
				(type default)
			)
			(layer "F.Fab")
		)
		(fp_line
			(start -0.2794 -0.1016)
			(end -0.2794 0.9906)
			(stroke
				(width 0.1)
				(type default)
			)
			(layer "F.Fab")
		)
		(pad "1" smd rect
			(at 0 0 180)
			(size 0.508 0.508)
			(layers "F.Cu" "F.Mask" "F.Paste")
			(net "RMII_SPRNGVLLE_BMC_PCH_RXD1")
		)
		(pad "2" smd rect
			(at 0 0.889 180)
			(size 0.508 0.508)
			(layers "F.Cu" "F.Mask" "F.Paste")
			(net "RMII_SPRNGVLLE_BMC_PCH_RXD1_R1")
		)
		(zone
			(layer "F.Cu")
			(hatch none 0.5)
			(connect_pads
				(clearance 0)
			)
			(min_thickness 0.25)
			(keepout
				(tracks not_allowed)
				(vias allowed)
				(pads allowed)
				(copperpour not_allowed)
				(footprints allowed)
			)
			(placement
				(enabled no)
				(sheetname "")
			)
			(fill
				(thermal_gap 0.5)
				(thermal_bridge_width 0.5)
				(island_removal_mode 0)
			)
			(polygon
				(pts
					(xy 390.906 -87.9475) (xy 390.398 -87.9475) (xy 390.398 -87.5665) (xy 390.906 -87.5665)
				)
			)
		)
		(zone
			(layer "F.Cu")
			(hatch none 0.5)
			(connect_pads
				(clearance 0)
			)
			(min_thickness 0.25)
			(keepout
				(tracks allowed)
				(vias not_allowed)
				(pads allowed)
				(copperpour not_allowed)
				(footprints allowed)
			)
			(placement
				(enabled no)
				(sheetname "")
			)
			(fill
				(thermal_gap 0.5)
				(thermal_bridge_width 0.5)
				(island_removal_mode 0)
			)
			(polygon
				(pts
					(xy 390.906 -87.5665) (xy 390.398 -87.5665) (xy 390.398 -87.9475) (xy 390.906 -87.9475)
				)
			)
		)
	)
	(footprint ""
		(layer "F.Cu")
		(at 328.9808 -26.6827 180)
		(property "Reference" "C6F4"
			(at 2.91973 -1.9812 90)
			(unlocked yes)
			(layer "F.SilkS")
			(effects
				(font
					(size 0.7874 0.5842)
					(thickness 0.1524)
				)
				(justify left)
			)
		)
		(property "Value" ""
			(at 0 0 180)
			(layer "F.Fab")
			(effects
				(font
					(size 1.27 1.27)
				)
			)
		)
		(duplicate_pad_numbers_are_jumpers no)
		(fp_line
			(start 2.2987 7.3533)
			(end 2.2987 -0.2413)
			(stroke
				(width 0.1524)
				(type default)
			)
			(layer "F.SilkS")
		)
		(fp_line
			(start 2.2987 -0.2413)
			(end 2.032 -0.2413)
			(stroke
				(width 0.1524)
				(type default)
			)
			(layer "F.SilkS")
		)
		(fp_line
			(start 2.032 1.524)
			(end 1.7272 1.524)
			(stroke
				(width 0.1524)
				(type default)
			)
			(layer "F.SilkS")
		)
		(fp_line
			(start 2.032 -1.524)
			(end 2.032 1.524)
			(stroke
				(width 0.1524)
				(type default)
			)
			(layer "F.SilkS")
		)
		(fp_line
			(start 1.7272 7.3533)
			(end 2.2987 7.3533)
			(stroke
				(width 0.1524)
				(type default)
			)
			(layer "F.SilkS")
		)
		(fp_line
			(start 1.7272 -1.524)
			(end 2.032 -1.524)
			(stroke
				(width 0.1524)
				(type default)
			)
			(layer "F.SilkS")
		)
		(fp_line
			(start -1.7272 -1.524)
			(end -2.032 -1.524)
			(stroke
				(width 0.1524)
				(type default)
			)
			(layer "F.SilkS")
		)
		(fp_line
			(start -2.032 1.524)
			(end -1.7272 1.524)
			(stroke
				(width 0.1524)
				(type default)
			)
			(layer "F.SilkS")
		)
		(fp_line
			(start -2.032 -0.2413)
			(end -2.2987 -0.2413)
			(stroke
				(width 0.1524)
				(type default)
			)
			(layer "F.SilkS")
		)
		(fp_line
			(start -2.032 -1.524)
			(end -2.032 1.524)
			(stroke
				(width 0.1524)
				(type default)
			)
			(layer "F.SilkS")
		)
		(fp_line
			(start -2.2987 7.3533)
			(end -1.7272 7.3533)
			(stroke
				(width 0.1524)
				(type default)
			)
			(layer "F.SilkS")
		)
		(fp_line
			(start -2.2987 -0.2413)
			(end -2.2987 7.3533)
			(stroke
				(width 0.1524)
				(type default)
			)
			(layer "F.SilkS")
		)
		(fp_rect
			(start 2.2987 -0.2413)
			(end -2.2987 7.3533)
			(stroke
				(width 0)
				(type default)
			)
			(fill no)
			(layer "F.CrtYd")
		)
		(fp_line
			(start 2.2987 7.3533)
			(end -2.2987 7.3533)
			(stroke
				(width 0.1)
				(type default)
			)
			(layer "F.Fab")
		)
		(fp_line
			(start 2.2987 -0.2413)
			(end 2.2987 7.3533)
			(stroke
				(width 0.1)
				(type default)
			)
			(layer "F.Fab")
		)
		(fp_line
			(start -2.2987 7.3533)
			(end -2.2987 -0.2413)
			(stroke
				(width 0.1)
				(type default)
			)
			(layer "F.Fab")
		)
		(fp_line
			(start -2.2987 -0.2413)
			(end 2.2987 -0.2413)
			(stroke
				(width 0.1)
				(type default)
			)
			(layer "F.Fab")
		)
		(pad "1" smd rect
			(at 0 0 180)
			(size 2.54 3.048)
			(layers "F.Cu" "F.Mask" "F.Paste")
			(net "PVPP_ABC")
		)
		(pad "2" smd rect
			(at 0 7.112 180)
			(size 2.54 3.048)
			(layers "F.Cu" "F.Mask" "F.Paste")
			(net "GND")
		)
	)
	(footprint ""
		(layer "F.Cu")
		(at 369.57 -136.4615 180)
		(property "Reference" "R7A19"
			(at 0 0 180)
			(layer "F.SilkS")
			(hide yes)
			(effects
				(font
					(size 1.27 1.27)
				)
			)
		)
		(property "Value" ""
			(at 0 0 180)
			(layer "F.Fab")
			(effects
				(font
					(size 1.27 1.27)
				)
			)
		)
		(duplicate_pad_numbers_are_jumpers no)
		(fp_poly
			(pts
				(xy -0.2794 -0.1016) (xy 0.2794 -0.1016) (xy 0.2794 0.9906) (xy -0.2794 0.9906)
			)
			(stroke
				(width 0)
				(type default)
			)
			(fill no)
			(layer "F.CrtYd")
		)
		(fp_line
			(start 0.2794 0.9906)
			(end 0.2794 -0.1016)
			(stroke
				(width 0.1)
				(type default)
			)
			(layer "F.Fab")
		)
		(fp_line
			(start 0.2794 -0.1016)
			(end -0.2794 -0.1016)
			(stroke
				(width 0.1)
				(type default)
			)
			(layer "F.Fab")
		)
		(fp_line
			(start -0.2794 0.9906)
			(end 0.2794 0.9906)
			(stroke
				(width 0.1)
				(type default)
			)
			(layer "F.Fab")
		)
		(fp_line
			(start -0.2794 -0.1016)
			(end -0.2794 0.9906)
			(stroke
				(width 0.1)
				(type default)
			)
			(layer "F.Fab")
		)
		(pad "1" smd rect
			(at 0 0 180)
			(size 0.508 0.508)
			(layers "F.Cu" "F.Mask" "F.Paste")
			(net "VSENSE_PVNN_PCH_STBY_QAT")
		)
		(pad "2" smd rect
			(at 0 0.889 180)
			(size 0.508 0.508)
			(layers "F.Cu" "F.Mask" "F.Paste")
			(net "VSENSE_PVNN_PCH_STBY_AVSP")
		)
		(zone
			(layer "F.Cu")
			(hatch none 0.5)
			(connect_pads
				(clearance 0)
			)
			(min_thickness 0.25)
			(keepout
				(tracks not_allowed)
				(vias allowed)
				(pads allowed)
				(copperpour not_allowed)
				(footprints allowed)
			)
			(placement
				(enabled no)
				(sheetname "")
			)
			(fill
				(thermal_gap 0.5)
				(thermal_bridge_width 0.5)
				(island_removal_mode 0)
			)
			(polygon
				(pts
					(xy 369.824 -137.0965) (xy 369.316 -137.0965) (xy 369.316 -136.7155) (xy 369.824 -136.7155)
				)
			)
		)
		(zone
			(layer "F.Cu")
			(hatch none 0.5)
			(connect_pads
				(clearance 0)
			)
			(min_thickness 0.25)
			(keepout
				(tracks allowed)
				(vias not_allowed)
				(pads allowed)
				(copperpour not_allowed)
				(footprints allowed)
			)
			(placement
				(enabled no)
				(sheetname "")
			)
			(fill
				(thermal_gap 0.5)
				(thermal_bridge_width 0.5)
				(island_removal_mode 0)
			)
			(polygon
				(pts
					(xy 369.824 -136.7155) (xy 369.316 -136.7155) (xy 369.316 -137.0965) (xy 369.824 -137.0965)
				)
			)
		)
	)
	(footprint ""
		(layer "F.Cu")
		(at 80.757268 -12.954 -90)
		(property "Reference" "C2G1"
			(at 1.848866 0.752348 270)
			(unlocked yes)
			(layer "F.SilkS")
			(effects
				(font
					(size 1.27 0.9652)
					(thickness 0.1524)
				)
			)
		)
		(property "Value" ""
			(at 0 0 270)
			(layer "F.Fab")
			(effects
				(font
					(size 1.27 1.27)
				)
			)
		)
		(duplicate_pad_numbers_are_jumpers no)
		(fp_rect
			(start -0.500126 1.598422)
			(end 0.500126 -0.201422)
			(stroke
				(width 0)
				(type default)
			)
			(fill no)
			(layer "F.CrtYd")
		)
		(fp_line
			(start -0.500126 1.598422)
			(end -0.500126 -0.201422)
			(stroke
				(width 0.1)
				(type default)
			)
			(layer "F.Fab")
		)
		(fp_line
			(start 0.500126 1.598422)
			(end -0.500126 1.598422)
			(stroke
				(width 0.1)
				(type default)
			)
			(layer "F.Fab")
		)
		(fp_line
			(start -0.500126 -0.201422)
			(end 0.500126 -0.201422)
			(stroke
				(width 0.1)
				(type default)
			)
			(layer "F.Fab")
		)
		(fp_line
			(start 0.500126 -0.201422)
			(end 0.500126 1.598422)
			(stroke
				(width 0.1)
				(type default)
			)
			(layer "F.Fab")
		)
		(pad "1" smd rect
			(at 0 0 180)
			(size 0.889 0.9906)
			(layers "F.Cu" "F.Mask" "F.Paste")
			(net "PVDDQ_GHJ")
		)
		(pad "2" smd rect
			(at 0 1.397 180)
			(size 0.889 0.9906)
			(layers "F.Cu" "F.Mask" "F.Paste")
			(net "GND")
		)
		(zone
			(layer "F.Cu")
			(hatch none 0.5)
			(connect_pads
				(clearance 0)
			)
			(min_thickness 0.25)
			(keepout
				(tracks allowed)
				(vias not_allowed)
				(pads allowed)
				(copperpour not_allowed)
				(footprints allowed)
			)
			(placement
				(enabled no)
				(sheetname "")
			)
			(fill
				(thermal_gap 0.5)
				(thermal_bridge_width 0.5)
				(island_removal_mode 0)
			)
			(polygon
				(pts
					(xy 79.804768 -13.4493) (xy 79.804768 -12.4587) (xy 80.312768 -12.4587) (xy 80.312768 -13.4493)
				)
			)
		)
		(zone
			(layer "F.Cu")
			(hatch none 0.5)
			(connect_pads
				(clearance 0)
			)
			(min_thickness 0.25)
			(keepout
				(tracks not_allowed)
				(vias allowed)
				(pads allowed)
				(copperpour not_allowed)
				(footprints allowed)
			)
			(placement
				(enabled no)
				(sheetname "")
			)
			(fill
				(thermal_gap 0.5)
				(thermal_bridge_width 0.5)
				(island_removal_mode 0)
			)
			(polygon
				(pts
					(xy 79.804768 -13.4493) (xy 79.804768 -12.4587) (xy 80.312768 -12.4587) (xy 80.312768 -13.4493)
				)
			)
		)
	)
	(footprint ""
		(layer "F.Cu")
		(at 417.703 -83.439 -90)
		(property "Reference" "C8D3"
			(at 0 0 270)
			(layer "F.SilkS")
			(hide yes)
			(effects
				(font
					(size 1.27 1.27)
				)
			)
		)
		(property "Value" ""
			(at 0 0 270)
			(layer "F.Fab")
			(effects
				(font
					(size 1.27 1.27)
				)
			)
		)
		(duplicate_pad_numbers_are_jumpers no)
		(fp_poly
			(pts
				(xy 0.3048 -0.1016) (xy 0.3048 0.9906) (xy -0.3048 0.9906) (xy -0.3048 -0.1016)
			)
			(stroke
				(width 0)
				(type default)
			)
			(fill no)
			(layer "F.CrtYd")
		)
		(fp_line
			(start -0.3048 0.9906)
			(end 0.3048 0.9906)
			(stroke
				(width 0.1)
				(type default)
			)
			(layer "F.Fab")
		)
		(fp_line
			(start 0.3048 0.9906)
			(end 0.3048 -0.1016)
			(stroke
				(width 0.1)
				(type default)
			)
			(layer "F.Fab")
		)
		(fp_line
			(start -0.3048 -0.1016)
			(end -0.3048 0.9906)
			(stroke
				(width 0.1)
				(type default)
			)
			(layer "F.Fab")
		)
		(fp_line
			(start 0.3048 -0.1016)
			(end -0.3048 -0.1016)
			(stroke
				(width 0.1)
				(type default)
			)
			(layer "F.Fab")
		)
		(pad "1" smd rect
			(at 0 0 270)
			(size 0.508 0.508)
			(layers "F.Cu" "F.Mask" "F.Paste")
			(net "IRQ_SML1_PMBUS_ALERT_N")
		)
		(pad "2" smd rect
			(at 0 0.889 270)
			(size 0.508 0.508)
			(layers "F.Cu" "F.Mask" "F.Paste")
			(net "GND")
		)
		(zone
			(layer "F.Cu")
			(hatch none 0.5)
			(connect_pads
				(clearance 0)
			)
			(min_thickness 0.25)
			(keepout
				(tracks not_allowed)
				(vias allowed)
				(pads allowed)
				(copperpour not_allowed)
				(footprints allowed)
			)
			(placement
				(enabled no)
				(sheetname "")
			)
			(fill
				(thermal_gap 0.5)
				(thermal_bridge_width 0.5)
				(island_removal_mode 0)
			)
			(polygon
				(pts
					(xy 417.068 -83.693) (xy 417.068 -83.185) (xy 417.449 -83.185) (xy 417.449 -83.693)
				)
			)
		)
		(zone
			(layer "F.Cu")
			(hatch none 0.5)
			(connect_pads
				(clearance 0)
			)
			(min_thickness 0.25)
			(keepout
				(tracks allowed)
				(vias not_allowed)
				(pads allowed)
				(copperpour not_allowed)
				(footprints allowed)
			)
			(placement
				(enabled no)
				(sheetname "")
			)
			(fill
				(thermal_gap 0.5)
				(thermal_bridge_width 0.5)
				(island_removal_mode 0)
			)
			(polygon
				(pts
					(xy 417.449 -83.693) (xy 417.449 -83.185) (xy 417.068 -83.185) (xy 417.068 -83.693)
				)
			)
		)
	)
	(footprint ""
		(layer "F.Cu")
		(at 205.036928 -57.031382)
		(property "Reference" "L4E1"
			(at 3.378708 -4.251706 0)
			(unlocked yes)
			(layer "F.SilkS")
			(effects
				(font
					(size 0.4064 0.254)
					(thickness 0.1524)
				)
			)
		)
		(property "Value" ""
			(at 0 0 0)
			(layer "F.Fab")
			(effects
				(font
					(size 1.27 1.27)
				)
			)
		)
		(duplicate_pad_numbers_are_jumpers no)
		(fp_line
			(start -1.1303 -3.199892)
			(end 8.3693 -3.199892)
			(stroke
				(width 0.1524)
				(type default)
			)
			(layer "F.SilkS")
		)
		(fp_line
			(start -1.1303 -1.6637)
			(end -1.1303 -3.199892)
			(stroke
				(width 0.1524)
				(type default)
			)
			(layer "F.SilkS")
		)
		(fp_line
			(start -1.1303 3.199892)
			(end -1.1303 1.6637)
			(stroke
				(width 0.1524)
				(type default)
			)
			(layer "F.SilkS")
		)
		(fp_line
			(start 8.3693 -3.199892)
			(end 8.3693 -1.6637)
			(stroke
				(width 0.1524)
				(type default)
			)
			(layer "F.SilkS")
		)
		(fp_line
			(start 8.3693 1.6637)
			(end 8.3693 3.199892)
			(stroke
				(width 0.1524)
				(type default)
			)
			(layer "F.SilkS")
		)
		(fp_line
			(start 8.3693 3.199892)
			(end -1.1303 3.199892)
			(stroke
				(width 0.1524)
				(type default)
			)
			(layer "F.SilkS")
		)
		(fp_rect
			(start -1.1303 3.199892)
			(end 8.3693 -3.199892)
			(stroke
				(width 0)
				(type default)
			)
			(fill no)
			(layer "F.CrtYd")
		)
		(fp_line
			(start -1.1303 -3.199892)
			(end 8.3693 -3.199892)
			(stroke
				(width 0.1)
				(type default)
			)
			(layer "F.Fab")
		)
		(fp_line
			(start -1.1303 3.199892)
			(end -1.1303 -3.199892)
			(stroke
				(width 0.1)
				(type default)
			)
			(layer "F.Fab")
		)
		(fp_line
			(start 8.3693 -3.199892)
			(end 8.3693 3.199892)
			(stroke
				(width 0.1)
				(type default)
			)
			(layer "F.Fab")
		)
		(fp_line
			(start 8.3693 3.199892)
			(end -1.1303 3.199892)
			(stroke
				(width 0.1)
				(type default)
			)
			(layer "F.Fab")
		)
		(pad "1" smd rect
			(at 0 0)
			(size 3.683 2.667)
			(layers "F.Cu" "F.Mask" "F.Paste")
			(net "VR_PVCCIN_CPU0_PHASE1")
		)
		(pad "2" smd rect
			(at 7.239 0)
			(size 3.683 2.667)
			(layers "F.Cu" "F.Mask" "F.Paste")
			(net "PVCCIN_CPU0")
		)
	)
	(footprint ""
		(layer "F.Cu")
		(at 355.149404 -137.150348 180)
		(property "Reference" "C12W2"
			(at -0.8382 -0.67818 180)
			(unlocked yes)
			(layer "F.SilkS")
			(effects
				(font
					(size 0.4064 0.254)
					(thickness 0.1524)
				)
				(justify left)
			)
		)
		(property "Value" ""
			(at 0 0 180)
			(layer "F.Fab")
			(effects
				(font
					(size 1.27 1.27)
				)
			)
		)
		(duplicate_pad_numbers_are_jumpers no)
		(fp_poly
			(pts
				(xy 0.3048 -0.1016) (xy 0.3048 0.9906) (xy -0.3048 0.9906) (xy -0.3048 -0.1016)
			)
			(stroke
				(width 0)
				(type default)
			)
			(fill no)
			(layer "F.CrtYd")
		)
		(fp_line
			(start 0.3048 0.9906)
			(end 0.3048 -0.1016)
			(stroke
				(width 0.1)
				(type default)
			)
			(layer "F.Fab")
		)
		(fp_line
			(start 0.3048 -0.1016)
			(end -0.3048 -0.1016)
			(stroke
				(width 0.1)
				(type default)
			)
			(layer "F.Fab")
		)
		(fp_line
			(start -0.3048 0.9906)
			(end 0.3048 0.9906)
			(stroke
				(width 0.1)
				(type default)
			)
			(layer "F.Fab")
		)
		(fp_line
			(start -0.3048 -0.1016)
			(end -0.3048 0.9906)
			(stroke
				(width 0.1)
				(type default)
			)
			(layer "F.Fab")
		)
		(pad "1" smd rect
			(at 0 0 180)
			(size 0.508 0.508)
			(layers "F.Cu" "F.Mask" "F.Paste")
			(net "VR_PVDDQ_DEF_AIINSEN")
		)
		(pad "2" smd rect
			(at 0 0.889 180)
			(size 0.508 0.508)
			(layers "F.Cu" "F.Mask" "F.Paste")
			(net "VR_PVDDQ_DEF_VINSEN")
		)
		(zone
			(layer "F.Cu")
			(hatch none 0.5)
			(connect_pads
				(clearance 0)
			)
			(min_thickness 0.25)
			(keepout
				(tracks not_allowed)
				(vias allowed)
				(pads allowed)
				(copperpour not_allowed)
				(footprints allowed)
			)
			(placement
				(enabled no)
				(sheetname "")
			)
			(fill
				(thermal_gap 0.5)
				(thermal_bridge_width 0.5)
				(island_removal_mode 0)
			)
			(polygon
				(pts
					(xy 355.403404 -137.785348) (xy 354.895404 -137.785348) (xy 354.895404 -137.404348) (xy 355.403404 -137.404348)
				)
			)
		)
		(zone
			(layer "F.Cu")
			(hatch none 0.5)
			(connect_pads
				(clearance 0)
			)
			(min_thickness 0.25)
			(keepout
				(tracks allowed)
				(vias not_allowed)
				(pads allowed)
				(copperpour not_allowed)
				(footprints allowed)
			)
			(placement
				(enabled no)
				(sheetname "")
			)
			(fill
				(thermal_gap 0.5)
				(thermal_bridge_width 0.5)
				(island_removal_mode 0)
			)
			(polygon
				(pts
					(xy 355.403404 -137.404348) (xy 354.895404 -137.404348) (xy 354.895404 -137.785348) (xy 355.403404 -137.785348)
				)
			)
		)
	)
	(footprint ""
		(layer "F.Cu")
		(at 383.14757 -78.140814 90)
		(property "Reference" "R7D27"
			(at 0 0 90)
			(layer "F.SilkS")
			(hide yes)
			(effects
				(font
					(size 1.27 1.27)
				)
			)
		)
		(property "Value" ""
			(at 0 0 90)
			(layer "F.Fab")
			(effects
				(font
					(size 1.27 1.27)
				)
			)
		)
		(duplicate_pad_numbers_are_jumpers no)
		(fp_poly
			(pts
				(xy -0.2794 -0.1016) (xy 0.2794 -0.1016) (xy 0.2794 0.9906) (xy -0.2794 0.9906)
			)
			(stroke
				(width 0)
				(type default)
			)
			(fill no)
			(layer "F.CrtYd")
		)
		(fp_line
			(start 0.2794 -0.1016)
			(end -0.2794 -0.1016)
			(stroke
				(width 0.1)
				(type default)
			)
			(layer "F.Fab")
		)
		(fp_line
			(start -0.2794 -0.1016)
			(end -0.2794 0.9906)
			(stroke
				(width 0.1)
				(type default)
			)
			(layer "F.Fab")
		)
		(fp_line
			(start 0.2794 0.9906)
			(end 0.2794 -0.1016)
			(stroke
				(width 0.1)
				(type default)
			)
			(layer "F.Fab")
		)
		(fp_line
			(start -0.2794 0.9906)
			(end 0.2794 0.9906)
			(stroke
				(width 0.1)
				(type default)
			)
			(layer "F.Fab")
		)
		(pad "1" smd rect
			(at 0 0 90)
			(size 0.508 0.508)
			(layers "F.Cu" "F.Mask" "F.Paste")
			(net "H_CPU0_MSMI_G_N")
		)
		(pad "2" smd rect
			(at 0 0.889 90)
			(size 0.508 0.508)
			(layers "F.Cu" "F.Mask" "F.Paste")
			(net "H_CPU_MSMI_G_N")
		)
		(zone
			(layer "F.Cu")
			(hatch none 0.5)
			(connect_pads
				(clearance 0)
			)
			(min_thickness 0.25)
			(keepout
				(tracks allowed)
				(vias not_allowed)
				(pads allowed)
				(copperpour not_allowed)
				(footprints allowed)
			)
			(placement
				(enabled no)
				(sheetname "")
			)
			(fill
				(thermal_gap 0.5)
				(thermal_bridge_width 0.5)
				(island_removal_mode 0)
			)
			(polygon
				(pts
					(xy 383.40157 -77.886814) (xy 383.40157 -78.394814) (xy 383.78257 -78.394814) (xy 383.78257 -77.886814)
				)
			)
		)
		(zone
			(layer "F.Cu")
			(hatch none 0.5)
			(connect_pads
				(clearance 0)
			)
			(min_thickness 0.25)
			(keepout
				(tracks not_allowed)
				(vias allowed)
				(pads allowed)
				(copperpour not_allowed)
				(footprints allowed)
			)
			(placement
				(enabled no)
				(sheetname "")
			)
			(fill
				(thermal_gap 0.5)
				(thermal_bridge_width 0.5)
				(island_removal_mode 0)
			)
			(polygon
				(pts
					(xy 383.78257 -77.886814) (xy 383.78257 -78.394814) (xy 383.40157 -78.394814) (xy 383.40157 -77.886814)
				)
			)
		)
	)
	(footprint ""
		(layer "F.Cu")
		(at 490.35081 -155.293314 -90)
		(property "Reference" "C9A1"
			(at 0 0 270)
			(layer "F.SilkS")
			(hide yes)
			(effects
				(font
					(size 1.27 1.27)
				)
			)
		)
		(property "Value" ""
			(at 0 0 270)
			(layer "F.Fab")
			(effects
				(font
					(size 1.27 1.27)
				)
			)
		)
		(duplicate_pad_numbers_are_jumpers no)
		(fp_poly
			(pts
				(xy 0.3048 -0.1016) (xy 0.3048 0.9906) (xy -0.3048 0.9906) (xy -0.3048 -0.1016)
			)
			(stroke
				(width 0)
				(type default)
			)
			(fill no)
			(layer "F.CrtYd")
		)
		(fp_line
			(start -0.3048 0.9906)
			(end 0.3048 0.9906)
			(stroke
				(width 0.1)
				(type default)
			)
			(layer "F.Fab")
		)
		(fp_line
			(start 0.3048 0.9906)
			(end 0.3048 -0.1016)
			(stroke
				(width 0.1)
				(type default)
			)
			(layer "F.Fab")
		)
		(fp_line
			(start -0.3048 -0.1016)
			(end -0.3048 0.9906)
			(stroke
				(width 0.1)
				(type default)
			)
			(layer "F.Fab")
		)
		(fp_line
			(start 0.3048 -0.1016)
			(end -0.3048 -0.1016)
			(stroke
				(width 0.1)
				(type default)
			)
			(layer "F.Fab")
		)
		(pad "1" smd rect
			(at 0 0 270)
			(size 0.508 0.508)
			(layers "F.Cu" "F.Mask" "F.Paste")
			(net "P5V_STBY_DGB_FS")
		)
		(pad "2" smd rect
			(at 0 0.889 270)
			(size 0.508 0.508)
			(layers "F.Cu" "F.Mask" "F.Paste")
			(net "GND")
		)
		(zone
			(layer "F.Cu")
			(hatch none 0.5)
			(connect_pads
				(clearance 0)
			)
			(min_thickness 0.25)
			(keepout
				(tracks not_allowed)
				(vias allowed)
				(pads allowed)
				(copperpour not_allowed)
				(footprints allowed)
			)
			(placement
				(enabled no)
				(sheetname "")
			)
			(fill
				(thermal_gap 0.5)
				(thermal_bridge_width 0.5)
				(island_removal_mode 0)
			)
			(polygon
				(pts
					(xy 489.71581 -155.547314) (xy 489.71581 -155.039314) (xy 490.09681 -155.039314) (xy 490.09681 -155.547314)
				)
			)
		)
		(zone
			(layer "F.Cu")
			(hatch none 0.5)
			(connect_pads
				(clearance 0)
			)
			(min_thickness 0.25)
			(keepout
				(tracks allowed)
				(vias not_allowed)
				(pads allowed)
				(copperpour not_allowed)
				(footprints allowed)
			)
			(placement
				(enabled no)
				(sheetname "")
			)
			(fill
				(thermal_gap 0.5)
				(thermal_bridge_width 0.5)
				(island_removal_mode 0)
			)
			(polygon
				(pts
					(xy 490.09681 -155.547314) (xy 490.09681 -155.039314) (xy 489.71581 -155.039314) (xy 489.71581 -155.547314)
				)
			)
		)
	)
	(footprint ""
		(layer "F.Cu")
		(at 258.208272 -77.636116)
		(property "Reference" "C5D24"
			(at 0 0 0)
			(layer "F.SilkS")
			(hide yes)
			(effects
				(font
					(size 1.27 1.27)
				)
			)
		)
		(property "Value" ""
			(at 0 0 0)
			(layer "F.Fab")
			(effects
				(font
					(size 1.27 1.27)
				)
			)
		)
		(duplicate_pad_numbers_are_jumpers no)
		(fp_poly
			(pts
				(xy -0.4953 -0.2032) (xy 0.4953 -0.2032) (xy 0.4953 1.6002) (xy -0.4953 1.6002)
			)
			(stroke
				(width 0)
				(type default)
			)
			(fill no)
			(layer "F.CrtYd")
		)
		(fp_line
			(start -0.4953 -0.2032)
			(end 0.4953 -0.2032)
			(stroke
				(width 0.1)
				(type default)
			)
			(layer "F.Fab")
		)
		(fp_line
			(start -0.4953 1.6002)
			(end -0.4953 -0.2032)
			(stroke
				(width 0.1)
				(type default)
			)
			(layer "F.Fab")
		)
		(fp_line
			(start 0.4953 -0.2032)
			(end 0.4953 1.6002)
			(stroke
				(width 0.1)
				(type default)
			)
			(layer "F.Fab")
		)
		(fp_line
			(start 0.4953 1.6002)
			(end -0.4953 1.6002)
			(stroke
				(width 0.1)
				(type default)
			)
			(layer "F.Fab")
		)
		(pad "1" smd rect
			(at 0 0)
			(size 0.762 0.889)
			(layers "F.Cu" "F.Mask" "F.Paste")
			(net "PVCCIN_CPU0")
		)
		(pad "2" smd rect
			(at 0 1.397)
			(size 0.762 0.889)
			(layers "F.Cu" "F.Mask" "F.Paste")
			(net "GND")
		)
		(zone
			(layer "F.Cu")
			(hatch none 0.5)
			(connect_pads
				(clearance 0)
			)
			(min_thickness 0.25)
			(keepout
				(tracks not_allowed)
				(vias allowed)
				(pads allowed)
				(copperpour not_allowed)
				(footprints allowed)
			)
			(placement
				(enabled no)
				(sheetname "")
			)
			(fill
				(thermal_gap 0.5)
				(thermal_bridge_width 0.5)
				(island_removal_mode 0)
			)
			(polygon
				(pts
					(xy 257.827272 -77.191616) (xy 258.589272 -77.191616) (xy 258.589272 -76.683616) (xy 257.827272 -76.683616)
				)
			)
		)
	)
	(footprint ""
		(layer "F.Cu")
		(at 496.000024 -5.500116 90)
		(property "Reference" "JA9G1"
			(at 0 0 90)
			(layer "F.SilkS")
			(hide yes)
			(effects
				(font
					(size 1.27 1.27)
				)
			)
		)
		(property "Value" "*"
			(at 12.1031 -6.0325 90)
			(unlocked yes)
			(layer "F.Fab")
			(hide yes)
			(effects
				(font
					(size 1.27 1.016)
					(thickness 0.1524)
				)
			)
		)
		(property "Device Type" "SKT-RJ45-LED-XFOR-1-GP_SOCKET-A"
			(at 12.1031 -7.5565 90)
			(unlocked yes)
			(layer "F.Fab")
			(hide yes)
			(effects
				(font
					(size 1.27 1.016)
					(thickness 0.1524)
				)
			)
		)
		(duplicate_pad_numbers_are_jumpers no)
		(fp_line
			(start 8.7503 -15.3416)
			(end 8.7503 -12.2174)
			(stroke
				(width 0.1524)
				(type default)
			)
			(layer "F.SilkS")
		)
		(fp_line
			(start -8.7503 -15.3416)
			(end 8.7503 -15.3416)
			(stroke
				(width 0.1524)
				(type default)
			)
			(layer "F.SilkS")
		)
		(fp_line
			(start 9.2583 -12.2174)
			(end 9.2583 -8.636)
			(stroke
				(width 0.1524)
				(type default)
			)
			(layer "F.SilkS")
		)
		(fp_line
			(start 8.7503 -12.2174)
			(end 9.2583 -12.2174)
			(stroke
				(width 0.1524)
				(type default)
			)
			(layer "F.SilkS")
		)
		(fp_line
			(start -8.7503 -12.2174)
			(end -8.7503 -15.3416)
			(stroke
				(width 0.1524)
				(type default)
			)
			(layer "F.SilkS")
		)
		(fp_line
			(start -9.2583 -12.2174)
			(end -8.7503 -12.2174)
			(stroke
				(width 0.1524)
				(type default)
			)
			(layer "F.SilkS")
		)
		(fp_line
			(start 7.999984 -12.159996)
			(end -7.999984 -12.159996)
			(stroke
				(width 0.1524)
				(type default)
			)
			(layer "F.SilkS")
		)
		(fp_line
			(start -8.50011 -11.65987)
			(end -8.50011 5.990082)
			(stroke
				(width 0.1524)
				(type default)
			)
			(layer "F.SilkS")
		)
		(fp_line
			(start 9.2583 -8.636)
			(end 8.509 -8.636)
			(stroke
				(width 0.1524)
				(type default)
			)
			(layer "F.SilkS")
		)
		(fp_line
			(start 8.509 -8.636)
			(end 8.509 -2.4511)
			(stroke
				(width 0.1524)
				(type default)
			)
			(layer "F.SilkS")
		)
		(fp_line
			(start -8.509 -8.636)
			(end -9.2583 -8.636)
			(stroke
				(width 0.1524)
				(type default)
			)
			(layer "F.SilkS")
		)
		(fp_line
			(start -9.2583 -8.636)
			(end -9.2583 -12.2174)
			(stroke
				(width 0.1524)
				(type default)
			)
			(layer "F.SilkS")
		)
		(fp_line
			(start 10.2489 -2.4511)
			(end 10.2489 2.4511)
			(stroke
				(width 0.1524)
				(type default)
			)
			(layer "F.SilkS")
		)
		(fp_line
			(start 8.509 -2.4511)
			(end 10.2489 -2.4511)
			(stroke
				(width 0.1524)
				(type default)
			)
			(layer "F.SilkS")
		)
		(fp_line
			(start -8.509 -2.4511)
			(end -8.509 -8.636)
			(stroke
				(width 0.1524)
				(type default)
			)
			(layer "F.SilkS")
		)
		(fp_line
			(start -10.2489 -2.4511)
			(end -8.509 -2.4511)
			(stroke
				(width 0.1524)
				(type default)
			)
			(layer "F.SilkS")
		)
		(fp_line
			(start 10.2489 2.4511)
			(end 8.7503 2.4511)
			(stroke
				(width 0.1524)
				(type default)
			)
			(layer "F.SilkS")
		)
		(fp_line
			(start 8.7503 2.4511)
			(end 8.7503 5.990082)
			(stroke
				(width 0.1524)
				(type default)
			)
			(layer "F.SilkS")
		)
		(fp_line
			(start -8.7503 2.4511)
			(end -10.2489 2.4511)
			(stroke
				(width 0.1524)
				(type default)
			)
			(layer "F.SilkS")
		)
		(fp_line
			(start -10.2489 2.4511)
			(end -10.2489 -2.4511)
			(stroke
				(width 0.1524)
				(type default)
			)
			(layer "F.SilkS")
		)
		(fp_line
			(start 8.7503 5.990082)
			(end 8.50011 5.990082)
			(stroke
				(width 0.1524)
				(type default)
			)
			(layer "F.SilkS")
		)
		(fp_line
			(start 8.50011 5.990082)
			(end 8.50011 -11.65987)
			(stroke
				(width 0.1524)
				(type default)
			)
			(layer "F.SilkS")
		)
		(fp_line
			(start -8.50011 5.990082)
			(end -8.7503 5.990082)
			(stroke
				(width 0.1524)
				(type default)
			)
			(layer "F.SilkS")
		)
		(fp_line
			(start -8.7503 5.990082)
			(end -8.7503 2.4511)
			(stroke
				(width 0.1524)
				(type default)
			)
			(layer "F.SilkS")
		)
		(fp_arc
			(start 5.07492 -14.474952)
			(mid 6.240464 -15.434998)
			(end 7.073392 -14.175486)
			(stroke
				(width 0.3048)
				(type default)
			)
			(layer "F.SilkS")
		)
		(fp_arc
			(start 3.044952 -14.474952)
			(mid 4.059936 -15.446216)
			(end 5.07492 -14.474952)
			(stroke
				(width 0.3048)
				(type default)
			)
			(layer "F.SilkS")
		)
		(fp_arc
			(start 1.014984 -14.474952)
			(mid 2.029968 -15.44573)
			(end 3.044952 -14.474952)
			(stroke
				(width 0.3048)
				(type default)
			)
			(layer "F.SilkS")
		)
		(fp_arc
			(start -1.014984 -14.474952)
			(mid 0 -15.44573)
			(end 1.014984 -14.474952)
			(stroke
				(width 0.3048)
				(type default)
			)
			(layer "F.SilkS")
		)
		(fp_arc
			(start -3.044952 -14.474952)
			(mid -2.029968 -15.445973)
			(end -1.014984 -14.474952)
			(stroke
				(width 0.3048)
				(type default)
			)
			(layer "F.SilkS")
		)
		(fp_arc
			(start -5.07492 -14.474698)
			(mid -4.060063 -15.445719)
			(end -3.044952 -14.474952)
			(stroke
				(width 0.3048)
				(type default)
			)
			(layer "F.SilkS")
		)
		(fp_arc
			(start -5.07492 -14.385544)
			(mid -5.085176 -14.279692)
			(end -5.106416 -14.175486)
			(stroke
				(width 0.3048)
				(type default)
			)
			(layer "F.SilkS")
		)
		(fp_arc
			(start 5.07492 -14.38529)
			(mid 5.064672 -14.279562)
			(end 5.043424 -14.175486)
			(stroke
				(width 0.3048)
				(type default)
			)
			(layer "F.SilkS")
		)
		(fp_arc
			(start 3.044952 -14.38529)
			(mid 3.034704 -14.279562)
			(end 3.013456 -14.175486)
			(stroke
				(width 0.3048)
				(type default)
			)
			(layer "F.SilkS")
		)
		(fp_arc
			(start 1.014984 -14.38529)
			(mid 1.004736 -14.279562)
			(end 0.983488 -14.175486)
			(stroke
				(width 0.3048)
				(type default)
			)
			(layer "F.SilkS")
		)
		(fp_arc
			(start -1.014984 -14.38529)
			(mid -1.025232 -14.279563)
			(end -1.04648 -14.175486)
			(stroke
				(width 0.3048)
				(type default)
			)
			(layer "F.SilkS")
		)
		(fp_arc
			(start -3.044952 -14.38529)
			(mid -3.0552 -14.279562)
			(end -3.076448 -14.175486)
			(stroke
				(width 0.3048)
				(type default)
			)
			(layer "F.SilkS")
		)
		(fp_arc
			(start 7.073392 -14.175486)
			(mid 7.849817 -12.469127)
			(end 6.089904 -13.115036)
			(stroke
				(width 0.3048)
				(type default)
			)
			(layer "F.SilkS")
		)
		(fp_arc
			(start 5.106416 -14.175486)
			(mid 5.085186 -14.279565)
			(end 5.07492 -14.38529)
			(stroke
				(width 0.3048)
				(type default)
			)
			(layer "F.SilkS")
		)
		(fp_arc
			(start 5.043424 -14.175486)
			(mid 5.07492 -14.175973)
			(end 5.106416 -14.175486)
			(stroke
				(width 0.3048)
				(type default)
			)
			(layer "F.SilkS")
		)
		(fp_arc
			(start 3.076448 -14.175486)
			(mid 3.055218 -14.279565)
			(end 3.044952 -14.38529)
			(stroke
				(width 0.3048)
				(type default)
			)
			(layer "F.SilkS")
		)
		(fp_arc
			(start 3.013456 -14.175486)
			(mid 3.044952 -14.175975)
			(end 3.076448 -14.175486)
			(stroke
				(width 0.3048)
				(type default)
			)
			(layer "F.SilkS")
		)
		(fp_arc
			(start 1.04648 -14.175486)
			(mid 1.025251 -14.279565)
			(end 1.014984 -14.38529)
			(stroke
				(width 0.3048)
				(type default)
			)
			(layer "F.SilkS")
		)
		(fp_arc
			(start 0.983488 -14.175486)
			(mid 1.014984 -14.175974)
			(end 1.04648 -14.175486)
			(stroke
				(width 0.3048)
				(type default)
			)
			(layer "F.SilkS")
		)
		(fp_arc
			(start -0.983488 -14.175486)
			(mid -1.004718 -14.279565)
			(end -1.014984 -14.38529)
			(stroke
				(width 0.3048)
				(type default)
			)
			(layer "F.SilkS")
		)
		(fp_arc
			(start -1.04648 -14.175486)
			(mid -1.014984 -14.175973)
			(end -0.983488 -14.175486)
			(stroke
				(width 0.3048)
				(type default)
			)
			(layer "F.SilkS")
		)
		(fp_arc
			(start -3.013456 -14.175486)
			(mid -3.034686 -14.279565)
			(end -3.044952 -14.38529)
			(stroke
				(width 0.3048)
				(type default)
			)
			(layer "F.SilkS")
		)
		(fp_arc
			(start -3.076448 -14.175486)
			(mid -3.044952 -14.175975)
			(end -3.013456 -14.175486)
			(stroke
				(width 0.3048)
				(type default)
			)
			(layer "F.SilkS")
		)
		(fp_arc
			(start -5.043424 -14.175486)
			(mid -5.064689 -14.279688)
			(end -5.07492 -14.385544)
			(stroke
				(width 0.3048)
				(type default)
			)
			(layer "F.SilkS")
		)
		(fp_arc
			(start -5.106416 -14.175486)
			(mid -5.07492 -14.175974)
			(end -5.043424 -14.175486)
			(stroke
				(width 0.3048)
				(type default)
			)
			(layer "F.SilkS")
		)
		(fp_arc
			(start -7.073392 -14.175486)
			(mid -6.240342 -15.435316)
			(end -5.07492 -14.474698)
			(stroke
				(width 0.3048)
				(type default)
			)
			(layer "F.SilkS")
		)
		(fp_arc
			(start 6.1214 -13.414502)
			(mid 6.089904 -13.414013)
			(end 6.058408 -13.414502)
			(stroke
				(width 0.3048)
				(type default)
			)
			(layer "F.SilkS")
		)
		(fp_arc
			(start 6.058408 -13.414502)
			(mid 6.07963 -13.310422)
			(end 6.089904 -13.204698)
			(stroke
				(width 0.3048)
				(type default)
			)
			(layer "F.SilkS")
		)
		(fp_arc
			(start 4.091432 -13.414502)
			(mid 4.059936 -13.414015)
			(end 4.02844 -13.414502)
			(stroke
				(width 0.3048)
				(type default)
			)
			(layer "F.SilkS")
		)
		(fp_arc
			(start 4.02844 -13.414502)
			(mid 4.049664 -13.310422)
			(end 4.059936 -13.204698)
			(stroke
				(width 0.3048)
				(type default)
			)
			(layer "F.SilkS")
		)
		(fp_arc
			(start 2.061464 -13.414502)
			(mid 2.029968 -13.414014)
			(end 1.998472 -13.414502)
			(stroke
				(width 0.3048)
				(type default)
			)
			(layer "F.SilkS")
		)
		(fp_arc
			(start 1.998472 -13.414502)
			(mid 2.019695 -13.310422)
			(end 2.029968 -13.204698)
			(stroke
				(width 0.3048)
				(type default)
			)
			(layer "F.SilkS")
		)
		(fp_arc
			(start 0.031496 -13.414502)
			(mid 0 -13.414013)
			(end -0.031496 -13.414502)
			(stroke
				(width 0.3048)
				(type default)
			)
			(layer "F.SilkS")
		)
		(fp_arc
			(start -0.031496 -13.414502)
			(mid -0.010273 -13.310422)
			(end 0 -13.204698)
			(stroke
				(width 0.3048)
				(type default)
			)
			(layer "F.SilkS")
		)
		(fp_arc
			(start -1.998472 -13.414502)
			(mid -2.029968 -13.414013)
			(end -2.061464 -13.414502)
			(stroke
				(width 0.3048)
				(type default)
			)
			(layer "F.SilkS")
		)
		(fp_arc
			(start -2.061464 -13.414502)
			(mid -2.04024 -13.310422)
			(end -2.029968 -13.204698)
			(stroke
				(width 0.3048)
				(type default)
			)
			(layer "F.SilkS")
		)
		(fp_arc
			(start -4.02844 -13.414502)
			(mid -4.059936 -13.414015)
			(end -4.091432 -13.414502)
			(stroke
				(width 0.3048)
				(type default)
			)
			(layer "F.SilkS")
		)
		(fp_arc
			(start -4.091432 -13.414502)
			(mid -4.070215 -13.310549)
			(end -4.059936 -13.204952)
			(stroke
				(width 0.3048)
				(type default)
			)
			(layer "F.SilkS")
		)
		(fp_arc
			(start -6.058408 -13.414502)
			(mid -6.089904 -13.414014)
			(end -6.1214 -13.414502)
			(stroke
				(width 0.3048)
				(type default)
			)
			(layer "F.SilkS")
		)
		(fp_arc
			(start -6.1214 -13.414502)
			(mid -6.100196 -13.310803)
			(end -6.089904 -13.20546)
			(stroke
				(width 0.3048)
				(type default)
			)
			(layer "F.SilkS")
		)
		(fp_arc
			(start -6.089904 -13.20546)
			(mid -6.079597 -13.3108)
			(end -6.058408 -13.414502)
			(stroke
				(width 0.3048)
				(type default)
			)
			(layer "F.SilkS")
		)
		(fp_arc
			(start -4.059936 -13.204952)
			(mid -4.049666 -13.31055)
			(end -4.02844 -13.414502)
			(stroke
				(width 0.3048)
				(type default)
			)
			(layer "F.SilkS")
		)
		(fp_arc
			(start 6.089904 -13.204698)
			(mid 6.100146 -13.310427)
			(end 6.1214 -13.414502)
			(stroke
				(width 0.3048)
				(type default)
			)
			(layer "F.SilkS")
		)
		(fp_arc
			(start 4.059936 -13.204698)
			(mid 4.070178 -13.310427)
			(end 4.091432 -13.414502)
			(stroke
				(width 0.3048)
				(type default)
			)
			(layer "F.SilkS")
		)
		(fp_arc
			(start 2.029968 -13.204698)
			(mid 2.04021 -13.310427)
			(end 2.061464 -13.414502)
			(stroke
				(width 0.3048)
				(type default)
			)
			(layer "F.SilkS")
		)
		(fp_arc
			(start 0 -13.204698)
			(mid 0.010242 -13.310427)
			(end 0.031496 -13.414502)
			(stroke
				(width 0.3048)
				(type default)
			)
			(layer "F.SilkS")
		)
		(fp_arc
			(start -2.029968 -13.204698)
			(mid -2.019726 -13.310427)
			(end -1.998472 -13.414502)
			(stroke
				(width 0.3048)
				(type default)
			)
			(layer "F.SilkS")
		)
		(fp_arc
			(start -2.029968 -13.11529)
			(mid -3.044698 -12.144026)
			(end -4.059936 -13.114782)
			(stroke
				(width 0.3048)
				(type default)
			)
			(layer "F.SilkS")
		)
		(fp_arc
			(start 6.089904 -13.115036)
			(mid 5.07492 -12.143529)
			(end 4.059936 -13.115036)
			(stroke
				(width 0.3048)
				(type default)
			)
			(layer "F.SilkS")
		)
		(fp_arc
			(start 4.059936 -13.115036)
			(mid 3.044952 -12.144258)
			(end 2.029968 -13.115036)
			(stroke
				(width 0.3048)
				(type default)
			)
			(layer "F.SilkS")
		)
		(fp_arc
			(start 2.029968 -13.115036)
			(mid 1.014984 -12.144258)
			(end 0 -13.115036)
			(stroke
				(width 0.3048)
				(type default)
			)
			(layer "F.SilkS")
		)
		(fp_arc
			(start 0 -13.115036)
			(mid -1.015111 -12.144258)
			(end -2.029968 -13.11529)
			(stroke
				(width 0.3048)
				(type default)
			)
			(layer "F.SilkS")
		)
		(fp_arc
			(start -4.059936 -13.114782)
			(mid -5.074793 -12.143761)
			(end -6.089904 -13.114528)
			(stroke
				(width 0.3048)
				(type default)
			)
			(layer "F.SilkS")
		)
		(fp_arc
			(start -6.089904 -13.114528)
			(mid -7.850005 -12.469299)
			(end -7.073392 -14.175486)
			(stroke
				(width 0.3048)
				(type default)
			)
			(layer "F.SilkS")
		)
		(fp_arc
			(start 7.999984 -12.159996)
			(mid 8.353643 -12.013515)
			(end 8.50011 -11.65987)
			(stroke
				(width 0.1524)
				(type default)
			)
			(layer "F.SilkS")
		)
		(fp_arc
			(start -8.50011 -11.65987)
			(mid -8.353608 -12.013471)
			(end -7.999984 -12.159996)
			(stroke
				(width 0.1524)
				(type default)
			)
			(layer "F.SilkS")
		)
		(fp_poly
			(pts
				(xy -9.0043 -8.89) (xy -8.255 -8.89) (xy -8.255 -1.905) (xy -9.5504 -1.905) (xy -9.5504 1.905) (xy -8.4963 1.905)
				(xy -8.4963 9.652) (xy 8.4963 9.652) (xy 8.4963 1.905) (xy 9.5504 1.905) (xy 9.5504 -1.905) (xy 8.255 -1.905)
				(xy 8.255 -8.89) (xy 9.0043 -8.89) (xy 9.0043 -11.9634) (xy 8.4963 -11.9634) (xy 8.4963 -14.6558)
				(xy -8.4963 -14.6558) (xy -8.4963 -11.9634) (xy -9.0043 -11.9634)
			)
			(stroke
				(width 0)
				(type default)
			)
			(fill no)
			(layer "F.CrtYd")
		)
		(fp_poly
			(pts
				(xy -9.0043 10.16) (xy -9.0043 2.7051) (xy -10.5029 2.7051) (xy -10.5029 -2.7051) (xy -8.763 -2.7051)
				(xy -8.763 -8.382) (xy -9.5123 -8.382) (xy -9.5123 -12.4714) (xy -9.0043 -12.4714) (xy -9.0043 -15.5956)
				(xy 9.0043 -15.5956) (xy 9.0043 -12.4714) (xy 9.5123 -12.4714) (xy 9.5123 -8.382) (xy 8.763 -8.382)
				(xy 8.763 -7.0358) (xy 8.255 -7.0358) (xy 8.255 -8.89) (xy 9.0043 -8.89) (xy 9.0043 -11.9634) (xy 8.4963 -11.9634)
				(xy 8.4963 -14.6558) (xy -8.4963 -14.6558) (xy -8.4963 -11.9634) (xy -9.0043 -11.9634) (xy -9.0043 -8.89)
				(xy -8.255 -8.89) (xy -8.255 -1.905) (xy -9.5504 -1.905) (xy -9.5504 1.905) (xy -8.4963 1.905) (xy -8.4963 9.652)
				(xy 8.4963 9.652) (xy 8.4963 1.905) (xy 9.5504 1.905) (xy 9.5504 -1.905) (xy 8.255 -1.905) (xy 8.255 -7.0231)
				(xy 8.763 -7.0231) (xy 8.763 -2.7051) (xy 10.5029 -2.7051) (xy 10.5029 2.7051) (xy 9.0043 2.7051)
				(xy 9.0043 10.16)
			)
			(stroke
				(width 0)
				(type default)
			)
			(fill no)
			(layer "F.CrtYd")
		)
		(fp_poly
			(pts
				(xy -9.0043 10.16) (xy -9.0043 2.7051) (xy -10.5029 2.7051) (xy -10.5029 -2.7051) (xy -8.763 -2.7051)
				(xy -8.763 -8.382) (xy -9.5123 -8.382) (xy -9.5123 -12.4714) (xy -9.0043 -12.4714) (xy -9.0043 -15.5956)
				(xy 9.0043 -15.5956) (xy 9.0043 -12.4714) (xy 9.5123 -12.4714) (xy 9.5123 -8.382) (xy 8.763 -8.382)
				(xy 8.763 -2.7051) (xy 10.5029 -2.7051) (xy 10.5029 2.7051) (xy 9.0043 2.7051) (xy 9.0043 10.16)
			)
			(stroke
				(width 0)
				(type default)
			)
			(fill no)
			(layer "F.Fab")
		)
		(fp_text user "Slit"
			(at -2.286 -7.4295 90)
			(unlocked yes)
			(layer "F.SilkS")
			(effects
				(font
					(size 1.27 1.016)
					(thickness 0.1524)
				)
				(justify left)
			)
		)
		(pad "1" thru_hole rect
			(at 9.299956 0 90)
			(size 1.4986 4.3942)
			(drill oval 0.508 1.8034
				(offset -0.0508 0)
			)
			(layers "*.Cu" "*.Mask")
			(remove_unused_layers no)
			(net "GND")
			(clearance 0.0127)
			(thermal_gap 0.0127)
			(padstack
				(mode front_inner_back)
				(layer "Inner"
					(shape oval)
					(size 1.2192 2.5146)
					(clearance 0.1524)
				)
				(layer "B.Cu"
					(shape oval)
					(size 1.2192 2.5146)
					(clearance 0.1524)
				)
			)
		)
		(pad "2" thru_hole rect
			(at -9.299956 0 90)
			(size 1.4986 4.3942)
			(drill oval 0.508 1.8034
				(offset 0.0508 0)
			)
			(layers "*.Cu" "*.Mask")
			(remove_unused_layers no)
			(net "GND")
			(clearance 0.0127)
			(thermal_gap 0.0127)
			(padstack
				(mode front_inner_back)
				(layer "Inner"
					(shape oval)
					(size 1.2192 2.5146)
					(clearance 0.1524)
				)
				(layer "B.Cu"
					(shape oval)
					(size 1.2192 2.5146)
					(clearance 0.1524)
				)
			)
		)
		(pad "L1" thru_hole circle
			(at 7.104888 -13.159994 90)
			(size 1.3208 1.3208)
			(drill 0.9144)
			(layers "*.Cu" "*.Mask")
			(remove_unused_layers no)
			(net "LED_LAN_2_R_N")
			(clearance 0.1524)
			(thermal_gap 0.1524)
		)
		(pad "L2" thru_hole circle
			(at 6.089904 -14.429994 90)
			(size 1.3208 1.3208)
			(drill 0.9144)
			(layers "*.Cu" "*.Mask")
			(remove_unused_layers no)
			(net "LED_LAN_0_R_N")
			(clearance 0.1524)
			(thermal_gap 0.1524)
		)
		(pad "L3" thru_hole circle
			(at -6.089904 -14.429994 90)
			(size 1.3208 1.3208)
			(drill 0.9144)
			(layers "*.Cu" "*.Mask")
			(remove_unused_layers no)
			(net "LED_LAN_1_R_N")
			(clearance 0.1524)
			(thermal_gap 0.1524)
		)
		(pad "L4" thru_hole circle
			(at -7.104888 -13.159994 90)
			(size 1.3208 1.3208)
			(drill 0.9144)
			(layers "*.Cu" "*.Mask")
			(remove_unused_layers no)
			(net "NIC_LED_ACT_ANODE_R")
			(clearance 0.1524)
			(thermal_gap 0.1524)
		)
		(pad "R1" thru_hole circle
			(at 5.07492 -13.159994 90)
			(size 1.3208 1.3208)
			(drill 0.9144)
			(layers "*.Cu" "*.Mask")
			(remove_unused_layers no)
			(net "GND_LAN_TRCT1234_C")
			(clearance 0.1524)
			(thermal_gap 0.1524)
		)
		(pad "R2" thru_hole circle
			(at 4.059936 -14.429994 90)
			(size 1.3208 1.3208)
			(drill 0.9144)
			(layers "*.Cu" "*.Mask")
			(remove_unused_layers no)
			(net "NIC_MDI_SPRV_RJ45_0_R_DP")
			(clearance 0.1524)
			(thermal_gap 0.1524)
		)
		(pad "R3" thru_hole circle
			(at 3.044952 -13.159994 90)
			(size 1.3208 1.3208)
			(drill 0.9144)
			(layers "*.Cu" "*.Mask")
			(remove_unused_layers no)
			(net "NIC_MDI_SPRV_RJ45_0_R_DN")
			(clearance 0.1524)
			(thermal_gap 0.1524)
		)
		(pad "R4" thru_hole circle
			(at 2.029968 -14.429994 90)
			(size 1.3208 1.3208)
			(drill 0.9144)
			(layers "*.Cu" "*.Mask")
			(remove_unused_layers no)
			(net "NIC_MDI_SPRV_RJ45_1_R_DP")
			(clearance 0.1524)
			(thermal_gap 0.1524)
		)
		(pad "R5" thru_hole circle
			(at 1.014984 -13.159994 90)
			(size 1.3208 1.3208)
			(drill 0.9144)
			(layers "*.Cu" "*.Mask")
			(remove_unused_layers no)
			(net "NIC_MDI_SPRV_RJ45_1_R_DN")
			(clearance 0.1524)
			(thermal_gap 0.1524)
		)
		(pad "R6" thru_hole circle
			(at 0 -14.429994 90)
			(size 1.3208 1.3208)
			(drill 0.9144)
			(layers "*.Cu" "*.Mask")
			(remove_unused_layers no)
			(net "GND")
			(clearance 0.1524)
			(thermal_gap 0.1524)
		)
		(pad "R7" thru_hole circle
			(at -1.014984 -13.159994 90)
			(size 1.3208 1.3208)
			(drill 0.9144)
			(layers "*.Cu" "*.Mask")
			(remove_unused_layers no)
			(net "NIC_MDI_SPRV_RJ45_2_R_DP")
			(clearance 0.1524)
			(thermal_gap 0.1524)
		)
		(pad "R8" thru_hole circle
			(at -2.029968 -14.429994 90)
			(size 1.3208 1.3208)
			(drill 0.9144)
			(layers "*.Cu" "*.Mask")
			(remove_unused_layers no)
			(net "NIC_MDI_SPRV_RJ45_2_R_DN")
			(clearance 0.1524)
			(thermal_gap 0.1524)
		)
		(pad "R9" thru_hole circle
			(at -3.044952 -13.159994 90)
			(size 1.3208 1.3208)
			(drill 0.9144)
			(layers "*.Cu" "*.Mask")
			(remove_unused_layers no)
			(net "NIC_MDI_SPRV_RJ45_3_R_DP")
			(clearance 0.1524)
			(thermal_gap 0.1524)
		)
		(pad "R10" thru_hole circle
			(at -4.059936 -14.429994 90)
			(size 1.3208 1.3208)
			(drill 0.9144)
			(layers "*.Cu" "*.Mask")
			(remove_unused_layers no)
			(net "NIC_MDI_SPRV_RJ45_3_R_DN")
			(clearance 0.1524)
			(thermal_gap 0.1524)
		)
		(pad "R11" thru_hole circle
			(at -5.07492 -13.159994 90)
			(size 1.3208 1.3208)
			(drill 0.9144)
			(layers "*.Cu" "*.Mask")
			(remove_unused_layers no)
			(net "GND_LAN_TRCT1234_C")
			(clearance 0.1524)
			(thermal_gap 0.1524)
		)
	)
	(footprint ""
		(layer "F.Cu")
		(at 474.472 -147.5105 180)
		(property "Reference" "R1L16"
			(at 0 0 180)
			(layer "F.SilkS")
			(hide yes)
			(effects
				(font
					(size 1.27 1.27)
				)
			)
		)
		(property "Value" ""
			(at 0 0 180)
			(layer "F.Fab")
			(effects
				(font
					(size 1.27 1.27)
				)
			)
		)
		(duplicate_pad_numbers_are_jumpers no)
		(fp_poly
			(pts
				(xy -0.2794 -0.1016) (xy 0.2794 -0.1016) (xy 0.2794 0.9906) (xy -0.2794 0.9906)
			)
			(stroke
				(width 0)
				(type default)
			)
			(fill no)
			(layer "F.CrtYd")
		)
		(fp_line
			(start 0.2794 0.9906)
			(end 0.2794 -0.1016)
			(stroke
				(width 0.1)
				(type default)
			)
			(layer "F.Fab")
		)
		(fp_line
			(start 0.2794 -0.1016)
			(end -0.2794 -0.1016)
			(stroke
				(width 0.1)
				(type default)
			)
			(layer "F.Fab")
		)
		(fp_line
			(start -0.2794 0.9906)
			(end 0.2794 0.9906)
			(stroke
				(width 0.1)
				(type default)
			)
			(layer "F.Fab")
		)
		(fp_line
			(start -0.2794 -0.1016)
			(end -0.2794 0.9906)
			(stroke
				(width 0.1)
				(type default)
			)
			(layer "F.Fab")
		)
		(pad "1" smd rect
			(at 0 0 180)
			(size 0.508 0.508)
			(layers "F.Cu" "F.Mask" "F.Paste")
			(net "PWRGD_P3V3_R1")
		)
		(pad "2" smd rect
			(at 0 0.889 180)
			(size 0.508 0.508)
			(layers "F.Cu" "F.Mask" "F.Paste")
			(net "PWRGD_P3V3")
		)
		(zone
			(layer "F.Cu")
			(hatch none 0.5)
			(connect_pads
				(clearance 0)
			)
			(min_thickness 0.25)
			(keepout
				(tracks not_allowed)
				(vias allowed)
				(pads allowed)
				(copperpour not_allowed)
				(footprints allowed)
			)
			(placement
				(enabled no)
				(sheetname "")
			)
			(fill
				(thermal_gap 0.5)
				(thermal_bridge_width 0.5)
				(island_removal_mode 0)
			)
			(polygon
				(pts
					(xy 474.726 -148.1455) (xy 474.218 -148.1455) (xy 474.218 -147.7645) (xy 474.726 -147.7645)
				)
			)
		)
		(zone
			(layer "F.Cu")
			(hatch none 0.5)
			(connect_pads
				(clearance 0)
			)
			(min_thickness 0.25)
			(keepout
				(tracks allowed)
				(vias not_allowed)
				(pads allowed)
				(copperpour not_allowed)
				(footprints allowed)
			)
			(placement
				(enabled no)
				(sheetname "")
			)
			(fill
				(thermal_gap 0.5)
				(thermal_bridge_width 0.5)
				(island_removal_mode 0)
			)
			(polygon
				(pts
					(xy 474.726 -147.7645) (xy 474.218 -147.7645) (xy 474.218 -148.1455) (xy 474.726 -148.1455)
				)
			)
		)
	)
	(footprint ""
		(layer "F.Cu")
		(at 107.8611 -12.954 90)
		(property "Reference" "C3G1"
			(at 1.848866 0.752348 90)
			(unlocked yes)
			(layer "F.SilkS")
			(effects
				(font
					(size 1.27 0.9652)
					(thickness 0.1524)
				)
			)
		)
		(property "Value" ""
			(at 0 0 90)
			(layer "F.Fab")
			(effects
				(font
					(size 1.27 1.27)
				)
			)
		)
		(duplicate_pad_numbers_are_jumpers no)
		(fp_rect
			(start -0.500126 1.598422)
			(end 0.500126 -0.201422)
			(stroke
				(width 0)
				(type default)
			)
			(fill no)
			(layer "F.CrtYd")
		)
		(fp_line
			(start 0.500126 -0.201422)
			(end 0.500126 1.598422)
			(stroke
				(width 0.1)
				(type default)
			)
			(layer "F.Fab")
		)
		(fp_line
			(start -0.500126 -0.201422)
			(end 0.500126 -0.201422)
			(stroke
				(width 0.1)
				(type default)
			)
			(layer "F.Fab")
		)
		(fp_line
			(start 0.500126 1.598422)
			(end -0.500126 1.598422)
			(stroke
				(width 0.1)
				(type default)
			)
			(layer "F.Fab")
		)
		(fp_line
			(start -0.500126 1.598422)
			(end -0.500126 -0.201422)
			(stroke
				(width 0.1)
				(type default)
			)
			(layer "F.Fab")
		)
		(pad "1" smd rect
			(at 0 0)
			(size 0.889 0.9906)
			(layers "F.Cu" "F.Mask" "F.Paste")
			(net "PVDDQ_GHJ")
		)
		(pad "2" smd rect
			(at 0 1.397)
			(size 0.889 0.9906)
			(layers "F.Cu" "F.Mask" "F.Paste")
			(net "GND")
		)
		(zone
			(layer "F.Cu")
			(hatch none 0.5)
			(connect_pads
				(clearance 0)
			)
			(min_thickness 0.25)
			(keepout
				(tracks allowed)
				(vias not_allowed)
				(pads allowed)
				(copperpour not_allowed)
				(footprints allowed)
			)
			(placement
				(enabled no)
				(sheetname "")
			)
			(fill
				(thermal_gap 0.5)
				(thermal_bridge_width 0.5)
				(island_removal_mode 0)
			)
			(polygon
				(pts
					(xy 108.8136 -12.4587) (xy 108.8136 -13.4493) (xy 108.3056 -13.4493) (xy 108.3056 -12.4587)
				)
			)
		)
		(zone
			(layer "F.Cu")
			(hatch none 0.5)
			(connect_pads
				(clearance 0)
			)
			(min_thickness 0.25)
			(keepout
				(tracks not_allowed)
				(vias allowed)
				(pads allowed)
				(copperpour not_allowed)
				(footprints allowed)
			)
			(placement
				(enabled no)
				(sheetname "")
			)
			(fill
				(thermal_gap 0.5)
				(thermal_bridge_width 0.5)
				(island_removal_mode 0)
			)
			(polygon
				(pts
					(xy 108.8136 -12.4587) (xy 108.8136 -13.4493) (xy 108.3056 -13.4493) (xy 108.3056 -12.4587)
				)
			)
		)
	)
	(footprint ""
		(layer "F.Cu")
		(at 24.007826 -87.841582 180)
		(property "Reference" "RF8"
			(at -0.8382 -0.67818 180)
			(unlocked yes)
			(layer "F.SilkS")
			(effects
				(font
					(size 0.4064 0.254)
					(thickness 0.1524)
				)
				(justify left)
			)
		)
		(property "Value" ""
			(at 0 0 180)
			(layer "F.Fab")
			(effects
				(font
					(size 1.27 1.27)
				)
			)
		)
		(duplicate_pad_numbers_are_jumpers no)
		(fp_poly
			(pts
				(xy -0.2794 -0.1016) (xy 0.2794 -0.1016) (xy 0.2794 0.9906) (xy -0.2794 0.9906)
			)
			(stroke
				(width 0)
				(type default)
			)
			(fill no)
			(layer "F.CrtYd")
		)
		(fp_line
			(start 0.2794 0.9906)
			(end 0.2794 -0.1016)
			(stroke
				(width 0.1)
				(type default)
			)
			(layer "F.Fab")
		)
		(fp_line
			(start 0.2794 -0.1016)
			(end -0.2794 -0.1016)
			(stroke
				(width 0.1)
				(type default)
			)
			(layer "F.Fab")
		)
		(fp_line
			(start -0.2794 0.9906)
			(end 0.2794 0.9906)
			(stroke
				(width 0.1)
				(type default)
			)
			(layer "F.Fab")
		)
		(fp_line
			(start -0.2794 -0.1016)
			(end -0.2794 0.9906)
			(stroke
				(width 0.1)
				(type default)
			)
			(layer "F.Fab")
		)
		(pad "1" smd rect
			(at 0 0 180)
			(size 0.508 0.508)
			(layers "F.Cu" "F.Mask" "F.Paste")
			(net "VR_PVCCIN_CPU1_AIREF2")
		)
		(pad "2" smd rect
			(at 0 0.889 180)
			(size 0.508 0.508)
			(layers "F.Cu" "F.Mask" "F.Paste")
			(net "ISENSE_PVCCIN_CPU1_PH2_IMON")
		)
		(zone
			(layer "F.Cu")
			(hatch none 0.5)
			(connect_pads
				(clearance 0)
			)
			(min_thickness 0.25)
			(keepout
				(tracks not_allowed)
				(vias allowed)
				(pads allowed)
				(copperpour not_allowed)
				(footprints allowed)
			)
			(placement
				(enabled no)
				(sheetname "")
			)
			(fill
				(thermal_gap 0.5)
				(thermal_bridge_width 0.5)
				(island_removal_mode 0)
			)
			(polygon
				(pts
					(xy 24.261826 -88.476582) (xy 23.753826 -88.476582) (xy 23.753826 -88.095582) (xy 24.261826 -88.095582)
				)
			)
		)
		(zone
			(layer "F.Cu")
			(hatch none 0.5)
			(connect_pads
				(clearance 0)
			)
			(min_thickness 0.25)
			(keepout
				(tracks allowed)
				(vias not_allowed)
				(pads allowed)
				(copperpour not_allowed)
				(footprints allowed)
			)
			(placement
				(enabled no)
				(sheetname "")
			)
			(fill
				(thermal_gap 0.5)
				(thermal_bridge_width 0.5)
				(island_removal_mode 0)
			)
			(polygon
				(pts
					(xy 24.261826 -88.095582) (xy 23.753826 -88.095582) (xy 23.753826 -88.476582) (xy 24.261826 -88.476582)
				)
			)
		)
	)
	(footprint ""
		(layer "F.Cu")
		(at 259.3848 -139.954 90)
		(property "Reference" "C5A20"
			(at 0 0 90)
			(layer "F.SilkS")
			(hide yes)
			(effects
				(font
					(size 1.27 1.27)
				)
			)
		)
		(property "Value" ""
			(at 0 0 90)
			(layer "F.Fab")
			(effects
				(font
					(size 1.27 1.27)
				)
			)
		)
		(duplicate_pad_numbers_are_jumpers no)
		(fp_rect
			(start -0.7239 -0.2159)
			(end 0.7239 1.9939)
			(stroke
				(width 0)
				(type default)
			)
			(fill no)
			(layer "F.CrtYd")
		)
		(fp_line
			(start 0.7239 -0.2159)
			(end -0.7239 -0.2159)
			(stroke
				(width 0.1)
				(type default)
			)
			(layer "F.Fab")
		)
		(fp_line
			(start -0.7239 -0.2159)
			(end -0.7239 1.9939)
			(stroke
				(width 0.1)
				(type default)
			)
			(layer "F.Fab")
		)
		(fp_line
			(start 0.7239 1.9939)
			(end 0.7239 -0.2159)
			(stroke
				(width 0.1)
				(type default)
			)
			(layer "F.Fab")
		)
		(fp_line
			(start -0.7239 1.9939)
			(end 0.7239 1.9939)
			(stroke
				(width 0.1)
				(type default)
			)
			(layer "F.Fab")
		)
		(pad "1" smd rect
			(at 0 0 90)
			(size 1.27 1.016)
			(layers "F.Cu" "F.Mask" "F.Paste")
			(net "PVDDQ_DEF")
		)
		(pad "2" smd rect
			(at 0 1.778 90)
			(size 1.27 1.016)
			(layers "F.Cu" "F.Mask" "F.Paste")
			(net "GND")
		)
		(zone
			(layer "F.Cu")
			(hatch none 0.5)
			(connect_pads
				(clearance 0)
			)
			(min_thickness 0.25)
			(keepout
				(tracks not_allowed)
				(vias allowed)
				(pads allowed)
				(copperpour not_allowed)
				(footprints allowed)
			)
			(placement
				(enabled no)
				(sheetname "")
			)
			(fill
				(thermal_gap 0.5)
				(thermal_bridge_width 0.5)
				(island_removal_mode 0)
			)
			(polygon
				(pts
					(xy 259.8928 -139.319) (xy 260.6548 -139.319) (xy 260.6548 -140.589) (xy 259.8928 -140.589)
				)
			)
		)
	)
	(footprint ""
		(layer "F.Cu")
		(at 198.925434 -73.295764 90)
		(property "Reference" "EU4D3"
			(at 3.334766 -1.669034 0)
			(unlocked yes)
			(layer "F.SilkS")
			(effects
				(font
					(size 0.7874 0.5842)
					(thickness 0.1524)
				)
			)
		)
		(property "Value" ""
			(at 0 0 90)
			(layer "F.Fab")
			(effects
				(font
					(size 1.27 1.27)
				)
			)
		)
		(duplicate_pad_numbers_are_jumpers no)
		(fp_line
			(start 2.9718 -3.5052)
			(end 2.9718 3.429)
			(stroke
				(width 0.1524)
				(type default)
			)
			(layer "F.SilkS")
		)
		(fp_line
			(start -3.0099 -3.5052)
			(end 2.9718 -3.5052)
			(stroke
				(width 0.1524)
				(type default)
			)
			(layer "F.SilkS")
		)
		(fp_line
			(start 2.9718 3.429)
			(end -3.0099 3.429)
			(stroke
				(width 0.1524)
				(type default)
			)
			(layer "F.SilkS")
		)
		(fp_line
			(start -3.0099 3.429)
			(end -3.0099 -3.5052)
			(stroke
				(width 0.1524)
				(type default)
			)
			(layer "F.SilkS")
		)
		(fp_circle
			(center -3.057398 -2.678684)
			(end -3.057398 -2.551684)
			(stroke
				(width 0.254)
				(type default)
			)
			(fill no)
			(layer "F.SilkS")
		)
		(fp_poly
			(pts
				(xy -2.9972 -3.4925) (xy -2.9972 -2.6924) (xy -2.1971 -3.4925)
			)
			(stroke
				(width 0)
				(type default)
			)
			(fill yes)
			(layer "F.SilkS")
		)
		(fp_poly
			(pts
				(xy -2.549906 -3.050032) (xy -2.549906 3.050032) (xy 2.549906 3.050032) (xy 2.549906 -3.050032)
			)
			(stroke
				(width 0)
				(type default)
			)
			(fill no)
			(layer "F.CrtYd")
		)
		(fp_line
			(start 2.549906 -3.050032)
			(end 2.549906 3.050032)
			(stroke
				(width 0.1)
				(type default)
			)
			(layer "F.Fab")
		)
		(fp_line
			(start -2.549906 -3.050032)
			(end 2.549906 -3.050032)
			(stroke
				(width 0.1)
				(type default)
			)
			(layer "F.Fab")
		)
		(fp_line
			(start 2.549906 3.050032)
			(end -2.549906 3.050032)
			(stroke
				(width 0.1)
				(type default)
			)
			(layer "F.Fab")
		)
		(fp_line
			(start -2.549906 3.050032)
			(end -2.549906 -3.050032)
			(stroke
				(width 0.1)
				(type default)
			)
			(layer "F.Fab")
		)
		(fp_circle
			(center -3.057398 -2.678684)
			(end -3.057398 -2.551684)
			(stroke
				(width 0.254)
				(type default)
			)
			(fill no)
			(layer "F.Fab")
		)
		(pad "1" smd rect
			(at -2.39522 -2.279904 90)
			(size 0.7112 0.254)
			(layers "F.Cu" "F.Mask" "F.Paste")
			(net "PVCCIN_CPU0")
		)
		(pad "2" smd rect
			(at -2.39522 -1.83007 90)
			(size 0.7112 0.254)
			(layers "F.Cu" "F.Mask" "F.Paste")
			(net "GND")
		)
		(pad "3" smd rect
			(at -2.39522 -1.379982 90)
			(size 0.7112 0.254)
			(layers "F.Cu" "F.Mask" "F.Paste")
			(net "VR_PVCCIN_CPU0_PH3_VCIN")
		)
		(pad "4" smd rect
			(at -2.39522 -0.929894 90)
			(size 0.7112 0.254)
			(layers "F.Cu" "F.Mask" "F.Paste")
			(net "P5V_STBY")
		)
		(pad "5" smd rect
			(at -2.39522 -0.48006 90)
			(size 0.7112 0.254)
			(layers "F.Cu" "F.Mask" "F.Paste")
			(net "GND")
		)
		(pad "6" smd rect
			(at -2.39522 -0.029972 90)
			(size 0.7112 0.254)
			(layers "F.Cu" "F.Mask" "F.Paste")
			(net "TP_PVCCIN_CPU0_PH3_GL_0")
		)
		(pad "7" smd custom
			(at 0.016764 1.145032 90)
			(size 0.53975 0.53975)
			(layers "F.Cu" "F.Mask" "F.Paste")
			(net "GND")
			(options
				(clearance outline)
				(anchor circle)
			)
			(primitives
				(gr_poly
					(pts
						(xy -2.7051 1.0795) (xy -2.7051 -0.3683) (xy -0.9271 -0.3683) (xy -0.9271 -1.0795) (xy 2.7051 -1.0795)
						(xy 2.7051 1.0795)
					)
					(width 0)
					(fill yes)
				)
			)
		)
		(pad "10" smd rect
			(at -0.008382 2.874772 90)
			(size 4.3434 0.6096)
			(layers "F.Cu" "F.Mask" "F.Paste")
			(net "VR_PVCCIN_CPU0_PHASE3")
		)
		(pad "25" smd rect
			(at 1.548384 -1.283208 90)
			(size 2.3368 2.0066)
			(layers "F.Cu" "F.Mask" "F.Paste")
			(net "VR_FET_SW_P12V_STBY_PVCCIN_CPU0")
		)
		(pad "30" smd rect
			(at 2.050034 -2.895092 90)
			(size 0.254 0.7112)
			(layers "F.Cu" "F.Mask" "F.Paste")
			(net "VR_FET_SW_P12V_STBY_PVCCIN_CPU0")
		)
		(pad "31" smd rect
			(at 1.599946 -2.895092 90)
			(size 0.254 0.7112)
			(layers "F.Cu" "F.Mask" "F.Paste")
			(net "Net_363")
		)
		(pad "32" smd rect
			(at 1.150112 -2.895092 90)
			(size 0.254 0.7112)
			(layers "F.Cu" "F.Mask" "F.Paste")
			(net "VR_PVCCIN_CPU0_PH3_PHASE")
		)
		(pad "33" smd rect
			(at 0.700024 -2.895092 90)
			(size 0.254 0.7112)
			(layers "F.Cu" "F.Mask" "F.Paste")
			(net "VR_PVCCIN_CPU0_PH3_BOOT_R")
		)
		(pad "34" smd rect
			(at 0.249936 -2.895092 90)
			(size 0.254 0.7112)
			(layers "F.Cu" "F.Mask" "F.Paste")
			(net "VR_PVCCIN_CPU0_PWM3")
		)
		(pad "35" smd rect
			(at -0.199898 -2.895092 90)
			(size 0.254 0.7112)
			(layers "F.Cu" "F.Mask" "F.Paste")
			(net "P5V_STBY")
		)
		(pad "36" smd rect
			(at -0.649986 -2.895092 90)
			(size 0.254 0.7112)
			(layers "F.Cu" "F.Mask" "F.Paste")
			(net "A_TSENSE_PVCCIN_CPU0")
		)
		(pad "37" smd rect
			(at -1.100074 -2.895092 90)
			(size 0.254 0.7112)
			(layers "F.Cu" "F.Mask" "F.Paste")
			(net "VR_PVCCIN_CPU0_PH3_OCSET")
		)
		(pad "38" smd rect
			(at -1.549908 -2.895092 90)
			(size 0.254 0.7112)
			(layers "F.Cu" "F.Mask" "F.Paste")
			(net "ISENSE_PVCCIN_CPU0_PH3_IMON")
		)
		(pad "39" smd rect
			(at -1.999996 -2.895092 90)
			(size 0.254 0.7112)
			(layers "F.Cu" "F.Mask" "F.Paste")
			(net "VR_PVCCIN_CPU0_AIREF3")
		)
		(pad "40" smd rect
			(at -0.871728 -1.283208 90)
			(size 1.8034 2.0066)
			(layers "F.Cu" "F.Mask" "F.Paste")
			(net "GND")
		)
		(pad "41" smd rect
			(at -1.533906 0.247904 90)
			(size 0.508 0.3556)
			(layers "F.Cu" "F.Mask" "F.Paste")
			(net "TP_PVCCIN_CPU0_PH3_GL_1")
		)
	)
	(footprint ""
		(layer "F.Cu")
		(at 440.550046 -57.596024 90)
		(property "Reference" "J8E4"
			(at 1.795272 -4.825746 90)
			(unlocked yes)
			(layer "F.SilkS")
			(effects
				(font
					(size 0.7874 0.5842)
					(thickness 0.1524)
				)
			)
		)
		(property "Value" ""
			(at 0 0 90)
			(layer "F.Fab")
			(effects
				(font
					(size 1.27 1.27)
				)
			)
		)
		(duplicate_pad_numbers_are_jumpers no)
		(fp_line
			(start 5.678424 -3.374898)
			(end 5.678424 -0.5842)
			(stroke
				(width 0.1524)
				(type default)
			)
			(layer "F.SilkS")
		)
		(fp_line
			(start 3.168396 -3.374898)
			(end 5.678424 -3.374898)
			(stroke
				(width 0.1524)
				(type default)
			)
			(layer "F.SilkS")
		)
		(fp_line
			(start -1.271778 -3.374898)
			(end 1.237996 -3.374898)
			(stroke
				(width 0.1524)
				(type default)
			)
			(layer "F.SilkS")
		)
		(fp_line
			(start -1.271778 -0.5842)
			(end -1.271778 -3.374898)
			(stroke
				(width 0.1524)
				(type default)
			)
			(layer "F.SilkS")
		)
		(fp_line
			(start -1.271778 25.384252)
			(end -1.271778 28.17495)
			(stroke
				(width 0.1524)
				(type default)
			)
			(layer "F.SilkS")
		)
		(fp_line
			(start 5.678424 28.17495)
			(end 5.678424 25.384252)
			(stroke
				(width 0.1524)
				(type default)
			)
			(layer "F.SilkS")
		)
		(fp_line
			(start 3.168396 28.17495)
			(end 5.678424 28.17495)
			(stroke
				(width 0.1524)
				(type default)
			)
			(layer "F.SilkS")
		)
		(fp_line
			(start -1.271778 28.17495)
			(end 1.237996 28.17495)
			(stroke
				(width 0.1524)
				(type default)
			)
			(layer "F.SilkS")
		)
		(fp_poly
			(pts
				(xy -2.986024 -0.4953) (xy -2.986024 0.5207) (xy -1.716024 0.0127)
			)
			(stroke
				(width 0)
				(type default)
			)
			(fill yes)
			(layer "F.SilkS")
		)
		(fp_poly
			(pts
				(xy -1.271778 -3.374898) (xy -1.271778 28.17495) (xy 5.678424 28.17495) (xy 5.678424 -3.374898)
			)
			(stroke
				(width 0)
				(type default)
			)
			(fill no)
			(layer "F.CrtYd")
		)
		(fp_line
			(start 5.678424 -3.374898)
			(end 5.678424 28.17495)
			(stroke
				(width 0.1)
				(type default)
			)
			(layer "F.Fab")
		)
		(fp_line
			(start -1.271778 -3.374898)
			(end 5.678424 -3.374898)
			(stroke
				(width 0.1)
				(type default)
			)
			(layer "F.Fab")
		)
		(fp_line
			(start 5.678424 28.17495)
			(end -1.271778 28.17495)
			(stroke
				(width 0.1)
				(type default)
			)
			(layer "F.Fab")
		)
		(fp_line
			(start -1.271778 28.17495)
			(end -1.271778 -3.374898)
			(stroke
				(width 0.1)
				(type default)
			)
			(layer "F.Fab")
		)
		(fp_poly
			(pts
				(xy -2.986024 -0.4953) (xy -2.986024 0.5207) (xy -1.716024 0.0127)
			)
			(stroke
				(width 0)
				(type default)
			)
			(fill yes)
			(layer "F.Fab")
		)
		(fp_text user "33"
			(at 6.764782 -1.348994 0)
			(unlocked yes)
			(layer "F.SilkS")
			(effects
				(font
					(size 0.7874 0.5842)
					(thickness 0.1524)
				)
				(justify left)
			)
		)
		(fp_text user "32"
			(at -2.003298 24.851106 0)
			(unlocked yes)
			(layer "F.SilkS")
			(effects
				(font
					(size 0.7874 0.5842)
					(thickness 0.1524)
				)
				(justify left)
			)
		)
		(fp_text user "64"
			(at 6.415786 25.105106 0)
			(unlocked yes)
			(layer "F.SilkS")
			(effects
				(font
					(size 0.7874 0.5842)
					(thickness 0.1524)
				)
				(justify left)
			)
		)
		(fp_text user "33"
			(at 6.76529 -1.350264 0)
			(unlocked yes)
			(layer "F.Fab")
			(effects
				(font
					(size 0.7874 0.5842)
					(thickness 0.1524)
				)
				(justify left)
			)
		)
		(fp_text user "32"
			(at -2.00279 24.847296 0)
			(unlocked yes)
			(layer "F.Fab")
			(effects
				(font
					(size 0.7874 0.5842)
					(thickness 0.1524)
				)
				(justify left)
			)
		)
		(fp_text user "64"
			(at 6.41604 25.103836 0)
			(unlocked yes)
			(layer "F.Fab")
			(effects
				(font
					(size 0.7874 0.5842)
					(thickness 0.1524)
				)
				(justify left)
			)
		)
		(pad "" np_thru_hole circle
			(at 2.203196 -2.500122 90)
			(size 0.254 0.254)
			(drill 1.1938)
			(layers "*.Cu" "*.Mask")
			(clearance 0.7874)
			(thermal_gap 0.7874)
		)
		(pad "" np_thru_hole circle
			(at 2.203196 27.29992 90)
			(size 0.254 0.254)
			(drill 0.8128)
			(layers "*.Cu" "*.Mask")
			(clearance 0.5969)
			(thermal_gap 0.5969)
		)
		(pad "1" smd rect
			(at 0 0 90)
			(size 2.0066 0.508)
			(layers "F.Cu" "F.Mask" "F.Paste")
			(net "SMB_OCP_FRU_STBY_LVC3_SCL")
		)
		(pad "2" smd rect
			(at 0 0.8001 90)
			(size 2.0066 0.508)
			(layers "F.Cu" "F.Mask" "F.Paste")
			(net "SMB_OCP_FRU_STBY_LVC3_SDA")
		)
		(pad "3" smd rect
			(at 0 1.599946 90)
			(size 2.0066 0.508)
			(layers "F.Cu" "F.Mask" "F.Paste")
			(net "EXT_MDIO_I2C_SEL")
		)
		(pad "4" smd rect
			(at 0 2.400046 90)
			(size 2.0066 0.508)
			(layers "F.Cu" "F.Mask" "F.Paste")
			(net "GND")
		)
		(pad "5" smd rect
			(at 0 3.199892 90)
			(size 2.0066 0.508)
			(layers "F.Cu" "F.Mask" "F.Paste")
			(net "Net_446")
		)
		(pad "6" smd rect
			(at 0 3.999992 90)
			(size 2.0066 0.508)
			(layers "F.Cu" "F.Mask" "F.Paste")
			(net "Net_445")
		)
		(pad "7" smd rect
			(at 0 4.800092 90)
			(size 2.0066 0.508)
			(layers "F.Cu" "F.Mask" "F.Paste")
			(net "GND")
		)
		(pad "8" smd rect
			(at 0 5.599938 90)
			(size 2.0066 0.508)
			(layers "F.Cu" "F.Mask" "F.Paste")
			(net "LED_GBE_P1_0")
		)
		(pad "9" smd rect
			(at 0 6.400038 90)
			(size 2.0066 0.508)
			(layers "F.Cu" "F.Mask" "F.Paste")
			(net "LED_GBE_P1_1")
		)
		(pad "10" smd rect
			(at 0 7.199884 90)
			(size 2.0066 0.508)
			(layers "F.Cu" "F.Mask" "F.Paste")
			(net "GND")
		)
		(pad "11" smd rect
			(at 0 7.999984 90)
			(size 2.0066 0.508)
			(layers "F.Cu" "F.Mask" "F.Paste")
			(net "Net_450")
		)
		(pad "12" smd rect
			(at 0 8.800084 90)
			(size 2.0066 0.508)
			(layers "F.Cu" "F.Mask" "F.Paste")
			(net "Net_449")
		)
		(pad "13" smd rect
			(at 0 9.59993 90)
			(size 2.0066 0.508)
			(layers "F.Cu" "F.Mask" "F.Paste")
			(net "GND")
		)
		(pad "14" smd rect
			(at 0 10.40003 90)
			(size 2.0066 0.508)
			(layers "F.Cu" "F.Mask" "F.Paste")
			(net "LED_GBE_P2_0")
		)
		(pad "15" smd rect
			(at 0 11.199876 90)
			(size 2.0066 0.508)
			(layers "F.Cu" "F.Mask" "F.Paste")
			(net "LED_GBE_P2_1")
		)
		(pad "16" smd rect
			(at 0 11.999976 90)
			(size 2.0066 0.508)
			(layers "F.Cu" "F.Mask" "F.Paste")
			(net "GND")
		)
		(pad "17" smd rect
			(at 0 12.800076 90)
			(size 2.0066 0.508)
			(layers "F.Cu" "F.Mask" "F.Paste")
			(net "Net_444")
		)
		(pad "18" smd rect
			(at 0 13.599922 90)
			(size 2.0066 0.508)
			(layers "F.Cu" "F.Mask" "F.Paste")
			(net "Net_443")
		)
		(pad "19" smd rect
			(at 0 14.400022 90)
			(size 2.0066 0.508)
			(layers "F.Cu" "F.Mask" "F.Paste")
			(net "GND")
		)
		(pad "20" smd rect
			(at 0 15.200122 90)
			(size 2.0066 0.508)
			(layers "F.Cu" "F.Mask" "F.Paste")
			(net "SMB_PCH_MEZZ_LOM0_SCL")
		)
		(pad "21" smd rect
			(at 0 15.999968 90)
			(size 2.0066 0.508)
			(layers "F.Cu" "F.Mask" "F.Paste")
			(net "SMB_PCH_MEZZ_LOM0_SDA")
		)
		(pad "22" smd rect
			(at 0 16.800068 90)
			(size 2.0066 0.508)
			(layers "F.Cu" "F.Mask" "F.Paste")
			(net "GND")
		)
		(pad "23" smd rect
			(at 0 17.599914 90)
			(size 2.0066 0.508)
			(layers "F.Cu" "F.Mask" "F.Paste")
			(net "Net_448")
		)
		(pad "24" smd rect
			(at 0 18.400014 90)
			(size 2.0066 0.508)
			(layers "F.Cu" "F.Mask" "F.Paste")
			(net "Net_447")
		)
		(pad "25" smd rect
			(at 0 19.200114 90)
			(size 2.0066 0.508)
			(layers "F.Cu" "F.Mask" "F.Paste")
			(net "GND")
		)
		(pad "26" smd rect
			(at 0 19.99996 90)
			(size 2.0066 0.508)
			(layers "F.Cu" "F.Mask" "F.Paste")
			(net "SMB_PCH_MEZZ_LOM1_SCL")
		)
		(pad "27" smd rect
			(at 0 20.80006 90)
			(size 2.0066 0.508)
			(layers "F.Cu" "F.Mask" "F.Paste")
			(net "SMB_PCH_MEZZ_LOM1_SDA")
		)
		(pad "28" smd rect
			(at 0 21.599906 90)
			(size 2.0066 0.508)
			(layers "F.Cu" "F.Mask" "F.Paste")
			(net "GND")
		)
		(pad "29" smd rect
			(at 0 22.400006 90)
			(size 2.0066 0.508)
			(layers "F.Cu" "F.Mask" "F.Paste")
			(net "SMB_PCH_MEZZ_LOM3_SCL")
		)
		(pad "30" smd rect
			(at 0 23.200106 90)
			(size 2.0066 0.508)
			(layers "F.Cu" "F.Mask" "F.Paste")
			(net "SMB_PCH_MEZZ_LOM3_SDA")
		)
		(pad "31" smd rect
			(at 0 23.999952 90)
			(size 2.0066 0.508)
			(layers "F.Cu" "F.Mask" "F.Paste")
			(net "FM_GBE2_LVC3_MOD_ABS")
		)
		(pad "32" smd rect
			(at 0 24.800052 90)
			(size 2.0066 0.508)
			(layers "F.Cu" "F.Mask" "F.Paste")
			(net "FM_GBE3_LVC3_MOD_ABS")
		)
		(pad "33" smd rect
			(at 4.406646 0 90)
			(size 2.0066 0.508)
			(layers "F.Cu" "F.Mask" "F.Paste")
			(net "P12V_STBY")
		)
		(pad "34" smd rect
			(at 4.406646 0.8001 90)
			(size 2.0066 0.508)
			(layers "F.Cu" "F.Mask" "F.Paste")
			(net "P12V_STBY")
		)
		(pad "35" smd rect
			(at 4.406646 1.599946 90)
			(size 2.0066 0.508)
			(layers "F.Cu" "F.Mask" "F.Paste")
			(net "P12V_STBY")
		)
		(pad "36" smd rect
			(at 4.406646 2.400046 90)
			(size 2.0066 0.508)
			(layers "F.Cu" "F.Mask" "F.Paste")
			(net "TP_RSVD<0>")
		)
		(pad "37" smd rect
			(at 4.406646 3.199892 90)
			(size 2.0066 0.508)
			(layers "F.Cu" "F.Mask" "F.Paste")
			(net "FM_GBE0_LVC3_MOD_ABS")
		)
		(pad "38" smd rect
			(at 4.406646 3.999992 90)
			(size 2.0066 0.508)
			(layers "F.Cu" "F.Mask" "F.Paste")
			(net "FM_GBE1_LVC3_MOD_ABS")
		)
		(pad "39" smd rect
			(at 4.406646 4.800092 90)
			(size 2.0066 0.508)
			(layers "F.Cu" "F.Mask" "F.Paste")
			(net "GND")
		)
		(pad "40" smd rect
			(at 4.406646 5.599938 90)
			(size 2.0066 0.508)
			(layers "F.Cu" "F.Mask" "F.Paste")
			(net "KR_P0_OCP_TX_DP")
		)
		(pad "41" smd rect
			(at 4.406646 6.400038 90)
			(size 2.0066 0.508)
			(layers "F.Cu" "F.Mask" "F.Paste")
			(net "KR_P0_OCP_TX_DN")
		)
		(pad "42" smd rect
			(at 4.406646 7.199884 90)
			(size 2.0066 0.508)
			(layers "F.Cu" "F.Mask" "F.Paste")
			(net "GND")
		)
		(pad "43" smd rect
			(at 4.406646 7.999984 90)
			(size 2.0066 0.508)
			(layers "F.Cu" "F.Mask" "F.Paste")
			(net "LED_GBE_P0_0")
		)
		(pad "44" smd rect
			(at 4.406646 8.800084 90)
			(size 2.0066 0.508)
			(layers "F.Cu" "F.Mask" "F.Paste")
			(net "LED_GBE_P0_1")
		)
		(pad "45" smd rect
			(at 4.406646 9.59993 90)
			(size 2.0066 0.508)
			(layers "F.Cu" "F.Mask" "F.Paste")
			(net "GND")
		)
		(pad "46" smd rect
			(at 4.406646 10.40003 90)
			(size 2.0066 0.508)
			(layers "F.Cu" "F.Mask" "F.Paste")
			(net "KR_P1_OCP_TX_DP")
		)
		(pad "47" smd rect
			(at 4.406646 11.199876 90)
			(size 2.0066 0.508)
			(layers "F.Cu" "F.Mask" "F.Paste")
			(net "KR_P1_OCP_TX_DN")
		)
		(pad "48" smd rect
			(at 4.406646 11.999976 90)
			(size 2.0066 0.508)
			(layers "F.Cu" "F.Mask" "F.Paste")
			(net "GND")
		)
		(pad "49" smd rect
			(at 4.406646 12.800076 90)
			(size 2.0066 0.508)
			(layers "F.Cu" "F.Mask" "F.Paste")
			(net "TP_SHARED_KR_MDC_0")
		)
		(pad "50" smd rect
			(at 4.406646 13.599922 90)
			(size 2.0066 0.508)
			(layers "F.Cu" "F.Mask" "F.Paste")
			(net "TP_SHARED_KR_MDIO_0")
		)
		(pad "51" smd rect
			(at 4.406646 14.400022 90)
			(size 2.0066 0.508)
			(layers "F.Cu" "F.Mask" "F.Paste")
			(net "GND")
		)
		(pad "52" smd rect
			(at 4.406646 15.200122 90)
			(size 2.0066 0.508)
			(layers "F.Cu" "F.Mask" "F.Paste")
			(net "KR_P0_OCP_RX_DP")
		)
		(pad "53" smd rect
			(at 4.406646 15.999968 90)
			(size 2.0066 0.508)
			(layers "F.Cu" "F.Mask" "F.Paste")
			(net "KR_P0_OCP_RX_DN")
		)
		(pad "54" smd rect
			(at 4.406646 16.800068 90)
			(size 2.0066 0.508)
			(layers "F.Cu" "F.Mask" "F.Paste")
			(net "GND")
		)
		(pad "55" smd rect
			(at 4.406646 17.599914 90)
			(size 2.0066 0.508)
			(layers "F.Cu" "F.Mask" "F.Paste")
			(net "LED_GBE_P3_0")
		)
		(pad "56" smd rect
			(at 4.406646 18.400014 90)
			(size 2.0066 0.508)
			(layers "F.Cu" "F.Mask" "F.Paste")
			(net "LED_GBE_P3_1")
		)
		(pad "57" smd rect
			(at 4.406646 19.200114 90)
			(size 2.0066 0.508)
			(layers "F.Cu" "F.Mask" "F.Paste")
			(net "GND")
		)
		(pad "58" smd rect
			(at 4.406646 19.99996 90)
			(size 2.0066 0.508)
			(layers "F.Cu" "F.Mask" "F.Paste")
			(net "KR_P1_OCP_RX_DP")
		)
		(pad "59" smd rect
			(at 4.406646 20.80006 90)
			(size 2.0066 0.508)
			(layers "F.Cu" "F.Mask" "F.Paste")
			(net "KR_P1_OCP_RX_DN")
		)
		(pad "60" smd rect
			(at 4.406646 21.599906 90)
			(size 2.0066 0.508)
			(layers "F.Cu" "F.Mask" "F.Paste")
			(net "GND")
		)
		(pad "61" smd rect
			(at 4.406646 22.400006 90)
			(size 2.0066 0.508)
			(layers "F.Cu" "F.Mask" "F.Paste")
			(net "SMB_PCH_MEZZ_LOM2_SCL")
		)
		(pad "62" smd rect
			(at 4.406646 23.200106 90)
			(size 2.0066 0.508)
			(layers "F.Cu" "F.Mask" "F.Paste")
			(net "SMB_PCH_MEZZ_LOM2_SDA")
		)
		(pad "63" smd rect
			(at 4.406646 23.999952 90)
			(size 2.0066 0.508)
			(layers "F.Cu" "F.Mask" "F.Paste")
			(net "GND")
		)
		(pad "64" smd rect
			(at 4.406646 24.800052 90)
			(size 2.0066 0.508)
			(layers "F.Cu" "F.Mask" "F.Paste")
			(net "FM_OCP_MEZZC_PRES_N")
		)
		(zone
			(layers "F.Cu" "B.Cu" "In1.Cu" "In2.Cu" "In3.Cu" "In4.Cu" "In5.Cu" "In6.Cu"
				"In7.Cu" "In8.Cu" "In9.Cu" "In10.Cu" "In11.Cu" "In12.Cu"
			)
			(hatch none 0.5)
			(connect_pads
				(clearance 0)
			)
			(min_thickness 0.25)
			(keepout
				(tracks not_allowed)
				(vias allowed)
				(pads allowed)
				(copperpour not_allowed)
				(footprints allowed)
			)
			(placement
				(enabled no)
				(sheetname "")
			)
			(fill
				(thermal_gap 0.5)
				(thermal_bridge_width 0.5)
				(island_removal_mode 0)
			)
			(polygon
				(pts
					(arc
						(start 468.573866 -59.79922)
						(mid 467.126066 -59.79922)
						(end 468.573866 -59.79922)
					)
				)
			)
		)
		(zone
			(layers "F.Cu" "B.Cu" "In1.Cu" "In2.Cu" "In3.Cu" "In4.Cu" "In5.Cu" "In6.Cu"
				"In7.Cu" "In8.Cu" "In9.Cu" "In10.Cu" "In11.Cu" "In12.Cu"
			)
			(hatch none 0.5)
			(connect_pads
				(clearance 0)
			)
			(min_thickness 0.25)
			(keepout
				(tracks not_allowed)
				(vias allowed)
				(pads allowed)
				(copperpour not_allowed)
				(footprints allowed)
			)
			(placement
				(enabled no)
				(sheetname "")
			)
			(fill
				(thermal_gap 0.5)
				(thermal_bridge_width 0.5)
				(island_removal_mode 0)
			)
			(polygon
				(pts
					(arc
						(start 438.964324 -59.79922)
						(mid 437.135524 -59.79922)
						(end 438.964324 -59.79922)
					)
				)
			)
		)
	)
	(footprint ""
		(layer "F.Cu")
		(at 337.947 -13.97 90)
		(property "Reference" "R7G9"
			(at 0 0 90)
			(layer "F.SilkS")
			(hide yes)
			(effects
				(font
					(size 1.27 1.27)
				)
			)
		)
		(property "Value" ""
			(at 0 0 90)
			(layer "F.Fab")
			(effects
				(font
					(size 1.27 1.27)
				)
			)
		)
		(duplicate_pad_numbers_are_jumpers no)
		(fp_rect
			(start 0.2794 -0.1016)
			(end -0.2794 0.9906)
			(stroke
				(width 0)
				(type default)
			)
			(fill no)
			(layer "F.CrtYd")
		)
		(fp_line
			(start 0.2794 -0.1016)
			(end -0.2794 -0.1016)
			(stroke
				(width 0.1)
				(type default)
			)
			(layer "F.Fab")
		)
		(fp_line
			(start -0.2794 -0.1016)
			(end -0.2794 0.9906)
			(stroke
				(width 0.1)
				(type default)
			)
			(layer "F.Fab")
		)
		(fp_line
			(start 0.2794 0.9906)
			(end 0.2794 -0.1016)
			(stroke
				(width 0.1)
				(type default)
			)
			(layer "F.Fab")
		)
		(fp_line
			(start -0.2794 0.9906)
			(end 0.2794 0.9906)
			(stroke
				(width 0.1)
				(type default)
			)
			(layer "F.Fab")
		)
		(pad "1" smd rect
			(at 0 0 90)
			(size 0.508 0.508)
			(layers "F.Cu" "F.Mask" "F.Paste")
			(net "VSENSE_PVDDQ_ABC_P")
		)
		(pad "2" smd rect
			(at 0 0.889 90)
			(size 0.508 0.508)
			(layers "F.Cu" "F.Mask" "F.Paste")
			(net "VR_PVDDQ_ABC_AVSP")
		)
		(zone
			(layer "F.Cu")
			(hatch none 0.5)
			(connect_pads
				(clearance 0)
			)
			(min_thickness 0.25)
			(keepout
				(tracks not_allowed)
				(vias allowed)
				(pads allowed)
				(copperpour not_allowed)
				(footprints allowed)
			)
			(placement
				(enabled no)
				(sheetname "")
			)
			(fill
				(thermal_gap 0.5)
				(thermal_bridge_width 0.5)
				(island_removal_mode 0)
			)
			(polygon
				(pts
					(xy 338.201 -14.224) (xy 338.201 -13.716) (xy 338.582 -13.716) (xy 338.582 -14.224)
				)
			)
		)
		(zone
			(layer "F.Cu")
			(hatch none 0.5)
			(connect_pads
				(clearance 0)
			)
			(min_thickness 0.25)
			(keepout
				(tracks allowed)
				(vias not_allowed)
				(pads allowed)
				(copperpour not_allowed)
				(footprints allowed)
			)
			(placement
				(enabled no)
				(sheetname "")
			)
			(fill
				(thermal_gap 0.5)
				(thermal_bridge_width 0.5)
				(island_removal_mode 0)
			)
			(polygon
				(pts
					(xy 338.201 -14.224) (xy 338.201 -13.716) (xy 338.582 -13.716) (xy 338.582 -14.224)
				)
			)
		)
	)
	(footprint ""
		(layer "F.Cu")
		(at 422.2877 -105.029 -90)
		(property "Reference" "R9W18"
			(at -0.8382 -0.67818 270)
			(unlocked yes)
			(layer "F.SilkS")
			(effects
				(font
					(size 0.4064 0.254)
					(thickness 0.1524)
				)
				(justify left)
			)
		)
		(property "Value" ""
			(at 0 0 270)
			(layer "F.Fab")
			(effects
				(font
					(size 1.27 1.27)
				)
			)
		)
		(duplicate_pad_numbers_are_jumpers no)
		(fp_poly
			(pts
				(xy -0.2794 -0.1016) (xy 0.2794 -0.1016) (xy 0.2794 0.9906) (xy -0.2794 0.9906)
			)
			(stroke
				(width 0)
				(type default)
			)
			(fill no)
			(layer "F.CrtYd")
		)
		(fp_line
			(start -0.2794 0.9906)
			(end 0.2794 0.9906)
			(stroke
				(width 0.1)
				(type default)
			)
			(layer "F.Fab")
		)
		(fp_line
			(start 0.2794 0.9906)
			(end 0.2794 -0.1016)
			(stroke
				(width 0.1)
				(type default)
			)
			(layer "F.Fab")
		)
		(fp_line
			(start -0.2794 -0.1016)
			(end -0.2794 0.9906)
			(stroke
				(width 0.1)
				(type default)
			)
			(layer "F.Fab")
		)
		(fp_line
			(start 0.2794 -0.1016)
			(end -0.2794 -0.1016)
			(stroke
				(width 0.1)
				(type default)
			)
			(layer "F.Fab")
		)
		(pad "1" smd rect
			(at 0 0 270)
			(size 0.508 0.508)
			(layers "F.Cu" "F.Mask" "F.Paste")
			(net "PVCCIO_CPU0")
		)
		(pad "2" smd rect
			(at 0 0.889 270)
			(size 0.508 0.508)
			(layers "F.Cu" "F.Mask" "F.Paste")
			(net "SMB_CPU0_PE_HP_GTL_R_SDA")
		)
		(zone
			(layer "F.Cu")
			(hatch none 0.5)
			(connect_pads
				(clearance 0)
			)
			(min_thickness 0.25)
			(keepout
				(tracks not_allowed)
				(vias allowed)
				(pads allowed)
				(copperpour not_allowed)
				(footprints allowed)
			)
			(placement
				(enabled no)
				(sheetname "")
			)
			(fill
				(thermal_gap 0.5)
				(thermal_bridge_width 0.5)
				(island_removal_mode 0)
			)
			(polygon
				(pts
					(xy 421.6527 -105.283) (xy 421.6527 -104.775) (xy 422.0337 -104.775) (xy 422.0337 -105.283)
				)
			)
		)
		(zone
			(layer "F.Cu")
			(hatch none 0.5)
			(connect_pads
				(clearance 0)
			)
			(min_thickness 0.25)
			(keepout
				(tracks allowed)
				(vias not_allowed)
				(pads allowed)
				(copperpour not_allowed)
				(footprints allowed)
			)
			(placement
				(enabled no)
				(sheetname "")
			)
			(fill
				(thermal_gap 0.5)
				(thermal_bridge_width 0.5)
				(island_removal_mode 0)
			)
			(polygon
				(pts
					(xy 422.0337 -105.283) (xy 422.0337 -104.775) (xy 421.6527 -104.775) (xy 421.6527 -105.283)
				)
			)
		)
	)
	(footprint ""
		(layer "F.Cu")
		(at 401.8915 -48.006 90)
		(property "Reference" "C7F2"
			(at 0 0 90)
			(layer "F.SilkS")
			(hide yes)
			(effects
				(font
					(size 1.27 1.27)
				)
			)
		)
		(property "Value" ""
			(at 0 0 90)
			(layer "F.Fab")
			(effects
				(font
					(size 1.27 1.27)
				)
			)
		)
		(duplicate_pad_numbers_are_jumpers no)
		(fp_poly
			(pts
				(xy 0.3048 -0.1016) (xy 0.3048 0.9906) (xy -0.3048 0.9906) (xy -0.3048 -0.1016)
			)
			(stroke
				(width 0)
				(type default)
			)
			(fill no)
			(layer "F.CrtYd")
		)
		(fp_line
			(start 0.3048 -0.1016)
			(end -0.3048 -0.1016)
			(stroke
				(width 0.1)
				(type default)
			)
			(layer "F.Fab")
		)
		(fp_line
			(start -0.3048 -0.1016)
			(end -0.3048 0.9906)
			(stroke
				(width 0.1)
				(type default)
			)
			(layer "F.Fab")
		)
		(fp_line
			(start 0.3048 0.9906)
			(end 0.3048 -0.1016)
			(stroke
				(width 0.1)
				(type default)
			)
			(layer "F.Fab")
		)
		(fp_line
			(start -0.3048 0.9906)
			(end 0.3048 0.9906)
			(stroke
				(width 0.1)
				(type default)
			)
			(layer "F.Fab")
		)
		(pad "1" smd rect
			(at 0 0 90)
			(size 0.508 0.508)
			(layers "F.Cu" "F.Mask" "F.Paste")
			(net "P3V3_STBY")
		)
		(pad "2" smd rect
			(at 0 0.889 90)
			(size 0.508 0.508)
			(layers "F.Cu" "F.Mask" "F.Paste")
			(net "GND")
		)
		(zone
			(layer "F.Cu")
			(hatch none 0.5)
			(connect_pads
				(clearance 0)
			)
			(min_thickness 0.25)
			(keepout
				(tracks allowed)
				(vias not_allowed)
				(pads allowed)
				(copperpour not_allowed)
				(footprints allowed)
			)
			(placement
				(enabled no)
				(sheetname "")
			)
			(fill
				(thermal_gap 0.5)
				(thermal_bridge_width 0.5)
				(island_removal_mode 0)
			)
			(polygon
				(pts
					(xy 402.1455 -47.752) (xy 402.1455 -48.26) (xy 402.5265 -48.26) (xy 402.5265 -47.752)
				)
			)
		)
		(zone
			(layer "F.Cu")
			(hatch none 0.5)
			(connect_pads
				(clearance 0)
			)
			(min_thickness 0.25)
			(keepout
				(tracks not_allowed)
				(vias allowed)
				(pads allowed)
				(copperpour not_allowed)
				(footprints allowed)
			)
			(placement
				(enabled no)
				(sheetname "")
			)
			(fill
				(thermal_gap 0.5)
				(thermal_bridge_width 0.5)
				(island_removal_mode 0)
			)
			(polygon
				(pts
					(xy 402.5265 -47.752) (xy 402.5265 -48.26) (xy 402.1455 -48.26) (xy 402.1455 -47.752)
				)
			)
		)
	)
	(footprint ""
		(layer "F.Cu")
		(at 416.814 -82.55 90)
		(property "Reference" "R2P8"
			(at 0 0 90)
			(layer "F.SilkS")
			(hide yes)
			(effects
				(font
					(size 1.27 1.27)
				)
			)
		)
		(property "Value" ""
			(at 0 0 90)
			(layer "F.Fab")
			(effects
				(font
					(size 1.27 1.27)
				)
			)
		)
		(duplicate_pad_numbers_are_jumpers no)
		(fp_poly
			(pts
				(xy -0.2794 -0.1016) (xy 0.2794 -0.1016) (xy 0.2794 0.9906) (xy -0.2794 0.9906)
			)
			(stroke
				(width 0)
				(type default)
			)
			(fill no)
			(layer "F.CrtYd")
		)
		(fp_line
			(start 0.2794 -0.1016)
			(end -0.2794 -0.1016)
			(stroke
				(width 0.1)
				(type default)
			)
			(layer "F.Fab")
		)
		(fp_line
			(start -0.2794 -0.1016)
			(end -0.2794 0.9906)
			(stroke
				(width 0.1)
				(type default)
			)
			(layer "F.Fab")
		)
		(fp_line
			(start 0.2794 0.9906)
			(end 0.2794 -0.1016)
			(stroke
				(width 0.1)
				(type default)
			)
			(layer "F.Fab")
		)
		(fp_line
			(start -0.2794 0.9906)
			(end 0.2794 0.9906)
			(stroke
				(width 0.1)
				(type default)
			)
			(layer "F.Fab")
		)
		(pad "1" smd rect
			(at 0 0 90)
			(size 0.508 0.508)
			(layers "F.Cu" "F.Mask" "F.Paste")
			(net "P3V3_STBY")
		)
		(pad "2" smd rect
			(at 0 0.889 90)
			(size 0.508 0.508)
			(layers "F.Cu" "F.Mask" "F.Paste")
			(net "IRQ_SML1_PMBUS_ALERT_N")
		)
		(zone
			(layer "F.Cu")
			(hatch none 0.5)
			(connect_pads
				(clearance 0)
			)
			(min_thickness 0.25)
			(keepout
				(tracks allowed)
				(vias not_allowed)
				(pads allowed)
				(copperpour not_allowed)
				(footprints allowed)
			)
			(placement
				(enabled no)
				(sheetname "")
			)
			(fill
				(thermal_gap 0.5)
				(thermal_bridge_width 0.5)
				(island_removal_mode 0)
			)
			(polygon
				(pts
					(xy 417.068 -82.296) (xy 417.068 -82.804) (xy 417.449 -82.804) (xy 417.449 -82.296)
				)
			)
		)
		(zone
			(layer "F.Cu")
			(hatch none 0.5)
			(connect_pads
				(clearance 0)
			)
			(min_thickness 0.25)
			(keepout
				(tracks not_allowed)
				(vias allowed)
				(pads allowed)
				(copperpour not_allowed)
				(footprints allowed)
			)
			(placement
				(enabled no)
				(sheetname "")
			)
			(fill
				(thermal_gap 0.5)
				(thermal_bridge_width 0.5)
				(island_removal_mode 0)
			)
			(polygon
				(pts
					(xy 417.449 -82.296) (xy 417.449 -82.804) (xy 417.068 -82.804) (xy 417.068 -82.296)
				)
			)
		)
	)
	(footprint ""
		(layer "F.Cu")
		(at 104.35844 -73.279)
		(property "Reference" "C2D39"
			(at 0 0 0)
			(layer "F.SilkS")
			(hide yes)
			(effects
				(font
					(size 1.27 1.27)
				)
			)
		)
		(property "Value" ""
			(at 0 0 0)
			(layer "F.Fab")
			(effects
				(font
					(size 1.27 1.27)
				)
			)
		)
		(duplicate_pad_numbers_are_jumpers no)
		(fp_poly
			(pts
				(xy -0.4953 -0.2032) (xy 0.4953 -0.2032) (xy 0.4953 1.6002) (xy -0.4953 1.6002)
			)
			(stroke
				(width 0)
				(type default)
			)
			(fill no)
			(layer "F.CrtYd")
		)
		(fp_line
			(start -0.4953 -0.2032)
			(end 0.4953 -0.2032)
			(stroke
				(width 0.1)
				(type default)
			)
			(layer "F.Fab")
		)
		(fp_line
			(start -0.4953 1.6002)
			(end -0.4953 -0.2032)
			(stroke
				(width 0.1)
				(type default)
			)
			(layer "F.Fab")
		)
		(fp_line
			(start 0.4953 -0.2032)
			(end 0.4953 1.6002)
			(stroke
				(width 0.1)
				(type default)
			)
			(layer "F.Fab")
		)
		(fp_line
			(start 0.4953 1.6002)
			(end -0.4953 1.6002)
			(stroke
				(width 0.1)
				(type default)
			)
			(layer "F.Fab")
		)
		(pad "1" smd rect
			(at 0 0)
			(size 0.762 0.889)
			(layers "F.Cu" "F.Mask" "F.Paste")
			(net "PVCCMCP_CPU1")
		)
		(pad "2" smd rect
			(at 0 1.397)
			(size 0.762 0.889)
			(layers "F.Cu" "F.Mask" "F.Paste")
			(net "GND")
		)
		(zone
			(layer "F.Cu")
			(hatch none 0.5)
			(connect_pads
				(clearance 0)
			)
			(min_thickness 0.25)
			(keepout
				(tracks not_allowed)
				(vias allowed)
				(pads allowed)
				(copperpour not_allowed)
				(footprints allowed)
			)
			(placement
				(enabled no)
				(sheetname "")
			)
			(fill
				(thermal_gap 0.5)
				(thermal_bridge_width 0.5)
				(island_removal_mode 0)
			)
			(polygon
				(pts
					(xy 103.97744 -72.8345) (xy 104.73944 -72.8345) (xy 104.73944 -72.3265) (xy 103.97744 -72.3265)
				)
			)
		)
	)
	(footprint ""
		(layer "F.Cu")
		(at 392.023346 -64.7065)
		(property "Reference" "C8E16"
			(at 0 0 0)
			(layer "F.SilkS")
			(hide yes)
			(effects
				(font
					(size 1.27 1.27)
				)
			)
		)
		(property "Value" ""
			(at 0 0 0)
			(layer "F.Fab")
			(effects
				(font
					(size 1.27 1.27)
				)
			)
		)
		(duplicate_pad_numbers_are_jumpers no)
		(fp_poly
			(pts
				(xy 0.3048 -0.1016) (xy 0.3048 0.9906) (xy -0.3048 0.9906) (xy -0.3048 -0.1016)
			)
			(stroke
				(width 0)
				(type default)
			)
			(fill no)
			(layer "F.CrtYd")
		)
		(fp_line
			(start -0.3048 -0.1016)
			(end -0.3048 0.9906)
			(stroke
				(width 0.1)
				(type default)
			)
			(layer "F.Fab")
		)
		(fp_line
			(start -0.3048 0.9906)
			(end 0.3048 0.9906)
			(stroke
				(width 0.1)
				(type default)
			)
			(layer "F.Fab")
		)
		(fp_line
			(start 0.3048 -0.1016)
			(end -0.3048 -0.1016)
			(stroke
				(width 0.1)
				(type default)
			)
			(layer "F.Fab")
		)
		(fp_line
			(start 0.3048 0.9906)
			(end 0.3048 -0.1016)
			(stroke
				(width 0.1)
				(type default)
			)
			(layer "F.Fab")
		)
		(pad "1" smd rect
			(at 0 0)
			(size 0.508 0.508)
			(layers "F.Cu" "F.Mask" "F.Paste")
			(net "VR_P5V_STBY_COMP")
		)
		(pad "2" smd rect
			(at 0 0.889)
			(size 0.508 0.508)
			(layers "F.Cu" "F.Mask" "F.Paste")
			(net "AGND_P5V_STBY")
		)
		(zone
			(layer "F.Cu")
			(hatch none 0.5)
			(connect_pads
				(clearance 0)
			)
			(min_thickness 0.25)
			(keepout
				(tracks allowed)
				(vias not_allowed)
				(pads allowed)
				(copperpour not_allowed)
				(footprints allowed)
			)
			(placement
				(enabled no)
				(sheetname "")
			)
			(fill
				(thermal_gap 0.5)
				(thermal_bridge_width 0.5)
				(island_removal_mode 0)
			)
			(polygon
				(pts
					(xy 391.769346 -64.4525) (xy 392.277346 -64.4525) (xy 392.277346 -64.0715) (xy 391.769346 -64.0715)
				)
			)
		)
		(zone
			(layer "F.Cu")
			(hatch none 0.5)
			(connect_pads
				(clearance 0)
			)
			(min_thickness 0.25)
			(keepout
				(tracks not_allowed)
				(vias allowed)
				(pads allowed)
				(copperpour not_allowed)
				(footprints allowed)
			)
			(placement
				(enabled no)
				(sheetname "")
			)
			(fill
				(thermal_gap 0.5)
				(thermal_bridge_width 0.5)
				(island_removal_mode 0)
			)
			(polygon
				(pts
					(xy 391.769346 -64.0715) (xy 392.277346 -64.0715) (xy 392.277346 -64.4525) (xy 391.769346 -64.4525)
				)
			)
		)
	)
	(footprint ""
		(layer "F.Cu")
		(at 366.2172 -92.1766 180)
		(property "Reference" "C7D1"
			(at 0 0 180)
			(layer "F.SilkS")
			(hide yes)
			(effects
				(font
					(size 1.27 1.27)
				)
			)
		)
		(property "Value" ""
			(at 0 0 180)
			(layer "F.Fab")
			(effects
				(font
					(size 1.27 1.27)
				)
			)
		)
		(duplicate_pad_numbers_are_jumpers no)
		(fp_poly
			(pts
				(xy 0.3048 -0.1016) (xy 0.3048 0.9906) (xy -0.3048 0.9906) (xy -0.3048 -0.1016)
			)
			(stroke
				(width 0)
				(type default)
			)
			(fill no)
			(layer "F.CrtYd")
		)
		(fp_line
			(start 0.3048 0.9906)
			(end 0.3048 -0.1016)
			(stroke
				(width 0.1)
				(type default)
			)
			(layer "F.Fab")
		)
		(fp_line
			(start 0.3048 -0.1016)
			(end -0.3048 -0.1016)
			(stroke
				(width 0.1)
				(type default)
			)
			(layer "F.Fab")
		)
		(fp_line
			(start -0.3048 0.9906)
			(end 0.3048 0.9906)
			(stroke
				(width 0.1)
				(type default)
			)
			(layer "F.Fab")
		)
		(fp_line
			(start -0.3048 -0.1016)
			(end -0.3048 0.9906)
			(stroke
				(width 0.1)
				(type default)
			)
			(layer "F.Fab")
		)
		(pad "1" smd rect
			(at 0 0 180)
			(size 0.508 0.508)
			(layers "F.Cu" "F.Mask" "F.Paste")
			(net "P3V3_STBY")
		)
		(pad "2" smd rect
			(at 0 0.889 180)
			(size 0.508 0.508)
			(layers "F.Cu" "F.Mask" "F.Paste")
			(net "GND")
		)
		(zone
			(layer "F.Cu")
			(hatch none 0.5)
			(connect_pads
				(clearance 0)
			)
			(min_thickness 0.25)
			(keepout
				(tracks not_allowed)
				(vias allowed)
				(pads allowed)
				(copperpour not_allowed)
				(footprints allowed)
			)
			(placement
				(enabled no)
				(sheetname "")
			)
			(fill
				(thermal_gap 0.5)
				(thermal_bridge_width 0.5)
				(island_removal_mode 0)
			)
			(polygon
				(pts
					(xy 366.4712 -92.8116) (xy 365.9632 -92.8116) (xy 365.9632 -92.4306) (xy 366.4712 -92.4306)
				)
			)
		)
		(zone
			(layer "F.Cu")
			(hatch none 0.5)
			(connect_pads
				(clearance 0)
			)
			(min_thickness 0.25)
			(keepout
				(tracks allowed)
				(vias not_allowed)
				(pads allowed)
				(copperpour not_allowed)
				(footprints allowed)
			)
			(placement
				(enabled no)
				(sheetname "")
			)
			(fill
				(thermal_gap 0.5)
				(thermal_bridge_width 0.5)
				(island_removal_mode 0)
			)
			(polygon
				(pts
					(xy 366.4712 -92.4306) (xy 365.9632 -92.4306) (xy 365.9632 -92.8116) (xy 366.4712 -92.8116)
				)
			)
		)
	)
	(footprint ""
		(layer "F.Cu")
		(at 435.404006 -41.663874 180)
		(property "Reference" "R25W4"
			(at 0 0 180)
			(layer "F.SilkS")
			(hide yes)
			(effects
				(font
					(size 1.27 1.27)
				)
			)
		)
		(property "Value" "*"
			(at 0.064008 -4.108196 180)
			(unlocked yes)
			(layer "F.Fab")
			(hide yes)
			(effects
				(font
					(size 1.27 1.016)
					(thickness 0.1524)
				)
			)
		)
		(property "Device Type" "120R2F-GP_RCL_GP-120R2F-GP,64.A"
			(at 0.064008 -5.632196 180)
			(unlocked yes)
			(layer "F.Fab")
			(hide yes)
			(effects
				(font
					(size 1.27 1.016)
					(thickness 0.1524)
				)
			)
		)
		(duplicate_pad_numbers_are_jumpers no)
		(fp_line
			(start 0.508 -0.9398)
			(end -0.508 -0.9398)
			(stroke
				(width 0.1524)
				(type default)
			)
			(layer "F.SilkS")
		)
		(fp_line
			(start -0.508 -0.9398)
			(end -0.508 0.9398)
			(stroke
				(width 0.1524)
				(type default)
			)
			(layer "F.SilkS")
		)
		(fp_rect
			(start -0.508 0.9398)
			(end 0.508 -0.9398)
			(stroke
				(width 0)
				(type default)
			)
			(fill no)
			(layer "F.CrtYd")
		)
		(fp_rect
			(start -0.508 0.9398)
			(end 0.508 -0.9398)
			(stroke
				(width 0)
				(type default)
			)
			(fill no)
			(layer "F.Fab")
		)
		(pad "1" smd custom
			(at 0 -0.4445 180)
			(size 0.1397 0.1397)
			(layers "F.Cu" "F.Mask" "F.Paste")
			(net "GND")
			(options
				(clearance outline)
				(anchor circle)
			)
			(primitives
				(gr_poly
					(pts
						(arc
							(start -0.1778 -0.2794)
							(mid -0.249642 -0.249642)
							(end -0.2794 -0.1778)
						)
						(arc
							(start -0.2794 0.1778)
							(mid -0.249642 0.249642)
							(end -0.1778 0.2794)
						)
						(arc
							(start 0.1778 0.2794)
							(mid 0.249642 0.249642)
							(end 0.2794 0.1778)
						)
						(arc
							(start 0.2794 -0.1778)
							(mid 0.249642 -0.249642)
							(end 0.1778 -0.2794)
						)
					)
					(width 0)
					(fill yes)
				)
			)
		)
		(pad "2" smd custom
			(at 0 0.4445 180)
			(size 0.1397 0.1397)
			(layers "F.Cu" "F.Mask" "F.Paste")
			(net "BMC_M_MALERT_N")
			(options
				(clearance outline)
				(anchor circle)
			)
			(primitives
				(gr_poly
					(pts
						(arc
							(start -0.1778 -0.2794)
							(mid -0.249642 -0.249642)
							(end -0.2794 -0.1778)
						)
						(arc
							(start -0.2794 0.1778)
							(mid -0.249642 0.249642)
							(end -0.1778 0.2794)
						)
						(arc
							(start 0.1778 0.2794)
							(mid 0.249642 0.249642)
							(end 0.2794 0.1778)
						)
						(arc
							(start 0.2794 -0.1778)
							(mid 0.249642 -0.249642)
							(end 0.1778 -0.2794)
						)
					)
					(width 0)
					(fill yes)
				)
			)
		)
	)
	(footprint ""
		(layer "F.Cu")
		(at 487.969306 -27.666696)
		(property "Reference" "R9F24"
			(at 0 0 0)
			(layer "F.SilkS")
			(hide yes)
			(effects
				(font
					(size 1.27 1.27)
				)
			)
		)
		(property "Value" ""
			(at 0 0 0)
			(layer "F.Fab")
			(effects
				(font
					(size 1.27 1.27)
				)
			)
		)
		(duplicate_pad_numbers_are_jumpers no)
		(fp_poly
			(pts
				(xy -0.2794 -0.1016) (xy 0.2794 -0.1016) (xy 0.2794 0.9906) (xy -0.2794 0.9906)
			)
			(stroke
				(width 0)
				(type default)
			)
			(fill no)
			(layer "F.CrtYd")
		)
		(fp_line
			(start -0.2794 -0.1016)
			(end -0.2794 0.9906)
			(stroke
				(width 0.1)
				(type default)
			)
			(layer "F.Fab")
		)
		(fp_line
			(start -0.2794 0.9906)
			(end 0.2794 0.9906)
			(stroke
				(width 0.1)
				(type default)
			)
			(layer "F.Fab")
		)
		(fp_line
			(start 0.2794 -0.1016)
			(end -0.2794 -0.1016)
			(stroke
				(width 0.1)
				(type default)
			)
			(layer "F.Fab")
		)
		(fp_line
			(start 0.2794 0.9906)
			(end 0.2794 -0.1016)
			(stroke
				(width 0.1)
				(type default)
			)
			(layer "F.Fab")
		)
		(pad "1" smd rect
			(at 0 0)
			(size 0.508 0.508)
			(layers "F.Cu" "F.Mask" "F.Paste")
			(net "SPA_MID_DBG_RX")
		)
		(pad "2" smd rect
			(at 0 0.889)
			(size 0.508 0.508)
			(layers "F.Cu" "F.Mask" "F.Paste")
			(net "SP2_BMC_CM_UART_RX")
		)
		(zone
			(layer "F.Cu")
			(hatch none 0.5)
			(connect_pads
				(clearance 0)
			)
			(min_thickness 0.25)
			(keepout
				(tracks allowed)
				(vias not_allowed)
				(pads allowed)
				(copperpour not_allowed)
				(footprints allowed)
			)
			(placement
				(enabled no)
				(sheetname "")
			)
			(fill
				(thermal_gap 0.5)
				(thermal_bridge_width 0.5)
				(island_removal_mode 0)
			)
			(polygon
				(pts
					(xy 487.715306 -27.412696) (xy 488.223306 -27.412696) (xy 488.223306 -27.031696) (xy 487.715306 -27.031696)
				)
			)
		)
		(zone
			(layer "F.Cu")
			(hatch none 0.5)
			(connect_pads
				(clearance 0)
			)
			(min_thickness 0.25)
			(keepout
				(tracks not_allowed)
				(vias allowed)
				(pads allowed)
				(copperpour not_allowed)
				(footprints allowed)
			)
			(placement
				(enabled no)
				(sheetname "")
			)
			(fill
				(thermal_gap 0.5)
				(thermal_bridge_width 0.5)
				(island_removal_mode 0)
			)
			(polygon
				(pts
					(xy 487.715306 -27.031696) (xy 488.223306 -27.031696) (xy 488.223306 -27.412696) (xy 487.715306 -27.412696)
				)
			)
		)
	)
	(footprint ""
		(layer "F.Cu")
		(at 164.846 -86.868 180)
		(property "Reference" "R4D1"
			(at 0 0 180)
			(layer "F.SilkS")
			(hide yes)
			(effects
				(font
					(size 1.27 1.27)
				)
			)
		)
		(property "Value" ""
			(at 0 0 180)
			(layer "F.Fab")
			(effects
				(font
					(size 1.27 1.27)
				)
			)
		)
		(duplicate_pad_numbers_are_jumpers no)
		(fp_poly
			(pts
				(xy -0.2794 -0.1016) (xy 0.2794 -0.1016) (xy 0.2794 0.9906) (xy -0.2794 0.9906)
			)
			(stroke
				(width 0)
				(type default)
			)
			(fill no)
			(layer "F.CrtYd")
		)
		(fp_line
			(start 0.2794 0.9906)
			(end 0.2794 -0.1016)
			(stroke
				(width 0.1)
				(type default)
			)
			(layer "F.Fab")
		)
		(fp_line
			(start 0.2794 -0.1016)
			(end -0.2794 -0.1016)
			(stroke
				(width 0.1)
				(type default)
			)
			(layer "F.Fab")
		)
		(fp_line
			(start -0.2794 0.9906)
			(end 0.2794 0.9906)
			(stroke
				(width 0.1)
				(type default)
			)
			(layer "F.Fab")
		)
		(fp_line
			(start -0.2794 -0.1016)
			(end -0.2794 0.9906)
			(stroke
				(width 0.1)
				(type default)
			)
			(layer "F.Fab")
		)
		(pad "1" smd rect
			(at 0 0 180)
			(size 0.508 0.508)
			(layers "F.Cu" "F.Mask" "F.Paste")
			(net "CLK_100M_CPU1_BCLK1_R_DN")
		)
		(pad "2" smd rect
			(at 0 0.889 180)
			(size 0.508 0.508)
			(layers "F.Cu" "F.Mask" "F.Paste")
			(net "CLK_100M_CPU1_BCLK1_DN")
		)
		(zone
			(layer "F.Cu")
			(hatch none 0.5)
			(connect_pads
				(clearance 0)
			)
			(min_thickness 0.25)
			(keepout
				(tracks not_allowed)
				(vias allowed)
				(pads allowed)
				(copperpour not_allowed)
				(footprints allowed)
			)
			(placement
				(enabled no)
				(sheetname "")
			)
			(fill
				(thermal_gap 0.5)
				(thermal_bridge_width 0.5)
				(island_removal_mode 0)
			)
			(polygon
				(pts
					(xy 165.1 -87.503) (xy 164.592 -87.503) (xy 164.592 -87.122) (xy 165.1 -87.122)
				)
			)
		)
		(zone
			(layer "F.Cu")
			(hatch none 0.5)
			(connect_pads
				(clearance 0)
			)
			(min_thickness 0.25)
			(keepout
				(tracks allowed)
				(vias not_allowed)
				(pads allowed)
				(copperpour not_allowed)
				(footprints allowed)
			)
			(placement
				(enabled no)
				(sheetname "")
			)
			(fill
				(thermal_gap 0.5)
				(thermal_bridge_width 0.5)
				(island_removal_mode 0)
			)
			(polygon
				(pts
					(xy 165.1 -87.122) (xy 164.592 -87.122) (xy 164.592 -87.503) (xy 165.1 -87.503)
				)
			)
		)
	)
	(footprint ""
		(layer "F.Cu")
		(at 382.708404 -158.248858 -90)
		(property "Reference" "CT67"
			(at -0.32893 -6.0706 0)
			(unlocked yes)
			(layer "F.SilkS")
			(effects
				(font
					(size 0.7874 0.5842)
					(thickness 0.1524)
				)
				(justify left)
			)
		)
		(property "Value" ""
			(at 0 0 270)
			(layer "F.Fab")
			(effects
				(font
					(size 1.27 1.27)
				)
			)
		)
		(duplicate_pad_numbers_are_jumpers no)
		(fp_poly
			(pts
				(xy 0.3048 -0.1016) (xy 0.3048 0.9906) (xy -0.3048 0.9906) (xy -0.3048 -0.1016)
			)
			(stroke
				(width 0)
				(type default)
			)
			(fill no)
			(layer "F.CrtYd")
		)
		(fp_line
			(start -0.3048 0.9906)
			(end 0.3048 0.9906)
			(stroke
				(width 0.1)
				(type default)
			)
			(layer "F.Fab")
		)
		(fp_line
			(start 0.3048 0.9906)
			(end 0.3048 -0.1016)
			(stroke
				(width 0.1)
				(type default)
			)
			(layer "F.Fab")
		)
		(fp_line
			(start -0.3048 -0.1016)
			(end -0.3048 0.9906)
			(stroke
				(width 0.1)
				(type default)
			)
			(layer "F.Fab")
		)
		(fp_line
			(start 0.3048 -0.1016)
			(end -0.3048 -0.1016)
			(stroke
				(width 0.1)
				(type default)
			)
			(layer "F.Fab")
		)
		(pad "1" smd rect
			(at 0 0 270)
			(size 0.508 0.508)
			(layers "F.Cu" "F.Mask" "F.Paste")
			(net "VR_P1V05_PCH_BIREF1")
		)
		(pad "2" smd rect
			(at 0 0.889 270)
			(size 0.508 0.508)
			(layers "F.Cu" "F.Mask" "F.Paste")
			(net "GND")
		)
		(zone
			(layer "F.Cu")
			(hatch none 0.5)
			(connect_pads
				(clearance 0)
			)
			(min_thickness 0.25)
			(keepout
				(tracks not_allowed)
				(vias allowed)
				(pads allowed)
				(copperpour not_allowed)
				(footprints allowed)
			)
			(placement
				(enabled no)
				(sheetname "")
			)
			(fill
				(thermal_gap 0.5)
				(thermal_bridge_width 0.5)
				(island_removal_mode 0)
			)
			(polygon
				(pts
					(xy 382.073404 -158.502858) (xy 382.073404 -157.994858) (xy 382.454404 -157.994858) (xy 382.454404 -158.502858)
				)
			)
		)
		(zone
			(layer "F.Cu")
			(hatch none 0.5)
			(connect_pads
				(clearance 0)
			)
			(min_thickness 0.25)
			(keepout
				(tracks allowed)
				(vias not_allowed)
				(pads allowed)
				(copperpour not_allowed)
				(footprints allowed)
			)
			(placement
				(enabled no)
				(sheetname "")
			)
			(fill
				(thermal_gap 0.5)
				(thermal_bridge_width 0.5)
				(island_removal_mode 0)
			)
			(polygon
				(pts
					(xy 382.454404 -158.502858) (xy 382.454404 -157.994858) (xy 382.073404 -157.994858) (xy 382.073404 -158.502858)
				)
			)
		)
	)
	(footprint ""
		(layer "F.Cu")
		(at 101.013768 -84.7598)
		(property "Reference" "C2D5"
			(at 0 0 0)
			(layer "F.SilkS")
			(hide yes)
			(effects
				(font
					(size 1.27 1.27)
				)
			)
		)
		(property "Value" ""
			(at 0 0 0)
			(layer "F.Fab")
			(effects
				(font
					(size 1.27 1.27)
				)
			)
		)
		(duplicate_pad_numbers_are_jumpers no)
		(fp_poly
			(pts
				(xy -0.4953 -0.2032) (xy 0.4953 -0.2032) (xy 0.4953 1.6002) (xy -0.4953 1.6002)
			)
			(stroke
				(width 0)
				(type default)
			)
			(fill no)
			(layer "F.CrtYd")
		)
		(fp_line
			(start -0.4953 -0.2032)
			(end 0.4953 -0.2032)
			(stroke
				(width 0.1)
				(type default)
			)
			(layer "F.Fab")
		)
		(fp_line
			(start -0.4953 1.6002)
			(end -0.4953 -0.2032)
			(stroke
				(width 0.1)
				(type default)
			)
			(layer "F.Fab")
		)
		(fp_line
			(start 0.4953 -0.2032)
			(end 0.4953 1.6002)
			(stroke
				(width 0.1)
				(type default)
			)
			(layer "F.Fab")
		)
		(fp_line
			(start 0.4953 1.6002)
			(end -0.4953 1.6002)
			(stroke
				(width 0.1)
				(type default)
			)
			(layer "F.Fab")
		)
		(pad "1" smd rect
			(at 0 0)
			(size 0.762 0.889)
			(layers "F.Cu" "F.Mask" "F.Paste")
			(net "PVDDQ_KLM")
		)
		(pad "2" smd rect
			(at 0 1.397)
			(size 0.762 0.889)
			(layers "F.Cu" "F.Mask" "F.Paste")
			(net "GND")
		)
		(zone
			(layer "F.Cu")
			(hatch none 0.5)
			(connect_pads
				(clearance 0)
			)
			(min_thickness 0.25)
			(keepout
				(tracks not_allowed)
				(vias allowed)
				(pads allowed)
				(copperpour not_allowed)
				(footprints allowed)
			)
			(placement
				(enabled no)
				(sheetname "")
			)
			(fill
				(thermal_gap 0.5)
				(thermal_bridge_width 0.5)
				(island_removal_mode 0)
			)
			(polygon
				(pts
					(xy 100.632768 -84.3153) (xy 101.394768 -84.3153) (xy 101.394768 -83.8073) (xy 100.632768 -83.8073)
				)
			)
		)
	)
	(footprint ""
		(layer "F.Cu")
		(at 253.392432 -149.8092 90)
		(property "Reference" "C5A4"
			(at 1.848866 0.752348 90)
			(unlocked yes)
			(layer "F.SilkS")
			(effects
				(font
					(size 1.27 0.9652)
					(thickness 0.1524)
				)
			)
		)
		(property "Value" ""
			(at 0 0 90)
			(layer "F.Fab")
			(effects
				(font
					(size 1.27 1.27)
				)
			)
		)
		(duplicate_pad_numbers_are_jumpers no)
		(fp_rect
			(start -0.500126 1.598422)
			(end 0.500126 -0.201422)
			(stroke
				(width 0)
				(type default)
			)
			(fill no)
			(layer "F.CrtYd")
		)
		(fp_line
			(start 0.500126 -0.201422)
			(end 0.500126 1.598422)
			(stroke
				(width 0.1)
				(type default)
			)
			(layer "F.Fab")
		)
		(fp_line
			(start -0.500126 -0.201422)
			(end 0.500126 -0.201422)
			(stroke
				(width 0.1)
				(type default)
			)
			(layer "F.Fab")
		)
		(fp_line
			(start 0.500126 1.598422)
			(end -0.500126 1.598422)
			(stroke
				(width 0.1)
				(type default)
			)
			(layer "F.Fab")
		)
		(fp_line
			(start -0.500126 1.598422)
			(end -0.500126 -0.201422)
			(stroke
				(width 0.1)
				(type default)
			)
			(layer "F.Fab")
		)
		(pad "1" smd rect
			(at 0 0)
			(size 0.889 0.9906)
			(layers "F.Cu" "F.Mask" "F.Paste")
			(net "PVDDQ_DEF")
		)
		(pad "2" smd rect
			(at 0 1.397)
			(size 0.889 0.9906)
			(layers "F.Cu" "F.Mask" "F.Paste")
			(net "GND")
		)
		(zone
			(layer "F.Cu")
			(hatch none 0.5)
			(connect_pads
				(clearance 0)
			)
			(min_thickness 0.25)
			(keepout
				(tracks not_allowed)
				(vias allowed)
				(pads allowed)
				(copperpour not_allowed)
				(footprints allowed)
			)
			(placement
				(enabled no)
				(sheetname "")
			)
			(fill
				(thermal_gap 0.5)
				(thermal_bridge_width 0.5)
				(island_removal_mode 0)
			)
			(polygon
				(pts
					(xy 254.344932 -149.3139) (xy 254.344932 -150.3045) (xy 253.836932 -150.3045) (xy 253.836932 -149.3139)
				)
			)
		)
		(zone
			(layer "F.Cu")
			(hatch none 0.5)
			(connect_pads
				(clearance 0)
			)
			(min_thickness 0.25)
			(keepout
				(tracks allowed)
				(vias not_allowed)
				(pads allowed)
				(copperpour not_allowed)
				(footprints allowed)
			)
			(placement
				(enabled no)
				(sheetname "")
			)
			(fill
				(thermal_gap 0.5)
				(thermal_bridge_width 0.5)
				(island_removal_mode 0)
			)
			(polygon
				(pts
					(xy 254.344932 -149.3139) (xy 254.344932 -150.3045) (xy 253.836932 -150.3045) (xy 253.836932 -149.3139)
				)
			)
		)
	)
	(footprint ""
		(layer "F.Cu")
		(at 206.248 -103.505 90)
		(property "Reference" "R4C2"
			(at 0 0 90)
			(layer "F.SilkS")
			(hide yes)
			(effects
				(font
					(size 1.27 1.27)
				)
			)
		)
		(property "Value" ""
			(at 0 0 90)
			(layer "F.Fab")
			(effects
				(font
					(size 1.27 1.27)
				)
			)
		)
		(duplicate_pad_numbers_are_jumpers no)
		(fp_poly
			(pts
				(xy -0.2794 -0.1016) (xy 0.2794 -0.1016) (xy 0.2794 0.9906) (xy -0.2794 0.9906)
			)
			(stroke
				(width 0)
				(type default)
			)
			(fill no)
			(layer "F.CrtYd")
		)
		(fp_line
			(start 0.2794 -0.1016)
			(end -0.2794 -0.1016)
			(stroke
				(width 0.1)
				(type default)
			)
			(layer "F.Fab")
		)
		(fp_line
			(start -0.2794 -0.1016)
			(end -0.2794 0.9906)
			(stroke
				(width 0.1)
				(type default)
			)
			(layer "F.Fab")
		)
		(fp_line
			(start 0.2794 0.9906)
			(end 0.2794 -0.1016)
			(stroke
				(width 0.1)
				(type default)
			)
			(layer "F.Fab")
		)
		(fp_line
			(start -0.2794 0.9906)
			(end 0.2794 0.9906)
			(stroke
				(width 0.1)
				(type default)
			)
			(layer "F.Fab")
		)
		(pad "1" smd rect
			(at 0 0 90)
			(size 0.508 0.508)
			(layers "F.Cu" "F.Mask" "F.Paste")
			(net "VSENSE_PVSA_CPU0_N")
		)
		(pad "2" smd rect
			(at 0 0.889 90)
			(size 0.508 0.508)
			(layers "F.Cu" "F.Mask" "F.Paste")
			(net "VSENSE_PVSA_CPU0_SKT_VRTN")
		)
		(zone
			(layer "F.Cu")
			(hatch none 0.5)
			(connect_pads
				(clearance 0)
			)
			(min_thickness 0.25)
			(keepout
				(tracks allowed)
				(vias not_allowed)
				(pads allowed)
				(copperpour not_allowed)
				(footprints allowed)
			)
			(placement
				(enabled no)
				(sheetname "")
			)
			(fill
				(thermal_gap 0.5)
				(thermal_bridge_width 0.5)
				(island_removal_mode 0)
			)
			(polygon
				(pts
					(xy 206.502 -103.251) (xy 206.502 -103.759) (xy 206.883 -103.759) (xy 206.883 -103.251)
				)
			)
		)
		(zone
			(layer "F.Cu")
			(hatch none 0.5)
			(connect_pads
				(clearance 0)
			)
			(min_thickness 0.25)
			(keepout
				(tracks not_allowed)
				(vias allowed)
				(pads allowed)
				(copperpour not_allowed)
				(footprints allowed)
			)
			(placement
				(enabled no)
				(sheetname "")
			)
			(fill
				(thermal_gap 0.5)
				(thermal_bridge_width 0.5)
				(island_removal_mode 0)
			)
			(polygon
				(pts
					(xy 206.883 -103.251) (xy 206.883 -103.759) (xy 206.502 -103.759) (xy 206.502 -103.251)
				)
			)
		)
	)
	(footprint ""
		(layer "F.Cu")
		(at 385.572 -56.3245)
		(property "Reference" "R7F30"
			(at 0 0 0)
			(layer "F.SilkS")
			(hide yes)
			(effects
				(font
					(size 1.27 1.27)
				)
			)
		)
		(property "Value" ""
			(at 0 0 0)
			(layer "F.Fab")
			(effects
				(font
					(size 1.27 1.27)
				)
			)
		)
		(duplicate_pad_numbers_are_jumpers no)
		(fp_poly
			(pts
				(xy -0.2794 -0.1016) (xy 0.2794 -0.1016) (xy 0.2794 0.9906) (xy -0.2794 0.9906)
			)
			(stroke
				(width 0)
				(type default)
			)
			(fill no)
			(layer "F.CrtYd")
		)
		(fp_line
			(start -0.2794 -0.1016)
			(end -0.2794 0.9906)
			(stroke
				(width 0.1)
				(type default)
			)
			(layer "F.Fab")
		)
		(fp_line
			(start -0.2794 0.9906)
			(end 0.2794 0.9906)
			(stroke
				(width 0.1)
				(type default)
			)
			(layer "F.Fab")
		)
		(fp_line
			(start 0.2794 -0.1016)
			(end -0.2794 -0.1016)
			(stroke
				(width 0.1)
				(type default)
			)
			(layer "F.Fab")
		)
		(fp_line
			(start 0.2794 0.9906)
			(end 0.2794 -0.1016)
			(stroke
				(width 0.1)
				(type default)
			)
			(layer "F.Fab")
		)
		(pad "1" smd rect
			(at 0 0)
			(size 0.508 0.508)
			(layers "F.Cu" "F.Mask" "F.Paste")
			(net "PU_BIOS_SPI_WP0_N")
		)
		(pad "2" smd rect
			(at 0 0.889)
			(size 0.508 0.508)
			(layers "F.Cu" "F.Mask" "F.Paste")
			(net "GND")
		)
		(zone
			(layer "F.Cu")
			(hatch none 0.5)
			(connect_pads
				(clearance 0)
			)
			(min_thickness 0.25)
			(keepout
				(tracks allowed)
				(vias not_allowed)
				(pads allowed)
				(copperpour not_allowed)
				(footprints allowed)
			)
			(placement
				(enabled no)
				(sheetname "")
			)
			(fill
				(thermal_gap 0.5)
				(thermal_bridge_width 0.5)
				(island_removal_mode 0)
			)
			(polygon
				(pts
					(xy 385.318 -56.0705) (xy 385.826 -56.0705) (xy 385.826 -55.6895) (xy 385.318 -55.6895)
				)
			)
		)
		(zone
			(layer "F.Cu")
			(hatch none 0.5)
			(connect_pads
				(clearance 0)
			)
			(min_thickness 0.25)
			(keepout
				(tracks not_allowed)
				(vias allowed)
				(pads allowed)
				(copperpour not_allowed)
				(footprints allowed)
			)
			(placement
				(enabled no)
				(sheetname "")
			)
			(fill
				(thermal_gap 0.5)
				(thermal_bridge_width 0.5)
				(island_removal_mode 0)
			)
			(polygon
				(pts
					(xy 385.318 -55.6895) (xy 385.826 -55.6895) (xy 385.826 -56.0705) (xy 385.318 -56.0705)
				)
			)
		)
	)
	(footprint ""
		(layer "F.Cu")
		(at 15.24 -86.741 180)
		(property "Reference" "R1D7"
			(at 0 0 180)
			(layer "F.SilkS")
			(hide yes)
			(effects
				(font
					(size 1.27 1.27)
				)
			)
		)
		(property "Value" ""
			(at 0 0 180)
			(layer "F.Fab")
			(effects
				(font
					(size 1.27 1.27)
				)
			)
		)
		(duplicate_pad_numbers_are_jumpers no)
		(fp_rect
			(start 0.2794 -0.1016)
			(end -0.2794 0.9906)
			(stroke
				(width 0)
				(type default)
			)
			(fill no)
			(layer "F.CrtYd")
		)
		(fp_line
			(start 0.2794 0.9906)
			(end 0.2794 -0.1016)
			(stroke
				(width 0.1)
				(type default)
			)
			(layer "F.Fab")
		)
		(fp_line
			(start 0.2794 -0.1016)
			(end -0.2794 -0.1016)
			(stroke
				(width 0.1)
				(type default)
			)
			(layer "F.Fab")
		)
		(fp_line
			(start -0.2794 0.9906)
			(end 0.2794 0.9906)
			(stroke
				(width 0.1)
				(type default)
			)
			(layer "F.Fab")
		)
		(fp_line
			(start -0.2794 -0.1016)
			(end -0.2794 0.9906)
			(stroke
				(width 0.1)
				(type default)
			)
			(layer "F.Fab")
		)
		(pad "1" smd rect
			(at 0 0 180)
			(size 0.508 0.508)
			(layers "F.Cu" "F.Mask" "F.Paste")
			(net "P3V3_STBY")
		)
		(pad "2" smd rect
			(at 0 0.889 180)
			(size 0.508 0.508)
			(layers "F.Cu" "F.Mask" "F.Paste")
			(net "FM_PVCCIN_CPU1_PWR_IN_ALERT_N")
		)
		(zone
			(layer "F.Cu")
			(hatch none 0.5)
			(connect_pads
				(clearance 0)
			)
			(min_thickness 0.25)
			(keepout
				(tracks not_allowed)
				(vias allowed)
				(pads allowed)
				(copperpour not_allowed)
				(footprints allowed)
			)
			(placement
				(enabled no)
				(sheetname "")
			)
			(fill
				(thermal_gap 0.5)
				(thermal_bridge_width 0.5)
				(island_removal_mode 0)
			)
			(polygon
				(pts
					(xy 14.986 -86.995) (xy 15.494 -86.995) (xy 15.494 -87.376) (xy 14.986 -87.376)
				)
			)
		)
		(zone
			(layer "F.Cu")
			(hatch none 0.5)
			(connect_pads
				(clearance 0)
			)
			(min_thickness 0.25)
			(keepout
				(tracks allowed)
				(vias not_allowed)
				(pads allowed)
				(copperpour not_allowed)
				(footprints allowed)
			)
			(placement
				(enabled no)
				(sheetname "")
			)
			(fill
				(thermal_gap 0.5)
				(thermal_bridge_width 0.5)
				(island_removal_mode 0)
			)
			(polygon
				(pts
					(xy 14.986 -86.995) (xy 15.494 -86.995) (xy 15.494 -87.376) (xy 14.986 -87.376)
				)
			)
		)
	)
	(footprint ""
		(layer "F.Cu")
		(at 340.38286 -2.02438 90)
		(property "Reference" "CT53"
			(at -0.8382 -0.67818 90)
			(unlocked yes)
			(layer "F.SilkS")
			(effects
				(font
					(size 0.4064 0.254)
					(thickness 0.1524)
				)
				(justify left)
			)
		)
		(property "Value" ""
			(at 0 0 90)
			(layer "F.Fab")
			(effects
				(font
					(size 1.27 1.27)
				)
			)
		)
		(duplicate_pad_numbers_are_jumpers no)
		(fp_poly
			(pts
				(xy 0.3048 -0.1016) (xy 0.3048 0.9906) (xy -0.3048 0.9906) (xy -0.3048 -0.1016)
			)
			(stroke
				(width 0)
				(type default)
			)
			(fill no)
			(layer "F.CrtYd")
		)
		(fp_line
			(start 0.3048 -0.1016)
			(end -0.3048 -0.1016)
			(stroke
				(width 0.1)
				(type default)
			)
			(layer "F.Fab")
		)
		(fp_line
			(start -0.3048 -0.1016)
			(end -0.3048 0.9906)
			(stroke
				(width 0.1)
				(type default)
			)
			(layer "F.Fab")
		)
		(fp_line
			(start 0.3048 0.9906)
			(end 0.3048 -0.1016)
			(stroke
				(width 0.1)
				(type default)
			)
			(layer "F.Fab")
		)
		(fp_line
			(start -0.3048 0.9906)
			(end 0.3048 0.9906)
			(stroke
				(width 0.1)
				(type default)
			)
			(layer "F.Fab")
		)
		(pad "1" smd rect
			(at 0 0 90)
			(size 0.508 0.508)
			(layers "F.Cu" "F.Mask" "F.Paste")
			(net "VR_PVDDQ_ABC_PH2_SW")
		)
		(pad "2" smd rect
			(at 0 0.889 90)
			(size 0.508 0.508)
			(layers "F.Cu" "F.Mask" "F.Paste")
			(net "VR_PVDDQ_ABC_PH2_SW_RC")
		)
		(zone
			(layer "F.Cu")
			(hatch none 0.5)
			(connect_pads
				(clearance 0)
			)
			(min_thickness 0.25)
			(keepout
				(tracks allowed)
				(vias not_allowed)
				(pads allowed)
				(copperpour not_allowed)
				(footprints allowed)
			)
			(placement
				(enabled no)
				(sheetname "")
			)
			(fill
				(thermal_gap 0.5)
				(thermal_bridge_width 0.5)
				(island_removal_mode 0)
			)
			(polygon
				(pts
					(xy 340.63686 -1.77038) (xy 340.63686 -2.27838) (xy 341.01786 -2.27838) (xy 341.01786 -1.77038)
				)
			)
		)
		(zone
			(layer "F.Cu")
			(hatch none 0.5)
			(connect_pads
				(clearance 0)
			)
			(min_thickness 0.25)
			(keepout
				(tracks not_allowed)
				(vias allowed)
				(pads allowed)
				(copperpour not_allowed)
				(footprints allowed)
			)
			(placement
				(enabled no)
				(sheetname "")
			)
			(fill
				(thermal_gap 0.5)
				(thermal_bridge_width 0.5)
				(island_removal_mode 0)
			)
			(polygon
				(pts
					(xy 341.01786 -1.77038) (xy 341.01786 -2.27838) (xy 340.63686 -2.27838) (xy 340.63686 -1.77038)
				)
			)
		)
	)
	(footprint ""
		(layer "F.Cu")
		(at 289.222434 -77.449934 180)
		(property "Reference" "XRU1"
			(at -17.990566 32.886396 0)
			(unlocked yes)
			(layer "F.SilkS")
			(effects
				(font
					(size 0.7874 0.5842)
					(thickness 0.1524)
				)
				(justify left)
			)
		)
		(property "Value" ""
			(at 0 0 180)
			(layer "F.Fab")
			(effects
				(font
					(size 1.27 1.27)
				)
			)
		)
		(duplicate_pad_numbers_are_jumpers no)
		(fp_line
			(start 19.221958 -10.649966)
			(end 19.221958 -29.399992)
			(stroke
				(width 0.1524)
				(type default)
			)
			(layer "F.SilkS")
		)
		(fp_line
			(start 19.221958 -29.399992)
			(end 18.62201 -29.399992)
			(stroke
				(width 0.1524)
				(type default)
			)
			(layer "F.SilkS")
		)
		(fp_line
			(start 18.62201 28.599892)
			(end 18.62201 8.850122)
			(stroke
				(width 0.1524)
				(type default)
			)
			(layer "F.SilkS")
		)
		(fp_line
			(start 18.62201 27.599894)
			(end 18.62201 8.850122)
			(stroke
				(width 0.1524)
				(type default)
			)
			(layer "F.SilkS")
		)
		(fp_line
			(start 18.62201 8.850122)
			(end 12.761976 8.850122)
			(stroke
				(width 0.1524)
				(type default)
			)
			(layer "F.SilkS")
		)
		(fp_line
			(start 18.62201 8.850122)
			(end 12.761976 8.850122)
			(stroke
				(width 0.1524)
				(type default)
			)
			(layer "F.SilkS")
		)
		(fp_line
			(start 18.62201 -29.399992)
			(end 18.62201 -30.39999)
			(stroke
				(width 0.1524)
				(type default)
			)
			(layer "F.SilkS")
		)
		(fp_line
			(start 18.62201 -30.39999)
			(end 17.622012 -30.39999)
			(stroke
				(width 0.1524)
				(type default)
			)
			(layer "F.SilkS")
		)
		(fp_line
			(start 17.622012 28.599892)
			(end 18.62201 28.599892)
			(stroke
				(width 0.1524)
				(type default)
			)
			(layer "F.SilkS")
		)
		(fp_line
			(start 17.622012 27.599894)
			(end 17.622012 28.599892)
			(stroke
				(width 0.1524)
				(type default)
			)
			(layer "F.SilkS")
		)
		(fp_line
			(start 17.622012 -29.399992)
			(end -14.777974 -29.399992)
			(stroke
				(width 0.1524)
				(type default)
			)
			(layer "F.SilkS")
		)
		(fp_line
			(start 17.622012 -30.39999)
			(end 17.622012 -29.399992)
			(stroke
				(width 0.1524)
				(type default)
			)
			(layer "F.SilkS")
		)
		(fp_line
			(start 12.761976 8.850122)
			(end 6.171946 4.890008)
			(stroke
				(width 0.1524)
				(type default)
			)
			(layer "F.SilkS")
		)
		(fp_line
			(start 12.761976 8.850122)
			(end 6.171946 4.890008)
			(stroke
				(width 0.1524)
				(type default)
			)
			(layer "F.SilkS")
		)
		(fp_line
			(start 12.761976 -10.649966)
			(end 19.221958 -10.649966)
			(stroke
				(width 0.1524)
				(type default)
			)
			(layer "F.SilkS")
		)
		(fp_line
			(start 12.761976 -10.649966)
			(end 19.221958 -10.649966)
			(stroke
				(width 0.1524)
				(type default)
			)
			(layer "F.SilkS")
		)
		(fp_line
			(start 6.171946 4.890008)
			(end 6.171946 -6.690106)
			(stroke
				(width 0.1524)
				(type default)
			)
			(layer "F.SilkS")
		)
		(fp_line
			(start 6.171946 4.890008)
			(end 6.171946 -6.690106)
			(stroke
				(width 0.1524)
				(type default)
			)
			(layer "F.SilkS")
		)
		(fp_line
			(start 6.171946 -6.690106)
			(end 12.761976 -10.649966)
			(stroke
				(width 0.1524)
				(type default)
			)
			(layer "F.SilkS")
		)
		(fp_line
			(start 6.171946 -6.690106)
			(end 12.761976 -10.649966)
			(stroke
				(width 0.1524)
				(type default)
			)
			(layer "F.SilkS")
		)
		(fp_line
			(start -14.777974 30.150054)
			(end -14.777974 27.599894)
			(stroke
				(width 0.1524)
				(type default)
			)
			(layer "F.SilkS")
		)
		(fp_line
			(start -14.777974 27.599894)
			(end 17.622012 27.599894)
			(stroke
				(width 0.1524)
				(type default)
			)
			(layer "F.SilkS")
		)
		(fp_line
			(start -14.777974 -29.399992)
			(end -14.777974 -31.949898)
			(stroke
				(width 0.1524)
				(type default)
			)
			(layer "F.SilkS")
		)
		(fp_line
			(start -14.777974 -31.949898)
			(end -21.77796 -31.949898)
			(stroke
				(width 0.1524)
				(type default)
			)
			(layer "F.SilkS")
		)
		(fp_line
			(start -17.777968 2.100072)
			(end -18.278094 2.100072)
			(stroke
				(width 0.1524)
				(type default)
			)
			(layer "F.SilkS")
		)
		(fp_line
			(start -17.777968 -3.899916)
			(end -17.777968 2.100072)
			(stroke
				(width 0.1524)
				(type default)
			)
			(layer "F.SilkS")
		)
		(fp_line
			(start -18.278094 3.599942)
			(end -21.77796 7.100062)
			(stroke
				(width 0.1524)
				(type default)
			)
			(layer "F.SilkS")
		)
		(fp_line
			(start -18.278094 2.100072)
			(end -18.278094 3.599942)
			(stroke
				(width 0.1524)
				(type default)
			)
			(layer "F.SilkS")
		)
		(fp_line
			(start -18.278094 -3.899916)
			(end -17.777968 -3.899916)
			(stroke
				(width 0.1524)
				(type default)
			)
			(layer "F.SilkS")
		)
		(fp_line
			(start -18.278094 -5.40004)
			(end -18.278094 -3.899916)
			(stroke
				(width 0.1524)
				(type default)
			)
			(layer "F.SilkS")
		)
		(fp_line
			(start -21.77796 30.150054)
			(end -14.777974 30.150054)
			(stroke
				(width 0.1524)
				(type default)
			)
			(layer "F.SilkS")
		)
		(fp_line
			(start -21.77796 7.100062)
			(end -21.77796 30.150054)
			(stroke
				(width 0.1524)
				(type default)
			)
			(layer "F.SilkS")
		)
		(fp_line
			(start -21.77796 -8.899906)
			(end -18.278094 -5.40004)
			(stroke
				(width 0.1524)
				(type default)
			)
			(layer "F.SilkS")
		)
		(fp_line
			(start -21.77796 -31.949898)
			(end -21.77796 -8.899906)
			(stroke
				(width 0.1524)
				(type default)
			)
			(layer "F.SilkS")
		)
		(fp_circle
			(center -28.829 -29.215334)
			(end -28.956 -29.215334)
			(stroke
				(width 0.254)
				(type default)
			)
			(fill no)
			(layer "F.SilkS")
		)
		(fp_poly
			(pts
				(xy -21.762212 30.150054) (xy -14.777974 30.150054) (xy -14.777974 27.599894) (xy 17.622012 27.599894)
				(xy 17.622012 28.599892) (xy 18.62201 28.599892) (xy 18.62201 8.850122) (xy 12.761976 8.850122)
				(xy 6.171946 4.890008) (xy 6.171946 -6.690106) (xy 12.761976 -10.649966) (xy 19.221958 -10.649966)
				(xy 19.221958 -29.399992) (xy 18.62201 -29.399992) (xy 18.62201 -30.39999) (xy 17.622012 -30.39999)
				(xy 17.622012 -29.399992) (xy -14.777974 -29.399992) (xy -14.777974 -31.949898) (xy -21.77796 -31.949898)
				(xy -21.77796 -8.899906) (xy -18.278094 -5.40004) (xy -18.278094 -3.899916) (xy -17.777968 -3.899916)
				(xy -17.777968 2.100072) (xy -18.278094 2.100072) (xy -18.278094 3.599942) (xy -21.77796 7.100062)
				(xy -21.77796 15.059406) (xy -20.051776 15.059406) (xy -20.048728 15.001748) (xy -20.04441 14.966442)
				(xy -20.036282 14.912086) (xy -20.02536 14.859762) (xy -20.007326 14.788134) (xy -19.98345 14.720062)
				(xy -19.96821 14.680692) (xy -19.937222 14.614144) (xy -19.910552 14.565376) (xy -19.878294 14.512544)
				(xy -19.833082 14.449044) (xy -19.790918 14.396466) (xy -19.746468 14.348714) (xy -19.70151 14.305026)
				(xy -19.629628 14.236954) (xy -19.548856 14.18336) (xy -19.442684 14.125956) (xy -19.368516 14.092936)
				(xy -19.202654 14.039342) (xy -19.046698 14.018514) (xy -18.893282 14.020546) (xy -18.758662 14.041882)
				(xy -18.615152 14.083792) (xy -18.402554 14.173962) (xy -18.269712 14.279118) (xy -18.178018 14.370558)
				(xy -18.112232 14.437614) (xy -18.027396 14.586204) (xy -17.924272 14.817598) (xy -17.897348 15.018766)
				(xy -17.888458 15.160498) (xy -17.906238 15.300198) (xy -17.959832 15.489936) (xy -18.057114 15.682976)
				(xy -18.231358 15.893034) (xy -18.479008 16.060928) (xy -18.689574 16.13916) (xy -18.864834 16.174466)
				(xy -19.001994 16.17726) (xy -19.118326 16.169894) (xy -19.228816 16.147542) (xy -19.45767 16.08074)
				(xy -19.611086 15.978886) (xy -19.714972 15.893034) (xy -19.798792 15.807182) (xy -19.89709 15.676372)
				(xy -19.983196 15.507716) (xy -20.0279 15.380462) (xy -20.056856 15.181834) (xy -20.051776 15.059914)
				(xy -21.77796 15.059914)
			)
			(stroke
				(width 0)
				(type default)
			)
			(fill no)
			(layer "F.CrtYd")
		)
		(fp_line
			(start -14.777974 30.150054)
			(end -21.77796 30.150054)
			(stroke
				(width 0.1)
				(type default)
			)
			(layer "F.Fab")
		)
		(fp_line
			(start -14.777974 27.420062)
			(end -14.777974 30.150054)
			(stroke
				(width 0.1)
				(type default)
			)
			(layer "F.Fab")
		)
		(fp_line
			(start -14.777974 -29.219906)
			(end -18.840958 -29.219906)
			(stroke
				(width 0.1)
				(type default)
			)
			(layer "F.Fab")
		)
		(fp_line
			(start -14.777974 -31.949898)
			(end -14.777974 -29.219906)
			(stroke
				(width 0.1)
				(type default)
			)
			(layer "F.Fab")
		)
		(fp_line
			(start -18.840958 27.420062)
			(end -14.777974 27.420062)
			(stroke
				(width 0.1)
				(type default)
			)
			(layer "F.Fab")
		)
		(fp_line
			(start -18.840958 22.649942)
			(end -18.840958 27.420062)
			(stroke
				(width 0.1)
				(type default)
			)
			(layer "F.Fab")
		)
		(fp_line
			(start -18.840958 22.649942)
			(end -19.777964 22.649942)
			(stroke
				(width 0.1)
				(type default)
			)
			(layer "F.Fab")
		)
		(fp_line
			(start -18.840958 -24.45004)
			(end -19.777964 -24.45004)
			(stroke
				(width 0.1)
				(type default)
			)
			(layer "F.Fab")
		)
		(fp_line
			(start -18.840958 -29.219906)
			(end -18.840958 -24.45004)
			(stroke
				(width 0.1)
				(type default)
			)
			(layer "F.Fab")
		)
		(fp_line
			(start -19.777964 22.649942)
			(end -18.840958 22.649942)
			(stroke
				(width 0.1)
				(type default)
			)
			(layer "F.Fab")
		)
		(fp_line
			(start -19.777964 22.649942)
			(end -19.777964 15.81658)
			(stroke
				(width 0.1)
				(type default)
			)
			(layer "F.Fab")
		)
		(fp_line
			(start -19.777964 15.81658)
			(end -19.777964 22.649942)
			(stroke
				(width 0.1)
				(type default)
			)
			(layer "F.Fab")
		)
		(fp_line
			(start -19.777964 5.100066)
			(end -19.777964 14.383258)
			(stroke
				(width 0.1)
				(type default)
			)
			(layer "F.Fab")
		)
		(fp_line
			(start -19.777964 -6.89991)
			(end -21.77796 -8.899906)
			(stroke
				(width 0.1)
				(type default)
			)
			(layer "F.Fab")
		)
		(fp_line
			(start -19.777964 -24.45004)
			(end -19.777964 -6.89991)
			(stroke
				(width 0.1)
				(type default)
			)
			(layer "F.Fab")
		)
		(fp_line
			(start -21.77796 30.150054)
			(end -21.77796 7.100062)
			(stroke
				(width 0.1)
				(type default)
			)
			(layer "F.Fab")
		)
		(fp_line
			(start -21.77796 7.100062)
			(end -19.777964 5.100066)
			(stroke
				(width 0.1)
				(type default)
			)
			(layer "F.Fab")
		)
		(fp_line
			(start -21.77796 -8.899906)
			(end -21.77796 -31.949898)
			(stroke
				(width 0.1)
				(type default)
			)
			(layer "F.Fab")
		)
		(fp_line
			(start -21.77796 -31.949898)
			(end -14.777974 -31.949898)
			(stroke
				(width 0.1)
				(type default)
			)
			(layer "F.Fab")
		)
		(fp_arc
			(start -19.777964 15.81658)
			(mid -20.051913 15.099951)
			(end -19.777964 14.383258)
			(stroke
				(width 0.1)
				(type default)
			)
			(layer "F.Fab")
		)
	)
	(footprint ""
		(layer "F.Cu")
		(at 487.800904 -116.993162 -90)
		(property "Reference" "J9B3"
			(at -2.227072 26.281888 0)
			(unlocked yes)
			(layer "F.SilkS")
			(effects
				(font
					(size 0.7874 0.5842)
					(thickness 0.1524)
				)
			)
		)
		(property "Value" ""
			(at 0 0 270)
			(layer "F.Fab")
			(effects
				(font
					(size 1.27 1.27)
				)
			)
		)
		(duplicate_pad_numbers_are_jumpers no)
		(fp_line
			(start -1.081278 50.574956)
			(end -1.081278 48.075088)
			(stroke
				(width 0.1524)
				(type default)
			)
			(layer "F.SilkS")
		)
		(fp_line
			(start 1.418844 50.574956)
			(end -1.081278 50.574956)
			(stroke
				(width 0.1524)
				(type default)
			)
			(layer "F.SilkS")
		)
		(fp_line
			(start 5.868924 50.574956)
			(end 3.368802 50.574956)
			(stroke
				(width 0.1524)
				(type default)
			)
			(layer "F.SilkS")
		)
		(fp_line
			(start 5.868924 48.075088)
			(end 5.868924 50.574956)
			(stroke
				(width 0.1524)
				(type default)
			)
			(layer "F.SilkS")
		)
		(fp_line
			(start -1.081278 -0.87503)
			(end -1.081278 -3.374898)
			(stroke
				(width 0.1524)
				(type default)
			)
			(layer "F.SilkS")
		)
		(fp_line
			(start -1.081278 -3.374898)
			(end 1.418844 -3.374898)
			(stroke
				(width 0.1524)
				(type default)
			)
			(layer "F.SilkS")
		)
		(fp_line
			(start 3.368802 -3.374898)
			(end 5.868924 -3.374898)
			(stroke
				(width 0.1524)
				(type default)
			)
			(layer "F.SilkS")
		)
		(fp_line
			(start 5.868924 -3.374898)
			(end 5.868924 -0.87503)
			(stroke
				(width 0.1524)
				(type default)
			)
			(layer "F.SilkS")
		)
		(fp_poly
			(pts
				(xy -2.72161 -0.368046) (xy -2.72161 0.647954) (xy -1.45161 0.139954)
			)
			(stroke
				(width 0)
				(type default)
			)
			(fill yes)
			(layer "F.SilkS")
		)
		(fp_poly
			(pts
				(xy -1.081278 -3.374898) (xy -1.081278 50.574956) (xy 5.868924 50.574956) (xy 5.868924 -3.374898)
			)
			(stroke
				(width 0)
				(type default)
			)
			(fill no)
			(layer "F.CrtYd")
		)
		(fp_line
			(start -1.081278 50.574956)
			(end -1.081278 -3.374898)
			(stroke
				(width 0.1)
				(type default)
			)
			(layer "F.Fab")
		)
		(fp_line
			(start 5.868924 50.574956)
			(end -1.081278 50.574956)
			(stroke
				(width 0.1)
				(type default)
			)
			(layer "F.Fab")
		)
		(fp_line
			(start -1.081278 -3.374898)
			(end 5.868924 -3.374898)
			(stroke
				(width 0.1)
				(type default)
			)
			(layer "F.Fab")
		)
		(fp_line
			(start 5.868924 -3.374898)
			(end 5.868924 50.574956)
			(stroke
				(width 0.1)
				(type default)
			)
			(layer "F.Fab")
		)
		(fp_poly
			(pts
				(xy -2.97561 -0.495046) (xy -2.97561 0.520954) (xy -1.70561 0.012954)
			)
			(stroke
				(width 0)
				(type default)
			)
			(fill yes)
			(layer "F.Fab")
		)
		(fp_text user "120"
			(at 6.538468 50.857404 0)
			(unlocked yes)
			(layer "F.SilkS")
			(effects
				(font
					(size 0.7874 0.5842)
					(thickness 0.1524)
				)
				(justify left)
			)
		)
		(fp_text user "119"
			(at -1.71323 50.851816 0)
			(unlocked yes)
			(layer "F.SilkS")
			(effects
				(font
					(size 0.7874 0.5842)
					(thickness 0.1524)
				)
				(justify left)
			)
		)
		(fp_text user "2"
			(at 5.413248 -3.705352 0)
			(unlocked yes)
			(layer "F.SilkS")
			(effects
				(font
					(size 0.7874 0.5842)
					(thickness 0.1524)
				)
				(justify left)
			)
		)
		(fp_text user "119"
			(at -1.716786 50.857404 0)
			(unlocked yes)
			(layer "F.Fab")
			(effects
				(font
					(size 0.7874 0.5842)
					(thickness 0.1524)
				)
				(justify left)
			)
		)
		(fp_text user "120"
			(at 6.538214 50.857404 0)
			(unlocked yes)
			(layer "F.Fab")
			(effects
				(font
					(size 0.7874 0.5842)
					(thickness 0.1524)
				)
				(justify left)
			)
		)
		(fp_text user "2"
			(at 5.412232 -3.704844 0)
			(unlocked yes)
			(layer "F.Fab")
			(effects
				(font
					(size 0.7874 0.5842)
					(thickness 0.1524)
				)
				(justify left)
			)
		)
		(pad "" np_thru_hole circle
			(at 2.393696 -2.500122 270)
			(size 0.254 0.254)
			(drill 1.1938)
			(layers "*.Cu" "*.Mask")
			(clearance 0.7874)
			(thermal_gap 0.7874)
		)
		(pad "" np_thru_hole circle
			(at 2.393696 49.699926 270)
			(size 0.254 0.254)
			(drill 0.8128)
			(layers "*.Cu" "*.Mask")
			(clearance 0.5969)
			(thermal_gap 0.5969)
		)
		(pad "1" smd rect
			(at 0 0 270)
			(size 2.3876 0.508)
			(layers "F.Cu" "F.Mask" "F.Paste")
			(net "FM_MEZZA_PRSNT1_N")
		)
		(pad "2" smd rect
			(at 4.787646 0 270)
			(size 2.3876 0.508)
			(layers "F.Cu" "F.Mask" "F.Paste")
			(net "P12V_STBY")
		)
		(pad "3" smd rect
			(at 0 0.8001 270)
			(size 2.3876 0.508)
			(layers "F.Cu" "F.Mask" "F.Paste")
			(net "P5V_STBY")
		)
		(pad "4" smd rect
			(at 4.787646 0.8001 270)
			(size 2.3876 0.508)
			(layers "F.Cu" "F.Mask" "F.Paste")
			(net "P12V_STBY")
		)
		(pad "5" smd rect
			(at 0 1.599946 270)
			(size 2.3876 0.508)
			(layers "F.Cu" "F.Mask" "F.Paste")
			(net "P5V_STBY")
		)
		(pad "6" smd rect
			(at 4.787646 1.599946 270)
			(size 2.3876 0.508)
			(layers "F.Cu" "F.Mask" "F.Paste")
			(net "P12V_STBY")
		)
		(pad "7" smd rect
			(at 0 2.400046 270)
			(size 2.3876 0.508)
			(layers "F.Cu" "F.Mask" "F.Paste")
			(net "P5V_STBY")
		)
		(pad "8" smd rect
			(at 4.787646 2.400046 270)
			(size 2.3876 0.508)
			(layers "F.Cu" "F.Mask" "F.Paste")
			(net "GND")
		)
		(pad "9" smd rect
			(at 0 3.199892 270)
			(size 2.3876 0.508)
			(layers "F.Cu" "F.Mask" "F.Paste")
			(net "GND")
		)
		(pad "10" smd rect
			(at 4.787646 3.199892 270)
			(size 2.3876 0.508)
			(layers "F.Cu" "F.Mask" "F.Paste")
			(net "GND")
		)
		(pad "11" smd rect
			(at 0 3.999992 270)
			(size 2.3876 0.508)
			(layers "F.Cu" "F.Mask" "F.Paste")
			(net "GND")
		)
		(pad "12" smd rect
			(at 4.787646 3.999992 270)
			(size 2.3876 0.508)
			(layers "F.Cu" "F.Mask" "F.Paste")
			(net "P3V3_STBY")
		)
		(pad "13" smd rect
			(at 0 4.800092 270)
			(size 2.3876 0.508)
			(layers "F.Cu" "F.Mask" "F.Paste")
			(net "P3V3_STBY")
		)
		(pad "14" smd rect
			(at 4.787646 4.800092 270)
			(size 2.3876 0.508)
			(layers "F.Cu" "F.Mask" "F.Paste")
			(net "GND")
		)
		(pad "15" smd rect
			(at 0 5.599938 270)
			(size 2.3876 0.508)
			(layers "F.Cu" "F.Mask" "F.Paste")
			(net "GND")
		)
		(pad "16" smd rect
			(at 4.787646 5.599938 270)
			(size 2.3876 0.508)
			(layers "F.Cu" "F.Mask" "F.Paste")
			(net "GND")
		)
		(pad "17" smd rect
			(at 0 6.400038 270)
			(size 2.3876 0.508)
			(layers "F.Cu" "F.Mask" "F.Paste")
			(net "GND")
		)
		(pad "18" smd rect
			(at 4.787646 6.400038 270)
			(size 2.3876 0.508)
			(layers "F.Cu" "F.Mask" "F.Paste")
			(net "P3V3")
		)
		(pad "19" smd rect
			(at 0 7.199884 270)
			(size 2.3876 0.508)
			(layers "F.Cu" "F.Mask" "F.Paste")
			(net "P3V3")
		)
		(pad "20" smd rect
			(at 4.787646 7.199884 270)
			(size 2.3876 0.508)
			(layers "F.Cu" "F.Mask" "F.Paste")
			(net "P3V3")
		)
		(pad "21" smd rect
			(at 0 7.999984 270)
			(size 2.3876 0.508)
			(layers "F.Cu" "F.Mask" "F.Paste")
			(net "P3V3")
		)
		(pad "22" smd rect
			(at 4.787646 7.999984 270)
			(size 2.3876 0.508)
			(layers "F.Cu" "F.Mask" "F.Paste")
			(net "P3V3")
		)
		(pad "23" smd rect
			(at 0 8.800084 270)
			(size 2.3876 0.508)
			(layers "F.Cu" "F.Mask" "F.Paste")
			(net "P3V3")
		)
		(pad "24" smd rect
			(at 4.787646 8.800084 270)
			(size 2.3876 0.508)
			(layers "F.Cu" "F.Mask" "F.Paste")
			(net "P3V3")
		)
		(pad "25" smd rect
			(at 0 9.59993 270)
			(size 2.3876 0.508)
			(layers "F.Cu" "F.Mask" "F.Paste")
			(net "P3V3")
		)
		(pad "26" smd rect
			(at 4.787646 9.59993 270)
			(size 2.3876 0.508)
			(layers "F.Cu" "F.Mask" "F.Paste")
			(net "GND")
		)
		(pad "27" smd rect
			(at 0 10.40003 270)
			(size 2.3876 0.508)
			(layers "F.Cu" "F.Mask" "F.Paste")
			(net "RMII_BMC_OCP_CRSDV_R")
		)
		(pad "28" smd rect
			(at 4.787646 10.40003 270)
			(size 2.3876 0.508)
			(layers "F.Cu" "F.Mask" "F.Paste")
			(net "IRQ_MEZZ_LAN_ALERT_N")
		)
		(pad "29" smd rect
			(at 0 11.199876 270)
			(size 2.3876 0.508)
			(layers "F.Cu" "F.Mask" "F.Paste")
			(net "CLK_50M_CKMNG_OCP")
		)
		(pad "30" smd rect
			(at 4.787646 11.199876 270)
			(size 2.3876 0.508)
			(layers "F.Cu" "F.Mask" "F.Paste")
			(net "SMB_OCP_FRU_STBY_LVC3_SCL")
		)
		(pad "31" smd rect
			(at 0 11.999976 270)
			(size 2.3876 0.508)
			(layers "F.Cu" "F.Mask" "F.Paste")
			(net "RMII_BMC_OCP_TXEN")
		)
		(pad "32" smd rect
			(at 4.787646 11.999976 270)
			(size 2.3876 0.508)
			(layers "F.Cu" "F.Mask" "F.Paste")
			(net "SMB_OCP_FRU_STBY_LVC3_SDA")
		)
		(pad "33" smd rect
			(at 0 12.800076 270)
			(size 2.3876 0.508)
			(layers "F.Cu" "F.Mask" "F.Paste")
			(net "RST_PCIE_CPU_DEV0_R_N")
		)
		(pad "34" smd rect
			(at 4.787646 12.800076 270)
			(size 2.3876 0.508)
			(layers "F.Cu" "F.Mask" "F.Paste")
			(net "FM_PE_OCP_WAKE_N")
		)
		(pad "35" smd rect
			(at 0 13.599922 270)
			(size 2.3876 0.508)
			(layers "F.Cu" "F.Mask" "F.Paste")
			(net "SMB_OCP_LAN_STBY_LVC3_SCL")
		)
		(pad "36" smd rect
			(at 4.787646 13.599922 270)
			(size 2.3876 0.508)
			(layers "F.Cu" "F.Mask" "F.Paste")
			(net "RMII_BMC_OCP_RXER_R")
		)
		(pad "37" smd rect
			(at 0 14.400022 270)
			(size 2.3876 0.508)
			(layers "F.Cu" "F.Mask" "F.Paste")
			(net "SMB_OCP_LAN_STBY_LVC3_SDA")
		)
		(pad "38" smd rect
			(at 4.787646 14.400022 270)
			(size 2.3876 0.508)
			(layers "F.Cu" "F.Mask" "F.Paste")
			(net "GND")
		)
		(pad "39" smd rect
			(at 0 15.200122 270)
			(size 2.3876 0.508)
			(layers "F.Cu" "F.Mask" "F.Paste")
			(net "GND")
		)
		(pad "40" smd rect
			(at 4.787646 15.200122 270)
			(size 2.3876 0.508)
			(layers "F.Cu" "F.Mask" "F.Paste")
			(net "RMII_BMC_OCP_TXD0")
		)
		(pad "41" smd rect
			(at 0 15.999968 270)
			(size 2.3876 0.508)
			(layers "F.Cu" "F.Mask" "F.Paste")
			(net "GND")
		)
		(pad "42" smd rect
			(at 4.787646 15.999968 270)
			(size 2.3876 0.508)
			(layers "F.Cu" "F.Mask" "F.Paste")
			(net "RMII_BMC_OCP_TXD1")
		)
		(pad "43" smd rect
			(at 0 16.800068 270)
			(size 2.3876 0.508)
			(layers "F.Cu" "F.Mask" "F.Paste")
			(net "RMII_BMC_OCP_RXD0_R")
		)
		(pad "44" smd rect
			(at 4.787646 16.800068 270)
			(size 2.3876 0.508)
			(layers "F.Cu" "F.Mask" "F.Paste")
			(net "GND")
		)
		(pad "45" smd rect
			(at 0 17.599914 270)
			(size 2.3876 0.508)
			(layers "F.Cu" "F.Mask" "F.Paste")
			(net "RMII_BMC_OCP_RXD1_R")
		)
		(pad "46" smd rect
			(at 4.787646 17.599914 270)
			(size 2.3876 0.508)
			(layers "F.Cu" "F.Mask" "F.Paste")
			(net "GND")
		)
		(pad "47" smd rect
			(at 0 18.400014 270)
			(size 2.3876 0.508)
			(layers "F.Cu" "F.Mask" "F.Paste")
			(net "GND")
		)
		(pad "48" smd rect
			(at 4.787646 18.400014 270)
			(size 2.3876 0.508)
			(layers "F.Cu" "F.Mask" "F.Paste")
			(net "CLK_100M_MEZZ1_DP")
		)
		(pad "49" smd rect
			(at 0 19.200114 270)
			(size 2.3876 0.508)
			(layers "F.Cu" "F.Mask" "F.Paste")
			(net "GND")
		)
		(pad "50" smd rect
			(at 4.787646 19.200114 270)
			(size 2.3876 0.508)
			(layers "F.Cu" "F.Mask" "F.Paste")
			(net "CLK_100M_MEZZ1_DN")
		)
		(pad "51" smd rect
			(at 0 19.99996 270)
			(size 2.3876 0.508)
			(layers "F.Cu" "F.Mask" "F.Paste")
			(net "CLK_100M_MEZZ2_DP")
		)
		(pad "52" smd rect
			(at 4.787646 19.99996 270)
			(size 2.3876 0.508)
			(layers "F.Cu" "F.Mask" "F.Paste")
			(net "GND")
		)
		(pad "53" smd rect
			(at 0 20.80006 270)
			(size 2.3876 0.508)
			(layers "F.Cu" "F.Mask" "F.Paste")
			(net "CLK_100M_MEZZ2_DN")
		)
		(pad "54" smd rect
			(at 4.787646 20.80006 270)
			(size 2.3876 0.508)
			(layers "F.Cu" "F.Mask" "F.Paste")
			(net "GND")
		)
		(pad "55" smd rect
			(at 0 21.599906 270)
			(size 2.3876 0.508)
			(layers "F.Cu" "F.Mask" "F.Paste")
			(net "GND")
		)
		(pad "56" smd rect
			(at 4.787646 21.599906 270)
			(size 2.3876 0.508)
			(layers "F.Cu" "F.Mask" "F.Paste")
			(net "P3E_OCP_CPU0_PE3_C_TXP<15>")
		)
		(pad "57" smd rect
			(at 0 22.400006 270)
			(size 2.3876 0.508)
			(layers "F.Cu" "F.Mask" "F.Paste")
			(net "GND")
		)
		(pad "58" smd rect
			(at 4.787646 22.400006 270)
			(size 2.3876 0.508)
			(layers "F.Cu" "F.Mask" "F.Paste")
			(net "P3E_OCP_CPU0_PE3_C_TXN<15>")
		)
		(pad "59" smd rect
			(at 0 23.200106 270)
			(size 2.3876 0.508)
			(layers "F.Cu" "F.Mask" "F.Paste")
			(net "P3E_CPU0_PE3_OCP_RXP<15>")
		)
		(pad "60" smd rect
			(at 4.787646 23.200106 270)
			(size 2.3876 0.508)
			(layers "F.Cu" "F.Mask" "F.Paste")
			(net "GND")
		)
		(pad "61" smd rect
			(at 0 23.999952 270)
			(size 2.3876 0.508)
			(layers "F.Cu" "F.Mask" "F.Paste")
			(net "P3E_CPU0_PE3_OCP_RXN<15>")
		)
		(pad "62" smd rect
			(at 4.787646 23.999952 270)
			(size 2.3876 0.508)
			(layers "F.Cu" "F.Mask" "F.Paste")
			(net "GND")
		)
		(pad "63" smd rect
			(at 0 24.800052 270)
			(size 2.3876 0.508)
			(layers "F.Cu" "F.Mask" "F.Paste")
			(net "GND")
		)
		(pad "64" smd rect
			(at 4.787646 24.800052 270)
			(size 2.3876 0.508)
			(layers "F.Cu" "F.Mask" "F.Paste")
			(net "P3E_OCP_CPU0_PE3_C_TXP<14>")
		)
		(pad "65" smd rect
			(at 0 25.599898 270)
			(size 2.3876 0.508)
			(layers "F.Cu" "F.Mask" "F.Paste")
			(net "GND")
		)
		(pad "66" smd rect
			(at 4.787646 25.599898 270)
			(size 2.3876 0.508)
			(layers "F.Cu" "F.Mask" "F.Paste")
			(net "P3E_OCP_CPU0_PE3_C_TXN<14>")
		)
		(pad "67" smd rect
			(at 0 26.399998 270)
			(size 2.3876 0.508)
			(layers "F.Cu" "F.Mask" "F.Paste")
			(net "P3E_CPU0_PE3_OCP_RXP<14>")
		)
		(pad "68" smd rect
			(at 4.787646 26.399998 270)
			(size 2.3876 0.508)
			(layers "F.Cu" "F.Mask" "F.Paste")
			(net "GND")
		)
		(pad "69" smd rect
			(at 0 27.200098 270)
			(size 2.3876 0.508)
			(layers "F.Cu" "F.Mask" "F.Paste")
			(net "P3E_CPU0_PE3_OCP_RXN<14>")
		)
		(pad "70" smd rect
			(at 4.787646 27.200098 270)
			(size 2.3876 0.508)
			(layers "F.Cu" "F.Mask" "F.Paste")
			(net "GND")
		)
		(pad "71" smd rect
			(at 0 27.999944 270)
			(size 2.3876 0.508)
			(layers "F.Cu" "F.Mask" "F.Paste")
			(net "GND")
		)
		(pad "72" smd rect
			(at 4.787646 27.999944 270)
			(size 2.3876 0.508)
			(layers "F.Cu" "F.Mask" "F.Paste")
			(net "P3E_OCP_CPU0_PE3_C_TXP<13>")
		)
		(pad "73" smd rect
			(at 0 28.800044 270)
			(size 2.3876 0.508)
			(layers "F.Cu" "F.Mask" "F.Paste")
			(net "GND")
		)
		(pad "74" smd rect
			(at 4.787646 28.800044 270)
			(size 2.3876 0.508)
			(layers "F.Cu" "F.Mask" "F.Paste")
			(net "P3E_OCP_CPU0_PE3_C_TXN<13>")
		)
		(pad "75" smd rect
			(at 0 29.59989 270)
			(size 2.3876 0.508)
			(layers "F.Cu" "F.Mask" "F.Paste")
			(net "P3E_CPU0_PE3_OCP_RXP<13>")
		)
		(pad "76" smd rect
			(at 4.787646 29.59989 270)
			(size 2.3876 0.508)
			(layers "F.Cu" "F.Mask" "F.Paste")
			(net "GND")
		)
		(pad "77" smd rect
			(at 0 30.39999 270)
			(size 2.3876 0.508)
			(layers "F.Cu" "F.Mask" "F.Paste")
			(net "P3E_CPU0_PE3_OCP_RXN<13>")
		)
		(pad "78" smd rect
			(at 4.787646 30.39999 270)
			(size 2.3876 0.508)
			(layers "F.Cu" "F.Mask" "F.Paste")
			(net "GND")
		)
		(pad "79" smd rect
			(at 0 31.20009 270)
			(size 2.3876 0.508)
			(layers "F.Cu" "F.Mask" "F.Paste")
			(net "GND")
		)
		(pad "80" smd rect
			(at 4.787646 31.20009 270)
			(size 2.3876 0.508)
			(layers "F.Cu" "F.Mask" "F.Paste")
			(net "P3E_OCP_CPU0_PE3_C_TXP<12>")
		)
		(pad "81" smd rect
			(at 0 31.999936 270)
			(size 2.3876 0.508)
			(layers "F.Cu" "F.Mask" "F.Paste")
			(net "GND")
		)
		(pad "82" smd rect
			(at 4.787646 31.999936 270)
			(size 2.3876 0.508)
			(layers "F.Cu" "F.Mask" "F.Paste")
			(net "P3E_OCP_CPU0_PE3_C_TXN<12>")
		)
		(pad "83" smd rect
			(at 0 32.800036 270)
			(size 2.3876 0.508)
			(layers "F.Cu" "F.Mask" "F.Paste")
			(net "P3E_CPU0_PE3_OCP_RXP<12>")
		)
		(pad "84" smd rect
			(at 4.787646 32.800036 270)
			(size 2.3876 0.508)
			(layers "F.Cu" "F.Mask" "F.Paste")
			(net "GND")
		)
		(pad "85" smd rect
			(at 0 33.599882 270)
			(size 2.3876 0.508)
			(layers "F.Cu" "F.Mask" "F.Paste")
			(net "P3E_CPU0_PE3_OCP_RXN<12>")
		)
		(pad "86" smd rect
			(at 4.787646 33.599882 270)
			(size 2.3876 0.508)
			(layers "F.Cu" "F.Mask" "F.Paste")
			(net "GND")
		)
		(pad "87" smd rect
			(at 0 34.399982 270)
			(size 2.3876 0.508)
			(layers "F.Cu" "F.Mask" "F.Paste")
			(net "GND")
		)
		(pad "88" smd rect
			(at 4.787646 34.399982 270)
			(size 2.3876 0.508)
			(layers "F.Cu" "F.Mask" "F.Paste")
			(net "P3E_OCP_CPU0_PE3_C_TXP<11>")
		)
		(pad "89" smd rect
			(at 0 35.200082 270)
			(size 2.3876 0.508)
			(layers "F.Cu" "F.Mask" "F.Paste")
			(net "GND")
		)
		(pad "90" smd rect
			(at 4.787646 35.200082 270)
			(size 2.3876 0.508)
			(layers "F.Cu" "F.Mask" "F.Paste")
			(net "P3E_OCP_CPU0_PE3_C_TXN<11>")
		)
		(pad "91" smd rect
			(at 0 35.999928 270)
			(size 2.3876 0.508)
			(layers "F.Cu" "F.Mask" "F.Paste")
			(net "P3E_CPU0_PE3_OCP_RXP<11>")
		)
		(pad "92" smd rect
			(at 4.787646 35.999928 270)
			(size 2.3876 0.508)
			(layers "F.Cu" "F.Mask" "F.Paste")
			(net "GND")
		)
		(pad "93" smd rect
			(at 0 36.800028 270)
			(size 2.3876 0.508)
			(layers "F.Cu" "F.Mask" "F.Paste")
			(net "P3E_CPU0_PE3_OCP_RXN<11>")
		)
		(pad "94" smd rect
			(at 4.787646 36.800028 270)
			(size 2.3876 0.508)
			(layers "F.Cu" "F.Mask" "F.Paste")
			(net "GND")
		)
		(pad "95" smd rect
			(at 0 37.599874 270)
			(size 2.3876 0.508)
			(layers "F.Cu" "F.Mask" "F.Paste")
			(net "GND")
		)
		(pad "96" smd rect
			(at 4.787646 37.599874 270)
			(size 2.3876 0.508)
			(layers "F.Cu" "F.Mask" "F.Paste")
			(net "P3E_OCP_CPU0_PE3_C_TXP<10>")
		)
		(pad "97" smd rect
			(at 0 38.399974 270)
			(size 2.3876 0.508)
			(layers "F.Cu" "F.Mask" "F.Paste")
			(net "GND")
		)
		(pad "98" smd rect
			(at 4.787646 38.399974 270)
			(size 2.3876 0.508)
			(layers "F.Cu" "F.Mask" "F.Paste")
			(net "P3E_OCP_CPU0_PE3_C_TXN<10>")
		)
		(pad "99" smd rect
			(at 0 39.200074 270)
			(size 2.3876 0.508)
			(layers "F.Cu" "F.Mask" "F.Paste")
			(net "P3E_CPU0_PE3_OCP_RXP<10>")
		)
		(pad "100" smd rect
			(at 4.787646 39.200074 270)
			(size 2.3876 0.508)
			(layers "F.Cu" "F.Mask" "F.Paste")
			(net "GND")
		)
		(pad "101" smd rect
			(at 0 39.99992 270)
			(size 2.3876 0.508)
			(layers "F.Cu" "F.Mask" "F.Paste")
			(net "P3E_CPU0_PE3_OCP_RXN<10>")
		)
		(pad "102" smd rect
			(at 4.787646 39.99992 270)
			(size 2.3876 0.508)
			(layers "F.Cu" "F.Mask" "F.Paste")
			(net "GND")
		)
		(pad "103" smd rect
			(at 0 40.80002 270)
			(size 2.3876 0.508)
			(layers "F.Cu" "F.Mask" "F.Paste")
			(net "GND")
		)
		(pad "104" smd rect
			(at 4.787646 40.80002 270)
			(size 2.3876 0.508)
			(layers "F.Cu" "F.Mask" "F.Paste")
			(net "P3E_OCP_CPU0_PE3_C_TXP<9>")
		)
		(pad "105" smd rect
			(at 0 41.60012 270)
			(size 2.3876 0.508)
			(layers "F.Cu" "F.Mask" "F.Paste")
			(net "GND")
		)
		(pad "106" smd rect
			(at 4.787646 41.60012 270)
			(size 2.3876 0.508)
			(layers "F.Cu" "F.Mask" "F.Paste")
			(net "P3E_OCP_CPU0_PE3_C_TXN<9>")
		)
		(pad "107" smd rect
			(at 0 42.399966 270)
			(size 2.3876 0.508)
			(layers "F.Cu" "F.Mask" "F.Paste")
			(net "P3E_CPU0_PE3_OCP_RXP<9>")
		)
		(pad "108" smd rect
			(at 4.787646 42.399966 270)
			(size 2.3876 0.508)
			(layers "F.Cu" "F.Mask" "F.Paste")
			(net "GND")
		)
		(pad "109" smd rect
			(at 0 43.200066 270)
			(size 2.3876 0.508)
			(layers "F.Cu" "F.Mask" "F.Paste")
			(net "P3E_CPU0_PE3_OCP_RXN<9>")
		)
		(pad "110" smd rect
			(at 4.787646 43.200066 270)
			(size 2.3876 0.508)
			(layers "F.Cu" "F.Mask" "F.Paste")
			(net "GND")
		)
		(pad "111" smd rect
			(at 0 43.999912 270)
			(size 2.3876 0.508)
			(layers "F.Cu" "F.Mask" "F.Paste")
			(net "GND")
		)
		(pad "112" smd rect
			(at 4.787646 43.999912 270)
			(size 2.3876 0.508)
			(layers "F.Cu" "F.Mask" "F.Paste")
			(net "P3E_OCP_CPU0_PE3_C_TXP<8>")
		)
		(pad "113" smd rect
			(at 0 44.800012 270)
			(size 2.3876 0.508)
			(layers "F.Cu" "F.Mask" "F.Paste")
			(net "GND")
		)
		(pad "114" smd rect
			(at 4.787646 44.800012 270)
			(size 2.3876 0.508)
			(layers "F.Cu" "F.Mask" "F.Paste")
			(net "P3E_OCP_CPU0_PE3_C_TXN<8>")
		)
		(pad "115" smd rect
			(at 0 45.600112 270)
			(size 2.3876 0.508)
			(layers "F.Cu" "F.Mask" "F.Paste")
			(net "P3E_CPU0_PE3_OCP_RXP<8>")
		)
		(pad "116" smd rect
			(at 4.787646 45.600112 270)
			(size 2.3876 0.508)
			(layers "F.Cu" "F.Mask" "F.Paste")
			(net "GND")
		)
		(pad "117" smd rect
			(at 0 46.399958 270)
			(size 2.3876 0.508)
			(layers "F.Cu" "F.Mask" "F.Paste")
			(net "P3E_CPU0_PE3_OCP_RXN<8>")
		)
		(pad "118" smd rect
			(at 4.787646 46.399958 270)
			(size 2.3876 0.508)
			(layers "F.Cu" "F.Mask" "F.Paste")
			(net "GND")
		)
		(pad "119" smd rect
			(at 0 47.200058 270)
			(size 2.3876 0.508)
			(layers "F.Cu" "F.Mask" "F.Paste")
			(net "GND")
		)
		(pad "120" smd rect
			(at 4.787646 47.200058 270)
			(size 2.3876 0.508)
			(layers "F.Cu" "F.Mask" "F.Paste")
			(net "FM_OCP_MEZZA_PRES_N")
		)
		(zone
			(layers "F.Cu" "B.Cu" "In1.Cu" "In2.Cu" "In3.Cu" "In4.Cu" "In5.Cu" "In6.Cu"
				"In7.Cu" "In8.Cu" "In9.Cu" "In10.Cu" "In11.Cu" "In12.Cu"
			)
			(hatch none 0.5)
			(connect_pads
				(clearance 0)
			)
			(min_thickness 0.25)
			(keepout
				(tracks not_allowed)
				(vias allowed)
				(pads allowed)
				(copperpour not_allowed)
				(footprints allowed)
			)
			(placement
				(enabled no)
				(sheetname "")
			)
			(fill
				(thermal_gap 0.5)
				(thermal_bridge_width 0.5)
				(island_removal_mode 0)
			)
			(polygon
				(pts
					(arc
						(start 438.824624 -114.599466)
						(mid 437.377332 -114.599466)
						(end 438.824624 -114.599466)
					)
				)
			)
		)
		(zone
			(layers "F.Cu" "B.Cu" "In1.Cu" "In2.Cu" "In3.Cu" "In4.Cu" "In5.Cu" "In6.Cu"
				"In7.Cu" "In8.Cu" "In9.Cu" "In10.Cu" "In11.Cu" "In12.Cu"
			)
			(hatch none 0.5)
			(connect_pads
				(clearance 0)
			)
			(min_thickness 0.25)
			(keepout
				(tracks not_allowed)
				(vias allowed)
				(pads allowed)
				(copperpour not_allowed)
				(footprints allowed)
			)
			(placement
				(enabled no)
				(sheetname "")
			)
			(fill
				(thermal_gap 0.5)
				(thermal_bridge_width 0.5)
				(island_removal_mode 0)
			)
			(polygon
				(pts
					(arc
						(start 491.215172 -114.599466)
						(mid 489.38688 -114.599466)
						(end 491.215172 -114.599466)
					)
				)
			)
		)
	)
	(footprint ""
		(layer "F.Cu")
		(at 411.0355 -108.204 -90)
		(property "Reference" "R2N5"
			(at 0 0 270)
			(layer "F.SilkS")
			(hide yes)
			(effects
				(font
					(size 1.27 1.27)
				)
			)
		)
		(property "Value" ""
			(at 0 0 270)
			(layer "F.Fab")
			(effects
				(font
					(size 1.27 1.27)
				)
			)
		)
		(duplicate_pad_numbers_are_jumpers no)
		(fp_poly
			(pts
				(xy -0.2794 -0.1016) (xy 0.2794 -0.1016) (xy 0.2794 0.9906) (xy -0.2794 0.9906)
			)
			(stroke
				(width 0)
				(type default)
			)
			(fill no)
			(layer "F.CrtYd")
		)
		(fp_line
			(start -0.2794 0.9906)
			(end 0.2794 0.9906)
			(stroke
				(width 0.1)
				(type default)
			)
			(layer "F.Fab")
		)
		(fp_line
			(start 0.2794 0.9906)
			(end 0.2794 -0.1016)
			(stroke
				(width 0.1)
				(type default)
			)
			(layer "F.Fab")
		)
		(fp_line
			(start -0.2794 -0.1016)
			(end -0.2794 0.9906)
			(stroke
				(width 0.1)
				(type default)
			)
			(layer "F.Fab")
		)
		(fp_line
			(start 0.2794 -0.1016)
			(end -0.2794 -0.1016)
			(stroke
				(width 0.1)
				(type default)
			)
			(layer "F.Fab")
		)
		(pad "1" smd rect
			(at 0 0 270)
			(size 0.508 0.508)
			(layers "F.Cu" "F.Mask" "F.Paste")
			(net "P3V3_STBY")
		)
		(pad "2" smd rect
			(at 0 0.889 270)
			(size 0.508 0.508)
			(layers "F.Cu" "F.Mask" "F.Paste")
			(net "SMB_SMLINK0_STBY_LVC3_SCL")
		)
		(zone
			(layer "F.Cu")
			(hatch none 0.5)
			(connect_pads
				(clearance 0)
			)
			(min_thickness 0.25)
			(keepout
				(tracks not_allowed)
				(vias allowed)
				(pads allowed)
				(copperpour not_allowed)
				(footprints allowed)
			)
			(placement
				(enabled no)
				(sheetname "")
			)
			(fill
				(thermal_gap 0.5)
				(thermal_bridge_width 0.5)
				(island_removal_mode 0)
			)
			(polygon
				(pts
					(xy 410.4005 -108.458) (xy 410.4005 -107.95) (xy 410.7815 -107.95) (xy 410.7815 -108.458)
				)
			)
		)
		(zone
			(layer "F.Cu")
			(hatch none 0.5)
			(connect_pads
				(clearance 0)
			)
			(min_thickness 0.25)
			(keepout
				(tracks allowed)
				(vias not_allowed)
				(pads allowed)
				(copperpour not_allowed)
				(footprints allowed)
			)
			(placement
				(enabled no)
				(sheetname "")
			)
			(fill
				(thermal_gap 0.5)
				(thermal_bridge_width 0.5)
				(island_removal_mode 0)
			)
			(polygon
				(pts
					(xy 410.7815 -108.458) (xy 410.7815 -107.95) (xy 410.4005 -107.95) (xy 410.4005 -108.458)
				)
			)
		)
	)
	(footprint ""
		(layer "F.Cu")
		(at 361.188 -133.985)
		(property "Reference" "C7B3"
			(at 0 0 0)
			(layer "F.SilkS")
			(hide yes)
			(effects
				(font
					(size 1.27 1.27)
				)
			)
		)
		(property "Value" ""
			(at 0 0 0)
			(layer "F.Fab")
			(effects
				(font
					(size 1.27 1.27)
				)
			)
		)
		(duplicate_pad_numbers_are_jumpers no)
		(fp_poly
			(pts
				(xy 0.3048 -0.1016) (xy 0.3048 0.9906) (xy -0.3048 0.9906) (xy -0.3048 -0.1016)
			)
			(stroke
				(width 0)
				(type default)
			)
			(fill no)
			(layer "F.CrtYd")
		)
		(fp_line
			(start -0.3048 -0.1016)
			(end -0.3048 0.9906)
			(stroke
				(width 0.1)
				(type default)
			)
			(layer "F.Fab")
		)
		(fp_line
			(start -0.3048 0.9906)
			(end 0.3048 0.9906)
			(stroke
				(width 0.1)
				(type default)
			)
			(layer "F.Fab")
		)
		(fp_line
			(start 0.3048 -0.1016)
			(end -0.3048 -0.1016)
			(stroke
				(width 0.1)
				(type default)
			)
			(layer "F.Fab")
		)
		(fp_line
			(start 0.3048 0.9906)
			(end 0.3048 -0.1016)
			(stroke
				(width 0.1)
				(type default)
			)
			(layer "F.Fab")
		)
		(pad "1" smd rect
			(at 0 0)
			(size 0.508 0.508)
			(layers "F.Cu" "F.Mask" "F.Paste")
			(net "PWRGD_PVDDQ_DEF_R")
		)
		(pad "2" smd rect
			(at 0 0.889)
			(size 0.508 0.508)
			(layers "F.Cu" "F.Mask" "F.Paste")
			(net "GND")
		)
		(zone
			(layer "F.Cu")
			(hatch none 0.5)
			(connect_pads
				(clearance 0)
			)
			(min_thickness 0.25)
			(keepout
				(tracks allowed)
				(vias not_allowed)
				(pads allowed)
				(copperpour not_allowed)
				(footprints allowed)
			)
			(placement
				(enabled no)
				(sheetname "")
			)
			(fill
				(thermal_gap 0.5)
				(thermal_bridge_width 0.5)
				(island_removal_mode 0)
			)
			(polygon
				(pts
					(xy 360.934 -133.731) (xy 361.442 -133.731) (xy 361.442 -133.35) (xy 360.934 -133.35)
				)
			)
		)
		(zone
			(layer "F.Cu")
			(hatch none 0.5)
			(connect_pads
				(clearance 0)
			)
			(min_thickness 0.25)
			(keepout
				(tracks not_allowed)
				(vias allowed)
				(pads allowed)
				(copperpour not_allowed)
				(footprints allowed)
			)
			(placement
				(enabled no)
				(sheetname "")
			)
			(fill
				(thermal_gap 0.5)
				(thermal_bridge_width 0.5)
				(island_removal_mode 0)
			)
			(polygon
				(pts
					(xy 360.934 -133.35) (xy 361.442 -133.35) (xy 361.442 -133.731) (xy 360.934 -133.731)
				)
			)
		)
	)
	(footprint ""
		(layer "F.Cu")
		(at 457.2 -31.735014 180)
		(property "Reference" "U9F3"
			(at -0.508 2.56667 180)
			(unlocked yes)
			(layer "F.SilkS")
			(effects
				(font
					(size 0.7874 0.5842)
					(thickness 0.1524)
				)
				(justify left)
			)
		)
		(property "Value" ""
			(at 0 0 180)
			(layer "F.Fab")
			(effects
				(font
					(size 1.27 1.27)
				)
			)
		)
		(duplicate_pad_numbers_are_jumpers no)
		(fp_circle
			(center -0.90805 -0.431546)
			(end -1.03505 -0.431546)
			(stroke
				(width 0.254)
				(type default)
			)
			(fill no)
			(layer "F.SilkS")
		)
		(fp_poly
			(pts
				(xy 0.21463 -0.450088) (xy 1.56337 -0.450088) (xy 1.56337 1.75006) (xy 0.21463 1.75006)
			)
			(stroke
				(width 0)
				(type default)
			)
			(fill no)
			(layer "F.CrtYd")
		)
		(fp_line
			(start 1.56337 1.75006)
			(end 0.21463 1.75006)
			(stroke
				(width 0.1)
				(type default)
			)
			(layer "F.Fab")
		)
		(fp_line
			(start 1.56337 -0.450088)
			(end 1.56337 1.75006)
			(stroke
				(width 0.1)
				(type default)
			)
			(layer "F.Fab")
		)
		(fp_line
			(start 0.21463 1.75006)
			(end 0.21463 -0.450088)
			(stroke
				(width 0.1)
				(type default)
			)
			(layer "F.Fab")
		)
		(fp_line
			(start 0.21463 -0.450088)
			(end 1.56337 -0.450088)
			(stroke
				(width 0.1)
				(type default)
			)
			(layer "F.Fab")
		)
		(fp_circle
			(center -0.4699 -0.8382)
			(end -0.5969 -0.8382)
			(stroke
				(width 0.254)
				(type default)
			)
			(fill no)
			(layer "F.Fab")
		)
		(pad "1" smd rect
			(at 0 0 180)
			(size 1.016 0.381)
			(layers "F.Cu" "F.Mask" "F.Paste")
			(net "Net_6467")
		)
		(pad "2" smd rect
			(at 0 0.649986 180)
			(size 1.016 0.381)
			(layers "F.Cu" "F.Mask" "F.Paste")
			(net "RST_BMC_DDR3_BUF_IN_N")
		)
		(pad "3" smd rect
			(at 0 1.299972 180)
			(size 1.016 0.381)
			(layers "F.Cu" "F.Mask" "F.Paste")
			(net "GND")
		)
		(pad "4" smd rect
			(at 1.778 1.299972 180)
			(size 1.016 0.381)
			(layers "F.Cu" "F.Mask" "F.Paste")
			(net "RST_BMC_DDR3_R_N")
		)
		(pad "5" smd rect
			(at 1.778 0 180)
			(size 1.016 0.381)
			(layers "F.Cu" "F.Mask" "F.Paste")
			(net "P3V3_STBY")
		)
	)
	(footprint ""
		(layer "F.Cu")
		(at 394.1064 -0.2286)
		(property "Reference" "R8G12"
			(at 0 0 0)
			(layer "F.SilkS")
			(hide yes)
			(effects
				(font
					(size 1.27 1.27)
				)
			)
		)
		(property "Value" ""
			(at 0 0 0)
			(layer "F.Fab")
			(effects
				(font
					(size 1.27 1.27)
				)
			)
		)
		(duplicate_pad_numbers_are_jumpers no)
		(fp_poly
			(pts
				(xy -0.2794 -0.1016) (xy 0.2794 -0.1016) (xy 0.2794 0.9906) (xy -0.2794 0.9906)
			)
			(stroke
				(width 0)
				(type default)
			)
			(fill no)
			(layer "F.CrtYd")
		)
		(fp_line
			(start -0.2794 -0.1016)
			(end -0.2794 0.9906)
			(stroke
				(width 0.1)
				(type default)
			)
			(layer "F.Fab")
		)
		(fp_line
			(start -0.2794 0.9906)
			(end 0.2794 0.9906)
			(stroke
				(width 0.1)
				(type default)
			)
			(layer "F.Fab")
		)
		(fp_line
			(start 0.2794 -0.1016)
			(end -0.2794 -0.1016)
			(stroke
				(width 0.1)
				(type default)
			)
			(layer "F.Fab")
		)
		(fp_line
			(start 0.2794 0.9906)
			(end 0.2794 -0.1016)
			(stroke
				(width 0.1)
				(type default)
			)
			(layer "F.Fab")
		)
		(pad "1" smd rect
			(at 0 0)
			(size 0.508 0.508)
			(layers "F.Cu" "F.Mask" "F.Paste")
			(net "JTAG_PCH_GBE_TMS")
		)
		(pad "2" smd rect
			(at 0 0.889)
			(size 0.508 0.508)
			(layers "F.Cu" "F.Mask" "F.Paste")
			(net "JTAG_TMS")
		)
		(zone
			(layer "F.Cu")
			(hatch none 0.5)
			(connect_pads
				(clearance 0)
			)
			(min_thickness 0.25)
			(keepout
				(tracks allowed)
				(vias not_allowed)
				(pads allowed)
				(copperpour not_allowed)
				(footprints allowed)
			)
			(placement
				(enabled no)
				(sheetname "")
			)
			(fill
				(thermal_gap 0.5)
				(thermal_bridge_width 0.5)
				(island_removal_mode 0)
			)
			(polygon
				(pts
					(xy 393.8524 0.0254) (xy 394.3604 0.0254) (xy 394.3604 0.4064) (xy 393.8524 0.4064)
				)
			)
		)
		(zone
			(layer "F.Cu")
			(hatch none 0.5)
			(connect_pads
				(clearance 0)
			)
			(min_thickness 0.25)
			(keepout
				(tracks not_allowed)
				(vias allowed)
				(pads allowed)
				(copperpour not_allowed)
				(footprints allowed)
			)
			(placement
				(enabled no)
				(sheetname "")
			)
			(fill
				(thermal_gap 0.5)
				(thermal_bridge_width 0.5)
				(island_removal_mode 0)
			)
			(polygon
				(pts
					(xy 393.8524 0.4064) (xy 394.3604 0.4064) (xy 394.3604 0.0254) (xy 393.8524 0.0254)
				)
			)
		)
	)
	(footprint ""
		(layer "F.Cu")
		(at 93.20784 -73.318116)
		(property "Reference" "C2D30"
			(at 0 0 0)
			(layer "F.SilkS")
			(hide yes)
			(effects
				(font
					(size 1.27 1.27)
				)
			)
		)
		(property "Value" ""
			(at 0 0 0)
			(layer "F.Fab")
			(effects
				(font
					(size 1.27 1.27)
				)
			)
		)
		(duplicate_pad_numbers_are_jumpers no)
		(fp_poly
			(pts
				(xy -0.4953 -0.2032) (xy 0.4953 -0.2032) (xy 0.4953 1.6002) (xy -0.4953 1.6002)
			)
			(stroke
				(width 0)
				(type default)
			)
			(fill no)
			(layer "F.CrtYd")
		)
		(fp_line
			(start -0.4953 -0.2032)
			(end 0.4953 -0.2032)
			(stroke
				(width 0.1)
				(type default)
			)
			(layer "F.Fab")
		)
		(fp_line
			(start -0.4953 1.6002)
			(end -0.4953 -0.2032)
			(stroke
				(width 0.1)
				(type default)
			)
			(layer "F.Fab")
		)
		(fp_line
			(start 0.4953 -0.2032)
			(end 0.4953 1.6002)
			(stroke
				(width 0.1)
				(type default)
			)
			(layer "F.Fab")
		)
		(fp_line
			(start 0.4953 1.6002)
			(end -0.4953 1.6002)
			(stroke
				(width 0.1)
				(type default)
			)
			(layer "F.Fab")
		)
		(pad "1" smd rect
			(at 0 0)
			(size 0.762 0.889)
			(layers "F.Cu" "F.Mask" "F.Paste")
			(net "PVCCIN_CPU1")
		)
		(pad "2" smd rect
			(at 0 1.397)
			(size 0.762 0.889)
			(layers "F.Cu" "F.Mask" "F.Paste")
			(net "GND")
		)
		(zone
			(layer "F.Cu")
			(hatch none 0.5)
			(connect_pads
				(clearance 0)
			)
			(min_thickness 0.25)
			(keepout
				(tracks not_allowed)
				(vias allowed)
				(pads allowed)
				(copperpour not_allowed)
				(footprints allowed)
			)
			(placement
				(enabled no)
				(sheetname "")
			)
			(fill
				(thermal_gap 0.5)
				(thermal_bridge_width 0.5)
				(island_removal_mode 0)
			)
			(polygon
				(pts
					(xy 92.82684 -72.873616) (xy 93.58884 -72.873616) (xy 93.58884 -72.365616) (xy 92.82684 -72.365616)
				)
			)
		)
	)
	(footprint ""
		(layer "F.Cu")
		(at 18.525744 -51.3842 180)
		(property "Reference" "Q1E1"
			(at 0 0 180)
			(layer "F.SilkS")
			(hide yes)
			(effects
				(font
					(size 1.27 1.27)
				)
			)
		)
		(property "Value" "*"
			(at -4.8514 -0.40005 180)
			(unlocked yes)
			(layer "F.Fab")
			(hide yes)
			(effects
				(font
					(size 0.889 0.889)
					(thickness 0.1524)
				)
			)
		)
		(property "Device Type" "2SB2907A-B0-00001-GP_DISCRET-GA"
			(at -4.8514 -1.92405 180)
			(unlocked yes)
			(layer "F.Fab")
			(hide yes)
			(effects
				(font
					(size 0.889 0.889)
					(thickness 0.1524)
				)
			)
		)
		(duplicate_pad_numbers_are_jumpers no)
		(fp_line
			(start 3.3274 0.8255)
			(end 2.59334 0.8255)
			(stroke
				(width 0.1524)
				(type default)
			)
			(layer "F.SilkS")
		)
		(fp_line
			(start 3.3274 -0.8255)
			(end 3.3274 0.8255)
			(stroke
				(width 0.1524)
				(type default)
			)
			(layer "F.SilkS")
		)
		(fp_line
			(start 2.460752 -0.8255)
			(end 3.3274 -0.8255)
			(stroke
				(width 0.1524)
				(type default)
			)
			(layer "F.SilkS")
		)
		(fp_line
			(start -2.188718 -1.3208)
			(end 2.188718 -1.3208)
			(stroke
				(width 0.1524)
				(type default)
			)
			(layer "F.SilkS")
		)
		(fp_line
			(start -2.59334 0.8255)
			(end -3.3274 0.8255)
			(stroke
				(width 0.1524)
				(type default)
			)
			(layer "F.SilkS")
		)
		(fp_line
			(start -3.3274 0.8255)
			(end -3.3274 -0.8255)
			(stroke
				(width 0.1524)
				(type default)
			)
			(layer "F.SilkS")
		)
		(fp_line
			(start -3.3274 -0.8255)
			(end -2.460752 -0.8255)
			(stroke
				(width 0.1524)
				(type default)
			)
			(layer "F.SilkS")
		)
		(fp_arc
			(start 2.59334 0.8255)
			(mid 0 2.870159)
			(end -2.59334 0.8255)
			(stroke
				(width 0.1524)
				(type default)
			)
			(layer "F.SilkS")
		)
		(fp_arc
			(start 2.188718 -1.3208)
			(mid 2.337892 -1.080376)
			(end 2.460752 -0.8255)
			(stroke
				(width 0.1524)
				(type default)
			)
			(layer "F.SilkS")
		)
		(fp_arc
			(start -2.460752 -0.8255)
			(mid -2.337885 -1.080372)
			(end -2.188718 -1.3208)
			(stroke
				(width 0.1524)
				(type default)
			)
			(layer "F.SilkS")
		)
		(fp_poly
			(pts
				(arc
					(start 2.413 0.2286)
					(mid 0 2.616334)
					(end -2.413 0.2286)
				)
				(xy -2.7432 0.2286) (xy -2.7432 -0.2286)
				(arc
					(start -2.374138 -0.2286)
					(mid -2.252325 -0.662833)
					(end -2.051812 -1.0668)
				)
				(arc
					(start 2.051812 -1.0668)
					(mid 2.252296 -0.662822)
					(end 2.374138 -0.2286)
				)
				(xy 2.7432 -0.2286) (xy 2.7432 0.2286)
			)
			(stroke
				(width 0)
				(type default)
			)
			(fill no)
			(layer "F.CrtYd")
		)
		(fp_poly
			(pts
				(arc
					(start 2.786634 1.0795)
					(mid 0 3.124369)
					(end -2.786634 1.0795)
				)
				(xy -3.5814 1.0795) (xy -3.5814 -1.0795)
				(arc
					(start -2.624328 -1.0795)
					(mid -2.483414 -1.33481)
					(end -2.31775 -1.5748)
				)
				(xy -0.000762 -1.5748) (xy -0.000762 -1.067054)
				(arc
					(start -2.052066 -1.067054)
					(mid -2.252571 -0.663082)
					(end -2.374392 -0.228854)
				)
				(xy -2.743454 -0.228854) (xy -2.743454 0.228854)
				(arc
					(start -2.413254 0.228854)
					(mid 0 2.61659)
					(end 2.413254 0.228854)
				)
				(xy 2.743454 0.228854) (xy 2.743454 -0.228854)
				(arc
					(start 2.374392 -0.228854)
					(mid 2.252549 -0.663073)
					(end 2.052066 -1.067054)
				)
				(xy 0.000762 -1.067054) (xy 0.000762 -1.5748)
				(arc
					(start 2.31775 -1.5748)
					(mid 2.483417 -1.334811)
					(end 2.624328 -1.0795)
				)
				(xy 3.5814 -1.0795) (xy 3.5814 1.0795)
			)
			(stroke
				(width 0)
				(type default)
			)
			(fill no)
			(layer "F.CrtYd")
		)
		(fp_poly
			(pts
				(arc
					(start 2.786634 1.0795)
					(mid 0 3.124369)
					(end -2.786634 1.0795)
				)
				(xy -3.5814 1.0795) (xy -3.5814 -1.0795)
				(arc
					(start -2.624328 -1.0795)
					(mid -2.483414 -1.33481)
					(end -2.31775 -1.5748)
				)
				(arc
					(start 2.31775 -1.5748)
					(mid 2.483417 -1.334811)
					(end 2.624328 -1.0795)
				)
				(xy 3.5814 -1.0795) (xy 3.5814 1.0795)
			)
			(stroke
				(width 0)
				(type default)
			)
			(fill no)
			(layer "F.Fab")
		)
		(pad "B" thru_hole circle
			(at 0 0 180)
			(size 1.143 1.143)
			(drill 0.7874)
			(layers "*.Cu" "*.Mask")
			(remove_unused_layers no)
			(net "ISENSE_TMP421_2_BC")
			(clearance 0.1778)
			(thermal_gap 0.1778)
		)
		(pad "C" thru_hole circle
			(at -2.500122 0 180)
			(size 1.143 1.143)
			(drill 0.7874)
			(layers "*.Cu" "*.Mask")
			(remove_unused_layers no)
			(net "ISENSE_TMP421_2_BC")
			(clearance 0.1778)
			(thermal_gap 0.1778)
		)
		(pad "E" thru_hole circle
			(at 2.500122 0 180)
			(size 1.143 1.143)
			(drill 0.7874)
			(layers "*.Cu" "*.Mask")
			(remove_unused_layers no)
			(net "ISENSE_TMP421_2_E")
			(clearance 0.1778)
			(thermal_gap 0.1778)
		)
	)
	(footprint ""
		(layer "F.Cu")
		(at 186.4868 -76.4921)
		(property "Reference" "R4D31"
			(at 0 0 0)
			(layer "F.SilkS")
			(hide yes)
			(effects
				(font
					(size 1.27 1.27)
				)
			)
		)
		(property "Value" ""
			(at 0 0 0)
			(layer "F.Fab")
			(effects
				(font
					(size 1.27 1.27)
				)
			)
		)
		(duplicate_pad_numbers_are_jumpers no)
		(fp_rect
			(start -0.2794 0.9906)
			(end 0.2794 -0.1016)
			(stroke
				(width 0)
				(type default)
			)
			(fill no)
			(layer "F.CrtYd")
		)
		(fp_line
			(start -0.2794 -0.1016)
			(end -0.2794 0.9906)
			(stroke
				(width 0.1)
				(type default)
			)
			(layer "F.Fab")
		)
		(fp_line
			(start -0.2794 0.9906)
			(end 0.2794 0.9906)
			(stroke
				(width 0.1)
				(type default)
			)
			(layer "F.Fab")
		)
		(fp_line
			(start 0.2794 -0.1016)
			(end -0.2794 -0.1016)
			(stroke
				(width 0.1)
				(type default)
			)
			(layer "F.Fab")
		)
		(fp_line
			(start 0.2794 0.9906)
			(end 0.2794 -0.1016)
			(stroke
				(width 0.1)
				(type default)
			)
			(layer "F.Fab")
		)
		(pad "1" smd rect
			(at 0 0)
			(size 0.508 0.508)
			(layers "F.Cu" "F.Mask" "F.Paste")
			(net "P3V3_STBY")
		)
		(pad "2" smd rect
			(at 0 0.889)
			(size 0.508 0.508)
			(layers "F.Cu" "F.Mask" "F.Paste")
			(net "PU_VR_PVCCIN_CPU0_IMON")
		)
		(zone
			(layer "F.Cu")
			(hatch none 0.5)
			(connect_pads
				(clearance 0)
			)
			(min_thickness 0.25)
			(keepout
				(tracks not_allowed)
				(vias allowed)
				(pads allowed)
				(copperpour not_allowed)
				(footprints allowed)
			)
			(placement
				(enabled no)
				(sheetname "")
			)
			(fill
				(thermal_gap 0.5)
				(thermal_bridge_width 0.5)
				(island_removal_mode 0)
			)
			(polygon
				(pts
					(xy 186.2328 -75.8571) (xy 186.7408 -75.8571) (xy 186.7408 -76.2381) (xy 186.2328 -76.2381)
				)
			)
		)
		(zone
			(layer "F.Cu")
			(hatch none 0.5)
			(connect_pads
				(clearance 0)
			)
			(min_thickness 0.25)
			(keepout
				(tracks allowed)
				(vias not_allowed)
				(pads allowed)
				(copperpour not_allowed)
				(footprints allowed)
			)
			(placement
				(enabled no)
				(sheetname "")
			)
			(fill
				(thermal_gap 0.5)
				(thermal_bridge_width 0.5)
				(island_removal_mode 0)
			)
			(polygon
				(pts
					(xy 186.2328 -75.8571) (xy 186.7408 -75.8571) (xy 186.7408 -76.2381) (xy 186.2328 -76.2381)
				)
			)
		)
	)
	(footprint ""
		(layer "F.Cu")
		(at 436.794402 -0.821182 -90)
		(property "Reference" "R8D21"
			(at 0 0 270)
			(layer "F.SilkS")
			(hide yes)
			(effects
				(font
					(size 1.27 1.27)
				)
			)
		)
		(property "Value" ""
			(at 0 0 270)
			(layer "F.Fab")
			(effects
				(font
					(size 1.27 1.27)
				)
			)
		)
		(duplicate_pad_numbers_are_jumpers no)
		(fp_poly
			(pts
				(xy -0.2794 -0.1016) (xy 0.2794 -0.1016) (xy 0.2794 0.9906) (xy -0.2794 0.9906)
			)
			(stroke
				(width 0)
				(type default)
			)
			(fill no)
			(layer "F.CrtYd")
		)
		(fp_line
			(start -0.2794 0.9906)
			(end 0.2794 0.9906)
			(stroke
				(width 0.1)
				(type default)
			)
			(layer "F.Fab")
		)
		(fp_line
			(start 0.2794 0.9906)
			(end 0.2794 -0.1016)
			(stroke
				(width 0.1)
				(type default)
			)
			(layer "F.Fab")
		)
		(fp_line
			(start -0.2794 -0.1016)
			(end -0.2794 0.9906)
			(stroke
				(width 0.1)
				(type default)
			)
			(layer "F.Fab")
		)
		(fp_line
			(start 0.2794 -0.1016)
			(end -0.2794 -0.1016)
			(stroke
				(width 0.1)
				(type default)
			)
			(layer "F.Fab")
		)
		(pad "1" smd rect
			(at 0 0 270)
			(size 0.508 0.508)
			(layers "F.Cu" "F.Mask" "F.Paste")
			(net "P3V3_STBY")
		)
		(pad "2" smd rect
			(at 0 0.889 270)
			(size 0.508 0.508)
			(layers "F.Cu" "F.Mask" "F.Paste")
			(net "FM_IE_DISABLE_N")
		)
		(zone
			(layer "F.Cu")
			(hatch none 0.5)
			(connect_pads
				(clearance 0)
			)
			(min_thickness 0.25)
			(keepout
				(tracks not_allowed)
				(vias allowed)
				(pads allowed)
				(copperpour not_allowed)
				(footprints allowed)
			)
			(placement
				(enabled no)
				(sheetname "")
			)
			(fill
				(thermal_gap 0.5)
				(thermal_bridge_width 0.5)
				(island_removal_mode 0)
			)
			(polygon
				(pts
					(xy 436.159402 -1.075182) (xy 436.159402 -0.567182) (xy 436.540402 -0.567182) (xy 436.540402 -1.075182)
				)
			)
		)
		(zone
			(layer "F.Cu")
			(hatch none 0.5)
			(connect_pads
				(clearance 0)
			)
			(min_thickness 0.25)
			(keepout
				(tracks allowed)
				(vias not_allowed)
				(pads allowed)
				(copperpour not_allowed)
				(footprints allowed)
			)
			(placement
				(enabled no)
				(sheetname "")
			)
			(fill
				(thermal_gap 0.5)
				(thermal_bridge_width 0.5)
				(island_removal_mode 0)
			)
			(polygon
				(pts
					(xy 436.540402 -1.075182) (xy 436.540402 -0.567182) (xy 436.159402 -0.567182) (xy 436.159402 -1.075182)
				)
			)
		)
	)
	(footprint ""
		(layer "F.Cu")
		(at 401.7518 -54.80558 -90)
		(property "Reference" "R7F4"
			(at 0 0 270)
			(layer "F.SilkS")
			(hide yes)
			(effects
				(font
					(size 1.27 1.27)
				)
			)
		)
		(property "Value" ""
			(at 0 0 270)
			(layer "F.Fab")
			(effects
				(font
					(size 1.27 1.27)
				)
			)
		)
		(duplicate_pad_numbers_are_jumpers no)
		(fp_poly
			(pts
				(xy -0.2794 -0.1016) (xy 0.2794 -0.1016) (xy 0.2794 0.9906) (xy -0.2794 0.9906)
			)
			(stroke
				(width 0)
				(type default)
			)
			(fill no)
			(layer "F.CrtYd")
		)
		(fp_line
			(start -0.2794 0.9906)
			(end 0.2794 0.9906)
			(stroke
				(width 0.1)
				(type default)
			)
			(layer "F.Fab")
		)
		(fp_line
			(start 0.2794 0.9906)
			(end 0.2794 -0.1016)
			(stroke
				(width 0.1)
				(type default)
			)
			(layer "F.Fab")
		)
		(fp_line
			(start -0.2794 -0.1016)
			(end -0.2794 0.9906)
			(stroke
				(width 0.1)
				(type default)
			)
			(layer "F.Fab")
		)
		(fp_line
			(start 0.2794 -0.1016)
			(end -0.2794 -0.1016)
			(stroke
				(width 0.1)
				(type default)
			)
			(layer "F.Fab")
		)
		(pad "1" smd rect
			(at 0 0 270)
			(size 0.508 0.508)
			(layers "F.Cu" "F.Mask" "F.Paste")
			(net "SPI_SWITCH_MISO")
		)
		(pad "2" smd rect
			(at 0 0.889 270)
			(size 0.508 0.508)
			(layers "F.Cu" "F.Mask" "F.Paste")
			(net "SPI_MISO_R0")
		)
		(zone
			(layer "F.Cu")
			(hatch none 0.5)
			(connect_pads
				(clearance 0)
			)
			(min_thickness 0.25)
			(keepout
				(tracks not_allowed)
				(vias allowed)
				(pads allowed)
				(copperpour not_allowed)
				(footprints allowed)
			)
			(placement
				(enabled no)
				(sheetname "")
			)
			(fill
				(thermal_gap 0.5)
				(thermal_bridge_width 0.5)
				(island_removal_mode 0)
			)
			(polygon
				(pts
					(xy 401.1168 -55.05958) (xy 401.1168 -54.55158) (xy 401.4978 -54.55158) (xy 401.4978 -55.05958)
				)
			)
		)
		(zone
			(layer "F.Cu")
			(hatch none 0.5)
			(connect_pads
				(clearance 0)
			)
			(min_thickness 0.25)
			(keepout
				(tracks allowed)
				(vias not_allowed)
				(pads allowed)
				(copperpour not_allowed)
				(footprints allowed)
			)
			(placement
				(enabled no)
				(sheetname "")
			)
			(fill
				(thermal_gap 0.5)
				(thermal_bridge_width 0.5)
				(island_removal_mode 0)
			)
			(polygon
				(pts
					(xy 401.4978 -55.05958) (xy 401.4978 -54.55158) (xy 401.1168 -54.55158) (xy 401.1168 -55.05958)
				)
			)
		)
	)
	(footprint ""
		(layer "F.Cu")
		(at 8.026146 -3.659886 -90)
		(property "Reference" "C1G16"
			(at 0 0 270)
			(layer "F.SilkS")
			(hide yes)
			(effects
				(font
					(size 1.27 1.27)
				)
			)
		)
		(property "Value" ""
			(at 0 0 270)
			(layer "F.Fab")
			(effects
				(font
					(size 1.27 1.27)
				)
			)
		)
		(duplicate_pad_numbers_are_jumpers no)
		(fp_rect
			(start -0.3048 0.9906)
			(end 0.3048 -0.1016)
			(stroke
				(width 0)
				(type default)
			)
			(fill no)
			(layer "F.CrtYd")
		)
		(fp_line
			(start -0.3048 0.9906)
			(end 0.3048 0.9906)
			(stroke
				(width 0.1)
				(type default)
			)
			(layer "F.Fab")
		)
		(fp_line
			(start 0.3048 0.9906)
			(end 0.3048 -0.1016)
			(stroke
				(width 0.1)
				(type default)
			)
			(layer "F.Fab")
		)
		(fp_line
			(start -0.3048 -0.1016)
			(end -0.3048 0.9906)
			(stroke
				(width 0.1)
				(type default)
			)
			(layer "F.Fab")
		)
		(fp_line
			(start 0.3048 -0.1016)
			(end -0.3048 -0.1016)
			(stroke
				(width 0.1)
				(type default)
			)
			(layer "F.Fab")
		)
		(pad "1" smd rect
			(at 0 0 270)
			(size 0.508 0.508)
			(layers "F.Cu" "F.Mask" "F.Paste")
			(net "VR_PVDDQ_GHJ_AVSP")
		)
		(pad "2" smd rect
			(at 0 0.889 270)
			(size 0.508 0.508)
			(layers "F.Cu" "F.Mask" "F.Paste")
			(net "VSENSE_PVDDQ_GHJ_N")
		)
		(zone
			(layer "F.Cu")
			(hatch none 0.5)
			(connect_pads
				(clearance 0)
			)
			(min_thickness 0.25)
			(keepout
				(tracks allowed)
				(vias not_allowed)
				(pads allowed)
				(copperpour not_allowed)
				(footprints allowed)
			)
			(placement
				(enabled no)
				(sheetname "")
			)
			(fill
				(thermal_gap 0.5)
				(thermal_bridge_width 0.5)
				(island_removal_mode 0)
			)
			(polygon
				(pts
					(xy 7.391146 -3.913886) (xy 7.391146 -3.405886) (xy 7.772146 -3.405886) (xy 7.772146 -3.913886)
				)
			)
		)
		(zone
			(layer "F.Cu")
			(hatch none 0.5)
			(connect_pads
				(clearance 0)
			)
			(min_thickness 0.25)
			(keepout
				(tracks not_allowed)
				(vias allowed)
				(pads allowed)
				(copperpour not_allowed)
				(footprints allowed)
			)
			(placement
				(enabled no)
				(sheetname "")
			)
			(fill
				(thermal_gap 0.5)
				(thermal_bridge_width 0.5)
				(island_removal_mode 0)
			)
			(polygon
				(pts
					(xy 7.391146 -3.913886) (xy 7.391146 -3.405886) (xy 7.772146 -3.405886) (xy 7.772146 -3.913886)
				)
			)
		)
	)
	(footprint ""
		(layer "F.Cu")
		(at 267.2588 -84.7598)
		(property "Reference" "C5D8"
			(at 0 0 0)
			(layer "F.SilkS")
			(hide yes)
			(effects
				(font
					(size 1.27 1.27)
				)
			)
		)
		(property "Value" ""
			(at 0 0 0)
			(layer "F.Fab")
			(effects
				(font
					(size 1.27 1.27)
				)
			)
		)
		(duplicate_pad_numbers_are_jumpers no)
		(fp_poly
			(pts
				(xy -0.4953 -0.2032) (xy 0.4953 -0.2032) (xy 0.4953 1.6002) (xy -0.4953 1.6002)
			)
			(stroke
				(width 0)
				(type default)
			)
			(fill no)
			(layer "F.CrtYd")
		)
		(fp_line
			(start -0.4953 -0.2032)
			(end 0.4953 -0.2032)
			(stroke
				(width 0.1)
				(type default)
			)
			(layer "F.Fab")
		)
		(fp_line
			(start -0.4953 1.6002)
			(end -0.4953 -0.2032)
			(stroke
				(width 0.1)
				(type default)
			)
			(layer "F.Fab")
		)
		(fp_line
			(start 0.4953 -0.2032)
			(end 0.4953 1.6002)
			(stroke
				(width 0.1)
				(type default)
			)
			(layer "F.Fab")
		)
		(fp_line
			(start 0.4953 1.6002)
			(end -0.4953 1.6002)
			(stroke
				(width 0.1)
				(type default)
			)
			(layer "F.Fab")
		)
		(pad "1" smd rect
			(at 0 0)
			(size 0.762 0.889)
			(layers "F.Cu" "F.Mask" "F.Paste")
			(net "PVDDQ_DEF")
		)
		(pad "2" smd rect
			(at 0 1.397)
			(size 0.762 0.889)
			(layers "F.Cu" "F.Mask" "F.Paste")
			(net "GND")
		)
		(zone
			(layer "F.Cu")
			(hatch none 0.5)
			(connect_pads
				(clearance 0)
			)
			(min_thickness 0.25)
			(keepout
				(tracks not_allowed)
				(vias allowed)
				(pads allowed)
				(copperpour not_allowed)
				(footprints allowed)
			)
			(placement
				(enabled no)
				(sheetname "")
			)
			(fill
				(thermal_gap 0.5)
				(thermal_bridge_width 0.5)
				(island_removal_mode 0)
			)
			(polygon
				(pts
					(xy 266.8778 -84.3153) (xy 267.6398 -84.3153) (xy 267.6398 -83.8073) (xy 266.8778 -83.8073)
				)
			)
		)
	)
	(footprint ""
		(layer "F.Cu")
		(at 20.9423 -83.312 90)
		(property "Reference" "U1D2"
			(at 1.1684 -0.90043 90)
			(unlocked yes)
			(layer "F.SilkS")
			(effects
				(font
					(size 0.7874 0.5842)
					(thickness 0.1524)
				)
			)
		)
		(property "Value" ""
			(at 0 0 90)
			(layer "F.Fab")
			(effects
				(font
					(size 1.27 1.27)
				)
			)
		)
		(duplicate_pad_numbers_are_jumpers no)
		(fp_circle
			(center -1.0795 -0.054102)
			(end -1.0795 0.072898)
			(stroke
				(width 0.254)
				(type default)
			)
			(fill no)
			(layer "F.SilkS")
		)
		(fp_rect
			(start -0.216154 1.27508)
			(end 1.333754 -0.275082)
			(stroke
				(width 0)
				(type default)
			)
			(fill no)
			(layer "F.CrtYd")
		)
		(fp_line
			(start 1.333754 -0.275082)
			(end 1.333754 1.27508)
			(stroke
				(width 0.1)
				(type default)
			)
			(layer "F.Fab")
		)
		(fp_line
			(start -0.216154 -0.275082)
			(end 1.333754 -0.275082)
			(stroke
				(width 0.1)
				(type default)
			)
			(layer "F.Fab")
		)
		(fp_line
			(start 1.333754 1.27508)
			(end -0.216154 1.27508)
			(stroke
				(width 0.1)
				(type default)
			)
			(layer "F.Fab")
		)
		(fp_line
			(start -0.216154 1.27508)
			(end -0.216154 -0.275082)
			(stroke
				(width 0.1)
				(type default)
			)
			(layer "F.Fab")
		)
		(fp_circle
			(center -1.0795 -0.054102)
			(end -1.0795 0.072898)
			(stroke
				(width 0.635)
				(type default)
			)
			(fill no)
			(layer "F.Fab")
		)
		(pad "1" smd rect
			(at 0 0 90)
			(size 0.9398 0.3048)
			(layers "F.Cu" "F.Mask" "F.Paste")
			(net "IRQ_OC_DETECT_N")
		)
		(pad "2" smd rect
			(at -0.0254 0.500126 90)
			(size 0.889 0.3048)
			(layers "F.Cu" "F.Mask" "F.Paste")
			(net "P12V_STBY")
		)
		(pad "3" smd rect
			(at -0.0254 0.999998 90)
			(size 0.889 0.3048)
			(layers "F.Cu" "F.Mask" "F.Paste")
			(net "A_HSC_HIGH")
		)
		(pad "4" smd rect
			(at 1.143 0.999998 90)
			(size 0.889 0.3048)
			(layers "F.Cu" "F.Mask" "F.Paste")
			(net "A_HSC_LOW")
		)
		(pad "5" smd rect
			(at 1.143 0.500126 90)
			(size 0.889 0.3048)
			(layers "F.Cu" "F.Mask" "F.Paste")
			(net "GND")
		)
		(pad "6" smd rect
			(at 1.143 0 90)
			(size 0.889 0.3048)
			(layers "F.Cu" "F.Mask" "F.Paste")
			(net "A_HSC_LOW_GATE")
		)
	)
	(footprint ""
		(layer "F.Cu")
		(at 398.030192 -10.917936)
		(property "Reference" "C7G25"
			(at 0 0 0)
			(layer "F.SilkS")
			(hide yes)
			(effects
				(font
					(size 1.27 1.27)
				)
			)
		)
		(property "Value" ""
			(at 0 0 0)
			(layer "F.Fab")
			(effects
				(font
					(size 1.27 1.27)
				)
			)
		)
		(duplicate_pad_numbers_are_jumpers no)
		(fp_rect
			(start -0.3048 0.9906)
			(end 0.3048 -0.1016)
			(stroke
				(width 0)
				(type default)
			)
			(fill no)
			(layer "F.CrtYd")
		)
		(fp_line
			(start -0.3048 -0.1016)
			(end -0.3048 0.9906)
			(stroke
				(width 0.1)
				(type default)
			)
			(layer "F.Fab")
		)
		(fp_line
			(start -0.3048 0.9906)
			(end 0.3048 0.9906)
			(stroke
				(width 0.1)
				(type default)
			)
			(layer "F.Fab")
		)
		(fp_line
			(start 0.3048 -0.1016)
			(end -0.3048 -0.1016)
			(stroke
				(width 0.1)
				(type default)
			)
			(layer "F.Fab")
		)
		(fp_line
			(start 0.3048 0.9906)
			(end 0.3048 -0.1016)
			(stroke
				(width 0.1)
				(type default)
			)
			(layer "F.Fab")
		)
		(pad "1" smd rect
			(at 0 0)
			(size 0.508 0.508)
			(layers "F.Cu" "F.Mask" "F.Paste")
			(net "P3E_CPU0_PE2_SS_TXP<5>")
		)
		(pad "2" smd rect
			(at 0 0.889)
			(size 0.508 0.508)
			(layers "F.Cu" "F.Mask" "F.Paste")
			(net "P3E_CPU0_PE2_SS_C_TXP<5>")
		)
		(zone
			(layer "F.Cu")
			(hatch none 0.5)
			(connect_pads
				(clearance 0)
			)
			(min_thickness 0.25)
			(keepout
				(tracks not_allowed)
				(vias allowed)
				(pads allowed)
				(copperpour not_allowed)
				(footprints allowed)
			)
			(placement
				(enabled no)
				(sheetname "")
			)
			(fill
				(thermal_gap 0.5)
				(thermal_bridge_width 0.5)
				(island_removal_mode 0)
			)
			(polygon
				(pts
					(xy 397.776192 -10.282936) (xy 398.284192 -10.282936) (xy 398.284192 -10.663936) (xy 397.776192 -10.663936)
				)
			)
		)
		(zone
			(layer "F.Cu")
			(hatch none 0.5)
			(connect_pads
				(clearance 0)
			)
			(min_thickness 0.25)
			(keepout
				(tracks allowed)
				(vias not_allowed)
				(pads allowed)
				(copperpour not_allowed)
				(footprints allowed)
			)
			(placement
				(enabled no)
				(sheetname "")
			)
			(fill
				(thermal_gap 0.5)
				(thermal_bridge_width 0.5)
				(island_removal_mode 0)
			)
			(polygon
				(pts
					(xy 397.776192 -10.282936) (xy 398.284192 -10.282936) (xy 398.284192 -10.663936) (xy 397.776192 -10.663936)
				)
			)
		)
	)
	(footprint ""
		(layer "F.Cu")
		(at 433.9336 -18.533872 -90)
		(property "Reference" "C10W4"
			(at -0.8382 -0.67818 270)
			(unlocked yes)
			(layer "F.SilkS")
			(effects
				(font
					(size 0.4064 0.254)
					(thickness 0.1524)
				)
				(justify left)
			)
		)
		(property "Value" ""
			(at 0 0 270)
			(layer "F.Fab")
			(effects
				(font
					(size 1.27 1.27)
				)
			)
		)
		(duplicate_pad_numbers_are_jumpers no)
		(fp_poly
			(pts
				(xy 0.3048 -0.1016) (xy 0.3048 0.9906) (xy -0.3048 0.9906) (xy -0.3048 -0.1016)
			)
			(stroke
				(width 0)
				(type default)
			)
			(fill no)
			(layer "F.CrtYd")
		)
		(fp_line
			(start -0.3048 0.9906)
			(end 0.3048 0.9906)
			(stroke
				(width 0.1)
				(type default)
			)
			(layer "F.Fab")
		)
		(fp_line
			(start 0.3048 0.9906)
			(end 0.3048 -0.1016)
			(stroke
				(width 0.1)
				(type default)
			)
			(layer "F.Fab")
		)
		(fp_line
			(start -0.3048 -0.1016)
			(end -0.3048 0.9906)
			(stroke
				(width 0.1)
				(type default)
			)
			(layer "F.Fab")
		)
		(fp_line
			(start 0.3048 -0.1016)
			(end -0.3048 -0.1016)
			(stroke
				(width 0.1)
				(type default)
			)
			(layer "F.Fab")
		)
		(pad "1" smd rect
			(at 0 0 270)
			(size 0.508 0.508)
			(layers "F.Cu" "F.Mask" "F.Paste")
			(net "P3V3_STBY")
		)
		(pad "2" smd rect
			(at 0 0.889 270)
			(size 0.508 0.508)
			(layers "F.Cu" "F.Mask" "F.Paste")
			(net "GND")
		)
		(zone
			(layer "F.Cu")
			(hatch none 0.5)
			(connect_pads
				(clearance 0)
			)
			(min_thickness 0.25)
			(keepout
				(tracks not_allowed)
				(vias allowed)
				(pads allowed)
				(copperpour not_allowed)
				(footprints allowed)
			)
			(placement
				(enabled no)
				(sheetname "")
			)
			(fill
				(thermal_gap 0.5)
				(thermal_bridge_width 0.5)
				(island_removal_mode 0)
			)
			(polygon
				(pts
					(xy 433.2986 -18.787872) (xy 433.2986 -18.279872) (xy 433.6796 -18.279872) (xy 433.6796 -18.787872)
				)
			)
		)
		(zone
			(layer "F.Cu")
			(hatch none 0.5)
			(connect_pads
				(clearance 0)
			)
			(min_thickness 0.25)
			(keepout
				(tracks allowed)
				(vias not_allowed)
				(pads allowed)
				(copperpour not_allowed)
				(footprints allowed)
			)
			(placement
				(enabled no)
				(sheetname "")
			)
			(fill
				(thermal_gap 0.5)
				(thermal_bridge_width 0.5)
				(island_removal_mode 0)
			)
			(polygon
				(pts
					(xy 433.6796 -18.787872) (xy 433.6796 -18.279872) (xy 433.2986 -18.279872) (xy 433.2986 -18.787872)
				)
			)
		)
	)
	(footprint ""
		(layer "F.Cu")
		(at 396.5448 -0.2286)
		(property "Reference" "R8G16"
			(at 0 0 0)
			(layer "F.SilkS")
			(hide yes)
			(effects
				(font
					(size 1.27 1.27)
				)
			)
		)
		(property "Value" ""
			(at 0 0 0)
			(layer "F.Fab")
			(effects
				(font
					(size 1.27 1.27)
				)
			)
		)
		(duplicate_pad_numbers_are_jumpers no)
		(fp_poly
			(pts
				(xy -0.2794 -0.1016) (xy 0.2794 -0.1016) (xy 0.2794 0.9906) (xy -0.2794 0.9906)
			)
			(stroke
				(width 0)
				(type default)
			)
			(fill no)
			(layer "F.CrtYd")
		)
		(fp_line
			(start -0.2794 -0.1016)
			(end -0.2794 0.9906)
			(stroke
				(width 0.1)
				(type default)
			)
			(layer "F.Fab")
		)
		(fp_line
			(start -0.2794 0.9906)
			(end 0.2794 0.9906)
			(stroke
				(width 0.1)
				(type default)
			)
			(layer "F.Fab")
		)
		(fp_line
			(start 0.2794 -0.1016)
			(end -0.2794 -0.1016)
			(stroke
				(width 0.1)
				(type default)
			)
			(layer "F.Fab")
		)
		(fp_line
			(start 0.2794 0.9906)
			(end 0.2794 -0.1016)
			(stroke
				(width 0.1)
				(type default)
			)
			(layer "F.Fab")
		)
		(pad "1" smd rect
			(at 0 0)
			(size 0.508 0.508)
			(layers "F.Cu" "F.Mask" "F.Paste")
			(net "JTAG_PCH_PLD_TCK")
		)
		(pad "2" smd rect
			(at 0 0.889)
			(size 0.508 0.508)
			(layers "F.Cu" "F.Mask" "F.Paste")
			(net "JTAG_TCK")
		)
		(zone
			(layer "F.Cu")
			(hatch none 0.5)
			(connect_pads
				(clearance 0)
			)
			(min_thickness 0.25)
			(keepout
				(tracks allowed)
				(vias not_allowed)
				(pads allowed)
				(copperpour not_allowed)
				(footprints allowed)
			)
			(placement
				(enabled no)
				(sheetname "")
			)
			(fill
				(thermal_gap 0.5)
				(thermal_bridge_width 0.5)
				(island_removal_mode 0)
			)
			(polygon
				(pts
					(xy 396.2908 0.0254) (xy 396.7988 0.0254) (xy 396.7988 0.4064) (xy 396.2908 0.4064)
				)
			)
		)
		(zone
			(layer "F.Cu")
			(hatch none 0.5)
			(connect_pads
				(clearance 0)
			)
			(min_thickness 0.25)
			(keepout
				(tracks not_allowed)
				(vias allowed)
				(pads allowed)
				(copperpour not_allowed)
				(footprints allowed)
			)
			(placement
				(enabled no)
				(sheetname "")
			)
			(fill
				(thermal_gap 0.5)
				(thermal_bridge_width 0.5)
				(island_removal_mode 0)
			)
			(polygon
				(pts
					(xy 396.2908 0.4064) (xy 396.7988 0.4064) (xy 396.7988 0.0254) (xy 396.2908 0.0254)
				)
			)
		)
	)
	(footprint ""
		(layer "F.Cu")
		(at 352.487738 2.51079 -90)
		(property "Reference" "RT36"
			(at 1.01473 0.656336 180)
			(unlocked yes)
			(layer "F.SilkS")
			(effects
				(font
					(size 0.4064 0.254)
					(thickness 0.1524)
				)
			)
		)
		(property "Value" ""
			(at 0 0 270)
			(layer "F.Fab")
			(effects
				(font
					(size 1.27 1.27)
				)
			)
		)
		(duplicate_pad_numbers_are_jumpers no)
		(fp_poly
			(pts
				(xy -0.4953 -0.2032) (xy 0.4953 -0.2032) (xy 0.4953 1.6002) (xy -0.4953 1.6002)
			)
			(stroke
				(width 0)
				(type default)
			)
			(fill no)
			(layer "F.CrtYd")
		)
		(fp_line
			(start -0.4953 1.6002)
			(end -0.4953 -0.2032)
			(stroke
				(width 0.1)
				(type default)
			)
			(layer "F.Fab")
		)
		(fp_line
			(start 0.4953 1.6002)
			(end -0.4953 1.6002)
			(stroke
				(width 0.1)
				(type default)
			)
			(layer "F.Fab")
		)
		(fp_line
			(start -0.4953 -0.2032)
			(end 0.4953 -0.2032)
			(stroke
				(width 0.1)
				(type default)
			)
			(layer "F.Fab")
		)
		(fp_line
			(start 0.4953 -0.2032)
			(end 0.4953 1.6002)
			(stroke
				(width 0.1)
				(type default)
			)
			(layer "F.Fab")
		)
		(pad "1" smd rect
			(at 0 0 270)
			(size 0.762 0.889)
			(layers "F.Cu" "F.Mask" "F.Paste")
			(net "VR_PVDDQ_ABC_PH2_BOOT")
		)
		(pad "2" smd rect
			(at 0 1.397 270)
			(size 0.762 0.889)
			(layers "F.Cu" "F.Mask" "F.Paste")
			(net "VR_PVDDQ_ABC_PH2_BOOT_R")
		)
		(zone
			(layer "F.Cu")
			(hatch none 0.5)
			(connect_pads
				(clearance 0)
			)
			(min_thickness 0.25)
			(keepout
				(tracks not_allowed)
				(vias allowed)
				(pads allowed)
				(copperpour not_allowed)
				(footprints allowed)
			)
			(placement
				(enabled no)
				(sheetname "")
			)
			(fill
				(thermal_gap 0.5)
				(thermal_bridge_width 0.5)
				(island_removal_mode 0)
			)
			(polygon
				(pts
					(xy 351.535238 2.12979) (xy 351.535238 2.89179) (xy 352.043238 2.89179) (xy 352.043238 2.12979)
				)
			)
		)
		(zone
			(layer "F.Cu")
			(hatch none 0.5)
			(connect_pads
				(clearance 0)
			)
			(min_thickness 0.25)
			(keepout
				(tracks allowed)
				(vias not_allowed)
				(pads allowed)
				(copperpour not_allowed)
				(footprints allowed)
			)
			(placement
				(enabled no)
				(sheetname "")
			)
			(fill
				(thermal_gap 0.5)
				(thermal_bridge_width 0.5)
				(island_removal_mode 0)
			)
			(polygon
				(pts
					(xy 351.535238 2.89179) (xy 352.043238 2.89179) (xy 352.043238 2.12979) (xy 351.535238 2.12979)
				)
			)
		)
	)
	(footprint ""
		(layer "F.Cu")
		(at 483.616 -139.4206)
		(property "Reference" "U6W12"
			(at 0 -1.2065 0)
			(unlocked yes)
			(layer "F.SilkS")
			(effects
				(font
					(size 1.27 0.9652)
					(thickness 0.1524)
				)
				(justify left)
			)
		)
		(property "Value" ""
			(at 0 0 0)
			(layer "F.Fab")
			(effects
				(font
					(size 1.27 1.27)
				)
			)
		)
		(duplicate_pad_numbers_are_jumpers no)
		(fp_circle
			(center -0.848614 -0.6477)
			(end -0.721614 -0.6477)
			(stroke
				(width 0.254)
				(type default)
			)
			(fill no)
			(layer "F.SilkS")
		)
		(fp_poly
			(pts
				(xy 0.21463 -0.450088) (xy 1.56337 -0.450088) (xy 1.56337 1.75006) (xy 0.21463 1.75006)
			)
			(stroke
				(width 0)
				(type default)
			)
			(fill no)
			(layer "F.CrtYd")
		)
		(fp_line
			(start 0.21463 -0.450088)
			(end 1.56337 -0.450088)
			(stroke
				(width 0.1)
				(type default)
			)
			(layer "F.Fab")
		)
		(fp_line
			(start 0.21463 1.75006)
			(end 0.21463 -0.450088)
			(stroke
				(width 0.1)
				(type default)
			)
			(layer "F.Fab")
		)
		(fp_line
			(start 1.56337 -0.450088)
			(end 1.56337 1.75006)
			(stroke
				(width 0.1)
				(type default)
			)
			(layer "F.Fab")
		)
		(fp_line
			(start 1.56337 1.75006)
			(end 0.21463 1.75006)
			(stroke
				(width 0.1)
				(type default)
			)
			(layer "F.Fab")
		)
		(fp_circle
			(center -0.848614 -0.6477)
			(end -0.721614 -0.6477)
			(stroke
				(width 0.254)
				(type default)
			)
			(fill no)
			(layer "F.Fab")
		)
		(pad "1" smd rect
			(at 0 0)
			(size 1.016 0.381)
			(layers "F.Cu" "F.Mask" "F.Paste")
			(net "SPA_MID_DBG2_RX_BUF")
		)
		(pad "2" smd rect
			(at 0 0.649986)
			(size 1.016 0.381)
			(layers "F.Cu" "F.Mask" "F.Paste")
			(net "GND")
		)
		(pad "3" smd rect
			(at 0 1.299972)
			(size 1.016 0.381)
			(layers "F.Cu" "F.Mask" "F.Paste")
			(net "SPA_MID_DBG1_RX")
		)
		(pad "4" smd rect
			(at 1.778 1.299972)
			(size 1.016 0.381)
			(layers "F.Cu" "F.Mask" "F.Paste")
			(net "SPA_MID_DBG_RX")
		)
		(pad "5" smd rect
			(at 1.778 0.649986)
			(size 1.016 0.381)
			(layers "F.Cu" "F.Mask" "F.Paste")
			(net "P3V3_STBY")
		)
		(pad "6" smd rect
			(at 1.778 0)
			(size 1.016 0.381)
			(layers "F.Cu" "F.Mask" "F.Paste")
			(net "DEBUG_CARD2_PRSNT")
		)
	)
	(footprint ""
		(layer "F.Cu")
		(at 185.3184 -138.2141)
		(property "Reference" "FB4A1"
			(at 0 0 0)
			(layer "F.SilkS")
			(hide yes)
			(effects
				(font
					(size 1.27 1.27)
				)
			)
		)
		(property "Value" ""
			(at 0 0 0)
			(layer "F.Fab")
			(effects
				(font
					(size 1.27 1.27)
				)
			)
		)
		(duplicate_pad_numbers_are_jumpers no)
		(fp_poly
			(pts
				(xy -0.7239 -0.26035) (xy 0.7239 -0.26035) (xy 0.7239 2.03835) (xy -0.7239 2.03835)
			)
			(stroke
				(width 0)
				(type default)
			)
			(fill no)
			(layer "F.CrtYd")
		)
		(fp_line
			(start -0.7239 -0.26035)
			(end 0.7239 -0.26035)
			(stroke
				(width 0.1)
				(type default)
			)
			(layer "F.Fab")
		)
		(fp_line
			(start -0.7239 2.03835)
			(end -0.7239 -0.26035)
			(stroke
				(width 0.1)
				(type default)
			)
			(layer "F.Fab")
		)
		(fp_line
			(start 0.7239 -0.26035)
			(end 0.7239 2.03835)
			(stroke
				(width 0.1)
				(type default)
			)
			(layer "F.Fab")
		)
		(fp_line
			(start 0.7239 2.03835)
			(end -0.7239 2.03835)
			(stroke
				(width 0.1)
				(type default)
			)
			(layer "F.Fab")
		)
		(pad "1" smd rect
			(at 0 0)
			(size 1.27 1.016)
			(layers "F.Cu" "F.Mask" "F.Paste")
			(net "P12V_STBY")
		)
		(pad "2" smd rect
			(at 0 1.778)
			(size 1.27 1.016)
			(layers "F.Cu" "F.Mask" "F.Paste")
			(net "VR_FET_SW_P12V_STBY_PVPP_KLM")
		)
		(zone
			(layer "F.Cu")
			(hatch none 0.5)
			(connect_pads
				(clearance 0)
			)
			(min_thickness 0.25)
			(keepout
				(tracks not_allowed)
				(vias allowed)
				(pads allowed)
				(copperpour not_allowed)
				(footprints allowed)
			)
			(placement
				(enabled no)
				(sheetname "")
			)
			(fill
				(thermal_gap 0.5)
				(thermal_bridge_width 0.5)
				(island_removal_mode 0)
			)
			(polygon
				(pts
					(xy 185.9534 -137.7061) (xy 185.9534 -136.9441) (xy 185.8645 -136.9441) (xy 184.6834 -136.9441)
					(xy 184.6834 -137.7061)
				)
			)
		)
	)
	(footprint ""
		(layer "F.Cu")
		(at 109.638592 -77.429614)
		(property "Reference" "C3D12"
			(at 0 0 0)
			(layer "F.SilkS")
			(hide yes)
			(effects
				(font
					(size 1.27 1.27)
				)
			)
		)
		(property "Value" ""
			(at 0 0 0)
			(layer "F.Fab")
			(effects
				(font
					(size 1.27 1.27)
				)
			)
		)
		(duplicate_pad_numbers_are_jumpers no)
		(fp_poly
			(pts
				(xy -0.4953 -0.2032) (xy 0.4953 -0.2032) (xy 0.4953 1.6002) (xy -0.4953 1.6002)
			)
			(stroke
				(width 0)
				(type default)
			)
			(fill no)
			(layer "F.CrtYd")
		)
		(fp_line
			(start -0.4953 -0.2032)
			(end 0.4953 -0.2032)
			(stroke
				(width 0.1)
				(type default)
			)
			(layer "F.Fab")
		)
		(fp_line
			(start -0.4953 1.6002)
			(end -0.4953 -0.2032)
			(stroke
				(width 0.1)
				(type default)
			)
			(layer "F.Fab")
		)
		(fp_line
			(start 0.4953 -0.2032)
			(end 0.4953 1.6002)
			(stroke
				(width 0.1)
				(type default)
			)
			(layer "F.Fab")
		)
		(fp_line
			(start 0.4953 1.6002)
			(end -0.4953 1.6002)
			(stroke
				(width 0.1)
				(type default)
			)
			(layer "F.Fab")
		)
		(pad "1" smd rect
			(at 0 0)
			(size 0.762 0.889)
			(layers "F.Cu" "F.Mask" "F.Paste")
			(net "PVCCMCP_CPU1")
		)
		(pad "2" smd rect
			(at 0 1.397)
			(size 0.762 0.889)
			(layers "F.Cu" "F.Mask" "F.Paste")
			(net "GND")
		)
		(zone
			(layer "F.Cu")
			(hatch none 0.5)
			(connect_pads
				(clearance 0)
			)
			(min_thickness 0.25)
			(keepout
				(tracks not_allowed)
				(vias allowed)
				(pads allowed)
				(copperpour not_allowed)
				(footprints allowed)
			)
			(placement
				(enabled no)
				(sheetname "")
			)
			(fill
				(thermal_gap 0.5)
				(thermal_bridge_width 0.5)
				(island_removal_mode 0)
			)
			(polygon
				(pts
					(xy 109.257592 -76.985114) (xy 110.019592 -76.985114) (xy 110.019592 -76.477114) (xy 109.257592 -76.477114)
				)
			)
		)
	)
	(footprint ""
		(layer "F.Cu")
		(at 184.147968 -134.173722 90)
		(property "Reference" "C4B1"
			(at 0 0 90)
			(layer "F.SilkS")
			(hide yes)
			(effects
				(font
					(size 1.27 1.27)
				)
			)
		)
		(property "Value" "*"
			(at -0.0762 -6.2357 90)
			(unlocked yes)
			(layer "F.Fab")
			(hide yes)
			(effects
				(font
					(size 1.27 1.016)
					(thickness 0.1524)
				)
			)
		)
		(property "Device Type" "SC22U16V5MX-4-GP_SMD-BCG5-SC22A"
			(at -0.0762 -8.2677 90)
			(unlocked yes)
			(layer "F.Fab")
			(hide yes)
			(effects
				(font
					(size 1.27 1.016)
					(thickness 0.1524)
				)
			)
		)
		(duplicate_pad_numbers_are_jumpers no)
		(fp_line
			(start 0.635 0)
			(end -0.635 0)
			(stroke
				(width 0.508)
				(type default)
			)
			(layer "F.SilkS")
		)
		(fp_rect
			(start -0.9652 1.778)
			(end 0.9652 -1.778)
			(stroke
				(width 0)
				(type default)
			)
			(fill no)
			(layer "F.CrtYd")
		)
		(fp_poly
			(pts
				(xy -0.9652 -1.778) (xy 0.9652 -1.778) (xy 0.9652 1.778) (xy -0.9652 1.778)
			)
			(stroke
				(width 0)
				(type default)
			)
			(fill no)
			(layer "F.Fab")
		)
		(pad "1" smd rect
			(at 0 -0.9652 90)
			(size 1.397 1.143)
			(layers "F.Cu" "F.Mask" "F.Paste")
			(net "VR_FET_SW_P12V_STBY_PVPP_KLM")
		)
		(pad "2" smd rect
			(at 0 0.9652 90)
			(size 1.397 1.143)
			(layers "F.Cu" "F.Mask" "F.Paste")
			(net "GND")
		)
	)
	(footprint ""
		(layer "F.Cu")
		(at 13.941806 3.507232 90)
		(property "Reference" "C1G23"
			(at 0 0 90)
			(layer "F.SilkS")
			(hide yes)
			(effects
				(font
					(size 1.27 1.27)
				)
			)
		)
		(property "Value" ""
			(at 0 0 90)
			(layer "F.Fab")
			(effects
				(font
					(size 1.27 1.27)
				)
			)
		)
		(duplicate_pad_numbers_are_jumpers no)
		(fp_poly
			(pts
				(xy 0.3048 -0.1016) (xy 0.3048 0.9906) (xy -0.3048 0.9906) (xy -0.3048 -0.1016)
			)
			(stroke
				(width 0)
				(type default)
			)
			(fill no)
			(layer "F.CrtYd")
		)
		(fp_line
			(start 0.3048 -0.1016)
			(end -0.3048 -0.1016)
			(stroke
				(width 0.1)
				(type default)
			)
			(layer "F.Fab")
		)
		(fp_line
			(start -0.3048 -0.1016)
			(end -0.3048 0.9906)
			(stroke
				(width 0.1)
				(type default)
			)
			(layer "F.Fab")
		)
		(fp_line
			(start 0.3048 0.9906)
			(end 0.3048 -0.1016)
			(stroke
				(width 0.1)
				(type default)
			)
			(layer "F.Fab")
		)
		(fp_line
			(start -0.3048 0.9906)
			(end 0.3048 0.9906)
			(stroke
				(width 0.1)
				(type default)
			)
			(layer "F.Fab")
		)
		(pad "1" smd rect
			(at 0 0 90)
			(size 0.508 0.508)
			(layers "F.Cu" "F.Mask" "F.Paste")
			(net "VR_PVDDQ_GHJ_VD12")
		)
		(pad "2" smd rect
			(at 0 0.889 90)
			(size 0.508 0.508)
			(layers "F.Cu" "F.Mask" "F.Paste")
			(net "GND")
		)
		(zone
			(layer "F.Cu")
			(hatch none 0.5)
			(connect_pads
				(clearance 0)
			)
			(min_thickness 0.25)
			(keepout
				(tracks allowed)
				(vias not_allowed)
				(pads allowed)
				(copperpour not_allowed)
				(footprints allowed)
			)
			(placement
				(enabled no)
				(sheetname "")
			)
			(fill
				(thermal_gap 0.5)
				(thermal_bridge_width 0.5)
				(island_removal_mode 0)
			)
			(polygon
				(pts
					(xy 14.195806 3.761232) (xy 14.195806 3.253232) (xy 14.576806 3.253232) (xy 14.576806 3.761232)
				)
			)
		)
		(zone
			(layer "F.Cu")
			(hatch none 0.5)
			(connect_pads
				(clearance 0)
			)
			(min_thickness 0.25)
			(keepout
				(tracks not_allowed)
				(vias allowed)
				(pads allowed)
				(copperpour not_allowed)
				(footprints allowed)
			)
			(placement
				(enabled no)
				(sheetname "")
			)
			(fill
				(thermal_gap 0.5)
				(thermal_bridge_width 0.5)
				(island_removal_mode 0)
			)
			(polygon
				(pts
					(xy 14.576806 3.761232) (xy 14.576806 3.253232) (xy 14.195806 3.253232) (xy 14.195806 3.761232)
				)
			)
		)
	)
	(footprint ""
		(layer "F.Cu")
		(at 33.2105 -76.708 90)
		(property "Reference" "C1D28"
			(at 0 0 90)
			(layer "F.SilkS")
			(hide yes)
			(effects
				(font
					(size 1.27 1.27)
				)
			)
		)
		(property "Value" ""
			(at 0 0 90)
			(layer "F.Fab")
			(effects
				(font
					(size 1.27 1.27)
				)
			)
		)
		(duplicate_pad_numbers_are_jumpers no)
		(fp_rect
			(start 0.3048 0.9906)
			(end -0.3048 -0.1016)
			(stroke
				(width 0)
				(type default)
			)
			(fill no)
			(layer "F.CrtYd")
		)
		(fp_line
			(start 0.3048 -0.1016)
			(end -0.3048 -0.1016)
			(stroke
				(width 0.1)
				(type default)
			)
			(layer "F.Fab")
		)
		(fp_line
			(start -0.3048 -0.1016)
			(end -0.3048 0.9906)
			(stroke
				(width 0.1)
				(type default)
			)
			(layer "F.Fab")
		)
		(fp_line
			(start 0.3048 0.9906)
			(end 0.3048 -0.1016)
			(stroke
				(width 0.1)
				(type default)
			)
			(layer "F.Fab")
		)
		(fp_line
			(start -0.3048 0.9906)
			(end 0.3048 0.9906)
			(stroke
				(width 0.1)
				(type default)
			)
			(layer "F.Fab")
		)
		(pad "1" smd rect
			(at 0 0 90)
			(size 0.508 0.508)
			(layers "F.Cu" "F.Mask" "F.Paste")
			(net "VR_FET_SW_P12V_STBY_PVCCIN_CPU1")
		)
		(pad "2" smd rect
			(at 0 0.889 90)
			(size 0.508 0.508)
			(layers "F.Cu" "F.Mask" "F.Paste")
			(net "GND")
		)
		(zone
			(layer "F.Cu")
			(hatch none 0.5)
			(connect_pads
				(clearance 0)
			)
			(min_thickness 0.25)
			(keepout
				(tracks not_allowed)
				(vias allowed)
				(pads allowed)
				(copperpour not_allowed)
				(footprints allowed)
			)
			(placement
				(enabled no)
				(sheetname "")
			)
			(fill
				(thermal_gap 0.5)
				(thermal_bridge_width 0.5)
				(island_removal_mode 0)
			)
			(polygon
				(pts
					(xy 33.8455 -76.962) (xy 33.4645 -76.962) (xy 33.4645 -76.454) (xy 33.8455 -76.454)
				)
			)
		)
		(zone
			(layer "F.Cu")
			(hatch none 0.5)
			(connect_pads
				(clearance 0)
			)
			(min_thickness 0.25)
			(keepout
				(tracks allowed)
				(vias not_allowed)
				(pads allowed)
				(copperpour not_allowed)
				(footprints allowed)
			)
			(placement
				(enabled no)
				(sheetname "")
			)
			(fill
				(thermal_gap 0.5)
				(thermal_bridge_width 0.5)
				(island_removal_mode 0)
			)
			(polygon
				(pts
					(xy 33.8455 -76.962) (xy 33.4645 -76.962) (xy 33.4645 -76.454) (xy 33.8455 -76.454)
				)
			)
		)
	)
	(footprint ""
		(layer "F.Cu")
		(at 27.559 -65.913 90)
		(property "Reference" "RT17"
			(at 1.01473 0.656336 0)
			(unlocked yes)
			(layer "F.SilkS")
			(effects
				(font
					(size 0.4064 0.254)
					(thickness 0.1524)
				)
			)
		)
		(property "Value" ""
			(at 0 0 90)
			(layer "F.Fab")
			(effects
				(font
					(size 1.27 1.27)
				)
			)
		)
		(duplicate_pad_numbers_are_jumpers no)
		(fp_poly
			(pts
				(xy -0.4953 -0.2032) (xy 0.4953 -0.2032) (xy 0.4953 1.6002) (xy -0.4953 1.6002)
			)
			(stroke
				(width 0)
				(type default)
			)
			(fill no)
			(layer "F.CrtYd")
		)
		(fp_line
			(start 0.4953 -0.2032)
			(end 0.4953 1.6002)
			(stroke
				(width 0.1)
				(type default)
			)
			(layer "F.Fab")
		)
		(fp_line
			(start -0.4953 -0.2032)
			(end 0.4953 -0.2032)
			(stroke
				(width 0.1)
				(type default)
			)
			(layer "F.Fab")
		)
		(fp_line
			(start 0.4953 1.6002)
			(end -0.4953 1.6002)
			(stroke
				(width 0.1)
				(type default)
			)
			(layer "F.Fab")
		)
		(fp_line
			(start -0.4953 1.6002)
			(end -0.4953 -0.2032)
			(stroke
				(width 0.1)
				(type default)
			)
			(layer "F.Fab")
		)
		(pad "1" smd rect
			(at 0 0 90)
			(size 0.762 0.889)
			(layers "F.Cu" "F.Mask" "F.Paste")
			(net "VR_PVCCIN_CPU1_PH2_BOOT")
		)
		(pad "2" smd rect
			(at 0 1.397 90)
			(size 0.762 0.889)
			(layers "F.Cu" "F.Mask" "F.Paste")
			(net "VR_PVCCIN_CPU1_PH2_BOOT_R")
		)
		(zone
			(layer "F.Cu")
			(hatch none 0.5)
			(connect_pads
				(clearance 0)
			)
			(min_thickness 0.25)
			(keepout
				(tracks allowed)
				(vias not_allowed)
				(pads allowed)
				(copperpour not_allowed)
				(footprints allowed)
			)
			(placement
				(enabled no)
				(sheetname "")
			)
			(fill
				(thermal_gap 0.5)
				(thermal_bridge_width 0.5)
				(island_removal_mode 0)
			)
			(polygon
				(pts
					(xy 28.5115 -66.294) (xy 28.0035 -66.294) (xy 28.0035 -65.532) (xy 28.5115 -65.532)
				)
			)
		)
		(zone
			(layer "F.Cu")
			(hatch none 0.5)
			(connect_pads
				(clearance 0)
			)
			(min_thickness 0.25)
			(keepout
				(tracks not_allowed)
				(vias allowed)
				(pads allowed)
				(copperpour not_allowed)
				(footprints allowed)
			)
			(placement
				(enabled no)
				(sheetname "")
			)
			(fill
				(thermal_gap 0.5)
				(thermal_bridge_width 0.5)
				(island_removal_mode 0)
			)
			(polygon
				(pts
					(xy 28.5115 -65.532) (xy 28.5115 -66.294) (xy 28.0035 -66.294) (xy 28.0035 -65.532)
				)
			)
		)
	)
	(footprint ""
		(layer "F.Cu")
		(at 245.7577 -12.954 -90)
		(property "Reference" "C5G1"
			(at 1.848866 0.752348 270)
			(unlocked yes)
			(layer "F.SilkS")
			(effects
				(font
					(size 1.27 0.9652)
					(thickness 0.1524)
				)
			)
		)
		(property "Value" ""
			(at 0 0 270)
			(layer "F.Fab")
			(effects
				(font
					(size 1.27 1.27)
				)
			)
		)
		(duplicate_pad_numbers_are_jumpers no)
		(fp_rect
			(start -0.500126 1.598422)
			(end 0.500126 -0.201422)
			(stroke
				(width 0)
				(type default)
			)
			(fill no)
			(layer "F.CrtYd")
		)
		(fp_line
			(start -0.500126 1.598422)
			(end -0.500126 -0.201422)
			(stroke
				(width 0.1)
				(type default)
			)
			(layer "F.Fab")
		)
		(fp_line
			(start 0.500126 1.598422)
			(end -0.500126 1.598422)
			(stroke
				(width 0.1)
				(type default)
			)
			(layer "F.Fab")
		)
		(fp_line
			(start -0.500126 -0.201422)
			(end 0.500126 -0.201422)
			(stroke
				(width 0.1)
				(type default)
			)
			(layer "F.Fab")
		)
		(fp_line
			(start 0.500126 -0.201422)
			(end 0.500126 1.598422)
			(stroke
				(width 0.1)
				(type default)
			)
			(layer "F.Fab")
		)
		(pad "1" smd rect
			(at 0 0 180)
			(size 0.889 0.9906)
			(layers "F.Cu" "F.Mask" "F.Paste")
			(net "PVDDQ_ABC")
		)
		(pad "2" smd rect
			(at 0 1.397 180)
			(size 0.889 0.9906)
			(layers "F.Cu" "F.Mask" "F.Paste")
			(net "GND")
		)
		(zone
			(layer "F.Cu")
			(hatch none 0.5)
			(connect_pads
				(clearance 0)
			)
			(min_thickness 0.25)
			(keepout
				(tracks allowed)
				(vias not_allowed)
				(pads allowed)
				(copperpour not_allowed)
				(footprints allowed)
			)
			(placement
				(enabled no)
				(sheetname "")
			)
			(fill
				(thermal_gap 0.5)
				(thermal_bridge_width 0.5)
				(island_removal_mode 0)
			)
			(polygon
				(pts
					(xy 244.8052 -13.4493) (xy 244.8052 -12.4587) (xy 245.3132 -12.4587) (xy 245.3132 -13.4493)
				)
			)
		)
		(zone
			(layer "F.Cu")
			(hatch none 0.5)
			(connect_pads
				(clearance 0)
			)
			(min_thickness 0.25)
			(keepout
				(tracks not_allowed)
				(vias allowed)
				(pads allowed)
				(copperpour not_allowed)
				(footprints allowed)
			)
			(placement
				(enabled no)
				(sheetname "")
			)
			(fill
				(thermal_gap 0.5)
				(thermal_bridge_width 0.5)
				(island_removal_mode 0)
			)
			(polygon
				(pts
					(xy 244.8052 -13.4493) (xy 244.8052 -12.4587) (xy 245.3132 -12.4587) (xy 245.3132 -13.4493)
				)
			)
		)
	)
	(footprint ""
		(layer "F.Cu")
		(at 204.089 -106.68 90)
		(property "Reference" "R6N2"
			(at -0.8382 -0.67818 90)
			(unlocked yes)
			(layer "F.SilkS")
			(effects
				(font
					(size 0.4064 0.254)
					(thickness 0.1524)
				)
				(justify left)
			)
		)
		(property "Value" ""
			(at 0 0 90)
			(layer "F.Fab")
			(effects
				(font
					(size 1.27 1.27)
				)
			)
		)
		(duplicate_pad_numbers_are_jumpers no)
		(fp_poly
			(pts
				(xy -0.2794 -0.1016) (xy 0.2794 -0.1016) (xy 0.2794 0.9906) (xy -0.2794 0.9906)
			)
			(stroke
				(width 0)
				(type default)
			)
			(fill no)
			(layer "F.CrtYd")
		)
		(fp_line
			(start 0.2794 -0.1016)
			(end -0.2794 -0.1016)
			(stroke
				(width 0.1)
				(type default)
			)
			(layer "F.Fab")
		)
		(fp_line
			(start -0.2794 -0.1016)
			(end -0.2794 0.9906)
			(stroke
				(width 0.1)
				(type default)
			)
			(layer "F.Fab")
		)
		(fp_line
			(start 0.2794 0.9906)
			(end 0.2794 -0.1016)
			(stroke
				(width 0.1)
				(type default)
			)
			(layer "F.Fab")
		)
		(fp_line
			(start -0.2794 0.9906)
			(end 0.2794 0.9906)
			(stroke
				(width 0.1)
				(type default)
			)
			(layer "F.Fab")
		)
		(pad "1" smd rect
			(at 0 0 90)
			(size 0.508 0.508)
			(layers "F.Cu" "F.Mask" "F.Paste")
			(net "SVID_DIO0_CPU0_R")
		)
		(pad "2" smd rect
			(at 0 0.889 90)
			(size 0.508 0.508)
			(layers "F.Cu" "F.Mask" "F.Paste")
			(net "PVCCIO_CPU0")
		)
		(zone
			(layer "F.Cu")
			(hatch none 0.5)
			(connect_pads
				(clearance 0)
			)
			(min_thickness 0.25)
			(keepout
				(tracks allowed)
				(vias not_allowed)
				(pads allowed)
				(copperpour not_allowed)
				(footprints allowed)
			)
			(placement
				(enabled no)
				(sheetname "")
			)
			(fill
				(thermal_gap 0.5)
				(thermal_bridge_width 0.5)
				(island_removal_mode 0)
			)
			(polygon
				(pts
					(xy 204.343 -106.426) (xy 204.343 -106.934) (xy 204.724 -106.934) (xy 204.724 -106.426)
				)
			)
		)
		(zone
			(layer "F.Cu")
			(hatch none 0.5)
			(connect_pads
				(clearance 0)
			)
			(min_thickness 0.25)
			(keepout
				(tracks not_allowed)
				(vias allowed)
				(pads allowed)
				(copperpour not_allowed)
				(footprints allowed)
			)
			(placement
				(enabled no)
				(sheetname "")
			)
			(fill
				(thermal_gap 0.5)
				(thermal_bridge_width 0.5)
				(island_removal_mode 0)
			)
			(polygon
				(pts
					(xy 204.724 -106.426) (xy 204.724 -106.934) (xy 204.343 -106.934) (xy 204.343 -106.426)
				)
			)
		)
	)
	(footprint ""
		(layer "F.Cu")
		(at 399.770092 0.779526 90)
		(property "Reference" "R8G18"
			(at 0 0 90)
			(layer "F.SilkS")
			(hide yes)
			(effects
				(font
					(size 1.27 1.27)
				)
			)
		)
		(property "Value" ""
			(at 0 0 90)
			(layer "F.Fab")
			(effects
				(font
					(size 1.27 1.27)
				)
			)
		)
		(duplicate_pad_numbers_are_jumpers no)
		(fp_poly
			(pts
				(xy -0.2794 -0.1016) (xy 0.2794 -0.1016) (xy 0.2794 0.9906) (xy -0.2794 0.9906)
			)
			(stroke
				(width 0)
				(type default)
			)
			(fill no)
			(layer "F.CrtYd")
		)
		(fp_line
			(start 0.2794 -0.1016)
			(end -0.2794 -0.1016)
			(stroke
				(width 0.1)
				(type default)
			)
			(layer "F.Fab")
		)
		(fp_line
			(start -0.2794 -0.1016)
			(end -0.2794 0.9906)
			(stroke
				(width 0.1)
				(type default)
			)
			(layer "F.Fab")
		)
		(fp_line
			(start 0.2794 0.9906)
			(end 0.2794 -0.1016)
			(stroke
				(width 0.1)
				(type default)
			)
			(layer "F.Fab")
		)
		(fp_line
			(start -0.2794 0.9906)
			(end 0.2794 0.9906)
			(stroke
				(width 0.1)
				(type default)
			)
			(layer "F.Fab")
		)
		(pad "1" smd rect
			(at 0 0 90)
			(size 0.508 0.508)
			(layers "F.Cu" "F.Mask" "F.Paste")
			(net "JTAG_PLD_TCK")
		)
		(pad "2" smd rect
			(at 0 0.889 90)
			(size 0.508 0.508)
			(layers "F.Cu" "F.Mask" "F.Paste")
			(net "JTAG_PLD_TCK_MUX")
		)
		(zone
			(layer "F.Cu")
			(hatch none 0.5)
			(connect_pads
				(clearance 0)
			)
			(min_thickness 0.25)
			(keepout
				(tracks allowed)
				(vias not_allowed)
				(pads allowed)
				(copperpour not_allowed)
				(footprints allowed)
			)
			(placement
				(enabled no)
				(sheetname "")
			)
			(fill
				(thermal_gap 0.5)
				(thermal_bridge_width 0.5)
				(island_removal_mode 0)
			)
			(polygon
				(pts
					(xy 400.024092 1.033526) (xy 400.024092 0.525526) (xy 400.405092 0.525526) (xy 400.405092 1.033526)
				)
			)
		)
		(zone
			(layer "F.Cu")
			(hatch none 0.5)
			(connect_pads
				(clearance 0)
			)
			(min_thickness 0.25)
			(keepout
				(tracks not_allowed)
				(vias allowed)
				(pads allowed)
				(copperpour not_allowed)
				(footprints allowed)
			)
			(placement
				(enabled no)
				(sheetname "")
			)
			(fill
				(thermal_gap 0.5)
				(thermal_bridge_width 0.5)
				(island_removal_mode 0)
			)
			(polygon
				(pts
					(xy 400.405092 1.033526) (xy 400.405092 0.525526) (xy 400.024092 0.525526) (xy 400.024092 1.033526)
				)
			)
		)
	)
	(footprint ""
		(layer "F.Cu")
		(at 13.462 -50.927 90)
		(property "Reference" "C1E17"
			(at 0 0 90)
			(layer "F.SilkS")
			(hide yes)
			(effects
				(font
					(size 1.27 1.27)
				)
			)
		)
		(property "Value" ""
			(at 0 0 90)
			(layer "F.Fab")
			(effects
				(font
					(size 1.27 1.27)
				)
			)
		)
		(duplicate_pad_numbers_are_jumpers no)
		(fp_rect
			(start -0.3048 -0.1016)
			(end 0.3048 0.9906)
			(stroke
				(width 0)
				(type default)
			)
			(fill no)
			(layer "F.CrtYd")
		)
		(fp_line
			(start 0.3048 -0.1016)
			(end -0.3048 -0.1016)
			(stroke
				(width 0.1)
				(type default)
			)
			(layer "F.Fab")
		)
		(fp_line
			(start -0.3048 -0.1016)
			(end -0.3048 0.9906)
			(stroke
				(width 0.1)
				(type default)
			)
			(layer "F.Fab")
		)
		(fp_line
			(start 0.3048 0.9906)
			(end 0.3048 -0.1016)
			(stroke
				(width 0.1)
				(type default)
			)
			(layer "F.Fab")
		)
		(fp_line
			(start -0.3048 0.9906)
			(end 0.3048 0.9906)
			(stroke
				(width 0.1)
				(type default)
			)
			(layer "F.Fab")
		)
		(pad "1" smd rect
			(at 0 0 90)
			(size 0.508 0.508)
			(layers "F.Cu" "F.Mask" "F.Paste")
			(net "P12V_PSU")
		)
		(pad "2" smd rect
			(at 0 0.889 90)
			(size 0.508 0.508)
			(layers "F.Cu" "F.Mask" "F.Paste")
			(net "GND")
		)
		(zone
			(layer "F.Cu")
			(hatch none 0.5)
			(connect_pads
				(clearance 0)
			)
			(min_thickness 0.25)
			(keepout
				(tracks allowed)
				(vias not_allowed)
				(pads allowed)
				(copperpour not_allowed)
				(footprints allowed)
			)
			(placement
				(enabled no)
				(sheetname "")
			)
			(fill
				(thermal_gap 0.5)
				(thermal_bridge_width 0.5)
				(island_removal_mode 0)
			)
			(polygon
				(pts
					(xy 13.716 -50.673) (xy 14.097 -50.673) (xy 14.097 -51.181) (xy 13.716 -51.181)
				)
			)
		)
		(zone
			(layer "F.Cu")
			(hatch none 0.5)
			(connect_pads
				(clearance 0)
			)
			(min_thickness 0.25)
			(keepout
				(tracks not_allowed)
				(vias allowed)
				(pads allowed)
				(copperpour not_allowed)
				(footprints allowed)
			)
			(placement
				(enabled no)
				(sheetname "")
			)
			(fill
				(thermal_gap 0.5)
				(thermal_bridge_width 0.5)
				(island_removal_mode 0)
			)
			(polygon
				(pts
					(xy 13.716 -50.673) (xy 14.097 -50.673) (xy 14.097 -51.181) (xy 13.716 -51.181)
				)
			)
		)
	)
	(footprint ""
		(layer "F.Cu")
		(at 19.195288 -4.574032 -90)
		(property "Reference" "C1G17"
			(at 0 0 270)
			(layer "F.SilkS")
			(hide yes)
			(effects
				(font
					(size 1.27 1.27)
				)
			)
		)
		(property "Value" ""
			(at 0 0 270)
			(layer "F.Fab")
			(effects
				(font
					(size 1.27 1.27)
				)
			)
		)
		(duplicate_pad_numbers_are_jumpers no)
		(fp_poly
			(pts
				(xy -0.7239 -0.2159) (xy 0.7239 -0.2159) (xy 0.7239 1.9939) (xy -0.7239 1.9939)
			)
			(stroke
				(width 0)
				(type default)
			)
			(fill no)
			(layer "F.CrtYd")
		)
		(fp_line
			(start -0.7239 1.9939)
			(end 0.7239 1.9939)
			(stroke
				(width 0.1)
				(type default)
			)
			(layer "F.Fab")
		)
		(fp_line
			(start 0.7239 1.9939)
			(end 0.7239 -0.2159)
			(stroke
				(width 0.1)
				(type default)
			)
			(layer "F.Fab")
		)
		(fp_line
			(start -0.7239 -0.2159)
			(end -0.7239 1.9939)
			(stroke
				(width 0.1)
				(type default)
			)
			(layer "F.Fab")
		)
		(fp_line
			(start 0.7239 -0.2159)
			(end -0.7239 -0.2159)
			(stroke
				(width 0.1)
				(type default)
			)
			(layer "F.Fab")
		)
		(pad "1" smd rect
			(at 0 0 270)
			(size 1.27 1.016)
			(layers "F.Cu" "F.Mask" "F.Paste")
			(net "PVDDQ_GHJ")
		)
		(pad "2" smd rect
			(at 0 1.778 270)
			(size 1.27 1.016)
			(layers "F.Cu" "F.Mask" "F.Paste")
			(net "GND")
		)
		(zone
			(layer "F.Cu")
			(hatch none 0.5)
			(connect_pads
				(clearance 0)
			)
			(min_thickness 0.25)
			(keepout
				(tracks not_allowed)
				(vias allowed)
				(pads allowed)
				(copperpour not_allowed)
				(footprints allowed)
			)
			(placement
				(enabled no)
				(sheetname "")
			)
			(fill
				(thermal_gap 0.5)
				(thermal_bridge_width 0.5)
				(island_removal_mode 0)
			)
			(polygon
				(pts
					(xy 18.687288 -5.209032) (xy 18.687288 -3.939032) (xy 17.925288 -3.939032) (xy 17.925288 -5.209032)
				)
			)
		)
	)
	(footprint ""
		(layer "F.Cu")
		(at 7.238746 -109.65307 90)
		(property "Reference" "C9M4"
			(at 0 0 90)
			(layer "F.SilkS")
			(hide yes)
			(effects
				(font
					(size 1.27 1.27)
				)
			)
		)
		(property "Value" ""
			(at 0 0 90)
			(layer "F.Fab")
			(effects
				(font
					(size 1.27 1.27)
				)
			)
		)
		(duplicate_pad_numbers_are_jumpers no)
		(fp_poly
			(pts
				(xy -0.7239 -0.2159) (xy 0.7239 -0.2159) (xy 0.7239 1.9939) (xy -0.7239 1.9939)
			)
			(stroke
				(width 0)
				(type default)
			)
			(fill no)
			(layer "F.CrtYd")
		)
		(fp_line
			(start 0.7239 -0.2159)
			(end -0.7239 -0.2159)
			(stroke
				(width 0.1)
				(type default)
			)
			(layer "F.Fab")
		)
		(fp_line
			(start -0.7239 -0.2159)
			(end -0.7239 1.9939)
			(stroke
				(width 0.1)
				(type default)
			)
			(layer "F.Fab")
		)
		(fp_line
			(start 0.7239 1.9939)
			(end 0.7239 -0.2159)
			(stroke
				(width 0.1)
				(type default)
			)
			(layer "F.Fab")
		)
		(fp_line
			(start -0.7239 1.9939)
			(end 0.7239 1.9939)
			(stroke
				(width 0.1)
				(type default)
			)
			(layer "F.Fab")
		)
		(pad "1" smd rect
			(at 0 0 90)
			(size 1.27 1.016)
			(layers "F.Cu" "F.Mask" "F.Paste")
			(net "P12V_FAN")
		)
		(pad "2" smd rect
			(at 0 1.778 90)
			(size 1.27 1.016)
			(layers "F.Cu" "F.Mask" "F.Paste")
			(net "GND")
		)
		(zone
			(layer "F.Cu")
			(hatch none 0.5)
			(connect_pads
				(clearance 0)
			)
			(min_thickness 0.25)
			(keepout
				(tracks not_allowed)
				(vias allowed)
				(pads allowed)
				(copperpour not_allowed)
				(footprints allowed)
			)
			(placement
				(enabled no)
				(sheetname "")
			)
			(fill
				(thermal_gap 0.5)
				(thermal_bridge_width 0.5)
				(island_removal_mode 0)
			)
			(polygon
				(pts
					(xy 7.746746 -109.01807) (xy 7.746746 -110.28807) (xy 8.508746 -110.28807) (xy 8.508746 -109.01807)
				)
			)
		)
	)
	(footprint ""
		(layer "F.Cu")
		(at 166.37 -70.6374 180)
		(property "Reference" "R4D46"
			(at 0 0 180)
			(layer "F.SilkS")
			(hide yes)
			(effects
				(font
					(size 1.27 1.27)
				)
			)
		)
		(property "Value" ""
			(at 0 0 180)
			(layer "F.Fab")
			(effects
				(font
					(size 1.27 1.27)
				)
			)
		)
		(duplicate_pad_numbers_are_jumpers no)
		(fp_poly
			(pts
				(xy -0.2794 -0.1016) (xy 0.2794 -0.1016) (xy 0.2794 0.9906) (xy -0.2794 0.9906)
			)
			(stroke
				(width 0)
				(type default)
			)
			(fill no)
			(layer "F.CrtYd")
		)
		(fp_line
			(start 0.2794 0.9906)
			(end 0.2794 -0.1016)
			(stroke
				(width 0.1)
				(type default)
			)
			(layer "F.Fab")
		)
		(fp_line
			(start 0.2794 -0.1016)
			(end -0.2794 -0.1016)
			(stroke
				(width 0.1)
				(type default)
			)
			(layer "F.Fab")
		)
		(fp_line
			(start -0.2794 0.9906)
			(end 0.2794 0.9906)
			(stroke
				(width 0.1)
				(type default)
			)
			(layer "F.Fab")
		)
		(fp_line
			(start -0.2794 -0.1016)
			(end -0.2794 0.9906)
			(stroke
				(width 0.1)
				(type default)
			)
			(layer "F.Fab")
		)
		(pad "1" smd rect
			(at 0 0 180)
			(size 0.508 0.508)
			(layers "F.Cu" "F.Mask" "F.Paste")
			(net "PWRGD_PVCCIO_CPU1_R")
		)
		(pad "2" smd rect
			(at 0 0.889 180)
			(size 0.508 0.508)
			(layers "F.Cu" "F.Mask" "F.Paste")
			(net "PWRGD_PVCCIO_CPU1")
		)
		(zone
			(layer "F.Cu")
			(hatch none 0.5)
			(connect_pads
				(clearance 0)
			)
			(min_thickness 0.25)
			(keepout
				(tracks not_allowed)
				(vias allowed)
				(pads allowed)
				(copperpour not_allowed)
				(footprints allowed)
			)
			(placement
				(enabled no)
				(sheetname "")
			)
			(fill
				(thermal_gap 0.5)
				(thermal_bridge_width 0.5)
				(island_removal_mode 0)
			)
			(polygon
				(pts
					(xy 166.624 -71.2724) (xy 166.116 -71.2724) (xy 166.116 -70.8914) (xy 166.624 -70.8914)
				)
			)
		)
		(zone
			(layer "F.Cu")
			(hatch none 0.5)
			(connect_pads
				(clearance 0)
			)
			(min_thickness 0.25)
			(keepout
				(tracks allowed)
				(vias not_allowed)
				(pads allowed)
				(copperpour not_allowed)
				(footprints allowed)
			)
			(placement
				(enabled no)
				(sheetname "")
			)
			(fill
				(thermal_gap 0.5)
				(thermal_bridge_width 0.5)
				(island_removal_mode 0)
			)
			(polygon
				(pts
					(xy 166.624 -70.8914) (xy 166.116 -70.8914) (xy 166.116 -71.2724) (xy 166.624 -71.2724)
				)
			)
		)
	)
	(footprint ""
		(layer "F.Cu")
		(at 101.92004 -73.318116)
		(property "Reference" "C2D37"
			(at 0 0 0)
			(layer "F.SilkS")
			(hide yes)
			(effects
				(font
					(size 1.27 1.27)
				)
			)
		)
		(property "Value" ""
			(at 0 0 0)
			(layer "F.Fab")
			(effects
				(font
					(size 1.27 1.27)
				)
			)
		)
		(duplicate_pad_numbers_are_jumpers no)
		(fp_poly
			(pts
				(xy -0.4953 -0.2032) (xy 0.4953 -0.2032) (xy 0.4953 1.6002) (xy -0.4953 1.6002)
			)
			(stroke
				(width 0)
				(type default)
			)
			(fill no)
			(layer "F.CrtYd")
		)
		(fp_line
			(start -0.4953 -0.2032)
			(end 0.4953 -0.2032)
			(stroke
				(width 0.1)
				(type default)
			)
			(layer "F.Fab")
		)
		(fp_line
			(start -0.4953 1.6002)
			(end -0.4953 -0.2032)
			(stroke
				(width 0.1)
				(type default)
			)
			(layer "F.Fab")
		)
		(fp_line
			(start 0.4953 -0.2032)
			(end 0.4953 1.6002)
			(stroke
				(width 0.1)
				(type default)
			)
			(layer "F.Fab")
		)
		(fp_line
			(start 0.4953 1.6002)
			(end -0.4953 1.6002)
			(stroke
				(width 0.1)
				(type default)
			)
			(layer "F.Fab")
		)
		(pad "1" smd rect
			(at 0 0)
			(size 0.762 0.889)
			(layers "F.Cu" "F.Mask" "F.Paste")
			(net "PVCCIN_CPU1")
		)
		(pad "2" smd rect
			(at 0 1.397)
			(size 0.762 0.889)
			(layers "F.Cu" "F.Mask" "F.Paste")
			(net "GND")
		)
		(zone
			(layer "F.Cu")
			(hatch none 0.5)
			(connect_pads
				(clearance 0)
			)
			(min_thickness 0.25)
			(keepout
				(tracks not_allowed)
				(vias allowed)
				(pads allowed)
				(copperpour not_allowed)
				(footprints allowed)
			)
			(placement
				(enabled no)
				(sheetname "")
			)
			(fill
				(thermal_gap 0.5)
				(thermal_bridge_width 0.5)
				(island_removal_mode 0)
			)
			(polygon
				(pts
					(xy 101.53904 -72.873616) (xy 102.30104 -72.873616) (xy 102.30104 -72.365616) (xy 101.53904 -72.365616)
				)
			)
		)
	)
	(footprint ""
		(layer "F.Cu")
		(at 476.031814 -22.405848)
		(property "Reference" "C9F1"
			(at 0 0 0)
			(layer "F.SilkS")
			(hide yes)
			(effects
				(font
					(size 1.27 1.27)
				)
			)
		)
		(property "Value" "*"
			(at -0.0762 -6.2357 0)
			(unlocked yes)
			(layer "F.Fab")
			(hide yes)
			(effects
				(font
					(size 1.27 1.016)
					(thickness 0.1524)
				)
			)
		)
		(property "Device Type" "SC22U16V5MX-4-GP_SMD-BCG5-SC22A"
			(at -0.0762 -8.2677 0)
			(unlocked yes)
			(layer "F.Fab")
			(hide yes)
			(effects
				(font
					(size 1.27 1.016)
					(thickness 0.1524)
				)
			)
		)
		(duplicate_pad_numbers_are_jumpers no)
		(fp_line
			(start 0.635 0)
			(end -0.635 0)
			(stroke
				(width 0.508)
				(type default)
			)
			(layer "F.SilkS")
		)
		(fp_rect
			(start -0.9652 1.778)
			(end 0.9652 -1.778)
			(stroke
				(width 0)
				(type default)
			)
			(fill no)
			(layer "F.CrtYd")
		)
		(fp_poly
			(pts
				(xy -0.9652 -1.778) (xy 0.9652 -1.778) (xy 0.9652 1.778) (xy -0.9652 1.778)
			)
			(stroke
				(width 0)
				(type default)
			)
			(fill no)
			(layer "F.Fab")
		)
		(pad "1" smd rect
			(at 0 -0.9652)
			(size 1.397 1.143)
			(layers "F.Cu" "F.Mask" "F.Paste")
			(net "VR_FET_SW_P12V_STBY_P3V3_STBY")
		)
		(pad "2" smd rect
			(at 0 0.9652)
			(size 1.397 1.143)
			(layers "F.Cu" "F.Mask" "F.Paste")
			(net "GND")
		)
	)
	(footprint ""
		(layer "F.Cu")
		(at 498.620034 -137.278618 90)
		(property "Reference" "DS9A7"
			(at -0.76073 0.85344 0)
			(unlocked yes)
			(layer "F.SilkS")
			(effects
				(font
					(size 0.7874 0.5842)
					(thickness 0.1524)
				)
			)
		)
		(property "Value" ""
			(at 0 0 90)
			(layer "F.Fab")
			(effects
				(font
					(size 1.27 1.27)
				)
			)
		)
		(duplicate_pad_numbers_are_jumpers no)
		(fp_line
			(start -1.353312 -0.498094)
			(end -1.353312 0.413512)
			(stroke
				(width 0.1524)
				(type default)
			)
			(layer "F.SilkS")
		)
		(fp_line
			(start -0.87249 0.413512)
			(end -1.353312 1.246378)
			(stroke
				(width 0.1524)
				(type default)
			)
			(layer "F.SilkS")
		)
		(fp_line
			(start -1.353312 0.413512)
			(end -0.87249 0.413512)
			(stroke
				(width 0.1524)
				(type default)
			)
			(layer "F.SilkS")
		)
		(fp_line
			(start -1.834134 0.413512)
			(end -1.353312 0.413512)
			(stroke
				(width 0.1524)
				(type default)
			)
			(layer "F.SilkS")
		)
		(fp_line
			(start -1.353312 1.246378)
			(end -1.834134 0.413512)
			(stroke
				(width 0.1524)
				(type default)
			)
			(layer "F.SilkS")
		)
		(fp_line
			(start -1.834134 1.246378)
			(end -0.87249 1.246378)
			(stroke
				(width 0.1524)
				(type default)
			)
			(layer "F.SilkS")
		)
		(fp_line
			(start -1.353312 2.36982)
			(end -1.353312 1.246378)
			(stroke
				(width 0.1524)
				(type default)
			)
			(layer "F.SilkS")
		)
		(fp_rect
			(start -0.4064 1.6891)
			(end 0.4064 0.0889)
			(stroke
				(width 0)
				(type default)
			)
			(fill no)
			(layer "F.CrtYd")
		)
		(fp_line
			(start 0.4064 0.0889)
			(end 0.4064 1.6891)
			(stroke
				(width 0.1)
				(type default)
			)
			(layer "F.Fab")
		)
		(fp_line
			(start -0.4064 0.0889)
			(end 0.4064 0.0889)
			(stroke
				(width 0.1)
				(type default)
			)
			(layer "F.Fab")
		)
		(fp_line
			(start -0.87249 0.413512)
			(end -1.353312 1.246378)
			(stroke
				(width 0.1)
				(type default)
			)
			(layer "F.Fab")
		)
		(fp_line
			(start -1.353312 0.413512)
			(end -1.353312 -0.498094)
			(stroke
				(width 0.1)
				(type default)
			)
			(layer "F.Fab")
		)
		(fp_line
			(start -1.834134 0.413512)
			(end -0.87249 0.413512)
			(stroke
				(width 0.1)
				(type default)
			)
			(layer "F.Fab")
		)
		(fp_line
			(start -1.353312 1.246378)
			(end -1.834134 0.413512)
			(stroke
				(width 0.1)
				(type default)
			)
			(layer "F.Fab")
		)
		(fp_line
			(start -1.353312 1.246378)
			(end -1.353312 2.36982)
			(stroke
				(width 0.1)
				(type default)
			)
			(layer "F.Fab")
		)
		(fp_line
			(start -1.834134 1.246378)
			(end -0.87249 1.246378)
			(stroke
				(width 0.1)
				(type default)
			)
			(layer "F.Fab")
		)
		(fp_line
			(start 0.4064 1.6891)
			(end -0.4064 1.6891)
			(stroke
				(width 0.1)
				(type default)
			)
			(layer "F.Fab")
		)
		(fp_line
			(start -0.4064 1.6891)
			(end -0.4064 0.0889)
			(stroke
				(width 0.1)
				(type default)
			)
			(layer "F.Fab")
		)
		(pad "1" smd rect
			(at 0 0 90)
			(size 0.762 1.27)
			(layers "F.Cu" "F.Mask" "F.Paste")
			(net "FM_UARTSW_MSB_R_N")
		)
		(pad "2" smd rect
			(at 0 1.778 90)
			(size 0.762 1.27)
			(layers "F.Cu" "F.Mask" "F.Paste")
			(net "FM_UARTSW_MSB_N")
		)
		(zone
			(layer "F.Cu")
			(hatch none 0.5)
			(connect_pads
				(clearance 0)
			)
			(min_thickness 0.25)
			(keepout
				(tracks not_allowed)
				(vias allowed)
				(pads allowed)
				(copperpour not_allowed)
				(footprints allowed)
			)
			(placement
				(enabled no)
				(sheetname "")
			)
			(fill
				(thermal_gap 0.5)
				(thermal_bridge_width 0.5)
				(island_removal_mode 0)
			)
			(polygon
				(pts
					(xy 499.280434 -136.897618) (xy 499.280434 -137.659618) (xy 499.737634 -137.659618) (xy 499.737634 -136.897618)
				)
			)
		)
		(zone
			(layer "F.Cu")
			(hatch none 0.5)
			(connect_pads
				(clearance 0)
			)
			(min_thickness 0.25)
			(keepout
				(tracks allowed)
				(vias not_allowed)
				(pads allowed)
				(copperpour not_allowed)
				(footprints allowed)
			)
			(placement
				(enabled no)
				(sheetname "")
			)
			(fill
				(thermal_gap 0.5)
				(thermal_bridge_width 0.5)
				(island_removal_mode 0)
			)
			(polygon
				(pts
					(xy 499.737634 -136.897618) (xy 499.737634 -137.659618) (xy 499.280434 -137.659618) (xy 499.280434 -136.897618)
				)
			)
		)
	)
	(footprint ""
		(layer "F.Cu")
		(at 195.5546 -130.2512 90)
		(property "Reference" "C4B12"
			(at 0 0 90)
			(layer "F.SilkS")
			(hide yes)
			(effects
				(font
					(size 1.27 1.27)
				)
			)
		)
		(property "Value" ""
			(at 0 0 90)
			(layer "F.Fab")
			(effects
				(font
					(size 1.27 1.27)
				)
			)
		)
		(duplicate_pad_numbers_are_jumpers no)
		(fp_poly
			(pts
				(xy 0.3048 -0.1016) (xy 0.3048 0.9906) (xy -0.3048 0.9906) (xy -0.3048 -0.1016)
			)
			(stroke
				(width 0)
				(type default)
			)
			(fill no)
			(layer "F.CrtYd")
		)
		(fp_line
			(start 0.3048 -0.1016)
			(end -0.3048 -0.1016)
			(stroke
				(width 0.1)
				(type default)
			)
			(layer "F.Fab")
		)
		(fp_line
			(start -0.3048 -0.1016)
			(end -0.3048 0.9906)
			(stroke
				(width 0.1)
				(type default)
			)
			(layer "F.Fab")
		)
		(fp_line
			(start 0.3048 0.9906)
			(end 0.3048 -0.1016)
			(stroke
				(width 0.1)
				(type default)
			)
			(layer "F.Fab")
		)
		(fp_line
			(start -0.3048 0.9906)
			(end 0.3048 0.9906)
			(stroke
				(width 0.1)
				(type default)
			)
			(layer "F.Fab")
		)
		(pad "1" smd rect
			(at 0 0 90)
			(size 0.508 0.508)
			(layers "F.Cu" "F.Mask" "F.Paste")
			(net "M_D_VREF")
		)
		(pad "2" smd rect
			(at 0 0.889 90)
			(size 0.508 0.508)
			(layers "F.Cu" "F.Mask" "F.Paste")
			(net "GND")
		)
		(zone
			(layer "F.Cu")
			(hatch none 0.5)
			(connect_pads
				(clearance 0)
			)
			(min_thickness 0.25)
			(keepout
				(tracks allowed)
				(vias not_allowed)
				(pads allowed)
				(copperpour not_allowed)
				(footprints allowed)
			)
			(placement
				(enabled no)
				(sheetname "")
			)
			(fill
				(thermal_gap 0.5)
				(thermal_bridge_width 0.5)
				(island_removal_mode 0)
			)
			(polygon
				(pts
					(xy 195.8086 -129.9972) (xy 195.8086 -130.5052) (xy 196.1896 -130.5052) (xy 196.1896 -129.9972)
				)
			)
		)
		(zone
			(layer "F.Cu")
			(hatch none 0.5)
			(connect_pads
				(clearance 0)
			)
			(min_thickness 0.25)
			(keepout
				(tracks not_allowed)
				(vias allowed)
				(pads allowed)
				(copperpour not_allowed)
				(footprints allowed)
			)
			(placement
				(enabled no)
				(sheetname "")
			)
			(fill
				(thermal_gap 0.5)
				(thermal_bridge_width 0.5)
				(island_removal_mode 0)
			)
			(polygon
				(pts
					(xy 196.1896 -129.9972) (xy 196.1896 -130.5052) (xy 195.8086 -130.5052) (xy 195.8086 -129.9972)
				)
			)
		)
	)
	(footprint ""
		(layer "F.Cu")
		(at 168.656 -86.868 180)
		(property "Reference" "R4D4"
			(at 0 0 180)
			(layer "F.SilkS")
			(hide yes)
			(effects
				(font
					(size 1.27 1.27)
				)
			)
		)
		(property "Value" ""
			(at 0 0 180)
			(layer "F.Fab")
			(effects
				(font
					(size 1.27 1.27)
				)
			)
		)
		(duplicate_pad_numbers_are_jumpers no)
		(fp_poly
			(pts
				(xy -0.2794 -0.1016) (xy 0.2794 -0.1016) (xy 0.2794 0.9906) (xy -0.2794 0.9906)
			)
			(stroke
				(width 0)
				(type default)
			)
			(fill no)
			(layer "F.CrtYd")
		)
		(fp_line
			(start 0.2794 0.9906)
			(end 0.2794 -0.1016)
			(stroke
				(width 0.1)
				(type default)
			)
			(layer "F.Fab")
		)
		(fp_line
			(start 0.2794 -0.1016)
			(end -0.2794 -0.1016)
			(stroke
				(width 0.1)
				(type default)
			)
			(layer "F.Fab")
		)
		(fp_line
			(start -0.2794 0.9906)
			(end 0.2794 0.9906)
			(stroke
				(width 0.1)
				(type default)
			)
			(layer "F.Fab")
		)
		(fp_line
			(start -0.2794 -0.1016)
			(end -0.2794 0.9906)
			(stroke
				(width 0.1)
				(type default)
			)
			(layer "F.Fab")
		)
		(pad "1" smd rect
			(at 0 0 180)
			(size 0.508 0.508)
			(layers "F.Cu" "F.Mask" "F.Paste")
			(net "CLK_100M_CPU1_BCLK0_R_DP")
		)
		(pad "2" smd rect
			(at 0 0.889 180)
			(size 0.508 0.508)
			(layers "F.Cu" "F.Mask" "F.Paste")
			(net "CLK_100M_CPU1_BCLK0_DP")
		)
		(zone
			(layer "F.Cu")
			(hatch none 0.5)
			(connect_pads
				(clearance 0)
			)
			(min_thickness 0.25)
			(keepout
				(tracks not_allowed)
				(vias allowed)
				(pads allowed)
				(copperpour not_allowed)
				(footprints allowed)
			)
			(placement
				(enabled no)
				(sheetname "")
			)
			(fill
				(thermal_gap 0.5)
				(thermal_bridge_width 0.5)
				(island_removal_mode 0)
			)
			(polygon
				(pts
					(xy 168.91 -87.503) (xy 168.402 -87.503) (xy 168.402 -87.122) (xy 168.91 -87.122)
				)
			)
		)
		(zone
			(layer "F.Cu")
			(hatch none 0.5)
			(connect_pads
				(clearance 0)
			)
			(min_thickness 0.25)
			(keepout
				(tracks allowed)
				(vias not_allowed)
				(pads allowed)
				(copperpour not_allowed)
				(footprints allowed)
			)
			(placement
				(enabled no)
				(sheetname "")
			)
			(fill
				(thermal_gap 0.5)
				(thermal_bridge_width 0.5)
				(island_removal_mode 0)
			)
			(polygon
				(pts
					(xy 168.91 -87.122) (xy 168.402 -87.122) (xy 168.402 -87.503) (xy 168.91 -87.503)
				)
			)
		)
	)
	(footprint ""
		(layer "F.Cu")
		(at 437.7055 -14.605 -90)
		(property "Reference" "R1U55"
			(at 0 0 270)
			(layer "F.SilkS")
			(hide yes)
			(effects
				(font
					(size 1.27 1.27)
				)
			)
		)
		(property "Value" ""
			(at 0 0 270)
			(layer "F.Fab")
			(effects
				(font
					(size 1.27 1.27)
				)
			)
		)
		(duplicate_pad_numbers_are_jumpers no)
		(fp_poly
			(pts
				(xy -0.2794 -0.1016) (xy 0.2794 -0.1016) (xy 0.2794 0.9906) (xy -0.2794 0.9906)
			)
			(stroke
				(width 0)
				(type default)
			)
			(fill no)
			(layer "F.CrtYd")
		)
		(fp_line
			(start -0.2794 0.9906)
			(end 0.2794 0.9906)
			(stroke
				(width 0.1)
				(type default)
			)
			(layer "F.Fab")
		)
		(fp_line
			(start 0.2794 0.9906)
			(end 0.2794 -0.1016)
			(stroke
				(width 0.1)
				(type default)
			)
			(layer "F.Fab")
		)
		(fp_line
			(start -0.2794 -0.1016)
			(end -0.2794 0.9906)
			(stroke
				(width 0.1)
				(type default)
			)
			(layer "F.Fab")
		)
		(fp_line
			(start 0.2794 -0.1016)
			(end -0.2794 -0.1016)
			(stroke
				(width 0.1)
				(type default)
			)
			(layer "F.Fab")
		)
		(pad "1" smd rect
			(at 0 0 270)
			(size 0.508 0.508)
			(layers "F.Cu" "F.Mask" "F.Paste")
			(net "H_CPU1_MEMGHJ_MEMHOT_G_N")
		)
		(pad "2" smd rect
			(at 0 0.889 270)
			(size 0.508 0.508)
			(layers "F.Cu" "F.Mask" "F.Paste")
			(net "H_CPU1_MEMGHJ_MEMHOT_G_PCH_N")
		)
		(zone
			(layer "F.Cu")
			(hatch none 0.5)
			(connect_pads
				(clearance 0)
			)
			(min_thickness 0.25)
			(keepout
				(tracks not_allowed)
				(vias allowed)
				(pads allowed)
				(copperpour not_allowed)
				(footprints allowed)
			)
			(placement
				(enabled no)
				(sheetname "")
			)
			(fill
				(thermal_gap 0.5)
				(thermal_bridge_width 0.5)
				(island_removal_mode 0)
			)
			(polygon
				(pts
					(xy 437.0705 -14.859) (xy 437.0705 -14.351) (xy 437.4515 -14.351) (xy 437.4515 -14.859)
				)
			)
		)
		(zone
			(layer "F.Cu")
			(hatch none 0.5)
			(connect_pads
				(clearance 0)
			)
			(min_thickness 0.25)
			(keepout
				(tracks allowed)
				(vias not_allowed)
				(pads allowed)
				(copperpour not_allowed)
				(footprints allowed)
			)
			(placement
				(enabled no)
				(sheetname "")
			)
			(fill
				(thermal_gap 0.5)
				(thermal_bridge_width 0.5)
				(island_removal_mode 0)
			)
			(polygon
				(pts
					(xy 437.4515 -14.859) (xy 437.4515 -14.351) (xy 437.0705 -14.351) (xy 437.0705 -14.859)
				)
			)
		)
	)
	(footprint ""
		(layer "F.Cu")
		(at 412.742888 -48.071024 180)
		(property "Reference" "R25W141"
			(at -0.8382 -0.67818 180)
			(unlocked yes)
			(layer "F.SilkS")
			(effects
				(font
					(size 0.4064 0.254)
					(thickness 0.1524)
				)
				(justify left)
			)
		)
		(property "Value" ""
			(at 0 0 180)
			(layer "F.Fab")
			(effects
				(font
					(size 1.27 1.27)
				)
			)
		)
		(duplicate_pad_numbers_are_jumpers no)
		(fp_poly
			(pts
				(xy -0.2794 -0.1016) (xy 0.2794 -0.1016) (xy 0.2794 0.9906) (xy -0.2794 0.9906)
			)
			(stroke
				(width 0)
				(type default)
			)
			(fill no)
			(layer "F.CrtYd")
		)
		(fp_line
			(start 0.2794 0.9906)
			(end 0.2794 -0.1016)
			(stroke
				(width 0.1)
				(type default)
			)
			(layer "F.Fab")
		)
		(fp_line
			(start 0.2794 -0.1016)
			(end -0.2794 -0.1016)
			(stroke
				(width 0.1)
				(type default)
			)
			(layer "F.Fab")
		)
		(fp_line
			(start -0.2794 0.9906)
			(end 0.2794 0.9906)
			(stroke
				(width 0.1)
				(type default)
			)
			(layer "F.Fab")
		)
		(fp_line
			(start -0.2794 -0.1016)
			(end -0.2794 0.9906)
			(stroke
				(width 0.1)
				(type default)
			)
			(layer "F.Fab")
		)
		(pad "1" smd rect
			(at 0 0 180)
			(size 0.508 0.508)
			(layers "F.Cu" "F.Mask" "F.Paste")
			(net "RST_PLTRST_BUF_N")
		)
		(pad "2" smd rect
			(at 0 0.889 180)
			(size 0.508 0.508)
			(layers "F.Cu" "F.Mask" "F.Paste")
			(net "RST_PLTRST_BUF_N_R")
		)
		(zone
			(layer "F.Cu")
			(hatch none 0.5)
			(connect_pads
				(clearance 0)
			)
			(min_thickness 0.25)
			(keepout
				(tracks not_allowed)
				(vias allowed)
				(pads allowed)
				(copperpour not_allowed)
				(footprints allowed)
			)
			(placement
				(enabled no)
				(sheetname "")
			)
			(fill
				(thermal_gap 0.5)
				(thermal_bridge_width 0.5)
				(island_removal_mode 0)
			)
			(polygon
				(pts
					(xy 412.996888 -48.706024) (xy 412.488888 -48.706024) (xy 412.488888 -48.325024) (xy 412.996888 -48.325024)
				)
			)
		)
		(zone
			(layer "F.Cu")
			(hatch none 0.5)
			(connect_pads
				(clearance 0)
			)
			(min_thickness 0.25)
			(keepout
				(tracks allowed)
				(vias not_allowed)
				(pads allowed)
				(copperpour not_allowed)
				(footprints allowed)
			)
			(placement
				(enabled no)
				(sheetname "")
			)
			(fill
				(thermal_gap 0.5)
				(thermal_bridge_width 0.5)
				(island_removal_mode 0)
			)
			(polygon
				(pts
					(xy 412.996888 -48.325024) (xy 412.488888 -48.325024) (xy 412.488888 -48.706024) (xy 412.996888 -48.706024)
				)
			)
		)
	)
	(footprint ""
		(layer "F.Cu")
		(at 80.739488 -140.208 -90)
		(property "Reference" "C2A9"
			(at 1.848866 0.752348 270)
			(unlocked yes)
			(layer "F.SilkS")
			(effects
				(font
					(size 1.27 0.9652)
					(thickness 0.1524)
				)
			)
		)
		(property "Value" ""
			(at 0 0 270)
			(layer "F.Fab")
			(effects
				(font
					(size 1.27 1.27)
				)
			)
		)
		(duplicate_pad_numbers_are_jumpers no)
		(fp_rect
			(start -0.500126 1.598422)
			(end 0.500126 -0.201422)
			(stroke
				(width 0)
				(type default)
			)
			(fill no)
			(layer "F.CrtYd")
		)
		(fp_line
			(start -0.500126 1.598422)
			(end -0.500126 -0.201422)
			(stroke
				(width 0.1)
				(type default)
			)
			(layer "F.Fab")
		)
		(fp_line
			(start 0.500126 1.598422)
			(end -0.500126 1.598422)
			(stroke
				(width 0.1)
				(type default)
			)
			(layer "F.Fab")
		)
		(fp_line
			(start -0.500126 -0.201422)
			(end 0.500126 -0.201422)
			(stroke
				(width 0.1)
				(type default)
			)
			(layer "F.Fab")
		)
		(fp_line
			(start 0.500126 -0.201422)
			(end 0.500126 1.598422)
			(stroke
				(width 0.1)
				(type default)
			)
			(layer "F.Fab")
		)
		(pad "1" smd rect
			(at 0 0 180)
			(size 0.889 0.9906)
			(layers "F.Cu" "F.Mask" "F.Paste")
			(net "PVDDQ_KLM")
		)
		(pad "2" smd rect
			(at 0 1.397 180)
			(size 0.889 0.9906)
			(layers "F.Cu" "F.Mask" "F.Paste")
			(net "GND")
		)
		(zone
			(layer "F.Cu")
			(hatch none 0.5)
			(connect_pads
				(clearance 0)
			)
			(min_thickness 0.25)
			(keepout
				(tracks allowed)
				(vias not_allowed)
				(pads allowed)
				(copperpour not_allowed)
				(footprints allowed)
			)
			(placement
				(enabled no)
				(sheetname "")
			)
			(fill
				(thermal_gap 0.5)
				(thermal_bridge_width 0.5)
				(island_removal_mode 0)
			)
			(polygon
				(pts
					(xy 79.786988 -140.7033) (xy 79.786988 -139.7127) (xy 80.294988 -139.7127) (xy 80.294988 -140.7033)
				)
			)
		)
		(zone
			(layer "F.Cu")
			(hatch none 0.5)
			(connect_pads
				(clearance 0)
			)
			(min_thickness 0.25)
			(keepout
				(tracks not_allowed)
				(vias allowed)
				(pads allowed)
				(copperpour not_allowed)
				(footprints allowed)
			)
			(placement
				(enabled no)
				(sheetname "")
			)
			(fill
				(thermal_gap 0.5)
				(thermal_bridge_width 0.5)
				(island_removal_mode 0)
			)
			(polygon
				(pts
					(xy 79.786988 -140.7033) (xy 79.786988 -139.7127) (xy 80.294988 -139.7127) (xy 80.294988 -140.7033)
				)
			)
		)
	)
	(footprint ""
		(layer "F.Cu")
		(at 183.769 -61.976 180)
		(property "Reference" "R4E10"
			(at 0 0 180)
			(layer "F.SilkS")
			(hide yes)
			(effects
				(font
					(size 1.27 1.27)
				)
			)
		)
		(property "Value" ""
			(at 0 0 180)
			(layer "F.Fab")
			(effects
				(font
					(size 1.27 1.27)
				)
			)
		)
		(duplicate_pad_numbers_are_jumpers no)
		(fp_rect
			(start 0.2794 -0.1016)
			(end -0.2794 0.9906)
			(stroke
				(width 0)
				(type default)
			)
			(fill no)
			(layer "F.CrtYd")
		)
		(fp_line
			(start 0.2794 0.9906)
			(end 0.2794 -0.1016)
			(stroke
				(width 0.1)
				(type default)
			)
			(layer "F.Fab")
		)
		(fp_line
			(start 0.2794 -0.1016)
			(end -0.2794 -0.1016)
			(stroke
				(width 0.1)
				(type default)
			)
			(layer "F.Fab")
		)
		(fp_line
			(start -0.2794 0.9906)
			(end 0.2794 0.9906)
			(stroke
				(width 0.1)
				(type default)
			)
			(layer "F.Fab")
		)
		(fp_line
			(start -0.2794 -0.1016)
			(end -0.2794 0.9906)
			(stroke
				(width 0.1)
				(type default)
			)
			(layer "F.Fab")
		)
		(pad "1" smd rect
			(at 0 0 180)
			(size 0.508 0.508)
			(layers "F.Cu" "F.Mask" "F.Paste")
			(net "PVCCIO_CPU0")
		)
		(pad "2" smd rect
			(at 0 0.889 180)
			(size 0.508 0.508)
			(layers "F.Cu" "F.Mask" "F.Paste")
			(net "SVID_DIO0_CPU0_R")
		)
		(zone
			(layer "F.Cu")
			(hatch none 0.5)
			(connect_pads
				(clearance 0)
			)
			(min_thickness 0.25)
			(keepout
				(tracks allowed)
				(vias not_allowed)
				(pads allowed)
				(copperpour not_allowed)
				(footprints allowed)
			)
			(placement
				(enabled no)
				(sheetname "")
			)
			(fill
				(thermal_gap 0.5)
				(thermal_bridge_width 0.5)
				(island_removal_mode 0)
			)
			(polygon
				(pts
					(xy 183.515 -62.23) (xy 184.023 -62.23) (xy 184.023 -62.611) (xy 183.515 -62.611)
				)
			)
		)
		(zone
			(layer "F.Cu")
			(hatch none 0.5)
			(connect_pads
				(clearance 0)
			)
			(min_thickness 0.25)
			(keepout
				(tracks not_allowed)
				(vias allowed)
				(pads allowed)
				(copperpour not_allowed)
				(footprints allowed)
			)
			(placement
				(enabled no)
				(sheetname "")
			)
			(fill
				(thermal_gap 0.5)
				(thermal_bridge_width 0.5)
				(island_removal_mode 0)
			)
			(polygon
				(pts
					(xy 183.515 -62.23) (xy 184.023 -62.23) (xy 184.023 -62.611) (xy 183.515 -62.611)
				)
			)
		)
	)
	(footprint ""
		(layer "F.Cu")
		(at 487.970576 -30.186376)
		(property "Reference" "R9F64"
			(at 0 0 0)
			(layer "F.SilkS")
			(hide yes)
			(effects
				(font
					(size 1.27 1.27)
				)
			)
		)
		(property "Value" ""
			(at 0 0 0)
			(layer "F.Fab")
			(effects
				(font
					(size 1.27 1.27)
				)
			)
		)
		(duplicate_pad_numbers_are_jumpers no)
		(fp_poly
			(pts
				(xy -0.2794 -0.1016) (xy 0.2794 -0.1016) (xy 0.2794 0.9906) (xy -0.2794 0.9906)
			)
			(stroke
				(width 0)
				(type default)
			)
			(fill no)
			(layer "F.CrtYd")
		)
		(fp_line
			(start -0.2794 -0.1016)
			(end -0.2794 0.9906)
			(stroke
				(width 0.1)
				(type default)
			)
			(layer "F.Fab")
		)
		(fp_line
			(start -0.2794 0.9906)
			(end 0.2794 0.9906)
			(stroke
				(width 0.1)
				(type default)
			)
			(layer "F.Fab")
		)
		(fp_line
			(start 0.2794 -0.1016)
			(end -0.2794 -0.1016)
			(stroke
				(width 0.1)
				(type default)
			)
			(layer "F.Fab")
		)
		(fp_line
			(start 0.2794 0.9906)
			(end 0.2794 -0.1016)
			(stroke
				(width 0.1)
				(type default)
			)
			(layer "F.Fab")
		)
		(pad "1" smd rect
			(at 0 0)
			(size 0.508 0.508)
			(layers "F.Cu" "F.Mask" "F.Paste")
			(net "SP2_BMC_CM_UART_TX_R1")
		)
		(pad "2" smd rect
			(at 0 0.889)
			(size 0.508 0.508)
			(layers "F.Cu" "F.Mask" "F.Paste")
			(net "SPA_MID_DBG_RX_R")
		)
		(zone
			(layer "F.Cu")
			(hatch none 0.5)
			(connect_pads
				(clearance 0)
			)
			(min_thickness 0.25)
			(keepout
				(tracks allowed)
				(vias not_allowed)
				(pads allowed)
				(copperpour not_allowed)
				(footprints allowed)
			)
			(placement
				(enabled no)
				(sheetname "")
			)
			(fill
				(thermal_gap 0.5)
				(thermal_bridge_width 0.5)
				(island_removal_mode 0)
			)
			(polygon
				(pts
					(xy 487.716576 -29.932376) (xy 488.224576 -29.932376) (xy 488.224576 -29.551376) (xy 487.716576 -29.551376)
				)
			)
		)
		(zone
			(layer "F.Cu")
			(hatch none 0.5)
			(connect_pads
				(clearance 0)
			)
			(min_thickness 0.25)
			(keepout
				(tracks not_allowed)
				(vias allowed)
				(pads allowed)
				(copperpour not_allowed)
				(footprints allowed)
			)
			(placement
				(enabled no)
				(sheetname "")
			)
			(fill
				(thermal_gap 0.5)
				(thermal_bridge_width 0.5)
				(island_removal_mode 0)
			)
			(polygon
				(pts
					(xy 487.716576 -29.551376) (xy 488.224576 -29.551376) (xy 488.224576 -29.932376) (xy 487.716576 -29.932376)
				)
			)
		)
	)
	(footprint ""
		(layer "F.Cu")
		(at 110.908592 -77.429614)
		(property "Reference" "C3D13"
			(at 0 0 0)
			(layer "F.SilkS")
			(hide yes)
			(effects
				(font
					(size 1.27 1.27)
				)
			)
		)
		(property "Value" ""
			(at 0 0 0)
			(layer "F.Fab")
			(effects
				(font
					(size 1.27 1.27)
				)
			)
		)
		(duplicate_pad_numbers_are_jumpers no)
		(fp_poly
			(pts
				(xy -0.4953 -0.2032) (xy 0.4953 -0.2032) (xy 0.4953 1.6002) (xy -0.4953 1.6002)
			)
			(stroke
				(width 0)
				(type default)
			)
			(fill no)
			(layer "F.CrtYd")
		)
		(fp_line
			(start -0.4953 -0.2032)
			(end 0.4953 -0.2032)
			(stroke
				(width 0.1)
				(type default)
			)
			(layer "F.Fab")
		)
		(fp_line
			(start -0.4953 1.6002)
			(end -0.4953 -0.2032)
			(stroke
				(width 0.1)
				(type default)
			)
			(layer "F.Fab")
		)
		(fp_line
			(start 0.4953 -0.2032)
			(end 0.4953 1.6002)
			(stroke
				(width 0.1)
				(type default)
			)
			(layer "F.Fab")
		)
		(fp_line
			(start 0.4953 1.6002)
			(end -0.4953 1.6002)
			(stroke
				(width 0.1)
				(type default)
			)
			(layer "F.Fab")
		)
		(pad "1" smd rect
			(at 0 0)
			(size 0.762 0.889)
			(layers "F.Cu" "F.Mask" "F.Paste")
			(net "PVCCMCP_CPU1")
		)
		(pad "2" smd rect
			(at 0 1.397)
			(size 0.762 0.889)
			(layers "F.Cu" "F.Mask" "F.Paste")
			(net "GND")
		)
		(zone
			(layer "F.Cu")
			(hatch none 0.5)
			(connect_pads
				(clearance 0)
			)
			(min_thickness 0.25)
			(keepout
				(tracks not_allowed)
				(vias allowed)
				(pads allowed)
				(copperpour not_allowed)
				(footprints allowed)
			)
			(placement
				(enabled no)
				(sheetname "")
			)
			(fill
				(thermal_gap 0.5)
				(thermal_bridge_width 0.5)
				(island_removal_mode 0)
			)
			(polygon
				(pts
					(xy 110.527592 -76.985114) (xy 111.289592 -76.985114) (xy 111.289592 -76.477114) (xy 110.527592 -76.477114)
				)
			)
		)
	)
	(footprint ""
		(layer "F.Cu")
		(at 320.6115 -124.587 90)
		(property "Reference" "C6B4"
			(at -0.8382 -0.67818 90)
			(unlocked yes)
			(layer "F.SilkS")
			(effects
				(font
					(size 0.4064 0.254)
					(thickness 0.1524)
				)
				(justify left)
			)
		)
		(property "Value" ""
			(at 0 0 90)
			(layer "F.Fab")
			(effects
				(font
					(size 1.27 1.27)
				)
			)
		)
		(duplicate_pad_numbers_are_jumpers no)
		(fp_poly
			(pts
				(xy 0.3048 -0.1016) (xy 0.3048 0.9906) (xy -0.3048 0.9906) (xy -0.3048 -0.1016)
			)
			(stroke
				(width 0)
				(type default)
			)
			(fill no)
			(layer "F.CrtYd")
		)
		(fp_line
			(start 0.3048 -0.1016)
			(end -0.3048 -0.1016)
			(stroke
				(width 0.1)
				(type default)
			)
			(layer "F.Fab")
		)
		(fp_line
			(start -0.3048 -0.1016)
			(end -0.3048 0.9906)
			(stroke
				(width 0.1)
				(type default)
			)
			(layer "F.Fab")
		)
		(fp_line
			(start 0.3048 0.9906)
			(end 0.3048 -0.1016)
			(stroke
				(width 0.1)
				(type default)
			)
			(layer "F.Fab")
		)
		(fp_line
			(start -0.3048 0.9906)
			(end 0.3048 0.9906)
			(stroke
				(width 0.1)
				(type default)
			)
			(layer "F.Fab")
		)
		(pad "1" smd rect
			(at 0 0 90)
			(size 0.508 0.508)
			(layers "F.Cu" "F.Mask" "F.Paste")
			(net "P3E_CPU0_PE1_PCH_TXN<15>")
		)
		(pad "2" smd rect
			(at 0 0.889 90)
			(size 0.508 0.508)
			(layers "F.Cu" "F.Mask" "F.Paste")
			(net "P3E_CPU0_PE1_PCH_C_TXN<15>")
		)
		(zone
			(layer "F.Cu")
			(hatch none 0.5)
			(connect_pads
				(clearance 0)
			)
			(min_thickness 0.25)
			(keepout
				(tracks allowed)
				(vias not_allowed)
				(pads allowed)
				(copperpour not_allowed)
				(footprints allowed)
			)
			(placement
				(enabled no)
				(sheetname "")
			)
			(fill
				(thermal_gap 0.5)
				(thermal_bridge_width 0.5)
				(island_removal_mode 0)
			)
			(polygon
				(pts
					(xy 320.8655 -124.333) (xy 320.8655 -124.841) (xy 321.2465 -124.841) (xy 321.2465 -124.333)
				)
			)
		)
		(zone
			(layer "F.Cu")
			(hatch none 0.5)
			(connect_pads
				(clearance 0)
			)
			(min_thickness 0.25)
			(keepout
				(tracks not_allowed)
				(vias allowed)
				(pads allowed)
				(copperpour not_allowed)
				(footprints allowed)
			)
			(placement
				(enabled no)
				(sheetname "")
			)
			(fill
				(thermal_gap 0.5)
				(thermal_bridge_width 0.5)
				(island_removal_mode 0)
			)
			(polygon
				(pts
					(xy 321.2465 -124.333) (xy 321.2465 -124.841) (xy 320.8655 -124.841) (xy 320.8655 -124.333)
				)
			)
		)
	)
	(footprint ""
		(layer "F.Cu")
		(at 17.526 -86.8172 180)
		(property "Reference" "R1D9"
			(at 0 0 180)
			(layer "F.SilkS")
			(hide yes)
			(effects
				(font
					(size 1.27 1.27)
				)
			)
		)
		(property "Value" ""
			(at 0 0 180)
			(layer "F.Fab")
			(effects
				(font
					(size 1.27 1.27)
				)
			)
		)
		(duplicate_pad_numbers_are_jumpers no)
		(fp_rect
			(start 0.2794 -0.1016)
			(end -0.2794 0.9906)
			(stroke
				(width 0)
				(type default)
			)
			(fill no)
			(layer "F.CrtYd")
		)
		(fp_line
			(start 0.2794 0.9906)
			(end 0.2794 -0.1016)
			(stroke
				(width 0.1)
				(type default)
			)
			(layer "F.Fab")
		)
		(fp_line
			(start 0.2794 -0.1016)
			(end -0.2794 -0.1016)
			(stroke
				(width 0.1)
				(type default)
			)
			(layer "F.Fab")
		)
		(fp_line
			(start -0.2794 0.9906)
			(end 0.2794 0.9906)
			(stroke
				(width 0.1)
				(type default)
			)
			(layer "F.Fab")
		)
		(fp_line
			(start -0.2794 -0.1016)
			(end -0.2794 0.9906)
			(stroke
				(width 0.1)
				(type default)
			)
			(layer "F.Fab")
		)
		(pad "1" smd rect
			(at 0 0 180)
			(size 0.508 0.508)
			(layers "F.Cu" "F.Mask" "F.Paste")
			(net "SVID_CLK0_CPU1_R")
		)
		(pad "2" smd rect
			(at 0 0.889 180)
			(size 0.508 0.508)
			(layers "F.Cu" "F.Mask" "F.Paste")
			(net "SVID_VCLK_PVCCIN_CPU1")
		)
		(zone
			(layer "F.Cu")
			(hatch none 0.5)
			(connect_pads
				(clearance 0)
			)
			(min_thickness 0.25)
			(keepout
				(tracks not_allowed)
				(vias allowed)
				(pads allowed)
				(copperpour not_allowed)
				(footprints allowed)
			)
			(placement
				(enabled no)
				(sheetname "")
			)
			(fill
				(thermal_gap 0.5)
				(thermal_bridge_width 0.5)
				(island_removal_mode 0)
			)
			(polygon
				(pts
					(xy 17.272 -87.0712) (xy 17.78 -87.0712) (xy 17.78 -87.4522) (xy 17.272 -87.4522)
				)
			)
		)
		(zone
			(layer "F.Cu")
			(hatch none 0.5)
			(connect_pads
				(clearance 0)
			)
			(min_thickness 0.25)
			(keepout
				(tracks allowed)
				(vias not_allowed)
				(pads allowed)
				(copperpour not_allowed)
				(footprints allowed)
			)
			(placement
				(enabled no)
				(sheetname "")
			)
			(fill
				(thermal_gap 0.5)
				(thermal_bridge_width 0.5)
				(island_removal_mode 0)
			)
			(polygon
				(pts
					(xy 17.272 -87.0712) (xy 17.78 -87.0712) (xy 17.78 -87.4522) (xy 17.272 -87.4522)
				)
			)
		)
	)
	(footprint ""
		(layer "F.Cu")
		(at 24.1554 -41.2242 -90)
		(property "Reference" "R1E12"
			(at 0 0 270)
			(layer "F.SilkS")
			(hide yes)
			(effects
				(font
					(size 1.27 1.27)
				)
			)
		)
		(property "Value" ""
			(at 0 0 270)
			(layer "F.Fab")
			(effects
				(font
					(size 1.27 1.27)
				)
			)
		)
		(duplicate_pad_numbers_are_jumpers no)
		(fp_rect
			(start 0.2794 0.9906)
			(end -0.2794 -0.1016)
			(stroke
				(width 0)
				(type default)
			)
			(fill no)
			(layer "F.CrtYd")
		)
		(fp_line
			(start -0.2794 0.9906)
			(end 0.2794 0.9906)
			(stroke
				(width 0.1)
				(type default)
			)
			(layer "F.Fab")
		)
		(fp_line
			(start 0.2794 0.9906)
			(end 0.2794 -0.1016)
			(stroke
				(width 0.1)
				(type default)
			)
			(layer "F.Fab")
		)
		(fp_line
			(start -0.2794 -0.1016)
			(end -0.2794 0.9906)
			(stroke
				(width 0.1)
				(type default)
			)
			(layer "F.Fab")
		)
		(fp_line
			(start 0.2794 -0.1016)
			(end -0.2794 -0.1016)
			(stroke
				(width 0.1)
				(type default)
			)
			(layer "F.Fab")
		)
		(pad "1" smd rect
			(at 0 0 270)
			(size 0.508 0.508)
			(layers "F.Cu" "F.Mask" "F.Paste")
			(net "P5V_STBY")
		)
		(pad "2" smd rect
			(at 0 0.889 270)
			(size 0.508 0.508)
			(layers "F.Cu" "F.Mask" "F.Paste")
			(net "FAN_PWM_OUT_SYS0_R")
		)
		(zone
			(layer "F.Cu")
			(hatch none 0.5)
			(connect_pads
				(clearance 0)
			)
			(min_thickness 0.25)
			(keepout
				(tracks not_allowed)
				(vias allowed)
				(pads allowed)
				(copperpour not_allowed)
				(footprints allowed)
			)
			(placement
				(enabled no)
				(sheetname "")
			)
			(fill
				(thermal_gap 0.5)
				(thermal_bridge_width 0.5)
				(island_removal_mode 0)
			)
			(polygon
				(pts
					(xy 23.5204 -40.9702) (xy 23.9014 -40.9702) (xy 23.9014 -41.4782) (xy 23.5204 -41.4782)
				)
			)
		)
		(zone
			(layer "F.Cu")
			(hatch none 0.5)
			(connect_pads
				(clearance 0)
			)
			(min_thickness 0.25)
			(keepout
				(tracks allowed)
				(vias not_allowed)
				(pads allowed)
				(copperpour not_allowed)
				(footprints allowed)
			)
			(placement
				(enabled no)
				(sheetname "")
			)
			(fill
				(thermal_gap 0.5)
				(thermal_bridge_width 0.5)
				(island_removal_mode 0)
			)
			(polygon
				(pts
					(xy 23.5204 -40.9702) (xy 23.9014 -40.9702) (xy 23.9014 -41.4782) (xy 23.5204 -41.4782)
				)
			)
		)
	)
	(footprint ""
		(layer "F.Cu")
		(at 178.689 -66.548 90)
		(property "Reference" "R4D58"
			(at 0 0 90)
			(layer "F.SilkS")
			(hide yes)
			(effects
				(font
					(size 1.27 1.27)
				)
			)
		)
		(property "Value" ""
			(at 0 0 90)
			(layer "F.Fab")
			(effects
				(font
					(size 1.27 1.27)
				)
			)
		)
		(duplicate_pad_numbers_are_jumpers no)
		(fp_rect
			(start -0.2794 -0.1016)
			(end 0.2794 0.9906)
			(stroke
				(width 0)
				(type default)
			)
			(fill no)
			(layer "F.CrtYd")
		)
		(fp_line
			(start 0.2794 -0.1016)
			(end -0.2794 -0.1016)
			(stroke
				(width 0.1)
				(type default)
			)
			(layer "F.Fab")
		)
		(fp_line
			(start -0.2794 -0.1016)
			(end -0.2794 0.9906)
			(stroke
				(width 0.1)
				(type default)
			)
			(layer "F.Fab")
		)
		(fp_line
			(start 0.2794 0.9906)
			(end 0.2794 -0.1016)
			(stroke
				(width 0.1)
				(type default)
			)
			(layer "F.Fab")
		)
		(fp_line
			(start -0.2794 0.9906)
			(end 0.2794 0.9906)
			(stroke
				(width 0.1)
				(type default)
			)
			(layer "F.Fab")
		)
		(pad "1" smd rect
			(at 0 0 90)
			(size 0.508 0.508)
			(layers "F.Cu" "F.Mask" "F.Paste")
			(net "P3V3_STBY")
		)
		(pad "2" smd rect
			(at 0 0.889 90)
			(size 0.508 0.508)
			(layers "F.Cu" "F.Mask" "F.Paste")
			(net "VR_VRRDY_PVCCIN_CPU0")
		)
		(zone
			(layer "F.Cu")
			(hatch none 0.5)
			(connect_pads
				(clearance 0)
			)
			(min_thickness 0.25)
			(keepout
				(tracks not_allowed)
				(vias allowed)
				(pads allowed)
				(copperpour not_allowed)
				(footprints allowed)
			)
			(placement
				(enabled no)
				(sheetname "")
			)
			(fill
				(thermal_gap 0.5)
				(thermal_bridge_width 0.5)
				(island_removal_mode 0)
			)
			(polygon
				(pts
					(xy 178.943 -66.294) (xy 179.324 -66.294) (xy 179.324 -66.802) (xy 178.943 -66.802)
				)
			)
		)
		(zone
			(layer "F.Cu")
			(hatch none 0.5)
			(connect_pads
				(clearance 0)
			)
			(min_thickness 0.25)
			(keepout
				(tracks allowed)
				(vias not_allowed)
				(pads allowed)
				(copperpour not_allowed)
				(footprints allowed)
			)
			(placement
				(enabled no)
				(sheetname "")
			)
			(fill
				(thermal_gap 0.5)
				(thermal_bridge_width 0.5)
				(island_removal_mode 0)
			)
			(polygon
				(pts
					(xy 178.943 -66.294) (xy 179.324 -66.294) (xy 179.324 -66.802) (xy 178.943 -66.802)
				)
			)
		)
	)
	(footprint ""
		(layer "F.Cu")
		(at 413.3215 -112.649 -90)
		(property "Reference" "R2T29"
			(at 0 0 270)
			(layer "F.SilkS")
			(hide yes)
			(effects
				(font
					(size 1.27 1.27)
				)
			)
		)
		(property "Value" ""
			(at 0 0 270)
			(layer "F.Fab")
			(effects
				(font
					(size 1.27 1.27)
				)
			)
		)
		(duplicate_pad_numbers_are_jumpers no)
		(fp_poly
			(pts
				(xy -0.2794 -0.1016) (xy 0.2794 -0.1016) (xy 0.2794 0.9906) (xy -0.2794 0.9906)
			)
			(stroke
				(width 0)
				(type default)
			)
			(fill no)
			(layer "F.CrtYd")
		)
		(fp_line
			(start -0.2794 0.9906)
			(end 0.2794 0.9906)
			(stroke
				(width 0.1)
				(type default)
			)
			(layer "F.Fab")
		)
		(fp_line
			(start 0.2794 0.9906)
			(end 0.2794 -0.1016)
			(stroke
				(width 0.1)
				(type default)
			)
			(layer "F.Fab")
		)
		(fp_line
			(start -0.2794 -0.1016)
			(end -0.2794 0.9906)
			(stroke
				(width 0.1)
				(type default)
			)
			(layer "F.Fab")
		)
		(fp_line
			(start 0.2794 -0.1016)
			(end -0.2794 -0.1016)
			(stroke
				(width 0.1)
				(type default)
			)
			(layer "F.Fab")
		)
		(pad "1" smd rect
			(at 0 0 270)
			(size 0.508 0.508)
			(layers "F.Cu" "F.Mask" "F.Paste")
			(net "P3V3_STBY")
		)
		(pad "2" smd rect
			(at 0 0.889 270)
			(size 0.508 0.508)
			(layers "F.Cu" "F.Mask" "F.Paste")
			(net "IRQ_OOB_MGMT_RISER_ALERT_N")
		)
		(zone
			(layer "F.Cu")
			(hatch none 0.5)
			(connect_pads
				(clearance 0)
			)
			(min_thickness 0.25)
			(keepout
				(tracks not_allowed)
				(vias allowed)
				(pads allowed)
				(copperpour not_allowed)
				(footprints allowed)
			)
			(placement
				(enabled no)
				(sheetname "")
			)
			(fill
				(thermal_gap 0.5)
				(thermal_bridge_width 0.5)
				(island_removal_mode 0)
			)
			(polygon
				(pts
					(xy 412.6865 -112.903) (xy 412.6865 -112.395) (xy 413.0675 -112.395) (xy 413.0675 -112.903)
				)
			)
		)
		(zone
			(layer "F.Cu")
			(hatch none 0.5)
			(connect_pads
				(clearance 0)
			)
			(min_thickness 0.25)
			(keepout
				(tracks allowed)
				(vias not_allowed)
				(pads allowed)
				(copperpour not_allowed)
				(footprints allowed)
			)
			(placement
				(enabled no)
				(sheetname "")
			)
			(fill
				(thermal_gap 0.5)
				(thermal_bridge_width 0.5)
				(island_removal_mode 0)
			)
			(polygon
				(pts
					(xy 413.0675 -112.903) (xy 413.0675 -112.395) (xy 412.6865 -112.395) (xy 412.6865 -112.903)
				)
			)
		)
	)
	(footprint ""
		(layer "F.Cu")
		(at 380.032768 -32.3215 -90)
		(property "Reference" "C8F12"
			(at 0 0 270)
			(layer "F.SilkS")
			(hide yes)
			(effects
				(font
					(size 1.27 1.27)
				)
			)
		)
		(property "Value" ""
			(at 0 0 270)
			(layer "F.Fab")
			(effects
				(font
					(size 1.27 1.27)
				)
			)
		)
		(duplicate_pad_numbers_are_jumpers no)
		(fp_poly
			(pts
				(xy 0.3048 -0.1016) (xy 0.3048 0.9906) (xy -0.3048 0.9906) (xy -0.3048 -0.1016)
			)
			(stroke
				(width 0)
				(type default)
			)
			(fill no)
			(layer "F.CrtYd")
		)
		(fp_line
			(start -0.3048 0.9906)
			(end 0.3048 0.9906)
			(stroke
				(width 0.1)
				(type default)
			)
			(layer "F.Fab")
		)
		(fp_line
			(start 0.3048 0.9906)
			(end 0.3048 -0.1016)
			(stroke
				(width 0.1)
				(type default)
			)
			(layer "F.Fab")
		)
		(fp_line
			(start -0.3048 -0.1016)
			(end -0.3048 0.9906)
			(stroke
				(width 0.1)
				(type default)
			)
			(layer "F.Fab")
		)
		(fp_line
			(start 0.3048 -0.1016)
			(end -0.3048 -0.1016)
			(stroke
				(width 0.1)
				(type default)
			)
			(layer "F.Fab")
		)
		(pad "1" smd rect
			(at 0 0 270)
			(size 0.508 0.508)
			(layers "F.Cu" "F.Mask" "F.Paste")
			(net "P3E_PCH_TX_0_DN")
		)
		(pad "2" smd rect
			(at 0 0.889 270)
			(size 0.508 0.508)
			(layers "F.Cu" "F.Mask" "F.Paste")
			(net "P3E_PCH_M2_SATA6G_TX_R_DN")
		)
		(zone
			(layer "F.Cu")
			(hatch none 0.5)
			(connect_pads
				(clearance 0)
			)
			(min_thickness 0.25)
			(keepout
				(tracks not_allowed)
				(vias allowed)
				(pads allowed)
				(copperpour not_allowed)
				(footprints allowed)
			)
			(placement
				(enabled no)
				(sheetname "")
			)
			(fill
				(thermal_gap 0.5)
				(thermal_bridge_width 0.5)
				(island_removal_mode 0)
			)
			(polygon
				(pts
					(xy 379.397768 -32.5755) (xy 379.397768 -32.0675) (xy 379.778768 -32.0675) (xy 379.778768 -32.5755)
				)
			)
		)
		(zone
			(layer "F.Cu")
			(hatch none 0.5)
			(connect_pads
				(clearance 0)
			)
			(min_thickness 0.25)
			(keepout
				(tracks allowed)
				(vias not_allowed)
				(pads allowed)
				(copperpour not_allowed)
				(footprints allowed)
			)
			(placement
				(enabled no)
				(sheetname "")
			)
			(fill
				(thermal_gap 0.5)
				(thermal_bridge_width 0.5)
				(island_removal_mode 0)
			)
			(polygon
				(pts
					(xy 379.778768 -32.5755) (xy 379.778768 -32.0675) (xy 379.397768 -32.0675) (xy 379.397768 -32.5755)
				)
			)
		)
	)
	(footprint ""
		(layer "F.Cu")
		(at 190.754 -86.741 -90)
		(property "Reference" "C4D2"
			(at -0.762 7.72033 90)
			(unlocked yes)
			(layer "F.SilkS")
			(effects
				(font
					(size 0.7874 0.5842)
					(thickness 0.1524)
				)
				(justify left)
			)
		)
		(property "Value" ""
			(at 0 0 270)
			(layer "F.Fab")
			(effects
				(font
					(size 1.27 1.27)
				)
			)
		)
		(duplicate_pad_numbers_are_jumpers no)
		(fp_line
			(start -3.400044 6.067044)
			(end -0.9017 6.067044)
			(stroke
				(width 0.1524)
				(type default)
			)
			(layer "F.SilkS")
		)
		(fp_line
			(start 0.9017 6.067044)
			(end 3.400044 6.067044)
			(stroke
				(width 0.1524)
				(type default)
			)
			(layer "F.SilkS")
		)
		(fp_line
			(start 3.400044 6.067044)
			(end 3.400044 0.028956)
			(stroke
				(width 0.1524)
				(type default)
			)
			(layer "F.SilkS")
		)
		(fp_line
			(start -0.9017 1.587754)
			(end -0.7239 1.587754)
			(stroke
				(width 0.1524)
				(type default)
			)
			(layer "F.SilkS")
		)
		(fp_line
			(start 0.7239 1.587754)
			(end 0.9017 1.587754)
			(stroke
				(width 0.1524)
				(type default)
			)
			(layer "F.SilkS")
		)
		(fp_line
			(start 0.9017 1.587754)
			(end 0.9017 -1.714246)
			(stroke
				(width 0.1524)
				(type default)
			)
			(layer "F.SilkS")
		)
		(fp_line
			(start -3.400044 0.028956)
			(end -3.400044 6.067044)
			(stroke
				(width 0.1524)
				(type default)
			)
			(layer "F.SilkS")
		)
		(fp_line
			(start 3.400044 0.028956)
			(end 2.638044 -0.733044)
			(stroke
				(width 0.1524)
				(type default)
			)
			(layer "F.SilkS")
		)
		(fp_line
			(start -2.638044 -0.733044)
			(end -3.400044 0.028956)
			(stroke
				(width 0.1524)
				(type default)
			)
			(layer "F.SilkS")
		)
		(fp_line
			(start -0.9017 -0.733044)
			(end -2.638044 -0.733044)
			(stroke
				(width 0.1524)
				(type default)
			)
			(layer "F.SilkS")
		)
		(fp_line
			(start 2.638044 -0.733044)
			(end 0.9017 -0.733044)
			(stroke
				(width 0.1524)
				(type default)
			)
			(layer "F.SilkS")
		)
		(fp_line
			(start -0.9017 -1.714246)
			(end -0.9017 1.587754)
			(stroke
				(width 0.1524)
				(type default)
			)
			(layer "F.SilkS")
		)
		(fp_line
			(start -0.7239 -1.714246)
			(end -0.9017 -1.714246)
			(stroke
				(width 0.1524)
				(type default)
			)
			(layer "F.SilkS")
		)
		(fp_line
			(start 0.9017 -1.714246)
			(end 0.7239 -1.714246)
			(stroke
				(width 0.1524)
				(type default)
			)
			(layer "F.SilkS")
		)
		(fp_poly
			(pts
				(xy -3.400044 6.067044) (xy 3.400044 6.067044) (xy 3.400044 0.028956) (xy 2.638044 -0.733044) (xy -2.638044 -0.733044)
				(xy -3.400044 0.028956)
			)
			(stroke
				(width 0)
				(type default)
			)
			(fill no)
			(layer "F.CrtYd")
		)
		(fp_line
			(start -3.400044 6.067044)
			(end 3.400044 6.067044)
			(stroke
				(width 0.1)
				(type default)
			)
			(layer "F.Fab")
		)
		(fp_line
			(start 3.400044 6.067044)
			(end 3.400044 0.028956)
			(stroke
				(width 0.1)
				(type default)
			)
			(layer "F.Fab")
		)
		(fp_line
			(start -3.400044 0.028956)
			(end -3.400044 6.067044)
			(stroke
				(width 0.1)
				(type default)
			)
			(layer "F.Fab")
		)
		(fp_line
			(start 3.400044 0.028956)
			(end 2.638044 -0.733044)
			(stroke
				(width 0.1)
				(type default)
			)
			(layer "F.Fab")
		)
		(fp_line
			(start -2.638044 -0.733044)
			(end -3.400044 0.028956)
			(stroke
				(width 0.1)
				(type default)
			)
			(layer "F.Fab")
		)
		(fp_line
			(start 2.638044 -0.733044)
			(end -2.638044 -0.733044)
			(stroke
				(width 0.1)
				(type default)
			)
			(layer "F.Fab")
		)
		(fp_circle
			(center 0 2.667)
			(end 0 -0.733044)
			(stroke
				(width 0.1)
				(type default)
			)
			(fill no)
			(layer "F.Fab")
		)
		(pad "1" smd rect
			(at 0 0 270)
			(size 0.7874 3.429)
			(layers "F.Cu" "F.Mask" "F.Paste")
			(net "VR_FET_SW_P12V_STBY_PVCCIN_CPU0")
		)
		(pad "2" smd rect
			(at 0 5.334 270)
			(size 0.7874 3.429)
			(layers "F.Cu" "F.Mask" "F.Paste")
			(net "GND")
		)
	)
	(footprint ""
		(layer "F.Cu")
		(at 399.923 -149.225 180)
		(property "Reference" "R8A7"
			(at 0 0 180)
			(layer "F.SilkS")
			(hide yes)
			(effects
				(font
					(size 1.27 1.27)
				)
			)
		)
		(property "Value" ""
			(at 0 0 180)
			(layer "F.Fab")
			(effects
				(font
					(size 1.27 1.27)
				)
			)
		)
		(duplicate_pad_numbers_are_jumpers no)
		(fp_poly
			(pts
				(xy -0.2794 -0.1016) (xy 0.2794 -0.1016) (xy 0.2794 0.9906) (xy -0.2794 0.9906)
			)
			(stroke
				(width 0)
				(type default)
			)
			(fill no)
			(layer "F.CrtYd")
		)
		(fp_line
			(start 0.2794 0.9906)
			(end 0.2794 -0.1016)
			(stroke
				(width 0.1)
				(type default)
			)
			(layer "F.Fab")
		)
		(fp_line
			(start 0.2794 -0.1016)
			(end -0.2794 -0.1016)
			(stroke
				(width 0.1)
				(type default)
			)
			(layer "F.Fab")
		)
		(fp_line
			(start -0.2794 0.9906)
			(end 0.2794 0.9906)
			(stroke
				(width 0.1)
				(type default)
			)
			(layer "F.Fab")
		)
		(fp_line
			(start -0.2794 -0.1016)
			(end -0.2794 0.9906)
			(stroke
				(width 0.1)
				(type default)
			)
			(layer "F.Fab")
		)
		(pad "1" smd rect
			(at 0 0 180)
			(size 0.508 0.508)
			(layers "F.Cu" "F.Mask" "F.Paste")
			(net "P3V3_STBY")
		)
		(pad "2" smd rect
			(at 0 0.889 180)
			(size 0.508 0.508)
			(layers "F.Cu" "F.Mask" "F.Paste")
			(net "VR_PVNN_PCH_VREN")
		)
		(zone
			(layer "F.Cu")
			(hatch none 0.5)
			(connect_pads
				(clearance 0)
			)
			(min_thickness 0.25)
			(keepout
				(tracks not_allowed)
				(vias allowed)
				(pads allowed)
				(copperpour not_allowed)
				(footprints allowed)
			)
			(placement
				(enabled no)
				(sheetname "")
			)
			(fill
				(thermal_gap 0.5)
				(thermal_bridge_width 0.5)
				(island_removal_mode 0)
			)
			(polygon
				(pts
					(xy 400.177 -149.86) (xy 399.669 -149.86) (xy 399.669 -149.479) (xy 400.177 -149.479)
				)
			)
		)
		(zone
			(layer "F.Cu")
			(hatch none 0.5)
			(connect_pads
				(clearance 0)
			)
			(min_thickness 0.25)
			(keepout
				(tracks allowed)
				(vias not_allowed)
				(pads allowed)
				(copperpour not_allowed)
				(footprints allowed)
			)
			(placement
				(enabled no)
				(sheetname "")
			)
			(fill
				(thermal_gap 0.5)
				(thermal_bridge_width 0.5)
				(island_removal_mode 0)
			)
			(polygon
				(pts
					(xy 400.177 -149.479) (xy 399.669 -149.479) (xy 399.669 -149.86) (xy 400.177 -149.86)
				)
			)
		)
	)
	(footprint ""
		(layer "F.Cu")
		(at 105.65384 -77.636116)
		(property "Reference" "C2D29"
			(at 0 0 0)
			(layer "F.SilkS")
			(hide yes)
			(effects
				(font
					(size 1.27 1.27)
				)
			)
		)
		(property "Value" ""
			(at 0 0 0)
			(layer "F.Fab")
			(effects
				(font
					(size 1.27 1.27)
				)
			)
		)
		(duplicate_pad_numbers_are_jumpers no)
		(fp_poly
			(pts
				(xy -0.4953 -0.2032) (xy 0.4953 -0.2032) (xy 0.4953 1.6002) (xy -0.4953 1.6002)
			)
			(stroke
				(width 0)
				(type default)
			)
			(fill no)
			(layer "F.CrtYd")
		)
		(fp_line
			(start -0.4953 -0.2032)
			(end 0.4953 -0.2032)
			(stroke
				(width 0.1)
				(type default)
			)
			(layer "F.Fab")
		)
		(fp_line
			(start -0.4953 1.6002)
			(end -0.4953 -0.2032)
			(stroke
				(width 0.1)
				(type default)
			)
			(layer "F.Fab")
		)
		(fp_line
			(start 0.4953 -0.2032)
			(end 0.4953 1.6002)
			(stroke
				(width 0.1)
				(type default)
			)
			(layer "F.Fab")
		)
		(fp_line
			(start 0.4953 1.6002)
			(end -0.4953 1.6002)
			(stroke
				(width 0.1)
				(type default)
			)
			(layer "F.Fab")
		)
		(pad "1" smd rect
			(at 0 0)
			(size 0.762 0.889)
			(layers "F.Cu" "F.Mask" "F.Paste")
			(net "PVCCMCP_CPU1")
		)
		(pad "2" smd rect
			(at 0 1.397)
			(size 0.762 0.889)
			(layers "F.Cu" "F.Mask" "F.Paste")
			(net "GND")
		)
		(zone
			(layer "F.Cu")
			(hatch none 0.5)
			(connect_pads
				(clearance 0)
			)
			(min_thickness 0.25)
			(keepout
				(tracks not_allowed)
				(vias allowed)
				(pads allowed)
				(copperpour not_allowed)
				(footprints allowed)
			)
			(placement
				(enabled no)
				(sheetname "")
			)
			(fill
				(thermal_gap 0.5)
				(thermal_bridge_width 0.5)
				(island_removal_mode 0)
			)
			(polygon
				(pts
					(xy 105.27284 -77.191616) (xy 106.03484 -77.191616) (xy 106.03484 -76.683616) (xy 105.27284 -76.683616)
				)
			)
		)
	)
	(footprint ""
		(layer "F.Cu")
		(at 194.749928 -67.97294 -90)
		(property "Reference" "C4D48"
			(at 0 0 270)
			(layer "F.SilkS")
			(hide yes)
			(effects
				(font
					(size 1.27 1.27)
				)
			)
		)
		(property "Value" ""
			(at 0 0 270)
			(layer "F.Fab")
			(effects
				(font
					(size 1.27 1.27)
				)
			)
		)
		(duplicate_pad_numbers_are_jumpers no)
		(fp_poly
			(pts
				(xy 0.3048 -0.1016) (xy 0.3048 0.9906) (xy -0.3048 0.9906) (xy -0.3048 -0.1016)
			)
			(stroke
				(width 0)
				(type default)
			)
			(fill no)
			(layer "F.CrtYd")
		)
		(fp_line
			(start -0.3048 0.9906)
			(end 0.3048 0.9906)
			(stroke
				(width 0.1)
				(type default)
			)
			(layer "F.Fab")
		)
		(fp_line
			(start 0.3048 0.9906)
			(end 0.3048 -0.1016)
			(stroke
				(width 0.1)
				(type default)
			)
			(layer "F.Fab")
		)
		(fp_line
			(start -0.3048 -0.1016)
			(end -0.3048 0.9906)
			(stroke
				(width 0.1)
				(type default)
			)
			(layer "F.Fab")
		)
		(fp_line
			(start 0.3048 -0.1016)
			(end -0.3048 -0.1016)
			(stroke
				(width 0.1)
				(type default)
			)
			(layer "F.Fab")
		)
		(pad "1" smd rect
			(at 0 0 270)
			(size 0.508 0.508)
			(layers "F.Cu" "F.Mask" "F.Paste")
			(net "VR_FET_SW_P12V_STBY_PVCCIN_CPU0")
		)
		(pad "2" smd rect
			(at 0 0.889 270)
			(size 0.508 0.508)
			(layers "F.Cu" "F.Mask" "F.Paste")
			(net "GND")
		)
		(zone
			(layer "F.Cu")
			(hatch none 0.5)
			(connect_pads
				(clearance 0)
			)
			(min_thickness 0.25)
			(keepout
				(tracks not_allowed)
				(vias allowed)
				(pads allowed)
				(copperpour not_allowed)
				(footprints allowed)
			)
			(placement
				(enabled no)
				(sheetname "")
			)
			(fill
				(thermal_gap 0.5)
				(thermal_bridge_width 0.5)
				(island_removal_mode 0)
			)
			(polygon
				(pts
					(xy 194.114928 -68.22694) (xy 194.114928 -67.71894) (xy 194.495928 -67.71894) (xy 194.495928 -68.22694)
				)
			)
		)
		(zone
			(layer "F.Cu")
			(hatch none 0.5)
			(connect_pads
				(clearance 0)
			)
			(min_thickness 0.25)
			(keepout
				(tracks allowed)
				(vias not_allowed)
				(pads allowed)
				(copperpour not_allowed)
				(footprints allowed)
			)
			(placement
				(enabled no)
				(sheetname "")
			)
			(fill
				(thermal_gap 0.5)
				(thermal_bridge_width 0.5)
				(island_removal_mode 0)
			)
			(polygon
				(pts
					(xy 194.495928 -68.22694) (xy 194.495928 -67.71894) (xy 194.114928 -67.71894) (xy 194.114928 -68.22694)
				)
			)
		)
	)
	(footprint ""
		(layer "F.Cu")
		(at 465.7344 3.9878 90)
		(property "Reference" "R9G35"
			(at 0 0 90)
			(layer "F.SilkS")
			(hide yes)
			(effects
				(font
					(size 1.27 1.27)
				)
			)
		)
		(property "Value" ""
			(at 0 0 90)
			(layer "F.Fab")
			(effects
				(font
					(size 1.27 1.27)
				)
			)
		)
		(duplicate_pad_numbers_are_jumpers no)
		(fp_poly
			(pts
				(xy -0.2794 -0.1016) (xy 0.2794 -0.1016) (xy 0.2794 0.9906) (xy -0.2794 0.9906)
			)
			(stroke
				(width 0)
				(type default)
			)
			(fill no)
			(layer "F.CrtYd")
		)
		(fp_line
			(start 0.2794 -0.1016)
			(end -0.2794 -0.1016)
			(stroke
				(width 0.1)
				(type default)
			)
			(layer "F.Fab")
		)
		(fp_line
			(start -0.2794 -0.1016)
			(end -0.2794 0.9906)
			(stroke
				(width 0.1)
				(type default)
			)
			(layer "F.Fab")
		)
		(fp_line
			(start 0.2794 0.9906)
			(end 0.2794 -0.1016)
			(stroke
				(width 0.1)
				(type default)
			)
			(layer "F.Fab")
		)
		(fp_line
			(start -0.2794 0.9906)
			(end 0.2794 0.9906)
			(stroke
				(width 0.1)
				(type default)
			)
			(layer "F.Fab")
		)
		(pad "1" smd rect
			(at 0 0 90)
			(size 0.508 0.508)
			(layers "F.Cu" "F.Mask" "F.Paste")
			(net "P3V3_STBY")
		)
		(pad "2" smd rect
			(at 0 0.889 90)
			(size 0.508 0.508)
			(layers "F.Cu" "F.Mask" "F.Paste")
			(net "FM_BATTERY_SENSE_EN_N")
		)
		(zone
			(layer "F.Cu")
			(hatch none 0.5)
			(connect_pads
				(clearance 0)
			)
			(min_thickness 0.25)
			(keepout
				(tracks allowed)
				(vias not_allowed)
				(pads allowed)
				(copperpour not_allowed)
				(footprints allowed)
			)
			(placement
				(enabled no)
				(sheetname "")
			)
			(fill
				(thermal_gap 0.5)
				(thermal_bridge_width 0.5)
				(island_removal_mode 0)
			)
			(polygon
				(pts
					(xy 465.9884 4.2418) (xy 465.9884 3.7338) (xy 466.3694 3.7338) (xy 466.3694 4.2418)
				)
			)
		)
		(zone
			(layer "F.Cu")
			(hatch none 0.5)
			(connect_pads
				(clearance 0)
			)
			(min_thickness 0.25)
			(keepout
				(tracks not_allowed)
				(vias allowed)
				(pads allowed)
				(copperpour not_allowed)
				(footprints allowed)
			)
			(placement
				(enabled no)
				(sheetname "")
			)
			(fill
				(thermal_gap 0.5)
				(thermal_bridge_width 0.5)
				(island_removal_mode 0)
			)
			(polygon
				(pts
					(xy 466.3694 4.2418) (xy 466.3694 3.7338) (xy 465.9884 3.7338) (xy 465.9884 4.2418)
				)
			)
		)
	)
	(footprint ""
		(layer "F.Cu")
		(at 403.719792 -10.917936)
		(property "Reference" "C8G4"
			(at 0 0 0)
			(layer "F.SilkS")
			(hide yes)
			(effects
				(font
					(size 1.27 1.27)
				)
			)
		)
		(property "Value" ""
			(at 0 0 0)
			(layer "F.Fab")
			(effects
				(font
					(size 1.27 1.27)
				)
			)
		)
		(duplicate_pad_numbers_are_jumpers no)
		(fp_rect
			(start -0.3048 0.9906)
			(end 0.3048 -0.1016)
			(stroke
				(width 0)
				(type default)
			)
			(fill no)
			(layer "F.CrtYd")
		)
		(fp_line
			(start -0.3048 -0.1016)
			(end -0.3048 0.9906)
			(stroke
				(width 0.1)
				(type default)
			)
			(layer "F.Fab")
		)
		(fp_line
			(start -0.3048 0.9906)
			(end 0.3048 0.9906)
			(stroke
				(width 0.1)
				(type default)
			)
			(layer "F.Fab")
		)
		(fp_line
			(start 0.3048 -0.1016)
			(end -0.3048 -0.1016)
			(stroke
				(width 0.1)
				(type default)
			)
			(layer "F.Fab")
		)
		(fp_line
			(start 0.3048 0.9906)
			(end 0.3048 -0.1016)
			(stroke
				(width 0.1)
				(type default)
			)
			(layer "F.Fab")
		)
		(pad "1" smd rect
			(at 0 0)
			(size 0.508 0.508)
			(layers "F.Cu" "F.Mask" "F.Paste")
			(net "P3E_CPU0_PE2_SS_TXN<3>")
		)
		(pad "2" smd rect
			(at 0 0.889)
			(size 0.508 0.508)
			(layers "F.Cu" "F.Mask" "F.Paste")
			(net "P3E_CPU0_PE2_SS_C_TXN<3>")
		)
		(zone
			(layer "F.Cu")
			(hatch none 0.5)
			(connect_pads
				(clearance 0)
			)
			(min_thickness 0.25)
			(keepout
				(tracks allowed)
				(vias not_allowed)
				(pads allowed)
				(copperpour not_allowed)
				(footprints allowed)
			)
			(placement
				(enabled no)
				(sheetname "")
			)
			(fill
				(thermal_gap 0.5)
				(thermal_bridge_width 0.5)
				(island_removal_mode 0)
			)
			(polygon
				(pts
					(xy 403.465792 -10.282936) (xy 403.973792 -10.282936) (xy 403.973792 -10.663936) (xy 403.465792 -10.663936)
				)
			)
		)
		(zone
			(layer "F.Cu")
			(hatch none 0.5)
			(connect_pads
				(clearance 0)
			)
			(min_thickness 0.25)
			(keepout
				(tracks not_allowed)
				(vias allowed)
				(pads allowed)
				(copperpour not_allowed)
				(footprints allowed)
			)
			(placement
				(enabled no)
				(sheetname "")
			)
			(fill
				(thermal_gap 0.5)
				(thermal_bridge_width 0.5)
				(island_removal_mode 0)
			)
			(polygon
				(pts
					(xy 403.465792 -10.282936) (xy 403.973792 -10.282936) (xy 403.973792 -10.663936) (xy 403.465792 -10.663936)
				)
			)
		)
	)
	(footprint ""
		(layer "F.Cu")
		(at 411.1625 -105.537 -90)
		(property "Reference" "R8C18"
			(at 0 0 270)
			(layer "F.SilkS")
			(hide yes)
			(effects
				(font
					(size 1.27 1.27)
				)
			)
		)
		(property "Value" ""
			(at 0 0 270)
			(layer "F.Fab")
			(effects
				(font
					(size 1.27 1.27)
				)
			)
		)
		(duplicate_pad_numbers_are_jumpers no)
		(fp_poly
			(pts
				(xy -0.2794 -0.1016) (xy 0.2794 -0.1016) (xy 0.2794 0.9906) (xy -0.2794 0.9906)
			)
			(stroke
				(width 0)
				(type default)
			)
			(fill no)
			(layer "F.CrtYd")
		)
		(fp_line
			(start -0.2794 0.9906)
			(end 0.2794 0.9906)
			(stroke
				(width 0.1)
				(type default)
			)
			(layer "F.Fab")
		)
		(fp_line
			(start 0.2794 0.9906)
			(end 0.2794 -0.1016)
			(stroke
				(width 0.1)
				(type default)
			)
			(layer "F.Fab")
		)
		(fp_line
			(start -0.2794 -0.1016)
			(end -0.2794 0.9906)
			(stroke
				(width 0.1)
				(type default)
			)
			(layer "F.Fab")
		)
		(fp_line
			(start 0.2794 -0.1016)
			(end -0.2794 -0.1016)
			(stroke
				(width 0.1)
				(type default)
			)
			(layer "F.Fab")
		)
		(pad "1" smd rect
			(at 0 0 270)
			(size 0.508 0.508)
			(layers "F.Cu" "F.Mask" "F.Paste")
			(net "P3V3_STBY")
		)
		(pad "2" smd rect
			(at 0 0.889 270)
			(size 0.508 0.508)
			(layers "F.Cu" "F.Mask" "F.Paste")
			(net "PU_PCH_TLS_ENABLE_STRAP")
		)
		(zone
			(layer "F.Cu")
			(hatch none 0.5)
			(connect_pads
				(clearance 0)
			)
			(min_thickness 0.25)
			(keepout
				(tracks not_allowed)
				(vias allowed)
				(pads allowed)
				(copperpour not_allowed)
				(footprints allowed)
			)
			(placement
				(enabled no)
				(sheetname "")
			)
			(fill
				(thermal_gap 0.5)
				(thermal_bridge_width 0.5)
				(island_removal_mode 0)
			)
			(polygon
				(pts
					(xy 410.5275 -105.791) (xy 410.5275 -105.283) (xy 410.9085 -105.283) (xy 410.9085 -105.791)
				)
			)
		)
		(zone
			(layer "F.Cu")
			(hatch none 0.5)
			(connect_pads
				(clearance 0)
			)
			(min_thickness 0.25)
			(keepout
				(tracks allowed)
				(vias not_allowed)
				(pads allowed)
				(copperpour not_allowed)
				(footprints allowed)
			)
			(placement
				(enabled no)
				(sheetname "")
			)
			(fill
				(thermal_gap 0.5)
				(thermal_bridge_width 0.5)
				(island_removal_mode 0)
			)
			(polygon
				(pts
					(xy 410.9085 -105.791) (xy 410.9085 -105.283) (xy 410.5275 -105.283) (xy 410.5275 -105.791)
				)
			)
		)
	)
	(footprint ""
		(layer "F.Cu")
		(at 162.306 -65.7606 90)
		(property "Reference" "SH3D1"
			(at 0 0 90)
			(layer "F.SilkS")
			(hide yes)
			(effects
				(font
					(size 1.27 1.27)
				)
			)
		)
		(property "Value" ""
			(at 0 0 90)
			(layer "F.Fab")
			(effects
				(font
					(size 1.27 1.27)
				)
			)
		)
		(duplicate_pad_numbers_are_jumpers no)
		(fp_poly
			(pts
				(xy -0.1651 -0.0508) (xy -0.1651 0.5842) (xy 0.1651 0.5842) (xy 0.1651 -0.0508)
			)
			(stroke
				(width 0)
				(type default)
			)
			(fill no)
			(layer "F.CrtYd")
		)
		(fp_line
			(start 0.1651 -0.0508)
			(end 0.1651 0.5842)
			(stroke
				(width 0.1)
				(type default)
			)
			(layer "F.Fab")
		)
		(fp_line
			(start -0.1651 -0.0508)
			(end 0.1651 -0.0508)
			(stroke
				(width 0.1)
				(type default)
			)
			(layer "F.Fab")
		)
		(fp_line
			(start 0.1651 0.5842)
			(end -0.1651 0.5842)
			(stroke
				(width 0.1)
				(type default)
			)
			(layer "F.Fab")
		)
		(fp_line
			(start -0.1651 0.5842)
			(end -0.1651 -0.0508)
			(stroke
				(width 0.1)
				(type default)
			)
			(layer "F.Fab")
		)
		(pad "1" smd custom
			(at 0 0 270)
			(size 0.0762 0.0762)
			(layers "F.Cu" "F.Mask" "F.Paste")
			(net "VSENSE_PVCCIO_CPU1_SKT_VRTN")
			(options
				(clearance outline)
				(anchor circle)
			)
			(primitives
				(gr_poly
					(pts
						(arc
							(start -0.1524 -0.10795)
							(mid -0.098518 -0.130268)
							(end -0.0762 -0.18415)
						)
						(xy -0.0762 -0.22225) (xy 0.0762 -0.22225)
						(arc
							(start 0.0762 -0.18415)
							(mid 0.098518 -0.130268)
							(end 0.1524 -0.10795)
						)
						(xy 0.1524 0.22225) (xy -0.1524 0.22225)
					)
					(width 0)
					(fill yes)
				)
			)
		)
		(pad "2" smd custom
			(at 0 0.5334 90)
			(size 0.0762 0.0762)
			(layers "F.Cu" "F.Mask" "F.Paste")
			(net "VSENSE_PVCCIO_CPU1_AVSN")
			(options
				(clearance outline)
				(anchor circle)
			)
			(primitives
				(gr_poly
					(pts
						(arc
							(start -0.1524 -0.10795)
							(mid -0.098518 -0.130268)
							(end -0.0762 -0.18415)
						)
						(xy -0.0762 -0.22225) (xy 0.0762 -0.22225)
						(arc
							(start 0.0762 -0.18415)
							(mid 0.098518 -0.130268)
							(end 0.1524 -0.10795)
						)
						(xy 0.1524 0.22225) (xy -0.1524 0.22225)
					)
					(width 0)
					(fill yes)
				)
			)
		)
	)
	(footprint ""
		(layer "F.Cu")
		(at 389.382 -66.3194)
		(property "Reference" "R7E17"
			(at 0 0 0)
			(layer "F.SilkS")
			(hide yes)
			(effects
				(font
					(size 1.27 1.27)
				)
			)
		)
		(property "Value" ""
			(at 0 0 0)
			(layer "F.Fab")
			(effects
				(font
					(size 1.27 1.27)
				)
			)
		)
		(duplicate_pad_numbers_are_jumpers no)
		(fp_poly
			(pts
				(xy -0.2794 -0.1016) (xy 0.2794 -0.1016) (xy 0.2794 0.9906) (xy -0.2794 0.9906)
			)
			(stroke
				(width 0)
				(type default)
			)
			(fill no)
			(layer "F.CrtYd")
		)
		(fp_line
			(start -0.2794 -0.1016)
			(end -0.2794 0.9906)
			(stroke
				(width 0.1)
				(type default)
			)
			(layer "F.Fab")
		)
		(fp_line
			(start -0.2794 0.9906)
			(end 0.2794 0.9906)
			(stroke
				(width 0.1)
				(type default)
			)
			(layer "F.Fab")
		)
		(fp_line
			(start 0.2794 -0.1016)
			(end -0.2794 -0.1016)
			(stroke
				(width 0.1)
				(type default)
			)
			(layer "F.Fab")
		)
		(fp_line
			(start 0.2794 0.9906)
			(end 0.2794 -0.1016)
			(stroke
				(width 0.1)
				(type default)
			)
			(layer "F.Fab")
		)
		(pad "1" smd rect
			(at 0 0)
			(size 0.508 0.508)
			(layers "F.Cu" "F.Mask" "F.Paste")
			(net "VR_FET_SW_P5V_STBY_PVIN")
		)
		(pad "2" smd rect
			(at 0 0.889)
			(size 0.508 0.508)
			(layers "F.Cu" "F.Mask" "F.Paste")
			(net "VR_P5V_STBY_VIN")
		)
		(zone
			(layer "F.Cu")
			(hatch none 0.5)
			(connect_pads
				(clearance 0)
			)
			(min_thickness 0.25)
			(keepout
				(tracks allowed)
				(vias not_allowed)
				(pads allowed)
				(copperpour not_allowed)
				(footprints allowed)
			)
			(placement
				(enabled no)
				(sheetname "")
			)
			(fill
				(thermal_gap 0.5)
				(thermal_bridge_width 0.5)
				(island_removal_mode 0)
			)
			(polygon
				(pts
					(xy 389.128 -66.0654) (xy 389.636 -66.0654) (xy 389.636 -65.6844) (xy 389.128 -65.6844)
				)
			)
		)
		(zone
			(layer "F.Cu")
			(hatch none 0.5)
			(connect_pads
				(clearance 0)
			)
			(min_thickness 0.25)
			(keepout
				(tracks not_allowed)
				(vias allowed)
				(pads allowed)
				(copperpour not_allowed)
				(footprints allowed)
			)
			(placement
				(enabled no)
				(sheetname "")
			)
			(fill
				(thermal_gap 0.5)
				(thermal_bridge_width 0.5)
				(island_removal_mode 0)
			)
			(polygon
				(pts
					(xy 389.128 -65.6844) (xy 389.636 -65.6844) (xy 389.636 -66.0654) (xy 389.128 -66.0654)
				)
			)
		)
	)
	(footprint ""
		(layer "F.Cu")
		(at 338.836 -13.1826 -90)
		(property "Reference" "C7G4"
			(at 0 0 270)
			(layer "F.SilkS")
			(hide yes)
			(effects
				(font
					(size 1.27 1.27)
				)
			)
		)
		(property "Value" ""
			(at 0 0 270)
			(layer "F.Fab")
			(effects
				(font
					(size 1.27 1.27)
				)
			)
		)
		(duplicate_pad_numbers_are_jumpers no)
		(fp_rect
			(start -0.3048 0.9906)
			(end 0.3048 -0.1016)
			(stroke
				(width 0)
				(type default)
			)
			(fill no)
			(layer "F.CrtYd")
		)
		(fp_line
			(start -0.3048 0.9906)
			(end 0.3048 0.9906)
			(stroke
				(width 0.1)
				(type default)
			)
			(layer "F.Fab")
		)
		(fp_line
			(start 0.3048 0.9906)
			(end 0.3048 -0.1016)
			(stroke
				(width 0.1)
				(type default)
			)
			(layer "F.Fab")
		)
		(fp_line
			(start -0.3048 -0.1016)
			(end -0.3048 0.9906)
			(stroke
				(width 0.1)
				(type default)
			)
			(layer "F.Fab")
		)
		(fp_line
			(start 0.3048 -0.1016)
			(end -0.3048 -0.1016)
			(stroke
				(width 0.1)
				(type default)
			)
			(layer "F.Fab")
		)
		(pad "1" smd rect
			(at 0 0 270)
			(size 0.508 0.508)
			(layers "F.Cu" "F.Mask" "F.Paste")
			(net "VR_PVDDQ_ABC_AVSP")
		)
		(pad "2" smd rect
			(at 0 0.889 270)
			(size 0.508 0.508)
			(layers "F.Cu" "F.Mask" "F.Paste")
			(net "VSENSE_PVDDQ_ABC_N")
		)
		(zone
			(layer "F.Cu")
			(hatch none 0.5)
			(connect_pads
				(clearance 0)
			)
			(min_thickness 0.25)
			(keepout
				(tracks allowed)
				(vias not_allowed)
				(pads allowed)
				(copperpour not_allowed)
				(footprints allowed)
			)
			(placement
				(enabled no)
				(sheetname "")
			)
			(fill
				(thermal_gap 0.5)
				(thermal_bridge_width 0.5)
				(island_removal_mode 0)
			)
			(polygon
				(pts
					(xy 338.201 -13.4366) (xy 338.201 -12.9286) (xy 338.582 -12.9286) (xy 338.582 -13.4366)
				)
			)
		)
	)
	(footprint ""
		(layer "F.Cu")
		(at 491.0455 -40.0304 90)
		(property "Reference" "R9F1"
			(at 0 0 90)
			(layer "F.SilkS")
			(hide yes)
			(effects
				(font
					(size 1.27 1.27)
				)
			)
		)
		(property "Value" ""
			(at 0 0 90)
			(layer "F.Fab")
			(effects
				(font
					(size 1.27 1.27)
				)
			)
		)
		(duplicate_pad_numbers_are_jumpers no)
		(fp_poly
			(pts
				(xy -0.2794 -0.1016) (xy 0.2794 -0.1016) (xy 0.2794 0.9906) (xy -0.2794 0.9906)
			)
			(stroke
				(width 0)
				(type default)
			)
			(fill no)
			(layer "F.CrtYd")
		)
		(fp_line
			(start 0.2794 -0.1016)
			(end -0.2794 -0.1016)
			(stroke
				(width 0.1)
				(type default)
			)
			(layer "F.Fab")
		)
		(fp_line
			(start -0.2794 -0.1016)
			(end -0.2794 0.9906)
			(stroke
				(width 0.1)
				(type default)
			)
			(layer "F.Fab")
		)
		(fp_line
			(start 0.2794 0.9906)
			(end 0.2794 -0.1016)
			(stroke
				(width 0.1)
				(type default)
			)
			(layer "F.Fab")
		)
		(fp_line
			(start -0.2794 0.9906)
			(end 0.2794 0.9906)
			(stroke
				(width 0.1)
				(type default)
			)
			(layer "F.Fab")
		)
		(pad "1" smd rect
			(at 0 0 90)
			(size 0.508 0.508)
			(layers "F.Cu" "F.Mask" "F.Paste")
			(net "RMII_BMC_PCH_SPRNGVLLE_CRSDV_R")
		)
		(pad "2" smd rect
			(at 0 0.889 90)
			(size 0.508 0.508)
			(layers "F.Cu" "F.Mask" "F.Paste")
			(net "RMII_BMC_PCH_SPRNGVLLE_CRSDV")
		)
		(zone
			(layer "F.Cu")
			(hatch none 0.5)
			(connect_pads
				(clearance 0)
			)
			(min_thickness 0.25)
			(keepout
				(tracks allowed)
				(vias not_allowed)
				(pads allowed)
				(copperpour not_allowed)
				(footprints allowed)
			)
			(placement
				(enabled no)
				(sheetname "")
			)
			(fill
				(thermal_gap 0.5)
				(thermal_bridge_width 0.5)
				(island_removal_mode 0)
			)
			(polygon
				(pts
					(xy 491.2995 -39.7764) (xy 491.2995 -40.2844) (xy 491.6805 -40.2844) (xy 491.6805 -39.7764)
				)
			)
		)
		(zone
			(layer "F.Cu")
			(hatch none 0.5)
			(connect_pads
				(clearance 0)
			)
			(min_thickness 0.25)
			(keepout
				(tracks not_allowed)
				(vias allowed)
				(pads allowed)
				(copperpour not_allowed)
				(footprints allowed)
			)
			(placement
				(enabled no)
				(sheetname "")
			)
			(fill
				(thermal_gap 0.5)
				(thermal_bridge_width 0.5)
				(island_removal_mode 0)
			)
			(polygon
				(pts
					(xy 491.6805 -39.7764) (xy 491.6805 -40.2844) (xy 491.2995 -40.2844) (xy 491.2995 -39.7764)
				)
			)
		)
	)
	(footprint ""
		(layer "F.Cu")
		(at 175.387 -81.407 90)
		(property "Reference" "R4D17"
			(at 0 0 90)
			(layer "F.SilkS")
			(hide yes)
			(effects
				(font
					(size 1.27 1.27)
				)
			)
		)
		(property "Value" ""
			(at 0 0 90)
			(layer "F.Fab")
			(effects
				(font
					(size 1.27 1.27)
				)
			)
		)
		(duplicate_pad_numbers_are_jumpers no)
		(fp_poly
			(pts
				(xy -0.2794 -0.1016) (xy 0.2794 -0.1016) (xy 0.2794 0.9906) (xy -0.2794 0.9906)
			)
			(stroke
				(width 0)
				(type default)
			)
			(fill no)
			(layer "F.CrtYd")
		)
		(fp_line
			(start 0.2794 -0.1016)
			(end -0.2794 -0.1016)
			(stroke
				(width 0.1)
				(type default)
			)
			(layer "F.Fab")
		)
		(fp_line
			(start -0.2794 -0.1016)
			(end -0.2794 0.9906)
			(stroke
				(width 0.1)
				(type default)
			)
			(layer "F.Fab")
		)
		(fp_line
			(start 0.2794 0.9906)
			(end 0.2794 -0.1016)
			(stroke
				(width 0.1)
				(type default)
			)
			(layer "F.Fab")
		)
		(fp_line
			(start -0.2794 0.9906)
			(end 0.2794 0.9906)
			(stroke
				(width 0.1)
				(type default)
			)
			(layer "F.Fab")
		)
		(pad "1" smd rect
			(at 0 0 90)
			(size 0.508 0.508)
			(layers "F.Cu" "F.Mask" "F.Paste")
			(net "CLK_100M_CPU0_BCLK2_R_DP")
		)
		(pad "2" smd rect
			(at 0 0.889 90)
			(size 0.508 0.508)
			(layers "F.Cu" "F.Mask" "F.Paste")
			(net "CLK_100M_CPU0_BCLK2_DP")
		)
		(zone
			(layer "F.Cu")
			(hatch none 0.5)
			(connect_pads
				(clearance 0)
			)
			(min_thickness 0.25)
			(keepout
				(tracks allowed)
				(vias not_allowed)
				(pads allowed)
				(copperpour not_allowed)
				(footprints allowed)
			)
			(placement
				(enabled no)
				(sheetname "")
			)
			(fill
				(thermal_gap 0.5)
				(thermal_bridge_width 0.5)
				(island_removal_mode 0)
			)
			(polygon
				(pts
					(xy 175.641 -81.153) (xy 175.641 -81.661) (xy 176.022 -81.661) (xy 176.022 -81.153)
				)
			)
		)
		(zone
			(layer "F.Cu")
			(hatch none 0.5)
			(connect_pads
				(clearance 0)
			)
			(min_thickness 0.25)
			(keepout
				(tracks not_allowed)
				(vias allowed)
				(pads allowed)
				(copperpour not_allowed)
				(footprints allowed)
			)
			(placement
				(enabled no)
				(sheetname "")
			)
			(fill
				(thermal_gap 0.5)
				(thermal_bridge_width 0.5)
				(island_removal_mode 0)
			)
			(polygon
				(pts
					(xy 176.022 -81.153) (xy 176.022 -81.661) (xy 175.641 -81.661) (xy 175.641 -81.153)
				)
			)
		)
	)
	(footprint ""
		(layer "F.Cu")
		(at 387.604 -88.2015)
		(property "Reference" "R7C20"
			(at 0 0 0)
			(layer "F.SilkS")
			(hide yes)
			(effects
				(font
					(size 1.27 1.27)
				)
			)
		)
		(property "Value" ""
			(at 0 0 0)
			(layer "F.Fab")
			(effects
				(font
					(size 1.27 1.27)
				)
			)
		)
		(duplicate_pad_numbers_are_jumpers no)
		(fp_poly
			(pts
				(xy -0.2794 -0.1016) (xy 0.2794 -0.1016) (xy 0.2794 0.9906) (xy -0.2794 0.9906)
			)
			(stroke
				(width 0)
				(type default)
			)
			(fill no)
			(layer "F.CrtYd")
		)
		(fp_line
			(start -0.2794 -0.1016)
			(end -0.2794 0.9906)
			(stroke
				(width 0.1)
				(type default)
			)
			(layer "F.Fab")
		)
		(fp_line
			(start -0.2794 0.9906)
			(end 0.2794 0.9906)
			(stroke
				(width 0.1)
				(type default)
			)
			(layer "F.Fab")
		)
		(fp_line
			(start 0.2794 -0.1016)
			(end -0.2794 -0.1016)
			(stroke
				(width 0.1)
				(type default)
			)
			(layer "F.Fab")
		)
		(fp_line
			(start 0.2794 0.9906)
			(end 0.2794 -0.1016)
			(stroke
				(width 0.1)
				(type default)
			)
			(layer "F.Fab")
		)
		(pad "1" smd rect
			(at 0 0)
			(size 0.508 0.508)
			(layers "F.Cu" "F.Mask" "F.Paste")
			(net "CLK_50M_CKMNG_PCH_10GBE")
		)
		(pad "2" smd rect
			(at 0 0.889)
			(size 0.508 0.508)
			(layers "F.Cu" "F.Mask" "F.Paste")
			(net "GND")
		)
		(zone
			(layer "F.Cu")
			(hatch none 0.5)
			(connect_pads
				(clearance 0)
			)
			(min_thickness 0.25)
			(keepout
				(tracks allowed)
				(vias not_allowed)
				(pads allowed)
				(copperpour not_allowed)
				(footprints allowed)
			)
			(placement
				(enabled no)
				(sheetname "")
			)
			(fill
				(thermal_gap 0.5)
				(thermal_bridge_width 0.5)
				(island_removal_mode 0)
			)
			(polygon
				(pts
					(xy 387.35 -87.9475) (xy 387.858 -87.9475) (xy 387.858 -87.5665) (xy 387.35 -87.5665)
				)
			)
		)
		(zone
			(layer "F.Cu")
			(hatch none 0.5)
			(connect_pads
				(clearance 0)
			)
			(min_thickness 0.25)
			(keepout
				(tracks not_allowed)
				(vias allowed)
				(pads allowed)
				(copperpour not_allowed)
				(footprints allowed)
			)
			(placement
				(enabled no)
				(sheetname "")
			)
			(fill
				(thermal_gap 0.5)
				(thermal_bridge_width 0.5)
				(island_removal_mode 0)
			)
			(polygon
				(pts
					(xy 387.35 -87.5665) (xy 387.858 -87.5665) (xy 387.858 -87.9475) (xy 387.35 -87.9475)
				)
			)
		)
	)
	(footprint ""
		(layer "F.Cu")
		(at 409.35402 -20.100036)
		(property "Reference" "FB1U3"
			(at 0 0 0)
			(layer "F.SilkS")
			(hide yes)
			(effects
				(font
					(size 1.27 1.27)
				)
			)
		)
		(property "Value" ""
			(at 0 0 0)
			(layer "F.Fab")
			(effects
				(font
					(size 1.27 1.27)
				)
			)
		)
		(duplicate_pad_numbers_are_jumpers no)
		(fp_poly
			(pts
				(xy -0.47625 -0.2413) (xy 0.47625 -0.2413) (xy 0.47625 1.5113) (xy -0.47625 1.5113)
			)
			(stroke
				(width 0)
				(type default)
			)
			(fill no)
			(layer "F.CrtYd")
		)
		(fp_line
			(start -0.47625 -0.2413)
			(end 0.47625 -0.2413)
			(stroke
				(width 0.1)
				(type default)
			)
			(layer "F.Fab")
		)
		(fp_line
			(start -0.47625 1.5113)
			(end -0.47625 -0.2413)
			(stroke
				(width 0.1)
				(type default)
			)
			(layer "F.Fab")
		)
		(fp_line
			(start 0.47625 -0.2413)
			(end 0.47625 1.5113)
			(stroke
				(width 0.1)
				(type default)
			)
			(layer "F.Fab")
		)
		(fp_line
			(start 0.47625 1.5113)
			(end -0.47625 1.5113)
			(stroke
				(width 0.1)
				(type default)
			)
			(layer "F.Fab")
		)
		(pad "1" smd rect
			(at 0 0)
			(size 0.762 0.889)
			(layers "F.Cu" "F.Mask" "F.Paste")
			(net "A_P1V05_STBY_PCH_SENSOR")
		)
		(pad "2" smd rect
			(at 0 1.27)
			(size 0.762 0.889)
			(layers "F.Cu" "F.Mask" "F.Paste")
			(net "P1V05_PCH_STBY")
		)
		(zone
			(layer "F.Cu")
			(hatch none 0.5)
			(connect_pads
				(clearance 0)
			)
			(min_thickness 0.25)
			(keepout
				(tracks allowed)
				(vias not_allowed)
				(pads allowed)
				(copperpour not_allowed)
				(footprints allowed)
			)
			(placement
				(enabled no)
				(sheetname "")
			)
			(fill
				(thermal_gap 0.5)
				(thermal_bridge_width 0.5)
				(island_removal_mode 0)
			)
			(polygon
				(pts
					(xy 408.96794 -19.650456) (xy 409.73502 -19.650456) (xy 409.73502 -19.274536) (xy 408.96794 -19.274536)
				)
			)
		)
		(zone
			(layer "F.Cu")
			(hatch none 0.5)
			(connect_pads
				(clearance 0)
			)
			(min_thickness 0.25)
			(keepout
				(tracks not_allowed)
				(vias allowed)
				(pads allowed)
				(copperpour not_allowed)
				(footprints allowed)
			)
			(placement
				(enabled no)
				(sheetname "")
			)
			(fill
				(thermal_gap 0.5)
				(thermal_bridge_width 0.5)
				(island_removal_mode 0)
			)
			(polygon
				(pts
					(xy 408.96794 -19.274536) (xy 409.73502 -19.274536) (xy 409.73502 -19.650456) (xy 408.96794 -19.650456)
				)
			)
		)
	)
	(footprint ""
		(layer "F.Cu")
		(at -2.1082 -143.256 90)
		(property "Reference" "CT12"
			(at -4.191 0.89027 90)
			(unlocked yes)
			(layer "F.SilkS")
			(effects
				(font
					(size 0.7874 0.5842)
					(thickness 0.1524)
				)
				(justify left)
			)
		)
		(property "Value" ""
			(at 0 0 90)
			(layer "F.Fab")
			(effects
				(font
					(size 1.27 1.27)
				)
			)
		)
		(duplicate_pad_numbers_are_jumpers no)
		(fp_poly
			(pts
				(xy 0.3048 -0.1016) (xy 0.3048 0.9906) (xy -0.3048 0.9906) (xy -0.3048 -0.1016)
			)
			(stroke
				(width 0)
				(type default)
			)
			(fill no)
			(layer "F.CrtYd")
		)
		(fp_line
			(start 0.3048 -0.1016)
			(end -0.3048 -0.1016)
			(stroke
				(width 0.1)
				(type default)
			)
			(layer "F.Fab")
		)
		(fp_line
			(start -0.3048 -0.1016)
			(end -0.3048 0.9906)
			(stroke
				(width 0.1)
				(type default)
			)
			(layer "F.Fab")
		)
		(fp_line
			(start 0.3048 0.9906)
			(end 0.3048 -0.1016)
			(stroke
				(width 0.1)
				(type default)
			)
			(layer "F.Fab")
		)
		(fp_line
			(start -0.3048 0.9906)
			(end 0.3048 0.9906)
			(stroke
				(width 0.1)
				(type default)
			)
			(layer "F.Fab")
		)
		(pad "1" smd rect
			(at 0 0 90)
			(size 0.508 0.508)
			(layers "F.Cu" "F.Mask" "F.Paste")
			(net "VR_PVDDQ_KLM_AIREF2")
		)
		(pad "2" smd rect
			(at 0 0.889 90)
			(size 0.508 0.508)
			(layers "F.Cu" "F.Mask" "F.Paste")
			(net "GND")
		)
		(zone
			(layer "F.Cu")
			(hatch none 0.5)
			(connect_pads
				(clearance 0)
			)
			(min_thickness 0.25)
			(keepout
				(tracks allowed)
				(vias not_allowed)
				(pads allowed)
				(copperpour not_allowed)
				(footprints allowed)
			)
			(placement
				(enabled no)
				(sheetname "")
			)
			(fill
				(thermal_gap 0.5)
				(thermal_bridge_width 0.5)
				(island_removal_mode 0)
			)
			(polygon
				(pts
					(xy -1.8542 -143.002) (xy -1.8542 -143.51) (xy -1.4732 -143.51) (xy -1.4732 -143.002)
				)
			)
		)
		(zone
			(layer "F.Cu")
			(hatch none 0.5)
			(connect_pads
				(clearance 0)
			)
			(min_thickness 0.25)
			(keepout
				(tracks not_allowed)
				(vias allowed)
				(pads allowed)
				(copperpour not_allowed)
				(footprints allowed)
			)
			(placement
				(enabled no)
				(sheetname "")
			)
			(fill
				(thermal_gap 0.5)
				(thermal_bridge_width 0.5)
				(island_removal_mode 0)
			)
			(polygon
				(pts
					(xy -1.4732 -143.002) (xy -1.4732 -143.51) (xy -1.8542 -143.51) (xy -1.8542 -143.002)
				)
			)
		)
	)
	(footprint ""
		(layer "F.Cu")
		(at 194.700398 -152.273 90)
		(property "Reference" "J4A1"
			(at -2.699512 42.53611 0)
			(unlocked yes)
			(layer "F.SilkS")
			(effects
				(font
					(size 0.7874 0.5842)
					(thickness 0.1524)
				)
				(justify left)
			)
		)
		(property "Value" ""
			(at 0 0 90)
			(layer "F.Fab")
			(effects
				(font
					(size 1.27 1.27)
				)
			)
		)
		(duplicate_pad_numbers_are_jumpers no)
		(fp_line
			(start 5.5499 -7.675118)
			(end 5.5499 -1.480058)
			(stroke
				(width 0.1524)
				(type default)
			)
			(layer "F.SilkS")
		)
		(fp_line
			(start -0.94996 -7.675118)
			(end 5.5499 -7.675118)
			(stroke
				(width 0.1524)
				(type default)
			)
			(layer "F.SilkS")
		)
		(fp_line
			(start -0.94996 -1.480058)
			(end -0.94996 -7.675118)
			(stroke
				(width 0.1524)
				(type default)
			)
			(layer "F.SilkS")
		)
		(fp_line
			(start 5.5499 128.130046)
			(end 5.5499 134.325106)
			(stroke
				(width 0.1524)
				(type default)
			)
			(layer "F.SilkS")
		)
		(fp_line
			(start 5.5499 134.325106)
			(end -0.94996 134.325106)
			(stroke
				(width 0.1524)
				(type default)
			)
			(layer "F.SilkS")
		)
		(fp_line
			(start -0.94996 134.325106)
			(end -0.94996 128.130046)
			(stroke
				(width 0.1524)
				(type default)
			)
			(layer "F.SilkS")
		)
		(fp_poly
			(pts
				(xy -2.886456 -0.89027) (xy -2.886456 0.12573) (xy -1.616456 -0.38227)
			)
			(stroke
				(width 0)
				(type default)
			)
			(fill yes)
			(layer "F.SilkS")
		)
		(fp_poly
			(pts
				(xy -0.94996 -7.675118) (xy -0.94996 134.325106) (xy 5.5499 134.325106) (xy 5.5499 -7.675118)
			)
			(stroke
				(width 0)
				(type default)
			)
			(fill no)
			(layer "F.CrtYd")
		)
		(fp_line
			(start 5.5499 -7.675118)
			(end 5.5499 134.325106)
			(stroke
				(width 0.1)
				(type default)
			)
			(layer "F.Fab")
		)
		(fp_line
			(start -0.94996 -7.675118)
			(end 5.5499 -7.675118)
			(stroke
				(width 0.1)
				(type default)
			)
			(layer "F.Fab")
		)
		(fp_line
			(start 5.5499 134.325106)
			(end -0.94996 134.325106)
			(stroke
				(width 0.1)
				(type default)
			)
			(layer "F.Fab")
		)
		(fp_line
			(start -0.94996 134.325106)
			(end -0.94996 -7.675118)
			(stroke
				(width 0.1)
				(type default)
			)
			(layer "F.Fab")
		)
		(fp_poly
			(pts
				(xy -2.984246 -0.461264) (xy -2.984246 0.554736) (xy -1.714246 0.046736)
			)
			(stroke
				(width 0)
				(type default)
			)
			(fill yes)
			(layer "F.Fab")
		)
		(fp_text user "145"
			(at 6.142228 -0.83693 0)
			(unlocked yes)
			(layer "F.SilkS")
			(effects
				(font
					(size 0.7874 0.5842)
					(thickness 0.1524)
				)
				(justify left)
			)
		)
		(fp_text user "221"
			(at 6.139688 63.13551 0)
			(unlocked yes)
			(layer "F.SilkS")
			(effects
				(font
					(size 0.7874 0.5842)
					(thickness 0.1524)
				)
				(justify left)
			)
		)
		(fp_text user "77"
			(at -1.586992 66.637154 0)
			(unlocked yes)
			(layer "F.SilkS")
			(effects
				(font
					(size 0.7874 0.5842)
					(thickness 0.1524)
				)
				(justify left)
			)
		)
		(fp_text user "222"
			(at 6.10743 68.723002 0)
			(unlocked yes)
			(layer "F.SilkS")
			(effects
				(font
					(size 0.7874 0.5842)
					(thickness 0.1524)
				)
				(justify left)
			)
		)
		(fp_text user "78"
			(at -1.69291 69.79285 0)
			(unlocked yes)
			(layer "F.SilkS")
			(effects
				(font
					(size 0.7874 0.5842)
					(thickness 0.1524)
				)
				(justify left)
			)
		)
		(fp_text user "288"
			(at 6.160008 125.43663 0)
			(unlocked yes)
			(layer "F.SilkS")
			(effects
				(font
					(size 0.7874 0.5842)
					(thickness 0.1524)
				)
				(justify left)
			)
		)
		(fp_text user "144"
			(at -1.655572 128.04013 0)
			(unlocked yes)
			(layer "F.SilkS")
			(effects
				(font
					(size 0.7874 0.5842)
					(thickness 0.1524)
				)
				(justify left)
			)
		)
		(fp_text user "145"
			(at 6.144768 -0.835406 0)
			(unlocked yes)
			(layer "F.Fab")
			(effects
				(font
					(size 0.7874 0.5842)
					(thickness 0.1524)
				)
				(justify left)
			)
		)
		(fp_text user "221"
			(at 3.296158 65.93078 90)
			(unlocked yes)
			(layer "F.Fab")
			(effects
				(font
					(size 0.7874 0.5842)
					(thickness 0.1524)
				)
				(justify left)
			)
		)
		(fp_text user "77"
			(at -0.513842 65.93078 90)
			(unlocked yes)
			(layer "F.Fab")
			(effects
				(font
					(size 0.7874 0.5842)
					(thickness 0.1524)
				)
				(justify left)
			)
		)
		(fp_text user "222"
			(at 3.296158 69.10578 90)
			(unlocked yes)
			(layer "F.Fab")
			(effects
				(font
					(size 0.7874 0.5842)
					(thickness 0.1524)
				)
				(justify left)
			)
		)
		(fp_text user "78"
			(at -0.513842 69.10578 90)
			(unlocked yes)
			(layer "F.Fab")
			(effects
				(font
					(size 0.7874 0.5842)
					(thickness 0.1524)
				)
				(justify left)
			)
		)
		(fp_text user "288"
			(at 3.296158 127.52578 90)
			(unlocked yes)
			(layer "F.Fab")
			(effects
				(font
					(size 0.7874 0.5842)
					(thickness 0.1524)
				)
				(justify left)
			)
		)
		(fp_text user "144"
			(at -0.513842 127.52578 90)
			(unlocked yes)
			(layer "F.Fab")
			(effects
				(font
					(size 0.7874 0.5842)
					(thickness 0.1524)
				)
				(justify left)
			)
		)
		(pad "" thru_hole circle
			(at 2.29997 -5.649976 90)
			(size 2.8194 2.8194)
			(drill 2.4384)
			(layers "*.Cu" "*.Mask")
			(remove_unused_layers no)
			(clearance 0.127)
			(thermal_gap 0.127)
		)
		(pad "" thru_hole oval
			(at 2.29997 68.90004 90)
			(size 2.8194 1.5748)
			(drill oval 2.4384 1.1938)
			(layers "*.Cu" "*.Mask")
			(remove_unused_layers no)
			(clearance 0.127)
			(thermal_gap 0.127)
		)
		(pad "" thru_hole circle
			(at 2.29997 132.299964 90)
			(size 2.8194 2.8194)
			(drill 2.4384)
			(layers "*.Cu" "*.Mask")
			(remove_unused_layers no)
			(clearance 0.127)
			(thermal_gap 0.127)
		)
		(pad "1" smd rect
			(at 0 0 90)
			(size 1.8034 0.508)
			(layers "F.Cu" "F.Mask" "F.Paste")
			(net "P12V_NVDIMM_DEF")
		)
		(pad "2" smd rect
			(at 0 0.849884 90)
			(size 1.8034 0.508)
			(layers "F.Cu" "F.Mask" "F.Paste")
			(net "GND")
		)
		(pad "3" smd rect
			(at 0 1.700022 90)
			(size 1.8034 0.508)
			(layers "F.Cu" "F.Mask" "F.Paste")
			(net "M_F_DQ<5>")
		)
		(pad "4" smd rect
			(at 0 2.549906 90)
			(size 1.8034 0.508)
			(layers "F.Cu" "F.Mask" "F.Paste")
			(net "GND")
		)
		(pad "5" smd rect
			(at 0 3.400044 90)
			(size 1.8034 0.508)
			(layers "F.Cu" "F.Mask" "F.Paste")
			(net "M_F_DQ<1>")
		)
		(pad "6" smd rect
			(at 0 4.249928 90)
			(size 1.8034 0.508)
			(layers "F.Cu" "F.Mask" "F.Paste")
			(net "GND")
		)
		(pad "7" smd rect
			(at 0 5.100066 90)
			(size 1.8034 0.508)
			(layers "F.Cu" "F.Mask" "F.Paste")
			(net "M_F_DQS_DP<9>")
		)
		(pad "8" smd rect
			(at 0 5.94995 90)
			(size 1.8034 0.508)
			(layers "F.Cu" "F.Mask" "F.Paste")
			(net "M_F_DQS_DN<9>")
		)
		(pad "9" smd rect
			(at 0 6.800088 90)
			(size 1.8034 0.508)
			(layers "F.Cu" "F.Mask" "F.Paste")
			(net "GND")
		)
		(pad "10" smd rect
			(at 0 7.649972 90)
			(size 1.8034 0.508)
			(layers "F.Cu" "F.Mask" "F.Paste")
			(net "M_F_DQ<7>")
		)
		(pad "11" smd rect
			(at 0 8.50011 90)
			(size 1.8034 0.508)
			(layers "F.Cu" "F.Mask" "F.Paste")
			(net "GND")
		)
		(pad "12" smd rect
			(at 0 9.349994 90)
			(size 1.8034 0.508)
			(layers "F.Cu" "F.Mask" "F.Paste")
			(net "M_F_DQ<3>")
		)
		(pad "13" smd rect
			(at 0 10.199878 90)
			(size 1.8034 0.508)
			(layers "F.Cu" "F.Mask" "F.Paste")
			(net "GND")
		)
		(pad "14" smd rect
			(at 0 11.050016 90)
			(size 1.8034 0.508)
			(layers "F.Cu" "F.Mask" "F.Paste")
			(net "M_F_DQ<13>")
		)
		(pad "15" smd rect
			(at 0 11.8999 90)
			(size 1.8034 0.508)
			(layers "F.Cu" "F.Mask" "F.Paste")
			(net "GND")
		)
		(pad "16" smd rect
			(at 0 12.750038 90)
			(size 1.8034 0.508)
			(layers "F.Cu" "F.Mask" "F.Paste")
			(net "M_F_DQ<9>")
		)
		(pad "17" smd rect
			(at 0 13.599922 90)
			(size 1.8034 0.508)
			(layers "F.Cu" "F.Mask" "F.Paste")
			(net "GND")
		)
		(pad "18" smd rect
			(at 0 14.45006 90)
			(size 1.8034 0.508)
			(layers "F.Cu" "F.Mask" "F.Paste")
			(net "M_F_DQS_DP<10>")
		)
		(pad "19" smd rect
			(at 0 15.299944 90)
			(size 1.8034 0.508)
			(layers "F.Cu" "F.Mask" "F.Paste")
			(net "M_F_DQS_DN<10>")
		)
		(pad "20" smd rect
			(at 0 16.150082 90)
			(size 1.8034 0.508)
			(layers "F.Cu" "F.Mask" "F.Paste")
			(net "GND")
		)
		(pad "21" smd rect
			(at 0 16.999966 90)
			(size 1.8034 0.508)
			(layers "F.Cu" "F.Mask" "F.Paste")
			(net "M_F_DQ<15>")
		)
		(pad "22" smd rect
			(at 0 17.850104 90)
			(size 1.8034 0.508)
			(layers "F.Cu" "F.Mask" "F.Paste")
			(net "GND")
		)
		(pad "23" smd rect
			(at 0 18.699988 90)
			(size 1.8034 0.508)
			(layers "F.Cu" "F.Mask" "F.Paste")
			(net "M_F_DQ<11>")
		)
		(pad "24" smd rect
			(at 0 19.550126 90)
			(size 1.8034 0.508)
			(layers "F.Cu" "F.Mask" "F.Paste")
			(net "GND")
		)
		(pad "25" smd rect
			(at 0 20.40001 90)
			(size 1.8034 0.508)
			(layers "F.Cu" "F.Mask" "F.Paste")
			(net "M_F_DQ<21>")
		)
		(pad "26" smd rect
			(at 0 21.249894 90)
			(size 1.8034 0.508)
			(layers "F.Cu" "F.Mask" "F.Paste")
			(net "GND")
		)
		(pad "27" smd rect
			(at 0 22.100032 90)
			(size 1.8034 0.508)
			(layers "F.Cu" "F.Mask" "F.Paste")
			(net "M_F_DQ<17>")
		)
		(pad "28" smd rect
			(at 0 22.949916 90)
			(size 1.8034 0.508)
			(layers "F.Cu" "F.Mask" "F.Paste")
			(net "GND")
		)
		(pad "29" smd rect
			(at 0 23.800054 90)
			(size 1.8034 0.508)
			(layers "F.Cu" "F.Mask" "F.Paste")
			(net "M_F_DQS_DP<11>")
		)
		(pad "30" smd rect
			(at 0 24.649938 90)
			(size 1.8034 0.508)
			(layers "F.Cu" "F.Mask" "F.Paste")
			(net "M_F_DQS_DN<11>")
		)
		(pad "31" smd rect
			(at 0 25.500076 90)
			(size 1.8034 0.508)
			(layers "F.Cu" "F.Mask" "F.Paste")
			(net "GND")
		)
		(pad "32" smd rect
			(at 0 26.34996 90)
			(size 1.8034 0.508)
			(layers "F.Cu" "F.Mask" "F.Paste")
			(net "M_F_DQ<23>")
		)
		(pad "33" smd rect
			(at 0 27.200098 90)
			(size 1.8034 0.508)
			(layers "F.Cu" "F.Mask" "F.Paste")
			(net "GND")
		)
		(pad "34" smd rect
			(at 0 28.049982 90)
			(size 1.8034 0.508)
			(layers "F.Cu" "F.Mask" "F.Paste")
			(net "M_F_DQ<19>")
		)
		(pad "35" smd rect
			(at 0 28.90012 90)
			(size 1.8034 0.508)
			(layers "F.Cu" "F.Mask" "F.Paste")
			(net "GND")
		)
		(pad "36" smd rect
			(at 0 29.750004 90)
			(size 1.8034 0.508)
			(layers "F.Cu" "F.Mask" "F.Paste")
			(net "M_F_DQ<29>")
		)
		(pad "37" smd rect
			(at 0 30.599888 90)
			(size 1.8034 0.508)
			(layers "F.Cu" "F.Mask" "F.Paste")
			(net "GND")
		)
		(pad "38" smd rect
			(at 0 31.450026 90)
			(size 1.8034 0.508)
			(layers "F.Cu" "F.Mask" "F.Paste")
			(net "M_F_DQ<25>")
		)
		(pad "39" smd rect
			(at 0 32.29991 90)
			(size 1.8034 0.508)
			(layers "F.Cu" "F.Mask" "F.Paste")
			(net "GND")
		)
		(pad "40" smd rect
			(at 0 33.150048 90)
			(size 1.8034 0.508)
			(layers "F.Cu" "F.Mask" "F.Paste")
			(net "M_F_DQS_DP<12>")
		)
		(pad "41" smd rect
			(at 0 33.999932 90)
			(size 1.8034 0.508)
			(layers "F.Cu" "F.Mask" "F.Paste")
			(net "M_F_DQS_DN<12>")
		)
		(pad "42" smd rect
			(at 0 34.85007 90)
			(size 1.8034 0.508)
			(layers "F.Cu" "F.Mask" "F.Paste")
			(net "GND")
		)
		(pad "43" smd rect
			(at 0 35.699954 90)
			(size 1.8034 0.508)
			(layers "F.Cu" "F.Mask" "F.Paste")
			(net "M_F_DQ<31>")
		)
		(pad "44" smd rect
			(at 0 36.550092 90)
			(size 1.8034 0.508)
			(layers "F.Cu" "F.Mask" "F.Paste")
			(net "GND")
		)
		(pad "45" smd rect
			(at 0 37.399976 90)
			(size 1.8034 0.508)
			(layers "F.Cu" "F.Mask" "F.Paste")
			(net "M_F_DQ<27>")
		)
		(pad "46" smd rect
			(at 0 38.250114 90)
			(size 1.8034 0.508)
			(layers "F.Cu" "F.Mask" "F.Paste")
			(net "GND")
		)
		(pad "47" smd rect
			(at 0 39.099998 90)
			(size 1.8034 0.508)
			(layers "F.Cu" "F.Mask" "F.Paste")
			(net "M_F_ECC<5>")
		)
		(pad "48" smd rect
			(at 0 39.949882 90)
			(size 1.8034 0.508)
			(layers "F.Cu" "F.Mask" "F.Paste")
			(net "GND")
		)
		(pad "49" smd rect
			(at 0 40.80002 90)
			(size 1.8034 0.508)
			(layers "F.Cu" "F.Mask" "F.Paste")
			(net "M_F_ECC<1>")
		)
		(pad "50" smd rect
			(at 0 41.649904 90)
			(size 1.8034 0.508)
			(layers "F.Cu" "F.Mask" "F.Paste")
			(net "GND")
		)
		(pad "51" smd rect
			(at 0 42.500042 90)
			(size 1.8034 0.508)
			(layers "F.Cu" "F.Mask" "F.Paste")
			(net "M_F_DQS_DP<17>")
		)
		(pad "52" smd rect
			(at 0 43.349926 90)
			(size 1.8034 0.508)
			(layers "F.Cu" "F.Mask" "F.Paste")
			(net "M_F_DQS_DN<17>")
		)
		(pad "53" smd rect
			(at 0 44.200064 90)
			(size 1.8034 0.508)
			(layers "F.Cu" "F.Mask" "F.Paste")
			(net "GND")
		)
		(pad "54" smd rect
			(at 0 45.049948 90)
			(size 1.8034 0.508)
			(layers "F.Cu" "F.Mask" "F.Paste")
			(net "M_F_ECC<7>")
		)
		(pad "55" smd rect
			(at 0 45.900086 90)
			(size 1.8034 0.508)
			(layers "F.Cu" "F.Mask" "F.Paste")
			(net "GND")
		)
		(pad "56" smd rect
			(at 0 46.74997 90)
			(size 1.8034 0.508)
			(layers "F.Cu" "F.Mask" "F.Paste")
			(net "M_F_ECC<3>")
		)
		(pad "57" smd rect
			(at 0 47.600108 90)
			(size 1.8034 0.508)
			(layers "F.Cu" "F.Mask" "F.Paste")
			(net "GND")
		)
		(pad "58" smd rect
			(at 0 48.449992 90)
			(size 1.8034 0.508)
			(layers "F.Cu" "F.Mask" "F.Paste")
			(net "M_DEF_RST_N")
		)
		(pad "59" smd rect
			(at 0 49.299876 90)
			(size 1.8034 0.508)
			(layers "F.Cu" "F.Mask" "F.Paste")
			(net "PVDDQ_DEF")
		)
		(pad "60" smd rect
			(at 0 50.150014 90)
			(size 1.8034 0.508)
			(layers "F.Cu" "F.Mask" "F.Paste")
			(net "M_F_CKE<0>")
		)
		(pad "61" smd rect
			(at 0 50.999898 90)
			(size 1.8034 0.508)
			(layers "F.Cu" "F.Mask" "F.Paste")
			(net "PVDDQ_DEF")
		)
		(pad "62" smd rect
			(at 0 51.850036 90)
			(size 1.8034 0.508)
			(layers "F.Cu" "F.Mask" "F.Paste")
			(net "M_F_ACT_N")
		)
		(pad "63" smd rect
			(at 0 52.69992 90)
			(size 1.8034 0.508)
			(layers "F.Cu" "F.Mask" "F.Paste")
			(net "M_F_BG<0>")
		)
		(pad "64" smd rect
			(at 0 53.550058 90)
			(size 1.8034 0.508)
			(layers "F.Cu" "F.Mask" "F.Paste")
			(net "PVDDQ_DEF")
		)
		(pad "65" smd rect
			(at 0 54.399942 90)
			(size 1.8034 0.508)
			(layers "F.Cu" "F.Mask" "F.Paste")
			(net "M_F_MA<12>")
		)
		(pad "66" smd rect
			(at 0 55.25008 90)
			(size 1.8034 0.508)
			(layers "F.Cu" "F.Mask" "F.Paste")
			(net "M_F_MA<9>")
		)
		(pad "67" smd rect
			(at 0 56.099964 90)
			(size 1.8034 0.508)
			(layers "F.Cu" "F.Mask" "F.Paste")
			(net "PVDDQ_DEF")
		)
		(pad "68" smd rect
			(at 0 56.950102 90)
			(size 1.8034 0.508)
			(layers "F.Cu" "F.Mask" "F.Paste")
			(net "M_F_MA<8>")
		)
		(pad "69" smd rect
			(at 0 57.799986 90)
			(size 1.8034 0.508)
			(layers "F.Cu" "F.Mask" "F.Paste")
			(net "M_F_MA<6>")
		)
		(pad "70" smd rect
			(at 0 58.650124 90)
			(size 1.8034 0.508)
			(layers "F.Cu" "F.Mask" "F.Paste")
			(net "PVDDQ_DEF")
		)
		(pad "71" smd rect
			(at 0 59.500008 90)
			(size 1.8034 0.508)
			(layers "F.Cu" "F.Mask" "F.Paste")
			(net "M_F_MA<3>")
		)
		(pad "72" smd rect
			(at 0 60.349892 90)
			(size 1.8034 0.508)
			(layers "F.Cu" "F.Mask" "F.Paste")
			(net "M_F_MA<1>")
		)
		(pad "73" smd rect
			(at 0 61.20003 90)
			(size 1.8034 0.508)
			(layers "F.Cu" "F.Mask" "F.Paste")
			(net "PVDDQ_DEF")
		)
		(pad "74" smd rect
			(at 0 62.049914 90)
			(size 1.8034 0.508)
			(layers "F.Cu" "F.Mask" "F.Paste")
			(net "M_F_CLK_DP<0>")
		)
		(pad "75" smd rect
			(at 0 62.900052 90)
			(size 1.8034 0.508)
			(layers "F.Cu" "F.Mask" "F.Paste")
			(net "M_F_CLK_DN<0>")
		)
		(pad "76" smd rect
			(at 0 63.749936 90)
			(size 1.8034 0.508)
			(layers "F.Cu" "F.Mask" "F.Paste")
			(net "PVDDQ_DEF")
		)
		(pad "77" smd rect
			(at 0 64.600074 90)
			(size 1.8034 0.508)
			(layers "F.Cu" "F.Mask" "F.Paste")
			(net "PVTT_DEF")
		)
		(pad "78" smd rect
			(at 0 70.550024 90)
			(size 1.8034 0.508)
			(layers "F.Cu" "F.Mask" "F.Paste")
			(net "FM_DIMM_EVENT_COD_N")
		)
		(pad "79" smd rect
			(at 0 71.399908 90)
			(size 1.8034 0.508)
			(layers "F.Cu" "F.Mask" "F.Paste")
			(net "M_F_MA<0>")
		)
		(pad "80" smd rect
			(at 0 72.250046 90)
			(size 1.8034 0.508)
			(layers "F.Cu" "F.Mask" "F.Paste")
			(net "PVDDQ_DEF")
		)
		(pad "81" smd rect
			(at 0 73.09993 90)
			(size 1.8034 0.508)
			(layers "F.Cu" "F.Mask" "F.Paste")
			(net "M_F_BA<0>")
		)
		(pad "82" smd rect
			(at 0 73.950068 90)
			(size 1.8034 0.508)
			(layers "F.Cu" "F.Mask" "F.Paste")
			(net "M_F_MA<16>")
		)
		(pad "83" smd rect
			(at 0 74.799952 90)
			(size 1.8034 0.508)
			(layers "F.Cu" "F.Mask" "F.Paste")
			(net "PVDDQ_DEF")
		)
		(pad "84" smd rect
			(at 0 75.65009 90)
			(size 1.8034 0.508)
			(layers "F.Cu" "F.Mask" "F.Paste")
			(net "M_F_CS_N<0>")
		)
		(pad "85" smd rect
			(at 0 76.499974 90)
			(size 1.8034 0.508)
			(layers "F.Cu" "F.Mask" "F.Paste")
			(net "PVDDQ_DEF")
		)
		(pad "86" smd rect
			(at 0 77.350112 90)
			(size 1.8034 0.508)
			(layers "F.Cu" "F.Mask" "F.Paste")
			(net "M_F_MA<15>")
		)
		(pad "87" smd rect
			(at 0 78.199996 90)
			(size 1.8034 0.508)
			(layers "F.Cu" "F.Mask" "F.Paste")
			(net "M_F_ODT<0>")
		)
		(pad "88" smd rect
			(at 0 79.04988 90)
			(size 1.8034 0.508)
			(layers "F.Cu" "F.Mask" "F.Paste")
			(net "PVDDQ_DEF")
		)
		(pad "89" smd rect
			(at 0 79.900018 90)
			(size 1.8034 0.508)
			(layers "F.Cu" "F.Mask" "F.Paste")
			(net "M_F_CS_N<1>")
		)
		(pad "90" smd rect
			(at 0 80.749902 90)
			(size 1.8034 0.508)
			(layers "F.Cu" "F.Mask" "F.Paste")
			(net "PVDDQ_DEF")
		)
		(pad "91" smd rect
			(at 0 81.60004 90)
			(size 1.8034 0.508)
			(layers "F.Cu" "F.Mask" "F.Paste")
			(net "M_F_ODT<1>")
		)
		(pad "92" smd rect
			(at 0 82.449924 90)
			(size 1.8034 0.508)
			(layers "F.Cu" "F.Mask" "F.Paste")
			(net "PVDDQ_DEF")
		)
		(pad "93" smd rect
			(at 0 83.300062 90)
			(size 1.8034 0.508)
			(layers "F.Cu" "F.Mask" "F.Paste")
			(net "M_F_CS_N<2>")
		)
		(pad "94" smd rect
			(at 0 84.149946 90)
			(size 1.8034 0.508)
			(layers "F.Cu" "F.Mask" "F.Paste")
			(net "GND")
		)
		(pad "95" smd rect
			(at 0 85.000084 90)
			(size 1.8034 0.508)
			(layers "F.Cu" "F.Mask" "F.Paste")
			(net "M_F_DQ<37>")
		)
		(pad "96" smd rect
			(at 0 85.849968 90)
			(size 1.8034 0.508)
			(layers "F.Cu" "F.Mask" "F.Paste")
			(net "GND")
		)
		(pad "97" smd rect
			(at 0 86.700106 90)
			(size 1.8034 0.508)
			(layers "F.Cu" "F.Mask" "F.Paste")
			(net "M_F_DQ<33>")
		)
		(pad "98" smd rect
			(at 0 87.54999 90)
			(size 1.8034 0.508)
			(layers "F.Cu" "F.Mask" "F.Paste")
			(net "GND")
		)
		(pad "99" smd rect
			(at 0 88.399874 90)
			(size 1.8034 0.508)
			(layers "F.Cu" "F.Mask" "F.Paste")
			(net "M_F_DQS_DP<13>")
		)
		(pad "100" smd rect
			(at 0 89.250012 90)
			(size 1.8034 0.508)
			(layers "F.Cu" "F.Mask" "F.Paste")
			(net "M_F_DQS_DN<13>")
		)
		(pad "101" smd rect
			(at 0 90.099896 90)
			(size 1.8034 0.508)
			(layers "F.Cu" "F.Mask" "F.Paste")
			(net "GND")
		)
		(pad "102" smd rect
			(at 0 90.950034 90)
			(size 1.8034 0.508)
			(layers "F.Cu" "F.Mask" "F.Paste")
			(net "M_F_DQ<39>")
		)
		(pad "103" smd rect
			(at 0 91.799918 90)
			(size 1.8034 0.508)
			(layers "F.Cu" "F.Mask" "F.Paste")
			(net "GND")
		)
		(pad "104" smd rect
			(at 0 92.650056 90)
			(size 1.8034 0.508)
			(layers "F.Cu" "F.Mask" "F.Paste")
			(net "M_F_DQ<35>")
		)
		(pad "105" smd rect
			(at 0 93.49994 90)
			(size 1.8034 0.508)
			(layers "F.Cu" "F.Mask" "F.Paste")
			(net "GND")
		)
		(pad "106" smd rect
			(at 0 94.350078 90)
			(size 1.8034 0.508)
			(layers "F.Cu" "F.Mask" "F.Paste")
			(net "M_F_DQ<45>")
		)
		(pad "107" smd rect
			(at 0 95.199962 90)
			(size 1.8034 0.508)
			(layers "F.Cu" "F.Mask" "F.Paste")
			(net "GND")
		)
		(pad "108" smd rect
			(at 0 96.0501 90)
			(size 1.8034 0.508)
			(layers "F.Cu" "F.Mask" "F.Paste")
			(net "M_F_DQ<41>")
		)
		(pad "109" smd rect
			(at 0 96.899984 90)
			(size 1.8034 0.508)
			(layers "F.Cu" "F.Mask" "F.Paste")
			(net "GND")
		)
		(pad "110" smd rect
			(at 0 97.750122 90)
			(size 1.8034 0.508)
			(layers "F.Cu" "F.Mask" "F.Paste")
			(net "M_F_DQS_DP<14>")
		)
		(pad "111" smd rect
			(at 0 98.600006 90)
			(size 1.8034 0.508)
			(layers "F.Cu" "F.Mask" "F.Paste")
			(net "M_F_DQS_DN<14>")
		)
		(pad "112" smd rect
			(at 0 99.44989 90)
			(size 1.8034 0.508)
			(layers "F.Cu" "F.Mask" "F.Paste")
			(net "GND")
		)
		(pad "113" smd rect
			(at 0 100.300028 90)
			(size 1.8034 0.508)
			(layers "F.Cu" "F.Mask" "F.Paste")
			(net "M_F_DQ<47>")
		)
		(pad "114" smd rect
			(at 0 101.149912 90)
			(size 1.8034 0.508)
			(layers "F.Cu" "F.Mask" "F.Paste")
			(net "GND")
		)
		(pad "115" smd rect
			(at 0 102.00005 90)
			(size 1.8034 0.508)
			(layers "F.Cu" "F.Mask" "F.Paste")
			(net "M_F_DQ<43>")
		)
		(pad "116" smd rect
			(at 0 102.849934 90)
			(size 1.8034 0.508)
			(layers "F.Cu" "F.Mask" "F.Paste")
			(net "GND")
		)
		(pad "117" smd rect
			(at 0 103.700072 90)
			(size 1.8034 0.508)
			(layers "F.Cu" "F.Mask" "F.Paste")
			(net "M_F_DQ<53>")
		)
		(pad "118" smd rect
			(at 0 104.549956 90)
			(size 1.8034 0.508)
			(layers "F.Cu" "F.Mask" "F.Paste")
			(net "GND")
		)
		(pad "119" smd rect
			(at 0 105.400094 90)
			(size 1.8034 0.508)
			(layers "F.Cu" "F.Mask" "F.Paste")
			(net "M_F_DQ<49>")
		)
		(pad "120" smd rect
			(at 0 106.249978 90)
			(size 1.8034 0.508)
			(layers "F.Cu" "F.Mask" "F.Paste")
			(net "GND")
		)
		(pad "121" smd rect
			(at 0 107.100116 90)
			(size 1.8034 0.508)
			(layers "F.Cu" "F.Mask" "F.Paste")
			(net "M_F_DQS_DP<15>")
		)
		(pad "122" smd rect
			(at 0 107.95 90)
			(size 1.8034 0.508)
			(layers "F.Cu" "F.Mask" "F.Paste")
			(net "M_F_DQS_DN<15>")
		)
		(pad "123" smd rect
			(at 0 108.799884 90)
			(size 1.8034 0.508)
			(layers "F.Cu" "F.Mask" "F.Paste")
			(net "GND")
		)
		(pad "124" smd rect
			(at 0 109.650022 90)
			(size 1.8034 0.508)
			(layers "F.Cu" "F.Mask" "F.Paste")
			(net "M_F_DQ<55>")
		)
		(pad "125" smd rect
			(at 0 110.499906 90)
			(size 1.8034 0.508)
			(layers "F.Cu" "F.Mask" "F.Paste")
			(net "GND")
		)
		(pad "126" smd rect
			(at 0 111.350044 90)
			(size 1.8034 0.508)
			(layers "F.Cu" "F.Mask" "F.Paste")
			(net "M_F_DQ<51>")
		)
		(pad "127" smd rect
			(at 0 112.199928 90)
			(size 1.8034 0.508)
			(layers "F.Cu" "F.Mask" "F.Paste")
			(net "GND")
		)
		(pad "128" smd rect
			(at 0 113.050066 90)
			(size 1.8034 0.508)
			(layers "F.Cu" "F.Mask" "F.Paste")
			(net "M_F_DQ<61>")
		)
		(pad "129" smd rect
			(at 0 113.89995 90)
			(size 1.8034 0.508)
			(layers "F.Cu" "F.Mask" "F.Paste")
			(net "GND")
		)
		(pad "130" smd rect
			(at 0 114.750088 90)
			(size 1.8034 0.508)
			(layers "F.Cu" "F.Mask" "F.Paste")
			(net "M_F_DQ<57>")
		)
		(pad "131" smd rect
			(at 0 115.599972 90)
			(size 1.8034 0.508)
			(layers "F.Cu" "F.Mask" "F.Paste")
			(net "GND")
		)
		(pad "132" smd rect
			(at 0 116.45011 90)
			(size 1.8034 0.508)
			(layers "F.Cu" "F.Mask" "F.Paste")
			(net "M_F_DQS_DP<16>")
		)
		(pad "133" smd rect
			(at 0 117.299994 90)
			(size 1.8034 0.508)
			(layers "F.Cu" "F.Mask" "F.Paste")
			(net "M_F_DQS_DN<16>")
		)
		(pad "134" smd rect
			(at 0 118.149878 90)
			(size 1.8034 0.508)
			(layers "F.Cu" "F.Mask" "F.Paste")
			(net "GND")
		)
		(pad "135" smd rect
			(at 0 119.000016 90)
			(size 1.8034 0.508)
			(layers "F.Cu" "F.Mask" "F.Paste")
			(net "M_F_DQ<63>")
		)
		(pad "136" smd rect
			(at 0 119.8499 90)
			(size 1.8034 0.508)
			(layers "F.Cu" "F.Mask" "F.Paste")
			(net "GND")
		)
		(pad "137" smd rect
			(at 0 120.700038 90)
			(size 1.8034 0.508)
			(layers "F.Cu" "F.Mask" "F.Paste")
			(net "M_F_DQ<59>")
		)
		(pad "138" smd rect
			(at 0 121.549922 90)
			(size 1.8034 0.508)
			(layers "F.Cu" "F.Mask" "F.Paste")
			(net "GND")
		)
		(pad "139" smd rect
			(at 0 122.40006 90)
			(size 1.8034 0.508)
			(layers "F.Cu" "F.Mask" "F.Paste")
			(net "GND")
		)
		(pad "140" smd rect
			(at 0 123.249944 90)
			(size 1.8034 0.508)
			(layers "F.Cu" "F.Mask" "F.Paste")
			(net "GND")
		)
		(pad "141" smd rect
			(at 0 124.100082 90)
			(size 1.8034 0.508)
			(layers "F.Cu" "F.Mask" "F.Paste")
			(net "SMB_DDR_DEF_VPP_SCL")
		)
		(pad "142" smd rect
			(at 0 124.949966 90)
			(size 1.8034 0.508)
			(layers "F.Cu" "F.Mask" "F.Paste")
			(net "PVPP_DEF")
		)
		(pad "143" smd rect
			(at 0 125.800104 90)
			(size 1.8034 0.508)
			(layers "F.Cu" "F.Mask" "F.Paste")
			(net "PVPP_DEF")
		)
		(pad "144" smd rect
			(at 0 126.649988 90)
			(size 1.8034 0.508)
			(layers "F.Cu" "F.Mask" "F.Paste")
			(net "TP_CH_F_DIMM_F0_RFU_2")
		)
		(pad "145" smd rect
			(at 4.59994 0 90)
			(size 1.8034 0.508)
			(layers "F.Cu" "F.Mask" "F.Paste")
			(net "P12V_NVDIMM_DEF")
		)
		(pad "146" smd rect
			(at 4.59994 0.849884 90)
			(size 1.8034 0.508)
			(layers "F.Cu" "F.Mask" "F.Paste")
			(net "M_F_VREF")
		)
		(pad "147" smd rect
			(at 4.59994 1.700022 90)
			(size 1.8034 0.508)
			(layers "F.Cu" "F.Mask" "F.Paste")
			(net "GND")
		)
		(pad "148" smd rect
			(at 4.59994 2.549906 90)
			(size 1.8034 0.508)
			(layers "F.Cu" "F.Mask" "F.Paste")
			(net "M_F_DQ<4>")
		)
		(pad "149" smd rect
			(at 4.59994 3.400044 90)
			(size 1.8034 0.508)
			(layers "F.Cu" "F.Mask" "F.Paste")
			(net "GND")
		)
		(pad "150" smd rect
			(at 4.59994 4.249928 90)
			(size 1.8034 0.508)
			(layers "F.Cu" "F.Mask" "F.Paste")
			(net "M_F_DQ<0>")
		)
		(pad "151" smd rect
			(at 4.59994 5.100066 90)
			(size 1.8034 0.508)
			(layers "F.Cu" "F.Mask" "F.Paste")
			(net "GND")
		)
		(pad "152" smd rect
			(at 4.59994 5.94995 90)
			(size 1.8034 0.508)
			(layers "F.Cu" "F.Mask" "F.Paste")
			(net "M_F_DQS_DN<0>")
		)
		(pad "153" smd rect
			(at 4.59994 6.800088 90)
			(size 1.8034 0.508)
			(layers "F.Cu" "F.Mask" "F.Paste")
			(net "M_F_DQS_DP<0>")
		)
		(pad "154" smd rect
			(at 4.59994 7.649972 90)
			(size 1.8034 0.508)
			(layers "F.Cu" "F.Mask" "F.Paste")
			(net "GND")
		)
		(pad "155" smd rect
			(at 4.59994 8.50011 90)
			(size 1.8034 0.508)
			(layers "F.Cu" "F.Mask" "F.Paste")
			(net "M_F_DQ<6>")
		)
		(pad "156" smd rect
			(at 4.59994 9.349994 90)
			(size 1.8034 0.508)
			(layers "F.Cu" "F.Mask" "F.Paste")
			(net "GND")
		)
		(pad "157" smd rect
			(at 4.59994 10.199878 90)
			(size 1.8034 0.508)
			(layers "F.Cu" "F.Mask" "F.Paste")
			(net "M_F_DQ<2>")
		)
		(pad "158" smd rect
			(at 4.59994 11.050016 90)
			(size 1.8034 0.508)
			(layers "F.Cu" "F.Mask" "F.Paste")
			(net "GND")
		)
		(pad "159" smd rect
			(at 4.59994 11.8999 90)
			(size 1.8034 0.508)
			(layers "F.Cu" "F.Mask" "F.Paste")
			(net "M_F_DQ<12>")
		)
		(pad "160" smd rect
			(at 4.59994 12.750038 90)
			(size 1.8034 0.508)
			(layers "F.Cu" "F.Mask" "F.Paste")
			(net "GND")
		)
		(pad "161" smd rect
			(at 4.59994 13.599922 90)
			(size 1.8034 0.508)
			(layers "F.Cu" "F.Mask" "F.Paste")
			(net "M_F_DQ<8>")
		)
		(pad "162" smd rect
			(at 4.59994 14.45006 90)
			(size 1.8034 0.508)
			(layers "F.Cu" "F.Mask" "F.Paste")
			(net "GND")
		)
		(pad "163" smd rect
			(at 4.59994 15.299944 90)
			(size 1.8034 0.508)
			(layers "F.Cu" "F.Mask" "F.Paste")
			(net "M_F_DQS_DN<1>")
		)
		(pad "164" smd rect
			(at 4.59994 16.150082 90)
			(size 1.8034 0.508)
			(layers "F.Cu" "F.Mask" "F.Paste")
			(net "M_F_DQS_DP<1>")
		)
		(pad "165" smd rect
			(at 4.59994 16.999966 90)
			(size 1.8034 0.508)
			(layers "F.Cu" "F.Mask" "F.Paste")
			(net "GND")
		)
		(pad "166" smd rect
			(at 4.59994 17.850104 90)
			(size 1.8034 0.508)
			(layers "F.Cu" "F.Mask" "F.Paste")
			(net "M_F_DQ<14>")
		)
		(pad "167" smd rect
			(at 4.59994 18.699988 90)
			(size 1.8034 0.508)
			(layers "F.Cu" "F.Mask" "F.Paste")
			(net "GND")
		)
		(pad "168" smd rect
			(at 4.59994 19.550126 90)
			(size 1.8034 0.508)
			(layers "F.Cu" "F.Mask" "F.Paste")
			(net "M_F_DQ<10>")
		)
		(pad "169" smd rect
			(at 4.59994 20.40001 90)
			(size 1.8034 0.508)
			(layers "F.Cu" "F.Mask" "F.Paste")
			(net "GND")
		)
		(pad "170" smd rect
			(at 4.59994 21.249894 90)
			(size 1.8034 0.508)
			(layers "F.Cu" "F.Mask" "F.Paste")
			(net "M_F_DQ<20>")
		)
		(pad "171" smd rect
			(at 4.59994 22.100032 90)
			(size 1.8034 0.508)
			(layers "F.Cu" "F.Mask" "F.Paste")
			(net "GND")
		)
		(pad "172" smd rect
			(at 4.59994 22.949916 90)
			(size 1.8034 0.508)
			(layers "F.Cu" "F.Mask" "F.Paste")
			(net "M_F_DQ<16>")
		)
		(pad "173" smd rect
			(at 4.59994 23.800054 90)
			(size 1.8034 0.508)
			(layers "F.Cu" "F.Mask" "F.Paste")
			(net "GND")
		)
		(pad "174" smd rect
			(at 4.59994 24.649938 90)
			(size 1.8034 0.508)
			(layers "F.Cu" "F.Mask" "F.Paste")
			(net "M_F_DQS_DN<2>")
		)
		(pad "175" smd rect
			(at 4.59994 25.500076 90)
			(size 1.8034 0.508)
			(layers "F.Cu" "F.Mask" "F.Paste")
			(net "M_F_DQS_DP<2>")
		)
		(pad "176" smd rect
			(at 4.59994 26.34996 90)
			(size 1.8034 0.508)
			(layers "F.Cu" "F.Mask" "F.Paste")
			(net "GND")
		)
		(pad "177" smd rect
			(at 4.59994 27.200098 90)
			(size 1.8034 0.508)
			(layers "F.Cu" "F.Mask" "F.Paste")
			(net "M_F_DQ<22>")
		)
		(pad "178" smd rect
			(at 4.59994 28.049982 90)
			(size 1.8034 0.508)
			(layers "F.Cu" "F.Mask" "F.Paste")
			(net "GND")
		)
		(pad "179" smd rect
			(at 4.59994 28.90012 90)
			(size 1.8034 0.508)
			(layers "F.Cu" "F.Mask" "F.Paste")
			(net "M_F_DQ<18>")
		)
		(pad "180" smd rect
			(at 4.59994 29.750004 90)
			(size 1.8034 0.508)
			(layers "F.Cu" "F.Mask" "F.Paste")
			(net "GND")
		)
		(pad "181" smd rect
			(at 4.59994 30.599888 90)
			(size 1.8034 0.508)
			(layers "F.Cu" "F.Mask" "F.Paste")
			(net "M_F_DQ<28>")
		)
		(pad "182" smd rect
			(at 4.59994 31.450026 90)
			(size 1.8034 0.508)
			(layers "F.Cu" "F.Mask" "F.Paste")
			(net "GND")
		)
		(pad "183" smd rect
			(at 4.59994 32.29991 90)
			(size 1.8034 0.508)
			(layers "F.Cu" "F.Mask" "F.Paste")
			(net "M_F_DQ<24>")
		)
		(pad "184" smd rect
			(at 4.59994 33.150048 90)
			(size 1.8034 0.508)
			(layers "F.Cu" "F.Mask" "F.Paste")
			(net "GND")
		)
		(pad "185" smd rect
			(at 4.59994 33.999932 90)
			(size 1.8034 0.508)
			(layers "F.Cu" "F.Mask" "F.Paste")
			(net "M_F_DQS_DN<3>")
		)
		(pad "186" smd rect
			(at 4.59994 34.85007 90)
			(size 1.8034 0.508)
			(layers "F.Cu" "F.Mask" "F.Paste")
			(net "M_F_DQS_DP<3>")
		)
		(pad "187" smd rect
			(at 4.59994 35.699954 90)
			(size 1.8034 0.508)
			(layers "F.Cu" "F.Mask" "F.Paste")
			(net "GND")
		)
		(pad "188" smd rect
			(at 4.59994 36.550092 90)
			(size 1.8034 0.508)
			(layers "F.Cu" "F.Mask" "F.Paste")
			(net "M_F_DQ<30>")
		)
		(pad "189" smd rect
			(at 4.59994 37.399976 90)
			(size 1.8034 0.508)
			(layers "F.Cu" "F.Mask" "F.Paste")
			(net "GND")
		)
		(pad "190" smd rect
			(at 4.59994 38.250114 90)
			(size 1.8034 0.508)
			(layers "F.Cu" "F.Mask" "F.Paste")
			(net "M_F_DQ<26>")
		)
		(pad "191" smd rect
			(at 4.59994 39.099998 90)
			(size 1.8034 0.508)
			(layers "F.Cu" "F.Mask" "F.Paste")
			(net "GND")
		)
		(pad "192" smd rect
			(at 4.59994 39.949882 90)
			(size 1.8034 0.508)
			(layers "F.Cu" "F.Mask" "F.Paste")
			(net "M_F_ECC<4>")
		)
		(pad "193" smd rect
			(at 4.59994 40.80002 90)
			(size 1.8034 0.508)
			(layers "F.Cu" "F.Mask" "F.Paste")
			(net "GND")
		)
		(pad "194" smd rect
			(at 4.59994 41.649904 90)
			(size 1.8034 0.508)
			(layers "F.Cu" "F.Mask" "F.Paste")
			(net "M_F_ECC<0>")
		)
		(pad "195" smd rect
			(at 4.59994 42.500042 90)
			(size 1.8034 0.508)
			(layers "F.Cu" "F.Mask" "F.Paste")
			(net "GND")
		)
		(pad "196" smd rect
			(at 4.59994 43.349926 90)
			(size 1.8034 0.508)
			(layers "F.Cu" "F.Mask" "F.Paste")
			(net "M_F_DQS_DN<8>")
		)
		(pad "197" smd rect
			(at 4.59994 44.200064 90)
			(size 1.8034 0.508)
			(layers "F.Cu" "F.Mask" "F.Paste")
			(net "M_F_DQS_DP<8>")
		)
		(pad "198" smd rect
			(at 4.59994 45.049948 90)
			(size 1.8034 0.508)
			(layers "F.Cu" "F.Mask" "F.Paste")
			(net "GND")
		)
		(pad "199" smd rect
			(at 4.59994 45.900086 90)
			(size 1.8034 0.508)
			(layers "F.Cu" "F.Mask" "F.Paste")
			(net "M_F_ECC<6>")
		)
		(pad "200" smd rect
			(at 4.59994 46.74997 90)
			(size 1.8034 0.508)
			(layers "F.Cu" "F.Mask" "F.Paste")
			(net "GND")
		)
		(pad "201" smd rect
			(at 4.59994 47.600108 90)
			(size 1.8034 0.508)
			(layers "F.Cu" "F.Mask" "F.Paste")
			(net "M_F_ECC<2>")
		)
		(pad "202" smd rect
			(at 4.59994 48.449992 90)
			(size 1.8034 0.508)
			(layers "F.Cu" "F.Mask" "F.Paste")
			(net "GND")
		)
		(pad "203" smd rect
			(at 4.59994 49.299876 90)
			(size 1.8034 0.508)
			(layers "F.Cu" "F.Mask" "F.Paste")
			(net "M_F_CKE<1>")
		)
		(pad "204" smd rect
			(at 4.59994 50.150014 90)
			(size 1.8034 0.508)
			(layers "F.Cu" "F.Mask" "F.Paste")
			(net "PVDDQ_DEF")
		)
		(pad "205" smd rect
			(at 4.59994 50.999898 90)
			(size 1.8034 0.508)
			(layers "F.Cu" "F.Mask" "F.Paste")
			(net "TP_CH_F_DIMM_F0_RFU_0")
		)
		(pad "206" smd rect
			(at 4.59994 51.850036 90)
			(size 1.8034 0.508)
			(layers "F.Cu" "F.Mask" "F.Paste")
			(net "PVDDQ_DEF")
		)
		(pad "207" smd rect
			(at 4.59994 52.69992 90)
			(size 1.8034 0.508)
			(layers "F.Cu" "F.Mask" "F.Paste")
			(net "M_F_BG<1>")
		)
		(pad "208" smd rect
			(at 4.59994 53.550058 90)
			(size 1.8034 0.508)
			(layers "F.Cu" "F.Mask" "F.Paste")
			(net "M_F_ALERT_N")
		)
		(pad "209" smd rect
			(at 4.59994 54.399942 90)
			(size 1.8034 0.508)
			(layers "F.Cu" "F.Mask" "F.Paste")
			(net "PVDDQ_DEF")
		)
		(pad "210" smd rect
			(at 4.59994 55.25008 90)
			(size 1.8034 0.508)
			(layers "F.Cu" "F.Mask" "F.Paste")
			(net "M_F_MA<11>")
		)
		(pad "211" smd rect
			(at 4.59994 56.099964 90)
			(size 1.8034 0.508)
			(layers "F.Cu" "F.Mask" "F.Paste")
			(net "M_F_MA<7>")
		)
		(pad "212" smd rect
			(at 4.59994 56.950102 90)
			(size 1.8034 0.508)
			(layers "F.Cu" "F.Mask" "F.Paste")
			(net "PVDDQ_DEF")
		)
		(pad "213" smd rect
			(at 4.59994 57.799986 90)
			(size 1.8034 0.508)
			(layers "F.Cu" "F.Mask" "F.Paste")
			(net "M_F_MA<5>")
		)
		(pad "214" smd rect
			(at 4.59994 58.650124 90)
			(size 1.8034 0.508)
			(layers "F.Cu" "F.Mask" "F.Paste")
			(net "M_F_MA<4>")
		)
		(pad "215" smd rect
			(at 4.59994 59.500008 90)
			(size 1.8034 0.508)
			(layers "F.Cu" "F.Mask" "F.Paste")
			(net "PVDDQ_DEF")
		)
		(pad "216" smd rect
			(at 4.59994 60.349892 90)
			(size 1.8034 0.508)
			(layers "F.Cu" "F.Mask" "F.Paste")
			(net "M_F_MA<2>")
		)
		(pad "217" smd rect
			(at 4.59994 61.20003 90)
			(size 1.8034 0.508)
			(layers "F.Cu" "F.Mask" "F.Paste")
			(net "PVDDQ_DEF")
		)
		(pad "218" smd rect
			(at 4.59994 62.049914 90)
			(size 1.8034 0.508)
			(layers "F.Cu" "F.Mask" "F.Paste")
			(net "M_F_CLK_DP<1>")
		)
		(pad "219" smd rect
			(at 4.59994 62.900052 90)
			(size 1.8034 0.508)
			(layers "F.Cu" "F.Mask" "F.Paste")
			(net "M_F_CLK_DN<1>")
		)
		(pad "220" smd rect
			(at 4.59994 63.749936 90)
			(size 1.8034 0.508)
			(layers "F.Cu" "F.Mask" "F.Paste")
			(net "PVDDQ_DEF")
		)
		(pad "221" smd rect
			(at 4.59994 64.600074 90)
			(size 1.8034 0.508)
			(layers "F.Cu" "F.Mask" "F.Paste")
			(net "PVTT_DEF")
		)
		(pad "222" smd rect
			(at 4.59994 70.550024 90)
			(size 1.8034 0.508)
			(layers "F.Cu" "F.Mask" "F.Paste")
			(net "M_F_PAR")
		)
		(pad "223" smd rect
			(at 4.59994 71.399908 90)
			(size 1.8034 0.508)
			(layers "F.Cu" "F.Mask" "F.Paste")
			(net "PVDDQ_DEF")
		)
		(pad "224" smd rect
			(at 4.59994 72.250046 90)
			(size 1.8034 0.508)
			(layers "F.Cu" "F.Mask" "F.Paste")
			(net "M_F_BA<1>")
		)
		(pad "225" smd rect
			(at 4.59994 73.09993 90)
			(size 1.8034 0.508)
			(layers "F.Cu" "F.Mask" "F.Paste")
			(net "M_F_MA<10>")
		)
		(pad "226" smd rect
			(at 4.59994 73.950068 90)
			(size 1.8034 0.508)
			(layers "F.Cu" "F.Mask" "F.Paste")
			(net "PVDDQ_DEF")
		)
		(pad "227" smd rect
			(at 4.59994 74.799952 90)
			(size 1.8034 0.508)
			(layers "F.Cu" "F.Mask" "F.Paste")
			(net "TP_CH_F_DIMM_F0_RFU_1")
		)
		(pad "228" smd rect
			(at 4.59994 75.65009 90)
			(size 1.8034 0.508)
			(layers "F.Cu" "F.Mask" "F.Paste")
			(net "M_F_MA<14>")
		)
		(pad "229" smd rect
			(at 4.59994 76.499974 90)
			(size 1.8034 0.508)
			(layers "F.Cu" "F.Mask" "F.Paste")
			(net "PVDDQ_DEF")
		)
		(pad "230" smd rect
			(at 4.59994 77.350112 90)
			(size 1.8034 0.508)
			(layers "F.Cu" "F.Mask" "F.Paste")
			(net "FM_ADR_COMPLETE_DEF_N")
		)
		(pad "231" smd rect
			(at 4.59994 78.199996 90)
			(size 1.8034 0.508)
			(layers "F.Cu" "F.Mask" "F.Paste")
			(net "PVDDQ_DEF")
		)
		(pad "232" smd rect
			(at 4.59994 79.04988 90)
			(size 1.8034 0.508)
			(layers "F.Cu" "F.Mask" "F.Paste")
			(net "M_F_MA<13>")
		)
		(pad "233" smd rect
			(at 4.59994 79.900018 90)
			(size 1.8034 0.508)
			(layers "F.Cu" "F.Mask" "F.Paste")
			(net "PVDDQ_DEF")
		)
		(pad "234" smd rect
			(at 4.59994 80.749902 90)
			(size 1.8034 0.508)
			(layers "F.Cu" "F.Mask" "F.Paste")
			(net "M_F_MA<17>")
		)
		(pad "235" smd rect
			(at 4.59994 81.60004 90)
			(size 1.8034 0.508)
			(layers "F.Cu" "F.Mask" "F.Paste")
			(net "M_F_C<2>")
		)
		(pad "236" smd rect
			(at 4.59994 82.449924 90)
			(size 1.8034 0.508)
			(layers "F.Cu" "F.Mask" "F.Paste")
			(net "PVDDQ_DEF")
		)
		(pad "237" smd rect
			(at 4.59994 83.300062 90)
			(size 1.8034 0.508)
			(layers "F.Cu" "F.Mask" "F.Paste")
			(net "M_F_CS_N<3>")
		)
		(pad "238" smd rect
			(at 4.59994 84.149946 90)
			(size 1.8034 0.508)
			(layers "F.Cu" "F.Mask" "F.Paste")
			(net "PVPP_DEF")
		)
		(pad "239" smd rect
			(at 4.59994 85.000084 90)
			(size 1.8034 0.508)
			(layers "F.Cu" "F.Mask" "F.Paste")
			(net "GND")
		)
		(pad "240" smd rect
			(at 4.59994 85.849968 90)
			(size 1.8034 0.508)
			(layers "F.Cu" "F.Mask" "F.Paste")
			(net "M_F_DQ<36>")
		)
		(pad "241" smd rect
			(at 4.59994 86.700106 90)
			(size 1.8034 0.508)
			(layers "F.Cu" "F.Mask" "F.Paste")
			(net "GND")
		)
		(pad "242" smd rect
			(at 4.59994 87.54999 90)
			(size 1.8034 0.508)
			(layers "F.Cu" "F.Mask" "F.Paste")
			(net "M_F_DQ<32>")
		)
		(pad "243" smd rect
			(at 4.59994 88.399874 90)
			(size 1.8034 0.508)
			(layers "F.Cu" "F.Mask" "F.Paste")
			(net "GND")
		)
		(pad "244" smd rect
			(at 4.59994 89.250012 90)
			(size 1.8034 0.508)
			(layers "F.Cu" "F.Mask" "F.Paste")
			(net "M_F_DQS_DN<4>")
		)
		(pad "245" smd rect
			(at 4.59994 90.099896 90)
			(size 1.8034 0.508)
			(layers "F.Cu" "F.Mask" "F.Paste")
			(net "M_F_DQS_DP<4>")
		)
		(pad "246" smd rect
			(at 4.59994 90.950034 90)
			(size 1.8034 0.508)
			(layers "F.Cu" "F.Mask" "F.Paste")
			(net "GND")
		)
		(pad "247" smd rect
			(at 4.59994 91.799918 90)
			(size 1.8034 0.508)
			(layers "F.Cu" "F.Mask" "F.Paste")
			(net "M_F_DQ<38>")
		)
		(pad "248" smd rect
			(at 4.59994 92.650056 90)
			(size 1.8034 0.508)
			(layers "F.Cu" "F.Mask" "F.Paste")
			(net "GND")
		)
		(pad "249" smd rect
			(at 4.59994 93.49994 90)
			(size 1.8034 0.508)
			(layers "F.Cu" "F.Mask" "F.Paste")
			(net "M_F_DQ<34>")
		)
		(pad "250" smd rect
			(at 4.59994 94.350078 90)
			(size 1.8034 0.508)
			(layers "F.Cu" "F.Mask" "F.Paste")
			(net "GND")
		)
		(pad "251" smd rect
			(at 4.59994 95.199962 90)
			(size 1.8034 0.508)
			(layers "F.Cu" "F.Mask" "F.Paste")
			(net "M_F_DQ<44>")
		)
		(pad "252" smd rect
			(at 4.59994 96.0501 90)
			(size 1.8034 0.508)
			(layers "F.Cu" "F.Mask" "F.Paste")
			(net "GND")
		)
		(pad "253" smd rect
			(at 4.59994 96.899984 90)
			(size 1.8034 0.508)
			(layers "F.Cu" "F.Mask" "F.Paste")
			(net "M_F_DQ<40>")
		)
		(pad "254" smd rect
			(at 4.59994 97.750122 90)
			(size 1.8034 0.508)
			(layers "F.Cu" "F.Mask" "F.Paste")
			(net "GND")
		)
		(pad "255" smd rect
			(at 4.59994 98.600006 90)
			(size 1.8034 0.508)
			(layers "F.Cu" "F.Mask" "F.Paste")
			(net "M_F_DQS_DN<5>")
		)
		(pad "256" smd rect
			(at 4.59994 99.44989 90)
			(size 1.8034 0.508)
			(layers "F.Cu" "F.Mask" "F.Paste")
			(net "M_F_DQS_DP<5>")
		)
		(pad "257" smd rect
			(at 4.59994 100.300028 90)
			(size 1.8034 0.508)
			(layers "F.Cu" "F.Mask" "F.Paste")
			(net "GND")
		)
		(pad "258" smd rect
			(at 4.59994 101.149912 90)
			(size 1.8034 0.508)
			(layers "F.Cu" "F.Mask" "F.Paste")
			(net "M_F_DQ<46>")
		)
		(pad "259" smd rect
			(at 4.59994 102.00005 90)
			(size 1.8034 0.508)
			(layers "F.Cu" "F.Mask" "F.Paste")
			(net "GND")
		)
		(pad "260" smd rect
			(at 4.59994 102.849934 90)
			(size 1.8034 0.508)
			(layers "F.Cu" "F.Mask" "F.Paste")
			(net "M_F_DQ<42>")
		)
		(pad "261" smd rect
			(at 4.59994 103.700072 90)
			(size 1.8034 0.508)
			(layers "F.Cu" "F.Mask" "F.Paste")
			(net "GND")
		)
		(pad "262" smd rect
			(at 4.59994 104.549956 90)
			(size 1.8034 0.508)
			(layers "F.Cu" "F.Mask" "F.Paste")
			(net "M_F_DQ<52>")
		)
		(pad "263" smd rect
			(at 4.59994 105.400094 90)
			(size 1.8034 0.508)
			(layers "F.Cu" "F.Mask" "F.Paste")
			(net "GND")
		)
		(pad "264" smd rect
			(at 4.59994 106.249978 90)
			(size 1.8034 0.508)
			(layers "F.Cu" "F.Mask" "F.Paste")
			(net "M_F_DQ<48>")
		)
		(pad "265" smd rect
			(at 4.59994 107.100116 90)
			(size 1.8034 0.508)
			(layers "F.Cu" "F.Mask" "F.Paste")
			(net "GND")
		)
		(pad "266" smd rect
			(at 4.59994 107.95 90)
			(size 1.8034 0.508)
			(layers "F.Cu" "F.Mask" "F.Paste")
			(net "M_F_DQS_DN<6>")
		)
		(pad "267" smd rect
			(at 4.59994 108.799884 90)
			(size 1.8034 0.508)
			(layers "F.Cu" "F.Mask" "F.Paste")
			(net "M_F_DQS_DP<6>")
		)
		(pad "268" smd rect
			(at 4.59994 109.650022 90)
			(size 1.8034 0.508)
			(layers "F.Cu" "F.Mask" "F.Paste")
			(net "GND")
		)
		(pad "269" smd rect
			(at 4.59994 110.499906 90)
			(size 1.8034 0.508)
			(layers "F.Cu" "F.Mask" "F.Paste")
			(net "M_F_DQ<54>")
		)
		(pad "270" smd rect
			(at 4.59994 111.350044 90)
			(size 1.8034 0.508)
			(layers "F.Cu" "F.Mask" "F.Paste")
			(net "GND")
		)
		(pad "271" smd rect
			(at 4.59994 112.199928 90)
			(size 1.8034 0.508)
			(layers "F.Cu" "F.Mask" "F.Paste")
			(net "M_F_DQ<50>")
		)
		(pad "272" smd rect
			(at 4.59994 113.050066 90)
			(size 1.8034 0.508)
			(layers "F.Cu" "F.Mask" "F.Paste")
			(net "GND")
		)
		(pad "273" smd rect
			(at 4.59994 113.89995 90)
			(size 1.8034 0.508)
			(layers "F.Cu" "F.Mask" "F.Paste")
			(net "M_F_DQ<60>")
		)
		(pad "274" smd rect
			(at 4.59994 114.750088 90)
			(size 1.8034 0.508)
			(layers "F.Cu" "F.Mask" "F.Paste")
			(net "GND")
		)
		(pad "275" smd rect
			(at 4.59994 115.599972 90)
			(size 1.8034 0.508)
			(layers "F.Cu" "F.Mask" "F.Paste")
			(net "M_F_DQ<56>")
		)
		(pad "276" smd rect
			(at 4.59994 116.45011 90)
			(size 1.8034 0.508)
			(layers "F.Cu" "F.Mask" "F.Paste")
			(net "GND")
		)
		(pad "277" smd rect
			(at 4.59994 117.299994 90)
			(size 1.8034 0.508)
			(layers "F.Cu" "F.Mask" "F.Paste")
			(net "M_F_DQS_DN<7>")
		)
		(pad "278" smd rect
			(at 4.59994 118.149878 90)
			(size 1.8034 0.508)
			(layers "F.Cu" "F.Mask" "F.Paste")
			(net "M_F_DQS_DP<7>")
		)
		(pad "279" smd rect
			(at 4.59994 119.000016 90)
			(size 1.8034 0.508)
			(layers "F.Cu" "F.Mask" "F.Paste")
			(net "GND")
		)
		(pad "280" smd rect
			(at 4.59994 119.8499 90)
			(size 1.8034 0.508)
			(layers "F.Cu" "F.Mask" "F.Paste")
			(net "M_F_DQ<62>")
		)
		(pad "281" smd rect
			(at 4.59994 120.700038 90)
			(size 1.8034 0.508)
			(layers "F.Cu" "F.Mask" "F.Paste")
			(net "GND")
		)
		(pad "282" smd rect
			(at 4.59994 121.549922 90)
			(size 1.8034 0.508)
			(layers "F.Cu" "F.Mask" "F.Paste")
			(net "M_F_DQ<58>")
		)
		(pad "283" smd rect
			(at 4.59994 122.40006 90)
			(size 1.8034 0.508)
			(layers "F.Cu" "F.Mask" "F.Paste")
			(net "GND")
		)
		(pad "284" smd rect
			(at 4.59994 123.249944 90)
			(size 1.8034 0.508)
			(layers "F.Cu" "F.Mask" "F.Paste")
			(net "PVPP_DEF")
		)
		(pad "285" smd rect
			(at 4.59994 124.100082 90)
			(size 1.8034 0.508)
			(layers "F.Cu" "F.Mask" "F.Paste")
			(net "SMB_DDR_DEF_VPP_SDA")
		)
		(pad "286" smd rect
			(at 4.59994 124.949966 90)
			(size 1.8034 0.508)
			(layers "F.Cu" "F.Mask" "F.Paste")
			(net "PVPP_DEF")
		)
		(pad "287" smd rect
			(at 4.59994 125.800104 90)
			(size 1.8034 0.508)
			(layers "F.Cu" "F.Mask" "F.Paste")
			(net "PVPP_DEF")
		)
		(pad "288" smd rect
			(at 4.59994 126.649988 90)
			(size 1.8034 0.508)
			(layers "F.Cu" "F.Mask" "F.Paste")
			(net "PVPP_DEF")
		)
	)
	(footprint ""
		(layer "F.Cu")
		(at 383.794 -55.4355 180)
		(property "Reference" "R7F28"
			(at 0 0 180)
			(layer "F.SilkS")
			(hide yes)
			(effects
				(font
					(size 1.27 1.27)
				)
			)
		)
		(property "Value" ""
			(at 0 0 180)
			(layer "F.Fab")
			(effects
				(font
					(size 1.27 1.27)
				)
			)
		)
		(duplicate_pad_numbers_are_jumpers no)
		(fp_poly
			(pts
				(xy -0.2794 -0.1016) (xy 0.2794 -0.1016) (xy 0.2794 0.9906) (xy -0.2794 0.9906)
			)
			(stroke
				(width 0)
				(type default)
			)
			(fill no)
			(layer "F.CrtYd")
		)
		(fp_line
			(start 0.2794 0.9906)
			(end 0.2794 -0.1016)
			(stroke
				(width 0.1)
				(type default)
			)
			(layer "F.Fab")
		)
		(fp_line
			(start 0.2794 -0.1016)
			(end -0.2794 -0.1016)
			(stroke
				(width 0.1)
				(type default)
			)
			(layer "F.Fab")
		)
		(fp_line
			(start -0.2794 0.9906)
			(end 0.2794 0.9906)
			(stroke
				(width 0.1)
				(type default)
			)
			(layer "F.Fab")
		)
		(fp_line
			(start -0.2794 -0.1016)
			(end -0.2794 0.9906)
			(stroke
				(width 0.1)
				(type default)
			)
			(layer "F.Fab")
		)
		(pad "1" smd rect
			(at 0 0 180)
			(size 0.508 0.508)
			(layers "F.Cu" "F.Mask" "F.Paste")
			(net "P3V3_STBY")
		)
		(pad "2" smd rect
			(at 0 0.889 180)
			(size 0.508 0.508)
			(layers "F.Cu" "F.Mask" "F.Paste")
			(net "PU_BIOS_SPI_WP0_N")
		)
		(zone
			(layer "F.Cu")
			(hatch none 0.5)
			(connect_pads
				(clearance 0)
			)
			(min_thickness 0.25)
			(keepout
				(tracks not_allowed)
				(vias allowed)
				(pads allowed)
				(copperpour not_allowed)
				(footprints allowed)
			)
			(placement
				(enabled no)
				(sheetname "")
			)
			(fill
				(thermal_gap 0.5)
				(thermal_bridge_width 0.5)
				(island_removal_mode 0)
			)
			(polygon
				(pts
					(xy 384.048 -56.0705) (xy 383.54 -56.0705) (xy 383.54 -55.6895) (xy 384.048 -55.6895)
				)
			)
		)
		(zone
			(layer "F.Cu")
			(hatch none 0.5)
			(connect_pads
				(clearance 0)
			)
			(min_thickness 0.25)
			(keepout
				(tracks allowed)
				(vias not_allowed)
				(pads allowed)
				(copperpour not_allowed)
				(footprints allowed)
			)
			(placement
				(enabled no)
				(sheetname "")
			)
			(fill
				(thermal_gap 0.5)
				(thermal_bridge_width 0.5)
				(island_removal_mode 0)
			)
			(polygon
				(pts
					(xy 384.048 -55.6895) (xy 383.54 -55.6895) (xy 383.54 -56.0705) (xy 384.048 -56.0705)
				)
			)
		)
	)
	(footprint ""
		(layer "F.Cu")
		(at 381.51562 -147.928076 180)
		(property "Reference" "CT68"
			(at -0.8382 -0.67818 180)
			(unlocked yes)
			(layer "F.SilkS")
			(effects
				(font
					(size 0.4064 0.254)
					(thickness 0.1524)
				)
				(justify left)
			)
		)
		(property "Value" ""
			(at 0 0 180)
			(layer "F.Fab")
			(effects
				(font
					(size 1.27 1.27)
				)
			)
		)
		(duplicate_pad_numbers_are_jumpers no)
		(fp_poly
			(pts
				(xy 0.3048 -0.1016) (xy 0.3048 0.9906) (xy -0.3048 0.9906) (xy -0.3048 -0.1016)
			)
			(stroke
				(width 0)
				(type default)
			)
			(fill no)
			(layer "F.CrtYd")
		)
		(fp_line
			(start 0.3048 0.9906)
			(end 0.3048 -0.1016)
			(stroke
				(width 0.1)
				(type default)
			)
			(layer "F.Fab")
		)
		(fp_line
			(start 0.3048 -0.1016)
			(end -0.3048 -0.1016)
			(stroke
				(width 0.1)
				(type default)
			)
			(layer "F.Fab")
		)
		(fp_line
			(start -0.3048 0.9906)
			(end 0.3048 0.9906)
			(stroke
				(width 0.1)
				(type default)
			)
			(layer "F.Fab")
		)
		(fp_line
			(start -0.3048 -0.1016)
			(end -0.3048 0.9906)
			(stroke
				(width 0.1)
				(type default)
			)
			(layer "F.Fab")
		)
		(pad "1" smd rect
			(at 0 0 180)
			(size 0.508 0.508)
			(layers "F.Cu" "F.Mask" "F.Paste")
			(net "VR_P1V05_PCH_STBY_PH1_PHASE_SW")
		)
		(pad "2" smd rect
			(at 0 0.889 180)
			(size 0.508 0.508)
			(layers "F.Cu" "F.Mask" "F.Paste")
			(net "VR_P1V05_PCH_STBY_PH1_SW_RC")
		)
		(zone
			(layer "F.Cu")
			(hatch none 0.5)
			(connect_pads
				(clearance 0)
			)
			(min_thickness 0.25)
			(keepout
				(tracks not_allowed)
				(vias allowed)
				(pads allowed)
				(copperpour not_allowed)
				(footprints allowed)
			)
			(placement
				(enabled no)
				(sheetname "")
			)
			(fill
				(thermal_gap 0.5)
				(thermal_bridge_width 0.5)
				(island_removal_mode 0)
			)
			(polygon
				(pts
					(xy 381.76962 -148.563076) (xy 381.26162 -148.563076) (xy 381.26162 -148.182076) (xy 381.76962 -148.182076)
				)
			)
		)
		(zone
			(layer "F.Cu")
			(hatch none 0.5)
			(connect_pads
				(clearance 0)
			)
			(min_thickness 0.25)
			(keepout
				(tracks allowed)
				(vias not_allowed)
				(pads allowed)
				(copperpour not_allowed)
				(footprints allowed)
			)
			(placement
				(enabled no)
				(sheetname "")
			)
			(fill
				(thermal_gap 0.5)
				(thermal_bridge_width 0.5)
				(island_removal_mode 0)
			)
			(polygon
				(pts
					(xy 381.76962 -148.182076) (xy 381.26162 -148.182076) (xy 381.26162 -148.563076) (xy 381.76962 -148.563076)
				)
			)
		)
	)
	(footprint ""
		(layer "F.Cu")
		(at 323.0245 -117.222016 -90)
		(property "Reference" "C832"
			(at -0.8382 -0.67818 270)
			(unlocked yes)
			(layer "F.SilkS")
			(effects
				(font
					(size 0.4064 0.254)
					(thickness 0.1524)
				)
				(justify left)
			)
		)
		(property "Value" ""
			(at 0 0 270)
			(layer "F.Fab")
			(effects
				(font
					(size 1.27 1.27)
				)
			)
		)
		(duplicate_pad_numbers_are_jumpers no)
		(fp_poly
			(pts
				(xy 0.3048 -0.1016) (xy 0.3048 0.9906) (xy -0.3048 0.9906) (xy -0.3048 -0.1016)
			)
			(stroke
				(width 0)
				(type default)
			)
			(fill no)
			(layer "F.CrtYd")
		)
		(fp_line
			(start -0.3048 0.9906)
			(end 0.3048 0.9906)
			(stroke
				(width 0.1)
				(type default)
			)
			(layer "F.Fab")
		)
		(fp_line
			(start 0.3048 0.9906)
			(end 0.3048 -0.1016)
			(stroke
				(width 0.1)
				(type default)
			)
			(layer "F.Fab")
		)
		(fp_line
			(start -0.3048 -0.1016)
			(end -0.3048 0.9906)
			(stroke
				(width 0.1)
				(type default)
			)
			(layer "F.Fab")
		)
		(fp_line
			(start 0.3048 -0.1016)
			(end -0.3048 -0.1016)
			(stroke
				(width 0.1)
				(type default)
			)
			(layer "F.Fab")
		)
		(pad "1" smd rect
			(at 0 0 270)
			(size 0.508 0.508)
			(layers "F.Cu" "F.Mask" "F.Paste")
			(net "P3E_CPU0_PE1_PCH_TXN<11>")
		)
		(pad "2" smd rect
			(at 0 0.889 270)
			(size 0.508 0.508)
			(layers "F.Cu" "F.Mask" "F.Paste")
			(net "P3E_CPU0_PE1_PCH_CON_TXN<11>")
		)
		(zone
			(layer "F.Cu")
			(hatch none 0.5)
			(connect_pads
				(clearance 0)
			)
			(min_thickness 0.25)
			(keepout
				(tracks not_allowed)
				(vias allowed)
				(pads allowed)
				(copperpour not_allowed)
				(footprints allowed)
			)
			(placement
				(enabled no)
				(sheetname "")
			)
			(fill
				(thermal_gap 0.5)
				(thermal_bridge_width 0.5)
				(island_removal_mode 0)
			)
			(polygon
				(pts
					(xy 322.3895 -117.476016) (xy 322.3895 -116.968016) (xy 322.7705 -116.968016) (xy 322.7705 -117.476016)
				)
			)
		)
		(zone
			(layer "F.Cu")
			(hatch none 0.5)
			(connect_pads
				(clearance 0)
			)
			(min_thickness 0.25)
			(keepout
				(tracks allowed)
				(vias not_allowed)
				(pads allowed)
				(copperpour not_allowed)
				(footprints allowed)
			)
			(placement
				(enabled no)
				(sheetname "")
			)
			(fill
				(thermal_gap 0.5)
				(thermal_bridge_width 0.5)
				(island_removal_mode 0)
			)
			(polygon
				(pts
					(xy 322.7705 -117.476016) (xy 322.7705 -116.968016) (xy 322.3895 -116.968016) (xy 322.3895 -117.476016)
				)
			)
		)
	)
	(footprint ""
		(layer "F.Cu")
		(at 178.054 -84.328 180)
		(property "Reference" "R4D69"
			(at 0 0 180)
			(layer "F.SilkS")
			(hide yes)
			(effects
				(font
					(size 1.27 1.27)
				)
			)
		)
		(property "Value" ""
			(at 0 0 180)
			(layer "F.Fab")
			(effects
				(font
					(size 1.27 1.27)
				)
			)
		)
		(duplicate_pad_numbers_are_jumpers no)
		(fp_poly
			(pts
				(xy -0.2794 -0.1016) (xy 0.2794 -0.1016) (xy 0.2794 0.9906) (xy -0.2794 0.9906)
			)
			(stroke
				(width 0)
				(type default)
			)
			(fill no)
			(layer "F.CrtYd")
		)
		(fp_line
			(start 0.2794 0.9906)
			(end 0.2794 -0.1016)
			(stroke
				(width 0.1)
				(type default)
			)
			(layer "F.Fab")
		)
		(fp_line
			(start 0.2794 -0.1016)
			(end -0.2794 -0.1016)
			(stroke
				(width 0.1)
				(type default)
			)
			(layer "F.Fab")
		)
		(fp_line
			(start -0.2794 0.9906)
			(end 0.2794 0.9906)
			(stroke
				(width 0.1)
				(type default)
			)
			(layer "F.Fab")
		)
		(fp_line
			(start -0.2794 -0.1016)
			(end -0.2794 0.9906)
			(stroke
				(width 0.1)
				(type default)
			)
			(layer "F.Fab")
		)
		(pad "1" smd rect
			(at 0 0 180)
			(size 0.508 0.508)
			(layers "F.Cu" "F.Mask" "F.Paste")
			(net "P3V3")
		)
		(pad "2" smd rect
			(at 0 0.889 180)
			(size 0.508 0.508)
			(layers "F.Cu" "F.Mask" "F.Paste")
			(net "FM_CPU1_MCP_CLK_EN_N")
		)
		(zone
			(layer "F.Cu")
			(hatch none 0.5)
			(connect_pads
				(clearance 0)
			)
			(min_thickness 0.25)
			(keepout
				(tracks not_allowed)
				(vias allowed)
				(pads allowed)
				(copperpour not_allowed)
				(footprints allowed)
			)
			(placement
				(enabled no)
				(sheetname "")
			)
			(fill
				(thermal_gap 0.5)
				(thermal_bridge_width 0.5)
				(island_removal_mode 0)
			)
			(polygon
				(pts
					(xy 178.308 -84.963) (xy 177.8 -84.963) (xy 177.8 -84.582) (xy 178.308 -84.582)
				)
			)
		)
		(zone
			(layer "F.Cu")
			(hatch none 0.5)
			(connect_pads
				(clearance 0)
			)
			(min_thickness 0.25)
			(keepout
				(tracks allowed)
				(vias not_allowed)
				(pads allowed)
				(copperpour not_allowed)
				(footprints allowed)
			)
			(placement
				(enabled no)
				(sheetname "")
			)
			(fill
				(thermal_gap 0.5)
				(thermal_bridge_width 0.5)
				(island_removal_mode 0)
			)
			(polygon
				(pts
					(xy 178.308 -84.582) (xy 177.8 -84.582) (xy 177.8 -84.963) (xy 178.308 -84.963)
				)
			)
		)
	)
	(footprint ""
		(layer "F.Cu")
		(at 12.66952 -3.53441 180)
		(property "Reference" "R12W31"
			(at -0.8382 -0.67818 180)
			(unlocked yes)
			(layer "F.SilkS")
			(effects
				(font
					(size 0.4064 0.254)
					(thickness 0.1524)
				)
				(justify left)
			)
		)
		(property "Value" ""
			(at 0 0 180)
			(layer "F.Fab")
			(effects
				(font
					(size 1.27 1.27)
				)
			)
		)
		(duplicate_pad_numbers_are_jumpers no)
		(fp_poly
			(pts
				(xy -0.2794 -0.1016) (xy 0.2794 -0.1016) (xy 0.2794 0.9906) (xy -0.2794 0.9906)
			)
			(stroke
				(width 0)
				(type default)
			)
			(fill no)
			(layer "F.CrtYd")
		)
		(fp_line
			(start 0.2794 0.9906)
			(end 0.2794 -0.1016)
			(stroke
				(width 0.1)
				(type default)
			)
			(layer "F.Fab")
		)
		(fp_line
			(start 0.2794 -0.1016)
			(end -0.2794 -0.1016)
			(stroke
				(width 0.1)
				(type default)
			)
			(layer "F.Fab")
		)
		(fp_line
			(start -0.2794 0.9906)
			(end 0.2794 0.9906)
			(stroke
				(width 0.1)
				(type default)
			)
			(layer "F.Fab")
		)
		(fp_line
			(start -0.2794 -0.1016)
			(end -0.2794 0.9906)
			(stroke
				(width 0.1)
				(type default)
			)
			(layer "F.Fab")
		)
		(pad "1" smd rect
			(at 0 0 180)
			(size 0.508 0.508)
			(layers "F.Cu" "F.Mask" "F.Paste")
			(net "PU_VR_PVDDQ_GHJ_FAULT1")
		)
		(pad "2" smd rect
			(at 0 0.889 180)
			(size 0.508 0.508)
			(layers "F.Cu" "F.Mask" "F.Paste")
			(net "PWRGD_PVDDQ_GHJ")
		)
		(zone
			(layer "F.Cu")
			(hatch none 0.5)
			(connect_pads
				(clearance 0)
			)
			(min_thickness 0.25)
			(keepout
				(tracks not_allowed)
				(vias allowed)
				(pads allowed)
				(copperpour not_allowed)
				(footprints allowed)
			)
			(placement
				(enabled no)
				(sheetname "")
			)
			(fill
				(thermal_gap 0.5)
				(thermal_bridge_width 0.5)
				(island_removal_mode 0)
			)
			(polygon
				(pts
					(xy 12.92352 -4.16941) (xy 12.41552 -4.16941) (xy 12.41552 -3.78841) (xy 12.92352 -3.78841)
				)
			)
		)
		(zone
			(layer "F.Cu")
			(hatch none 0.5)
			(connect_pads
				(clearance 0)
			)
			(min_thickness 0.25)
			(keepout
				(tracks allowed)
				(vias not_allowed)
				(pads allowed)
				(copperpour not_allowed)
				(footprints allowed)
			)
			(placement
				(enabled no)
				(sheetname "")
			)
			(fill
				(thermal_gap 0.5)
				(thermal_bridge_width 0.5)
				(island_removal_mode 0)
			)
			(polygon
				(pts
					(xy 12.92352 -3.78841) (xy 12.41552 -3.78841) (xy 12.41552 -4.16941) (xy 12.92352 -4.16941)
				)
			)
		)
	)
	(footprint ""
		(layer "F.Cu")
		(at 29.699458 3.778758 90)
		(property "Reference" "J1G3"
			(at 7.054088 34.562542 0)
			(unlocked yes)
			(layer "F.SilkS")
			(effects
				(font
					(size 0.7874 0.5842)
					(thickness 0.1524)
				)
				(justify left)
			)
		)
		(property "Value" ""
			(at 0 0 90)
			(layer "F.Fab")
			(effects
				(font
					(size 1.27 1.27)
				)
			)
		)
		(duplicate_pad_numbers_are_jumpers no)
		(fp_line
			(start 5.5499 -7.675118)
			(end 5.5499 -1.480058)
			(stroke
				(width 0.1524)
				(type default)
			)
			(layer "F.SilkS")
		)
		(fp_line
			(start -0.94996 -7.675118)
			(end 5.5499 -7.675118)
			(stroke
				(width 0.1524)
				(type default)
			)
			(layer "F.SilkS")
		)
		(fp_line
			(start -0.94996 -1.480058)
			(end -0.94996 -7.675118)
			(stroke
				(width 0.1524)
				(type default)
			)
			(layer "F.SilkS")
		)
		(fp_line
			(start 5.5499 128.130046)
			(end 5.5499 134.325106)
			(stroke
				(width 0.1524)
				(type default)
			)
			(layer "F.SilkS")
		)
		(fp_line
			(start 5.5499 134.325106)
			(end -0.94996 134.325106)
			(stroke
				(width 0.1524)
				(type default)
			)
			(layer "F.SilkS")
		)
		(fp_line
			(start -0.94996 134.325106)
			(end -0.94996 128.130046)
			(stroke
				(width 0.1524)
				(type default)
			)
			(layer "F.SilkS")
		)
		(fp_poly
			(pts
				(xy -2.984246 -0.461264) (xy -2.984246 0.554736) (xy -1.714246 0.046736)
			)
			(stroke
				(width 0)
				(type default)
			)
			(fill yes)
			(layer "F.SilkS")
		)
		(fp_poly
			(pts
				(xy -0.94996 -7.675118) (xy -0.94996 134.325106) (xy 5.5499 134.325106) (xy 5.5499 -7.675118)
			)
			(stroke
				(width 0)
				(type default)
			)
			(fill no)
			(layer "F.CrtYd")
		)
		(fp_line
			(start 5.5499 -7.675118)
			(end 5.5499 134.325106)
			(stroke
				(width 0.1)
				(type default)
			)
			(layer "F.Fab")
		)
		(fp_line
			(start -0.94996 -7.675118)
			(end 5.5499 -7.675118)
			(stroke
				(width 0.1)
				(type default)
			)
			(layer "F.Fab")
		)
		(fp_line
			(start 5.5499 134.325106)
			(end -0.94996 134.325106)
			(stroke
				(width 0.1)
				(type default)
			)
			(layer "F.Fab")
		)
		(fp_line
			(start -0.94996 134.325106)
			(end -0.94996 -7.675118)
			(stroke
				(width 0.1)
				(type default)
			)
			(layer "F.Fab")
		)
		(fp_poly
			(pts
				(xy -2.984246 -0.461264) (xy -2.984246 0.554736) (xy -1.714246 0.046736)
			)
			(stroke
				(width 0)
				(type default)
			)
			(fill yes)
			(layer "F.Fab")
		)
		(fp_text user "145"
			(at 6.035548 0.224282 0)
			(unlocked yes)
			(layer "F.SilkS")
			(effects
				(font
					(size 0.7874 0.5842)
					(thickness 0.1524)
				)
				(justify left)
			)
		)
		(fp_text user "221"
			(at 5.657342 64.9986 0)
			(unlocked yes)
			(layer "F.SilkS")
			(effects
				(font
					(size 0.7874 0.5842)
					(thickness 0.1524)
				)
				(justify left)
			)
		)
		(fp_text user "77"
			(at -1.630934 65.24244 0)
			(unlocked yes)
			(layer "F.SilkS")
			(effects
				(font
					(size 0.7874 0.5842)
					(thickness 0.1524)
				)
				(justify left)
			)
		)
		(fp_text user "78"
			(at -1.683512 69.690742 0)
			(unlocked yes)
			(layer "F.SilkS")
			(effects
				(font
					(size 0.7874 0.5842)
					(thickness 0.1524)
				)
				(justify left)
			)
		)
		(fp_text user "222"
			(at 6.058408 70.221602 0)
			(unlocked yes)
			(layer "F.SilkS")
			(effects
				(font
					(size 0.7874 0.5842)
					(thickness 0.1524)
				)
				(justify left)
			)
		)
		(fp_text user "144"
			(at -1.513332 125.900942 0)
			(unlocked yes)
			(layer "F.SilkS")
			(effects
				(font
					(size 0.7874 0.5842)
					(thickness 0.1524)
				)
				(justify left)
			)
		)
		(fp_text user "288"
			(at 6.241288 128.136142 0)
			(unlocked yes)
			(layer "F.SilkS")
			(effects
				(font
					(size 0.7874 0.5842)
					(thickness 0.1524)
				)
				(justify left)
			)
		)
		(fp_text user "145"
			(at 3.143758 -0.843788 90)
			(unlocked yes)
			(layer "F.Fab")
			(effects
				(font
					(size 0.7874 0.5842)
					(thickness 0.1524)
				)
				(justify left)
			)
		)
		(fp_text user "221"
			(at 1.556258 65.712848 90)
			(unlocked yes)
			(layer "F.Fab")
			(effects
				(font
					(size 0.7874 0.5842)
					(thickness 0.1524)
				)
				(justify left)
			)
		)
		(fp_text user "77"
			(at -1.098042 66.009012 90)
			(unlocked yes)
			(layer "F.Fab")
			(effects
				(font
					(size 0.7874 0.5842)
					(thickness 0.1524)
				)
				(justify left)
			)
		)
		(fp_text user "78"
			(at -0.945642 69.387212 90)
			(unlocked yes)
			(layer "F.Fab")
			(effects
				(font
					(size 0.7874 0.5842)
					(thickness 0.1524)
				)
				(justify left)
			)
		)
		(fp_text user "222"
			(at 3.092958 69.488812 90)
			(unlocked yes)
			(layer "F.Fab")
			(effects
				(font
					(size 0.7874 0.5842)
					(thickness 0.1524)
				)
				(justify left)
			)
		)
		(fp_text user "288"
			(at 2.965958 127.756412 90)
			(unlocked yes)
			(layer "F.Fab")
			(effects
				(font
					(size 0.7874 0.5842)
					(thickness 0.1524)
				)
				(justify left)
			)
		)
		(fp_text user "144"
			(at -0.564642 127.832612 90)
			(unlocked yes)
			(layer "F.Fab")
			(effects
				(font
					(size 0.7874 0.5842)
					(thickness 0.1524)
				)
				(justify left)
			)
		)
		(pad "" thru_hole circle
			(at 2.29997 -5.649976 90)
			(size 2.8194 2.8194)
			(drill 2.4384)
			(layers "*.Cu" "*.Mask")
			(remove_unused_layers no)
			(clearance 0.127)
			(thermal_gap 0.127)
		)
		(pad "" thru_hole oval
			(at 2.29997 68.90004 90)
			(size 2.8194 1.5748)
			(drill oval 2.4384 1.1938)
			(layers "*.Cu" "*.Mask")
			(remove_unused_layers no)
			(clearance 0.127)
			(thermal_gap 0.127)
		)
		(pad "" thru_hole circle
			(at 2.29997 132.299964 90)
			(size 2.8194 2.8194)
			(drill 2.4384)
			(layers "*.Cu" "*.Mask")
			(remove_unused_layers no)
			(clearance 0.127)
			(thermal_gap 0.127)
		)
		(pad "1" smd rect
			(at 0 0 90)
			(size 1.8034 0.508)
			(layers "F.Cu" "F.Mask" "F.Paste")
			(net "P12V_NVDIMM_GHJ")
		)
		(pad "2" smd rect
			(at 0 0.849884 90)
			(size 1.8034 0.508)
			(layers "F.Cu" "F.Mask" "F.Paste")
			(net "GND")
		)
		(pad "3" smd rect
			(at 0 1.700022 90)
			(size 1.8034 0.508)
			(layers "F.Cu" "F.Mask" "F.Paste")
			(net "M_J_DQ<5>")
		)
		(pad "4" smd rect
			(at 0 2.549906 90)
			(size 1.8034 0.508)
			(layers "F.Cu" "F.Mask" "F.Paste")
			(net "GND")
		)
		(pad "5" smd rect
			(at 0 3.400044 90)
			(size 1.8034 0.508)
			(layers "F.Cu" "F.Mask" "F.Paste")
			(net "M_J_DQ<1>")
		)
		(pad "6" smd rect
			(at 0 4.249928 90)
			(size 1.8034 0.508)
			(layers "F.Cu" "F.Mask" "F.Paste")
			(net "GND")
		)
		(pad "7" smd rect
			(at 0 5.100066 90)
			(size 1.8034 0.508)
			(layers "F.Cu" "F.Mask" "F.Paste")
			(net "M_J_DQS_DP<9>")
		)
		(pad "8" smd rect
			(at 0 5.94995 90)
			(size 1.8034 0.508)
			(layers "F.Cu" "F.Mask" "F.Paste")
			(net "M_J_DQS_DN<9>")
		)
		(pad "9" smd rect
			(at 0 6.800088 90)
			(size 1.8034 0.508)
			(layers "F.Cu" "F.Mask" "F.Paste")
			(net "GND")
		)
		(pad "10" smd rect
			(at 0 7.649972 90)
			(size 1.8034 0.508)
			(layers "F.Cu" "F.Mask" "F.Paste")
			(net "M_J_DQ<7>")
		)
		(pad "11" smd rect
			(at 0 8.50011 90)
			(size 1.8034 0.508)
			(layers "F.Cu" "F.Mask" "F.Paste")
			(net "GND")
		)
		(pad "12" smd rect
			(at 0 9.349994 90)
			(size 1.8034 0.508)
			(layers "F.Cu" "F.Mask" "F.Paste")
			(net "M_J_DQ<3>")
		)
		(pad "13" smd rect
			(at 0 10.199878 90)
			(size 1.8034 0.508)
			(layers "F.Cu" "F.Mask" "F.Paste")
			(net "GND")
		)
		(pad "14" smd rect
			(at 0 11.050016 90)
			(size 1.8034 0.508)
			(layers "F.Cu" "F.Mask" "F.Paste")
			(net "M_J_DQ<13>")
		)
		(pad "15" smd rect
			(at 0 11.8999 90)
			(size 1.8034 0.508)
			(layers "F.Cu" "F.Mask" "F.Paste")
			(net "GND")
		)
		(pad "16" smd rect
			(at 0 12.750038 90)
			(size 1.8034 0.508)
			(layers "F.Cu" "F.Mask" "F.Paste")
			(net "M_J_DQ<9>")
		)
		(pad "17" smd rect
			(at 0 13.599922 90)
			(size 1.8034 0.508)
			(layers "F.Cu" "F.Mask" "F.Paste")
			(net "GND")
		)
		(pad "18" smd rect
			(at 0 14.45006 90)
			(size 1.8034 0.508)
			(layers "F.Cu" "F.Mask" "F.Paste")
			(net "M_J_DQS_DP<10>")
		)
		(pad "19" smd rect
			(at 0 15.299944 90)
			(size 1.8034 0.508)
			(layers "F.Cu" "F.Mask" "F.Paste")
			(net "M_J_DQS_DN<10>")
		)
		(pad "20" smd rect
			(at 0 16.150082 90)
			(size 1.8034 0.508)
			(layers "F.Cu" "F.Mask" "F.Paste")
			(net "GND")
		)
		(pad "21" smd rect
			(at 0 16.999966 90)
			(size 1.8034 0.508)
			(layers "F.Cu" "F.Mask" "F.Paste")
			(net "M_J_DQ<15>")
		)
		(pad "22" smd rect
			(at 0 17.850104 90)
			(size 1.8034 0.508)
			(layers "F.Cu" "F.Mask" "F.Paste")
			(net "GND")
		)
		(pad "23" smd rect
			(at 0 18.699988 90)
			(size 1.8034 0.508)
			(layers "F.Cu" "F.Mask" "F.Paste")
			(net "M_J_DQ<11>")
		)
		(pad "24" smd rect
			(at 0 19.550126 90)
			(size 1.8034 0.508)
			(layers "F.Cu" "F.Mask" "F.Paste")
			(net "GND")
		)
		(pad "25" smd rect
			(at 0 20.40001 90)
			(size 1.8034 0.508)
			(layers "F.Cu" "F.Mask" "F.Paste")
			(net "M_J_DQ<21>")
		)
		(pad "26" smd rect
			(at 0 21.249894 90)
			(size 1.8034 0.508)
			(layers "F.Cu" "F.Mask" "F.Paste")
			(net "GND")
		)
		(pad "27" smd rect
			(at 0 22.100032 90)
			(size 1.8034 0.508)
			(layers "F.Cu" "F.Mask" "F.Paste")
			(net "M_J_DQ<17>")
		)
		(pad "28" smd rect
			(at 0 22.949916 90)
			(size 1.8034 0.508)
			(layers "F.Cu" "F.Mask" "F.Paste")
			(net "GND")
		)
		(pad "29" smd rect
			(at 0 23.800054 90)
			(size 1.8034 0.508)
			(layers "F.Cu" "F.Mask" "F.Paste")
			(net "M_J_DQS_DP<11>")
		)
		(pad "30" smd rect
			(at 0 24.649938 90)
			(size 1.8034 0.508)
			(layers "F.Cu" "F.Mask" "F.Paste")
			(net "M_J_DQS_DN<11>")
		)
		(pad "31" smd rect
			(at 0 25.500076 90)
			(size 1.8034 0.508)
			(layers "F.Cu" "F.Mask" "F.Paste")
			(net "GND")
		)
		(pad "32" smd rect
			(at 0 26.34996 90)
			(size 1.8034 0.508)
			(layers "F.Cu" "F.Mask" "F.Paste")
			(net "M_J_DQ<23>")
		)
		(pad "33" smd rect
			(at 0 27.200098 90)
			(size 1.8034 0.508)
			(layers "F.Cu" "F.Mask" "F.Paste")
			(net "GND")
		)
		(pad "34" smd rect
			(at 0 28.049982 90)
			(size 1.8034 0.508)
			(layers "F.Cu" "F.Mask" "F.Paste")
			(net "M_J_DQ<19>")
		)
		(pad "35" smd rect
			(at 0 28.90012 90)
			(size 1.8034 0.508)
			(layers "F.Cu" "F.Mask" "F.Paste")
			(net "GND")
		)
		(pad "36" smd rect
			(at 0 29.750004 90)
			(size 1.8034 0.508)
			(layers "F.Cu" "F.Mask" "F.Paste")
			(net "M_J_DQ<29>")
		)
		(pad "37" smd rect
			(at 0 30.599888 90)
			(size 1.8034 0.508)
			(layers "F.Cu" "F.Mask" "F.Paste")
			(net "GND")
		)
		(pad "38" smd rect
			(at 0 31.450026 90)
			(size 1.8034 0.508)
			(layers "F.Cu" "F.Mask" "F.Paste")
			(net "M_J_DQ<25>")
		)
		(pad "39" smd rect
			(at 0 32.29991 90)
			(size 1.8034 0.508)
			(layers "F.Cu" "F.Mask" "F.Paste")
			(net "GND")
		)
		(pad "40" smd rect
			(at 0 33.150048 90)
			(size 1.8034 0.508)
			(layers "F.Cu" "F.Mask" "F.Paste")
			(net "M_J_DQS_DP<12>")
		)
		(pad "41" smd rect
			(at 0 33.999932 90)
			(size 1.8034 0.508)
			(layers "F.Cu" "F.Mask" "F.Paste")
			(net "M_J_DQS_DN<12>")
		)
		(pad "42" smd rect
			(at 0 34.85007 90)
			(size 1.8034 0.508)
			(layers "F.Cu" "F.Mask" "F.Paste")
			(net "GND")
		)
		(pad "43" smd rect
			(at 0 35.699954 90)
			(size 1.8034 0.508)
			(layers "F.Cu" "F.Mask" "F.Paste")
			(net "M_J_DQ<31>")
		)
		(pad "44" smd rect
			(at 0 36.550092 90)
			(size 1.8034 0.508)
			(layers "F.Cu" "F.Mask" "F.Paste")
			(net "GND")
		)
		(pad "45" smd rect
			(at 0 37.399976 90)
			(size 1.8034 0.508)
			(layers "F.Cu" "F.Mask" "F.Paste")
			(net "M_J_DQ<27>")
		)
		(pad "46" smd rect
			(at 0 38.250114 90)
			(size 1.8034 0.508)
			(layers "F.Cu" "F.Mask" "F.Paste")
			(net "GND")
		)
		(pad "47" smd rect
			(at 0 39.099998 90)
			(size 1.8034 0.508)
			(layers "F.Cu" "F.Mask" "F.Paste")
			(net "M_J_ECC<5>")
		)
		(pad "48" smd rect
			(at 0 39.949882 90)
			(size 1.8034 0.508)
			(layers "F.Cu" "F.Mask" "F.Paste")
			(net "GND")
		)
		(pad "49" smd rect
			(at 0 40.80002 90)
			(size 1.8034 0.508)
			(layers "F.Cu" "F.Mask" "F.Paste")
			(net "M_J_ECC<1>")
		)
		(pad "50" smd rect
			(at 0 41.649904 90)
			(size 1.8034 0.508)
			(layers "F.Cu" "F.Mask" "F.Paste")
			(net "GND")
		)
		(pad "51" smd rect
			(at 0 42.500042 90)
			(size 1.8034 0.508)
			(layers "F.Cu" "F.Mask" "F.Paste")
			(net "M_J_DQS_DP<17>")
		)
		(pad "52" smd rect
			(at 0 43.349926 90)
			(size 1.8034 0.508)
			(layers "F.Cu" "F.Mask" "F.Paste")
			(net "M_J_DQS_DN<17>")
		)
		(pad "53" smd rect
			(at 0 44.200064 90)
			(size 1.8034 0.508)
			(layers "F.Cu" "F.Mask" "F.Paste")
			(net "GND")
		)
		(pad "54" smd rect
			(at 0 45.049948 90)
			(size 1.8034 0.508)
			(layers "F.Cu" "F.Mask" "F.Paste")
			(net "M_J_ECC<7>")
		)
		(pad "55" smd rect
			(at 0 45.900086 90)
			(size 1.8034 0.508)
			(layers "F.Cu" "F.Mask" "F.Paste")
			(net "GND")
		)
		(pad "56" smd rect
			(at 0 46.74997 90)
			(size 1.8034 0.508)
			(layers "F.Cu" "F.Mask" "F.Paste")
			(net "M_J_ECC<3>")
		)
		(pad "57" smd rect
			(at 0 47.600108 90)
			(size 1.8034 0.508)
			(layers "F.Cu" "F.Mask" "F.Paste")
			(net "GND")
		)
		(pad "58" smd rect
			(at 0 48.449992 90)
			(size 1.8034 0.508)
			(layers "F.Cu" "F.Mask" "F.Paste")
			(net "M_GHJ_RST_N")
		)
		(pad "59" smd rect
			(at 0 49.299876 90)
			(size 1.8034 0.508)
			(layers "F.Cu" "F.Mask" "F.Paste")
			(net "PVDDQ_GHJ")
		)
		(pad "60" smd rect
			(at 0 50.150014 90)
			(size 1.8034 0.508)
			(layers "F.Cu" "F.Mask" "F.Paste")
			(net "M_J_CKE<0>")
		)
		(pad "61" smd rect
			(at 0 50.999898 90)
			(size 1.8034 0.508)
			(layers "F.Cu" "F.Mask" "F.Paste")
			(net "PVDDQ_GHJ")
		)
		(pad "62" smd rect
			(at 0 51.850036 90)
			(size 1.8034 0.508)
			(layers "F.Cu" "F.Mask" "F.Paste")
			(net "M_J_ACT_N")
		)
		(pad "63" smd rect
			(at 0 52.69992 90)
			(size 1.8034 0.508)
			(layers "F.Cu" "F.Mask" "F.Paste")
			(net "M_J_BG<0>")
		)
		(pad "64" smd rect
			(at 0 53.550058 90)
			(size 1.8034 0.508)
			(layers "F.Cu" "F.Mask" "F.Paste")
			(net "PVDDQ_GHJ")
		)
		(pad "65" smd rect
			(at 0 54.399942 90)
			(size 1.8034 0.508)
			(layers "F.Cu" "F.Mask" "F.Paste")
			(net "M_J_MA<12>")
		)
		(pad "66" smd rect
			(at 0 55.25008 90)
			(size 1.8034 0.508)
			(layers "F.Cu" "F.Mask" "F.Paste")
			(net "M_J_MA<9>")
		)
		(pad "67" smd rect
			(at 0 56.099964 90)
			(size 1.8034 0.508)
			(layers "F.Cu" "F.Mask" "F.Paste")
			(net "PVDDQ_GHJ")
		)
		(pad "68" smd rect
			(at 0 56.950102 90)
			(size 1.8034 0.508)
			(layers "F.Cu" "F.Mask" "F.Paste")
			(net "M_J_MA<8>")
		)
		(pad "69" smd rect
			(at 0 57.799986 90)
			(size 1.8034 0.508)
			(layers "F.Cu" "F.Mask" "F.Paste")
			(net "M_J_MA<6>")
		)
		(pad "70" smd rect
			(at 0 58.650124 90)
			(size 1.8034 0.508)
			(layers "F.Cu" "F.Mask" "F.Paste")
			(net "PVDDQ_GHJ")
		)
		(pad "71" smd rect
			(at 0 59.500008 90)
			(size 1.8034 0.508)
			(layers "F.Cu" "F.Mask" "F.Paste")
			(net "M_J_MA<3>")
		)
		(pad "72" smd rect
			(at 0 60.349892 90)
			(size 1.8034 0.508)
			(layers "F.Cu" "F.Mask" "F.Paste")
			(net "M_J_MA<1>")
		)
		(pad "73" smd rect
			(at 0 61.20003 90)
			(size 1.8034 0.508)
			(layers "F.Cu" "F.Mask" "F.Paste")
			(net "PVDDQ_GHJ")
		)
		(pad "74" smd rect
			(at 0 62.049914 90)
			(size 1.8034 0.508)
			(layers "F.Cu" "F.Mask" "F.Paste")
			(net "M_J_CLK_DP<0>")
		)
		(pad "75" smd rect
			(at 0 62.900052 90)
			(size 1.8034 0.508)
			(layers "F.Cu" "F.Mask" "F.Paste")
			(net "M_J_CLK_DN<0>")
		)
		(pad "76" smd rect
			(at 0 63.749936 90)
			(size 1.8034 0.508)
			(layers "F.Cu" "F.Mask" "F.Paste")
			(net "PVDDQ_GHJ")
		)
		(pad "77" smd rect
			(at 0 64.600074 90)
			(size 1.8034 0.508)
			(layers "F.Cu" "F.Mask" "F.Paste")
			(net "PVTT_GHJ")
		)
		(pad "78" smd rect
			(at 0 70.550024 90)
			(size 1.8034 0.508)
			(layers "F.Cu" "F.Mask" "F.Paste")
			(net "FM_DIMM_EVENT_COD_N")
		)
		(pad "79" smd rect
			(at 0 71.399908 90)
			(size 1.8034 0.508)
			(layers "F.Cu" "F.Mask" "F.Paste")
			(net "M_J_MA<0>")
		)
		(pad "80" smd rect
			(at 0 72.250046 90)
			(size 1.8034 0.508)
			(layers "F.Cu" "F.Mask" "F.Paste")
			(net "PVDDQ_GHJ")
		)
		(pad "81" smd rect
			(at 0 73.09993 90)
			(size 1.8034 0.508)
			(layers "F.Cu" "F.Mask" "F.Paste")
			(net "M_J_BA<0>")
		)
		(pad "82" smd rect
			(at 0 73.950068 90)
			(size 1.8034 0.508)
			(layers "F.Cu" "F.Mask" "F.Paste")
			(net "M_J_MA<16>")
		)
		(pad "83" smd rect
			(at 0 74.799952 90)
			(size 1.8034 0.508)
			(layers "F.Cu" "F.Mask" "F.Paste")
			(net "PVDDQ_GHJ")
		)
		(pad "84" smd rect
			(at 0 75.65009 90)
			(size 1.8034 0.508)
			(layers "F.Cu" "F.Mask" "F.Paste")
			(net "M_J_CS_N<0>")
		)
		(pad "85" smd rect
			(at 0 76.499974 90)
			(size 1.8034 0.508)
			(layers "F.Cu" "F.Mask" "F.Paste")
			(net "PVDDQ_GHJ")
		)
		(pad "86" smd rect
			(at 0 77.350112 90)
			(size 1.8034 0.508)
			(layers "F.Cu" "F.Mask" "F.Paste")
			(net "M_J_MA<15>")
		)
		(pad "87" smd rect
			(at 0 78.199996 90)
			(size 1.8034 0.508)
			(layers "F.Cu" "F.Mask" "F.Paste")
			(net "M_J_ODT<0>")
		)
		(pad "88" smd rect
			(at 0 79.04988 90)
			(size 1.8034 0.508)
			(layers "F.Cu" "F.Mask" "F.Paste")
			(net "PVDDQ_GHJ")
		)
		(pad "89" smd rect
			(at 0 79.900018 90)
			(size 1.8034 0.508)
			(layers "F.Cu" "F.Mask" "F.Paste")
			(net "M_J_CS_N<1>")
		)
		(pad "90" smd rect
			(at 0 80.749902 90)
			(size 1.8034 0.508)
			(layers "F.Cu" "F.Mask" "F.Paste")
			(net "PVDDQ_GHJ")
		)
		(pad "91" smd rect
			(at 0 81.60004 90)
			(size 1.8034 0.508)
			(layers "F.Cu" "F.Mask" "F.Paste")
			(net "M_J_ODT<1>")
		)
		(pad "92" smd rect
			(at 0 82.449924 90)
			(size 1.8034 0.508)
			(layers "F.Cu" "F.Mask" "F.Paste")
			(net "PVDDQ_GHJ")
		)
		(pad "93" smd rect
			(at 0 83.300062 90)
			(size 1.8034 0.508)
			(layers "F.Cu" "F.Mask" "F.Paste")
			(net "M_J_CS_N<2>")
		)
		(pad "94" smd rect
			(at 0 84.149946 90)
			(size 1.8034 0.508)
			(layers "F.Cu" "F.Mask" "F.Paste")
			(net "GND")
		)
		(pad "95" smd rect
			(at 0 85.000084 90)
			(size 1.8034 0.508)
			(layers "F.Cu" "F.Mask" "F.Paste")
			(net "M_J_DQ<37>")
		)
		(pad "96" smd rect
			(at 0 85.849968 90)
			(size 1.8034 0.508)
			(layers "F.Cu" "F.Mask" "F.Paste")
			(net "GND")
		)
		(pad "97" smd rect
			(at 0 86.700106 90)
			(size 1.8034 0.508)
			(layers "F.Cu" "F.Mask" "F.Paste")
			(net "M_J_DQ<33>")
		)
		(pad "98" smd rect
			(at 0 87.54999 90)
			(size 1.8034 0.508)
			(layers "F.Cu" "F.Mask" "F.Paste")
			(net "GND")
		)
		(pad "99" smd rect
			(at 0 88.399874 90)
			(size 1.8034 0.508)
			(layers "F.Cu" "F.Mask" "F.Paste")
			(net "M_J_DQS_DP<13>")
		)
		(pad "100" smd rect
			(at 0 89.250012 90)
			(size 1.8034 0.508)
			(layers "F.Cu" "F.Mask" "F.Paste")
			(net "M_J_DQS_DN<13>")
		)
		(pad "101" smd rect
			(at 0 90.099896 90)
			(size 1.8034 0.508)
			(layers "F.Cu" "F.Mask" "F.Paste")
			(net "GND")
		)
		(pad "102" smd rect
			(at 0 90.950034 90)
			(size 1.8034 0.508)
			(layers "F.Cu" "F.Mask" "F.Paste")
			(net "M_J_DQ<39>")
		)
		(pad "103" smd rect
			(at 0 91.799918 90)
			(size 1.8034 0.508)
			(layers "F.Cu" "F.Mask" "F.Paste")
			(net "GND")
		)
		(pad "104" smd rect
			(at 0 92.650056 90)
			(size 1.8034 0.508)
			(layers "F.Cu" "F.Mask" "F.Paste")
			(net "M_J_DQ<35>")
		)
		(pad "105" smd rect
			(at 0 93.49994 90)
			(size 1.8034 0.508)
			(layers "F.Cu" "F.Mask" "F.Paste")
			(net "GND")
		)
		(pad "106" smd rect
			(at 0 94.350078 90)
			(size 1.8034 0.508)
			(layers "F.Cu" "F.Mask" "F.Paste")
			(net "M_J_DQ<45>")
		)
		(pad "107" smd rect
			(at 0 95.199962 90)
			(size 1.8034 0.508)
			(layers "F.Cu" "F.Mask" "F.Paste")
			(net "GND")
		)
		(pad "108" smd rect
			(at 0 96.0501 90)
			(size 1.8034 0.508)
			(layers "F.Cu" "F.Mask" "F.Paste")
			(net "M_J_DQ<41>")
		)
		(pad "109" smd rect
			(at 0 96.899984 90)
			(size 1.8034 0.508)
			(layers "F.Cu" "F.Mask" "F.Paste")
			(net "GND")
		)
		(pad "110" smd rect
			(at 0 97.750122 90)
			(size 1.8034 0.508)
			(layers "F.Cu" "F.Mask" "F.Paste")
			(net "M_J_DQS_DP<14>")
		)
		(pad "111" smd rect
			(at 0 98.600006 90)
			(size 1.8034 0.508)
			(layers "F.Cu" "F.Mask" "F.Paste")
			(net "M_J_DQS_DN<14>")
		)
		(pad "112" smd rect
			(at 0 99.44989 90)
			(size 1.8034 0.508)
			(layers "F.Cu" "F.Mask" "F.Paste")
			(net "GND")
		)
		(pad "113" smd rect
			(at 0 100.300028 90)
			(size 1.8034 0.508)
			(layers "F.Cu" "F.Mask" "F.Paste")
			(net "M_J_DQ<47>")
		)
		(pad "114" smd rect
			(at 0 101.149912 90)
			(size 1.8034 0.508)
			(layers "F.Cu" "F.Mask" "F.Paste")
			(net "GND")
		)
		(pad "115" smd rect
			(at 0 102.00005 90)
			(size 1.8034 0.508)
			(layers "F.Cu" "F.Mask" "F.Paste")
			(net "M_J_DQ<43>")
		)
		(pad "116" smd rect
			(at 0 102.849934 90)
			(size 1.8034 0.508)
			(layers "F.Cu" "F.Mask" "F.Paste")
			(net "GND")
		)
		(pad "117" smd rect
			(at 0 103.700072 90)
			(size 1.8034 0.508)
			(layers "F.Cu" "F.Mask" "F.Paste")
			(net "M_J_DQ<53>")
		)
		(pad "118" smd rect
			(at 0 104.549956 90)
			(size 1.8034 0.508)
			(layers "F.Cu" "F.Mask" "F.Paste")
			(net "GND")
		)
		(pad "119" smd rect
			(at 0 105.400094 90)
			(size 1.8034 0.508)
			(layers "F.Cu" "F.Mask" "F.Paste")
			(net "M_J_DQ<49>")
		)
		(pad "120" smd rect
			(at 0 106.249978 90)
			(size 1.8034 0.508)
			(layers "F.Cu" "F.Mask" "F.Paste")
			(net "GND")
		)
		(pad "121" smd rect
			(at 0 107.100116 90)
			(size 1.8034 0.508)
			(layers "F.Cu" "F.Mask" "F.Paste")
			(net "M_J_DQS_DP<15>")
		)
		(pad "122" smd rect
			(at 0 107.95 90)
			(size 1.8034 0.508)
			(layers "F.Cu" "F.Mask" "F.Paste")
			(net "M_J_DQS_DN<15>")
		)
		(pad "123" smd rect
			(at 0 108.799884 90)
			(size 1.8034 0.508)
			(layers "F.Cu" "F.Mask" "F.Paste")
			(net "GND")
		)
		(pad "124" smd rect
			(at 0 109.650022 90)
			(size 1.8034 0.508)
			(layers "F.Cu" "F.Mask" "F.Paste")
			(net "M_J_DQ<55>")
		)
		(pad "125" smd rect
			(at 0 110.499906 90)
			(size 1.8034 0.508)
			(layers "F.Cu" "F.Mask" "F.Paste")
			(net "GND")
		)
		(pad "126" smd rect
			(at 0 111.350044 90)
			(size 1.8034 0.508)
			(layers "F.Cu" "F.Mask" "F.Paste")
			(net "M_J_DQ<51>")
		)
		(pad "127" smd rect
			(at 0 112.199928 90)
			(size 1.8034 0.508)
			(layers "F.Cu" "F.Mask" "F.Paste")
			(net "GND")
		)
		(pad "128" smd rect
			(at 0 113.050066 90)
			(size 1.8034 0.508)
			(layers "F.Cu" "F.Mask" "F.Paste")
			(net "M_J_DQ<61>")
		)
		(pad "129" smd rect
			(at 0 113.89995 90)
			(size 1.8034 0.508)
			(layers "F.Cu" "F.Mask" "F.Paste")
			(net "GND")
		)
		(pad "130" smd rect
			(at 0 114.750088 90)
			(size 1.8034 0.508)
			(layers "F.Cu" "F.Mask" "F.Paste")
			(net "M_J_DQ<57>")
		)
		(pad "131" smd rect
			(at 0 115.599972 90)
			(size 1.8034 0.508)
			(layers "F.Cu" "F.Mask" "F.Paste")
			(net "GND")
		)
		(pad "132" smd rect
			(at 0 116.45011 90)
			(size 1.8034 0.508)
			(layers "F.Cu" "F.Mask" "F.Paste")
			(net "M_J_DQS_DP<16>")
		)
		(pad "133" smd rect
			(at 0 117.299994 90)
			(size 1.8034 0.508)
			(layers "F.Cu" "F.Mask" "F.Paste")
			(net "M_J_DQS_DN<16>")
		)
		(pad "134" smd rect
			(at 0 118.149878 90)
			(size 1.8034 0.508)
			(layers "F.Cu" "F.Mask" "F.Paste")
			(net "GND")
		)
		(pad "135" smd rect
			(at 0 119.000016 90)
			(size 1.8034 0.508)
			(layers "F.Cu" "F.Mask" "F.Paste")
			(net "M_J_DQ<63>")
		)
		(pad "136" smd rect
			(at 0 119.8499 90)
			(size 1.8034 0.508)
			(layers "F.Cu" "F.Mask" "F.Paste")
			(net "GND")
		)
		(pad "137" smd rect
			(at 0 120.700038 90)
			(size 1.8034 0.508)
			(layers "F.Cu" "F.Mask" "F.Paste")
			(net "M_J_DQ<59>")
		)
		(pad "138" smd rect
			(at 0 121.549922 90)
			(size 1.8034 0.508)
			(layers "F.Cu" "F.Mask" "F.Paste")
			(net "GND")
		)
		(pad "139" smd rect
			(at 0 122.40006 90)
			(size 1.8034 0.508)
			(layers "F.Cu" "F.Mask" "F.Paste")
			(net "GND")
		)
		(pad "140" smd rect
			(at 0 123.249944 90)
			(size 1.8034 0.508)
			(layers "F.Cu" "F.Mask" "F.Paste")
			(net "GND")
		)
		(pad "141" smd rect
			(at 0 124.100082 90)
			(size 1.8034 0.508)
			(layers "F.Cu" "F.Mask" "F.Paste")
			(net "SMB_DDR_GHJ_VPP_SCL")
		)
		(pad "142" smd rect
			(at 0 124.949966 90)
			(size 1.8034 0.508)
			(layers "F.Cu" "F.Mask" "F.Paste")
			(net "PVPP_GHJ")
		)
		(pad "143" smd rect
			(at 0 125.800104 90)
			(size 1.8034 0.508)
			(layers "F.Cu" "F.Mask" "F.Paste")
			(net "PVPP_GHJ")
		)
		(pad "144" smd rect
			(at 0 126.649988 90)
			(size 1.8034 0.508)
			(layers "F.Cu" "F.Mask" "F.Paste")
			(net "TP_CH_J_DIMM_J0_RFU_2")
		)
		(pad "145" smd rect
			(at 4.59994 0 90)
			(size 1.8034 0.508)
			(layers "F.Cu" "F.Mask" "F.Paste")
			(net "P12V_NVDIMM_GHJ")
		)
		(pad "146" smd rect
			(at 4.59994 0.849884 90)
			(size 1.8034 0.508)
			(layers "F.Cu" "F.Mask" "F.Paste")
			(net "M_J_VREF")
		)
		(pad "147" smd rect
			(at 4.59994 1.700022 90)
			(size 1.8034 0.508)
			(layers "F.Cu" "F.Mask" "F.Paste")
			(net "GND")
		)
		(pad "148" smd rect
			(at 4.59994 2.549906 90)
			(size 1.8034 0.508)
			(layers "F.Cu" "F.Mask" "F.Paste")
			(net "M_J_DQ<4>")
		)
		(pad "149" smd rect
			(at 4.59994 3.400044 90)
			(size 1.8034 0.508)
			(layers "F.Cu" "F.Mask" "F.Paste")
			(net "GND")
		)
		(pad "150" smd rect
			(at 4.59994 4.249928 90)
			(size 1.8034 0.508)
			(layers "F.Cu" "F.Mask" "F.Paste")
			(net "M_J_DQ<0>")
		)
		(pad "151" smd rect
			(at 4.59994 5.100066 90)
			(size 1.8034 0.508)
			(layers "F.Cu" "F.Mask" "F.Paste")
			(net "GND")
		)
		(pad "152" smd rect
			(at 4.59994 5.94995 90)
			(size 1.8034 0.508)
			(layers "F.Cu" "F.Mask" "F.Paste")
			(net "M_J_DQS_DN<0>")
		)
		(pad "153" smd rect
			(at 4.59994 6.800088 90)
			(size 1.8034 0.508)
			(layers "F.Cu" "F.Mask" "F.Paste")
			(net "M_J_DQS_DP<0>")
		)
		(pad "154" smd rect
			(at 4.59994 7.649972 90)
			(size 1.8034 0.508)
			(layers "F.Cu" "F.Mask" "F.Paste")
			(net "GND")
		)
		(pad "155" smd rect
			(at 4.59994 8.50011 90)
			(size 1.8034 0.508)
			(layers "F.Cu" "F.Mask" "F.Paste")
			(net "M_J_DQ<6>")
		)
		(pad "156" smd rect
			(at 4.59994 9.349994 90)
			(size 1.8034 0.508)
			(layers "F.Cu" "F.Mask" "F.Paste")
			(net "GND")
		)
		(pad "157" smd rect
			(at 4.59994 10.199878 90)
			(size 1.8034 0.508)
			(layers "F.Cu" "F.Mask" "F.Paste")
			(net "M_J_DQ<2>")
		)
		(pad "158" smd rect
			(at 4.59994 11.050016 90)
			(size 1.8034 0.508)
			(layers "F.Cu" "F.Mask" "F.Paste")
			(net "GND")
		)
		(pad "159" smd rect
			(at 4.59994 11.8999 90)
			(size 1.8034 0.508)
			(layers "F.Cu" "F.Mask" "F.Paste")
			(net "M_J_DQ<12>")
		)
		(pad "160" smd rect
			(at 4.59994 12.750038 90)
			(size 1.8034 0.508)
			(layers "F.Cu" "F.Mask" "F.Paste")
			(net "GND")
		)
		(pad "161" smd rect
			(at 4.59994 13.599922 90)
			(size 1.8034 0.508)
			(layers "F.Cu" "F.Mask" "F.Paste")
			(net "M_J_DQ<8>")
		)
		(pad "162" smd rect
			(at 4.59994 14.45006 90)
			(size 1.8034 0.508)
			(layers "F.Cu" "F.Mask" "F.Paste")
			(net "GND")
		)
		(pad "163" smd rect
			(at 4.59994 15.299944 90)
			(size 1.8034 0.508)
			(layers "F.Cu" "F.Mask" "F.Paste")
			(net "M_J_DQS_DN<1>")
		)
		(pad "164" smd rect
			(at 4.59994 16.150082 90)
			(size 1.8034 0.508)
			(layers "F.Cu" "F.Mask" "F.Paste")
			(net "M_J_DQS_DP<1>")
		)
		(pad "165" smd rect
			(at 4.59994 16.999966 90)
			(size 1.8034 0.508)
			(layers "F.Cu" "F.Mask" "F.Paste")
			(net "GND")
		)
		(pad "166" smd rect
			(at 4.59994 17.850104 90)
			(size 1.8034 0.508)
			(layers "F.Cu" "F.Mask" "F.Paste")
			(net "M_J_DQ<14>")
		)
		(pad "167" smd rect
			(at 4.59994 18.699988 90)
			(size 1.8034 0.508)
			(layers "F.Cu" "F.Mask" "F.Paste")
			(net "GND")
		)
		(pad "168" smd rect
			(at 4.59994 19.550126 90)
			(size 1.8034 0.508)
			(layers "F.Cu" "F.Mask" "F.Paste")
			(net "M_J_DQ<10>")
		)
		(pad "169" smd rect
			(at 4.59994 20.40001 90)
			(size 1.8034 0.508)
			(layers "F.Cu" "F.Mask" "F.Paste")
			(net "GND")
		)
		(pad "170" smd rect
			(at 4.59994 21.249894 90)
			(size 1.8034 0.508)
			(layers "F.Cu" "F.Mask" "F.Paste")
			(net "M_J_DQ<20>")
		)
		(pad "171" smd rect
			(at 4.59994 22.100032 90)
			(size 1.8034 0.508)
			(layers "F.Cu" "F.Mask" "F.Paste")
			(net "GND")
		)
		(pad "172" smd rect
			(at 4.59994 22.949916 90)
			(size 1.8034 0.508)
			(layers "F.Cu" "F.Mask" "F.Paste")
			(net "M_J_DQ<16>")
		)
		(pad "173" smd rect
			(at 4.59994 23.800054 90)
			(size 1.8034 0.508)
			(layers "F.Cu" "F.Mask" "F.Paste")
			(net "GND")
		)
		(pad "174" smd rect
			(at 4.59994 24.649938 90)
			(size 1.8034 0.508)
			(layers "F.Cu" "F.Mask" "F.Paste")
			(net "M_J_DQS_DN<2>")
		)
		(pad "175" smd rect
			(at 4.59994 25.500076 90)
			(size 1.8034 0.508)
			(layers "F.Cu" "F.Mask" "F.Paste")
			(net "M_J_DQS_DP<2>")
		)
		(pad "176" smd rect
			(at 4.59994 26.34996 90)
			(size 1.8034 0.508)
			(layers "F.Cu" "F.Mask" "F.Paste")
			(net "GND")
		)
		(pad "177" smd rect
			(at 4.59994 27.200098 90)
			(size 1.8034 0.508)
			(layers "F.Cu" "F.Mask" "F.Paste")
			(net "M_J_DQ<22>")
		)
		(pad "178" smd rect
			(at 4.59994 28.049982 90)
			(size 1.8034 0.508)
			(layers "F.Cu" "F.Mask" "F.Paste")
			(net "GND")
		)
		(pad "179" smd rect
			(at 4.59994 28.90012 90)
			(size 1.8034 0.508)
			(layers "F.Cu" "F.Mask" "F.Paste")
			(net "M_J_DQ<18>")
		)
		(pad "180" smd rect
			(at 4.59994 29.750004 90)
			(size 1.8034 0.508)
			(layers "F.Cu" "F.Mask" "F.Paste")
			(net "GND")
		)
		(pad "181" smd rect
			(at 4.59994 30.599888 90)
			(size 1.8034 0.508)
			(layers "F.Cu" "F.Mask" "F.Paste")
			(net "M_J_DQ<28>")
		)
		(pad "182" smd rect
			(at 4.59994 31.450026 90)
			(size 1.8034 0.508)
			(layers "F.Cu" "F.Mask" "F.Paste")
			(net "GND")
		)
		(pad "183" smd rect
			(at 4.59994 32.29991 90)
			(size 1.8034 0.508)
			(layers "F.Cu" "F.Mask" "F.Paste")
			(net "M_J_DQ<24>")
		)
		(pad "184" smd rect
			(at 4.59994 33.150048 90)
			(size 1.8034 0.508)
			(layers "F.Cu" "F.Mask" "F.Paste")
			(net "GND")
		)
		(pad "185" smd rect
			(at 4.59994 33.999932 90)
			(size 1.8034 0.508)
			(layers "F.Cu" "F.Mask" "F.Paste")
			(net "M_J_DQS_DN<3>")
		)
		(pad "186" smd rect
			(at 4.59994 34.85007 90)
			(size 1.8034 0.508)
			(layers "F.Cu" "F.Mask" "F.Paste")
			(net "M_J_DQS_DP<3>")
		)
		(pad "187" smd rect
			(at 4.59994 35.699954 90)
			(size 1.8034 0.508)
			(layers "F.Cu" "F.Mask" "F.Paste")
			(net "GND")
		)
		(pad "188" smd rect
			(at 4.59994 36.550092 90)
			(size 1.8034 0.508)
			(layers "F.Cu" "F.Mask" "F.Paste")
			(net "M_J_DQ<30>")
		)
		(pad "189" smd rect
			(at 4.59994 37.399976 90)
			(size 1.8034 0.508)
			(layers "F.Cu" "F.Mask" "F.Paste")
			(net "GND")
		)
		(pad "190" smd rect
			(at 4.59994 38.250114 90)
			(size 1.8034 0.508)
			(layers "F.Cu" "F.Mask" "F.Paste")
			(net "M_J_DQ<26>")
		)
		(pad "191" smd rect
			(at 4.59994 39.099998 90)
			(size 1.8034 0.508)
			(layers "F.Cu" "F.Mask" "F.Paste")
			(net "GND")
		)
		(pad "192" smd rect
			(at 4.59994 39.949882 90)
			(size 1.8034 0.508)
			(layers "F.Cu" "F.Mask" "F.Paste")
			(net "M_J_ECC<4>")
		)
		(pad "193" smd rect
			(at 4.59994 40.80002 90)
			(size 1.8034 0.508)
			(layers "F.Cu" "F.Mask" "F.Paste")
			(net "GND")
		)
		(pad "194" smd rect
			(at 4.59994 41.649904 90)
			(size 1.8034 0.508)
			(layers "F.Cu" "F.Mask" "F.Paste")
			(net "M_J_ECC<0>")
		)
		(pad "195" smd rect
			(at 4.59994 42.500042 90)
			(size 1.8034 0.508)
			(layers "F.Cu" "F.Mask" "F.Paste")
			(net "GND")
		)
		(pad "196" smd rect
			(at 4.59994 43.349926 90)
			(size 1.8034 0.508)
			(layers "F.Cu" "F.Mask" "F.Paste")
			(net "M_J_DQS_DN<8>")
		)
		(pad "197" smd rect
			(at 4.59994 44.200064 90)
			(size 1.8034 0.508)
			(layers "F.Cu" "F.Mask" "F.Paste")
			(net "M_J_DQS_DP<8>")
		)
		(pad "198" smd rect
			(at 4.59994 45.049948 90)
			(size 1.8034 0.508)
			(layers "F.Cu" "F.Mask" "F.Paste")
			(net "GND")
		)
		(pad "199" smd rect
			(at 4.59994 45.900086 90)
			(size 1.8034 0.508)
			(layers "F.Cu" "F.Mask" "F.Paste")
			(net "M_J_ECC<6>")
		)
		(pad "200" smd rect
			(at 4.59994 46.74997 90)
			(size 1.8034 0.508)
			(layers "F.Cu" "F.Mask" "F.Paste")
			(net "GND")
		)
		(pad "201" smd rect
			(at 4.59994 47.600108 90)
			(size 1.8034 0.508)
			(layers "F.Cu" "F.Mask" "F.Paste")
			(net "M_J_ECC<2>")
		)
		(pad "202" smd rect
			(at 4.59994 48.449992 90)
			(size 1.8034 0.508)
			(layers "F.Cu" "F.Mask" "F.Paste")
			(net "GND")
		)
		(pad "203" smd rect
			(at 4.59994 49.299876 90)
			(size 1.8034 0.508)
			(layers "F.Cu" "F.Mask" "F.Paste")
			(net "M_J_CKE<1>")
		)
		(pad "204" smd rect
			(at 4.59994 50.150014 90)
			(size 1.8034 0.508)
			(layers "F.Cu" "F.Mask" "F.Paste")
			(net "PVDDQ_GHJ")
		)
		(pad "205" smd rect
			(at 4.59994 50.999898 90)
			(size 1.8034 0.508)
			(layers "F.Cu" "F.Mask" "F.Paste")
			(net "TP_CH_J_DIMM_J0_RFU_0")
		)
		(pad "206" smd rect
			(at 4.59994 51.850036 90)
			(size 1.8034 0.508)
			(layers "F.Cu" "F.Mask" "F.Paste")
			(net "PVDDQ_GHJ")
		)
		(pad "207" smd rect
			(at 4.59994 52.69992 90)
			(size 1.8034 0.508)
			(layers "F.Cu" "F.Mask" "F.Paste")
			(net "M_J_BG<1>")
		)
		(pad "208" smd rect
			(at 4.59994 53.550058 90)
			(size 1.8034 0.508)
			(layers "F.Cu" "F.Mask" "F.Paste")
			(net "M_J_ALERT_N")
		)
		(pad "209" smd rect
			(at 4.59994 54.399942 90)
			(size 1.8034 0.508)
			(layers "F.Cu" "F.Mask" "F.Paste")
			(net "PVDDQ_GHJ")
		)
		(pad "210" smd rect
			(at 4.59994 55.25008 90)
			(size 1.8034 0.508)
			(layers "F.Cu" "F.Mask" "F.Paste")
			(net "M_J_MA<11>")
		)
		(pad "211" smd rect
			(at 4.59994 56.099964 90)
			(size 1.8034 0.508)
			(layers "F.Cu" "F.Mask" "F.Paste")
			(net "M_J_MA<7>")
		)
		(pad "212" smd rect
			(at 4.59994 56.950102 90)
			(size 1.8034 0.508)
			(layers "F.Cu" "F.Mask" "F.Paste")
			(net "PVDDQ_GHJ")
		)
		(pad "213" smd rect
			(at 4.59994 57.799986 90)
			(size 1.8034 0.508)
			(layers "F.Cu" "F.Mask" "F.Paste")
			(net "M_J_MA<5>")
		)
		(pad "214" smd rect
			(at 4.59994 58.650124 90)
			(size 1.8034 0.508)
			(layers "F.Cu" "F.Mask" "F.Paste")
			(net "M_J_MA<4>")
		)
		(pad "215" smd rect
			(at 4.59994 59.500008 90)
			(size 1.8034 0.508)
			(layers "F.Cu" "F.Mask" "F.Paste")
			(net "PVDDQ_GHJ")
		)
		(pad "216" smd rect
			(at 4.59994 60.349892 90)
			(size 1.8034 0.508)
			(layers "F.Cu" "F.Mask" "F.Paste")
			(net "M_J_MA<2>")
		)
		(pad "217" smd rect
			(at 4.59994 61.20003 90)
			(size 1.8034 0.508)
			(layers "F.Cu" "F.Mask" "F.Paste")
			(net "PVDDQ_GHJ")
		)
		(pad "218" smd rect
			(at 4.59994 62.049914 90)
			(size 1.8034 0.508)
			(layers "F.Cu" "F.Mask" "F.Paste")
			(net "M_J_CLK_DP<1>")
		)
		(pad "219" smd rect
			(at 4.59994 62.900052 90)
			(size 1.8034 0.508)
			(layers "F.Cu" "F.Mask" "F.Paste")
			(net "M_J_CLK_DN<1>")
		)
		(pad "220" smd rect
			(at 4.59994 63.749936 90)
			(size 1.8034 0.508)
			(layers "F.Cu" "F.Mask" "F.Paste")
			(net "PVDDQ_GHJ")
		)
		(pad "221" smd rect
			(at 4.59994 64.600074 90)
			(size 1.8034 0.508)
			(layers "F.Cu" "F.Mask" "F.Paste")
			(net "PVTT_GHJ")
		)
		(pad "222" smd rect
			(at 4.59994 70.550024 90)
			(size 1.8034 0.508)
			(layers "F.Cu" "F.Mask" "F.Paste")
			(net "M_J_PAR")
		)
		(pad "223" smd rect
			(at 4.59994 71.399908 90)
			(size 1.8034 0.508)
			(layers "F.Cu" "F.Mask" "F.Paste")
			(net "PVDDQ_GHJ")
		)
		(pad "224" smd rect
			(at 4.59994 72.250046 90)
			(size 1.8034 0.508)
			(layers "F.Cu" "F.Mask" "F.Paste")
			(net "M_J_BA<1>")
		)
		(pad "225" smd rect
			(at 4.59994 73.09993 90)
			(size 1.8034 0.508)
			(layers "F.Cu" "F.Mask" "F.Paste")
			(net "M_J_MA<10>")
		)
		(pad "226" smd rect
			(at 4.59994 73.950068 90)
			(size 1.8034 0.508)
			(layers "F.Cu" "F.Mask" "F.Paste")
			(net "PVDDQ_GHJ")
		)
		(pad "227" smd rect
			(at 4.59994 74.799952 90)
			(size 1.8034 0.508)
			(layers "F.Cu" "F.Mask" "F.Paste")
			(net "TP_CH_J_DIMM_J0_RFU_1")
		)
		(pad "228" smd rect
			(at 4.59994 75.65009 90)
			(size 1.8034 0.508)
			(layers "F.Cu" "F.Mask" "F.Paste")
			(net "M_J_MA<14>")
		)
		(pad "229" smd rect
			(at 4.59994 76.499974 90)
			(size 1.8034 0.508)
			(layers "F.Cu" "F.Mask" "F.Paste")
			(net "PVDDQ_GHJ")
		)
		(pad "230" smd rect
			(at 4.59994 77.350112 90)
			(size 1.8034 0.508)
			(layers "F.Cu" "F.Mask" "F.Paste")
			(net "FM_ADR_COMPLETE_GHJ_N")
		)
		(pad "231" smd rect
			(at 4.59994 78.199996 90)
			(size 1.8034 0.508)
			(layers "F.Cu" "F.Mask" "F.Paste")
			(net "PVDDQ_GHJ")
		)
		(pad "232" smd rect
			(at 4.59994 79.04988 90)
			(size 1.8034 0.508)
			(layers "F.Cu" "F.Mask" "F.Paste")
			(net "M_J_MA<13>")
		)
		(pad "233" smd rect
			(at 4.59994 79.900018 90)
			(size 1.8034 0.508)
			(layers "F.Cu" "F.Mask" "F.Paste")
			(net "PVDDQ_GHJ")
		)
		(pad "234" smd rect
			(at 4.59994 80.749902 90)
			(size 1.8034 0.508)
			(layers "F.Cu" "F.Mask" "F.Paste")
			(net "M_J_MA<17>")
		)
		(pad "235" smd rect
			(at 4.59994 81.60004 90)
			(size 1.8034 0.508)
			(layers "F.Cu" "F.Mask" "F.Paste")
			(net "M_J_C<2>")
		)
		(pad "236" smd rect
			(at 4.59994 82.449924 90)
			(size 1.8034 0.508)
			(layers "F.Cu" "F.Mask" "F.Paste")
			(net "PVDDQ_GHJ")
		)
		(pad "237" smd rect
			(at 4.59994 83.300062 90)
			(size 1.8034 0.508)
			(layers "F.Cu" "F.Mask" "F.Paste")
			(net "M_J_CS_N<3>")
		)
		(pad "238" smd rect
			(at 4.59994 84.149946 90)
			(size 1.8034 0.508)
			(layers "F.Cu" "F.Mask" "F.Paste")
			(net "PVPP_GHJ")
		)
		(pad "239" smd rect
			(at 4.59994 85.000084 90)
			(size 1.8034 0.508)
			(layers "F.Cu" "F.Mask" "F.Paste")
			(net "GND")
		)
		(pad "240" smd rect
			(at 4.59994 85.849968 90)
			(size 1.8034 0.508)
			(layers "F.Cu" "F.Mask" "F.Paste")
			(net "M_J_DQ<36>")
		)
		(pad "241" smd rect
			(at 4.59994 86.700106 90)
			(size 1.8034 0.508)
			(layers "F.Cu" "F.Mask" "F.Paste")
			(net "GND")
		)
		(pad "242" smd rect
			(at 4.59994 87.54999 90)
			(size 1.8034 0.508)
			(layers "F.Cu" "F.Mask" "F.Paste")
			(net "M_J_DQ<32>")
		)
		(pad "243" smd rect
			(at 4.59994 88.399874 90)
			(size 1.8034 0.508)
			(layers "F.Cu" "F.Mask" "F.Paste")
			(net "GND")
		)
		(pad "244" smd rect
			(at 4.59994 89.250012 90)
			(size 1.8034 0.508)
			(layers "F.Cu" "F.Mask" "F.Paste")
			(net "M_J_DQS_DN<4>")
		)
		(pad "245" smd rect
			(at 4.59994 90.099896 90)
			(size 1.8034 0.508)
			(layers "F.Cu" "F.Mask" "F.Paste")
			(net "M_J_DQS_DP<4>")
		)
		(pad "246" smd rect
			(at 4.59994 90.950034 90)
			(size 1.8034 0.508)
			(layers "F.Cu" "F.Mask" "F.Paste")
			(net "GND")
		)
		(pad "247" smd rect
			(at 4.59994 91.799918 90)
			(size 1.8034 0.508)
			(layers "F.Cu" "F.Mask" "F.Paste")
			(net "M_J_DQ<38>")
		)
		(pad "248" smd rect
			(at 4.59994 92.650056 90)
			(size 1.8034 0.508)
			(layers "F.Cu" "F.Mask" "F.Paste")
			(net "GND")
		)
		(pad "249" smd rect
			(at 4.59994 93.49994 90)
			(size 1.8034 0.508)
			(layers "F.Cu" "F.Mask" "F.Paste")
			(net "M_J_DQ<34>")
		)
		(pad "250" smd rect
			(at 4.59994 94.350078 90)
			(size 1.8034 0.508)
			(layers "F.Cu" "F.Mask" "F.Paste")
			(net "GND")
		)
		(pad "251" smd rect
			(at 4.59994 95.199962 90)
			(size 1.8034 0.508)
			(layers "F.Cu" "F.Mask" "F.Paste")
			(net "M_J_DQ<44>")
		)
		(pad "252" smd rect
			(at 4.59994 96.0501 90)
			(size 1.8034 0.508)
			(layers "F.Cu" "F.Mask" "F.Paste")
			(net "GND")
		)
		(pad "253" smd rect
			(at 4.59994 96.899984 90)
			(size 1.8034 0.508)
			(layers "F.Cu" "F.Mask" "F.Paste")
			(net "M_J_DQ<40>")
		)
		(pad "254" smd rect
			(at 4.59994 97.750122 90)
			(size 1.8034 0.508)
			(layers "F.Cu" "F.Mask" "F.Paste")
			(net "GND")
		)
		(pad "255" smd rect
			(at 4.59994 98.600006 90)
			(size 1.8034 0.508)
			(layers "F.Cu" "F.Mask" "F.Paste")
			(net "M_J_DQS_DN<5>")
		)
		(pad "256" smd rect
			(at 4.59994 99.44989 90)
			(size 1.8034 0.508)
			(layers "F.Cu" "F.Mask" "F.Paste")
			(net "M_J_DQS_DP<5>")
		)
		(pad "257" smd rect
			(at 4.59994 100.300028 90)
			(size 1.8034 0.508)
			(layers "F.Cu" "F.Mask" "F.Paste")
			(net "GND")
		)
		(pad "258" smd rect
			(at 4.59994 101.149912 90)
			(size 1.8034 0.508)
			(layers "F.Cu" "F.Mask" "F.Paste")
			(net "M_J_DQ<46>")
		)
		(pad "259" smd rect
			(at 4.59994 102.00005 90)
			(size 1.8034 0.508)
			(layers "F.Cu" "F.Mask" "F.Paste")
			(net "GND")
		)
		(pad "260" smd rect
			(at 4.59994 102.849934 90)
			(size 1.8034 0.508)
			(layers "F.Cu" "F.Mask" "F.Paste")
			(net "M_J_DQ<42>")
		)
		(pad "261" smd rect
			(at 4.59994 103.700072 90)
			(size 1.8034 0.508)
			(layers "F.Cu" "F.Mask" "F.Paste")
			(net "GND")
		)
		(pad "262" smd rect
			(at 4.59994 104.549956 90)
			(size 1.8034 0.508)
			(layers "F.Cu" "F.Mask" "F.Paste")
			(net "M_J_DQ<52>")
		)
		(pad "263" smd rect
			(at 4.59994 105.400094 90)
			(size 1.8034 0.508)
			(layers "F.Cu" "F.Mask" "F.Paste")
			(net "GND")
		)
		(pad "264" smd rect
			(at 4.59994 106.249978 90)
			(size 1.8034 0.508)
			(layers "F.Cu" "F.Mask" "F.Paste")
			(net "M_J_DQ<48>")
		)
		(pad "265" smd rect
			(at 4.59994 107.100116 90)
			(size 1.8034 0.508)
			(layers "F.Cu" "F.Mask" "F.Paste")
			(net "GND")
		)
		(pad "266" smd rect
			(at 4.59994 107.95 90)
			(size 1.8034 0.508)
			(layers "F.Cu" "F.Mask" "F.Paste")
			(net "M_J_DQS_DN<6>")
		)
		(pad "267" smd rect
			(at 4.59994 108.799884 90)
			(size 1.8034 0.508)
			(layers "F.Cu" "F.Mask" "F.Paste")
			(net "M_J_DQS_DP<6>")
		)
		(pad "268" smd rect
			(at 4.59994 109.650022 90)
			(size 1.8034 0.508)
			(layers "F.Cu" "F.Mask" "F.Paste")
			(net "GND")
		)
		(pad "269" smd rect
			(at 4.59994 110.499906 90)
			(size 1.8034 0.508)
			(layers "F.Cu" "F.Mask" "F.Paste")
			(net "M_J_DQ<54>")
		)
		(pad "270" smd rect
			(at 4.59994 111.350044 90)
			(size 1.8034 0.508)
			(layers "F.Cu" "F.Mask" "F.Paste")
			(net "GND")
		)
		(pad "271" smd rect
			(at 4.59994 112.199928 90)
			(size 1.8034 0.508)
			(layers "F.Cu" "F.Mask" "F.Paste")
			(net "M_J_DQ<50>")
		)
		(pad "272" smd rect
			(at 4.59994 113.050066 90)
			(size 1.8034 0.508)
			(layers "F.Cu" "F.Mask" "F.Paste")
			(net "GND")
		)
		(pad "273" smd rect
			(at 4.59994 113.89995 90)
			(size 1.8034 0.508)
			(layers "F.Cu" "F.Mask" "F.Paste")
			(net "M_J_DQ<60>")
		)
		(pad "274" smd rect
			(at 4.59994 114.750088 90)
			(size 1.8034 0.508)
			(layers "F.Cu" "F.Mask" "F.Paste")
			(net "GND")
		)
		(pad "275" smd rect
			(at 4.59994 115.599972 90)
			(size 1.8034 0.508)
			(layers "F.Cu" "F.Mask" "F.Paste")
			(net "M_J_DQ<56>")
		)
		(pad "276" smd rect
			(at 4.59994 116.45011 90)
			(size 1.8034 0.508)
			(layers "F.Cu" "F.Mask" "F.Paste")
			(net "GND")
		)
		(pad "277" smd rect
			(at 4.59994 117.299994 90)
			(size 1.8034 0.508)
			(layers "F.Cu" "F.Mask" "F.Paste")
			(net "M_J_DQS_DN<7>")
		)
		(pad "278" smd rect
			(at 4.59994 118.149878 90)
			(size 1.8034 0.508)
			(layers "F.Cu" "F.Mask" "F.Paste")
			(net "M_J_DQS_DP<7>")
		)
		(pad "279" smd rect
			(at 4.59994 119.000016 90)
			(size 1.8034 0.508)
			(layers "F.Cu" "F.Mask" "F.Paste")
			(net "GND")
		)
		(pad "280" smd rect
			(at 4.59994 119.8499 90)
			(size 1.8034 0.508)
			(layers "F.Cu" "F.Mask" "F.Paste")
			(net "M_J_DQ<62>")
		)
		(pad "281" smd rect
			(at 4.59994 120.700038 90)
			(size 1.8034 0.508)
			(layers "F.Cu" "F.Mask" "F.Paste")
			(net "GND")
		)
		(pad "282" smd rect
			(at 4.59994 121.549922 90)
			(size 1.8034 0.508)
			(layers "F.Cu" "F.Mask" "F.Paste")
			(net "M_J_DQ<58>")
		)
		(pad "283" smd rect
			(at 4.59994 122.40006 90)
			(size 1.8034 0.508)
			(layers "F.Cu" "F.Mask" "F.Paste")
			(net "GND")
		)
		(pad "284" smd rect
			(at 4.59994 123.249944 90)
			(size 1.8034 0.508)
			(layers "F.Cu" "F.Mask" "F.Paste")
			(net "PVPP_GHJ")
		)
		(pad "285" smd rect
			(at 4.59994 124.100082 90)
			(size 1.8034 0.508)
			(layers "F.Cu" "F.Mask" "F.Paste")
			(net "SMB_DDR_GHJ_VPP_SDA")
		)
		(pad "286" smd rect
			(at 4.59994 124.949966 90)
			(size 1.8034 0.508)
			(layers "F.Cu" "F.Mask" "F.Paste")
			(net "PVPP_GHJ")
		)
		(pad "287" smd rect
			(at 4.59994 125.800104 90)
			(size 1.8034 0.508)
			(layers "F.Cu" "F.Mask" "F.Paste")
			(net "PVPP_GHJ")
		)
		(pad "288" smd rect
			(at 4.59994 126.649988 90)
			(size 1.8034 0.508)
			(layers "F.Cu" "F.Mask" "F.Paste")
			(net "PVPP_GHJ")
		)
	)
	(footprint ""
		(layer "F.Cu")
		(at 487.6292 -50.6857)
		(property "Reference" "R9E2"
			(at 0 0 0)
			(layer "F.SilkS")
			(hide yes)
			(effects
				(font
					(size 1.27 1.27)
				)
			)
		)
		(property "Value" ""
			(at 0 0 0)
			(layer "F.Fab")
			(effects
				(font
					(size 1.27 1.27)
				)
			)
		)
		(duplicate_pad_numbers_are_jumpers no)
		(fp_poly
			(pts
				(xy -0.2794 -0.1016) (xy 0.2794 -0.1016) (xy 0.2794 0.9906) (xy -0.2794 0.9906)
			)
			(stroke
				(width 0)
				(type default)
			)
			(fill no)
			(layer "F.CrtYd")
		)
		(fp_line
			(start -0.2794 -0.1016)
			(end -0.2794 0.9906)
			(stroke
				(width 0.1)
				(type default)
			)
			(layer "F.Fab")
		)
		(fp_line
			(start -0.2794 0.9906)
			(end 0.2794 0.9906)
			(stroke
				(width 0.1)
				(type default)
			)
			(layer "F.Fab")
		)
		(fp_line
			(start 0.2794 -0.1016)
			(end -0.2794 -0.1016)
			(stroke
				(width 0.1)
				(type default)
			)
			(layer "F.Fab")
		)
		(fp_line
			(start 0.2794 0.9906)
			(end 0.2794 -0.1016)
			(stroke
				(width 0.1)
				(type default)
			)
			(layer "F.Fab")
		)
		(pad "1" smd rect
			(at 0 0)
			(size 0.508 0.508)
			(layers "F.Cu" "F.Mask" "F.Paste")
			(net "P3V3_STBY")
		)
		(pad "2" smd rect
			(at 0 0.889)
			(size 0.508 0.508)
			(layers "F.Cu" "F.Mask" "F.Paste")
			(net "PU_JTAG_SPRV_TCK")
		)
		(zone
			(layer "F.Cu")
			(hatch none 0.5)
			(connect_pads
				(clearance 0)
			)
			(min_thickness 0.25)
			(keepout
				(tracks allowed)
				(vias not_allowed)
				(pads allowed)
				(copperpour not_allowed)
				(footprints allowed)
			)
			(placement
				(enabled no)
				(sheetname "")
			)
			(fill
				(thermal_gap 0.5)
				(thermal_bridge_width 0.5)
				(island_removal_mode 0)
			)
			(polygon
				(pts
					(xy 487.3752 -50.4317) (xy 487.8832 -50.4317) (xy 487.8832 -50.0507) (xy 487.3752 -50.0507)
				)
			)
		)
		(zone
			(layer "F.Cu")
			(hatch none 0.5)
			(connect_pads
				(clearance 0)
			)
			(min_thickness 0.25)
			(keepout
				(tracks not_allowed)
				(vias allowed)
				(pads allowed)
				(copperpour not_allowed)
				(footprints allowed)
			)
			(placement
				(enabled no)
				(sheetname "")
			)
			(fill
				(thermal_gap 0.5)
				(thermal_bridge_width 0.5)
				(island_removal_mode 0)
			)
			(polygon
				(pts
					(xy 487.3752 -50.0507) (xy 487.8832 -50.0507) (xy 487.8832 -50.4317) (xy 487.3752 -50.4317)
				)
			)
		)
	)
	(footprint ""
		(layer "F.Cu")
		(at 15.113 -101.981)
		(property "Reference" "R1C11"
			(at 0 0 0)
			(layer "F.SilkS")
			(hide yes)
			(effects
				(font
					(size 1.27 1.27)
				)
			)
		)
		(property "Value" ""
			(at 0 0 0)
			(layer "F.Fab")
			(effects
				(font
					(size 1.27 1.27)
				)
			)
		)
		(duplicate_pad_numbers_are_jumpers no)
		(fp_poly
			(pts
				(xy -0.2794 -0.1016) (xy 0.2794 -0.1016) (xy 0.2794 0.9906) (xy -0.2794 0.9906)
			)
			(stroke
				(width 0)
				(type default)
			)
			(fill no)
			(layer "F.CrtYd")
		)
		(fp_line
			(start -0.2794 -0.1016)
			(end -0.2794 0.9906)
			(stroke
				(width 0.1)
				(type default)
			)
			(layer "F.Fab")
		)
		(fp_line
			(start -0.2794 0.9906)
			(end 0.2794 0.9906)
			(stroke
				(width 0.1)
				(type default)
			)
			(layer "F.Fab")
		)
		(fp_line
			(start 0.2794 -0.1016)
			(end -0.2794 -0.1016)
			(stroke
				(width 0.1)
				(type default)
			)
			(layer "F.Fab")
		)
		(fp_line
			(start 0.2794 0.9906)
			(end 0.2794 -0.1016)
			(stroke
				(width 0.1)
				(type default)
			)
			(layer "F.Fab")
		)
		(pad "1" smd rect
			(at 0 0)
			(size 0.508 0.508)
			(layers "F.Cu" "F.Mask" "F.Paste")
			(net "SMB_LAN_STBY_LVC3_SCL")
		)
		(pad "2" smd rect
			(at 0 0.889)
			(size 0.508 0.508)
			(layers "F.Cu" "F.Mask" "F.Paste")
			(net "FAN_TACH1_R")
		)
		(zone
			(layer "F.Cu")
			(hatch none 0.5)
			(connect_pads
				(clearance 0)
			)
			(min_thickness 0.25)
			(keepout
				(tracks allowed)
				(vias not_allowed)
				(pads allowed)
				(copperpour not_allowed)
				(footprints allowed)
			)
			(placement
				(enabled no)
				(sheetname "")
			)
			(fill
				(thermal_gap 0.5)
				(thermal_bridge_width 0.5)
				(island_removal_mode 0)
			)
			(polygon
				(pts
					(xy 14.859 -101.727) (xy 15.367 -101.727) (xy 15.367 -101.346) (xy 14.859 -101.346)
				)
			)
		)
		(zone
			(layer "F.Cu")
			(hatch none 0.5)
			(connect_pads
				(clearance 0)
			)
			(min_thickness 0.25)
			(keepout
				(tracks not_allowed)
				(vias allowed)
				(pads allowed)
				(copperpour not_allowed)
				(footprints allowed)
			)
			(placement
				(enabled no)
				(sheetname "")
			)
			(fill
				(thermal_gap 0.5)
				(thermal_bridge_width 0.5)
				(island_removal_mode 0)
			)
			(polygon
				(pts
					(xy 14.859 -101.346) (xy 15.367 -101.346) (xy 15.367 -101.727) (xy 14.859 -101.727)
				)
			)
		)
	)
	(footprint ""
		(layer "F.Cu")
		(at 322.27647 -128.38176 180)
		(property "Reference" "R6B3"
			(at 0 0 180)
			(layer "F.SilkS")
			(hide yes)
			(effects
				(font
					(size 1.27 1.27)
				)
			)
		)
		(property "Value" ""
			(at 0 0 180)
			(layer "F.Fab")
			(effects
				(font
					(size 1.27 1.27)
				)
			)
		)
		(duplicate_pad_numbers_are_jumpers no)
		(fp_poly
			(pts
				(xy -0.2794 -0.1016) (xy 0.2794 -0.1016) (xy 0.2794 0.9906) (xy -0.2794 0.9906)
			)
			(stroke
				(width 0)
				(type default)
			)
			(fill no)
			(layer "F.CrtYd")
		)
		(fp_line
			(start 0.2794 0.9906)
			(end 0.2794 -0.1016)
			(stroke
				(width 0.1)
				(type default)
			)
			(layer "F.Fab")
		)
		(fp_line
			(start 0.2794 -0.1016)
			(end -0.2794 -0.1016)
			(stroke
				(width 0.1)
				(type default)
			)
			(layer "F.Fab")
		)
		(fp_line
			(start -0.2794 0.9906)
			(end 0.2794 0.9906)
			(stroke
				(width 0.1)
				(type default)
			)
			(layer "F.Fab")
		)
		(fp_line
			(start -0.2794 -0.1016)
			(end -0.2794 0.9906)
			(stroke
				(width 0.1)
				(type default)
			)
			(layer "F.Fab")
		)
		(pad "1" smd rect
			(at 0 0 180)
			(size 0.508 0.508)
			(layers "F.Cu" "F.Mask" "F.Paste")
			(net "SVID_ALERT1_CPU0_N")
		)
		(pad "2" smd rect
			(at 0 0.889 180)
			(size 0.508 0.508)
			(layers "F.Cu" "F.Mask" "F.Paste")
			(net "SVID_ALERT1_CPU0_R_N")
		)
		(zone
			(layer "F.Cu")
			(hatch none 0.5)
			(connect_pads
				(clearance 0)
			)
			(min_thickness 0.25)
			(keepout
				(tracks not_allowed)
				(vias allowed)
				(pads allowed)
				(copperpour not_allowed)
				(footprints allowed)
			)
			(placement
				(enabled no)
				(sheetname "")
			)
			(fill
				(thermal_gap 0.5)
				(thermal_bridge_width 0.5)
				(island_removal_mode 0)
			)
			(polygon
				(pts
					(xy 322.53047 -129.01676) (xy 322.02247 -129.01676) (xy 322.02247 -128.63576) (xy 322.53047 -128.63576)
				)
			)
		)
		(zone
			(layer "F.Cu")
			(hatch none 0.5)
			(connect_pads
				(clearance 0)
			)
			(min_thickness 0.25)
			(keepout
				(tracks allowed)
				(vias not_allowed)
				(pads allowed)
				(copperpour not_allowed)
				(footprints allowed)
			)
			(placement
				(enabled no)
				(sheetname "")
			)
			(fill
				(thermal_gap 0.5)
				(thermal_bridge_width 0.5)
				(island_removal_mode 0)
			)
			(polygon
				(pts
					(xy 322.53047 -128.63576) (xy 322.02247 -128.63576) (xy 322.02247 -129.01676) (xy 322.53047 -129.01676)
				)
			)
		)
	)
	(footprint ""
		(layer "F.Cu")
		(at 13.8938 -31.242 90)
		(property "Reference" "C1F10"
			(at 0 0 90)
			(layer "F.SilkS")
			(hide yes)
			(effects
				(font
					(size 1.27 1.27)
				)
			)
		)
		(property "Value" ""
			(at 0 0 90)
			(layer "F.Fab")
			(effects
				(font
					(size 1.27 1.27)
				)
			)
		)
		(duplicate_pad_numbers_are_jumpers no)
		(fp_rect
			(start -0.3048 -0.1016)
			(end 0.3048 0.9906)
			(stroke
				(width 0)
				(type default)
			)
			(fill no)
			(layer "F.CrtYd")
		)
		(fp_line
			(start 0.3048 -0.1016)
			(end -0.3048 -0.1016)
			(stroke
				(width 0.1)
				(type default)
			)
			(layer "F.Fab")
		)
		(fp_line
			(start -0.3048 -0.1016)
			(end -0.3048 0.9906)
			(stroke
				(width 0.1)
				(type default)
			)
			(layer "F.Fab")
		)
		(fp_line
			(start 0.3048 0.9906)
			(end 0.3048 -0.1016)
			(stroke
				(width 0.1)
				(type default)
			)
			(layer "F.Fab")
		)
		(fp_line
			(start -0.3048 0.9906)
			(end 0.3048 0.9906)
			(stroke
				(width 0.1)
				(type default)
			)
			(layer "F.Fab")
		)
		(pad "1" smd rect
			(at 0 0 90)
			(size 0.508 0.508)
			(layers "F.Cu" "F.Mask" "F.Paste")
			(net "P3E_CPU1_PE3_MP_C_TXN<4>")
		)
		(pad "2" smd rect
			(at 0 0.889 90)
			(size 0.508 0.508)
			(layers "F.Cu" "F.Mask" "F.Paste")
			(net "P3E_CPU1_PE3_MP_TXN<4>")
		)
		(zone
			(layer "F.Cu")
			(hatch none 0.5)
			(connect_pads
				(clearance 0)
			)
			(min_thickness 0.25)
			(keepout
				(tracks not_allowed)
				(vias allowed)
				(pads allowed)
				(copperpour not_allowed)
				(footprints allowed)
			)
			(placement
				(enabled no)
				(sheetname "")
			)
			(fill
				(thermal_gap 0.5)
				(thermal_bridge_width 0.5)
				(island_removal_mode 0)
			)
			(polygon
				(pts
					(xy 14.1478 -30.988) (xy 14.5288 -30.988) (xy 14.5288 -31.496) (xy 14.1478 -31.496)
				)
			)
		)
		(zone
			(layer "F.Cu")
			(hatch none 0.5)
			(connect_pads
				(clearance 0)
			)
			(min_thickness 0.25)
			(keepout
				(tracks allowed)
				(vias not_allowed)
				(pads allowed)
				(copperpour not_allowed)
				(footprints allowed)
			)
			(placement
				(enabled no)
				(sheetname "")
			)
			(fill
				(thermal_gap 0.5)
				(thermal_bridge_width 0.5)
				(island_removal_mode 0)
			)
			(polygon
				(pts
					(xy 14.1478 -30.988) (xy 14.5288 -30.988) (xy 14.5288 -31.496) (xy 14.1478 -31.496)
				)
			)
		)
	)
	(footprint ""
		(layer "F.Cu")
		(at 430.9491 -26.797)
		(property "Reference" "R1T24"
			(at 0 0 0)
			(layer "F.SilkS")
			(hide yes)
			(effects
				(font
					(size 1.27 1.27)
				)
			)
		)
		(property "Value" ""
			(at 0 0 0)
			(layer "F.Fab")
			(effects
				(font
					(size 1.27 1.27)
				)
			)
		)
		(duplicate_pad_numbers_are_jumpers no)
		(fp_poly
			(pts
				(xy -0.2794 -0.1016) (xy 0.2794 -0.1016) (xy 0.2794 0.9906) (xy -0.2794 0.9906)
			)
			(stroke
				(width 0)
				(type default)
			)
			(fill no)
			(layer "F.CrtYd")
		)
		(fp_line
			(start -0.2794 -0.1016)
			(end -0.2794 0.9906)
			(stroke
				(width 0.1)
				(type default)
			)
			(layer "F.Fab")
		)
		(fp_line
			(start -0.2794 0.9906)
			(end 0.2794 0.9906)
			(stroke
				(width 0.1)
				(type default)
			)
			(layer "F.Fab")
		)
		(fp_line
			(start 0.2794 -0.1016)
			(end -0.2794 -0.1016)
			(stroke
				(width 0.1)
				(type default)
			)
			(layer "F.Fab")
		)
		(fp_line
			(start 0.2794 0.9906)
			(end 0.2794 -0.1016)
			(stroke
				(width 0.1)
				(type default)
			)
			(layer "F.Fab")
		)
		(pad "1" smd rect
			(at 0 0)
			(size 0.508 0.508)
			(layers "F.Cu" "F.Mask" "F.Paste")
			(net "PUMP_TACH0")
		)
		(pad "2" smd rect
			(at 0 0.889)
			(size 0.508 0.508)
			(layers "F.Cu" "F.Mask" "F.Paste")
			(net "FM_FLASH_DESC_OVERRIDE")
		)
		(zone
			(layer "F.Cu")
			(hatch none 0.5)
			(connect_pads
				(clearance 0)
			)
			(min_thickness 0.25)
			(keepout
				(tracks allowed)
				(vias not_allowed)
				(pads allowed)
				(copperpour not_allowed)
				(footprints allowed)
			)
			(placement
				(enabled no)
				(sheetname "")
			)
			(fill
				(thermal_gap 0.5)
				(thermal_bridge_width 0.5)
				(island_removal_mode 0)
			)
			(polygon
				(pts
					(xy 430.6951 -26.543) (xy 431.2031 -26.543) (xy 431.2031 -26.162) (xy 430.6951 -26.162)
				)
			)
		)
		(zone
			(layer "F.Cu")
			(hatch none 0.5)
			(connect_pads
				(clearance 0)
			)
			(min_thickness 0.25)
			(keepout
				(tracks not_allowed)
				(vias allowed)
				(pads allowed)
				(copperpour not_allowed)
				(footprints allowed)
			)
			(placement
				(enabled no)
				(sheetname "")
			)
			(fill
				(thermal_gap 0.5)
				(thermal_bridge_width 0.5)
				(island_removal_mode 0)
			)
			(polygon
				(pts
					(xy 430.6951 -26.162) (xy 431.2031 -26.162) (xy 431.2031 -26.543) (xy 430.6951 -26.543)
				)
			)
		)
	)
	(footprint ""
		(layer "F.Cu")
		(at 404.927054 -98.441764)
		(property "Reference" "C8C2"
			(at 0 0 0)
			(layer "F.SilkS")
			(hide yes)
			(effects
				(font
					(size 1.27 1.27)
				)
			)
		)
		(property "Value" ""
			(at 0 0 0)
			(layer "F.Fab")
			(effects
				(font
					(size 1.27 1.27)
				)
			)
		)
		(duplicate_pad_numbers_are_jumpers no)
		(fp_poly
			(pts
				(xy 0.3048 -0.1016) (xy 0.3048 0.9906) (xy -0.3048 0.9906) (xy -0.3048 -0.1016)
			)
			(stroke
				(width 0)
				(type default)
			)
			(fill no)
			(layer "F.CrtYd")
		)
		(fp_line
			(start -0.3048 -0.1016)
			(end -0.3048 0.9906)
			(stroke
				(width 0.1)
				(type default)
			)
			(layer "F.Fab")
		)
		(fp_line
			(start -0.3048 0.9906)
			(end 0.3048 0.9906)
			(stroke
				(width 0.1)
				(type default)
			)
			(layer "F.Fab")
		)
		(fp_line
			(start 0.3048 -0.1016)
			(end -0.3048 -0.1016)
			(stroke
				(width 0.1)
				(type default)
			)
			(layer "F.Fab")
		)
		(fp_line
			(start 0.3048 0.9906)
			(end 0.3048 -0.1016)
			(stroke
				(width 0.1)
				(type default)
			)
			(layer "F.Fab")
		)
		(pad "1" smd rect
			(at 0 0)
			(size 0.508 0.508)
			(layers "F.Cu" "F.Mask" "F.Paste")
			(net "XTAL_KR_25M_OUT")
		)
		(pad "2" smd rect
			(at 0 0.889)
			(size 0.508 0.508)
			(layers "F.Cu" "F.Mask" "F.Paste")
			(net "GND")
		)
		(zone
			(layer "F.Cu")
			(hatch none 0.5)
			(connect_pads
				(clearance 0)
			)
			(min_thickness 0.25)
			(keepout
				(tracks allowed)
				(vias not_allowed)
				(pads allowed)
				(copperpour not_allowed)
				(footprints allowed)
			)
			(placement
				(enabled no)
				(sheetname "")
			)
			(fill
				(thermal_gap 0.5)
				(thermal_bridge_width 0.5)
				(island_removal_mode 0)
			)
			(polygon
				(pts
					(xy 404.673054 -98.187764) (xy 405.181054 -98.187764) (xy 405.181054 -97.806764) (xy 404.673054 -97.806764)
				)
			)
		)
		(zone
			(layer "F.Cu")
			(hatch none 0.5)
			(connect_pads
				(clearance 0)
			)
			(min_thickness 0.25)
			(keepout
				(tracks not_allowed)
				(vias allowed)
				(pads allowed)
				(copperpour not_allowed)
				(footprints allowed)
			)
			(placement
				(enabled no)
				(sheetname "")
			)
			(fill
				(thermal_gap 0.5)
				(thermal_bridge_width 0.5)
				(island_removal_mode 0)
			)
			(polygon
				(pts
					(xy 404.673054 -97.806764) (xy 405.181054 -97.806764) (xy 405.181054 -98.187764) (xy 404.673054 -98.187764)
				)
			)
		)
	)
	(footprint ""
		(layer "F.Cu")
		(at 412.3944 -50.18532 90)
		(property "Reference" "R25W62"
			(at -0.8382 -0.67818 90)
			(unlocked yes)
			(layer "F.SilkS")
			(effects
				(font
					(size 0.4064 0.254)
					(thickness 0.1524)
				)
				(justify left)
			)
		)
		(property "Value" ""
			(at 0 0 90)
			(layer "F.Fab")
			(effects
				(font
					(size 1.27 1.27)
				)
			)
		)
		(duplicate_pad_numbers_are_jumpers no)
		(fp_poly
			(pts
				(xy -0.2794 -0.1016) (xy 0.2794 -0.1016) (xy 0.2794 0.9906) (xy -0.2794 0.9906)
			)
			(stroke
				(width 0)
				(type default)
			)
			(fill no)
			(layer "F.CrtYd")
		)
		(fp_line
			(start 0.2794 -0.1016)
			(end -0.2794 -0.1016)
			(stroke
				(width 0.1)
				(type default)
			)
			(layer "F.Fab")
		)
		(fp_line
			(start -0.2794 -0.1016)
			(end -0.2794 0.9906)
			(stroke
				(width 0.1)
				(type default)
			)
			(layer "F.Fab")
		)
		(fp_line
			(start 0.2794 0.9906)
			(end 0.2794 -0.1016)
			(stroke
				(width 0.1)
				(type default)
			)
			(layer "F.Fab")
		)
		(fp_line
			(start -0.2794 0.9906)
			(end 0.2794 0.9906)
			(stroke
				(width 0.1)
				(type default)
			)
			(layer "F.Fab")
		)
		(pad "1" smd rect
			(at 0 0 90)
			(size 0.508 0.508)
			(layers "F.Cu" "F.Mask" "F.Paste")
			(net "RST_PLTRST_BUF_N_R")
		)
		(pad "2" smd rect
			(at 0 0.889 90)
			(size 0.508 0.508)
			(layers "F.Cu" "F.Mask" "F.Paste")
			(net "GND")
		)
		(zone
			(layer "F.Cu")
			(hatch none 0.5)
			(connect_pads
				(clearance 0)
			)
			(min_thickness 0.25)
			(keepout
				(tracks allowed)
				(vias not_allowed)
				(pads allowed)
				(copperpour not_allowed)
				(footprints allowed)
			)
			(placement
				(enabled no)
				(sheetname "")
			)
			(fill
				(thermal_gap 0.5)
				(thermal_bridge_width 0.5)
				(island_removal_mode 0)
			)
			(polygon
				(pts
					(xy 412.6484 -49.93132) (xy 412.6484 -50.43932) (xy 413.0294 -50.43932) (xy 413.0294 -49.93132)
				)
			)
		)
		(zone
			(layer "F.Cu")
			(hatch none 0.5)
			(connect_pads
				(clearance 0)
			)
			(min_thickness 0.25)
			(keepout
				(tracks not_allowed)
				(vias allowed)
				(pads allowed)
				(copperpour not_allowed)
				(footprints allowed)
			)
			(placement
				(enabled no)
				(sheetname "")
			)
			(fill
				(thermal_gap 0.5)
				(thermal_bridge_width 0.5)
				(island_removal_mode 0)
			)
			(polygon
				(pts
					(xy 413.0294 -49.93132) (xy 413.0294 -50.43932) (xy 412.6484 -50.43932) (xy 412.6484 -49.93132)
				)
			)
		)
	)
	(footprint ""
		(layer "F.Cu")
		(at 362.523532 12.003278 -90)
		(property "Reference" "T1P23"
			(at 0 0 270)
			(layer "F.SilkS")
			(hide yes)
			(effects
				(font
					(size 1.27 1.27)
				)
			)
		)
		(property "Value" "*"
			(at -3.302 1.12395 270)
			(unlocked yes)
			(layer "F.Fab")
			(hide yes)
			(effects
				(font
					(size 0.889 0.889)
					(thickness 0.1524)
				)
			)
		)
		(property "Device Type" "TPAD-DIFF-4P-GP_DISCRET-GB3-TPA"
			(at -3.302 -0.40005 270)
			(unlocked yes)
			(layer "F.Fab")
			(hide yes)
			(effects
				(font
					(size 0.889 0.889)
					(thickness 0.1524)
				)
			)
		)
		(duplicate_pad_numbers_are_jumpers no)
		(fp_line
			(start -2.286 2.286)
			(end 2.286 2.286)
			(stroke
				(width 0.1524)
				(type default)
			)
			(layer "F.SilkS")
		)
		(fp_line
			(start 2.286 2.286)
			(end 2.286 -2.286)
			(stroke
				(width 0.1524)
				(type default)
			)
			(layer "F.SilkS")
		)
		(fp_line
			(start -2.286 -2.286)
			(end -2.286 2.286)
			(stroke
				(width 0.1524)
				(type default)
			)
			(layer "F.SilkS")
		)
		(fp_line
			(start 2.286 -2.286)
			(end -2.286 -2.286)
			(stroke
				(width 0.1524)
				(type default)
			)
			(layer "F.SilkS")
		)
		(fp_line
			(start -2.413 -2.413)
			(end -2.413 -1.143)
			(stroke
				(width 0.4064)
				(type default)
			)
			(layer "F.SilkS")
		)
		(fp_line
			(start -1.143 -2.413)
			(end -2.413 -2.413)
			(stroke
				(width 0.4064)
				(type default)
			)
			(layer "F.SilkS")
		)
		(fp_rect
			(start -2.54 2.54)
			(end 2.54 -2.54)
			(stroke
				(width 0)
				(type default)
			)
			(fill no)
			(layer "F.CrtYd")
		)
		(fp_rect
			(start -2.54 2.54)
			(end 2.54 -2.54)
			(stroke
				(width 0)
				(type default)
			)
			(fill no)
			(layer "F.Fab")
		)
		(pad "1" thru_hole circle
			(at -1.27 -1.27 270)
			(size 1.524 1.524)
			(drill 0.9144)
			(layers "*.Cu" "*.Mask")
			(remove_unused_layers no)
			(net "L12_100OHM_6INCH_DP")
			(clearance -0.0508)
			(thermal_gap 0.127)
			(padstack
				(mode front_inner_back)
				(layer "Inner"
					(shape circle)
					(size 1.1684 1.1684)
					(clearance 0.127)
				)
				(layer "B.Cu"
					(shape circle)
					(size 1.524 1.524)
					(clearance -0.0508)
				)
			)
		)
		(pad "2" thru_hole circle
			(at 1.27 -1.27 270)
			(size 1.524 1.524)
			(drill 0.9144)
			(layers "*.Cu" "*.Mask")
			(remove_unused_layers no)
			(net "L12_100OHM_6INCH_DN")
			(clearance -0.0508)
			(thermal_gap 0.127)
			(padstack
				(mode front_inner_back)
				(layer "Inner"
					(shape circle)
					(size 1.1684 1.1684)
					(clearance 0.127)
				)
				(layer "B.Cu"
					(shape circle)
					(size 1.524 1.524)
					(clearance -0.0508)
				)
			)
		)
		(pad "GND1" thru_hole rect
			(at -1.27 1.27 270)
			(size 1.524 1.524)
			(drill 0.9144)
			(layers "*.Cu" "*.Mask")
			(remove_unused_layers no)
			(net "GND")
			(clearance -0.0508)
			(thermal_gap 0.127)
			(padstack
				(mode front_inner_back)
				(layer "Inner"
					(shape circle)
					(size 1.1684 1.1684)
					(clearance 0.127)
				)
				(layer "B.Cu"
					(shape rect)
					(size 1.524 1.524)
					(clearance -0.0508)
				)
			)
		)
		(pad "GND2" thru_hole rect
			(at 1.27 1.27 270)
			(size 1.524 1.524)
			(drill 0.9144)
			(layers "*.Cu" "*.Mask")
			(remove_unused_layers no)
			(net "GND")
			(clearance -0.0508)
			(thermal_gap 0.127)
			(padstack
				(mode front_inner_back)
				(layer "Inner"
					(shape circle)
					(size 1.1684 1.1684)
					(clearance 0.127)
				)
				(layer "B.Cu"
					(shape rect)
					(size 1.524 1.524)
					(clearance -0.0508)
				)
			)
		)
	)
	(footprint ""
		(layer "F.Cu")
		(at 370.7384 -128.524 -90)
		(property "Reference" "R7B7"
			(at 0 0 270)
			(layer "F.SilkS")
			(hide yes)
			(effects
				(font
					(size 1.27 1.27)
				)
			)
		)
		(property "Value" ""
			(at 0 0 270)
			(layer "F.Fab")
			(effects
				(font
					(size 1.27 1.27)
				)
			)
		)
		(duplicate_pad_numbers_are_jumpers no)
		(fp_poly
			(pts
				(xy -0.2794 -0.1016) (xy 0.2794 -0.1016) (xy 0.2794 0.9906) (xy -0.2794 0.9906)
			)
			(stroke
				(width 0)
				(type default)
			)
			(fill no)
			(layer "F.CrtYd")
		)
		(fp_line
			(start -0.2794 0.9906)
			(end 0.2794 0.9906)
			(stroke
				(width 0.1)
				(type default)
			)
			(layer "F.Fab")
		)
		(fp_line
			(start 0.2794 0.9906)
			(end 0.2794 -0.1016)
			(stroke
				(width 0.1)
				(type default)
			)
			(layer "F.Fab")
		)
		(fp_line
			(start -0.2794 -0.1016)
			(end -0.2794 0.9906)
			(stroke
				(width 0.1)
				(type default)
			)
			(layer "F.Fab")
		)
		(fp_line
			(start 0.2794 -0.1016)
			(end -0.2794 -0.1016)
			(stroke
				(width 0.1)
				(type default)
			)
			(layer "F.Fab")
		)
		(pad "1" smd rect
			(at 0 0 270)
			(size 0.508 0.508)
			(layers "F.Cu" "F.Mask" "F.Paste")
			(net "A_EXTCLKP")
		)
		(pad "2" smd rect
			(at 0 0.889 270)
			(size 0.508 0.508)
			(layers "F.Cu" "F.Mask" "F.Paste")
			(net "GND")
		)
		(zone
			(layer "F.Cu")
			(hatch none 0.5)
			(connect_pads
				(clearance 0)
			)
			(min_thickness 0.25)
			(keepout
				(tracks not_allowed)
				(vias allowed)
				(pads allowed)
				(copperpour not_allowed)
				(footprints allowed)
			)
			(placement
				(enabled no)
				(sheetname "")
			)
			(fill
				(thermal_gap 0.5)
				(thermal_bridge_width 0.5)
				(island_removal_mode 0)
			)
			(polygon
				(pts
					(xy 370.1034 -128.778) (xy 370.1034 -128.27) (xy 370.4844 -128.27) (xy 370.4844 -128.778)
				)
			)
		)
		(zone
			(layer "F.Cu")
			(hatch none 0.5)
			(connect_pads
				(clearance 0)
			)
			(min_thickness 0.25)
			(keepout
				(tracks allowed)
				(vias not_allowed)
				(pads allowed)
				(copperpour not_allowed)
				(footprints allowed)
			)
			(placement
				(enabled no)
				(sheetname "")
			)
			(fill
				(thermal_gap 0.5)
				(thermal_bridge_width 0.5)
				(island_removal_mode 0)
			)
			(polygon
				(pts
					(xy 370.4844 -128.778) (xy 370.4844 -128.27) (xy 370.1034 -128.27) (xy 370.1034 -128.778)
				)
			)
		)
	)
	(footprint ""
		(layer "F.Cu")
		(at 195.58 -22.606 90)
		(property "Reference" "C4F10"
			(at 0 0 90)
			(layer "F.SilkS")
			(hide yes)
			(effects
				(font
					(size 1.27 1.27)
				)
			)
		)
		(property "Value" ""
			(at 0 0 90)
			(layer "F.Fab")
			(effects
				(font
					(size 1.27 1.27)
				)
			)
		)
		(duplicate_pad_numbers_are_jumpers no)
		(fp_poly
			(pts
				(xy 0.3048 -0.1016) (xy 0.3048 0.9906) (xy -0.3048 0.9906) (xy -0.3048 -0.1016)
			)
			(stroke
				(width 0)
				(type default)
			)
			(fill no)
			(layer "F.CrtYd")
		)
		(fp_line
			(start 0.3048 -0.1016)
			(end -0.3048 -0.1016)
			(stroke
				(width 0.1)
				(type default)
			)
			(layer "F.Fab")
		)
		(fp_line
			(start -0.3048 -0.1016)
			(end -0.3048 0.9906)
			(stroke
				(width 0.1)
				(type default)
			)
			(layer "F.Fab")
		)
		(fp_line
			(start 0.3048 0.9906)
			(end 0.3048 -0.1016)
			(stroke
				(width 0.1)
				(type default)
			)
			(layer "F.Fab")
		)
		(fp_line
			(start -0.3048 0.9906)
			(end 0.3048 0.9906)
			(stroke
				(width 0.1)
				(type default)
			)
			(layer "F.Fab")
		)
		(pad "1" smd rect
			(at 0 0 90)
			(size 0.508 0.508)
			(layers "F.Cu" "F.Mask" "F.Paste")
			(net "M_A_VREF")
		)
		(pad "2" smd rect
			(at 0 0.889 90)
			(size 0.508 0.508)
			(layers "F.Cu" "F.Mask" "F.Paste")
			(net "GND")
		)
		(zone
			(layer "F.Cu")
			(hatch none 0.5)
			(connect_pads
				(clearance 0)
			)
			(min_thickness 0.25)
			(keepout
				(tracks allowed)
				(vias not_allowed)
				(pads allowed)
				(copperpour not_allowed)
				(footprints allowed)
			)
			(placement
				(enabled no)
				(sheetname "")
			)
			(fill
				(thermal_gap 0.5)
				(thermal_bridge_width 0.5)
				(island_removal_mode 0)
			)
			(polygon
				(pts
					(xy 195.834 -22.352) (xy 195.834 -22.86) (xy 196.215 -22.86) (xy 196.215 -22.352)
				)
			)
		)
		(zone
			(layer "F.Cu")
			(hatch none 0.5)
			(connect_pads
				(clearance 0)
			)
			(min_thickness 0.25)
			(keepout
				(tracks not_allowed)
				(vias allowed)
				(pads allowed)
				(copperpour not_allowed)
				(footprints allowed)
			)
			(placement
				(enabled no)
				(sheetname "")
			)
			(fill
				(thermal_gap 0.5)
				(thermal_bridge_width 0.5)
				(island_removal_mode 0)
			)
			(polygon
				(pts
					(xy 196.215 -22.352) (xy 196.215 -22.86) (xy 195.834 -22.86) (xy 195.834 -22.352)
				)
			)
		)
	)
	(footprint ""
		(layer "F.Cu")
		(at 33.925002 -73.295764 90)
		(property "Reference" "EU1D3"
			(at 2.420366 5.267198 0)
			(unlocked yes)
			(layer "F.SilkS")
			(effects
				(font
					(size 0.7874 0.5842)
					(thickness 0.1524)
				)
			)
		)
		(property "Value" ""
			(at 0 0 90)
			(layer "F.Fab")
			(effects
				(font
					(size 1.27 1.27)
				)
			)
		)
		(duplicate_pad_numbers_are_jumpers no)
		(fp_line
			(start 2.9718 -3.5052)
			(end 2.9718 3.429)
			(stroke
				(width 0.1524)
				(type default)
			)
			(layer "F.SilkS")
		)
		(fp_line
			(start -3.0099 -3.5052)
			(end 2.9718 -3.5052)
			(stroke
				(width 0.1524)
				(type default)
			)
			(layer "F.SilkS")
		)
		(fp_line
			(start 2.9718 3.429)
			(end -3.0099 3.429)
			(stroke
				(width 0.1524)
				(type default)
			)
			(layer "F.SilkS")
		)
		(fp_line
			(start -3.0099 3.429)
			(end -3.0099 -3.5052)
			(stroke
				(width 0.1524)
				(type default)
			)
			(layer "F.SilkS")
		)
		(fp_circle
			(center -3.057398 -2.678684)
			(end -3.057398 -2.551684)
			(stroke
				(width 0.254)
				(type default)
			)
			(fill no)
			(layer "F.SilkS")
		)
		(fp_poly
			(pts
				(xy -2.9972 -3.4925) (xy -2.9972 -2.6924) (xy -2.1971 -3.4925)
			)
			(stroke
				(width 0)
				(type default)
			)
			(fill yes)
			(layer "F.SilkS")
		)
		(fp_poly
			(pts
				(xy -2.549906 -3.050032) (xy -2.549906 3.050032) (xy 2.549906 3.050032) (xy 2.549906 -3.050032)
			)
			(stroke
				(width 0)
				(type default)
			)
			(fill no)
			(layer "F.CrtYd")
		)
		(fp_line
			(start 2.549906 -3.050032)
			(end 2.549906 3.050032)
			(stroke
				(width 0.1)
				(type default)
			)
			(layer "F.Fab")
		)
		(fp_line
			(start -2.549906 -3.050032)
			(end 2.549906 -3.050032)
			(stroke
				(width 0.1)
				(type default)
			)
			(layer "F.Fab")
		)
		(fp_line
			(start 2.549906 3.050032)
			(end -2.549906 3.050032)
			(stroke
				(width 0.1)
				(type default)
			)
			(layer "F.Fab")
		)
		(fp_line
			(start -2.549906 3.050032)
			(end -2.549906 -3.050032)
			(stroke
				(width 0.1)
				(type default)
			)
			(layer "F.Fab")
		)
		(fp_circle
			(center -3.057398 -2.678684)
			(end -3.057398 -2.551684)
			(stroke
				(width 0.254)
				(type default)
			)
			(fill no)
			(layer "F.Fab")
		)
		(pad "1" smd rect
			(at -2.39522 -2.279904 90)
			(size 0.7112 0.254)
			(layers "F.Cu" "F.Mask" "F.Paste")
			(net "PVCCIN_CPU1")
		)
		(pad "2" smd rect
			(at -2.39522 -1.83007 90)
			(size 0.7112 0.254)
			(layers "F.Cu" "F.Mask" "F.Paste")
			(net "GND")
		)
		(pad "3" smd rect
			(at -2.39522 -1.379982 90)
			(size 0.7112 0.254)
			(layers "F.Cu" "F.Mask" "F.Paste")
			(net "VR_PVCCIN_CPU1_PH3_VCIN")
		)
		(pad "4" smd rect
			(at -2.39522 -0.929894 90)
			(size 0.7112 0.254)
			(layers "F.Cu" "F.Mask" "F.Paste")
			(net "P5V_STBY")
		)
		(pad "5" smd rect
			(at -2.39522 -0.48006 90)
			(size 0.7112 0.254)
			(layers "F.Cu" "F.Mask" "F.Paste")
			(net "GND")
		)
		(pad "6" smd rect
			(at -2.39522 -0.029972 90)
			(size 0.7112 0.254)
			(layers "F.Cu" "F.Mask" "F.Paste")
			(net "TP_PVCCIN_CPU1_PH3_GL_0")
		)
		(pad "7" smd custom
			(at 0.016764 1.145032 90)
			(size 0.53975 0.53975)
			(layers "F.Cu" "F.Mask" "F.Paste")
			(net "GND")
			(options
				(clearance outline)
				(anchor circle)
			)
			(primitives
				(gr_poly
					(pts
						(xy -2.7051 1.0795) (xy -2.7051 -0.3683) (xy -0.9271 -0.3683) (xy -0.9271 -1.0795) (xy 2.7051 -1.0795)
						(xy 2.7051 1.0795)
					)
					(width 0)
					(fill yes)
				)
			)
		)
		(pad "10" smd rect
			(at -0.008382 2.874772 90)
			(size 4.3434 0.6096)
			(layers "F.Cu" "F.Mask" "F.Paste")
			(net "VR_PVCCIN_CPU1_PHASE3")
		)
		(pad "25" smd rect
			(at 1.548384 -1.283208 90)
			(size 2.3368 2.0066)
			(layers "F.Cu" "F.Mask" "F.Paste")
			(net "VR_FET_SW_P12V_STBY_PVCCIN_CPU1")
		)
		(pad "30" smd rect
			(at 2.050034 -2.895092 90)
			(size 0.254 0.7112)
			(layers "F.Cu" "F.Mask" "F.Paste")
			(net "VR_FET_SW_P12V_STBY_PVCCIN_CPU1")
		)
		(pad "31" smd rect
			(at 1.599946 -2.895092 90)
			(size 0.254 0.7112)
			(layers "F.Cu" "F.Mask" "F.Paste")
			(net "Net_294")
		)
		(pad "32" smd rect
			(at 1.150112 -2.895092 90)
			(size 0.254 0.7112)
			(layers "F.Cu" "F.Mask" "F.Paste")
			(net "VR_PVCCIN_CPU1_PH3_PHASE")
		)
		(pad "33" smd rect
			(at 0.700024 -2.895092 90)
			(size 0.254 0.7112)
			(layers "F.Cu" "F.Mask" "F.Paste")
			(net "VR_PVCCIN_CPU1_PH3_BOOT_R")
		)
		(pad "34" smd rect
			(at 0.249936 -2.895092 90)
			(size 0.254 0.7112)
			(layers "F.Cu" "F.Mask" "F.Paste")
			(net "VR_PVCCIN_CPU1_PWM3")
		)
		(pad "35" smd rect
			(at -0.199898 -2.895092 90)
			(size 0.254 0.7112)
			(layers "F.Cu" "F.Mask" "F.Paste")
			(net "P5V_STBY")
		)
		(pad "36" smd rect
			(at -0.649986 -2.895092 90)
			(size 0.254 0.7112)
			(layers "F.Cu" "F.Mask" "F.Paste")
			(net "A_TSENSE_PVCCIN_CPU1")
		)
		(pad "37" smd rect
			(at -1.100074 -2.895092 90)
			(size 0.254 0.7112)
			(layers "F.Cu" "F.Mask" "F.Paste")
			(net "VR_PVCCIN_CPU1_PH3_OCSET")
		)
		(pad "38" smd rect
			(at -1.549908 -2.895092 90)
			(size 0.254 0.7112)
			(layers "F.Cu" "F.Mask" "F.Paste")
			(net "ISENSE_PVCCIN_CPU1_PH3_IMON")
		)
		(pad "39" smd rect
			(at -1.999996 -2.895092 90)
			(size 0.254 0.7112)
			(layers "F.Cu" "F.Mask" "F.Paste")
			(net "VR_PVCCIN_CPU1_AIREF3")
		)
		(pad "40" smd rect
			(at -0.871728 -1.283208 90)
			(size 1.8034 2.0066)
			(layers "F.Cu" "F.Mask" "F.Paste")
			(net "GND")
		)
		(pad "41" smd rect
			(at -1.533906 0.247904 90)
			(size 0.508 0.3556)
			(layers "F.Cu" "F.Mask" "F.Paste")
			(net "TP_PVCCIN_CPU1_PH3_GL_1")
		)
	)
	(footprint ""
		(layer "F.Cu")
		(at 382.27 3.81 90)
		(property "Reference" "J7G2"
			(at 3.02133 18.669 0)
			(unlocked yes)
			(layer "F.SilkS")
			(effects
				(font
					(size 0.7874 0.5842)
					(thickness 0.1524)
				)
			)
		)
		(property "Value" ""
			(at 0 0 90)
			(layer "F.Fab")
			(effects
				(font
					(size 1.27 1.27)
				)
			)
		)
		(duplicate_pad_numbers_are_jumpers no)
		(fp_line
			(start 1.2954 -1.27)
			(end 1.2954 19.05)
			(stroke
				(width 0.1524)
				(type default)
			)
			(layer "F.SilkS")
		)
		(fp_line
			(start -1.2954 -1.27)
			(end 1.2954 -1.27)
			(stroke
				(width 0.1524)
				(type default)
			)
			(layer "F.SilkS")
		)
		(fp_line
			(start 1.2954 19.05)
			(end -1.2954 19.05)
			(stroke
				(width 0.1524)
				(type default)
			)
			(layer "F.SilkS")
		)
		(fp_line
			(start -1.2954 19.05)
			(end -1.2954 -1.27)
			(stroke
				(width 0.1524)
				(type default)
			)
			(layer "F.SilkS")
		)
		(fp_poly
			(pts
				(xy 1.070356 -0.705866) (xy 2.340356 -1.213866) (xy 2.340356 -0.197866)
			)
			(stroke
				(width 0)
				(type default)
			)
			(fill yes)
			(layer "F.SilkS")
		)
		(fp_poly
			(pts
				(xy 1.4732 0.0254) (xy 2.7432 -0.4826) (xy 2.7432 0.5334)
			)
			(stroke
				(width 0)
				(type default)
			)
			(fill yes)
			(layer "B.SilkS")
		)
		(fp_poly
			(pts
				(xy -1.2954 19.05) (xy 1.2954 19.05) (xy 1.2954 -1.27) (xy -1.2954 -1.27)
			)
			(stroke
				(width 0)
				(type default)
			)
			(fill no)
			(layer "F.CrtYd")
		)
		(fp_poly
			(pts
				(xy 1.4732 0.0254) (xy 2.7432 -0.4826) (xy 2.7432 0.5334)
			)
			(stroke
				(width 0)
				(type default)
			)
			(fill yes)
			(layer "B.Fab")
		)
		(fp_line
			(start 1.2954 -1.27)
			(end -1.2954 -1.27)
			(stroke
				(width 0.1)
				(type default)
			)
			(layer "F.Fab")
		)
		(fp_line
			(start -1.2954 -1.27)
			(end -1.2954 19.05)
			(stroke
				(width 0.1)
				(type default)
			)
			(layer "F.Fab")
		)
		(fp_line
			(start 1.2954 19.05)
			(end 1.2954 -1.27)
			(stroke
				(width 0.1)
				(type default)
			)
			(layer "F.Fab")
		)
		(fp_line
			(start -1.2954 19.05)
			(end 1.2954 19.05)
			(stroke
				(width 0.1)
				(type default)
			)
			(layer "F.Fab")
		)
		(fp_poly
			(pts
				(xy 1.4732 0.0254) (xy 2.7432 -0.4826) (xy 2.7432 0.5334)
			)
			(stroke
				(width 0)
				(type default)
			)
			(fill yes)
			(layer "F.Fab")
		)
		(fp_text user "8"
			(at 1.76911 19.26844 0)
			(unlocked yes)
			(layer "F.SilkS")
			(effects
				(font
					(size 0.7874 0.5842)
					(thickness 0.1524)
				)
			)
		)
		(fp_text user "8"
			(at 1.8288 17.85747 90)
			(unlocked yes)
			(layer "B.SilkS")
			(effects
				(font
					(size 0.7874 0.5842)
					(thickness 0.1524)
				)
			)
		)
		(fp_text user "8"
			(at 1.8288 17.85747 90)
			(unlocked yes)
			(layer "B.Fab")
			(effects
				(font
					(size 0.7874 0.5842)
					(thickness 0.1524)
				)
			)
		)
		(fp_text user "8"
			(at 0.218694 -1.651 0)
			(unlocked yes)
			(layer "F.Fab")
			(effects
				(font
					(size 0.7874 0.5842)
					(thickness 0.1524)
				)
			)
		)
		(pad "1" thru_hole rect
			(at 0 0 90)
			(size 1.6256 1.6256)
			(drill 1.2446)
			(layers "*.Cu" "*.Mask")
			(remove_unused_layers no)
			(net "P3V3_STBY_PLD_D")
			(clearance 0.127)
			(thermal_gap 0.127)
			(padstack
				(mode front_inner_back)
				(layer "Inner"
					(shape circle)
					(size 1.6256 1.6256)
					(clearance 0.127)
				)
				(layer "B.Cu"
					(shape rect)
					(size 1.6256 1.6256)
					(clearance 0.127)
				)
			)
		)
		(pad "2" thru_hole circle
			(at 0 2.54 90)
			(size 1.6256 1.6256)
			(drill 1.2446)
			(layers "*.Cu" "*.Mask")
			(remove_unused_layers no)
			(net "JTAG_TDO_R")
			(clearance 0.127)
			(thermal_gap 0.127)
		)
		(pad "3" thru_hole circle
			(at 0 5.08 90)
			(size 1.6256 1.6256)
			(drill 1.2446)
			(layers "*.Cu" "*.Mask")
			(remove_unused_layers no)
			(net "JTAG_TDI_R")
			(clearance 0.127)
			(thermal_gap 0.127)
		)
		(pad "4" thru_hole circle
			(at 0 7.62 90)
			(size 1.6256 1.6256)
			(drill 1.2446)
			(layers "*.Cu" "*.Mask")
			(remove_unused_layers no)
			(net "JTAG_TRST_N")
			(clearance 0.127)
			(thermal_gap 0.127)
		)
		(pad "5" thru_hole circle
			(at 0 10.16 90)
			(size 1.6256 1.6256)
			(drill 1.2446)
			(layers "*.Cu" "*.Mask")
			(remove_unused_layers no)
			(net "PWRGD_P3V3_STBY")
			(clearance 0.127)
			(thermal_gap 0.127)
		)
		(pad "6" thru_hole circle
			(at 0 12.7 90)
			(size 1.6256 1.6256)
			(drill 1.2446)
			(layers "*.Cu" "*.Mask")
			(remove_unused_layers no)
			(net "JTAG_TMS_R")
			(clearance 0.127)
			(thermal_gap 0.127)
		)
		(pad "7" thru_hole circle
			(at 0 15.24 90)
			(size 1.6256 1.6256)
			(drill 1.2446)
			(layers "*.Cu" "*.Mask")
			(remove_unused_layers no)
			(net "GND")
			(clearance 0.127)
			(thermal_gap 0.127)
		)
		(pad "8" thru_hole circle
			(at 0 17.78 90)
			(size 1.6256 1.6256)
			(drill 1.2446)
			(layers "*.Cu" "*.Mask")
			(remove_unused_layers no)
			(net "JTAG_TCK_R")
			(clearance 0.127)
			(thermal_gap 0.127)
		)
	)
	(footprint ""
		(layer "F.Cu")
		(at 393.1412 1.5748 90)
		(property "Reference" "R8G20"
			(at 0 0 90)
			(layer "F.SilkS")
			(hide yes)
			(effects
				(font
					(size 1.27 1.27)
				)
			)
		)
		(property "Value" ""
			(at 0 0 90)
			(layer "F.Fab")
			(effects
				(font
					(size 1.27 1.27)
				)
			)
		)
		(duplicate_pad_numbers_are_jumpers no)
		(fp_poly
			(pts
				(xy -0.2794 -0.1016) (xy 0.2794 -0.1016) (xy 0.2794 0.9906) (xy -0.2794 0.9906)
			)
			(stroke
				(width 0)
				(type default)
			)
			(fill no)
			(layer "F.CrtYd")
		)
		(fp_line
			(start 0.2794 -0.1016)
			(end -0.2794 -0.1016)
			(stroke
				(width 0.1)
				(type default)
			)
			(layer "F.Fab")
		)
		(fp_line
			(start -0.2794 -0.1016)
			(end -0.2794 0.9906)
			(stroke
				(width 0.1)
				(type default)
			)
			(layer "F.Fab")
		)
		(fp_line
			(start 0.2794 0.9906)
			(end 0.2794 -0.1016)
			(stroke
				(width 0.1)
				(type default)
			)
			(layer "F.Fab")
		)
		(fp_line
			(start -0.2794 0.9906)
			(end 0.2794 0.9906)
			(stroke
				(width 0.1)
				(type default)
			)
			(layer "F.Fab")
		)
		(pad "1" smd rect
			(at 0 0 90)
			(size 0.508 0.508)
			(layers "F.Cu" "F.Mask" "F.Paste")
			(net "P3V3_STBY")
		)
		(pad "2" smd rect
			(at 0 0.889 90)
			(size 0.508 0.508)
			(layers "F.Cu" "F.Mask" "F.Paste")
			(net "JTAG_TMS_R")
		)
		(zone
			(layer "F.Cu")
			(hatch none 0.5)
			(connect_pads
				(clearance 0)
			)
			(min_thickness 0.25)
			(keepout
				(tracks allowed)
				(vias not_allowed)
				(pads allowed)
				(copperpour not_allowed)
				(footprints allowed)
			)
			(placement
				(enabled no)
				(sheetname "")
			)
			(fill
				(thermal_gap 0.5)
				(thermal_bridge_width 0.5)
				(island_removal_mode 0)
			)
			(polygon
				(pts
					(xy 393.3952 1.8288) (xy 393.3952 1.3208) (xy 393.7762 1.3208) (xy 393.7762 1.8288)
				)
			)
		)
		(zone
			(layer "F.Cu")
			(hatch none 0.5)
			(connect_pads
				(clearance 0)
			)
			(min_thickness 0.25)
			(keepout
				(tracks not_allowed)
				(vias allowed)
				(pads allowed)
				(copperpour not_allowed)
				(footprints allowed)
			)
			(placement
				(enabled no)
				(sheetname "")
			)
			(fill
				(thermal_gap 0.5)
				(thermal_bridge_width 0.5)
				(island_removal_mode 0)
			)
			(polygon
				(pts
					(xy 393.7762 1.8288) (xy 393.7762 1.3208) (xy 393.3952 1.3208) (xy 393.3952 1.8288)
				)
			)
		)
	)
	(footprint ""
		(layer "F.Cu")
		(at 363.8804 -136.7536 90)
		(property "Reference" "R12W29"
			(at -0.8382 -0.67818 90)
			(unlocked yes)
			(layer "F.SilkS")
			(effects
				(font
					(size 0.4064 0.254)
					(thickness 0.1524)
				)
				(justify left)
			)
		)
		(property "Value" ""
			(at 0 0 90)
			(layer "F.Fab")
			(effects
				(font
					(size 1.27 1.27)
				)
			)
		)
		(duplicate_pad_numbers_are_jumpers no)
		(fp_poly
			(pts
				(xy -0.2794 -0.1016) (xy 0.2794 -0.1016) (xy 0.2794 0.9906) (xy -0.2794 0.9906)
			)
			(stroke
				(width 0)
				(type default)
			)
			(fill no)
			(layer "F.CrtYd")
		)
		(fp_line
			(start 0.2794 -0.1016)
			(end -0.2794 -0.1016)
			(stroke
				(width 0.1)
				(type default)
			)
			(layer "F.Fab")
		)
		(fp_line
			(start -0.2794 -0.1016)
			(end -0.2794 0.9906)
			(stroke
				(width 0.1)
				(type default)
			)
			(layer "F.Fab")
		)
		(fp_line
			(start 0.2794 0.9906)
			(end 0.2794 -0.1016)
			(stroke
				(width 0.1)
				(type default)
			)
			(layer "F.Fab")
		)
		(fp_line
			(start -0.2794 0.9906)
			(end 0.2794 0.9906)
			(stroke
				(width 0.1)
				(type default)
			)
			(layer "F.Fab")
		)
		(pad "1" smd rect
			(at 0 0 90)
			(size 0.508 0.508)
			(layers "F.Cu" "F.Mask" "F.Paste")
			(net "TP_PVDDQ_DEF_MP1")
		)
		(pad "2" smd rect
			(at 0 0.889 90)
			(size 0.508 0.508)
			(layers "F.Cu" "F.Mask" "F.Paste")
			(net "PWRGD_PVDDQ_DEF")
		)
		(zone
			(layer "F.Cu")
			(hatch none 0.5)
			(connect_pads
				(clearance 0)
			)
			(min_thickness 0.25)
			(keepout
				(tracks allowed)
				(vias not_allowed)
				(pads allowed)
				(copperpour not_allowed)
				(footprints allowed)
			)
			(placement
				(enabled no)
				(sheetname "")
			)
			(fill
				(thermal_gap 0.5)
				(thermal_bridge_width 0.5)
				(island_removal_mode 0)
			)
			(polygon
				(pts
					(xy 364.1344 -136.4996) (xy 364.1344 -137.0076) (xy 364.5154 -137.0076) (xy 364.5154 -136.4996)
				)
			)
		)
		(zone
			(layer "F.Cu")
			(hatch none 0.5)
			(connect_pads
				(clearance 0)
			)
			(min_thickness 0.25)
			(keepout
				(tracks not_allowed)
				(vias allowed)
				(pads allowed)
				(copperpour not_allowed)
				(footprints allowed)
			)
			(placement
				(enabled no)
				(sheetname "")
			)
			(fill
				(thermal_gap 0.5)
				(thermal_bridge_width 0.5)
				(island_removal_mode 0)
			)
			(polygon
				(pts
					(xy 364.5154 -136.4996) (xy 364.5154 -137.0076) (xy 364.1344 -137.0076) (xy 364.1344 -136.4996)
				)
			)
		)
	)
	(footprint ""
		(layer "F.Cu")
		(at 266.920472 -77.636116)
		(property "Reference" "C5D31"
			(at 0 0 0)
			(layer "F.SilkS")
			(hide yes)
			(effects
				(font
					(size 1.27 1.27)
				)
			)
		)
		(property "Value" ""
			(at 0 0 0)
			(layer "F.Fab")
			(effects
				(font
					(size 1.27 1.27)
				)
			)
		)
		(duplicate_pad_numbers_are_jumpers no)
		(fp_poly
			(pts
				(xy -0.4953 -0.2032) (xy 0.4953 -0.2032) (xy 0.4953 1.6002) (xy -0.4953 1.6002)
			)
			(stroke
				(width 0)
				(type default)
			)
			(fill no)
			(layer "F.CrtYd")
		)
		(fp_line
			(start -0.4953 -0.2032)
			(end 0.4953 -0.2032)
			(stroke
				(width 0.1)
				(type default)
			)
			(layer "F.Fab")
		)
		(fp_line
			(start -0.4953 1.6002)
			(end -0.4953 -0.2032)
			(stroke
				(width 0.1)
				(type default)
			)
			(layer "F.Fab")
		)
		(fp_line
			(start 0.4953 -0.2032)
			(end 0.4953 1.6002)
			(stroke
				(width 0.1)
				(type default)
			)
			(layer "F.Fab")
		)
		(fp_line
			(start 0.4953 1.6002)
			(end -0.4953 1.6002)
			(stroke
				(width 0.1)
				(type default)
			)
			(layer "F.Fab")
		)
		(pad "1" smd rect
			(at 0 0)
			(size 0.762 0.889)
			(layers "F.Cu" "F.Mask" "F.Paste")
			(net "PVCCIN_CPU0")
		)
		(pad "2" smd rect
			(at 0 1.397)
			(size 0.762 0.889)
			(layers "F.Cu" "F.Mask" "F.Paste")
			(net "GND")
		)
		(zone
			(layer "F.Cu")
			(hatch none 0.5)
			(connect_pads
				(clearance 0)
			)
			(min_thickness 0.25)
			(keepout
				(tracks not_allowed)
				(vias allowed)
				(pads allowed)
				(copperpour not_allowed)
				(footprints allowed)
			)
			(placement
				(enabled no)
				(sheetname "")
			)
			(fill
				(thermal_gap 0.5)
				(thermal_bridge_width 0.5)
				(island_removal_mode 0)
			)
			(polygon
				(pts
					(xy 266.539472 -77.191616) (xy 267.301472 -77.191616) (xy 267.301472 -76.683616) (xy 266.539472 -76.683616)
				)
			)
		)
	)
	(footprint ""
		(layer "F.Cu")
		(at 403.987 -115.697 90)
		(property "Reference" "R25W140"
			(at -0.8382 -0.67818 90)
			(unlocked yes)
			(layer "F.SilkS")
			(effects
				(font
					(size 0.4064 0.254)
					(thickness 0.1524)
				)
				(justify left)
			)
		)
		(property "Value" ""
			(at 0 0 90)
			(layer "F.Fab")
			(effects
				(font
					(size 1.27 1.27)
				)
			)
		)
		(duplicate_pad_numbers_are_jumpers no)
		(fp_poly
			(pts
				(xy -0.2794 -0.1016) (xy 0.2794 -0.1016) (xy 0.2794 0.9906) (xy -0.2794 0.9906)
			)
			(stroke
				(width 0)
				(type default)
			)
			(fill no)
			(layer "F.CrtYd")
		)
		(fp_line
			(start 0.2794 -0.1016)
			(end -0.2794 -0.1016)
			(stroke
				(width 0.1)
				(type default)
			)
			(layer "F.Fab")
		)
		(fp_line
			(start -0.2794 -0.1016)
			(end -0.2794 0.9906)
			(stroke
				(width 0.1)
				(type default)
			)
			(layer "F.Fab")
		)
		(fp_line
			(start 0.2794 0.9906)
			(end 0.2794 -0.1016)
			(stroke
				(width 0.1)
				(type default)
			)
			(layer "F.Fab")
		)
		(fp_line
			(start -0.2794 0.9906)
			(end 0.2794 0.9906)
			(stroke
				(width 0.1)
				(type default)
			)
			(layer "F.Fab")
		)
		(pad "1" smd rect
			(at 0 0 90)
			(size 0.508 0.508)
			(layers "F.Cu" "F.Mask" "F.Paste")
			(net "CLK_48M_USB_BMC")
		)
		(pad "2" smd rect
			(at 0 0.889 90)
			(size 0.508 0.508)
			(layers "F.Cu" "F.Mask" "F.Paste")
			(net "CLK_48M_USB_BMC_R")
		)
		(zone
			(layer "F.Cu")
			(hatch none 0.5)
			(connect_pads
				(clearance 0)
			)
			(min_thickness 0.25)
			(keepout
				(tracks allowed)
				(vias not_allowed)
				(pads allowed)
				(copperpour not_allowed)
				(footprints allowed)
			)
			(placement
				(enabled no)
				(sheetname "")
			)
			(fill
				(thermal_gap 0.5)
				(thermal_bridge_width 0.5)
				(island_removal_mode 0)
			)
			(polygon
				(pts
					(xy 404.241 -115.443) (xy 404.241 -115.951) (xy 404.622 -115.951) (xy 404.622 -115.443)
				)
			)
		)
		(zone
			(layer "F.Cu")
			(hatch none 0.5)
			(connect_pads
				(clearance 0)
			)
			(min_thickness 0.25)
			(keepout
				(tracks not_allowed)
				(vias allowed)
				(pads allowed)
				(copperpour not_allowed)
				(footprints allowed)
			)
			(placement
				(enabled no)
				(sheetname "")
			)
			(fill
				(thermal_gap 0.5)
				(thermal_bridge_width 0.5)
				(island_removal_mode 0)
			)
			(polygon
				(pts
					(xy 404.622 -115.443) (xy 404.622 -115.951) (xy 404.241 -115.951) (xy 404.241 -115.443)
				)
			)
		)
	)
	(footprint ""
		(layer "F.Cu")
		(at 370.111274 -64.113664 90)
		(property "Reference" "R7E6"
			(at 0 0 90)
			(layer "F.SilkS")
			(hide yes)
			(effects
				(font
					(size 1.27 1.27)
				)
			)
		)
		(property "Value" ""
			(at 0 0 90)
			(layer "F.Fab")
			(effects
				(font
					(size 1.27 1.27)
				)
			)
		)
		(duplicate_pad_numbers_are_jumpers no)
		(fp_poly
			(pts
				(xy -0.2794 -0.1016) (xy 0.2794 -0.1016) (xy 0.2794 0.9906) (xy -0.2794 0.9906)
			)
			(stroke
				(width 0)
				(type default)
			)
			(fill no)
			(layer "F.CrtYd")
		)
		(fp_line
			(start 0.2794 -0.1016)
			(end -0.2794 -0.1016)
			(stroke
				(width 0.1)
				(type default)
			)
			(layer "F.Fab")
		)
		(fp_line
			(start -0.2794 -0.1016)
			(end -0.2794 0.9906)
			(stroke
				(width 0.1)
				(type default)
			)
			(layer "F.Fab")
		)
		(fp_line
			(start 0.2794 0.9906)
			(end 0.2794 -0.1016)
			(stroke
				(width 0.1)
				(type default)
			)
			(layer "F.Fab")
		)
		(fp_line
			(start -0.2794 0.9906)
			(end 0.2794 0.9906)
			(stroke
				(width 0.1)
				(type default)
			)
			(layer "F.Fab")
		)
		(pad "1" smd rect
			(at 0 0 90)
			(size 0.508 0.508)
			(layers "F.Cu" "F.Mask" "F.Paste")
			(net "P3V3_STBY")
		)
		(pad "2" smd rect
			(at 0 0.889 90)
			(size 0.508 0.508)
			(layers "F.Cu" "F.Mask" "F.Paste")
			(net "PU_RST_PERST_BIT1")
		)
		(zone
			(layer "F.Cu")
			(hatch none 0.5)
			(connect_pads
				(clearance 0)
			)
			(min_thickness 0.25)
			(keepout
				(tracks allowed)
				(vias not_allowed)
				(pads allowed)
				(copperpour not_allowed)
				(footprints allowed)
			)
			(placement
				(enabled no)
				(sheetname "")
			)
			(fill
				(thermal_gap 0.5)
				(thermal_bridge_width 0.5)
				(island_removal_mode 0)
			)
			(polygon
				(pts
					(xy 370.365274 -63.859664) (xy 370.365274 -64.367664) (xy 370.746274 -64.367664) (xy 370.746274 -63.859664)
				)
			)
		)
		(zone
			(layer "F.Cu")
			(hatch none 0.5)
			(connect_pads
				(clearance 0)
			)
			(min_thickness 0.25)
			(keepout
				(tracks not_allowed)
				(vias allowed)
				(pads allowed)
				(copperpour not_allowed)
				(footprints allowed)
			)
			(placement
				(enabled no)
				(sheetname "")
			)
			(fill
				(thermal_gap 0.5)
				(thermal_bridge_width 0.5)
				(island_removal_mode 0)
			)
			(polygon
				(pts
					(xy 370.746274 -63.859664) (xy 370.746274 -64.367664) (xy 370.365274 -64.367664) (xy 370.365274 -63.859664)
				)
			)
		)
	)
	(footprint ""
		(layer "F.Cu")
		(at 172.0469 -6.9342 -90)
		(property "Reference" "R4G15"
			(at 0 0 270)
			(layer "F.SilkS")
			(hide yes)
			(effects
				(font
					(size 1.27 1.27)
				)
			)
		)
		(property "Value" ""
			(at 0 0 270)
			(layer "F.Fab")
			(effects
				(font
					(size 1.27 1.27)
				)
			)
		)
		(duplicate_pad_numbers_are_jumpers no)
		(fp_poly
			(pts
				(xy -0.2794 -0.1016) (xy 0.2794 -0.1016) (xy 0.2794 0.9906) (xy -0.2794 0.9906)
			)
			(stroke
				(width 0)
				(type default)
			)
			(fill no)
			(layer "F.CrtYd")
		)
		(fp_line
			(start -0.2794 0.9906)
			(end 0.2794 0.9906)
			(stroke
				(width 0.1)
				(type default)
			)
			(layer "F.Fab")
		)
		(fp_line
			(start 0.2794 0.9906)
			(end 0.2794 -0.1016)
			(stroke
				(width 0.1)
				(type default)
			)
			(layer "F.Fab")
		)
		(fp_line
			(start -0.2794 -0.1016)
			(end -0.2794 0.9906)
			(stroke
				(width 0.1)
				(type default)
			)
			(layer "F.Fab")
		)
		(fp_line
			(start 0.2794 -0.1016)
			(end -0.2794 -0.1016)
			(stroke
				(width 0.1)
				(type default)
			)
			(layer "F.Fab")
		)
		(pad "1" smd rect
			(at 0 0 270)
			(size 0.508 0.508)
			(layers "F.Cu" "F.Mask" "F.Paste")
			(net "PWRGD_PVTT_GHJ_CPU1_R")
		)
		(pad "2" smd rect
			(at 0 0.889 270)
			(size 0.508 0.508)
			(layers "F.Cu" "F.Mask" "F.Paste")
			(net "PWRGD_PVTT_CPU1")
		)
		(zone
			(layer "F.Cu")
			(hatch none 0.5)
			(connect_pads
				(clearance 0)
			)
			(min_thickness 0.25)
			(keepout
				(tracks not_allowed)
				(vias allowed)
				(pads allowed)
				(copperpour not_allowed)
				(footprints allowed)
			)
			(placement
				(enabled no)
				(sheetname "")
			)
			(fill
				(thermal_gap 0.5)
				(thermal_bridge_width 0.5)
				(island_removal_mode 0)
			)
			(polygon
				(pts
					(xy 171.4119 -7.1882) (xy 171.4119 -6.6802) (xy 171.7929 -6.6802) (xy 171.7929 -7.1882)
				)
			)
		)
		(zone
			(layer "F.Cu")
			(hatch none 0.5)
			(connect_pads
				(clearance 0)
			)
			(min_thickness 0.25)
			(keepout
				(tracks allowed)
				(vias not_allowed)
				(pads allowed)
				(copperpour not_allowed)
				(footprints allowed)
			)
			(placement
				(enabled no)
				(sheetname "")
			)
			(fill
				(thermal_gap 0.5)
				(thermal_bridge_width 0.5)
				(island_removal_mode 0)
			)
			(polygon
				(pts
					(xy 171.7929 -7.1882) (xy 171.7929 -6.6802) (xy 171.4119 -6.6802) (xy 171.4119 -7.1882)
				)
			)
		)
	)
	(footprint ""
		(layer "F.Cu")
		(at 402.641054 -43.729148 90)
		(property "Reference" "R1T35"
			(at 0 0 90)
			(layer "F.SilkS")
			(hide yes)
			(effects
				(font
					(size 1.27 1.27)
				)
			)
		)
		(property "Value" ""
			(at 0 0 90)
			(layer "F.Fab")
			(effects
				(font
					(size 1.27 1.27)
				)
			)
		)
		(duplicate_pad_numbers_are_jumpers no)
		(fp_poly
			(pts
				(xy -0.2794 -0.1016) (xy 0.2794 -0.1016) (xy 0.2794 0.9906) (xy -0.2794 0.9906)
			)
			(stroke
				(width 0)
				(type default)
			)
			(fill no)
			(layer "F.CrtYd")
		)
		(fp_line
			(start 0.2794 -0.1016)
			(end -0.2794 -0.1016)
			(stroke
				(width 0.1)
				(type default)
			)
			(layer "F.Fab")
		)
		(fp_line
			(start -0.2794 -0.1016)
			(end -0.2794 0.9906)
			(stroke
				(width 0.1)
				(type default)
			)
			(layer "F.Fab")
		)
		(fp_line
			(start 0.2794 0.9906)
			(end 0.2794 -0.1016)
			(stroke
				(width 0.1)
				(type default)
			)
			(layer "F.Fab")
		)
		(fp_line
			(start -0.2794 0.9906)
			(end 0.2794 0.9906)
			(stroke
				(width 0.1)
				(type default)
			)
			(layer "F.Fab")
		)
		(pad "1" smd rect
			(at 0 0 90)
			(size 0.508 0.508)
			(layers "F.Cu" "F.Mask" "F.Paste")
			(net "FM_CPU0_PROCHOT_LVT3_N")
		)
		(pad "2" smd rect
			(at 0 0.889 90)
			(size 0.508 0.508)
			(layers "F.Cu" "F.Mask" "F.Paste")
			(net "FM_CPU0_PROCHOT_PCH_N")
		)
		(zone
			(layer "F.Cu")
			(hatch none 0.5)
			(connect_pads
				(clearance 0)
			)
			(min_thickness 0.25)
			(keepout
				(tracks allowed)
				(vias not_allowed)
				(pads allowed)
				(copperpour not_allowed)
				(footprints allowed)
			)
			(placement
				(enabled no)
				(sheetname "")
			)
			(fill
				(thermal_gap 0.5)
				(thermal_bridge_width 0.5)
				(island_removal_mode 0)
			)
			(polygon
				(pts
					(xy 402.895054 -43.475148) (xy 402.895054 -43.983148) (xy 403.276054 -43.983148) (xy 403.276054 -43.475148)
				)
			)
		)
		(zone
			(layer "F.Cu")
			(hatch none 0.5)
			(connect_pads
				(clearance 0)
			)
			(min_thickness 0.25)
			(keepout
				(tracks not_allowed)
				(vias allowed)
				(pads allowed)
				(copperpour not_allowed)
				(footprints allowed)
			)
			(placement
				(enabled no)
				(sheetname "")
			)
			(fill
				(thermal_gap 0.5)
				(thermal_bridge_width 0.5)
				(island_removal_mode 0)
			)
			(polygon
				(pts
					(xy 403.276054 -43.475148) (xy 403.276054 -43.983148) (xy 402.895054 -43.983148) (xy 402.895054 -43.475148)
				)
			)
		)
	)
	(footprint ""
		(layer "F.Cu")
		(at 188.98108 -65.27038 180)
		(property "Reference" "CF1"
			(at 0 0 180)
			(layer "F.SilkS")
			(hide yes)
			(effects
				(font
					(size 1.27 1.27)
				)
			)
		)
		(property "Value" "*"
			(at 1.1811 -2.8194 180)
			(unlocked yes)
			(layer "F.Fab")
			(hide yes)
			(effects
				(font
					(size 1.27 1.016)
					(thickness 0.1524)
				)
			)
		)
		(property "Device Type" "SC22P50V2JN-4GP_SMD-BCG-SC22P5A"
			(at 1.1811 -4.3434 180)
			(unlocked yes)
			(layer "F.Fab")
			(hide yes)
			(effects
				(font
					(size 1.27 1.016)
					(thickness 0.1524)
				)
			)
		)
		(duplicate_pad_numbers_are_jumpers no)
		(fp_rect
			(start -0.4318 0.9525)
			(end 0.4318 -0.9525)
			(stroke
				(width 0)
				(type default)
			)
			(fill no)
			(layer "F.CrtYd")
		)
		(fp_rect
			(start -0.4318 0.9525)
			(end 0.4318 -0.9525)
			(stroke
				(width 0)
				(type default)
			)
			(fill no)
			(layer "F.Fab")
		)
		(pad "1" smd custom
			(at 0 -0.4445 180)
			(size 0.1524 0.1524)
			(layers "F.Cu" "F.Mask" "F.Paste")
			(net "VR_PVCCIN_CPU0_AIREF1")
			(options
				(clearance outline)
				(anchor circle)
			)
			(primitives
				(gr_poly
					(pts
						(arc
							(start 0.3048 -0.2032)
							(mid 0.275042 -0.275042)
							(end 0.2032 -0.3048)
						)
						(arc
							(start -0.2032 -0.3048)
							(mid -0.275042 -0.275042)
							(end -0.3048 -0.2032)
						)
						(arc
							(start -0.3048 0.2032)
							(mid -0.275042 0.275042)
							(end -0.2032 0.3048)
						)
						(arc
							(start 0.2032 0.3048)
							(mid 0.275042 0.275042)
							(end 0.3048 0.2032)
						)
					)
					(width 0)
					(fill yes)
				)
			)
		)
		(pad "2" smd custom
			(at 0 0.4445 180)
			(size 0.1524 0.1524)
			(layers "F.Cu" "F.Mask" "F.Paste")
			(net "ISENSE_PVCCIN_CPU0_PH1_IMON")
			(options
				(clearance outline)
				(anchor circle)
			)
			(primitives
				(gr_poly
					(pts
						(arc
							(start 0.3048 -0.2032)
							(mid 0.275042 -0.275042)
							(end 0.2032 -0.3048)
						)
						(arc
							(start -0.2032 -0.3048)
							(mid -0.275042 -0.275042)
							(end -0.3048 -0.2032)
						)
						(arc
							(start -0.3048 0.2032)
							(mid -0.275042 0.275042)
							(end -0.2032 0.3048)
						)
						(arc
							(start 0.2032 0.3048)
							(mid 0.275042 0.275042)
							(end 0.3048 0.2032)
						)
					)
					(width 0)
					(fill yes)
				)
			)
		)
	)
	(footprint ""
		(layer "F.Cu")
		(at 181.1147 -76.52385 -90)
		(property "Reference" "C4D15"
			(at 0 0 270)
			(layer "F.SilkS")
			(hide yes)
			(effects
				(font
					(size 1.27 1.27)
				)
			)
		)
		(property "Value" ""
			(at 0 0 270)
			(layer "F.Fab")
			(effects
				(font
					(size 1.27 1.27)
				)
			)
		)
		(duplicate_pad_numbers_are_jumpers no)
		(fp_poly
			(pts
				(xy 0.3048 -0.1016) (xy 0.3048 0.9906) (xy -0.3048 0.9906) (xy -0.3048 -0.1016)
			)
			(stroke
				(width 0)
				(type default)
			)
			(fill no)
			(layer "F.CrtYd")
		)
		(fp_line
			(start -0.3048 0.9906)
			(end 0.3048 0.9906)
			(stroke
				(width 0.1)
				(type default)
			)
			(layer "F.Fab")
		)
		(fp_line
			(start 0.3048 0.9906)
			(end 0.3048 -0.1016)
			(stroke
				(width 0.1)
				(type default)
			)
			(layer "F.Fab")
		)
		(fp_line
			(start -0.3048 -0.1016)
			(end -0.3048 0.9906)
			(stroke
				(width 0.1)
				(type default)
			)
			(layer "F.Fab")
		)
		(fp_line
			(start 0.3048 -0.1016)
			(end -0.3048 -0.1016)
			(stroke
				(width 0.1)
				(type default)
			)
			(layer "F.Fab")
		)
		(pad "1" smd rect
			(at 0 0 270)
			(size 0.508 0.508)
			(layers "F.Cu" "F.Mask" "F.Paste")
			(net "VR_PVCCIN_CPU0_VDD")
		)
		(pad "2" smd rect
			(at 0 0.889 270)
			(size 0.508 0.508)
			(layers "F.Cu" "F.Mask" "F.Paste")
			(net "GND")
		)
		(zone
			(layer "F.Cu")
			(hatch none 0.5)
			(connect_pads
				(clearance 0)
			)
			(min_thickness 0.25)
			(keepout
				(tracks not_allowed)
				(vias allowed)
				(pads allowed)
				(copperpour not_allowed)
				(footprints allowed)
			)
			(placement
				(enabled no)
				(sheetname "")
			)
			(fill
				(thermal_gap 0.5)
				(thermal_bridge_width 0.5)
				(island_removal_mode 0)
			)
			(polygon
				(pts
					(xy 180.4797 -76.77785) (xy 180.4797 -76.26985) (xy 180.8607 -76.26985) (xy 180.8607 -76.77785)
				)
			)
		)
		(zone
			(layer "F.Cu")
			(hatch none 0.5)
			(connect_pads
				(clearance 0)
			)
			(min_thickness 0.25)
			(keepout
				(tracks allowed)
				(vias not_allowed)
				(pads allowed)
				(copperpour not_allowed)
				(footprints allowed)
			)
			(placement
				(enabled no)
				(sheetname "")
			)
			(fill
				(thermal_gap 0.5)
				(thermal_bridge_width 0.5)
				(island_removal_mode 0)
			)
			(polygon
				(pts
					(xy 180.8607 -76.77785) (xy 180.8607 -76.26985) (xy 180.4797 -76.26985) (xy 180.4797 -76.77785)
				)
			)
		)
	)
	(footprint ""
		(layer "F.Cu")
		(at 407.399236 -47.889414 180)
		(property "Reference" "R25W66"
			(at -0.8382 -0.67818 180)
			(unlocked yes)
			(layer "F.SilkS")
			(effects
				(font
					(size 0.4064 0.254)
					(thickness 0.1524)
				)
				(justify left)
			)
		)
		(property "Value" ""
			(at 0 0 180)
			(layer "F.Fab")
			(effects
				(font
					(size 1.27 1.27)
				)
			)
		)
		(duplicate_pad_numbers_are_jumpers no)
		(fp_poly
			(pts
				(xy -0.2794 -0.1016) (xy 0.2794 -0.1016) (xy 0.2794 0.9906) (xy -0.2794 0.9906)
			)
			(stroke
				(width 0)
				(type default)
			)
			(fill no)
			(layer "F.CrtYd")
		)
		(fp_line
			(start 0.2794 0.9906)
			(end 0.2794 -0.1016)
			(stroke
				(width 0.1)
				(type default)
			)
			(layer "F.Fab")
		)
		(fp_line
			(start 0.2794 -0.1016)
			(end -0.2794 -0.1016)
			(stroke
				(width 0.1)
				(type default)
			)
			(layer "F.Fab")
		)
		(fp_line
			(start -0.2794 0.9906)
			(end 0.2794 0.9906)
			(stroke
				(width 0.1)
				(type default)
			)
			(layer "F.Fab")
		)
		(fp_line
			(start -0.2794 -0.1016)
			(end -0.2794 0.9906)
			(stroke
				(width 0.1)
				(type default)
			)
			(layer "F.Fab")
		)
		(pad "1" smd rect
			(at 0 0 180)
			(size 0.508 0.508)
			(layers "F.Cu" "F.Mask" "F.Paste")
			(net "CLK_24M_BMC_LPC")
		)
		(pad "2" smd rect
			(at 0 0.889 180)
			(size 0.508 0.508)
			(layers "F.Cu" "F.Mask" "F.Paste")
			(net "GND")
		)
		(zone
			(layer "F.Cu")
			(hatch none 0.5)
			(connect_pads
				(clearance 0)
			)
			(min_thickness 0.25)
			(keepout
				(tracks not_allowed)
				(vias allowed)
				(pads allowed)
				(copperpour not_allowed)
				(footprints allowed)
			)
			(placement
				(enabled no)
				(sheetname "")
			)
			(fill
				(thermal_gap 0.5)
				(thermal_bridge_width 0.5)
				(island_removal_mode 0)
			)
			(polygon
				(pts
					(xy 407.653236 -48.524414) (xy 407.145236 -48.524414) (xy 407.145236 -48.143414) (xy 407.653236 -48.143414)
				)
			)
		)
		(zone
			(layer "F.Cu")
			(hatch none 0.5)
			(connect_pads
				(clearance 0)
			)
			(min_thickness 0.25)
			(keepout
				(tracks allowed)
				(vias not_allowed)
				(pads allowed)
				(copperpour not_allowed)
				(footprints allowed)
			)
			(placement
				(enabled no)
				(sheetname "")
			)
			(fill
				(thermal_gap 0.5)
				(thermal_bridge_width 0.5)
				(island_removal_mode 0)
			)
			(polygon
				(pts
					(xy 407.653236 -48.143414) (xy 407.145236 -48.143414) (xy 407.145236 -48.524414) (xy 407.653236 -48.524414)
				)
			)
		)
	)
	(footprint ""
		(layer "F.Cu")
		(at 100.67544 -77.636116)
		(property "Reference" "C2D25"
			(at 0 0 0)
			(layer "F.SilkS")
			(hide yes)
			(effects
				(font
					(size 1.27 1.27)
				)
			)
		)
		(property "Value" ""
			(at 0 0 0)
			(layer "F.Fab")
			(effects
				(font
					(size 1.27 1.27)
				)
			)
		)
		(duplicate_pad_numbers_are_jumpers no)
		(fp_poly
			(pts
				(xy -0.4953 -0.2032) (xy 0.4953 -0.2032) (xy 0.4953 1.6002) (xy -0.4953 1.6002)
			)
			(stroke
				(width 0)
				(type default)
			)
			(fill no)
			(layer "F.CrtYd")
		)
		(fp_line
			(start -0.4953 -0.2032)
			(end 0.4953 -0.2032)
			(stroke
				(width 0.1)
				(type default)
			)
			(layer "F.Fab")
		)
		(fp_line
			(start -0.4953 1.6002)
			(end -0.4953 -0.2032)
			(stroke
				(width 0.1)
				(type default)
			)
			(layer "F.Fab")
		)
		(fp_line
			(start 0.4953 -0.2032)
			(end 0.4953 1.6002)
			(stroke
				(width 0.1)
				(type default)
			)
			(layer "F.Fab")
		)
		(fp_line
			(start 0.4953 1.6002)
			(end -0.4953 1.6002)
			(stroke
				(width 0.1)
				(type default)
			)
			(layer "F.Fab")
		)
		(pad "1" smd rect
			(at 0 0)
			(size 0.762 0.889)
			(layers "F.Cu" "F.Mask" "F.Paste")
			(net "PVCCIN_CPU1")
		)
		(pad "2" smd rect
			(at 0 1.397)
			(size 0.762 0.889)
			(layers "F.Cu" "F.Mask" "F.Paste")
			(net "GND")
		)
		(zone
			(layer "F.Cu")
			(hatch none 0.5)
			(connect_pads
				(clearance 0)
			)
			(min_thickness 0.25)
			(keepout
				(tracks not_allowed)
				(vias allowed)
				(pads allowed)
				(copperpour not_allowed)
				(footprints allowed)
			)
			(placement
				(enabled no)
				(sheetname "")
			)
			(fill
				(thermal_gap 0.5)
				(thermal_bridge_width 0.5)
				(island_removal_mode 0)
			)
			(polygon
				(pts
					(xy 100.29444 -77.191616) (xy 101.05644 -77.191616) (xy 101.05644 -76.683616) (xy 100.29444 -76.683616)
				)
			)
		)
	)
	(footprint ""
		(layer "F.Cu")
		(at 18.288 -98.7044 -90)
		(property "Reference" "R1C16"
			(at 0 0 270)
			(layer "F.SilkS")
			(hide yes)
			(effects
				(font
					(size 1.27 1.27)
				)
			)
		)
		(property "Value" ""
			(at 0 0 270)
			(layer "F.Fab")
			(effects
				(font
					(size 1.27 1.27)
				)
			)
		)
		(duplicate_pad_numbers_are_jumpers no)
		(fp_poly
			(pts
				(xy -0.2794 -0.1016) (xy 0.2794 -0.1016) (xy 0.2794 0.9906) (xy -0.2794 0.9906)
			)
			(stroke
				(width 0)
				(type default)
			)
			(fill no)
			(layer "F.CrtYd")
		)
		(fp_line
			(start -0.2794 0.9906)
			(end 0.2794 0.9906)
			(stroke
				(width 0.1)
				(type default)
			)
			(layer "F.Fab")
		)
		(fp_line
			(start 0.2794 0.9906)
			(end 0.2794 -0.1016)
			(stroke
				(width 0.1)
				(type default)
			)
			(layer "F.Fab")
		)
		(fp_line
			(start -0.2794 -0.1016)
			(end -0.2794 0.9906)
			(stroke
				(width 0.1)
				(type default)
			)
			(layer "F.Fab")
		)
		(fp_line
			(start 0.2794 -0.1016)
			(end -0.2794 -0.1016)
			(stroke
				(width 0.1)
				(type default)
			)
			(layer "F.Fab")
		)
		(pad "1" smd rect
			(at 0 0 270)
			(size 0.508 0.508)
			(layers "F.Cu" "F.Mask" "F.Paste")
			(net "VR_PVCCIN_CPU1_AVINSEN")
		)
		(pad "2" smd rect
			(at 0 0.889 270)
			(size 0.508 0.508)
			(layers "F.Cu" "F.Mask" "F.Paste")
			(net "GND")
		)
		(zone
			(layer "F.Cu")
			(hatch none 0.5)
			(connect_pads
				(clearance 0)
			)
			(min_thickness 0.25)
			(keepout
				(tracks not_allowed)
				(vias allowed)
				(pads allowed)
				(copperpour not_allowed)
				(footprints allowed)
			)
			(placement
				(enabled no)
				(sheetname "")
			)
			(fill
				(thermal_gap 0.5)
				(thermal_bridge_width 0.5)
				(island_removal_mode 0)
			)
			(polygon
				(pts
					(xy 17.653 -98.9584) (xy 17.653 -98.4504) (xy 18.034 -98.4504) (xy 18.034 -98.9584)
				)
			)
		)
		(zone
			(layer "F.Cu")
			(hatch none 0.5)
			(connect_pads
				(clearance 0)
			)
			(min_thickness 0.25)
			(keepout
				(tracks allowed)
				(vias not_allowed)
				(pads allowed)
				(copperpour not_allowed)
				(footprints allowed)
			)
			(placement
				(enabled no)
				(sheetname "")
			)
			(fill
				(thermal_gap 0.5)
				(thermal_bridge_width 0.5)
				(island_removal_mode 0)
			)
			(polygon
				(pts
					(xy 18.034 -98.9584) (xy 18.034 -98.4504) (xy 17.653 -98.4504) (xy 17.653 -98.9584)
				)
			)
		)
	)
	(footprint ""
		(layer "F.Cu")
		(at 457.0095 -30.48 90)
		(property "Reference" "R9F52"
			(at 0 0 90)
			(layer "F.SilkS")
			(hide yes)
			(effects
				(font
					(size 1.27 1.27)
				)
			)
		)
		(property "Value" ""
			(at 0 0 90)
			(layer "F.Fab")
			(effects
				(font
					(size 1.27 1.27)
				)
			)
		)
		(duplicate_pad_numbers_are_jumpers no)
		(fp_poly
			(pts
				(xy -0.2794 -0.1016) (xy 0.2794 -0.1016) (xy 0.2794 0.9906) (xy -0.2794 0.9906)
			)
			(stroke
				(width 0)
				(type default)
			)
			(fill no)
			(layer "F.CrtYd")
		)
		(fp_line
			(start 0.2794 -0.1016)
			(end -0.2794 -0.1016)
			(stroke
				(width 0.1)
				(type default)
			)
			(layer "F.Fab")
		)
		(fp_line
			(start -0.2794 -0.1016)
			(end -0.2794 0.9906)
			(stroke
				(width 0.1)
				(type default)
			)
			(layer "F.Fab")
		)
		(fp_line
			(start 0.2794 0.9906)
			(end 0.2794 -0.1016)
			(stroke
				(width 0.1)
				(type default)
			)
			(layer "F.Fab")
		)
		(fp_line
			(start -0.2794 0.9906)
			(end 0.2794 0.9906)
			(stroke
				(width 0.1)
				(type default)
			)
			(layer "F.Fab")
		)
		(pad "1" smd rect
			(at 0 0 90)
			(size 0.508 0.508)
			(layers "F.Cu" "F.Mask" "F.Paste")
			(net "P3V3_STBY")
		)
		(pad "2" smd rect
			(at 0 0.889 90)
			(size 0.508 0.508)
			(layers "F.Cu" "F.Mask" "F.Paste")
			(net "FM_BMC_FAULT_LED")
		)
		(zone
			(layer "F.Cu")
			(hatch none 0.5)
			(connect_pads
				(clearance 0)
			)
			(min_thickness 0.25)
			(keepout
				(tracks allowed)
				(vias not_allowed)
				(pads allowed)
				(copperpour not_allowed)
				(footprints allowed)
			)
			(placement
				(enabled no)
				(sheetname "")
			)
			(fill
				(thermal_gap 0.5)
				(thermal_bridge_width 0.5)
				(island_removal_mode 0)
			)
			(polygon
				(pts
					(xy 457.2635 -30.226) (xy 457.2635 -30.734) (xy 457.6445 -30.734) (xy 457.6445 -30.226)
				)
			)
		)
		(zone
			(layer "F.Cu")
			(hatch none 0.5)
			(connect_pads
				(clearance 0)
			)
			(min_thickness 0.25)
			(keepout
				(tracks not_allowed)
				(vias allowed)
				(pads allowed)
				(copperpour not_allowed)
				(footprints allowed)
			)
			(placement
				(enabled no)
				(sheetname "")
			)
			(fill
				(thermal_gap 0.5)
				(thermal_bridge_width 0.5)
				(island_removal_mode 0)
			)
			(polygon
				(pts
					(xy 457.6445 -30.226) (xy 457.6445 -30.734) (xy 457.2635 -30.734) (xy 457.2635 -30.226)
				)
			)
		)
	)
	(footprint ""
		(layer "F.Cu")
		(at 339.222588 -119.211598 90)
		(property "Reference" "C6B17"
			(at -0.8382 -0.67818 90)
			(unlocked yes)
			(layer "F.SilkS")
			(effects
				(font
					(size 0.4064 0.254)
					(thickness 0.1524)
				)
				(justify left)
			)
		)
		(property "Value" ""
			(at 0 0 90)
			(layer "F.Fab")
			(effects
				(font
					(size 1.27 1.27)
				)
			)
		)
		(duplicate_pad_numbers_are_jumpers no)
		(fp_poly
			(pts
				(xy 0.3048 -0.1016) (xy 0.3048 0.9906) (xy -0.3048 0.9906) (xy -0.3048 -0.1016)
			)
			(stroke
				(width 0)
				(type default)
			)
			(fill no)
			(layer "F.CrtYd")
		)
		(fp_line
			(start 0.3048 -0.1016)
			(end -0.3048 -0.1016)
			(stroke
				(width 0.1)
				(type default)
			)
			(layer "F.Fab")
		)
		(fp_line
			(start -0.3048 -0.1016)
			(end -0.3048 0.9906)
			(stroke
				(width 0.1)
				(type default)
			)
			(layer "F.Fab")
		)
		(fp_line
			(start 0.3048 0.9906)
			(end 0.3048 -0.1016)
			(stroke
				(width 0.1)
				(type default)
			)
			(layer "F.Fab")
		)
		(fp_line
			(start -0.3048 0.9906)
			(end 0.3048 0.9906)
			(stroke
				(width 0.1)
				(type default)
			)
			(layer "F.Fab")
		)
		(pad "1" smd rect
			(at 0 0 90)
			(size 0.508 0.508)
			(layers "F.Cu" "F.Mask" "F.Paste")
			(net "P3E_CPU0_PE1_PCH_TXN<9>")
		)
		(pad "2" smd rect
			(at 0 0.889 90)
			(size 0.508 0.508)
			(layers "F.Cu" "F.Mask" "F.Paste")
			(net "P3E_CPU0_PE1_PCH_C_TXN<9>")
		)
		(zone
			(layer "F.Cu")
			(hatch none 0.5)
			(connect_pads
				(clearance 0)
			)
			(min_thickness 0.25)
			(keepout
				(tracks allowed)
				(vias not_allowed)
				(pads allowed)
				(copperpour not_allowed)
				(footprints allowed)
			)
			(placement
				(enabled no)
				(sheetname "")
			)
			(fill
				(thermal_gap 0.5)
				(thermal_bridge_width 0.5)
				(island_removal_mode 0)
			)
			(polygon
				(pts
					(xy 339.476588 -118.957598) (xy 339.476588 -119.465598) (xy 339.857588 -119.465598) (xy 339.857588 -118.957598)
				)
			)
		)
		(zone
			(layer "F.Cu")
			(hatch none 0.5)
			(connect_pads
				(clearance 0)
			)
			(min_thickness 0.25)
			(keepout
				(tracks not_allowed)
				(vias allowed)
				(pads allowed)
				(copperpour not_allowed)
				(footprints allowed)
			)
			(placement
				(enabled no)
				(sheetname "")
			)
			(fill
				(thermal_gap 0.5)
				(thermal_bridge_width 0.5)
				(island_removal_mode 0)
			)
			(polygon
				(pts
					(xy 339.857588 -118.957598) (xy 339.857588 -119.465598) (xy 339.476588 -119.465598) (xy 339.476588 -118.957598)
				)
			)
		)
	)
	(footprint ""
		(layer "F.Cu")
		(at 369.2906 -100.2284 180)
		(property "Reference" "C7C13"
			(at 0 0 180)
			(layer "F.SilkS")
			(hide yes)
			(effects
				(font
					(size 1.27 1.27)
				)
			)
		)
		(property "Value" ""
			(at 0 0 180)
			(layer "F.Fab")
			(effects
				(font
					(size 1.27 1.27)
				)
			)
		)
		(duplicate_pad_numbers_are_jumpers no)
		(fp_poly
			(pts
				(xy 0.3048 -0.1016) (xy 0.3048 0.9906) (xy -0.3048 0.9906) (xy -0.3048 -0.1016)
			)
			(stroke
				(width 0)
				(type default)
			)
			(fill no)
			(layer "F.CrtYd")
		)
		(fp_line
			(start 0.3048 0.9906)
			(end 0.3048 -0.1016)
			(stroke
				(width 0.1)
				(type default)
			)
			(layer "F.Fab")
		)
		(fp_line
			(start 0.3048 -0.1016)
			(end -0.3048 -0.1016)
			(stroke
				(width 0.1)
				(type default)
			)
			(layer "F.Fab")
		)
		(fp_line
			(start -0.3048 0.9906)
			(end 0.3048 0.9906)
			(stroke
				(width 0.1)
				(type default)
			)
			(layer "F.Fab")
		)
		(fp_line
			(start -0.3048 -0.1016)
			(end -0.3048 0.9906)
			(stroke
				(width 0.1)
				(type default)
			)
			(layer "F.Fab")
		)
		(pad "1" smd rect
			(at 0 0 180)
			(size 0.508 0.508)
			(layers "F.Cu" "F.Mask" "F.Paste")
			(net "XTAL_33K_RTC1")
		)
		(pad "2" smd rect
			(at 0 0.889 180)
			(size 0.508 0.508)
			(layers "F.Cu" "F.Mask" "F.Paste")
			(net "GND")
		)
		(zone
			(layer "F.Cu")
			(hatch none 0.5)
			(connect_pads
				(clearance 0)
			)
			(min_thickness 0.25)
			(keepout
				(tracks not_allowed)
				(vias allowed)
				(pads allowed)
				(copperpour not_allowed)
				(footprints allowed)
			)
			(placement
				(enabled no)
				(sheetname "")
			)
			(fill
				(thermal_gap 0.5)
				(thermal_bridge_width 0.5)
				(island_removal_mode 0)
			)
			(polygon
				(pts
					(xy 369.5446 -100.8634) (xy 369.0366 -100.8634) (xy 369.0366 -100.4824) (xy 369.5446 -100.4824)
				)
			)
		)
		(zone
			(layer "F.Cu")
			(hatch none 0.5)
			(connect_pads
				(clearance 0)
			)
			(min_thickness 0.25)
			(keepout
				(tracks allowed)
				(vias not_allowed)
				(pads allowed)
				(copperpour not_allowed)
				(footprints allowed)
			)
			(placement
				(enabled no)
				(sheetname "")
			)
			(fill
				(thermal_gap 0.5)
				(thermal_bridge_width 0.5)
				(island_removal_mode 0)
			)
			(polygon
				(pts
					(xy 369.5446 -100.4824) (xy 369.0366 -100.4824) (xy 369.0366 -100.8634) (xy 369.5446 -100.8634)
				)
			)
		)
	)
	(footprint ""
		(layer "F.Cu")
		(at 423.650664 -13.872464 180)
		(property "Reference" "R6W41"
			(at -0.8382 -0.67818 180)
			(unlocked yes)
			(layer "F.SilkS")
			(effects
				(font
					(size 0.4064 0.254)
					(thickness 0.1524)
				)
				(justify left)
			)
		)
		(property "Value" ""
			(at 0 0 180)
			(layer "F.Fab")
			(effects
				(font
					(size 1.27 1.27)
				)
			)
		)
		(duplicate_pad_numbers_are_jumpers no)
		(fp_poly
			(pts
				(xy -0.2794 -0.1016) (xy 0.2794 -0.1016) (xy 0.2794 0.9906) (xy -0.2794 0.9906)
			)
			(stroke
				(width 0)
				(type default)
			)
			(fill no)
			(layer "F.CrtYd")
		)
		(fp_line
			(start 0.2794 0.9906)
			(end 0.2794 -0.1016)
			(stroke
				(width 0.1)
				(type default)
			)
			(layer "F.Fab")
		)
		(fp_line
			(start 0.2794 -0.1016)
			(end -0.2794 -0.1016)
			(stroke
				(width 0.1)
				(type default)
			)
			(layer "F.Fab")
		)
		(fp_line
			(start -0.2794 0.9906)
			(end 0.2794 0.9906)
			(stroke
				(width 0.1)
				(type default)
			)
			(layer "F.Fab")
		)
		(fp_line
			(start -0.2794 -0.1016)
			(end -0.2794 0.9906)
			(stroke
				(width 0.1)
				(type default)
			)
			(layer "F.Fab")
		)
		(pad "1" smd rect
			(at 0 0 180)
			(size 0.508 0.508)
			(layers "F.Cu" "F.Mask" "F.Paste")
			(net "P3V3_STBY")
		)
		(pad "2" smd rect
			(at 0 0.889 180)
			(size 0.508 0.508)
			(layers "F.Cu" "F.Mask" "F.Paste")
			(net "PCA9554_INT_N")
		)
		(zone
			(layer "F.Cu")
			(hatch none 0.5)
			(connect_pads
				(clearance 0)
			)
			(min_thickness 0.25)
			(keepout
				(tracks not_allowed)
				(vias allowed)
				(pads allowed)
				(copperpour not_allowed)
				(footprints allowed)
			)
			(placement
				(enabled no)
				(sheetname "")
			)
			(fill
				(thermal_gap 0.5)
				(thermal_bridge_width 0.5)
				(island_removal_mode 0)
			)
			(polygon
				(pts
					(xy 423.904664 -14.507464) (xy 423.396664 -14.507464) (xy 423.396664 -14.126464) (xy 423.904664 -14.126464)
				)
			)
		)
		(zone
			(layer "F.Cu")
			(hatch none 0.5)
			(connect_pads
				(clearance 0)
			)
			(min_thickness 0.25)
			(keepout
				(tracks allowed)
				(vias not_allowed)
				(pads allowed)
				(copperpour not_allowed)
				(footprints allowed)
			)
			(placement
				(enabled no)
				(sheetname "")
			)
			(fill
				(thermal_gap 0.5)
				(thermal_bridge_width 0.5)
				(island_removal_mode 0)
			)
			(polygon
				(pts
					(xy 423.904664 -14.126464) (xy 423.396664 -14.126464) (xy 423.396664 -14.507464) (xy 423.904664 -14.507464)
				)
			)
		)
	)
	(footprint ""
		(layer "F.Cu")
		(at 386.1054 1.651 -90)
		(property "Reference" "R7G22"
			(at 0 0 270)
			(layer "F.SilkS")
			(hide yes)
			(effects
				(font
					(size 1.27 1.27)
				)
			)
		)
		(property "Value" ""
			(at 0 0 270)
			(layer "F.Fab")
			(effects
				(font
					(size 1.27 1.27)
				)
			)
		)
		(duplicate_pad_numbers_are_jumpers no)
		(fp_poly
			(pts
				(xy -0.2794 -0.1016) (xy 0.2794 -0.1016) (xy 0.2794 0.9906) (xy -0.2794 0.9906)
			)
			(stroke
				(width 0)
				(type default)
			)
			(fill no)
			(layer "F.CrtYd")
		)
		(fp_line
			(start -0.2794 0.9906)
			(end 0.2794 0.9906)
			(stroke
				(width 0.1)
				(type default)
			)
			(layer "F.Fab")
		)
		(fp_line
			(start 0.2794 0.9906)
			(end 0.2794 -0.1016)
			(stroke
				(width 0.1)
				(type default)
			)
			(layer "F.Fab")
		)
		(fp_line
			(start -0.2794 -0.1016)
			(end -0.2794 0.9906)
			(stroke
				(width 0.1)
				(type default)
			)
			(layer "F.Fab")
		)
		(fp_line
			(start 0.2794 -0.1016)
			(end -0.2794 -0.1016)
			(stroke
				(width 0.1)
				(type default)
			)
			(layer "F.Fab")
		)
		(pad "1" smd rect
			(at 0 0 270)
			(size 0.508 0.508)
			(layers "F.Cu" "F.Mask" "F.Paste")
			(net "P3V3_STBY")
		)
		(pad "2" smd rect
			(at 0 0.889 270)
			(size 0.508 0.508)
			(layers "F.Cu" "F.Mask" "F.Paste")
			(net "JTAG_TDO_R")
		)
		(zone
			(layer "F.Cu")
			(hatch none 0.5)
			(connect_pads
				(clearance 0)
			)
			(min_thickness 0.25)
			(keepout
				(tracks not_allowed)
				(vias allowed)
				(pads allowed)
				(copperpour not_allowed)
				(footprints allowed)
			)
			(placement
				(enabled no)
				(sheetname "")
			)
			(fill
				(thermal_gap 0.5)
				(thermal_bridge_width 0.5)
				(island_removal_mode 0)
			)
			(polygon
				(pts
					(xy 385.4704 1.397) (xy 385.4704 1.905) (xy 385.8514 1.905) (xy 385.8514 1.397)
				)
			)
		)
		(zone
			(layer "F.Cu")
			(hatch none 0.5)
			(connect_pads
				(clearance 0)
			)
			(min_thickness 0.25)
			(keepout
				(tracks allowed)
				(vias not_allowed)
				(pads allowed)
				(copperpour not_allowed)
				(footprints allowed)
			)
			(placement
				(enabled no)
				(sheetname "")
			)
			(fill
				(thermal_gap 0.5)
				(thermal_bridge_width 0.5)
				(island_removal_mode 0)
			)
			(polygon
				(pts
					(xy 385.8514 1.397) (xy 385.8514 1.905) (xy 385.4704 1.905) (xy 385.4704 1.397)
				)
			)
		)
	)
	(footprint ""
		(layer "F.Cu")
		(at 344.678 -15.367 -90)
		(property "Reference" "EU7G1"
			(at 1.27 4.03733 90)
			(unlocked yes)
			(layer "F.SilkS")
			(effects
				(font
					(size 0.7874 0.5842)
					(thickness 0.1524)
				)
				(justify left)
			)
		)
		(property "Value" ""
			(at 0 0 270)
			(layer "F.Fab")
			(effects
				(font
					(size 1.27 1.27)
				)
			)
		)
		(duplicate_pad_numbers_are_jumpers no)
		(fp_line
			(start -3.0607 3.0607)
			(end -3.0607 -3.0607)
			(stroke
				(width 0.1524)
				(type default)
			)
			(layer "F.SilkS")
		)
		(fp_line
			(start 3.0607 3.0607)
			(end -3.0607 3.0607)
			(stroke
				(width 0.1524)
				(type default)
			)
			(layer "F.SilkS")
		)
		(fp_line
			(start -2.549906 2.549906)
			(end -2.549906 2.267204)
			(stroke
				(width 0.1524)
				(type default)
			)
			(layer "F.SilkS")
		)
		(fp_line
			(start -2.277618 2.549906)
			(end -2.549906 2.549906)
			(stroke
				(width 0.1524)
				(type default)
			)
			(layer "F.SilkS")
		)
		(fp_line
			(start 2.549906 2.549906)
			(end 2.249678 2.549906)
			(stroke
				(width 0.1524)
				(type default)
			)
			(layer "F.SilkS")
		)
		(fp_line
			(start 2.549906 2.233422)
			(end 2.549906 2.549906)
			(stroke
				(width 0.1524)
				(type default)
			)
			(layer "F.SilkS")
		)
		(fp_line
			(start -2.549906 -2.29362)
			(end -2.549906 -2.549906)
			(stroke
				(width 0.1524)
				(type default)
			)
			(layer "F.SilkS")
		)
		(fp_line
			(start -2.549906 -2.549906)
			(end -2.249678 -2.549906)
			(stroke
				(width 0.1524)
				(type default)
			)
			(layer "F.SilkS")
		)
		(fp_line
			(start 2.245614 -2.549906)
			(end 2.549906 -2.549906)
			(stroke
				(width 0.1524)
				(type default)
			)
			(layer "F.SilkS")
		)
		(fp_line
			(start 2.549906 -2.549906)
			(end 2.549906 -2.258314)
			(stroke
				(width 0.1524)
				(type default)
			)
			(layer "F.SilkS")
		)
		(fp_line
			(start -3.0607 -3.0607)
			(end 3.0607 -3.0607)
			(stroke
				(width 0.1524)
				(type default)
			)
			(layer "F.SilkS")
		)
		(fp_line
			(start 3.0607 -3.0607)
			(end 3.0607 3.0607)
			(stroke
				(width 0.1524)
				(type default)
			)
			(layer "F.SilkS")
		)
		(fp_circle
			(center -3.237738 -2.256536)
			(end -3.237738 -2.383536)
			(stroke
				(width 0.254)
				(type default)
			)
			(fill no)
			(layer "F.SilkS")
		)
		(fp_poly
			(pts
				(xy -3.0607 -3.0607) (xy -3.0607 -2.0193) (xy -2.0193 -3.0607)
			)
			(stroke
				(width 0)
				(type default)
			)
			(fill yes)
			(layer "F.SilkS")
		)
		(fp_rect
			(start -1.8415 1.8415)
			(end 1.8415 -1.8415)
			(stroke
				(width 0)
				(type default)
			)
			(fill yes)
			(layer "F.Paste")
		)
		(fp_rect
			(start -2.549906 2.549906)
			(end 2.549906 -2.549906)
			(stroke
				(width 0)
				(type default)
			)
			(fill no)
			(layer "F.CrtYd")
		)
		(fp_line
			(start -2.549906 2.549906)
			(end -2.549906 -2.549906)
			(stroke
				(width 0.1)
				(type default)
			)
			(layer "F.Fab")
		)
		(fp_line
			(start 2.549906 2.549906)
			(end -2.549906 2.549906)
			(stroke
				(width 0.1)
				(type default)
			)
			(layer "F.Fab")
		)
		(fp_line
			(start -2.549906 -2.549906)
			(end 2.549906 -2.549906)
			(stroke
				(width 0.1)
				(type default)
			)
			(layer "F.Fab")
		)
		(fp_line
			(start 2.549906 -2.549906)
			(end 2.549906 2.549906)
			(stroke
				(width 0.1)
				(type default)
			)
			(layer "F.Fab")
		)
		(fp_circle
			(center -3.237738 -2.256536)
			(end -3.237738 -2.383536)
			(stroke
				(width 0.254)
				(type default)
			)
			(fill no)
			(layer "F.Fab")
		)
		(pad "1" smd custom
			(at -2.4511 -1.800098 270)
			(size 0.0508 0.0508)
			(layers "F.Cu" "F.Mask" "F.Paste")
			(net "Net_281")
			(options
				(clearance outline)
				(anchor circle)
			)
			(primitives
				(gr_poly
					(pts
						(arc
							(start 0.254 -0.1016)
							(mid 0.3556 0)
							(end 0.254 0.1016)
						)
						(xy -0.3556 0.1016) (xy -0.3556 -0.1016)
					)
					(width 0)
					(fill yes)
				)
			)
		)
		(pad "2" smd custom
			(at -2.4511 -1.400048 270)
			(size 0.0508 0.0508)
			(layers "F.Cu" "F.Mask" "F.Paste")
			(net "Net_345")
			(options
				(clearance outline)
				(anchor circle)
			)
			(primitives
				(gr_poly
					(pts
						(arc
							(start 0.254 -0.1016)
							(mid 0.3556 0)
							(end 0.254 0.1016)
						)
						(xy -0.3556 0.1016) (xy -0.3556 -0.1016)
					)
					(width 0)
					(fill yes)
				)
			)
		)
		(pad "3" smd custom
			(at -2.4511 -0.999998 270)
			(size 0.0508 0.0508)
			(layers "F.Cu" "F.Mask" "F.Paste")
			(net "Net_242")
			(options
				(clearance outline)
				(anchor circle)
			)
			(primitives
				(gr_poly
					(pts
						(arc
							(start 0.254 -0.1016)
							(mid 0.3556 0)
							(end 0.254 0.1016)
						)
						(xy -0.3556 0.1016) (xy -0.3556 -0.1016)
					)
					(width 0)
					(fill yes)
				)
			)
		)
		(pad "4" smd custom
			(at -2.4511 -0.599948 270)
			(size 0.0508 0.0508)
			(layers "F.Cu" "F.Mask" "F.Paste")
			(net "VR_PVDDQ_ABC_PWM2")
			(options
				(clearance outline)
				(anchor circle)
			)
			(primitives
				(gr_poly
					(pts
						(arc
							(start 0.254 -0.1016)
							(mid 0.3556 0)
							(end 0.254 0.1016)
						)
						(xy -0.3556 0.1016) (xy -0.3556 -0.1016)
					)
					(width 0)
					(fill yes)
				)
			)
		)
		(pad "5" smd custom
			(at -2.4511 -0.199898 270)
			(size 0.0508 0.0508)
			(layers "F.Cu" "F.Mask" "F.Paste")
			(net "VR_PVDDQ_ABC_PWM1")
			(options
				(clearance outline)
				(anchor circle)
			)
			(primitives
				(gr_poly
					(pts
						(arc
							(start 0.254 -0.1016)
							(mid 0.3556 0)
							(end 0.254 0.1016)
						)
						(xy -0.3556 0.1016) (xy -0.3556 -0.1016)
					)
					(width 0)
					(fill yes)
				)
			)
		)
		(pad "6" smd custom
			(at -2.4511 0.199898 270)
			(size 0.0508 0.0508)
			(layers "F.Cu" "F.Mask" "F.Paste")
			(net "SMB_VR_STBY_LVC3_SDA")
			(options
				(clearance outline)
				(anchor circle)
			)
			(primitives
				(gr_poly
					(pts
						(arc
							(start 0.254 -0.1016)
							(mid 0.3556 0)
							(end 0.254 0.1016)
						)
						(xy -0.3556 0.1016) (xy -0.3556 -0.1016)
					)
					(width 0)
					(fill yes)
				)
			)
		)
		(pad "7" smd custom
			(at -2.4511 0.599948 270)
			(size 0.0508 0.0508)
			(layers "F.Cu" "F.Mask" "F.Paste")
			(net "SMB_VR_STBY_LVC3_SCL")
			(options
				(clearance outline)
				(anchor circle)
			)
			(primitives
				(gr_poly
					(pts
						(arc
							(start 0.254 -0.1016)
							(mid 0.3556 0)
							(end 0.254 0.1016)
						)
						(xy -0.3556 0.1016) (xy -0.3556 -0.1016)
					)
					(width 0)
					(fill yes)
				)
			)
		)
		(pad "8" smd custom
			(at -2.4511 0.999998 270)
			(size 0.0508 0.0508)
			(layers "F.Cu" "F.Mask" "F.Paste")
			(net "Net_282")
			(options
				(clearance outline)
				(anchor circle)
			)
			(primitives
				(gr_poly
					(pts
						(arc
							(start 0.254 -0.1016)
							(mid 0.3556 0)
							(end 0.254 0.1016)
						)
						(xy -0.3556 0.1016) (xy -0.3556 -0.1016)
					)
					(width 0)
					(fill yes)
				)
			)
		)
		(pad "9" smd custom
			(at -2.4511 1.400048 270)
			(size 0.0508 0.0508)
			(layers "F.Cu" "F.Mask" "F.Paste")
			(net "PWRGD_PVDDQ_ABC_R")
			(options
				(clearance outline)
				(anchor circle)
			)
			(primitives
				(gr_poly
					(pts
						(arc
							(start 0.254 -0.1016)
							(mid 0.3556 0)
							(end 0.254 0.1016)
						)
						(xy -0.3556 0.1016) (xy -0.3556 -0.1016)
					)
					(width 0)
					(fill yes)
				)
			)
		)
		(pad "10" smd custom
			(at -2.4511 1.800098 270)
			(size 0.0508 0.0508)
			(layers "F.Cu" "F.Mask" "F.Paste")
			(net "VR_PVDDQ_ABC_VREN")
			(options
				(clearance outline)
				(anchor circle)
			)
			(primitives
				(gr_poly
					(pts
						(arc
							(start 0.254 -0.1016)
							(mid 0.3556 0)
							(end 0.254 0.1016)
						)
						(xy -0.3556 0.1016) (xy -0.3556 -0.1016)
					)
					(width 0)
					(fill yes)
				)
			)
		)
		(pad "11" smd custom
			(at -1.800098 2.4511 270)
			(size 0.0508 0.0508)
			(layers "F.Cu" "F.Mask" "F.Paste")
			(net "IRQ_PVDDQ_ABC_VRHOT_LVT3_R_N")
			(options
				(clearance outline)
				(anchor circle)
			)
			(primitives
				(gr_poly
					(pts
						(arc
							(start -0.1016 -0.254)
							(mid 0 -0.3556)
							(end 0.1016 -0.254)
						)
						(xy 0.1016 0.3556) (xy -0.1016 0.3556)
					)
					(width 0)
					(fill yes)
				)
			)
		)
		(pad "12" smd custom
			(at -1.400048 2.4511 270)
			(size 0.0508 0.0508)
			(layers "F.Cu" "F.Mask" "F.Paste")
			(net "Net_221")
			(options
				(clearance outline)
				(anchor circle)
			)
			(primitives
				(gr_poly
					(pts
						(arc
							(start -0.1016 -0.254)
							(mid 0 -0.3556)
							(end 0.1016 -0.254)
						)
						(xy 0.1016 0.3556) (xy -0.1016 0.3556)
					)
					(width 0)
					(fill yes)
				)
			)
		)
		(pad "13" smd custom
			(at -0.999998 2.4511 270)
			(size 0.0508 0.0508)
			(layers "F.Cu" "F.Mask" "F.Paste")
			(net "PU_VR_PVDDQ_ABC_FAULT1")
			(options
				(clearance outline)
				(anchor circle)
			)
			(primitives
				(gr_poly
					(pts
						(arc
							(start -0.1016 -0.254)
							(mid 0 -0.3556)
							(end 0.1016 -0.254)
						)
						(xy 0.1016 0.3556) (xy -0.1016 0.3556)
					)
					(width 0)
					(fill yes)
				)
			)
		)
		(pad "14" smd custom
			(at -0.599948 2.4511 270)
			(size 0.0508 0.0508)
			(layers "F.Cu" "F.Mask" "F.Paste")
			(net "TP_PVDDQ_ABC_MP1")
			(options
				(clearance outline)
				(anchor circle)
			)
			(primitives
				(gr_poly
					(pts
						(arc
							(start -0.1016 -0.254)
							(mid 0 -0.3556)
							(end 0.1016 -0.254)
						)
						(xy 0.1016 0.3556) (xy -0.1016 0.3556)
					)
					(width 0)
					(fill yes)
				)
			)
		)
		(pad "15" smd custom
			(at -0.199898 2.4511 270)
			(size 0.0508 0.0508)
			(layers "F.Cu" "F.Mask" "F.Paste")
			(net "SVID_CLK_PVDDQ_ABC")
			(options
				(clearance outline)
				(anchor circle)
			)
			(primitives
				(gr_poly
					(pts
						(arc
							(start -0.1016 -0.254)
							(mid 0 -0.3556)
							(end 0.1016 -0.254)
						)
						(xy 0.1016 0.3556) (xy -0.1016 0.3556)
					)
					(width 0)
					(fill yes)
				)
			)
		)
		(pad "16" smd custom
			(at 0.199898 2.4511 270)
			(size 0.0508 0.0508)
			(layers "F.Cu" "F.Mask" "F.Paste")
			(net "SVID_VDIO_PVDDQ_ABC")
			(options
				(clearance outline)
				(anchor circle)
			)
			(primitives
				(gr_poly
					(pts
						(arc
							(start -0.1016 -0.254)
							(mid 0 -0.3556)
							(end 0.1016 -0.254)
						)
						(xy 0.1016 0.3556) (xy -0.1016 0.3556)
					)
					(width 0)
					(fill yes)
				)
			)
		)
		(pad "17" smd custom
			(at 0.599948 2.4511 270)
			(size 0.0508 0.0508)
			(layers "F.Cu" "F.Mask" "F.Paste")
			(net "SVID_ALERT_PVDDQ_ABC")
			(options
				(clearance outline)
				(anchor circle)
			)
			(primitives
				(gr_poly
					(pts
						(arc
							(start -0.1016 -0.254)
							(mid 0 -0.3556)
							(end 0.1016 -0.254)
						)
						(xy 0.1016 0.3556) (xy -0.1016 0.3556)
					)
					(width 0)
					(fill yes)
				)
			)
		)
		(pad "18" smd custom
			(at 0.999998 2.4511 270)
			(size 0.0508 0.0508)
			(layers "F.Cu" "F.Mask" "F.Paste")
			(net "TP_PVDDQ_ABC_MP2")
			(options
				(clearance outline)
				(anchor circle)
			)
			(primitives
				(gr_poly
					(pts
						(arc
							(start -0.1016 -0.254)
							(mid 0 -0.3556)
							(end 0.1016 -0.254)
						)
						(xy 0.1016 0.3556) (xy -0.1016 0.3556)
					)
					(width 0)
					(fill yes)
				)
			)
		)
		(pad "19" smd custom
			(at 1.400048 2.4511 270)
			(size 0.0508 0.0508)
			(layers "F.Cu" "F.Mask" "F.Paste")
			(net "VR_PVDDQ_ABC_AVSP")
			(options
				(clearance outline)
				(anchor circle)
			)
			(primitives
				(gr_poly
					(pts
						(arc
							(start -0.1016 -0.254)
							(mid 0 -0.3556)
							(end 0.1016 -0.254)
						)
						(xy 0.1016 0.3556) (xy -0.1016 0.3556)
					)
					(width 0)
					(fill yes)
				)
			)
		)
		(pad "20" smd custom
			(at 1.800098 2.4511 270)
			(size 0.0508 0.0508)
			(layers "F.Cu" "F.Mask" "F.Paste")
			(net "VSENSE_PVDDQ_ABC_N")
			(options
				(clearance outline)
				(anchor circle)
			)
			(primitives
				(gr_poly
					(pts
						(arc
							(start -0.1016 -0.254)
							(mid 0 -0.3556)
							(end 0.1016 -0.254)
						)
						(xy 0.1016 0.3556) (xy -0.1016 0.3556)
					)
					(width 0)
					(fill yes)
				)
			)
		)
		(pad "21" smd custom
			(at 2.4511 1.800098 270)
			(size 0.0508 0.0508)
			(layers "F.Cu" "F.Mask" "F.Paste")
			(net "VR_PVDDQ_ABC_AIREF1")
			(options
				(clearance outline)
				(anchor circle)
			)
			(primitives
				(gr_poly
					(pts
						(arc
							(start -0.254 0.1016)
							(mid -0.3556 0)
							(end -0.254 -0.1016)
						)
						(xy 0.3556 -0.1016) (xy 0.3556 0.1016)
					)
					(width 0)
					(fill yes)
				)
			)
		)
		(pad "22" smd custom
			(at 2.4511 1.400048 270)
			(size 0.0508 0.0508)
			(layers "F.Cu" "F.Mask" "F.Paste")
			(net "ISENSE_PVDDQ_ABC_PH1_IMON")
			(options
				(clearance outline)
				(anchor circle)
			)
			(primitives
				(gr_poly
					(pts
						(arc
							(start -0.254 0.1016)
							(mid -0.3556 0)
							(end -0.254 -0.1016)
						)
						(xy 0.3556 -0.1016) (xy 0.3556 0.1016)
					)
					(width 0)
					(fill yes)
				)
			)
		)
		(pad "23" smd custom
			(at 2.4511 0.999998 270)
			(size 0.0508 0.0508)
			(layers "F.Cu" "F.Mask" "F.Paste")
			(net "VR_PVDDQ_ABC_AIREF2")
			(options
				(clearance outline)
				(anchor circle)
			)
			(primitives
				(gr_poly
					(pts
						(arc
							(start -0.254 0.1016)
							(mid -0.3556 0)
							(end -0.254 -0.1016)
						)
						(xy 0.3556 -0.1016) (xy 0.3556 0.1016)
					)
					(width 0)
					(fill yes)
				)
			)
		)
		(pad "24" smd custom
			(at 2.4511 0.599948 270)
			(size 0.0508 0.0508)
			(layers "F.Cu" "F.Mask" "F.Paste")
			(net "ISENSE_PVDDQ_ABC_PH2_IMON")
			(options
				(clearance outline)
				(anchor circle)
			)
			(primitives
				(gr_poly
					(pts
						(arc
							(start -0.254 0.1016)
							(mid -0.3556 0)
							(end -0.254 -0.1016)
						)
						(xy 0.3556 -0.1016) (xy 0.3556 0.1016)
					)
					(width 0)
					(fill yes)
				)
			)
		)
		(pad "25" smd custom
			(at 2.4511 0.199898 270)
			(size 0.0508 0.0508)
			(layers "F.Cu" "F.Mask" "F.Paste")
			(net "Net_241")
			(options
				(clearance outline)
				(anchor circle)
			)
			(primitives
				(gr_poly
					(pts
						(arc
							(start -0.254 0.1016)
							(mid -0.3556 0)
							(end -0.254 -0.1016)
						)
						(xy 0.3556 -0.1016) (xy 0.3556 0.1016)
					)
					(width 0)
					(fill yes)
				)
			)
		)
		(pad "26" smd custom
			(at 2.4511 -0.199898 270)
			(size 0.0508 0.0508)
			(layers "F.Cu" "F.Mask" "F.Paste")
			(net "Net_240")
			(options
				(clearance outline)
				(anchor circle)
			)
			(primitives
				(gr_poly
					(pts
						(arc
							(start -0.254 0.1016)
							(mid -0.3556 0)
							(end -0.254 -0.1016)
						)
						(xy 0.3556 -0.1016) (xy 0.3556 0.1016)
					)
					(width 0)
					(fill yes)
				)
			)
		)
		(pad "27" smd custom
			(at 2.4511 -0.599948 270)
			(size 0.0508 0.0508)
			(layers "F.Cu" "F.Mask" "F.Paste")
			(net "GND")
			(options
				(clearance outline)
				(anchor circle)
			)
			(primitives
				(gr_poly
					(pts
						(arc
							(start -0.254 0.1016)
							(mid -0.3556 0)
							(end -0.254 -0.1016)
						)
						(xy 0.3556 -0.1016) (xy 0.3556 0.1016)
					)
					(width 0)
					(fill yes)
				)
			)
		)
		(pad "28" smd custom
			(at 2.4511 -0.999998 270)
			(size 0.0508 0.0508)
			(layers "F.Cu" "F.Mask" "F.Paste")
			(net "Net_346")
			(options
				(clearance outline)
				(anchor circle)
			)
			(primitives
				(gr_poly
					(pts
						(arc
							(start -0.254 0.1016)
							(mid -0.3556 0)
							(end -0.254 -0.1016)
						)
						(xy 0.3556 -0.1016) (xy 0.3556 0.1016)
					)
					(width 0)
					(fill yes)
				)
			)
		)
		(pad "29" smd custom
			(at 2.4511 -1.400048 270)
			(size 0.0508 0.0508)
			(layers "F.Cu" "F.Mask" "F.Paste")
			(net "Net_225")
			(options
				(clearance outline)
				(anchor circle)
			)
			(primitives
				(gr_poly
					(pts
						(arc
							(start -0.254 0.1016)
							(mid -0.3556 0)
							(end -0.254 -0.1016)
						)
						(xy 0.3556 -0.1016) (xy 0.3556 0.1016)
					)
					(width 0)
					(fill yes)
				)
			)
		)
		(pad "30" smd custom
			(at 2.4511 -1.800098 270)
			(size 0.0508 0.0508)
			(layers "F.Cu" "F.Mask" "F.Paste")
			(net "Net_224")
			(options
				(clearance outline)
				(anchor circle)
			)
			(primitives
				(gr_poly
					(pts
						(arc
							(start -0.254 0.1016)
							(mid -0.3556 0)
							(end -0.254 -0.1016)
						)
						(xy 0.3556 -0.1016) (xy 0.3556 0.1016)
					)
					(width 0)
					(fill yes)
				)
			)
		)
		(pad "31" smd custom
			(at 1.800098 -2.4511 270)
			(size 0.0508 0.0508)
			(layers "F.Cu" "F.Mask" "F.Paste")
			(net "Net_222")
			(options
				(clearance outline)
				(anchor circle)
			)
			(primitives
				(gr_poly
					(pts
						(arc
							(start 0.1016 0.254)
							(mid 0 0.3556)
							(end -0.1016 0.254)
						)
						(xy -0.1016 -0.3556) (xy 0.1016 -0.3556)
					)
					(width 0)
					(fill yes)
				)
			)
		)
		(pad "32" smd custom
			(at 1.400048 -2.4511 270)
			(size 0.0508 0.0508)
			(layers "F.Cu" "F.Mask" "F.Paste")
			(net "GND")
			(options
				(clearance outline)
				(anchor circle)
			)
			(primitives
				(gr_poly
					(pts
						(arc
							(start 0.1016 0.254)
							(mid 0 0.3556)
							(end -0.1016 0.254)
						)
						(xy -0.1016 -0.3556) (xy 0.1016 -0.3556)
					)
					(width 0)
					(fill yes)
				)
			)
		)
		(pad "33" smd custom
			(at 0.999998 -2.4511 270)
			(size 0.0508 0.0508)
			(layers "F.Cu" "F.Mask" "F.Paste")
			(net "VR_PVDDQ_ABC_XADDR2")
			(options
				(clearance outline)
				(anchor circle)
			)
			(primitives
				(gr_poly
					(pts
						(arc
							(start 0.1016 0.254)
							(mid 0 0.3556)
							(end -0.1016 0.254)
						)
						(xy -0.1016 -0.3556) (xy 0.1016 -0.3556)
					)
					(width 0)
					(fill yes)
				)
			)
		)
		(pad "34" smd custom
			(at 0.599948 -2.4511 270)
			(size 0.0508 0.0508)
			(layers "F.Cu" "F.Mask" "F.Paste")
			(net "Net_223")
			(options
				(clearance outline)
				(anchor circle)
			)
			(primitives
				(gr_poly
					(pts
						(arc
							(start 0.1016 0.254)
							(mid 0 0.3556)
							(end -0.1016 0.254)
						)
						(xy -0.1016 -0.3556) (xy 0.1016 -0.3556)
					)
					(width 0)
					(fill yes)
				)
			)
		)
		(pad "35" smd custom
			(at 0.199898 -2.4511 270)
			(size 0.0508 0.0508)
			(layers "F.Cu" "F.Mask" "F.Paste")
			(net "A_TSENSE_PVDDQ_ABC")
			(options
				(clearance outline)
				(anchor circle)
			)
			(primitives
				(gr_poly
					(pts
						(arc
							(start 0.1016 0.254)
							(mid 0 0.3556)
							(end -0.1016 0.254)
						)
						(xy -0.1016 -0.3556) (xy 0.1016 -0.3556)
					)
					(width 0)
					(fill yes)
				)
			)
		)
		(pad "36" smd custom
			(at -0.199898 -2.4511 270)
			(size 0.0508 0.0508)
			(layers "F.Cu" "F.Mask" "F.Paste")
			(net "VR_PVDDQ_ABC_XADDR1")
			(options
				(clearance outline)
				(anchor circle)
			)
			(primitives
				(gr_poly
					(pts
						(arc
							(start 0.1016 0.254)
							(mid 0 0.3556)
							(end -0.1016 0.254)
						)
						(xy -0.1016 -0.3556) (xy 0.1016 -0.3556)
					)
					(width 0)
					(fill yes)
				)
			)
		)
		(pad "37" smd custom
			(at -0.599948 -2.4511 270)
			(size 0.0508 0.0508)
			(layers "F.Cu" "F.Mask" "F.Paste")
			(net "VR_PVDDQ_ABC_VINSEN")
			(options
				(clearance outline)
				(anchor circle)
			)
			(primitives
				(gr_poly
					(pts
						(arc
							(start 0.1016 0.254)
							(mid 0 0.3556)
							(end -0.1016 0.254)
						)
						(xy -0.1016 -0.3556) (xy 0.1016 -0.3556)
					)
					(width 0)
					(fill yes)
				)
			)
		)
		(pad "38" smd custom
			(at -0.999998 -2.4511 270)
			(size 0.0508 0.0508)
			(layers "F.Cu" "F.Mask" "F.Paste")
			(net "VR_PVDDQ_ABC_AIINSEN")
			(options
				(clearance outline)
				(anchor circle)
			)
			(primitives
				(gr_poly
					(pts
						(arc
							(start 0.1016 0.254)
							(mid 0 0.3556)
							(end -0.1016 0.254)
						)
						(xy -0.1016 -0.3556) (xy 0.1016 -0.3556)
					)
					(width 0)
					(fill yes)
				)
			)
		)
		(pad "39" smd custom
			(at -1.400048 -2.4511 270)
			(size 0.0508 0.0508)
			(layers "F.Cu" "F.Mask" "F.Paste")
			(net "VR_PVDDQ_ABC_VDD")
			(options
				(clearance outline)
				(anchor circle)
			)
			(primitives
				(gr_poly
					(pts
						(arc
							(start 0.1016 0.254)
							(mid 0 0.3556)
							(end -0.1016 0.254)
						)
						(xy -0.1016 -0.3556) (xy 0.1016 -0.3556)
					)
					(width 0)
					(fill yes)
				)
			)
		)
		(pad "40" smd custom
			(at -1.800098 -2.4511 270)
			(size 0.0508 0.0508)
			(layers "F.Cu" "F.Mask" "F.Paste")
			(net "VR_PVDDQ_ABC_VD12")
			(options
				(clearance outline)
				(anchor circle)
			)
			(primitives
				(gr_poly
					(pts
						(arc
							(start 0.1016 0.254)
							(mid 0 0.3556)
							(end -0.1016 0.254)
						)
						(xy -0.1016 -0.3556) (xy 0.1016 -0.3556)
					)
					(width 0)
					(fill yes)
				)
			)
		)
		(pad "41" smd rect
			(at 0 0 270)
			(size 3.683 3.683)
			(layers "F.Cu" "F.Mask" "F.Paste")
			(net "GND")
		)
		(zone
			(layer "F.Cu")
			(hatch none 0.5)
			(connect_pads
				(clearance 0)
			)
			(min_thickness 0.25)
			(keepout
				(tracks allowed)
				(vias not_allowed)
				(pads allowed)
				(copperpour not_allowed)
				(footprints allowed)
			)
			(placement
				(enabled no)
				(sheetname "")
			)
			(fill
				(thermal_gap 0.5)
				(thermal_bridge_width 0.5)
				(island_removal_mode 0)
			)
			(polygon
				(pts
					(xy 342.5825 -17.4625) (xy 343.04351 -17.4625) (xy 343.04351 -17.2085) (xy 342.8365 -17.2085) (xy 342.8365 -13.5255)
					(xy 346.5195 -13.5255) (xy 346.5195 -17.2085) (xy 343.045542 -17.2085) (xy 343.045542 -17.4625)
					(xy 346.7735 -17.4625) (xy 346.7735 -13.2715) (xy 342.5825 -13.2715)
				)
			)
		)
		(zone
			(layer "F.Cu")
			(hatch none 0.5)
			(connect_pads
				(clearance 0)
			)
			(min_thickness 0.25)
			(keepout
				(tracks not_allowed)
				(vias allowed)
				(pads allowed)
				(copperpour not_allowed)
				(footprints allowed)
			)
			(placement
				(enabled no)
				(sheetname "")
			)
			(fill
				(thermal_gap 0.5)
				(thermal_bridge_width 0.5)
				(island_removal_mode 0)
			)
			(polygon
				(pts
					(xy 342.5825 -17.4625) (xy 343.04351 -17.4625) (xy 343.04351 -17.2085) (xy 342.8365 -17.2085) (xy 342.8365 -13.5255)
					(xy 346.5195 -13.5255) (xy 346.5195 -17.2085) (xy 343.045542 -17.2085) (xy 343.045542 -17.4625)
					(xy 346.7735 -17.4625) (xy 346.7735 -13.2715) (xy 342.5825 -13.2715)
				)
			)
		)
	)
	(footprint ""
		(layer "F.Cu")
		(at 436.8165 -15.367 90)
		(property "Reference" "R1U41"
			(at 0 0 90)
			(layer "F.SilkS")
			(hide yes)
			(effects
				(font
					(size 1.27 1.27)
				)
			)
		)
		(property "Value" ""
			(at 0 0 90)
			(layer "F.Fab")
			(effects
				(font
					(size 1.27 1.27)
				)
			)
		)
		(duplicate_pad_numbers_are_jumpers no)
		(fp_poly
			(pts
				(xy -0.2794 -0.1016) (xy 0.2794 -0.1016) (xy 0.2794 0.9906) (xy -0.2794 0.9906)
			)
			(stroke
				(width 0)
				(type default)
			)
			(fill no)
			(layer "F.CrtYd")
		)
		(fp_line
			(start 0.2794 -0.1016)
			(end -0.2794 -0.1016)
			(stroke
				(width 0.1)
				(type default)
			)
			(layer "F.Fab")
		)
		(fp_line
			(start -0.2794 -0.1016)
			(end -0.2794 0.9906)
			(stroke
				(width 0.1)
				(type default)
			)
			(layer "F.Fab")
		)
		(fp_line
			(start 0.2794 0.9906)
			(end 0.2794 -0.1016)
			(stroke
				(width 0.1)
				(type default)
			)
			(layer "F.Fab")
		)
		(fp_line
			(start -0.2794 0.9906)
			(end 0.2794 0.9906)
			(stroke
				(width 0.1)
				(type default)
			)
			(layer "F.Fab")
		)
		(pad "1" smd rect
			(at 0 0 90)
			(size 0.508 0.508)
			(layers "F.Cu" "F.Mask" "F.Paste")
			(net "PVCCIO_CPU1")
		)
		(pad "2" smd rect
			(at 0 0.889 90)
			(size 0.508 0.508)
			(layers "F.Cu" "F.Mask" "F.Paste")
			(net "H_CPU1_MEMGHJ_MEMHOT_G_N")
		)
		(zone
			(layer "F.Cu")
			(hatch none 0.5)
			(connect_pads
				(clearance 0)
			)
			(min_thickness 0.25)
			(keepout
				(tracks allowed)
				(vias not_allowed)
				(pads allowed)
				(copperpour not_allowed)
				(footprints allowed)
			)
			(placement
				(enabled no)
				(sheetname "")
			)
			(fill
				(thermal_gap 0.5)
				(thermal_bridge_width 0.5)
				(island_removal_mode 0)
			)
			(polygon
				(pts
					(xy 437.0705 -15.113) (xy 437.0705 -15.621) (xy 437.4515 -15.621) (xy 437.4515 -15.113)
				)
			)
		)
		(zone
			(layer "F.Cu")
			(hatch none 0.5)
			(connect_pads
				(clearance 0)
			)
			(min_thickness 0.25)
			(keepout
				(tracks not_allowed)
				(vias allowed)
				(pads allowed)
				(copperpour not_allowed)
				(footprints allowed)
			)
			(placement
				(enabled no)
				(sheetname "")
			)
			(fill
				(thermal_gap 0.5)
				(thermal_bridge_width 0.5)
				(island_removal_mode 0)
			)
			(polygon
				(pts
					(xy 437.4515 -15.113) (xy 437.4515 -15.621) (xy 437.0705 -15.621) (xy 437.0705 -15.113)
				)
			)
		)
	)
	(footprint ""
		(layer "F.Cu")
		(at 44.1071 -51.3334 90)
		(property "Reference" "RT8P1"
			(at 1.27127 0.4699 180)
			(unlocked yes)
			(layer "F.SilkS")
			(effects
				(font
					(size 0.7874 0.5842)
					(thickness 0.1524)
				)
			)
		)
		(property "Value" ""
			(at 0 0 90)
			(layer "F.Fab")
			(effects
				(font
					(size 1.27 1.27)
				)
			)
		)
		(duplicate_pad_numbers_are_jumpers no)
		(fp_poly
			(pts
				(xy -0.4953 -0.2032) (xy 0.4953 -0.2032) (xy 0.4953 1.6002) (xy -0.4953 1.6002)
			)
			(stroke
				(width 0)
				(type default)
			)
			(fill no)
			(layer "F.CrtYd")
		)
		(fp_line
			(start 0.4953 -0.2032)
			(end 0.4953 1.6002)
			(stroke
				(width 0.1)
				(type default)
			)
			(layer "F.Fab")
		)
		(fp_line
			(start -0.4953 -0.2032)
			(end 0.4953 -0.2032)
			(stroke
				(width 0.1)
				(type default)
			)
			(layer "F.Fab")
		)
		(fp_line
			(start 0.4953 1.6002)
			(end -0.4953 1.6002)
			(stroke
				(width 0.1)
				(type default)
			)
			(layer "F.Fab")
		)
		(fp_line
			(start -0.4953 1.6002)
			(end -0.4953 -0.2032)
			(stroke
				(width 0.1)
				(type default)
			)
			(layer "F.Fab")
		)
		(pad "1" smd rect
			(at 0 0 90)
			(size 0.762 0.889)
			(layers "F.Cu" "F.Mask" "F.Paste")
			(net "PVCCIN_CPU1")
		)
		(pad "2" smd rect
			(at 0 1.397 90)
			(size 0.762 0.889)
			(layers "F.Cu" "F.Mask" "F.Paste")
			(net "VSENSE_VCCINR2PMAX_CPU1")
		)
		(zone
			(layer "F.Cu")
			(hatch none 0.5)
			(connect_pads
				(clearance 0)
			)
			(min_thickness 0.25)
			(keepout
				(tracks allowed)
				(vias not_allowed)
				(pads allowed)
				(copperpour not_allowed)
				(footprints allowed)
			)
			(placement
				(enabled no)
				(sheetname "")
			)
			(fill
				(thermal_gap 0.5)
				(thermal_bridge_width 0.5)
				(island_removal_mode 0)
			)
			(polygon
				(pts
					(xy 45.0596 -51.7144) (xy 44.5516 -51.7144) (xy 44.5516 -50.9524) (xy 45.0596 -50.9524)
				)
			)
		)
		(zone
			(layer "F.Cu")
			(hatch none 0.5)
			(connect_pads
				(clearance 0)
			)
			(min_thickness 0.25)
			(keepout
				(tracks not_allowed)
				(vias allowed)
				(pads allowed)
				(copperpour not_allowed)
				(footprints allowed)
			)
			(placement
				(enabled no)
				(sheetname "")
			)
			(fill
				(thermal_gap 0.5)
				(thermal_bridge_width 0.5)
				(island_removal_mode 0)
			)
			(polygon
				(pts
					(xy 45.0596 -50.9524) (xy 45.0596 -51.7144) (xy 44.5516 -51.7144) (xy 44.5516 -50.9524)
				)
			)
		)
	)
	(footprint ""
		(layer "F.Cu")
		(at 369.8494 -129.286 90)
		(property "Reference" "R7B6"
			(at 0 0 90)
			(layer "F.SilkS")
			(hide yes)
			(effects
				(font
					(size 1.27 1.27)
				)
			)
		)
		(property "Value" ""
			(at 0 0 90)
			(layer "F.Fab")
			(effects
				(font
					(size 1.27 1.27)
				)
			)
		)
		(duplicate_pad_numbers_are_jumpers no)
		(fp_poly
			(pts
				(xy -0.2794 -0.1016) (xy 0.2794 -0.1016) (xy 0.2794 0.9906) (xy -0.2794 0.9906)
			)
			(stroke
				(width 0)
				(type default)
			)
			(fill no)
			(layer "F.CrtYd")
		)
		(fp_line
			(start 0.2794 -0.1016)
			(end -0.2794 -0.1016)
			(stroke
				(width 0.1)
				(type default)
			)
			(layer "F.Fab")
		)
		(fp_line
			(start -0.2794 -0.1016)
			(end -0.2794 0.9906)
			(stroke
				(width 0.1)
				(type default)
			)
			(layer "F.Fab")
		)
		(fp_line
			(start 0.2794 0.9906)
			(end 0.2794 -0.1016)
			(stroke
				(width 0.1)
				(type default)
			)
			(layer "F.Fab")
		)
		(fp_line
			(start -0.2794 0.9906)
			(end 0.2794 0.9906)
			(stroke
				(width 0.1)
				(type default)
			)
			(layer "F.Fab")
		)
		(pad "1" smd rect
			(at 0 0 90)
			(size 0.508 0.508)
			(layers "F.Cu" "F.Mask" "F.Paste")
			(net "P3V3_STBY")
		)
		(pad "2" smd rect
			(at 0 0.889 90)
			(size 0.508 0.508)
			(layers "F.Cu" "F.Mask" "F.Paste")
			(net "FM_PCH_PRSNT_N")
		)
		(zone
			(layer "F.Cu")
			(hatch none 0.5)
			(connect_pads
				(clearance 0)
			)
			(min_thickness 0.25)
			(keepout
				(tracks allowed)
				(vias not_allowed)
				(pads allowed)
				(copperpour not_allowed)
				(footprints allowed)
			)
			(placement
				(enabled no)
				(sheetname "")
			)
			(fill
				(thermal_gap 0.5)
				(thermal_bridge_width 0.5)
				(island_removal_mode 0)
			)
			(polygon
				(pts
					(xy 370.1034 -129.032) (xy 370.1034 -129.54) (xy 370.4844 -129.54) (xy 370.4844 -129.032)
				)
			)
		)
		(zone
			(layer "F.Cu")
			(hatch none 0.5)
			(connect_pads
				(clearance 0)
			)
			(min_thickness 0.25)
			(keepout
				(tracks not_allowed)
				(vias allowed)
				(pads allowed)
				(copperpour not_allowed)
				(footprints allowed)
			)
			(placement
				(enabled no)
				(sheetname "")
			)
			(fill
				(thermal_gap 0.5)
				(thermal_bridge_width 0.5)
				(island_removal_mode 0)
			)
			(polygon
				(pts
					(xy 370.4844 -129.032) (xy 370.4844 -129.54) (xy 370.1034 -129.54) (xy 370.1034 -129.032)
				)
			)
		)
	)
	(footprint ""
		(layer "F.Cu")
		(at 454.29932 -128.25222 -90)
		(property "Reference" "F9B1"
			(at 0 0 270)
			(layer "F.SilkS")
			(hide yes)
			(effects
				(font
					(size 1.27 1.27)
				)
			)
		)
		(property "Value" ""
			(at 0 0 270)
			(layer "F.Fab")
			(effects
				(font
					(size 1.27 1.27)
				)
			)
		)
		(duplicate_pad_numbers_are_jumpers no)
		(fp_poly
			(pts
				(xy 1.7018 4.7117) (xy -1.7018 4.7117) (xy -1.7018 -0.0127) (xy 1.7018 -0.0127)
			)
			(stroke
				(width 0)
				(type default)
			)
			(fill no)
			(layer "F.CrtYd")
		)
		(fp_line
			(start -1.7018 4.7117)
			(end -1.7018 -0.0127)
			(stroke
				(width 0.1)
				(type default)
			)
			(layer "F.Fab")
		)
		(fp_line
			(start 1.7018 4.7117)
			(end -1.7018 4.7117)
			(stroke
				(width 0.1)
				(type default)
			)
			(layer "F.Fab")
		)
		(fp_line
			(start -1.7018 -0.0127)
			(end 1.7018 -0.0127)
			(stroke
				(width 0.1)
				(type default)
			)
			(layer "F.Fab")
		)
		(fp_line
			(start 1.7018 -0.0127)
			(end 1.7018 4.7117)
			(stroke
				(width 0.1)
				(type default)
			)
			(layer "F.Fab")
		)
		(pad "1" smd rect
			(at 0 0 270)
			(size 3.302 1.397)
			(layers "F.Cu" "F.Mask" "F.Paste")
			(net "P12V")
		)
		(pad "2" smd rect
			(at 0 4.699 270)
			(size 3.302 1.397)
			(layers "F.Cu" "F.Mask" "F.Paste")
			(net "P12V_HDD_SATA")
		)
		(zone
			(layers "F.Cu" "B.Cu" "In1.Cu" "In2.Cu" "In3.Cu" "In4.Cu" "In5.Cu" "In6.Cu"
				"In7.Cu" "In8.Cu" "In9.Cu" "In10.Cu" "In11.Cu" "In12.Cu"
			)
			(hatch none 0.5)
			(connect_pads
				(clearance 0)
			)
			(min_thickness 0.25)
			(keepout
				(tracks allowed)
				(vias not_allowed)
				(pads allowed)
				(copperpour not_allowed)
				(footprints allowed)
			)
			(placement
				(enabled no)
				(sheetname "")
			)
			(fill
				(thermal_gap 0.5)
				(thermal_bridge_width 0.5)
				(island_removal_mode 0)
			)
			(polygon
				(pts
					(xy 450.29882 -129.90322) (xy 450.29882 -126.60122) (xy 453.60082 -126.60122) (xy 453.60082 -129.90322)
				)
			)
		)
	)
	(footprint ""
		(layer "F.Cu")
		(at 24.7015 -84.455)
		(property "Reference" "U1D1"
			(at -0.3683 -2.25933 0)
			(unlocked yes)
			(layer "F.SilkS")
			(effects
				(font
					(size 0.7874 0.5842)
					(thickness 0.1524)
				)
				(justify left)
			)
		)
		(property "Value" ""
			(at 0 0 0)
			(layer "F.Fab")
			(effects
				(font
					(size 1.27 1.27)
				)
			)
		)
		(duplicate_pad_numbers_are_jumpers no)
		(fp_circle
			(center -0.160782 -0.675386)
			(end -0.033782 -0.675386)
			(stroke
				(width 0.254)
				(type default)
			)
			(fill no)
			(layer "F.SilkS")
		)
		(fp_poly
			(pts
				(xy 0.21463 -0.450088) (xy 1.56337 -0.450088) (xy 1.56337 1.75006) (xy 0.21463 1.75006)
			)
			(stroke
				(width 0)
				(type default)
			)
			(fill no)
			(layer "F.CrtYd")
		)
		(fp_line
			(start 0.21463 -0.450088)
			(end 1.56337 -0.450088)
			(stroke
				(width 0.1)
				(type default)
			)
			(layer "F.Fab")
		)
		(fp_line
			(start 0.21463 1.75006)
			(end 0.21463 -0.450088)
			(stroke
				(width 0.1)
				(type default)
			)
			(layer "F.Fab")
		)
		(fp_line
			(start 1.56337 -0.450088)
			(end 1.56337 1.75006)
			(stroke
				(width 0.1)
				(type default)
			)
			(layer "F.Fab")
		)
		(fp_line
			(start 1.56337 1.75006)
			(end 0.21463 1.75006)
			(stroke
				(width 0.1)
				(type default)
			)
			(layer "F.Fab")
		)
		(fp_circle
			(center -0.4699 -0.8382)
			(end -0.3429 -0.8382)
			(stroke
				(width 0.254)
				(type default)
			)
			(fill no)
			(layer "F.Fab")
		)
		(pad "1" smd rect
			(at 0 0)
			(size 1.016 0.381)
			(layers "F.Cu" "F.Mask" "F.Paste")
			(net "FM_OC_DETECT_EN")
		)
		(pad "2" smd rect
			(at 0 0.649986)
			(size 1.016 0.381)
			(layers "F.Cu" "F.Mask" "F.Paste")
			(net "IRQ_OC_DETECT_N")
		)
		(pad "3" smd rect
			(at 0 1.299972)
			(size 1.016 0.381)
			(layers "F.Cu" "F.Mask" "F.Paste")
			(net "GND")
		)
		(pad "4" smd rect
			(at 1.778 1.299972)
			(size 1.016 0.381)
			(layers "F.Cu" "F.Mask" "F.Paste")
			(net "FM_OC_DETECT_N")
		)
		(pad "5" smd rect
			(at 1.778 0)
			(size 1.016 0.381)
			(layers "F.Cu" "F.Mask" "F.Paste")
			(net "P3V3_STBY")
		)
	)
	(footprint ""
		(layer "F.Cu")
		(at 95.69704 -81.573116)
		(property "Reference" "C2D11"
			(at 0 0 0)
			(layer "F.SilkS")
			(hide yes)
			(effects
				(font
					(size 1.27 1.27)
				)
			)
		)
		(property "Value" ""
			(at 0 0 0)
			(layer "F.Fab")
			(effects
				(font
					(size 1.27 1.27)
				)
			)
		)
		(duplicate_pad_numbers_are_jumpers no)
		(fp_poly
			(pts
				(xy -0.4953 -0.2032) (xy 0.4953 -0.2032) (xy 0.4953 1.6002) (xy -0.4953 1.6002)
			)
			(stroke
				(width 0)
				(type default)
			)
			(fill no)
			(layer "F.CrtYd")
		)
		(fp_line
			(start -0.4953 -0.2032)
			(end 0.4953 -0.2032)
			(stroke
				(width 0.1)
				(type default)
			)
			(layer "F.Fab")
		)
		(fp_line
			(start -0.4953 1.6002)
			(end -0.4953 -0.2032)
			(stroke
				(width 0.1)
				(type default)
			)
			(layer "F.Fab")
		)
		(fp_line
			(start 0.4953 -0.2032)
			(end 0.4953 1.6002)
			(stroke
				(width 0.1)
				(type default)
			)
			(layer "F.Fab")
		)
		(fp_line
			(start 0.4953 1.6002)
			(end -0.4953 1.6002)
			(stroke
				(width 0.1)
				(type default)
			)
			(layer "F.Fab")
		)
		(pad "1" smd rect
			(at 0 0)
			(size 0.762 0.889)
			(layers "F.Cu" "F.Mask" "F.Paste")
			(net "PVSA_CPU1")
		)
		(pad "2" smd rect
			(at 0 1.397)
			(size 0.762 0.889)
			(layers "F.Cu" "F.Mask" "F.Paste")
			(net "GND")
		)
		(zone
			(layer "F.Cu")
			(hatch none 0.5)
			(connect_pads
				(clearance 0)
			)
			(min_thickness 0.25)
			(keepout
				(tracks not_allowed)
				(vias allowed)
				(pads allowed)
				(copperpour not_allowed)
				(footprints allowed)
			)
			(placement
				(enabled no)
				(sheetname "")
			)
			(fill
				(thermal_gap 0.5)
				(thermal_bridge_width 0.5)
				(island_removal_mode 0)
			)
			(polygon
				(pts
					(xy 95.31604 -81.128616) (xy 96.07804 -81.128616) (xy 96.07804 -80.620616) (xy 95.31604 -80.620616)
				)
			)
		)
	)
	(footprint ""
		(layer "F.Cu")
		(at 411.6578 -102.4636 180)
		(property "Reference" "R7W12"
			(at -0.8382 -0.67818 180)
			(unlocked yes)
			(layer "F.SilkS")
			(effects
				(font
					(size 0.4064 0.254)
					(thickness 0.1524)
				)
				(justify left)
			)
		)
		(property "Value" ""
			(at 0 0 180)
			(layer "F.Fab")
			(effects
				(font
					(size 1.27 1.27)
				)
			)
		)
		(duplicate_pad_numbers_are_jumpers no)
		(fp_poly
			(pts
				(xy -0.2794 -0.1016) (xy 0.2794 -0.1016) (xy 0.2794 0.9906) (xy -0.2794 0.9906)
			)
			(stroke
				(width 0)
				(type default)
			)
			(fill no)
			(layer "F.CrtYd")
		)
		(fp_line
			(start 0.2794 0.9906)
			(end 0.2794 -0.1016)
			(stroke
				(width 0.1)
				(type default)
			)
			(layer "F.Fab")
		)
		(fp_line
			(start 0.2794 -0.1016)
			(end -0.2794 -0.1016)
			(stroke
				(width 0.1)
				(type default)
			)
			(layer "F.Fab")
		)
		(fp_line
			(start -0.2794 0.9906)
			(end 0.2794 0.9906)
			(stroke
				(width 0.1)
				(type default)
			)
			(layer "F.Fab")
		)
		(fp_line
			(start -0.2794 -0.1016)
			(end -0.2794 0.9906)
			(stroke
				(width 0.1)
				(type default)
			)
			(layer "F.Fab")
		)
		(pad "1" smd rect
			(at 0 0 180)
			(size 0.508 0.508)
			(layers "F.Cu" "F.Mask" "F.Paste")
			(net "FM_CPU1_RC_ERROR_N")
		)
		(pad "2" smd rect
			(at 0 0.889 180)
			(size 0.508 0.508)
			(layers "F.Cu" "F.Mask" "F.Paste")
			(net "FM_CPU1_RC_ERROR_R1_N")
		)
		(zone
			(layer "F.Cu")
			(hatch none 0.5)
			(connect_pads
				(clearance 0)
			)
			(min_thickness 0.25)
			(keepout
				(tracks not_allowed)
				(vias allowed)
				(pads allowed)
				(copperpour not_allowed)
				(footprints allowed)
			)
			(placement
				(enabled no)
				(sheetname "")
			)
			(fill
				(thermal_gap 0.5)
				(thermal_bridge_width 0.5)
				(island_removal_mode 0)
			)
			(polygon
				(pts
					(xy 411.9118 -103.0986) (xy 411.4038 -103.0986) (xy 411.4038 -102.7176) (xy 411.9118 -102.7176)
				)
			)
		)
		(zone
			(layer "F.Cu")
			(hatch none 0.5)
			(connect_pads
				(clearance 0)
			)
			(min_thickness 0.25)
			(keepout
				(tracks allowed)
				(vias not_allowed)
				(pads allowed)
				(copperpour not_allowed)
				(footprints allowed)
			)
			(placement
				(enabled no)
				(sheetname "")
			)
			(fill
				(thermal_gap 0.5)
				(thermal_bridge_width 0.5)
				(island_removal_mode 0)
			)
			(polygon
				(pts
					(xy 411.9118 -102.7176) (xy 411.4038 -102.7176) (xy 411.4038 -103.0986) (xy 411.9118 -103.0986)
				)
			)
		)
	)
	(footprint ""
		(layer "F.Cu")
		(at 11.89863 -3.541268 180)
		(property "Reference" "R12W32"
			(at -0.8382 -0.67818 180)
			(unlocked yes)
			(layer "F.SilkS")
			(effects
				(font
					(size 0.4064 0.254)
					(thickness 0.1524)
				)
				(justify left)
			)
		)
		(property "Value" ""
			(at 0 0 180)
			(layer "F.Fab")
			(effects
				(font
					(size 1.27 1.27)
				)
			)
		)
		(duplicate_pad_numbers_are_jumpers no)
		(fp_poly
			(pts
				(xy -0.2794 -0.1016) (xy 0.2794 -0.1016) (xy 0.2794 0.9906) (xy -0.2794 0.9906)
			)
			(stroke
				(width 0)
				(type default)
			)
			(fill no)
			(layer "F.CrtYd")
		)
		(fp_line
			(start 0.2794 0.9906)
			(end 0.2794 -0.1016)
			(stroke
				(width 0.1)
				(type default)
			)
			(layer "F.Fab")
		)
		(fp_line
			(start 0.2794 -0.1016)
			(end -0.2794 -0.1016)
			(stroke
				(width 0.1)
				(type default)
			)
			(layer "F.Fab")
		)
		(fp_line
			(start -0.2794 0.9906)
			(end 0.2794 0.9906)
			(stroke
				(width 0.1)
				(type default)
			)
			(layer "F.Fab")
		)
		(fp_line
			(start -0.2794 -0.1016)
			(end -0.2794 0.9906)
			(stroke
				(width 0.1)
				(type default)
			)
			(layer "F.Fab")
		)
		(pad "1" smd rect
			(at 0 0 180)
			(size 0.508 0.508)
			(layers "F.Cu" "F.Mask" "F.Paste")
			(net "TP_PVDDQ_GHJ_MP1")
		)
		(pad "2" smd rect
			(at 0 0.889 180)
			(size 0.508 0.508)
			(layers "F.Cu" "F.Mask" "F.Paste")
			(net "PWRGD_PVDDQ_GHJ")
		)
		(zone
			(layer "F.Cu")
			(hatch none 0.5)
			(connect_pads
				(clearance 0)
			)
			(min_thickness 0.25)
			(keepout
				(tracks not_allowed)
				(vias allowed)
				(pads allowed)
				(copperpour not_allowed)
				(footprints allowed)
			)
			(placement
				(enabled no)
				(sheetname "")
			)
			(fill
				(thermal_gap 0.5)
				(thermal_bridge_width 0.5)
				(island_removal_mode 0)
			)
			(polygon
				(pts
					(xy 12.15263 -4.176268) (xy 11.64463 -4.176268) (xy 11.64463 -3.795268) (xy 12.15263 -3.795268)
				)
			)
		)
		(zone
			(layer "F.Cu")
			(hatch none 0.5)
			(connect_pads
				(clearance 0)
			)
			(min_thickness 0.25)
			(keepout
				(tracks allowed)
				(vias not_allowed)
				(pads allowed)
				(copperpour not_allowed)
				(footprints allowed)
			)
			(placement
				(enabled no)
				(sheetname "")
			)
			(fill
				(thermal_gap 0.5)
				(thermal_bridge_width 0.5)
				(island_removal_mode 0)
			)
			(polygon
				(pts
					(xy 12.15263 -3.795268) (xy 11.64463 -3.795268) (xy 11.64463 -4.176268) (xy 12.15263 -4.176268)
				)
			)
		)
	)
	(footprint ""
		(layer "F.Cu")
		(at 411.444694 -131.805172 90)
		(property "Reference" "R8B5"
			(at 0 0 90)
			(layer "F.SilkS")
			(hide yes)
			(effects
				(font
					(size 1.27 1.27)
				)
			)
		)
		(property "Value" ""
			(at 0 0 90)
			(layer "F.Fab")
			(effects
				(font
					(size 1.27 1.27)
				)
			)
		)
		(duplicate_pad_numbers_are_jumpers no)
		(fp_poly
			(pts
				(xy -0.2794 -0.1016) (xy 0.2794 -0.1016) (xy 0.2794 0.9906) (xy -0.2794 0.9906)
			)
			(stroke
				(width 0)
				(type default)
			)
			(fill no)
			(layer "F.CrtYd")
		)
		(fp_line
			(start 0.2794 -0.1016)
			(end -0.2794 -0.1016)
			(stroke
				(width 0.1)
				(type default)
			)
			(layer "F.Fab")
		)
		(fp_line
			(start -0.2794 -0.1016)
			(end -0.2794 0.9906)
			(stroke
				(width 0.1)
				(type default)
			)
			(layer "F.Fab")
		)
		(fp_line
			(start 0.2794 0.9906)
			(end 0.2794 -0.1016)
			(stroke
				(width 0.1)
				(type default)
			)
			(layer "F.Fab")
		)
		(fp_line
			(start -0.2794 0.9906)
			(end 0.2794 0.9906)
			(stroke
				(width 0.1)
				(type default)
			)
			(layer "F.Fab")
		)
		(pad "1" smd rect
			(at 0 0 90)
			(size 0.508 0.508)
			(layers "F.Cu" "F.Mask" "F.Paste")
			(net "PVPP_ABC")
		)
		(pad "2" smd rect
			(at 0 0.889 90)
			(size 0.508 0.508)
			(layers "F.Cu" "F.Mask" "F.Paste")
			(net "LED_HFI0_CPU0_N")
		)
		(zone
			(layer "F.Cu")
			(hatch none 0.5)
			(connect_pads
				(clearance 0)
			)
			(min_thickness 0.25)
			(keepout
				(tracks allowed)
				(vias not_allowed)
				(pads allowed)
				(copperpour not_allowed)
				(footprints allowed)
			)
			(placement
				(enabled no)
				(sheetname "")
			)
			(fill
				(thermal_gap 0.5)
				(thermal_bridge_width 0.5)
				(island_removal_mode 0)
			)
			(polygon
				(pts
					(xy 411.698694 -131.551172) (xy 411.698694 -132.059172) (xy 412.079694 -132.059172) (xy 412.079694 -131.551172)
				)
			)
		)
		(zone
			(layer "F.Cu")
			(hatch none 0.5)
			(connect_pads
				(clearance 0)
			)
			(min_thickness 0.25)
			(keepout
				(tracks not_allowed)
				(vias allowed)
				(pads allowed)
				(copperpour not_allowed)
				(footprints allowed)
			)
			(placement
				(enabled no)
				(sheetname "")
			)
			(fill
				(thermal_gap 0.5)
				(thermal_bridge_width 0.5)
				(island_removal_mode 0)
			)
			(polygon
				(pts
					(xy 412.079694 -131.551172) (xy 412.079694 -132.059172) (xy 411.698694 -132.059172) (xy 411.698694 -131.551172)
				)
			)
		)
	)
	(footprint ""
		(layer "F.Cu")
		(at -2.8956 -6.98754 -90)
		(property "Reference" "C1G15"
			(at 0 0 270)
			(layer "F.SilkS")
			(hide yes)
			(effects
				(font
					(size 1.27 1.27)
				)
			)
		)
		(property "Value" "*"
			(at -2.3114 0.10795 270)
			(unlocked yes)
			(layer "F.Fab")
			(hide yes)
			(effects
				(font
					(size 0.889 0.889)
					(thickness 0.1524)
				)
			)
		)
		(property "Device Type" "ST270U2D5VBM-GP_SMD-TCG2-ST270A"
			(at -2.3114 -1.41605 270)
			(unlocked yes)
			(layer "F.Fab")
			(hide yes)
			(effects
				(font
					(size 0.889 0.889)
					(thickness 0.1524)
				)
			)
		)
		(duplicate_pad_numbers_are_jumpers no)
		(fp_line
			(start -1.5494 0.4826)
			(end -1.5494 -0.4826)
			(stroke
				(width 0.1524)
				(type default)
			)
			(layer "F.SilkS")
		)
		(fp_line
			(start 1.5494 -0.4826)
			(end 1.5494 0.4826)
			(stroke
				(width 0.1524)
				(type default)
			)
			(layer "F.SilkS")
		)
		(fp_line
			(start -1.0922 -2.35458)
			(end 1.0922 -2.35458)
			(stroke
				(width 0.508)
				(type default)
			)
			(layer "F.SilkS")
		)
		(fp_poly
			(pts
				(xy -1.3462 1.9558) (xy -1.3462 1.905) (xy -1.5494 1.905) (xy -1.5494 -1.905) (xy -1.3462 -1.905)
				(xy -1.3462 -1.9558) (xy 1.3462 -1.9558) (xy 1.3462 -1.905) (xy 1.5494 -1.905) (xy 1.5494 1.905)
				(xy 1.3462 1.905) (xy 1.3462 1.9558)
			)
			(stroke
				(width 0)
				(type default)
			)
			(fill no)
			(layer "F.CrtYd")
		)
		(fp_poly
			(pts
				(xy -1.3462 1.9558) (xy -1.3462 1.905) (xy -1.5494 1.905) (xy -1.5494 -1.905) (xy -1.3462 -1.905)
				(xy -1.3462 -1.9558) (xy 1.3462 -1.9558) (xy 1.3462 -1.905) (xy 1.5494 -1.905) (xy 1.5494 1.905)
				(xy 1.3462 1.905) (xy 1.3462 1.9558)
			)
			(stroke
				(width 0)
				(type default)
			)
			(fill no)
			(layer "F.Fab")
		)
		(pad "1" smd rect
			(at 0 -1.27508 270)
			(size 2.6924 1.3462)
			(layers "F.Cu" "F.Mask" "F.Paste")
			(net "VR_FET_SW_P12V_STBY_PVDDQ_GHJ")
		)
		(pad "2" smd rect
			(at 0 1.27508 270)
			(size 2.6924 1.3462)
			(layers "F.Cu" "F.Mask" "F.Paste")
			(net "GND")
		)
	)
	(footprint ""
		(layer "F.Cu")
		(at 172.280072 -73.839324)
		(property "Reference" "Q4W1"
			(at 0 -1.2065 0)
			(unlocked yes)
			(layer "F.SilkS")
			(effects
				(font
					(size 1.27 0.9652)
					(thickness 0.1524)
				)
				(justify left)
			)
		)
		(property "Value" ""
			(at 0 0 0)
			(layer "F.Fab")
			(effects
				(font
					(size 1.27 1.27)
				)
			)
		)
		(duplicate_pad_numbers_are_jumpers no)
		(fp_circle
			(center -0.643382 -0.50546)
			(end -0.516382 -0.50546)
			(stroke
				(width 0.254)
				(type default)
			)
			(fill no)
			(layer "F.SilkS")
		)
		(fp_poly
			(pts
				(xy 0.21463 -0.450088) (xy 1.56337 -0.450088) (xy 1.56337 1.75006) (xy 0.21463 1.75006)
			)
			(stroke
				(width 0)
				(type default)
			)
			(fill no)
			(layer "F.CrtYd")
		)
		(fp_line
			(start 0.21463 -0.450088)
			(end 1.56337 -0.450088)
			(stroke
				(width 0.1)
				(type default)
			)
			(layer "F.Fab")
		)
		(fp_line
			(start 0.21463 1.75006)
			(end 0.21463 -0.450088)
			(stroke
				(width 0.1)
				(type default)
			)
			(layer "F.Fab")
		)
		(fp_line
			(start 1.56337 -0.450088)
			(end 1.56337 1.75006)
			(stroke
				(width 0.1)
				(type default)
			)
			(layer "F.Fab")
		)
		(fp_line
			(start 1.56337 1.75006)
			(end 0.21463 1.75006)
			(stroke
				(width 0.1)
				(type default)
			)
			(layer "F.Fab")
		)
		(fp_circle
			(center -0.848614 -0.6477)
			(end -0.721614 -0.6477)
			(stroke
				(width 0.254)
				(type default)
			)
			(fill no)
			(layer "F.Fab")
		)
		(pad "1" smd rect
			(at 0 0)
			(size 1.016 0.381)
			(layers "F.Cu" "F.Mask" "F.Paste")
			(net "SMB_HOST_STBY_LVC3_SDA_R2")
		)
		(pad "2" smd rect
			(at 0 0.649986)
			(size 1.016 0.381)
			(layers "F.Cu" "F.Mask" "F.Paste")
			(net "P3V3_DB1200_R1")
		)
		(pad "3" smd rect
			(at 0 1.299972)
			(size 1.016 0.381)
			(layers "F.Cu" "F.Mask" "F.Paste")
			(net "SMB_HOST_STBY_LVC3_SCL")
		)
		(pad "4" smd rect
			(at 1.778 1.299972)
			(size 1.016 0.381)
			(layers "F.Cu" "F.Mask" "F.Paste")
			(net "SMB_HOST_STBY_LVC3_SCL_R2")
		)
		(pad "5" smd rect
			(at 1.778 0.649986)
			(size 1.016 0.381)
			(layers "F.Cu" "F.Mask" "F.Paste")
			(net "P3V3_DB1200_R1")
		)
		(pad "6" smd rect
			(at 1.778 0)
			(size 1.016 0.381)
			(layers "F.Cu" "F.Mask" "F.Paste")
			(net "SMB_HOST_STBY_LVC3_SDA")
		)
	)
	(footprint ""
		(layer "F.Cu")
		(at 399.9738 -130.1496 180)
		(property "Reference" "C8B2"
			(at 0 0 180)
			(layer "F.SilkS")
			(hide yes)
			(effects
				(font
					(size 1.27 1.27)
				)
			)
		)
		(property "Value" ""
			(at 0 0 180)
			(layer "F.Fab")
			(effects
				(font
					(size 1.27 1.27)
				)
			)
		)
		(duplicate_pad_numbers_are_jumpers no)
		(fp_poly
			(pts
				(xy -0.4953 -0.2032) (xy 0.4953 -0.2032) (xy 0.4953 1.6002) (xy -0.4953 1.6002)
			)
			(stroke
				(width 0)
				(type default)
			)
			(fill no)
			(layer "F.CrtYd")
		)
		(fp_line
			(start 0.4953 1.6002)
			(end -0.4953 1.6002)
			(stroke
				(width 0.1)
				(type default)
			)
			(layer "F.Fab")
		)
		(fp_line
			(start 0.4953 -0.2032)
			(end 0.4953 1.6002)
			(stroke
				(width 0.1)
				(type default)
			)
			(layer "F.Fab")
		)
		(fp_line
			(start -0.4953 1.6002)
			(end -0.4953 -0.2032)
			(stroke
				(width 0.1)
				(type default)
			)
			(layer "F.Fab")
		)
		(fp_line
			(start -0.4953 -0.2032)
			(end 0.4953 -0.2032)
			(stroke
				(width 0.1)
				(type default)
			)
			(layer "F.Fab")
		)
		(pad "1" smd rect
			(at 0 0 180)
			(size 0.762 0.889)
			(layers "F.Cu" "F.Mask" "F.Paste")
			(net "P1V8_PCH_STBY")
		)
		(pad "2" smd rect
			(at 0 1.397 180)
			(size 0.762 0.889)
			(layers "F.Cu" "F.Mask" "F.Paste")
			(net "GND")
		)
		(zone
			(layer "F.Cu")
			(hatch none 0.5)
			(connect_pads
				(clearance 0)
			)
			(min_thickness 0.25)
			(keepout
				(tracks not_allowed)
				(vias allowed)
				(pads allowed)
				(copperpour not_allowed)
				(footprints allowed)
			)
			(placement
				(enabled no)
				(sheetname "")
			)
			(fill
				(thermal_gap 0.5)
				(thermal_bridge_width 0.5)
				(island_removal_mode 0)
			)
			(polygon
				(pts
					(xy 400.3548 -130.5941) (xy 399.5928 -130.5941) (xy 399.5928 -131.1021) (xy 400.3548 -131.1021)
				)
			)
		)
	)
	(footprint ""
		(layer "F.Cu")
		(at 279.82545 -70.438518 90)
		(property "Reference" "R6D12"
			(at 0 0 90)
			(layer "F.SilkS")
			(hide yes)
			(effects
				(font
					(size 1.27 1.27)
				)
			)
		)
		(property "Value" ""
			(at 0 0 90)
			(layer "F.Fab")
			(effects
				(font
					(size 1.27 1.27)
				)
			)
		)
		(duplicate_pad_numbers_are_jumpers no)
		(fp_poly
			(pts
				(xy -0.2794 -0.1016) (xy 0.2794 -0.1016) (xy 0.2794 0.9906) (xy -0.2794 0.9906)
			)
			(stroke
				(width 0)
				(type default)
			)
			(fill no)
			(layer "F.CrtYd")
		)
		(fp_line
			(start 0.2794 -0.1016)
			(end -0.2794 -0.1016)
			(stroke
				(width 0.1)
				(type default)
			)
			(layer "F.Fab")
		)
		(fp_line
			(start -0.2794 -0.1016)
			(end -0.2794 0.9906)
			(stroke
				(width 0.1)
				(type default)
			)
			(layer "F.Fab")
		)
		(fp_line
			(start 0.2794 0.9906)
			(end 0.2794 -0.1016)
			(stroke
				(width 0.1)
				(type default)
			)
			(layer "F.Fab")
		)
		(fp_line
			(start -0.2794 0.9906)
			(end 0.2794 0.9906)
			(stroke
				(width 0.1)
				(type default)
			)
			(layer "F.Fab")
		)
		(pad "1" smd rect
			(at 0 0 90)
			(size 0.508 0.508)
			(layers "F.Cu" "F.Mask" "F.Paste")
			(net "PVCCIO_CPU0")
		)
		(pad "2" smd rect
			(at 0 0.889 90)
			(size 0.508 0.508)
			(layers "F.Cu" "F.Mask" "F.Paste")
			(net "RST_CPU0_G_N")
		)
		(zone
			(layer "F.Cu")
			(hatch none 0.5)
			(connect_pads
				(clearance 0)
			)
			(min_thickness 0.25)
			(keepout
				(tracks allowed)
				(vias not_allowed)
				(pads allowed)
				(copperpour not_allowed)
				(footprints allowed)
			)
			(placement
				(enabled no)
				(sheetname "")
			)
			(fill
				(thermal_gap 0.5)
				(thermal_bridge_width 0.5)
				(island_removal_mode 0)
			)
			(polygon
				(pts
					(xy 280.07945 -70.184518) (xy 280.07945 -70.692518) (xy 280.46045 -70.692518) (xy 280.46045 -70.184518)
				)
			)
		)
		(zone
			(layer "F.Cu")
			(hatch none 0.5)
			(connect_pads
				(clearance 0)
			)
			(min_thickness 0.25)
			(keepout
				(tracks not_allowed)
				(vias allowed)
				(pads allowed)
				(copperpour not_allowed)
				(footprints allowed)
			)
			(placement
				(enabled no)
				(sheetname "")
			)
			(fill
				(thermal_gap 0.5)
				(thermal_bridge_width 0.5)
				(island_removal_mode 0)
			)
			(polygon
				(pts
					(xy 280.46045 -70.184518) (xy 280.46045 -70.692518) (xy 280.07945 -70.692518) (xy 280.07945 -70.184518)
				)
			)
		)
	)
	(footprint ""
		(layer "F.Cu")
		(at 40.036496 -73.287382)
		(property "Reference" "L1D2"
			(at 3.378708 -4.251706 0)
			(unlocked yes)
			(layer "F.SilkS")
			(effects
				(font
					(size 0.4064 0.254)
					(thickness 0.1524)
				)
			)
		)
		(property "Value" ""
			(at 0 0 0)
			(layer "F.Fab")
			(effects
				(font
					(size 1.27 1.27)
				)
			)
		)
		(duplicate_pad_numbers_are_jumpers no)
		(fp_line
			(start -1.1303 -3.199892)
			(end 8.3693 -3.199892)
			(stroke
				(width 0.1524)
				(type default)
			)
			(layer "F.SilkS")
		)
		(fp_line
			(start -1.1303 -1.6637)
			(end -1.1303 -3.199892)
			(stroke
				(width 0.1524)
				(type default)
			)
			(layer "F.SilkS")
		)
		(fp_line
			(start -1.1303 3.199892)
			(end -1.1303 1.6637)
			(stroke
				(width 0.1524)
				(type default)
			)
			(layer "F.SilkS")
		)
		(fp_line
			(start 8.3693 -3.199892)
			(end 8.3693 -1.6637)
			(stroke
				(width 0.1524)
				(type default)
			)
			(layer "F.SilkS")
		)
		(fp_line
			(start 8.3693 1.6637)
			(end 8.3693 3.199892)
			(stroke
				(width 0.1524)
				(type default)
			)
			(layer "F.SilkS")
		)
		(fp_line
			(start 8.3693 3.199892)
			(end -1.1303 3.199892)
			(stroke
				(width 0.1524)
				(type default)
			)
			(layer "F.SilkS")
		)
		(fp_rect
			(start -1.1303 3.199892)
			(end 8.3693 -3.199892)
			(stroke
				(width 0)
				(type default)
			)
			(fill no)
			(layer "F.CrtYd")
		)
		(fp_line
			(start -1.1303 -3.199892)
			(end 8.3693 -3.199892)
			(stroke
				(width 0.1)
				(type default)
			)
			(layer "F.Fab")
		)
		(fp_line
			(start -1.1303 3.199892)
			(end -1.1303 -3.199892)
			(stroke
				(width 0.1)
				(type default)
			)
			(layer "F.Fab")
		)
		(fp_line
			(start 8.3693 -3.199892)
			(end 8.3693 3.199892)
			(stroke
				(width 0.1)
				(type default)
			)
			(layer "F.Fab")
		)
		(fp_line
			(start 8.3693 3.199892)
			(end -1.1303 3.199892)
			(stroke
				(width 0.1)
				(type default)
			)
			(layer "F.Fab")
		)
		(pad "1" smd rect
			(at 0 0)
			(size 3.683 2.667)
			(layers "F.Cu" "F.Mask" "F.Paste")
			(net "VR_PVCCIN_CPU1_PHASE3")
		)
		(pad "2" smd rect
			(at 7.239 0)
			(size 3.683 2.667)
			(layers "F.Cu" "F.Mask" "F.Paste")
			(net "PVCCIN_CPU1")
		)
	)
	(footprint ""
		(layer "F.Cu")
		(at 351.028 -130.048 90)
		(property "Reference" "C7B8"
			(at 0 0 90)
			(layer "F.SilkS")
			(hide yes)
			(effects
				(font
					(size 1.27 1.27)
				)
			)
		)
		(property "Value" "*"
			(at -0.0762 -6.2357 90)
			(unlocked yes)
			(layer "F.Fab")
			(hide yes)
			(effects
				(font
					(size 1.27 1.016)
					(thickness 0.1524)
				)
			)
		)
		(property "Device Type" "SC22U16V5MX-4-GP_SMD-BCG5-SC22A"
			(at -0.0762 -8.2677 90)
			(unlocked yes)
			(layer "F.Fab")
			(hide yes)
			(effects
				(font
					(size 1.27 1.016)
					(thickness 0.1524)
				)
			)
		)
		(duplicate_pad_numbers_are_jumpers no)
		(fp_line
			(start 0.635 0)
			(end -0.635 0)
			(stroke
				(width 0.508)
				(type default)
			)
			(layer "F.SilkS")
		)
		(fp_rect
			(start -0.9652 1.778)
			(end 0.9652 -1.778)
			(stroke
				(width 0)
				(type default)
			)
			(fill no)
			(layer "F.CrtYd")
		)
		(fp_poly
			(pts
				(xy -0.9652 -1.778) (xy 0.9652 -1.778) (xy 0.9652 1.778) (xy -0.9652 1.778)
			)
			(stroke
				(width 0)
				(type default)
			)
			(fill no)
			(layer "F.Fab")
		)
		(pad "1" smd rect
			(at 0 -0.9652 90)
			(size 1.397 1.143)
			(layers "F.Cu" "F.Mask" "F.Paste")
			(net "VR_FET_SW_P12V_STBY_PVPP_DEF")
		)
		(pad "2" smd rect
			(at 0 0.9652 90)
			(size 1.397 1.143)
			(layers "F.Cu" "F.Mask" "F.Paste")
			(net "GND")
		)
	)
	(footprint ""
		(layer "F.Cu")
		(at 408.30373 -100.185982 -90)
		(property "Reference" "Y8C1"
			(at 2.8956 1.09347 270)
			(unlocked yes)
			(layer "F.SilkS")
			(effects
				(font
					(size 0.7874 0.5842)
					(thickness 0.1524)
				)
				(justify left)
			)
		)
		(property "Value" ""
			(at 0 0 270)
			(layer "F.Fab")
			(effects
				(font
					(size 1.27 1.27)
				)
			)
		)
		(duplicate_pad_numbers_are_jumpers no)
		(fp_circle
			(center -0.942594 -0.103378)
			(end -0.942594 -0.230378)
			(stroke
				(width 0.254)
				(type default)
			)
			(fill no)
			(layer "F.SilkS")
		)
		(fp_rect
			(start -0.499872 2.70002)
			(end 2.100072 -0.599948)
			(stroke
				(width 0)
				(type default)
			)
			(fill no)
			(layer "F.CrtYd")
		)
		(fp_line
			(start -0.499872 2.70002)
			(end -0.499872 -0.599948)
			(stroke
				(width 0.1)
				(type default)
			)
			(layer "F.Fab")
		)
		(fp_line
			(start 2.100072 2.70002)
			(end -0.499872 2.70002)
			(stroke
				(width 0.1)
				(type default)
			)
			(layer "F.Fab")
		)
		(fp_line
			(start -0.499872 -0.599948)
			(end 2.100072 -0.599948)
			(stroke
				(width 0.1)
				(type default)
			)
			(layer "F.Fab")
		)
		(fp_line
			(start 2.100072 -0.599948)
			(end 2.100072 2.70002)
			(stroke
				(width 0.1)
				(type default)
			)
			(layer "F.Fab")
		)
		(fp_circle
			(center -1.049782 -0.44323)
			(end -1.049782 -0.57023)
			(stroke
				(width 0.254)
				(type default)
			)
			(fill no)
			(layer "F.Fab")
		)
		(pad "1" smd rect
			(at 0 0 270)
			(size 1.0414 1.143)
			(layers "F.Cu" "F.Mask" "F.Paste")
			(net "XTAL_KR_25M_IN")
		)
		(pad "2" smd rect
			(at 0 2.100072 270)
			(size 1.0414 1.143)
			(layers "F.Cu" "F.Mask" "F.Paste")
			(net "GND")
		)
		(pad "3" smd rect
			(at 1.6002 2.100072 270)
			(size 1.0414 1.143)
			(layers "F.Cu" "F.Mask" "F.Paste")
			(net "XTAL_KR_25M_OUT")
		)
		(pad "4" smd rect
			(at 1.6002 0 270)
			(size 1.0414 1.143)
			(layers "F.Cu" "F.Mask" "F.Paste")
			(net "GND")
		)
	)
	(footprint ""
		(layer "F.Cu")
		(at 340.233 -23.749)
		(property "Reference" "R7F14"
			(at 0 0 0)
			(layer "F.SilkS")
			(hide yes)
			(effects
				(font
					(size 1.27 1.27)
				)
			)
		)
		(property "Value" ""
			(at 0 0 0)
			(layer "F.Fab")
			(effects
				(font
					(size 1.27 1.27)
				)
			)
		)
		(duplicate_pad_numbers_are_jumpers no)
		(fp_rect
			(start -0.2794 0.9906)
			(end 0.2794 -0.1016)
			(stroke
				(width 0)
				(type default)
			)
			(fill no)
			(layer "F.CrtYd")
		)
		(fp_line
			(start -0.2794 -0.1016)
			(end -0.2794 0.9906)
			(stroke
				(width 0.1)
				(type default)
			)
			(layer "F.Fab")
		)
		(fp_line
			(start -0.2794 0.9906)
			(end 0.2794 0.9906)
			(stroke
				(width 0.1)
				(type default)
			)
			(layer "F.Fab")
		)
		(fp_line
			(start 0.2794 -0.1016)
			(end -0.2794 -0.1016)
			(stroke
				(width 0.1)
				(type default)
			)
			(layer "F.Fab")
		)
		(fp_line
			(start 0.2794 0.9906)
			(end 0.2794 -0.1016)
			(stroke
				(width 0.1)
				(type default)
			)
			(layer "F.Fab")
		)
		(pad "1" smd rect
			(at 0 0)
			(size 0.508 0.508)
			(layers "F.Cu" "F.Mask" "F.Paste")
			(net "FM_PVPP_CPU0_EN")
		)
		(pad "2" smd rect
			(at 0 0.889)
			(size 0.508 0.508)
			(layers "F.Cu" "F.Mask" "F.Paste")
			(net "GND")
		)
		(zone
			(layer "F.Cu")
			(hatch none 0.5)
			(connect_pads
				(clearance 0)
			)
			(min_thickness 0.25)
			(keepout
				(tracks allowed)
				(vias not_allowed)
				(pads allowed)
				(copperpour not_allowed)
				(footprints allowed)
			)
			(placement
				(enabled no)
				(sheetname "")
			)
			(fill
				(thermal_gap 0.5)
				(thermal_bridge_width 0.5)
				(island_removal_mode 0)
			)
			(polygon
				(pts
					(xy 339.979 -23.114) (xy 340.487 -23.114) (xy 340.487 -23.495) (xy 339.979 -23.495)
				)
			)
		)
		(zone
			(layer "F.Cu")
			(hatch none 0.5)
			(connect_pads
				(clearance 0)
			)
			(min_thickness 0.25)
			(keepout
				(tracks not_allowed)
				(vias allowed)
				(pads allowed)
				(copperpour not_allowed)
				(footprints allowed)
			)
			(placement
				(enabled no)
				(sheetname "")
			)
			(fill
				(thermal_gap 0.5)
				(thermal_bridge_width 0.5)
				(island_removal_mode 0)
			)
			(polygon
				(pts
					(xy 339.979 -23.114) (xy 340.487 -23.114) (xy 340.487 -23.495) (xy 339.979 -23.495)
				)
			)
		)
	)
	(footprint ""
		(layer "F.Cu")
		(at 204.4192 -77.47 -90)
		(property "Reference" "CT41"
			(at -0.8382 -0.67818 270)
			(unlocked yes)
			(layer "F.SilkS")
			(effects
				(font
					(size 0.4064 0.254)
					(thickness 0.1524)
				)
				(justify left)
			)
		)
		(property "Value" ""
			(at 0 0 270)
			(layer "F.Fab")
			(effects
				(font
					(size 1.27 1.27)
				)
			)
		)
		(duplicate_pad_numbers_are_jumpers no)
		(fp_poly
			(pts
				(xy 0.3048 -0.1016) (xy 0.3048 0.9906) (xy -0.3048 0.9906) (xy -0.3048 -0.1016)
			)
			(stroke
				(width 0)
				(type default)
			)
			(fill no)
			(layer "F.CrtYd")
		)
		(fp_line
			(start -0.3048 0.9906)
			(end 0.3048 0.9906)
			(stroke
				(width 0.1)
				(type default)
			)
			(layer "F.Fab")
		)
		(fp_line
			(start 0.3048 0.9906)
			(end 0.3048 -0.1016)
			(stroke
				(width 0.1)
				(type default)
			)
			(layer "F.Fab")
		)
		(fp_line
			(start -0.3048 -0.1016)
			(end -0.3048 0.9906)
			(stroke
				(width 0.1)
				(type default)
			)
			(layer "F.Fab")
		)
		(fp_line
			(start 0.3048 -0.1016)
			(end -0.3048 -0.1016)
			(stroke
				(width 0.1)
				(type default)
			)
			(layer "F.Fab")
		)
		(pad "1" smd rect
			(at 0 0 270)
			(size 0.508 0.508)
			(layers "F.Cu" "F.Mask" "F.Paste")
			(net "VR_PVCCIN_CPU0_PHASE4")
		)
		(pad "2" smd rect
			(at 0 0.889 270)
			(size 0.508 0.508)
			(layers "F.Cu" "F.Mask" "F.Paste")
			(net "VR_PVCCIN_CPU0_PHASE4_RC")
		)
		(zone
			(layer "F.Cu")
			(hatch none 0.5)
			(connect_pads
				(clearance 0)
			)
			(min_thickness 0.25)
			(keepout
				(tracks not_allowed)
				(vias allowed)
				(pads allowed)
				(copperpour not_allowed)
				(footprints allowed)
			)
			(placement
				(enabled no)
				(sheetname "")
			)
			(fill
				(thermal_gap 0.5)
				(thermal_bridge_width 0.5)
				(island_removal_mode 0)
			)
			(polygon
				(pts
					(xy 203.7842 -77.724) (xy 203.7842 -77.216) (xy 204.1652 -77.216) (xy 204.1652 -77.724)
				)
			)
		)
		(zone
			(layer "F.Cu")
			(hatch none 0.5)
			(connect_pads
				(clearance 0)
			)
			(min_thickness 0.25)
			(keepout
				(tracks allowed)
				(vias not_allowed)
				(pads allowed)
				(copperpour not_allowed)
				(footprints allowed)
			)
			(placement
				(enabled no)
				(sheetname "")
			)
			(fill
				(thermal_gap 0.5)
				(thermal_bridge_width 0.5)
				(island_removal_mode 0)
			)
			(polygon
				(pts
					(xy 204.1652 -77.724) (xy 204.1652 -77.216) (xy 203.7842 -77.216) (xy 203.7842 -77.724)
				)
			)
		)
	)
	(footprint ""
		(layer "F.Cu")
		(at 342.4428 -127.5588 90)
		(property "Reference" "C7B10"
			(at 0 0 90)
			(layer "F.SilkS")
			(hide yes)
			(effects
				(font
					(size 1.27 1.27)
				)
			)
		)
		(property "Value" ""
			(at 0 0 90)
			(layer "F.Fab")
			(effects
				(font
					(size 1.27 1.27)
				)
			)
		)
		(duplicate_pad_numbers_are_jumpers no)
		(fp_poly
			(pts
				(xy 0.3048 -0.1016) (xy 0.3048 0.9906) (xy -0.3048 0.9906) (xy -0.3048 -0.1016)
			)
			(stroke
				(width 0)
				(type default)
			)
			(fill no)
			(layer "F.CrtYd")
		)
		(fp_line
			(start 0.3048 -0.1016)
			(end -0.3048 -0.1016)
			(stroke
				(width 0.1)
				(type default)
			)
			(layer "F.Fab")
		)
		(fp_line
			(start -0.3048 -0.1016)
			(end -0.3048 0.9906)
			(stroke
				(width 0.1)
				(type default)
			)
			(layer "F.Fab")
		)
		(fp_line
			(start 0.3048 0.9906)
			(end 0.3048 -0.1016)
			(stroke
				(width 0.1)
				(type default)
			)
			(layer "F.Fab")
		)
		(fp_line
			(start -0.3048 0.9906)
			(end 0.3048 0.9906)
			(stroke
				(width 0.1)
				(type default)
			)
			(layer "F.Fab")
		)
		(pad "1" smd rect
			(at 0 0 90)
			(size 0.508 0.508)
			(layers "F.Cu" "F.Mask" "F.Paste")
			(net "VR_FB_PVPP_DEF")
		)
		(pad "2" smd rect
			(at 0 0.889 90)
			(size 0.508 0.508)
			(layers "F.Cu" "F.Mask" "F.Paste")
			(net "VR_COMP_PVPP_DEF_3")
		)
		(zone
			(layer "F.Cu")
			(hatch none 0.5)
			(connect_pads
				(clearance 0)
			)
			(min_thickness 0.25)
			(keepout
				(tracks allowed)
				(vias not_allowed)
				(pads allowed)
				(copperpour not_allowed)
				(footprints allowed)
			)
			(placement
				(enabled no)
				(sheetname "")
			)
			(fill
				(thermal_gap 0.5)
				(thermal_bridge_width 0.5)
				(island_removal_mode 0)
			)
			(polygon
				(pts
					(xy 342.6968 -127.3048) (xy 342.6968 -127.8128) (xy 343.0778 -127.8128) (xy 343.0778 -127.3048)
				)
			)
		)
		(zone
			(layer "F.Cu")
			(hatch none 0.5)
			(connect_pads
				(clearance 0)
			)
			(min_thickness 0.25)
			(keepout
				(tracks not_allowed)
				(vias allowed)
				(pads allowed)
				(copperpour not_allowed)
				(footprints allowed)
			)
			(placement
				(enabled no)
				(sheetname "")
			)
			(fill
				(thermal_gap 0.5)
				(thermal_bridge_width 0.5)
				(island_removal_mode 0)
			)
			(polygon
				(pts
					(xy 343.0778 -127.3048) (xy 343.0778 -127.8128) (xy 342.6968 -127.8128) (xy 342.6968 -127.3048)
				)
			)
		)
	)
	(footprint ""
		(layer "F.Cu")
		(at 462.114392 -37.956998)
		(property "Reference" "R9F11"
			(at 0 0 0)
			(layer "F.SilkS")
			(hide yes)
			(effects
				(font
					(size 1.27 1.27)
				)
			)
		)
		(property "Value" ""
			(at 0 0 0)
			(layer "F.Fab")
			(effects
				(font
					(size 1.27 1.27)
				)
			)
		)
		(duplicate_pad_numbers_are_jumpers no)
		(fp_poly
			(pts
				(xy -0.2794 -0.1016) (xy 0.2794 -0.1016) (xy 0.2794 0.9906) (xy -0.2794 0.9906)
			)
			(stroke
				(width 0)
				(type default)
			)
			(fill no)
			(layer "F.CrtYd")
		)
		(fp_line
			(start -0.2794 -0.1016)
			(end -0.2794 0.9906)
			(stroke
				(width 0.1)
				(type default)
			)
			(layer "F.Fab")
		)
		(fp_line
			(start -0.2794 0.9906)
			(end 0.2794 0.9906)
			(stroke
				(width 0.1)
				(type default)
			)
			(layer "F.Fab")
		)
		(fp_line
			(start 0.2794 -0.1016)
			(end -0.2794 -0.1016)
			(stroke
				(width 0.1)
				(type default)
			)
			(layer "F.Fab")
		)
		(fp_line
			(start 0.2794 0.9906)
			(end 0.2794 -0.1016)
			(stroke
				(width 0.1)
				(type default)
			)
			(layer "F.Fab")
		)
		(pad "1" smd rect
			(at 0 0)
			(size 0.508 0.508)
			(layers "F.Cu" "F.Mask" "F.Paste")
			(net "PWRGD_P1V15_BMC_STBY_R")
		)
		(pad "2" smd rect
			(at 0 0.889)
			(size 0.508 0.508)
			(layers "F.Cu" "F.Mask" "F.Paste")
			(net "PWRGD_P1V15_BMC_STBY")
		)
		(zone
			(layer "F.Cu")
			(hatch none 0.5)
			(connect_pads
				(clearance 0)
			)
			(min_thickness 0.25)
			(keepout
				(tracks allowed)
				(vias not_allowed)
				(pads allowed)
				(copperpour not_allowed)
				(footprints allowed)
			)
			(placement
				(enabled no)
				(sheetname "")
			)
			(fill
				(thermal_gap 0.5)
				(thermal_bridge_width 0.5)
				(island_removal_mode 0)
			)
			(polygon
				(pts
					(xy 461.860392 -37.702998) (xy 462.368392 -37.702998) (xy 462.368392 -37.321998) (xy 461.860392 -37.321998)
				)
			)
		)
		(zone
			(layer "F.Cu")
			(hatch none 0.5)
			(connect_pads
				(clearance 0)
			)
			(min_thickness 0.25)
			(keepout
				(tracks not_allowed)
				(vias allowed)
				(pads allowed)
				(copperpour not_allowed)
				(footprints allowed)
			)
			(placement
				(enabled no)
				(sheetname "")
			)
			(fill
				(thermal_gap 0.5)
				(thermal_bridge_width 0.5)
				(island_removal_mode 0)
			)
			(polygon
				(pts
					(xy 461.860392 -37.321998) (xy 462.368392 -37.321998) (xy 462.368392 -37.702998) (xy 461.860392 -37.702998)
				)
			)
		)
	)
	(footprint ""
		(layer "F.Cu")
		(at 454.025 -37.846 180)
		(property "Reference" "R9E24"
			(at 0 0 180)
			(layer "F.SilkS")
			(hide yes)
			(effects
				(font
					(size 1.27 1.27)
				)
			)
		)
		(property "Value" ""
			(at 0 0 180)
			(layer "F.Fab")
			(effects
				(font
					(size 1.27 1.27)
				)
			)
		)
		(duplicate_pad_numbers_are_jumpers no)
		(fp_poly
			(pts
				(xy -0.2794 -0.1016) (xy 0.2794 -0.1016) (xy 0.2794 0.9906) (xy -0.2794 0.9906)
			)
			(stroke
				(width 0)
				(type default)
			)
			(fill no)
			(layer "F.CrtYd")
		)
		(fp_line
			(start 0.2794 0.9906)
			(end 0.2794 -0.1016)
			(stroke
				(width 0.1)
				(type default)
			)
			(layer "F.Fab")
		)
		(fp_line
			(start 0.2794 -0.1016)
			(end -0.2794 -0.1016)
			(stroke
				(width 0.1)
				(type default)
			)
			(layer "F.Fab")
		)
		(fp_line
			(start -0.2794 0.9906)
			(end 0.2794 0.9906)
			(stroke
				(width 0.1)
				(type default)
			)
			(layer "F.Fab")
		)
		(fp_line
			(start -0.2794 -0.1016)
			(end -0.2794 0.9906)
			(stroke
				(width 0.1)
				(type default)
			)
			(layer "F.Fab")
		)
		(pad "1" smd rect
			(at 0 0 180)
			(size 0.508 0.508)
			(layers "F.Cu" "F.Mask" "F.Paste")
			(net "FM_HEARTBEAT_LED_A")
		)
		(pad "2" smd rect
			(at 0 0.889 180)
			(size 0.508 0.508)
			(layers "F.Cu" "F.Mask" "F.Paste")
			(net "P3V3_STBY")
		)
		(zone
			(layer "F.Cu")
			(hatch none 0.5)
			(connect_pads
				(clearance 0)
			)
			(min_thickness 0.25)
			(keepout
				(tracks not_allowed)
				(vias allowed)
				(pads allowed)
				(copperpour not_allowed)
				(footprints allowed)
			)
			(placement
				(enabled no)
				(sheetname "")
			)
			(fill
				(thermal_gap 0.5)
				(thermal_bridge_width 0.5)
				(island_removal_mode 0)
			)
			(polygon
				(pts
					(xy 454.279 -38.481) (xy 453.771 -38.481) (xy 453.771 -38.1) (xy 454.279 -38.1)
				)
			)
		)
		(zone
			(layer "F.Cu")
			(hatch none 0.5)
			(connect_pads
				(clearance 0)
			)
			(min_thickness 0.25)
			(keepout
				(tracks allowed)
				(vias not_allowed)
				(pads allowed)
				(copperpour not_allowed)
				(footprints allowed)
			)
			(placement
				(enabled no)
				(sheetname "")
			)
			(fill
				(thermal_gap 0.5)
				(thermal_bridge_width 0.5)
				(island_removal_mode 0)
			)
			(polygon
				(pts
					(xy 454.279 -38.1) (xy 453.771 -38.1) (xy 453.771 -38.481) (xy 454.279 -38.481)
				)
			)
		)
	)
	(footprint ""
		(layer "F.Cu")
		(at 463.3849 -23.9903 180)
		(property "Reference" "C8E17"
			(at 0 0 180)
			(layer "F.SilkS")
			(hide yes)
			(effects
				(font
					(size 1.27 1.27)
				)
			)
		)
		(property "Value" ""
			(at 0 0 180)
			(layer "F.Fab")
			(effects
				(font
					(size 1.27 1.27)
				)
			)
		)
		(duplicate_pad_numbers_are_jumpers no)
		(fp_rect
			(start 0.3048 0.9906)
			(end -0.3048 -0.1016)
			(stroke
				(width 0)
				(type default)
			)
			(fill no)
			(layer "F.CrtYd")
		)
		(fp_line
			(start 0.3048 0.9906)
			(end 0.3048 -0.1016)
			(stroke
				(width 0.1)
				(type default)
			)
			(layer "F.Fab")
		)
		(fp_line
			(start 0.3048 -0.1016)
			(end -0.3048 -0.1016)
			(stroke
				(width 0.1)
				(type default)
			)
			(layer "F.Fab")
		)
		(fp_line
			(start -0.3048 0.9906)
			(end 0.3048 0.9906)
			(stroke
				(width 0.1)
				(type default)
			)
			(layer "F.Fab")
		)
		(fp_line
			(start -0.3048 -0.1016)
			(end -0.3048 0.9906)
			(stroke
				(width 0.1)
				(type default)
			)
			(layer "F.Fab")
		)
		(pad "1" smd rect
			(at 0 0 180)
			(size 0.508 0.508)
			(layers "F.Cu" "F.Mask" "F.Paste")
			(net "PWRGD_P5V_STBY")
		)
		(pad "2" smd rect
			(at 0 0.889 180)
			(size 0.508 0.508)
			(layers "F.Cu" "F.Mask" "F.Paste")
			(net "AGND_P3V3_STBY")
		)
		(zone
			(layer "F.Cu")
			(hatch none 0.5)
			(connect_pads
				(clearance 0)
			)
			(min_thickness 0.25)
			(keepout
				(tracks not_allowed)
				(vias allowed)
				(pads allowed)
				(copperpour not_allowed)
				(footprints allowed)
			)
			(placement
				(enabled no)
				(sheetname "")
			)
			(fill
				(thermal_gap 0.5)
				(thermal_bridge_width 0.5)
				(island_removal_mode 0)
			)
			(polygon
				(pts
					(xy 463.1309 -24.6253) (xy 463.1309 -24.2443) (xy 463.6389 -24.2443) (xy 463.6389 -24.6253)
				)
			)
		)
		(zone
			(layer "F.Cu")
			(hatch none 0.5)
			(connect_pads
				(clearance 0)
			)
			(min_thickness 0.25)
			(keepout
				(tracks allowed)
				(vias not_allowed)
				(pads allowed)
				(copperpour not_allowed)
				(footprints allowed)
			)
			(placement
				(enabled no)
				(sheetname "")
			)
			(fill
				(thermal_gap 0.5)
				(thermal_bridge_width 0.5)
				(island_removal_mode 0)
			)
			(polygon
				(pts
					(xy 463.1309 -24.6253) (xy 463.1309 -24.2443) (xy 463.6389 -24.2443) (xy 463.6389 -24.6253)
				)
			)
		)
	)
	(footprint ""
		(layer "F.Cu")
		(at 338.074 -11.684 90)
		(property "Reference" "C7G27"
			(at 0 0 90)
			(layer "F.SilkS")
			(hide yes)
			(effects
				(font
					(size 1.27 1.27)
				)
			)
		)
		(property "Value" ""
			(at 0 0 90)
			(layer "F.Fab")
			(effects
				(font
					(size 1.27 1.27)
				)
			)
		)
		(duplicate_pad_numbers_are_jumpers no)
		(fp_rect
			(start 0.7239 -0.2159)
			(end -0.7239 1.9939)
			(stroke
				(width 0)
				(type default)
			)
			(fill no)
			(layer "F.CrtYd")
		)
		(fp_line
			(start 0.7239 -0.2159)
			(end -0.7239 -0.2159)
			(stroke
				(width 0.1)
				(type default)
			)
			(layer "F.Fab")
		)
		(fp_line
			(start -0.7239 -0.2159)
			(end -0.7239 1.9939)
			(stroke
				(width 0.1)
				(type default)
			)
			(layer "F.Fab")
		)
		(fp_line
			(start 0.7239 1.9939)
			(end 0.7239 -0.2159)
			(stroke
				(width 0.1)
				(type default)
			)
			(layer "F.Fab")
		)
		(fp_line
			(start -0.7239 1.9939)
			(end 0.7239 1.9939)
			(stroke
				(width 0.1)
				(type default)
			)
			(layer "F.Fab")
		)
		(pad "1" smd rect
			(at 0 0 90)
			(size 1.27 1.016)
			(layers "F.Cu" "F.Mask" "F.Paste")
			(net "PVDDQ_ABC")
		)
		(pad "2" smd rect
			(at 0 1.778 90)
			(size 1.27 1.016)
			(layers "F.Cu" "F.Mask" "F.Paste")
			(net "GND")
		)
		(zone
			(layer "F.Cu")
			(hatch none 0.5)
			(connect_pads
				(clearance 0)
			)
			(min_thickness 0.25)
			(keepout
				(tracks not_allowed)
				(vias allowed)
				(pads allowed)
				(copperpour not_allowed)
				(footprints allowed)
			)
			(placement
				(enabled no)
				(sheetname "")
			)
			(fill
				(thermal_gap 0.5)
				(thermal_bridge_width 0.5)
				(island_removal_mode 0)
			)
			(polygon
				(pts
					(xy 338.582 -12.319) (xy 338.582 -11.049) (xy 339.344 -11.049) (xy 339.344 -12.319)
				)
			)
		)
	)
	(footprint ""
		(layer "F.Cu")
		(at 105.712768 -79.6036 180)
		(property "Reference" "C2D18"
			(at 0 0 180)
			(layer "F.SilkS")
			(hide yes)
			(effects
				(font
					(size 1.27 1.27)
				)
			)
		)
		(property "Value" ""
			(at 0 0 180)
			(layer "F.Fab")
			(effects
				(font
					(size 1.27 1.27)
				)
			)
		)
		(duplicate_pad_numbers_are_jumpers no)
		(fp_poly
			(pts
				(xy -0.4953 -0.2032) (xy 0.4953 -0.2032) (xy 0.4953 1.6002) (xy -0.4953 1.6002)
			)
			(stroke
				(width 0)
				(type default)
			)
			(fill no)
			(layer "F.CrtYd")
		)
		(fp_line
			(start 0.4953 1.6002)
			(end -0.4953 1.6002)
			(stroke
				(width 0.1)
				(type default)
			)
			(layer "F.Fab")
		)
		(fp_line
			(start 0.4953 -0.2032)
			(end 0.4953 1.6002)
			(stroke
				(width 0.1)
				(type default)
			)
			(layer "F.Fab")
		)
		(fp_line
			(start -0.4953 1.6002)
			(end -0.4953 -0.2032)
			(stroke
				(width 0.1)
				(type default)
			)
			(layer "F.Fab")
		)
		(fp_line
			(start -0.4953 -0.2032)
			(end 0.4953 -0.2032)
			(stroke
				(width 0.1)
				(type default)
			)
			(layer "F.Fab")
		)
		(pad "1" smd rect
			(at 0 0 180)
			(size 0.762 0.889)
			(layers "F.Cu" "F.Mask" "F.Paste")
			(net "PVCCMCP_CPU1")
		)
		(pad "2" smd rect
			(at 0 1.397 180)
			(size 0.762 0.889)
			(layers "F.Cu" "F.Mask" "F.Paste")
			(net "GND")
		)
		(zone
			(layer "F.Cu")
			(hatch none 0.5)
			(connect_pads
				(clearance 0)
			)
			(min_thickness 0.25)
			(keepout
				(tracks not_allowed)
				(vias allowed)
				(pads allowed)
				(copperpour not_allowed)
				(footprints allowed)
			)
			(placement
				(enabled no)
				(sheetname "")
			)
			(fill
				(thermal_gap 0.5)
				(thermal_bridge_width 0.5)
				(island_removal_mode 0)
			)
			(polygon
				(pts
					(xy 106.093768 -80.0481) (xy 105.331768 -80.0481) (xy 105.331768 -80.5561) (xy 106.093768 -80.5561)
				)
			)
		)
	)
	(footprint ""
		(layer "F.Cu")
		(at 172.3771 -132.4864 90)
		(property "Reference" "R4B1"
			(at 0 0 90)
			(layer "F.SilkS")
			(hide yes)
			(effects
				(font
					(size 1.27 1.27)
				)
			)
		)
		(property "Value" ""
			(at 0 0 90)
			(layer "F.Fab")
			(effects
				(font
					(size 1.27 1.27)
				)
			)
		)
		(duplicate_pad_numbers_are_jumpers no)
		(fp_poly
			(pts
				(xy -0.2794 -0.1016) (xy 0.2794 -0.1016) (xy 0.2794 0.9906) (xy -0.2794 0.9906)
			)
			(stroke
				(width 0)
				(type default)
			)
			(fill no)
			(layer "F.CrtYd")
		)
		(fp_line
			(start 0.2794 -0.1016)
			(end -0.2794 -0.1016)
			(stroke
				(width 0.1)
				(type default)
			)
			(layer "F.Fab")
		)
		(fp_line
			(start -0.2794 -0.1016)
			(end -0.2794 0.9906)
			(stroke
				(width 0.1)
				(type default)
			)
			(layer "F.Fab")
		)
		(fp_line
			(start 0.2794 0.9906)
			(end 0.2794 -0.1016)
			(stroke
				(width 0.1)
				(type default)
			)
			(layer "F.Fab")
		)
		(fp_line
			(start -0.2794 0.9906)
			(end 0.2794 0.9906)
			(stroke
				(width 0.1)
				(type default)
			)
			(layer "F.Fab")
		)
		(pad "1" smd rect
			(at 0 0 90)
			(size 0.508 0.508)
			(layers "F.Cu" "F.Mask" "F.Paste")
			(net "FM_PVPP_CPU1_EN")
		)
		(pad "2" smd rect
			(at 0 0.889 90)
			(size 0.508 0.508)
			(layers "F.Cu" "F.Mask" "F.Paste")
			(net "FM_PVPP_PVDDQ_CPU1_EN_KLM")
		)
		(zone
			(layer "F.Cu")
			(hatch none 0.5)
			(connect_pads
				(clearance 0)
			)
			(min_thickness 0.25)
			(keepout
				(tracks allowed)
				(vias not_allowed)
				(pads allowed)
				(copperpour not_allowed)
				(footprints allowed)
			)
			(placement
				(enabled no)
				(sheetname "")
			)
			(fill
				(thermal_gap 0.5)
				(thermal_bridge_width 0.5)
				(island_removal_mode 0)
			)
			(polygon
				(pts
					(xy 172.6311 -132.2324) (xy 172.6311 -132.7404) (xy 173.0121 -132.7404) (xy 173.0121 -132.2324)
				)
			)
		)
		(zone
			(layer "F.Cu")
			(hatch none 0.5)
			(connect_pads
				(clearance 0)
			)
			(min_thickness 0.25)
			(keepout
				(tracks not_allowed)
				(vias allowed)
				(pads allowed)
				(copperpour not_allowed)
				(footprints allowed)
			)
			(placement
				(enabled no)
				(sheetname "")
			)
			(fill
				(thermal_gap 0.5)
				(thermal_bridge_width 0.5)
				(island_removal_mode 0)
			)
			(polygon
				(pts
					(xy 173.0121 -132.2324) (xy 173.0121 -132.7404) (xy 172.6311 -132.7404) (xy 172.6311 -132.2324)
				)
			)
		)
	)
	(footprint ""
		(layer "F.Cu")
		(at 181.5084 -146.812)
		(property "Reference" "C4A10"
			(at 0 0 0)
			(layer "F.SilkS")
			(hide yes)
			(effects
				(font
					(size 1.27 1.27)
				)
			)
		)
		(property "Value" ""
			(at 0 0 0)
			(layer "F.Fab")
			(effects
				(font
					(size 1.27 1.27)
				)
			)
		)
		(duplicate_pad_numbers_are_jumpers no)
		(fp_rect
			(start 0.3048 -0.1016)
			(end -0.3048 0.9906)
			(stroke
				(width 0)
				(type default)
			)
			(fill no)
			(layer "F.CrtYd")
		)
		(fp_line
			(start -0.3048 -0.1016)
			(end -0.3048 0.9906)
			(stroke
				(width 0.1)
				(type default)
			)
			(layer "F.Fab")
		)
		(fp_line
			(start -0.3048 0.9906)
			(end 0.3048 0.9906)
			(stroke
				(width 0.1)
				(type default)
			)
			(layer "F.Fab")
		)
		(fp_line
			(start 0.3048 -0.1016)
			(end -0.3048 -0.1016)
			(stroke
				(width 0.1)
				(type default)
			)
			(layer "F.Fab")
		)
		(fp_line
			(start 0.3048 0.9906)
			(end 0.3048 -0.1016)
			(stroke
				(width 0.1)
				(type default)
			)
			(layer "F.Fab")
		)
		(pad "1" smd rect
			(at 0 0)
			(size 0.508 0.508)
			(layers "F.Cu" "F.Mask" "F.Paste")
			(net "VR_PVTT_DEF_BIAS")
		)
		(pad "2" smd rect
			(at 0 0.889)
			(size 0.508 0.508)
			(layers "F.Cu" "F.Mask" "F.Paste")
			(net "GND")
		)
		(zone
			(layer "F.Cu")
			(hatch none 0.5)
			(connect_pads
				(clearance 0)
			)
			(min_thickness 0.25)
			(keepout
				(tracks not_allowed)
				(vias allowed)
				(pads allowed)
				(copperpour not_allowed)
				(footprints allowed)
			)
			(placement
				(enabled no)
				(sheetname "")
			)
			(fill
				(thermal_gap 0.5)
				(thermal_bridge_width 0.5)
				(island_removal_mode 0)
			)
			(polygon
				(pts
					(xy 181.7624 -146.558) (xy 181.2544 -146.558) (xy 181.2544 -146.177) (xy 181.7624 -146.177)
				)
			)
		)
		(zone
			(layer "F.Cu")
			(hatch none 0.5)
			(connect_pads
				(clearance 0)
			)
			(min_thickness 0.25)
			(keepout
				(tracks allowed)
				(vias not_allowed)
				(pads allowed)
				(copperpour not_allowed)
				(footprints allowed)
			)
			(placement
				(enabled no)
				(sheetname "")
			)
			(fill
				(thermal_gap 0.5)
				(thermal_bridge_width 0.5)
				(island_removal_mode 0)
			)
			(polygon
				(pts
					(xy 181.7624 -146.558) (xy 181.2544 -146.558) (xy 181.2544 -146.177) (xy 181.7624 -146.177)
				)
			)
		)
	)
	(footprint ""
		(layer "F.Cu")
		(at 205.036928 -89.289382)
		(property "Reference" "L4C3"
			(at 3.378708 -4.251706 0)
			(unlocked yes)
			(layer "F.SilkS")
			(effects
				(font
					(size 0.4064 0.254)
					(thickness 0.1524)
				)
			)
		)
		(property "Value" ""
			(at 0 0 0)
			(layer "F.Fab")
			(effects
				(font
					(size 1.27 1.27)
				)
			)
		)
		(duplicate_pad_numbers_are_jumpers no)
		(fp_line
			(start -1.1303 -3.199892)
			(end 8.3693 -3.199892)
			(stroke
				(width 0.1524)
				(type default)
			)
			(layer "F.SilkS")
		)
		(fp_line
			(start -1.1303 -1.6637)
			(end -1.1303 -3.199892)
			(stroke
				(width 0.1524)
				(type default)
			)
			(layer "F.SilkS")
		)
		(fp_line
			(start -1.1303 3.199892)
			(end -1.1303 1.6637)
			(stroke
				(width 0.1524)
				(type default)
			)
			(layer "F.SilkS")
		)
		(fp_line
			(start 8.3693 -3.199892)
			(end 8.3693 -1.6637)
			(stroke
				(width 0.1524)
				(type default)
			)
			(layer "F.SilkS")
		)
		(fp_line
			(start 8.3693 1.6637)
			(end 8.3693 3.199892)
			(stroke
				(width 0.1524)
				(type default)
			)
			(layer "F.SilkS")
		)
		(fp_line
			(start 8.3693 3.199892)
			(end -1.1303 3.199892)
			(stroke
				(width 0.1524)
				(type default)
			)
			(layer "F.SilkS")
		)
		(fp_rect
			(start -1.1303 3.199892)
			(end 8.3693 -3.199892)
			(stroke
				(width 0)
				(type default)
			)
			(fill no)
			(layer "F.CrtYd")
		)
		(fp_line
			(start -1.1303 -3.199892)
			(end 8.3693 -3.199892)
			(stroke
				(width 0.1)
				(type default)
			)
			(layer "F.Fab")
		)
		(fp_line
			(start -1.1303 3.199892)
			(end -1.1303 -3.199892)
			(stroke
				(width 0.1)
				(type default)
			)
			(layer "F.Fab")
		)
		(fp_line
			(start 8.3693 -3.199892)
			(end 8.3693 3.199892)
			(stroke
				(width 0.1)
				(type default)
			)
			(layer "F.Fab")
		)
		(fp_line
			(start 8.3693 3.199892)
			(end -1.1303 3.199892)
			(stroke
				(width 0.1)
				(type default)
			)
			(layer "F.Fab")
		)
		(pad "1" smd rect
			(at 0 0)
			(size 3.683 2.667)
			(layers "F.Cu" "F.Mask" "F.Paste")
			(net "VR_PVCCIN_CPU0_PHASE5")
		)
		(pad "2" smd rect
			(at 7.239 0)
			(size 3.683 2.667)
			(layers "F.Cu" "F.Mask" "F.Paste")
			(net "PVCCIN_CPU0")
		)
	)
	(footprint ""
		(layer "F.Cu")
		(at -4.191 -125.222)
		(property "Reference" "R12W36"
			(at -0.8382 -0.67818 0)
			(unlocked yes)
			(layer "F.SilkS")
			(effects
				(font
					(size 0.4064 0.254)
					(thickness 0.1524)
				)
				(justify left)
			)
		)
		(property "Value" ""
			(at 0 0 0)
			(layer "F.Fab")
			(effects
				(font
					(size 1.27 1.27)
				)
			)
		)
		(duplicate_pad_numbers_are_jumpers no)
		(fp_poly
			(pts
				(xy -0.2794 -0.1016) (xy 0.2794 -0.1016) (xy 0.2794 0.9906) (xy -0.2794 0.9906)
			)
			(stroke
				(width 0)
				(type default)
			)
			(fill no)
			(layer "F.CrtYd")
		)
		(fp_line
			(start -0.2794 -0.1016)
			(end -0.2794 0.9906)
			(stroke
				(width 0.1)
				(type default)
			)
			(layer "F.Fab")
		)
		(fp_line
			(start -0.2794 0.9906)
			(end 0.2794 0.9906)
			(stroke
				(width 0.1)
				(type default)
			)
			(layer "F.Fab")
		)
		(fp_line
			(start 0.2794 -0.1016)
			(end -0.2794 -0.1016)
			(stroke
				(width 0.1)
				(type default)
			)
			(layer "F.Fab")
		)
		(fp_line
			(start 0.2794 0.9906)
			(end 0.2794 -0.1016)
			(stroke
				(width 0.1)
				(type default)
			)
			(layer "F.Fab")
		)
		(pad "1" smd rect
			(at 0 0)
			(size 0.508 0.508)
			(layers "F.Cu" "F.Mask" "F.Paste")
			(net "NC_PVDDQ_KLM_GP0")
		)
		(pad "2" smd rect
			(at 0 0.889)
			(size 0.508 0.508)
			(layers "F.Cu" "F.Mask" "F.Paste")
			(net "PWRGD_PVDDQ_KLM")
		)
		(zone
			(layer "F.Cu")
			(hatch none 0.5)
			(connect_pads
				(clearance 0)
			)
			(min_thickness 0.25)
			(keepout
				(tracks allowed)
				(vias not_allowed)
				(pads allowed)
				(copperpour not_allowed)
				(footprints allowed)
			)
			(placement
				(enabled no)
				(sheetname "")
			)
			(fill
				(thermal_gap 0.5)
				(thermal_bridge_width 0.5)
				(island_removal_mode 0)
			)
			(polygon
				(pts
					(xy -4.445 -124.968) (xy -3.937 -124.968) (xy -3.937 -124.587) (xy -4.445 -124.587)
				)
			)
		)
		(zone
			(layer "F.Cu")
			(hatch none 0.5)
			(connect_pads
				(clearance 0)
			)
			(min_thickness 0.25)
			(keepout
				(tracks not_allowed)
				(vias allowed)
				(pads allowed)
				(copperpour not_allowed)
				(footprints allowed)
			)
			(placement
				(enabled no)
				(sheetname "")
			)
			(fill
				(thermal_gap 0.5)
				(thermal_bridge_width 0.5)
				(island_removal_mode 0)
			)
			(polygon
				(pts
					(xy -4.445 -124.587) (xy -3.937 -124.587) (xy -3.937 -124.968) (xy -4.445 -124.968)
				)
			)
		)
	)
	(footprint ""
		(layer "F.Cu")
		(at 278.13 -83.8454)
		(property "Reference" "R6D2"
			(at 0 0 0)
			(layer "F.SilkS")
			(hide yes)
			(effects
				(font
					(size 1.27 1.27)
				)
			)
		)
		(property "Value" ""
			(at 0 0 0)
			(layer "F.Fab")
			(effects
				(font
					(size 1.27 1.27)
				)
			)
		)
		(duplicate_pad_numbers_are_jumpers no)
		(fp_poly
			(pts
				(xy -0.2794 -0.1016) (xy 0.2794 -0.1016) (xy 0.2794 0.9906) (xy -0.2794 0.9906)
			)
			(stroke
				(width 0)
				(type default)
			)
			(fill no)
			(layer "F.CrtYd")
		)
		(fp_line
			(start -0.2794 -0.1016)
			(end -0.2794 0.9906)
			(stroke
				(width 0.1)
				(type default)
			)
			(layer "F.Fab")
		)
		(fp_line
			(start -0.2794 0.9906)
			(end 0.2794 0.9906)
			(stroke
				(width 0.1)
				(type default)
			)
			(layer "F.Fab")
		)
		(fp_line
			(start 0.2794 -0.1016)
			(end -0.2794 -0.1016)
			(stroke
				(width 0.1)
				(type default)
			)
			(layer "F.Fab")
		)
		(fp_line
			(start 0.2794 0.9906)
			(end 0.2794 -0.1016)
			(stroke
				(width 0.1)
				(type default)
			)
			(layer "F.Fab")
		)
		(pad "1" smd rect
			(at 0 0)
			(size 0.508 0.508)
			(layers "F.Cu" "F.Mask" "F.Paste")
			(net "A_CPU0_MCP01_RBIAS")
		)
		(pad "2" smd rect
			(at 0 0.889)
			(size 0.508 0.508)
			(layers "F.Cu" "F.Mask" "F.Paste")
			(net "GND")
		)
		(zone
			(layer "F.Cu")
			(hatch none 0.5)
			(connect_pads
				(clearance 0)
			)
			(min_thickness 0.25)
			(keepout
				(tracks allowed)
				(vias not_allowed)
				(pads allowed)
				(copperpour not_allowed)
				(footprints allowed)
			)
			(placement
				(enabled no)
				(sheetname "")
			)
			(fill
				(thermal_gap 0.5)
				(thermal_bridge_width 0.5)
				(island_removal_mode 0)
			)
			(polygon
				(pts
					(xy 277.876 -83.5914) (xy 278.384 -83.5914) (xy 278.384 -83.2104) (xy 277.876 -83.2104)
				)
			)
		)
		(zone
			(layer "F.Cu")
			(hatch none 0.5)
			(connect_pads
				(clearance 0)
			)
			(min_thickness 0.25)
			(keepout
				(tracks not_allowed)
				(vias allowed)
				(pads allowed)
				(copperpour not_allowed)
				(footprints allowed)
			)
			(placement
				(enabled no)
				(sheetname "")
			)
			(fill
				(thermal_gap 0.5)
				(thermal_bridge_width 0.5)
				(island_removal_mode 0)
			)
			(polygon
				(pts
					(xy 277.876 -83.2104) (xy 278.384 -83.2104) (xy 278.384 -83.5914) (xy 277.876 -83.5914)
				)
			)
		)
	)
	(footprint ""
		(layer "F.Cu")
		(at 252.1585 -12.954 -90)
		(property "Reference" "C5G3"
			(at 1.848866 0.752348 270)
			(unlocked yes)
			(layer "F.SilkS")
			(effects
				(font
					(size 1.27 0.9652)
					(thickness 0.1524)
				)
			)
		)
		(property "Value" ""
			(at 0 0 270)
			(layer "F.Fab")
			(effects
				(font
					(size 1.27 1.27)
				)
			)
		)
		(duplicate_pad_numbers_are_jumpers no)
		(fp_rect
			(start -0.500126 1.598422)
			(end 0.500126 -0.201422)
			(stroke
				(width 0)
				(type default)
			)
			(fill no)
			(layer "F.CrtYd")
		)
		(fp_line
			(start -0.500126 1.598422)
			(end -0.500126 -0.201422)
			(stroke
				(width 0.1)
				(type default)
			)
			(layer "F.Fab")
		)
		(fp_line
			(start 0.500126 1.598422)
			(end -0.500126 1.598422)
			(stroke
				(width 0.1)
				(type default)
			)
			(layer "F.Fab")
		)
		(fp_line
			(start -0.500126 -0.201422)
			(end 0.500126 -0.201422)
			(stroke
				(width 0.1)
				(type default)
			)
			(layer "F.Fab")
		)
		(fp_line
			(start 0.500126 -0.201422)
			(end 0.500126 1.598422)
			(stroke
				(width 0.1)
				(type default)
			)
			(layer "F.Fab")
		)
		(pad "1" smd rect
			(at 0 0 180)
			(size 0.889 0.9906)
			(layers "F.Cu" "F.Mask" "F.Paste")
			(net "PVDDQ_ABC")
		)
		(pad "2" smd rect
			(at 0 1.397 180)
			(size 0.889 0.9906)
			(layers "F.Cu" "F.Mask" "F.Paste")
			(net "GND")
		)
		(zone
			(layer "F.Cu")
			(hatch none 0.5)
			(connect_pads
				(clearance 0)
			)
			(min_thickness 0.25)
			(keepout
				(tracks allowed)
				(vias not_allowed)
				(pads allowed)
				(copperpour not_allowed)
				(footprints allowed)
			)
			(placement
				(enabled no)
				(sheetname "")
			)
			(fill
				(thermal_gap 0.5)
				(thermal_bridge_width 0.5)
				(island_removal_mode 0)
			)
			(polygon
				(pts
					(xy 251.206 -13.4493) (xy 251.206 -12.4587) (xy 251.714 -12.4587) (xy 251.714 -13.4493)
				)
			)
		)
		(zone
			(layer "F.Cu")
			(hatch none 0.5)
			(connect_pads
				(clearance 0)
			)
			(min_thickness 0.25)
			(keepout
				(tracks not_allowed)
				(vias allowed)
				(pads allowed)
				(copperpour not_allowed)
				(footprints allowed)
			)
			(placement
				(enabled no)
				(sheetname "")
			)
			(fill
				(thermal_gap 0.5)
				(thermal_bridge_width 0.5)
				(island_removal_mode 0)
			)
			(polygon
				(pts
					(xy 251.206 -13.4493) (xy 251.206 -12.4587) (xy 251.714 -12.4587) (xy 251.714 -13.4493)
				)
			)
		)
	)
	(footprint ""
		(layer "F.Cu")
		(at 381.576072 -155.432506 180)
		(property "Reference" "C7A10"
			(at 0 0 180)
			(layer "F.SilkS")
			(hide yes)
			(effects
				(font
					(size 1.27 1.27)
				)
			)
		)
		(property "Value" ""
			(at 0 0 180)
			(layer "F.Fab")
			(effects
				(font
					(size 1.27 1.27)
				)
			)
		)
		(duplicate_pad_numbers_are_jumpers no)
		(fp_poly
			(pts
				(xy 0.3048 -0.1016) (xy 0.3048 0.9906) (xy -0.3048 0.9906) (xy -0.3048 -0.1016)
			)
			(stroke
				(width 0)
				(type default)
			)
			(fill no)
			(layer "F.CrtYd")
		)
		(fp_line
			(start 0.3048 0.9906)
			(end 0.3048 -0.1016)
			(stroke
				(width 0.1)
				(type default)
			)
			(layer "F.Fab")
		)
		(fp_line
			(start 0.3048 -0.1016)
			(end -0.3048 -0.1016)
			(stroke
				(width 0.1)
				(type default)
			)
			(layer "F.Fab")
		)
		(fp_line
			(start -0.3048 0.9906)
			(end 0.3048 0.9906)
			(stroke
				(width 0.1)
				(type default)
			)
			(layer "F.Fab")
		)
		(fp_line
			(start -0.3048 -0.1016)
			(end -0.3048 0.9906)
			(stroke
				(width 0.1)
				(type default)
			)
			(layer "F.Fab")
		)
		(pad "1" smd rect
			(at 0 0 180)
			(size 0.508 0.508)
			(layers "F.Cu" "F.Mask" "F.Paste")
			(net "VR_P1V05_PCH_STBY_PH1_VCIN")
		)
		(pad "2" smd rect
			(at 0 0.889 180)
			(size 0.508 0.508)
			(layers "F.Cu" "F.Mask" "F.Paste")
			(net "GND")
		)
		(zone
			(layer "F.Cu")
			(hatch none 0.5)
			(connect_pads
				(clearance 0)
			)
			(min_thickness 0.25)
			(keepout
				(tracks not_allowed)
				(vias allowed)
				(pads allowed)
				(copperpour not_allowed)
				(footprints allowed)
			)
			(placement
				(enabled no)
				(sheetname "")
			)
			(fill
				(thermal_gap 0.5)
				(thermal_bridge_width 0.5)
				(island_removal_mode 0)
			)
			(polygon
				(pts
					(xy 381.830072 -156.067506) (xy 381.322072 -156.067506) (xy 381.322072 -155.686506) (xy 381.830072 -155.686506)
				)
			)
		)
		(zone
			(layer "F.Cu")
			(hatch none 0.5)
			(connect_pads
				(clearance 0)
			)
			(min_thickness 0.25)
			(keepout
				(tracks allowed)
				(vias not_allowed)
				(pads allowed)
				(copperpour not_allowed)
				(footprints allowed)
			)
			(placement
				(enabled no)
				(sheetname "")
			)
			(fill
				(thermal_gap 0.5)
				(thermal_bridge_width 0.5)
				(island_removal_mode 0)
			)
			(polygon
				(pts
					(xy 381.830072 -155.686506) (xy 381.322072 -155.686506) (xy 381.322072 -156.067506) (xy 381.830072 -156.067506)
				)
			)
		)
	)
	(footprint ""
		(layer "F.Cu")
		(at 447.104262 -29.378148 90)
		(property "Reference" "C25W19"
			(at 0.97536 0.76708 0)
			(unlocked yes)
			(layer "F.SilkS")
			(effects
				(font
					(size 0.4064 0.254)
					(thickness 0.1524)
				)
			)
		)
		(property "Value" ""
			(at 0 0 90)
			(layer "F.Fab")
			(effects
				(font
					(size 1.27 1.27)
				)
			)
		)
		(duplicate_pad_numbers_are_jumpers no)
		(fp_poly
			(pts
				(xy -0.4953 -0.2032) (xy 0.4953 -0.2032) (xy 0.4953 1.6002) (xy -0.4953 1.6002)
			)
			(stroke
				(width 0)
				(type default)
			)
			(fill no)
			(layer "F.CrtYd")
		)
		(fp_line
			(start 0.4953 -0.2032)
			(end 0.4953 1.6002)
			(stroke
				(width 0.1)
				(type default)
			)
			(layer "F.Fab")
		)
		(fp_line
			(start -0.4953 -0.2032)
			(end 0.4953 -0.2032)
			(stroke
				(width 0.1)
				(type default)
			)
			(layer "F.Fab")
		)
		(fp_line
			(start 0.4953 1.6002)
			(end -0.4953 1.6002)
			(stroke
				(width 0.1)
				(type default)
			)
			(layer "F.Fab")
		)
		(fp_line
			(start -0.4953 1.6002)
			(end -0.4953 -0.2032)
			(stroke
				(width 0.1)
				(type default)
			)
			(layer "F.Fab")
		)
		(pad "1" smd rect
			(at 0 0 90)
			(size 0.762 0.889)
			(layers "F.Cu" "F.Mask" "F.Paste")
			(net "P1V2_AUX_BMC")
		)
		(pad "2" smd rect
			(at 0 1.397 90)
			(size 0.762 0.889)
			(layers "F.Cu" "F.Mask" "F.Paste")
			(net "GND")
		)
		(zone
			(layer "F.Cu")
			(hatch none 0.5)
			(connect_pads
				(clearance 0)
			)
			(min_thickness 0.25)
			(keepout
				(tracks not_allowed)
				(vias allowed)
				(pads allowed)
				(copperpour not_allowed)
				(footprints allowed)
			)
			(placement
				(enabled no)
				(sheetname "")
			)
			(fill
				(thermal_gap 0.5)
				(thermal_bridge_width 0.5)
				(island_removal_mode 0)
			)
			(polygon
				(pts
					(xy 447.548762 -28.997148) (xy 447.548762 -29.759148) (xy 448.056762 -29.759148) (xy 448.056762 -28.997148)
				)
			)
		)
	)
	(footprint ""
		(layer "F.Cu")
		(at 175.387 -85.217 90)
		(property "Reference" "R4D10"
			(at 0 0 90)
			(layer "F.SilkS")
			(hide yes)
			(effects
				(font
					(size 1.27 1.27)
				)
			)
		)
		(property "Value" ""
			(at 0 0 90)
			(layer "F.Fab")
			(effects
				(font
					(size 1.27 1.27)
				)
			)
		)
		(duplicate_pad_numbers_are_jumpers no)
		(fp_poly
			(pts
				(xy -0.2794 -0.1016) (xy 0.2794 -0.1016) (xy 0.2794 0.9906) (xy -0.2794 0.9906)
			)
			(stroke
				(width 0)
				(type default)
			)
			(fill no)
			(layer "F.CrtYd")
		)
		(fp_line
			(start 0.2794 -0.1016)
			(end -0.2794 -0.1016)
			(stroke
				(width 0.1)
				(type default)
			)
			(layer "F.Fab")
		)
		(fp_line
			(start -0.2794 -0.1016)
			(end -0.2794 0.9906)
			(stroke
				(width 0.1)
				(type default)
			)
			(layer "F.Fab")
		)
		(fp_line
			(start 0.2794 0.9906)
			(end 0.2794 -0.1016)
			(stroke
				(width 0.1)
				(type default)
			)
			(layer "F.Fab")
		)
		(fp_line
			(start -0.2794 0.9906)
			(end 0.2794 0.9906)
			(stroke
				(width 0.1)
				(type default)
			)
			(layer "F.Fab")
		)
		(pad "1" smd rect
			(at 0 0 90)
			(size 0.508 0.508)
			(layers "F.Cu" "F.Mask" "F.Paste")
			(net "CLK_100M_CPU0_PE_REFCLK_R_DN")
		)
		(pad "2" smd rect
			(at 0 0.889 90)
			(size 0.508 0.508)
			(layers "F.Cu" "F.Mask" "F.Paste")
			(net "CLK_100M_CPU0_PE_REFCLK_DN")
		)
		(zone
			(layer "F.Cu")
			(hatch none 0.5)
			(connect_pads
				(clearance 0)
			)
			(min_thickness 0.25)
			(keepout
				(tracks allowed)
				(vias not_allowed)
				(pads allowed)
				(copperpour not_allowed)
				(footprints allowed)
			)
			(placement
				(enabled no)
				(sheetname "")
			)
			(fill
				(thermal_gap 0.5)
				(thermal_bridge_width 0.5)
				(island_removal_mode 0)
			)
			(polygon
				(pts
					(xy 175.641 -84.963) (xy 175.641 -85.471) (xy 176.022 -85.471) (xy 176.022 -84.963)
				)
			)
		)
		(zone
			(layer "F.Cu")
			(hatch none 0.5)
			(connect_pads
				(clearance 0)
			)
			(min_thickness 0.25)
			(keepout
				(tracks not_allowed)
				(vias allowed)
				(pads allowed)
				(copperpour not_allowed)
				(footprints allowed)
			)
			(placement
				(enabled no)
				(sheetname "")
			)
			(fill
				(thermal_gap 0.5)
				(thermal_bridge_width 0.5)
				(island_removal_mode 0)
			)
			(polygon
				(pts
					(xy 176.022 -84.963) (xy 176.022 -85.471) (xy 175.641 -85.471) (xy 175.641 -84.963)
				)
			)
		)
	)
	(footprint ""
		(layer "F.Cu")
		(at 452.767192 -23.605998)
		(property "Reference" "EU25F2"
			(at -0.256286 -1.613408 0)
			(unlocked yes)
			(layer "F.SilkS")
			(effects
				(font
					(size 1.27 0.964946)
					(thickness 0.000001)
				)
				(justify left)
			)
		)
		(property "Value" ""
			(at 0 0 0)
			(layer "F.Fab")
			(effects
				(font
					(size 1.27 1.27)
				)
			)
		)
		(duplicate_pad_numbers_are_jumpers no)
		(fp_circle
			(center -0.835152 -0.417322)
			(end -0.708406 -0.417322)
			(stroke
				(width 0.254)
				(type default)
			)
			(fill no)
			(layer "F.SilkS")
		)
		(fp_poly
			(pts
				(xy -0.064516 -1.0922) (xy -0.064516 -0.3302) (xy 0.697484 -1.0922)
			)
			(stroke
				(width 0)
				(type default)
			)
			(fill yes)
			(layer "F.SilkS")
		)
		(fp_rect
			(start 0.597408 2.295398)
			(end 2.273808 -0.295402)
			(stroke
				(width 0)
				(type default)
			)
			(fill yes)
			(layer "F.Paste")
		)
		(fp_rect
			(start -0.064516 2.500122)
			(end 2.935478 -0.500126)
			(stroke
				(width 0)
				(type default)
			)
			(fill no)
			(layer "F.CrtYd")
		)
		(fp_line
			(start -0.064516 -0.500126)
			(end 2.935478 -0.500126)
			(stroke
				(width 0.1)
				(type default)
			)
			(layer "F.Fab")
		)
		(fp_line
			(start -0.064516 2.500122)
			(end -0.064516 -0.500126)
			(stroke
				(width 0.1)
				(type default)
			)
			(layer "F.Fab")
		)
		(fp_line
			(start 2.935478 -0.500126)
			(end 2.935478 2.500122)
			(stroke
				(width 0.1)
				(type default)
			)
			(layer "F.Fab")
		)
		(fp_line
			(start 2.935478 2.500122)
			(end -0.064516 2.500122)
			(stroke
				(width 0.1)
				(type default)
			)
			(layer "F.Fab")
		)
		(fp_circle
			(center -0.835152 -0.417322)
			(end -0.708406 -0.417322)
			(stroke
				(width 0.254)
				(type default)
			)
			(fill no)
			(layer "F.Fab")
		)
		(pad "1" smd rect
			(at 0 0)
			(size 0.6858 0.3048)
			(layers "F.Cu" "F.Mask" "F.Paste")
			(net "P2V5_AUX_BMC")
		)
		(pad "2" smd rect
			(at 0 0.500126)
			(size 0.6858 0.3048)
			(layers "F.Cu" "F.Mask" "F.Paste")
			(net "P2V5_AUX_BMC")
		)
		(pad "3" smd rect
			(at 0 0.999998)
			(size 0.6858 0.3048)
			(layers "F.Cu" "F.Mask" "F.Paste")
			(net "P2V5_AUX_BMC")
		)
		(pad "4" smd rect
			(at 0 1.500124)
			(size 0.6858 0.3048)
			(layers "F.Cu" "F.Mask" "F.Paste")
			(net "VR_P2V5_BMC_STBY_FB")
		)
		(pad "5" smd rect
			(at 0 1.999996)
			(size 0.6858 0.3048)
			(layers "F.Cu" "F.Mask" "F.Paste")
			(net "PWRGD_P2V5_BMC_STBY_R")
		)
		(pad "6" smd rect
			(at 2.871216 1.999996)
			(size 0.6858 0.3048)
			(layers "F.Cu" "F.Mask" "F.Paste")
			(net "PWRGD_P3V3_STBY")
		)
		(pad "7" smd rect
			(at 2.871216 1.500124)
			(size 0.6858 0.3048)
			(layers "F.Cu" "F.Mask" "F.Paste")
			(net "P3V3_STBY")
		)
		(pad "8" smd rect
			(at 2.871216 0.999998)
			(size 0.6858 0.3048)
			(layers "F.Cu" "F.Mask" "F.Paste")
			(net "P3V3_STBY")
		)
		(pad "9" smd rect
			(at 2.871216 0.500126)
			(size 0.6858 0.3048)
			(layers "F.Cu" "F.Mask" "F.Paste")
			(net "P3V3_STBY")
		)
		(pad "10" smd rect
			(at 2.871216 0)
			(size 0.6858 0.3048)
			(layers "F.Cu" "F.Mask" "F.Paste")
			(net "P3V3_STBY")
		)
		(pad "11" smd rect
			(at 1.435608 0.999998)
			(size 1.6764 2.5908)
			(layers "F.Cu" "F.Mask" "F.Paste")
			(net "GND")
		)
	)
	(footprint ""
		(layer "F.Cu")
		(at 96.949768 -79.6036 180)
		(property "Reference" "C2D12"
			(at 0 0 180)
			(layer "F.SilkS")
			(hide yes)
			(effects
				(font
					(size 1.27 1.27)
				)
			)
		)
		(property "Value" ""
			(at 0 0 180)
			(layer "F.Fab")
			(effects
				(font
					(size 1.27 1.27)
				)
			)
		)
		(duplicate_pad_numbers_are_jumpers no)
		(fp_poly
			(pts
				(xy -0.4953 -0.2032) (xy 0.4953 -0.2032) (xy 0.4953 1.6002) (xy -0.4953 1.6002)
			)
			(stroke
				(width 0)
				(type default)
			)
			(fill no)
			(layer "F.CrtYd")
		)
		(fp_line
			(start 0.4953 1.6002)
			(end -0.4953 1.6002)
			(stroke
				(width 0.1)
				(type default)
			)
			(layer "F.Fab")
		)
		(fp_line
			(start 0.4953 -0.2032)
			(end 0.4953 1.6002)
			(stroke
				(width 0.1)
				(type default)
			)
			(layer "F.Fab")
		)
		(fp_line
			(start -0.4953 1.6002)
			(end -0.4953 -0.2032)
			(stroke
				(width 0.1)
				(type default)
			)
			(layer "F.Fab")
		)
		(fp_line
			(start -0.4953 -0.2032)
			(end 0.4953 -0.2032)
			(stroke
				(width 0.1)
				(type default)
			)
			(layer "F.Fab")
		)
		(pad "1" smd rect
			(at 0 0 180)
			(size 0.762 0.889)
			(layers "F.Cu" "F.Mask" "F.Paste")
			(net "PVCCIN_CPU1")
		)
		(pad "2" smd rect
			(at 0 1.397 180)
			(size 0.762 0.889)
			(layers "F.Cu" "F.Mask" "F.Paste")
			(net "GND")
		)
		(zone
			(layer "F.Cu")
			(hatch none 0.5)
			(connect_pads
				(clearance 0)
			)
			(min_thickness 0.25)
			(keepout
				(tracks not_allowed)
				(vias allowed)
				(pads allowed)
				(copperpour not_allowed)
				(footprints allowed)
			)
			(placement
				(enabled no)
				(sheetname "")
			)
			(fill
				(thermal_gap 0.5)
				(thermal_bridge_width 0.5)
				(island_removal_mode 0)
			)
			(polygon
				(pts
					(xy 97.330768 -80.0481) (xy 96.568768 -80.0481) (xy 96.568768 -80.5561) (xy 97.330768 -80.5561)
				)
			)
		)
	)
	(footprint ""
		(layer "F.Cu")
		(at 457.923392 -42.401998 -90)
		(property "Reference" "C9E10"
			(at 0 0 270)
			(layer "F.SilkS")
			(hide yes)
			(effects
				(font
					(size 1.27 1.27)
				)
			)
		)
		(property "Value" ""
			(at 0 0 270)
			(layer "F.Fab")
			(effects
				(font
					(size 1.27 1.27)
				)
			)
		)
		(duplicate_pad_numbers_are_jumpers no)
		(fp_poly
			(pts
				(xy -0.4953 -0.2032) (xy 0.4953 -0.2032) (xy 0.4953 1.6002) (xy -0.4953 1.6002)
			)
			(stroke
				(width 0)
				(type default)
			)
			(fill no)
			(layer "F.CrtYd")
		)
		(fp_line
			(start -0.4953 1.6002)
			(end -0.4953 -0.2032)
			(stroke
				(width 0.1)
				(type default)
			)
			(layer "F.Fab")
		)
		(fp_line
			(start 0.4953 1.6002)
			(end -0.4953 1.6002)
			(stroke
				(width 0.1)
				(type default)
			)
			(layer "F.Fab")
		)
		(fp_line
			(start -0.4953 -0.2032)
			(end 0.4953 -0.2032)
			(stroke
				(width 0.1)
				(type default)
			)
			(layer "F.Fab")
		)
		(fp_line
			(start 0.4953 -0.2032)
			(end 0.4953 1.6002)
			(stroke
				(width 0.1)
				(type default)
			)
			(layer "F.Fab")
		)
		(pad "1" smd rect
			(at 0 0 270)
			(size 0.762 0.889)
			(layers "F.Cu" "F.Mask" "F.Paste")
			(net "P1V15_AUX_BMC")
		)
		(pad "2" smd rect
			(at 0 1.397 270)
			(size 0.762 0.889)
			(layers "F.Cu" "F.Mask" "F.Paste")
			(net "GND")
		)
		(zone
			(layer "F.Cu")
			(hatch none 0.5)
			(connect_pads
				(clearance 0)
			)
			(min_thickness 0.25)
			(keepout
				(tracks not_allowed)
				(vias allowed)
				(pads allowed)
				(copperpour not_allowed)
				(footprints allowed)
			)
			(placement
				(enabled no)
				(sheetname "")
			)
			(fill
				(thermal_gap 0.5)
				(thermal_bridge_width 0.5)
				(island_removal_mode 0)
			)
			(polygon
				(pts
					(xy 457.478892 -42.782998) (xy 457.478892 -42.020998) (xy 456.970892 -42.020998) (xy 456.970892 -42.782998)
				)
			)
		)
	)
	(footprint ""
		(layer "F.Cu")
		(at 49.4284 -59.143392 180)
		(property "Reference" "C1E9"
			(at 0 0 180)
			(layer "F.SilkS")
			(hide yes)
			(effects
				(font
					(size 1.27 1.27)
				)
			)
		)
		(property "Value" ""
			(at 0 0 180)
			(layer "F.Fab")
			(effects
				(font
					(size 1.27 1.27)
				)
			)
		)
		(duplicate_pad_numbers_are_jumpers no)
		(fp_poly
			(pts
				(xy -0.4953 -0.2032) (xy 0.4953 -0.2032) (xy 0.4953 1.6002) (xy -0.4953 1.6002)
			)
			(stroke
				(width 0)
				(type default)
			)
			(fill no)
			(layer "F.CrtYd")
		)
		(fp_line
			(start 0.4953 1.6002)
			(end -0.4953 1.6002)
			(stroke
				(width 0.1)
				(type default)
			)
			(layer "F.Fab")
		)
		(fp_line
			(start 0.4953 -0.2032)
			(end 0.4953 1.6002)
			(stroke
				(width 0.1)
				(type default)
			)
			(layer "F.Fab")
		)
		(fp_line
			(start -0.4953 1.6002)
			(end -0.4953 -0.2032)
			(stroke
				(width 0.1)
				(type default)
			)
			(layer "F.Fab")
		)
		(fp_line
			(start -0.4953 -0.2032)
			(end 0.4953 -0.2032)
			(stroke
				(width 0.1)
				(type default)
			)
			(layer "F.Fab")
		)
		(pad "1" smd rect
			(at 0 0 180)
			(size 0.762 0.889)
			(layers "F.Cu" "F.Mask" "F.Paste")
			(net "PVCCIN_CPU1")
		)
		(pad "2" smd rect
			(at 0 1.397 180)
			(size 0.762 0.889)
			(layers "F.Cu" "F.Mask" "F.Paste")
			(net "GND")
		)
		(zone
			(layer "F.Cu")
			(hatch none 0.5)
			(connect_pads
				(clearance 0)
			)
			(min_thickness 0.25)
			(keepout
				(tracks not_allowed)
				(vias allowed)
				(pads allowed)
				(copperpour not_allowed)
				(footprints allowed)
			)
			(placement
				(enabled no)
				(sheetname "")
			)
			(fill
				(thermal_gap 0.5)
				(thermal_bridge_width 0.5)
				(island_removal_mode 0)
			)
			(polygon
				(pts
					(xy 49.8094 -59.587892) (xy 49.0474 -59.587892) (xy 49.0474 -60.095892) (xy 49.8094 -60.095892)
				)
			)
		)
	)
	(footprint ""
		(layer "F.Cu")
		(at 487.554016 -155.702254 -90)
		(property "Reference" "S9A1"
			(at -1.97485 3.5941 0)
			(unlocked yes)
			(layer "F.SilkS")
			(effects
				(font
					(size 0.7874 0.5842)
					(thickness 0.1524)
				)
				(justify left)
			)
		)
		(property "Value" ""
			(at 0 0 270)
			(layer "F.Fab")
			(effects
				(font
					(size 1.27 1.27)
				)
			)
		)
		(duplicate_pad_numbers_are_jumpers no)
		(fp_line
			(start 1.800098 5.3721)
			(end 3.022092 5.3721)
			(stroke
				(width 0.1524)
				(type default)
			)
			(layer "F.SilkS")
		)
		(fp_line
			(start -0.7112 0.978154)
			(end -0.7112 3.52044)
			(stroke
				(width 0.1524)
				(type default)
			)
			(layer "F.SilkS")
		)
		(fp_line
			(start 5.5372 0.973836)
			(end 5.5372 3.52044)
			(stroke
				(width 0.1524)
				(type default)
			)
			(layer "F.SilkS")
		)
		(fp_line
			(start 3.024632 -0.8763)
			(end 1.800098 -0.8763)
			(stroke
				(width 0.1524)
				(type default)
			)
			(layer "F.SilkS")
		)
		(fp_circle
			(center -1.972818 -0.651002)
			(end -1.972818 -0.778002)
			(stroke
				(width 0.254)
				(type default)
			)
			(fill no)
			(layer "F.SilkS")
		)
		(fp_rect
			(start -0.7112 5.3721)
			(end 5.5372 -0.8763)
			(stroke
				(width 0)
				(type default)
			)
			(fill no)
			(layer "F.CrtYd")
		)
		(fp_line
			(start -0.7112 5.3721)
			(end -0.7112 -0.8763)
			(stroke
				(width 0.1)
				(type default)
			)
			(layer "F.Fab")
		)
		(fp_line
			(start 5.5372 5.3721)
			(end -0.7112 5.3721)
			(stroke
				(width 0.1)
				(type default)
			)
			(layer "F.Fab")
		)
		(fp_line
			(start -0.7112 -0.8763)
			(end 5.5372 -0.8763)
			(stroke
				(width 0.1)
				(type default)
			)
			(layer "F.Fab")
		)
		(fp_line
			(start 5.5372 -0.8763)
			(end 5.5372 5.3721)
			(stroke
				(width 0.1)
				(type default)
			)
			(layer "F.Fab")
		)
		(fp_circle
			(center -1.972818 -0.651002)
			(end -1.972818 -0.778002)
			(stroke
				(width 0.254)
				(type default)
			)
			(fill no)
			(layer "F.Fab")
		)
		(fp_text user "4"
			(at 5.881624 5.809996 0)
			(unlocked yes)
			(layer "F.SilkS")
			(effects
				(font
					(size 0.7874 0.5842)
					(thickness 0.1524)
				)
				(justify left)
			)
		)
		(fp_text user "2"
			(at 5.373624 -0.735584 0)
			(unlocked yes)
			(layer "F.SilkS")
			(effects
				(font
					(size 0.7874 0.5842)
					(thickness 0.1524)
				)
				(justify left)
			)
		)
		(fp_text user "4"
			(at 6.354064 3.663696 0)
			(unlocked yes)
			(layer "F.Fab")
			(effects
				(font
					(size 0.635 0.635)
					(thickness 0.1524)
				)
				(justify left)
			)
		)
		(fp_text user "2"
			(at 6.338316 1.57861 0)
			(unlocked yes)
			(layer "F.Fab")
			(effects
				(font
					(size 0.635 0.635)
					(thickness 0.1524)
				)
				(justify left)
			)
		)
		(pad "1" smd rect
			(at 0 0 270)
			(size 2.921 1.27)
			(layers "F.Cu" "F.Mask" "F.Paste")
			(net "FM_DEBUG_RST_BTN_N")
		)
		(pad "2" smd rect
			(at 4.826 0 270)
			(size 2.921 1.27)
			(layers "F.Cu" "F.Mask" "F.Paste")
			(net "FM_DEBUG_RST_BTN_N")
		)
		(pad "3" smd rect
			(at 0 4.4958 270)
			(size 2.921 1.27)
			(layers "F.Cu" "F.Mask" "F.Paste")
			(net "GND")
		)
		(pad "4" smd rect
			(at 4.826 4.4958 270)
			(size 2.921 1.27)
			(layers "F.Cu" "F.Mask" "F.Paste")
			(net "GND")
		)
	)
	(footprint ""
		(layer "F.Cu")
		(at 427.355 -22.86 90)
		(property "Reference" "R10W3"
			(at -0.8382 -0.67818 90)
			(unlocked yes)
			(layer "F.SilkS")
			(effects
				(font
					(size 0.4064 0.254)
					(thickness 0.1524)
				)
				(justify left)
			)
		)
		(property "Value" ""
			(at 0 0 90)
			(layer "F.Fab")
			(effects
				(font
					(size 1.27 1.27)
				)
			)
		)
		(duplicate_pad_numbers_are_jumpers no)
		(fp_poly
			(pts
				(xy -0.2794 -0.1016) (xy 0.2794 -0.1016) (xy 0.2794 0.9906) (xy -0.2794 0.9906)
			)
			(stroke
				(width 0)
				(type default)
			)
			(fill no)
			(layer "F.CrtYd")
		)
		(fp_line
			(start 0.2794 -0.1016)
			(end -0.2794 -0.1016)
			(stroke
				(width 0.1)
				(type default)
			)
			(layer "F.Fab")
		)
		(fp_line
			(start -0.2794 -0.1016)
			(end -0.2794 0.9906)
			(stroke
				(width 0.1)
				(type default)
			)
			(layer "F.Fab")
		)
		(fp_line
			(start 0.2794 0.9906)
			(end 0.2794 -0.1016)
			(stroke
				(width 0.1)
				(type default)
			)
			(layer "F.Fab")
		)
		(fp_line
			(start -0.2794 0.9906)
			(end 0.2794 0.9906)
			(stroke
				(width 0.1)
				(type default)
			)
			(layer "F.Fab")
		)
		(pad "1" smd rect
			(at 0 0 90)
			(size 0.508 0.508)
			(layers "F.Cu" "F.Mask" "F.Paste")
			(net "P5V_STBY")
		)
		(pad "2" smd rect
			(at 0 0.889 90)
			(size 0.508 0.508)
			(layers "F.Cu" "F.Mask" "F.Paste")
			(net "PUMP_PWM_OUT_R")
		)
		(zone
			(layer "F.Cu")
			(hatch none 0.5)
			(connect_pads
				(clearance 0)
			)
			(min_thickness 0.25)
			(keepout
				(tracks allowed)
				(vias not_allowed)
				(pads allowed)
				(copperpour not_allowed)
				(footprints allowed)
			)
			(placement
				(enabled no)
				(sheetname "")
			)
			(fill
				(thermal_gap 0.5)
				(thermal_bridge_width 0.5)
				(island_removal_mode 0)
			)
			(polygon
				(pts
					(xy 427.609 -22.606) (xy 427.609 -23.114) (xy 427.99 -23.114) (xy 427.99 -22.606)
				)
			)
		)
		(zone
			(layer "F.Cu")
			(hatch none 0.5)
			(connect_pads
				(clearance 0)
			)
			(min_thickness 0.25)
			(keepout
				(tracks not_allowed)
				(vias allowed)
				(pads allowed)
				(copperpour not_allowed)
				(footprints allowed)
			)
			(placement
				(enabled no)
				(sheetname "")
			)
			(fill
				(thermal_gap 0.5)
				(thermal_bridge_width 0.5)
				(island_removal_mode 0)
			)
			(polygon
				(pts
					(xy 427.99 -22.606) (xy 427.99 -23.114) (xy 427.609 -23.114) (xy 427.609 -22.606)
				)
			)
		)
	)
	(footprint ""
		(layer "F.Cu")
		(at 384.291586 -67.6656 180)
		(property "Reference" "C7E11"
			(at 0 0 180)
			(layer "F.SilkS")
			(hide yes)
			(effects
				(font
					(size 1.27 1.27)
				)
			)
		)
		(property "Value" ""
			(at 0 0 180)
			(layer "F.Fab")
			(effects
				(font
					(size 1.27 1.27)
				)
			)
		)
		(duplicate_pad_numbers_are_jumpers no)
		(fp_line
			(start 0.9017 1.953768)
			(end 0.9017 0.824484)
			(stroke
				(width 0.1524)
				(type default)
			)
			(layer "F.SilkS")
		)
		(fp_line
			(start -0.9017 1.953006)
			(end -0.9017 0.823976)
			(stroke
				(width 0.1524)
				(type default)
			)
			(layer "F.SilkS")
		)
		(fp_poly
			(pts
				(xy -0.9017 -0.3048) (xy 0.9017 -0.3048) (xy 0.9017 3.0988) (xy -0.9017 3.0988)
			)
			(stroke
				(width 0)
				(type default)
			)
			(fill no)
			(layer "F.CrtYd")
		)
		(fp_line
			(start 0.9017 3.0988)
			(end 0.9017 -0.3048)
			(stroke
				(width 0.1)
				(type default)
			)
			(layer "F.Fab")
		)
		(fp_line
			(start 0.9017 -0.3048)
			(end -0.9017 -0.3048)
			(stroke
				(width 0.1)
				(type default)
			)
			(layer "F.Fab")
		)
		(fp_line
			(start -0.9017 3.0988)
			(end 0.9017 3.0988)
			(stroke
				(width 0.1)
				(type default)
			)
			(layer "F.Fab")
		)
		(fp_line
			(start -0.9017 -0.3048)
			(end -0.9017 3.0988)
			(stroke
				(width 0.1)
				(type default)
			)
			(layer "F.Fab")
		)
		(pad "1" smd rect
			(at 0 0 180)
			(size 1.524 1.016)
			(layers "F.Cu" "F.Mask" "F.Paste")
			(net "VR_FET_SW_P5V_STBY_PVIN")
		)
		(pad "2" smd rect
			(at 0 2.794 180)
			(size 1.524 1.016)
			(layers "F.Cu" "F.Mask" "F.Paste")
			(net "GND")
		)
		(zone
			(layer "F.Cu")
			(hatch none 0.5)
			(connect_pads
				(clearance 0)
			)
			(min_thickness 0.25)
			(keepout
				(tracks allowed)
				(vias not_allowed)
				(pads allowed)
				(copperpour not_allowed)
				(footprints allowed)
			)
			(placement
				(enabled no)
				(sheetname "")
			)
			(fill
				(thermal_gap 0.5)
				(thermal_bridge_width 0.5)
				(island_removal_mode 0)
			)
			(polygon
				(pts
					(xy 383.529586 -68.1736) (xy 383.529586 -69.9516) (xy 385.053586 -69.9516) (xy 385.053586 -68.1736)
				)
			)
		)
	)
	(footprint ""
		(layer "F.Cu")
		(at 188.5696 -70.5739 180)
		(property "Reference" "RF5"
			(at -0.8382 -0.67818 180)
			(unlocked yes)
			(layer "F.SilkS")
			(effects
				(font
					(size 0.4064 0.254)
					(thickness 0.1524)
				)
				(justify left)
			)
		)
		(property "Value" ""
			(at 0 0 180)
			(layer "F.Fab")
			(effects
				(font
					(size 1.27 1.27)
				)
			)
		)
		(duplicate_pad_numbers_are_jumpers no)
		(fp_poly
			(pts
				(xy -0.2794 -0.1016) (xy 0.2794 -0.1016) (xy 0.2794 0.9906) (xy -0.2794 0.9906)
			)
			(stroke
				(width 0)
				(type default)
			)
			(fill no)
			(layer "F.CrtYd")
		)
		(fp_line
			(start 0.2794 0.9906)
			(end 0.2794 -0.1016)
			(stroke
				(width 0.1)
				(type default)
			)
			(layer "F.Fab")
		)
		(fp_line
			(start 0.2794 -0.1016)
			(end -0.2794 -0.1016)
			(stroke
				(width 0.1)
				(type default)
			)
			(layer "F.Fab")
		)
		(fp_line
			(start -0.2794 0.9906)
			(end 0.2794 0.9906)
			(stroke
				(width 0.1)
				(type default)
			)
			(layer "F.Fab")
		)
		(fp_line
			(start -0.2794 -0.1016)
			(end -0.2794 0.9906)
			(stroke
				(width 0.1)
				(type default)
			)
			(layer "F.Fab")
		)
		(pad "1" smd rect
			(at 0 0 180)
			(size 0.508 0.508)
			(layers "F.Cu" "F.Mask" "F.Paste")
			(net "VR_PVCCIN_CPU0_AIREF5")
		)
		(pad "2" smd rect
			(at 0 0.889 180)
			(size 0.508 0.508)
			(layers "F.Cu" "F.Mask" "F.Paste")
			(net "ISENSE_PVCCIN_CPU0_PH5_IMON")
		)
		(zone
			(layer "F.Cu")
			(hatch none 0.5)
			(connect_pads
				(clearance 0)
			)
			(min_thickness 0.25)
			(keepout
				(tracks not_allowed)
				(vias allowed)
				(pads allowed)
				(copperpour not_allowed)
				(footprints allowed)
			)
			(placement
				(enabled no)
				(sheetname "")
			)
			(fill
				(thermal_gap 0.5)
				(thermal_bridge_width 0.5)
				(island_removal_mode 0)
			)
			(polygon
				(pts
					(xy 188.8236 -71.2089) (xy 188.3156 -71.2089) (xy 188.3156 -70.8279) (xy 188.8236 -70.8279)
				)
			)
		)
		(zone
			(layer "F.Cu")
			(hatch none 0.5)
			(connect_pads
				(clearance 0)
			)
			(min_thickness 0.25)
			(keepout
				(tracks allowed)
				(vias not_allowed)
				(pads allowed)
				(copperpour not_allowed)
				(footprints allowed)
			)
			(placement
				(enabled no)
				(sheetname "")
			)
			(fill
				(thermal_gap 0.5)
				(thermal_bridge_width 0.5)
				(island_removal_mode 0)
			)
			(polygon
				(pts
					(xy 188.8236 -70.8279) (xy 188.3156 -70.8279) (xy 188.3156 -71.2089) (xy 188.8236 -71.2089)
				)
			)
		)
	)
	(footprint ""
		(layer "F.Cu")
		(at 206.751936 11.952478 -90)
		(property "Reference" "T1P2"
			(at 0 0 270)
			(layer "F.SilkS")
			(hide yes)
			(effects
				(font
					(size 1.27 1.27)
				)
			)
		)
		(property "Value" "*"
			(at -3.302 1.12395 270)
			(unlocked yes)
			(layer "F.Fab")
			(hide yes)
			(effects
				(font
					(size 0.889 0.889)
					(thickness 0.1524)
				)
			)
		)
		(property "Device Type" "TPAD-DIFF-4P-GP_DISCRET-GB3-TPA"
			(at -3.302 -0.40005 270)
			(unlocked yes)
			(layer "F.Fab")
			(hide yes)
			(effects
				(font
					(size 0.889 0.889)
					(thickness 0.1524)
				)
			)
		)
		(duplicate_pad_numbers_are_jumpers no)
		(fp_line
			(start -2.286 2.286)
			(end 2.286 2.286)
			(stroke
				(width 0.1524)
				(type default)
			)
			(layer "F.SilkS")
		)
		(fp_line
			(start 2.286 2.286)
			(end 2.286 -2.286)
			(stroke
				(width 0.1524)
				(type default)
			)
			(layer "F.SilkS")
		)
		(fp_line
			(start -2.286 -2.286)
			(end -2.286 2.286)
			(stroke
				(width 0.1524)
				(type default)
			)
			(layer "F.SilkS")
		)
		(fp_line
			(start 2.286 -2.286)
			(end -2.286 -2.286)
			(stroke
				(width 0.1524)
				(type default)
			)
			(layer "F.SilkS")
		)
		(fp_line
			(start -2.413 -2.413)
			(end -2.413 -1.143)
			(stroke
				(width 0.4064)
				(type default)
			)
			(layer "F.SilkS")
		)
		(fp_line
			(start -1.143 -2.413)
			(end -2.413 -2.413)
			(stroke
				(width 0.4064)
				(type default)
			)
			(layer "F.SilkS")
		)
		(fp_rect
			(start -2.54 2.54)
			(end 2.54 -2.54)
			(stroke
				(width 0)
				(type default)
			)
			(fill no)
			(layer "F.CrtYd")
		)
		(fp_rect
			(start -2.54 2.54)
			(end 2.54 -2.54)
			(stroke
				(width 0)
				(type default)
			)
			(fill no)
			(layer "F.Fab")
		)
		(pad "1" thru_hole circle
			(at -1.27 -1.27 270)
			(size 1.524 1.524)
			(drill 0.9144)
			(layers "*.Cu" "*.Mask")
			(remove_unused_layers no)
			(net "L3_85OHM_6INCH_DP")
			(clearance -0.0508)
			(thermal_gap 0.127)
			(padstack
				(mode front_inner_back)
				(layer "Inner"
					(shape circle)
					(size 1.1684 1.1684)
					(clearance 0.127)
				)
				(layer "B.Cu"
					(shape circle)
					(size 1.524 1.524)
					(clearance -0.0508)
				)
			)
		)
		(pad "2" thru_hole circle
			(at 1.27 -1.27 270)
			(size 1.524 1.524)
			(drill 0.9144)
			(layers "*.Cu" "*.Mask")
			(remove_unused_layers no)
			(net "L3_85OHM_6INCH_DN")
			(clearance -0.0508)
			(thermal_gap 0.127)
			(padstack
				(mode front_inner_back)
				(layer "Inner"
					(shape circle)
					(size 1.1684 1.1684)
					(clearance 0.127)
				)
				(layer "B.Cu"
					(shape circle)
					(size 1.524 1.524)
					(clearance -0.0508)
				)
			)
		)
		(pad "GND1" thru_hole rect
			(at -1.27 1.27 270)
			(size 1.524 1.524)
			(drill 0.9144)
			(layers "*.Cu" "*.Mask")
			(remove_unused_layers no)
			(net "GND")
			(clearance -0.0508)
			(thermal_gap 0.127)
			(padstack
				(mode front_inner_back)
				(layer "Inner"
					(shape circle)
					(size 1.1684 1.1684)
					(clearance 0.127)
				)
				(layer "B.Cu"
					(shape rect)
					(size 1.524 1.524)
					(clearance -0.0508)
				)
			)
		)
		(pad "GND2" thru_hole rect
			(at 1.27 1.27 270)
			(size 1.524 1.524)
			(drill 0.9144)
			(layers "*.Cu" "*.Mask")
			(remove_unused_layers no)
			(net "GND")
			(clearance -0.0508)
			(thermal_gap 0.127)
			(padstack
				(mode front_inner_back)
				(layer "Inner"
					(shape circle)
					(size 1.1684 1.1684)
					(clearance 0.127)
				)
				(layer "B.Cu"
					(shape rect)
					(size 1.524 1.524)
					(clearance -0.0508)
				)
			)
		)
	)
	(footprint ""
		(layer "F.Cu")
		(at 419.316408 -48.064166 180)
		(property "Reference" "R1T23"
			(at -0.8382 -0.67818 180)
			(unlocked yes)
			(layer "F.SilkS")
			(effects
				(font
					(size 0.4064 0.254)
					(thickness 0.1524)
				)
				(justify left)
			)
		)
		(property "Value" ""
			(at 0 0 180)
			(layer "F.Fab")
			(effects
				(font
					(size 1.27 1.27)
				)
			)
		)
		(duplicate_pad_numbers_are_jumpers no)
		(fp_poly
			(pts
				(xy -0.2794 -0.1016) (xy 0.2794 -0.1016) (xy 0.2794 0.9906) (xy -0.2794 0.9906)
			)
			(stroke
				(width 0)
				(type default)
			)
			(fill no)
			(layer "F.CrtYd")
		)
		(fp_line
			(start 0.2794 0.9906)
			(end 0.2794 -0.1016)
			(stroke
				(width 0.1)
				(type default)
			)
			(layer "F.Fab")
		)
		(fp_line
			(start 0.2794 -0.1016)
			(end -0.2794 -0.1016)
			(stroke
				(width 0.1)
				(type default)
			)
			(layer "F.Fab")
		)
		(fp_line
			(start -0.2794 0.9906)
			(end 0.2794 0.9906)
			(stroke
				(width 0.1)
				(type default)
			)
			(layer "F.Fab")
		)
		(fp_line
			(start -0.2794 -0.1016)
			(end -0.2794 0.9906)
			(stroke
				(width 0.1)
				(type default)
			)
			(layer "F.Fab")
		)
		(pad "1" smd rect
			(at 0 0 180)
			(size 0.508 0.508)
			(layers "F.Cu" "F.Mask" "F.Paste")
			(net "FM_BMC_ONCTL_R_N")
		)
		(pad "2" smd rect
			(at 0 0.889 180)
			(size 0.508 0.508)
			(layers "F.Cu" "F.Mask" "F.Paste")
			(net "GND")
		)
		(zone
			(layer "F.Cu")
			(hatch none 0.5)
			(connect_pads
				(clearance 0)
			)
			(min_thickness 0.25)
			(keepout
				(tracks not_allowed)
				(vias allowed)
				(pads allowed)
				(copperpour not_allowed)
				(footprints allowed)
			)
			(placement
				(enabled no)
				(sheetname "")
			)
			(fill
				(thermal_gap 0.5)
				(thermal_bridge_width 0.5)
				(island_removal_mode 0)
			)
			(polygon
				(pts
					(xy 419.570408 -48.699166) (xy 419.062408 -48.699166) (xy 419.062408 -48.318166) (xy 419.570408 -48.318166)
				)
			)
		)
		(zone
			(layer "F.Cu")
			(hatch none 0.5)
			(connect_pads
				(clearance 0)
			)
			(min_thickness 0.25)
			(keepout
				(tracks allowed)
				(vias not_allowed)
				(pads allowed)
				(copperpour not_allowed)
				(footprints allowed)
			)
			(placement
				(enabled no)
				(sheetname "")
			)
			(fill
				(thermal_gap 0.5)
				(thermal_bridge_width 0.5)
				(island_removal_mode 0)
			)
			(polygon
				(pts
					(xy 419.570408 -48.318166) (xy 419.062408 -48.318166) (xy 419.062408 -48.699166) (xy 419.570408 -48.699166)
				)
			)
		)
	)
	(footprint ""
		(layer "F.Cu")
		(at 487.995976 -137.2616 -90)
		(property "Reference" "R1L37"
			(at 0 0 270)
			(layer "F.SilkS")
			(hide yes)
			(effects
				(font
					(size 1.27 1.27)
				)
			)
		)
		(property "Value" ""
			(at 0 0 270)
			(layer "F.Fab")
			(effects
				(font
					(size 1.27 1.27)
				)
			)
		)
		(duplicate_pad_numbers_are_jumpers no)
		(fp_poly
			(pts
				(xy -0.2794 -0.1016) (xy 0.2794 -0.1016) (xy 0.2794 0.9906) (xy -0.2794 0.9906)
			)
			(stroke
				(width 0)
				(type default)
			)
			(fill no)
			(layer "F.CrtYd")
		)
		(fp_line
			(start -0.2794 0.9906)
			(end 0.2794 0.9906)
			(stroke
				(width 0.1)
				(type default)
			)
			(layer "F.Fab")
		)
		(fp_line
			(start 0.2794 0.9906)
			(end 0.2794 -0.1016)
			(stroke
				(width 0.1)
				(type default)
			)
			(layer "F.Fab")
		)
		(fp_line
			(start -0.2794 -0.1016)
			(end -0.2794 0.9906)
			(stroke
				(width 0.1)
				(type default)
			)
			(layer "F.Fab")
		)
		(fp_line
			(start 0.2794 -0.1016)
			(end -0.2794 -0.1016)
			(stroke
				(width 0.1)
				(type default)
			)
			(layer "F.Fab")
		)
		(pad "1" smd rect
			(at 0 0 270)
			(size 0.508 0.508)
			(layers "F.Cu" "F.Mask" "F.Paste")
			(net "P5V_STBY")
		)
		(pad "2" smd rect
			(at 0 0.889 270)
			(size 0.508 0.508)
			(layers "F.Cu" "F.Mask" "F.Paste")
			(net "LED_P5V_STBY")
		)
		(zone
			(layer "F.Cu")
			(hatch none 0.5)
			(connect_pads
				(clearance 0)
			)
			(min_thickness 0.25)
			(keepout
				(tracks not_allowed)
				(vias allowed)
				(pads allowed)
				(copperpour not_allowed)
				(footprints allowed)
			)
			(placement
				(enabled no)
				(sheetname "")
			)
			(fill
				(thermal_gap 0.5)
				(thermal_bridge_width 0.5)
				(island_removal_mode 0)
			)
			(polygon
				(pts
					(xy 487.360976 -137.5156) (xy 487.360976 -137.0076) (xy 487.741976 -137.0076) (xy 487.741976 -137.5156)
				)
			)
		)
		(zone
			(layer "F.Cu")
			(hatch none 0.5)
			(connect_pads
				(clearance 0)
			)
			(min_thickness 0.25)
			(keepout
				(tracks allowed)
				(vias not_allowed)
				(pads allowed)
				(copperpour not_allowed)
				(footprints allowed)
			)
			(placement
				(enabled no)
				(sheetname "")
			)
			(fill
				(thermal_gap 0.5)
				(thermal_bridge_width 0.5)
				(island_removal_mode 0)
			)
			(polygon
				(pts
					(xy 487.741976 -137.5156) (xy 487.741976 -137.0076) (xy 487.360976 -137.0076) (xy 487.360976 -137.5156)
				)
			)
		)
	)
	(footprint ""
		(layer "F.Cu")
		(at 19.088608 -1.07696 -90)
		(property "Reference" "R1G20"
			(at 0 0 270)
			(layer "F.SilkS")
			(hide yes)
			(effects
				(font
					(size 1.27 1.27)
				)
			)
		)
		(property "Value" ""
			(at 0 0 270)
			(layer "F.Fab")
			(effects
				(font
					(size 1.27 1.27)
				)
			)
		)
		(duplicate_pad_numbers_are_jumpers no)
		(fp_rect
			(start 0.4953 1.6002)
			(end -0.4953 -0.2032)
			(stroke
				(width 0)
				(type default)
			)
			(fill no)
			(layer "F.CrtYd")
		)
		(fp_line
			(start -0.4953 1.6002)
			(end -0.4953 -0.2032)
			(stroke
				(width 0.1)
				(type default)
			)
			(layer "F.Fab")
		)
		(fp_line
			(start 0.4953 1.6002)
			(end -0.4953 1.6002)
			(stroke
				(width 0.1)
				(type default)
			)
			(layer "F.Fab")
		)
		(fp_line
			(start -0.4953 -0.2032)
			(end 0.4953 -0.2032)
			(stroke
				(width 0.1)
				(type default)
			)
			(layer "F.Fab")
		)
		(fp_line
			(start 0.4953 -0.2032)
			(end 0.4953 1.6002)
			(stroke
				(width 0.1)
				(type default)
			)
			(layer "F.Fab")
		)
		(pad "1" smd rect
			(at 0 0 270)
			(size 0.762 0.889)
			(layers "F.Cu" "F.Mask" "F.Paste")
			(net "PVDDQ_GHJ")
		)
		(pad "2" smd rect
			(at 0 1.397 270)
			(size 0.762 0.889)
			(layers "F.Cu" "F.Mask" "F.Paste")
			(net "GND")
		)
		(zone
			(layer "F.Cu")
			(hatch none 0.5)
			(connect_pads
				(clearance 0)
			)
			(min_thickness 0.25)
			(keepout
				(tracks not_allowed)
				(vias allowed)
				(pads allowed)
				(copperpour not_allowed)
				(footprints allowed)
			)
			(placement
				(enabled no)
				(sheetname "")
			)
			(fill
				(thermal_gap 0.5)
				(thermal_bridge_width 0.5)
				(island_removal_mode 0)
			)
			(polygon
				(pts
					(xy 18.136108 -0.69596) (xy 18.644108 -0.69596) (xy 18.644108 -1.45796) (xy 18.136108 -1.45796)
				)
			)
		)
		(zone
			(layer "F.Cu")
			(hatch none 0.5)
			(connect_pads
				(clearance 0)
			)
			(min_thickness 0.25)
			(keepout
				(tracks allowed)
				(vias not_allowed)
				(pads allowed)
				(copperpour not_allowed)
				(footprints allowed)
			)
			(placement
				(enabled no)
				(sheetname "")
			)
			(fill
				(thermal_gap 0.5)
				(thermal_bridge_width 0.5)
				(island_removal_mode 0)
			)
			(polygon
				(pts
					(xy 18.136108 -0.69596) (xy 18.644108 -0.69596) (xy 18.644108 -1.45796) (xy 18.136108 -1.45796)
				)
			)
		)
	)
	(footprint ""
		(layer "F.Cu")
		(at 38.965886 -85.6996 -90)
		(property "Reference" "CT14"
			(at -0.8382 -0.67818 270)
			(unlocked yes)
			(layer "F.SilkS")
			(effects
				(font
					(size 0.4064 0.254)
					(thickness 0.1524)
				)
				(justify left)
			)
		)
		(property "Value" ""
			(at 0 0 270)
			(layer "F.Fab")
			(effects
				(font
					(size 1.27 1.27)
				)
			)
		)
		(duplicate_pad_numbers_are_jumpers no)
		(fp_poly
			(pts
				(xy 0.3048 -0.1016) (xy 0.3048 0.9906) (xy -0.3048 0.9906) (xy -0.3048 -0.1016)
			)
			(stroke
				(width 0)
				(type default)
			)
			(fill no)
			(layer "F.CrtYd")
		)
		(fp_line
			(start -0.3048 0.9906)
			(end 0.3048 0.9906)
			(stroke
				(width 0.1)
				(type default)
			)
			(layer "F.Fab")
		)
		(fp_line
			(start 0.3048 0.9906)
			(end 0.3048 -0.1016)
			(stroke
				(width 0.1)
				(type default)
			)
			(layer "F.Fab")
		)
		(fp_line
			(start -0.3048 -0.1016)
			(end -0.3048 0.9906)
			(stroke
				(width 0.1)
				(type default)
			)
			(layer "F.Fab")
		)
		(fp_line
			(start 0.3048 -0.1016)
			(end -0.3048 -0.1016)
			(stroke
				(width 0.1)
				(type default)
			)
			(layer "F.Fab")
		)
		(pad "1" smd rect
			(at 0 0 270)
			(size 0.508 0.508)
			(layers "F.Cu" "F.Mask" "F.Paste")
			(net "VR_PVCCIN_CPU1_PHASE5")
		)
		(pad "2" smd rect
			(at 0 0.889 270)
			(size 0.508 0.508)
			(layers "F.Cu" "F.Mask" "F.Paste")
			(net "VR_PVCCIN_CPU1_PHASE5_RC")
		)
		(zone
			(layer "F.Cu")
			(hatch none 0.5)
			(connect_pads
				(clearance 0)
			)
			(min_thickness 0.25)
			(keepout
				(tracks not_allowed)
				(vias allowed)
				(pads allowed)
				(copperpour not_allowed)
				(footprints allowed)
			)
			(placement
				(enabled no)
				(sheetname "")
			)
			(fill
				(thermal_gap 0.5)
				(thermal_bridge_width 0.5)
				(island_removal_mode 0)
			)
			(polygon
				(pts
					(xy 38.330886 -85.9536) (xy 38.330886 -85.4456) (xy 38.711886 -85.4456) (xy 38.711886 -85.9536)
				)
			)
		)
		(zone
			(layer "F.Cu")
			(hatch none 0.5)
			(connect_pads
				(clearance 0)
			)
			(min_thickness 0.25)
			(keepout
				(tracks allowed)
				(vias not_allowed)
				(pads allowed)
				(copperpour not_allowed)
				(footprints allowed)
			)
			(placement
				(enabled no)
				(sheetname "")
			)
			(fill
				(thermal_gap 0.5)
				(thermal_bridge_width 0.5)
				(island_removal_mode 0)
			)
			(polygon
				(pts
					(xy 38.711886 -85.9536) (xy 38.711886 -85.4456) (xy 38.330886 -85.4456) (xy 38.330886 -85.9536)
				)
			)
		)
	)
	(footprint ""
		(layer "F.Cu")
		(at 214.503 -70.358)
		(property "Reference" "C4D34"
			(at 0 0 0)
			(layer "F.SilkS")
			(hide yes)
			(effects
				(font
					(size 1.27 1.27)
				)
			)
		)
		(property "Value" ""
			(at 0 0 0)
			(layer "F.Fab")
			(effects
				(font
					(size 1.27 1.27)
				)
			)
		)
		(duplicate_pad_numbers_are_jumpers no)
		(fp_poly
			(pts
				(xy -0.4953 -0.2032) (xy 0.4953 -0.2032) (xy 0.4953 1.6002) (xy -0.4953 1.6002)
			)
			(stroke
				(width 0)
				(type default)
			)
			(fill no)
			(layer "F.CrtYd")
		)
		(fp_line
			(start -0.4953 -0.2032)
			(end 0.4953 -0.2032)
			(stroke
				(width 0.1)
				(type default)
			)
			(layer "F.Fab")
		)
		(fp_line
			(start -0.4953 1.6002)
			(end -0.4953 -0.2032)
			(stroke
				(width 0.1)
				(type default)
			)
			(layer "F.Fab")
		)
		(fp_line
			(start 0.4953 -0.2032)
			(end 0.4953 1.6002)
			(stroke
				(width 0.1)
				(type default)
			)
			(layer "F.Fab")
		)
		(fp_line
			(start 0.4953 1.6002)
			(end -0.4953 1.6002)
			(stroke
				(width 0.1)
				(type default)
			)
			(layer "F.Fab")
		)
		(pad "1" smd rect
			(at 0 0)
			(size 0.762 0.889)
			(layers "F.Cu" "F.Mask" "F.Paste")
			(net "PVCCIN_CPU0")
		)
		(pad "2" smd rect
			(at 0 1.397)
			(size 0.762 0.889)
			(layers "F.Cu" "F.Mask" "F.Paste")
			(net "GND")
		)
		(zone
			(layer "F.Cu")
			(hatch none 0.5)
			(connect_pads
				(clearance 0)
			)
			(min_thickness 0.25)
			(keepout
				(tracks not_allowed)
				(vias allowed)
				(pads allowed)
				(copperpour not_allowed)
				(footprints allowed)
			)
			(placement
				(enabled no)
				(sheetname "")
			)
			(fill
				(thermal_gap 0.5)
				(thermal_bridge_width 0.5)
				(island_removal_mode 0)
			)
			(polygon
				(pts
					(xy 214.122 -69.9135) (xy 214.884 -69.9135) (xy 214.884 -69.4055) (xy 214.122 -69.4055)
				)
			)
		)
	)
	(footprint ""
		(layer "F.Cu")
		(at 351.913444 -146.90471 90)
		(property "Reference" "R7A21"
			(at 0 0 90)
			(layer "F.SilkS")
			(hide yes)
			(effects
				(font
					(size 1.27 1.27)
				)
			)
		)
		(property "Value" ""
			(at 0 0 90)
			(layer "F.Fab")
			(effects
				(font
					(size 1.27 1.27)
				)
			)
		)
		(duplicate_pad_numbers_are_jumpers no)
		(fp_poly
			(pts
				(xy -0.2794 -0.1016) (xy 0.2794 -0.1016) (xy 0.2794 0.9906) (xy -0.2794 0.9906)
			)
			(stroke
				(width 0)
				(type default)
			)
			(fill no)
			(layer "F.CrtYd")
		)
		(fp_line
			(start 0.2794 -0.1016)
			(end -0.2794 -0.1016)
			(stroke
				(width 0.1)
				(type default)
			)
			(layer "F.Fab")
		)
		(fp_line
			(start -0.2794 -0.1016)
			(end -0.2794 0.9906)
			(stroke
				(width 0.1)
				(type default)
			)
			(layer "F.Fab")
		)
		(fp_line
			(start 0.2794 0.9906)
			(end 0.2794 -0.1016)
			(stroke
				(width 0.1)
				(type default)
			)
			(layer "F.Fab")
		)
		(fp_line
			(start -0.2794 0.9906)
			(end 0.2794 0.9906)
			(stroke
				(width 0.1)
				(type default)
			)
			(layer "F.Fab")
		)
		(pad "1" smd rect
			(at 0 0 90)
			(size 0.508 0.508)
			(layers "F.Cu" "F.Mask" "F.Paste")
			(net "VR_PVDDQ_DEF_PH2_OCSET")
		)
		(pad "2" smd rect
			(at 0 0.889 90)
			(size 0.508 0.508)
			(layers "F.Cu" "F.Mask" "F.Paste")
			(net "GND")
		)
		(zone
			(layer "F.Cu")
			(hatch none 0.5)
			(connect_pads
				(clearance 0)
			)
			(min_thickness 0.25)
			(keepout
				(tracks allowed)
				(vias not_allowed)
				(pads allowed)
				(copperpour not_allowed)
				(footprints allowed)
			)
			(placement
				(enabled no)
				(sheetname "")
			)
			(fill
				(thermal_gap 0.5)
				(thermal_bridge_width 0.5)
				(island_removal_mode 0)
			)
			(polygon
				(pts
					(xy 352.167444 -146.65071) (xy 352.167444 -147.15871) (xy 352.548444 -147.15871) (xy 352.548444 -146.65071)
				)
			)
		)
		(zone
			(layer "F.Cu")
			(hatch none 0.5)
			(connect_pads
				(clearance 0)
			)
			(min_thickness 0.25)
			(keepout
				(tracks not_allowed)
				(vias allowed)
				(pads allowed)
				(copperpour not_allowed)
				(footprints allowed)
			)
			(placement
				(enabled no)
				(sheetname "")
			)
			(fill
				(thermal_gap 0.5)
				(thermal_bridge_width 0.5)
				(island_removal_mode 0)
			)
			(polygon
				(pts
					(xy 352.548444 -146.65071) (xy 352.548444 -147.15871) (xy 352.167444 -147.15871) (xy 352.167444 -146.65071)
				)
			)
		)
	)
	(footprint ""
		(layer "F.Cu")
		(at 433.0446 -16.832072 180)
		(property "Reference" "R6W47"
			(at -0.8382 -0.67818 180)
			(unlocked yes)
			(layer "F.SilkS")
			(effects
				(font
					(size 0.4064 0.254)
					(thickness 0.1524)
				)
				(justify left)
			)
		)
		(property "Value" ""
			(at 0 0 180)
			(layer "F.Fab")
			(effects
				(font
					(size 1.27 1.27)
				)
			)
		)
		(duplicate_pad_numbers_are_jumpers no)
		(fp_poly
			(pts
				(xy -0.2794 -0.1016) (xy 0.2794 -0.1016) (xy 0.2794 0.9906) (xy -0.2794 0.9906)
			)
			(stroke
				(width 0)
				(type default)
			)
			(fill no)
			(layer "F.CrtYd")
		)
		(fp_line
			(start 0.2794 0.9906)
			(end 0.2794 -0.1016)
			(stroke
				(width 0.1)
				(type default)
			)
			(layer "F.Fab")
		)
		(fp_line
			(start 0.2794 -0.1016)
			(end -0.2794 -0.1016)
			(stroke
				(width 0.1)
				(type default)
			)
			(layer "F.Fab")
		)
		(fp_line
			(start -0.2794 0.9906)
			(end 0.2794 0.9906)
			(stroke
				(width 0.1)
				(type default)
			)
			(layer "F.Fab")
		)
		(fp_line
			(start -0.2794 -0.1016)
			(end -0.2794 0.9906)
			(stroke
				(width 0.1)
				(type default)
			)
			(layer "F.Fab")
		)
		(pad "1" smd rect
			(at 0 0 180)
			(size 0.508 0.508)
			(layers "F.Cu" "F.Mask" "F.Paste")
			(net "PCA9554_A0")
		)
		(pad "2" smd rect
			(at 0 0.889 180)
			(size 0.508 0.508)
			(layers "F.Cu" "F.Mask" "F.Paste")
			(net "GND")
		)
		(zone
			(layer "F.Cu")
			(hatch none 0.5)
			(connect_pads
				(clearance 0)
			)
			(min_thickness 0.25)
			(keepout
				(tracks not_allowed)
				(vias allowed)
				(pads allowed)
				(copperpour not_allowed)
				(footprints allowed)
			)
			(placement
				(enabled no)
				(sheetname "")
			)
			(fill
				(thermal_gap 0.5)
				(thermal_bridge_width 0.5)
				(island_removal_mode 0)
			)
			(polygon
				(pts
					(xy 433.2986 -17.467072) (xy 432.7906 -17.467072) (xy 432.7906 -17.086072) (xy 433.2986 -17.086072)
				)
			)
		)
		(zone
			(layer "F.Cu")
			(hatch none 0.5)
			(connect_pads
				(clearance 0)
			)
			(min_thickness 0.25)
			(keepout
				(tracks allowed)
				(vias not_allowed)
				(pads allowed)
				(copperpour not_allowed)
				(footprints allowed)
			)
			(placement
				(enabled no)
				(sheetname "")
			)
			(fill
				(thermal_gap 0.5)
				(thermal_bridge_width 0.5)
				(island_removal_mode 0)
			)
			(polygon
				(pts
					(xy 433.2986 -17.086072) (xy 432.7906 -17.086072) (xy 432.7906 -17.467072) (xy 433.2986 -17.467072)
				)
			)
		)
	)
	(footprint ""
		(layer "F.Cu")
		(at 209.296 -51.382168)
		(property "Reference" "R5P1"
			(at 0 0 0)
			(layer "F.SilkS")
			(hide yes)
			(effects
				(font
					(size 1.27 1.27)
				)
			)
		)
		(property "Value" ""
			(at 0 0 0)
			(layer "F.Fab")
			(effects
				(font
					(size 1.27 1.27)
				)
			)
		)
		(duplicate_pad_numbers_are_jumpers no)
		(fp_poly
			(pts
				(xy -0.4953 -0.2032) (xy 0.4953 -0.2032) (xy 0.4953 1.6002) (xy -0.4953 1.6002)
			)
			(stroke
				(width 0)
				(type default)
			)
			(fill no)
			(layer "F.CrtYd")
		)
		(fp_line
			(start -0.4953 -0.2032)
			(end 0.4953 -0.2032)
			(stroke
				(width 0.1)
				(type default)
			)
			(layer "F.Fab")
		)
		(fp_line
			(start -0.4953 1.6002)
			(end -0.4953 -0.2032)
			(stroke
				(width 0.1)
				(type default)
			)
			(layer "F.Fab")
		)
		(fp_line
			(start 0.4953 -0.2032)
			(end 0.4953 1.6002)
			(stroke
				(width 0.1)
				(type default)
			)
			(layer "F.Fab")
		)
		(fp_line
			(start 0.4953 1.6002)
			(end -0.4953 1.6002)
			(stroke
				(width 0.1)
				(type default)
			)
			(layer "F.Fab")
		)
		(pad "1" smd rect
			(at 0 0)
			(size 0.762 0.889)
			(layers "F.Cu" "F.Mask" "F.Paste")
			(net "PVCCIN_CPU0")
		)
		(pad "2" smd rect
			(at 0 1.397)
			(size 0.762 0.889)
			(layers "F.Cu" "F.Mask" "F.Paste")
			(net "VSENSE_VCCINR2PMAX_CPU0")
		)
		(zone
			(layer "F.Cu")
			(hatch none 0.5)
			(connect_pads
				(clearance 0)
			)
			(min_thickness 0.25)
			(keepout
				(tracks not_allowed)
				(vias allowed)
				(pads allowed)
				(copperpour not_allowed)
				(footprints allowed)
			)
			(placement
				(enabled no)
				(sheetname "")
			)
			(fill
				(thermal_gap 0.5)
				(thermal_bridge_width 0.5)
				(island_removal_mode 0)
			)
			(polygon
				(pts
					(xy 208.915 -50.429668) (xy 209.677 -50.429668) (xy 209.677 -50.937668) (xy 208.915 -50.937668)
				)
			)
		)
		(zone
			(layer "F.Cu")
			(hatch none 0.5)
			(connect_pads
				(clearance 0)
			)
			(min_thickness 0.25)
			(keepout
				(tracks allowed)
				(vias not_allowed)
				(pads allowed)
				(copperpour not_allowed)
				(footprints allowed)
			)
			(placement
				(enabled no)
				(sheetname "")
			)
			(fill
				(thermal_gap 0.5)
				(thermal_bridge_width 0.5)
				(island_removal_mode 0)
			)
			(polygon
				(pts
					(xy 209.677 -50.429668) (xy 209.677 -50.937668) (xy 208.915 -50.937668) (xy 208.915 -50.429668)
				)
			)
		)
	)
	(footprint ""
		(layer "F.Cu")
		(at 439.160412 -153.572718 90)
		(property "Reference" "FB25W2"
			(at 0 0 90)
			(layer "F.SilkS")
			(hide yes)
			(effects
				(font
					(size 1.27 1.27)
				)
			)
		)
		(property "Value" "*"
			(at -0.0127 -7.01675 90)
			(unlocked yes)
			(layer "F.Fab")
			(hide yes)
			(effects
				(font
					(size 0.889 0.889)
					(thickness 0.1524)
				)
			)
		)
		(property "Device Type" "BLM15AG121SN-1GP_DISCRET-G-BLMA"
			(at -0.0127 -8.54075 90)
			(unlocked yes)
			(layer "F.Fab")
			(hide yes)
			(effects
				(font
					(size 0.889 0.889)
					(thickness 0.1524)
				)
			)
		)
		(duplicate_pad_numbers_are_jumpers no)
		(fp_line
			(start 0.508 -0.9398)
			(end -0.508 -0.9398)
			(stroke
				(width 0.1524)
				(type default)
			)
			(layer "F.SilkS")
		)
		(fp_line
			(start -0.508 -0.9398)
			(end -0.508 0.9398)
			(stroke
				(width 0.1524)
				(type default)
			)
			(layer "F.SilkS")
		)
		(fp_line
			(start -0.508 0.9398)
			(end -0.508 0.8636)
			(stroke
				(width 0.1524)
				(type default)
			)
			(layer "F.SilkS")
		)
		(fp_rect
			(start -0.508 0.9398)
			(end 0.508 -0.9398)
			(stroke
				(width 0)
				(type default)
			)
			(fill no)
			(layer "F.CrtYd")
		)
		(fp_rect
			(start -0.508 0.9398)
			(end 0.508 -0.9398)
			(stroke
				(width 0)
				(type default)
			)
			(fill no)
			(layer "F.Fab")
		)
		(pad "1" smd custom
			(at 0 -0.4445 90)
			(size 0.1397 0.1397)
			(layers "F.Cu" "F.Mask" "F.Paste")
			(net "XDP_PCH_TCK1_R")
			(options
				(clearance outline)
				(anchor circle)
			)
			(primitives
				(gr_poly
					(pts
						(arc
							(start -0.1778 -0.2794)
							(mid -0.249642 -0.249642)
							(end -0.2794 -0.1778)
						)
						(arc
							(start -0.2794 0.1778)
							(mid -0.249642 0.249642)
							(end -0.1778 0.2794)
						)
						(arc
							(start 0.1778 0.2794)
							(mid 0.249642 0.249642)
							(end 0.2794 0.1778)
						)
						(arc
							(start 0.2794 -0.1778)
							(mid 0.249642 -0.249642)
							(end 0.1778 -0.2794)
						)
					)
					(width 0)
					(fill yes)
				)
			)
		)
		(pad "2" smd custom
			(at 0 0.4445 90)
			(size 0.1397 0.1397)
			(layers "F.Cu" "F.Mask" "F.Paste")
			(net "XDP_PCH_TCK1")
			(options
				(clearance outline)
				(anchor circle)
			)
			(primitives
				(gr_poly
					(pts
						(arc
							(start -0.1778 -0.2794)
							(mid -0.249642 -0.249642)
							(end -0.2794 -0.1778)
						)
						(arc
							(start -0.2794 0.1778)
							(mid -0.249642 0.249642)
							(end -0.1778 0.2794)
						)
						(arc
							(start 0.1778 0.2794)
							(mid 0.249642 0.249642)
							(end 0.2794 0.1778)
						)
						(arc
							(start 0.2794 -0.1778)
							(mid 0.249642 -0.249642)
							(end 0.1778 -0.2794)
						)
					)
					(width 0)
					(fill yes)
				)
			)
		)
	)
	(footprint ""
		(layer "F.Cu")
		(at 193.4464 -63.25108)
		(property "Reference" "R4E19"
			(at 0 0 0)
			(layer "F.SilkS")
			(hide yes)
			(effects
				(font
					(size 1.27 1.27)
				)
			)
		)
		(property "Value" ""
			(at 0 0 0)
			(layer "F.Fab")
			(effects
				(font
					(size 1.27 1.27)
				)
			)
		)
		(duplicate_pad_numbers_are_jumpers no)
		(fp_poly
			(pts
				(xy -0.2794 -0.1016) (xy 0.2794 -0.1016) (xy 0.2794 0.9906) (xy -0.2794 0.9906)
			)
			(stroke
				(width 0)
				(type default)
			)
			(fill no)
			(layer "F.CrtYd")
		)
		(fp_line
			(start -0.2794 -0.1016)
			(end -0.2794 0.9906)
			(stroke
				(width 0.1)
				(type default)
			)
			(layer "F.Fab")
		)
		(fp_line
			(start -0.2794 0.9906)
			(end 0.2794 0.9906)
			(stroke
				(width 0.1)
				(type default)
			)
			(layer "F.Fab")
		)
		(fp_line
			(start 0.2794 -0.1016)
			(end -0.2794 -0.1016)
			(stroke
				(width 0.1)
				(type default)
			)
			(layer "F.Fab")
		)
		(fp_line
			(start 0.2794 0.9906)
			(end 0.2794 -0.1016)
			(stroke
				(width 0.1)
				(type default)
			)
			(layer "F.Fab")
		)
		(pad "1" smd rect
			(at 0 0)
			(size 0.508 0.508)
			(layers "F.Cu" "F.Mask" "F.Paste")
			(net "VR_PVCCIN_CPU0_PH2_OCSET")
		)
		(pad "2" smd rect
			(at 0 0.889)
			(size 0.508 0.508)
			(layers "F.Cu" "F.Mask" "F.Paste")
			(net "GND")
		)
		(zone
			(layer "F.Cu")
			(hatch none 0.5)
			(connect_pads
				(clearance 0)
			)
			(min_thickness 0.25)
			(keepout
				(tracks allowed)
				(vias not_allowed)
				(pads allowed)
				(copperpour not_allowed)
				(footprints allowed)
			)
			(placement
				(enabled no)
				(sheetname "")
			)
			(fill
				(thermal_gap 0.5)
				(thermal_bridge_width 0.5)
				(island_removal_mode 0)
			)
			(polygon
				(pts
					(xy 193.1924 -62.99708) (xy 193.7004 -62.99708) (xy 193.7004 -62.61608) (xy 193.1924 -62.61608)
				)
			)
		)
		(zone
			(layer "F.Cu")
			(hatch none 0.5)
			(connect_pads
				(clearance 0)
			)
			(min_thickness 0.25)
			(keepout
				(tracks not_allowed)
				(vias allowed)
				(pads allowed)
				(copperpour not_allowed)
				(footprints allowed)
			)
			(placement
				(enabled no)
				(sheetname "")
			)
			(fill
				(thermal_gap 0.5)
				(thermal_bridge_width 0.5)
				(island_removal_mode 0)
			)
			(polygon
				(pts
					(xy 193.1924 -62.61608) (xy 193.7004 -62.61608) (xy 193.7004 -62.99708) (xy 193.1924 -62.99708)
				)
			)
		)
	)
	(footprint ""
		(layer "F.Cu")
		(at 24.05634 -93.323156 180)
		(property "Reference" "RF11"
			(at -0.8382 -0.67818 180)
			(unlocked yes)
			(layer "F.SilkS")
			(effects
				(font
					(size 0.4064 0.254)
					(thickness 0.1524)
				)
				(justify left)
			)
		)
		(property "Value" ""
			(at 0 0 180)
			(layer "F.Fab")
			(effects
				(font
					(size 1.27 1.27)
				)
			)
		)
		(duplicate_pad_numbers_are_jumpers no)
		(fp_poly
			(pts
				(xy -0.2794 -0.1016) (xy 0.2794 -0.1016) (xy 0.2794 0.9906) (xy -0.2794 0.9906)
			)
			(stroke
				(width 0)
				(type default)
			)
			(fill no)
			(layer "F.CrtYd")
		)
		(fp_line
			(start 0.2794 0.9906)
			(end 0.2794 -0.1016)
			(stroke
				(width 0.1)
				(type default)
			)
			(layer "F.Fab")
		)
		(fp_line
			(start 0.2794 -0.1016)
			(end -0.2794 -0.1016)
			(stroke
				(width 0.1)
				(type default)
			)
			(layer "F.Fab")
		)
		(fp_line
			(start -0.2794 0.9906)
			(end 0.2794 0.9906)
			(stroke
				(width 0.1)
				(type default)
			)
			(layer "F.Fab")
		)
		(fp_line
			(start -0.2794 -0.1016)
			(end -0.2794 0.9906)
			(stroke
				(width 0.1)
				(type default)
			)
			(layer "F.Fab")
		)
		(pad "1" smd rect
			(at 0 0 180)
			(size 0.508 0.508)
			(layers "F.Cu" "F.Mask" "F.Paste")
			(net "VR_PVCCIN_CPU1_AIREF5")
		)
		(pad "2" smd rect
			(at 0 0.889 180)
			(size 0.508 0.508)
			(layers "F.Cu" "F.Mask" "F.Paste")
			(net "ISENSE_PVCCIN_CPU1_PH5_IMON")
		)
		(zone
			(layer "F.Cu")
			(hatch none 0.5)
			(connect_pads
				(clearance 0)
			)
			(min_thickness 0.25)
			(keepout
				(tracks not_allowed)
				(vias allowed)
				(pads allowed)
				(copperpour not_allowed)
				(footprints allowed)
			)
			(placement
				(enabled no)
				(sheetname "")
			)
			(fill
				(thermal_gap 0.5)
				(thermal_bridge_width 0.5)
				(island_removal_mode 0)
			)
			(polygon
				(pts
					(xy 24.31034 -93.958156) (xy 23.80234 -93.958156) (xy 23.80234 -93.577156) (xy 24.31034 -93.577156)
				)
			)
		)
		(zone
			(layer "F.Cu")
			(hatch none 0.5)
			(connect_pads
				(clearance 0)
			)
			(min_thickness 0.25)
			(keepout
				(tracks allowed)
				(vias not_allowed)
				(pads allowed)
				(copperpour not_allowed)
				(footprints allowed)
			)
			(placement
				(enabled no)
				(sheetname "")
			)
			(fill
				(thermal_gap 0.5)
				(thermal_bridge_width 0.5)
				(island_removal_mode 0)
			)
			(polygon
				(pts
					(xy 24.31034 -93.577156) (xy 23.80234 -93.577156) (xy 23.80234 -93.958156) (xy 24.31034 -93.958156)
				)
			)
		)
	)
	(footprint ""
		(layer "F.Cu")
		(at 23.114 -73.406 -90)
		(property "Reference" "R1D39"
			(at 0 0 270)
			(layer "F.SilkS")
			(hide yes)
			(effects
				(font
					(size 1.27 1.27)
				)
			)
		)
		(property "Value" ""
			(at 0 0 270)
			(layer "F.Fab")
			(effects
				(font
					(size 1.27 1.27)
				)
			)
		)
		(duplicate_pad_numbers_are_jumpers no)
		(fp_poly
			(pts
				(xy -0.2794 -0.1016) (xy 0.2794 -0.1016) (xy 0.2794 0.9906) (xy -0.2794 0.9906)
			)
			(stroke
				(width 0)
				(type default)
			)
			(fill no)
			(layer "F.CrtYd")
		)
		(fp_line
			(start -0.2794 0.9906)
			(end 0.2794 0.9906)
			(stroke
				(width 0.1)
				(type default)
			)
			(layer "F.Fab")
		)
		(fp_line
			(start 0.2794 0.9906)
			(end 0.2794 -0.1016)
			(stroke
				(width 0.1)
				(type default)
			)
			(layer "F.Fab")
		)
		(fp_line
			(start -0.2794 -0.1016)
			(end -0.2794 0.9906)
			(stroke
				(width 0.1)
				(type default)
			)
			(layer "F.Fab")
		)
		(fp_line
			(start 0.2794 -0.1016)
			(end -0.2794 -0.1016)
			(stroke
				(width 0.1)
				(type default)
			)
			(layer "F.Fab")
		)
		(pad "1" smd rect
			(at 0 0 270)
			(size 0.508 0.508)
			(layers "F.Cu" "F.Mask" "F.Paste")
			(net "A_HSC_VCAP")
		)
		(pad "2" smd rect
			(at 0 0.889 270)
			(size 0.508 0.508)
			(layers "F.Cu" "F.Mask" "F.Paste")
			(net "A_HSC_PSET")
		)
		(zone
			(layer "F.Cu")
			(hatch none 0.5)
			(connect_pads
				(clearance 0)
			)
			(min_thickness 0.25)
			(keepout
				(tracks not_allowed)
				(vias allowed)
				(pads allowed)
				(copperpour not_allowed)
				(footprints allowed)
			)
			(placement
				(enabled no)
				(sheetname "")
			)
			(fill
				(thermal_gap 0.5)
				(thermal_bridge_width 0.5)
				(island_removal_mode 0)
			)
			(polygon
				(pts
					(xy 22.479 -73.66) (xy 22.479 -73.152) (xy 22.86 -73.152) (xy 22.86 -73.66)
				)
			)
		)
		(zone
			(layer "F.Cu")
			(hatch none 0.5)
			(connect_pads
				(clearance 0)
			)
			(min_thickness 0.25)
			(keepout
				(tracks allowed)
				(vias not_allowed)
				(pads allowed)
				(copperpour not_allowed)
				(footprints allowed)
			)
			(placement
				(enabled no)
				(sheetname "")
			)
			(fill
				(thermal_gap 0.5)
				(thermal_bridge_width 0.5)
				(island_removal_mode 0)
			)
			(polygon
				(pts
					(xy 22.86 -73.66) (xy 22.86 -73.152) (xy 22.479 -73.152) (xy 22.479 -73.66)
				)
			)
		)
	)
	(footprint ""
		(layer "F.Cu")
		(at 332.888844 -117.35562 -90)
		(property "Reference" "C843"
			(at -0.8382 -0.67818 270)
			(unlocked yes)
			(layer "F.SilkS")
			(effects
				(font
					(size 0.4064 0.254)
					(thickness 0.1524)
				)
				(justify left)
			)
		)
		(property "Value" ""
			(at 0 0 270)
			(layer "F.Fab")
			(effects
				(font
					(size 1.27 1.27)
				)
			)
		)
		(duplicate_pad_numbers_are_jumpers no)
		(fp_poly
			(pts
				(xy 0.3048 -0.1016) (xy 0.3048 0.9906) (xy -0.3048 0.9906) (xy -0.3048 -0.1016)
			)
			(stroke
				(width 0)
				(type default)
			)
			(fill no)
			(layer "F.CrtYd")
		)
		(fp_line
			(start -0.3048 0.9906)
			(end 0.3048 0.9906)
			(stroke
				(width 0.1)
				(type default)
			)
			(layer "F.Fab")
		)
		(fp_line
			(start 0.3048 0.9906)
			(end 0.3048 -0.1016)
			(stroke
				(width 0.1)
				(type default)
			)
			(layer "F.Fab")
		)
		(fp_line
			(start -0.3048 -0.1016)
			(end -0.3048 0.9906)
			(stroke
				(width 0.1)
				(type default)
			)
			(layer "F.Fab")
		)
		(fp_line
			(start 0.3048 -0.1016)
			(end -0.3048 -0.1016)
			(stroke
				(width 0.1)
				(type default)
			)
			(layer "F.Fab")
		)
		(pad "1" smd rect
			(at 0 0 270)
			(size 0.508 0.508)
			(layers "F.Cu" "F.Mask" "F.Paste")
			(net "P3E_CPU0_PE1_PCH_TXP<8>")
		)
		(pad "2" smd rect
			(at 0 0.889 270)
			(size 0.508 0.508)
			(layers "F.Cu" "F.Mask" "F.Paste")
			(net "P3E_CPU0_PE1_PCH_CON_TXP<8>")
		)
		(zone
			(layer "F.Cu")
			(hatch none 0.5)
			(connect_pads
				(clearance 0)
			)
			(min_thickness 0.25)
			(keepout
				(tracks not_allowed)
				(vias allowed)
				(pads allowed)
				(copperpour not_allowed)
				(footprints allowed)
			)
			(placement
				(enabled no)
				(sheetname "")
			)
			(fill
				(thermal_gap 0.5)
				(thermal_bridge_width 0.5)
				(island_removal_mode 0)
			)
			(polygon
				(pts
					(xy 332.253844 -117.60962) (xy 332.253844 -117.10162) (xy 332.634844 -117.10162) (xy 332.634844 -117.60962)
				)
			)
		)
		(zone
			(layer "F.Cu")
			(hatch none 0.5)
			(connect_pads
				(clearance 0)
			)
			(min_thickness 0.25)
			(keepout
				(tracks allowed)
				(vias not_allowed)
				(pads allowed)
				(copperpour not_allowed)
				(footprints allowed)
			)
			(placement
				(enabled no)
				(sheetname "")
			)
			(fill
				(thermal_gap 0.5)
				(thermal_bridge_width 0.5)
				(island_removal_mode 0)
			)
			(polygon
				(pts
					(xy 332.634844 -117.60962) (xy 332.634844 -117.10162) (xy 332.253844 -117.10162) (xy 332.253844 -117.60962)
				)
			)
		)
	)
	(footprint ""
		(layer "F.Cu")
		(at 0.74676 -11.99896)
		(property "Reference" "RT19"
			(at 1.01473 0.656336 270)
			(unlocked yes)
			(layer "F.SilkS")
			(effects
				(font
					(size 0.4064 0.254)
					(thickness 0.1524)
				)
			)
		)
		(property "Value" ""
			(at 0 0 0)
			(layer "F.Fab")
			(effects
				(font
					(size 1.27 1.27)
				)
			)
		)
		(duplicate_pad_numbers_are_jumpers no)
		(fp_rect
			(start -0.4953 1.6002)
			(end 0.4953 -0.2032)
			(stroke
				(width 0)
				(type default)
			)
			(fill no)
			(layer "F.CrtYd")
		)
		(fp_line
			(start -0.4953 -0.2032)
			(end 0.4953 -0.2032)
			(stroke
				(width 0.1)
				(type default)
			)
			(layer "F.Fab")
		)
		(fp_line
			(start -0.4953 1.6002)
			(end -0.4953 -0.2032)
			(stroke
				(width 0.1)
				(type default)
			)
			(layer "F.Fab")
		)
		(fp_line
			(start 0.4953 -0.2032)
			(end 0.4953 1.6002)
			(stroke
				(width 0.1)
				(type default)
			)
			(layer "F.Fab")
		)
		(fp_line
			(start 0.4953 1.6002)
			(end -0.4953 1.6002)
			(stroke
				(width 0.1)
				(type default)
			)
			(layer "F.Fab")
		)
		(pad "1" smd rect
			(at 0 0)
			(size 0.762 0.889)
			(layers "F.Cu" "F.Mask" "F.Paste")
			(net "VR_PVDDQ_GHJ_PH1_BOOT")
		)
		(pad "2" smd rect
			(at 0 1.397)
			(size 0.762 0.889)
			(layers "F.Cu" "F.Mask" "F.Paste")
			(net "VR_PVDDQ_GHJ_PH1_BOOT_R")
		)
		(zone
			(layer "F.Cu")
			(hatch none 0.5)
			(connect_pads
				(clearance 0)
			)
			(min_thickness 0.25)
			(keepout
				(tracks not_allowed)
				(vias allowed)
				(pads allowed)
				(copperpour not_allowed)
				(footprints allowed)
			)
			(placement
				(enabled no)
				(sheetname "")
			)
			(fill
				(thermal_gap 0.5)
				(thermal_bridge_width 0.5)
				(island_removal_mode 0)
			)
			(polygon
				(pts
					(xy 0.36576 -11.04646) (xy 1.12776 -11.04646) (xy 1.12776 -11.55446) (xy 0.36576 -11.55446)
				)
			)
		)
		(zone
			(layer "F.Cu")
			(hatch none 0.5)
			(connect_pads
				(clearance 0)
			)
			(min_thickness 0.25)
			(keepout
				(tracks allowed)
				(vias not_allowed)
				(pads allowed)
				(copperpour not_allowed)
				(footprints allowed)
			)
			(placement
				(enabled no)
				(sheetname "")
			)
			(fill
				(thermal_gap 0.5)
				(thermal_bridge_width 0.5)
				(island_removal_mode 0)
			)
			(polygon
				(pts
					(xy 0.36576 -11.04646) (xy 1.12776 -11.04646) (xy 1.12776 -11.55446) (xy 0.36576 -11.55446)
				)
			)
		)
	)
	(footprint ""
		(layer "F.Cu")
		(at 411.0355 -111.633 -90)
		(property "Reference" "R8C1"
			(at 0 0 270)
			(layer "F.SilkS")
			(hide yes)
			(effects
				(font
					(size 1.27 1.27)
				)
			)
		)
		(property "Value" ""
			(at 0 0 270)
			(layer "F.Fab")
			(effects
				(font
					(size 1.27 1.27)
				)
			)
		)
		(duplicate_pad_numbers_are_jumpers no)
		(fp_poly
			(pts
				(xy -0.2794 -0.1016) (xy 0.2794 -0.1016) (xy 0.2794 0.9906) (xy -0.2794 0.9906)
			)
			(stroke
				(width 0)
				(type default)
			)
			(fill no)
			(layer "F.CrtYd")
		)
		(fp_line
			(start -0.2794 0.9906)
			(end 0.2794 0.9906)
			(stroke
				(width 0.1)
				(type default)
			)
			(layer "F.Fab")
		)
		(fp_line
			(start 0.2794 0.9906)
			(end 0.2794 -0.1016)
			(stroke
				(width 0.1)
				(type default)
			)
			(layer "F.Fab")
		)
		(fp_line
			(start -0.2794 -0.1016)
			(end -0.2794 0.9906)
			(stroke
				(width 0.1)
				(type default)
			)
			(layer "F.Fab")
		)
		(fp_line
			(start 0.2794 -0.1016)
			(end -0.2794 -0.1016)
			(stroke
				(width 0.1)
				(type default)
			)
			(layer "F.Fab")
		)
		(pad "1" smd rect
			(at 0 0 270)
			(size 0.508 0.508)
			(layers "F.Cu" "F.Mask" "F.Paste")
			(net "P3V3_STBY")
		)
		(pad "2" smd rect
			(at 0 0.889 270)
			(size 0.508 0.508)
			(layers "F.Cu" "F.Mask" "F.Paste")
			(net "FM_SLT_CFG1")
		)
		(zone
			(layer "F.Cu")
			(hatch none 0.5)
			(connect_pads
				(clearance 0)
			)
			(min_thickness 0.25)
			(keepout
				(tracks not_allowed)
				(vias allowed)
				(pads allowed)
				(copperpour not_allowed)
				(footprints allowed)
			)
			(placement
				(enabled no)
				(sheetname "")
			)
			(fill
				(thermal_gap 0.5)
				(thermal_bridge_width 0.5)
				(island_removal_mode 0)
			)
			(polygon
				(pts
					(xy 410.4005 -111.887) (xy 410.4005 -111.379) (xy 410.7815 -111.379) (xy 410.7815 -111.887)
				)
			)
		)
		(zone
			(layer "F.Cu")
			(hatch none 0.5)
			(connect_pads
				(clearance 0)
			)
			(min_thickness 0.25)
			(keepout
				(tracks allowed)
				(vias not_allowed)
				(pads allowed)
				(copperpour not_allowed)
				(footprints allowed)
			)
			(placement
				(enabled no)
				(sheetname "")
			)
			(fill
				(thermal_gap 0.5)
				(thermal_bridge_width 0.5)
				(island_removal_mode 0)
			)
			(polygon
				(pts
					(xy 410.7815 -111.887) (xy 410.7815 -111.379) (xy 410.4005 -111.379) (xy 410.4005 -111.887)
				)
			)
		)
	)
	(footprint ""
		(layer "F.Cu")
		(at 410.340048 -66.529966)
		(property "Reference" "J8E1"
			(at 0.762 9.42213 180)
			(unlocked yes)
			(layer "F.SilkS")
			(effects
				(font
					(size 0.7874 0.5842)
					(thickness 0.1524)
				)
			)
		)
		(property "Value" ""
			(at 0 0 0)
			(layer "F.Fab")
			(effects
				(font
					(size 1.27 1.27)
				)
			)
		)
		(duplicate_pad_numbers_are_jumpers no)
		(fp_poly
			(pts
				(xy -1.048512 -0.391414) (xy -1.587246 -1.648714) (xy -2.305558 -0.930402)
			)
			(stroke
				(width 0)
				(type default)
			)
			(fill yes)
			(layer "F.SilkS")
		)
		(fp_rect
			(start -0.4572 7.72922)
			(end 4.6736 -2.71018)
			(stroke
				(width 0)
				(type default)
			)
			(fill no)
			(layer "F.CrtYd")
		)
		(fp_line
			(start -0.4572 -2.71018)
			(end -0.4572 7.72922)
			(stroke
				(width 0.1)
				(type default)
			)
			(layer "F.Fab")
		)
		(fp_line
			(start -0.4572 7.72922)
			(end 4.6736 7.72922)
			(stroke
				(width 0.1)
				(type default)
			)
			(layer "F.Fab")
		)
		(fp_line
			(start 4.6736 -2.71018)
			(end -0.4572 -2.71018)
			(stroke
				(width 0.1)
				(type default)
			)
			(layer "F.Fab")
		)
		(fp_line
			(start 4.6736 7.72922)
			(end 4.6736 -2.71018)
			(stroke
				(width 0.1)
				(type default)
			)
			(layer "F.Fab")
		)
		(fp_poly
			(pts
				(xy -1.215644 -0.006858) (xy -2.485644 0.501142) (xy -2.485644 -0.514858)
			)
			(stroke
				(width 0)
				(type default)
			)
			(fill yes)
			(layer "F.Fab")
		)
		(fp_text user "6"
			(at -1.763776 5.710682 0)
			(unlocked yes)
			(layer "F.SilkS")
			(effects
				(font
					(size 0.7874 0.5842)
					(thickness 0.1524)
				)
				(justify left)
			)
		)
		(fp_text user "7"
			(at 5.340604 1.199642 0)
			(unlocked yes)
			(layer "F.SilkS")
			(effects
				(font
					(size 0.7874 0.5842)
					(thickness 0.1524)
				)
				(justify left)
			)
		)
		(fp_text user "11"
			(at 5.407152 6.367018 0)
			(unlocked yes)
			(layer "F.SilkS")
			(effects
				(font
					(size 0.7874 0.5842)
					(thickness 0.1524)
				)
				(justify left)
			)
		)
		(fp_text user "6"
			(at -2.42951 4.930394 0)
			(unlocked yes)
			(layer "F.Fab")
			(effects
				(font
					(size 0.7874 0.5842)
					(thickness 0.1524)
				)
				(justify left)
			)
		)
		(fp_text user "11"
			(at 5.280152 4.716018 0)
			(unlocked yes)
			(layer "F.Fab")
			(effects
				(font
					(size 0.7874 0.5842)
					(thickness 0.1524)
				)
				(justify left)
			)
		)
		(fp_text user "7"
			(at 6.282944 0.5588 0)
			(unlocked yes)
			(layer "F.Fab")
			(effects
				(font
					(size 0.7874 0.5842)
					(thickness 0.1524)
				)
				(justify left)
			)
		)
		(pad "" np_thru_hole circle
			(at 3.20802 -0.52578)
			(size 0.254 0.254)
			(drill 0.762)
			(layers "*.Cu" "*.Mask")
			(clearance 0.5715)
			(thermal_gap 0.5715)
		)
		(pad "" np_thru_hole circle
			(at 3.20802 5.51942)
			(size 0.254 0.254)
			(drill 0.762)
			(layers "*.Cu" "*.Mask")
			(clearance 0.5715)
			(thermal_gap 0.5715)
		)
		(pad "1" smd rect
			(at 0 0)
			(size 1.6256 0.6096)
			(layers "F.Cu" "F.Mask" "F.Paste")
			(net "SPI_PCH_TPM_CLK_R")
		)
		(pad "2" smd rect
			(at 0 0.999998)
			(size 1.6256 0.6096)
			(layers "F.Cu" "F.Mask" "F.Paste")
			(net "RST_PLTRST_BUF_N")
		)
		(pad "3" smd rect
			(at 0 1.999996)
			(size 1.6256 0.6096)
			(layers "F.Cu" "F.Mask" "F.Paste")
			(net "SPI_PCH_TPM_MOSI_R")
		)
		(pad "4" smd rect
			(at 0 2.999994)
			(size 1.6256 0.6096)
			(layers "F.Cu" "F.Mask" "F.Paste")
			(net "SPI_PCH_TPM_MISO_R")
		)
		(pad "5" smd rect
			(at 0 3.999992)
			(size 1.6256 0.6096)
			(layers "F.Cu" "F.Mask" "F.Paste")
			(net "SPI_PCH_TPM_CS_R_N")
		)
		(pad "6" smd rect
			(at 0 4.99999)
			(size 1.6256 0.6096)
			(layers "F.Cu" "F.Mask" "F.Paste")
			(net "SMB_SENSOR_STBY_LVC3_SDA")
		)
		(pad "7" smd rect
			(at 4.2164 0.499872)
			(size 1.6256 0.6096)
			(layers "F.Cu" "F.Mask" "F.Paste")
			(net "P3V3_STBY")
		)
		(pad "8" smd rect
			(at 4.2164 1.49987)
			(size 1.6256 0.6096)
			(layers "F.Cu" "F.Mask" "F.Paste")
			(net "FM_TPM_PRES_RST_N")
		)
		(pad "9" smd rect
			(at 4.2164 2.499868)
			(size 1.6256 0.6096)
			(layers "F.Cu" "F.Mask" "F.Paste")
			(net "IRQ_SPI_TPM_N_R")
		)
		(pad "10" smd rect
			(at 4.2164 3.499866)
			(size 1.6256 0.6096)
			(layers "F.Cu" "F.Mask" "F.Paste")
			(net "SMB_SENSOR_STBY_LVC3_SCL")
		)
		(pad "11" smd rect
			(at 4.2164 4.499864)
			(size 1.6256 0.6096)
			(layers "F.Cu" "F.Mask" "F.Paste")
			(net "GND")
		)
		(pad "MP1" smd custom
			(at 2.1082 -1.71958)
			(size 0.34925 0.34925)
			(layers "F.Cu" "F.Mask" "F.Paste")
			(net "GND")
			(options
				(clearance outline)
				(anchor circle)
			)
			(primitives
				(gr_poly
					(pts
						(arc
							(start 1.49733 0.6985)
							(mid 1.09982 0.558768)
							(end 0.70231 0.6985)
						)
						(xy -2.921 0.6985) (xy -2.921 -0.6985) (xy 2.921 -0.6985) (xy 2.921 0.6985)
					)
					(width 0)
					(fill yes)
				)
			)
		)
		(pad "MP2" smd custom
			(at 2.00406 6.800596)
			(size 0.34925 0.34925)
			(layers "F.Cu" "F.Mask" "F.Paste")
			(net "GND")
			(options
				(clearance outline)
				(anchor circle)
			)
			(primitives
				(gr_poly
					(pts
						(arc
							(start 1.49733 -0.6985)
							(mid 1.09982 -0.558768)
							(end 0.70231 -0.6985)
						)
						(xy -2.921 -0.6985) (xy -2.921 0.6985) (xy 2.921 0.6985) (xy 2.921 -0.6985)
					)
					(width 0)
					(fill yes)
				)
			)
		)
		(zone
			(layers "F.Cu" "B.Cu" "In1.Cu" "In2.Cu" "In3.Cu" "In4.Cu" "In5.Cu" "In6.Cu"
				"In7.Cu" "In8.Cu" "In9.Cu" "In10.Cu" "In11.Cu" "In12.Cu"
			)
			(hatch none 0.5)
			(connect_pads
				(clearance 0)
			)
			(min_thickness 0.25)
			(keepout
				(tracks not_allowed)
				(vias allowed)
				(pads allowed)
				(copperpour not_allowed)
				(footprints allowed)
			)
			(placement
				(enabled no)
				(sheetname "")
			)
			(fill
				(thermal_gap 0.5)
				(thermal_bridge_width 0.5)
				(island_removal_mode 0)
			)
			(polygon
				(pts
					(arc
						(start 414.246568 -67.055746)
						(mid 412.849568 -67.055746)
						(end 414.246568 -67.055746)
					)
				)
			)
		)
		(zone
			(layers "F.Cu" "B.Cu" "In1.Cu" "In2.Cu" "In3.Cu" "In4.Cu" "In5.Cu" "In6.Cu"
				"In7.Cu" "In8.Cu" "In9.Cu" "In10.Cu" "In11.Cu" "In12.Cu"
			)
			(hatch none 0.5)
			(connect_pads
				(clearance 0)
			)
			(min_thickness 0.25)
			(keepout
				(tracks not_allowed)
				(vias allowed)
				(pads allowed)
				(copperpour not_allowed)
				(footprints allowed)
			)
			(placement
				(enabled no)
				(sheetname "")
			)
			(fill
				(thermal_gap 0.5)
				(thermal_bridge_width 0.5)
				(island_removal_mode 0)
			)
			(polygon
				(pts
					(arc
						(start 414.246568 -61.010546)
						(mid 412.849568 -61.010546)
						(end 414.246568 -61.010546)
					)
				)
			)
		)
	)
	(footprint ""
		(layer "F.Cu")
		(at 340.614 -137.1727 90)
		(property "Reference" "C7A34"
			(at 0 0 90)
			(layer "F.SilkS")
			(hide yes)
			(effects
				(font
					(size 1.27 1.27)
				)
			)
		)
		(property "Value" ""
			(at 0 0 90)
			(layer "F.Fab")
			(effects
				(font
					(size 1.27 1.27)
				)
			)
		)
		(duplicate_pad_numbers_are_jumpers no)
		(fp_poly
			(pts
				(xy 0.3048 -0.1016) (xy 0.3048 0.9906) (xy -0.3048 0.9906) (xy -0.3048 -0.1016)
			)
			(stroke
				(width 0)
				(type default)
			)
			(fill no)
			(layer "F.CrtYd")
		)
		(fp_line
			(start 0.3048 -0.1016)
			(end -0.3048 -0.1016)
			(stroke
				(width 0.1)
				(type default)
			)
			(layer "F.Fab")
		)
		(fp_line
			(start -0.3048 -0.1016)
			(end -0.3048 0.9906)
			(stroke
				(width 0.1)
				(type default)
			)
			(layer "F.Fab")
		)
		(fp_line
			(start 0.3048 0.9906)
			(end 0.3048 -0.1016)
			(stroke
				(width 0.1)
				(type default)
			)
			(layer "F.Fab")
		)
		(fp_line
			(start -0.3048 0.9906)
			(end 0.3048 0.9906)
			(stroke
				(width 0.1)
				(type default)
			)
			(layer "F.Fab")
		)
		(pad "1" smd rect
			(at 0 0 90)
			(size 0.508 0.508)
			(layers "F.Cu" "F.Mask" "F.Paste")
			(net "VR_PVPP_DEF_PHASE")
		)
		(pad "2" smd rect
			(at 0 0.889 90)
			(size 0.508 0.508)
			(layers "F.Cu" "F.Mask" "F.Paste")
			(net "VR_PVPP_DEF_SNUB")
		)
		(zone
			(layer "F.Cu")
			(hatch none 0.5)
			(connect_pads
				(clearance 0)
			)
			(min_thickness 0.25)
			(keepout
				(tracks allowed)
				(vias not_allowed)
				(pads allowed)
				(copperpour not_allowed)
				(footprints allowed)
			)
			(placement
				(enabled no)
				(sheetname "")
			)
			(fill
				(thermal_gap 0.5)
				(thermal_bridge_width 0.5)
				(island_removal_mode 0)
			)
			(polygon
				(pts
					(xy 340.868 -136.9187) (xy 340.868 -137.4267) (xy 341.249 -137.4267) (xy 341.249 -136.9187)
				)
			)
		)
		(zone
			(layer "F.Cu")
			(hatch none 0.5)
			(connect_pads
				(clearance 0)
			)
			(min_thickness 0.25)
			(keepout
				(tracks not_allowed)
				(vias allowed)
				(pads allowed)
				(copperpour not_allowed)
				(footprints allowed)
			)
			(placement
				(enabled no)
				(sheetname "")
			)
			(fill
				(thermal_gap 0.5)
				(thermal_bridge_width 0.5)
				(island_removal_mode 0)
			)
			(polygon
				(pts
					(xy 341.249 -136.9187) (xy 341.249 -137.4267) (xy 340.868 -137.4267) (xy 340.868 -136.9187)
				)
			)
		)
	)
	(footprint ""
		(layer "F.Cu")
		(at 29.6164 -67.757802 -90)
		(property "Reference" "C1D35"
			(at 0 0 270)
			(layer "F.SilkS")
			(hide yes)
			(effects
				(font
					(size 1.27 1.27)
				)
			)
		)
		(property "Value" ""
			(at 0 0 270)
			(layer "F.Fab")
			(effects
				(font
					(size 1.27 1.27)
				)
			)
		)
		(duplicate_pad_numbers_are_jumpers no)
		(fp_rect
			(start 0.3048 -0.1016)
			(end -0.3048 0.9906)
			(stroke
				(width 0)
				(type default)
			)
			(fill no)
			(layer "F.CrtYd")
		)
		(fp_line
			(start -0.3048 0.9906)
			(end 0.3048 0.9906)
			(stroke
				(width 0.1)
				(type default)
			)
			(layer "F.Fab")
		)
		(fp_line
			(start 0.3048 0.9906)
			(end 0.3048 -0.1016)
			(stroke
				(width 0.1)
				(type default)
			)
			(layer "F.Fab")
		)
		(fp_line
			(start -0.3048 -0.1016)
			(end -0.3048 0.9906)
			(stroke
				(width 0.1)
				(type default)
			)
			(layer "F.Fab")
		)
		(fp_line
			(start 0.3048 -0.1016)
			(end -0.3048 -0.1016)
			(stroke
				(width 0.1)
				(type default)
			)
			(layer "F.Fab")
		)
		(pad "1" smd rect
			(at 0 0 270)
			(size 0.508 0.508)
			(layers "F.Cu" "F.Mask" "F.Paste")
			(net "VR_FET_SW_P12V_STBY_PVCCIN_CPU1")
		)
		(pad "2" smd rect
			(at 0 0.889 270)
			(size 0.508 0.508)
			(layers "F.Cu" "F.Mask" "F.Paste")
			(net "GND")
		)
		(zone
			(layer "F.Cu")
			(hatch none 0.5)
			(connect_pads
				(clearance 0)
			)
			(min_thickness 0.25)
			(keepout
				(tracks allowed)
				(vias not_allowed)
				(pads allowed)
				(copperpour not_allowed)
				(footprints allowed)
			)
			(placement
				(enabled no)
				(sheetname "")
			)
			(fill
				(thermal_gap 0.5)
				(thermal_bridge_width 0.5)
				(island_removal_mode 0)
			)
			(polygon
				(pts
					(xy 29.3624 -67.503802) (xy 29.3624 -68.011802) (xy 28.9814 -68.011802) (xy 28.9814 -67.503802)
				)
			)
		)
		(zone
			(layer "F.Cu")
			(hatch none 0.5)
			(connect_pads
				(clearance 0)
			)
			(min_thickness 0.25)
			(keepout
				(tracks not_allowed)
				(vias allowed)
				(pads allowed)
				(copperpour not_allowed)
				(footprints allowed)
			)
			(placement
				(enabled no)
				(sheetname "")
			)
			(fill
				(thermal_gap 0.5)
				(thermal_bridge_width 0.5)
				(island_removal_mode 0)
			)
			(polygon
				(pts
					(xy 29.3624 -67.503802) (xy 29.3624 -68.011802) (xy 28.9814 -68.011802) (xy 28.9814 -67.503802)
				)
			)
		)
	)
	(footprint ""
		(layer "F.Cu")
		(at 93.136212 -12.824968 -90)
		(property "Reference" "C2G8"
			(at 0 0 270)
			(layer "F.SilkS")
			(hide yes)
			(effects
				(font
					(size 1.27 1.27)
				)
			)
		)
		(property "Value" ""
			(at 0 0 270)
			(layer "F.Fab")
			(effects
				(font
					(size 1.27 1.27)
				)
			)
		)
		(duplicate_pad_numbers_are_jumpers no)
		(fp_rect
			(start -0.500126 1.598422)
			(end 0.500126 -0.201422)
			(stroke
				(width 0)
				(type default)
			)
			(fill no)
			(layer "F.CrtYd")
		)
		(fp_line
			(start -0.500126 1.598422)
			(end -0.500126 -0.201422)
			(stroke
				(width 0.1)
				(type default)
			)
			(layer "F.Fab")
		)
		(fp_line
			(start 0.500126 1.598422)
			(end -0.500126 1.598422)
			(stroke
				(width 0.1)
				(type default)
			)
			(layer "F.Fab")
		)
		(fp_line
			(start -0.500126 -0.201422)
			(end 0.500126 -0.201422)
			(stroke
				(width 0.1)
				(type default)
			)
			(layer "F.Fab")
		)
		(fp_line
			(start 0.500126 -0.201422)
			(end 0.500126 1.598422)
			(stroke
				(width 0.1)
				(type default)
			)
			(layer "F.Fab")
		)
		(pad "1" smd rect
			(at 0 0 180)
			(size 0.889 0.9906)
			(layers "F.Cu" "F.Mask" "F.Paste")
			(net "PVDDQ_GHJ")
		)
		(pad "2" smd rect
			(at 0 1.397 180)
			(size 0.889 0.9906)
			(layers "F.Cu" "F.Mask" "F.Paste")
			(net "GND")
		)
		(zone
			(layer "F.Cu")
			(hatch none 0.5)
			(connect_pads
				(clearance 0)
			)
			(min_thickness 0.25)
			(keepout
				(tracks allowed)
				(vias not_allowed)
				(pads allowed)
				(copperpour not_allowed)
				(footprints allowed)
			)
			(placement
				(enabled no)
				(sheetname "")
			)
			(fill
				(thermal_gap 0.5)
				(thermal_bridge_width 0.5)
				(island_removal_mode 0)
			)
			(polygon
				(pts
					(xy 92.183712 -13.320268) (xy 92.183712 -12.329668) (xy 92.691712 -12.329668) (xy 92.691712 -13.320268)
				)
			)
		)
		(zone
			(layer "F.Cu")
			(hatch none 0.5)
			(connect_pads
				(clearance 0)
			)
			(min_thickness 0.25)
			(keepout
				(tracks not_allowed)
				(vias allowed)
				(pads allowed)
				(copperpour not_allowed)
				(footprints allowed)
			)
			(placement
				(enabled no)
				(sheetname "")
			)
			(fill
				(thermal_gap 0.5)
				(thermal_bridge_width 0.5)
				(island_removal_mode 0)
			)
			(polygon
				(pts
					(xy 92.183712 -13.320268) (xy 92.183712 -12.329668) (xy 92.691712 -12.329668) (xy 92.691712 -13.320268)
				)
			)
		)
	)
	(footprint ""
		(layer "F.Cu")
		(at 214.503 -59.17692 180)
		(property "Reference" "C4E11"
			(at 0 0 180)
			(layer "F.SilkS")
			(hide yes)
			(effects
				(font
					(size 1.27 1.27)
				)
			)
		)
		(property "Value" ""
			(at 0 0 180)
			(layer "F.Fab")
			(effects
				(font
					(size 1.27 1.27)
				)
			)
		)
		(duplicate_pad_numbers_are_jumpers no)
		(fp_poly
			(pts
				(xy -0.4953 -0.2032) (xy 0.4953 -0.2032) (xy 0.4953 1.6002) (xy -0.4953 1.6002)
			)
			(stroke
				(width 0)
				(type default)
			)
			(fill no)
			(layer "F.CrtYd")
		)
		(fp_line
			(start 0.4953 1.6002)
			(end -0.4953 1.6002)
			(stroke
				(width 0.1)
				(type default)
			)
			(layer "F.Fab")
		)
		(fp_line
			(start 0.4953 -0.2032)
			(end 0.4953 1.6002)
			(stroke
				(width 0.1)
				(type default)
			)
			(layer "F.Fab")
		)
		(fp_line
			(start -0.4953 1.6002)
			(end -0.4953 -0.2032)
			(stroke
				(width 0.1)
				(type default)
			)
			(layer "F.Fab")
		)
		(fp_line
			(start -0.4953 -0.2032)
			(end 0.4953 -0.2032)
			(stroke
				(width 0.1)
				(type default)
			)
			(layer "F.Fab")
		)
		(pad "1" smd rect
			(at 0 0 180)
			(size 0.762 0.889)
			(layers "F.Cu" "F.Mask" "F.Paste")
			(net "PVCCIN_CPU0")
		)
		(pad "2" smd rect
			(at 0 1.397 180)
			(size 0.762 0.889)
			(layers "F.Cu" "F.Mask" "F.Paste")
			(net "GND")
		)
		(zone
			(layer "F.Cu")
			(hatch none 0.5)
			(connect_pads
				(clearance 0)
			)
			(min_thickness 0.25)
			(keepout
				(tracks not_allowed)
				(vias allowed)
				(pads allowed)
				(copperpour not_allowed)
				(footprints allowed)
			)
			(placement
				(enabled no)
				(sheetname "")
			)
			(fill
				(thermal_gap 0.5)
				(thermal_bridge_width 0.5)
				(island_removal_mode 0)
			)
			(polygon
				(pts
					(xy 214.884 -59.62142) (xy 214.122 -59.62142) (xy 214.122 -60.12942) (xy 214.884 -60.12942)
				)
			)
		)
	)
	(footprint ""
		(layer "F.Cu")
		(at 466.344 -137.033 90)
		(property "Reference" "U9A5"
			(at -0.51816 2.26949 90)
			(unlocked yes)
			(layer "F.SilkS")
			(effects
				(font
					(size 0.7874 0.5842)
					(thickness 0.1524)
				)
				(justify left)
			)
		)
		(property "Value" ""
			(at 0 0 90)
			(layer "F.Fab")
			(effects
				(font
					(size 1.27 1.27)
				)
			)
		)
		(duplicate_pad_numbers_are_jumpers no)
		(fp_circle
			(center -0.4699 -0.8382)
			(end -0.4699 -0.7112)
			(stroke
				(width 0.254)
				(type default)
			)
			(fill no)
			(layer "F.SilkS")
		)
		(fp_poly
			(pts
				(xy 0.21463 -0.450088) (xy 1.56337 -0.450088) (xy 1.56337 1.75006) (xy 0.21463 1.75006)
			)
			(stroke
				(width 0)
				(type default)
			)
			(fill no)
			(layer "F.CrtYd")
		)
		(fp_line
			(start 1.56337 -0.450088)
			(end 1.56337 1.75006)
			(stroke
				(width 0.1)
				(type default)
			)
			(layer "F.Fab")
		)
		(fp_line
			(start 0.21463 -0.450088)
			(end 1.56337 -0.450088)
			(stroke
				(width 0.1)
				(type default)
			)
			(layer "F.Fab")
		)
		(fp_line
			(start 1.56337 1.75006)
			(end 0.21463 1.75006)
			(stroke
				(width 0.1)
				(type default)
			)
			(layer "F.Fab")
		)
		(fp_line
			(start 0.21463 1.75006)
			(end 0.21463 -0.450088)
			(stroke
				(width 0.1)
				(type default)
			)
			(layer "F.Fab")
		)
		(fp_circle
			(center -0.4699 -0.8382)
			(end -0.4699 -0.7112)
			(stroke
				(width 0.254)
				(type default)
			)
			(fill no)
			(layer "F.Fab")
		)
		(pad "1" smd rect
			(at 0 0 90)
			(size 1.016 0.381)
			(layers "F.Cu" "F.Mask" "F.Paste")
			(net "FM_CPU0_OR_CPU1_MCP_PRES")
		)
		(pad "2" smd rect
			(at 0 0.649986 90)
			(size 1.016 0.381)
			(layers "F.Cu" "F.Mask" "F.Paste")
			(net "JTAG_MCP_TCK_R1")
		)
		(pad "3" smd rect
			(at 0 1.299972 90)
			(size 1.016 0.381)
			(layers "F.Cu" "F.Mask" "F.Paste")
			(net "GND")
		)
		(pad "4" smd rect
			(at 1.778 1.299972 90)
			(size 1.016 0.381)
			(layers "F.Cu" "F.Mask" "F.Paste")
			(net "GND")
		)
		(pad "5" smd rect
			(at 1.778 0 90)
			(size 1.016 0.381)
			(layers "F.Cu" "F.Mask" "F.Paste")
			(net "P3V3_STBY")
		)
	)
	(footprint ""
		(layer "F.Cu")
		(at 281.178 -74.041 90)
		(property "Reference" "R6D8"
			(at 0 0 90)
			(layer "F.SilkS")
			(hide yes)
			(effects
				(font
					(size 1.27 1.27)
				)
			)
		)
		(property "Value" ""
			(at 0 0 90)
			(layer "F.Fab")
			(effects
				(font
					(size 1.27 1.27)
				)
			)
		)
		(duplicate_pad_numbers_are_jumpers no)
		(fp_rect
			(start -0.2794 -0.1016)
			(end 0.2794 0.9906)
			(stroke
				(width 0)
				(type default)
			)
			(fill no)
			(layer "F.CrtYd")
		)
		(fp_line
			(start 0.2794 -0.1016)
			(end -0.2794 -0.1016)
			(stroke
				(width 0.1)
				(type default)
			)
			(layer "F.Fab")
		)
		(fp_line
			(start -0.2794 -0.1016)
			(end -0.2794 0.9906)
			(stroke
				(width 0.1)
				(type default)
			)
			(layer "F.Fab")
		)
		(fp_line
			(start 0.2794 0.9906)
			(end 0.2794 -0.1016)
			(stroke
				(width 0.1)
				(type default)
			)
			(layer "F.Fab")
		)
		(fp_line
			(start -0.2794 0.9906)
			(end 0.2794 0.9906)
			(stroke
				(width 0.1)
				(type default)
			)
			(layer "F.Fab")
		)
		(pad "1" smd rect
			(at 0 0 90)
			(size 0.508 0.508)
			(layers "F.Cu" "F.Mask" "F.Paste")
			(net "PVCCIO_CPU0")
		)
		(pad "2" smd rect
			(at 0 0.889 90)
			(size 0.508 0.508)
			(layers "F.Cu" "F.Mask" "F.Paste")
			(net "PWRGD_CPU0_G")
		)
		(zone
			(layer "F.Cu")
			(hatch none 0.5)
			(connect_pads
				(clearance 0)
			)
			(min_thickness 0.25)
			(keepout
				(tracks allowed)
				(vias not_allowed)
				(pads allowed)
				(copperpour not_allowed)
				(footprints allowed)
			)
			(placement
				(enabled no)
				(sheetname "")
			)
			(fill
				(thermal_gap 0.5)
				(thermal_bridge_width 0.5)
				(island_removal_mode 0)
			)
			(polygon
				(pts
					(xy 281.432 -73.787) (xy 281.813 -73.787) (xy 281.813 -74.295) (xy 281.432 -74.295)
				)
			)
		)
		(zone
			(layer "F.Cu")
			(hatch none 0.5)
			(connect_pads
				(clearance 0)
			)
			(min_thickness 0.25)
			(keepout
				(tracks not_allowed)
				(vias allowed)
				(pads allowed)
				(copperpour not_allowed)
				(footprints allowed)
			)
			(placement
				(enabled no)
				(sheetname "")
			)
			(fill
				(thermal_gap 0.5)
				(thermal_bridge_width 0.5)
				(island_removal_mode 0)
			)
			(polygon
				(pts
					(xy 281.432 -73.787) (xy 281.813 -73.787) (xy 281.813 -74.295) (xy 281.432 -74.295)
				)
			)
		)
	)
	(footprint ""
		(layer "F.Cu")
		(at 338.235036 -25.265126 90)
		(property "Reference" "C7F4"
			(at 0 0 90)
			(layer "F.SilkS")
			(hide yes)
			(effects
				(font
					(size 1.27 1.27)
				)
			)
		)
		(property "Value" ""
			(at 0 0 90)
			(layer "F.Fab")
			(effects
				(font
					(size 1.27 1.27)
				)
			)
		)
		(duplicate_pad_numbers_are_jumpers no)
		(fp_rect
			(start 0.4953 1.6002)
			(end -0.4953 -0.2032)
			(stroke
				(width 0)
				(type default)
			)
			(fill no)
			(layer "F.CrtYd")
		)
		(fp_line
			(start 0.4953 -0.2032)
			(end 0.4953 1.6002)
			(stroke
				(width 0.1)
				(type default)
			)
			(layer "F.Fab")
		)
		(fp_line
			(start -0.4953 -0.2032)
			(end 0.4953 -0.2032)
			(stroke
				(width 0.1)
				(type default)
			)
			(layer "F.Fab")
		)
		(fp_line
			(start 0.4953 1.6002)
			(end -0.4953 1.6002)
			(stroke
				(width 0.1)
				(type default)
			)
			(layer "F.Fab")
		)
		(fp_line
			(start -0.4953 1.6002)
			(end -0.4953 -0.2032)
			(stroke
				(width 0.1)
				(type default)
			)
			(layer "F.Fab")
		)
		(pad "1" smd rect
			(at 0 0 90)
			(size 0.762 0.889)
			(layers "F.Cu" "F.Mask" "F.Paste")
			(net "VR_PVPP_ABC_PHASE")
		)
		(pad "2" smd rect
			(at 0 1.397 90)
			(size 0.762 0.889)
			(layers "F.Cu" "F.Mask" "F.Paste")
			(net "VR_PVPP_ABC_BOOT_R")
		)
		(zone
			(layer "F.Cu")
			(hatch none 0.5)
			(connect_pads
				(clearance 0)
			)
			(min_thickness 0.25)
			(keepout
				(tracks not_allowed)
				(vias allowed)
				(pads allowed)
				(copperpour not_allowed)
				(footprints allowed)
			)
			(placement
				(enabled no)
				(sheetname "")
			)
			(fill
				(thermal_gap 0.5)
				(thermal_bridge_width 0.5)
				(island_removal_mode 0)
			)
			(polygon
				(pts
					(xy 339.187536 -25.646126) (xy 338.679536 -25.646126) (xy 338.679536 -24.884126) (xy 339.187536 -24.884126)
				)
			)
		)
	)
	(footprint ""
		(layer "F.Cu")
		(at 377.567444 -10.916158)
		(property "Reference" "C7G18"
			(at 0 0 0)
			(layer "F.SilkS")
			(hide yes)
			(effects
				(font
					(size 1.27 1.27)
				)
			)
		)
		(property "Value" ""
			(at 0 0 0)
			(layer "F.Fab")
			(effects
				(font
					(size 1.27 1.27)
				)
			)
		)
		(duplicate_pad_numbers_are_jumpers no)
		(fp_rect
			(start -0.3048 0.9906)
			(end 0.3048 -0.1016)
			(stroke
				(width 0)
				(type default)
			)
			(fill no)
			(layer "F.CrtYd")
		)
		(fp_line
			(start -0.3048 -0.1016)
			(end -0.3048 0.9906)
			(stroke
				(width 0.1)
				(type default)
			)
			(layer "F.Fab")
		)
		(fp_line
			(start -0.3048 0.9906)
			(end 0.3048 0.9906)
			(stroke
				(width 0.1)
				(type default)
			)
			(layer "F.Fab")
		)
		(fp_line
			(start 0.3048 -0.1016)
			(end -0.3048 -0.1016)
			(stroke
				(width 0.1)
				(type default)
			)
			(layer "F.Fab")
		)
		(fp_line
			(start 0.3048 0.9906)
			(end 0.3048 -0.1016)
			(stroke
				(width 0.1)
				(type default)
			)
			(layer "F.Fab")
		)
		(pad "1" smd rect
			(at 0 0)
			(size 0.508 0.508)
			(layers "F.Cu" "F.Mask" "F.Paste")
			(net "P3E_CPU0_PE2_SS_TXN<9>")
		)
		(pad "2" smd rect
			(at 0 0.889)
			(size 0.508 0.508)
			(layers "F.Cu" "F.Mask" "F.Paste")
			(net "P3E_CPU0_PE2_SS_C_TXN<9>")
		)
		(zone
			(layer "F.Cu")
			(hatch none 0.5)
			(connect_pads
				(clearance 0)
			)
			(min_thickness 0.25)
			(keepout
				(tracks allowed)
				(vias not_allowed)
				(pads allowed)
				(copperpour not_allowed)
				(footprints allowed)
			)
			(placement
				(enabled no)
				(sheetname "")
			)
			(fill
				(thermal_gap 0.5)
				(thermal_bridge_width 0.5)
				(island_removal_mode 0)
			)
			(polygon
				(pts
					(xy 377.313444 -10.281158) (xy 377.821444 -10.281158) (xy 377.821444 -10.662158) (xy 377.313444 -10.662158)
				)
			)
		)
	)
	(footprint ""
		(layer "F.Cu")
		(at 408.813 -102.9335 180)
		(property "Reference" "R8C24"
			(at 0 0 180)
			(layer "F.SilkS")
			(hide yes)
			(effects
				(font
					(size 1.27 1.27)
				)
			)
		)
		(property "Value" ""
			(at 0 0 180)
			(layer "F.Fab")
			(effects
				(font
					(size 1.27 1.27)
				)
			)
		)
		(duplicate_pad_numbers_are_jumpers no)
		(fp_poly
			(pts
				(xy -0.2794 -0.1016) (xy 0.2794 -0.1016) (xy 0.2794 0.9906) (xy -0.2794 0.9906)
			)
			(stroke
				(width 0)
				(type default)
			)
			(fill no)
			(layer "F.CrtYd")
		)
		(fp_line
			(start 0.2794 0.9906)
			(end 0.2794 -0.1016)
			(stroke
				(width 0.1)
				(type default)
			)
			(layer "F.Fab")
		)
		(fp_line
			(start 0.2794 -0.1016)
			(end -0.2794 -0.1016)
			(stroke
				(width 0.1)
				(type default)
			)
			(layer "F.Fab")
		)
		(fp_line
			(start -0.2794 0.9906)
			(end 0.2794 0.9906)
			(stroke
				(width 0.1)
				(type default)
			)
			(layer "F.Fab")
		)
		(fp_line
			(start -0.2794 -0.1016)
			(end -0.2794 0.9906)
			(stroke
				(width 0.1)
				(type default)
			)
			(layer "F.Fab")
		)
		(pad "1" smd rect
			(at 0 0 180)
			(size 0.508 0.508)
			(layers "F.Cu" "F.Mask" "F.Paste")
			(net "FM_GBE_LOM_DISABLE_N")
		)
		(pad "2" smd rect
			(at 0 0.889 180)
			(size 0.508 0.508)
			(layers "F.Cu" "F.Mask" "F.Paste")
			(net "FM_1GB_LOM_DISABLE_N")
		)
		(zone
			(layer "F.Cu")
			(hatch none 0.5)
			(connect_pads
				(clearance 0)
			)
			(min_thickness 0.25)
			(keepout
				(tracks not_allowed)
				(vias allowed)
				(pads allowed)
				(copperpour not_allowed)
				(footprints allowed)
			)
			(placement
				(enabled no)
				(sheetname "")
			)
			(fill
				(thermal_gap 0.5)
				(thermal_bridge_width 0.5)
				(island_removal_mode 0)
			)
			(polygon
				(pts
					(xy 409.067 -103.5685) (xy 408.559 -103.5685) (xy 408.559 -103.1875) (xy 409.067 -103.1875)
				)
			)
		)
		(zone
			(layer "F.Cu")
			(hatch none 0.5)
			(connect_pads
				(clearance 0)
			)
			(min_thickness 0.25)
			(keepout
				(tracks allowed)
				(vias not_allowed)
				(pads allowed)
				(copperpour not_allowed)
				(footprints allowed)
			)
			(placement
				(enabled no)
				(sheetname "")
			)
			(fill
				(thermal_gap 0.5)
				(thermal_bridge_width 0.5)
				(island_removal_mode 0)
			)
			(polygon
				(pts
					(xy 409.067 -103.1875) (xy 408.559 -103.1875) (xy 408.559 -103.5685) (xy 409.067 -103.5685)
				)
			)
		)
	)
	(footprint ""
		(layer "F.Cu")
		(at 6.35 -127.127 90)
		(property "Reference" "R1B12"
			(at -0.8382 -0.67818 90)
			(unlocked yes)
			(layer "F.SilkS")
			(effects
				(font
					(size 0.4064 0.254)
					(thickness 0.1524)
				)
				(justify left)
			)
		)
		(property "Value" ""
			(at 0 0 90)
			(layer "F.Fab")
			(effects
				(font
					(size 1.27 1.27)
				)
			)
		)
		(duplicate_pad_numbers_are_jumpers no)
		(fp_poly
			(pts
				(xy -0.2794 -0.1016) (xy 0.2794 -0.1016) (xy 0.2794 0.9906) (xy -0.2794 0.9906)
			)
			(stroke
				(width 0)
				(type default)
			)
			(fill no)
			(layer "F.CrtYd")
		)
		(fp_line
			(start 0.2794 -0.1016)
			(end -0.2794 -0.1016)
			(stroke
				(width 0.1)
				(type default)
			)
			(layer "F.Fab")
		)
		(fp_line
			(start -0.2794 -0.1016)
			(end -0.2794 0.9906)
			(stroke
				(width 0.1)
				(type default)
			)
			(layer "F.Fab")
		)
		(fp_line
			(start 0.2794 0.9906)
			(end 0.2794 -0.1016)
			(stroke
				(width 0.1)
				(type default)
			)
			(layer "F.Fab")
		)
		(fp_line
			(start -0.2794 0.9906)
			(end 0.2794 0.9906)
			(stroke
				(width 0.1)
				(type default)
			)
			(layer "F.Fab")
		)
		(pad "1" smd rect
			(at 0 0 90)
			(size 0.508 0.508)
			(layers "F.Cu" "F.Mask" "F.Paste")
			(net "VR_PVDDQ_KLM_XADDR1")
		)
		(pad "2" smd rect
			(at 0 0.889 90)
			(size 0.508 0.508)
			(layers "F.Cu" "F.Mask" "F.Paste")
			(net "GND")
		)
		(zone
			(layer "F.Cu")
			(hatch none 0.5)
			(connect_pads
				(clearance 0)
			)
			(min_thickness 0.25)
			(keepout
				(tracks allowed)
				(vias not_allowed)
				(pads allowed)
				(copperpour not_allowed)
				(footprints allowed)
			)
			(placement
				(enabled no)
				(sheetname "")
			)
			(fill
				(thermal_gap 0.5)
				(thermal_bridge_width 0.5)
				(island_removal_mode 0)
			)
			(polygon
				(pts
					(xy 6.604 -126.873) (xy 6.604 -127.381) (xy 6.985 -127.381) (xy 6.985 -126.873)
				)
			)
		)
		(zone
			(layer "F.Cu")
			(hatch none 0.5)
			(connect_pads
				(clearance 0)
			)
			(min_thickness 0.25)
			(keepout
				(tracks not_allowed)
				(vias allowed)
				(pads allowed)
				(copperpour not_allowed)
				(footprints allowed)
			)
			(placement
				(enabled no)
				(sheetname "")
			)
			(fill
				(thermal_gap 0.5)
				(thermal_bridge_width 0.5)
				(island_removal_mode 0)
			)
			(polygon
				(pts
					(xy 6.985 -126.873) (xy 6.985 -127.381) (xy 6.604 -127.381) (xy 6.604 -126.873)
				)
			)
		)
	)
	(footprint ""
		(layer "F.Cu")
		(at 40.036496 -97.671382)
		(property "Reference" "L1C1"
			(at 3.378708 -4.251706 0)
			(unlocked yes)
			(layer "F.SilkS")
			(effects
				(font
					(size 0.4064 0.254)
					(thickness 0.1524)
				)
			)
		)
		(property "Value" ""
			(at 0 0 0)
			(layer "F.Fab")
			(effects
				(font
					(size 1.27 1.27)
				)
			)
		)
		(duplicate_pad_numbers_are_jumpers no)
		(fp_line
			(start -1.1303 -3.199892)
			(end 8.3693 -3.199892)
			(stroke
				(width 0.1524)
				(type default)
			)
			(layer "F.SilkS")
		)
		(fp_line
			(start -1.1303 -1.6637)
			(end -1.1303 -3.199892)
			(stroke
				(width 0.1524)
				(type default)
			)
			(layer "F.SilkS")
		)
		(fp_line
			(start -1.1303 3.199892)
			(end -1.1303 1.6637)
			(stroke
				(width 0.1524)
				(type default)
			)
			(layer "F.SilkS")
		)
		(fp_line
			(start 8.3693 -3.199892)
			(end 8.3693 -1.6637)
			(stroke
				(width 0.1524)
				(type default)
			)
			(layer "F.SilkS")
		)
		(fp_line
			(start 8.3693 1.6637)
			(end 8.3693 3.199892)
			(stroke
				(width 0.1524)
				(type default)
			)
			(layer "F.SilkS")
		)
		(fp_line
			(start 8.3693 3.199892)
			(end -1.1303 3.199892)
			(stroke
				(width 0.1524)
				(type default)
			)
			(layer "F.SilkS")
		)
		(fp_rect
			(start -1.1303 3.199892)
			(end 8.3693 -3.199892)
			(stroke
				(width 0)
				(type default)
			)
			(fill no)
			(layer "F.CrtYd")
		)
		(fp_line
			(start -1.1303 -3.199892)
			(end 8.3693 -3.199892)
			(stroke
				(width 0.1)
				(type default)
			)
			(layer "F.Fab")
		)
		(fp_line
			(start -1.1303 3.199892)
			(end -1.1303 -3.199892)
			(stroke
				(width 0.1)
				(type default)
			)
			(layer "F.Fab")
		)
		(fp_line
			(start 8.3693 -3.199892)
			(end 8.3693 3.199892)
			(stroke
				(width 0.1)
				(type default)
			)
			(layer "F.Fab")
		)
		(fp_line
			(start 8.3693 3.199892)
			(end -1.1303 3.199892)
			(stroke
				(width 0.1)
				(type default)
			)
			(layer "F.Fab")
		)
		(pad "1" smd rect
			(at 0 0)
			(size 3.683 2.667)
			(layers "F.Cu" "F.Mask" "F.Paste")
			(net "VR_PVSA_CPU1_PHASE_SW")
		)
		(pad "2" smd rect
			(at 7.239 0)
			(size 3.683 2.667)
			(layers "F.Cu" "F.Mask" "F.Paste")
			(net "PVSA_CPU1")
		)
	)
	(footprint ""
		(layer "F.Cu")
		(at 475.2213 -138.557 90)
		(property "Reference" "Q9A2"
			(at 2.83591 -1.4351 0)
			(unlocked yes)
			(layer "F.SilkS")
			(effects
				(font
					(size 0.7874 0.5842)
					(thickness 0.1524)
				)
				(justify left)
			)
		)
		(property "Value" ""
			(at 0 0 90)
			(layer "F.Fab")
			(effects
				(font
					(size 1.27 1.27)
				)
			)
		)
		(duplicate_pad_numbers_are_jumpers no)
		(fp_circle
			(center -0.508 -0.7874)
			(end -0.508 -0.6604)
			(stroke
				(width 0.254)
				(type default)
			)
			(fill no)
			(layer "F.SilkS")
		)
		(fp_poly
			(pts
				(xy 0.2159 1.7526) (xy 1.5621 1.7526) (xy 1.5621 -0.4572) (xy 0.2159 -0.4572)
			)
			(stroke
				(width 0)
				(type default)
			)
			(fill no)
			(layer "F.CrtYd")
		)
		(fp_line
			(start 1.5621 -0.45466)
			(end 0.2159 -0.45466)
			(stroke
				(width 0.1)
				(type default)
			)
			(layer "F.Fab")
		)
		(fp_line
			(start 0.2159 -0.45466)
			(end 0.2159 1.75514)
			(stroke
				(width 0.1)
				(type default)
			)
			(layer "F.Fab")
		)
		(fp_line
			(start 1.5621 1.75514)
			(end 1.5621 -0.45466)
			(stroke
				(width 0.1)
				(type default)
			)
			(layer "F.Fab")
		)
		(fp_line
			(start 0.2159 1.75514)
			(end 1.5621 1.75514)
			(stroke
				(width 0.1)
				(type default)
			)
			(layer "F.Fab")
		)
		(fp_circle
			(center -0.508 -0.7874)
			(end -0.508 -0.6604)
			(stroke
				(width 0.254)
				(type default)
			)
			(fill no)
			(layer "F.Fab")
		)
		(pad "1" smd rect
			(at 0 0 90)
			(size 1.016 0.381)
			(layers "F.Cu" "F.Mask" "F.Paste")
			(net "GND")
		)
		(pad "2" smd rect
			(at 0 0.65024 90)
			(size 1.016 0.381)
			(layers "F.Cu" "F.Mask" "F.Paste")
			(net "FM_PWR_LED_N")
		)
		(pad "3" smd rect
			(at 0 1.30048 90)
			(size 1.016 0.381)
			(layers "F.Cu" "F.Mask" "F.Paste")
			(net "FM_PWR_LED_K")
		)
		(pad "4" smd rect
			(at 1.778 1.30048 90)
			(size 1.016 0.381)
			(layers "F.Cu" "F.Mask" "F.Paste")
			(net "GND")
		)
		(pad "5" smd rect
			(at 1.778 0.65024 90)
			(size 1.016 0.381)
			(layers "F.Cu" "F.Mask" "F.Paste")
			(net "FM_PWR_LED")
		)
		(pad "6" smd rect
			(at 1.778 0 90)
			(size 1.016 0.381)
			(layers "F.Cu" "F.Mask" "F.Paste")
			(net "FM_PWR_LED")
		)
		(zone
			(layer "F.Cu")
			(hatch none 0.5)
			(connect_pads
				(clearance 0)
			)
			(min_thickness 0.25)
			(keepout
				(tracks allowed)
				(vias not_allowed)
				(pads allowed)
				(copperpour not_allowed)
				(footprints allowed)
			)
			(placement
				(enabled no)
				(sheetname "")
			)
			(fill
				(thermal_gap 0.5)
				(thermal_bridge_width 0.5)
				(island_removal_mode 0)
			)
			(polygon
				(pts
					(xy 475.0308 -139.827) (xy 475.0308 -140.843) (xy 476.7199 -140.843) (xy 476.7199 -139.827)
				)
			)
		)
		(zone
			(layer "F.Cu")
			(hatch none 0.5)
			(connect_pads
				(clearance 0)
			)
			(min_thickness 0.25)
			(keepout
				(tracks allowed)
				(vias not_allowed)
				(pads allowed)
				(copperpour not_allowed)
				(footprints allowed)
			)
			(placement
				(enabled no)
				(sheetname "")
			)
			(fill
				(thermal_gap 0.5)
				(thermal_bridge_width 0.5)
				(island_removal_mode 0)
			)
			(polygon
				(pts
					(xy 475.0308 -138.049) (xy 475.0308 -139.065) (xy 476.7199 -139.065) (xy 476.7199 -138.049)
				)
			)
		)
	)
	(footprint ""
		(layer "F.Cu")
		(at 94.447868 -140.100812 90)
		(property "Reference" "C2A16"
			(at 0 0 90)
			(layer "F.SilkS")
			(hide yes)
			(effects
				(font
					(size 1.27 1.27)
				)
			)
		)
		(property "Value" ""
			(at 0 0 90)
			(layer "F.Fab")
			(effects
				(font
					(size 1.27 1.27)
				)
			)
		)
		(duplicate_pad_numbers_are_jumpers no)
		(fp_poly
			(pts
				(xy -0.7239 -0.2159) (xy 0.7239 -0.2159) (xy 0.7239 1.9939) (xy -0.7239 1.9939)
			)
			(stroke
				(width 0)
				(type default)
			)
			(fill no)
			(layer "F.CrtYd")
		)
		(fp_line
			(start 0.7239 -0.2159)
			(end -0.7239 -0.2159)
			(stroke
				(width 0.1)
				(type default)
			)
			(layer "F.Fab")
		)
		(fp_line
			(start -0.7239 -0.2159)
			(end -0.7239 1.9939)
			(stroke
				(width 0.1)
				(type default)
			)
			(layer "F.Fab")
		)
		(fp_line
			(start 0.7239 1.9939)
			(end 0.7239 -0.2159)
			(stroke
				(width 0.1)
				(type default)
			)
			(layer "F.Fab")
		)
		(fp_line
			(start -0.7239 1.9939)
			(end 0.7239 1.9939)
			(stroke
				(width 0.1)
				(type default)
			)
			(layer "F.Fab")
		)
		(pad "1" smd rect
			(at 0 0 90)
			(size 1.27 1.016)
			(layers "F.Cu" "F.Mask" "F.Paste")
			(net "PVDDQ_KLM")
		)
		(pad "2" smd rect
			(at 0 1.778 90)
			(size 1.27 1.016)
			(layers "F.Cu" "F.Mask" "F.Paste")
			(net "GND")
		)
		(zone
			(layer "F.Cu")
			(hatch none 0.5)
			(connect_pads
				(clearance 0)
			)
			(min_thickness 0.25)
			(keepout
				(tracks not_allowed)
				(vias allowed)
				(pads allowed)
				(copperpour not_allowed)
				(footprints allowed)
			)
			(placement
				(enabled no)
				(sheetname "")
			)
			(fill
				(thermal_gap 0.5)
				(thermal_bridge_width 0.5)
				(island_removal_mode 0)
			)
			(polygon
				(pts
					(xy 94.955868 -139.465812) (xy 94.955868 -140.735812) (xy 95.717868 -140.735812) (xy 95.717868 -139.465812)
				)
			)
		)
	)
	(footprint ""
		(layer "F.Cu")
		(at 349.631 -133.223 180)
		(property "Reference" "C7B5"
			(at 0 0 180)
			(layer "F.SilkS")
			(hide yes)
			(effects
				(font
					(size 1.27 1.27)
				)
			)
		)
		(property "Value" ""
			(at 0 0 180)
			(layer "F.Fab")
			(effects
				(font
					(size 1.27 1.27)
				)
			)
		)
		(duplicate_pad_numbers_are_jumpers no)
		(fp_poly
			(pts
				(xy -0.7239 -0.2159) (xy 0.7239 -0.2159) (xy 0.7239 1.9939) (xy -0.7239 1.9939)
			)
			(stroke
				(width 0)
				(type default)
			)
			(fill no)
			(layer "F.CrtYd")
		)
		(fp_line
			(start 0.7239 1.9939)
			(end 0.7239 -0.2159)
			(stroke
				(width 0.1)
				(type default)
			)
			(layer "F.Fab")
		)
		(fp_line
			(start 0.7239 -0.2159)
			(end -0.7239 -0.2159)
			(stroke
				(width 0.1)
				(type default)
			)
			(layer "F.Fab")
		)
		(fp_line
			(start -0.7239 1.9939)
			(end 0.7239 1.9939)
			(stroke
				(width 0.1)
				(type default)
			)
			(layer "F.Fab")
		)
		(fp_line
			(start -0.7239 -0.2159)
			(end -0.7239 1.9939)
			(stroke
				(width 0.1)
				(type default)
			)
			(layer "F.Fab")
		)
		(pad "1" smd rect
			(at 0 0 180)
			(size 1.27 1.016)
			(layers "F.Cu" "F.Mask" "F.Paste")
			(net "VR_FET_SW_P12V_STBY_PVPP_DEF")
		)
		(pad "2" smd rect
			(at 0 1.778 180)
			(size 1.27 1.016)
			(layers "F.Cu" "F.Mask" "F.Paste")
			(net "GND")
		)
		(zone
			(layer "F.Cu")
			(hatch none 0.5)
			(connect_pads
				(clearance 0)
			)
			(min_thickness 0.25)
			(keepout
				(tracks not_allowed)
				(vias allowed)
				(pads allowed)
				(copperpour not_allowed)
				(footprints allowed)
			)
			(placement
				(enabled no)
				(sheetname "")
			)
			(fill
				(thermal_gap 0.5)
				(thermal_bridge_width 0.5)
				(island_removal_mode 0)
			)
			(polygon
				(pts
					(xy 350.266 -133.731) (xy 348.996 -133.731) (xy 348.996 -134.493) (xy 350.266 -134.493)
				)
			)
		)
	)
	(footprint ""
		(layer "F.Cu")
		(at 184.2516 -75.4253 180)
		(property "Reference" "C4D17"
			(at 0 0 180)
			(layer "F.SilkS")
			(hide yes)
			(effects
				(font
					(size 1.27 1.27)
				)
			)
		)
		(property "Value" ""
			(at 0 0 180)
			(layer "F.Fab")
			(effects
				(font
					(size 1.27 1.27)
				)
			)
		)
		(duplicate_pad_numbers_are_jumpers no)
		(fp_rect
			(start 0.3048 -0.1016)
			(end -0.3048 0.9906)
			(stroke
				(width 0)
				(type default)
			)
			(fill no)
			(layer "F.CrtYd")
		)
		(fp_line
			(start 0.3048 0.9906)
			(end 0.3048 -0.1016)
			(stroke
				(width 0.1)
				(type default)
			)
			(layer "F.Fab")
		)
		(fp_line
			(start 0.3048 -0.1016)
			(end -0.3048 -0.1016)
			(stroke
				(width 0.1)
				(type default)
			)
			(layer "F.Fab")
		)
		(fp_line
			(start -0.3048 0.9906)
			(end 0.3048 0.9906)
			(stroke
				(width 0.1)
				(type default)
			)
			(layer "F.Fab")
		)
		(fp_line
			(start -0.3048 -0.1016)
			(end -0.3048 0.9906)
			(stroke
				(width 0.1)
				(type default)
			)
			(layer "F.Fab")
		)
		(pad "1" smd rect
			(at 0 0 180)
			(size 0.508 0.508)
			(layers "F.Cu" "F.Mask" "F.Paste")
			(net "A_TSENSE_PVCCIN_CPU0")
		)
		(pad "2" smd rect
			(at 0 0.889 180)
			(size 0.508 0.508)
			(layers "F.Cu" "F.Mask" "F.Paste")
			(net "GND")
		)
		(zone
			(layer "F.Cu")
			(hatch none 0.5)
			(connect_pads
				(clearance 0)
			)
			(min_thickness 0.25)
			(keepout
				(tracks not_allowed)
				(vias allowed)
				(pads allowed)
				(copperpour not_allowed)
				(footprints allowed)
			)
			(placement
				(enabled no)
				(sheetname "")
			)
			(fill
				(thermal_gap 0.5)
				(thermal_bridge_width 0.5)
				(island_removal_mode 0)
			)
			(polygon
				(pts
					(xy 183.9976 -75.6793) (xy 184.5056 -75.6793) (xy 184.5056 -76.0603) (xy 183.9976 -76.0603)
				)
			)
		)
		(zone
			(layer "F.Cu")
			(hatch none 0.5)
			(connect_pads
				(clearance 0)
			)
			(min_thickness 0.25)
			(keepout
				(tracks allowed)
				(vias not_allowed)
				(pads allowed)
				(copperpour not_allowed)
				(footprints allowed)
			)
			(placement
				(enabled no)
				(sheetname "")
			)
			(fill
				(thermal_gap 0.5)
				(thermal_bridge_width 0.5)
				(island_removal_mode 0)
			)
			(polygon
				(pts
					(xy 183.9976 -75.6793) (xy 184.5056 -75.6793) (xy 184.5056 -76.0603) (xy 183.9976 -76.0603)
				)
			)
		)
	)
	(footprint ""
		(layer "F.Cu")
		(at 370.967 -99.695)
		(property "Reference" "R7W9"
			(at -0.8382 -0.67818 0)
			(unlocked yes)
			(layer "F.SilkS")
			(effects
				(font
					(size 0.4064 0.254)
					(thickness 0.1524)
				)
				(justify left)
			)
		)
		(property "Value" ""
			(at 0 0 0)
			(layer "F.Fab")
			(effects
				(font
					(size 1.27 1.27)
				)
			)
		)
		(duplicate_pad_numbers_are_jumpers no)
		(fp_poly
			(pts
				(xy -0.2794 -0.1016) (xy 0.2794 -0.1016) (xy 0.2794 0.9906) (xy -0.2794 0.9906)
			)
			(stroke
				(width 0)
				(type default)
			)
			(fill no)
			(layer "F.CrtYd")
		)
		(fp_line
			(start -0.2794 -0.1016)
			(end -0.2794 0.9906)
			(stroke
				(width 0.1)
				(type default)
			)
			(layer "F.Fab")
		)
		(fp_line
			(start -0.2794 0.9906)
			(end 0.2794 0.9906)
			(stroke
				(width 0.1)
				(type default)
			)
			(layer "F.Fab")
		)
		(fp_line
			(start 0.2794 -0.1016)
			(end -0.2794 -0.1016)
			(stroke
				(width 0.1)
				(type default)
			)
			(layer "F.Fab")
		)
		(fp_line
			(start 0.2794 0.9906)
			(end 0.2794 -0.1016)
			(stroke
				(width 0.1)
				(type default)
			)
			(layer "F.Fab")
		)
		(pad "1" smd rect
			(at 0 0)
			(size 0.508 0.508)
			(layers "F.Cu" "F.Mask" "F.Paste")
			(net "FM_CPU0_RC_ERROR_N")
		)
		(pad "2" smd rect
			(at 0 0.889)
			(size 0.508 0.508)
			(layers "F.Cu" "F.Mask" "F.Paste")
			(net "FM_CPU0_RC_ERROR_R_N")
		)
		(zone
			(layer "F.Cu")
			(hatch none 0.5)
			(connect_pads
				(clearance 0)
			)
			(min_thickness 0.25)
			(keepout
				(tracks allowed)
				(vias not_allowed)
				(pads allowed)
				(copperpour not_allowed)
				(footprints allowed)
			)
			(placement
				(enabled no)
				(sheetname "")
			)
			(fill
				(thermal_gap 0.5)
				(thermal_bridge_width 0.5)
				(island_removal_mode 0)
			)
			(polygon
				(pts
					(xy 370.713 -99.441) (xy 371.221 -99.441) (xy 371.221 -99.06) (xy 370.713 -99.06)
				)
			)
		)
		(zone
			(layer "F.Cu")
			(hatch none 0.5)
			(connect_pads
				(clearance 0)
			)
			(min_thickness 0.25)
			(keepout
				(tracks not_allowed)
				(vias allowed)
				(pads allowed)
				(copperpour not_allowed)
				(footprints allowed)
			)
			(placement
				(enabled no)
				(sheetname "")
			)
			(fill
				(thermal_gap 0.5)
				(thermal_bridge_width 0.5)
				(island_removal_mode 0)
			)
			(polygon
				(pts
					(xy 370.713 -99.06) (xy 371.221 -99.06) (xy 371.221 -99.441) (xy 370.713 -99.441)
				)
			)
		)
	)
	(footprint ""
		(layer "F.Cu")
		(at 22.225 -71.6788 90)
		(property "Reference" "C1D21"
			(at 0 0 90)
			(layer "F.SilkS")
			(hide yes)
			(effects
				(font
					(size 1.27 1.27)
				)
			)
		)
		(property "Value" ""
			(at 0 0 90)
			(layer "F.Fab")
			(effects
				(font
					(size 1.27 1.27)
				)
			)
		)
		(duplicate_pad_numbers_are_jumpers no)
		(fp_poly
			(pts
				(xy 0.3048 -0.1016) (xy 0.3048 0.9906) (xy -0.3048 0.9906) (xy -0.3048 -0.1016)
			)
			(stroke
				(width 0)
				(type default)
			)
			(fill no)
			(layer "F.CrtYd")
		)
		(fp_line
			(start 0.3048 -0.1016)
			(end -0.3048 -0.1016)
			(stroke
				(width 0.1)
				(type default)
			)
			(layer "F.Fab")
		)
		(fp_line
			(start -0.3048 -0.1016)
			(end -0.3048 0.9906)
			(stroke
				(width 0.1)
				(type default)
			)
			(layer "F.Fab")
		)
		(fp_line
			(start 0.3048 0.9906)
			(end 0.3048 -0.1016)
			(stroke
				(width 0.1)
				(type default)
			)
			(layer "F.Fab")
		)
		(fp_line
			(start -0.3048 0.9906)
			(end 0.3048 0.9906)
			(stroke
				(width 0.1)
				(type default)
			)
			(layer "F.Fab")
		)
		(pad "1" smd rect
			(at 0 0 90)
			(size 0.508 0.508)
			(layers "F.Cu" "F.Mask" "F.Paste")
			(net "A_HSC_PSET")
		)
		(pad "2" smd rect
			(at 0 0.889 90)
			(size 0.508 0.508)
			(layers "F.Cu" "F.Mask" "F.Paste")
			(net "AGND_HSC")
		)
		(zone
			(layer "F.Cu")
			(hatch none 0.5)
			(connect_pads
				(clearance 0)
			)
			(min_thickness 0.25)
			(keepout
				(tracks allowed)
				(vias not_allowed)
				(pads allowed)
				(copperpour not_allowed)
				(footprints allowed)
			)
			(placement
				(enabled no)
				(sheetname "")
			)
			(fill
				(thermal_gap 0.5)
				(thermal_bridge_width 0.5)
				(island_removal_mode 0)
			)
			(polygon
				(pts
					(xy 22.479 -71.4248) (xy 22.479 -71.9328) (xy 22.86 -71.9328) (xy 22.86 -71.4248)
				)
			)
		)
		(zone
			(layer "F.Cu")
			(hatch none 0.5)
			(connect_pads
				(clearance 0)
			)
			(min_thickness 0.25)
			(keepout
				(tracks not_allowed)
				(vias allowed)
				(pads allowed)
				(copperpour not_allowed)
				(footprints allowed)
			)
			(placement
				(enabled no)
				(sheetname "")
			)
			(fill
				(thermal_gap 0.5)
				(thermal_bridge_width 0.5)
				(island_removal_mode 0)
			)
			(polygon
				(pts
					(xy 22.86 -71.4248) (xy 22.86 -71.9328) (xy 22.479 -71.9328) (xy 22.479 -71.4248)
				)
			)
		)
	)
	(footprint ""
		(layer "F.Cu")
		(at 173.5836 -104.4448 180)
		(property "Reference" "C4C3"
			(at 0 0 180)
			(layer "F.SilkS")
			(hide yes)
			(effects
				(font
					(size 1.27 1.27)
				)
			)
		)
		(property "Value" ""
			(at 0 0 180)
			(layer "F.Fab")
			(effects
				(font
					(size 1.27 1.27)
				)
			)
		)
		(duplicate_pad_numbers_are_jumpers no)
		(fp_poly
			(pts
				(xy 0.3048 -0.1016) (xy 0.3048 0.9906) (xy -0.3048 0.9906) (xy -0.3048 -0.1016)
			)
			(stroke
				(width 0)
				(type default)
			)
			(fill no)
			(layer "F.CrtYd")
		)
		(fp_line
			(start 0.3048 0.9906)
			(end 0.3048 -0.1016)
			(stroke
				(width 0.1)
				(type default)
			)
			(layer "F.Fab")
		)
		(fp_line
			(start 0.3048 -0.1016)
			(end -0.3048 -0.1016)
			(stroke
				(width 0.1)
				(type default)
			)
			(layer "F.Fab")
		)
		(fp_line
			(start -0.3048 0.9906)
			(end 0.3048 0.9906)
			(stroke
				(width 0.1)
				(type default)
			)
			(layer "F.Fab")
		)
		(fp_line
			(start -0.3048 -0.1016)
			(end -0.3048 0.9906)
			(stroke
				(width 0.1)
				(type default)
			)
			(layer "F.Fab")
		)
		(pad "1" smd rect
			(at 0 0 180)
			(size 0.508 0.508)
			(layers "F.Cu" "F.Mask" "F.Paste")
			(net "P3V3_STBY")
		)
		(pad "2" smd rect
			(at 0 0.889 180)
			(size 0.508 0.508)
			(layers "F.Cu" "F.Mask" "F.Paste")
			(net "GND")
		)
		(zone
			(layer "F.Cu")
			(hatch none 0.5)
			(connect_pads
				(clearance 0)
			)
			(min_thickness 0.25)
			(keepout
				(tracks not_allowed)
				(vias allowed)
				(pads allowed)
				(copperpour not_allowed)
				(footprints allowed)
			)
			(placement
				(enabled no)
				(sheetname "")
			)
			(fill
				(thermal_gap 0.5)
				(thermal_bridge_width 0.5)
				(island_removal_mode 0)
			)
			(polygon
				(pts
					(xy 173.8376 -105.0798) (xy 173.3296 -105.0798) (xy 173.3296 -104.6988) (xy 173.8376 -104.6988)
				)
			)
		)
		(zone
			(layer "F.Cu")
			(hatch none 0.5)
			(connect_pads
				(clearance 0)
			)
			(min_thickness 0.25)
			(keepout
				(tracks allowed)
				(vias not_allowed)
				(pads allowed)
				(copperpour not_allowed)
				(footprints allowed)
			)
			(placement
				(enabled no)
				(sheetname "")
			)
			(fill
				(thermal_gap 0.5)
				(thermal_bridge_width 0.5)
				(island_removal_mode 0)
			)
			(polygon
				(pts
					(xy 173.8376 -104.6988) (xy 173.3296 -104.6988) (xy 173.3296 -105.0798) (xy 173.8376 -105.0798)
				)
			)
		)
	)
	(footprint ""
		(layer "F.Cu")
		(at 408.7495 -113.284 -90)
		(property "Reference" "R8B30"
			(at 0 0 270)
			(layer "F.SilkS")
			(hide yes)
			(effects
				(font
					(size 1.27 1.27)
				)
			)
		)
		(property "Value" ""
			(at 0 0 270)
			(layer "F.Fab")
			(effects
				(font
					(size 1.27 1.27)
				)
			)
		)
		(duplicate_pad_numbers_are_jumpers no)
		(fp_poly
			(pts
				(xy -0.2794 -0.1016) (xy 0.2794 -0.1016) (xy 0.2794 0.9906) (xy -0.2794 0.9906)
			)
			(stroke
				(width 0)
				(type default)
			)
			(fill no)
			(layer "F.CrtYd")
		)
		(fp_line
			(start -0.2794 0.9906)
			(end 0.2794 0.9906)
			(stroke
				(width 0.1)
				(type default)
			)
			(layer "F.Fab")
		)
		(fp_line
			(start 0.2794 0.9906)
			(end 0.2794 -0.1016)
			(stroke
				(width 0.1)
				(type default)
			)
			(layer "F.Fab")
		)
		(fp_line
			(start -0.2794 -0.1016)
			(end -0.2794 0.9906)
			(stroke
				(width 0.1)
				(type default)
			)
			(layer "F.Fab")
		)
		(fp_line
			(start 0.2794 -0.1016)
			(end -0.2794 -0.1016)
			(stroke
				(width 0.1)
				(type default)
			)
			(layer "F.Fab")
		)
		(pad "1" smd rect
			(at 0 0 270)
			(size 0.508 0.508)
			(layers "F.Cu" "F.Mask" "F.Paste")
			(net "P3V3_STBY")
		)
		(pad "2" smd rect
			(at 0 0.889 270)
			(size 0.508 0.508)
			(layers "F.Cu" "F.Mask" "F.Paste")
			(net "FM_XRC_READY_N")
		)
		(zone
			(layer "F.Cu")
			(hatch none 0.5)
			(connect_pads
				(clearance 0)
			)
			(min_thickness 0.25)
			(keepout
				(tracks not_allowed)
				(vias allowed)
				(pads allowed)
				(copperpour not_allowed)
				(footprints allowed)
			)
			(placement
				(enabled no)
				(sheetname "")
			)
			(fill
				(thermal_gap 0.5)
				(thermal_bridge_width 0.5)
				(island_removal_mode 0)
			)
			(polygon
				(pts
					(xy 408.1145 -113.538) (xy 408.1145 -113.03) (xy 408.4955 -113.03) (xy 408.4955 -113.538)
				)
			)
		)
		(zone
			(layer "F.Cu")
			(hatch none 0.5)
			(connect_pads
				(clearance 0)
			)
			(min_thickness 0.25)
			(keepout
				(tracks allowed)
				(vias not_allowed)
				(pads allowed)
				(copperpour not_allowed)
				(footprints allowed)
			)
			(placement
				(enabled no)
				(sheetname "")
			)
			(fill
				(thermal_gap 0.5)
				(thermal_bridge_width 0.5)
				(island_removal_mode 0)
			)
			(polygon
				(pts
					(xy 408.4955 -113.538) (xy 408.4955 -113.03) (xy 408.1145 -113.03) (xy 408.1145 -113.538)
				)
			)
		)
	)
	(footprint ""
		(layer "F.Cu")
		(at 486.687876 -27.227784)
		(property "Reference" "R9F68"
			(at 0 0 0)
			(layer "F.SilkS")
			(hide yes)
			(effects
				(font
					(size 1.27 1.27)
				)
			)
		)
		(property "Value" ""
			(at 0 0 0)
			(layer "F.Fab")
			(effects
				(font
					(size 1.27 1.27)
				)
			)
		)
		(duplicate_pad_numbers_are_jumpers no)
		(fp_poly
			(pts
				(xy -0.2794 -0.1016) (xy 0.2794 -0.1016) (xy 0.2794 0.9906) (xy -0.2794 0.9906)
			)
			(stroke
				(width 0)
				(type default)
			)
			(fill no)
			(layer "F.CrtYd")
		)
		(fp_line
			(start -0.2794 -0.1016)
			(end -0.2794 0.9906)
			(stroke
				(width 0.1)
				(type default)
			)
			(layer "F.Fab")
		)
		(fp_line
			(start -0.2794 0.9906)
			(end 0.2794 0.9906)
			(stroke
				(width 0.1)
				(type default)
			)
			(layer "F.Fab")
		)
		(fp_line
			(start 0.2794 -0.1016)
			(end -0.2794 -0.1016)
			(stroke
				(width 0.1)
				(type default)
			)
			(layer "F.Fab")
		)
		(fp_line
			(start 0.2794 0.9906)
			(end 0.2794 -0.1016)
			(stroke
				(width 0.1)
				(type default)
			)
			(layer "F.Fab")
		)
		(pad "1" smd rect
			(at 0 0)
			(size 0.508 0.508)
			(layers "F.Cu" "F.Mask" "F.Paste")
			(net "SP2_BMC_CM_UART_RX_R")
		)
		(pad "2" smd rect
			(at 0 0.889)
			(size 0.508 0.508)
			(layers "F.Cu" "F.Mask" "F.Paste")
			(net "SP2_BMC_CM_UART_RX")
		)
		(zone
			(layer "F.Cu")
			(hatch none 0.5)
			(connect_pads
				(clearance 0)
			)
			(min_thickness 0.25)
			(keepout
				(tracks allowed)
				(vias not_allowed)
				(pads allowed)
				(copperpour not_allowed)
				(footprints allowed)
			)
			(placement
				(enabled no)
				(sheetname "")
			)
			(fill
				(thermal_gap 0.5)
				(thermal_bridge_width 0.5)
				(island_removal_mode 0)
			)
			(polygon
				(pts
					(xy 486.433876 -26.973784) (xy 486.941876 -26.973784) (xy 486.941876 -26.592784) (xy 486.433876 -26.592784)
				)
			)
		)
		(zone
			(layer "F.Cu")
			(hatch none 0.5)
			(connect_pads
				(clearance 0)
			)
			(min_thickness 0.25)
			(keepout
				(tracks not_allowed)
				(vias allowed)
				(pads allowed)
				(copperpour not_allowed)
				(footprints allowed)
			)
			(placement
				(enabled no)
				(sheetname "")
			)
			(fill
				(thermal_gap 0.5)
				(thermal_bridge_width 0.5)
				(island_removal_mode 0)
			)
			(polygon
				(pts
					(xy 486.433876 -26.592784) (xy 486.941876 -26.592784) (xy 486.941876 -26.973784) (xy 486.433876 -26.973784)
				)
			)
		)
	)
	(footprint ""
		(layer "F.Cu")
		(at 198.065644 -77.513942 90)
		(property "Reference" "C4D5"
			(at -0.8382 -0.67818 90)
			(unlocked yes)
			(layer "F.SilkS")
			(effects
				(font
					(size 0.4064 0.254)
					(thickness 0.1524)
				)
				(justify left)
			)
		)
		(property "Value" ""
			(at 0 0 90)
			(layer "F.Fab")
			(effects
				(font
					(size 1.27 1.27)
				)
			)
		)
		(duplicate_pad_numbers_are_jumpers no)
		(fp_poly
			(pts
				(xy 0.3048 -0.1016) (xy 0.3048 0.9906) (xy -0.3048 0.9906) (xy -0.3048 -0.1016)
			)
			(stroke
				(width 0)
				(type default)
			)
			(fill no)
			(layer "F.CrtYd")
		)
		(fp_line
			(start 0.3048 -0.1016)
			(end -0.3048 -0.1016)
			(stroke
				(width 0.1)
				(type default)
			)
			(layer "F.Fab")
		)
		(fp_line
			(start -0.3048 -0.1016)
			(end -0.3048 0.9906)
			(stroke
				(width 0.1)
				(type default)
			)
			(layer "F.Fab")
		)
		(fp_line
			(start 0.3048 0.9906)
			(end 0.3048 -0.1016)
			(stroke
				(width 0.1)
				(type default)
			)
			(layer "F.Fab")
		)
		(fp_line
			(start -0.3048 0.9906)
			(end 0.3048 0.9906)
			(stroke
				(width 0.1)
				(type default)
			)
			(layer "F.Fab")
		)
		(pad "1" smd rect
			(at 0 0 90)
			(size 0.508 0.508)
			(layers "F.Cu" "F.Mask" "F.Paste")
			(net "P5V_STBY")
		)
		(pad "2" smd rect
			(at 0 0.889 90)
			(size 0.508 0.508)
			(layers "F.Cu" "F.Mask" "F.Paste")
			(net "GND")
		)
		(zone
			(layer "F.Cu")
			(hatch none 0.5)
			(connect_pads
				(clearance 0)
			)
			(min_thickness 0.25)
			(keepout
				(tracks allowed)
				(vias not_allowed)
				(pads allowed)
				(copperpour not_allowed)
				(footprints allowed)
			)
			(placement
				(enabled no)
				(sheetname "")
			)
			(fill
				(thermal_gap 0.5)
				(thermal_bridge_width 0.5)
				(island_removal_mode 0)
			)
			(polygon
				(pts
					(xy 198.319644 -77.259942) (xy 198.319644 -77.767942) (xy 198.700644 -77.767942) (xy 198.700644 -77.259942)
				)
			)
		)
		(zone
			(layer "F.Cu")
			(hatch none 0.5)
			(connect_pads
				(clearance 0)
			)
			(min_thickness 0.25)
			(keepout
				(tracks not_allowed)
				(vias allowed)
				(pads allowed)
				(copperpour not_allowed)
				(footprints allowed)
			)
			(placement
				(enabled no)
				(sheetname "")
			)
			(fill
				(thermal_gap 0.5)
				(thermal_bridge_width 0.5)
				(island_removal_mode 0)
			)
			(polygon
				(pts
					(xy 198.700644 -77.259942) (xy 198.700644 -77.767942) (xy 198.319644 -77.767942) (xy 198.319644 -77.259942)
				)
			)
		)
	)
	(footprint ""
		(layer "F.Cu")
		(at 166.497 -73.66 180)
		(property "Reference" "R4D40"
			(at 0 0 180)
			(layer "F.SilkS")
			(hide yes)
			(effects
				(font
					(size 1.27 1.27)
				)
			)
		)
		(property "Value" ""
			(at 0 0 180)
			(layer "F.Fab")
			(effects
				(font
					(size 1.27 1.27)
				)
			)
		)
		(duplicate_pad_numbers_are_jumpers no)
		(fp_poly
			(pts
				(xy -0.2794 -0.1016) (xy 0.2794 -0.1016) (xy 0.2794 0.9906) (xy -0.2794 0.9906)
			)
			(stroke
				(width 0)
				(type default)
			)
			(fill no)
			(layer "F.CrtYd")
		)
		(fp_line
			(start 0.2794 0.9906)
			(end 0.2794 -0.1016)
			(stroke
				(width 0.1)
				(type default)
			)
			(layer "F.Fab")
		)
		(fp_line
			(start 0.2794 -0.1016)
			(end -0.2794 -0.1016)
			(stroke
				(width 0.1)
				(type default)
			)
			(layer "F.Fab")
		)
		(fp_line
			(start -0.2794 0.9906)
			(end 0.2794 0.9906)
			(stroke
				(width 0.1)
				(type default)
			)
			(layer "F.Fab")
		)
		(fp_line
			(start -0.2794 -0.1016)
			(end -0.2794 0.9906)
			(stroke
				(width 0.1)
				(type default)
			)
			(layer "F.Fab")
		)
		(pad "1" smd rect
			(at 0 0 180)
			(size 0.508 0.508)
			(layers "F.Cu" "F.Mask" "F.Paste")
			(net "P3V3_DB1200")
		)
		(pad "2" smd rect
			(at 0 0.889 180)
			(size 0.508 0.508)
			(layers "F.Cu" "F.Mask" "F.Paste")
			(net "FM_100M_N")
		)
		(zone
			(layer "F.Cu")
			(hatch none 0.5)
			(connect_pads
				(clearance 0)
			)
			(min_thickness 0.25)
			(keepout
				(tracks not_allowed)
				(vias allowed)
				(pads allowed)
				(copperpour not_allowed)
				(footprints allowed)
			)
			(placement
				(enabled no)
				(sheetname "")
			)
			(fill
				(thermal_gap 0.5)
				(thermal_bridge_width 0.5)
				(island_removal_mode 0)
			)
			(polygon
				(pts
					(xy 166.751 -74.295) (xy 166.243 -74.295) (xy 166.243 -73.914) (xy 166.751 -73.914)
				)
			)
		)
		(zone
			(layer "F.Cu")
			(hatch none 0.5)
			(connect_pads
				(clearance 0)
			)
			(min_thickness 0.25)
			(keepout
				(tracks allowed)
				(vias not_allowed)
				(pads allowed)
				(copperpour not_allowed)
				(footprints allowed)
			)
			(placement
				(enabled no)
				(sheetname "")
			)
			(fill
				(thermal_gap 0.5)
				(thermal_bridge_width 0.5)
				(island_removal_mode 0)
			)
			(polygon
				(pts
					(xy 166.751 -73.914) (xy 166.243 -73.914) (xy 166.243 -74.295) (xy 166.751 -74.295)
				)
			)
		)
	)
	(footprint ""
		(layer "F.Cu")
		(at 365.76 -130.302)
		(property "Reference" ""
			(at 0 0 0)
			(layer "F.SilkS")
			(hide yes)
			(effects
				(font
					(size 1.27 1.27)
				)
			)
		)
		(property "Value" ""
			(at 0 0 0)
			(layer "F.Fab")
			(effects
				(font
					(size 1.27 1.27)
				)
			)
		)
		(duplicate_pad_numbers_are_jumpers no)
		(fp_poly
			(pts
				(arc
					(start 2.032 0)
					(mid -2.032 0)
					(end 2.032 0)
				)
			)
			(stroke
				(width 0)
				(type default)
			)
			(fill no)
			(layer "F.CrtYd")
		)
		(pad "1" smd circle
			(at 0 0)
			(size 1.016 1.016)
			(layers "F.Cu" "F.Mask" "F.Paste")
			(net "Net_132")
		)
		(zone
			(layer "F.Cu")
			(hatch none 0.5)
			(connect_pads
				(clearance 0)
			)
			(min_thickness 0.25)
			(keepout
				(tracks not_allowed)
				(vias allowed)
				(pads allowed)
				(copperpour not_allowed)
				(footprints allowed)
			)
			(placement
				(enabled no)
				(sheetname "")
			)
			(fill
				(thermal_gap 0.5)
				(thermal_bridge_width 0.5)
				(island_removal_mode 0)
			)
			(polygon
				(pts
					(arc
						(start 367.284 -130.302)
						(mid 364.236 -130.302)
						(end 367.284 -130.302)
					)
				)
			)
		)
		(zone
			(layers "F.Cu" "B.Cu" "In1.Cu" "In2.Cu" "In3.Cu" "In4.Cu" "In5.Cu" "In6.Cu"
				"In7.Cu" "In8.Cu" "In9.Cu" "In10.Cu" "In11.Cu" "In12.Cu"
			)
			(hatch none 0.5)
			(connect_pads
				(clearance 0)
			)
			(min_thickness 0.25)
			(keepout
				(tracks allowed)
				(vias not_allowed)
				(pads allowed)
				(copperpour not_allowed)
				(footprints allowed)
			)
			(placement
				(enabled no)
				(sheetname "")
			)
			(fill
				(thermal_gap 0.5)
				(thermal_bridge_width 0.5)
				(island_removal_mode 0)
			)
			(polygon
				(pts
					(arc
						(start 367.284 -130.302)
						(mid 364.236 -130.302)
						(end 367.284 -130.302)
					)
				)
			)
		)
	)
	(footprint ""
		(layer "F.Cu")
		(at 108.252768 -79.6036 180)
		(property "Reference" "C3D4"
			(at 0 0 180)
			(layer "F.SilkS")
			(hide yes)
			(effects
				(font
					(size 1.27 1.27)
				)
			)
		)
		(property "Value" ""
			(at 0 0 180)
			(layer "F.Fab")
			(effects
				(font
					(size 1.27 1.27)
				)
			)
		)
		(duplicate_pad_numbers_are_jumpers no)
		(fp_poly
			(pts
				(xy -0.4953 -0.2032) (xy 0.4953 -0.2032) (xy 0.4953 1.6002) (xy -0.4953 1.6002)
			)
			(stroke
				(width 0)
				(type default)
			)
			(fill no)
			(layer "F.CrtYd")
		)
		(fp_line
			(start 0.4953 1.6002)
			(end -0.4953 1.6002)
			(stroke
				(width 0.1)
				(type default)
			)
			(layer "F.Fab")
		)
		(fp_line
			(start 0.4953 -0.2032)
			(end 0.4953 1.6002)
			(stroke
				(width 0.1)
				(type default)
			)
			(layer "F.Fab")
		)
		(fp_line
			(start -0.4953 1.6002)
			(end -0.4953 -0.2032)
			(stroke
				(width 0.1)
				(type default)
			)
			(layer "F.Fab")
		)
		(fp_line
			(start -0.4953 -0.2032)
			(end 0.4953 -0.2032)
			(stroke
				(width 0.1)
				(type default)
			)
			(layer "F.Fab")
		)
		(pad "1" smd rect
			(at 0 0 180)
			(size 0.762 0.889)
			(layers "F.Cu" "F.Mask" "F.Paste")
			(net "PVCCMCP_CPU1")
		)
		(pad "2" smd rect
			(at 0 1.397 180)
			(size 0.762 0.889)
			(layers "F.Cu" "F.Mask" "F.Paste")
			(net "GND")
		)
		(zone
			(layer "F.Cu")
			(hatch none 0.5)
			(connect_pads
				(clearance 0)
			)
			(min_thickness 0.25)
			(keepout
				(tracks not_allowed)
				(vias allowed)
				(pads allowed)
				(copperpour not_allowed)
				(footprints allowed)
			)
			(placement
				(enabled no)
				(sheetname "")
			)
			(fill
				(thermal_gap 0.5)
				(thermal_bridge_width 0.5)
				(island_removal_mode 0)
			)
			(polygon
				(pts
					(xy 108.633768 -80.0481) (xy 107.871768 -80.0481) (xy 107.871768 -80.5561) (xy 108.633768 -80.5561)
				)
			)
		)
	)
	(footprint ""
		(layer "F.Cu")
		(at 465.582 -22.225 -90)
		(property "Reference" "C8F2"
			(at 0 0 270)
			(layer "F.SilkS")
			(hide yes)
			(effects
				(font
					(size 1.27 1.27)
				)
			)
		)
		(property "Value" ""
			(at 0 0 270)
			(layer "F.Fab")
			(effects
				(font
					(size 1.27 1.27)
				)
			)
		)
		(duplicate_pad_numbers_are_jumpers no)
		(fp_rect
			(start 0.3048 0.9906)
			(end -0.3048 -0.1016)
			(stroke
				(width 0)
				(type default)
			)
			(fill no)
			(layer "F.CrtYd")
		)
		(fp_line
			(start -0.3048 0.9906)
			(end 0.3048 0.9906)
			(stroke
				(width 0.1)
				(type default)
			)
			(layer "F.Fab")
		)
		(fp_line
			(start 0.3048 0.9906)
			(end 0.3048 -0.1016)
			(stroke
				(width 0.1)
				(type default)
			)
			(layer "F.Fab")
		)
		(fp_line
			(start -0.3048 -0.1016)
			(end -0.3048 0.9906)
			(stroke
				(width 0.1)
				(type default)
			)
			(layer "F.Fab")
		)
		(fp_line
			(start 0.3048 -0.1016)
			(end -0.3048 -0.1016)
			(stroke
				(width 0.1)
				(type default)
			)
			(layer "F.Fab")
		)
		(pad "1" smd rect
			(at 0 0 270)
			(size 0.508 0.508)
			(layers "F.Cu" "F.Mask" "F.Paste")
			(net "PWRGD_P3V3_STBY_R")
		)
		(pad "2" smd rect
			(at 0 0.889 270)
			(size 0.508 0.508)
			(layers "F.Cu" "F.Mask" "F.Paste")
			(net "GND")
		)
		(zone
			(layer "F.Cu")
			(hatch none 0.5)
			(connect_pads
				(clearance 0)
			)
			(min_thickness 0.25)
			(keepout
				(tracks allowed)
				(vias not_allowed)
				(pads allowed)
				(copperpour not_allowed)
				(footprints allowed)
			)
			(placement
				(enabled no)
				(sheetname "")
			)
			(fill
				(thermal_gap 0.5)
				(thermal_bridge_width 0.5)
				(island_removal_mode 0)
			)
			(polygon
				(pts
					(xy 464.947 -21.971) (xy 465.328 -21.971) (xy 465.328 -22.479) (xy 464.947 -22.479)
				)
			)
		)
		(zone
			(layer "F.Cu")
			(hatch none 0.5)
			(connect_pads
				(clearance 0)
			)
			(min_thickness 0.25)
			(keepout
				(tracks not_allowed)
				(vias allowed)
				(pads allowed)
				(copperpour not_allowed)
				(footprints allowed)
			)
			(placement
				(enabled no)
				(sheetname "")
			)
			(fill
				(thermal_gap 0.5)
				(thermal_bridge_width 0.5)
				(island_removal_mode 0)
			)
			(polygon
				(pts
					(xy 464.947 -21.971) (xy 465.328 -21.971) (xy 465.328 -22.479) (xy 464.947 -22.479)
				)
			)
		)
	)
	(footprint ""
		(layer "F.Cu")
		(at 317.7286 -31.8516 90)
		(property "Reference" "C6F1"
			(at 0 0 90)
			(layer "F.SilkS")
			(hide yes)
			(effects
				(font
					(size 1.27 1.27)
				)
			)
		)
		(property "Value" ""
			(at 0 0 90)
			(layer "F.Fab")
			(effects
				(font
					(size 1.27 1.27)
				)
			)
		)
		(duplicate_pad_numbers_are_jumpers no)
		(fp_poly
			(pts
				(xy 0.3048 -0.1016) (xy 0.3048 0.9906) (xy -0.3048 0.9906) (xy -0.3048 -0.1016)
			)
			(stroke
				(width 0)
				(type default)
			)
			(fill no)
			(layer "F.CrtYd")
		)
		(fp_line
			(start 0.3048 -0.1016)
			(end -0.3048 -0.1016)
			(stroke
				(width 0.1)
				(type default)
			)
			(layer "F.Fab")
		)
		(fp_line
			(start -0.3048 -0.1016)
			(end -0.3048 0.9906)
			(stroke
				(width 0.1)
				(type default)
			)
			(layer "F.Fab")
		)
		(fp_line
			(start 0.3048 0.9906)
			(end 0.3048 -0.1016)
			(stroke
				(width 0.1)
				(type default)
			)
			(layer "F.Fab")
		)
		(fp_line
			(start -0.3048 0.9906)
			(end 0.3048 0.9906)
			(stroke
				(width 0.1)
				(type default)
			)
			(layer "F.Fab")
		)
		(pad "1" smd rect
			(at 0 0 90)
			(size 0.508 0.508)
			(layers "F.Cu" "F.Mask" "F.Paste")
			(net "P3V3")
		)
		(pad "2" smd rect
			(at 0 0.889 90)
			(size 0.508 0.508)
			(layers "F.Cu" "F.Mask" "F.Paste")
			(net "GND")
		)
		(zone
			(layer "F.Cu")
			(hatch none 0.5)
			(connect_pads
				(clearance 0)
			)
			(min_thickness 0.25)
			(keepout
				(tracks allowed)
				(vias not_allowed)
				(pads allowed)
				(copperpour not_allowed)
				(footprints allowed)
			)
			(placement
				(enabled no)
				(sheetname "")
			)
			(fill
				(thermal_gap 0.5)
				(thermal_bridge_width 0.5)
				(island_removal_mode 0)
			)
			(polygon
				(pts
					(xy 317.9826 -31.5976) (xy 317.9826 -32.1056) (xy 318.3636 -32.1056) (xy 318.3636 -31.5976)
				)
			)
		)
		(zone
			(layer "F.Cu")
			(hatch none 0.5)
			(connect_pads
				(clearance 0)
			)
			(min_thickness 0.25)
			(keepout
				(tracks not_allowed)
				(vias allowed)
				(pads allowed)
				(copperpour not_allowed)
				(footprints allowed)
			)
			(placement
				(enabled no)
				(sheetname "")
			)
			(fill
				(thermal_gap 0.5)
				(thermal_bridge_width 0.5)
				(island_removal_mode 0)
			)
			(polygon
				(pts
					(xy 318.3636 -31.5976) (xy 318.3636 -32.1056) (xy 317.9826 -32.1056) (xy 317.9826 -31.5976)
				)
			)
		)
	)
	(footprint ""
		(layer "F.Cu")
		(at 389.0645 -79.8322 -90)
		(property "Reference" "R7D32"
			(at 0 0 270)
			(layer "F.SilkS")
			(hide yes)
			(effects
				(font
					(size 1.27 1.27)
				)
			)
		)
		(property "Value" ""
			(at 0 0 270)
			(layer "F.Fab")
			(effects
				(font
					(size 1.27 1.27)
				)
			)
		)
		(duplicate_pad_numbers_are_jumpers no)
		(fp_poly
			(pts
				(xy -0.2794 -0.1016) (xy 0.2794 -0.1016) (xy 0.2794 0.9906) (xy -0.2794 0.9906)
			)
			(stroke
				(width 0)
				(type default)
			)
			(fill no)
			(layer "F.CrtYd")
		)
		(fp_line
			(start -0.2794 0.9906)
			(end 0.2794 0.9906)
			(stroke
				(width 0.1)
				(type default)
			)
			(layer "F.Fab")
		)
		(fp_line
			(start 0.2794 0.9906)
			(end 0.2794 -0.1016)
			(stroke
				(width 0.1)
				(type default)
			)
			(layer "F.Fab")
		)
		(fp_line
			(start -0.2794 -0.1016)
			(end -0.2794 0.9906)
			(stroke
				(width 0.1)
				(type default)
			)
			(layer "F.Fab")
		)
		(fp_line
			(start 0.2794 -0.1016)
			(end -0.2794 -0.1016)
			(stroke
				(width 0.1)
				(type default)
			)
			(layer "F.Fab")
		)
		(pad "1" smd rect
			(at 0 0 270)
			(size 0.508 0.508)
			(layers "F.Cu" "F.Mask" "F.Paste")
			(net "P0V7_GTL2104_VREF_0")
		)
		(pad "2" smd rect
			(at 0 0.889 270)
			(size 0.508 0.508)
			(layers "F.Cu" "F.Mask" "F.Paste")
			(net "GND")
		)
		(zone
			(layer "F.Cu")
			(hatch none 0.5)
			(connect_pads
				(clearance 0)
			)
			(min_thickness 0.25)
			(keepout
				(tracks not_allowed)
				(vias allowed)
				(pads allowed)
				(copperpour not_allowed)
				(footprints allowed)
			)
			(placement
				(enabled no)
				(sheetname "")
			)
			(fill
				(thermal_gap 0.5)
				(thermal_bridge_width 0.5)
				(island_removal_mode 0)
			)
			(polygon
				(pts
					(xy 388.4295 -80.0862) (xy 388.4295 -79.5782) (xy 388.8105 -79.5782) (xy 388.8105 -80.0862)
				)
			)
		)
		(zone
			(layer "F.Cu")
			(hatch none 0.5)
			(connect_pads
				(clearance 0)
			)
			(min_thickness 0.25)
			(keepout
				(tracks allowed)
				(vias not_allowed)
				(pads allowed)
				(copperpour not_allowed)
				(footprints allowed)
			)
			(placement
				(enabled no)
				(sheetname "")
			)
			(fill
				(thermal_gap 0.5)
				(thermal_bridge_width 0.5)
				(island_removal_mode 0)
			)
			(polygon
				(pts
					(xy 388.8105 -80.0862) (xy 388.8105 -79.5782) (xy 388.4295 -79.5782) (xy 388.4295 -80.0862)
				)
			)
		)
	)
	(footprint ""
		(layer "F.Cu")
		(at 447.301366 -28.33116 90)
		(property "Reference" "C25W6"
			(at -0.8382 -0.67818 90)
			(unlocked yes)
			(layer "F.SilkS")
			(effects
				(font
					(size 0.4064 0.254)
					(thickness 0.1524)
				)
				(justify left)
			)
		)
		(property "Value" ""
			(at 0 0 90)
			(layer "F.Fab")
			(effects
				(font
					(size 1.27 1.27)
				)
			)
		)
		(duplicate_pad_numbers_are_jumpers no)
		(fp_poly
			(pts
				(xy 0.3048 -0.1016) (xy 0.3048 0.9906) (xy -0.3048 0.9906) (xy -0.3048 -0.1016)
			)
			(stroke
				(width 0)
				(type default)
			)
			(fill no)
			(layer "F.CrtYd")
		)
		(fp_line
			(start 0.3048 -0.1016)
			(end -0.3048 -0.1016)
			(stroke
				(width 0.1)
				(type default)
			)
			(layer "F.Fab")
		)
		(fp_line
			(start -0.3048 -0.1016)
			(end -0.3048 0.9906)
			(stroke
				(width 0.1)
				(type default)
			)
			(layer "F.Fab")
		)
		(fp_line
			(start 0.3048 0.9906)
			(end 0.3048 -0.1016)
			(stroke
				(width 0.1)
				(type default)
			)
			(layer "F.Fab")
		)
		(fp_line
			(start -0.3048 0.9906)
			(end 0.3048 0.9906)
			(stroke
				(width 0.1)
				(type default)
			)
			(layer "F.Fab")
		)
		(pad "1" smd rect
			(at 0 0 90)
			(size 0.508 0.508)
			(layers "F.Cu" "F.Mask" "F.Paste")
			(net "P1V2_AUX_BMC")
		)
		(pad "2" smd rect
			(at 0 0.889 90)
			(size 0.508 0.508)
			(layers "F.Cu" "F.Mask" "F.Paste")
			(net "GND")
		)
		(zone
			(layer "F.Cu")
			(hatch none 0.5)
			(connect_pads
				(clearance 0)
			)
			(min_thickness 0.25)
			(keepout
				(tracks allowed)
				(vias not_allowed)
				(pads allowed)
				(copperpour not_allowed)
				(footprints allowed)
			)
			(placement
				(enabled no)
				(sheetname "")
			)
			(fill
				(thermal_gap 0.5)
				(thermal_bridge_width 0.5)
				(island_removal_mode 0)
			)
			(polygon
				(pts
					(xy 447.555366 -28.07716) (xy 447.555366 -28.58516) (xy 447.936366 -28.58516) (xy 447.936366 -28.07716)
				)
			)
		)
		(zone
			(layer "F.Cu")
			(hatch none 0.5)
			(connect_pads
				(clearance 0)
			)
			(min_thickness 0.25)
			(keepout
				(tracks not_allowed)
				(vias allowed)
				(pads allowed)
				(copperpour not_allowed)
				(footprints allowed)
			)
			(placement
				(enabled no)
				(sheetname "")
			)
			(fill
				(thermal_gap 0.5)
				(thermal_bridge_width 0.5)
				(island_removal_mode 0)
			)
			(polygon
				(pts
					(xy 447.936366 -28.07716) (xy 447.936366 -28.58516) (xy 447.555366 -28.58516) (xy 447.555366 -28.07716)
				)
			)
		)
	)
	(footprint ""
		(layer "F.Cu")
		(at 93.139768 -140.208 -90)
		(property "Reference" "C2A13"
			(at 1.848866 0.752348 270)
			(unlocked yes)
			(layer "F.SilkS")
			(effects
				(font
					(size 1.27 0.9652)
					(thickness 0.1524)
				)
			)
		)
		(property "Value" ""
			(at 0 0 270)
			(layer "F.Fab")
			(effects
				(font
					(size 1.27 1.27)
				)
			)
		)
		(duplicate_pad_numbers_are_jumpers no)
		(fp_rect
			(start -0.500126 1.598422)
			(end 0.500126 -0.201422)
			(stroke
				(width 0)
				(type default)
			)
			(fill no)
			(layer "F.CrtYd")
		)
		(fp_line
			(start -0.500126 1.598422)
			(end -0.500126 -0.201422)
			(stroke
				(width 0.1)
				(type default)
			)
			(layer "F.Fab")
		)
		(fp_line
			(start 0.500126 1.598422)
			(end -0.500126 1.598422)
			(stroke
				(width 0.1)
				(type default)
			)
			(layer "F.Fab")
		)
		(fp_line
			(start -0.500126 -0.201422)
			(end 0.500126 -0.201422)
			(stroke
				(width 0.1)
				(type default)
			)
			(layer "F.Fab")
		)
		(fp_line
			(start 0.500126 -0.201422)
			(end 0.500126 1.598422)
			(stroke
				(width 0.1)
				(type default)
			)
			(layer "F.Fab")
		)
		(pad "1" smd rect
			(at 0 0 180)
			(size 0.889 0.9906)
			(layers "F.Cu" "F.Mask" "F.Paste")
			(net "PVDDQ_KLM")
		)
		(pad "2" smd rect
			(at 0 1.397 180)
			(size 0.889 0.9906)
			(layers "F.Cu" "F.Mask" "F.Paste")
			(net "GND")
		)
		(zone
			(layer "F.Cu")
			(hatch none 0.5)
			(connect_pads
				(clearance 0)
			)
			(min_thickness 0.25)
			(keepout
				(tracks allowed)
				(vias not_allowed)
				(pads allowed)
				(copperpour not_allowed)
				(footprints allowed)
			)
			(placement
				(enabled no)
				(sheetname "")
			)
			(fill
				(thermal_gap 0.5)
				(thermal_bridge_width 0.5)
				(island_removal_mode 0)
			)
			(polygon
				(pts
					(xy 92.187268 -140.7033) (xy 92.187268 -139.7127) (xy 92.695268 -139.7127) (xy 92.695268 -140.7033)
				)
			)
		)
		(zone
			(layer "F.Cu")
			(hatch none 0.5)
			(connect_pads
				(clearance 0)
			)
			(min_thickness 0.25)
			(keepout
				(tracks not_allowed)
				(vias allowed)
				(pads allowed)
				(copperpour not_allowed)
				(footprints allowed)
			)
			(placement
				(enabled no)
				(sheetname "")
			)
			(fill
				(thermal_gap 0.5)
				(thermal_bridge_width 0.5)
				(island_removal_mode 0)
			)
			(polygon
				(pts
					(xy 92.187268 -140.7033) (xy 92.187268 -139.7127) (xy 92.695268 -139.7127) (xy 92.695268 -140.7033)
				)
			)
		)
	)
	(footprint ""
		(layer "F.Cu")
		(at 415.749994 -47.828962 180)
		(property "Reference" "R25W65"
			(at -0.8382 -0.67818 180)
			(unlocked yes)
			(layer "F.SilkS")
			(effects
				(font
					(size 0.4064 0.254)
					(thickness 0.1524)
				)
				(justify left)
			)
		)
		(property "Value" ""
			(at 0 0 180)
			(layer "F.Fab")
			(effects
				(font
					(size 1.27 1.27)
				)
			)
		)
		(duplicate_pad_numbers_are_jumpers no)
		(fp_poly
			(pts
				(xy -0.2794 -0.1016) (xy 0.2794 -0.1016) (xy 0.2794 0.9906) (xy -0.2794 0.9906)
			)
			(stroke
				(width 0)
				(type default)
			)
			(fill no)
			(layer "F.CrtYd")
		)
		(fp_line
			(start 0.2794 0.9906)
			(end 0.2794 -0.1016)
			(stroke
				(width 0.1)
				(type default)
			)
			(layer "F.Fab")
		)
		(fp_line
			(start 0.2794 -0.1016)
			(end -0.2794 -0.1016)
			(stroke
				(width 0.1)
				(type default)
			)
			(layer "F.Fab")
		)
		(fp_line
			(start -0.2794 0.9906)
			(end 0.2794 0.9906)
			(stroke
				(width 0.1)
				(type default)
			)
			(layer "F.Fab")
		)
		(fp_line
			(start -0.2794 -0.1016)
			(end -0.2794 0.9906)
			(stroke
				(width 0.1)
				(type default)
			)
			(layer "F.Fab")
		)
		(pad "1" smd rect
			(at 0 0 180)
			(size 0.508 0.508)
			(layers "F.Cu" "F.Mask" "F.Paste")
			(net "P2E_SSB_BMC_TX_C_DN")
		)
		(pad "2" smd rect
			(at 0 0.889 180)
			(size 0.508 0.508)
			(layers "F.Cu" "F.Mask" "F.Paste")
			(net "GND")
		)
		(zone
			(layer "F.Cu")
			(hatch none 0.5)
			(connect_pads
				(clearance 0)
			)
			(min_thickness 0.25)
			(keepout
				(tracks not_allowed)
				(vias allowed)
				(pads allowed)
				(copperpour not_allowed)
				(footprints allowed)
			)
			(placement
				(enabled no)
				(sheetname "")
			)
			(fill
				(thermal_gap 0.5)
				(thermal_bridge_width 0.5)
				(island_removal_mode 0)
			)
			(polygon
				(pts
					(xy 416.003994 -48.463962) (xy 415.495994 -48.463962) (xy 415.495994 -48.082962) (xy 416.003994 -48.082962)
				)
			)
		)
		(zone
			(layer "F.Cu")
			(hatch none 0.5)
			(connect_pads
				(clearance 0)
			)
			(min_thickness 0.25)
			(keepout
				(tracks allowed)
				(vias not_allowed)
				(pads allowed)
				(copperpour not_allowed)
				(footprints allowed)
			)
			(placement
				(enabled no)
				(sheetname "")
			)
			(fill
				(thermal_gap 0.5)
				(thermal_bridge_width 0.5)
				(island_removal_mode 0)
			)
			(polygon
				(pts
					(xy 416.003994 -48.082962) (xy 415.495994 -48.082962) (xy 415.495994 -48.463962) (xy 416.003994 -48.463962)
				)
			)
		)
	)
	(footprint ""
		(layer "F.Cu")
		(at 455.217784 -1.539494 90)
		(property "Reference" "RN8F1"
			(at -0.8382 -0.67818 90)
			(unlocked yes)
			(layer "F.SilkS")
			(effects
				(font
					(size 0.4064 0.254)
					(thickness 0.1524)
				)
				(justify left)
			)
		)
		(property "Value" ""
			(at 0 0 90)
			(layer "F.Fab")
			(effects
				(font
					(size 1.27 1.27)
				)
			)
		)
		(duplicate_pad_numbers_are_jumpers no)
		(fp_poly
			(pts
				(xy -0.2794 -0.1016) (xy 0.2794 -0.1016) (xy 0.2794 0.9906) (xy -0.2794 0.9906)
			)
			(stroke
				(width 0)
				(type default)
			)
			(fill no)
			(layer "F.CrtYd")
		)
		(fp_line
			(start 0.2794 -0.1016)
			(end -0.2794 -0.1016)
			(stroke
				(width 0.1)
				(type default)
			)
			(layer "F.Fab")
		)
		(fp_line
			(start -0.2794 -0.1016)
			(end -0.2794 0.9906)
			(stroke
				(width 0.1)
				(type default)
			)
			(layer "F.Fab")
		)
		(fp_line
			(start 0.2794 0.9906)
			(end 0.2794 -0.1016)
			(stroke
				(width 0.1)
				(type default)
			)
			(layer "F.Fab")
		)
		(fp_line
			(start -0.2794 0.9906)
			(end 0.2794 0.9906)
			(stroke
				(width 0.1)
				(type default)
			)
			(layer "F.Fab")
		)
		(pad "1" smd rect
			(at 0 0 90)
			(size 0.508 0.508)
			(layers "F.Cu" "F.Mask" "F.Paste")
			(net "P3V3_STBY")
		)
		(pad "2" smd rect
			(at 0 0.889 90)
			(size 0.508 0.508)
			(layers "F.Cu" "F.Mask" "F.Paste")
			(net "PU_SPI_BMC_BT_CS0_N")
		)
		(zone
			(layer "F.Cu")
			(hatch none 0.5)
			(connect_pads
				(clearance 0)
			)
			(min_thickness 0.25)
			(keepout
				(tracks allowed)
				(vias not_allowed)
				(pads allowed)
				(copperpour not_allowed)
				(footprints allowed)
			)
			(placement
				(enabled no)
				(sheetname "")
			)
			(fill
				(thermal_gap 0.5)
				(thermal_bridge_width 0.5)
				(island_removal_mode 0)
			)
			(polygon
				(pts
					(xy 455.471784 -1.285494) (xy 455.471784 -1.793494) (xy 455.852784 -1.793494) (xy 455.852784 -1.285494)
				)
			)
		)
		(zone
			(layer "F.Cu")
			(hatch none 0.5)
			(connect_pads
				(clearance 0)
			)
			(min_thickness 0.25)
			(keepout
				(tracks not_allowed)
				(vias allowed)
				(pads allowed)
				(copperpour not_allowed)
				(footprints allowed)
			)
			(placement
				(enabled no)
				(sheetname "")
			)
			(fill
				(thermal_gap 0.5)
				(thermal_bridge_width 0.5)
				(island_removal_mode 0)
			)
			(polygon
				(pts
					(xy 455.852784 -1.285494) (xy 455.852784 -1.793494) (xy 455.471784 -1.793494) (xy 455.471784 -1.285494)
				)
			)
		)
	)
	(footprint ""
		(layer "F.Cu")
		(at 263.1948 -79.6036 180)
		(property "Reference" "C5D15"
			(at 0 0 180)
			(layer "F.SilkS")
			(hide yes)
			(effects
				(font
					(size 1.27 1.27)
				)
			)
		)
		(property "Value" ""
			(at 0 0 180)
			(layer "F.Fab")
			(effects
				(font
					(size 1.27 1.27)
				)
			)
		)
		(duplicate_pad_numbers_are_jumpers no)
		(fp_poly
			(pts
				(xy -0.4953 -0.2032) (xy 0.4953 -0.2032) (xy 0.4953 1.6002) (xy -0.4953 1.6002)
			)
			(stroke
				(width 0)
				(type default)
			)
			(fill no)
			(layer "F.CrtYd")
		)
		(fp_line
			(start 0.4953 1.6002)
			(end -0.4953 1.6002)
			(stroke
				(width 0.1)
				(type default)
			)
			(layer "F.Fab")
		)
		(fp_line
			(start 0.4953 -0.2032)
			(end 0.4953 1.6002)
			(stroke
				(width 0.1)
				(type default)
			)
			(layer "F.Fab")
		)
		(fp_line
			(start -0.4953 1.6002)
			(end -0.4953 -0.2032)
			(stroke
				(width 0.1)
				(type default)
			)
			(layer "F.Fab")
		)
		(fp_line
			(start -0.4953 -0.2032)
			(end 0.4953 -0.2032)
			(stroke
				(width 0.1)
				(type default)
			)
			(layer "F.Fab")
		)
		(pad "1" smd rect
			(at 0 0 180)
			(size 0.762 0.889)
			(layers "F.Cu" "F.Mask" "F.Paste")
			(net "PVCCIN_CPU0")
		)
		(pad "2" smd rect
			(at 0 1.397 180)
			(size 0.762 0.889)
			(layers "F.Cu" "F.Mask" "F.Paste")
			(net "GND")
		)
		(zone
			(layer "F.Cu")
			(hatch none 0.5)
			(connect_pads
				(clearance 0)
			)
			(min_thickness 0.25)
			(keepout
				(tracks not_allowed)
				(vias allowed)
				(pads allowed)
				(copperpour not_allowed)
				(footprints allowed)
			)
			(placement
				(enabled no)
				(sheetname "")
			)
			(fill
				(thermal_gap 0.5)
				(thermal_bridge_width 0.5)
				(island_removal_mode 0)
			)
			(polygon
				(pts
					(xy 263.5758 -80.0481) (xy 262.8138 -80.0481) (xy 262.8138 -80.5561) (xy 263.5758 -80.5561)
				)
			)
		)
	)
	(footprint ""
		(layer "F.Cu")
		(at 390.906 -151.236426)
		(property "Reference" "C8A7"
			(at 0 0 0)
			(layer "F.SilkS")
			(hide yes)
			(effects
				(font
					(size 1.27 1.27)
				)
			)
		)
		(property "Value" ""
			(at 0 0 0)
			(layer "F.Fab")
			(effects
				(font
					(size 1.27 1.27)
				)
			)
		)
		(duplicate_pad_numbers_are_jumpers no)
		(fp_poly
			(pts
				(xy 0.3048 -0.1016) (xy 0.3048 0.9906) (xy -0.3048 0.9906) (xy -0.3048 -0.1016)
			)
			(stroke
				(width 0)
				(type default)
			)
			(fill no)
			(layer "F.CrtYd")
		)
		(fp_line
			(start -0.3048 -0.1016)
			(end -0.3048 0.9906)
			(stroke
				(width 0.1)
				(type default)
			)
			(layer "F.Fab")
		)
		(fp_line
			(start -0.3048 0.9906)
			(end 0.3048 0.9906)
			(stroke
				(width 0.1)
				(type default)
			)
			(layer "F.Fab")
		)
		(fp_line
			(start 0.3048 -0.1016)
			(end -0.3048 -0.1016)
			(stroke
				(width 0.1)
				(type default)
			)
			(layer "F.Fab")
		)
		(fp_line
			(start 0.3048 0.9906)
			(end 0.3048 -0.1016)
			(stroke
				(width 0.1)
				(type default)
			)
			(layer "F.Fab")
		)
		(pad "1" smd rect
			(at 0 0)
			(size 0.508 0.508)
			(layers "F.Cu" "F.Mask" "F.Paste")
			(net "VR_PVNN_P1V05_PCH_VD12")
		)
		(pad "2" smd rect
			(at 0 0.889)
			(size 0.508 0.508)
			(layers "F.Cu" "F.Mask" "F.Paste")
			(net "GND")
		)
		(zone
			(layer "F.Cu")
			(hatch none 0.5)
			(connect_pads
				(clearance 0)
			)
			(min_thickness 0.25)
			(keepout
				(tracks allowed)
				(vias not_allowed)
				(pads allowed)
				(copperpour not_allowed)
				(footprints allowed)
			)
			(placement
				(enabled no)
				(sheetname "")
			)
			(fill
				(thermal_gap 0.5)
				(thermal_bridge_width 0.5)
				(island_removal_mode 0)
			)
			(polygon
				(pts
					(xy 390.652 -150.982426) (xy 391.16 -150.982426) (xy 391.16 -150.601426) (xy 390.652 -150.601426)
				)
			)
		)
		(zone
			(layer "F.Cu")
			(hatch none 0.5)
			(connect_pads
				(clearance 0)
			)
			(min_thickness 0.25)
			(keepout
				(tracks not_allowed)
				(vias allowed)
				(pads allowed)
				(copperpour not_allowed)
				(footprints allowed)
			)
			(placement
				(enabled no)
				(sheetname "")
			)
			(fill
				(thermal_gap 0.5)
				(thermal_bridge_width 0.5)
				(island_removal_mode 0)
			)
			(polygon
				(pts
					(xy 390.652 -150.601426) (xy 391.16 -150.601426) (xy 391.16 -150.982426) (xy 390.652 -150.982426)
				)
			)
		)
	)
	(footprint ""
		(layer "F.Cu")
		(at -1.41986 -131.65836 180)
		(property "Reference" "R1B5"
			(at 0 0 180)
			(layer "F.SilkS")
			(hide yes)
			(effects
				(font
					(size 1.27 1.27)
				)
			)
		)
		(property "Value" ""
			(at 0 0 180)
			(layer "F.Fab")
			(effects
				(font
					(size 1.27 1.27)
				)
			)
		)
		(duplicate_pad_numbers_are_jumpers no)
		(fp_rect
			(start 0.2794 -0.1016)
			(end -0.2794 0.9906)
			(stroke
				(width 0)
				(type default)
			)
			(fill no)
			(layer "F.CrtYd")
		)
		(fp_line
			(start 0.2794 0.9906)
			(end 0.2794 -0.1016)
			(stroke
				(width 0.1)
				(type default)
			)
			(layer "F.Fab")
		)
		(fp_line
			(start 0.2794 -0.1016)
			(end -0.2794 -0.1016)
			(stroke
				(width 0.1)
				(type default)
			)
			(layer "F.Fab")
		)
		(fp_line
			(start -0.2794 0.9906)
			(end 0.2794 0.9906)
			(stroke
				(width 0.1)
				(type default)
			)
			(layer "F.Fab")
		)
		(fp_line
			(start -0.2794 -0.1016)
			(end -0.2794 0.9906)
			(stroke
				(width 0.1)
				(type default)
			)
			(layer "F.Fab")
		)
		(pad "1" smd rect
			(at 0 0 180)
			(size 0.508 0.508)
			(layers "F.Cu" "F.Mask" "F.Paste")
			(net "PWRGD_PVDDQ_KLM_R")
		)
		(pad "2" smd rect
			(at 0 0.889 180)
			(size 0.508 0.508)
			(layers "F.Cu" "F.Mask" "F.Paste")
			(net "PWRGD_PVDDQ_KLM")
		)
		(zone
			(layer "F.Cu")
			(hatch none 0.5)
			(connect_pads
				(clearance 0)
			)
			(min_thickness 0.25)
			(keepout
				(tracks not_allowed)
				(vias allowed)
				(pads allowed)
				(copperpour not_allowed)
				(footprints allowed)
			)
			(placement
				(enabled no)
				(sheetname "")
			)
			(fill
				(thermal_gap 0.5)
				(thermal_bridge_width 0.5)
				(island_removal_mode 0)
			)
			(polygon
				(pts
					(xy -1.67386 -131.91236) (xy -1.16586 -131.91236) (xy -1.16586 -132.29336) (xy -1.67386 -132.29336)
				)
			)
		)
		(zone
			(layer "F.Cu")
			(hatch none 0.5)
			(connect_pads
				(clearance 0)
			)
			(min_thickness 0.25)
			(keepout
				(tracks allowed)
				(vias not_allowed)
				(pads allowed)
				(copperpour not_allowed)
				(footprints allowed)
			)
			(placement
				(enabled no)
				(sheetname "")
			)
			(fill
				(thermal_gap 0.5)
				(thermal_bridge_width 0.5)
				(island_removal_mode 0)
			)
			(polygon
				(pts
					(xy -1.67386 -131.91236) (xy -1.16586 -131.91236) (xy -1.16586 -132.29336) (xy -1.67386 -132.29336)
				)
			)
		)
	)
	(footprint ""
		(layer "F.Cu")
		(at 30.013656 -78.33741)
		(property "Reference" "CT21"
			(at -0.88773 0.5842 90)
			(unlocked yes)
			(layer "F.SilkS")
			(effects
				(font
					(size 0.7874 0.5842)
					(thickness 0.1524)
				)
				(justify left)
			)
		)
		(property "Value" ""
			(at 0 0 0)
			(layer "F.Fab")
			(effects
				(font
					(size 1.27 1.27)
				)
			)
		)
		(duplicate_pad_numbers_are_jumpers no)
		(fp_poly
			(pts
				(xy 0.3048 -0.1016) (xy 0.3048 0.9906) (xy -0.3048 0.9906) (xy -0.3048 -0.1016)
			)
			(stroke
				(width 0)
				(type default)
			)
			(fill no)
			(layer "F.CrtYd")
		)
		(fp_line
			(start -0.3048 -0.1016)
			(end -0.3048 0.9906)
			(stroke
				(width 0.1)
				(type default)
			)
			(layer "F.Fab")
		)
		(fp_line
			(start -0.3048 0.9906)
			(end 0.3048 0.9906)
			(stroke
				(width 0.1)
				(type default)
			)
			(layer "F.Fab")
		)
		(fp_line
			(start 0.3048 -0.1016)
			(end -0.3048 -0.1016)
			(stroke
				(width 0.1)
				(type default)
			)
			(layer "F.Fab")
		)
		(fp_line
			(start 0.3048 0.9906)
			(end 0.3048 -0.1016)
			(stroke
				(width 0.1)
				(type default)
			)
			(layer "F.Fab")
		)
		(pad "1" smd rect
			(at 0 0)
			(size 0.508 0.508)
			(layers "F.Cu" "F.Mask" "F.Paste")
			(net "VR_PVCCIN_CPU1_AIREF4")
		)
		(pad "2" smd rect
			(at 0 0.889)
			(size 0.508 0.508)
			(layers "F.Cu" "F.Mask" "F.Paste")
			(net "GND")
		)
		(zone
			(layer "F.Cu")
			(hatch none 0.5)
			(connect_pads
				(clearance 0)
			)
			(min_thickness 0.25)
			(keepout
				(tracks allowed)
				(vias not_allowed)
				(pads allowed)
				(copperpour not_allowed)
				(footprints allowed)
			)
			(placement
				(enabled no)
				(sheetname "")
			)
			(fill
				(thermal_gap 0.5)
				(thermal_bridge_width 0.5)
				(island_removal_mode 0)
			)
			(polygon
				(pts
					(xy 29.759656 -78.08341) (xy 30.267656 -78.08341) (xy 30.267656 -77.70241) (xy 29.759656 -77.70241)
				)
			)
		)
		(zone
			(layer "F.Cu")
			(hatch none 0.5)
			(connect_pads
				(clearance 0)
			)
			(min_thickness 0.25)
			(keepout
				(tracks not_allowed)
				(vias allowed)
				(pads allowed)
				(copperpour not_allowed)
				(footprints allowed)
			)
			(placement
				(enabled no)
				(sheetname "")
			)
			(fill
				(thermal_gap 0.5)
				(thermal_bridge_width 0.5)
				(island_removal_mode 0)
			)
			(polygon
				(pts
					(xy 29.759656 -77.70241) (xy 30.267656 -77.70241) (xy 30.267656 -78.08341) (xy 29.759656 -78.08341)
				)
			)
		)
	)
	(footprint ""
		(layer "F.Cu")
		(at 395.6812 1.5748 -90)
		(property "Reference" "R8G21"
			(at 0 0 270)
			(layer "F.SilkS")
			(hide yes)
			(effects
				(font
					(size 1.27 1.27)
				)
			)
		)
		(property "Value" ""
			(at 0 0 270)
			(layer "F.Fab")
			(effects
				(font
					(size 1.27 1.27)
				)
			)
		)
		(duplicate_pad_numbers_are_jumpers no)
		(fp_poly
			(pts
				(xy -0.2794 -0.1016) (xy 0.2794 -0.1016) (xy 0.2794 0.9906) (xy -0.2794 0.9906)
			)
			(stroke
				(width 0)
				(type default)
			)
			(fill no)
			(layer "F.CrtYd")
		)
		(fp_line
			(start -0.2794 0.9906)
			(end 0.2794 0.9906)
			(stroke
				(width 0.1)
				(type default)
			)
			(layer "F.Fab")
		)
		(fp_line
			(start 0.2794 0.9906)
			(end 0.2794 -0.1016)
			(stroke
				(width 0.1)
				(type default)
			)
			(layer "F.Fab")
		)
		(fp_line
			(start -0.2794 -0.1016)
			(end -0.2794 0.9906)
			(stroke
				(width 0.1)
				(type default)
			)
			(layer "F.Fab")
		)
		(fp_line
			(start 0.2794 -0.1016)
			(end -0.2794 -0.1016)
			(stroke
				(width 0.1)
				(type default)
			)
			(layer "F.Fab")
		)
		(pad "1" smd rect
			(at 0 0 270)
			(size 0.508 0.508)
			(layers "F.Cu" "F.Mask" "F.Paste")
			(net "JTAG_TMS")
		)
		(pad "2" smd rect
			(at 0 0.889 270)
			(size 0.508 0.508)
			(layers "F.Cu" "F.Mask" "F.Paste")
			(net "JTAG_TMS_R")
		)
		(zone
			(layer "F.Cu")
			(hatch none 0.5)
			(connect_pads
				(clearance 0)
			)
			(min_thickness 0.25)
			(keepout
				(tracks not_allowed)
				(vias allowed)
				(pads allowed)
				(copperpour not_allowed)
				(footprints allowed)
			)
			(placement
				(enabled no)
				(sheetname "")
			)
			(fill
				(thermal_gap 0.5)
				(thermal_bridge_width 0.5)
				(island_removal_mode 0)
			)
			(polygon
				(pts
					(xy 395.0462 1.3208) (xy 395.0462 1.8288) (xy 395.4272 1.8288) (xy 395.4272 1.3208)
				)
			)
		)
		(zone
			(layer "F.Cu")
			(hatch none 0.5)
			(connect_pads
				(clearance 0)
			)
			(min_thickness 0.25)
			(keepout
				(tracks allowed)
				(vias not_allowed)
				(pads allowed)
				(copperpour not_allowed)
				(footprints allowed)
			)
			(placement
				(enabled no)
				(sheetname "")
			)
			(fill
				(thermal_gap 0.5)
				(thermal_bridge_width 0.5)
				(island_removal_mode 0)
			)
			(polygon
				(pts
					(xy 395.4272 1.3208) (xy 395.4272 1.8288) (xy 395.0462 1.8288) (xy 395.0462 1.3208)
				)
			)
		)
	)
	(footprint ""
		(layer "F.Cu")
		(at 472.7575 -139.573 90)
		(property "Reference" "R9A18"
			(at 0 0 90)
			(layer "F.SilkS")
			(hide yes)
			(effects
				(font
					(size 1.27 1.27)
				)
			)
		)
		(property "Value" ""
			(at 0 0 90)
			(layer "F.Fab")
			(effects
				(font
					(size 1.27 1.27)
				)
			)
		)
		(duplicate_pad_numbers_are_jumpers no)
		(fp_poly
			(pts
				(xy -0.2794 -0.1016) (xy 0.2794 -0.1016) (xy 0.2794 0.9906) (xy -0.2794 0.9906)
			)
			(stroke
				(width 0)
				(type default)
			)
			(fill no)
			(layer "F.CrtYd")
		)
		(fp_line
			(start 0.2794 -0.1016)
			(end -0.2794 -0.1016)
			(stroke
				(width 0.1)
				(type default)
			)
			(layer "F.Fab")
		)
		(fp_line
			(start -0.2794 -0.1016)
			(end -0.2794 0.9906)
			(stroke
				(width 0.1)
				(type default)
			)
			(layer "F.Fab")
		)
		(fp_line
			(start 0.2794 0.9906)
			(end 0.2794 -0.1016)
			(stroke
				(width 0.1)
				(type default)
			)
			(layer "F.Fab")
		)
		(fp_line
			(start -0.2794 0.9906)
			(end 0.2794 0.9906)
			(stroke
				(width 0.1)
				(type default)
			)
			(layer "F.Fab")
		)
		(pad "1" smd rect
			(at 0 0 90)
			(size 0.508 0.508)
			(layers "F.Cu" "F.Mask" "F.Paste")
			(net "P3V3_STBY")
		)
		(pad "2" smd rect
			(at 0 0.889 90)
			(size 0.508 0.508)
			(layers "F.Cu" "F.Mask" "F.Paste")
			(net "FM_PWR_LED")
		)
		(zone
			(layer "F.Cu")
			(hatch none 0.5)
			(connect_pads
				(clearance 0)
			)
			(min_thickness 0.25)
			(keepout
				(tracks allowed)
				(vias not_allowed)
				(pads allowed)
				(copperpour not_allowed)
				(footprints allowed)
			)
			(placement
				(enabled no)
				(sheetname "")
			)
			(fill
				(thermal_gap 0.5)
				(thermal_bridge_width 0.5)
				(island_removal_mode 0)
			)
			(polygon
				(pts
					(xy 473.0115 -139.319) (xy 473.0115 -139.827) (xy 473.3925 -139.827) (xy 473.3925 -139.319)
				)
			)
		)
		(zone
			(layer "F.Cu")
			(hatch none 0.5)
			(connect_pads
				(clearance 0)
			)
			(min_thickness 0.25)
			(keepout
				(tracks not_allowed)
				(vias allowed)
				(pads allowed)
				(copperpour not_allowed)
				(footprints allowed)
			)
			(placement
				(enabled no)
				(sheetname "")
			)
			(fill
				(thermal_gap 0.5)
				(thermal_bridge_width 0.5)
				(island_removal_mode 0)
			)
			(polygon
				(pts
					(xy 473.3925 -139.319) (xy 473.3925 -139.827) (xy 473.0115 -139.827) (xy 473.0115 -139.319)
				)
			)
		)
	)
	(footprint ""
		(layer "F.Cu")
		(at 16.1036 -98.7044 -90)
		(property "Reference" "C1C7"
			(at 0 0 270)
			(layer "F.SilkS")
			(hide yes)
			(effects
				(font
					(size 1.27 1.27)
				)
			)
		)
		(property "Value" ""
			(at 0 0 270)
			(layer "F.Fab")
			(effects
				(font
					(size 1.27 1.27)
				)
			)
		)
		(duplicate_pad_numbers_are_jumpers no)
		(fp_poly
			(pts
				(xy 0.3048 -0.1016) (xy 0.3048 0.9906) (xy -0.3048 0.9906) (xy -0.3048 -0.1016)
			)
			(stroke
				(width 0)
				(type default)
			)
			(fill no)
			(layer "F.CrtYd")
		)
		(fp_line
			(start -0.3048 0.9906)
			(end 0.3048 0.9906)
			(stroke
				(width 0.1)
				(type default)
			)
			(layer "F.Fab")
		)
		(fp_line
			(start 0.3048 0.9906)
			(end 0.3048 -0.1016)
			(stroke
				(width 0.1)
				(type default)
			)
			(layer "F.Fab")
		)
		(fp_line
			(start -0.3048 -0.1016)
			(end -0.3048 0.9906)
			(stroke
				(width 0.1)
				(type default)
			)
			(layer "F.Fab")
		)
		(fp_line
			(start 0.3048 -0.1016)
			(end -0.3048 -0.1016)
			(stroke
				(width 0.1)
				(type default)
			)
			(layer "F.Fab")
		)
		(pad "1" smd rect
			(at 0 0 270)
			(size 0.508 0.508)
			(layers "F.Cu" "F.Mask" "F.Paste")
			(net "VR_PVCCIN_CPU1_VDD")
		)
		(pad "2" smd rect
			(at 0 0.889 270)
			(size 0.508 0.508)
			(layers "F.Cu" "F.Mask" "F.Paste")
			(net "GND")
		)
		(zone
			(layer "F.Cu")
			(hatch none 0.5)
			(connect_pads
				(clearance 0)
			)
			(min_thickness 0.25)
			(keepout
				(tracks not_allowed)
				(vias allowed)
				(pads allowed)
				(copperpour not_allowed)
				(footprints allowed)
			)
			(placement
				(enabled no)
				(sheetname "")
			)
			(fill
				(thermal_gap 0.5)
				(thermal_bridge_width 0.5)
				(island_removal_mode 0)
			)
			(polygon
				(pts
					(xy 15.4686 -98.9584) (xy 15.4686 -98.4504) (xy 15.8496 -98.4504) (xy 15.8496 -98.9584)
				)
			)
		)
		(zone
			(layer "F.Cu")
			(hatch none 0.5)
			(connect_pads
				(clearance 0)
			)
			(min_thickness 0.25)
			(keepout
				(tracks allowed)
				(vias not_allowed)
				(pads allowed)
				(copperpour not_allowed)
				(footprints allowed)
			)
			(placement
				(enabled no)
				(sheetname "")
			)
			(fill
				(thermal_gap 0.5)
				(thermal_bridge_width 0.5)
				(island_removal_mode 0)
			)
			(polygon
				(pts
					(xy 15.8496 -98.9584) (xy 15.8496 -98.4504) (xy 15.4686 -98.4504) (xy 15.4686 -98.9584)
				)
			)
		)
	)
	(footprint ""
		(layer "F.Cu")
		(at 468.493602 -36.626292 -90)
		(property "Reference" "C9F13"
			(at 0 0 270)
			(layer "F.SilkS")
			(hide yes)
			(effects
				(font
					(size 1.27 1.27)
				)
			)
		)
		(property "Value" ""
			(at 0 0 270)
			(layer "F.Fab")
			(effects
				(font
					(size 1.27 1.27)
				)
			)
		)
		(duplicate_pad_numbers_are_jumpers no)
		(fp_poly
			(pts
				(xy -0.7239 -0.2159) (xy 0.7239 -0.2159) (xy 0.7239 1.9939) (xy -0.7239 1.9939)
			)
			(stroke
				(width 0)
				(type default)
			)
			(fill no)
			(layer "F.CrtYd")
		)
		(fp_line
			(start -0.7239 1.9939)
			(end 0.7239 1.9939)
			(stroke
				(width 0.1)
				(type default)
			)
			(layer "F.Fab")
		)
		(fp_line
			(start 0.7239 1.9939)
			(end 0.7239 -0.2159)
			(stroke
				(width 0.1)
				(type default)
			)
			(layer "F.Fab")
		)
		(fp_line
			(start -0.7239 -0.2159)
			(end -0.7239 1.9939)
			(stroke
				(width 0.1)
				(type default)
			)
			(layer "F.Fab")
		)
		(fp_line
			(start 0.7239 -0.2159)
			(end -0.7239 -0.2159)
			(stroke
				(width 0.1)
				(type default)
			)
			(layer "F.Fab")
		)
		(pad "1" smd rect
			(at 0 0 270)
			(size 1.27 1.016)
			(layers "F.Cu" "F.Mask" "F.Paste")
			(net "P1V2_AUX_BMC")
		)
		(pad "2" smd rect
			(at 0 1.778 270)
			(size 1.27 1.016)
			(layers "F.Cu" "F.Mask" "F.Paste")
			(net "GND")
		)
		(zone
			(layer "F.Cu")
			(hatch none 0.5)
			(connect_pads
				(clearance 0)
			)
			(min_thickness 0.25)
			(keepout
				(tracks not_allowed)
				(vias allowed)
				(pads allowed)
				(copperpour not_allowed)
				(footprints allowed)
			)
			(placement
				(enabled no)
				(sheetname "")
			)
			(fill
				(thermal_gap 0.5)
				(thermal_bridge_width 0.5)
				(island_removal_mode 0)
			)
			(polygon
				(pts
					(xy 467.985602 -37.261292) (xy 467.985602 -35.991292) (xy 467.223602 -35.991292) (xy 467.223602 -37.261292)
				)
			)
		)
	)
	(footprint ""
		(layer "F.Cu")
		(at 22.66188 -83.24342 180)
		(property "Reference" "R1D14"
			(at 0 0 180)
			(layer "F.SilkS")
			(hide yes)
			(effects
				(font
					(size 1.27 1.27)
				)
			)
		)
		(property "Value" ""
			(at 0 0 180)
			(layer "F.Fab")
			(effects
				(font
					(size 1.27 1.27)
				)
			)
		)
		(duplicate_pad_numbers_are_jumpers no)
		(fp_poly
			(pts
				(xy -0.2794 -0.1016) (xy 0.2794 -0.1016) (xy 0.2794 0.9906) (xy -0.2794 0.9906)
			)
			(stroke
				(width 0)
				(type default)
			)
			(fill no)
			(layer "F.CrtYd")
		)
		(fp_line
			(start 0.2794 0.9906)
			(end 0.2794 -0.1016)
			(stroke
				(width 0.1)
				(type default)
			)
			(layer "F.Fab")
		)
		(fp_line
			(start 0.2794 -0.1016)
			(end -0.2794 -0.1016)
			(stroke
				(width 0.1)
				(type default)
			)
			(layer "F.Fab")
		)
		(fp_line
			(start -0.2794 0.9906)
			(end 0.2794 0.9906)
			(stroke
				(width 0.1)
				(type default)
			)
			(layer "F.Fab")
		)
		(fp_line
			(start -0.2794 -0.1016)
			(end -0.2794 0.9906)
			(stroke
				(width 0.1)
				(type default)
			)
			(layer "F.Fab")
		)
		(pad "1" smd rect
			(at 0 0 180)
			(size 0.508 0.508)
			(layers "F.Cu" "F.Mask" "F.Paste")
			(net "A_HSC_CSOUT")
		)
		(pad "2" smd rect
			(at 0 0.889 180)
			(size 0.508 0.508)
			(layers "F.Cu" "F.Mask" "F.Paste")
			(net "A_HSC_LOW")
		)
		(zone
			(layer "F.Cu")
			(hatch none 0.5)
			(connect_pads
				(clearance 0)
			)
			(min_thickness 0.25)
			(keepout
				(tracks not_allowed)
				(vias allowed)
				(pads allowed)
				(copperpour not_allowed)
				(footprints allowed)
			)
			(placement
				(enabled no)
				(sheetname "")
			)
			(fill
				(thermal_gap 0.5)
				(thermal_bridge_width 0.5)
				(island_removal_mode 0)
			)
			(polygon
				(pts
					(xy 22.91588 -83.87842) (xy 22.40788 -83.87842) (xy 22.40788 -83.49742) (xy 22.91588 -83.49742)
				)
			)
		)
		(zone
			(layer "F.Cu")
			(hatch none 0.5)
			(connect_pads
				(clearance 0)
			)
			(min_thickness 0.25)
			(keepout
				(tracks allowed)
				(vias not_allowed)
				(pads allowed)
				(copperpour not_allowed)
				(footprints allowed)
			)
			(placement
				(enabled no)
				(sheetname "")
			)
			(fill
				(thermal_gap 0.5)
				(thermal_bridge_width 0.5)
				(island_removal_mode 0)
			)
			(polygon
				(pts
					(xy 22.91588 -83.49742) (xy 22.40788 -83.49742) (xy 22.40788 -83.87842) (xy 22.91588 -83.87842)
				)
			)
		)
	)
	(footprint ""
		(layer "F.Cu")
		(at 10.180828 -126.827026 -90)
		(property "Reference" "R12W16"
			(at 0 0 270)
			(layer "F.SilkS")
			(hide yes)
			(effects
				(font
					(size 1.27 1.27)
				)
			)
		)
		(property "Value" "*"
			(at 0 -8.9535 270)
			(unlocked yes)
			(layer "F.Fab")
			(hide yes)
			(effects
				(font
					(size 1.27 1.016)
					(thickness 0.1524)
				)
			)
		)
		(property "Device Type" "665KR5B-1-GP_SMD-RG3-665KR5B-1A"
			(at 0 -10.6299 270)
			(unlocked yes)
			(layer "F.Fab")
			(hide yes)
			(effects
				(font
					(size 1.27 1.016)
					(thickness 0.1524)
				)
			)
		)
		(duplicate_pad_numbers_are_jumpers no)
		(fp_line
			(start -0.889 1.7018)
			(end 0.889 1.7018)
			(stroke
				(width 0.1524)
				(type default)
			)
			(layer "F.SilkS")
		)
		(fp_line
			(start 0.889 1.7018)
			(end 0.889 -0.508)
			(stroke
				(width 0.1524)
				(type default)
			)
			(layer "F.SilkS")
		)
		(fp_line
			(start -0.889 0.0762)
			(end -0.889 1.7018)
			(stroke
				(width 0.1524)
				(type default)
			)
			(layer "F.SilkS")
		)
		(fp_line
			(start -0.889 -1.7018)
			(end -0.889 0.2794)
			(stroke
				(width 0.1524)
				(type default)
			)
			(layer "F.SilkS")
		)
		(fp_line
			(start 0.889 -1.7018)
			(end 0.889 -0.381)
			(stroke
				(width 0.1524)
				(type default)
			)
			(layer "F.SilkS")
		)
		(fp_line
			(start 0.889 -1.7018)
			(end -0.889 -1.7018)
			(stroke
				(width 0.1524)
				(type default)
			)
			(layer "F.SilkS")
		)
		(fp_poly
			(pts
				(xy 0.9652 -1.778) (xy 0.9652 1.778) (xy -0.9652 1.778) (xy -0.9652 -1.778)
			)
			(stroke
				(width 0)
				(type default)
			)
			(fill no)
			(layer "F.CrtYd")
		)
		(fp_rect
			(start -0.9652 1.778)
			(end 0.9652 -1.778)
			(stroke
				(width 0)
				(type default)
			)
			(fill no)
			(layer "F.Fab")
		)
		(pad "1" smd rect
			(at 0 -0.9652 270)
			(size 1.397 1.143)
			(layers "F.Cu" "F.Mask" "F.Paste")
			(net "P12V_STBY")
		)
		(pad "2" smd rect
			(at 0 0.9652 270)
			(size 1.397 1.143)
			(layers "F.Cu" "F.Mask" "F.Paste")
			(net "VR_PVDDQ_KLM_AIINSEN")
		)
	)
	(footprint ""
		(layer "F.Cu")
		(at 400.685 -82.3595 180)
		(property "Reference" "R2P16"
			(at 0 0 180)
			(layer "F.SilkS")
			(hide yes)
			(effects
				(font
					(size 1.27 1.27)
				)
			)
		)
		(property "Value" ""
			(at 0 0 180)
			(layer "F.Fab")
			(effects
				(font
					(size 1.27 1.27)
				)
			)
		)
		(duplicate_pad_numbers_are_jumpers no)
		(fp_poly
			(pts
				(xy -0.2794 -0.1016) (xy 0.2794 -0.1016) (xy 0.2794 0.9906) (xy -0.2794 0.9906)
			)
			(stroke
				(width 0)
				(type default)
			)
			(fill no)
			(layer "F.CrtYd")
		)
		(fp_line
			(start 0.2794 0.9906)
			(end 0.2794 -0.1016)
			(stroke
				(width 0.1)
				(type default)
			)
			(layer "F.Fab")
		)
		(fp_line
			(start 0.2794 -0.1016)
			(end -0.2794 -0.1016)
			(stroke
				(width 0.1)
				(type default)
			)
			(layer "F.Fab")
		)
		(fp_line
			(start -0.2794 0.9906)
			(end 0.2794 0.9906)
			(stroke
				(width 0.1)
				(type default)
			)
			(layer "F.Fab")
		)
		(fp_line
			(start -0.2794 -0.1016)
			(end -0.2794 0.9906)
			(stroke
				(width 0.1)
				(type default)
			)
			(layer "F.Fab")
		)
		(pad "1" smd rect
			(at 0 0 180)
			(size 0.508 0.508)
			(layers "F.Cu" "F.Mask" "F.Paste")
			(net "P3V3_STBY")
		)
		(pad "2" smd rect
			(at 0 0.889 180)
			(size 0.508 0.508)
			(layers "F.Cu" "F.Mask" "F.Paste")
			(net "FM_M2_DET_LVC3")
		)
		(zone
			(layer "F.Cu")
			(hatch none 0.5)
			(connect_pads
				(clearance 0)
			)
			(min_thickness 0.25)
			(keepout
				(tracks not_allowed)
				(vias allowed)
				(pads allowed)
				(copperpour not_allowed)
				(footprints allowed)
			)
			(placement
				(enabled no)
				(sheetname "")
			)
			(fill
				(thermal_gap 0.5)
				(thermal_bridge_width 0.5)
				(island_removal_mode 0)
			)
			(polygon
				(pts
					(xy 400.939 -82.9945) (xy 400.431 -82.9945) (xy 400.431 -82.6135) (xy 400.939 -82.6135)
				)
			)
		)
		(zone
			(layer "F.Cu")
			(hatch none 0.5)
			(connect_pads
				(clearance 0)
			)
			(min_thickness 0.25)
			(keepout
				(tracks allowed)
				(vias not_allowed)
				(pads allowed)
				(copperpour not_allowed)
				(footprints allowed)
			)
			(placement
				(enabled no)
				(sheetname "")
			)
			(fill
				(thermal_gap 0.5)
				(thermal_bridge_width 0.5)
				(island_removal_mode 0)
			)
			(polygon
				(pts
					(xy 400.939 -82.6135) (xy 400.431 -82.6135) (xy 400.431 -82.9945) (xy 400.939 -82.9945)
				)
			)
		)
	)
	(footprint ""
		(layer "F.Cu")
		(at 363.87024 -138.41857 90)
		(property "Reference" "R7A12"
			(at 0 0 90)
			(layer "F.SilkS")
			(hide yes)
			(effects
				(font
					(size 1.27 1.27)
				)
			)
		)
		(property "Value" ""
			(at 0 0 90)
			(layer "F.Fab")
			(effects
				(font
					(size 1.27 1.27)
				)
			)
		)
		(duplicate_pad_numbers_are_jumpers no)
		(fp_rect
			(start -0.2794 -0.1016)
			(end 0.2794 0.9906)
			(stroke
				(width 0)
				(type default)
			)
			(fill no)
			(layer "F.CrtYd")
		)
		(fp_line
			(start 0.2794 -0.1016)
			(end -0.2794 -0.1016)
			(stroke
				(width 0.1)
				(type default)
			)
			(layer "F.Fab")
		)
		(fp_line
			(start -0.2794 -0.1016)
			(end -0.2794 0.9906)
			(stroke
				(width 0.1)
				(type default)
			)
			(layer "F.Fab")
		)
		(fp_line
			(start 0.2794 0.9906)
			(end 0.2794 -0.1016)
			(stroke
				(width 0.1)
				(type default)
			)
			(layer "F.Fab")
		)
		(fp_line
			(start -0.2794 0.9906)
			(end 0.2794 0.9906)
			(stroke
				(width 0.1)
				(type default)
			)
			(layer "F.Fab")
		)
		(pad "1" smd rect
			(at 0 0 90)
			(size 0.508 0.508)
			(layers "F.Cu" "F.Mask" "F.Paste")
			(net "SVID_VDIO_PVDDQ_DEF")
		)
		(pad "2" smd rect
			(at 0 0.889 90)
			(size 0.508 0.508)
			(layers "F.Cu" "F.Mask" "F.Paste")
			(net "SVID_DIO1_CPU0_R")
		)
		(zone
			(layer "F.Cu")
			(hatch none 0.5)
			(connect_pads
				(clearance 0)
			)
			(min_thickness 0.25)
			(keepout
				(tracks allowed)
				(vias not_allowed)
				(pads allowed)
				(copperpour not_allowed)
				(footprints allowed)
			)
			(placement
				(enabled no)
				(sheetname "")
			)
			(fill
				(thermal_gap 0.5)
				(thermal_bridge_width 0.5)
				(island_removal_mode 0)
			)
			(polygon
				(pts
					(xy 364.12424 -138.16457) (xy 364.50524 -138.16457) (xy 364.50524 -138.67257) (xy 364.12424 -138.67257)
				)
			)
		)
		(zone
			(layer "F.Cu")
			(hatch none 0.5)
			(connect_pads
				(clearance 0)
			)
			(min_thickness 0.25)
			(keepout
				(tracks not_allowed)
				(vias allowed)
				(pads allowed)
				(copperpour not_allowed)
				(footprints allowed)
			)
			(placement
				(enabled no)
				(sheetname "")
			)
			(fill
				(thermal_gap 0.5)
				(thermal_bridge_width 0.5)
				(island_removal_mode 0)
			)
			(polygon
				(pts
					(xy 364.12424 -138.16457) (xy 364.50524 -138.16457) (xy 364.50524 -138.67257) (xy 364.12424 -138.67257)
				)
			)
		)
	)
	(footprint ""
		(layer "F.Cu")
		(at 61.285628 -165.04158 -90)
		(property "Reference" "T1D10"
			(at 0 0 270)
			(layer "F.SilkS")
			(hide yes)
			(effects
				(font
					(size 1.27 1.27)
				)
			)
		)
		(property "Value" "*"
			(at -3.4036 -4.46405 270)
			(unlocked yes)
			(layer "F.Fab")
			(hide yes)
			(effects
				(font
					(size 0.889 0.889)
					(thickness 0.1524)
				)
			)
		)
		(property "Device Type" "TEST-PAD-12P-1-GP-U_DISCRET-GBA"
			(at -3.4036 -5.98805 270)
			(unlocked yes)
			(layer "F.Fab")
			(hide yes)
			(effects
				(font
					(size 0.889 0.889)
					(thickness 0.1524)
				)
			)
		)
		(duplicate_pad_numbers_are_jumpers no)
		(fp_line
			(start -2.3876 3.4798)
			(end -2.3876 -4.826)
			(stroke
				(width 0.1524)
				(type default)
			)
			(layer "F.SilkS")
		)
		(fp_line
			(start 2.3622 3.4798)
			(end -2.3876 3.4798)
			(stroke
				(width 0.1524)
				(type default)
			)
			(layer "F.SilkS")
		)
		(fp_line
			(start -2.3876 -4.826)
			(end 2.3622 -4.826)
			(stroke
				(width 0.1524)
				(type default)
			)
			(layer "F.SilkS")
		)
		(fp_line
			(start 2.3622 -4.826)
			(end 2.3622 3.4798)
			(stroke
				(width 0.1524)
				(type default)
			)
			(layer "F.SilkS")
		)
		(fp_rect
			(start -2.6416 3.7338)
			(end 2.6162 -5.08)
			(stroke
				(width 0)
				(type default)
			)
			(fill no)
			(layer "F.CrtYd")
		)
		(fp_rect
			(start -2.6416 3.7338)
			(end 2.6162 -5.08)
			(stroke
				(width 0)
				(type default)
			)
			(fill no)
			(layer "F.Fab")
		)
		(pad "1" smd circle
			(at 0.496824 -1.301496 270)
			(size 0.6604 0.6604)
			(layers "F.Cu" "F.Mask" "F.Paste")
			(net "L12_85OHM_5INCH_DN")
		)
		(pad "2" smd circle
			(at -0.503936 -1.301496 270)
			(size 0.6604 0.6604)
			(layers "F.Cu" "F.Mask" "F.Paste")
			(net "L12_85OHM_5INCH_DP")
		)
		(pad "3" smd custom
			(at -0.00889 0.370078 270)
			(size 0.74295 0.74295)
			(layers "F.Cu" "F.Mask" "F.Paste")
			(net "GND")
			(options
				(clearance outline)
				(anchor circle)
			)
			(primitives
				(gr_poly
					(pts
						(xy -2.1209 1.4859) (xy 2.1209 1.4859) (xy 2.1209 -1.4859) (xy 1.08585 -1.4859) (xy 1.08585 -0.4699)
						(xy -1.08585 -0.4699) (xy -1.08585 -1.4859) (xy -2.1209 -1.4859)
					)
					(width 0)
					(fill yes)
				)
			)
		)
		(pad "4" thru_hole circle
			(at 1.266444 -3.851656 270)
			(size 1.4478 1.4478)
			(drill 1.0414)
			(layers "*.Cu" "*.Mask")
			(remove_unused_layers no)
			(net "GND")
			(clearance 0.1524)
			(thermal_gap 0.1524)
		)
		(pad "5" thru_hole circle
			(at -1.273556 -3.851656 270)
			(size 1.4478 1.4478)
			(drill 1.0414)
			(layers "*.Cu" "*.Mask")
			(remove_unused_layers no)
			(net "GND")
			(clearance 0.1524)
			(thermal_gap 0.1524)
		)
		(pad "6" thru_hole circle
			(at 1.266444 2.498344 270)
			(size 1.4478 1.4478)
			(drill 1.0414)
			(layers "*.Cu" "*.Mask")
			(remove_unused_layers no)
			(net "GND")
			(clearance 0.1524)
			(thermal_gap 0.1524)
		)
		(pad "7" thru_hole circle
			(at -1.273556 2.498344 270)
			(size 1.4478 1.4478)
			(drill 1.0414)
			(layers "*.Cu" "*.Mask")
			(remove_unused_layers no)
			(net "GND")
			(clearance 0.1524)
			(thermal_gap 0.1524)
		)
		(pad "8" thru_hole circle
			(at 1.27 -0.4572 270)
			(size 0.7112 0.7112)
			(drill 0.4064)
			(layers "*.Cu" "*.Mask")
			(remove_unused_layers no)
			(net "GND")
			(clearance 0.1016)
			(thermal_gap 0.1016)
		)
		(pad "9" thru_hole circle
			(at 1.27 0.762 270)
			(size 0.7112 0.7112)
			(drill 0.4064)
			(layers "*.Cu" "*.Mask")
			(remove_unused_layers no)
			(net "GND")
			(clearance 0.1016)
			(thermal_gap 0.1016)
		)
		(pad "10" thru_hole circle
			(at -0.0254 0.762 270)
			(size 0.7112 0.7112)
			(drill 0.4064)
			(layers "*.Cu" "*.Mask")
			(remove_unused_layers no)
			(net "GND")
			(clearance 0.1016)
			(thermal_gap 0.1016)
		)
		(pad "11" thru_hole circle
			(at -1.27 0.762 270)
			(size 0.7112 0.7112)
			(drill 0.4064)
			(layers "*.Cu" "*.Mask")
			(remove_unused_layers no)
			(net "GND")
			(clearance 0.1016)
			(thermal_gap 0.1016)
		)
		(pad "12" thru_hole circle
			(at -1.27 -0.4572 270)
			(size 0.7112 0.7112)
			(drill 0.4064)
			(layers "*.Cu" "*.Mask")
			(remove_unused_layers no)
			(net "GND")
			(clearance 0.1016)
			(thermal_gap 0.1016)
		)
	)
	(footprint ""
		(layer "F.Cu")
		(at 353.5807 -15.737586 90)
		(property "Reference" "C7G2"
			(at -4.21767 2.921 0)
			(unlocked yes)
			(layer "F.SilkS")
			(effects
				(font
					(size 0.7874 0.5842)
					(thickness 0.1524)
				)
				(justify left)
			)
		)
		(property "Value" ""
			(at 0 0 90)
			(layer "F.Fab")
			(effects
				(font
					(size 1.27 1.27)
				)
			)
		)
		(duplicate_pad_numbers_are_jumpers no)
		(fp_line
			(start 0.9017 -1.714246)
			(end 0.7239 -1.714246)
			(stroke
				(width 0.1524)
				(type default)
			)
			(layer "F.SilkS")
		)
		(fp_line
			(start -0.7239 -1.714246)
			(end -0.9017 -1.714246)
			(stroke
				(width 0.1524)
				(type default)
			)
			(layer "F.SilkS")
		)
		(fp_line
			(start -0.9017 -1.714246)
			(end -0.9017 1.587754)
			(stroke
				(width 0.1524)
				(type default)
			)
			(layer "F.SilkS")
		)
		(fp_line
			(start 2.638044 -0.733044)
			(end 0.9017 -0.733044)
			(stroke
				(width 0.1524)
				(type default)
			)
			(layer "F.SilkS")
		)
		(fp_line
			(start -0.9017 -0.733044)
			(end -2.638044 -0.733044)
			(stroke
				(width 0.1524)
				(type default)
			)
			(layer "F.SilkS")
		)
		(fp_line
			(start -2.638044 -0.733044)
			(end -3.400044 0.028956)
			(stroke
				(width 0.1524)
				(type default)
			)
			(layer "F.SilkS")
		)
		(fp_line
			(start 3.400044 0.028956)
			(end 2.638044 -0.733044)
			(stroke
				(width 0.1524)
				(type default)
			)
			(layer "F.SilkS")
		)
		(fp_line
			(start -3.400044 0.028956)
			(end -3.400044 6.067044)
			(stroke
				(width 0.1524)
				(type default)
			)
			(layer "F.SilkS")
		)
		(fp_line
			(start 0.9017 1.587754)
			(end 0.9017 -1.714246)
			(stroke
				(width 0.1524)
				(type default)
			)
			(layer "F.SilkS")
		)
		(fp_line
			(start 0.7239 1.587754)
			(end 0.9017 1.587754)
			(stroke
				(width 0.1524)
				(type default)
			)
			(layer "F.SilkS")
		)
		(fp_line
			(start -0.9017 1.587754)
			(end -0.7239 1.587754)
			(stroke
				(width 0.1524)
				(type default)
			)
			(layer "F.SilkS")
		)
		(fp_line
			(start 3.400044 6.067044)
			(end 3.400044 0.028956)
			(stroke
				(width 0.1524)
				(type default)
			)
			(layer "F.SilkS")
		)
		(fp_line
			(start 0.9017 6.067044)
			(end 3.400044 6.067044)
			(stroke
				(width 0.1524)
				(type default)
			)
			(layer "F.SilkS")
		)
		(fp_line
			(start -3.400044 6.067044)
			(end -0.9017 6.067044)
			(stroke
				(width 0.1524)
				(type default)
			)
			(layer "F.SilkS")
		)
		(fp_poly
			(pts
				(xy -3.400044 6.067044) (xy 3.400044 6.067044) (xy 3.400044 0.028956) (xy 2.638044 -0.733044) (xy -2.638044 -0.733044)
				(xy -3.400044 0.028956)
			)
			(stroke
				(width 0)
				(type default)
			)
			(fill no)
			(layer "F.CrtYd")
		)
		(fp_line
			(start 2.638044 -0.733044)
			(end -2.638044 -0.733044)
			(stroke
				(width 0.1)
				(type default)
			)
			(layer "F.Fab")
		)
		(fp_line
			(start -2.638044 -0.733044)
			(end -3.400044 0.028956)
			(stroke
				(width 0.1)
				(type default)
			)
			(layer "F.Fab")
		)
		(fp_line
			(start 3.400044 0.028956)
			(end 2.638044 -0.733044)
			(stroke
				(width 0.1)
				(type default)
			)
			(layer "F.Fab")
		)
		(fp_line
			(start -3.400044 0.028956)
			(end -3.400044 6.067044)
			(stroke
				(width 0.1)
				(type default)
			)
			(layer "F.Fab")
		)
		(fp_line
			(start 3.400044 6.067044)
			(end 3.400044 0.028956)
			(stroke
				(width 0.1)
				(type default)
			)
			(layer "F.Fab")
		)
		(fp_line
			(start -3.400044 6.067044)
			(end 3.400044 6.067044)
			(stroke
				(width 0.1)
				(type default)
			)
			(layer "F.Fab")
		)
		(fp_circle
			(center 0 2.667)
			(end 0 6.067044)
			(stroke
				(width 0.1)
				(type default)
			)
			(fill no)
			(layer "F.Fab")
		)
		(pad "1" smd rect
			(at 0 0 90)
			(size 0.7874 3.429)
			(layers "F.Cu" "F.Mask" "F.Paste")
			(net "VR_FET_SW_P12V_STBY_PVDDQ_ABC")
		)
		(pad "2" smd rect
			(at 0 5.334 90)
			(size 0.7874 3.429)
			(layers "F.Cu" "F.Mask" "F.Paste")
			(net "GND")
		)
	)
	(footprint ""
		(layer "F.Cu")
		(at 482.67366 -29.28112 90)
		(property "Reference" "R8F27"
			(at 0 0 90)
			(layer "F.SilkS")
			(hide yes)
			(effects
				(font
					(size 1.27 1.27)
				)
			)
		)
		(property "Value" ""
			(at 0 0 90)
			(layer "F.Fab")
			(effects
				(font
					(size 1.27 1.27)
				)
			)
		)
		(duplicate_pad_numbers_are_jumpers no)
		(fp_poly
			(pts
				(xy -0.2794 -0.1016) (xy 0.2794 -0.1016) (xy 0.2794 0.9906) (xy -0.2794 0.9906)
			)
			(stroke
				(width 0)
				(type default)
			)
			(fill no)
			(layer "F.CrtYd")
		)
		(fp_line
			(start 0.2794 -0.1016)
			(end -0.2794 -0.1016)
			(stroke
				(width 0.1)
				(type default)
			)
			(layer "F.Fab")
		)
		(fp_line
			(start -0.2794 -0.1016)
			(end -0.2794 0.9906)
			(stroke
				(width 0.1)
				(type default)
			)
			(layer "F.Fab")
		)
		(fp_line
			(start 0.2794 0.9906)
			(end 0.2794 -0.1016)
			(stroke
				(width 0.1)
				(type default)
			)
			(layer "F.Fab")
		)
		(fp_line
			(start -0.2794 0.9906)
			(end 0.2794 0.9906)
			(stroke
				(width 0.1)
				(type default)
			)
			(layer "F.Fab")
		)
		(pad "1" smd rect
			(at 0 0 90)
			(size 0.508 0.508)
			(layers "F.Cu" "F.Mask" "F.Paste")
			(net "CLK_32K_SUSCLK_PLD_R")
		)
		(pad "2" smd rect
			(at 0 0.889 90)
			(size 0.508 0.508)
			(layers "F.Cu" "F.Mask" "F.Paste")
			(net "CLK_32K_SUSCLK_PLD")
		)
		(zone
			(layer "F.Cu")
			(hatch none 0.5)
			(connect_pads
				(clearance 0)
			)
			(min_thickness 0.25)
			(keepout
				(tracks allowed)
				(vias not_allowed)
				(pads allowed)
				(copperpour not_allowed)
				(footprints allowed)
			)
			(placement
				(enabled no)
				(sheetname "")
			)
			(fill
				(thermal_gap 0.5)
				(thermal_bridge_width 0.5)
				(island_removal_mode 0)
			)
			(polygon
				(pts
					(xy 482.92766 -29.02712) (xy 482.92766 -29.53512) (xy 483.30866 -29.53512) (xy 483.30866 -29.02712)
				)
			)
		)
		(zone
			(layer "F.Cu")
			(hatch none 0.5)
			(connect_pads
				(clearance 0)
			)
			(min_thickness 0.25)
			(keepout
				(tracks not_allowed)
				(vias allowed)
				(pads allowed)
				(copperpour not_allowed)
				(footprints allowed)
			)
			(placement
				(enabled no)
				(sheetname "")
			)
			(fill
				(thermal_gap 0.5)
				(thermal_bridge_width 0.5)
				(island_removal_mode 0)
			)
			(polygon
				(pts
					(xy 483.30866 -29.02712) (xy 483.30866 -29.53512) (xy 482.92766 -29.53512) (xy 482.92766 -29.02712)
				)
			)
		)
	)
	(footprint ""
		(layer "F.Cu")
		(at 355.24948 -135.742934)
		(property "Reference" "C7A38"
			(at 0 0 0)
			(layer "F.SilkS")
			(hide yes)
			(effects
				(font
					(size 1.27 1.27)
				)
			)
		)
		(property "Value" ""
			(at 0 0 0)
			(layer "F.Fab")
			(effects
				(font
					(size 1.27 1.27)
				)
			)
		)
		(duplicate_pad_numbers_are_jumpers no)
		(fp_rect
			(start -0.3048 0.9906)
			(end 0.3048 -0.1016)
			(stroke
				(width 0)
				(type default)
			)
			(fill no)
			(layer "F.CrtYd")
		)
		(fp_line
			(start -0.3048 -0.1016)
			(end -0.3048 0.9906)
			(stroke
				(width 0.1)
				(type default)
			)
			(layer "F.Fab")
		)
		(fp_line
			(start -0.3048 0.9906)
			(end 0.3048 0.9906)
			(stroke
				(width 0.1)
				(type default)
			)
			(layer "F.Fab")
		)
		(fp_line
			(start 0.3048 -0.1016)
			(end -0.3048 -0.1016)
			(stroke
				(width 0.1)
				(type default)
			)
			(layer "F.Fab")
		)
		(fp_line
			(start 0.3048 0.9906)
			(end 0.3048 -0.1016)
			(stroke
				(width 0.1)
				(type default)
			)
			(layer "F.Fab")
		)
		(pad "1" smd rect
			(at 0 0)
			(size 0.508 0.508)
			(layers "F.Cu" "F.Mask" "F.Paste")
			(net "VR_PVDDQ_DEF_VDD")
		)
		(pad "2" smd rect
			(at 0 0.889)
			(size 0.508 0.508)
			(layers "F.Cu" "F.Mask" "F.Paste")
			(net "GND")
		)
		(zone
			(layer "F.Cu")
			(hatch none 0.5)
			(connect_pads
				(clearance 0)
			)
			(min_thickness 0.25)
			(keepout
				(tracks not_allowed)
				(vias allowed)
				(pads allowed)
				(copperpour not_allowed)
				(footprints allowed)
			)
			(placement
				(enabled no)
				(sheetname "")
			)
			(fill
				(thermal_gap 0.5)
				(thermal_bridge_width 0.5)
				(island_removal_mode 0)
			)
			(polygon
				(pts
					(xy 354.99548 -135.107934) (xy 355.50348 -135.107934) (xy 355.50348 -135.488934) (xy 354.99548 -135.488934)
				)
			)
		)
		(zone
			(layer "F.Cu")
			(hatch none 0.5)
			(connect_pads
				(clearance 0)
			)
			(min_thickness 0.25)
			(keepout
				(tracks allowed)
				(vias not_allowed)
				(pads allowed)
				(copperpour not_allowed)
				(footprints allowed)
			)
			(placement
				(enabled no)
				(sheetname "")
			)
			(fill
				(thermal_gap 0.5)
				(thermal_bridge_width 0.5)
				(island_removal_mode 0)
			)
			(polygon
				(pts
					(xy 354.99548 -135.107934) (xy 355.50348 -135.107934) (xy 355.50348 -135.488934) (xy 354.99548 -135.488934)
				)
			)
		)
	)
	(footprint ""
		(layer "F.Cu")
		(at 176.0855 -7.874 90)
		(property "Reference" "C4G10"
			(at 0 0 90)
			(layer "F.SilkS")
			(hide yes)
			(effects
				(font
					(size 1.27 1.27)
				)
			)
		)
		(property "Value" ""
			(at 0 0 90)
			(layer "F.Fab")
			(effects
				(font
					(size 1.27 1.27)
				)
			)
		)
		(duplicate_pad_numbers_are_jumpers no)
		(fp_poly
			(pts
				(xy 0.3048 -0.1016) (xy 0.3048 0.9906) (xy -0.3048 0.9906) (xy -0.3048 -0.1016)
			)
			(stroke
				(width 0)
				(type default)
			)
			(fill no)
			(layer "F.CrtYd")
		)
		(fp_line
			(start 0.3048 -0.1016)
			(end -0.3048 -0.1016)
			(stroke
				(width 0.1)
				(type default)
			)
			(layer "F.Fab")
		)
		(fp_line
			(start -0.3048 -0.1016)
			(end -0.3048 0.9906)
			(stroke
				(width 0.1)
				(type default)
			)
			(layer "F.Fab")
		)
		(fp_line
			(start 0.3048 0.9906)
			(end 0.3048 -0.1016)
			(stroke
				(width 0.1)
				(type default)
			)
			(layer "F.Fab")
		)
		(fp_line
			(start -0.3048 0.9906)
			(end 0.3048 0.9906)
			(stroke
				(width 0.1)
				(type default)
			)
			(layer "F.Fab")
		)
		(pad "1" smd rect
			(at 0 0 90)
			(size 0.508 0.508)
			(layers "F.Cu" "F.Mask" "F.Paste")
			(net "VR_COMP_RC_PVPP_GHJ")
		)
		(pad "2" smd rect
			(at 0 0.889 90)
			(size 0.508 0.508)
			(layers "F.Cu" "F.Mask" "F.Paste")
			(net "VR_COMP_PVPP_GHJ_3")
		)
		(zone
			(layer "F.Cu")
			(hatch none 0.5)
			(connect_pads
				(clearance 0)
			)
			(min_thickness 0.25)
			(keepout
				(tracks allowed)
				(vias not_allowed)
				(pads allowed)
				(copperpour not_allowed)
				(footprints allowed)
			)
			(placement
				(enabled no)
				(sheetname "")
			)
			(fill
				(thermal_gap 0.5)
				(thermal_bridge_width 0.5)
				(island_removal_mode 0)
			)
			(polygon
				(pts
					(xy 176.3395 -7.62) (xy 176.3395 -8.128) (xy 176.7205 -8.128) (xy 176.7205 -7.62)
				)
			)
		)
		(zone
			(layer "F.Cu")
			(hatch none 0.5)
			(connect_pads
				(clearance 0)
			)
			(min_thickness 0.25)
			(keepout
				(tracks not_allowed)
				(vias allowed)
				(pads allowed)
				(copperpour not_allowed)
				(footprints allowed)
			)
			(placement
				(enabled no)
				(sheetname "")
			)
			(fill
				(thermal_gap 0.5)
				(thermal_bridge_width 0.5)
				(island_removal_mode 0)
			)
			(polygon
				(pts
					(xy 176.7205 -7.62) (xy 176.7205 -8.128) (xy 176.3395 -8.128) (xy 176.3395 -7.62)
				)
			)
		)
	)
	(footprint ""
		(layer "F.Cu")
		(at 156.70022 -123.7107)
		(property "Reference" "U3B1"
			(at 4.46278 3.54457 0)
			(unlocked yes)
			(layer "F.SilkS")
			(effects
				(font
					(size 0.7874 0.5842)
					(thickness 0.1524)
				)
			)
		)
		(property "Value" ""
			(at 0 0 0)
			(layer "F.Fab")
			(effects
				(font
					(size 1.27 1.27)
				)
			)
		)
		(duplicate_pad_numbers_are_jumpers no)
		(fp_line
			(start 3.225038 2.52476)
			(end 1.348486 2.52476)
			(stroke
				(width 0.1524)
				(type default)
			)
			(layer "F.SilkS")
		)
		(fp_line
			(start 3.225292 -0.57404)
			(end 1.352804 -0.57404)
			(stroke
				(width 0.1524)
				(type default)
			)
			(layer "F.SilkS")
		)
		(fp_circle
			(center -1.454404 -0.556514)
			(end -1.327404 -0.556514)
			(stroke
				(width 0.254)
				(type default)
			)
			(fill no)
			(layer "F.SilkS")
		)
		(fp_poly
			(pts
				(xy 0.7366 -0.57404) (xy 3.8354 -0.57404) (xy 3.8354 2.52476) (xy 0.7366 2.52476)
			)
			(stroke
				(width 0)
				(type default)
			)
			(fill no)
			(layer "F.CrtYd")
		)
		(fp_line
			(start 0.7366 -0.57404)
			(end 3.8354 -0.57404)
			(stroke
				(width 0.1)
				(type default)
			)
			(layer "F.Fab")
		)
		(fp_line
			(start 0.7366 2.52476)
			(end 0.7366 -0.57404)
			(stroke
				(width 0.1)
				(type default)
			)
			(layer "F.Fab")
		)
		(fp_line
			(start 3.8354 -0.57404)
			(end 3.8354 2.52476)
			(stroke
				(width 0.1)
				(type default)
			)
			(layer "F.Fab")
		)
		(fp_line
			(start 3.8354 2.52476)
			(end 0.7366 2.52476)
			(stroke
				(width 0.1)
				(type default)
			)
			(layer "F.Fab")
		)
		(fp_circle
			(center -1.454404 -0.556514)
			(end -1.327404 -0.556514)
			(stroke
				(width 0.254)
				(type default)
			)
			(fill no)
			(layer "F.Fab")
		)
		(pad "1" smd rect
			(at 0 0)
			(size 1.778 0.4572)
			(layers "F.Cu" "F.Mask" "F.Paste")
			(net "PVCCIO_CPU1")
		)
		(pad "2" smd rect
			(at 0 0.65024)
			(size 1.778 0.4572)
			(layers "F.Cu" "F.Mask" "F.Paste")
			(net "SMB_DDR_KLM_SCL_G")
		)
		(pad "3" smd rect
			(at 0 1.30048)
			(size 1.778 0.4572)
			(layers "F.Cu" "F.Mask" "F.Paste")
			(net "SMB_DDR_KLM_SDA_G")
		)
		(pad "4" smd rect
			(at 0 1.95072)
			(size 1.778 0.4572)
			(layers "F.Cu" "F.Mask" "F.Paste")
			(net "GND")
		)
		(pad "5" smd rect
			(at 4.572 1.95072)
			(size 1.778 0.4572)
			(layers "F.Cu" "F.Mask" "F.Paste")
			(net "TP_SMB_DDR_KLM_EN")
		)
		(pad "6" smd rect
			(at 4.572 1.30048)
			(size 1.778 0.4572)
			(layers "F.Cu" "F.Mask" "F.Paste")
			(net "SMB_DDR_KLM_VPP_SDA_R")
		)
		(pad "7" smd rect
			(at 4.572 0.65024)
			(size 1.778 0.4572)
			(layers "F.Cu" "F.Mask" "F.Paste")
			(net "SMB_DDR_KLM_VPP_SCL_R")
		)
		(pad "8" smd rect
			(at 4.572 0)
			(size 1.778 0.4572)
			(layers "F.Cu" "F.Mask" "F.Paste")
			(net "PVPP_KLM")
		)
	)
	(footprint ""
		(layer "F.Cu")
		(at 372.0084 -131.7498 180)
		(property "Reference" "C7B23"
			(at 0 0 180)
			(layer "F.SilkS")
			(hide yes)
			(effects
				(font
					(size 1.27 1.27)
				)
			)
		)
		(property "Value" ""
			(at 0 0 180)
			(layer "F.Fab")
			(effects
				(font
					(size 1.27 1.27)
				)
			)
		)
		(duplicate_pad_numbers_are_jumpers no)
		(fp_poly
			(pts
				(xy -0.4953 -0.2032) (xy 0.4953 -0.2032) (xy 0.4953 1.6002) (xy -0.4953 1.6002)
			)
			(stroke
				(width 0)
				(type default)
			)
			(fill no)
			(layer "F.CrtYd")
		)
		(fp_line
			(start 0.4953 1.6002)
			(end -0.4953 1.6002)
			(stroke
				(width 0.1)
				(type default)
			)
			(layer "F.Fab")
		)
		(fp_line
			(start 0.4953 -0.2032)
			(end 0.4953 1.6002)
			(stroke
				(width 0.1)
				(type default)
			)
			(layer "F.Fab")
		)
		(fp_line
			(start -0.4953 1.6002)
			(end -0.4953 -0.2032)
			(stroke
				(width 0.1)
				(type default)
			)
			(layer "F.Fab")
		)
		(fp_line
			(start -0.4953 -0.2032)
			(end 0.4953 -0.2032)
			(stroke
				(width 0.1)
				(type default)
			)
			(layer "F.Fab")
		)
		(pad "1" smd rect
			(at 0 0 180)
			(size 0.762 0.889)
			(layers "F.Cu" "F.Mask" "F.Paste")
			(net "P1V05_PCH_STBY")
		)
		(pad "2" smd rect
			(at 0 1.397 180)
			(size 0.762 0.889)
			(layers "F.Cu" "F.Mask" "F.Paste")
			(net "GND")
		)
		(zone
			(layer "F.Cu")
			(hatch none 0.5)
			(connect_pads
				(clearance 0)
			)
			(min_thickness 0.25)
			(keepout
				(tracks not_allowed)
				(vias allowed)
				(pads allowed)
				(copperpour not_allowed)
				(footprints allowed)
			)
			(placement
				(enabled no)
				(sheetname "")
			)
			(fill
				(thermal_gap 0.5)
				(thermal_bridge_width 0.5)
				(island_removal_mode 0)
			)
			(polygon
				(pts
					(xy 372.3894 -132.1943) (xy 371.6274 -132.1943) (xy 371.6274 -132.7023) (xy 372.3894 -132.7023)
				)
			)
		)
	)
	(footprint ""
		(layer "F.Cu")
		(at 163.576 -77.978 -90)
		(property "Reference" "R4D23"
			(at 0 0 270)
			(layer "F.SilkS")
			(hide yes)
			(effects
				(font
					(size 1.27 1.27)
				)
			)
		)
		(property "Value" ""
			(at 0 0 270)
			(layer "F.Fab")
			(effects
				(font
					(size 1.27 1.27)
				)
			)
		)
		(duplicate_pad_numbers_are_jumpers no)
		(fp_poly
			(pts
				(xy -0.2794 -0.1016) (xy 0.2794 -0.1016) (xy 0.2794 0.9906) (xy -0.2794 0.9906)
			)
			(stroke
				(width 0)
				(type default)
			)
			(fill no)
			(layer "F.CrtYd")
		)
		(fp_line
			(start -0.2794 0.9906)
			(end 0.2794 0.9906)
			(stroke
				(width 0.1)
				(type default)
			)
			(layer "F.Fab")
		)
		(fp_line
			(start 0.2794 0.9906)
			(end 0.2794 -0.1016)
			(stroke
				(width 0.1)
				(type default)
			)
			(layer "F.Fab")
		)
		(fp_line
			(start -0.2794 -0.1016)
			(end -0.2794 0.9906)
			(stroke
				(width 0.1)
				(type default)
			)
			(layer "F.Fab")
		)
		(fp_line
			(start 0.2794 -0.1016)
			(end -0.2794 -0.1016)
			(stroke
				(width 0.1)
				(type default)
			)
			(layer "F.Fab")
		)
		(pad "1" smd rect
			(at 0 0 270)
			(size 0.508 0.508)
			(layers "F.Cu" "F.Mask" "F.Paste")
			(net "CLK_100M_CPU1_RC_REFCLK1_R_DP")
		)
		(pad "2" smd rect
			(at 0 0.889 270)
			(size 0.508 0.508)
			(layers "F.Cu" "F.Mask" "F.Paste")
			(net "CLK_100M_CPU1_RC_REFCLK1_DP")
		)
		(zone
			(layer "F.Cu")
			(hatch none 0.5)
			(connect_pads
				(clearance 0)
			)
			(min_thickness 0.25)
			(keepout
				(tracks not_allowed)
				(vias allowed)
				(pads allowed)
				(copperpour not_allowed)
				(footprints allowed)
			)
			(placement
				(enabled no)
				(sheetname "")
			)
			(fill
				(thermal_gap 0.5)
				(thermal_bridge_width 0.5)
				(island_removal_mode 0)
			)
			(polygon
				(pts
					(xy 162.941 -78.232) (xy 162.941 -77.724) (xy 163.322 -77.724) (xy 163.322 -78.232)
				)
			)
		)
		(zone
			(layer "F.Cu")
			(hatch none 0.5)
			(connect_pads
				(clearance 0)
			)
			(min_thickness 0.25)
			(keepout
				(tracks allowed)
				(vias not_allowed)
				(pads allowed)
				(copperpour not_allowed)
				(footprints allowed)
			)
			(placement
				(enabled no)
				(sheetname "")
			)
			(fill
				(thermal_gap 0.5)
				(thermal_bridge_width 0.5)
				(island_removal_mode 0)
			)
			(polygon
				(pts
					(xy 163.322 -78.232) (xy 163.322 -77.724) (xy 162.941 -77.724) (xy 162.941 -78.232)
				)
			)
		)
	)
	(footprint ""
		(layer "F.Cu")
		(at 175.133 -131.3815 180)
		(property "Reference" "R4B8"
			(at 0 0 180)
			(layer "F.SilkS")
			(hide yes)
			(effects
				(font
					(size 1.27 1.27)
				)
			)
		)
		(property "Value" ""
			(at 0 0 180)
			(layer "F.Fab")
			(effects
				(font
					(size 1.27 1.27)
				)
			)
		)
		(duplicate_pad_numbers_are_jumpers no)
		(fp_poly
			(pts
				(xy -0.2794 -0.1016) (xy 0.2794 -0.1016) (xy 0.2794 0.9906) (xy -0.2794 0.9906)
			)
			(stroke
				(width 0)
				(type default)
			)
			(fill no)
			(layer "F.CrtYd")
		)
		(fp_line
			(start 0.2794 0.9906)
			(end 0.2794 -0.1016)
			(stroke
				(width 0.1)
				(type default)
			)
			(layer "F.Fab")
		)
		(fp_line
			(start 0.2794 -0.1016)
			(end -0.2794 -0.1016)
			(stroke
				(width 0.1)
				(type default)
			)
			(layer "F.Fab")
		)
		(fp_line
			(start -0.2794 0.9906)
			(end 0.2794 0.9906)
			(stroke
				(width 0.1)
				(type default)
			)
			(layer "F.Fab")
		)
		(fp_line
			(start -0.2794 -0.1016)
			(end -0.2794 0.9906)
			(stroke
				(width 0.1)
				(type default)
			)
			(layer "F.Fab")
		)
		(pad "1" smd rect
			(at 0 0 180)
			(size 0.508 0.508)
			(layers "F.Cu" "F.Mask" "F.Paste")
			(net "VR_COMP_RC_PVPP_KLM")
		)
		(pad "2" smd rect
			(at 0 0.889 180)
			(size 0.508 0.508)
			(layers "F.Cu" "F.Mask" "F.Paste")
			(net "VR_FB_PVPP_KLM")
		)
		(zone
			(layer "F.Cu")
			(hatch none 0.5)
			(connect_pads
				(clearance 0)
			)
			(min_thickness 0.25)
			(keepout
				(tracks not_allowed)
				(vias allowed)
				(pads allowed)
				(copperpour not_allowed)
				(footprints allowed)
			)
			(placement
				(enabled no)
				(sheetname "")
			)
			(fill
				(thermal_gap 0.5)
				(thermal_bridge_width 0.5)
				(island_removal_mode 0)
			)
			(polygon
				(pts
					(xy 175.387 -132.0165) (xy 174.879 -132.0165) (xy 174.879 -131.6355) (xy 175.387 -131.6355)
				)
			)
		)
		(zone
			(layer "F.Cu")
			(hatch none 0.5)
			(connect_pads
				(clearance 0)
			)
			(min_thickness 0.25)
			(keepout
				(tracks allowed)
				(vias not_allowed)
				(pads allowed)
				(copperpour not_allowed)
				(footprints allowed)
			)
			(placement
				(enabled no)
				(sheetname "")
			)
			(fill
				(thermal_gap 0.5)
				(thermal_bridge_width 0.5)
				(island_removal_mode 0)
			)
			(polygon
				(pts
					(xy 175.387 -131.6355) (xy 174.879 -131.6355) (xy 174.879 -132.0165) (xy 175.387 -132.0165)
				)
			)
		)
	)
	(footprint ""
		(layer "F.Cu")
		(at 406.654 -93.280992 90)
		(property "Reference" "C8C6"
			(at 0 0 90)
			(layer "F.SilkS")
			(hide yes)
			(effects
				(font
					(size 1.27 1.27)
				)
			)
		)
		(property "Value" ""
			(at 0 0 90)
			(layer "F.Fab")
			(effects
				(font
					(size 1.27 1.27)
				)
			)
		)
		(duplicate_pad_numbers_are_jumpers no)
		(fp_poly
			(pts
				(xy -0.4953 -0.2032) (xy 0.4953 -0.2032) (xy 0.4953 1.6002) (xy -0.4953 1.6002)
			)
			(stroke
				(width 0)
				(type default)
			)
			(fill no)
			(layer "F.CrtYd")
		)
		(fp_line
			(start 0.4953 -0.2032)
			(end 0.4953 1.6002)
			(stroke
				(width 0.1)
				(type default)
			)
			(layer "F.Fab")
		)
		(fp_line
			(start -0.4953 -0.2032)
			(end 0.4953 -0.2032)
			(stroke
				(width 0.1)
				(type default)
			)
			(layer "F.Fab")
		)
		(fp_line
			(start 0.4953 1.6002)
			(end -0.4953 1.6002)
			(stroke
				(width 0.1)
				(type default)
			)
			(layer "F.Fab")
		)
		(fp_line
			(start -0.4953 1.6002)
			(end -0.4953 -0.2032)
			(stroke
				(width 0.1)
				(type default)
			)
			(layer "F.Fab")
		)
		(pad "1" smd rect
			(at 0 0 90)
			(size 0.762 0.889)
			(layers "F.Cu" "F.Mask" "F.Paste")
			(net "P3V3_STBY")
		)
		(pad "2" smd rect
			(at 0 1.397 90)
			(size 0.762 0.889)
			(layers "F.Cu" "F.Mask" "F.Paste")
			(net "GND")
		)
		(zone
			(layer "F.Cu")
			(hatch none 0.5)
			(connect_pads
				(clearance 0)
			)
			(min_thickness 0.25)
			(keepout
				(tracks not_allowed)
				(vias allowed)
				(pads allowed)
				(copperpour not_allowed)
				(footprints allowed)
			)
			(placement
				(enabled no)
				(sheetname "")
			)
			(fill
				(thermal_gap 0.5)
				(thermal_bridge_width 0.5)
				(island_removal_mode 0)
			)
			(polygon
				(pts
					(xy 407.0985 -92.899992) (xy 407.0985 -93.661992) (xy 407.6065 -93.661992) (xy 407.6065 -92.899992)
				)
			)
		)
	)
	(footprint ""
		(layer "F.Cu")
		(at 164.465 -74.803)
		(property "Reference" "C4D23"
			(at 0 0 0)
			(layer "F.SilkS")
			(hide yes)
			(effects
				(font
					(size 1.27 1.27)
				)
			)
		)
		(property "Value" ""
			(at 0 0 0)
			(layer "F.Fab")
			(effects
				(font
					(size 1.27 1.27)
				)
			)
		)
		(duplicate_pad_numbers_are_jumpers no)
		(fp_poly
			(pts
				(xy 0.3048 -0.1016) (xy 0.3048 0.9906) (xy -0.3048 0.9906) (xy -0.3048 -0.1016)
			)
			(stroke
				(width 0)
				(type default)
			)
			(fill no)
			(layer "F.CrtYd")
		)
		(fp_line
			(start -0.3048 -0.1016)
			(end -0.3048 0.9906)
			(stroke
				(width 0.1)
				(type default)
			)
			(layer "F.Fab")
		)
		(fp_line
			(start -0.3048 0.9906)
			(end 0.3048 0.9906)
			(stroke
				(width 0.1)
				(type default)
			)
			(layer "F.Fab")
		)
		(fp_line
			(start 0.3048 -0.1016)
			(end -0.3048 -0.1016)
			(stroke
				(width 0.1)
				(type default)
			)
			(layer "F.Fab")
		)
		(fp_line
			(start 0.3048 0.9906)
			(end 0.3048 -0.1016)
			(stroke
				(width 0.1)
				(type default)
			)
			(layer "F.Fab")
		)
		(pad "1" smd rect
			(at 0 0)
			(size 0.508 0.508)
			(layers "F.Cu" "F.Mask" "F.Paste")
			(net "P3V3_DB1200_A")
		)
		(pad "2" smd rect
			(at 0 0.889)
			(size 0.508 0.508)
			(layers "F.Cu" "F.Mask" "F.Paste")
			(net "GND")
		)
		(zone
			(layer "F.Cu")
			(hatch none 0.5)
			(connect_pads
				(clearance 0)
			)
			(min_thickness 0.25)
			(keepout
				(tracks allowed)
				(vias not_allowed)
				(pads allowed)
				(copperpour not_allowed)
				(footprints allowed)
			)
			(placement
				(enabled no)
				(sheetname "")
			)
			(fill
				(thermal_gap 0.5)
				(thermal_bridge_width 0.5)
				(island_removal_mode 0)
			)
			(polygon
				(pts
					(xy 164.211 -74.549) (xy 164.719 -74.549) (xy 164.719 -74.168) (xy 164.211 -74.168)
				)
			)
		)
		(zone
			(layer "F.Cu")
			(hatch none 0.5)
			(connect_pads
				(clearance 0)
			)
			(min_thickness 0.25)
			(keepout
				(tracks not_allowed)
				(vias allowed)
				(pads allowed)
				(copperpour not_allowed)
				(footprints allowed)
			)
			(placement
				(enabled no)
				(sheetname "")
			)
			(fill
				(thermal_gap 0.5)
				(thermal_bridge_width 0.5)
				(island_removal_mode 0)
			)
			(polygon
				(pts
					(xy 164.211 -74.168) (xy 164.719 -74.168) (xy 164.719 -74.549) (xy 164.211 -74.549)
				)
			)
		)
	)
	(footprint ""
		(layer "F.Cu")
		(at 104.40924 -77.636116)
		(property "Reference" "C2D28"
			(at 0 0 0)
			(layer "F.SilkS")
			(hide yes)
			(effects
				(font
					(size 1.27 1.27)
				)
			)
		)
		(property "Value" ""
			(at 0 0 0)
			(layer "F.Fab")
			(effects
				(font
					(size 1.27 1.27)
				)
			)
		)
		(duplicate_pad_numbers_are_jumpers no)
		(fp_poly
			(pts
				(xy -0.4953 -0.2032) (xy 0.4953 -0.2032) (xy 0.4953 1.6002) (xy -0.4953 1.6002)
			)
			(stroke
				(width 0)
				(type default)
			)
			(fill no)
			(layer "F.CrtYd")
		)
		(fp_line
			(start -0.4953 -0.2032)
			(end 0.4953 -0.2032)
			(stroke
				(width 0.1)
				(type default)
			)
			(layer "F.Fab")
		)
		(fp_line
			(start -0.4953 1.6002)
			(end -0.4953 -0.2032)
			(stroke
				(width 0.1)
				(type default)
			)
			(layer "F.Fab")
		)
		(fp_line
			(start 0.4953 -0.2032)
			(end 0.4953 1.6002)
			(stroke
				(width 0.1)
				(type default)
			)
			(layer "F.Fab")
		)
		(fp_line
			(start 0.4953 1.6002)
			(end -0.4953 1.6002)
			(stroke
				(width 0.1)
				(type default)
			)
			(layer "F.Fab")
		)
		(pad "1" smd rect
			(at 0 0)
			(size 0.762 0.889)
			(layers "F.Cu" "F.Mask" "F.Paste")
			(net "PVCCMCP_CPU1")
		)
		(pad "2" smd rect
			(at 0 1.397)
			(size 0.762 0.889)
			(layers "F.Cu" "F.Mask" "F.Paste")
			(net "GND")
		)
		(zone
			(layer "F.Cu")
			(hatch none 0.5)
			(connect_pads
				(clearance 0)
			)
			(min_thickness 0.25)
			(keepout
				(tracks not_allowed)
				(vias allowed)
				(pads allowed)
				(copperpour not_allowed)
				(footprints allowed)
			)
			(placement
				(enabled no)
				(sheetname "")
			)
			(fill
				(thermal_gap 0.5)
				(thermal_bridge_width 0.5)
				(island_removal_mode 0)
			)
			(polygon
				(pts
					(xy 104.02824 -77.191616) (xy 104.79024 -77.191616) (xy 104.79024 -76.683616) (xy 104.02824 -76.683616)
				)
			)
		)
	)
	(footprint ""
		(layer "F.Cu")
		(at 347.988636 -141.454378 -90)
		(property "Reference" "C7A20"
			(at 0 0 270)
			(layer "F.SilkS")
			(hide yes)
			(effects
				(font
					(size 1.27 1.27)
				)
			)
		)
		(property "Value" ""
			(at 0 0 270)
			(layer "F.Fab")
			(effects
				(font
					(size 1.27 1.27)
				)
			)
		)
		(duplicate_pad_numbers_are_jumpers no)
		(fp_poly
			(pts
				(xy 0.3048 -0.1016) (xy 0.3048 0.9906) (xy -0.3048 0.9906) (xy -0.3048 -0.1016)
			)
			(stroke
				(width 0)
				(type default)
			)
			(fill no)
			(layer "F.CrtYd")
		)
		(fp_line
			(start -0.3048 0.9906)
			(end 0.3048 0.9906)
			(stroke
				(width 0.1)
				(type default)
			)
			(layer "F.Fab")
		)
		(fp_line
			(start 0.3048 0.9906)
			(end 0.3048 -0.1016)
			(stroke
				(width 0.1)
				(type default)
			)
			(layer "F.Fab")
		)
		(fp_line
			(start -0.3048 -0.1016)
			(end -0.3048 0.9906)
			(stroke
				(width 0.1)
				(type default)
			)
			(layer "F.Fab")
		)
		(fp_line
			(start 0.3048 -0.1016)
			(end -0.3048 -0.1016)
			(stroke
				(width 0.1)
				(type default)
			)
			(layer "F.Fab")
		)
		(pad "1" smd rect
			(at 0 0 270)
			(size 0.508 0.508)
			(layers "F.Cu" "F.Mask" "F.Paste")
			(net "VR_FET_SW_P12V_STBY_PVDDQ_DEF")
		)
		(pad "2" smd rect
			(at 0 0.889 270)
			(size 0.508 0.508)
			(layers "F.Cu" "F.Mask" "F.Paste")
			(net "GND")
		)
		(zone
			(layer "F.Cu")
			(hatch none 0.5)
			(connect_pads
				(clearance 0)
			)
			(min_thickness 0.25)
			(keepout
				(tracks not_allowed)
				(vias allowed)
				(pads allowed)
				(copperpour not_allowed)
				(footprints allowed)
			)
			(placement
				(enabled no)
				(sheetname "")
			)
			(fill
				(thermal_gap 0.5)
				(thermal_bridge_width 0.5)
				(island_removal_mode 0)
			)
			(polygon
				(pts
					(xy 347.353636 -141.708378) (xy 347.353636 -141.200378) (xy 347.734636 -141.200378) (xy 347.734636 -141.708378)
				)
			)
		)
		(zone
			(layer "F.Cu")
			(hatch none 0.5)
			(connect_pads
				(clearance 0)
			)
			(min_thickness 0.25)
			(keepout
				(tracks allowed)
				(vias not_allowed)
				(pads allowed)
				(copperpour not_allowed)
				(footprints allowed)
			)
			(placement
				(enabled no)
				(sheetname "")
			)
			(fill
				(thermal_gap 0.5)
				(thermal_bridge_width 0.5)
				(island_removal_mode 0)
			)
			(polygon
				(pts
					(xy 347.734636 -141.708378) (xy 347.734636 -141.200378) (xy 347.353636 -141.200378) (xy 347.353636 -141.708378)
				)
			)
		)
	)
	(footprint ""
		(layer "F.Cu")
		(at 445.91732 -24.47798)
		(property "Reference" "C25W14"
			(at -0.8382 -0.67818 0)
			(unlocked yes)
			(layer "F.SilkS")
			(effects
				(font
					(size 0.4064 0.254)
					(thickness 0.1524)
				)
				(justify left)
			)
		)
		(property "Value" ""
			(at 0 0 0)
			(layer "F.Fab")
			(effects
				(font
					(size 1.27 1.27)
				)
			)
		)
		(duplicate_pad_numbers_are_jumpers no)
		(fp_poly
			(pts
				(xy 0.3048 -0.1016) (xy 0.3048 0.9906) (xy -0.3048 0.9906) (xy -0.3048 -0.1016)
			)
			(stroke
				(width 0)
				(type default)
			)
			(fill no)
			(layer "F.CrtYd")
		)
		(fp_line
			(start -0.3048 -0.1016)
			(end -0.3048 0.9906)
			(stroke
				(width 0.1)
				(type default)
			)
			(layer "F.Fab")
		)
		(fp_line
			(start -0.3048 0.9906)
			(end 0.3048 0.9906)
			(stroke
				(width 0.1)
				(type default)
			)
			(layer "F.Fab")
		)
		(fp_line
			(start 0.3048 -0.1016)
			(end -0.3048 -0.1016)
			(stroke
				(width 0.1)
				(type default)
			)
			(layer "F.Fab")
		)
		(fp_line
			(start 0.3048 0.9906)
			(end 0.3048 -0.1016)
			(stroke
				(width 0.1)
				(type default)
			)
			(layer "F.Fab")
		)
		(pad "1" smd rect
			(at 0 0)
			(size 0.508 0.508)
			(layers "F.Cu" "F.Mask" "F.Paste")
			(net "P2V5_AUX_BMC")
		)
		(pad "2" smd rect
			(at 0 0.889)
			(size 0.508 0.508)
			(layers "F.Cu" "F.Mask" "F.Paste")
			(net "GND")
		)
		(zone
			(layer "F.Cu")
			(hatch none 0.5)
			(connect_pads
				(clearance 0)
			)
			(min_thickness 0.25)
			(keepout
				(tracks allowed)
				(vias not_allowed)
				(pads allowed)
				(copperpour not_allowed)
				(footprints allowed)
			)
			(placement
				(enabled no)
				(sheetname "")
			)
			(fill
				(thermal_gap 0.5)
				(thermal_bridge_width 0.5)
				(island_removal_mode 0)
			)
			(polygon
				(pts
					(xy 445.66332 -24.22398) (xy 446.17132 -24.22398) (xy 446.17132 -23.84298) (xy 445.66332 -23.84298)
				)
			)
		)
		(zone
			(layer "F.Cu")
			(hatch none 0.5)
			(connect_pads
				(clearance 0)
			)
			(min_thickness 0.25)
			(keepout
				(tracks not_allowed)
				(vias allowed)
				(pads allowed)
				(copperpour not_allowed)
				(footprints allowed)
			)
			(placement
				(enabled no)
				(sheetname "")
			)
			(fill
				(thermal_gap 0.5)
				(thermal_bridge_width 0.5)
				(island_removal_mode 0)
			)
			(polygon
				(pts
					(xy 445.66332 -23.84298) (xy 446.17132 -23.84298) (xy 446.17132 -24.22398) (xy 445.66332 -24.22398)
				)
			)
		)
	)
	(footprint ""
		(layer "F.Cu")
		(at 417.398454 -105.34777 180)
		(property "Reference" "C9W8"
			(at -0.8382 -0.67818 180)
			(unlocked yes)
			(layer "F.SilkS")
			(effects
				(font
					(size 0.4064 0.254)
					(thickness 0.1524)
				)
				(justify left)
			)
		)
		(property "Value" ""
			(at 0 0 180)
			(layer "F.Fab")
			(effects
				(font
					(size 1.27 1.27)
				)
			)
		)
		(duplicate_pad_numbers_are_jumpers no)
		(fp_poly
			(pts
				(xy 0.3048 -0.1016) (xy 0.3048 0.9906) (xy -0.3048 0.9906) (xy -0.3048 -0.1016)
			)
			(stroke
				(width 0)
				(type default)
			)
			(fill no)
			(layer "F.CrtYd")
		)
		(fp_line
			(start 0.3048 0.9906)
			(end 0.3048 -0.1016)
			(stroke
				(width 0.1)
				(type default)
			)
			(layer "F.Fab")
		)
		(fp_line
			(start 0.3048 -0.1016)
			(end -0.3048 -0.1016)
			(stroke
				(width 0.1)
				(type default)
			)
			(layer "F.Fab")
		)
		(fp_line
			(start -0.3048 0.9906)
			(end 0.3048 0.9906)
			(stroke
				(width 0.1)
				(type default)
			)
			(layer "F.Fab")
		)
		(fp_line
			(start -0.3048 -0.1016)
			(end -0.3048 0.9906)
			(stroke
				(width 0.1)
				(type default)
			)
			(layer "F.Fab")
		)
		(pad "1" smd rect
			(at 0 0 180)
			(size 0.508 0.508)
			(layers "F.Cu" "F.Mask" "F.Paste")
			(net "PVCCIO_CPU0")
		)
		(pad "2" smd rect
			(at 0 0.889 180)
			(size 0.508 0.508)
			(layers "F.Cu" "F.Mask" "F.Paste")
			(net "GND")
		)
		(zone
			(layer "F.Cu")
			(hatch none 0.5)
			(connect_pads
				(clearance 0)
			)
			(min_thickness 0.25)
			(keepout
				(tracks not_allowed)
				(vias allowed)
				(pads allowed)
				(copperpour not_allowed)
				(footprints allowed)
			)
			(placement
				(enabled no)
				(sheetname "")
			)
			(fill
				(thermal_gap 0.5)
				(thermal_bridge_width 0.5)
				(island_removal_mode 0)
			)
			(polygon
				(pts
					(xy 417.652454 -105.98277) (xy 417.144454 -105.98277) (xy 417.144454 -105.60177) (xy 417.652454 -105.60177)
				)
			)
		)
		(zone
			(layer "F.Cu")
			(hatch none 0.5)
			(connect_pads
				(clearance 0)
			)
			(min_thickness 0.25)
			(keepout
				(tracks allowed)
				(vias not_allowed)
				(pads allowed)
				(copperpour not_allowed)
				(footprints allowed)
			)
			(placement
				(enabled no)
				(sheetname "")
			)
			(fill
				(thermal_gap 0.5)
				(thermal_bridge_width 0.5)
				(island_removal_mode 0)
			)
			(polygon
				(pts
					(xy 417.652454 -105.60177) (xy 417.144454 -105.60177) (xy 417.144454 -105.98277) (xy 417.652454 -105.98277)
				)
			)
		)
	)
	(footprint ""
		(layer "F.Cu")
		(at 394.589 -85.0265 180)
		(property "Reference" "R2U11"
			(at 0 0 180)
			(layer "F.SilkS")
			(hide yes)
			(effects
				(font
					(size 1.27 1.27)
				)
			)
		)
		(property "Value" ""
			(at 0 0 180)
			(layer "F.Fab")
			(effects
				(font
					(size 1.27 1.27)
				)
			)
		)
		(duplicate_pad_numbers_are_jumpers no)
		(fp_poly
			(pts
				(xy -0.2794 -0.1016) (xy 0.2794 -0.1016) (xy 0.2794 0.9906) (xy -0.2794 0.9906)
			)
			(stroke
				(width 0)
				(type default)
			)
			(fill no)
			(layer "F.CrtYd")
		)
		(fp_line
			(start 0.2794 0.9906)
			(end 0.2794 -0.1016)
			(stroke
				(width 0.1)
				(type default)
			)
			(layer "F.Fab")
		)
		(fp_line
			(start 0.2794 -0.1016)
			(end -0.2794 -0.1016)
			(stroke
				(width 0.1)
				(type default)
			)
			(layer "F.Fab")
		)
		(fp_line
			(start -0.2794 0.9906)
			(end 0.2794 0.9906)
			(stroke
				(width 0.1)
				(type default)
			)
			(layer "F.Fab")
		)
		(fp_line
			(start -0.2794 -0.1016)
			(end -0.2794 0.9906)
			(stroke
				(width 0.1)
				(type default)
			)
			(layer "F.Fab")
		)
		(pad "1" smd rect
			(at 0 0 180)
			(size 0.508 0.508)
			(layers "F.Cu" "F.Mask" "F.Paste")
			(net "P3V3_STBY")
		)
		(pad "2" smd rect
			(at 0 0.889 180)
			(size 0.508 0.508)
			(layers "F.Cu" "F.Mask" "F.Paste")
			(net "SMB_LAN_STBY_LVC3_SDA")
		)
		(zone
			(layer "F.Cu")
			(hatch none 0.5)
			(connect_pads
				(clearance 0)
			)
			(min_thickness 0.25)
			(keepout
				(tracks not_allowed)
				(vias allowed)
				(pads allowed)
				(copperpour not_allowed)
				(footprints allowed)
			)
			(placement
				(enabled no)
				(sheetname "")
			)
			(fill
				(thermal_gap 0.5)
				(thermal_bridge_width 0.5)
				(island_removal_mode 0)
			)
			(polygon
				(pts
					(xy 394.843 -85.6615) (xy 394.335 -85.6615) (xy 394.335 -85.2805) (xy 394.843 -85.2805)
				)
			)
		)
		(zone
			(layer "F.Cu")
			(hatch none 0.5)
			(connect_pads
				(clearance 0)
			)
			(min_thickness 0.25)
			(keepout
				(tracks allowed)
				(vias not_allowed)
				(pads allowed)
				(copperpour not_allowed)
				(footprints allowed)
			)
			(placement
				(enabled no)
				(sheetname "")
			)
			(fill
				(thermal_gap 0.5)
				(thermal_bridge_width 0.5)
				(island_removal_mode 0)
			)
			(polygon
				(pts
					(xy 394.843 -85.2805) (xy 394.335 -85.2805) (xy 394.335 -85.6615) (xy 394.843 -85.6615)
				)
			)
		)
	)
	(footprint ""
		(layer "F.Cu")
		(at 166.116 -86.868 180)
		(property "Reference" "R4D2"
			(at 0 0 180)
			(layer "F.SilkS")
			(hide yes)
			(effects
				(font
					(size 1.27 1.27)
				)
			)
		)
		(property "Value" ""
			(at 0 0 180)
			(layer "F.Fab")
			(effects
				(font
					(size 1.27 1.27)
				)
			)
		)
		(duplicate_pad_numbers_are_jumpers no)
		(fp_poly
			(pts
				(xy -0.2794 -0.1016) (xy 0.2794 -0.1016) (xy 0.2794 0.9906) (xy -0.2794 0.9906)
			)
			(stroke
				(width 0)
				(type default)
			)
			(fill no)
			(layer "F.CrtYd")
		)
		(fp_line
			(start 0.2794 0.9906)
			(end 0.2794 -0.1016)
			(stroke
				(width 0.1)
				(type default)
			)
			(layer "F.Fab")
		)
		(fp_line
			(start 0.2794 -0.1016)
			(end -0.2794 -0.1016)
			(stroke
				(width 0.1)
				(type default)
			)
			(layer "F.Fab")
		)
		(fp_line
			(start -0.2794 0.9906)
			(end 0.2794 0.9906)
			(stroke
				(width 0.1)
				(type default)
			)
			(layer "F.Fab")
		)
		(fp_line
			(start -0.2794 -0.1016)
			(end -0.2794 0.9906)
			(stroke
				(width 0.1)
				(type default)
			)
			(layer "F.Fab")
		)
		(pad "1" smd rect
			(at 0 0 180)
			(size 0.508 0.508)
			(layers "F.Cu" "F.Mask" "F.Paste")
			(net "CLK_100M_CPU1_BCLK1_R_DP")
		)
		(pad "2" smd rect
			(at 0 0.889 180)
			(size 0.508 0.508)
			(layers "F.Cu" "F.Mask" "F.Paste")
			(net "CLK_100M_CPU1_BCLK1_DP")
		)
		(zone
			(layer "F.Cu")
			(hatch none 0.5)
			(connect_pads
				(clearance 0)
			)
			(min_thickness 0.25)
			(keepout
				(tracks not_allowed)
				(vias allowed)
				(pads allowed)
				(copperpour not_allowed)
				(footprints allowed)
			)
			(placement
				(enabled no)
				(sheetname "")
			)
			(fill
				(thermal_gap 0.5)
				(thermal_bridge_width 0.5)
				(island_removal_mode 0)
			)
			(polygon
				(pts
					(xy 166.37 -87.503) (xy 165.862 -87.503) (xy 165.862 -87.122) (xy 166.37 -87.122)
				)
			)
		)
		(zone
			(layer "F.Cu")
			(hatch none 0.5)
			(connect_pads
				(clearance 0)
			)
			(min_thickness 0.25)
			(keepout
				(tracks allowed)
				(vias not_allowed)
				(pads allowed)
				(copperpour not_allowed)
				(footprints allowed)
			)
			(placement
				(enabled no)
				(sheetname "")
			)
			(fill
				(thermal_gap 0.5)
				(thermal_bridge_width 0.5)
				(island_removal_mode 0)
			)
			(polygon
				(pts
					(xy 166.37 -87.122) (xy 165.862 -87.122) (xy 165.862 -87.503) (xy 166.37 -87.503)
				)
			)
		)
	)
	(footprint ""
		(layer "F.Cu")
		(at 80.757268 -149.8092 -90)
		(property "Reference" "C2A1"
			(at 1.848866 0.752348 270)
			(unlocked yes)
			(layer "F.SilkS")
			(effects
				(font
					(size 1.27 0.9652)
					(thickness 0.1524)
				)
			)
		)
		(property "Value" ""
			(at 0 0 270)
			(layer "F.Fab")
			(effects
				(font
					(size 1.27 1.27)
				)
			)
		)
		(duplicate_pad_numbers_are_jumpers no)
		(fp_rect
			(start -0.500126 1.598422)
			(end 0.500126 -0.201422)
			(stroke
				(width 0)
				(type default)
			)
			(fill no)
			(layer "F.CrtYd")
		)
		(fp_line
			(start -0.500126 1.598422)
			(end -0.500126 -0.201422)
			(stroke
				(width 0.1)
				(type default)
			)
			(layer "F.Fab")
		)
		(fp_line
			(start 0.500126 1.598422)
			(end -0.500126 1.598422)
			(stroke
				(width 0.1)
				(type default)
			)
			(layer "F.Fab")
		)
		(fp_line
			(start -0.500126 -0.201422)
			(end 0.500126 -0.201422)
			(stroke
				(width 0.1)
				(type default)
			)
			(layer "F.Fab")
		)
		(fp_line
			(start 0.500126 -0.201422)
			(end 0.500126 1.598422)
			(stroke
				(width 0.1)
				(type default)
			)
			(layer "F.Fab")
		)
		(pad "1" smd rect
			(at 0 0 180)
			(size 0.889 0.9906)
			(layers "F.Cu" "F.Mask" "F.Paste")
			(net "PVDDQ_KLM")
		)
		(pad "2" smd rect
			(at 0 1.397 180)
			(size 0.889 0.9906)
			(layers "F.Cu" "F.Mask" "F.Paste")
			(net "GND")
		)
		(zone
			(layer "F.Cu")
			(hatch none 0.5)
			(connect_pads
				(clearance 0)
			)
			(min_thickness 0.25)
			(keepout
				(tracks not_allowed)
				(vias allowed)
				(pads allowed)
				(copperpour not_allowed)
				(footprints allowed)
			)
			(placement
				(enabled no)
				(sheetname "")
			)
			(fill
				(thermal_gap 0.5)
				(thermal_bridge_width 0.5)
				(island_removal_mode 0)
			)
			(polygon
				(pts
					(xy 79.804768 -150.3045) (xy 79.804768 -149.3139) (xy 80.312768 -149.3139) (xy 80.312768 -150.3045)
				)
			)
		)
		(zone
			(layer "F.Cu")
			(hatch none 0.5)
			(connect_pads
				(clearance 0)
			)
			(min_thickness 0.25)
			(keepout
				(tracks allowed)
				(vias not_allowed)
				(pads allowed)
				(copperpour not_allowed)
				(footprints allowed)
			)
			(placement
				(enabled no)
				(sheetname "")
			)
			(fill
				(thermal_gap 0.5)
				(thermal_bridge_width 0.5)
				(island_removal_mode 0)
			)
			(polygon
				(pts
					(xy 79.804768 -150.3045) (xy 79.804768 -149.3139) (xy 80.312768 -149.3139) (xy 80.312768 -150.3045)
				)
			)
		)
	)
	(footprint ""
		(layer "F.Cu")
		(at 329.594972 -43.80103 90)
		(property "Reference" "J6E1"
			(at -3.59283 -5.018024 90)
			(unlocked yes)
			(layer "F.SilkS")
			(effects
				(font
					(size 0.7874 0.5842)
					(thickness 0.1524)
				)
			)
		)
		(property "Value" ""
			(at 0 0 90)
			(layer "F.Fab")
			(effects
				(font
					(size 1.27 1.27)
				)
			)
		)
		(duplicate_pad_numbers_are_jumpers no)
		(fp_line
			(start -0.381 -3.81)
			(end -5.969 -3.81)
			(stroke
				(width 0.1524)
				(type default)
			)
			(layer "F.SilkS")
		)
		(fp_line
			(start -5.969 -3.81)
			(end -5.969 -3.048)
			(stroke
				(width 0.1524)
				(type default)
			)
			(layer "F.SilkS")
		)
		(fp_line
			(start -5.969 -3.048)
			(end -7.2771 -3.048)
			(stroke
				(width 0.1524)
				(type default)
			)
			(layer "F.SilkS")
		)
		(fp_line
			(start -7.2771 -3.048)
			(end -7.2771 28.194)
			(stroke
				(width 0.1524)
				(type default)
			)
			(layer "F.SilkS")
		)
		(fp_line
			(start 0.9271 28.194)
			(end 0.9271 -1.703832)
			(stroke
				(width 0.1524)
				(type default)
			)
			(layer "F.SilkS")
		)
		(fp_line
			(start -7.2771 28.194)
			(end 0.9271 28.194)
			(stroke
				(width 0.1524)
				(type default)
			)
			(layer "F.SilkS")
		)
		(fp_poly
			(pts
				(xy 1.661668 0.048006) (xy 2.931668 0.556006) (xy 2.931668 -0.459994)
			)
			(stroke
				(width 0)
				(type default)
			)
			(fill yes)
			(layer "F.SilkS")
		)
		(fp_poly
			(pts
				(xy -7.2771 28.194) (xy -7.2771 -3.048) (xy -5.969 -3.048) (xy -5.969 -3.81) (xy -0.381 -3.81) (xy -0.381 -3.048)
				(xy 0.9271 -3.048) (xy 0.9271 28.194)
			)
			(stroke
				(width 0)
				(type default)
			)
			(fill no)
			(layer "F.CrtYd")
		)
		(fp_line
			(start -0.381 -3.81)
			(end -0.381 -3.048)
			(stroke
				(width 0.1)
				(type default)
			)
			(layer "F.Fab")
		)
		(fp_line
			(start -5.969 -3.81)
			(end -0.381 -3.81)
			(stroke
				(width 0.1)
				(type default)
			)
			(layer "F.Fab")
		)
		(fp_line
			(start 0.9271 -3.048)
			(end 0.9271 28.194)
			(stroke
				(width 0.1)
				(type default)
			)
			(layer "F.Fab")
		)
		(fp_line
			(start -0.381 -3.048)
			(end 0.9271 -3.048)
			(stroke
				(width 0.1)
				(type default)
			)
			(layer "F.Fab")
		)
		(fp_line
			(start -5.969 -3.048)
			(end -5.969 -3.81)
			(stroke
				(width 0.1)
				(type default)
			)
			(layer "F.Fab")
		)
		(fp_line
			(start -7.2771 -3.048)
			(end -5.969 -3.048)
			(stroke
				(width 0.1)
				(type default)
			)
			(layer "F.Fab")
		)
		(fp_line
			(start -7.2771 28.1686)
			(end -7.2771 -3.048)
			(stroke
				(width 0.1)
				(type default)
			)
			(layer "F.Fab")
		)
		(fp_line
			(start 0.9271 28.194)
			(end -7.2771 28.194)
			(stroke
				(width 0.1)
				(type default)
			)
			(layer "F.Fab")
		)
		(fp_line
			(start -7.2771 28.194)
			(end -7.2771 28.1686)
			(stroke
				(width 0.1)
				(type default)
			)
			(layer "F.Fab")
		)
		(fp_poly
			(pts
				(xy 1.661668 0.048006) (xy 2.931668 -0.459994) (xy 2.931668 0.556006)
			)
			(stroke
				(width 0)
				(type default)
			)
			(fill yes)
			(layer "F.Fab")
		)
		(fp_text user "F1"
			(at -7.935214 -0.6096 0)
			(unlocked yes)
			(layer "F.SilkS")
			(effects
				(font
					(size 0.7874 0.5842)
					(thickness 0.1524)
				)
				(justify left)
			)
		)
		(fp_text user "A20"
			(at 1.631442 23.46579 0)
			(unlocked yes)
			(layer "F.SilkS")
			(effects
				(font
					(size 0.7874 0.5842)
					(thickness 0.1524)
				)
				(justify left)
			)
		)
		(fp_text user "F20"
			(at -8.040878 24.58085 0)
			(unlocked yes)
			(layer "F.SilkS")
			(effects
				(font
					(size 0.7874 0.5842)
					(thickness 0.1524)
				)
				(justify left)
			)
		)
		(pad "" np_thru_hole circle
			(at -3.175 26.5557 90)
			(size 0.254 0.254)
			(drill 1.27)
			(layers "*.Cu" "*.Mask")
			(clearance 0.8255)
			(thermal_gap 0.8255)
		)
		(pad "" np_thru_hole circle
			(at -0.127 -2.4257 90)
			(size 0.254 0.254)
			(drill 1.27)
			(layers "*.Cu" "*.Mask")
			(clearance 0.8255)
			(thermal_gap 0.8255)
		)
		(pad "A1" smd circle
			(at 0 0 90)
			(size 0.635 0.635)
			(layers "F.Cu" "F.Mask" "F.Paste")
			(net "PVCCMCP_CPU0")
		)
		(pad "A2" smd circle
			(at 0 1.27 90)
			(size 0.635 0.635)
			(layers "F.Cu" "F.Mask" "F.Paste")
			(net "PVCCMCP_CPU0")
		)
		(pad "A3" smd circle
			(at 0 2.54 90)
			(size 0.635 0.635)
			(layers "F.Cu" "F.Mask" "F.Paste")
			(net "PVCCMCP_CPU0")
		)
		(pad "A4" smd circle
			(at 0 3.81 90)
			(size 0.635 0.635)
			(layers "F.Cu" "F.Mask" "F.Paste")
			(net "VSENSE_PVCCMCP_CPU0_SKT_VSEN")
		)
		(pad "A5" smd circle
			(at 0 5.08 90)
			(size 0.635 0.635)
			(layers "F.Cu" "F.Mask" "F.Paste")
			(net "PVCCMCP_CPU0")
		)
		(pad "A6" smd circle
			(at 0 6.35 90)
			(size 0.635 0.635)
			(layers "F.Cu" "F.Mask" "F.Paste")
			(net "PVCCMCP_CPU0")
		)
		(pad "A7" smd circle
			(at 0 7.62 90)
			(size 0.635 0.635)
			(layers "F.Cu" "F.Mask" "F.Paste")
			(net "PVCCMCP_CPU0")
		)
		(pad "A8" smd circle
			(at 0 8.89 90)
			(size 0.635 0.635)
			(layers "F.Cu" "F.Mask" "F.Paste")
			(net "PVCCMCP_CPU0")
		)
		(pad "A9" smd circle
			(at 0 10.16 90)
			(size 0.635 0.635)
			(layers "F.Cu" "F.Mask" "F.Paste")
			(net "PVCCMCP_CPU0")
		)
		(pad "A10" smd circle
			(at 0 11.43 90)
			(size 0.635 0.635)
			(layers "F.Cu" "F.Mask" "F.Paste")
			(net "PVCCMCP_CPU0")
		)
		(pad "A11" smd circle
			(at 0 12.7 90)
			(size 0.635 0.635)
			(layers "F.Cu" "F.Mask" "F.Paste")
			(net "PVCCMCP_CPU0")
		)
		(pad "A12" smd circle
			(at 0 13.97 90)
			(size 0.635 0.635)
			(layers "F.Cu" "F.Mask" "F.Paste")
			(net "PVCCMCP_CPU0")
		)
		(pad "A13" smd circle
			(at 0 15.24 90)
			(size 0.635 0.635)
			(layers "F.Cu" "F.Mask" "F.Paste")
			(net "PVCCMCP_CPU0")
		)
		(pad "A14" smd circle
			(at 0 16.51 90)
			(size 0.635 0.635)
			(layers "F.Cu" "F.Mask" "F.Paste")
			(net "PVCCMCP_CPU0")
		)
		(pad "A15" smd circle
			(at 0 17.78 90)
			(size 0.635 0.635)
			(layers "F.Cu" "F.Mask" "F.Paste")
			(net "PVCCMCP_CPU0")
		)
		(pad "A16" smd circle
			(at 0 19.05 90)
			(size 0.635 0.635)
			(layers "F.Cu" "F.Mask" "F.Paste")
			(net "PVCCMCP_CPU0")
		)
		(pad "A17" smd circle
			(at 0 20.32 90)
			(size 0.635 0.635)
			(layers "F.Cu" "F.Mask" "F.Paste")
			(net "PVCCMCP_CPU0")
		)
		(pad "A18" smd circle
			(at 0 21.59 90)
			(size 0.635 0.635)
			(layers "F.Cu" "F.Mask" "F.Paste")
			(net "PVCCMCP_CPU0")
		)
		(pad "A19" smd circle
			(at 0 22.86 90)
			(size 0.635 0.635)
			(layers "F.Cu" "F.Mask" "F.Paste")
			(net "GND")
		)
		(pad "A20" smd circle
			(at 0 24.13 90)
			(size 0.635 0.635)
			(layers "F.Cu" "F.Mask" "F.Paste")
			(net "GND")
		)
		(pad "B1" smd circle
			(at -1.27 0 90)
			(size 0.635 0.635)
			(layers "F.Cu" "F.Mask" "F.Paste")
			(net "PVCCMCP_CPU0")
		)
		(pad "B2" smd circle
			(at -1.27 1.27 90)
			(size 0.635 0.635)
			(layers "F.Cu" "F.Mask" "F.Paste")
			(net "PVCCMCP_CPU0")
		)
		(pad "B3" smd circle
			(at -1.27 2.54 90)
			(size 0.635 0.635)
			(layers "F.Cu" "F.Mask" "F.Paste")
			(net "PVCCMCP_CPU0")
		)
		(pad "B4" smd circle
			(at -1.27 3.81 90)
			(size 0.635 0.635)
			(layers "F.Cu" "F.Mask" "F.Paste")
			(net "VSENSE_PVCCMCP_CPU0_SKT_VRTN")
		)
		(pad "B5" smd circle
			(at -1.27 5.08 90)
			(size 0.635 0.635)
			(layers "F.Cu" "F.Mask" "F.Paste")
			(net "PVCCMCP_CPU0")
		)
		(pad "B6" smd circle
			(at -1.27 6.35 90)
			(size 0.635 0.635)
			(layers "F.Cu" "F.Mask" "F.Paste")
			(net "PVCCMCP_CPU0")
		)
		(pad "B7" smd circle
			(at -1.27 7.62 90)
			(size 0.635 0.635)
			(layers "F.Cu" "F.Mask" "F.Paste")
			(net "PVCCMCP_CPU0")
		)
		(pad "B8" smd circle
			(at -1.27 8.89 90)
			(size 0.635 0.635)
			(layers "F.Cu" "F.Mask" "F.Paste")
			(net "PVCCMCP_CPU0")
		)
		(pad "B9" smd circle
			(at -1.27 10.16 90)
			(size 0.635 0.635)
			(layers "F.Cu" "F.Mask" "F.Paste")
			(net "PVCCMCP_CPU0")
		)
		(pad "B10" smd circle
			(at -1.27 11.43 90)
			(size 0.635 0.635)
			(layers "F.Cu" "F.Mask" "F.Paste")
			(net "PVCCMCP_CPU0")
		)
		(pad "B11" smd circle
			(at -1.27 12.7 90)
			(size 0.635 0.635)
			(layers "F.Cu" "F.Mask" "F.Paste")
			(net "PVCCMCP_CPU0")
		)
		(pad "B12" smd circle
			(at -1.27 13.97 90)
			(size 0.635 0.635)
			(layers "F.Cu" "F.Mask" "F.Paste")
			(net "PVCCMCP_CPU0")
		)
		(pad "B13" smd circle
			(at -1.27 15.24 90)
			(size 0.635 0.635)
			(layers "F.Cu" "F.Mask" "F.Paste")
			(net "PVCCMCP_CPU0")
		)
		(pad "B14" smd circle
			(at -1.27 16.51 90)
			(size 0.635 0.635)
			(layers "F.Cu" "F.Mask" "F.Paste")
			(net "PVCCMCP_CPU0")
		)
		(pad "B15" smd circle
			(at -1.27 17.78 90)
			(size 0.635 0.635)
			(layers "F.Cu" "F.Mask" "F.Paste")
			(net "PVCCMCP_CPU0")
		)
		(pad "B16" smd circle
			(at -1.27 19.05 90)
			(size 0.635 0.635)
			(layers "F.Cu" "F.Mask" "F.Paste")
			(net "PVCCMCP_CPU0")
		)
		(pad "B17" smd circle
			(at -1.27 20.32 90)
			(size 0.635 0.635)
			(layers "F.Cu" "F.Mask" "F.Paste")
			(net "PVCCMCP_CPU0")
		)
		(pad "B18" smd circle
			(at -1.27 21.59 90)
			(size 0.635 0.635)
			(layers "F.Cu" "F.Mask" "F.Paste")
			(net "PVCCMCP_CPU0")
		)
		(pad "B19" smd circle
			(at -1.27 22.86 90)
			(size 0.635 0.635)
			(layers "F.Cu" "F.Mask" "F.Paste")
			(net "GND")
		)
		(pad "B20" smd circle
			(at -1.27 24.13 90)
			(size 0.635 0.635)
			(layers "F.Cu" "F.Mask" "F.Paste")
			(net "GND")
		)
		(pad "C1" smd circle
			(at -2.54 0 90)
			(size 0.635 0.635)
			(layers "F.Cu" "F.Mask" "F.Paste")
			(net "PVCCMCP_CPU0")
		)
		(pad "C2" smd circle
			(at -2.54 1.27 90)
			(size 0.635 0.635)
			(layers "F.Cu" "F.Mask" "F.Paste")
			(net "PVCCMCP_CPU0")
		)
		(pad "C3" smd circle
			(at -2.54 2.54 90)
			(size 0.635 0.635)
			(layers "F.Cu" "F.Mask" "F.Paste")
			(net "PVCCMCP_CPU0")
		)
		(pad "C4" smd circle
			(at -2.54 3.81 90)
			(size 0.635 0.635)
			(layers "F.Cu" "F.Mask" "F.Paste")
			(net "PVCCMCP_CPU0")
		)
		(pad "C5" smd circle
			(at -2.54 5.08 90)
			(size 0.635 0.635)
			(layers "F.Cu" "F.Mask" "F.Paste")
			(net "PVCCMCP_CPU0")
		)
		(pad "C6" smd circle
			(at -2.54 6.35 90)
			(size 0.635 0.635)
			(layers "F.Cu" "F.Mask" "F.Paste")
			(net "PVCCMCP_CPU0")
		)
		(pad "C7" smd circle
			(at -2.54 7.62 90)
			(size 0.635 0.635)
			(layers "F.Cu" "F.Mask" "F.Paste")
			(net "PVCCMCP_CPU0")
		)
		(pad "C8" smd circle
			(at -2.54 8.89 90)
			(size 0.635 0.635)
			(layers "F.Cu" "F.Mask" "F.Paste")
			(net "PVCCMCP_CPU0")
		)
		(pad "C9" smd circle
			(at -2.54 10.16 90)
			(size 0.635 0.635)
			(layers "F.Cu" "F.Mask" "F.Paste")
			(net "PVCCMCP_CPU0")
		)
		(pad "C10" smd circle
			(at -2.54 11.43 90)
			(size 0.635 0.635)
			(layers "F.Cu" "F.Mask" "F.Paste")
			(net "PVCCMCP_CPU0")
		)
		(pad "C11" smd circle
			(at -2.54 12.7 90)
			(size 0.635 0.635)
			(layers "F.Cu" "F.Mask" "F.Paste")
			(net "PVCCMCP_CPU0")
		)
		(pad "C12" smd circle
			(at -2.54 13.97 90)
			(size 0.635 0.635)
			(layers "F.Cu" "F.Mask" "F.Paste")
			(net "PVCCMCP_CPU0")
		)
		(pad "C13" smd circle
			(at -2.54 15.24 90)
			(size 0.635 0.635)
			(layers "F.Cu" "F.Mask" "F.Paste")
			(net "PVCCMCP_CPU0")
		)
		(pad "C14" smd circle
			(at -2.54 16.51 90)
			(size 0.635 0.635)
			(layers "F.Cu" "F.Mask" "F.Paste")
			(net "PVCCMCP_CPU0")
		)
		(pad "C15" smd circle
			(at -2.54 17.78 90)
			(size 0.635 0.635)
			(layers "F.Cu" "F.Mask" "F.Paste")
			(net "PVCCMCP_CPU0")
		)
		(pad "C16" smd circle
			(at -2.54 19.05 90)
			(size 0.635 0.635)
			(layers "F.Cu" "F.Mask" "F.Paste")
			(net "PVCCMCP_CPU0")
		)
		(pad "C17" smd circle
			(at -2.54 20.32 90)
			(size 0.635 0.635)
			(layers "F.Cu" "F.Mask" "F.Paste")
			(net "PVCCMCP_CPU0")
		)
		(pad "C18" smd circle
			(at -2.54 21.59 90)
			(size 0.635 0.635)
			(layers "F.Cu" "F.Mask" "F.Paste")
			(net "PVCCMCP_CPU0")
		)
		(pad "C19" smd circle
			(at -2.54 22.86 90)
			(size 0.635 0.635)
			(layers "F.Cu" "F.Mask" "F.Paste")
			(net "GND")
		)
		(pad "C20" smd circle
			(at -2.54 24.13 90)
			(size 0.635 0.635)
			(layers "F.Cu" "F.Mask" "F.Paste")
			(net "GND")
		)
		(pad "D1" smd circle
			(at -3.81 0 90)
			(size 0.635 0.635)
			(layers "F.Cu" "F.Mask" "F.Paste")
			(net "VSENSE_P1V8MCP_CPU0_SKT_VSEN")
		)
		(pad "D2" smd circle
			(at -3.81 1.27 90)
			(size 0.635 0.635)
			(layers "F.Cu" "F.Mask" "F.Paste")
			(net "VSENSE_P1V8MCP_CPU0_SKT_VRTN")
		)
		(pad "D3" smd circle
			(at -3.81 2.54 90)
			(size 0.635 0.635)
			(layers "F.Cu" "F.Mask" "F.Paste")
			(net "P1V8_MCP_CPU0")
		)
		(pad "D4" smd circle
			(at -3.81 3.81 90)
			(size 0.635 0.635)
			(layers "F.Cu" "F.Mask" "F.Paste")
			(net "GND")
		)
		(pad "D5" smd circle
			(at -3.81 5.08 90)
			(size 0.635 0.635)
			(layers "F.Cu" "F.Mask" "F.Paste")
			(net "GND")
		)
		(pad "D6" smd circle
			(at -3.81 6.35 90)
			(size 0.635 0.635)
			(layers "F.Cu" "F.Mask" "F.Paste")
			(net "GND")
		)
		(pad "D7" smd circle
			(at -3.81 7.62 90)
			(size 0.635 0.635)
			(layers "F.Cu" "F.Mask" "F.Paste")
			(net "GND")
		)
		(pad "D8" smd circle
			(at -3.81 8.89 90)
			(size 0.635 0.635)
			(layers "F.Cu" "F.Mask" "F.Paste")
			(net "GND")
		)
		(pad "D9" smd circle
			(at -3.81 10.16 90)
			(size 0.635 0.635)
			(layers "F.Cu" "F.Mask" "F.Paste")
			(net "GND")
		)
		(pad "D10" smd circle
			(at -3.81 11.43 90)
			(size 0.635 0.635)
			(layers "F.Cu" "F.Mask" "F.Paste")
			(net "GND")
		)
		(pad "D11" smd circle
			(at -3.81 12.7 90)
			(size 0.635 0.635)
			(layers "F.Cu" "F.Mask" "F.Paste")
			(net "GND")
		)
		(pad "D12" smd circle
			(at -3.81 13.97 90)
			(size 0.635 0.635)
			(layers "F.Cu" "F.Mask" "F.Paste")
			(net "GND")
		)
		(pad "D13" smd circle
			(at -3.81 15.24 90)
			(size 0.635 0.635)
			(layers "F.Cu" "F.Mask" "F.Paste")
			(net "GND")
		)
		(pad "D14" smd circle
			(at -3.81 16.51 90)
			(size 0.635 0.635)
			(layers "F.Cu" "F.Mask" "F.Paste")
			(net "GND")
		)
		(pad "D15" smd circle
			(at -3.81 17.78 90)
			(size 0.635 0.635)
			(layers "F.Cu" "F.Mask" "F.Paste")
			(net "GND")
		)
		(pad "D16" smd circle
			(at -3.81 19.05 90)
			(size 0.635 0.635)
			(layers "F.Cu" "F.Mask" "F.Paste")
			(net "GND")
		)
		(pad "D17" smd circle
			(at -3.81 20.32 90)
			(size 0.635 0.635)
			(layers "F.Cu" "F.Mask" "F.Paste")
			(net "GND")
		)
		(pad "D18" smd circle
			(at -3.81 21.59 90)
			(size 0.635 0.635)
			(layers "F.Cu" "F.Mask" "F.Paste")
			(net "GND")
		)
		(pad "D19" smd circle
			(at -3.81 22.86 90)
			(size 0.635 0.635)
			(layers "F.Cu" "F.Mask" "F.Paste")
			(net "GND")
		)
		(pad "D20" smd circle
			(at -3.81 24.13 90)
			(size 0.635 0.635)
			(layers "F.Cu" "F.Mask" "F.Paste")
			(net "GND")
		)
		(pad "E1" smd circle
			(at -5.08 0 90)
			(size 0.635 0.635)
			(layers "F.Cu" "F.Mask" "F.Paste")
			(net "P1V8_MCP_CPU0")
		)
		(pad "E2" smd circle
			(at -5.08 1.27 90)
			(size 0.635 0.635)
			(layers "F.Cu" "F.Mask" "F.Paste")
			(net "P1V8_MCP_CPU0")
		)
		(pad "E3" smd circle
			(at -5.08 2.54 90)
			(size 0.635 0.635)
			(layers "F.Cu" "F.Mask" "F.Paste")
			(net "P1V8_MCP_CPU0")
		)
		(pad "E4" smd circle
			(at -5.08 3.81 90)
			(size 0.635 0.635)
			(layers "F.Cu" "F.Mask" "F.Paste")
			(net "GND")
		)
		(pad "E5" smd circle
			(at -5.08 5.08 90)
			(size 0.635 0.635)
			(layers "F.Cu" "F.Mask" "F.Paste")
			(net "CLK_322M_156M_CPU0_OSC_VRM_DP")
		)
		(pad "E6" smd circle
			(at -5.08 6.35 90)
			(size 0.635 0.635)
			(layers "F.Cu" "F.Mask" "F.Paste")
			(net "GND")
		)
		(pad "E7" smd circle
			(at -5.08 7.62 90)
			(size 0.635 0.635)
			(layers "F.Cu" "F.Mask" "F.Paste")
			(net "GND")
		)
		(pad "E8" smd circle
			(at -5.08 8.89 90)
			(size 0.635 0.635)
			(layers "F.Cu" "F.Mask" "F.Paste")
			(net "GND")
		)
		(pad "E9" smd circle
			(at -5.08 10.16 90)
			(size 0.635 0.635)
			(layers "F.Cu" "F.Mask" "F.Paste")
			(net "GND")
		)
		(pad "E10" smd circle
			(at -5.08 11.43 90)
			(size 0.635 0.635)
			(layers "F.Cu" "F.Mask" "F.Paste")
			(net "GND")
		)
		(pad "E11" smd circle
			(at -5.08 12.7 90)
			(size 0.635 0.635)
			(layers "F.Cu" "F.Mask" "F.Paste")
			(net "GND")
		)
		(pad "E12" smd circle
			(at -5.08 13.97 90)
			(size 0.635 0.635)
			(layers "F.Cu" "F.Mask" "F.Paste")
			(net "GND")
		)
		(pad "E13" smd circle
			(at -5.08 15.24 90)
			(size 0.635 0.635)
			(layers "F.Cu" "F.Mask" "F.Paste")
			(net "GND")
		)
		(pad "E14" smd circle
			(at -5.08 16.51 90)
			(size 0.635 0.635)
			(layers "F.Cu" "F.Mask" "F.Paste")
			(net "GND")
		)
		(pad "E15" smd circle
			(at -5.08 17.78 90)
			(size 0.635 0.635)
			(layers "F.Cu" "F.Mask" "F.Paste")
			(net "GND")
		)
		(pad "E16" smd circle
			(at -5.08 19.05 90)
			(size 0.635 0.635)
			(layers "F.Cu" "F.Mask" "F.Paste")
			(net "GND")
		)
		(pad "E17" smd circle
			(at -5.08 20.32 90)
			(size 0.635 0.635)
			(layers "F.Cu" "F.Mask" "F.Paste")
			(net "GND")
		)
		(pad "E18" smd circle
			(at -5.08 21.59 90)
			(size 0.635 0.635)
			(layers "F.Cu" "F.Mask" "F.Paste")
			(net "GND")
		)
		(pad "E19" smd circle
			(at -5.08 22.86 90)
			(size 0.635 0.635)
			(layers "F.Cu" "F.Mask" "F.Paste")
			(net "GND")
		)
		(pad "E20" smd circle
			(at -5.08 24.13 90)
			(size 0.635 0.635)
			(layers "F.Cu" "F.Mask" "F.Paste")
			(net "GND")
		)
		(pad "F1" smd circle
			(at -6.35 0 90)
			(size 0.635 0.635)
			(layers "F.Cu" "F.Mask" "F.Paste")
			(net "P1V8_MCP_CPU0")
		)
		(pad "F2" smd circle
			(at -6.35 1.27 90)
			(size 0.635 0.635)
			(layers "F.Cu" "F.Mask" "F.Paste")
			(net "P1V8_MCP_CPU0")
		)
		(pad "F3" smd circle
			(at -6.35 2.54 90)
			(size 0.635 0.635)
			(layers "F.Cu" "F.Mask" "F.Paste")
			(net "P1V8_MCP_CPU0")
		)
		(pad "F4" smd circle
			(at -6.35 3.81 90)
			(size 0.635 0.635)
			(layers "F.Cu" "F.Mask" "F.Paste")
			(net "GND")
		)
		(pad "F5" smd circle
			(at -6.35 5.08 90)
			(size 0.635 0.635)
			(layers "F.Cu" "F.Mask" "F.Paste")
			(net "CLK_322M_156M_CPU0_OSC_VRM_DN")
		)
		(pad "F6" smd circle
			(at -6.35 6.35 90)
			(size 0.635 0.635)
			(layers "F.Cu" "F.Mask" "F.Paste")
			(net "GND")
		)
		(pad "F7" smd circle
			(at -6.35 7.62 90)
			(size 0.635 0.635)
			(layers "F.Cu" "F.Mask" "F.Paste")
			(net "GND")
		)
		(pad "F8" smd circle
			(at -6.35 8.89 90)
			(size 0.635 0.635)
			(layers "F.Cu" "F.Mask" "F.Paste")
			(net "GND")
		)
		(pad "F9" smd circle
			(at -6.35 10.16 90)
			(size 0.635 0.635)
			(layers "F.Cu" "F.Mask" "F.Paste")
			(net "GND")
		)
		(pad "F10" smd circle
			(at -6.35 11.43 90)
			(size 0.635 0.635)
			(layers "F.Cu" "F.Mask" "F.Paste")
			(net "GND")
		)
		(pad "F11" smd circle
			(at -6.35 12.7 90)
			(size 0.635 0.635)
			(layers "F.Cu" "F.Mask" "F.Paste")
			(net "GND")
		)
		(pad "F12" smd circle
			(at -6.35 13.97 90)
			(size 0.635 0.635)
			(layers "F.Cu" "F.Mask" "F.Paste")
			(net "GND")
		)
		(pad "F13" smd circle
			(at -6.35 15.24 90)
			(size 0.635 0.635)
			(layers "F.Cu" "F.Mask" "F.Paste")
			(net "GND")
		)
		(pad "F14" smd circle
			(at -6.35 16.51 90)
			(size 0.635 0.635)
			(layers "F.Cu" "F.Mask" "F.Paste")
			(net "GND")
		)
		(pad "F15" smd circle
			(at -6.35 17.78 90)
			(size 0.635 0.635)
			(layers "F.Cu" "F.Mask" "F.Paste")
			(net "GND")
		)
		(pad "F16" smd circle
			(at -6.35 19.05 90)
			(size 0.635 0.635)
			(layers "F.Cu" "F.Mask" "F.Paste")
			(net "GND")
		)
		(pad "F17" smd circle
			(at -6.35 20.32 90)
			(size 0.635 0.635)
			(layers "F.Cu" "F.Mask" "F.Paste")
			(net "GND")
		)
		(pad "F18" smd circle
			(at -6.35 21.59 90)
			(size 0.635 0.635)
			(layers "F.Cu" "F.Mask" "F.Paste")
			(net "GND")
		)
		(pad "F19" smd circle
			(at -6.35 22.86 90)
			(size 0.635 0.635)
			(layers "F.Cu" "F.Mask" "F.Paste")
			(net "GND")
		)
		(pad "F20" smd circle
			(at -6.35 24.13 90)
			(size 0.635 0.635)
			(layers "F.Cu" "F.Mask" "F.Paste")
			(net "GND")
		)
		(zone
			(layers "F.Cu" "B.Cu" "In1.Cu" "In2.Cu" "In3.Cu" "In4.Cu" "In5.Cu" "In6.Cu"
				"In7.Cu" "In8.Cu" "In9.Cu" "In10.Cu" "In11.Cu" "In12.Cu"
			)
			(hatch none 0.5)
			(connect_pads
				(clearance 0)
			)
			(min_thickness 0.25)
			(keepout
				(tracks not_allowed)
				(vias allowed)
				(pads allowed)
				(copperpour not_allowed)
				(footprints allowed)
			)
			(placement
				(enabled no)
				(sheetname "")
			)
			(fill
				(thermal_gap 0.5)
				(thermal_bridge_width 0.5)
				(island_removal_mode 0)
			)
			(polygon
				(pts
					(arc
						(start 328.121772 -43.67403)
						(mid 326.216772 -43.67403)
						(end 328.121772 -43.67403)
					)
				)
			)
		)
		(zone
			(layers "F.Cu" "B.Cu" "In1.Cu" "In2.Cu" "In3.Cu" "In4.Cu" "In5.Cu" "In6.Cu"
				"In7.Cu" "In8.Cu" "In9.Cu" "In10.Cu" "In11.Cu" "In12.Cu"
			)
			(hatch none 0.5)
			(connect_pads
				(clearance 0)
			)
			(min_thickness 0.25)
			(keepout
				(tracks not_allowed)
				(vias allowed)
				(pads allowed)
				(copperpour not_allowed)
				(footprints allowed)
			)
			(placement
				(enabled no)
				(sheetname "")
			)
			(fill
				(thermal_gap 0.5)
				(thermal_bridge_width 0.5)
				(island_removal_mode 0)
			)
			(polygon
				(pts
					(arc
						(start 357.103172 -40.62603)
						(mid 355.198172 -40.62603)
						(end 357.103172 -40.62603)
					)
				)
			)
		)
	)
	(footprint ""
		(layer "F.Cu")
		(at 485.5845 -31.684468 180)
		(property "Reference" "Y8F1"
			(at -0.8001 3.55727 180)
			(unlocked yes)
			(layer "F.SilkS")
			(effects
				(font
					(size 0.7874 0.5842)
					(thickness 0.1524)
				)
				(justify left)
			)
		)
		(property "Value" ""
			(at 0 0 180)
			(layer "F.Fab")
			(effects
				(font
					(size 1.27 1.27)
				)
			)
		)
		(duplicate_pad_numbers_are_jumpers no)
		(fp_circle
			(center -1.049782 -0.44323)
			(end -1.176782 -0.44323)
			(stroke
				(width 0.254)
				(type default)
			)
			(fill no)
			(layer "F.SilkS")
		)
		(fp_rect
			(start -0.499872 2.70002)
			(end 2.100072 -0.599948)
			(stroke
				(width 0)
				(type default)
			)
			(fill no)
			(layer "F.CrtYd")
		)
		(fp_line
			(start 2.100072 2.70002)
			(end -0.499872 2.70002)
			(stroke
				(width 0.1)
				(type default)
			)
			(layer "F.Fab")
		)
		(fp_line
			(start 2.100072 -0.599948)
			(end 2.100072 2.70002)
			(stroke
				(width 0.1)
				(type default)
			)
			(layer "F.Fab")
		)
		(fp_line
			(start -0.499872 2.70002)
			(end -0.499872 -0.599948)
			(stroke
				(width 0.1)
				(type default)
			)
			(layer "F.Fab")
		)
		(fp_line
			(start -0.499872 -0.599948)
			(end 2.100072 -0.599948)
			(stroke
				(width 0.1)
				(type default)
			)
			(layer "F.Fab")
		)
		(fp_circle
			(center -1.049782 -0.44323)
			(end -1.176782 -0.44323)
			(stroke
				(width 0.254)
				(type default)
			)
			(fill no)
			(layer "F.Fab")
		)
		(pad "1" smd rect
			(at 0 0 180)
			(size 1.0414 1.143)
			(layers "F.Cu" "F.Mask" "F.Paste")
			(net "XTAL_CK_MNG_IN")
		)
		(pad "2" smd rect
			(at 0 2.100072 180)
			(size 1.0414 1.143)
			(layers "F.Cu" "F.Mask" "F.Paste")
			(net "GND")
		)
		(pad "3" smd rect
			(at 1.6002 2.100072 180)
			(size 1.0414 1.143)
			(layers "F.Cu" "F.Mask" "F.Paste")
			(net "XTAL_CK_MNG_OUT")
		)
		(pad "4" smd rect
			(at 1.6002 0 180)
			(size 1.0414 1.143)
			(layers "F.Cu" "F.Mask" "F.Paste")
			(net "GND")
		)
	)
	(footprint ""
		(layer "F.Cu")
		(at 2.397506 -147.328382 90)
		(property "Reference" "EU1A1"
			(at 3.292348 -1.686306 0)
			(unlocked yes)
			(layer "F.SilkS")
			(effects
				(font
					(size 0.7874 0.5842)
					(thickness 0.1524)
				)
			)
		)
		(property "Value" ""
			(at 0 0 90)
			(layer "F.Fab")
			(effects
				(font
					(size 1.27 1.27)
				)
			)
		)
		(duplicate_pad_numbers_are_jumpers no)
		(fp_line
			(start 2.9718 -3.5052)
			(end 2.9718 3.429)
			(stroke
				(width 0.1524)
				(type default)
			)
			(layer "F.SilkS")
		)
		(fp_line
			(start -3.0099 -3.5052)
			(end 2.9718 -3.5052)
			(stroke
				(width 0.1524)
				(type default)
			)
			(layer "F.SilkS")
		)
		(fp_line
			(start 2.9718 3.429)
			(end -3.0099 3.429)
			(stroke
				(width 0.1524)
				(type default)
			)
			(layer "F.SilkS")
		)
		(fp_line
			(start -3.0099 3.429)
			(end -3.0099 -3.5052)
			(stroke
				(width 0.1524)
				(type default)
			)
			(layer "F.SilkS")
		)
		(fp_circle
			(center -3.057398 -2.678684)
			(end -3.057398 -2.551684)
			(stroke
				(width 0.254)
				(type default)
			)
			(fill no)
			(layer "F.SilkS")
		)
		(fp_poly
			(pts
				(xy -2.9972 -3.4925) (xy -2.9972 -2.6924) (xy -2.1971 -3.4925)
			)
			(stroke
				(width 0)
				(type default)
			)
			(fill yes)
			(layer "F.SilkS")
		)
		(fp_poly
			(pts
				(xy -2.549906 -3.050032) (xy -2.549906 3.050032) (xy 2.549906 3.050032) (xy 2.549906 -3.050032)
			)
			(stroke
				(width 0)
				(type default)
			)
			(fill no)
			(layer "F.CrtYd")
		)
		(fp_line
			(start 2.549906 -3.050032)
			(end 2.549906 3.050032)
			(stroke
				(width 0.1)
				(type default)
			)
			(layer "F.Fab")
		)
		(fp_line
			(start -2.549906 -3.050032)
			(end 2.549906 -3.050032)
			(stroke
				(width 0.1)
				(type default)
			)
			(layer "F.Fab")
		)
		(fp_line
			(start 2.549906 3.050032)
			(end -2.549906 3.050032)
			(stroke
				(width 0.1)
				(type default)
			)
			(layer "F.Fab")
		)
		(fp_line
			(start -2.549906 3.050032)
			(end -2.549906 -3.050032)
			(stroke
				(width 0.1)
				(type default)
			)
			(layer "F.Fab")
		)
		(fp_circle
			(center -3.057398 -2.678684)
			(end -3.057398 -2.551684)
			(stroke
				(width 0.254)
				(type default)
			)
			(fill no)
			(layer "F.Fab")
		)
		(pad "1" smd rect
			(at -2.39522 -2.279904 90)
			(size 0.7112 0.254)
			(layers "F.Cu" "F.Mask" "F.Paste")
			(net "PVDDQ_KLM")
		)
		(pad "2" smd rect
			(at -2.39522 -1.83007 90)
			(size 0.7112 0.254)
			(layers "F.Cu" "F.Mask" "F.Paste")
			(net "GND")
		)
		(pad "3" smd rect
			(at -2.39522 -1.379982 90)
			(size 0.7112 0.254)
			(layers "F.Cu" "F.Mask" "F.Paste")
			(net "VR_PVDDQ_KLM_PH2_VCIN")
		)
		(pad "4" smd rect
			(at -2.39522 -0.929894 90)
			(size 0.7112 0.254)
			(layers "F.Cu" "F.Mask" "F.Paste")
			(net "P5V_STBY")
		)
		(pad "5" smd rect
			(at -2.39522 -0.48006 90)
			(size 0.7112 0.254)
			(layers "F.Cu" "F.Mask" "F.Paste")
			(net "GND")
		)
		(pad "6" smd rect
			(at -2.39522 -0.029972 90)
			(size 0.7112 0.254)
			(layers "F.Cu" "F.Mask" "F.Paste")
			(net "TP_PVDDQ_KLM_PH2_GL_0")
		)
		(pad "7" smd custom
			(at 0.016764 1.145032 90)
			(size 0.53975 0.53975)
			(layers "F.Cu" "F.Mask" "F.Paste")
			(net "GND")
			(options
				(clearance outline)
				(anchor circle)
			)
			(primitives
				(gr_poly
					(pts
						(xy -2.7051 1.0795) (xy -2.7051 -0.3683) (xy -0.9271 -0.3683) (xy -0.9271 -1.0795) (xy 2.7051 -1.0795)
						(xy 2.7051 1.0795)
					)
					(width 0)
					(fill yes)
				)
			)
		)
		(pad "10" smd rect
			(at -0.008382 2.874772 90)
			(size 4.3434 0.6096)
			(layers "F.Cu" "F.Mask" "F.Paste")
			(net "VR_PVDDQ_KLM_PH2_SW")
		)
		(pad "25" smd rect
			(at 1.548384 -1.283208 90)
			(size 2.3368 2.0066)
			(layers "F.Cu" "F.Mask" "F.Paste")
			(net "VR_FET_SW_P12V_STBY_PVDDQ_KLM")
		)
		(pad "30" smd rect
			(at 2.050034 -2.895092 90)
			(size 0.254 0.7112)
			(layers "F.Cu" "F.Mask" "F.Paste")
			(net "VR_FET_SW_P12V_STBY_PVDDQ_KLM")
		)
		(pad "31" smd rect
			(at 1.599946 -2.895092 90)
			(size 0.254 0.7112)
			(layers "F.Cu" "F.Mask" "F.Paste")
			(net "Net_373")
		)
		(pad "32" smd rect
			(at 1.150112 -2.895092 90)
			(size 0.254 0.7112)
			(layers "F.Cu" "F.Mask" "F.Paste")
			(net "VR_PVDDQ_KLM_PH2_PHASE")
		)
		(pad "33" smd rect
			(at 0.700024 -2.895092 90)
			(size 0.254 0.7112)
			(layers "F.Cu" "F.Mask" "F.Paste")
			(net "VR_PVDDQ_KLM_PH2_BOOT_R")
		)
		(pad "34" smd rect
			(at 0.249936 -2.895092 90)
			(size 0.254 0.7112)
			(layers "F.Cu" "F.Mask" "F.Paste")
			(net "VR_PVDDQ_KLM_PWM2")
		)
		(pad "35" smd rect
			(at -0.199898 -2.895092 90)
			(size 0.254 0.7112)
			(layers "F.Cu" "F.Mask" "F.Paste")
			(net "P5V_STBY")
		)
		(pad "36" smd rect
			(at -0.649986 -2.895092 90)
			(size 0.254 0.7112)
			(layers "F.Cu" "F.Mask" "F.Paste")
			(net "A_TSENSE_PVDDQ_KLM")
		)
		(pad "37" smd rect
			(at -1.100074 -2.895092 90)
			(size 0.254 0.7112)
			(layers "F.Cu" "F.Mask" "F.Paste")
			(net "VR_PVDDQ_KLM_PH2_OCSET")
		)
		(pad "38" smd rect
			(at -1.549908 -2.895092 90)
			(size 0.254 0.7112)
			(layers "F.Cu" "F.Mask" "F.Paste")
			(net "ISENSE_PVDDQ_KLM_PH2_IMON")
		)
		(pad "39" smd rect
			(at -1.999996 -2.895092 90)
			(size 0.254 0.7112)
			(layers "F.Cu" "F.Mask" "F.Paste")
			(net "VR_PVDDQ_KLM_AIREF2")
		)
		(pad "40" smd rect
			(at -0.871728 -1.283208 90)
			(size 1.8034 2.0066)
			(layers "F.Cu" "F.Mask" "F.Paste")
			(net "GND")
		)
		(pad "41" smd rect
			(at -1.533906 0.247904 90)
			(size 0.508 0.3556)
			(layers "F.Cu" "F.Mask" "F.Paste")
			(net "TP_PVDDQ_KLM_PH2_GL_1")
		)
	)
	(footprint ""
		(layer "F.Cu")
		(at 22.4282 -98.19894)
		(property "Reference" "R1C18"
			(at 0 0 0)
			(layer "F.SilkS")
			(hide yes)
			(effects
				(font
					(size 1.27 1.27)
				)
			)
		)
		(property "Value" ""
			(at 0 0 0)
			(layer "F.Fab")
			(effects
				(font
					(size 1.27 1.27)
				)
			)
		)
		(duplicate_pad_numbers_are_jumpers no)
		(fp_rect
			(start -0.2794 0.9906)
			(end 0.2794 -0.1016)
			(stroke
				(width 0)
				(type default)
			)
			(fill no)
			(layer "F.CrtYd")
		)
		(fp_line
			(start -0.2794 -0.1016)
			(end -0.2794 0.9906)
			(stroke
				(width 0.1)
				(type default)
			)
			(layer "F.Fab")
		)
		(fp_line
			(start -0.2794 0.9906)
			(end 0.2794 0.9906)
			(stroke
				(width 0.1)
				(type default)
			)
			(layer "F.Fab")
		)
		(fp_line
			(start 0.2794 -0.1016)
			(end -0.2794 -0.1016)
			(stroke
				(width 0.1)
				(type default)
			)
			(layer "F.Fab")
		)
		(fp_line
			(start 0.2794 0.9906)
			(end 0.2794 -0.1016)
			(stroke
				(width 0.1)
				(type default)
			)
			(layer "F.Fab")
		)
		(pad "1" smd rect
			(at 0 0)
			(size 0.508 0.508)
			(layers "F.Cu" "F.Mask" "F.Paste")
			(net "P3V3_STBY")
		)
		(pad "2" smd rect
			(at 0 0.889)
			(size 0.508 0.508)
			(layers "F.Cu" "F.Mask" "F.Paste")
			(net "PU_VR_PVCCIN_CPU1_IMON")
		)
		(zone
			(layer "F.Cu")
			(hatch none 0.5)
			(connect_pads
				(clearance 0)
			)
			(min_thickness 0.25)
			(keepout
				(tracks not_allowed)
				(vias allowed)
				(pads allowed)
				(copperpour not_allowed)
				(footprints allowed)
			)
			(placement
				(enabled no)
				(sheetname "")
			)
			(fill
				(thermal_gap 0.5)
				(thermal_bridge_width 0.5)
				(island_removal_mode 0)
			)
			(polygon
				(pts
					(xy 22.1742 -97.56394) (xy 22.6822 -97.56394) (xy 22.6822 -97.94494) (xy 22.1742 -97.94494)
				)
			)
		)
		(zone
			(layer "F.Cu")
			(hatch none 0.5)
			(connect_pads
				(clearance 0)
			)
			(min_thickness 0.25)
			(keepout
				(tracks allowed)
				(vias not_allowed)
				(pads allowed)
				(copperpour not_allowed)
				(footprints allowed)
			)
			(placement
				(enabled no)
				(sheetname "")
			)
			(fill
				(thermal_gap 0.5)
				(thermal_bridge_width 0.5)
				(island_removal_mode 0)
			)
			(polygon
				(pts
					(xy 22.1742 -97.56394) (xy 22.6822 -97.56394) (xy 22.6822 -97.94494) (xy 22.1742 -97.94494)
				)
			)
		)
	)
	(footprint ""
		(layer "F.Cu")
		(at 269.559532 -140.208 90)
		(property "Reference" "C5A17"
			(at 1.848866 0.752348 90)
			(unlocked yes)
			(layer "F.SilkS")
			(effects
				(font
					(size 1.27 0.9652)
					(thickness 0.1524)
				)
			)
		)
		(property "Value" ""
			(at 0 0 90)
			(layer "F.Fab")
			(effects
				(font
					(size 1.27 1.27)
				)
			)
		)
		(duplicate_pad_numbers_are_jumpers no)
		(fp_rect
			(start -0.500126 1.598422)
			(end 0.500126 -0.201422)
			(stroke
				(width 0)
				(type default)
			)
			(fill no)
			(layer "F.CrtYd")
		)
		(fp_line
			(start 0.500126 -0.201422)
			(end 0.500126 1.598422)
			(stroke
				(width 0.1)
				(type default)
			)
			(layer "F.Fab")
		)
		(fp_line
			(start -0.500126 -0.201422)
			(end 0.500126 -0.201422)
			(stroke
				(width 0.1)
				(type default)
			)
			(layer "F.Fab")
		)
		(fp_line
			(start 0.500126 1.598422)
			(end -0.500126 1.598422)
			(stroke
				(width 0.1)
				(type default)
			)
			(layer "F.Fab")
		)
		(fp_line
			(start -0.500126 1.598422)
			(end -0.500126 -0.201422)
			(stroke
				(width 0.1)
				(type default)
			)
			(layer "F.Fab")
		)
		(pad "1" smd rect
			(at 0 0)
			(size 0.889 0.9906)
			(layers "F.Cu" "F.Mask" "F.Paste")
			(net "PVDDQ_DEF")
		)
		(pad "2" smd rect
			(at 0 1.397)
			(size 0.889 0.9906)
			(layers "F.Cu" "F.Mask" "F.Paste")
			(net "GND")
		)
		(zone
			(layer "F.Cu")
			(hatch none 0.5)
			(connect_pads
				(clearance 0)
			)
			(min_thickness 0.25)
			(keepout
				(tracks not_allowed)
				(vias allowed)
				(pads allowed)
				(copperpour not_allowed)
				(footprints allowed)
			)
			(placement
				(enabled no)
				(sheetname "")
			)
			(fill
				(thermal_gap 0.5)
				(thermal_bridge_width 0.5)
				(island_removal_mode 0)
			)
			(polygon
				(pts
					(xy 270.512032 -139.7127) (xy 270.512032 -140.7033) (xy 270.004032 -140.7033) (xy 270.004032 -139.7127)
				)
			)
		)
		(zone
			(layer "F.Cu")
			(hatch none 0.5)
			(connect_pads
				(clearance 0)
			)
			(min_thickness 0.25)
			(keepout
				(tracks allowed)
				(vias not_allowed)
				(pads allowed)
				(copperpour not_allowed)
				(footprints allowed)
			)
			(placement
				(enabled no)
				(sheetname "")
			)
			(fill
				(thermal_gap 0.5)
				(thermal_bridge_width 0.5)
				(island_removal_mode 0)
			)
			(polygon
				(pts
					(xy 270.512032 -139.7127) (xy 270.512032 -140.7033) (xy 270.004032 -140.7033) (xy 270.004032 -139.7127)
				)
			)
		)
	)
	(footprint ""
		(layer "F.Cu")
		(at 161.798 -59.309 180)
		(property "Reference" "C3E1"
			(at 0 0 180)
			(layer "F.SilkS")
			(hide yes)
			(effects
				(font
					(size 1.27 1.27)
				)
			)
		)
		(property "Value" ""
			(at 0 0 180)
			(layer "F.Fab")
			(effects
				(font
					(size 1.27 1.27)
				)
			)
		)
		(duplicate_pad_numbers_are_jumpers no)
		(fp_poly
			(pts
				(xy -0.4953 -0.2032) (xy 0.4953 -0.2032) (xy 0.4953 1.6002) (xy -0.4953 1.6002)
			)
			(stroke
				(width 0)
				(type default)
			)
			(fill no)
			(layer "F.CrtYd")
		)
		(fp_line
			(start 0.4953 1.6002)
			(end -0.4953 1.6002)
			(stroke
				(width 0.1)
				(type default)
			)
			(layer "F.Fab")
		)
		(fp_line
			(start 0.4953 -0.2032)
			(end 0.4953 1.6002)
			(stroke
				(width 0.1)
				(type default)
			)
			(layer "F.Fab")
		)
		(fp_line
			(start -0.4953 1.6002)
			(end -0.4953 -0.2032)
			(stroke
				(width 0.1)
				(type default)
			)
			(layer "F.Fab")
		)
		(fp_line
			(start -0.4953 -0.2032)
			(end 0.4953 -0.2032)
			(stroke
				(width 0.1)
				(type default)
			)
			(layer "F.Fab")
		)
		(pad "1" smd rect
			(at 0 0 180)
			(size 0.762 0.889)
			(layers "F.Cu" "F.Mask" "F.Paste")
			(net "PVCCIO_CPU1")
		)
		(pad "2" smd rect
			(at 0 1.397 180)
			(size 0.762 0.889)
			(layers "F.Cu" "F.Mask" "F.Paste")
			(net "GND")
		)
		(zone
			(layer "F.Cu")
			(hatch none 0.5)
			(connect_pads
				(clearance 0)
			)
			(min_thickness 0.25)
			(keepout
				(tracks not_allowed)
				(vias allowed)
				(pads allowed)
				(copperpour not_allowed)
				(footprints allowed)
			)
			(placement
				(enabled no)
				(sheetname "")
			)
			(fill
				(thermal_gap 0.5)
				(thermal_bridge_width 0.5)
				(island_removal_mode 0)
			)
			(polygon
				(pts
					(xy 162.179 -59.7535) (xy 161.417 -59.7535) (xy 161.417 -60.2615) (xy 162.179 -60.2615)
				)
			)
		)
	)
	(footprint ""
		(layer "F.Cu")
		(at 157.97022 -125.1077 90)
		(property "Reference" "C3B4"
			(at 0 0 90)
			(layer "F.SilkS")
			(hide yes)
			(effects
				(font
					(size 1.27 1.27)
				)
			)
		)
		(property "Value" ""
			(at 0 0 90)
			(layer "F.Fab")
			(effects
				(font
					(size 1.27 1.27)
				)
			)
		)
		(duplicate_pad_numbers_are_jumpers no)
		(fp_poly
			(pts
				(xy 0.3048 -0.1016) (xy 0.3048 0.9906) (xy -0.3048 0.9906) (xy -0.3048 -0.1016)
			)
			(stroke
				(width 0)
				(type default)
			)
			(fill no)
			(layer "F.CrtYd")
		)
		(fp_line
			(start 0.3048 -0.1016)
			(end -0.3048 -0.1016)
			(stroke
				(width 0.1)
				(type default)
			)
			(layer "F.Fab")
		)
		(fp_line
			(start -0.3048 -0.1016)
			(end -0.3048 0.9906)
			(stroke
				(width 0.1)
				(type default)
			)
			(layer "F.Fab")
		)
		(fp_line
			(start 0.3048 0.9906)
			(end 0.3048 -0.1016)
			(stroke
				(width 0.1)
				(type default)
			)
			(layer "F.Fab")
		)
		(fp_line
			(start -0.3048 0.9906)
			(end 0.3048 0.9906)
			(stroke
				(width 0.1)
				(type default)
			)
			(layer "F.Fab")
		)
		(pad "1" smd rect
			(at 0 0 90)
			(size 0.508 0.508)
			(layers "F.Cu" "F.Mask" "F.Paste")
			(net "PVCCIO_CPU1")
		)
		(pad "2" smd rect
			(at 0 0.889 90)
			(size 0.508 0.508)
			(layers "F.Cu" "F.Mask" "F.Paste")
			(net "GND")
		)
		(zone
			(layer "F.Cu")
			(hatch none 0.5)
			(connect_pads
				(clearance 0)
			)
			(min_thickness 0.25)
			(keepout
				(tracks allowed)
				(vias not_allowed)
				(pads allowed)
				(copperpour not_allowed)
				(footprints allowed)
			)
			(placement
				(enabled no)
				(sheetname "")
			)
			(fill
				(thermal_gap 0.5)
				(thermal_bridge_width 0.5)
				(island_removal_mode 0)
			)
			(polygon
				(pts
					(xy 158.22422 -124.8537) (xy 158.22422 -125.3617) (xy 158.60522 -125.3617) (xy 158.60522 -124.8537)
				)
			)
		)
		(zone
			(layer "F.Cu")
			(hatch none 0.5)
			(connect_pads
				(clearance 0)
			)
			(min_thickness 0.25)
			(keepout
				(tracks not_allowed)
				(vias allowed)
				(pads allowed)
				(copperpour not_allowed)
				(footprints allowed)
			)
			(placement
				(enabled no)
				(sheetname "")
			)
			(fill
				(thermal_gap 0.5)
				(thermal_bridge_width 0.5)
				(island_removal_mode 0)
			)
			(polygon
				(pts
					(xy 158.60522 -124.8537) (xy 158.60522 -125.3617) (xy 158.22422 -125.3617) (xy 158.22422 -124.8537)
				)
			)
		)
	)
	(footprint ""
		(layer "F.Cu")
		(at 339.471 -21.209 90)
		(property "Reference" "R7F20"
			(at -0.8382 -0.67818 90)
			(unlocked yes)
			(layer "F.SilkS")
			(effects
				(font
					(size 0.4064 0.254)
					(thickness 0.1524)
				)
				(justify left)
			)
		)
		(property "Value" ""
			(at 0 0 90)
			(layer "F.Fab")
			(effects
				(font
					(size 1.27 1.27)
				)
			)
		)
		(duplicate_pad_numbers_are_jumpers no)
		(fp_poly
			(pts
				(xy -0.2794 -0.1016) (xy 0.2794 -0.1016) (xy 0.2794 0.9906) (xy -0.2794 0.9906)
			)
			(stroke
				(width 0)
				(type default)
			)
			(fill no)
			(layer "F.CrtYd")
		)
		(fp_line
			(start 0.2794 -0.1016)
			(end -0.2794 -0.1016)
			(stroke
				(width 0.1)
				(type default)
			)
			(layer "F.Fab")
		)
		(fp_line
			(start -0.2794 -0.1016)
			(end -0.2794 0.9906)
			(stroke
				(width 0.1)
				(type default)
			)
			(layer "F.Fab")
		)
		(fp_line
			(start 0.2794 0.9906)
			(end 0.2794 -0.1016)
			(stroke
				(width 0.1)
				(type default)
			)
			(layer "F.Fab")
		)
		(fp_line
			(start -0.2794 0.9906)
			(end 0.2794 0.9906)
			(stroke
				(width 0.1)
				(type default)
			)
			(layer "F.Fab")
		)
		(pad "1" smd rect
			(at 0 0 90)
			(size 0.508 0.508)
			(layers "F.Cu" "F.Mask" "F.Paste")
			(net "P3V3_STBY")
		)
		(pad "2" smd rect
			(at 0 0.889 90)
			(size 0.508 0.508)
			(layers "F.Cu" "F.Mask" "F.Paste")
			(net "VR_PVDDQ_ABC_VREN")
		)
		(zone
			(layer "F.Cu")
			(hatch none 0.5)
			(connect_pads
				(clearance 0)
			)
			(min_thickness 0.25)
			(keepout
				(tracks allowed)
				(vias not_allowed)
				(pads allowed)
				(copperpour not_allowed)
				(footprints allowed)
			)
			(placement
				(enabled no)
				(sheetname "")
			)
			(fill
				(thermal_gap 0.5)
				(thermal_bridge_width 0.5)
				(island_removal_mode 0)
			)
			(polygon
				(pts
					(xy 339.725 -20.955) (xy 339.725 -21.463) (xy 340.106 -21.463) (xy 340.106 -20.955)
				)
			)
		)
		(zone
			(layer "F.Cu")
			(hatch none 0.5)
			(connect_pads
				(clearance 0)
			)
			(min_thickness 0.25)
			(keepout
				(tracks not_allowed)
				(vias allowed)
				(pads allowed)
				(copperpour not_allowed)
				(footprints allowed)
			)
			(placement
				(enabled no)
				(sheetname "")
			)
			(fill
				(thermal_gap 0.5)
				(thermal_bridge_width 0.5)
				(island_removal_mode 0)
			)
			(polygon
				(pts
					(xy 340.106 -20.955) (xy 340.106 -21.463) (xy 339.725 -21.463) (xy 339.725 -20.955)
				)
			)
		)
	)
	(footprint ""
		(layer "F.Cu")
		(at 35.86734 -93.897196 -90)
		(property "Reference" "RT38"
			(at 0 0 270)
			(layer "F.SilkS")
			(hide yes)
			(effects
				(font
					(size 1.27 1.27)
				)
			)
		)
		(property "Value" "*"
			(at -0.0254 -2.6289 270)
			(unlocked yes)
			(layer "F.Fab")
			(hide yes)
			(effects
				(font
					(size 1.27 1.016)
					(thickness 0.1524)
				)
			)
		)
		(property "Device Type" "1R3F-GP_RCL_GP-1R3F-GP,64.1R00A"
			(at -0.0254 -4.1529 270)
			(unlocked yes)
			(layer "F.Fab")
			(hide yes)
			(effects
				(font
					(size 1.27 1.016)
					(thickness 0.1524)
				)
			)
		)
		(duplicate_pad_numbers_are_jumpers no)
		(fp_line
			(start -0.4826 0)
			(end -0.2032 0)
			(stroke
				(width 0.2032)
				(type default)
			)
			(layer "F.SilkS")
		)
		(fp_line
			(start 0.2032 0)
			(end 0.4826 0)
			(stroke
				(width 0.2032)
				(type default)
			)
			(layer "F.SilkS")
		)
		(fp_rect
			(start -0.5842 1.3335)
			(end 0.5842 -1.3335)
			(stroke
				(width 0)
				(type default)
			)
			(fill no)
			(layer "F.CrtYd")
		)
		(fp_rect
			(start -0.5842 1.3335)
			(end 0.5842 -1.3335)
			(stroke
				(width 0)
				(type default)
			)
			(fill no)
			(layer "F.Fab")
		)
		(pad "1" smd custom
			(at 0 -0.762 270)
			(size 0.2159 0.2159)
			(layers "F.Cu" "F.Mask" "F.Paste")
			(net "VR_PVSA_CPU1_PHASE_SW_RC")
			(options
				(clearance outline)
				(anchor circle)
			)
			(primitives
				(gr_poly
					(pts
						(arc
							(start -0.3302 -0.4318)
							(mid -0.402042 -0.402042)
							(end -0.4318 -0.3302)
						)
						(arc
							(start -0.4318 0.3302)
							(mid -0.402042 0.402042)
							(end -0.3302 0.4318)
						)
						(arc
							(start 0.3302 0.4318)
							(mid 0.402042 0.402042)
							(end 0.4318 0.3302)
						)
						(arc
							(start 0.4318 -0.3302)
							(mid 0.402042 -0.402042)
							(end 0.3302 -0.4318)
						)
					)
					(width 0)
					(fill yes)
				)
			)
		)
		(pad "2" smd custom
			(at 0 0.762 270)
			(size 0.2159 0.2159)
			(layers "F.Cu" "F.Mask" "F.Paste")
			(net "GND")
			(options
				(clearance outline)
				(anchor circle)
			)
			(primitives
				(gr_poly
					(pts
						(arc
							(start -0.3302 -0.4318)
							(mid -0.402042 -0.402042)
							(end -0.4318 -0.3302)
						)
						(arc
							(start -0.4318 0.3302)
							(mid -0.402042 0.402042)
							(end -0.3302 0.4318)
						)
						(arc
							(start 0.3302 0.4318)
							(mid 0.402042 0.402042)
							(end 0.4318 0.3302)
						)
						(arc
							(start 0.4318 -0.3302)
							(mid 0.402042 -0.402042)
							(end 0.3302 -0.4318)
						)
					)
					(width 0)
					(fill yes)
				)
			)
		)
	)
	(footprint ""
		(layer "F.Cu")
		(at 103.400606 -68.365116 180)
		(property "Reference" "C2D45"
			(at 0 0 180)
			(layer "F.SilkS")
			(hide yes)
			(effects
				(font
					(size 1.27 1.27)
				)
			)
		)
		(property "Value" ""
			(at 0 0 180)
			(layer "F.Fab")
			(effects
				(font
					(size 1.27 1.27)
				)
			)
		)
		(duplicate_pad_numbers_are_jumpers no)
		(fp_poly
			(pts
				(xy -0.4953 -0.2032) (xy 0.4953 -0.2032) (xy 0.4953 1.6002) (xy -0.4953 1.6002)
			)
			(stroke
				(width 0)
				(type default)
			)
			(fill no)
			(layer "F.CrtYd")
		)
		(fp_line
			(start 0.4953 1.6002)
			(end -0.4953 1.6002)
			(stroke
				(width 0.1)
				(type default)
			)
			(layer "F.Fab")
		)
		(fp_line
			(start 0.4953 -0.2032)
			(end 0.4953 1.6002)
			(stroke
				(width 0.1)
				(type default)
			)
			(layer "F.Fab")
		)
		(fp_line
			(start -0.4953 1.6002)
			(end -0.4953 -0.2032)
			(stroke
				(width 0.1)
				(type default)
			)
			(layer "F.Fab")
		)
		(fp_line
			(start -0.4953 -0.2032)
			(end 0.4953 -0.2032)
			(stroke
				(width 0.1)
				(type default)
			)
			(layer "F.Fab")
		)
		(pad "1" smd rect
			(at 0 0 180)
			(size 0.762 0.889)
			(layers "F.Cu" "F.Mask" "F.Paste")
			(net "PVDDQ_GHJ")
		)
		(pad "2" smd rect
			(at 0 1.397 180)
			(size 0.762 0.889)
			(layers "F.Cu" "F.Mask" "F.Paste")
			(net "GND")
		)
		(zone
			(layer "F.Cu")
			(hatch none 0.5)
			(connect_pads
				(clearance 0)
			)
			(min_thickness 0.25)
			(keepout
				(tracks not_allowed)
				(vias allowed)
				(pads allowed)
				(copperpour not_allowed)
				(footprints allowed)
			)
			(placement
				(enabled no)
				(sheetname "")
			)
			(fill
				(thermal_gap 0.5)
				(thermal_bridge_width 0.5)
				(island_removal_mode 0)
			)
			(polygon
				(pts
					(xy 103.781606 -68.809616) (xy 103.019606 -68.809616) (xy 103.019606 -69.317616) (xy 103.781606 -69.317616)
				)
			)
		)
	)
	(footprint ""
		(layer "F.Cu")
		(at 166.8272 -20.828 90)
		(property "Reference" "C4F11"
			(at 2.89433 0.6858 0)
			(unlocked yes)
			(layer "F.SilkS")
			(effects
				(font
					(size 0.7874 0.5842)
					(thickness 0.1524)
				)
				(justify left)
			)
		)
		(property "Value" ""
			(at 0 0 90)
			(layer "F.Fab")
			(effects
				(font
					(size 1.27 1.27)
				)
			)
		)
		(duplicate_pad_numbers_are_jumpers no)
		(fp_line
			(start 2.032 -1.524)
			(end 2.032 1.524)
			(stroke
				(width 0.1524)
				(type default)
			)
			(layer "F.SilkS")
		)
		(fp_line
			(start 1.7272 -1.524)
			(end 2.032 -1.524)
			(stroke
				(width 0.1524)
				(type default)
			)
			(layer "F.SilkS")
		)
		(fp_line
			(start -1.7272 -1.524)
			(end -2.032 -1.524)
			(stroke
				(width 0.1524)
				(type default)
			)
			(layer "F.SilkS")
		)
		(fp_line
			(start -2.032 -1.524)
			(end -2.032 1.524)
			(stroke
				(width 0.1524)
				(type default)
			)
			(layer "F.SilkS")
		)
		(fp_line
			(start 2.2987 -0.2413)
			(end 2.032 -0.2413)
			(stroke
				(width 0.1524)
				(type default)
			)
			(layer "F.SilkS")
		)
		(fp_line
			(start -2.032 -0.2413)
			(end -2.2987 -0.2413)
			(stroke
				(width 0.1524)
				(type default)
			)
			(layer "F.SilkS")
		)
		(fp_line
			(start -2.2987 -0.2413)
			(end -2.2987 7.3533)
			(stroke
				(width 0.1524)
				(type default)
			)
			(layer "F.SilkS")
		)
		(fp_line
			(start 2.032 1.524)
			(end 1.7272 1.524)
			(stroke
				(width 0.1524)
				(type default)
			)
			(layer "F.SilkS")
		)
		(fp_line
			(start -2.032 1.524)
			(end -1.7272 1.524)
			(stroke
				(width 0.1524)
				(type default)
			)
			(layer "F.SilkS")
		)
		(fp_line
			(start 2.2987 7.3533)
			(end 2.2987 -0.2413)
			(stroke
				(width 0.1524)
				(type default)
			)
			(layer "F.SilkS")
		)
		(fp_line
			(start 1.7272 7.3533)
			(end 2.2987 7.3533)
			(stroke
				(width 0.1524)
				(type default)
			)
			(layer "F.SilkS")
		)
		(fp_line
			(start -2.2987 7.3533)
			(end -1.7272 7.3533)
			(stroke
				(width 0.1524)
				(type default)
			)
			(layer "F.SilkS")
		)
		(fp_rect
			(start -2.2987 -0.2413)
			(end 2.2987 7.3533)
			(stroke
				(width 0)
				(type default)
			)
			(fill no)
			(layer "F.CrtYd")
		)
		(fp_line
			(start 2.2987 -0.2413)
			(end 2.2987 7.3533)
			(stroke
				(width 0.1)
				(type default)
			)
			(layer "F.Fab")
		)
		(fp_line
			(start -2.2987 -0.2413)
			(end 2.2987 -0.2413)
			(stroke
				(width 0.1)
				(type default)
			)
			(layer "F.Fab")
		)
		(fp_line
			(start 2.2987 7.3533)
			(end -2.2987 7.3533)
			(stroke
				(width 0.1)
				(type default)
			)
			(layer "F.Fab")
		)
		(fp_line
			(start -2.2987 7.3533)
			(end -2.2987 -0.2413)
			(stroke
				(width 0.1)
				(type default)
			)
			(layer "F.Fab")
		)
		(pad "1" smd rect
			(at 0 0 90)
			(size 2.54 3.048)
			(layers "F.Cu" "F.Mask" "F.Paste")
			(net "PVPP_GHJ")
		)
		(pad "2" smd rect
			(at 0 7.112 90)
			(size 2.54 3.048)
			(layers "F.Cu" "F.Mask" "F.Paste")
			(net "GND")
		)
	)
	(footprint ""
		(layer "F.Cu")
		(at 391.795 -88.2015)
		(property "Reference" "R8D13"
			(at 0 0 0)
			(layer "F.SilkS")
			(hide yes)
			(effects
				(font
					(size 1.27 1.27)
				)
			)
		)
		(property "Value" ""
			(at 0 0 0)
			(layer "F.Fab")
			(effects
				(font
					(size 1.27 1.27)
				)
			)
		)
		(duplicate_pad_numbers_are_jumpers no)
		(fp_poly
			(pts
				(xy -0.2794 -0.1016) (xy 0.2794 -0.1016) (xy 0.2794 0.9906) (xy -0.2794 0.9906)
			)
			(stroke
				(width 0)
				(type default)
			)
			(fill no)
			(layer "F.CrtYd")
		)
		(fp_line
			(start -0.2794 -0.1016)
			(end -0.2794 0.9906)
			(stroke
				(width 0.1)
				(type default)
			)
			(layer "F.Fab")
		)
		(fp_line
			(start -0.2794 0.9906)
			(end 0.2794 0.9906)
			(stroke
				(width 0.1)
				(type default)
			)
			(layer "F.Fab")
		)
		(fp_line
			(start 0.2794 -0.1016)
			(end -0.2794 -0.1016)
			(stroke
				(width 0.1)
				(type default)
			)
			(layer "F.Fab")
		)
		(fp_line
			(start 0.2794 0.9906)
			(end 0.2794 -0.1016)
			(stroke
				(width 0.1)
				(type default)
			)
			(layer "F.Fab")
		)
		(pad "1" smd rect
			(at 0 0)
			(size 0.508 0.508)
			(layers "F.Cu" "F.Mask" "F.Paste")
			(net "P3V3_STBY")
		)
		(pad "2" smd rect
			(at 0 0.889)
			(size 0.508 0.508)
			(layers "F.Cu" "F.Mask" "F.Paste")
			(net "PU_ADR_TIMER_HOLD_OFF_N")
		)
		(zone
			(layer "F.Cu")
			(hatch none 0.5)
			(connect_pads
				(clearance 0)
			)
			(min_thickness 0.25)
			(keepout
				(tracks allowed)
				(vias not_allowed)
				(pads allowed)
				(copperpour not_allowed)
				(footprints allowed)
			)
			(placement
				(enabled no)
				(sheetname "")
			)
			(fill
				(thermal_gap 0.5)
				(thermal_bridge_width 0.5)
				(island_removal_mode 0)
			)
			(polygon
				(pts
					(xy 391.541 -87.9475) (xy 392.049 -87.9475) (xy 392.049 -87.5665) (xy 391.541 -87.5665)
				)
			)
		)
		(zone
			(layer "F.Cu")
			(hatch none 0.5)
			(connect_pads
				(clearance 0)
			)
			(min_thickness 0.25)
			(keepout
				(tracks not_allowed)
				(vias allowed)
				(pads allowed)
				(copperpour not_allowed)
				(footprints allowed)
			)
			(placement
				(enabled no)
				(sheetname "")
			)
			(fill
				(thermal_gap 0.5)
				(thermal_bridge_width 0.5)
				(island_removal_mode 0)
			)
			(polygon
				(pts
					(xy 391.541 -87.5665) (xy 392.049 -87.5665) (xy 392.049 -87.9475) (xy 391.541 -87.9475)
				)
			)
		)
	)
	(footprint ""
		(layer "F.Cu")
		(at 209.296 -52.79898 -90)
		(property "Reference" "R4E13"
			(at 0 0 270)
			(layer "F.SilkS")
			(hide yes)
			(effects
				(font
					(size 1.27 1.27)
				)
			)
		)
		(property "Value" ""
			(at 0 0 270)
			(layer "F.Fab")
			(effects
				(font
					(size 1.27 1.27)
				)
			)
		)
		(duplicate_pad_numbers_are_jumpers no)
		(fp_poly
			(pts
				(xy -0.4953 -0.2032) (xy 0.4953 -0.2032) (xy 0.4953 1.6002) (xy -0.4953 1.6002)
			)
			(stroke
				(width 0)
				(type default)
			)
			(fill no)
			(layer "F.CrtYd")
		)
		(fp_line
			(start -0.4953 1.6002)
			(end -0.4953 -0.2032)
			(stroke
				(width 0.1)
				(type default)
			)
			(layer "F.Fab")
		)
		(fp_line
			(start 0.4953 1.6002)
			(end -0.4953 1.6002)
			(stroke
				(width 0.1)
				(type default)
			)
			(layer "F.Fab")
		)
		(fp_line
			(start -0.4953 -0.2032)
			(end 0.4953 -0.2032)
			(stroke
				(width 0.1)
				(type default)
			)
			(layer "F.Fab")
		)
		(fp_line
			(start 0.4953 -0.2032)
			(end 0.4953 1.6002)
			(stroke
				(width 0.1)
				(type default)
			)
			(layer "F.Fab")
		)
		(pad "1" smd rect
			(at 0 0 270)
			(size 0.762 0.889)
			(layers "F.Cu" "F.Mask" "F.Paste")
			(net "PVCCIN_CPU0")
		)
		(pad "2" smd rect
			(at 0 1.397 270)
			(size 0.762 0.889)
			(layers "F.Cu" "F.Mask" "F.Paste")
			(net "GND")
		)
		(zone
			(layer "F.Cu")
			(hatch none 0.5)
			(connect_pads
				(clearance 0)
			)
			(min_thickness 0.25)
			(keepout
				(tracks not_allowed)
				(vias allowed)
				(pads allowed)
				(copperpour not_allowed)
				(footprints allowed)
			)
			(placement
				(enabled no)
				(sheetname "")
			)
			(fill
				(thermal_gap 0.5)
				(thermal_bridge_width 0.5)
				(island_removal_mode 0)
			)
			(polygon
				(pts
					(xy 208.3435 -53.17998) (xy 208.3435 -52.41798) (xy 208.8515 -52.41798) (xy 208.8515 -53.17998)
				)
			)
		)
		(zone
			(layer "F.Cu")
			(hatch none 0.5)
			(connect_pads
				(clearance 0)
			)
			(min_thickness 0.25)
			(keepout
				(tracks allowed)
				(vias not_allowed)
				(pads allowed)
				(copperpour not_allowed)
				(footprints allowed)
			)
			(placement
				(enabled no)
				(sheetname "")
			)
			(fill
				(thermal_gap 0.5)
				(thermal_bridge_width 0.5)
				(island_removal_mode 0)
			)
			(polygon
				(pts
					(xy 208.3435 -52.41798) (xy 208.8515 -52.41798) (xy 208.8515 -53.17998) (xy 208.3435 -53.17998)
				)
			)
		)
	)
	(footprint ""
		(layer "F.Cu")
		(at 420.103046 -48.968152)
		(property "Reference" "R25W101"
			(at -0.8382 -0.67818 0)
			(unlocked yes)
			(layer "F.SilkS")
			(effects
				(font
					(size 0.4064 0.254)
					(thickness 0.1524)
				)
				(justify left)
			)
		)
		(property "Value" ""
			(at 0 0 0)
			(layer "F.Fab")
			(effects
				(font
					(size 1.27 1.27)
				)
			)
		)
		(duplicate_pad_numbers_are_jumpers no)
		(fp_poly
			(pts
				(xy -0.2794 -0.1016) (xy 0.2794 -0.1016) (xy 0.2794 0.9906) (xy -0.2794 0.9906)
			)
			(stroke
				(width 0)
				(type default)
			)
			(fill no)
			(layer "F.CrtYd")
		)
		(fp_line
			(start -0.2794 -0.1016)
			(end -0.2794 0.9906)
			(stroke
				(width 0.1)
				(type default)
			)
			(layer "F.Fab")
		)
		(fp_line
			(start -0.2794 0.9906)
			(end 0.2794 0.9906)
			(stroke
				(width 0.1)
				(type default)
			)
			(layer "F.Fab")
		)
		(fp_line
			(start 0.2794 -0.1016)
			(end -0.2794 -0.1016)
			(stroke
				(width 0.1)
				(type default)
			)
			(layer "F.Fab")
		)
		(fp_line
			(start 0.2794 0.9906)
			(end 0.2794 -0.1016)
			(stroke
				(width 0.1)
				(type default)
			)
			(layer "F.Fab")
		)
		(pad "1" smd rect
			(at 0 0)
			(size 0.508 0.508)
			(layers "F.Cu" "F.Mask" "F.Paste")
			(net "P3V3_STBY")
		)
		(pad "2" smd rect
			(at 0 0.889)
			(size 0.508 0.508)
			(layers "F.Cu" "F.Mask" "F.Paste")
			(net "BMC_STRAP_BIT17")
		)
		(zone
			(layer "F.Cu")
			(hatch none 0.5)
			(connect_pads
				(clearance 0)
			)
			(min_thickness 0.25)
			(keepout
				(tracks allowed)
				(vias not_allowed)
				(pads allowed)
				(copperpour not_allowed)
				(footprints allowed)
			)
			(placement
				(enabled no)
				(sheetname "")
			)
			(fill
				(thermal_gap 0.5)
				(thermal_bridge_width 0.5)
				(island_removal_mode 0)
			)
			(polygon
				(pts
					(xy 419.849046 -48.714152) (xy 420.357046 -48.714152) (xy 420.357046 -48.333152) (xy 419.849046 -48.333152)
				)
			)
		)
		(zone
			(layer "F.Cu")
			(hatch none 0.5)
			(connect_pads
				(clearance 0)
			)
			(min_thickness 0.25)
			(keepout
				(tracks not_allowed)
				(vias allowed)
				(pads allowed)
				(copperpour not_allowed)
				(footprints allowed)
			)
			(placement
				(enabled no)
				(sheetname "")
			)
			(fill
				(thermal_gap 0.5)
				(thermal_bridge_width 0.5)
				(island_removal_mode 0)
			)
			(polygon
				(pts
					(xy 419.849046 -48.333152) (xy 420.357046 -48.333152) (xy 420.357046 -48.714152) (xy 419.849046 -48.714152)
				)
			)
		)
	)
	(footprint ""
		(layer "F.Cu")
		(at 353.387914 -134.222744 180)
		(property "Reference" "R3M1"
			(at 0 0 180)
			(layer "F.SilkS")
			(hide yes)
			(effects
				(font
					(size 1.27 1.27)
				)
			)
		)
		(property "Value" ""
			(at 0 0 180)
			(layer "F.Fab")
			(effects
				(font
					(size 1.27 1.27)
				)
			)
		)
		(duplicate_pad_numbers_are_jumpers no)
		(fp_rect
			(start -0.2794 -0.1016)
			(end 0.2794 0.9906)
			(stroke
				(width 0)
				(type default)
			)
			(fill no)
			(layer "F.CrtYd")
		)
		(fp_line
			(start 0.2794 0.9906)
			(end 0.2794 -0.1016)
			(stroke
				(width 0.1)
				(type default)
			)
			(layer "F.Fab")
		)
		(fp_line
			(start 0.2794 -0.1016)
			(end -0.2794 -0.1016)
			(stroke
				(width 0.1)
				(type default)
			)
			(layer "F.Fab")
		)
		(fp_line
			(start -0.2794 0.9906)
			(end 0.2794 0.9906)
			(stroke
				(width 0.1)
				(type default)
			)
			(layer "F.Fab")
		)
		(fp_line
			(start -0.2794 -0.1016)
			(end -0.2794 0.9906)
			(stroke
				(width 0.1)
				(type default)
			)
			(layer "F.Fab")
		)
		(pad "1" smd rect
			(at 0 0 180)
			(size 0.508 0.508)
			(layers "F.Cu" "F.Mask" "F.Paste")
			(net "P3V3_STBY")
		)
		(pad "2" smd rect
			(at 0 0.889 180)
			(size 0.508 0.508)
			(layers "F.Cu" "F.Mask" "F.Paste")
			(net "VR_PVDDQ_DEF_VDD")
		)
		(zone
			(layer "F.Cu")
			(hatch none 0.5)
			(connect_pads
				(clearance 0)
			)
			(min_thickness 0.25)
			(keepout
				(tracks allowed)
				(vias not_allowed)
				(pads allowed)
				(copperpour not_allowed)
				(footprints allowed)
			)
			(placement
				(enabled no)
				(sheetname "")
			)
			(fill
				(thermal_gap 0.5)
				(thermal_bridge_width 0.5)
				(island_removal_mode 0)
			)
			(polygon
				(pts
					(xy 353.641914 -134.476744) (xy 353.641914 -134.857744) (xy 353.133914 -134.857744) (xy 353.133914 -134.476744)
				)
			)
		)
		(zone
			(layer "F.Cu")
			(hatch none 0.5)
			(connect_pads
				(clearance 0)
			)
			(min_thickness 0.25)
			(keepout
				(tracks not_allowed)
				(vias allowed)
				(pads allowed)
				(copperpour not_allowed)
				(footprints allowed)
			)
			(placement
				(enabled no)
				(sheetname "")
			)
			(fill
				(thermal_gap 0.5)
				(thermal_bridge_width 0.5)
				(island_removal_mode 0)
			)
			(polygon
				(pts
					(xy 353.641914 -134.476744) (xy 353.641914 -134.857744) (xy 353.133914 -134.857744) (xy 353.133914 -134.476744)
				)
			)
		)
	)
	(footprint ""
		(layer "F.Cu")
		(at 400.558 -154.19324 180)
		(property "Reference" "R8W2"
			(at -0.8382 -0.67818 180)
			(unlocked yes)
			(layer "F.SilkS")
			(effects
				(font
					(size 0.4064 0.254)
					(thickness 0.1524)
				)
				(justify left)
			)
		)
		(property "Value" ""
			(at 0 0 180)
			(layer "F.Fab")
			(effects
				(font
					(size 1.27 1.27)
				)
			)
		)
		(duplicate_pad_numbers_are_jumpers no)
		(fp_poly
			(pts
				(xy -0.2794 -0.1016) (xy 0.2794 -0.1016) (xy 0.2794 0.9906) (xy -0.2794 0.9906)
			)
			(stroke
				(width 0)
				(type default)
			)
			(fill no)
			(layer "F.CrtYd")
		)
		(fp_line
			(start 0.2794 0.9906)
			(end 0.2794 -0.1016)
			(stroke
				(width 0.1)
				(type default)
			)
			(layer "F.Fab")
		)
		(fp_line
			(start 0.2794 -0.1016)
			(end -0.2794 -0.1016)
			(stroke
				(width 0.1)
				(type default)
			)
			(layer "F.Fab")
		)
		(fp_line
			(start -0.2794 0.9906)
			(end 0.2794 0.9906)
			(stroke
				(width 0.1)
				(type default)
			)
			(layer "F.Fab")
		)
		(fp_line
			(start -0.2794 -0.1016)
			(end -0.2794 0.9906)
			(stroke
				(width 0.1)
				(type default)
			)
			(layer "F.Fab")
		)
		(pad "1" smd rect
			(at 0 0 180)
			(size 0.508 0.508)
			(layers "F.Cu" "F.Mask" "F.Paste")
			(net "PU_PVNN_PCH_VCLK")
		)
		(pad "2" smd rect
			(at 0 0.889 180)
			(size 0.508 0.508)
			(layers "F.Cu" "F.Mask" "F.Paste")
			(net "VR_PVNN_P1V05_PCH_VD12")
		)
		(zone
			(layer "F.Cu")
			(hatch none 0.5)
			(connect_pads
				(clearance 0)
			)
			(min_thickness 0.25)
			(keepout
				(tracks not_allowed)
				(vias allowed)
				(pads allowed)
				(copperpour not_allowed)
				(footprints allowed)
			)
			(placement
				(enabled no)
				(sheetname "")
			)
			(fill
				(thermal_gap 0.5)
				(thermal_bridge_width 0.5)
				(island_removal_mode 0)
			)
			(polygon
				(pts
					(xy 400.812 -154.82824) (xy 400.304 -154.82824) (xy 400.304 -154.44724) (xy 400.812 -154.44724)
				)
			)
		)
		(zone
			(layer "F.Cu")
			(hatch none 0.5)
			(connect_pads
				(clearance 0)
			)
			(min_thickness 0.25)
			(keepout
				(tracks allowed)
				(vias not_allowed)
				(pads allowed)
				(copperpour not_allowed)
				(footprints allowed)
			)
			(placement
				(enabled no)
				(sheetname "")
			)
			(fill
				(thermal_gap 0.5)
				(thermal_bridge_width 0.5)
				(island_removal_mode 0)
			)
			(polygon
				(pts
					(xy 400.812 -154.44724) (xy 400.304 -154.44724) (xy 400.304 -154.82824) (xy 400.812 -154.82824)
				)
			)
		)
	)
	(footprint ""
		(layer "F.Cu")
		(at 11.130026 -4.419854)
		(property "Reference" "R1G7"
			(at 0 0 0)
			(layer "F.SilkS")
			(hide yes)
			(effects
				(font
					(size 1.27 1.27)
				)
			)
		)
		(property "Value" ""
			(at 0 0 0)
			(layer "F.Fab")
			(effects
				(font
					(size 1.27 1.27)
				)
			)
		)
		(duplicate_pad_numbers_are_jumpers no)
		(fp_rect
			(start -0.2794 -0.1016)
			(end 0.2794 0.9906)
			(stroke
				(width 0)
				(type default)
			)
			(fill no)
			(layer "F.CrtYd")
		)
		(fp_line
			(start -0.2794 -0.1016)
			(end -0.2794 0.9906)
			(stroke
				(width 0.1)
				(type default)
			)
			(layer "F.Fab")
		)
		(fp_line
			(start -0.2794 0.9906)
			(end 0.2794 0.9906)
			(stroke
				(width 0.1)
				(type default)
			)
			(layer "F.Fab")
		)
		(fp_line
			(start 0.2794 -0.1016)
			(end -0.2794 -0.1016)
			(stroke
				(width 0.1)
				(type default)
			)
			(layer "F.Fab")
		)
		(fp_line
			(start 0.2794 0.9906)
			(end 0.2794 -0.1016)
			(stroke
				(width 0.1)
				(type default)
			)
			(layer "F.Fab")
		)
		(pad "1" smd rect
			(at 0 0)
			(size 0.508 0.508)
			(layers "F.Cu" "F.Mask" "F.Paste")
			(net "SVID_CLK1_CPU1_R")
		)
		(pad "2" smd rect
			(at 0 0.889)
			(size 0.508 0.508)
			(layers "F.Cu" "F.Mask" "F.Paste")
			(net "SVID_CLK_PVDDQ_GHJ")
		)
		(zone
			(layer "F.Cu")
			(hatch none 0.5)
			(connect_pads
				(clearance 0)
			)
			(min_thickness 0.25)
			(keepout
				(tracks allowed)
				(vias not_allowed)
				(pads allowed)
				(copperpour not_allowed)
				(footprints allowed)
			)
			(placement
				(enabled no)
				(sheetname "")
			)
			(fill
				(thermal_gap 0.5)
				(thermal_bridge_width 0.5)
				(island_removal_mode 0)
			)
			(polygon
				(pts
					(xy 10.876026 -4.165854) (xy 10.876026 -3.784854) (xy 11.384026 -3.784854) (xy 11.384026 -4.165854)
				)
			)
		)
		(zone
			(layer "F.Cu")
			(hatch none 0.5)
			(connect_pads
				(clearance 0)
			)
			(min_thickness 0.25)
			(keepout
				(tracks not_allowed)
				(vias allowed)
				(pads allowed)
				(copperpour not_allowed)
				(footprints allowed)
			)
			(placement
				(enabled no)
				(sheetname "")
			)
			(fill
				(thermal_gap 0.5)
				(thermal_bridge_width 0.5)
				(island_removal_mode 0)
			)
			(polygon
				(pts
					(xy 10.876026 -4.165854) (xy 10.876026 -3.784854) (xy 11.384026 -3.784854) (xy 11.384026 -4.165854)
				)
			)
		)
	)
	(footprint ""
		(layer "F.Cu")
		(at 163.576 -85.598 -90)
		(property "Reference" "R4D9"
			(at 0 0 270)
			(layer "F.SilkS")
			(hide yes)
			(effects
				(font
					(size 1.27 1.27)
				)
			)
		)
		(property "Value" ""
			(at 0 0 270)
			(layer "F.Fab")
			(effects
				(font
					(size 1.27 1.27)
				)
			)
		)
		(duplicate_pad_numbers_are_jumpers no)
		(fp_poly
			(pts
				(xy -0.2794 -0.1016) (xy 0.2794 -0.1016) (xy 0.2794 0.9906) (xy -0.2794 0.9906)
			)
			(stroke
				(width 0)
				(type default)
			)
			(fill no)
			(layer "F.CrtYd")
		)
		(fp_line
			(start -0.2794 0.9906)
			(end 0.2794 0.9906)
			(stroke
				(width 0.1)
				(type default)
			)
			(layer "F.Fab")
		)
		(fp_line
			(start 0.2794 0.9906)
			(end 0.2794 -0.1016)
			(stroke
				(width 0.1)
				(type default)
			)
			(layer "F.Fab")
		)
		(fp_line
			(start -0.2794 -0.1016)
			(end -0.2794 0.9906)
			(stroke
				(width 0.1)
				(type default)
			)
			(layer "F.Fab")
		)
		(fp_line
			(start 0.2794 -0.1016)
			(end -0.2794 -0.1016)
			(stroke
				(width 0.1)
				(type default)
			)
			(layer "F.Fab")
		)
		(pad "1" smd rect
			(at 0 0 270)
			(size 0.508 0.508)
			(layers "F.Cu" "F.Mask" "F.Paste")
			(net "CLK_100M_CPU1_BCLK2_R_DP")
		)
		(pad "2" smd rect
			(at 0 0.889 270)
			(size 0.508 0.508)
			(layers "F.Cu" "F.Mask" "F.Paste")
			(net "CLK_100M_CPU1_BCLK2_DP")
		)
		(zone
			(layer "F.Cu")
			(hatch none 0.5)
			(connect_pads
				(clearance 0)
			)
			(min_thickness 0.25)
			(keepout
				(tracks not_allowed)
				(vias allowed)
				(pads allowed)
				(copperpour not_allowed)
				(footprints allowed)
			)
			(placement
				(enabled no)
				(sheetname "")
			)
			(fill
				(thermal_gap 0.5)
				(thermal_bridge_width 0.5)
				(island_removal_mode 0)
			)
			(polygon
				(pts
					(xy 162.941 -85.852) (xy 162.941 -85.344) (xy 163.322 -85.344) (xy 163.322 -85.852)
				)
			)
		)
		(zone
			(layer "F.Cu")
			(hatch none 0.5)
			(connect_pads
				(clearance 0)
			)
			(min_thickness 0.25)
			(keepout
				(tracks allowed)
				(vias not_allowed)
				(pads allowed)
				(copperpour not_allowed)
				(footprints allowed)
			)
			(placement
				(enabled no)
				(sheetname "")
			)
			(fill
				(thermal_gap 0.5)
				(thermal_bridge_width 0.5)
				(island_removal_mode 0)
			)
			(polygon
				(pts
					(xy 163.322 -85.852) (xy 163.322 -85.344) (xy 162.941 -85.344) (xy 162.941 -85.852)
				)
			)
		)
	)
	(footprint ""
		(layer "F.Cu")
		(at 377.8123 -137.1092)
		(property "Reference" "C7A36"
			(at 0 0 0)
			(layer "F.SilkS")
			(hide yes)
			(effects
				(font
					(size 1.27 1.27)
				)
			)
		)
		(property "Value" ""
			(at 0 0 0)
			(layer "F.Fab")
			(effects
				(font
					(size 1.27 1.27)
				)
			)
		)
		(duplicate_pad_numbers_are_jumpers no)
		(fp_rect
			(start -0.4953 1.6002)
			(end 0.4953 -0.2032)
			(stroke
				(width 0)
				(type default)
			)
			(fill no)
			(layer "F.CrtYd")
		)
		(fp_line
			(start -0.4953 -0.2032)
			(end 0.4953 -0.2032)
			(stroke
				(width 0.1)
				(type default)
			)
			(layer "F.Fab")
		)
		(fp_line
			(start -0.4953 1.6002)
			(end -0.4953 -0.2032)
			(stroke
				(width 0.1)
				(type default)
			)
			(layer "F.Fab")
		)
		(fp_line
			(start 0.4953 -0.2032)
			(end 0.4953 1.6002)
			(stroke
				(width 0.1)
				(type default)
			)
			(layer "F.Fab")
		)
		(fp_line
			(start 0.4953 1.6002)
			(end -0.4953 1.6002)
			(stroke
				(width 0.1)
				(type default)
			)
			(layer "F.Fab")
		)
		(pad "1" smd rect
			(at 0 0)
			(size 0.762 0.889)
			(layers "F.Cu" "F.Mask" "F.Paste")
			(net "PVNN_PCH_STBY")
		)
		(pad "2" smd rect
			(at 0 1.397)
			(size 0.762 0.889)
			(layers "F.Cu" "F.Mask" "F.Paste")
			(net "GND")
		)
		(zone
			(layer "F.Cu")
			(hatch none 0.5)
			(connect_pads
				(clearance 0)
			)
			(min_thickness 0.25)
			(keepout
				(tracks not_allowed)
				(vias allowed)
				(pads allowed)
				(copperpour not_allowed)
				(footprints allowed)
			)
			(placement
				(enabled no)
				(sheetname "")
			)
			(fill
				(thermal_gap 0.5)
				(thermal_bridge_width 0.5)
				(island_removal_mode 0)
			)
			(polygon
				(pts
					(xy 377.4313 -136.1567) (xy 378.1933 -136.1567) (xy 378.1933 -136.6647) (xy 377.4313 -136.6647)
				)
			)
		)
	)
	(footprint ""
		(layer "F.Cu")
		(at 7.665212 -108.42117 90)
		(property "Reference" "C9M5"
			(at 0 0 90)
			(layer "F.SilkS")
			(hide yes)
			(effects
				(font
					(size 1.27 1.27)
				)
			)
		)
		(property "Value" ""
			(at 0 0 90)
			(layer "F.Fab")
			(effects
				(font
					(size 1.27 1.27)
				)
			)
		)
		(duplicate_pad_numbers_are_jumpers no)
		(fp_poly
			(pts
				(xy 0.3048 -0.1016) (xy 0.3048 0.9906) (xy -0.3048 0.9906) (xy -0.3048 -0.1016)
			)
			(stroke
				(width 0)
				(type default)
			)
			(fill no)
			(layer "F.CrtYd")
		)
		(fp_line
			(start 0.3048 -0.1016)
			(end -0.3048 -0.1016)
			(stroke
				(width 0.1)
				(type default)
			)
			(layer "F.Fab")
		)
		(fp_line
			(start -0.3048 -0.1016)
			(end -0.3048 0.9906)
			(stroke
				(width 0.1)
				(type default)
			)
			(layer "F.Fab")
		)
		(fp_line
			(start 0.3048 0.9906)
			(end 0.3048 -0.1016)
			(stroke
				(width 0.1)
				(type default)
			)
			(layer "F.Fab")
		)
		(fp_line
			(start -0.3048 0.9906)
			(end 0.3048 0.9906)
			(stroke
				(width 0.1)
				(type default)
			)
			(layer "F.Fab")
		)
		(pad "1" smd rect
			(at 0 0 90)
			(size 0.508 0.508)
			(layers "F.Cu" "F.Mask" "F.Paste")
			(net "P12V_FAN")
		)
		(pad "2" smd rect
			(at 0 0.889 90)
			(size 0.508 0.508)
			(layers "F.Cu" "F.Mask" "F.Paste")
			(net "GND")
		)
		(zone
			(layer "F.Cu")
			(hatch none 0.5)
			(connect_pads
				(clearance 0)
			)
			(min_thickness 0.25)
			(keepout
				(tracks allowed)
				(vias not_allowed)
				(pads allowed)
				(copperpour not_allowed)
				(footprints allowed)
			)
			(placement
				(enabled no)
				(sheetname "")
			)
			(fill
				(thermal_gap 0.5)
				(thermal_bridge_width 0.5)
				(island_removal_mode 0)
			)
			(polygon
				(pts
					(xy 7.919212 -108.16717) (xy 7.919212 -108.67517) (xy 8.300212 -108.67517) (xy 8.300212 -108.16717)
				)
			)
		)
		(zone
			(layer "F.Cu")
			(hatch none 0.5)
			(connect_pads
				(clearance 0)
			)
			(min_thickness 0.25)
			(keepout
				(tracks not_allowed)
				(vias allowed)
				(pads allowed)
				(copperpour not_allowed)
				(footprints allowed)
			)
			(placement
				(enabled no)
				(sheetname "")
			)
			(fill
				(thermal_gap 0.5)
				(thermal_bridge_width 0.5)
				(island_removal_mode 0)
			)
			(polygon
				(pts
					(xy 8.300212 -108.16717) (xy 8.300212 -108.67517) (xy 7.919212 -108.67517) (xy 7.919212 -108.16717)
				)
			)
		)
	)
	(footprint ""
		(layer "F.Cu")
		(at 385.2926 -0.254)
		(property "Reference" "R7G16"
			(at 0 0 0)
			(layer "F.SilkS")
			(hide yes)
			(effects
				(font
					(size 1.27 1.27)
				)
			)
		)
		(property "Value" ""
			(at 0 0 0)
			(layer "F.Fab")
			(effects
				(font
					(size 1.27 1.27)
				)
			)
		)
		(duplicate_pad_numbers_are_jumpers no)
		(fp_poly
			(pts
				(xy -0.2794 -0.1016) (xy 0.2794 -0.1016) (xy 0.2794 0.9906) (xy -0.2794 0.9906)
			)
			(stroke
				(width 0)
				(type default)
			)
			(fill no)
			(layer "F.CrtYd")
		)
		(fp_line
			(start -0.2794 -0.1016)
			(end -0.2794 0.9906)
			(stroke
				(width 0.1)
				(type default)
			)
			(layer "F.Fab")
		)
		(fp_line
			(start -0.2794 0.9906)
			(end 0.2794 0.9906)
			(stroke
				(width 0.1)
				(type default)
			)
			(layer "F.Fab")
		)
		(fp_line
			(start 0.2794 -0.1016)
			(end -0.2794 -0.1016)
			(stroke
				(width 0.1)
				(type default)
			)
			(layer "F.Fab")
		)
		(fp_line
			(start 0.2794 0.9906)
			(end 0.2794 -0.1016)
			(stroke
				(width 0.1)
				(type default)
			)
			(layer "F.Fab")
		)
		(pad "1" smd rect
			(at 0 0)
			(size 0.508 0.508)
			(layers "F.Cu" "F.Mask" "F.Paste")
			(net "JTAG_PCH_GBE_TDO")
		)
		(pad "2" smd rect
			(at 0 0.889)
			(size 0.508 0.508)
			(layers "F.Cu" "F.Mask" "F.Paste")
			(net "JTAG_TDO")
		)
		(zone
			(layer "F.Cu")
			(hatch none 0.5)
			(connect_pads
				(clearance 0)
			)
			(min_thickness 0.25)
			(keepout
				(tracks allowed)
				(vias not_allowed)
				(pads allowed)
				(copperpour not_allowed)
				(footprints allowed)
			)
			(placement
				(enabled no)
				(sheetname "")
			)
			(fill
				(thermal_gap 0.5)
				(thermal_bridge_width 0.5)
				(island_removal_mode 0)
			)
			(polygon
				(pts
					(xy 385.0386 0) (xy 385.5466 0) (xy 385.5466 0.381) (xy 385.0386 0.381)
				)
			)
		)
		(zone
			(layer "F.Cu")
			(hatch none 0.5)
			(connect_pads
				(clearance 0)
			)
			(min_thickness 0.25)
			(keepout
				(tracks not_allowed)
				(vias allowed)
				(pads allowed)
				(copperpour not_allowed)
				(footprints allowed)
			)
			(placement
				(enabled no)
				(sheetname "")
			)
			(fill
				(thermal_gap 0.5)
				(thermal_bridge_width 0.5)
				(island_removal_mode 0)
			)
			(polygon
				(pts
					(xy 385.0386 0.381) (xy 385.5466 0.381) (xy 385.5466 0) (xy 385.0386 0)
				)
			)
		)
	)
	(footprint ""
		(layer "F.Cu")
		(at -0.60706 -132.54736)
		(property "Reference" "R1B2"
			(at 0 0 0)
			(layer "F.SilkS")
			(hide yes)
			(effects
				(font
					(size 1.27 1.27)
				)
			)
		)
		(property "Value" ""
			(at 0 0 0)
			(layer "F.Fab")
			(effects
				(font
					(size 1.27 1.27)
				)
			)
		)
		(duplicate_pad_numbers_are_jumpers no)
		(fp_rect
			(start -0.2794 0.9906)
			(end 0.2794 -0.1016)
			(stroke
				(width 0)
				(type default)
			)
			(fill no)
			(layer "F.CrtYd")
		)
		(fp_line
			(start -0.2794 -0.1016)
			(end -0.2794 0.9906)
			(stroke
				(width 0.1)
				(type default)
			)
			(layer "F.Fab")
		)
		(fp_line
			(start -0.2794 0.9906)
			(end 0.2794 0.9906)
			(stroke
				(width 0.1)
				(type default)
			)
			(layer "F.Fab")
		)
		(fp_line
			(start 0.2794 -0.1016)
			(end -0.2794 -0.1016)
			(stroke
				(width 0.1)
				(type default)
			)
			(layer "F.Fab")
		)
		(fp_line
			(start 0.2794 0.9906)
			(end 0.2794 -0.1016)
			(stroke
				(width 0.1)
				(type default)
			)
			(layer "F.Fab")
		)
		(pad "1" smd rect
			(at 0 0)
			(size 0.508 0.508)
			(layers "F.Cu" "F.Mask" "F.Paste")
			(net "P3V3_STBY")
		)
		(pad "2" smd rect
			(at 0 0.889)
			(size 0.508 0.508)
			(layers "F.Cu" "F.Mask" "F.Paste")
			(net "PWRGD_PVDDQ_KLM_R")
		)
		(zone
			(layer "F.Cu")
			(hatch none 0.5)
			(connect_pads
				(clearance 0)
			)
			(min_thickness 0.25)
			(keepout
				(tracks not_allowed)
				(vias allowed)
				(pads allowed)
				(copperpour not_allowed)
				(footprints allowed)
			)
			(placement
				(enabled no)
				(sheetname "")
			)
			(fill
				(thermal_gap 0.5)
				(thermal_bridge_width 0.5)
				(island_removal_mode 0)
			)
			(polygon
				(pts
					(xy -0.86106 -131.91236) (xy -0.35306 -131.91236) (xy -0.35306 -132.29336) (xy -0.86106 -132.29336)
				)
			)
		)
		(zone
			(layer "F.Cu")
			(hatch none 0.5)
			(connect_pads
				(clearance 0)
			)
			(min_thickness 0.25)
			(keepout
				(tracks allowed)
				(vias not_allowed)
				(pads allowed)
				(copperpour not_allowed)
				(footprints allowed)
			)
			(placement
				(enabled no)
				(sheetname "")
			)
			(fill
				(thermal_gap 0.5)
				(thermal_bridge_width 0.5)
				(island_removal_mode 0)
			)
			(polygon
				(pts
					(xy -0.86106 -131.91236) (xy -0.35306 -131.91236) (xy -0.35306 -132.29336) (xy -0.86106 -132.29336)
				)
			)
		)
	)
	(footprint ""
		(layer "F.Cu")
		(at 281.178 -74.93 90)
		(property "Reference" "R6D7"
			(at 0 0 90)
			(layer "F.SilkS")
			(hide yes)
			(effects
				(font
					(size 1.27 1.27)
				)
			)
		)
		(property "Value" ""
			(at 0 0 90)
			(layer "F.Fab")
			(effects
				(font
					(size 1.27 1.27)
				)
			)
		)
		(duplicate_pad_numbers_are_jumpers no)
		(fp_rect
			(start -0.2794 -0.1016)
			(end 0.2794 0.9906)
			(stroke
				(width 0)
				(type default)
			)
			(fill no)
			(layer "F.CrtYd")
		)
		(fp_line
			(start 0.2794 -0.1016)
			(end -0.2794 -0.1016)
			(stroke
				(width 0.1)
				(type default)
			)
			(layer "F.Fab")
		)
		(fp_line
			(start -0.2794 -0.1016)
			(end -0.2794 0.9906)
			(stroke
				(width 0.1)
				(type default)
			)
			(layer "F.Fab")
		)
		(fp_line
			(start 0.2794 0.9906)
			(end 0.2794 -0.1016)
			(stroke
				(width 0.1)
				(type default)
			)
			(layer "F.Fab")
		)
		(fp_line
			(start -0.2794 0.9906)
			(end 0.2794 0.9906)
			(stroke
				(width 0.1)
				(type default)
			)
			(layer "F.Fab")
		)
		(pad "1" smd rect
			(at 0 0 90)
			(size 0.508 0.508)
			(layers "F.Cu" "F.Mask" "F.Paste")
			(net "PVCCIO_CPU0")
		)
		(pad "2" smd rect
			(at 0 0.889 90)
			(size 0.508 0.508)
			(layers "F.Cu" "F.Mask" "F.Paste")
			(net "H_CPU0_BMCINIT")
		)
		(zone
			(layer "F.Cu")
			(hatch none 0.5)
			(connect_pads
				(clearance 0)
			)
			(min_thickness 0.25)
			(keepout
				(tracks allowed)
				(vias not_allowed)
				(pads allowed)
				(copperpour not_allowed)
				(footprints allowed)
			)
			(placement
				(enabled no)
				(sheetname "")
			)
			(fill
				(thermal_gap 0.5)
				(thermal_bridge_width 0.5)
				(island_removal_mode 0)
			)
			(polygon
				(pts
					(xy 281.432 -74.676) (xy 281.813 -74.676) (xy 281.813 -75.184) (xy 281.432 -75.184)
				)
			)
		)
		(zone
			(layer "F.Cu")
			(hatch none 0.5)
			(connect_pads
				(clearance 0)
			)
			(min_thickness 0.25)
			(keepout
				(tracks not_allowed)
				(vias allowed)
				(pads allowed)
				(copperpour not_allowed)
				(footprints allowed)
			)
			(placement
				(enabled no)
				(sheetname "")
			)
			(fill
				(thermal_gap 0.5)
				(thermal_bridge_width 0.5)
				(island_removal_mode 0)
			)
			(polygon
				(pts
					(xy 281.432 -74.676) (xy 281.813 -74.676) (xy 281.813 -75.184) (xy 281.432 -75.184)
				)
			)
		)
	)
	(footprint ""
		(layer "F.Cu")
		(at 169.103294 -10.262362 90)
		(property "Reference" "C4G26"
			(at 0 0 90)
			(layer "F.SilkS")
			(hide yes)
			(effects
				(font
					(size 1.27 1.27)
				)
			)
		)
		(property "Value" ""
			(at 0 0 90)
			(layer "F.Fab")
			(effects
				(font
					(size 1.27 1.27)
				)
			)
		)
		(duplicate_pad_numbers_are_jumpers no)
		(fp_rect
			(start 0.4953 1.6002)
			(end -0.4953 -0.2032)
			(stroke
				(width 0)
				(type default)
			)
			(fill no)
			(layer "F.CrtYd")
		)
		(fp_line
			(start 0.4953 -0.2032)
			(end 0.4953 1.6002)
			(stroke
				(width 0.1)
				(type default)
			)
			(layer "F.Fab")
		)
		(fp_line
			(start -0.4953 -0.2032)
			(end 0.4953 -0.2032)
			(stroke
				(width 0.1)
				(type default)
			)
			(layer "F.Fab")
		)
		(fp_line
			(start 0.4953 1.6002)
			(end -0.4953 1.6002)
			(stroke
				(width 0.1)
				(type default)
			)
			(layer "F.Fab")
		)
		(fp_line
			(start -0.4953 1.6002)
			(end -0.4953 -0.2032)
			(stroke
				(width 0.1)
				(type default)
			)
			(layer "F.Fab")
		)
		(pad "1" smd rect
			(at 0 0 90)
			(size 0.762 0.889)
			(layers "F.Cu" "F.Mask" "F.Paste")
			(net "VR_PVPP_GHJ_PHASE")
		)
		(pad "2" smd rect
			(at 0 1.397 90)
			(size 0.762 0.889)
			(layers "F.Cu" "F.Mask" "F.Paste")
			(net "VR_PVPP_GHJ_BOOT_R")
		)
		(zone
			(layer "F.Cu")
			(hatch none 0.5)
			(connect_pads
				(clearance 0)
			)
			(min_thickness 0.25)
			(keepout
				(tracks not_allowed)
				(vias allowed)
				(pads allowed)
				(copperpour not_allowed)
				(footprints allowed)
			)
			(placement
				(enabled no)
				(sheetname "")
			)
			(fill
				(thermal_gap 0.5)
				(thermal_bridge_width 0.5)
				(island_removal_mode 0)
			)
			(polygon
				(pts
					(xy 170.055794 -10.643362) (xy 169.547794 -10.643362) (xy 169.547794 -9.881362) (xy 170.055794 -9.881362)
				)
			)
		)
	)
	(footprint ""
		(layer "F.Cu")
		(at 83.856068 -12.954 -90)
		(property "Reference" "C2G2"
			(at 1.848866 0.752348 270)
			(unlocked yes)
			(layer "F.SilkS")
			(effects
				(font
					(size 1.27 0.9652)
					(thickness 0.1524)
				)
			)
		)
		(property "Value" ""
			(at 0 0 270)
			(layer "F.Fab")
			(effects
				(font
					(size 1.27 1.27)
				)
			)
		)
		(duplicate_pad_numbers_are_jumpers no)
		(fp_rect
			(start -0.500126 1.598422)
			(end 0.500126 -0.201422)
			(stroke
				(width 0)
				(type default)
			)
			(fill no)
			(layer "F.CrtYd")
		)
		(fp_line
			(start -0.500126 1.598422)
			(end -0.500126 -0.201422)
			(stroke
				(width 0.1)
				(type default)
			)
			(layer "F.Fab")
		)
		(fp_line
			(start 0.500126 1.598422)
			(end -0.500126 1.598422)
			(stroke
				(width 0.1)
				(type default)
			)
			(layer "F.Fab")
		)
		(fp_line
			(start -0.500126 -0.201422)
			(end 0.500126 -0.201422)
			(stroke
				(width 0.1)
				(type default)
			)
			(layer "F.Fab")
		)
		(fp_line
			(start 0.500126 -0.201422)
			(end 0.500126 1.598422)
			(stroke
				(width 0.1)
				(type default)
			)
			(layer "F.Fab")
		)
		(pad "1" smd rect
			(at 0 0 180)
			(size 0.889 0.9906)
			(layers "F.Cu" "F.Mask" "F.Paste")
			(net "PVDDQ_GHJ")
		)
		(pad "2" smd rect
			(at 0 1.397 180)
			(size 0.889 0.9906)
			(layers "F.Cu" "F.Mask" "F.Paste")
			(net "GND")
		)
		(zone
			(layer "F.Cu")
			(hatch none 0.5)
			(connect_pads
				(clearance 0)
			)
			(min_thickness 0.25)
			(keepout
				(tracks allowed)
				(vias not_allowed)
				(pads allowed)
				(copperpour not_allowed)
				(footprints allowed)
			)
			(placement
				(enabled no)
				(sheetname "")
			)
			(fill
				(thermal_gap 0.5)
				(thermal_bridge_width 0.5)
				(island_removal_mode 0)
			)
			(polygon
				(pts
					(xy 82.903568 -13.4493) (xy 82.903568 -12.4587) (xy 83.411568 -12.4587) (xy 83.411568 -13.4493)
				)
			)
		)
		(zone
			(layer "F.Cu")
			(hatch none 0.5)
			(connect_pads
				(clearance 0)
			)
			(min_thickness 0.25)
			(keepout
				(tracks not_allowed)
				(vias allowed)
				(pads allowed)
				(copperpour not_allowed)
				(footprints allowed)
			)
			(placement
				(enabled no)
				(sheetname "")
			)
			(fill
				(thermal_gap 0.5)
				(thermal_bridge_width 0.5)
				(island_removal_mode 0)
			)
			(polygon
				(pts
					(xy 82.903568 -13.4493) (xy 82.903568 -12.4587) (xy 83.411568 -12.4587) (xy 83.411568 -13.4493)
				)
			)
		)
	)
	(footprint ""
		(layer "F.Cu")
		(at 473.075 -146.7485)
		(property "Reference" "R9A13"
			(at 0 0 0)
			(layer "F.SilkS")
			(hide yes)
			(effects
				(font
					(size 1.27 1.27)
				)
			)
		)
		(property "Value" ""
			(at 0 0 0)
			(layer "F.Fab")
			(effects
				(font
					(size 1.27 1.27)
				)
			)
		)
		(duplicate_pad_numbers_are_jumpers no)
		(fp_poly
			(pts
				(xy -0.2794 -0.1016) (xy 0.2794 -0.1016) (xy 0.2794 0.9906) (xy -0.2794 0.9906)
			)
			(stroke
				(width 0)
				(type default)
			)
			(fill no)
			(layer "F.CrtYd")
		)
		(fp_line
			(start -0.2794 -0.1016)
			(end -0.2794 0.9906)
			(stroke
				(width 0.1)
				(type default)
			)
			(layer "F.Fab")
		)
		(fp_line
			(start -0.2794 0.9906)
			(end 0.2794 0.9906)
			(stroke
				(width 0.1)
				(type default)
			)
			(layer "F.Fab")
		)
		(fp_line
			(start 0.2794 -0.1016)
			(end -0.2794 -0.1016)
			(stroke
				(width 0.1)
				(type default)
			)
			(layer "F.Fab")
		)
		(fp_line
			(start 0.2794 0.9906)
			(end 0.2794 -0.1016)
			(stroke
				(width 0.1)
				(type default)
			)
			(layer "F.Fab")
		)
		(pad "1" smd rect
			(at 0 0)
			(size 0.508 0.508)
			(layers "F.Cu" "F.Mask" "F.Paste")
			(net "FM_PCH_SATA_RAID_KEY_R")
		)
		(pad "2" smd rect
			(at 0 0.889)
			(size 0.508 0.508)
			(layers "F.Cu" "F.Mask" "F.Paste")
			(net "FM_PCH_SATA_RAID_KEY")
		)
		(zone
			(layer "F.Cu")
			(hatch none 0.5)
			(connect_pads
				(clearance 0)
			)
			(min_thickness 0.25)
			(keepout
				(tracks allowed)
				(vias not_allowed)
				(pads allowed)
				(copperpour not_allowed)
				(footprints allowed)
			)
			(placement
				(enabled no)
				(sheetname "")
			)
			(fill
				(thermal_gap 0.5)
				(thermal_bridge_width 0.5)
				(island_removal_mode 0)
			)
			(polygon
				(pts
					(xy 472.821 -146.4945) (xy 473.329 -146.4945) (xy 473.329 -146.1135) (xy 472.821 -146.1135)
				)
			)
		)
		(zone
			(layer "F.Cu")
			(hatch none 0.5)
			(connect_pads
				(clearance 0)
			)
			(min_thickness 0.25)
			(keepout
				(tracks not_allowed)
				(vias allowed)
				(pads allowed)
				(copperpour not_allowed)
				(footprints allowed)
			)
			(placement
				(enabled no)
				(sheetname "")
			)
			(fill
				(thermal_gap 0.5)
				(thermal_bridge_width 0.5)
				(island_removal_mode 0)
			)
			(polygon
				(pts
					(xy 472.821 -146.1135) (xy 473.329 -146.1135) (xy 473.329 -146.4945) (xy 472.821 -146.4945)
				)
			)
		)
	)
	(footprint ""
		(layer "F.Cu")
		(at 351.028 -28.575 180)
		(property "Reference" "C7F5"
			(at 0 0 180)
			(layer "F.SilkS")
			(hide yes)
			(effects
				(font
					(size 1.27 1.27)
				)
			)
		)
		(property "Value" ""
			(at 0 0 180)
			(layer "F.Fab")
			(effects
				(font
					(size 1.27 1.27)
				)
			)
		)
		(duplicate_pad_numbers_are_jumpers no)
		(fp_poly
			(pts
				(xy -0.7239 -0.2159) (xy 0.7239 -0.2159) (xy 0.7239 1.9939) (xy -0.7239 1.9939)
			)
			(stroke
				(width 0)
				(type default)
			)
			(fill no)
			(layer "F.CrtYd")
		)
		(fp_line
			(start 0.7239 1.9939)
			(end 0.7239 -0.2159)
			(stroke
				(width 0.1)
				(type default)
			)
			(layer "F.Fab")
		)
		(fp_line
			(start 0.7239 -0.2159)
			(end -0.7239 -0.2159)
			(stroke
				(width 0.1)
				(type default)
			)
			(layer "F.Fab")
		)
		(fp_line
			(start -0.7239 1.9939)
			(end 0.7239 1.9939)
			(stroke
				(width 0.1)
				(type default)
			)
			(layer "F.Fab")
		)
		(fp_line
			(start -0.7239 -0.2159)
			(end -0.7239 1.9939)
			(stroke
				(width 0.1)
				(type default)
			)
			(layer "F.Fab")
		)
		(pad "1" smd rect
			(at 0 0 180)
			(size 1.27 1.016)
			(layers "F.Cu" "F.Mask" "F.Paste")
			(net "VR_FET_SW_P12V_STBY_PVPP_ABC")
		)
		(pad "2" smd rect
			(at 0 1.778 180)
			(size 1.27 1.016)
			(layers "F.Cu" "F.Mask" "F.Paste")
			(net "GND")
		)
		(zone
			(layer "F.Cu")
			(hatch none 0.5)
			(connect_pads
				(clearance 0)
			)
			(min_thickness 0.25)
			(keepout
				(tracks not_allowed)
				(vias allowed)
				(pads allowed)
				(copperpour not_allowed)
				(footprints allowed)
			)
			(placement
				(enabled no)
				(sheetname "")
			)
			(fill
				(thermal_gap 0.5)
				(thermal_bridge_width 0.5)
				(island_removal_mode 0)
			)
			(polygon
				(pts
					(xy 351.663 -29.083) (xy 350.393 -29.083) (xy 350.393 -29.845) (xy 351.663 -29.845)
				)
			)
		)
	)
	(footprint ""
		(layer "F.Cu")
		(at 422.5798 -21.4122 180)
		(property "Reference" "R8E19"
			(at 0 0 180)
			(layer "F.SilkS")
			(hide yes)
			(effects
				(font
					(size 1.27 1.27)
				)
			)
		)
		(property "Value" ""
			(at 0 0 180)
			(layer "F.Fab")
			(effects
				(font
					(size 1.27 1.27)
				)
			)
		)
		(duplicate_pad_numbers_are_jumpers no)
		(fp_poly
			(pts
				(xy -0.2794 -0.1016) (xy 0.2794 -0.1016) (xy 0.2794 0.9906) (xy -0.2794 0.9906)
			)
			(stroke
				(width 0)
				(type default)
			)
			(fill no)
			(layer "F.CrtYd")
		)
		(fp_line
			(start 0.2794 0.9906)
			(end 0.2794 -0.1016)
			(stroke
				(width 0.1)
				(type default)
			)
			(layer "F.Fab")
		)
		(fp_line
			(start 0.2794 -0.1016)
			(end -0.2794 -0.1016)
			(stroke
				(width 0.1)
				(type default)
			)
			(layer "F.Fab")
		)
		(fp_line
			(start -0.2794 0.9906)
			(end 0.2794 0.9906)
			(stroke
				(width 0.1)
				(type default)
			)
			(layer "F.Fab")
		)
		(fp_line
			(start -0.2794 -0.1016)
			(end -0.2794 0.9906)
			(stroke
				(width 0.1)
				(type default)
			)
			(layer "F.Fab")
		)
		(pad "1" smd rect
			(at 0 0 180)
			(size 0.508 0.508)
			(layers "F.Cu" "F.Mask" "F.Paste")
			(net "P3V3_STBY")
		)
		(pad "2" smd rect
			(at 0 0.889 180)
			(size 0.508 0.508)
			(layers "F.Cu" "F.Mask" "F.Paste")
			(net "FM_BIOS_TOP_SWAP")
		)
		(zone
			(layer "F.Cu")
			(hatch none 0.5)
			(connect_pads
				(clearance 0)
			)
			(min_thickness 0.25)
			(keepout
				(tracks not_allowed)
				(vias allowed)
				(pads allowed)
				(copperpour not_allowed)
				(footprints allowed)
			)
			(placement
				(enabled no)
				(sheetname "")
			)
			(fill
				(thermal_gap 0.5)
				(thermal_bridge_width 0.5)
				(island_removal_mode 0)
			)
			(polygon
				(pts
					(xy 422.8338 -22.0472) (xy 422.3258 -22.0472) (xy 422.3258 -21.6662) (xy 422.8338 -21.6662)
				)
			)
		)
		(zone
			(layer "F.Cu")
			(hatch none 0.5)
			(connect_pads
				(clearance 0)
			)
			(min_thickness 0.25)
			(keepout
				(tracks allowed)
				(vias not_allowed)
				(pads allowed)
				(copperpour not_allowed)
				(footprints allowed)
			)
			(placement
				(enabled no)
				(sheetname "")
			)
			(fill
				(thermal_gap 0.5)
				(thermal_bridge_width 0.5)
				(island_removal_mode 0)
			)
			(polygon
				(pts
					(xy 422.8338 -21.6662) (xy 422.3258 -21.6662) (xy 422.3258 -22.0472) (xy 422.8338 -22.0472)
				)
			)
		)
	)
	(footprint ""
		(layer "F.Cu")
		(at 423.421048 3.679952 180)
		(property "Reference" "BT8G1"
			(at 0 0 180)
			(layer "F.SilkS")
			(hide yes)
			(effects
				(font
					(size 1.27 1.27)
				)
			)
		)
		(property "Value" ""
			(at 0 0 180)
			(layer "F.Fab")
			(effects
				(font
					(size 1.27 1.27)
				)
			)
		)
		(duplicate_pad_numbers_are_jumpers no)
	)
	(footprint ""
		(layer "F.Cu")
		(at 406.654 -94.474792 90)
		(property "Reference" "C8C5"
			(at 0 0 90)
			(layer "F.SilkS")
			(hide yes)
			(effects
				(font
					(size 1.27 1.27)
				)
			)
		)
		(property "Value" ""
			(at 0 0 90)
			(layer "F.Fab")
			(effects
				(font
					(size 1.27 1.27)
				)
			)
		)
		(duplicate_pad_numbers_are_jumpers no)
		(fp_poly
			(pts
				(xy -0.4953 -0.2032) (xy 0.4953 -0.2032) (xy 0.4953 1.6002) (xy -0.4953 1.6002)
			)
			(stroke
				(width 0)
				(type default)
			)
			(fill no)
			(layer "F.CrtYd")
		)
		(fp_line
			(start 0.4953 -0.2032)
			(end 0.4953 1.6002)
			(stroke
				(width 0.1)
				(type default)
			)
			(layer "F.Fab")
		)
		(fp_line
			(start -0.4953 -0.2032)
			(end 0.4953 -0.2032)
			(stroke
				(width 0.1)
				(type default)
			)
			(layer "F.Fab")
		)
		(fp_line
			(start 0.4953 1.6002)
			(end -0.4953 1.6002)
			(stroke
				(width 0.1)
				(type default)
			)
			(layer "F.Fab")
		)
		(fp_line
			(start -0.4953 1.6002)
			(end -0.4953 -0.2032)
			(stroke
				(width 0.1)
				(type default)
			)
			(layer "F.Fab")
		)
		(pad "1" smd rect
			(at 0 0 90)
			(size 0.762 0.889)
			(layers "F.Cu" "F.Mask" "F.Paste")
			(net "P3V3_STBY")
		)
		(pad "2" smd rect
			(at 0 1.397 90)
			(size 0.762 0.889)
			(layers "F.Cu" "F.Mask" "F.Paste")
			(net "GND")
		)
		(zone
			(layer "F.Cu")
			(hatch none 0.5)
			(connect_pads
				(clearance 0)
			)
			(min_thickness 0.25)
			(keepout
				(tracks not_allowed)
				(vias allowed)
				(pads allowed)
				(copperpour not_allowed)
				(footprints allowed)
			)
			(placement
				(enabled no)
				(sheetname "")
			)
			(fill
				(thermal_gap 0.5)
				(thermal_bridge_width 0.5)
				(island_removal_mode 0)
			)
			(polygon
				(pts
					(xy 407.0985 -94.093792) (xy 407.0985 -94.855792) (xy 407.6065 -94.855792) (xy 407.6065 -94.093792)
				)
			)
		)
	)
	(footprint ""
		(layer "F.Cu")
		(at 31.754826 -85.4837 -90)
		(property "Reference" "C1D32"
			(at 0 0 270)
			(layer "F.SilkS")
			(hide yes)
			(effects
				(font
					(size 1.27 1.27)
				)
			)
		)
		(property "Value" ""
			(at 0 0 270)
			(layer "F.Fab")
			(effects
				(font
					(size 1.27 1.27)
				)
			)
		)
		(duplicate_pad_numbers_are_jumpers no)
		(fp_rect
			(start 0.3048 0.9906)
			(end -0.3048 -0.1016)
			(stroke
				(width 0)
				(type default)
			)
			(fill no)
			(layer "F.CrtYd")
		)
		(fp_line
			(start -0.3048 0.9906)
			(end 0.3048 0.9906)
			(stroke
				(width 0.1)
				(type default)
			)
			(layer "F.Fab")
		)
		(fp_line
			(start 0.3048 0.9906)
			(end 0.3048 -0.1016)
			(stroke
				(width 0.1)
				(type default)
			)
			(layer "F.Fab")
		)
		(fp_line
			(start -0.3048 -0.1016)
			(end -0.3048 0.9906)
			(stroke
				(width 0.1)
				(type default)
			)
			(layer "F.Fab")
		)
		(fp_line
			(start 0.3048 -0.1016)
			(end -0.3048 -0.1016)
			(stroke
				(width 0.1)
				(type default)
			)
			(layer "F.Fab")
		)
		(pad "1" smd rect
			(at 0 0 270)
			(size 0.508 0.508)
			(layers "F.Cu" "F.Mask" "F.Paste")
			(net "VR_PVCCIN_CPU1_PH5_VCIN")
		)
		(pad "2" smd rect
			(at 0 0.889 270)
			(size 0.508 0.508)
			(layers "F.Cu" "F.Mask" "F.Paste")
			(net "GND")
		)
		(zone
			(layer "F.Cu")
			(hatch none 0.5)
			(connect_pads
				(clearance 0)
			)
			(min_thickness 0.25)
			(keepout
				(tracks allowed)
				(vias not_allowed)
				(pads allowed)
				(copperpour not_allowed)
				(footprints allowed)
			)
			(placement
				(enabled no)
				(sheetname "")
			)
			(fill
				(thermal_gap 0.5)
				(thermal_bridge_width 0.5)
				(island_removal_mode 0)
			)
			(polygon
				(pts
					(xy 31.119826 -85.2297) (xy 31.500826 -85.2297) (xy 31.500826 -85.7377) (xy 31.119826 -85.7377)
				)
			)
		)
		(zone
			(layer "F.Cu")
			(hatch none 0.5)
			(connect_pads
				(clearance 0)
			)
			(min_thickness 0.25)
			(keepout
				(tracks not_allowed)
				(vias allowed)
				(pads allowed)
				(copperpour not_allowed)
				(footprints allowed)
			)
			(placement
				(enabled no)
				(sheetname "")
			)
			(fill
				(thermal_gap 0.5)
				(thermal_bridge_width 0.5)
				(island_removal_mode 0)
			)
			(polygon
				(pts
					(xy 31.119826 -85.2297) (xy 31.500826 -85.2297) (xy 31.500826 -85.7377) (xy 31.119826 -85.7377)
				)
			)
		)
	)
	(footprint ""
		(layer "F.Cu")
		(at 379.2982 -29.232352 -90)
		(property "Reference" "R8F18"
			(at 0 0 270)
			(layer "F.SilkS")
			(hide yes)
			(effects
				(font
					(size 1.27 1.27)
				)
			)
		)
		(property "Value" ""
			(at 0 0 270)
			(layer "F.Fab")
			(effects
				(font
					(size 1.27 1.27)
				)
			)
		)
		(duplicate_pad_numbers_are_jumpers no)
		(fp_poly
			(pts
				(xy -0.2794 -0.1016) (xy 0.2794 -0.1016) (xy 0.2794 0.9906) (xy -0.2794 0.9906)
			)
			(stroke
				(width 0)
				(type default)
			)
			(fill no)
			(layer "F.CrtYd")
		)
		(fp_line
			(start -0.2794 0.9906)
			(end 0.2794 0.9906)
			(stroke
				(width 0.1)
				(type default)
			)
			(layer "F.Fab")
		)
		(fp_line
			(start 0.2794 0.9906)
			(end 0.2794 -0.1016)
			(stroke
				(width 0.1)
				(type default)
			)
			(layer "F.Fab")
		)
		(fp_line
			(start -0.2794 -0.1016)
			(end -0.2794 0.9906)
			(stroke
				(width 0.1)
				(type default)
			)
			(layer "F.Fab")
		)
		(fp_line
			(start 0.2794 -0.1016)
			(end -0.2794 -0.1016)
			(stroke
				(width 0.1)
				(type default)
			)
			(layer "F.Fab")
		)
		(pad "1" smd rect
			(at 0 0 270)
			(size 0.508 0.508)
			(layers "F.Cu" "F.Mask" "F.Paste")
			(net "P3E_PCH_RX_0_DP")
		)
		(pad "2" smd rect
			(at 0 0.889 270)
			(size 0.508 0.508)
			(layers "F.Cu" "F.Mask" "F.Paste")
			(net "P3E_PCH_M2_SATA6G_RX_R_DP")
		)
		(zone
			(layer "F.Cu")
			(hatch none 0.5)
			(connect_pads
				(clearance 0)
			)
			(min_thickness 0.25)
			(keepout
				(tracks not_allowed)
				(vias allowed)
				(pads allowed)
				(copperpour not_allowed)
				(footprints allowed)
			)
			(placement
				(enabled no)
				(sheetname "")
			)
			(fill
				(thermal_gap 0.5)
				(thermal_bridge_width 0.5)
				(island_removal_mode 0)
			)
			(polygon
				(pts
					(xy 378.6632 -29.486352) (xy 378.6632 -28.978352) (xy 379.0442 -28.978352) (xy 379.0442 -29.486352)
				)
			)
		)
		(zone
			(layer "F.Cu")
			(hatch none 0.5)
			(connect_pads
				(clearance 0)
			)
			(min_thickness 0.25)
			(keepout
				(tracks allowed)
				(vias not_allowed)
				(pads allowed)
				(copperpour not_allowed)
				(footprints allowed)
			)
			(placement
				(enabled no)
				(sheetname "")
			)
			(fill
				(thermal_gap 0.5)
				(thermal_bridge_width 0.5)
				(island_removal_mode 0)
			)
			(polygon
				(pts
					(xy 379.0442 -29.486352) (xy 379.0442 -28.978352) (xy 378.6632 -28.978352) (xy 378.6632 -29.486352)
				)
			)
		)
	)
	(footprint ""
		(layer "F.Cu")
		(at 173.093888 -10.255504 -90)
		(property "Reference" "R4G24"
			(at 1.01473 0.656336 180)
			(unlocked yes)
			(layer "F.SilkS")
			(effects
				(font
					(size 0.4064 0.254)
					(thickness 0.1524)
				)
			)
		)
		(property "Value" ""
			(at 0 0 270)
			(layer "F.Fab")
			(effects
				(font
					(size 1.27 1.27)
				)
			)
		)
		(duplicate_pad_numbers_are_jumpers no)
		(fp_poly
			(pts
				(xy -0.4953 -0.2032) (xy 0.4953 -0.2032) (xy 0.4953 1.6002) (xy -0.4953 1.6002)
			)
			(stroke
				(width 0)
				(type default)
			)
			(fill no)
			(layer "F.CrtYd")
		)
		(fp_line
			(start -0.4953 1.6002)
			(end -0.4953 -0.2032)
			(stroke
				(width 0.1)
				(type default)
			)
			(layer "F.Fab")
		)
		(fp_line
			(start 0.4953 1.6002)
			(end -0.4953 1.6002)
			(stroke
				(width 0.1)
				(type default)
			)
			(layer "F.Fab")
		)
		(fp_line
			(start -0.4953 -0.2032)
			(end 0.4953 -0.2032)
			(stroke
				(width 0.1)
				(type default)
			)
			(layer "F.Fab")
		)
		(fp_line
			(start 0.4953 -0.2032)
			(end 0.4953 1.6002)
			(stroke
				(width 0.1)
				(type default)
			)
			(layer "F.Fab")
		)
		(pad "1" smd rect
			(at 0 0 270)
			(size 0.762 0.889)
			(layers "F.Cu" "F.Mask" "F.Paste")
			(net "VR_PVPP_GHJ_BOOT")
		)
		(pad "2" smd rect
			(at 0 1.397 270)
			(size 0.762 0.889)
			(layers "F.Cu" "F.Mask" "F.Paste")
			(net "VR_PVPP_GHJ_BOOT_R")
		)
		(zone
			(layer "F.Cu")
			(hatch none 0.5)
			(connect_pads
				(clearance 0)
			)
			(min_thickness 0.25)
			(keepout
				(tracks not_allowed)
				(vias allowed)
				(pads allowed)
				(copperpour not_allowed)
				(footprints allowed)
			)
			(placement
				(enabled no)
				(sheetname "")
			)
			(fill
				(thermal_gap 0.5)
				(thermal_bridge_width 0.5)
				(island_removal_mode 0)
			)
			(polygon
				(pts
					(xy 172.141388 -10.636504) (xy 172.141388 -9.874504) (xy 172.649388 -9.874504) (xy 172.649388 -10.636504)
				)
			)
		)
		(zone
			(layer "F.Cu")
			(hatch none 0.5)
			(connect_pads
				(clearance 0)
			)
			(min_thickness 0.25)
			(keepout
				(tracks allowed)
				(vias not_allowed)
				(pads allowed)
				(copperpour not_allowed)
				(footprints allowed)
			)
			(placement
				(enabled no)
				(sheetname "")
			)
			(fill
				(thermal_gap 0.5)
				(thermal_bridge_width 0.5)
				(island_removal_mode 0)
			)
			(polygon
				(pts
					(xy 172.141388 -9.874504) (xy 172.649388 -9.874504) (xy 172.649388 -10.636504) (xy 172.141388 -10.636504)
				)
			)
		)
	)
	(footprint ""
		(layer "F.Cu")
		(at 383.032 -87.3125 180)
		(property "Reference" "R7D8"
			(at 0 0 180)
			(layer "F.SilkS")
			(hide yes)
			(effects
				(font
					(size 1.27 1.27)
				)
			)
		)
		(property "Value" ""
			(at 0 0 180)
			(layer "F.Fab")
			(effects
				(font
					(size 1.27 1.27)
				)
			)
		)
		(duplicate_pad_numbers_are_jumpers no)
		(fp_poly
			(pts
				(xy -0.2794 -0.1016) (xy 0.2794 -0.1016) (xy 0.2794 0.9906) (xy -0.2794 0.9906)
			)
			(stroke
				(width 0)
				(type default)
			)
			(fill no)
			(layer "F.CrtYd")
		)
		(fp_line
			(start 0.2794 0.9906)
			(end 0.2794 -0.1016)
			(stroke
				(width 0.1)
				(type default)
			)
			(layer "F.Fab")
		)
		(fp_line
			(start 0.2794 -0.1016)
			(end -0.2794 -0.1016)
			(stroke
				(width 0.1)
				(type default)
			)
			(layer "F.Fab")
		)
		(fp_line
			(start -0.2794 0.9906)
			(end 0.2794 0.9906)
			(stroke
				(width 0.1)
				(type default)
			)
			(layer "F.Fab")
		)
		(fp_line
			(start -0.2794 -0.1016)
			(end -0.2794 0.9906)
			(stroke
				(width 0.1)
				(type default)
			)
			(layer "F.Fab")
		)
		(pad "1" smd rect
			(at 0 0 180)
			(size 0.508 0.508)
			(layers "F.Cu" "F.Mask" "F.Paste")
			(net "P3V3_STBY")
		)
		(pad "2" smd rect
			(at 0 0.889 180)
			(size 0.508 0.508)
			(layers "F.Cu" "F.Mask" "F.Paste")
			(net "PU_LPC_CLKRUN_N")
		)
		(zone
			(layer "F.Cu")
			(hatch none 0.5)
			(connect_pads
				(clearance 0)
			)
			(min_thickness 0.25)
			(keepout
				(tracks not_allowed)
				(vias allowed)
				(pads allowed)
				(copperpour not_allowed)
				(footprints allowed)
			)
			(placement
				(enabled no)
				(sheetname "")
			)
			(fill
				(thermal_gap 0.5)
				(thermal_bridge_width 0.5)
				(island_removal_mode 0)
			)
			(polygon
				(pts
					(xy 383.286 -87.9475) (xy 382.778 -87.9475) (xy 382.778 -87.5665) (xy 383.286 -87.5665)
				)
			)
		)
		(zone
			(layer "F.Cu")
			(hatch none 0.5)
			(connect_pads
				(clearance 0)
			)
			(min_thickness 0.25)
			(keepout
				(tracks allowed)
				(vias not_allowed)
				(pads allowed)
				(copperpour not_allowed)
				(footprints allowed)
			)
			(placement
				(enabled no)
				(sheetname "")
			)
			(fill
				(thermal_gap 0.5)
				(thermal_bridge_width 0.5)
				(island_removal_mode 0)
			)
			(polygon
				(pts
					(xy 383.286 -87.5665) (xy 382.778 -87.5665) (xy 382.778 -87.9475) (xy 383.286 -87.9475)
				)
			)
		)
	)
	(footprint ""
		(layer "F.Cu")
		(at 408.673046 -107.434634 -90)
		(property "Reference" "R2P22"
			(at -0.8382 -0.849376 270)
			(unlocked yes)
			(layer "F.SilkS")
			(effects
				(font
					(size 0.7874 0.5842)
					(thickness 0.1524)
				)
				(justify left)
			)
		)
		(property "Value" ""
			(at 0 0 270)
			(layer "F.Fab")
			(effects
				(font
					(size 1.27 1.27)
				)
			)
		)
		(duplicate_pad_numbers_are_jumpers no)
		(fp_poly
			(pts
				(xy -0.2794 -0.1016) (xy 0.2794 -0.1016) (xy 0.2794 0.9906) (xy -0.2794 0.9906)
			)
			(stroke
				(width 0)
				(type default)
			)
			(fill no)
			(layer "F.CrtYd")
		)
		(fp_line
			(start -0.2794 0.9906)
			(end 0.2794 0.9906)
			(stroke
				(width 0.1)
				(type default)
			)
			(layer "F.Fab")
		)
		(fp_line
			(start 0.2794 0.9906)
			(end 0.2794 -0.1016)
			(stroke
				(width 0.1)
				(type default)
			)
			(layer "F.Fab")
		)
		(fp_line
			(start -0.2794 -0.1016)
			(end -0.2794 0.9906)
			(stroke
				(width 0.1)
				(type default)
			)
			(layer "F.Fab")
		)
		(fp_line
			(start 0.2794 -0.1016)
			(end -0.2794 -0.1016)
			(stroke
				(width 0.1)
				(type default)
			)
			(layer "F.Fab")
		)
		(pad "1" smd rect
			(at 0 0 270)
			(size 0.508 0.508)
			(layers "F.Cu" "F.Mask" "F.Paste")
			(net "P3V3_STBY")
		)
		(pad "2" smd rect
			(at 0 0.889 270)
			(size 0.508 0.508)
			(layers "F.Cu" "F.Mask" "F.Paste")
			(net "FM_CPU1_RC_EN")
		)
		(zone
			(layer "F.Cu")
			(hatch none 0.5)
			(connect_pads
				(clearance 0)
			)
			(min_thickness 0.25)
			(keepout
				(tracks not_allowed)
				(vias allowed)
				(pads allowed)
				(copperpour not_allowed)
				(footprints allowed)
			)
			(placement
				(enabled no)
				(sheetname "")
			)
			(fill
				(thermal_gap 0.5)
				(thermal_bridge_width 0.5)
				(island_removal_mode 0)
			)
			(polygon
				(pts
					(xy 408.038046 -107.688634) (xy 408.038046 -107.180634) (xy 408.419046 -107.180634) (xy 408.419046 -107.688634)
				)
			)
		)
		(zone
			(layer "F.Cu")
			(hatch none 0.5)
			(connect_pads
				(clearance 0)
			)
			(min_thickness 0.25)
			(keepout
				(tracks allowed)
				(vias not_allowed)
				(pads allowed)
				(copperpour not_allowed)
				(footprints allowed)
			)
			(placement
				(enabled no)
				(sheetname "")
			)
			(fill
				(thermal_gap 0.5)
				(thermal_bridge_width 0.5)
				(island_removal_mode 0)
			)
			(polygon
				(pts
					(xy 408.419046 -107.688634) (xy 408.419046 -107.180634) (xy 408.038046 -107.180634) (xy 408.038046 -107.688634)
				)
			)
		)
	)
	(footprint ""
		(layer "F.Cu")
		(at 264.7696 -84.7598)
		(property "Reference" "C5D6"
			(at 0 0 0)
			(layer "F.SilkS")
			(hide yes)
			(effects
				(font
					(size 1.27 1.27)
				)
			)
		)
		(property "Value" ""
			(at 0 0 0)
			(layer "F.Fab")
			(effects
				(font
					(size 1.27 1.27)
				)
			)
		)
		(duplicate_pad_numbers_are_jumpers no)
		(fp_poly
			(pts
				(xy -0.4953 -0.2032) (xy 0.4953 -0.2032) (xy 0.4953 1.6002) (xy -0.4953 1.6002)
			)
			(stroke
				(width 0)
				(type default)
			)
			(fill no)
			(layer "F.CrtYd")
		)
		(fp_line
			(start -0.4953 -0.2032)
			(end 0.4953 -0.2032)
			(stroke
				(width 0.1)
				(type default)
			)
			(layer "F.Fab")
		)
		(fp_line
			(start -0.4953 1.6002)
			(end -0.4953 -0.2032)
			(stroke
				(width 0.1)
				(type default)
			)
			(layer "F.Fab")
		)
		(fp_line
			(start 0.4953 -0.2032)
			(end 0.4953 1.6002)
			(stroke
				(width 0.1)
				(type default)
			)
			(layer "F.Fab")
		)
		(fp_line
			(start 0.4953 1.6002)
			(end -0.4953 1.6002)
			(stroke
				(width 0.1)
				(type default)
			)
			(layer "F.Fab")
		)
		(pad "1" smd rect
			(at 0 0)
			(size 0.762 0.889)
			(layers "F.Cu" "F.Mask" "F.Paste")
			(net "PVDDQ_DEF")
		)
		(pad "2" smd rect
			(at 0 1.397)
			(size 0.762 0.889)
			(layers "F.Cu" "F.Mask" "F.Paste")
			(net "GND")
		)
		(zone
			(layer "F.Cu")
			(hatch none 0.5)
			(connect_pads
				(clearance 0)
			)
			(min_thickness 0.25)
			(keepout
				(tracks not_allowed)
				(vias allowed)
				(pads allowed)
				(copperpour not_allowed)
				(footprints allowed)
			)
			(placement
				(enabled no)
				(sheetname "")
			)
			(fill
				(thermal_gap 0.5)
				(thermal_bridge_width 0.5)
				(island_removal_mode 0)
			)
			(polygon
				(pts
					(xy 264.3886 -84.3153) (xy 265.1506 -84.3153) (xy 265.1506 -83.8073) (xy 264.3886 -83.8073)
				)
			)
		)
	)
	(footprint ""
		(layer "F.Cu")
		(at 362.593382 -147.15871 180)
		(property "Reference" "L7A5"
			(at 0 0 180)
			(layer "F.SilkS")
			(hide yes)
			(effects
				(font
					(size 1.27 1.27)
				)
			)
		)
		(property "Value" "*"
			(at -3.5941 0.3429 180)
			(unlocked yes)
			(layer "F.Fab")
			(hide yes)
			(effects
				(font
					(size 1.27 1.016)
					(thickness 0.1524)
				)
			)
		)
		(property "Device Type" "IND-100NH-35-GP_DISCRET-G8-INDA"
			(at -3.5941 -1.1811 180)
			(unlocked yes)
			(layer "F.Fab")
			(hide yes)
			(effects
				(font
					(size 1.27 1.016)
					(thickness 0.1524)
				)
			)
		)
		(duplicate_pad_numbers_are_jumpers no)
		(fp_line
			(start 2.2479 2.794)
			(end -2.2479 2.794)
			(stroke
				(width 0.1524)
				(type default)
			)
			(layer "F.SilkS")
		)
		(fp_line
			(start 2.2479 -2.794)
			(end 2.2479 2.794)
			(stroke
				(width 0.1524)
				(type default)
			)
			(layer "F.SilkS")
		)
		(fp_line
			(start -2.2479 2.794)
			(end -2.2479 -2.794)
			(stroke
				(width 0.1524)
				(type default)
			)
			(layer "F.SilkS")
		)
		(fp_line
			(start -2.2479 -2.794)
			(end 2.2479 -2.794)
			(stroke
				(width 0.1524)
				(type default)
			)
			(layer "F.SilkS")
		)
		(fp_rect
			(start -1.9939 1.9939)
			(end 1.9939 -1.9939)
			(stroke
				(width 0)
				(type default)
			)
			(fill no)
			(layer "F.CrtYd")
		)
		(fp_poly
			(pts
				(xy -2.5019 2.8702) (xy -2.5019 1.9939) (xy 1.9939 1.9939) (xy 1.9939 -1.9939) (xy -1.9939 -1.9939)
				(xy -1.9939 1.9812) (xy -2.5019 1.9812) (xy -2.5019 -2.8702) (xy 2.5019 -2.8702) (xy 2.5019 2.8702)
			)
			(stroke
				(width 0)
				(type default)
			)
			(fill no)
			(layer "F.CrtYd")
		)
		(fp_rect
			(start -2.5019 2.8702)
			(end 2.5019 -2.8702)
			(stroke
				(width 0)
				(type default)
			)
			(fill no)
			(layer "F.Fab")
		)
		(pad "1" smd rect
			(at 0 -1.745996 180)
			(size 1.5494 1.6002)
			(layers "F.Cu" "F.Mask" "F.Paste")
			(net "P12V_STBY")
		)
		(pad "2" smd rect
			(at 0 1.745996 180)
			(size 1.5494 1.6002)
			(layers "F.Cu" "F.Mask" "F.Paste")
			(net "VR_FET_SW_P12V_STBY_PVDDQ_DEF")
		)
	)
	(footprint ""
		(layer "F.Cu")
		(at 112.4458 -69.85)
		(property "Reference" "R3D26"
			(at 0 0 0)
			(layer "F.SilkS")
			(hide yes)
			(effects
				(font
					(size 1.27 1.27)
				)
			)
		)
		(property "Value" ""
			(at 0 0 0)
			(layer "F.Fab")
			(effects
				(font
					(size 1.27 1.27)
				)
			)
		)
		(duplicate_pad_numbers_are_jumpers no)
		(fp_poly
			(pts
				(xy -0.2794 -0.1016) (xy 0.2794 -0.1016) (xy 0.2794 0.9906) (xy -0.2794 0.9906)
			)
			(stroke
				(width 0)
				(type default)
			)
			(fill no)
			(layer "F.CrtYd")
		)
		(fp_line
			(start -0.2794 -0.1016)
			(end -0.2794 0.9906)
			(stroke
				(width 0.1)
				(type default)
			)
			(layer "F.Fab")
		)
		(fp_line
			(start -0.2794 0.9906)
			(end 0.2794 0.9906)
			(stroke
				(width 0.1)
				(type default)
			)
			(layer "F.Fab")
		)
		(fp_line
			(start 0.2794 -0.1016)
			(end -0.2794 -0.1016)
			(stroke
				(width 0.1)
				(type default)
			)
			(layer "F.Fab")
		)
		(fp_line
			(start 0.2794 0.9906)
			(end 0.2794 -0.1016)
			(stroke
				(width 0.1)
				(type default)
			)
			(layer "F.Fab")
		)
		(pad "1" smd rect
			(at 0 0)
			(size 0.508 0.508)
			(layers "F.Cu" "F.Mask" "F.Paste")
			(net "PVCCIO_CPU1")
		)
		(pad "2" smd rect
			(at 0 0.889)
			(size 0.508 0.508)
			(layers "F.Cu" "F.Mask" "F.Paste")
			(net "PU_CPU1_SAFE_MODE_BOOT")
		)
		(zone
			(layer "F.Cu")
			(hatch none 0.5)
			(connect_pads
				(clearance 0)
			)
			(min_thickness 0.25)
			(keepout
				(tracks allowed)
				(vias not_allowed)
				(pads allowed)
				(copperpour not_allowed)
				(footprints allowed)
			)
			(placement
				(enabled no)
				(sheetname "")
			)
			(fill
				(thermal_gap 0.5)
				(thermal_bridge_width 0.5)
				(island_removal_mode 0)
			)
			(polygon
				(pts
					(xy 112.1918 -69.596) (xy 112.6998 -69.596) (xy 112.6998 -69.215) (xy 112.1918 -69.215)
				)
			)
		)
		(zone
			(layer "F.Cu")
			(hatch none 0.5)
			(connect_pads
				(clearance 0)
			)
			(min_thickness 0.25)
			(keepout
				(tracks not_allowed)
				(vias allowed)
				(pads allowed)
				(copperpour not_allowed)
				(footprints allowed)
			)
			(placement
				(enabled no)
				(sheetname "")
			)
			(fill
				(thermal_gap 0.5)
				(thermal_bridge_width 0.5)
				(island_removal_mode 0)
			)
			(polygon
				(pts
					(xy 112.1918 -69.215) (xy 112.6998 -69.215) (xy 112.6998 -69.596) (xy 112.1918 -69.596)
				)
			)
		)
	)
	(footprint ""
		(layer "F.Cu")
		(at 399.48231 -61.962538 -90)
		(property "Reference" "C8E4"
			(at 0 0 270)
			(layer "F.SilkS")
			(hide yes)
			(effects
				(font
					(size 1.27 1.27)
				)
			)
		)
		(property "Value" "*"
			(at 0 -9.7155 270)
			(unlocked yes)
			(layer "F.Fab")
			(hide yes)
			(effects
				(font
					(size 1.27 1.016)
					(thickness 0.1524)
				)
			)
		)
		(property "Device Type" "ST220U10VDM-LGP_SMD-TCG-ST220UA"
			(at 0 -11.2395 270)
			(unlocked yes)
			(layer "F.Fab")
			(hide yes)
			(effects
				(font
					(size 1.27 1.016)
					(thickness 0.1524)
				)
			)
		)
		(duplicate_pad_numbers_are_jumpers no)
		(fp_line
			(start -2.286 4.8768)
			(end -2.286 2.032)
			(stroke
				(width 0.1524)
				(type default)
			)
			(layer "F.SilkS")
		)
		(fp_line
			(start 2.286 4.8768)
			(end -2.286 4.8768)
			(stroke
				(width 0.1524)
				(type default)
			)
			(layer "F.SilkS")
		)
		(fp_line
			(start 2.286 2.032)
			(end 2.286 4.8768)
			(stroke
				(width 0.1524)
				(type default)
			)
			(layer "F.SilkS")
		)
		(fp_line
			(start 2.286 -2.032)
			(end 2.286 -4.8768)
			(stroke
				(width 0.1524)
				(type default)
			)
			(layer "F.SilkS")
		)
		(fp_line
			(start 2.1082 -4.699)
			(end -2.1082 -4.699)
			(stroke
				(width 0.508)
				(type default)
			)
			(layer "F.SilkS")
		)
		(fp_line
			(start -2.286 -4.8768)
			(end -2.286 -2.032)
			(stroke
				(width 0.1524)
				(type default)
			)
			(layer "F.SilkS")
		)
		(fp_line
			(start 2.286 -4.8768)
			(end -2.286 -4.8768)
			(stroke
				(width 0.1524)
				(type default)
			)
			(layer "F.SilkS")
		)
		(fp_rect
			(start -2.1463 3.6449)
			(end 2.1463 -3.6449)
			(stroke
				(width 0)
				(type default)
			)
			(fill no)
			(layer "F.CrtYd")
		)
		(fp_poly
			(pts
				(xy -2.54 4.953) (xy -2.54 4.2926) (xy -3.81 4.2926) (xy -3.81 -4.2926) (xy -2.54 -4.2926) (xy -2.54 -4.953)
				(xy 2.54 -4.953) (xy 2.54 -4.2926) (xy 3.81 -4.2926) (xy 3.81 -1.6256) (xy 2.1463 -1.6256) (xy 2.1463 -3.6449)
				(xy -2.1463 -3.6449) (xy -2.1463 3.6449) (xy 2.1463 3.6449) (xy 2.1463 -1.6129) (xy 3.81 -1.6129)
				(xy 3.81 4.2926) (xy 2.54 4.2926) (xy 2.54 4.953)
			)
			(stroke
				(width 0)
				(type default)
			)
			(fill no)
			(layer "F.CrtYd")
		)
		(fp_rect
			(start -2.54 4.953)
			(end 2.54 -4.953)
			(stroke
				(width 0)
				(type default)
			)
			(fill no)
			(layer "F.Fab")
		)
		(fp_rect
			(start -3.81 4.2926)
			(end -2.54 -4.2926)
			(stroke
				(width 0)
				(type default)
			)
			(fill no)
			(layer "F.Fab")
		)
		(fp_rect
			(start 2.54 4.2926)
			(end 3.81 -4.2926)
			(stroke
				(width 0)
				(type default)
			)
			(fill no)
			(layer "F.Fab")
		)
		(pad "1" smd rect
			(at 0 -3.1496 270)
			(size 2.413 2.286)
			(layers "F.Cu" "F.Mask" "F.Paste")
			(net "P5V_STBY")
		)
		(pad "2" smd rect
			(at 0 3.1496 270)
			(size 2.413 2.286)
			(layers "F.Cu" "F.Mask" "F.Paste")
			(net "GND")
		)
		(zone
			(layer "F.Cu")
			(hatch none 0.5)
			(connect_pads
				(clearance 0)
			)
			(min_thickness 0.25)
			(keepout
				(tracks allowed)
				(vias not_allowed)
				(pads allowed)
				(copperpour not_allowed)
				(footprints allowed)
			)
			(placement
				(enabled no)
				(sheetname "")
			)
			(fill
				(thermal_gap 0.5)
				(thermal_bridge_width 0.5)
				(island_removal_mode 0)
			)
			(polygon
				(pts
					(xy 394.88491 -63.473838) (xy 394.88491 -60.451238) (xy 397.78051 -60.451238) (xy 398.11071 -60.451238)
					(xy 398.11071 -63.473838) (xy 397.78051 -63.473838)
				)
			)
		)
		(zone
			(layer "F.Cu")
			(hatch none 0.5)
			(connect_pads
				(clearance 0)
			)
			(min_thickness 0.25)
			(keepout
				(tracks allowed)
				(vias not_allowed)
				(pads allowed)
				(copperpour not_allowed)
				(footprints allowed)
			)
			(placement
				(enabled no)
				(sheetname "")
			)
			(fill
				(thermal_gap 0.5)
				(thermal_bridge_width 0.5)
				(island_removal_mode 0)
			)
			(polygon
				(pts
					(xy 401.17141 -60.451238) (xy 404.07971 -60.451238) (xy 404.07971 -63.473838) (xy 401.18411 -63.473838)
					(xy 400.85391 -63.473838) (xy 400.85391 -60.451238)
				)
			)
		)
	)
	(footprint ""
		(layer "F.Cu")
		(at 412.632652 -134.747 180)
		(property "Reference" "R8B1"
			(at 0 0 180)
			(layer "F.SilkS")
			(hide yes)
			(effects
				(font
					(size 1.27 1.27)
				)
			)
		)
		(property "Value" ""
			(at 0 0 180)
			(layer "F.Fab")
			(effects
				(font
					(size 1.27 1.27)
				)
			)
		)
		(duplicate_pad_numbers_are_jumpers no)
		(fp_poly
			(pts
				(xy -0.2794 -0.1016) (xy 0.2794 -0.1016) (xy 0.2794 0.9906) (xy -0.2794 0.9906)
			)
			(stroke
				(width 0)
				(type default)
			)
			(fill no)
			(layer "F.CrtYd")
		)
		(fp_line
			(start 0.2794 0.9906)
			(end 0.2794 -0.1016)
			(stroke
				(width 0.1)
				(type default)
			)
			(layer "F.Fab")
		)
		(fp_line
			(start 0.2794 -0.1016)
			(end -0.2794 -0.1016)
			(stroke
				(width 0.1)
				(type default)
			)
			(layer "F.Fab")
		)
		(fp_line
			(start -0.2794 0.9906)
			(end 0.2794 0.9906)
			(stroke
				(width 0.1)
				(type default)
			)
			(layer "F.Fab")
		)
		(fp_line
			(start -0.2794 -0.1016)
			(end -0.2794 0.9906)
			(stroke
				(width 0.1)
				(type default)
			)
			(layer "F.Fab")
		)
		(pad "1" smd rect
			(at 0 0 180)
			(size 0.508 0.508)
			(layers "F.Cu" "F.Mask" "F.Paste")
			(net "XDP_PCH_TCK1")
		)
		(pad "2" smd rect
			(at 0 0.889 180)
			(size 0.508 0.508)
			(layers "F.Cu" "F.Mask" "F.Paste")
			(net "GND")
		)
		(zone
			(layer "F.Cu")
			(hatch none 0.5)
			(connect_pads
				(clearance 0)
			)
			(min_thickness 0.25)
			(keepout
				(tracks not_allowed)
				(vias allowed)
				(pads allowed)
				(copperpour not_allowed)
				(footprints allowed)
			)
			(placement
				(enabled no)
				(sheetname "")
			)
			(fill
				(thermal_gap 0.5)
				(thermal_bridge_width 0.5)
				(island_removal_mode 0)
			)
			(polygon
				(pts
					(xy 412.886652 -135.382) (xy 412.378652 -135.382) (xy 412.378652 -135.001) (xy 412.886652 -135.001)
				)
			)
		)
		(zone
			(layer "F.Cu")
			(hatch none 0.5)
			(connect_pads
				(clearance 0)
			)
			(min_thickness 0.25)
			(keepout
				(tracks allowed)
				(vias not_allowed)
				(pads allowed)
				(copperpour not_allowed)
				(footprints allowed)
			)
			(placement
				(enabled no)
				(sheetname "")
			)
			(fill
				(thermal_gap 0.5)
				(thermal_bridge_width 0.5)
				(island_removal_mode 0)
			)
			(polygon
				(pts
					(xy 412.886652 -135.001) (xy 412.378652 -135.001) (xy 412.378652 -135.382) (xy 412.886652 -135.382)
				)
			)
		)
	)
	(footprint ""
		(layer "F.Cu")
		(at 406.516078 -120.271032 90)
		(property "Reference" "R1W18"
			(at -0.8382 -0.67818 90)
			(unlocked yes)
			(layer "F.SilkS")
			(effects
				(font
					(size 0.4064 0.254)
					(thickness 0.1524)
				)
				(justify left)
			)
		)
		(property "Value" ""
			(at 0 0 90)
			(layer "F.Fab")
			(effects
				(font
					(size 1.27 1.27)
				)
			)
		)
		(duplicate_pad_numbers_are_jumpers no)
		(fp_poly
			(pts
				(xy -0.2794 -0.1016) (xy 0.2794 -0.1016) (xy 0.2794 0.9906) (xy -0.2794 0.9906)
			)
			(stroke
				(width 0)
				(type default)
			)
			(fill no)
			(layer "F.CrtYd")
		)
		(fp_line
			(start 0.2794 -0.1016)
			(end -0.2794 -0.1016)
			(stroke
				(width 0.1)
				(type default)
			)
			(layer "F.Fab")
		)
		(fp_line
			(start -0.2794 -0.1016)
			(end -0.2794 0.9906)
			(stroke
				(width 0.1)
				(type default)
			)
			(layer "F.Fab")
		)
		(fp_line
			(start 0.2794 0.9906)
			(end 0.2794 -0.1016)
			(stroke
				(width 0.1)
				(type default)
			)
			(layer "F.Fab")
		)
		(fp_line
			(start -0.2794 0.9906)
			(end 0.2794 0.9906)
			(stroke
				(width 0.1)
				(type default)
			)
			(layer "F.Fab")
		)
		(pad "1" smd rect
			(at 0 0 90)
			(size 0.508 0.508)
			(layers "F.Cu" "F.Mask" "F.Paste")
			(net "USB2_P02_DP_R")
		)
		(pad "2" smd rect
			(at 0 0.889 90)
			(size 0.508 0.508)
			(layers "F.Cu" "F.Mask" "F.Paste")
			(net "USB2_P02_DP")
		)
		(zone
			(layer "F.Cu")
			(hatch none 0.5)
			(connect_pads
				(clearance 0)
			)
			(min_thickness 0.25)
			(keepout
				(tracks allowed)
				(vias not_allowed)
				(pads allowed)
				(copperpour not_allowed)
				(footprints allowed)
			)
			(placement
				(enabled no)
				(sheetname "")
			)
			(fill
				(thermal_gap 0.5)
				(thermal_bridge_width 0.5)
				(island_removal_mode 0)
			)
			(polygon
				(pts
					(xy 406.770078 -120.017032) (xy 406.770078 -120.525032) (xy 407.151078 -120.525032) (xy 407.151078 -120.017032)
				)
			)
		)
		(zone
			(layer "F.Cu")
			(hatch none 0.5)
			(connect_pads
				(clearance 0)
			)
			(min_thickness 0.25)
			(keepout
				(tracks not_allowed)
				(vias allowed)
				(pads allowed)
				(copperpour not_allowed)
				(footprints allowed)
			)
			(placement
				(enabled no)
				(sheetname "")
			)
			(fill
				(thermal_gap 0.5)
				(thermal_bridge_width 0.5)
				(island_removal_mode 0)
			)
			(polygon
				(pts
					(xy 407.151078 -120.017032) (xy 407.151078 -120.525032) (xy 406.770078 -120.525032) (xy 406.770078 -120.017032)
				)
			)
		)
	)
	(footprint ""
		(layer "F.Cu")
		(at 352.424238 -0.124206)
		(property "Reference" "R7G30"
			(at 0 0 0)
			(layer "F.SilkS")
			(hide yes)
			(effects
				(font
					(size 1.27 1.27)
				)
			)
		)
		(property "Value" ""
			(at 0 0 0)
			(layer "F.Fab")
			(effects
				(font
					(size 1.27 1.27)
				)
			)
		)
		(duplicate_pad_numbers_are_jumpers no)
		(fp_poly
			(pts
				(xy -0.2794 -0.1016) (xy 0.2794 -0.1016) (xy 0.2794 0.9906) (xy -0.2794 0.9906)
			)
			(stroke
				(width 0)
				(type default)
			)
			(fill no)
			(layer "F.CrtYd")
		)
		(fp_line
			(start -0.2794 -0.1016)
			(end -0.2794 0.9906)
			(stroke
				(width 0.1)
				(type default)
			)
			(layer "F.Fab")
		)
		(fp_line
			(start -0.2794 0.9906)
			(end 0.2794 0.9906)
			(stroke
				(width 0.1)
				(type default)
			)
			(layer "F.Fab")
		)
		(fp_line
			(start 0.2794 -0.1016)
			(end -0.2794 -0.1016)
			(stroke
				(width 0.1)
				(type default)
			)
			(layer "F.Fab")
		)
		(fp_line
			(start 0.2794 0.9906)
			(end 0.2794 -0.1016)
			(stroke
				(width 0.1)
				(type default)
			)
			(layer "F.Fab")
		)
		(pad "1" smd rect
			(at 0 0)
			(size 0.508 0.508)
			(layers "F.Cu" "F.Mask" "F.Paste")
			(net "VR_PVDDQ_ABC_PH2_OCSET")
		)
		(pad "2" smd rect
			(at 0 0.889)
			(size 0.508 0.508)
			(layers "F.Cu" "F.Mask" "F.Paste")
			(net "GND")
		)
		(zone
			(layer "F.Cu")
			(hatch none 0.5)
			(connect_pads
				(clearance 0)
			)
			(min_thickness 0.25)
			(keepout
				(tracks allowed)
				(vias not_allowed)
				(pads allowed)
				(copperpour not_allowed)
				(footprints allowed)
			)
			(placement
				(enabled no)
				(sheetname "")
			)
			(fill
				(thermal_gap 0.5)
				(thermal_bridge_width 0.5)
				(island_removal_mode 0)
			)
			(polygon
				(pts
					(xy 352.170238 0.129794) (xy 352.678238 0.129794) (xy 352.678238 0.510794) (xy 352.170238 0.510794)
				)
			)
		)
		(zone
			(layer "F.Cu")
			(hatch none 0.5)
			(connect_pads
				(clearance 0)
			)
			(min_thickness 0.25)
			(keepout
				(tracks not_allowed)
				(vias allowed)
				(pads allowed)
				(copperpour not_allowed)
				(footprints allowed)
			)
			(placement
				(enabled no)
				(sheetname "")
			)
			(fill
				(thermal_gap 0.5)
				(thermal_bridge_width 0.5)
				(island_removal_mode 0)
			)
			(polygon
				(pts
					(xy 352.170238 0.510794) (xy 352.678238 0.510794) (xy 352.678238 0.129794) (xy 352.170238 0.129794)
				)
			)
		)
	)
	(footprint ""
		(layer "F.Cu")
		(at 183.769 -65.024)
		(property "Reference" "R4D66"
			(at 0 0 0)
			(layer "F.SilkS")
			(hide yes)
			(effects
				(font
					(size 1.27 1.27)
				)
			)
		)
		(property "Value" ""
			(at 0 0 0)
			(layer "F.Fab")
			(effects
				(font
					(size 1.27 1.27)
				)
			)
		)
		(duplicate_pad_numbers_are_jumpers no)
		(fp_rect
			(start -0.2794 0.9906)
			(end 0.2794 -0.1016)
			(stroke
				(width 0)
				(type default)
			)
			(fill no)
			(layer "F.CrtYd")
		)
		(fp_line
			(start -0.2794 -0.1016)
			(end -0.2794 0.9906)
			(stroke
				(width 0.1)
				(type default)
			)
			(layer "F.Fab")
		)
		(fp_line
			(start -0.2794 0.9906)
			(end 0.2794 0.9906)
			(stroke
				(width 0.1)
				(type default)
			)
			(layer "F.Fab")
		)
		(fp_line
			(start 0.2794 -0.1016)
			(end -0.2794 -0.1016)
			(stroke
				(width 0.1)
				(type default)
			)
			(layer "F.Fab")
		)
		(fp_line
			(start 0.2794 0.9906)
			(end 0.2794 -0.1016)
			(stroke
				(width 0.1)
				(type default)
			)
			(layer "F.Fab")
		)
		(pad "1" smd rect
			(at 0 0)
			(size 0.508 0.508)
			(layers "F.Cu" "F.Mask" "F.Paste")
			(net "SVID_VDIO_PVCCIN_CPU0")
		)
		(pad "2" smd rect
			(at 0 0.889)
			(size 0.508 0.508)
			(layers "F.Cu" "F.Mask" "F.Paste")
			(net "SVID_DIO0_CPU0_R")
		)
		(zone
			(layer "F.Cu")
			(hatch none 0.5)
			(connect_pads
				(clearance 0)
			)
			(min_thickness 0.25)
			(keepout
				(tracks allowed)
				(vias not_allowed)
				(pads allowed)
				(copperpour not_allowed)
				(footprints allowed)
			)
			(placement
				(enabled no)
				(sheetname "")
			)
			(fill
				(thermal_gap 0.5)
				(thermal_bridge_width 0.5)
				(island_removal_mode 0)
			)
			(polygon
				(pts
					(xy 183.515 -64.389) (xy 184.023 -64.389) (xy 184.023 -64.77) (xy 183.515 -64.77)
				)
			)
		)
		(zone
			(layer "F.Cu")
			(hatch none 0.5)
			(connect_pads
				(clearance 0)
			)
			(min_thickness 0.25)
			(keepout
				(tracks not_allowed)
				(vias allowed)
				(pads allowed)
				(copperpour not_allowed)
				(footprints allowed)
			)
			(placement
				(enabled no)
				(sheetname "")
			)
			(fill
				(thermal_gap 0.5)
				(thermal_bridge_width 0.5)
				(island_removal_mode 0)
			)
			(polygon
				(pts
					(xy 183.515 -64.389) (xy 184.023 -64.389) (xy 184.023 -64.77) (xy 183.515 -64.77)
				)
			)
		)
	)
	(footprint ""
		(layer "F.Cu")
		(at 449.69938 -35.8775 90)
		(property "Reference" "R25W3"
			(at 0 0 90)
			(layer "F.SilkS")
			(hide yes)
			(effects
				(font
					(size 1.27 1.27)
				)
			)
		)
		(property "Value" "*"
			(at 0.064008 -4.108196 90)
			(unlocked yes)
			(layer "F.Fab")
			(hide yes)
			(effects
				(font
					(size 1.27 1.016)
					(thickness 0.1524)
				)
			)
		)
		(property "Device Type" "120R2F-GP_RCL_GP-120R2F-GP,64.A"
			(at 0.064008 -5.632196 90)
			(unlocked yes)
			(layer "F.Fab")
			(hide yes)
			(effects
				(font
					(size 1.27 1.016)
					(thickness 0.1524)
				)
			)
		)
		(duplicate_pad_numbers_are_jumpers no)
		(fp_line
			(start 0.508 -0.9398)
			(end -0.508 -0.9398)
			(stroke
				(width 0.1524)
				(type default)
			)
			(layer "F.SilkS")
		)
		(fp_line
			(start -0.508 -0.9398)
			(end -0.508 0.9398)
			(stroke
				(width 0.1524)
				(type default)
			)
			(layer "F.SilkS")
		)
		(fp_rect
			(start -0.508 0.9398)
			(end 0.508 -0.9398)
			(stroke
				(width 0)
				(type default)
			)
			(fill no)
			(layer "F.CrtYd")
		)
		(fp_rect
			(start -0.508 0.9398)
			(end 0.508 -0.9398)
			(stroke
				(width 0)
				(type default)
			)
			(fill no)
			(layer "F.Fab")
		)
		(pad "1" smd custom
			(at 0 -0.4445 90)
			(size 0.1397 0.1397)
			(layers "F.Cu" "F.Mask" "F.Paste")
			(net "GND")
			(options
				(clearance outline)
				(anchor circle)
			)
			(primitives
				(gr_poly
					(pts
						(arc
							(start -0.1778 -0.2794)
							(mid -0.249642 -0.249642)
							(end -0.2794 -0.1778)
						)
						(arc
							(start -0.2794 0.1778)
							(mid -0.249642 0.249642)
							(end -0.1778 0.2794)
						)
						(arc
							(start 0.1778 0.2794)
							(mid 0.249642 0.249642)
							(end 0.2794 0.1778)
						)
						(arc
							(start 0.2794 -0.1778)
							(mid 0.249642 -0.249642)
							(end 0.1778 -0.2794)
						)
					)
					(width 0)
					(fill yes)
				)
			)
		)
		(pad "2" smd custom
			(at 0 0.4445 90)
			(size 0.1397 0.1397)
			(layers "F.Cu" "F.Mask" "F.Paste")
			(net "BMC_M_RST_N")
			(options
				(clearance outline)
				(anchor circle)
			)
			(primitives
				(gr_poly
					(pts
						(arc
							(start -0.1778 -0.2794)
							(mid -0.249642 -0.249642)
							(end -0.2794 -0.1778)
						)
						(arc
							(start -0.2794 0.1778)
							(mid -0.249642 0.249642)
							(end -0.1778 0.2794)
						)
						(arc
							(start 0.1778 0.2794)
							(mid 0.249642 0.249642)
							(end 0.2794 0.1778)
						)
						(arc
							(start 0.2794 -0.1778)
							(mid 0.249642 -0.249642)
							(end 0.1778 -0.2794)
						)
					)
					(width 0)
					(fill yes)
				)
			)
		)
	)
	(footprint ""
		(layer "F.Cu")
		(at 28.7274 -104.5718 90)
		(property "Reference" "R1C33"
			(at 0 0 90)
			(layer "F.SilkS")
			(hide yes)
			(effects
				(font
					(size 1.27 1.27)
				)
			)
		)
		(property "Value" ""
			(at 0 0 90)
			(layer "F.Fab")
			(effects
				(font
					(size 1.27 1.27)
				)
			)
		)
		(duplicate_pad_numbers_are_jumpers no)
		(fp_poly
			(pts
				(xy -0.2794 -0.1016) (xy 0.2794 -0.1016) (xy 0.2794 0.9906) (xy -0.2794 0.9906)
			)
			(stroke
				(width 0)
				(type default)
			)
			(fill no)
			(layer "F.CrtYd")
		)
		(fp_line
			(start 0.2794 -0.1016)
			(end -0.2794 -0.1016)
			(stroke
				(width 0.1)
				(type default)
			)
			(layer "F.Fab")
		)
		(fp_line
			(start -0.2794 -0.1016)
			(end -0.2794 0.9906)
			(stroke
				(width 0.1)
				(type default)
			)
			(layer "F.Fab")
		)
		(fp_line
			(start 0.2794 0.9906)
			(end 0.2794 -0.1016)
			(stroke
				(width 0.1)
				(type default)
			)
			(layer "F.Fab")
		)
		(fp_line
			(start -0.2794 0.9906)
			(end 0.2794 0.9906)
			(stroke
				(width 0.1)
				(type default)
			)
			(layer "F.Fab")
		)
		(pad "1" smd rect
			(at 0 0 90)
			(size 0.508 0.508)
			(layers "F.Cu" "F.Mask" "F.Paste")
			(net "GND")
		)
		(pad "2" smd rect
			(at 0 0.889 90)
			(size 0.508 0.508)
			(layers "F.Cu" "F.Mask" "F.Paste")
			(net "PD_PIROM_CPU1_ADDR1")
		)
		(zone
			(layer "F.Cu")
			(hatch none 0.5)
			(connect_pads
				(clearance 0)
			)
			(min_thickness 0.25)
			(keepout
				(tracks allowed)
				(vias not_allowed)
				(pads allowed)
				(copperpour not_allowed)
				(footprints allowed)
			)
			(placement
				(enabled no)
				(sheetname "")
			)
			(fill
				(thermal_gap 0.5)
				(thermal_bridge_width 0.5)
				(island_removal_mode 0)
			)
			(polygon
				(pts
					(xy 28.9814 -104.3178) (xy 28.9814 -104.8258) (xy 29.3624 -104.8258) (xy 29.3624 -104.3178)
				)
			)
		)
		(zone
			(layer "F.Cu")
			(hatch none 0.5)
			(connect_pads
				(clearance 0)
			)
			(min_thickness 0.25)
			(keepout
				(tracks not_allowed)
				(vias allowed)
				(pads allowed)
				(copperpour not_allowed)
				(footprints allowed)
			)
			(placement
				(enabled no)
				(sheetname "")
			)
			(fill
				(thermal_gap 0.5)
				(thermal_bridge_width 0.5)
				(island_removal_mode 0)
			)
			(polygon
				(pts
					(xy 29.3624 -104.3178) (xy 29.3624 -104.8258) (xy 28.9814 -104.8258) (xy 28.9814 -104.3178)
				)
			)
		)
	)
	(footprint ""
		(layer "F.Cu")
		(at 399.770092 -0.109474 90)
		(property "Reference" "R7G114"
			(at -0.8382 -0.67818 90)
			(unlocked yes)
			(layer "F.SilkS")
			(effects
				(font
					(size 0.4064 0.254)
					(thickness 0.1524)
				)
				(justify left)
			)
		)
		(property "Value" ""
			(at 0 0 90)
			(layer "F.Fab")
			(effects
				(font
					(size 1.27 1.27)
				)
			)
		)
		(duplicate_pad_numbers_are_jumpers no)
		(fp_poly
			(pts
				(xy -0.2794 -0.1016) (xy 0.2794 -0.1016) (xy 0.2794 0.9906) (xy -0.2794 0.9906)
			)
			(stroke
				(width 0)
				(type default)
			)
			(fill no)
			(layer "F.CrtYd")
		)
		(fp_line
			(start 0.2794 -0.1016)
			(end -0.2794 -0.1016)
			(stroke
				(width 0.1)
				(type default)
			)
			(layer "F.Fab")
		)
		(fp_line
			(start -0.2794 -0.1016)
			(end -0.2794 0.9906)
			(stroke
				(width 0.1)
				(type default)
			)
			(layer "F.Fab")
		)
		(fp_line
			(start 0.2794 0.9906)
			(end 0.2794 -0.1016)
			(stroke
				(width 0.1)
				(type default)
			)
			(layer "F.Fab")
		)
		(fp_line
			(start -0.2794 0.9906)
			(end 0.2794 0.9906)
			(stroke
				(width 0.1)
				(type default)
			)
			(layer "F.Fab")
		)
		(pad "1" smd rect
			(at 0 0 90)
			(size 0.508 0.508)
			(layers "F.Cu" "F.Mask" "F.Paste")
			(net "BMC_JTAG_SEL_N")
		)
		(pad "2" smd rect
			(at 0 0.889 90)
			(size 0.508 0.508)
			(layers "F.Cu" "F.Mask" "F.Paste")
			(net "BMC_JTAG_SEL_N_MUX")
		)
		(zone
			(layer "F.Cu")
			(hatch none 0.5)
			(connect_pads
				(clearance 0)
			)
			(min_thickness 0.25)
			(keepout
				(tracks allowed)
				(vias not_allowed)
				(pads allowed)
				(copperpour not_allowed)
				(footprints allowed)
			)
			(placement
				(enabled no)
				(sheetname "")
			)
			(fill
				(thermal_gap 0.5)
				(thermal_bridge_width 0.5)
				(island_removal_mode 0)
			)
			(polygon
				(pts
					(xy 400.024092 0.144526) (xy 400.024092 -0.363474) (xy 400.405092 -0.363474) (xy 400.405092 0.144526)
				)
			)
		)
		(zone
			(layer "F.Cu")
			(hatch none 0.5)
			(connect_pads
				(clearance 0)
			)
			(min_thickness 0.25)
			(keepout
				(tracks not_allowed)
				(vias allowed)
				(pads allowed)
				(copperpour not_allowed)
				(footprints allowed)
			)
			(placement
				(enabled no)
				(sheetname "")
			)
			(fill
				(thermal_gap 0.5)
				(thermal_bridge_width 0.5)
				(island_removal_mode 0)
			)
			(polygon
				(pts
					(xy 400.405092 0.144526) (xy 400.405092 -0.363474) (xy 400.024092 -0.363474) (xy 400.024092 0.144526)
				)
			)
		)
	)
	(footprint ""
		(layer "F.Cu")
		(at 368.0206 -136.4234 180)
		(property "Reference" "R7A18"
			(at 0 0 180)
			(layer "F.SilkS")
			(hide yes)
			(effects
				(font
					(size 1.27 1.27)
				)
			)
		)
		(property "Value" ""
			(at 0 0 180)
			(layer "F.Fab")
			(effects
				(font
					(size 1.27 1.27)
				)
			)
		)
		(duplicate_pad_numbers_are_jumpers no)
		(fp_poly
			(pts
				(xy -0.2794 -0.1016) (xy 0.2794 -0.1016) (xy 0.2794 0.9906) (xy -0.2794 0.9906)
			)
			(stroke
				(width 0)
				(type default)
			)
			(fill no)
			(layer "F.CrtYd")
		)
		(fp_line
			(start 0.2794 0.9906)
			(end 0.2794 -0.1016)
			(stroke
				(width 0.1)
				(type default)
			)
			(layer "F.Fab")
		)
		(fp_line
			(start 0.2794 -0.1016)
			(end -0.2794 -0.1016)
			(stroke
				(width 0.1)
				(type default)
			)
			(layer "F.Fab")
		)
		(fp_line
			(start -0.2794 0.9906)
			(end 0.2794 0.9906)
			(stroke
				(width 0.1)
				(type default)
			)
			(layer "F.Fab")
		)
		(fp_line
			(start -0.2794 -0.1016)
			(end -0.2794 0.9906)
			(stroke
				(width 0.1)
				(type default)
			)
			(layer "F.Fab")
		)
		(pad "1" smd rect
			(at 0 0 180)
			(size 0.508 0.508)
			(layers "F.Cu" "F.Mask" "F.Paste")
			(net "GND")
		)
		(pad "2" smd rect
			(at 0 0.889 180)
			(size 0.508 0.508)
			(layers "F.Cu" "F.Mask" "F.Paste")
			(net "VSENSE_PVNN_PCH_STBY_AVSN")
		)
		(zone
			(layer "F.Cu")
			(hatch none 0.5)
			(connect_pads
				(clearance 0)
			)
			(min_thickness 0.25)
			(keepout
				(tracks not_allowed)
				(vias allowed)
				(pads allowed)
				(copperpour not_allowed)
				(footprints allowed)
			)
			(placement
				(enabled no)
				(sheetname "")
			)
			(fill
				(thermal_gap 0.5)
				(thermal_bridge_width 0.5)
				(island_removal_mode 0)
			)
			(polygon
				(pts
					(xy 368.2746 -137.0584) (xy 367.7666 -137.0584) (xy 367.7666 -136.6774) (xy 368.2746 -136.6774)
				)
			)
		)
		(zone
			(layer "F.Cu")
			(hatch none 0.5)
			(connect_pads
				(clearance 0)
			)
			(min_thickness 0.25)
			(keepout
				(tracks allowed)
				(vias not_allowed)
				(pads allowed)
				(copperpour not_allowed)
				(footprints allowed)
			)
			(placement
				(enabled no)
				(sheetname "")
			)
			(fill
				(thermal_gap 0.5)
				(thermal_bridge_width 0.5)
				(island_removal_mode 0)
			)
			(polygon
				(pts
					(xy 368.2746 -136.6774) (xy 367.7666 -136.6774) (xy 367.7666 -137.0584) (xy 368.2746 -137.0584)
				)
			)
		)
	)
	(footprint ""
		(layer "F.Cu")
		(at 197.162928 -53.221382 -90)
		(property "Reference" "C4E10"
			(at 0 0 270)
			(layer "F.SilkS")
			(hide yes)
			(effects
				(font
					(size 1.27 1.27)
				)
			)
		)
		(property "Value" ""
			(at 0 0 270)
			(layer "F.Fab")
			(effects
				(font
					(size 1.27 1.27)
				)
			)
		)
		(duplicate_pad_numbers_are_jumpers no)
		(fp_poly
			(pts
				(xy 0.3048 -0.1016) (xy 0.3048 0.9906) (xy -0.3048 0.9906) (xy -0.3048 -0.1016)
			)
			(stroke
				(width 0)
				(type default)
			)
			(fill no)
			(layer "F.CrtYd")
		)
		(fp_line
			(start -0.3048 0.9906)
			(end 0.3048 0.9906)
			(stroke
				(width 0.1)
				(type default)
			)
			(layer "F.Fab")
		)
		(fp_line
			(start 0.3048 0.9906)
			(end 0.3048 -0.1016)
			(stroke
				(width 0.1)
				(type default)
			)
			(layer "F.Fab")
		)
		(fp_line
			(start -0.3048 -0.1016)
			(end -0.3048 0.9906)
			(stroke
				(width 0.1)
				(type default)
			)
			(layer "F.Fab")
		)
		(fp_line
			(start 0.3048 -0.1016)
			(end -0.3048 -0.1016)
			(stroke
				(width 0.1)
				(type default)
			)
			(layer "F.Fab")
		)
		(pad "1" smd rect
			(at 0 0 270)
			(size 0.508 0.508)
			(layers "F.Cu" "F.Mask" "F.Paste")
			(net "VR_PVCCIN_CPU0_PH1_VCIN")
		)
		(pad "2" smd rect
			(at 0 0.889 270)
			(size 0.508 0.508)
			(layers "F.Cu" "F.Mask" "F.Paste")
			(net "GND")
		)
		(zone
			(layer "F.Cu")
			(hatch none 0.5)
			(connect_pads
				(clearance 0)
			)
			(min_thickness 0.25)
			(keepout
				(tracks not_allowed)
				(vias allowed)
				(pads allowed)
				(copperpour not_allowed)
				(footprints allowed)
			)
			(placement
				(enabled no)
				(sheetname "")
			)
			(fill
				(thermal_gap 0.5)
				(thermal_bridge_width 0.5)
				(island_removal_mode 0)
			)
			(polygon
				(pts
					(xy 196.527928 -53.475382) (xy 196.527928 -52.967382) (xy 196.908928 -52.967382) (xy 196.908928 -53.475382)
				)
			)
		)
		(zone
			(layer "F.Cu")
			(hatch none 0.5)
			(connect_pads
				(clearance 0)
			)
			(min_thickness 0.25)
			(keepout
				(tracks allowed)
				(vias not_allowed)
				(pads allowed)
				(copperpour not_allowed)
				(footprints allowed)
			)
			(placement
				(enabled no)
				(sheetname "")
			)
			(fill
				(thermal_gap 0.5)
				(thermal_bridge_width 0.5)
				(island_removal_mode 0)
			)
			(polygon
				(pts
					(xy 196.908928 -53.475382) (xy 196.908928 -52.967382) (xy 196.527928 -52.967382) (xy 196.527928 -53.475382)
				)
			)
		)
	)
	(footprint ""
		(layer "F.Cu")
		(at 107.134406 -68.365116 180)
		(property "Reference" "C3D25"
			(at 0 0 180)
			(layer "F.SilkS")
			(hide yes)
			(effects
				(font
					(size 1.27 1.27)
				)
			)
		)
		(property "Value" ""
			(at 0 0 180)
			(layer "F.Fab")
			(effects
				(font
					(size 1.27 1.27)
				)
			)
		)
		(duplicate_pad_numbers_are_jumpers no)
		(fp_poly
			(pts
				(xy -0.4953 -0.2032) (xy 0.4953 -0.2032) (xy 0.4953 1.6002) (xy -0.4953 1.6002)
			)
			(stroke
				(width 0)
				(type default)
			)
			(fill no)
			(layer "F.CrtYd")
		)
		(fp_line
			(start 0.4953 1.6002)
			(end -0.4953 1.6002)
			(stroke
				(width 0.1)
				(type default)
			)
			(layer "F.Fab")
		)
		(fp_line
			(start 0.4953 -0.2032)
			(end 0.4953 1.6002)
			(stroke
				(width 0.1)
				(type default)
			)
			(layer "F.Fab")
		)
		(fp_line
			(start -0.4953 1.6002)
			(end -0.4953 -0.2032)
			(stroke
				(width 0.1)
				(type default)
			)
			(layer "F.Fab")
		)
		(fp_line
			(start -0.4953 -0.2032)
			(end 0.4953 -0.2032)
			(stroke
				(width 0.1)
				(type default)
			)
			(layer "F.Fab")
		)
		(pad "1" smd rect
			(at 0 0 180)
			(size 0.762 0.889)
			(layers "F.Cu" "F.Mask" "F.Paste")
			(net "PVDDQ_GHJ")
		)
		(pad "2" smd rect
			(at 0 1.397 180)
			(size 0.762 0.889)
			(layers "F.Cu" "F.Mask" "F.Paste")
			(net "GND")
		)
		(zone
			(layer "F.Cu")
			(hatch none 0.5)
			(connect_pads
				(clearance 0)
			)
			(min_thickness 0.25)
			(keepout
				(tracks not_allowed)
				(vias allowed)
				(pads allowed)
				(copperpour not_allowed)
				(footprints allowed)
			)
			(placement
				(enabled no)
				(sheetname "")
			)
			(fill
				(thermal_gap 0.5)
				(thermal_bridge_width 0.5)
				(island_removal_mode 0)
			)
			(polygon
				(pts
					(xy 107.515406 -68.809616) (xy 106.753406 -68.809616) (xy 106.753406 -69.317616) (xy 107.515406 -69.317616)
				)
			)
		)
	)
	(footprint ""
		(layer "F.Cu")
		(at 345.3638 -28.5623 90)
		(property "Reference" "EU7F1"
			(at 5.27939 -1.76022 0)
			(unlocked yes)
			(layer "F.SilkS")
			(effects
				(font
					(size 0.7874 0.5842)
					(thickness 0.1524)
				)
				(justify left)
			)
		)
		(property "Value" ""
			(at 0 0 90)
			(layer "F.Fab")
			(effects
				(font
					(size 1.27 1.27)
				)
			)
		)
		(duplicate_pad_numbers_are_jumpers no)
		(fp_line
			(start 3.4671 -3.4671)
			(end 3.4671 3.4671)
			(stroke
				(width 0.1524)
				(type default)
			)
			(layer "F.SilkS")
		)
		(fp_line
			(start -3.4671 -3.4671)
			(end 3.4671 -3.4671)
			(stroke
				(width 0.1524)
				(type default)
			)
			(layer "F.SilkS")
		)
		(fp_line
			(start 3.10007 -3.10007)
			(end 3.10007 -2.900934)
			(stroke
				(width 0.1524)
				(type default)
			)
			(layer "F.SilkS")
		)
		(fp_line
			(start 2.897886 -3.10007)
			(end 3.10007 -3.10007)
			(stroke
				(width 0.1524)
				(type default)
			)
			(layer "F.SilkS")
		)
		(fp_line
			(start -3.10007 -3.10007)
			(end -2.897886 -3.10007)
			(stroke
				(width 0.1524)
				(type default)
			)
			(layer "F.SilkS")
		)
		(fp_line
			(start -3.10007 -2.900934)
			(end -3.10007 -3.10007)
			(stroke
				(width 0.1524)
				(type default)
			)
			(layer "F.SilkS")
		)
		(fp_line
			(start 3.10007 2.897378)
			(end 3.10007 3.10007)
			(stroke
				(width 0.1524)
				(type default)
			)
			(layer "F.SilkS")
		)
		(fp_line
			(start 3.10007 3.10007)
			(end 2.897886 3.10007)
			(stroke
				(width 0.1524)
				(type default)
			)
			(layer "F.SilkS")
		)
		(fp_line
			(start -2.897886 3.10007)
			(end -3.10007 3.10007)
			(stroke
				(width 0.1524)
				(type default)
			)
			(layer "F.SilkS")
		)
		(fp_line
			(start -3.10007 3.10007)
			(end -3.10007 2.897378)
			(stroke
				(width 0.1524)
				(type default)
			)
			(layer "F.SilkS")
		)
		(fp_line
			(start 3.4671 3.4671)
			(end -3.4671 3.4671)
			(stroke
				(width 0.1524)
				(type default)
			)
			(layer "F.SilkS")
		)
		(fp_line
			(start -3.4671 3.4671)
			(end -3.4671 -3.4671)
			(stroke
				(width 0.1524)
				(type default)
			)
			(layer "F.SilkS")
		)
		(fp_circle
			(center -3.976878 -2.29108)
			(end -3.976878 -2.16408)
			(stroke
				(width 0.254)
				(type default)
			)
			(fill no)
			(layer "F.SilkS")
		)
		(fp_poly
			(pts
				(xy -3.4671 -3.4671) (xy -3.4671 -2.5146) (xy -2.5146 -3.4671)
			)
			(stroke
				(width 0)
				(type default)
			)
			(fill yes)
			(layer "F.SilkS")
		)
		(fp_rect
			(start -2.1971 -0.1905)
			(end -0.6985 -2.1971)
			(stroke
				(width 0)
				(type default)
			)
			(fill yes)
			(layer "F.Paste")
		)
		(fp_rect
			(start -0.1905 2.1971)
			(end 2.1971 -2.1971)
			(stroke
				(width 0)
				(type default)
			)
			(fill yes)
			(layer "F.Paste")
		)
		(fp_rect
			(start -2.1971 2.1971)
			(end -0.6985 0.1905)
			(stroke
				(width 0)
				(type default)
			)
			(fill yes)
			(layer "F.Paste")
		)
		(fp_poly
			(pts
				(xy -3.10007 -3.10007) (xy -3.10007 3.10007) (xy 3.10007 3.10007) (xy 3.10007 -3.10007)
			)
			(stroke
				(width 0)
				(type default)
			)
			(fill no)
			(layer "F.CrtYd")
		)
		(fp_line
			(start 3.10007 -3.10007)
			(end 3.10007 3.10007)
			(stroke
				(width 0.1)
				(type default)
			)
			(layer "F.Fab")
		)
		(fp_line
			(start -3.10007 -3.10007)
			(end 3.10007 -3.10007)
			(stroke
				(width 0.1)
				(type default)
			)
			(layer "F.Fab")
		)
		(fp_line
			(start 3.10007 3.10007)
			(end -3.10007 3.10007)
			(stroke
				(width 0.1)
				(type default)
			)
			(layer "F.Fab")
		)
		(fp_line
			(start -3.10007 3.10007)
			(end -3.10007 -3.10007)
			(stroke
				(width 0.1)
				(type default)
			)
			(layer "F.Fab")
		)
		(fp_circle
			(center -3.917696 -3.100578)
			(end -3.917696 -2.973578)
			(stroke
				(width 0.254)
				(type default)
			)
			(fill no)
			(layer "F.Fab")
		)
		(pad "1" smd custom
			(at -2.8321 -2.249932 90)
			(size 0.06985 0.06985)
			(layers "F.Cu" "F.Mask" "F.Paste")
			(net "VR_PVPP_ABC_SS")
			(options
				(clearance outline)
				(anchor circle)
			)
			(primitives
				(gr_poly
					(pts
						(arc
							(start 0.2413 -0.1397)
							(mid 0.381 0)
							(end 0.2413 0.1397)
						)
						(xy -0.381 0.1397) (xy -0.381 -0.1397)
					)
					(width 0)
					(fill yes)
				)
			)
		)
		(pad "2" smd custom
			(at -2.8321 -1.75006 90)
			(size 0.06985 0.06985)
			(layers "F.Cu" "F.Mask" "F.Paste")
			(net "VR_FB_PVPP_ABC")
			(options
				(clearance outline)
				(anchor circle)
			)
			(primitives
				(gr_poly
					(pts
						(arc
							(start 0.2413 -0.1397)
							(mid 0.381 0)
							(end 0.2413 0.1397)
						)
						(xy -0.381 0.1397) (xy -0.381 -0.1397)
					)
					(width 0)
					(fill yes)
				)
			)
		)
		(pad "3" smd custom
			(at -2.8321 -1.249934 90)
			(size 0.06985 0.06985)
			(layers "F.Cu" "F.Mask" "F.Paste")
			(net "VR_COMP_PVPP_ABC_3")
			(options
				(clearance outline)
				(anchor circle)
			)
			(primitives
				(gr_poly
					(pts
						(arc
							(start 0.2413 -0.1397)
							(mid 0.381 0)
							(end 0.2413 0.1397)
						)
						(xy -0.381 0.1397) (xy -0.381 -0.1397)
					)
					(width 0)
					(fill yes)
				)
			)
		)
		(pad "4" smd custom
			(at -2.8321 -0.750062 90)
			(size 0.06985 0.06985)
			(layers "F.Cu" "F.Mask" "F.Paste")
			(net "VR_PVPP_ABC_ISET")
			(options
				(clearance outline)
				(anchor circle)
			)
			(primitives
				(gr_poly
					(pts
						(arc
							(start 0.2413 -0.1397)
							(mid 0.381 0)
							(end 0.2413 0.1397)
						)
						(xy -0.381 0.1397) (xy -0.381 -0.1397)
					)
					(width 0)
					(fill yes)
				)
			)
		)
		(pad "5" smd custom
			(at -2.8321 -0.249936 90)
			(size 0.06985 0.06985)
			(layers "F.Cu" "F.Mask" "F.Paste")
			(net "AGND_PVPP_ABC")
			(options
				(clearance outline)
				(anchor circle)
			)
			(primitives
				(gr_poly
					(pts
						(arc
							(start 0.2413 -0.1397)
							(mid 0.381 0)
							(end 0.2413 0.1397)
						)
						(xy -0.381 0.1397) (xy -0.381 -0.1397)
					)
					(width 0)
					(fill yes)
				)
			)
		)
		(pad "6" smd custom
			(at -2.8321 0.249936 90)
			(size 0.06985 0.06985)
			(layers "F.Cu" "F.Mask" "F.Paste")
			(net "AGND_PVPP_ABC")
			(options
				(clearance outline)
				(anchor circle)
			)
			(primitives
				(gr_poly
					(pts
						(arc
							(start 0.2413 -0.1397)
							(mid 0.381 0)
							(end 0.2413 0.1397)
						)
						(xy -0.381 0.1397) (xy -0.381 -0.1397)
					)
					(width 0)
					(fill yes)
				)
			)
		)
		(pad "7" smd custom
			(at -2.8321 0.750062 90)
			(size 0.06985 0.06985)
			(layers "F.Cu" "F.Mask" "F.Paste")
			(net "PWRGD_PVPP_ABC_R")
			(options
				(clearance outline)
				(anchor circle)
			)
			(primitives
				(gr_poly
					(pts
						(arc
							(start 0.2413 -0.1397)
							(mid 0.381 0)
							(end 0.2413 0.1397)
						)
						(xy -0.381 0.1397) (xy -0.381 -0.1397)
					)
					(width 0)
					(fill yes)
				)
			)
		)
		(pad "8" smd custom
			(at -2.8321 1.249934 90)
			(size 0.06985 0.06985)
			(layers "F.Cu" "F.Mask" "F.Paste")
			(net "VR_FET_SW_P12V_STBY_PVPP_ABC")
			(options
				(clearance outline)
				(anchor circle)
			)
			(primitives
				(gr_poly
					(pts
						(arc
							(start 0.2413 -0.1397)
							(mid 0.381 0)
							(end 0.2413 0.1397)
						)
						(xy -0.381 0.1397) (xy -0.381 -0.1397)
					)
					(width 0)
					(fill yes)
				)
			)
		)
		(pad "9" smd custom
			(at -2.8321 1.75006 90)
			(size 0.06985 0.06985)
			(layers "F.Cu" "F.Mask" "F.Paste")
			(net "VR_FET_SW_P12V_STBY_PVPP_ABC")
			(options
				(clearance outline)
				(anchor circle)
			)
			(primitives
				(gr_poly
					(pts
						(arc
							(start 0.2413 -0.1397)
							(mid 0.381 0)
							(end 0.2413 0.1397)
						)
						(xy -0.381 0.1397) (xy -0.381 -0.1397)
					)
					(width 0)
					(fill yes)
				)
			)
		)
		(pad "10" smd custom
			(at -2.8321 2.249932 90)
			(size 0.06985 0.06985)
			(layers "F.Cu" "F.Mask" "F.Paste")
			(net "VR_FET_SW_P12V_STBY_PVPP_ABC")
			(options
				(clearance outline)
				(anchor circle)
			)
			(primitives
				(gr_poly
					(pts
						(arc
							(start 0.2413 -0.1397)
							(mid 0.381 0)
							(end 0.2413 0.1397)
						)
						(xy -0.381 0.1397) (xy -0.381 -0.1397)
					)
					(width 0)
					(fill yes)
				)
			)
		)
		(pad "11" smd custom
			(at -2.249932 2.8321 90)
			(size 0.06985 0.06985)
			(layers "F.Cu" "F.Mask" "F.Paste")
			(net "VR_FET_SW_P12V_STBY_PVPP_ABC")
			(options
				(clearance outline)
				(anchor circle)
			)
			(primitives
				(gr_poly
					(pts
						(arc
							(start -0.1397 -0.2413)
							(mid 0 -0.381)
							(end 0.1397 -0.2413)
						)
						(xy 0.1397 0.381) (xy -0.1397 0.381)
					)
					(width 0)
					(fill yes)
				)
			)
		)
		(pad "12" smd custom
			(at -1.75006 2.8321 90)
			(size 0.06985 0.06985)
			(layers "F.Cu" "F.Mask" "F.Paste")
			(net "VR_FET_SW_P12V_STBY_PVPP_ABC")
			(options
				(clearance outline)
				(anchor circle)
			)
			(primitives
				(gr_poly
					(pts
						(arc
							(start -0.1397 -0.2413)
							(mid 0 -0.381)
							(end 0.1397 -0.2413)
						)
						(xy 0.1397 0.381) (xy -0.1397 0.381)
					)
					(width 0)
					(fill yes)
				)
			)
		)
		(pad "13" smd custom
			(at -1.249934 2.8321 90)
			(size 0.06985 0.06985)
			(layers "F.Cu" "F.Mask" "F.Paste")
			(net "VR_FET_SW_P12V_STBY_PVPP_ABC")
			(options
				(clearance outline)
				(anchor circle)
			)
			(primitives
				(gr_poly
					(pts
						(arc
							(start -0.1397 -0.2413)
							(mid 0 -0.381)
							(end 0.1397 -0.2413)
						)
						(xy 0.1397 0.381) (xy -0.1397 0.381)
					)
					(width 0)
					(fill yes)
				)
			)
		)
		(pad "14" smd custom
			(at -0.750062 2.8321 90)
			(size 0.06985 0.06985)
			(layers "F.Cu" "F.Mask" "F.Paste")
			(net "VR_FET_SW_P12V_STBY_PVPP_ABC")
			(options
				(clearance outline)
				(anchor circle)
			)
			(primitives
				(gr_poly
					(pts
						(arc
							(start -0.1397 -0.2413)
							(mid 0 -0.381)
							(end 0.1397 -0.2413)
						)
						(xy 0.1397 0.381) (xy -0.1397 0.381)
					)
					(width 0)
					(fill yes)
				)
			)
		)
		(pad "15" smd custom
			(at -0.249936 2.8321 90)
			(size 0.06985 0.06985)
			(layers "F.Cu" "F.Mask" "F.Paste")
			(net "VR_PVPP_ABC_PHASE")
			(options
				(clearance outline)
				(anchor circle)
			)
			(primitives
				(gr_poly
					(pts
						(arc
							(start -0.1397 -0.2413)
							(mid 0 -0.381)
							(end 0.1397 -0.2413)
						)
						(xy 0.1397 0.381) (xy -0.1397 0.381)
					)
					(width 0)
					(fill yes)
				)
			)
		)
		(pad "16" smd custom
			(at 0.249936 2.8321 90)
			(size 0.06985 0.06985)
			(layers "F.Cu" "F.Mask" "F.Paste")
			(net "GND")
			(options
				(clearance outline)
				(anchor circle)
			)
			(primitives
				(gr_poly
					(pts
						(arc
							(start -0.1397 -0.2413)
							(mid 0 -0.381)
							(end 0.1397 -0.2413)
						)
						(xy 0.1397 0.381) (xy -0.1397 0.381)
					)
					(width 0)
					(fill yes)
				)
			)
		)
		(pad "17" smd custom
			(at 0.750062 2.8321 90)
			(size 0.06985 0.06985)
			(layers "F.Cu" "F.Mask" "F.Paste")
			(net "GND")
			(options
				(clearance outline)
				(anchor circle)
			)
			(primitives
				(gr_poly
					(pts
						(arc
							(start -0.1397 -0.2413)
							(mid 0 -0.381)
							(end 0.1397 -0.2413)
						)
						(xy 0.1397 0.381) (xy -0.1397 0.381)
					)
					(width 0)
					(fill yes)
				)
			)
		)
		(pad "18" smd custom
			(at 1.249934 2.8321 90)
			(size 0.06985 0.06985)
			(layers "F.Cu" "F.Mask" "F.Paste")
			(net "GND")
			(options
				(clearance outline)
				(anchor circle)
			)
			(primitives
				(gr_poly
					(pts
						(arc
							(start -0.1397 -0.2413)
							(mid 0 -0.381)
							(end 0.1397 -0.2413)
						)
						(xy 0.1397 0.381) (xy -0.1397 0.381)
					)
					(width 0)
					(fill yes)
				)
			)
		)
		(pad "19" smd custom
			(at 1.75006 2.8321 90)
			(size 0.06985 0.06985)
			(layers "F.Cu" "F.Mask" "F.Paste")
			(net "GND")
			(options
				(clearance outline)
				(anchor circle)
			)
			(primitives
				(gr_poly
					(pts
						(arc
							(start -0.1397 -0.2413)
							(mid 0 -0.381)
							(end 0.1397 -0.2413)
						)
						(xy 0.1397 0.381) (xy -0.1397 0.381)
					)
					(width 0)
					(fill yes)
				)
			)
		)
		(pad "20" smd custom
			(at 2.249932 2.8321 90)
			(size 0.06985 0.06985)
			(layers "F.Cu" "F.Mask" "F.Paste")
			(net "GND")
			(options
				(clearance outline)
				(anchor circle)
			)
			(primitives
				(gr_poly
					(pts
						(arc
							(start -0.1397 -0.2413)
							(mid 0 -0.381)
							(end 0.1397 -0.2413)
						)
						(xy 0.1397 0.381) (xy -0.1397 0.381)
					)
					(width 0)
					(fill yes)
				)
			)
		)
		(pad "21" smd custom
			(at 2.8321 2.249932 90)
			(size 0.06985 0.06985)
			(layers "F.Cu" "F.Mask" "F.Paste")
			(net "GND")
			(options
				(clearance outline)
				(anchor circle)
			)
			(primitives
				(gr_poly
					(pts
						(arc
							(start -0.2413 0.1397)
							(mid -0.381 0)
							(end -0.2413 -0.1397)
						)
						(xy 0.381 -0.1397) (xy 0.381 0.1397)
					)
					(width 0)
					(fill yes)
				)
			)
		)
		(pad "22" smd custom
			(at 2.8321 1.75006 90)
			(size 0.06985 0.06985)
			(layers "F.Cu" "F.Mask" "F.Paste")
			(net "GND")
			(options
				(clearance outline)
				(anchor circle)
			)
			(primitives
				(gr_poly
					(pts
						(arc
							(start -0.2413 0.1397)
							(mid -0.381 0)
							(end -0.2413 -0.1397)
						)
						(xy 0.381 -0.1397) (xy 0.381 0.1397)
					)
					(width 0)
					(fill yes)
				)
			)
		)
		(pad "23" smd custom
			(at 2.8321 1.249934 90)
			(size 0.06985 0.06985)
			(layers "F.Cu" "F.Mask" "F.Paste")
			(net "GND")
			(options
				(clearance outline)
				(anchor circle)
			)
			(primitives
				(gr_poly
					(pts
						(arc
							(start -0.2413 0.1397)
							(mid -0.381 0)
							(end -0.2413 -0.1397)
						)
						(xy 0.381 -0.1397) (xy 0.381 0.1397)
					)
					(width 0)
					(fill yes)
				)
			)
		)
		(pad "24" smd custom
			(at 2.8321 0.750062 90)
			(size 0.06985 0.06985)
			(layers "F.Cu" "F.Mask" "F.Paste")
			(net "GND")
			(options
				(clearance outline)
				(anchor circle)
			)
			(primitives
				(gr_poly
					(pts
						(arc
							(start -0.2413 0.1397)
							(mid -0.381 0)
							(end -0.2413 -0.1397)
						)
						(xy 0.381 -0.1397) (xy 0.381 0.1397)
					)
					(width 0)
					(fill yes)
				)
			)
		)
		(pad "25" smd custom
			(at 2.8321 0.249936 90)
			(size 0.06985 0.06985)
			(layers "F.Cu" "F.Mask" "F.Paste")
			(net "GND")
			(options
				(clearance outline)
				(anchor circle)
			)
			(primitives
				(gr_poly
					(pts
						(arc
							(start -0.2413 0.1397)
							(mid -0.381 0)
							(end -0.2413 -0.1397)
						)
						(xy 0.381 -0.1397) (xy 0.381 0.1397)
					)
					(width 0)
					(fill yes)
				)
			)
		)
		(pad "26" smd custom
			(at 2.8321 -0.249936 90)
			(size 0.06985 0.06985)
			(layers "F.Cu" "F.Mask" "F.Paste")
			(net "GND")
			(options
				(clearance outline)
				(anchor circle)
			)
			(primitives
				(gr_poly
					(pts
						(arc
							(start -0.2413 0.1397)
							(mid -0.381 0)
							(end -0.2413 -0.1397)
						)
						(xy 0.381 -0.1397) (xy 0.381 0.1397)
					)
					(width 0)
					(fill yes)
				)
			)
		)
		(pad "27" smd custom
			(at 2.8321 -0.750062 90)
			(size 0.06985 0.06985)
			(layers "F.Cu" "F.Mask" "F.Paste")
			(net "GND")
			(options
				(clearance outline)
				(anchor circle)
			)
			(primitives
				(gr_poly
					(pts
						(arc
							(start -0.2413 0.1397)
							(mid -0.381 0)
							(end -0.2413 -0.1397)
						)
						(xy 0.381 -0.1397) (xy 0.381 0.1397)
					)
					(width 0)
					(fill yes)
				)
			)
		)
		(pad "28" smd custom
			(at 2.8321 -1.249934 90)
			(size 0.06985 0.06985)
			(layers "F.Cu" "F.Mask" "F.Paste")
			(net "GND")
			(options
				(clearance outline)
				(anchor circle)
			)
			(primitives
				(gr_poly
					(pts
						(arc
							(start -0.2413 0.1397)
							(mid -0.381 0)
							(end -0.2413 -0.1397)
						)
						(xy 0.381 -0.1397) (xy 0.381 0.1397)
					)
					(width 0)
					(fill yes)
				)
			)
		)
		(pad "29" smd custom
			(at 2.8321 -1.75006 90)
			(size 0.06985 0.06985)
			(layers "F.Cu" "F.Mask" "F.Paste")
			(net "VR_PVPP_ABC_PHASE")
			(options
				(clearance outline)
				(anchor circle)
			)
			(primitives
				(gr_poly
					(pts
						(arc
							(start -0.2413 0.1397)
							(mid -0.381 0)
							(end -0.2413 -0.1397)
						)
						(xy 0.381 -0.1397) (xy 0.381 0.1397)
					)
					(width 0)
					(fill yes)
				)
			)
		)
		(pad "30" smd custom
			(at 2.8321 -2.249932 90)
			(size 0.06985 0.06985)
			(layers "F.Cu" "F.Mask" "F.Paste")
			(net "VR_PVPP_ABC_PHASE")
			(options
				(clearance outline)
				(anchor circle)
			)
			(primitives
				(gr_poly
					(pts
						(arc
							(start -0.2413 0.1397)
							(mid -0.381 0)
							(end -0.2413 -0.1397)
						)
						(xy 0.381 -0.1397) (xy 0.381 0.1397)
					)
					(width 0)
					(fill yes)
				)
			)
		)
		(pad "31" smd custom
			(at 2.249932 -2.8321 90)
			(size 0.06985 0.06985)
			(layers "F.Cu" "F.Mask" "F.Paste")
			(net "VR_PVPP_ABC_PHASE")
			(options
				(clearance outline)
				(anchor circle)
			)
			(primitives
				(gr_poly
					(pts
						(arc
							(start 0.1397 0.2413)
							(mid 0 0.381)
							(end -0.1397 0.2413)
						)
						(xy -0.1397 -0.381) (xy 0.1397 -0.381)
					)
					(width 0)
					(fill yes)
				)
			)
		)
		(pad "32" smd custom
			(at 1.75006 -2.8321 90)
			(size 0.06985 0.06985)
			(layers "F.Cu" "F.Mask" "F.Paste")
			(net "VR_PVPP_ABC_PHASE")
			(options
				(clearance outline)
				(anchor circle)
			)
			(primitives
				(gr_poly
					(pts
						(arc
							(start 0.1397 0.2413)
							(mid 0 0.381)
							(end -0.1397 0.2413)
						)
						(xy -0.1397 -0.381) (xy 0.1397 -0.381)
					)
					(width 0)
					(fill yes)
				)
			)
		)
		(pad "33" smd custom
			(at 1.249934 -2.8321 90)
			(size 0.06985 0.06985)
			(layers "F.Cu" "F.Mask" "F.Paste")
			(net "VR_PVPP_ABC_PHASE")
			(options
				(clearance outline)
				(anchor circle)
			)
			(primitives
				(gr_poly
					(pts
						(arc
							(start 0.1397 0.2413)
							(mid 0 0.381)
							(end -0.1397 0.2413)
						)
						(xy -0.1397 -0.381) (xy 0.1397 -0.381)
					)
					(width 0)
					(fill yes)
				)
			)
		)
		(pad "34" smd custom
			(at 0.750062 -2.8321 90)
			(size 0.06985 0.06985)
			(layers "F.Cu" "F.Mask" "F.Paste")
			(net "VR_PVPP_ABC_PHASE")
			(options
				(clearance outline)
				(anchor circle)
			)
			(primitives
				(gr_poly
					(pts
						(arc
							(start 0.1397 0.2413)
							(mid 0 0.381)
							(end -0.1397 0.2413)
						)
						(xy -0.1397 -0.381) (xy 0.1397 -0.381)
					)
					(width 0)
					(fill yes)
				)
			)
		)
		(pad "35" smd custom
			(at 0.249936 -2.8321 90)
			(size 0.06985 0.06985)
			(layers "F.Cu" "F.Mask" "F.Paste")
			(net "VR_PVPP_ABC_PHASE")
			(options
				(clearance outline)
				(anchor circle)
			)
			(primitives
				(gr_poly
					(pts
						(arc
							(start 0.1397 0.2413)
							(mid 0 0.381)
							(end -0.1397 0.2413)
						)
						(xy -0.1397 -0.381) (xy 0.1397 -0.381)
					)
					(width 0)
					(fill yes)
				)
			)
		)
		(pad "36" smd custom
			(at -0.249936 -2.8321 90)
			(size 0.06985 0.06985)
			(layers "F.Cu" "F.Mask" "F.Paste")
			(net "VR_PVPP_ABC_BOOT")
			(options
				(clearance outline)
				(anchor circle)
			)
			(primitives
				(gr_poly
					(pts
						(arc
							(start 0.1397 0.2413)
							(mid 0 0.381)
							(end -0.1397 0.2413)
						)
						(xy -0.1397 -0.381) (xy 0.1397 -0.381)
					)
					(width 0)
					(fill yes)
				)
			)
		)
		(pad "37" smd custom
			(at -0.750062 -2.8321 90)
			(size 0.06985 0.06985)
			(layers "F.Cu" "F.Mask" "F.Paste")
			(net "GND")
			(options
				(clearance outline)
				(anchor circle)
			)
			(primitives
				(gr_poly
					(pts
						(arc
							(start 0.1397 0.2413)
							(mid 0 0.381)
							(end -0.1397 0.2413)
						)
						(xy -0.1397 -0.381) (xy 0.1397 -0.381)
					)
					(width 0)
					(fill yes)
				)
			)
		)
		(pad "38" smd custom
			(at -1.249934 -2.8321 90)
			(size 0.06985 0.06985)
			(layers "F.Cu" "F.Mask" "F.Paste")
			(net "VR_VB_PVPP_ABC")
			(options
				(clearance outline)
				(anchor circle)
			)
			(primitives
				(gr_poly
					(pts
						(arc
							(start 0.1397 0.2413)
							(mid 0 0.381)
							(end -0.1397 0.2413)
						)
						(xy -0.1397 -0.381) (xy 0.1397 -0.381)
					)
					(width 0)
					(fill yes)
				)
			)
		)
		(pad "39" smd custom
			(at -1.75006 -2.8321 90)
			(size 0.06985 0.06985)
			(layers "F.Cu" "F.Mask" "F.Paste")
			(net "VR_FET_SW_P12V_STBY_PVPP_ABC")
			(options
				(clearance outline)
				(anchor circle)
			)
			(primitives
				(gr_poly
					(pts
						(arc
							(start 0.1397 0.2413)
							(mid 0 0.381)
							(end -0.1397 0.2413)
						)
						(xy -0.1397 -0.381) (xy 0.1397 -0.381)
					)
					(width 0)
					(fill yes)
				)
			)
		)
		(pad "40" smd custom
			(at -2.249932 -2.8321 90)
			(size 0.06985 0.06985)
			(layers "F.Cu" "F.Mask" "F.Paste")
			(net "FM_PVPP_PVDDQ_CPU0_EN_ABC")
			(options
				(clearance outline)
				(anchor circle)
			)
			(primitives
				(gr_poly
					(pts
						(arc
							(start 0.1397 0.2413)
							(mid 0 0.381)
							(end -0.1397 0.2413)
						)
						(xy -0.1397 -0.381) (xy 0.1397 -0.381)
					)
					(width 0)
					(fill yes)
				)
			)
		)
		(pad "41" smd rect
			(at -1.4478 -1.1938 90)
			(size 1.4986 2.0066)
			(layers "F.Cu" "F.Mask" "F.Paste")
			(net "GND")
		)
		(pad "42" smd rect
			(at -1.4478 1.1938 90)
			(size 1.4986 2.0066)
			(layers "F.Cu" "F.Mask" "F.Paste")
			(net "VR_FET_SW_P12V_STBY_PVPP_ABC")
		)
		(pad "43" smd rect
			(at 1.0033 0 90)
			(size 2.3876 4.3942)
			(layers "F.Cu" "F.Mask" "F.Paste")
			(net "VR_PVPP_ABC_PHASE")
		)
	)
	(footprint ""
		(layer "F.Cu")
		(at 439.976006 -41.663874 180)
		(property "Reference" "R25W7"
			(at 0 0 180)
			(layer "F.SilkS")
			(hide yes)
			(effects
				(font
					(size 1.27 1.27)
				)
			)
		)
		(property "Value" "*"
			(at 0.064008 -4.108196 180)
			(unlocked yes)
			(layer "F.Fab")
			(hide yes)
			(effects
				(font
					(size 1.27 1.016)
					(thickness 0.1524)
				)
			)
		)
		(property "Device Type" "120R2F-GP_RCL_GP-120R2F-GP,64.A"
			(at 0.064008 -5.632196 180)
			(unlocked yes)
			(layer "F.Fab")
			(hide yes)
			(effects
				(font
					(size 1.27 1.016)
					(thickness 0.1524)
				)
			)
		)
		(duplicate_pad_numbers_are_jumpers no)
		(fp_line
			(start 0.508 -0.9398)
			(end -0.508 -0.9398)
			(stroke
				(width 0.1524)
				(type default)
			)
			(layer "F.SilkS")
		)
		(fp_line
			(start -0.508 -0.9398)
			(end -0.508 0.9398)
			(stroke
				(width 0.1524)
				(type default)
			)
			(layer "F.SilkS")
		)
		(fp_rect
			(start -0.508 0.9398)
			(end 0.508 -0.9398)
			(stroke
				(width 0)
				(type default)
			)
			(fill no)
			(layer "F.CrtYd")
		)
		(fp_rect
			(start -0.508 0.9398)
			(end 0.508 -0.9398)
			(stroke
				(width 0)
				(type default)
			)
			(fill no)
			(layer "F.Fab")
		)
		(pad "1" smd custom
			(at 0 -0.4445 180)
			(size 0.1397 0.1397)
			(layers "F.Cu" "F.Mask" "F.Paste")
			(net "GND")
			(options
				(clearance outline)
				(anchor circle)
			)
			(primitives
				(gr_poly
					(pts
						(arc
							(start -0.1778 -0.2794)
							(mid -0.249642 -0.249642)
							(end -0.2794 -0.1778)
						)
						(arc
							(start -0.2794 0.1778)
							(mid -0.249642 0.249642)
							(end -0.1778 0.2794)
						)
						(arc
							(start 0.1778 0.2794)
							(mid 0.249642 0.249642)
							(end 0.2794 0.1778)
						)
						(arc
							(start 0.2794 -0.1778)
							(mid 0.249642 -0.249642)
							(end 0.1778 -0.2794)
						)
					)
					(width 0)
					(fill yes)
				)
			)
		)
		(pad "2" smd custom
			(at 0 0.4445 180)
			(size 0.1397 0.1397)
			(layers "F.Cu" "F.Mask" "F.Paste")
			(net "BMC_M_CAS_N")
			(options
				(clearance outline)
				(anchor circle)
			)
			(primitives
				(gr_poly
					(pts
						(arc
							(start -0.1778 -0.2794)
							(mid -0.249642 -0.249642)
							(end -0.2794 -0.1778)
						)
						(arc
							(start -0.2794 0.1778)
							(mid -0.249642 0.249642)
							(end -0.1778 0.2794)
						)
						(arc
							(start 0.1778 0.2794)
							(mid 0.249642 0.249642)
							(end 0.2794 0.1778)
						)
						(arc
							(start 0.2794 -0.1778)
							(mid 0.249642 -0.249642)
							(end 0.1778 -0.2794)
						)
					)
					(width 0)
					(fill yes)
				)
			)
		)
	)
	(footprint ""
		(layer "F.Cu")
		(at 266.397232 -12.954 90)
		(property "Reference" "C5G5"
			(at 1.848866 0.752348 90)
			(unlocked yes)
			(layer "F.SilkS")
			(effects
				(font
					(size 1.27 0.9652)
					(thickness 0.1524)
				)
			)
		)
		(property "Value" ""
			(at 0 0 90)
			(layer "F.Fab")
			(effects
				(font
					(size 1.27 1.27)
				)
			)
		)
		(duplicate_pad_numbers_are_jumpers no)
		(fp_rect
			(start -0.500126 1.598422)
			(end 0.500126 -0.201422)
			(stroke
				(width 0)
				(type default)
			)
			(fill no)
			(layer "F.CrtYd")
		)
		(fp_line
			(start 0.500126 -0.201422)
			(end 0.500126 1.598422)
			(stroke
				(width 0.1)
				(type default)
			)
			(layer "F.Fab")
		)
		(fp_line
			(start -0.500126 -0.201422)
			(end 0.500126 -0.201422)
			(stroke
				(width 0.1)
				(type default)
			)
			(layer "F.Fab")
		)
		(fp_line
			(start 0.500126 1.598422)
			(end -0.500126 1.598422)
			(stroke
				(width 0.1)
				(type default)
			)
			(layer "F.Fab")
		)
		(fp_line
			(start -0.500126 1.598422)
			(end -0.500126 -0.201422)
			(stroke
				(width 0.1)
				(type default)
			)
			(layer "F.Fab")
		)
		(pad "1" smd rect
			(at 0 0)
			(size 0.889 0.9906)
			(layers "F.Cu" "F.Mask" "F.Paste")
			(net "PVDDQ_ABC")
		)
		(pad "2" smd rect
			(at 0 1.397)
			(size 0.889 0.9906)
			(layers "F.Cu" "F.Mask" "F.Paste")
			(net "GND")
		)
		(zone
			(layer "F.Cu")
			(hatch none 0.5)
			(connect_pads
				(clearance 0)
			)
			(min_thickness 0.25)
			(keepout
				(tracks not_allowed)
				(vias allowed)
				(pads allowed)
				(copperpour not_allowed)
				(footprints allowed)
			)
			(placement
				(enabled no)
				(sheetname "")
			)
			(fill
				(thermal_gap 0.5)
				(thermal_bridge_width 0.5)
				(island_removal_mode 0)
			)
			(polygon
				(pts
					(xy 267.349732 -12.4587) (xy 267.349732 -13.4493) (xy 266.841732 -13.4493) (xy 266.841732 -12.4587)
				)
			)
		)
		(zone
			(layer "F.Cu")
			(hatch none 0.5)
			(connect_pads
				(clearance 0)
			)
			(min_thickness 0.25)
			(keepout
				(tracks allowed)
				(vias not_allowed)
				(pads allowed)
				(copperpour not_allowed)
				(footprints allowed)
			)
			(placement
				(enabled no)
				(sheetname "")
			)
			(fill
				(thermal_gap 0.5)
				(thermal_bridge_width 0.5)
				(island_removal_mode 0)
			)
			(polygon
				(pts
					(xy 267.349732 -12.4587) (xy 267.349732 -13.4493) (xy 266.841732 -13.4493) (xy 266.841732 -12.4587)
				)
			)
		)
	)
	(footprint ""
		(layer "F.Cu")
		(at 451.358 -28.7655)
		(property "Reference" "C25W2"
			(at -0.8382 -0.67818 0)
			(unlocked yes)
			(layer "F.SilkS")
			(effects
				(font
					(size 0.4064 0.254)
					(thickness 0.1524)
				)
				(justify left)
			)
		)
		(property "Value" ""
			(at 0 0 0)
			(layer "F.Fab")
			(effects
				(font
					(size 1.27 1.27)
				)
			)
		)
		(duplicate_pad_numbers_are_jumpers no)
		(fp_poly
			(pts
				(xy 0.3048 -0.1016) (xy 0.3048 0.9906) (xy -0.3048 0.9906) (xy -0.3048 -0.1016)
			)
			(stroke
				(width 0)
				(type default)
			)
			(fill no)
			(layer "F.CrtYd")
		)
		(fp_line
			(start -0.3048 -0.1016)
			(end -0.3048 0.9906)
			(stroke
				(width 0.1)
				(type default)
			)
			(layer "F.Fab")
		)
		(fp_line
			(start -0.3048 0.9906)
			(end 0.3048 0.9906)
			(stroke
				(width 0.1)
				(type default)
			)
			(layer "F.Fab")
		)
		(fp_line
			(start 0.3048 -0.1016)
			(end -0.3048 -0.1016)
			(stroke
				(width 0.1)
				(type default)
			)
			(layer "F.Fab")
		)
		(fp_line
			(start 0.3048 0.9906)
			(end 0.3048 -0.1016)
			(stroke
				(width 0.1)
				(type default)
			)
			(layer "F.Fab")
		)
		(pad "1" smd rect
			(at 0 0)
			(size 0.508 0.508)
			(layers "F.Cu" "F.Mask" "F.Paste")
			(net "P1V2_AUX_BMC")
		)
		(pad "2" smd rect
			(at 0 0.889)
			(size 0.508 0.508)
			(layers "F.Cu" "F.Mask" "F.Paste")
			(net "GND")
		)
		(zone
			(layer "F.Cu")
			(hatch none 0.5)
			(connect_pads
				(clearance 0)
			)
			(min_thickness 0.25)
			(keepout
				(tracks allowed)
				(vias not_allowed)
				(pads allowed)
				(copperpour not_allowed)
				(footprints allowed)
			)
			(placement
				(enabled no)
				(sheetname "")
			)
			(fill
				(thermal_gap 0.5)
				(thermal_bridge_width 0.5)
				(island_removal_mode 0)
			)
			(polygon
				(pts
					(xy 451.104 -28.5115) (xy 451.612 -28.5115) (xy 451.612 -28.1305) (xy 451.104 -28.1305)
				)
			)
		)
		(zone
			(layer "F.Cu")
			(hatch none 0.5)
			(connect_pads
				(clearance 0)
			)
			(min_thickness 0.25)
			(keepout
				(tracks not_allowed)
				(vias allowed)
				(pads allowed)
				(copperpour not_allowed)
				(footprints allowed)
			)
			(placement
				(enabled no)
				(sheetname "")
			)
			(fill
				(thermal_gap 0.5)
				(thermal_bridge_width 0.5)
				(island_removal_mode 0)
			)
			(polygon
				(pts
					(xy 451.104 -28.1305) (xy 451.612 -28.1305) (xy 451.612 -28.5115) (xy 451.104 -28.5115)
				)
			)
		)
	)
	(footprint ""
		(layer "F.Cu")
		(at 337.429602 -120.038368 90)
		(property "Reference" "C6B16"
			(at -0.8382 -0.67818 90)
			(unlocked yes)
			(layer "F.SilkS")
			(effects
				(font
					(size 0.4064 0.254)
					(thickness 0.1524)
				)
				(justify left)
			)
		)
		(property "Value" ""
			(at 0 0 90)
			(layer "F.Fab")
			(effects
				(font
					(size 1.27 1.27)
				)
			)
		)
		(duplicate_pad_numbers_are_jumpers no)
		(fp_poly
			(pts
				(xy 0.3048 -0.1016) (xy 0.3048 0.9906) (xy -0.3048 0.9906) (xy -0.3048 -0.1016)
			)
			(stroke
				(width 0)
				(type default)
			)
			(fill no)
			(layer "F.CrtYd")
		)
		(fp_line
			(start 0.3048 -0.1016)
			(end -0.3048 -0.1016)
			(stroke
				(width 0.1)
				(type default)
			)
			(layer "F.Fab")
		)
		(fp_line
			(start -0.3048 -0.1016)
			(end -0.3048 0.9906)
			(stroke
				(width 0.1)
				(type default)
			)
			(layer "F.Fab")
		)
		(fp_line
			(start 0.3048 0.9906)
			(end 0.3048 -0.1016)
			(stroke
				(width 0.1)
				(type default)
			)
			(layer "F.Fab")
		)
		(fp_line
			(start -0.3048 0.9906)
			(end 0.3048 0.9906)
			(stroke
				(width 0.1)
				(type default)
			)
			(layer "F.Fab")
		)
		(pad "1" smd rect
			(at 0 0 90)
			(size 0.508 0.508)
			(layers "F.Cu" "F.Mask" "F.Paste")
			(net "P3E_CPU0_PE1_PCH_TXP<10>")
		)
		(pad "2" smd rect
			(at 0 0.889 90)
			(size 0.508 0.508)
			(layers "F.Cu" "F.Mask" "F.Paste")
			(net "P3E_CPU0_PE1_PCH_C_TXP<10>")
		)
		(zone
			(layer "F.Cu")
			(hatch none 0.5)
			(connect_pads
				(clearance 0)
			)
			(min_thickness 0.25)
			(keepout
				(tracks allowed)
				(vias not_allowed)
				(pads allowed)
				(copperpour not_allowed)
				(footprints allowed)
			)
			(placement
				(enabled no)
				(sheetname "")
			)
			(fill
				(thermal_gap 0.5)
				(thermal_bridge_width 0.5)
				(island_removal_mode 0)
			)
			(polygon
				(pts
					(xy 337.683602 -119.784368) (xy 337.683602 -120.292368) (xy 338.064602 -120.292368) (xy 338.064602 -119.784368)
				)
			)
		)
		(zone
			(layer "F.Cu")
			(hatch none 0.5)
			(connect_pads
				(clearance 0)
			)
			(min_thickness 0.25)
			(keepout
				(tracks not_allowed)
				(vias allowed)
				(pads allowed)
				(copperpour not_allowed)
				(footprints allowed)
			)
			(placement
				(enabled no)
				(sheetname "")
			)
			(fill
				(thermal_gap 0.5)
				(thermal_bridge_width 0.5)
				(island_removal_mode 0)
			)
			(polygon
				(pts
					(xy 338.064602 -119.784368) (xy 338.064602 -120.292368) (xy 337.683602 -120.292368) (xy 337.683602 -119.784368)
				)
			)
		)
	)
	(footprint ""
		(layer "F.Cu")
		(at 13.335 -101.981)
		(property "Reference" "R1C9"
			(at 0 0 0)
			(layer "F.SilkS")
			(hide yes)
			(effects
				(font
					(size 1.27 1.27)
				)
			)
		)
		(property "Value" ""
			(at 0 0 0)
			(layer "F.Fab")
			(effects
				(font
					(size 1.27 1.27)
				)
			)
		)
		(duplicate_pad_numbers_are_jumpers no)
		(fp_poly
			(pts
				(xy -0.2794 -0.1016) (xy 0.2794 -0.1016) (xy 0.2794 0.9906) (xy -0.2794 0.9906)
			)
			(stroke
				(width 0)
				(type default)
			)
			(fill no)
			(layer "F.CrtYd")
		)
		(fp_line
			(start -0.2794 -0.1016)
			(end -0.2794 0.9906)
			(stroke
				(width 0.1)
				(type default)
			)
			(layer "F.Fab")
		)
		(fp_line
			(start -0.2794 0.9906)
			(end 0.2794 0.9906)
			(stroke
				(width 0.1)
				(type default)
			)
			(layer "F.Fab")
		)
		(fp_line
			(start 0.2794 -0.1016)
			(end -0.2794 -0.1016)
			(stroke
				(width 0.1)
				(type default)
			)
			(layer "F.Fab")
		)
		(fp_line
			(start 0.2794 0.9906)
			(end 0.2794 -0.1016)
			(stroke
				(width 0.1)
				(type default)
			)
			(layer "F.Fab")
		)
		(pad "1" smd rect
			(at 0 0)
			(size 0.508 0.508)
			(layers "F.Cu" "F.Mask" "F.Paste")
			(net "IRQ_BOARD_BMC_ALERT_N")
		)
		(pad "2" smd rect
			(at 0 0.889)
			(size 0.508 0.508)
			(layers "F.Cu" "F.Mask" "F.Paste")
			(net "FAN_TACH2_R")
		)
		(zone
			(layer "F.Cu")
			(hatch none 0.5)
			(connect_pads
				(clearance 0)
			)
			(min_thickness 0.25)
			(keepout
				(tracks allowed)
				(vias not_allowed)
				(pads allowed)
				(copperpour not_allowed)
				(footprints allowed)
			)
			(placement
				(enabled no)
				(sheetname "")
			)
			(fill
				(thermal_gap 0.5)
				(thermal_bridge_width 0.5)
				(island_removal_mode 0)
			)
			(polygon
				(pts
					(xy 13.081 -101.727) (xy 13.589 -101.727) (xy 13.589 -101.346) (xy 13.081 -101.346)
				)
			)
		)
		(zone
			(layer "F.Cu")
			(hatch none 0.5)
			(connect_pads
				(clearance 0)
			)
			(min_thickness 0.25)
			(keepout
				(tracks not_allowed)
				(vias allowed)
				(pads allowed)
				(copperpour not_allowed)
				(footprints allowed)
			)
			(placement
				(enabled no)
				(sheetname "")
			)
			(fill
				(thermal_gap 0.5)
				(thermal_bridge_width 0.5)
				(island_removal_mode 0)
			)
			(polygon
				(pts
					(xy 13.081 -101.346) (xy 13.589 -101.346) (xy 13.589 -101.727) (xy 13.081 -101.727)
				)
			)
		)
	)
	(footprint ""
		(layer "F.Cu")
		(at 434.37048 -43.844464 -90)
		(property "Reference" "R9F33"
			(at 0 0 270)
			(layer "F.SilkS")
			(hide yes)
			(effects
				(font
					(size 1.27 1.27)
				)
			)
		)
		(property "Value" ""
			(at 0 0 270)
			(layer "F.Fab")
			(effects
				(font
					(size 1.27 1.27)
				)
			)
		)
		(duplicate_pad_numbers_are_jumpers no)
		(fp_poly
			(pts
				(xy -0.2794 -0.1016) (xy 0.2794 -0.1016) (xy 0.2794 0.9906) (xy -0.2794 0.9906)
			)
			(stroke
				(width 0)
				(type default)
			)
			(fill no)
			(layer "F.CrtYd")
		)
		(fp_line
			(start -0.2794 0.9906)
			(end 0.2794 0.9906)
			(stroke
				(width 0.1)
				(type default)
			)
			(layer "F.Fab")
		)
		(fp_line
			(start 0.2794 0.9906)
			(end 0.2794 -0.1016)
			(stroke
				(width 0.1)
				(type default)
			)
			(layer "F.Fab")
		)
		(fp_line
			(start -0.2794 -0.1016)
			(end -0.2794 0.9906)
			(stroke
				(width 0.1)
				(type default)
			)
			(layer "F.Fab")
		)
		(fp_line
			(start 0.2794 -0.1016)
			(end -0.2794 -0.1016)
			(stroke
				(width 0.1)
				(type default)
			)
			(layer "F.Fab")
		)
		(pad "1" smd rect
			(at 0 0 270)
			(size 0.508 0.508)
			(layers "F.Cu" "F.Mask" "F.Paste")
			(net "PECI_BMC")
		)
		(pad "2" smd rect
			(at 0 0.889 270)
			(size 0.508 0.508)
			(layers "F.Cu" "F.Mask" "F.Paste")
			(net "PECI_BMC_R")
		)
		(zone
			(layer "F.Cu")
			(hatch none 0.5)
			(connect_pads
				(clearance 0)
			)
			(min_thickness 0.25)
			(keepout
				(tracks not_allowed)
				(vias allowed)
				(pads allowed)
				(copperpour not_allowed)
				(footprints allowed)
			)
			(placement
				(enabled no)
				(sheetname "")
			)
			(fill
				(thermal_gap 0.5)
				(thermal_bridge_width 0.5)
				(island_removal_mode 0)
			)
			(polygon
				(pts
					(xy 433.73548 -44.098464) (xy 433.73548 -43.590464) (xy 434.11648 -43.590464) (xy 434.11648 -44.098464)
				)
			)
		)
		(zone
			(layer "F.Cu")
			(hatch none 0.5)
			(connect_pads
				(clearance 0)
			)
			(min_thickness 0.25)
			(keepout
				(tracks allowed)
				(vias not_allowed)
				(pads allowed)
				(copperpour not_allowed)
				(footprints allowed)
			)
			(placement
				(enabled no)
				(sheetname "")
			)
			(fill
				(thermal_gap 0.5)
				(thermal_bridge_width 0.5)
				(island_removal_mode 0)
			)
			(polygon
				(pts
					(xy 434.11648 -44.098464) (xy 434.11648 -43.590464) (xy 433.73548 -43.590464) (xy 433.73548 -44.098464)
				)
			)
		)
	)
	(footprint ""
		(layer "F.Cu")
		(at 426.5295 -130.556 -90)
		(property "Reference" "R8B6"
			(at 0 0 270)
			(layer "F.SilkS")
			(hide yes)
			(effects
				(font
					(size 1.27 1.27)
				)
			)
		)
		(property "Value" ""
			(at 0 0 270)
			(layer "F.Fab")
			(effects
				(font
					(size 1.27 1.27)
				)
			)
		)
		(duplicate_pad_numbers_are_jumpers no)
		(fp_poly
			(pts
				(xy -0.2794 -0.1016) (xy 0.2794 -0.1016) (xy 0.2794 0.9906) (xy -0.2794 0.9906)
			)
			(stroke
				(width 0)
				(type default)
			)
			(fill no)
			(layer "F.CrtYd")
		)
		(fp_line
			(start -0.2794 0.9906)
			(end 0.2794 0.9906)
			(stroke
				(width 0.1)
				(type default)
			)
			(layer "F.Fab")
		)
		(fp_line
			(start 0.2794 0.9906)
			(end 0.2794 -0.1016)
			(stroke
				(width 0.1)
				(type default)
			)
			(layer "F.Fab")
		)
		(fp_line
			(start -0.2794 -0.1016)
			(end -0.2794 0.9906)
			(stroke
				(width 0.1)
				(type default)
			)
			(layer "F.Fab")
		)
		(fp_line
			(start 0.2794 -0.1016)
			(end -0.2794 -0.1016)
			(stroke
				(width 0.1)
				(type default)
			)
			(layer "F.Fab")
		)
		(pad "1" smd rect
			(at 0 0 270)
			(size 0.508 0.508)
			(layers "F.Cu" "F.Mask" "F.Paste")
			(net "PVPP_ABC")
		)
		(pad "2" smd rect
			(at 0 0.889 270)
			(size 0.508 0.508)
			(layers "F.Cu" "F.Mask" "F.Paste")
			(net "SMB_HFI0_CPU0_LVC2_SCL")
		)
		(zone
			(layer "F.Cu")
			(hatch none 0.5)
			(connect_pads
				(clearance 0)
			)
			(min_thickness 0.25)
			(keepout
				(tracks not_allowed)
				(vias allowed)
				(pads allowed)
				(copperpour not_allowed)
				(footprints allowed)
			)
			(placement
				(enabled no)
				(sheetname "")
			)
			(fill
				(thermal_gap 0.5)
				(thermal_bridge_width 0.5)
				(island_removal_mode 0)
			)
			(polygon
				(pts
					(xy 425.8945 -130.81) (xy 425.8945 -130.302) (xy 426.2755 -130.302) (xy 426.2755 -130.81)
				)
			)
		)
		(zone
			(layer "F.Cu")
			(hatch none 0.5)
			(connect_pads
				(clearance 0)
			)
			(min_thickness 0.25)
			(keepout
				(tracks allowed)
				(vias not_allowed)
				(pads allowed)
				(copperpour not_allowed)
				(footprints allowed)
			)
			(placement
				(enabled no)
				(sheetname "")
			)
			(fill
				(thermal_gap 0.5)
				(thermal_bridge_width 0.5)
				(island_removal_mode 0)
			)
			(polygon
				(pts
					(xy 426.2755 -130.81) (xy 426.2755 -130.302) (xy 425.8945 -130.302) (xy 425.8945 -130.81)
				)
			)
		)
	)
	(footprint ""
		(layer "F.Cu")
		(at 464.7057 -24.0157 90)
		(property "Reference" "R8E40"
			(at 0 0 90)
			(layer "F.SilkS")
			(hide yes)
			(effects
				(font
					(size 1.27 1.27)
				)
			)
		)
		(property "Value" ""
			(at 0 0 90)
			(layer "F.Fab")
			(effects
				(font
					(size 1.27 1.27)
				)
			)
		)
		(duplicate_pad_numbers_are_jumpers no)
		(fp_poly
			(pts
				(xy -0.2794 -0.1016) (xy 0.2794 -0.1016) (xy 0.2794 0.9906) (xy -0.2794 0.9906)
			)
			(stroke
				(width 0)
				(type default)
			)
			(fill no)
			(layer "F.CrtYd")
		)
		(fp_line
			(start 0.2794 -0.1016)
			(end -0.2794 -0.1016)
			(stroke
				(width 0.1)
				(type default)
			)
			(layer "F.Fab")
		)
		(fp_line
			(start -0.2794 -0.1016)
			(end -0.2794 0.9906)
			(stroke
				(width 0.1)
				(type default)
			)
			(layer "F.Fab")
		)
		(fp_line
			(start 0.2794 0.9906)
			(end 0.2794 -0.1016)
			(stroke
				(width 0.1)
				(type default)
			)
			(layer "F.Fab")
		)
		(fp_line
			(start -0.2794 0.9906)
			(end 0.2794 0.9906)
			(stroke
				(width 0.1)
				(type default)
			)
			(layer "F.Fab")
		)
		(pad "1" smd rect
			(at 0 0 90)
			(size 0.508 0.508)
			(layers "F.Cu" "F.Mask" "F.Paste")
			(net "P3V3_STBY")
		)
		(pad "2" smd rect
			(at 0 0.889 90)
			(size 0.508 0.508)
			(layers "F.Cu" "F.Mask" "F.Paste")
			(net "VR_P3V3_STBY_EN")
		)
		(zone
			(layer "F.Cu")
			(hatch none 0.5)
			(connect_pads
				(clearance 0)
			)
			(min_thickness 0.25)
			(keepout
				(tracks allowed)
				(vias not_allowed)
				(pads allowed)
				(copperpour not_allowed)
				(footprints allowed)
			)
			(placement
				(enabled no)
				(sheetname "")
			)
			(fill
				(thermal_gap 0.5)
				(thermal_bridge_width 0.5)
				(island_removal_mode 0)
			)
			(polygon
				(pts
					(xy 464.9597 -23.7617) (xy 464.9597 -24.2697) (xy 465.3407 -24.2697) (xy 465.3407 -23.7617)
				)
			)
		)
		(zone
			(layer "F.Cu")
			(hatch none 0.5)
			(connect_pads
				(clearance 0)
			)
			(min_thickness 0.25)
			(keepout
				(tracks not_allowed)
				(vias allowed)
				(pads allowed)
				(copperpour not_allowed)
				(footprints allowed)
			)
			(placement
				(enabled no)
				(sheetname "")
			)
			(fill
				(thermal_gap 0.5)
				(thermal_bridge_width 0.5)
				(island_removal_mode 0)
			)
			(polygon
				(pts
					(xy 465.3407 -23.7617) (xy 465.3407 -24.2697) (xy 464.9597 -24.2697) (xy 464.9597 -23.7617)
				)
			)
		)
	)
	(footprint ""
		(layer "F.Cu")
		(at 388.8359 -154.2161)
		(property "Reference" "C7A40"
			(at 0 0 0)
			(layer "F.SilkS")
			(hide yes)
			(effects
				(font
					(size 1.27 1.27)
				)
			)
		)
		(property "Value" ""
			(at 0 0 0)
			(layer "F.Fab")
			(effects
				(font
					(size 1.27 1.27)
				)
			)
		)
		(duplicate_pad_numbers_are_jumpers no)
		(fp_poly
			(pts
				(xy 0.3048 -0.1016) (xy 0.3048 0.9906) (xy -0.3048 0.9906) (xy -0.3048 -0.1016)
			)
			(stroke
				(width 0)
				(type default)
			)
			(fill no)
			(layer "F.CrtYd")
		)
		(fp_line
			(start -0.3048 -0.1016)
			(end -0.3048 0.9906)
			(stroke
				(width 0.1)
				(type default)
			)
			(layer "F.Fab")
		)
		(fp_line
			(start -0.3048 0.9906)
			(end 0.3048 0.9906)
			(stroke
				(width 0.1)
				(type default)
			)
			(layer "F.Fab")
		)
		(fp_line
			(start 0.3048 -0.1016)
			(end -0.3048 -0.1016)
			(stroke
				(width 0.1)
				(type default)
			)
			(layer "F.Fab")
		)
		(fp_line
			(start 0.3048 0.9906)
			(end 0.3048 -0.1016)
			(stroke
				(width 0.1)
				(type default)
			)
			(layer "F.Fab")
		)
		(pad "1" smd rect
			(at 0 0)
			(size 0.508 0.508)
			(layers "F.Cu" "F.Mask" "F.Paste")
			(net "VR_FET_SW_P12V_STBY_PVDDQ_DEF")
		)
		(pad "2" smd rect
			(at 0 0.889)
			(size 0.508 0.508)
			(layers "F.Cu" "F.Mask" "F.Paste")
			(net "GND")
		)
		(zone
			(layer "F.Cu")
			(hatch none 0.5)
			(connect_pads
				(clearance 0)
			)
			(min_thickness 0.25)
			(keepout
				(tracks allowed)
				(vias not_allowed)
				(pads allowed)
				(copperpour not_allowed)
				(footprints allowed)
			)
			(placement
				(enabled no)
				(sheetname "")
			)
			(fill
				(thermal_gap 0.5)
				(thermal_bridge_width 0.5)
				(island_removal_mode 0)
			)
			(polygon
				(pts
					(xy 388.5819 -153.9621) (xy 389.0899 -153.9621) (xy 389.0899 -153.5811) (xy 388.5819 -153.5811)
				)
			)
		)
		(zone
			(layer "F.Cu")
			(hatch none 0.5)
			(connect_pads
				(clearance 0)
			)
			(min_thickness 0.25)
			(keepout
				(tracks not_allowed)
				(vias allowed)
				(pads allowed)
				(copperpour not_allowed)
				(footprints allowed)
			)
			(placement
				(enabled no)
				(sheetname "")
			)
			(fill
				(thermal_gap 0.5)
				(thermal_bridge_width 0.5)
				(island_removal_mode 0)
			)
			(polygon
				(pts
					(xy 388.5819 -153.5811) (xy 389.0899 -153.5811) (xy 389.0899 -153.9621) (xy 388.5819 -153.9621)
				)
			)
		)
	)
	(footprint ""
		(layer "F.Cu")
		(at 10.795 -15.875)
		(property "Reference" "L1F2"
			(at 3.378708 -4.251706 0)
			(unlocked yes)
			(layer "F.SilkS")
			(effects
				(font
					(size 0.4064 0.254)
					(thickness 0.1524)
				)
			)
		)
		(property "Value" ""
			(at 0 0 0)
			(layer "F.Fab")
			(effects
				(font
					(size 1.27 1.27)
				)
			)
		)
		(duplicate_pad_numbers_are_jumpers no)
		(fp_line
			(start -1.1303 -3.199892)
			(end 8.3693 -3.199892)
			(stroke
				(width 0.1524)
				(type default)
			)
			(layer "F.SilkS")
		)
		(fp_line
			(start -1.1303 -1.6637)
			(end -1.1303 -3.199892)
			(stroke
				(width 0.1524)
				(type default)
			)
			(layer "F.SilkS")
		)
		(fp_line
			(start -1.1303 3.199892)
			(end -1.1303 1.6637)
			(stroke
				(width 0.1524)
				(type default)
			)
			(layer "F.SilkS")
		)
		(fp_line
			(start 8.3693 -3.199892)
			(end 8.3693 -1.6637)
			(stroke
				(width 0.1524)
				(type default)
			)
			(layer "F.SilkS")
		)
		(fp_line
			(start 8.3693 1.6637)
			(end 8.3693 3.199892)
			(stroke
				(width 0.1524)
				(type default)
			)
			(layer "F.SilkS")
		)
		(fp_line
			(start 8.3693 3.199892)
			(end -1.1303 3.199892)
			(stroke
				(width 0.1524)
				(type default)
			)
			(layer "F.SilkS")
		)
		(fp_rect
			(start -1.1303 3.199892)
			(end 8.3693 -3.199892)
			(stroke
				(width 0)
				(type default)
			)
			(fill no)
			(layer "F.CrtYd")
		)
		(fp_line
			(start -1.1303 -3.199892)
			(end 8.3693 -3.199892)
			(stroke
				(width 0.1)
				(type default)
			)
			(layer "F.Fab")
		)
		(fp_line
			(start -1.1303 3.199892)
			(end -1.1303 -3.199892)
			(stroke
				(width 0.1)
				(type default)
			)
			(layer "F.Fab")
		)
		(fp_line
			(start 8.3693 -3.199892)
			(end 8.3693 3.199892)
			(stroke
				(width 0.1)
				(type default)
			)
			(layer "F.Fab")
		)
		(fp_line
			(start 8.3693 3.199892)
			(end -1.1303 3.199892)
			(stroke
				(width 0.1)
				(type default)
			)
			(layer "F.Fab")
		)
		(pad "1" smd rect
			(at 0 0)
			(size 3.683 2.667)
			(layers "F.Cu" "F.Mask" "F.Paste")
			(net "VR_PVDDQ_GHJ_PH2_SW")
		)
		(pad "2" smd rect
			(at 7.239 0)
			(size 3.683 2.667)
			(layers "F.Cu" "F.Mask" "F.Paste")
			(net "PVDDQ_GHJ")
		)
	)
	(footprint ""
		(layer "F.Cu")
		(at 384.4798 -0.254)
		(property "Reference" "R7G15"
			(at 0 0 0)
			(layer "F.SilkS")
			(hide yes)
			(effects
				(font
					(size 1.27 1.27)
				)
			)
		)
		(property "Value" ""
			(at 0 0 0)
			(layer "F.Fab")
			(effects
				(font
					(size 1.27 1.27)
				)
			)
		)
		(duplicate_pad_numbers_are_jumpers no)
		(fp_poly
			(pts
				(xy -0.2794 -0.1016) (xy 0.2794 -0.1016) (xy 0.2794 0.9906) (xy -0.2794 0.9906)
			)
			(stroke
				(width 0)
				(type default)
			)
			(fill no)
			(layer "F.CrtYd")
		)
		(fp_line
			(start -0.2794 -0.1016)
			(end -0.2794 0.9906)
			(stroke
				(width 0.1)
				(type default)
			)
			(layer "F.Fab")
		)
		(fp_line
			(start -0.2794 0.9906)
			(end 0.2794 0.9906)
			(stroke
				(width 0.1)
				(type default)
			)
			(layer "F.Fab")
		)
		(fp_line
			(start 0.2794 -0.1016)
			(end -0.2794 -0.1016)
			(stroke
				(width 0.1)
				(type default)
			)
			(layer "F.Fab")
		)
		(fp_line
			(start 0.2794 0.9906)
			(end 0.2794 -0.1016)
			(stroke
				(width 0.1)
				(type default)
			)
			(layer "F.Fab")
		)
		(pad "1" smd rect
			(at 0 0)
			(size 0.508 0.508)
			(layers "F.Cu" "F.Mask" "F.Paste")
			(net "JTAG_PCH_PLD_TDO")
		)
		(pad "2" smd rect
			(at 0 0.889)
			(size 0.508 0.508)
			(layers "F.Cu" "F.Mask" "F.Paste")
			(net "JTAG_TDO")
		)
		(zone
			(layer "F.Cu")
			(hatch none 0.5)
			(connect_pads
				(clearance 0)
			)
			(min_thickness 0.25)
			(keepout
				(tracks allowed)
				(vias not_allowed)
				(pads allowed)
				(copperpour not_allowed)
				(footprints allowed)
			)
			(placement
				(enabled no)
				(sheetname "")
			)
			(fill
				(thermal_gap 0.5)
				(thermal_bridge_width 0.5)
				(island_removal_mode 0)
			)
			(polygon
				(pts
					(xy 384.2258 0) (xy 384.7338 0) (xy 384.7338 0.381) (xy 384.2258 0.381)
				)
			)
		)
		(zone
			(layer "F.Cu")
			(hatch none 0.5)
			(connect_pads
				(clearance 0)
			)
			(min_thickness 0.25)
			(keepout
				(tracks not_allowed)
				(vias allowed)
				(pads allowed)
				(copperpour not_allowed)
				(footprints allowed)
			)
			(placement
				(enabled no)
				(sheetname "")
			)
			(fill
				(thermal_gap 0.5)
				(thermal_bridge_width 0.5)
				(island_removal_mode 0)
			)
			(polygon
				(pts
					(xy 384.2258 0.381) (xy 384.7338 0.381) (xy 384.7338 0) (xy 384.2258 0)
				)
			)
		)
	)
	(footprint ""
		(layer "F.Cu")
		(at 401.13966 -152.66416 -90)
		(property "Reference" "R8W8"
			(at -0.8382 -0.67818 270)
			(unlocked yes)
			(layer "F.SilkS")
			(effects
				(font
					(size 0.4064 0.254)
					(thickness 0.1524)
				)
				(justify left)
			)
		)
		(property "Value" ""
			(at 0 0 270)
			(layer "F.Fab")
			(effects
				(font
					(size 1.27 1.27)
				)
			)
		)
		(duplicate_pad_numbers_are_jumpers no)
		(fp_poly
			(pts
				(xy -0.2794 -0.1016) (xy 0.2794 -0.1016) (xy 0.2794 0.9906) (xy -0.2794 0.9906)
			)
			(stroke
				(width 0)
				(type default)
			)
			(fill no)
			(layer "F.CrtYd")
		)
		(fp_line
			(start -0.2794 0.9906)
			(end 0.2794 0.9906)
			(stroke
				(width 0.1)
				(type default)
			)
			(layer "F.Fab")
		)
		(fp_line
			(start 0.2794 0.9906)
			(end 0.2794 -0.1016)
			(stroke
				(width 0.1)
				(type default)
			)
			(layer "F.Fab")
		)
		(fp_line
			(start -0.2794 -0.1016)
			(end -0.2794 0.9906)
			(stroke
				(width 0.1)
				(type default)
			)
			(layer "F.Fab")
		)
		(fp_line
			(start 0.2794 -0.1016)
			(end -0.2794 -0.1016)
			(stroke
				(width 0.1)
				(type default)
			)
			(layer "F.Fab")
		)
		(pad "1" smd rect
			(at 0 0 270)
			(size 0.508 0.508)
			(layers "F.Cu" "F.Mask" "F.Paste")
			(net "P3V3_STBY")
		)
		(pad "2" smd rect
			(at 0 0.889 270)
			(size 0.508 0.508)
			(layers "F.Cu" "F.Mask" "F.Paste")
			(net "PU_PVNN_PCH_PINALRT_N")
		)
		(zone
			(layer "F.Cu")
			(hatch none 0.5)
			(connect_pads
				(clearance 0)
			)
			(min_thickness 0.25)
			(keepout
				(tracks not_allowed)
				(vias allowed)
				(pads allowed)
				(copperpour not_allowed)
				(footprints allowed)
			)
			(placement
				(enabled no)
				(sheetname "")
			)
			(fill
				(thermal_gap 0.5)
				(thermal_bridge_width 0.5)
				(island_removal_mode 0)
			)
			(polygon
				(pts
					(xy 400.50466 -152.91816) (xy 400.50466 -152.41016) (xy 400.88566 -152.41016) (xy 400.88566 -152.91816)
				)
			)
		)
		(zone
			(layer "F.Cu")
			(hatch none 0.5)
			(connect_pads
				(clearance 0)
			)
			(min_thickness 0.25)
			(keepout
				(tracks allowed)
				(vias not_allowed)
				(pads allowed)
				(copperpour not_allowed)
				(footprints allowed)
			)
			(placement
				(enabled no)
				(sheetname "")
			)
			(fill
				(thermal_gap 0.5)
				(thermal_bridge_width 0.5)
				(island_removal_mode 0)
			)
			(polygon
				(pts
					(xy 400.88566 -152.91816) (xy 400.88566 -152.41016) (xy 400.50466 -152.41016) (xy 400.50466 -152.91816)
				)
			)
		)
	)
	(footprint ""
		(layer "F.Cu")
		(at 362.9152 -133.096 180)
		(property "Reference" "R7B4"
			(at 0 0 180)
			(layer "F.SilkS")
			(hide yes)
			(effects
				(font
					(size 1.27 1.27)
				)
			)
		)
		(property "Value" ""
			(at 0 0 180)
			(layer "F.Fab")
			(effects
				(font
					(size 1.27 1.27)
				)
			)
		)
		(duplicate_pad_numbers_are_jumpers no)
		(fp_poly
			(pts
				(xy -0.2794 -0.1016) (xy 0.2794 -0.1016) (xy 0.2794 0.9906) (xy -0.2794 0.9906)
			)
			(stroke
				(width 0)
				(type default)
			)
			(fill no)
			(layer "F.CrtYd")
		)
		(fp_line
			(start 0.2794 0.9906)
			(end 0.2794 -0.1016)
			(stroke
				(width 0.1)
				(type default)
			)
			(layer "F.Fab")
		)
		(fp_line
			(start 0.2794 -0.1016)
			(end -0.2794 -0.1016)
			(stroke
				(width 0.1)
				(type default)
			)
			(layer "F.Fab")
		)
		(fp_line
			(start -0.2794 0.9906)
			(end 0.2794 0.9906)
			(stroke
				(width 0.1)
				(type default)
			)
			(layer "F.Fab")
		)
		(fp_line
			(start -0.2794 -0.1016)
			(end -0.2794 0.9906)
			(stroke
				(width 0.1)
				(type default)
			)
			(layer "F.Fab")
		)
		(pad "1" smd rect
			(at 0 0 180)
			(size 0.508 0.508)
			(layers "F.Cu" "F.Mask" "F.Paste")
			(net "P3V3_STBY")
		)
		(pad "2" smd rect
			(at 0 0.889 180)
			(size 0.508 0.508)
			(layers "F.Cu" "F.Mask" "F.Paste")
			(net "IRQ_PVDDQ_DEF_VRHOT_LVT3_R_N")
		)
		(zone
			(layer "F.Cu")
			(hatch none 0.5)
			(connect_pads
				(clearance 0)
			)
			(min_thickness 0.25)
			(keepout
				(tracks not_allowed)
				(vias allowed)
				(pads allowed)
				(copperpour not_allowed)
				(footprints allowed)
			)
			(placement
				(enabled no)
				(sheetname "")
			)
			(fill
				(thermal_gap 0.5)
				(thermal_bridge_width 0.5)
				(island_removal_mode 0)
			)
			(polygon
				(pts
					(xy 363.1692 -133.731) (xy 362.6612 -133.731) (xy 362.6612 -133.35) (xy 363.1692 -133.35)
				)
			)
		)
		(zone
			(layer "F.Cu")
			(hatch none 0.5)
			(connect_pads
				(clearance 0)
			)
			(min_thickness 0.25)
			(keepout
				(tracks allowed)
				(vias not_allowed)
				(pads allowed)
				(copperpour not_allowed)
				(footprints allowed)
			)
			(placement
				(enabled no)
				(sheetname "")
			)
			(fill
				(thermal_gap 0.5)
				(thermal_bridge_width 0.5)
				(island_removal_mode 0)
			)
			(polygon
				(pts
					(xy 363.1692 -133.35) (xy 362.6612 -133.35) (xy 362.6612 -133.731) (xy 363.1692 -133.731)
				)
			)
		)
	)
	(footprint ""
		(layer "F.Cu")
		(at 490.148372 -55.87365)
		(property "Reference" "C30W4"
			(at 0 0 0)
			(layer "F.SilkS")
			(hide yes)
			(effects
				(font
					(size 1.27 1.27)
				)
			)
		)
		(property "Value" "*"
			(at -0.0762 -6.2357 0)
			(unlocked yes)
			(layer "F.Fab")
			(hide yes)
			(effects
				(font
					(size 1.27 1.016)
					(thickness 0.1524)
				)
			)
		)
		(property "Device Type" "SC22U16V5MX-4-GP_SMD-BCG5-SC22A"
			(at -0.0762 -8.2677 0)
			(unlocked yes)
			(layer "F.Fab")
			(hide yes)
			(effects
				(font
					(size 1.27 1.016)
					(thickness 0.1524)
				)
			)
		)
		(duplicate_pad_numbers_are_jumpers no)
		(fp_line
			(start 0.635 0)
			(end -0.635 0)
			(stroke
				(width 0.508)
				(type default)
			)
			(layer "F.SilkS")
		)
		(fp_rect
			(start -0.9652 1.778)
			(end 0.9652 -1.778)
			(stroke
				(width 0)
				(type default)
			)
			(fill no)
			(layer "F.CrtYd")
		)
		(fp_poly
			(pts
				(xy -0.9652 -1.778) (xy 0.9652 -1.778) (xy 0.9652 1.778) (xy -0.9652 1.778)
			)
			(stroke
				(width 0)
				(type default)
			)
			(fill no)
			(layer "F.Fab")
		)
		(pad "1" smd rect
			(at 0 -0.9652)
			(size 1.397 1.143)
			(layers "F.Cu" "F.Mask" "F.Paste")
			(net "P5V_STBY_USBC")
		)
		(pad "2" smd rect
			(at 0 0.9652)
			(size 1.397 1.143)
			(layers "F.Cu" "F.Mask" "F.Paste")
			(net "GND")
		)
	)
	(footprint ""
		(layer "F.Cu")
		(at 259.49402 -12.961112 90)
		(property "Reference" "C5G9"
			(at 0 0 90)
			(layer "F.SilkS")
			(hide yes)
			(effects
				(font
					(size 1.27 1.27)
				)
			)
		)
		(property "Value" ""
			(at 0 0 90)
			(layer "F.Fab")
			(effects
				(font
					(size 1.27 1.27)
				)
			)
		)
		(duplicate_pad_numbers_are_jumpers no)
		(fp_rect
			(start -0.7239 -0.2159)
			(end 0.7239 1.9939)
			(stroke
				(width 0)
				(type default)
			)
			(fill no)
			(layer "F.CrtYd")
		)
		(fp_line
			(start 0.7239 -0.2159)
			(end -0.7239 -0.2159)
			(stroke
				(width 0.1)
				(type default)
			)
			(layer "F.Fab")
		)
		(fp_line
			(start -0.7239 -0.2159)
			(end -0.7239 1.9939)
			(stroke
				(width 0.1)
				(type default)
			)
			(layer "F.Fab")
		)
		(fp_line
			(start 0.7239 1.9939)
			(end 0.7239 -0.2159)
			(stroke
				(width 0.1)
				(type default)
			)
			(layer "F.Fab")
		)
		(fp_line
			(start -0.7239 1.9939)
			(end 0.7239 1.9939)
			(stroke
				(width 0.1)
				(type default)
			)
			(layer "F.Fab")
		)
		(pad "1" smd rect
			(at 0 0 90)
			(size 1.27 1.016)
			(layers "F.Cu" "F.Mask" "F.Paste")
			(net "PVDDQ_ABC")
		)
		(pad "2" smd rect
			(at 0 1.778 90)
			(size 1.27 1.016)
			(layers "F.Cu" "F.Mask" "F.Paste")
			(net "GND")
		)
		(zone
			(layer "F.Cu")
			(hatch none 0.5)
			(connect_pads
				(clearance 0)
			)
			(min_thickness 0.25)
			(keepout
				(tracks not_allowed)
				(vias allowed)
				(pads allowed)
				(copperpour not_allowed)
				(footprints allowed)
			)
			(placement
				(enabled no)
				(sheetname "")
			)
			(fill
				(thermal_gap 0.5)
				(thermal_bridge_width 0.5)
				(island_removal_mode 0)
			)
			(polygon
				(pts
					(xy 260.00202 -12.326112) (xy 260.76402 -12.326112) (xy 260.76402 -13.596112) (xy 260.00202 -13.596112)
				)
			)
		)
	)
	(footprint ""
		(layer "F.Cu")
		(at 410.806138 -107.146598 90)
		(property "Reference" "R8C14"
			(at 0 0 90)
			(layer "F.SilkS")
			(hide yes)
			(effects
				(font
					(size 1.27 1.27)
				)
			)
		)
		(property "Value" ""
			(at 0 0 90)
			(layer "F.Fab")
			(effects
				(font
					(size 1.27 1.27)
				)
			)
		)
		(duplicate_pad_numbers_are_jumpers no)
		(fp_poly
			(pts
				(xy -0.2794 -0.1016) (xy 0.2794 -0.1016) (xy 0.2794 0.9906) (xy -0.2794 0.9906)
			)
			(stroke
				(width 0)
				(type default)
			)
			(fill no)
			(layer "F.CrtYd")
		)
		(fp_line
			(start 0.2794 -0.1016)
			(end -0.2794 -0.1016)
			(stroke
				(width 0.1)
				(type default)
			)
			(layer "F.Fab")
		)
		(fp_line
			(start -0.2794 -0.1016)
			(end -0.2794 0.9906)
			(stroke
				(width 0.1)
				(type default)
			)
			(layer "F.Fab")
		)
		(fp_line
			(start 0.2794 0.9906)
			(end 0.2794 -0.1016)
			(stroke
				(width 0.1)
				(type default)
			)
			(layer "F.Fab")
		)
		(fp_line
			(start -0.2794 0.9906)
			(end 0.2794 0.9906)
			(stroke
				(width 0.1)
				(type default)
			)
			(layer "F.Fab")
		)
		(pad "1" smd rect
			(at 0 0 90)
			(size 0.508 0.508)
			(layers "F.Cu" "F.Mask" "F.Paste")
			(net "SMB_HOST_STBY_LVC3_SCL_R1")
		)
		(pad "2" smd rect
			(at 0 0.889 90)
			(size 0.508 0.508)
			(layers "F.Cu" "F.Mask" "F.Paste")
			(net "SMB_HOST_STBY_LVC3_SCL")
		)
		(zone
			(layer "F.Cu")
			(hatch none 0.5)
			(connect_pads
				(clearance 0)
			)
			(min_thickness 0.25)
			(keepout
				(tracks allowed)
				(vias not_allowed)
				(pads allowed)
				(copperpour not_allowed)
				(footprints allowed)
			)
			(placement
				(enabled no)
				(sheetname "")
			)
			(fill
				(thermal_gap 0.5)
				(thermal_bridge_width 0.5)
				(island_removal_mode 0)
			)
			(polygon
				(pts
					(xy 411.060138 -106.892598) (xy 411.060138 -107.400598) (xy 411.441138 -107.400598) (xy 411.441138 -106.892598)
				)
			)
		)
		(zone
			(layer "F.Cu")
			(hatch none 0.5)
			(connect_pads
				(clearance 0)
			)
			(min_thickness 0.25)
			(keepout
				(tracks not_allowed)
				(vias allowed)
				(pads allowed)
				(copperpour not_allowed)
				(footprints allowed)
			)
			(placement
				(enabled no)
				(sheetname "")
			)
			(fill
				(thermal_gap 0.5)
				(thermal_bridge_width 0.5)
				(island_removal_mode 0)
			)
			(polygon
				(pts
					(xy 411.441138 -106.892598) (xy 411.441138 -107.400598) (xy 411.060138 -107.400598) (xy 411.060138 -106.892598)
				)
			)
		)
	)
	(footprint ""
		(layer "F.Cu")
		(at 109.728 -69.85)
		(property "Reference" "R3D22"
			(at 0 0 0)
			(layer "F.SilkS")
			(hide yes)
			(effects
				(font
					(size 1.27 1.27)
				)
			)
		)
		(property "Value" ""
			(at 0 0 0)
			(layer "F.Fab")
			(effects
				(font
					(size 1.27 1.27)
				)
			)
		)
		(duplicate_pad_numbers_are_jumpers no)
		(fp_poly
			(pts
				(xy -0.2794 -0.1016) (xy 0.2794 -0.1016) (xy 0.2794 0.9906) (xy -0.2794 0.9906)
			)
			(stroke
				(width 0)
				(type default)
			)
			(fill no)
			(layer "F.CrtYd")
		)
		(fp_line
			(start -0.2794 -0.1016)
			(end -0.2794 0.9906)
			(stroke
				(width 0.1)
				(type default)
			)
			(layer "F.Fab")
		)
		(fp_line
			(start -0.2794 0.9906)
			(end 0.2794 0.9906)
			(stroke
				(width 0.1)
				(type default)
			)
			(layer "F.Fab")
		)
		(fp_line
			(start 0.2794 -0.1016)
			(end -0.2794 -0.1016)
			(stroke
				(width 0.1)
				(type default)
			)
			(layer "F.Fab")
		)
		(fp_line
			(start 0.2794 0.9906)
			(end 0.2794 -0.1016)
			(stroke
				(width 0.1)
				(type default)
			)
			(layer "F.Fab")
		)
		(pad "1" smd rect
			(at 0 0)
			(size 0.508 0.508)
			(layers "F.Cu" "F.Mask" "F.Paste")
			(net "PVCCIO_CPU1")
		)
		(pad "2" smd rect
			(at 0 0.889)
			(size 0.508 0.508)
			(layers "F.Cu" "F.Mask" "F.Paste")
			(net "PU_CPU1_FRMAGENT")
		)
		(zone
			(layer "F.Cu")
			(hatch none 0.5)
			(connect_pads
				(clearance 0)
			)
			(min_thickness 0.25)
			(keepout
				(tracks allowed)
				(vias not_allowed)
				(pads allowed)
				(copperpour not_allowed)
				(footprints allowed)
			)
			(placement
				(enabled no)
				(sheetname "")
			)
			(fill
				(thermal_gap 0.5)
				(thermal_bridge_width 0.5)
				(island_removal_mode 0)
			)
			(polygon
				(pts
					(xy 109.474 -69.596) (xy 109.982 -69.596) (xy 109.982 -69.215) (xy 109.474 -69.215)
				)
			)
		)
		(zone
			(layer "F.Cu")
			(hatch none 0.5)
			(connect_pads
				(clearance 0)
			)
			(min_thickness 0.25)
			(keepout
				(tracks not_allowed)
				(vias allowed)
				(pads allowed)
				(copperpour not_allowed)
				(footprints allowed)
			)
			(placement
				(enabled no)
				(sheetname "")
			)
			(fill
				(thermal_gap 0.5)
				(thermal_bridge_width 0.5)
				(island_removal_mode 0)
			)
			(polygon
				(pts
					(xy 109.474 -69.215) (xy 109.982 -69.215) (xy 109.982 -69.596) (xy 109.474 -69.596)
				)
			)
		)
	)
	(footprint ""
		(layer "F.Cu")
		(at 464.312 -128.4986 -90)
		(property "Reference" "C9B8"
			(at 0 0 270)
			(layer "F.SilkS")
			(hide yes)
			(effects
				(font
					(size 1.27 1.27)
				)
			)
		)
		(property "Value" ""
			(at 0 0 270)
			(layer "F.Fab")
			(effects
				(font
					(size 1.27 1.27)
				)
			)
		)
		(duplicate_pad_numbers_are_jumpers no)
		(fp_line
			(start -2.2987 7.3533)
			(end -1.7272 7.3533)
			(stroke
				(width 0.1524)
				(type default)
			)
			(layer "F.SilkS")
		)
		(fp_line
			(start 1.7272 7.3533)
			(end 2.2987 7.3533)
			(stroke
				(width 0.1524)
				(type default)
			)
			(layer "F.SilkS")
		)
		(fp_line
			(start 2.2987 7.3533)
			(end 2.2987 -0.2413)
			(stroke
				(width 0.1524)
				(type default)
			)
			(layer "F.SilkS")
		)
		(fp_line
			(start -2.032 1.524)
			(end -1.7272 1.524)
			(stroke
				(width 0.1524)
				(type default)
			)
			(layer "F.SilkS")
		)
		(fp_line
			(start 2.032 1.524)
			(end 1.7272 1.524)
			(stroke
				(width 0.1524)
				(type default)
			)
			(layer "F.SilkS")
		)
		(fp_line
			(start -2.2987 -0.2413)
			(end -2.2987 7.3533)
			(stroke
				(width 0.1524)
				(type default)
			)
			(layer "F.SilkS")
		)
		(fp_line
			(start -2.032 -0.2413)
			(end -2.2987 -0.2413)
			(stroke
				(width 0.1524)
				(type default)
			)
			(layer "F.SilkS")
		)
		(fp_line
			(start 2.2987 -0.2413)
			(end 2.032 -0.2413)
			(stroke
				(width 0.1524)
				(type default)
			)
			(layer "F.SilkS")
		)
		(fp_line
			(start -2.032 -1.524)
			(end -2.032 1.524)
			(stroke
				(width 0.1524)
				(type default)
			)
			(layer "F.SilkS")
		)
		(fp_line
			(start -1.7272 -1.524)
			(end -2.032 -1.524)
			(stroke
				(width 0.1524)
				(type default)
			)
			(layer "F.SilkS")
		)
		(fp_line
			(start 1.7272 -1.524)
			(end 2.032 -1.524)
			(stroke
				(width 0.1524)
				(type default)
			)
			(layer "F.SilkS")
		)
		(fp_line
			(start 2.032 -1.524)
			(end 2.032 1.524)
			(stroke
				(width 0.1524)
				(type default)
			)
			(layer "F.SilkS")
		)
		(fp_poly
			(pts
				(xy -2.2987 -0.2413) (xy 2.2987 -0.2413) (xy 2.2987 7.3533) (xy -2.2987 7.3533)
			)
			(stroke
				(width 0)
				(type default)
			)
			(fill no)
			(layer "F.CrtYd")
		)
		(fp_line
			(start -2.2987 7.3533)
			(end -2.2987 -0.2413)
			(stroke
				(width 0.1)
				(type default)
			)
			(layer "F.Fab")
		)
		(fp_line
			(start 2.2987 7.3533)
			(end -2.2987 7.3533)
			(stroke
				(width 0.1)
				(type default)
			)
			(layer "F.Fab")
		)
		(fp_line
			(start -2.2987 -0.2413)
			(end 2.2987 -0.2413)
			(stroke
				(width 0.1)
				(type default)
			)
			(layer "F.Fab")
		)
		(fp_line
			(start 2.2987 -0.2413)
			(end 2.2987 7.3533)
			(stroke
				(width 0.1)
				(type default)
			)
			(layer "F.Fab")
		)
		(pad "1" smd rect
			(at 0 0 270)
			(size 2.54 3.048)
			(layers "F.Cu" "F.Mask" "F.Paste")
			(net "P5V_USB")
		)
		(pad "2" smd rect
			(at 0 7.112 270)
			(size 2.54 3.048)
			(layers "F.Cu" "F.Mask" "F.Paste")
			(net "GND")
		)
	)
	(footprint ""
		(layer "F.Cu")
		(at 178.943 -8.1788)
		(property "Reference" "C4G9"
			(at 0 0 0)
			(layer "F.SilkS")
			(hide yes)
			(effects
				(font
					(size 1.27 1.27)
				)
			)
		)
		(property "Value" ""
			(at 0 0 0)
			(layer "F.Fab")
			(effects
				(font
					(size 1.27 1.27)
				)
			)
		)
		(duplicate_pad_numbers_are_jumpers no)
		(fp_rect
			(start -0.3048 0.9906)
			(end 0.3048 -0.1016)
			(stroke
				(width 0)
				(type default)
			)
			(fill no)
			(layer "F.CrtYd")
		)
		(fp_line
			(start -0.3048 -0.1016)
			(end -0.3048 0.9906)
			(stroke
				(width 0.1)
				(type default)
			)
			(layer "F.Fab")
		)
		(fp_line
			(start -0.3048 0.9906)
			(end 0.3048 0.9906)
			(stroke
				(width 0.1)
				(type default)
			)
			(layer "F.Fab")
		)
		(fp_line
			(start 0.3048 -0.1016)
			(end -0.3048 -0.1016)
			(stroke
				(width 0.1)
				(type default)
			)
			(layer "F.Fab")
		)
		(fp_line
			(start 0.3048 0.9906)
			(end 0.3048 -0.1016)
			(stroke
				(width 0.1)
				(type default)
			)
			(layer "F.Fab")
		)
		(pad "1" smd rect
			(at 0 0)
			(size 0.508 0.508)
			(layers "F.Cu" "F.Mask" "F.Paste")
			(net "PWRGD_PVPP_GHJ_R")
		)
		(pad "2" smd rect
			(at 0 0.889)
			(size 0.508 0.508)
			(layers "F.Cu" "F.Mask" "F.Paste")
			(net "GND")
		)
		(zone
			(layer "F.Cu")
			(hatch none 0.5)
			(connect_pads
				(clearance 0)
			)
			(min_thickness 0.25)
			(keepout
				(tracks allowed)
				(vias not_allowed)
				(pads allowed)
				(copperpour not_allowed)
				(footprints allowed)
			)
			(placement
				(enabled no)
				(sheetname "")
			)
			(fill
				(thermal_gap 0.5)
				(thermal_bridge_width 0.5)
				(island_removal_mode 0)
			)
			(polygon
				(pts
					(xy 178.689 -7.5438) (xy 179.197 -7.5438) (xy 179.197 -7.9248) (xy 178.689 -7.9248)
				)
			)
		)
		(zone
			(layer "F.Cu")
			(hatch none 0.5)
			(connect_pads
				(clearance 0)
			)
			(min_thickness 0.25)
			(keepout
				(tracks not_allowed)
				(vias allowed)
				(pads allowed)
				(copperpour not_allowed)
				(footprints allowed)
			)
			(placement
				(enabled no)
				(sheetname "")
			)
			(fill
				(thermal_gap 0.5)
				(thermal_bridge_width 0.5)
				(island_removal_mode 0)
			)
			(polygon
				(pts
					(xy 178.689 -7.5438) (xy 179.197 -7.5438) (xy 179.197 -7.9248) (xy 178.689 -7.9248)
				)
			)
		)
	)
	(footprint ""
		(layer "F.Cu")
		(at 374.4849 -136.9949)
		(property "Reference" "C7A33"
			(at 0 0 0)
			(layer "F.SilkS")
			(hide yes)
			(effects
				(font
					(size 1.27 1.27)
				)
			)
		)
		(property "Value" ""
			(at 0 0 0)
			(layer "F.Fab")
			(effects
				(font
					(size 1.27 1.27)
				)
			)
		)
		(duplicate_pad_numbers_are_jumpers no)
		(fp_rect
			(start -0.7239 1.9939)
			(end 0.7239 -0.2159)
			(stroke
				(width 0)
				(type default)
			)
			(fill no)
			(layer "F.CrtYd")
		)
		(fp_line
			(start -0.7239 -0.2159)
			(end -0.7239 1.9939)
			(stroke
				(width 0.1)
				(type default)
			)
			(layer "F.Fab")
		)
		(fp_line
			(start -0.7239 1.9939)
			(end 0.7239 1.9939)
			(stroke
				(width 0.1)
				(type default)
			)
			(layer "F.Fab")
		)
		(fp_line
			(start 0.7239 -0.2159)
			(end -0.7239 -0.2159)
			(stroke
				(width 0.1)
				(type default)
			)
			(layer "F.Fab")
		)
		(fp_line
			(start 0.7239 1.9939)
			(end 0.7239 -0.2159)
			(stroke
				(width 0.1)
				(type default)
			)
			(layer "F.Fab")
		)
		(pad "1" smd rect
			(at 0 0)
			(size 1.27 1.016)
			(layers "F.Cu" "F.Mask" "F.Paste")
			(net "PVNN_PCH_STBY")
		)
		(pad "2" smd rect
			(at 0 1.778)
			(size 1.27 1.016)
			(layers "F.Cu" "F.Mask" "F.Paste")
			(net "GND")
		)
		(zone
			(layer "F.Cu")
			(hatch none 0.5)
			(connect_pads
				(clearance 0)
			)
			(min_thickness 0.25)
			(keepout
				(tracks not_allowed)
				(vias allowed)
				(pads allowed)
				(copperpour not_allowed)
				(footprints allowed)
			)
			(placement
				(enabled no)
				(sheetname "")
			)
			(fill
				(thermal_gap 0.5)
				(thermal_bridge_width 0.5)
				(island_removal_mode 0)
			)
			(polygon
				(pts
					(xy 373.8499 -135.7249) (xy 375.1199 -135.7249) (xy 375.1199 -136.4869) (xy 373.8499 -136.4869)
				)
			)
		)
	)
	(footprint ""
		(layer "F.Cu")
		(at 375.167144 -10.916158)
		(property "Reference" "C7G16"
			(at 0 0 0)
			(layer "F.SilkS")
			(hide yes)
			(effects
				(font
					(size 1.27 1.27)
				)
			)
		)
		(property "Value" ""
			(at 0 0 0)
			(layer "F.Fab")
			(effects
				(font
					(size 1.27 1.27)
				)
			)
		)
		(duplicate_pad_numbers_are_jumpers no)
		(fp_rect
			(start -0.3048 0.9906)
			(end 0.3048 -0.1016)
			(stroke
				(width 0)
				(type default)
			)
			(fill no)
			(layer "F.CrtYd")
		)
		(fp_line
			(start -0.3048 -0.1016)
			(end -0.3048 0.9906)
			(stroke
				(width 0.1)
				(type default)
			)
			(layer "F.Fab")
		)
		(fp_line
			(start -0.3048 0.9906)
			(end 0.3048 0.9906)
			(stroke
				(width 0.1)
				(type default)
			)
			(layer "F.Fab")
		)
		(fp_line
			(start 0.3048 -0.1016)
			(end -0.3048 -0.1016)
			(stroke
				(width 0.1)
				(type default)
			)
			(layer "F.Fab")
		)
		(fp_line
			(start 0.3048 0.9906)
			(end 0.3048 -0.1016)
			(stroke
				(width 0.1)
				(type default)
			)
			(layer "F.Fab")
		)
		(pad "1" smd rect
			(at 0 0)
			(size 0.508 0.508)
			(layers "F.Cu" "F.Mask" "F.Paste")
			(net "P3E_CPU0_PE2_SS_TXN<10>")
		)
		(pad "2" smd rect
			(at 0 0.889)
			(size 0.508 0.508)
			(layers "F.Cu" "F.Mask" "F.Paste")
			(net "P3E_CPU0_PE2_SS_C_TXN<10>")
		)
		(zone
			(layer "F.Cu")
			(hatch none 0.5)
			(connect_pads
				(clearance 0)
			)
			(min_thickness 0.25)
			(keepout
				(tracks allowed)
				(vias not_allowed)
				(pads allowed)
				(copperpour not_allowed)
				(footprints allowed)
			)
			(placement
				(enabled no)
				(sheetname "")
			)
			(fill
				(thermal_gap 0.5)
				(thermal_bridge_width 0.5)
				(island_removal_mode 0)
			)
			(polygon
				(pts
					(xy 374.913144 -10.281158) (xy 375.421144 -10.281158) (xy 375.421144 -10.662158) (xy 374.913144 -10.662158)
				)
			)
		)
		(zone
			(layer "F.Cu")
			(hatch none 0.5)
			(connect_pads
				(clearance 0)
			)
			(min_thickness 0.25)
			(keepout
				(tracks not_allowed)
				(vias allowed)
				(pads allowed)
				(copperpour not_allowed)
				(footprints allowed)
			)
			(placement
				(enabled no)
				(sheetname "")
			)
			(fill
				(thermal_gap 0.5)
				(thermal_bridge_width 0.5)
				(island_removal_mode 0)
			)
			(polygon
				(pts
					(xy 374.913144 -10.281158) (xy 375.421144 -10.281158) (xy 375.421144 -10.662158) (xy 374.913144 -10.662158)
				)
			)
		)
	)
	(footprint ""
		(layer "F.Cu")
		(at 30.579568 -3.321812 90)
		(property "Reference" "C1G19"
			(at 0 0 90)
			(layer "F.SilkS")
			(hide yes)
			(effects
				(font
					(size 1.27 1.27)
				)
			)
		)
		(property "Value" ""
			(at 0 0 90)
			(layer "F.Fab")
			(effects
				(font
					(size 1.27 1.27)
				)
			)
		)
		(duplicate_pad_numbers_are_jumpers no)
		(fp_poly
			(pts
				(xy 0.3048 -0.1016) (xy 0.3048 0.9906) (xy -0.3048 0.9906) (xy -0.3048 -0.1016)
			)
			(stroke
				(width 0)
				(type default)
			)
			(fill no)
			(layer "F.CrtYd")
		)
		(fp_line
			(start 0.3048 -0.1016)
			(end -0.3048 -0.1016)
			(stroke
				(width 0.1)
				(type default)
			)
			(layer "F.Fab")
		)
		(fp_line
			(start -0.3048 -0.1016)
			(end -0.3048 0.9906)
			(stroke
				(width 0.1)
				(type default)
			)
			(layer "F.Fab")
		)
		(fp_line
			(start 0.3048 0.9906)
			(end 0.3048 -0.1016)
			(stroke
				(width 0.1)
				(type default)
			)
			(layer "F.Fab")
		)
		(fp_line
			(start -0.3048 0.9906)
			(end 0.3048 0.9906)
			(stroke
				(width 0.1)
				(type default)
			)
			(layer "F.Fab")
		)
		(pad "1" smd rect
			(at 0 0 90)
			(size 0.508 0.508)
			(layers "F.Cu" "F.Mask" "F.Paste")
			(net "M_J_VREF")
		)
		(pad "2" smd rect
			(at 0 0.889 90)
			(size 0.508 0.508)
			(layers "F.Cu" "F.Mask" "F.Paste")
			(net "GND")
		)
		(zone
			(layer "F.Cu")
			(hatch none 0.5)
			(connect_pads
				(clearance 0)
			)
			(min_thickness 0.25)
			(keepout
				(tracks allowed)
				(vias not_allowed)
				(pads allowed)
				(copperpour not_allowed)
				(footprints allowed)
			)
			(placement
				(enabled no)
				(sheetname "")
			)
			(fill
				(thermal_gap 0.5)
				(thermal_bridge_width 0.5)
				(island_removal_mode 0)
			)
			(polygon
				(pts
					(xy 30.833568 -3.067812) (xy 30.833568 -3.575812) (xy 31.214568 -3.575812) (xy 31.214568 -3.067812)
				)
			)
		)
		(zone
			(layer "F.Cu")
			(hatch none 0.5)
			(connect_pads
				(clearance 0)
			)
			(min_thickness 0.25)
			(keepout
				(tracks not_allowed)
				(vias allowed)
				(pads allowed)
				(copperpour not_allowed)
				(footprints allowed)
			)
			(placement
				(enabled no)
				(sheetname "")
			)
			(fill
				(thermal_gap 0.5)
				(thermal_bridge_width 0.5)
				(island_removal_mode 0)
			)
			(polygon
				(pts
					(xy 31.214568 -3.067812) (xy 31.214568 -3.575812) (xy 30.833568 -3.575812) (xy 30.833568 -3.067812)
				)
			)
		)
	)
	(footprint ""
		(layer "F.Cu")
		(at 392.049 -0.254)
		(property "Reference" "R8G10"
			(at 0 0 0)
			(layer "F.SilkS")
			(hide yes)
			(effects
				(font
					(size 1.27 1.27)
				)
			)
		)
		(property "Value" ""
			(at 0 0 0)
			(layer "F.Fab")
			(effects
				(font
					(size 1.27 1.27)
				)
			)
		)
		(duplicate_pad_numbers_are_jumpers no)
		(fp_poly
			(pts
				(xy -0.2794 -0.1016) (xy 0.2794 -0.1016) (xy 0.2794 0.9906) (xy -0.2794 0.9906)
			)
			(stroke
				(width 0)
				(type default)
			)
			(fill no)
			(layer "F.CrtYd")
		)
		(fp_line
			(start -0.2794 -0.1016)
			(end -0.2794 0.9906)
			(stroke
				(width 0.1)
				(type default)
			)
			(layer "F.Fab")
		)
		(fp_line
			(start -0.2794 0.9906)
			(end 0.2794 0.9906)
			(stroke
				(width 0.1)
				(type default)
			)
			(layer "F.Fab")
		)
		(fp_line
			(start 0.2794 -0.1016)
			(end -0.2794 -0.1016)
			(stroke
				(width 0.1)
				(type default)
			)
			(layer "F.Fab")
		)
		(fp_line
			(start 0.2794 0.9906)
			(end 0.2794 -0.1016)
			(stroke
				(width 0.1)
				(type default)
			)
			(layer "F.Fab")
		)
		(pad "1" smd rect
			(at 0 0)
			(size 0.508 0.508)
			(layers "F.Cu" "F.Mask" "F.Paste")
			(net "JTAG_BMC_TRST_N")
		)
		(pad "2" smd rect
			(at 0 0.889)
			(size 0.508 0.508)
			(layers "F.Cu" "F.Mask" "F.Paste")
			(net "JTAG_TRST_N")
		)
		(zone
			(layer "F.Cu")
			(hatch none 0.5)
			(connect_pads
				(clearance 0)
			)
			(min_thickness 0.25)
			(keepout
				(tracks allowed)
				(vias not_allowed)
				(pads allowed)
				(copperpour not_allowed)
				(footprints allowed)
			)
			(placement
				(enabled no)
				(sheetname "")
			)
			(fill
				(thermal_gap 0.5)
				(thermal_bridge_width 0.5)
				(island_removal_mode 0)
			)
			(polygon
				(pts
					(xy 391.795 0) (xy 392.303 0) (xy 392.303 0.381) (xy 391.795 0.381)
				)
			)
		)
		(zone
			(layer "F.Cu")
			(hatch none 0.5)
			(connect_pads
				(clearance 0)
			)
			(min_thickness 0.25)
			(keepout
				(tracks not_allowed)
				(vias allowed)
				(pads allowed)
				(copperpour not_allowed)
				(footprints allowed)
			)
			(placement
				(enabled no)
				(sheetname "")
			)
			(fill
				(thermal_gap 0.5)
				(thermal_bridge_width 0.5)
				(island_removal_mode 0)
			)
			(polygon
				(pts
					(xy 391.795 0.381) (xy 392.303 0.381) (xy 392.303 0) (xy 391.795 0)
				)
			)
		)
	)
	(footprint ""
		(layer "F.Cu")
		(at 480.842574 4.65709 90)
		(property "Reference" "C9G16"
			(at 0 0 90)
			(layer "F.SilkS")
			(hide yes)
			(effects
				(font
					(size 1.27 1.27)
				)
			)
		)
		(property "Value" ""
			(at 0 0 90)
			(layer "F.Fab")
			(effects
				(font
					(size 1.27 1.27)
				)
			)
		)
		(duplicate_pad_numbers_are_jumpers no)
		(fp_poly
			(pts
				(xy 0.3048 -0.1016) (xy 0.3048 0.9906) (xy -0.3048 0.9906) (xy -0.3048 -0.1016)
			)
			(stroke
				(width 0)
				(type default)
			)
			(fill no)
			(layer "F.CrtYd")
		)
		(fp_line
			(start 0.3048 -0.1016)
			(end -0.3048 -0.1016)
			(stroke
				(width 0.1)
				(type default)
			)
			(layer "F.Fab")
		)
		(fp_line
			(start -0.3048 -0.1016)
			(end -0.3048 0.9906)
			(stroke
				(width 0.1)
				(type default)
			)
			(layer "F.Fab")
		)
		(fp_line
			(start 0.3048 0.9906)
			(end 0.3048 -0.1016)
			(stroke
				(width 0.1)
				(type default)
			)
			(layer "F.Fab")
		)
		(fp_line
			(start -0.3048 0.9906)
			(end 0.3048 0.9906)
			(stroke
				(width 0.1)
				(type default)
			)
			(layer "F.Fab")
		)
		(pad "1" smd rect
			(at 0 0 90)
			(size 0.508 0.508)
			(layers "F.Cu" "F.Mask" "F.Paste")
			(net "NIC_SET_P_MDI_2_DP")
		)
		(pad "2" smd rect
			(at 0 0.889 90)
			(size 0.508 0.508)
			(layers "F.Cu" "F.Mask" "F.Paste")
			(net "NIC_MDI_MNG_TX_DP")
		)
		(zone
			(layer "F.Cu")
			(hatch none 0.5)
			(connect_pads
				(clearance 0)
			)
			(min_thickness 0.25)
			(keepout
				(tracks allowed)
				(vias not_allowed)
				(pads allowed)
				(copperpour not_allowed)
				(footprints allowed)
			)
			(placement
				(enabled no)
				(sheetname "")
			)
			(fill
				(thermal_gap 0.5)
				(thermal_bridge_width 0.5)
				(island_removal_mode 0)
			)
			(polygon
				(pts
					(xy 481.096574 4.91109) (xy 481.096574 4.40309) (xy 481.477574 4.40309) (xy 481.477574 4.91109)
				)
			)
		)
		(zone
			(layer "F.Cu")
			(hatch none 0.5)
			(connect_pads
				(clearance 0)
			)
			(min_thickness 0.25)
			(keepout
				(tracks not_allowed)
				(vias allowed)
				(pads allowed)
				(copperpour not_allowed)
				(footprints allowed)
			)
			(placement
				(enabled no)
				(sheetname "")
			)
			(fill
				(thermal_gap 0.5)
				(thermal_bridge_width 0.5)
				(island_removal_mode 0)
			)
			(polygon
				(pts
					(xy 481.477574 4.91109) (xy 481.477574 4.40309) (xy 481.096574 4.40309) (xy 481.096574 4.91109)
				)
			)
		)
	)
	(footprint ""
		(layer "F.Cu")
		(at 99.43084 -73.318116)
		(property "Reference" "C2D35"
			(at 0 0 0)
			(layer "F.SilkS")
			(hide yes)
			(effects
				(font
					(size 1.27 1.27)
				)
			)
		)
		(property "Value" ""
			(at 0 0 0)
			(layer "F.Fab")
			(effects
				(font
					(size 1.27 1.27)
				)
			)
		)
		(duplicate_pad_numbers_are_jumpers no)
		(fp_poly
			(pts
				(xy -0.4953 -0.2032) (xy 0.4953 -0.2032) (xy 0.4953 1.6002) (xy -0.4953 1.6002)
			)
			(stroke
				(width 0)
				(type default)
			)
			(fill no)
			(layer "F.CrtYd")
		)
		(fp_line
			(start -0.4953 -0.2032)
			(end 0.4953 -0.2032)
			(stroke
				(width 0.1)
				(type default)
			)
			(layer "F.Fab")
		)
		(fp_line
			(start -0.4953 1.6002)
			(end -0.4953 -0.2032)
			(stroke
				(width 0.1)
				(type default)
			)
			(layer "F.Fab")
		)
		(fp_line
			(start 0.4953 -0.2032)
			(end 0.4953 1.6002)
			(stroke
				(width 0.1)
				(type default)
			)
			(layer "F.Fab")
		)
		(fp_line
			(start 0.4953 1.6002)
			(end -0.4953 1.6002)
			(stroke
				(width 0.1)
				(type default)
			)
			(layer "F.Fab")
		)
		(pad "1" smd rect
			(at 0 0)
			(size 0.762 0.889)
			(layers "F.Cu" "F.Mask" "F.Paste")
			(net "PVCCIN_CPU1")
		)
		(pad "2" smd rect
			(at 0 1.397)
			(size 0.762 0.889)
			(layers "F.Cu" "F.Mask" "F.Paste")
			(net "GND")
		)
		(zone
			(layer "F.Cu")
			(hatch none 0.5)
			(connect_pads
				(clearance 0)
			)
			(min_thickness 0.25)
			(keepout
				(tracks not_allowed)
				(vias allowed)
				(pads allowed)
				(copperpour not_allowed)
				(footprints allowed)
			)
			(placement
				(enabled no)
				(sheetname "")
			)
			(fill
				(thermal_gap 0.5)
				(thermal_bridge_width 0.5)
				(island_removal_mode 0)
			)
			(polygon
				(pts
					(xy 99.04984 -72.873616) (xy 99.81184 -72.873616) (xy 99.81184 -72.365616) (xy 99.04984 -72.365616)
				)
			)
		)
	)
	(footprint ""
		(layer "F.Cu")
		(at 282.067 -76.835 -90)
		(property "Reference" "R6D5"
			(at 0 0 270)
			(layer "F.SilkS")
			(hide yes)
			(effects
				(font
					(size 1.27 1.27)
				)
			)
		)
		(property "Value" ""
			(at 0 0 270)
			(layer "F.Fab")
			(effects
				(font
					(size 1.27 1.27)
				)
			)
		)
		(duplicate_pad_numbers_are_jumpers no)
		(fp_rect
			(start 0.2794 0.9906)
			(end -0.2794 -0.1016)
			(stroke
				(width 0)
				(type default)
			)
			(fill no)
			(layer "F.CrtYd")
		)
		(fp_line
			(start -0.2794 0.9906)
			(end 0.2794 0.9906)
			(stroke
				(width 0.1)
				(type default)
			)
			(layer "F.Fab")
		)
		(fp_line
			(start 0.2794 0.9906)
			(end 0.2794 -0.1016)
			(stroke
				(width 0.1)
				(type default)
			)
			(layer "F.Fab")
		)
		(fp_line
			(start -0.2794 -0.1016)
			(end -0.2794 0.9906)
			(stroke
				(width 0.1)
				(type default)
			)
			(layer "F.Fab")
		)
		(fp_line
			(start 0.2794 -0.1016)
			(end -0.2794 -0.1016)
			(stroke
				(width 0.1)
				(type default)
			)
			(layer "F.Fab")
		)
		(pad "1" smd rect
			(at 0 0 270)
			(size 0.508 0.508)
			(layers "F.Cu" "F.Mask" "F.Paste")
			(net "PD_CPU0_TEST12")
		)
		(pad "2" smd rect
			(at 0 0.889 270)
			(size 0.508 0.508)
			(layers "F.Cu" "F.Mask" "F.Paste")
			(net "GND")
		)
		(zone
			(layer "F.Cu")
			(hatch none 0.5)
			(connect_pads
				(clearance 0)
			)
			(min_thickness 0.25)
			(keepout
				(tracks not_allowed)
				(vias allowed)
				(pads allowed)
				(copperpour not_allowed)
				(footprints allowed)
			)
			(placement
				(enabled no)
				(sheetname "")
			)
			(fill
				(thermal_gap 0.5)
				(thermal_bridge_width 0.5)
				(island_removal_mode 0)
			)
			(polygon
				(pts
					(xy 281.432 -76.581) (xy 281.813 -76.581) (xy 281.813 -77.089) (xy 281.432 -77.089)
				)
			)
		)
		(zone
			(layer "F.Cu")
			(hatch none 0.5)
			(connect_pads
				(clearance 0)
			)
			(min_thickness 0.25)
			(keepout
				(tracks allowed)
				(vias not_allowed)
				(pads allowed)
				(copperpour not_allowed)
				(footprints allowed)
			)
			(placement
				(enabled no)
				(sheetname "")
			)
			(fill
				(thermal_gap 0.5)
				(thermal_bridge_width 0.5)
				(island_removal_mode 0)
			)
			(polygon
				(pts
					(xy 281.432 -76.581) (xy 281.813 -76.581) (xy 281.813 -77.089) (xy 281.432 -77.089)
				)
			)
		)
	)
	(footprint ""
		(layer "F.Cu")
		(at 460.082392 -37.956998)
		(property "Reference" "C9F8"
			(at 0 0 0)
			(layer "F.SilkS")
			(hide yes)
			(effects
				(font
					(size 1.27 1.27)
				)
			)
		)
		(property "Value" ""
			(at 0 0 0)
			(layer "F.Fab")
			(effects
				(font
					(size 1.27 1.27)
				)
			)
		)
		(duplicate_pad_numbers_are_jumpers no)
		(fp_poly
			(pts
				(xy 0.3048 -0.1016) (xy 0.3048 0.9906) (xy -0.3048 0.9906) (xy -0.3048 -0.1016)
			)
			(stroke
				(width 0)
				(type default)
			)
			(fill no)
			(layer "F.CrtYd")
		)
		(fp_line
			(start -0.3048 -0.1016)
			(end -0.3048 0.9906)
			(stroke
				(width 0.1)
				(type default)
			)
			(layer "F.Fab")
		)
		(fp_line
			(start -0.3048 0.9906)
			(end 0.3048 0.9906)
			(stroke
				(width 0.1)
				(type default)
			)
			(layer "F.Fab")
		)
		(fp_line
			(start 0.3048 -0.1016)
			(end -0.3048 -0.1016)
			(stroke
				(width 0.1)
				(type default)
			)
			(layer "F.Fab")
		)
		(fp_line
			(start 0.3048 0.9906)
			(end 0.3048 -0.1016)
			(stroke
				(width 0.1)
				(type default)
			)
			(layer "F.Fab")
		)
		(pad "1" smd rect
			(at 0 0)
			(size 0.508 0.508)
			(layers "F.Cu" "F.Mask" "F.Paste")
			(net "PWRGD_P1V15_BMC_STBY_R")
		)
		(pad "2" smd rect
			(at 0 0.889)
			(size 0.508 0.508)
			(layers "F.Cu" "F.Mask" "F.Paste")
			(net "GND")
		)
		(zone
			(layer "F.Cu")
			(hatch none 0.5)
			(connect_pads
				(clearance 0)
			)
			(min_thickness 0.25)
			(keepout
				(tracks allowed)
				(vias not_allowed)
				(pads allowed)
				(copperpour not_allowed)
				(footprints allowed)
			)
			(placement
				(enabled no)
				(sheetname "")
			)
			(fill
				(thermal_gap 0.5)
				(thermal_bridge_width 0.5)
				(island_removal_mode 0)
			)
			(polygon
				(pts
					(xy 459.828392 -37.702998) (xy 460.336392 -37.702998) (xy 460.336392 -37.321998) (xy 459.828392 -37.321998)
				)
			)
		)
		(zone
			(layer "F.Cu")
			(hatch none 0.5)
			(connect_pads
				(clearance 0)
			)
			(min_thickness 0.25)
			(keepout
				(tracks not_allowed)
				(vias allowed)
				(pads allowed)
				(copperpour not_allowed)
				(footprints allowed)
			)
			(placement
				(enabled no)
				(sheetname "")
			)
			(fill
				(thermal_gap 0.5)
				(thermal_bridge_width 0.5)
				(island_removal_mode 0)
			)
			(polygon
				(pts
					(xy 459.828392 -37.321998) (xy 460.336392 -37.321998) (xy 460.336392 -37.702998) (xy 459.828392 -37.702998)
				)
			)
		)
	)
	(footprint ""
		(layer "F.Cu")
		(at 446.786 -16.002 90)
		(property "Reference" "R25W153"
			(at -0.8382 -0.67818 90)
			(unlocked yes)
			(layer "F.SilkS")
			(effects
				(font
					(size 0.4064 0.254)
					(thickness 0.1524)
				)
				(justify left)
			)
		)
		(property "Value" ""
			(at 0 0 90)
			(layer "F.Fab")
			(effects
				(font
					(size 1.27 1.27)
				)
			)
		)
		(duplicate_pad_numbers_are_jumpers no)
		(fp_poly
			(pts
				(xy -0.2794 -0.1016) (xy 0.2794 -0.1016) (xy 0.2794 0.9906) (xy -0.2794 0.9906)
			)
			(stroke
				(width 0)
				(type default)
			)
			(fill no)
			(layer "F.CrtYd")
		)
		(fp_line
			(start 0.2794 -0.1016)
			(end -0.2794 -0.1016)
			(stroke
				(width 0.1)
				(type default)
			)
			(layer "F.Fab")
		)
		(fp_line
			(start -0.2794 -0.1016)
			(end -0.2794 0.9906)
			(stroke
				(width 0.1)
				(type default)
			)
			(layer "F.Fab")
		)
		(fp_line
			(start 0.2794 0.9906)
			(end 0.2794 -0.1016)
			(stroke
				(width 0.1)
				(type default)
			)
			(layer "F.Fab")
		)
		(fp_line
			(start -0.2794 0.9906)
			(end 0.2794 0.9906)
			(stroke
				(width 0.1)
				(type default)
			)
			(layer "F.Fab")
		)
		(pad "1" smd rect
			(at 0 0 90)
			(size 0.508 0.508)
			(layers "F.Cu" "F.Mask" "F.Paste")
			(net "P3V3_STBY")
		)
		(pad "2" smd rect
			(at 0 0.889 90)
			(size 0.508 0.508)
			(layers "F.Cu" "F.Mask" "F.Paste")
			(net "RST_BMC_SRST_N")
		)
		(zone
			(layer "F.Cu")
			(hatch none 0.5)
			(connect_pads
				(clearance 0)
			)
			(min_thickness 0.25)
			(keepout
				(tracks allowed)
				(vias not_allowed)
				(pads allowed)
				(copperpour not_allowed)
				(footprints allowed)
			)
			(placement
				(enabled no)
				(sheetname "")
			)
			(fill
				(thermal_gap 0.5)
				(thermal_bridge_width 0.5)
				(island_removal_mode 0)
			)
			(polygon
				(pts
					(xy 447.04 -15.748) (xy 447.04 -16.256) (xy 447.421 -16.256) (xy 447.421 -15.748)
				)
			)
		)
		(zone
			(layer "F.Cu")
			(hatch none 0.5)
			(connect_pads
				(clearance 0)
			)
			(min_thickness 0.25)
			(keepout
				(tracks not_allowed)
				(vias allowed)
				(pads allowed)
				(copperpour not_allowed)
				(footprints allowed)
			)
			(placement
				(enabled no)
				(sheetname "")
			)
			(fill
				(thermal_gap 0.5)
				(thermal_bridge_width 0.5)
				(island_removal_mode 0)
			)
			(polygon
				(pts
					(xy 447.421 -15.748) (xy 447.421 -16.256) (xy 447.04 -16.256) (xy 447.04 -15.748)
				)
			)
		)
	)
	(footprint ""
		(layer "F.Cu")
		(at 88.392 -140.208 90)
		(property "Reference" "C2A12"
			(at 1.848866 0.752348 90)
			(unlocked yes)
			(layer "F.SilkS")
			(effects
				(font
					(size 1.27 0.9652)
					(thickness 0.1524)
				)
			)
		)
		(property "Value" ""
			(at 0 0 90)
			(layer "F.Fab")
			(effects
				(font
					(size 1.27 1.27)
				)
			)
		)
		(duplicate_pad_numbers_are_jumpers no)
		(fp_rect
			(start -0.500126 1.598422)
			(end 0.500126 -0.201422)
			(stroke
				(width 0)
				(type default)
			)
			(fill no)
			(layer "F.CrtYd")
		)
		(fp_line
			(start 0.500126 -0.201422)
			(end 0.500126 1.598422)
			(stroke
				(width 0.1)
				(type default)
			)
			(layer "F.Fab")
		)
		(fp_line
			(start -0.500126 -0.201422)
			(end 0.500126 -0.201422)
			(stroke
				(width 0.1)
				(type default)
			)
			(layer "F.Fab")
		)
		(fp_line
			(start 0.500126 1.598422)
			(end -0.500126 1.598422)
			(stroke
				(width 0.1)
				(type default)
			)
			(layer "F.Fab")
		)
		(fp_line
			(start -0.500126 1.598422)
			(end -0.500126 -0.201422)
			(stroke
				(width 0.1)
				(type default)
			)
			(layer "F.Fab")
		)
		(pad "1" smd rect
			(at 0 0)
			(size 0.889 0.9906)
			(layers "F.Cu" "F.Mask" "F.Paste")
			(net "PVDDQ_KLM")
		)
		(pad "2" smd rect
			(at 0 1.397)
			(size 0.889 0.9906)
			(layers "F.Cu" "F.Mask" "F.Paste")
			(net "GND")
		)
		(zone
			(layer "F.Cu")
			(hatch none 0.5)
			(connect_pads
				(clearance 0)
			)
			(min_thickness 0.25)
			(keepout
				(tracks not_allowed)
				(vias allowed)
				(pads allowed)
				(copperpour not_allowed)
				(footprints allowed)
			)
			(placement
				(enabled no)
				(sheetname "")
			)
			(fill
				(thermal_gap 0.5)
				(thermal_bridge_width 0.5)
				(island_removal_mode 0)
			)
			(polygon
				(pts
					(xy 89.3445 -139.7127) (xy 89.3445 -140.7033) (xy 88.8365 -140.7033) (xy 88.8365 -139.7127)
				)
			)
		)
		(zone
			(layer "F.Cu")
			(hatch none 0.5)
			(connect_pads
				(clearance 0)
			)
			(min_thickness 0.25)
			(keepout
				(tracks allowed)
				(vias not_allowed)
				(pads allowed)
				(copperpour not_allowed)
				(footprints allowed)
			)
			(placement
				(enabled no)
				(sheetname "")
			)
			(fill
				(thermal_gap 0.5)
				(thermal_bridge_width 0.5)
				(island_removal_mode 0)
			)
			(polygon
				(pts
					(xy 89.3445 -139.7127) (xy 89.3445 -140.7033) (xy 88.8365 -140.7033) (xy 88.8365 -139.7127)
				)
			)
		)
	)
	(footprint ""
		(layer "F.Cu")
		(at 161.723832 -71.43369)
		(property "Reference" "R3D18"
			(at 0 0 0)
			(layer "F.SilkS")
			(hide yes)
			(effects
				(font
					(size 1.27 1.27)
				)
			)
		)
		(property "Value" ""
			(at 0 0 0)
			(layer "F.Fab")
			(effects
				(font
					(size 1.27 1.27)
				)
			)
		)
		(duplicate_pad_numbers_are_jumpers no)
		(fp_poly
			(pts
				(xy -0.2794 -0.1016) (xy 0.2794 -0.1016) (xy 0.2794 0.9906) (xy -0.2794 0.9906)
			)
			(stroke
				(width 0)
				(type default)
			)
			(fill no)
			(layer "F.CrtYd")
		)
		(fp_line
			(start -0.2794 -0.1016)
			(end -0.2794 0.9906)
			(stroke
				(width 0.1)
				(type default)
			)
			(layer "F.Fab")
		)
		(fp_line
			(start -0.2794 0.9906)
			(end 0.2794 0.9906)
			(stroke
				(width 0.1)
				(type default)
			)
			(layer "F.Fab")
		)
		(fp_line
			(start 0.2794 -0.1016)
			(end -0.2794 -0.1016)
			(stroke
				(width 0.1)
				(type default)
			)
			(layer "F.Fab")
		)
		(fp_line
			(start 0.2794 0.9906)
			(end 0.2794 -0.1016)
			(stroke
				(width 0.1)
				(type default)
			)
			(layer "F.Fab")
		)
		(pad "1" smd rect
			(at 0 0)
			(size 0.508 0.508)
			(layers "F.Cu" "F.Mask" "F.Paste")
			(net "H_CPU0_FAST_WAKE_N")
		)
		(pad "2" smd rect
			(at 0 0.889)
			(size 0.508 0.508)
			(layers "F.Cu" "F.Mask" "F.Paste")
			(net "H_CPU1_FAST_WAKE_N")
		)
		(zone
			(layer "F.Cu")
			(hatch none 0.5)
			(connect_pads
				(clearance 0)
			)
			(min_thickness 0.25)
			(keepout
				(tracks allowed)
				(vias not_allowed)
				(pads allowed)
				(copperpour not_allowed)
				(footprints allowed)
			)
			(placement
				(enabled no)
				(sheetname "")
			)
			(fill
				(thermal_gap 0.5)
				(thermal_bridge_width 0.5)
				(island_removal_mode 0)
			)
			(polygon
				(pts
					(xy 161.469832 -71.17969) (xy 161.977832 -71.17969) (xy 161.977832 -70.79869) (xy 161.469832 -70.79869)
				)
			)
		)
		(zone
			(layer "F.Cu")
			(hatch none 0.5)
			(connect_pads
				(clearance 0)
			)
			(min_thickness 0.25)
			(keepout
				(tracks not_allowed)
				(vias allowed)
				(pads allowed)
				(copperpour not_allowed)
				(footprints allowed)
			)
			(placement
				(enabled no)
				(sheetname "")
			)
			(fill
				(thermal_gap 0.5)
				(thermal_bridge_width 0.5)
				(island_removal_mode 0)
			)
			(polygon
				(pts
					(xy 161.469832 -70.79869) (xy 161.977832 -70.79869) (xy 161.977832 -71.17969) (xy 161.469832 -71.17969)
				)
			)
		)
	)
	(footprint ""
		(layer "F.Cu")
		(at 459.3336 -30.6832)
		(property "Reference" "R1U5"
			(at 0 0 0)
			(layer "F.SilkS")
			(hide yes)
			(effects
				(font
					(size 1.27 1.27)
				)
			)
		)
		(property "Value" ""
			(at 0 0 0)
			(layer "F.Fab")
			(effects
				(font
					(size 1.27 1.27)
				)
			)
		)
		(duplicate_pad_numbers_are_jumpers no)
		(fp_poly
			(pts
				(xy -0.2794 -0.1016) (xy 0.2794 -0.1016) (xy 0.2794 0.9906) (xy -0.2794 0.9906)
			)
			(stroke
				(width 0)
				(type default)
			)
			(fill no)
			(layer "F.CrtYd")
		)
		(fp_line
			(start -0.2794 -0.1016)
			(end -0.2794 0.9906)
			(stroke
				(width 0.1)
				(type default)
			)
			(layer "F.Fab")
		)
		(fp_line
			(start -0.2794 0.9906)
			(end 0.2794 0.9906)
			(stroke
				(width 0.1)
				(type default)
			)
			(layer "F.Fab")
		)
		(fp_line
			(start 0.2794 -0.1016)
			(end -0.2794 -0.1016)
			(stroke
				(width 0.1)
				(type default)
			)
			(layer "F.Fab")
		)
		(fp_line
			(start 0.2794 0.9906)
			(end 0.2794 -0.1016)
			(stroke
				(width 0.1)
				(type default)
			)
			(layer "F.Fab")
		)
		(pad "1" smd rect
			(at 0 0)
			(size 0.508 0.508)
			(layers "F.Cu" "F.Mask" "F.Paste")
			(net "FAN_TACH0")
		)
		(pad "2" smd rect
			(at 0 0.889)
			(size 0.508 0.508)
			(layers "F.Cu" "F.Mask" "F.Paste")
			(net "GND")
		)
		(zone
			(layer "F.Cu")
			(hatch none 0.5)
			(connect_pads
				(clearance 0)
			)
			(min_thickness 0.25)
			(keepout
				(tracks allowed)
				(vias not_allowed)
				(pads allowed)
				(copperpour not_allowed)
				(footprints allowed)
			)
			(placement
				(enabled no)
				(sheetname "")
			)
			(fill
				(thermal_gap 0.5)
				(thermal_bridge_width 0.5)
				(island_removal_mode 0)
			)
			(polygon
				(pts
					(xy 459.0796 -30.4292) (xy 459.5876 -30.4292) (xy 459.5876 -30.0482) (xy 459.0796 -30.0482)
				)
			)
		)
		(zone
			(layer "F.Cu")
			(hatch none 0.5)
			(connect_pads
				(clearance 0)
			)
			(min_thickness 0.25)
			(keepout
				(tracks not_allowed)
				(vias allowed)
				(pads allowed)
				(copperpour not_allowed)
				(footprints allowed)
			)
			(placement
				(enabled no)
				(sheetname "")
			)
			(fill
				(thermal_gap 0.5)
				(thermal_bridge_width 0.5)
				(island_removal_mode 0)
			)
			(polygon
				(pts
					(xy 459.0796 -30.0482) (xy 459.5876 -30.0482) (xy 459.5876 -30.4292) (xy 459.0796 -30.4292)
				)
			)
		)
	)
	(footprint ""
		(layer "F.Cu")
		(at 490.7153 -49.8094 90)
		(property "Reference" "R9E5"
			(at 0 0 90)
			(layer "F.SilkS")
			(hide yes)
			(effects
				(font
					(size 1.27 1.27)
				)
			)
		)
		(property "Value" ""
			(at 0 0 90)
			(layer "F.Fab")
			(effects
				(font
					(size 1.27 1.27)
				)
			)
		)
		(duplicate_pad_numbers_are_jumpers no)
		(fp_poly
			(pts
				(xy -0.2794 -0.1016) (xy 0.2794 -0.1016) (xy 0.2794 0.9906) (xy -0.2794 0.9906)
			)
			(stroke
				(width 0)
				(type default)
			)
			(fill no)
			(layer "F.CrtYd")
		)
		(fp_line
			(start 0.2794 -0.1016)
			(end -0.2794 -0.1016)
			(stroke
				(width 0.1)
				(type default)
			)
			(layer "F.Fab")
		)
		(fp_line
			(start -0.2794 -0.1016)
			(end -0.2794 0.9906)
			(stroke
				(width 0.1)
				(type default)
			)
			(layer "F.Fab")
		)
		(fp_line
			(start 0.2794 0.9906)
			(end 0.2794 -0.1016)
			(stroke
				(width 0.1)
				(type default)
			)
			(layer "F.Fab")
		)
		(fp_line
			(start -0.2794 0.9906)
			(end 0.2794 0.9906)
			(stroke
				(width 0.1)
				(type default)
			)
			(layer "F.Fab")
		)
		(pad "1" smd rect
			(at 0 0 90)
			(size 0.508 0.508)
			(layers "F.Cu" "F.Mask" "F.Paste")
			(net "SPI_NIC_CS_R_N")
		)
		(pad "2" smd rect
			(at 0 0.889 90)
			(size 0.508 0.508)
			(layers "F.Cu" "F.Mask" "F.Paste")
			(net "SPI_NIC_CS_N")
		)
		(zone
			(layer "F.Cu")
			(hatch none 0.5)
			(connect_pads
				(clearance 0)
			)
			(min_thickness 0.25)
			(keepout
				(tracks allowed)
				(vias not_allowed)
				(pads allowed)
				(copperpour not_allowed)
				(footprints allowed)
			)
			(placement
				(enabled no)
				(sheetname "")
			)
			(fill
				(thermal_gap 0.5)
				(thermal_bridge_width 0.5)
				(island_removal_mode 0)
			)
			(polygon
				(pts
					(xy 490.9693 -49.5554) (xy 490.9693 -50.0634) (xy 491.3503 -50.0634) (xy 491.3503 -49.5554)
				)
			)
		)
		(zone
			(layer "F.Cu")
			(hatch none 0.5)
			(connect_pads
				(clearance 0)
			)
			(min_thickness 0.25)
			(keepout
				(tracks not_allowed)
				(vias allowed)
				(pads allowed)
				(copperpour not_allowed)
				(footprints allowed)
			)
			(placement
				(enabled no)
				(sheetname "")
			)
			(fill
				(thermal_gap 0.5)
				(thermal_bridge_width 0.5)
				(island_removal_mode 0)
			)
			(polygon
				(pts
					(xy 491.3503 -49.5554) (xy 491.3503 -50.0634) (xy 490.9693 -50.0634) (xy 490.9693 -49.5554)
				)
			)
		)
	)
	(footprint ""
		(layer "F.Cu")
		(at 431.8 -26.797)
		(property "Reference" "R25W157"
			(at -0.8382 -0.67818 0)
			(unlocked yes)
			(layer "F.SilkS")
			(effects
				(font
					(size 0.4064 0.254)
					(thickness 0.1524)
				)
				(justify left)
			)
		)
		(property "Value" ""
			(at 0 0 0)
			(layer "F.Fab")
			(effects
				(font
					(size 1.27 1.27)
				)
			)
		)
		(duplicate_pad_numbers_are_jumpers no)
		(fp_poly
			(pts
				(xy -0.2794 -0.1016) (xy 0.2794 -0.1016) (xy 0.2794 0.9906) (xy -0.2794 0.9906)
			)
			(stroke
				(width 0)
				(type default)
			)
			(fill no)
			(layer "F.CrtYd")
		)
		(fp_line
			(start -0.2794 -0.1016)
			(end -0.2794 0.9906)
			(stroke
				(width 0.1)
				(type default)
			)
			(layer "F.Fab")
		)
		(fp_line
			(start -0.2794 0.9906)
			(end 0.2794 0.9906)
			(stroke
				(width 0.1)
				(type default)
			)
			(layer "F.Fab")
		)
		(fp_line
			(start 0.2794 -0.1016)
			(end -0.2794 -0.1016)
			(stroke
				(width 0.1)
				(type default)
			)
			(layer "F.Fab")
		)
		(fp_line
			(start 0.2794 0.9906)
			(end 0.2794 -0.1016)
			(stroke
				(width 0.1)
				(type default)
			)
			(layer "F.Fab")
		)
		(pad "1" smd rect
			(at 0 0)
			(size 0.508 0.508)
			(layers "F.Cu" "F.Mask" "F.Paste")
			(net "PUMP_TACH0")
		)
		(pad "2" smd rect
			(at 0 0.889)
			(size 0.508 0.508)
			(layers "F.Cu" "F.Mask" "F.Paste")
			(net "GND")
		)
		(zone
			(layer "F.Cu")
			(hatch none 0.5)
			(connect_pads
				(clearance 0)
			)
			(min_thickness 0.25)
			(keepout
				(tracks allowed)
				(vias not_allowed)
				(pads allowed)
				(copperpour not_allowed)
				(footprints allowed)
			)
			(placement
				(enabled no)
				(sheetname "")
			)
			(fill
				(thermal_gap 0.5)
				(thermal_bridge_width 0.5)
				(island_removal_mode 0)
			)
			(polygon
				(pts
					(xy 431.546 -26.543) (xy 432.054 -26.543) (xy 432.054 -26.162) (xy 431.546 -26.162)
				)
			)
		)
		(zone
			(layer "F.Cu")
			(hatch none 0.5)
			(connect_pads
				(clearance 0)
			)
			(min_thickness 0.25)
			(keepout
				(tracks not_allowed)
				(vias allowed)
				(pads allowed)
				(copperpour not_allowed)
				(footprints allowed)
			)
			(placement
				(enabled no)
				(sheetname "")
			)
			(fill
				(thermal_gap 0.5)
				(thermal_bridge_width 0.5)
				(island_removal_mode 0)
			)
			(polygon
				(pts
					(xy 431.546 -26.162) (xy 432.054 -26.162) (xy 432.054 -26.543) (xy 431.546 -26.543)
				)
			)
		)
	)
	(footprint ""
		(layer "F.Cu")
		(at 436.8165 -16.129 90)
		(property "Reference" "R1U35"
			(at 0 0 90)
			(layer "F.SilkS")
			(hide yes)
			(effects
				(font
					(size 1.27 1.27)
				)
			)
		)
		(property "Value" ""
			(at 0 0 90)
			(layer "F.Fab")
			(effects
				(font
					(size 1.27 1.27)
				)
			)
		)
		(duplicate_pad_numbers_are_jumpers no)
		(fp_poly
			(pts
				(xy -0.2794 -0.1016) (xy 0.2794 -0.1016) (xy 0.2794 0.9906) (xy -0.2794 0.9906)
			)
			(stroke
				(width 0)
				(type default)
			)
			(fill no)
			(layer "F.CrtYd")
		)
		(fp_line
			(start 0.2794 -0.1016)
			(end -0.2794 -0.1016)
			(stroke
				(width 0.1)
				(type default)
			)
			(layer "F.Fab")
		)
		(fp_line
			(start -0.2794 -0.1016)
			(end -0.2794 0.9906)
			(stroke
				(width 0.1)
				(type default)
			)
			(layer "F.Fab")
		)
		(fp_line
			(start 0.2794 0.9906)
			(end 0.2794 -0.1016)
			(stroke
				(width 0.1)
				(type default)
			)
			(layer "F.Fab")
		)
		(fp_line
			(start -0.2794 0.9906)
			(end 0.2794 0.9906)
			(stroke
				(width 0.1)
				(type default)
			)
			(layer "F.Fab")
		)
		(pad "1" smd rect
			(at 0 0 90)
			(size 0.508 0.508)
			(layers "F.Cu" "F.Mask" "F.Paste")
			(net "PVCCIO_CPU1")
		)
		(pad "2" smd rect
			(at 0 0.889 90)
			(size 0.508 0.508)
			(layers "F.Cu" "F.Mask" "F.Paste")
			(net "H_CPU1_MEMKLM_MEMHOT_G_N")
		)
		(zone
			(layer "F.Cu")
			(hatch none 0.5)
			(connect_pads
				(clearance 0)
			)
			(min_thickness 0.25)
			(keepout
				(tracks allowed)
				(vias not_allowed)
				(pads allowed)
				(copperpour not_allowed)
				(footprints allowed)
			)
			(placement
				(enabled no)
				(sheetname "")
			)
			(fill
				(thermal_gap 0.5)
				(thermal_bridge_width 0.5)
				(island_removal_mode 0)
			)
			(polygon
				(pts
					(xy 437.0705 -15.875) (xy 437.0705 -16.383) (xy 437.4515 -16.383) (xy 437.4515 -15.875)
				)
			)
		)
		(zone
			(layer "F.Cu")
			(hatch none 0.5)
			(connect_pads
				(clearance 0)
			)
			(min_thickness 0.25)
			(keepout
				(tracks not_allowed)
				(vias allowed)
				(pads allowed)
				(copperpour not_allowed)
				(footprints allowed)
			)
			(placement
				(enabled no)
				(sheetname "")
			)
			(fill
				(thermal_gap 0.5)
				(thermal_bridge_width 0.5)
				(island_removal_mode 0)
			)
			(polygon
				(pts
					(xy 437.4515 -15.875) (xy 437.4515 -16.383) (xy 437.0705 -16.383) (xy 437.0705 -15.875)
				)
			)
		)
	)
	(footprint ""
		(layer "F.Cu")
		(at 258.0386 -3.321812 -90)
		(property "Reference" "C5G19"
			(at 0 0 270)
			(layer "F.SilkS")
			(hide yes)
			(effects
				(font
					(size 1.27 1.27)
				)
			)
		)
		(property "Value" ""
			(at 0 0 270)
			(layer "F.Fab")
			(effects
				(font
					(size 1.27 1.27)
				)
			)
		)
		(duplicate_pad_numbers_are_jumpers no)
		(fp_rect
			(start -0.500126 1.598422)
			(end 0.500126 -0.201422)
			(stroke
				(width 0)
				(type default)
			)
			(fill no)
			(layer "F.CrtYd")
		)
		(fp_line
			(start -0.500126 1.598422)
			(end -0.500126 -0.201422)
			(stroke
				(width 0.1)
				(type default)
			)
			(layer "F.Fab")
		)
		(fp_line
			(start 0.500126 1.598422)
			(end -0.500126 1.598422)
			(stroke
				(width 0.1)
				(type default)
			)
			(layer "F.Fab")
		)
		(fp_line
			(start -0.500126 -0.201422)
			(end 0.500126 -0.201422)
			(stroke
				(width 0.1)
				(type default)
			)
			(layer "F.Fab")
		)
		(fp_line
			(start 0.500126 -0.201422)
			(end 0.500126 1.598422)
			(stroke
				(width 0.1)
				(type default)
			)
			(layer "F.Fab")
		)
		(pad "1" smd rect
			(at 0 0 180)
			(size 0.889 0.9906)
			(layers "F.Cu" "F.Mask" "F.Paste")
			(net "PVDDQ_ABC")
		)
		(pad "2" smd rect
			(at 0 1.397 180)
			(size 0.889 0.9906)
			(layers "F.Cu" "F.Mask" "F.Paste")
			(net "GND")
		)
		(zone
			(layer "F.Cu")
			(hatch none 0.5)
			(connect_pads
				(clearance 0)
			)
			(min_thickness 0.25)
			(keepout
				(tracks not_allowed)
				(vias allowed)
				(pads allowed)
				(copperpour not_allowed)
				(footprints allowed)
			)
			(placement
				(enabled no)
				(sheetname "")
			)
			(fill
				(thermal_gap 0.5)
				(thermal_bridge_width 0.5)
				(island_removal_mode 0)
			)
			(polygon
				(pts
					(xy 257.0861 -3.817112) (xy 257.0861 -2.826512) (xy 257.5941 -2.826512) (xy 257.5941 -3.817112)
				)
			)
		)
		(zone
			(layer "F.Cu")
			(hatch none 0.5)
			(connect_pads
				(clearance 0)
			)
			(min_thickness 0.25)
			(keepout
				(tracks allowed)
				(vias not_allowed)
				(pads allowed)
				(copperpour not_allowed)
				(footprints allowed)
			)
			(placement
				(enabled no)
				(sheetname "")
			)
			(fill
				(thermal_gap 0.5)
				(thermal_bridge_width 0.5)
				(island_removal_mode 0)
			)
			(polygon
				(pts
					(xy 257.0861 -3.817112) (xy 257.0861 -2.826512) (xy 257.5941 -2.826512) (xy 257.5941 -3.817112)
				)
			)
		)
	)
	(footprint ""
		(layer "F.Cu")
		(at 434.6702 -17.5006)
		(property "Reference" "R1U61"
			(at 0 0 0)
			(layer "F.SilkS")
			(hide yes)
			(effects
				(font
					(size 1.27 1.27)
				)
			)
		)
		(property "Value" ""
			(at 0 0 0)
			(layer "F.Fab")
			(effects
				(font
					(size 1.27 1.27)
				)
			)
		)
		(duplicate_pad_numbers_are_jumpers no)
		(fp_poly
			(pts
				(xy -0.2794 -0.1016) (xy 0.2794 -0.1016) (xy 0.2794 0.9906) (xy -0.2794 0.9906)
			)
			(stroke
				(width 0)
				(type default)
			)
			(fill no)
			(layer "F.CrtYd")
		)
		(fp_line
			(start -0.2794 -0.1016)
			(end -0.2794 0.9906)
			(stroke
				(width 0.1)
				(type default)
			)
			(layer "F.Fab")
		)
		(fp_line
			(start -0.2794 0.9906)
			(end 0.2794 0.9906)
			(stroke
				(width 0.1)
				(type default)
			)
			(layer "F.Fab")
		)
		(fp_line
			(start 0.2794 -0.1016)
			(end -0.2794 -0.1016)
			(stroke
				(width 0.1)
				(type default)
			)
			(layer "F.Fab")
		)
		(fp_line
			(start 0.2794 0.9906)
			(end 0.2794 -0.1016)
			(stroke
				(width 0.1)
				(type default)
			)
			(layer "F.Fab")
		)
		(pad "1" smd rect
			(at 0 0)
			(size 0.508 0.508)
			(layers "F.Cu" "F.Mask" "F.Paste")
			(net "H_CPU1_MEMKLM_MEMHOT_LVT3_K_N")
		)
		(pad "2" smd rect
			(at 0 0.889)
			(size 0.508 0.508)
			(layers "F.Cu" "F.Mask" "F.Paste")
			(net "H_CPU1_MEMKLM_MEMHOT_G_PCH_N")
		)
		(zone
			(layer "F.Cu")
			(hatch none 0.5)
			(connect_pads
				(clearance 0)
			)
			(min_thickness 0.25)
			(keepout
				(tracks allowed)
				(vias not_allowed)
				(pads allowed)
				(copperpour not_allowed)
				(footprints allowed)
			)
			(placement
				(enabled no)
				(sheetname "")
			)
			(fill
				(thermal_gap 0.5)
				(thermal_bridge_width 0.5)
				(island_removal_mode 0)
			)
			(polygon
				(pts
					(xy 434.4162 -17.2466) (xy 434.9242 -17.2466) (xy 434.9242 -16.8656) (xy 434.4162 -16.8656)
				)
			)
		)
		(zone
			(layer "F.Cu")
			(hatch none 0.5)
			(connect_pads
				(clearance 0)
			)
			(min_thickness 0.25)
			(keepout
				(tracks not_allowed)
				(vias allowed)
				(pads allowed)
				(copperpour not_allowed)
				(footprints allowed)
			)
			(placement
				(enabled no)
				(sheetname "")
			)
			(fill
				(thermal_gap 0.5)
				(thermal_bridge_width 0.5)
				(island_removal_mode 0)
			)
			(polygon
				(pts
					(xy 434.4162 -16.8656) (xy 434.9242 -16.8656) (xy 434.9242 -17.2466) (xy 434.4162 -17.2466)
				)
			)
		)
	)
	(footprint ""
		(layer "F.Cu")
		(at 14.1224 -37.719 -90)
		(property "Reference" "R1F9"
			(at 0 0 270)
			(layer "F.SilkS")
			(hide yes)
			(effects
				(font
					(size 1.27 1.27)
				)
			)
		)
		(property "Value" ""
			(at 0 0 270)
			(layer "F.Fab")
			(effects
				(font
					(size 1.27 1.27)
				)
			)
		)
		(duplicate_pad_numbers_are_jumpers no)
		(fp_poly
			(pts
				(xy -0.2794 -0.1016) (xy 0.2794 -0.1016) (xy 0.2794 0.9906) (xy -0.2794 0.9906)
			)
			(stroke
				(width 0)
				(type default)
			)
			(fill no)
			(layer "F.CrtYd")
		)
		(fp_line
			(start -0.2794 0.9906)
			(end 0.2794 0.9906)
			(stroke
				(width 0.1)
				(type default)
			)
			(layer "F.Fab")
		)
		(fp_line
			(start 0.2794 0.9906)
			(end 0.2794 -0.1016)
			(stroke
				(width 0.1)
				(type default)
			)
			(layer "F.Fab")
		)
		(fp_line
			(start -0.2794 -0.1016)
			(end -0.2794 0.9906)
			(stroke
				(width 0.1)
				(type default)
			)
			(layer "F.Fab")
		)
		(fp_line
			(start 0.2794 -0.1016)
			(end -0.2794 -0.1016)
			(stroke
				(width 0.1)
				(type default)
			)
			(layer "F.Fab")
		)
		(pad "1" smd rect
			(at 0 0 270)
			(size 0.508 0.508)
			(layers "F.Cu" "F.Mask" "F.Paste")
			(net "FM_BMC_READY_N")
		)
		(pad "2" smd rect
			(at 0 0.889 270)
			(size 0.508 0.508)
			(layers "F.Cu" "F.Mask" "F.Paste")
			(net "FAN_PWM_OUT_SYS0_R1")
		)
		(zone
			(layer "F.Cu")
			(hatch none 0.5)
			(connect_pads
				(clearance 0)
			)
			(min_thickness 0.25)
			(keepout
				(tracks not_allowed)
				(vias allowed)
				(pads allowed)
				(copperpour not_allowed)
				(footprints allowed)
			)
			(placement
				(enabled no)
				(sheetname "")
			)
			(fill
				(thermal_gap 0.5)
				(thermal_bridge_width 0.5)
				(island_removal_mode 0)
			)
			(polygon
				(pts
					(xy 13.4874 -37.973) (xy 13.4874 -37.465) (xy 13.8684 -37.465) (xy 13.8684 -37.973)
				)
			)
		)
		(zone
			(layer "F.Cu")
			(hatch none 0.5)
			(connect_pads
				(clearance 0)
			)
			(min_thickness 0.25)
			(keepout
				(tracks allowed)
				(vias not_allowed)
				(pads allowed)
				(copperpour not_allowed)
				(footprints allowed)
			)
			(placement
				(enabled no)
				(sheetname "")
			)
			(fill
				(thermal_gap 0.5)
				(thermal_bridge_width 0.5)
				(island_removal_mode 0)
			)
			(polygon
				(pts
					(xy 13.8684 -37.973) (xy 13.8684 -37.465) (xy 13.4874 -37.465) (xy 13.4874 -37.973)
				)
			)
		)
	)
	(footprint ""
		(layer "F.Cu")
		(at 13.8938 -25.908 90)
		(property "Reference" "C1F16"
			(at 0 0 90)
			(layer "F.SilkS")
			(hide yes)
			(effects
				(font
					(size 1.27 1.27)
				)
			)
		)
		(property "Value" ""
			(at 0 0 90)
			(layer "F.Fab")
			(effects
				(font
					(size 1.27 1.27)
				)
			)
		)
		(duplicate_pad_numbers_are_jumpers no)
		(fp_rect
			(start -0.3048 -0.1016)
			(end 0.3048 0.9906)
			(stroke
				(width 0)
				(type default)
			)
			(fill no)
			(layer "F.CrtYd")
		)
		(fp_line
			(start 0.3048 -0.1016)
			(end -0.3048 -0.1016)
			(stroke
				(width 0.1)
				(type default)
			)
			(layer "F.Fab")
		)
		(fp_line
			(start -0.3048 -0.1016)
			(end -0.3048 0.9906)
			(stroke
				(width 0.1)
				(type default)
			)
			(layer "F.Fab")
		)
		(fp_line
			(start 0.3048 0.9906)
			(end 0.3048 -0.1016)
			(stroke
				(width 0.1)
				(type default)
			)
			(layer "F.Fab")
		)
		(fp_line
			(start -0.3048 0.9906)
			(end 0.3048 0.9906)
			(stroke
				(width 0.1)
				(type default)
			)
			(layer "F.Fab")
		)
		(pad "1" smd rect
			(at 0 0 90)
			(size 0.508 0.508)
			(layers "F.Cu" "F.Mask" "F.Paste")
			(net "P3E_CPU1_PE3_MP_C_TXN<1>")
		)
		(pad "2" smd rect
			(at 0 0.889 90)
			(size 0.508 0.508)
			(layers "F.Cu" "F.Mask" "F.Paste")
			(net "P3E_CPU1_PE3_MP_TXN<1>")
		)
		(zone
			(layer "F.Cu")
			(hatch none 0.5)
			(connect_pads
				(clearance 0)
			)
			(min_thickness 0.25)
			(keepout
				(tracks not_allowed)
				(vias allowed)
				(pads allowed)
				(copperpour not_allowed)
				(footprints allowed)
			)
			(placement
				(enabled no)
				(sheetname "")
			)
			(fill
				(thermal_gap 0.5)
				(thermal_bridge_width 0.5)
				(island_removal_mode 0)
			)
			(polygon
				(pts
					(xy 14.1478 -25.654) (xy 14.5288 -25.654) (xy 14.5288 -26.162) (xy 14.1478 -26.162)
				)
			)
		)
		(zone
			(layer "F.Cu")
			(hatch none 0.5)
			(connect_pads
				(clearance 0)
			)
			(min_thickness 0.25)
			(keepout
				(tracks allowed)
				(vias not_allowed)
				(pads allowed)
				(copperpour not_allowed)
				(footprints allowed)
			)
			(placement
				(enabled no)
				(sheetname "")
			)
			(fill
				(thermal_gap 0.5)
				(thermal_bridge_width 0.5)
				(island_removal_mode 0)
			)
			(polygon
				(pts
					(xy 14.1478 -25.654) (xy 14.5288 -25.654) (xy 14.5288 -26.162) (xy 14.1478 -26.162)
				)
			)
		)
	)
	(footprint ""
		(layer "F.Cu")
		(at 339.9282 -128.3335)
		(property "Reference" "C7B11"
			(at 0 0 0)
			(layer "F.SilkS")
			(hide yes)
			(effects
				(font
					(size 1.27 1.27)
				)
			)
		)
		(property "Value" ""
			(at 0 0 0)
			(layer "F.Fab")
			(effects
				(font
					(size 1.27 1.27)
				)
			)
		)
		(duplicate_pad_numbers_are_jumpers no)
		(fp_poly
			(pts
				(xy 0.3048 -0.1016) (xy 0.3048 0.9906) (xy -0.3048 0.9906) (xy -0.3048 -0.1016)
			)
			(stroke
				(width 0)
				(type default)
			)
			(fill no)
			(layer "F.CrtYd")
		)
		(fp_line
			(start -0.3048 -0.1016)
			(end -0.3048 0.9906)
			(stroke
				(width 0.1)
				(type default)
			)
			(layer "F.Fab")
		)
		(fp_line
			(start -0.3048 0.9906)
			(end 0.3048 0.9906)
			(stroke
				(width 0.1)
				(type default)
			)
			(layer "F.Fab")
		)
		(fp_line
			(start 0.3048 -0.1016)
			(end -0.3048 -0.1016)
			(stroke
				(width 0.1)
				(type default)
			)
			(layer "F.Fab")
		)
		(fp_line
			(start 0.3048 0.9906)
			(end 0.3048 -0.1016)
			(stroke
				(width 0.1)
				(type default)
			)
			(layer "F.Fab")
		)
		(pad "1" smd rect
			(at 0 0)
			(size 0.508 0.508)
			(layers "F.Cu" "F.Mask" "F.Paste")
			(net "VR_PVPP_DEF_SS")
		)
		(pad "2" smd rect
			(at 0 0.889)
			(size 0.508 0.508)
			(layers "F.Cu" "F.Mask" "F.Paste")
			(net "AGND_PVPP_DEF")
		)
		(zone
			(layer "F.Cu")
			(hatch none 0.5)
			(connect_pads
				(clearance 0)
			)
			(min_thickness 0.25)
			(keepout
				(tracks allowed)
				(vias not_allowed)
				(pads allowed)
				(copperpour not_allowed)
				(footprints allowed)
			)
			(placement
				(enabled no)
				(sheetname "")
			)
			(fill
				(thermal_gap 0.5)
				(thermal_bridge_width 0.5)
				(island_removal_mode 0)
			)
			(polygon
				(pts
					(xy 339.6742 -128.0795) (xy 340.1822 -128.0795) (xy 340.1822 -127.6985) (xy 339.6742 -127.6985)
				)
			)
		)
		(zone
			(layer "F.Cu")
			(hatch none 0.5)
			(connect_pads
				(clearance 0)
			)
			(min_thickness 0.25)
			(keepout
				(tracks not_allowed)
				(vias allowed)
				(pads allowed)
				(copperpour not_allowed)
				(footprints allowed)
			)
			(placement
				(enabled no)
				(sheetname "")
			)
			(fill
				(thermal_gap 0.5)
				(thermal_bridge_width 0.5)
				(island_removal_mode 0)
			)
			(polygon
				(pts
					(xy 339.6742 -127.6985) (xy 340.1822 -127.6985) (xy 340.1822 -128.0795) (xy 339.6742 -128.0795)
				)
			)
		)
	)
	(footprint ""
		(layer "F.Cu")
		(at 349.1738 -157.2768 90)
		(property "Reference" "C7A16"
			(at 0 0 90)
			(layer "F.SilkS")
			(hide yes)
			(effects
				(font
					(size 1.27 1.27)
				)
			)
		)
		(property "Value" ""
			(at 0 0 90)
			(layer "F.Fab")
			(effects
				(font
					(size 1.27 1.27)
				)
			)
		)
		(duplicate_pad_numbers_are_jumpers no)
		(fp_poly
			(pts
				(xy 0.3048 -0.1016) (xy 0.3048 0.9906) (xy -0.3048 0.9906) (xy -0.3048 -0.1016)
			)
			(stroke
				(width 0)
				(type default)
			)
			(fill no)
			(layer "F.CrtYd")
		)
		(fp_line
			(start 0.3048 -0.1016)
			(end -0.3048 -0.1016)
			(stroke
				(width 0.1)
				(type default)
			)
			(layer "F.Fab")
		)
		(fp_line
			(start -0.3048 -0.1016)
			(end -0.3048 0.9906)
			(stroke
				(width 0.1)
				(type default)
			)
			(layer "F.Fab")
		)
		(fp_line
			(start 0.3048 0.9906)
			(end 0.3048 -0.1016)
			(stroke
				(width 0.1)
				(type default)
			)
			(layer "F.Fab")
		)
		(fp_line
			(start -0.3048 0.9906)
			(end 0.3048 0.9906)
			(stroke
				(width 0.1)
				(type default)
			)
			(layer "F.Fab")
		)
		(pad "1" smd rect
			(at 0 0 90)
			(size 0.508 0.508)
			(layers "F.Cu" "F.Mask" "F.Paste")
			(net "VR_PVDDQ_DEF_PH1_VCIN")
		)
		(pad "2" smd rect
			(at 0 0.889 90)
			(size 0.508 0.508)
			(layers "F.Cu" "F.Mask" "F.Paste")
			(net "GND")
		)
		(zone
			(layer "F.Cu")
			(hatch none 0.5)
			(connect_pads
				(clearance 0)
			)
			(min_thickness 0.25)
			(keepout
				(tracks allowed)
				(vias not_allowed)
				(pads allowed)
				(copperpour not_allowed)
				(footprints allowed)
			)
			(placement
				(enabled no)
				(sheetname "")
			)
			(fill
				(thermal_gap 0.5)
				(thermal_bridge_width 0.5)
				(island_removal_mode 0)
			)
			(polygon
				(pts
					(xy 349.4278 -157.0228) (xy 349.4278 -157.5308) (xy 349.8088 -157.5308) (xy 349.8088 -157.0228)
				)
			)
		)
		(zone
			(layer "F.Cu")
			(hatch none 0.5)
			(connect_pads
				(clearance 0)
			)
			(min_thickness 0.25)
			(keepout
				(tracks not_allowed)
				(vias allowed)
				(pads allowed)
				(copperpour not_allowed)
				(footprints allowed)
			)
			(placement
				(enabled no)
				(sheetname "")
			)
			(fill
				(thermal_gap 0.5)
				(thermal_bridge_width 0.5)
				(island_removal_mode 0)
			)
			(polygon
				(pts
					(xy 349.8088 -157.0228) (xy 349.8088 -157.5308) (xy 349.4278 -157.5308) (xy 349.4278 -157.0228)
				)
			)
		)
	)
	(footprint ""
		(layer "F.Cu")
		(at 388.502906 -164.916612 90)
		(property "Reference" "T1D20"
			(at 0 0 90)
			(layer "F.SilkS")
			(hide yes)
			(effects
				(font
					(size 1.27 1.27)
				)
			)
		)
		(property "Value" "*"
			(at -3.4036 -4.46405 90)
			(unlocked yes)
			(layer "F.Fab")
			(hide yes)
			(effects
				(font
					(size 0.889 0.889)
					(thickness 0.1524)
				)
			)
		)
		(property "Device Type" "TEST-PAD-12P-1-GP-U_DISCRET-GBA"
			(at -3.4036 -5.98805 90)
			(unlocked yes)
			(layer "F.Fab")
			(hide yes)
			(effects
				(font
					(size 0.889 0.889)
					(thickness 0.1524)
				)
			)
		)
		(duplicate_pad_numbers_are_jumpers no)
		(fp_line
			(start 2.3622 -4.826)
			(end 2.3622 3.4798)
			(stroke
				(width 0.1524)
				(type default)
			)
			(layer "F.SilkS")
		)
		(fp_line
			(start -2.3876 -4.826)
			(end 2.3622 -4.826)
			(stroke
				(width 0.1524)
				(type default)
			)
			(layer "F.SilkS")
		)
		(fp_line
			(start 2.3622 3.4798)
			(end -2.3876 3.4798)
			(stroke
				(width 0.1524)
				(type default)
			)
			(layer "F.SilkS")
		)
		(fp_line
			(start -2.3876 3.4798)
			(end -2.3876 -4.826)
			(stroke
				(width 0.1524)
				(type default)
			)
			(layer "F.SilkS")
		)
		(fp_rect
			(start -2.6416 3.7338)
			(end 2.6162 -5.08)
			(stroke
				(width 0)
				(type default)
			)
			(fill no)
			(layer "F.CrtYd")
		)
		(fp_rect
			(start -2.6416 3.7338)
			(end 2.6162 -5.08)
			(stroke
				(width 0)
				(type default)
			)
			(fill no)
			(layer "F.Fab")
		)
		(pad "1" smd circle
			(at 0.496824 -1.301496 90)
			(size 0.6604 0.6604)
			(layers "F.Cu" "F.Mask" "F.Paste")
			(net "L10_85OHM_10INCH_DN")
		)
		(pad "2" smd circle
			(at -0.503936 -1.301496 90)
			(size 0.6604 0.6604)
			(layers "F.Cu" "F.Mask" "F.Paste")
			(net "L10_85OHM_10INCH_DP")
		)
		(pad "3" smd custom
			(at -0.00889 0.370078 90)
			(size 0.74295 0.74295)
			(layers "F.Cu" "F.Mask" "F.Paste")
			(net "GND")
			(options
				(clearance outline)
				(anchor circle)
			)
			(primitives
				(gr_poly
					(pts
						(xy -2.1209 1.4859) (xy 2.1209 1.4859) (xy 2.1209 -1.4859) (xy 1.08585 -1.4859) (xy 1.08585 -0.4699)
						(xy -1.08585 -0.4699) (xy -1.08585 -1.4859) (xy -2.1209 -1.4859)
					)
					(width 0)
					(fill yes)
				)
			)
		)
		(pad "4" thru_hole circle
			(at 1.266444 -3.851656 90)
			(size 1.4478 1.4478)
			(drill 1.0414)
			(layers "*.Cu" "*.Mask")
			(remove_unused_layers no)
			(net "GND")
			(clearance 0.1524)
			(thermal_gap 0.1524)
		)
		(pad "5" thru_hole circle
			(at -1.273556 -3.851656 90)
			(size 1.4478 1.4478)
			(drill 1.0414)
			(layers "*.Cu" "*.Mask")
			(remove_unused_layers no)
			(net "GND")
			(clearance 0.1524)
			(thermal_gap 0.1524)
		)
		(pad "6" thru_hole circle
			(at 1.266444 2.498344 90)
			(size 1.4478 1.4478)
			(drill 1.0414)
			(layers "*.Cu" "*.Mask")
			(remove_unused_layers no)
			(net "GND")
			(clearance 0.1524)
			(thermal_gap 0.1524)
		)
		(pad "7" thru_hole circle
			(at -1.273556 2.498344 90)
			(size 1.4478 1.4478)
			(drill 1.0414)
			(layers "*.Cu" "*.Mask")
			(remove_unused_layers no)
			(net "GND")
			(clearance 0.1524)
			(thermal_gap 0.1524)
		)
		(pad "8" thru_hole circle
			(at 1.27 -0.4572 90)
			(size 0.7112 0.7112)
			(drill 0.4064)
			(layers "*.Cu" "*.Mask")
			(remove_unused_layers no)
			(net "GND")
			(clearance 0.1016)
			(thermal_gap 0.1016)
		)
		(pad "9" thru_hole circle
			(at 1.27 0.762 90)
			(size 0.7112 0.7112)
			(drill 0.4064)
			(layers "*.Cu" "*.Mask")
			(remove_unused_layers no)
			(net "GND")
			(clearance 0.1016)
			(thermal_gap 0.1016)
		)
		(pad "10" thru_hole circle
			(at -0.0254 0.762 90)
			(size 0.7112 0.7112)
			(drill 0.4064)
			(layers "*.Cu" "*.Mask")
			(remove_unused_layers no)
			(net "GND")
			(clearance 0.1016)
			(thermal_gap 0.1016)
		)
		(pad "11" thru_hole circle
			(at -1.27 0.762 90)
			(size 0.7112 0.7112)
			(drill 0.4064)
			(layers "*.Cu" "*.Mask")
			(remove_unused_layers no)
			(net "GND")
			(clearance 0.1016)
			(thermal_gap 0.1016)
		)
		(pad "12" thru_hole circle
			(at -1.27 -0.4572 90)
			(size 0.7112 0.7112)
			(drill 0.4064)
			(layers "*.Cu" "*.Mask")
			(remove_unused_layers no)
			(net "GND")
			(clearance 0.1016)
			(thermal_gap 0.1016)
		)
	)
	(footprint ""
		(layer "F.Cu")
		(at 153.5176 -130.3528 -90)
		(property "Reference" "C3B1"
			(at 0 0 270)
			(layer "F.SilkS")
			(hide yes)
			(effects
				(font
					(size 1.27 1.27)
				)
			)
		)
		(property "Value" ""
			(at 0 0 270)
			(layer "F.Fab")
			(effects
				(font
					(size 1.27 1.27)
				)
			)
		)
		(duplicate_pad_numbers_are_jumpers no)
		(fp_rect
			(start -0.4953 1.6002)
			(end 0.4953 -0.2032)
			(stroke
				(width 0)
				(type default)
			)
			(fill no)
			(layer "F.CrtYd")
		)
		(fp_line
			(start -0.4953 1.6002)
			(end -0.4953 -0.2032)
			(stroke
				(width 0.1)
				(type default)
			)
			(layer "F.Fab")
		)
		(fp_line
			(start 0.4953 1.6002)
			(end -0.4953 1.6002)
			(stroke
				(width 0.1)
				(type default)
			)
			(layer "F.Fab")
		)
		(fp_line
			(start -0.4953 -0.2032)
			(end 0.4953 -0.2032)
			(stroke
				(width 0.1)
				(type default)
			)
			(layer "F.Fab")
		)
		(fp_line
			(start 0.4953 -0.2032)
			(end 0.4953 1.6002)
			(stroke
				(width 0.1)
				(type default)
			)
			(layer "F.Fab")
		)
		(pad "1" smd rect
			(at 0 0 270)
			(size 0.762 0.889)
			(layers "F.Cu" "F.Mask" "F.Paste")
			(net "PVPP_KLM")
		)
		(pad "2" smd rect
			(at 0 1.397 270)
			(size 0.762 0.889)
			(layers "F.Cu" "F.Mask" "F.Paste")
			(net "GND")
		)
		(zone
			(layer "F.Cu")
			(hatch none 0.5)
			(connect_pads
				(clearance 0)
			)
			(min_thickness 0.25)
			(keepout
				(tracks not_allowed)
				(vias allowed)
				(pads allowed)
				(copperpour not_allowed)
				(footprints allowed)
			)
			(placement
				(enabled no)
				(sheetname "")
			)
			(fill
				(thermal_gap 0.5)
				(thermal_bridge_width 0.5)
				(island_removal_mode 0)
			)
			(polygon
				(pts
					(xy 152.5651 -130.7338) (xy 152.5651 -129.9718) (xy 153.0731 -129.9718) (xy 153.0731 -130.7338)
				)
			)
		)
	)
	(footprint ""
		(layer "F.Cu")
		(at 193.9036 -75.1332 90)
		(property "Reference" "C4D28"
			(at 0 0 90)
			(layer "F.SilkS")
			(hide yes)
			(effects
				(font
					(size 1.27 1.27)
				)
			)
		)
		(property "Value" ""
			(at 0 0 90)
			(layer "F.Fab")
			(effects
				(font
					(size 1.27 1.27)
				)
			)
		)
		(duplicate_pad_numbers_are_jumpers no)
		(fp_rect
			(start -0.3048 0.9906)
			(end 0.3048 -0.1016)
			(stroke
				(width 0)
				(type default)
			)
			(fill no)
			(layer "F.CrtYd")
		)
		(fp_line
			(start 0.3048 -0.1016)
			(end -0.3048 -0.1016)
			(stroke
				(width 0.1)
				(type default)
			)
			(layer "F.Fab")
		)
		(fp_line
			(start -0.3048 -0.1016)
			(end -0.3048 0.9906)
			(stroke
				(width 0.1)
				(type default)
			)
			(layer "F.Fab")
		)
		(fp_line
			(start 0.3048 0.9906)
			(end 0.3048 -0.1016)
			(stroke
				(width 0.1)
				(type default)
			)
			(layer "F.Fab")
		)
		(fp_line
			(start -0.3048 0.9906)
			(end 0.3048 0.9906)
			(stroke
				(width 0.1)
				(type default)
			)
			(layer "F.Fab")
		)
		(pad "1" smd rect
			(at 0 0 90)
			(size 0.508 0.508)
			(layers "F.Cu" "F.Mask" "F.Paste")
			(net "VR_PVCCIN_CPU0_PH3_BOOT")
		)
		(pad "2" smd rect
			(at 0 0.889 90)
			(size 0.508 0.508)
			(layers "F.Cu" "F.Mask" "F.Paste")
			(net "VR_PVCCIN_CPU0_PH3_PHASE")
		)
		(zone
			(layer "F.Cu")
			(hatch none 0.5)
			(connect_pads
				(clearance 0)
			)
			(min_thickness 0.25)
			(keepout
				(tracks allowed)
				(vias not_allowed)
				(pads allowed)
				(copperpour not_allowed)
				(footprints allowed)
			)
			(placement
				(enabled no)
				(sheetname "")
			)
			(fill
				(thermal_gap 0.5)
				(thermal_bridge_width 0.5)
				(island_removal_mode 0)
			)
			(polygon
				(pts
					(xy 194.5386 -74.8792) (xy 194.5386 -75.3872) (xy 194.1576 -75.3872) (xy 194.1576 -74.8792)
				)
			)
		)
		(zone
			(layer "F.Cu")
			(hatch none 0.5)
			(connect_pads
				(clearance 0)
			)
			(min_thickness 0.25)
			(keepout
				(tracks not_allowed)
				(vias allowed)
				(pads allowed)
				(copperpour not_allowed)
				(footprints allowed)
			)
			(placement
				(enabled no)
				(sheetname "")
			)
			(fill
				(thermal_gap 0.5)
				(thermal_bridge_width 0.5)
				(island_removal_mode 0)
			)
			(polygon
				(pts
					(xy 194.5386 -74.8792) (xy 194.5386 -75.3872) (xy 194.1576 -75.3872) (xy 194.1576 -74.8792)
				)
			)
		)
	)
	(footprint ""
		(layer "F.Cu")
		(at 163.449 -47.879 90)
		(property "Reference" "C4E29"
			(at 2.92862 3.24612 0)
			(unlocked yes)
			(layer "F.SilkS")
			(effects
				(font
					(size 0.4064 0.254)
					(thickness 0.1524)
				)
			)
		)
		(property "Value" ""
			(at 0 0 90)
			(layer "F.Fab")
			(effects
				(font
					(size 1.27 1.27)
				)
			)
		)
		(duplicate_pad_numbers_are_jumpers no)
		(fp_line
			(start 2.504948 -1.616456)
			(end 2.504948 1.633728)
			(stroke
				(width 0.1524)
				(type default)
			)
			(layer "F.SilkS")
		)
		(fp_line
			(start 1.6002 -1.616456)
			(end 2.504948 -1.616456)
			(stroke
				(width 0.1524)
				(type default)
			)
			(layer "F.SilkS")
		)
		(fp_line
			(start -1.6002 -1.616456)
			(end -2.563114 -1.616456)
			(stroke
				(width 0.1524)
				(type default)
			)
			(layer "F.SilkS")
		)
		(fp_line
			(start -2.563114 -1.616456)
			(end -2.563114 1.633728)
			(stroke
				(width 0.1524)
				(type default)
			)
			(layer "F.SilkS")
		)
		(fp_line
			(start 2.504948 1.633728)
			(end 1.6002 1.633728)
			(stroke
				(width 0.1524)
				(type default)
			)
			(layer "F.SilkS")
		)
		(fp_line
			(start -2.563114 1.633728)
			(end -1.6002 1.633728)
			(stroke
				(width 0.1524)
				(type default)
			)
			(layer "F.SilkS")
		)
		(fp_line
			(start 2.286 7.366)
			(end 2.286 1.63195)
			(stroke
				(width 0.1524)
				(type default)
			)
			(layer "F.SilkS")
		)
		(fp_line
			(start 2.286 7.366)
			(end 1.600708 7.366)
			(stroke
				(width 0.1524)
				(type default)
			)
			(layer "F.SilkS")
		)
		(fp_line
			(start -2.286 7.366)
			(end -2.286 1.632712)
			(stroke
				(width 0.1524)
				(type default)
			)
			(layer "F.SilkS")
		)
		(fp_line
			(start -2.286 7.366)
			(end -1.60147 7.366)
			(stroke
				(width 0.1524)
				(type default)
			)
			(layer "F.SilkS")
		)
		(fp_rect
			(start -2.286 7.366)
			(end 2.286 -0.254)
			(stroke
				(width 0)
				(type default)
			)
			(fill no)
			(layer "F.CrtYd")
		)
		(fp_line
			(start 2.286 -0.254)
			(end 2.286 7.366)
			(stroke
				(width 0.1)
				(type default)
			)
			(layer "F.Fab")
		)
		(fp_line
			(start -2.286 -0.254)
			(end 2.286 -0.254)
			(stroke
				(width 0.1)
				(type default)
			)
			(layer "F.Fab")
		)
		(fp_line
			(start 2.286 7.366)
			(end -2.286 7.366)
			(stroke
				(width 0.1)
				(type default)
			)
			(layer "F.Fab")
		)
		(fp_line
			(start -2.286 7.366)
			(end -2.286 -0.254)
			(stroke
				(width 0.1)
				(type default)
			)
			(layer "F.Fab")
		)
		(pad "1" smd rect
			(at 0 0 90)
			(size 2.54 3.048)
			(layers "F.Cu" "F.Mask" "F.Paste")
			(net "PVCCMCP_CPU1")
		)
		(pad "2" smd rect
			(at 0 7.112 90)
			(size 2.54 3.048)
			(layers "F.Cu" "F.Mask" "F.Paste")
			(net "GND")
		)
	)
	(footprint ""
		(layer "F.Cu")
		(at 405.257 -23.0505)
		(property "Reference" "R25W89"
			(at -0.8382 -0.67818 0)
			(unlocked yes)
			(layer "F.SilkS")
			(effects
				(font
					(size 0.4064 0.254)
					(thickness 0.1524)
				)
				(justify left)
			)
		)
		(property "Value" ""
			(at 0 0 0)
			(layer "F.Fab")
			(effects
				(font
					(size 1.27 1.27)
				)
			)
		)
		(duplicate_pad_numbers_are_jumpers no)
		(fp_poly
			(pts
				(xy -0.2794 -0.1016) (xy 0.2794 -0.1016) (xy 0.2794 0.9906) (xy -0.2794 0.9906)
			)
			(stroke
				(width 0)
				(type default)
			)
			(fill no)
			(layer "F.CrtYd")
		)
		(fp_line
			(start -0.2794 -0.1016)
			(end -0.2794 0.9906)
			(stroke
				(width 0.1)
				(type default)
			)
			(layer "F.Fab")
		)
		(fp_line
			(start -0.2794 0.9906)
			(end 0.2794 0.9906)
			(stroke
				(width 0.1)
				(type default)
			)
			(layer "F.Fab")
		)
		(fp_line
			(start 0.2794 -0.1016)
			(end -0.2794 -0.1016)
			(stroke
				(width 0.1)
				(type default)
			)
			(layer "F.Fab")
		)
		(fp_line
			(start 0.2794 0.9906)
			(end 0.2794 -0.1016)
			(stroke
				(width 0.1)
				(type default)
			)
			(layer "F.Fab")
		)
		(pad "1" smd rect
			(at 0 0)
			(size 0.508 0.508)
			(layers "F.Cu" "F.Mask" "F.Paste")
			(net "RMII_BMC_PCH_SPRNGVLLE_TXD0_R")
		)
		(pad "2" smd rect
			(at 0 0.889)
			(size 0.508 0.508)
			(layers "F.Cu" "F.Mask" "F.Paste")
			(net "RMII_BMC_PCH_SPRNGVLLE_TXD0")
		)
		(zone
			(layer "F.Cu")
			(hatch none 0.5)
			(connect_pads
				(clearance 0)
			)
			(min_thickness 0.25)
			(keepout
				(tracks allowed)
				(vias not_allowed)
				(pads allowed)
				(copperpour not_allowed)
				(footprints allowed)
			)
			(placement
				(enabled no)
				(sheetname "")
			)
			(fill
				(thermal_gap 0.5)
				(thermal_bridge_width 0.5)
				(island_removal_mode 0)
			)
			(polygon
				(pts
					(xy 405.003 -22.7965) (xy 405.511 -22.7965) (xy 405.511 -22.4155) (xy 405.003 -22.4155)
				)
			)
		)
		(zone
			(layer "F.Cu")
			(hatch none 0.5)
			(connect_pads
				(clearance 0)
			)
			(min_thickness 0.25)
			(keepout
				(tracks not_allowed)
				(vias allowed)
				(pads allowed)
				(copperpour not_allowed)
				(footprints allowed)
			)
			(placement
				(enabled no)
				(sheetname "")
			)
			(fill
				(thermal_gap 0.5)
				(thermal_bridge_width 0.5)
				(island_removal_mode 0)
			)
			(polygon
				(pts
					(xy 405.003 -22.4155) (xy 405.511 -22.4155) (xy 405.511 -22.7965) (xy 405.003 -22.7965)
				)
			)
		)
	)
	(footprint ""
		(layer "F.Cu")
		(at 406.9461 -64.135 90)
		(property "Reference" "R8E4"
			(at 0 0 90)
			(layer "F.SilkS")
			(hide yes)
			(effects
				(font
					(size 1.27 1.27)
				)
			)
		)
		(property "Value" ""
			(at 0 0 90)
			(layer "F.Fab")
			(effects
				(font
					(size 1.27 1.27)
				)
			)
		)
		(duplicate_pad_numbers_are_jumpers no)
		(fp_poly
			(pts
				(xy -0.2794 -0.1016) (xy 0.2794 -0.1016) (xy 0.2794 0.9906) (xy -0.2794 0.9906)
			)
			(stroke
				(width 0)
				(type default)
			)
			(fill no)
			(layer "F.CrtYd")
		)
		(pad "1" smd rect
			(at 0 0 90)
			(size 0.508 0.508)
			(layers "F.Cu" "F.Mask" "F.Paste")
			(net "SPI_PCH_MOSI")
		)
		(pad "2" smd rect
			(at 0 0.889 90)
			(size 0.508 0.508)
			(layers "F.Cu" "F.Mask" "F.Paste")
			(net "GND")
		)
		(zone
			(layer "F.Cu")
			(hatch none 0.5)
			(connect_pads
				(clearance 0)
			)
			(min_thickness 0.25)
			(keepout
				(tracks allowed)
				(vias not_allowed)
				(pads allowed)
				(copperpour not_allowed)
				(footprints allowed)
			)
			(placement
				(enabled no)
				(sheetname "")
			)
			(fill
				(thermal_gap 0.5)
				(thermal_bridge_width 0.5)
				(island_removal_mode 0)
			)
			(polygon
				(pts
					(xy 407.2001 -63.881) (xy 407.2001 -64.389) (xy 407.5811 -64.389) (xy 407.5811 -63.881)
				)
			)
		)
		(zone
			(layer "F.Cu")
			(hatch none 0.5)
			(connect_pads
				(clearance 0)
			)
			(min_thickness 0.25)
			(keepout
				(tracks not_allowed)
				(vias allowed)
				(pads allowed)
				(copperpour not_allowed)
				(footprints allowed)
			)
			(placement
				(enabled no)
				(sheetname "")
			)
			(fill
				(thermal_gap 0.5)
				(thermal_bridge_width 0.5)
				(island_removal_mode 0)
			)
			(polygon
				(pts
					(xy 407.5811 -63.881) (xy 407.5811 -64.389) (xy 407.2001 -64.389) (xy 407.2001 -63.881)
				)
			)
		)
	)
	(footprint ""
		(layer "F.Cu")
		(at 442.89472 -129.58318)
		(property "Reference" "F8B1"
			(at 0 0 0)
			(layer "F.SilkS")
			(hide yes)
			(effects
				(font
					(size 1.27 1.27)
				)
			)
		)
		(property "Value" "*"
			(at -0.02032 -4.5212 0)
			(unlocked yes)
			(layer "F.Fab")
			(hide yes)
			(effects
				(font
					(size 1.27 1.016)
					(thickness 0.1524)
				)
			)
		)
		(property "Device Type" "FUSE-3A75V-GP_DISCRET-G5-FUSE-A"
			(at -0.02032 -6.0452 0)
			(unlocked yes)
			(layer "F.Fab")
			(hide yes)
			(effects
				(font
					(size 1.27 1.016)
					(thickness 0.1524)
				)
			)
		)
		(duplicate_pad_numbers_are_jumpers no)
		(fp_line
			(start -1.1684 -2.2225)
			(end -1.1684 2.2225)
			(stroke
				(width 0.1524)
				(type default)
			)
			(layer "F.SilkS")
		)
		(fp_line
			(start -1.1684 2.2225)
			(end 1.1684 2.2225)
			(stroke
				(width 0.1524)
				(type default)
			)
			(layer "F.SilkS")
		)
		(fp_line
			(start 1.1684 -2.2225)
			(end -1.1684 -2.2225)
			(stroke
				(width 0.1524)
				(type default)
			)
			(layer "F.SilkS")
		)
		(fp_line
			(start 1.1684 2.2225)
			(end 1.1684 -2.2225)
			(stroke
				(width 0.1524)
				(type default)
			)
			(layer "F.SilkS")
		)
		(fp_rect
			(start -0.7874 1.5875)
			(end 0.7874 -1.5875)
			(stroke
				(width 0)
				(type default)
			)
			(fill no)
			(layer "F.CrtYd")
		)
		(fp_poly
			(pts
				(xy -1.4224 2.2987) (xy -1.4224 -2.2987) (xy 1.4224 -2.2987) (xy 1.4224 -0.25146) (xy 0.7874 -0.25146)
				(xy 0.7874 -1.5875) (xy -0.7874 -1.5875) (xy -0.7874 1.5875) (xy 0.7874 1.5875) (xy 0.7874 -0.24892)
				(xy 1.4224 -0.24892) (xy 1.4224 2.2987)
			)
			(stroke
				(width 0)
				(type default)
			)
			(fill no)
			(layer "F.CrtYd")
		)
		(fp_rect
			(start -1.4224 2.2987)
			(end 1.4224 -2.2987)
			(stroke
				(width 0)
				(type default)
			)
			(fill no)
			(layer "F.Fab")
		)
		(pad "1" smd rect
			(at 0 -1.2446)
			(size 1.8288 1.4478)
			(layers "F.Cu" "F.Mask" "F.Paste")
			(net "P5V_HDD_SATA")
		)
		(pad "2" smd rect
			(at 0 1.2446)
			(size 1.8288 1.4478)
			(layers "F.Cu" "F.Mask" "F.Paste")
			(net "P5V")
		)
	)
	(footprint ""
		(layer "F.Cu")
		(at 14.732 -90.0684 -90)
		(property "Reference" "C1C23"
			(at 0 0 270)
			(layer "F.SilkS")
			(hide yes)
			(effects
				(font
					(size 1.27 1.27)
				)
			)
		)
		(property "Value" ""
			(at 0 0 270)
			(layer "F.Fab")
			(effects
				(font
					(size 1.27 1.27)
				)
			)
		)
		(duplicate_pad_numbers_are_jumpers no)
		(fp_rect
			(start 0.3048 0.9906)
			(end -0.3048 -0.1016)
			(stroke
				(width 0)
				(type default)
			)
			(fill no)
			(layer "F.CrtYd")
		)
		(fp_line
			(start -0.3048 0.9906)
			(end 0.3048 0.9906)
			(stroke
				(width 0.1)
				(type default)
			)
			(layer "F.Fab")
		)
		(fp_line
			(start 0.3048 0.9906)
			(end 0.3048 -0.1016)
			(stroke
				(width 0.1)
				(type default)
			)
			(layer "F.Fab")
		)
		(fp_line
			(start -0.3048 -0.1016)
			(end -0.3048 0.9906)
			(stroke
				(width 0.1)
				(type default)
			)
			(layer "F.Fab")
		)
		(fp_line
			(start 0.3048 -0.1016)
			(end -0.3048 -0.1016)
			(stroke
				(width 0.1)
				(type default)
			)
			(layer "F.Fab")
		)
		(pad "1" smd rect
			(at 0 0 270)
			(size 0.508 0.508)
			(layers "F.Cu" "F.Mask" "F.Paste")
			(net "VR_VRRDY_PVCCIN_CPU1")
		)
		(pad "2" smd rect
			(at 0 0.889 270)
			(size 0.508 0.508)
			(layers "F.Cu" "F.Mask" "F.Paste")
			(net "GND")
		)
		(zone
			(layer "F.Cu")
			(hatch none 0.5)
			(connect_pads
				(clearance 0)
			)
			(min_thickness 0.25)
			(keepout
				(tracks not_allowed)
				(vias allowed)
				(pads allowed)
				(copperpour not_allowed)
				(footprints allowed)
			)
			(placement
				(enabled no)
				(sheetname "")
			)
			(fill
				(thermal_gap 0.5)
				(thermal_bridge_width 0.5)
				(island_removal_mode 0)
			)
			(polygon
				(pts
					(xy 14.097 -89.8144) (xy 14.478 -89.8144) (xy 14.478 -90.3224) (xy 14.097 -90.3224)
				)
			)
		)
		(zone
			(layer "F.Cu")
			(hatch none 0.5)
			(connect_pads
				(clearance 0)
			)
			(min_thickness 0.25)
			(keepout
				(tracks allowed)
				(vias not_allowed)
				(pads allowed)
				(copperpour not_allowed)
				(footprints allowed)
			)
			(placement
				(enabled no)
				(sheetname "")
			)
			(fill
				(thermal_gap 0.5)
				(thermal_bridge_width 0.5)
				(island_removal_mode 0)
			)
			(polygon
				(pts
					(xy 14.097 -89.8144) (xy 14.478 -89.8144) (xy 14.478 -90.3224) (xy 14.097 -90.3224)
				)
			)
		)
	)
	(footprint ""
		(layer "F.Cu")
		(at 185.4454 -146.6723)
		(property "Reference" "R4A6"
			(at 0 0 0)
			(layer "F.SilkS")
			(hide yes)
			(effects
				(font
					(size 1.27 1.27)
				)
			)
		)
		(property "Value" ""
			(at 0 0 0)
			(layer "F.Fab")
			(effects
				(font
					(size 1.27 1.27)
				)
			)
		)
		(duplicate_pad_numbers_are_jumpers no)
		(fp_poly
			(pts
				(xy -0.2794 -0.1016) (xy 0.2794 -0.1016) (xy 0.2794 0.9906) (xy -0.2794 0.9906)
			)
			(stroke
				(width 0)
				(type default)
			)
			(fill no)
			(layer "F.CrtYd")
		)
		(fp_line
			(start -0.2794 -0.1016)
			(end -0.2794 0.9906)
			(stroke
				(width 0.1)
				(type default)
			)
			(layer "F.Fab")
		)
		(fp_line
			(start -0.2794 0.9906)
			(end 0.2794 0.9906)
			(stroke
				(width 0.1)
				(type default)
			)
			(layer "F.Fab")
		)
		(fp_line
			(start 0.2794 -0.1016)
			(end -0.2794 -0.1016)
			(stroke
				(width 0.1)
				(type default)
			)
			(layer "F.Fab")
		)
		(fp_line
			(start 0.2794 0.9906)
			(end 0.2794 -0.1016)
			(stroke
				(width 0.1)
				(type default)
			)
			(layer "F.Fab")
		)
		(pad "1" smd rect
			(at 0 0)
			(size 0.508 0.508)
			(layers "F.Cu" "F.Mask" "F.Paste")
			(net "PWRGD_PVTT_DEF_CPU0_R")
		)
		(pad "2" smd rect
			(at 0 0.889)
			(size 0.508 0.508)
			(layers "F.Cu" "F.Mask" "F.Paste")
			(net "PWRGD_PVTT_CPU0")
		)
		(zone
			(layer "F.Cu")
			(hatch none 0.5)
			(connect_pads
				(clearance 0)
			)
			(min_thickness 0.25)
			(keepout
				(tracks allowed)
				(vias not_allowed)
				(pads allowed)
				(copperpour not_allowed)
				(footprints allowed)
			)
			(placement
				(enabled no)
				(sheetname "")
			)
			(fill
				(thermal_gap 0.5)
				(thermal_bridge_width 0.5)
				(island_removal_mode 0)
			)
			(polygon
				(pts
					(xy 185.1914 -146.4183) (xy 185.6994 -146.4183) (xy 185.6994 -146.0373) (xy 185.1914 -146.0373)
				)
			)
		)
		(zone
			(layer "F.Cu")
			(hatch none 0.5)
			(connect_pads
				(clearance 0)
			)
			(min_thickness 0.25)
			(keepout
				(tracks not_allowed)
				(vias allowed)
				(pads allowed)
				(copperpour not_allowed)
				(footprints allowed)
			)
			(placement
				(enabled no)
				(sheetname "")
			)
			(fill
				(thermal_gap 0.5)
				(thermal_bridge_width 0.5)
				(island_removal_mode 0)
			)
			(polygon
				(pts
					(xy 185.1914 -146.0373) (xy 185.6994 -146.0373) (xy 185.6994 -146.4183) (xy 185.1914 -146.4183)
				)
			)
		)
	)
	(footprint ""
		(layer "F.Cu")
		(at 181.60873 -24.431752 90)
		(property "Reference" "Q12W1"
			(at 0 0 90)
			(layer "F.SilkS")
			(hide yes)
			(effects
				(font
					(size 1.27 1.27)
				)
			)
		)
		(property "Value" "*"
			(at -4.572 -7.6835 90)
			(unlocked yes)
			(layer "F.Fab")
			(hide yes)
			(effects
				(font
					(size 1.27 1.016)
					(thickness 0.1524)
				)
			)
		)
		(property "Device Type" "BSL308C-H6327-GP_DISCRET-GB1-BA"
			(at -4.572 -9.2075 90)
			(unlocked yes)
			(layer "F.Fab")
			(hide yes)
			(effects
				(font
					(size 1.27 1.016)
					(thickness 0.1524)
				)
			)
		)
		(duplicate_pad_numbers_are_jumpers no)
		(fp_line
			(start 1.102868 -0.081534)
			(end 1.102868 0.081534)
			(stroke
				(width 0.1524)
				(type default)
			)
			(layer "F.SilkS")
		)
		(fp_line
			(start -1.8796 -0.081534)
			(end 1.102868 -0.081534)
			(stroke
				(width 0.1524)
				(type default)
			)
			(layer "F.SilkS")
		)
		(fp_line
			(start -1.8796 -0.081534)
			(end -1.524 0)
			(stroke
				(width 0.1524)
				(type default)
			)
			(layer "F.SilkS")
		)
		(fp_line
			(start -1.524 0)
			(end -1.8796 0.081534)
			(stroke
				(width 0.1524)
				(type default)
			)
			(layer "F.SilkS")
		)
		(fp_line
			(start 1.102868 0.081534)
			(end -1.8796 0.081534)
			(stroke
				(width 0.1524)
				(type default)
			)
			(layer "F.SilkS")
		)
		(fp_line
			(start -1.8796 0.081534)
			(end -1.8796 -0.081534)
			(stroke
				(width 0.1524)
				(type default)
			)
			(layer "F.SilkS")
		)
		(fp_line
			(start -1.7018 0.3048)
			(end -1.7018 1.8796)
			(stroke
				(width 0.508)
				(type default)
			)
			(layer "F.SilkS")
		)
		(fp_poly
			(pts
				(xy -1.179068 0.081534) (xy -1.179068 -0.081534) (xy 1.102868 -0.081534) (xy 1.102868 0.081534)
			)
			(stroke
				(width 0)
				(type default)
			)
			(fill yes)
			(layer "F.SilkS")
		)
		(fp_rect
			(start -1.4478 1.2446)
			(end 1.4478 -1.2446)
			(stroke
				(width 0)
				(type default)
			)
			(fill no)
			(layer "F.CrtYd")
		)
		(fp_poly
			(pts
				(xy -1.4478 -1.23952) (xy -1.9558 -1.23952) (xy -1.9558 2.1336) (xy 1.9558 2.1336) (xy 1.9558 -2.1336)
				(xy -1.9558 -2.1336) (xy -1.9558 -1.2446) (xy 1.4478 -1.2446) (xy 1.4478 1.2446) (xy -1.4478 1.2446)
			)
			(stroke
				(width 0)
				(type default)
			)
			(fill no)
			(layer "F.CrtYd")
		)
		(fp_rect
			(start -1.9558 2.1336)
			(end 1.9558 -2.1336)
			(stroke
				(width 0)
				(type default)
			)
			(fill no)
			(layer "F.Fab")
		)
		(pad "1" smd rect
			(at -0.950468 0.995934 90)
			(size 0.4572 1.27)
			(layers "F.Cu" "F.Mask" "F.Paste")
			(net "PWRGD_PVDDQ_ABC")
		)
		(pad "2" smd rect
			(at 0 0.995934 90)
			(size 0.4572 1.27)
			(layers "F.Cu" "F.Mask" "F.Paste")
			(net "P12V_NVDIMM_ABC")
		)
		(pad "3" smd rect
			(at 0.950468 0.995934 90)
			(size 0.4572 1.27)
			(layers "F.Cu" "F.Mask" "F.Paste")
			(net "PWRGD_PVDDQ_ABC_N")
		)
		(pad "4" smd rect
			(at 0.950468 -0.995934 90)
			(size 0.4572 1.27)
			(layers "F.Cu" "F.Mask" "F.Paste")
			(net "P12V_NVDIMM_ABC_D")
		)
		(pad "5" smd rect
			(at 0 -0.995934 90)
			(size 0.4572 1.27)
			(layers "F.Cu" "F.Mask" "F.Paste")
			(net "GND")
		)
		(pad "6" smd rect
			(at -0.950468 -0.995934 90)
			(size 0.4572 1.27)
			(layers "F.Cu" "F.Mask" "F.Paste")
			(net "PWRGD_PVDDQ_ABC_N")
		)
	)
	(footprint ""
		(layer "F.Cu")
		(at 9.017 13.2715 -90)
		(property "Reference" "T1P31"
			(at 0 0 270)
			(layer "F.SilkS")
			(hide yes)
			(effects
				(font
					(size 1.27 1.27)
				)
			)
		)
		(property "Value" "*"
			(at 0 -3.44805 270)
			(unlocked yes)
			(layer "F.Fab")
			(hide yes)
			(effects
				(font
					(size 0.889 0.889)
					(thickness 0.1524)
				)
			)
		)
		(property "Device Type" "TPAD-SE-2P-GP_DISCRET-GA1-TPADA"
			(at 0 -4.97205 270)
			(unlocked yes)
			(layer "F.Fab")
			(hide yes)
			(effects
				(font
					(size 0.889 0.889)
					(thickness 0.1524)
				)
			)
		)
		(duplicate_pad_numbers_are_jumpers no)
		(fp_line
			(start -1.016 2.286)
			(end -1.016 -2.286)
			(stroke
				(width 0.1524)
				(type default)
			)
			(layer "F.SilkS")
		)
		(fp_line
			(start 1.016 2.286)
			(end -1.016 2.286)
			(stroke
				(width 0.1524)
				(type default)
			)
			(layer "F.SilkS")
		)
		(fp_line
			(start -1.016 -2.286)
			(end 1.016 -2.286)
			(stroke
				(width 0.1524)
				(type default)
			)
			(layer "F.SilkS")
		)
		(fp_line
			(start 1.016 -2.286)
			(end 1.016 2.286)
			(stroke
				(width 0.1524)
				(type default)
			)
			(layer "F.SilkS")
		)
		(fp_rect
			(start -1.27 2.54)
			(end 1.27 -2.54)
			(stroke
				(width 0)
				(type default)
			)
			(fill no)
			(layer "F.CrtYd")
		)
		(fp_rect
			(start -1.27 2.54)
			(end 1.27 -2.54)
			(stroke
				(width 0)
				(type default)
			)
			(fill no)
			(layer "F.Fab")
		)
		(pad "1" thru_hole circle
			(at 0 -1.27 270)
			(size 1.524 1.524)
			(drill 0.9144)
			(layers "*.Cu" "*.Mask")
			(remove_unused_layers no)
			(net "L1_50OHM_6INCH")
			(clearance -0.0508)
			(thermal_gap 0.127)
			(padstack
				(mode front_inner_back)
				(layer "Inner"
					(shape circle)
					(size 1.1684 1.1684)
					(clearance 0.127)
				)
				(layer "B.Cu"
					(shape circle)
					(size 1.524 1.524)
					(clearance -0.0508)
				)
			)
		)
		(pad "GND1" thru_hole rect
			(at 0 1.27 270)
			(size 1.524 1.524)
			(drill 0.9144)
			(layers "*.Cu" "*.Mask")
			(remove_unused_layers no)
			(net "GND")
			(clearance -0.0508)
			(thermal_gap 0.127)
			(padstack
				(mode front_inner_back)
				(layer "Inner"
					(shape circle)
					(size 1.1684 1.1684)
					(clearance 0.127)
				)
				(layer "B.Cu"
					(shape rect)
					(size 1.524 1.524)
					(clearance -0.0508)
				)
			)
		)
	)
	(footprint ""
		(layer "F.Cu")
		(at 487.554016 -146.508978 -90)
		(property "Reference" "S9A2"
			(at 1.282446 -2.299208 270)
			(unlocked yes)
			(layer "F.SilkS")
			(effects
				(font
					(size 1.778 2.032)
					(thickness 0.1524)
				)
				(justify left)
			)
		)
		(property "Value" ""
			(at 0 0 270)
			(layer "F.Fab")
			(effects
				(font
					(size 1.27 1.27)
				)
			)
		)
		(duplicate_pad_numbers_are_jumpers no)
		(fp_line
			(start 1.800098 5.3721)
			(end 3.022092 5.3721)
			(stroke
				(width 0.1524)
				(type default)
			)
			(layer "F.SilkS")
		)
		(fp_line
			(start -0.7112 0.978154)
			(end -0.7112 3.52044)
			(stroke
				(width 0.1524)
				(type default)
			)
			(layer "F.SilkS")
		)
		(fp_line
			(start 5.5372 0.973836)
			(end 5.5372 3.52044)
			(stroke
				(width 0.1524)
				(type default)
			)
			(layer "F.SilkS")
		)
		(fp_line
			(start 3.024632 -0.8763)
			(end 1.800098 -0.8763)
			(stroke
				(width 0.1524)
				(type default)
			)
			(layer "F.SilkS")
		)
		(fp_circle
			(center -1.972818 -0.651002)
			(end -1.972818 -0.778002)
			(stroke
				(width 0.254)
				(type default)
			)
			(fill no)
			(layer "F.SilkS")
		)
		(fp_rect
			(start -0.7112 5.3721)
			(end 5.5372 -0.8763)
			(stroke
				(width 0)
				(type default)
			)
			(fill no)
			(layer "F.CrtYd")
		)
		(fp_line
			(start -0.7112 5.3721)
			(end -0.7112 -0.8763)
			(stroke
				(width 0.1)
				(type default)
			)
			(layer "F.Fab")
		)
		(fp_line
			(start 5.5372 5.3721)
			(end -0.7112 5.3721)
			(stroke
				(width 0.1)
				(type default)
			)
			(layer "F.Fab")
		)
		(fp_line
			(start -0.7112 -0.8763)
			(end 5.5372 -0.8763)
			(stroke
				(width 0.1)
				(type default)
			)
			(layer "F.Fab")
		)
		(fp_line
			(start 5.5372 -0.8763)
			(end 5.5372 5.3721)
			(stroke
				(width 0.1)
				(type default)
			)
			(layer "F.Fab")
		)
		(fp_circle
			(center -1.972818 -0.651002)
			(end -1.972818 -0.778002)
			(stroke
				(width 0.254)
				(type default)
			)
			(fill no)
			(layer "F.Fab")
		)
		(fp_text user "4"
			(at 7.040372 6.11124 0)
			(unlocked yes)
			(layer "F.SilkS")
			(effects
				(font
					(size 0.7874 0.5842)
					(thickness 0.1524)
				)
				(justify left)
			)
		)
		(fp_text user "3"
			(at -0.055372 6.018276 0)
			(unlocked yes)
			(layer "F.SilkS")
			(effects
				(font
					(size 0.7874 0.5842)
					(thickness 0.1524)
				)
				(justify left)
			)
		)
		(fp_text user "2"
			(at 5.997448 -1.599184 0)
			(unlocked yes)
			(layer "F.SilkS")
			(effects
				(font
					(size 0.7874 0.5842)
					(thickness 0.1524)
				)
				(justify left)
			)
		)
		(fp_text user "3"
			(at -1.454404 3.553206 0)
			(unlocked yes)
			(layer "F.Fab")
			(effects
				(font
					(size 0.7874 0.5842)
					(thickness 0.1524)
				)
				(justify left)
			)
		)
		(fp_text user "4"
			(at -1.422908 1.380998 0)
			(unlocked yes)
			(layer "F.Fab")
			(effects
				(font
					(size 0.7874 0.5842)
					(thickness 0.1524)
				)
				(justify left)
			)
		)
		(fp_text user "2"
			(at 5.080508 -0.918972 0)
			(unlocked yes)
			(layer "F.Fab")
			(effects
				(font
					(size 0.7874 0.5842)
					(thickness 0.1524)
				)
				(justify left)
			)
		)
		(pad "1" smd rect
			(at 0 0 270)
			(size 2.921 1.27)
			(layers "F.Cu" "F.Mask" "F.Paste")
			(net "GND")
		)
		(pad "2" smd rect
			(at 4.826 0 270)
			(size 2.921 1.27)
			(layers "F.Cu" "F.Mask" "F.Paste")
			(net "GND")
		)
		(pad "3" smd rect
			(at 0 4.4958 270)
			(size 2.921 1.27)
			(layers "F.Cu" "F.Mask" "F.Paste")
			(net "FP_PWR_BTN_R_N")
		)
		(pad "4" smd rect
			(at 4.826 4.4958 270)
			(size 2.921 1.27)
			(layers "F.Cu" "F.Mask" "F.Paste")
			(net "FP_PWR_BTN_R_N")
		)
	)
	(footprint ""
		(layer "F.Cu")
		(at 261.747 -23.241 180)
		(property "Reference" "C5F2"
			(at 0 0 180)
			(layer "F.SilkS")
			(hide yes)
			(effects
				(font
					(size 1.27 1.27)
				)
			)
		)
		(property "Value" ""
			(at 0 0 180)
			(layer "F.Fab")
			(effects
				(font
					(size 1.27 1.27)
				)
			)
		)
		(duplicate_pad_numbers_are_jumpers no)
		(fp_rect
			(start -0.500126 1.598422)
			(end 0.500126 -0.201422)
			(stroke
				(width 0)
				(type default)
			)
			(fill no)
			(layer "F.CrtYd")
		)
		(fp_line
			(start 0.500126 1.598422)
			(end -0.500126 1.598422)
			(stroke
				(width 0.1)
				(type default)
			)
			(layer "F.Fab")
		)
		(fp_line
			(start 0.500126 -0.201422)
			(end 0.500126 1.598422)
			(stroke
				(width 0.1)
				(type default)
			)
			(layer "F.Fab")
		)
		(fp_line
			(start -0.500126 1.598422)
			(end -0.500126 -0.201422)
			(stroke
				(width 0.1)
				(type default)
			)
			(layer "F.Fab")
		)
		(fp_line
			(start -0.500126 -0.201422)
			(end 0.500126 -0.201422)
			(stroke
				(width 0.1)
				(type default)
			)
			(layer "F.Fab")
		)
		(pad "1" smd rect
			(at 0 0 90)
			(size 0.889 0.9906)
			(layers "F.Cu" "F.Mask" "F.Paste")
			(net "PVDDQ_ABC")
		)
		(pad "2" smd rect
			(at 0 1.397 90)
			(size 0.889 0.9906)
			(layers "F.Cu" "F.Mask" "F.Paste")
			(net "GND")
		)
		(zone
			(layer "F.Cu")
			(hatch none 0.5)
			(connect_pads
				(clearance 0)
			)
			(min_thickness 0.25)
			(keepout
				(tracks not_allowed)
				(vias allowed)
				(pads allowed)
				(copperpour not_allowed)
				(footprints allowed)
			)
			(placement
				(enabled no)
				(sheetname "")
			)
			(fill
				(thermal_gap 0.5)
				(thermal_bridge_width 0.5)
				(island_removal_mode 0)
			)
			(polygon
				(pts
					(xy 262.2423 -24.1935) (xy 261.2517 -24.1935) (xy 261.2517 -23.6855) (xy 262.2423 -23.6855)
				)
			)
		)
		(zone
			(layer "F.Cu")
			(hatch none 0.5)
			(connect_pads
				(clearance 0)
			)
			(min_thickness 0.25)
			(keepout
				(tracks allowed)
				(vias not_allowed)
				(pads allowed)
				(copperpour not_allowed)
				(footprints allowed)
			)
			(placement
				(enabled no)
				(sheetname "")
			)
			(fill
				(thermal_gap 0.5)
				(thermal_bridge_width 0.5)
				(island_removal_mode 0)
			)
			(polygon
				(pts
					(xy 262.2423 -24.1935) (xy 261.2517 -24.1935) (xy 261.2517 -23.6855) (xy 262.2423 -23.6855)
				)
			)
		)
	)
	(footprint ""
		(layer "F.Cu")
		(at 322.7324 -35.052 -90)
		(property "Reference" "R6F2"
			(at 0 0 270)
			(layer "F.SilkS")
			(hide yes)
			(effects
				(font
					(size 1.27 1.27)
				)
			)
		)
		(property "Value" ""
			(at 0 0 270)
			(layer "F.Fab")
			(effects
				(font
					(size 1.27 1.27)
				)
			)
		)
		(duplicate_pad_numbers_are_jumpers no)
		(fp_poly
			(pts
				(xy -0.2794 -0.1016) (xy 0.2794 -0.1016) (xy 0.2794 0.9906) (xy -0.2794 0.9906)
			)
			(stroke
				(width 0)
				(type default)
			)
			(fill no)
			(layer "F.CrtYd")
		)
		(fp_line
			(start -0.2794 0.9906)
			(end 0.2794 0.9906)
			(stroke
				(width 0.1)
				(type default)
			)
			(layer "F.Fab")
		)
		(fp_line
			(start 0.2794 0.9906)
			(end 0.2794 -0.1016)
			(stroke
				(width 0.1)
				(type default)
			)
			(layer "F.Fab")
		)
		(fp_line
			(start -0.2794 -0.1016)
			(end -0.2794 0.9906)
			(stroke
				(width 0.1)
				(type default)
			)
			(layer "F.Fab")
		)
		(fp_line
			(start 0.2794 -0.1016)
			(end -0.2794 -0.1016)
			(stroke
				(width 0.1)
				(type default)
			)
			(layer "F.Fab")
		)
		(pad "1" smd rect
			(at 0 0 270)
			(size 0.508 0.508)
			(layers "F.Cu" "F.Mask" "F.Paste")
			(net "FM_ADR_COMPLETE_CPU1_N")
		)
		(pad "2" smd rect
			(at 0 0.889 270)
			(size 0.508 0.508)
			(layers "F.Cu" "F.Mask" "F.Paste")
			(net "FM_ADR_COMPLETE_KLM_N")
		)
		(zone
			(layer "F.Cu")
			(hatch none 0.5)
			(connect_pads
				(clearance 0)
			)
			(min_thickness 0.25)
			(keepout
				(tracks not_allowed)
				(vias allowed)
				(pads allowed)
				(copperpour not_allowed)
				(footprints allowed)
			)
			(placement
				(enabled no)
				(sheetname "")
			)
			(fill
				(thermal_gap 0.5)
				(thermal_bridge_width 0.5)
				(island_removal_mode 0)
			)
			(polygon
				(pts
					(xy 322.0974 -35.306) (xy 322.0974 -34.798) (xy 322.4784 -34.798) (xy 322.4784 -35.306)
				)
			)
		)
		(zone
			(layer "F.Cu")
			(hatch none 0.5)
			(connect_pads
				(clearance 0)
			)
			(min_thickness 0.25)
			(keepout
				(tracks allowed)
				(vias not_allowed)
				(pads allowed)
				(copperpour not_allowed)
				(footprints allowed)
			)
			(placement
				(enabled no)
				(sheetname "")
			)
			(fill
				(thermal_gap 0.5)
				(thermal_bridge_width 0.5)
				(island_removal_mode 0)
			)
			(polygon
				(pts
					(xy 322.4784 -35.306) (xy 322.4784 -34.798) (xy 322.0974 -34.798) (xy 322.0974 -35.306)
				)
			)
		)
	)
	(footprint ""
		(layer "F.Cu")
		(at 5.6388 -142.875 -90)
		(property "Reference" "RT7"
			(at 0 0 270)
			(layer "F.SilkS")
			(hide yes)
			(effects
				(font
					(size 1.27 1.27)
				)
			)
		)
		(property "Value" "*"
			(at -0.0254 -2.6289 270)
			(unlocked yes)
			(layer "F.Fab")
			(hide yes)
			(effects
				(font
					(size 1.27 1.016)
					(thickness 0.1524)
				)
			)
		)
		(property "Device Type" "1R3F-GP_RCL_GP-1R3F-GP,64.1R00A"
			(at -0.0254 -4.1529 270)
			(unlocked yes)
			(layer "F.Fab")
			(hide yes)
			(effects
				(font
					(size 1.27 1.016)
					(thickness 0.1524)
				)
			)
		)
		(duplicate_pad_numbers_are_jumpers no)
		(fp_line
			(start -0.4826 0)
			(end -0.2032 0)
			(stroke
				(width 0.2032)
				(type default)
			)
			(layer "F.SilkS")
		)
		(fp_line
			(start 0.2032 0)
			(end 0.4826 0)
			(stroke
				(width 0.2032)
				(type default)
			)
			(layer "F.SilkS")
		)
		(fp_rect
			(start -0.5842 1.3335)
			(end 0.5842 -1.3335)
			(stroke
				(width 0)
				(type default)
			)
			(fill no)
			(layer "F.CrtYd")
		)
		(fp_rect
			(start -0.5842 1.3335)
			(end 0.5842 -1.3335)
			(stroke
				(width 0)
				(type default)
			)
			(fill no)
			(layer "F.Fab")
		)
		(pad "1" smd custom
			(at 0 -0.762 270)
			(size 0.2159 0.2159)
			(layers "F.Cu" "F.Mask" "F.Paste")
			(net "VR_PVDDQ_KLM_PH2_RC")
			(options
				(clearance outline)
				(anchor circle)
			)
			(primitives
				(gr_poly
					(pts
						(arc
							(start -0.3302 -0.4318)
							(mid -0.402042 -0.402042)
							(end -0.4318 -0.3302)
						)
						(arc
							(start -0.4318 0.3302)
							(mid -0.402042 0.402042)
							(end -0.3302 0.4318)
						)
						(arc
							(start 0.3302 0.4318)
							(mid 0.402042 0.402042)
							(end 0.4318 0.3302)
						)
						(arc
							(start 0.4318 -0.3302)
							(mid 0.402042 -0.402042)
							(end 0.3302 -0.4318)
						)
					)
					(width 0)
					(fill yes)
				)
			)
		)
		(pad "2" smd custom
			(at 0 0.762 270)
			(size 0.2159 0.2159)
			(layers "F.Cu" "F.Mask" "F.Paste")
			(net "GND")
			(options
				(clearance outline)
				(anchor circle)
			)
			(primitives
				(gr_poly
					(pts
						(arc
							(start -0.3302 -0.4318)
							(mid -0.402042 -0.402042)
							(end -0.4318 -0.3302)
						)
						(arc
							(start -0.4318 0.3302)
							(mid -0.402042 0.402042)
							(end -0.3302 0.4318)
						)
						(arc
							(start 0.3302 0.4318)
							(mid 0.402042 0.402042)
							(end 0.4318 0.3302)
						)
						(arc
							(start 0.4318 -0.3302)
							(mid 0.402042 -0.402042)
							(end 0.3302 -0.4318)
						)
					)
					(width 0)
					(fill yes)
				)
			)
		)
	)
	(footprint ""
		(layer "F.Cu")
		(at 16.764 -69.977 -90)
		(property "Reference" "R1D45"
			(at 0 0 270)
			(layer "F.SilkS")
			(hide yes)
			(effects
				(font
					(size 1.27 1.27)
				)
			)
		)
		(property "Value" ""
			(at 0 0 270)
			(layer "F.Fab")
			(effects
				(font
					(size 1.27 1.27)
				)
			)
		)
		(duplicate_pad_numbers_are_jumpers no)
		(fp_rect
			(start -0.2794 0.9906)
			(end 0.2794 -0.1016)
			(stroke
				(width 0)
				(type default)
			)
			(fill no)
			(layer "F.CrtYd")
		)
		(fp_line
			(start -0.2794 0.9906)
			(end 0.2794 0.9906)
			(stroke
				(width 0.1)
				(type default)
			)
			(layer "F.Fab")
		)
		(fp_line
			(start 0.2794 0.9906)
			(end 0.2794 -0.1016)
			(stroke
				(width 0.1)
				(type default)
			)
			(layer "F.Fab")
		)
		(fp_line
			(start -0.2794 -0.1016)
			(end -0.2794 0.9906)
			(stroke
				(width 0.1)
				(type default)
			)
			(layer "F.Fab")
		)
		(fp_line
			(start 0.2794 -0.1016)
			(end -0.2794 -0.1016)
			(stroke
				(width 0.1)
				(type default)
			)
			(layer "F.Fab")
		)
		(pad "1" smd rect
			(at 0 0 270)
			(size 0.508 0.508)
			(layers "F.Cu" "F.Mask" "F.Paste")
			(net "A_HSC_MON")
		)
		(pad "2" smd rect
			(at 0 0.889 270)
			(size 0.508 0.508)
			(layers "F.Cu" "F.Mask" "F.Paste")
			(net "A_HSC_HSN")
		)
		(zone
			(layer "F.Cu")
			(hatch none 0.5)
			(connect_pads
				(clearance 0)
			)
			(min_thickness 0.25)
			(keepout
				(tracks not_allowed)
				(vias allowed)
				(pads allowed)
				(copperpour not_allowed)
				(footprints allowed)
			)
			(placement
				(enabled no)
				(sheetname "")
			)
			(fill
				(thermal_gap 0.5)
				(thermal_bridge_width 0.5)
				(island_removal_mode 0)
			)
			(polygon
				(pts
					(xy 16.129 -70.231) (xy 16.129 -69.723) (xy 16.51 -69.723) (xy 16.51 -70.231)
				)
			)
		)
		(zone
			(layer "F.Cu")
			(hatch none 0.5)
			(connect_pads
				(clearance 0)
			)
			(min_thickness 0.25)
			(keepout
				(tracks allowed)
				(vias not_allowed)
				(pads allowed)
				(copperpour not_allowed)
				(footprints allowed)
			)
			(placement
				(enabled no)
				(sheetname "")
			)
			(fill
				(thermal_gap 0.5)
				(thermal_bridge_width 0.5)
				(island_removal_mode 0)
			)
			(polygon
				(pts
					(xy 16.129 -70.231) (xy 16.129 -69.723) (xy 16.51 -69.723) (xy 16.51 -70.231)
				)
			)
		)
	)
	(footprint ""
		(layer "F.Cu")
		(at 173.9265 -67.056 90)
		(property "Reference" "R4D57"
			(at 0 0 90)
			(layer "F.SilkS")
			(hide yes)
			(effects
				(font
					(size 1.27 1.27)
				)
			)
		)
		(property "Value" ""
			(at 0 0 90)
			(layer "F.Fab")
			(effects
				(font
					(size 1.27 1.27)
				)
			)
		)
		(duplicate_pad_numbers_are_jumpers no)
		(fp_poly
			(pts
				(xy -0.2794 -0.1016) (xy 0.2794 -0.1016) (xy 0.2794 0.9906) (xy -0.2794 0.9906)
			)
			(stroke
				(width 0)
				(type default)
			)
			(fill no)
			(layer "F.CrtYd")
		)
		(fp_line
			(start 0.2794 -0.1016)
			(end -0.2794 -0.1016)
			(stroke
				(width 0.1)
				(type default)
			)
			(layer "F.Fab")
		)
		(fp_line
			(start -0.2794 -0.1016)
			(end -0.2794 0.9906)
			(stroke
				(width 0.1)
				(type default)
			)
			(layer "F.Fab")
		)
		(fp_line
			(start 0.2794 0.9906)
			(end 0.2794 -0.1016)
			(stroke
				(width 0.1)
				(type default)
			)
			(layer "F.Fab")
		)
		(fp_line
			(start -0.2794 0.9906)
			(end 0.2794 0.9906)
			(stroke
				(width 0.1)
				(type default)
			)
			(layer "F.Fab")
		)
		(pad "1" smd rect
			(at 0 0 90)
			(size 0.508 0.508)
			(layers "F.Cu" "F.Mask" "F.Paste")
			(net "VR_PVCCIO_CPU1_VINSEN")
		)
		(pad "2" smd rect
			(at 0 0.889 90)
			(size 0.508 0.508)
			(layers "F.Cu" "F.Mask" "F.Paste")
			(net "GND")
		)
		(zone
			(layer "F.Cu")
			(hatch none 0.5)
			(connect_pads
				(clearance 0)
			)
			(min_thickness 0.25)
			(keepout
				(tracks allowed)
				(vias not_allowed)
				(pads allowed)
				(copperpour not_allowed)
				(footprints allowed)
			)
			(placement
				(enabled no)
				(sheetname "")
			)
			(fill
				(thermal_gap 0.5)
				(thermal_bridge_width 0.5)
				(island_removal_mode 0)
			)
			(polygon
				(pts
					(xy 174.1805 -66.802) (xy 174.1805 -67.31) (xy 174.5615 -67.31) (xy 174.5615 -66.802)
				)
			)
		)
		(zone
			(layer "F.Cu")
			(hatch none 0.5)
			(connect_pads
				(clearance 0)
			)
			(min_thickness 0.25)
			(keepout
				(tracks not_allowed)
				(vias allowed)
				(pads allowed)
				(copperpour not_allowed)
				(footprints allowed)
			)
			(placement
				(enabled no)
				(sheetname "")
			)
			(fill
				(thermal_gap 0.5)
				(thermal_bridge_width 0.5)
				(island_removal_mode 0)
			)
			(polygon
				(pts
					(xy 174.5615 -66.802) (xy 174.5615 -67.31) (xy 174.1805 -67.31) (xy 174.1805 -66.802)
				)
			)
		)
	)
	(footprint ""
		(layer "F.Cu")
		(at 204.089 -105.918 90)
		(property "Reference" "R6N1"
			(at 0 0 90)
			(layer "F.SilkS")
			(hide yes)
			(effects
				(font
					(size 1.27 1.27)
				)
			)
		)
		(property "Value" ""
			(at 0 0 90)
			(layer "F.Fab")
			(effects
				(font
					(size 1.27 1.27)
				)
			)
		)
		(duplicate_pad_numbers_are_jumpers no)
		(fp_poly
			(pts
				(xy -0.2794 -0.1016) (xy 0.2794 -0.1016) (xy 0.2794 0.9906) (xy -0.2794 0.9906)
			)
			(stroke
				(width 0)
				(type default)
			)
			(fill no)
			(layer "F.CrtYd")
		)
		(fp_line
			(start 0.2794 -0.1016)
			(end -0.2794 -0.1016)
			(stroke
				(width 0.1)
				(type default)
			)
			(layer "F.Fab")
		)
		(fp_line
			(start -0.2794 -0.1016)
			(end -0.2794 0.9906)
			(stroke
				(width 0.1)
				(type default)
			)
			(layer "F.Fab")
		)
		(fp_line
			(start 0.2794 0.9906)
			(end 0.2794 -0.1016)
			(stroke
				(width 0.1)
				(type default)
			)
			(layer "F.Fab")
		)
		(fp_line
			(start -0.2794 0.9906)
			(end 0.2794 0.9906)
			(stroke
				(width 0.1)
				(type default)
			)
			(layer "F.Fab")
		)
		(pad "1" smd rect
			(at 0 0 90)
			(size 0.508 0.508)
			(layers "F.Cu" "F.Mask" "F.Paste")
			(net "SVID_ALERT0_CPU0_R_N")
		)
		(pad "2" smd rect
			(at 0 0.889 90)
			(size 0.508 0.508)
			(layers "F.Cu" "F.Mask" "F.Paste")
			(net "PVCCIO_CPU0")
		)
		(zone
			(layer "F.Cu")
			(hatch none 0.5)
			(connect_pads
				(clearance 0)
			)
			(min_thickness 0.25)
			(keepout
				(tracks allowed)
				(vias not_allowed)
				(pads allowed)
				(copperpour not_allowed)
				(footprints allowed)
			)
			(placement
				(enabled no)
				(sheetname "")
			)
			(fill
				(thermal_gap 0.5)
				(thermal_bridge_width 0.5)
				(island_removal_mode 0)
			)
			(polygon
				(pts
					(xy 204.343 -105.664) (xy 204.343 -106.172) (xy 204.724 -106.172) (xy 204.724 -105.664)
				)
			)
		)
		(zone
			(layer "F.Cu")
			(hatch none 0.5)
			(connect_pads
				(clearance 0)
			)
			(min_thickness 0.25)
			(keepout
				(tracks not_allowed)
				(vias allowed)
				(pads allowed)
				(copperpour not_allowed)
				(footprints allowed)
			)
			(placement
				(enabled no)
				(sheetname "")
			)
			(fill
				(thermal_gap 0.5)
				(thermal_bridge_width 0.5)
				(island_removal_mode 0)
			)
			(polygon
				(pts
					(xy 204.724 -105.664) (xy 204.724 -106.172) (xy 204.343 -106.172) (xy 204.343 -105.664)
				)
			)
		)
	)
	(footprint ""
		(layer "F.Cu")
		(at 399.542 -146.5326)
		(property "Reference" ""
			(at 0 0 0)
			(layer "F.SilkS")
			(hide yes)
			(effects
				(font
					(size 1.27 1.27)
				)
			)
		)
		(property "Value" ""
			(at 0 0 0)
			(layer "F.Fab")
			(effects
				(font
					(size 1.27 1.27)
				)
			)
		)
		(duplicate_pad_numbers_are_jumpers no)
		(fp_poly
			(pts
				(arc
					(start 2.032 0)
					(mid -2.032 0)
					(end 2.032 0)
				)
			)
			(stroke
				(width 0)
				(type default)
			)
			(fill no)
			(layer "F.CrtYd")
		)
		(pad "1" smd circle
			(at 0 0)
			(size 1.016 1.016)
			(layers "F.Cu" "F.Mask" "F.Paste")
			(net "Net_133")
		)
		(zone
			(layer "F.Cu")
			(hatch none 0.5)
			(connect_pads
				(clearance 0)
			)
			(min_thickness 0.25)
			(keepout
				(tracks not_allowed)
				(vias allowed)
				(pads allowed)
				(copperpour not_allowed)
				(footprints allowed)
			)
			(placement
				(enabled no)
				(sheetname "")
			)
			(fill
				(thermal_gap 0.5)
				(thermal_bridge_width 0.5)
				(island_removal_mode 0)
			)
			(polygon
				(pts
					(arc
						(start 401.066 -146.5326)
						(mid 398.018 -146.5326)
						(end 401.066 -146.5326)
					)
				)
			)
		)
		(zone
			(layers "F.Cu" "B.Cu" "In1.Cu" "In2.Cu" "In3.Cu" "In4.Cu" "In5.Cu" "In6.Cu"
				"In7.Cu" "In8.Cu" "In9.Cu" "In10.Cu" "In11.Cu" "In12.Cu"
			)
			(hatch none 0.5)
			(connect_pads
				(clearance 0)
			)
			(min_thickness 0.25)
			(keepout
				(tracks allowed)
				(vias not_allowed)
				(pads allowed)
				(copperpour not_allowed)
				(footprints allowed)
			)
			(placement
				(enabled no)
				(sheetname "")
			)
			(fill
				(thermal_gap 0.5)
				(thermal_bridge_width 0.5)
				(island_removal_mode 0)
			)
			(polygon
				(pts
					(arc
						(start 401.066 -146.5326)
						(mid 398.018 -146.5326)
						(end 401.066 -146.5326)
					)
				)
			)
		)
	)
	(footprint ""
		(layer "F.Cu")
		(at 165.9763 -133.1976)
		(property "Reference" "C4B2"
			(at 0 0 0)
			(layer "F.SilkS")
			(hide yes)
			(effects
				(font
					(size 1.27 1.27)
				)
			)
		)
		(property "Value" ""
			(at 0 0 0)
			(layer "F.Fab")
			(effects
				(font
					(size 1.27 1.27)
				)
			)
		)
		(duplicate_pad_numbers_are_jumpers no)
		(fp_poly
			(pts
				(xy -0.7239 -0.2159) (xy 0.7239 -0.2159) (xy 0.7239 1.9939) (xy -0.7239 1.9939)
			)
			(stroke
				(width 0)
				(type default)
			)
			(fill no)
			(layer "F.CrtYd")
		)
		(fp_line
			(start -0.7239 -0.2159)
			(end -0.7239 1.9939)
			(stroke
				(width 0.1)
				(type default)
			)
			(layer "F.Fab")
		)
		(fp_line
			(start -0.7239 1.9939)
			(end 0.7239 1.9939)
			(stroke
				(width 0.1)
				(type default)
			)
			(layer "F.Fab")
		)
		(fp_line
			(start 0.7239 -0.2159)
			(end -0.7239 -0.2159)
			(stroke
				(width 0.1)
				(type default)
			)
			(layer "F.Fab")
		)
		(fp_line
			(start 0.7239 1.9939)
			(end 0.7239 -0.2159)
			(stroke
				(width 0.1)
				(type default)
			)
			(layer "F.Fab")
		)
		(pad "1" smd rect
			(at 0 0)
			(size 1.27 1.016)
			(layers "F.Cu" "F.Mask" "F.Paste")
			(net "PVPP_KLM")
		)
		(pad "2" smd rect
			(at 0 1.778)
			(size 1.27 1.016)
			(layers "F.Cu" "F.Mask" "F.Paste")
			(net "GND")
		)
		(zone
			(layer "F.Cu")
			(hatch none 0.5)
			(connect_pads
				(clearance 0)
			)
			(min_thickness 0.25)
			(keepout
				(tracks not_allowed)
				(vias allowed)
				(pads allowed)
				(copperpour not_allowed)
				(footprints allowed)
			)
			(placement
				(enabled no)
				(sheetname "")
			)
			(fill
				(thermal_gap 0.5)
				(thermal_bridge_width 0.5)
				(island_removal_mode 0)
			)
			(polygon
				(pts
					(xy 165.3413 -132.6896) (xy 166.6113 -132.6896) (xy 166.6113 -131.9276) (xy 165.3413 -131.9276)
				)
			)
		)
	)
	(footprint ""
		(layer "F.Cu")
		(at 471.5891 -43.0784 -90)
		(property "Reference" "C9F6"
			(at 0 0 270)
			(layer "F.SilkS")
			(hide yes)
			(effects
				(font
					(size 1.27 1.27)
				)
			)
		)
		(property "Value" ""
			(at 0 0 270)
			(layer "F.Fab")
			(effects
				(font
					(size 1.27 1.27)
				)
			)
		)
		(duplicate_pad_numbers_are_jumpers no)
		(fp_poly
			(pts
				(xy 0.3048 -0.1016) (xy 0.3048 0.9906) (xy -0.3048 0.9906) (xy -0.3048 -0.1016)
			)
			(stroke
				(width 0)
				(type default)
			)
			(fill no)
			(layer "F.CrtYd")
		)
		(fp_line
			(start -0.3048 0.9906)
			(end 0.3048 0.9906)
			(stroke
				(width 0.1)
				(type default)
			)
			(layer "F.Fab")
		)
		(fp_line
			(start 0.3048 0.9906)
			(end 0.3048 -0.1016)
			(stroke
				(width 0.1)
				(type default)
			)
			(layer "F.Fab")
		)
		(fp_line
			(start -0.3048 -0.1016)
			(end -0.3048 0.9906)
			(stroke
				(width 0.1)
				(type default)
			)
			(layer "F.Fab")
		)
		(fp_line
			(start 0.3048 -0.1016)
			(end -0.3048 -0.1016)
			(stroke
				(width 0.1)
				(type default)
			)
			(layer "F.Fab")
		)
		(pad "1" smd rect
			(at 0 0 270)
			(size 0.508 0.508)
			(layers "F.Cu" "F.Mask" "F.Paste")
			(net "PWRGD_P2V5_BMC_STBY")
		)
		(pad "2" smd rect
			(at 0 0.889 270)
			(size 0.508 0.508)
			(layers "F.Cu" "F.Mask" "F.Paste")
			(net "GND")
		)
		(zone
			(layer "F.Cu")
			(hatch none 0.5)
			(connect_pads
				(clearance 0)
			)
			(min_thickness 0.25)
			(keepout
				(tracks not_allowed)
				(vias allowed)
				(pads allowed)
				(copperpour not_allowed)
				(footprints allowed)
			)
			(placement
				(enabled no)
				(sheetname "")
			)
			(fill
				(thermal_gap 0.5)
				(thermal_bridge_width 0.5)
				(island_removal_mode 0)
			)
			(polygon
				(pts
					(xy 470.9541 -43.3324) (xy 470.9541 -42.8244) (xy 471.3351 -42.8244) (xy 471.3351 -43.3324)
				)
			)
		)
		(zone
			(layer "F.Cu")
			(hatch none 0.5)
			(connect_pads
				(clearance 0)
			)
			(min_thickness 0.25)
			(keepout
				(tracks allowed)
				(vias not_allowed)
				(pads allowed)
				(copperpour not_allowed)
				(footprints allowed)
			)
			(placement
				(enabled no)
				(sheetname "")
			)
			(fill
				(thermal_gap 0.5)
				(thermal_bridge_width 0.5)
				(island_removal_mode 0)
			)
			(polygon
				(pts
					(xy 471.3351 -43.3324) (xy 471.3351 -42.8244) (xy 470.9541 -42.8244) (xy 470.9541 -43.3324)
				)
			)
		)
	)
	(footprint ""
		(layer "F.Cu")
		(at 26.898092 -13.3985)
		(property "Reference" "C1G8"
			(at 0 0 0)
			(layer "F.SilkS")
			(hide yes)
			(effects
				(font
					(size 1.27 1.27)
				)
			)
		)
		(property "Value" ""
			(at 0 0 0)
			(layer "F.Fab")
			(effects
				(font
					(size 1.27 1.27)
				)
			)
		)
		(duplicate_pad_numbers_are_jumpers no)
		(fp_poly
			(pts
				(xy 0.3048 -0.1016) (xy 0.3048 0.9906) (xy -0.3048 0.9906) (xy -0.3048 -0.1016)
			)
			(stroke
				(width 0)
				(type default)
			)
			(fill no)
			(layer "F.CrtYd")
		)
		(fp_line
			(start -0.3048 -0.1016)
			(end -0.3048 0.9906)
			(stroke
				(width 0.1)
				(type default)
			)
			(layer "F.Fab")
		)
		(fp_line
			(start -0.3048 0.9906)
			(end 0.3048 0.9906)
			(stroke
				(width 0.1)
				(type default)
			)
			(layer "F.Fab")
		)
		(fp_line
			(start 0.3048 -0.1016)
			(end -0.3048 -0.1016)
			(stroke
				(width 0.1)
				(type default)
			)
			(layer "F.Fab")
		)
		(fp_line
			(start 0.3048 0.9906)
			(end 0.3048 -0.1016)
			(stroke
				(width 0.1)
				(type default)
			)
			(layer "F.Fab")
		)
		(pad "1" smd rect
			(at 0 0)
			(size 0.508 0.508)
			(layers "F.Cu" "F.Mask" "F.Paste")
			(net "M_H_CPU_VREF")
		)
		(pad "2" smd rect
			(at 0 0.889)
			(size 0.508 0.508)
			(layers "F.Cu" "F.Mask" "F.Paste")
			(net "GND")
		)
		(zone
			(layer "F.Cu")
			(hatch none 0.5)
			(connect_pads
				(clearance 0)
			)
			(min_thickness 0.25)
			(keepout
				(tracks allowed)
				(vias not_allowed)
				(pads allowed)
				(copperpour not_allowed)
				(footprints allowed)
			)
			(placement
				(enabled no)
				(sheetname "")
			)
			(fill
				(thermal_gap 0.5)
				(thermal_bridge_width 0.5)
				(island_removal_mode 0)
			)
			(polygon
				(pts
					(xy 26.644092 -13.1445) (xy 27.152092 -13.1445) (xy 27.152092 -12.7635) (xy 26.644092 -12.7635)
				)
			)
		)
		(zone
			(layer "F.Cu")
			(hatch none 0.5)
			(connect_pads
				(clearance 0)
			)
			(min_thickness 0.25)
			(keepout
				(tracks not_allowed)
				(vias allowed)
				(pads allowed)
				(copperpour not_allowed)
				(footprints allowed)
			)
			(placement
				(enabled no)
				(sheetname "")
			)
			(fill
				(thermal_gap 0.5)
				(thermal_bridge_width 0.5)
				(island_removal_mode 0)
			)
			(polygon
				(pts
					(xy 26.644092 -12.7635) (xy 27.152092 -12.7635) (xy 27.152092 -13.1445) (xy 26.644092 -13.1445)
				)
			)
		)
	)
	(footprint ""
		(layer "F.Cu")
		(at 176.0855 -131.318 90)
		(property "Reference" "C4B9"
			(at 0 0 90)
			(layer "F.SilkS")
			(hide yes)
			(effects
				(font
					(size 1.27 1.27)
				)
			)
		)
		(property "Value" ""
			(at 0 0 90)
			(layer "F.Fab")
			(effects
				(font
					(size 1.27 1.27)
				)
			)
		)
		(duplicate_pad_numbers_are_jumpers no)
		(fp_poly
			(pts
				(xy 0.3048 -0.1016) (xy 0.3048 0.9906) (xy -0.3048 0.9906) (xy -0.3048 -0.1016)
			)
			(stroke
				(width 0)
				(type default)
			)
			(fill no)
			(layer "F.CrtYd")
		)
		(fp_line
			(start 0.3048 -0.1016)
			(end -0.3048 -0.1016)
			(stroke
				(width 0.1)
				(type default)
			)
			(layer "F.Fab")
		)
		(fp_line
			(start -0.3048 -0.1016)
			(end -0.3048 0.9906)
			(stroke
				(width 0.1)
				(type default)
			)
			(layer "F.Fab")
		)
		(fp_line
			(start 0.3048 0.9906)
			(end 0.3048 -0.1016)
			(stroke
				(width 0.1)
				(type default)
			)
			(layer "F.Fab")
		)
		(fp_line
			(start -0.3048 0.9906)
			(end 0.3048 0.9906)
			(stroke
				(width 0.1)
				(type default)
			)
			(layer "F.Fab")
		)
		(pad "1" smd rect
			(at 0 0 90)
			(size 0.508 0.508)
			(layers "F.Cu" "F.Mask" "F.Paste")
			(net "VR_COMP_RC_PVPP_KLM")
		)
		(pad "2" smd rect
			(at 0 0.889 90)
			(size 0.508 0.508)
			(layers "F.Cu" "F.Mask" "F.Paste")
			(net "VR_COMP_PVPP_KLM_3")
		)
		(zone
			(layer "F.Cu")
			(hatch none 0.5)
			(connect_pads
				(clearance 0)
			)
			(min_thickness 0.25)
			(keepout
				(tracks allowed)
				(vias not_allowed)
				(pads allowed)
				(copperpour not_allowed)
				(footprints allowed)
			)
			(placement
				(enabled no)
				(sheetname "")
			)
			(fill
				(thermal_gap 0.5)
				(thermal_bridge_width 0.5)
				(island_removal_mode 0)
			)
			(polygon
				(pts
					(xy 176.3395 -131.064) (xy 176.3395 -131.572) (xy 176.7205 -131.572) (xy 176.7205 -131.064)
				)
			)
		)
		(zone
			(layer "F.Cu")
			(hatch none 0.5)
			(connect_pads
				(clearance 0)
			)
			(min_thickness 0.25)
			(keepout
				(tracks not_allowed)
				(vias allowed)
				(pads allowed)
				(copperpour not_allowed)
				(footprints allowed)
			)
			(placement
				(enabled no)
				(sheetname "")
			)
			(fill
				(thermal_gap 0.5)
				(thermal_bridge_width 0.5)
				(island_removal_mode 0)
			)
			(polygon
				(pts
					(xy 176.7205 -131.064) (xy 176.7205 -131.572) (xy 176.3395 -131.572) (xy 176.3395 -131.064)
				)
			)
		)
	)
	(footprint ""
		(layer "F.Cu")
		(at 488.974638 -28.42768 180)
		(property "Reference" "R9F25"
			(at 0 0 180)
			(layer "F.SilkS")
			(hide yes)
			(effects
				(font
					(size 1.27 1.27)
				)
			)
		)
		(property "Value" ""
			(at 0 0 180)
			(layer "F.Fab")
			(effects
				(font
					(size 1.27 1.27)
				)
			)
		)
		(duplicate_pad_numbers_are_jumpers no)
		(fp_poly
			(pts
				(xy -0.2794 -0.1016) (xy 0.2794 -0.1016) (xy 0.2794 0.9906) (xy -0.2794 0.9906)
			)
			(stroke
				(width 0)
				(type default)
			)
			(fill no)
			(layer "F.CrtYd")
		)
		(fp_line
			(start 0.2794 0.9906)
			(end 0.2794 -0.1016)
			(stroke
				(width 0.1)
				(type default)
			)
			(layer "F.Fab")
		)
		(fp_line
			(start 0.2794 -0.1016)
			(end -0.2794 -0.1016)
			(stroke
				(width 0.1)
				(type default)
			)
			(layer "F.Fab")
		)
		(fp_line
			(start -0.2794 0.9906)
			(end 0.2794 0.9906)
			(stroke
				(width 0.1)
				(type default)
			)
			(layer "F.Fab")
		)
		(fp_line
			(start -0.2794 -0.1016)
			(end -0.2794 0.9906)
			(stroke
				(width 0.1)
				(type default)
			)
			(layer "F.Fab")
		)
		(pad "1" smd rect
			(at 0 0 180)
			(size 0.508 0.508)
			(layers "F.Cu" "F.Mask" "F.Paste")
			(net "SPA_MID_DBG_RX")
		)
		(pad "2" smd rect
			(at 0 0.889 180)
			(size 0.508 0.508)
			(layers "F.Cu" "F.Mask" "F.Paste")
			(net "UART_MUX_IN_R")
		)
		(zone
			(layer "F.Cu")
			(hatch none 0.5)
			(connect_pads
				(clearance 0)
			)
			(min_thickness 0.25)
			(keepout
				(tracks not_allowed)
				(vias allowed)
				(pads allowed)
				(copperpour not_allowed)
				(footprints allowed)
			)
			(placement
				(enabled no)
				(sheetname "")
			)
			(fill
				(thermal_gap 0.5)
				(thermal_bridge_width 0.5)
				(island_removal_mode 0)
			)
			(polygon
				(pts
					(xy 489.228638 -29.06268) (xy 488.720638 -29.06268) (xy 488.720638 -28.68168) (xy 489.228638 -28.68168)
				)
			)
		)
		(zone
			(layer "F.Cu")
			(hatch none 0.5)
			(connect_pads
				(clearance 0)
			)
			(min_thickness 0.25)
			(keepout
				(tracks allowed)
				(vias not_allowed)
				(pads allowed)
				(copperpour not_allowed)
				(footprints allowed)
			)
			(placement
				(enabled no)
				(sheetname "")
			)
			(fill
				(thermal_gap 0.5)
				(thermal_bridge_width 0.5)
				(island_removal_mode 0)
			)
			(polygon
				(pts
					(xy 489.228638 -28.68168) (xy 488.720638 -28.68168) (xy 488.720638 -29.06268) (xy 489.228638 -29.06268)
				)
			)
		)
	)
	(footprint ""
		(layer "F.Cu")
		(at 188.22797 -60.461144 180)
		(property "Reference" "C4E9"
			(at 0 0 180)
			(layer "F.SilkS")
			(hide yes)
			(effects
				(font
					(size 1.27 1.27)
				)
			)
		)
		(property "Value" "*"
			(at -0.0762 -6.2357 180)
			(unlocked yes)
			(layer "F.Fab")
			(hide yes)
			(effects
				(font
					(size 1.27 1.016)
					(thickness 0.1524)
				)
			)
		)
		(property "Device Type" "SC22U16V5MX-4-GP_SMD-BCG5-SC22A"
			(at -0.0762 -8.2677 180)
			(unlocked yes)
			(layer "F.Fab")
			(hide yes)
			(effects
				(font
					(size 1.27 1.016)
					(thickness 0.1524)
				)
			)
		)
		(duplicate_pad_numbers_are_jumpers no)
		(fp_line
			(start 0.635 0)
			(end -0.635 0)
			(stroke
				(width 0.508)
				(type default)
			)
			(layer "F.SilkS")
		)
		(fp_rect
			(start -0.9652 1.778)
			(end 0.9652 -1.778)
			(stroke
				(width 0)
				(type default)
			)
			(fill no)
			(layer "F.CrtYd")
		)
		(fp_poly
			(pts
				(xy -0.9652 -1.778) (xy 0.9652 -1.778) (xy 0.9652 1.778) (xy -0.9652 1.778)
			)
			(stroke
				(width 0)
				(type default)
			)
			(fill no)
			(layer "F.Fab")
		)
		(pad "1" smd rect
			(at 0 -0.9652 180)
			(size 1.397 1.143)
			(layers "F.Cu" "F.Mask" "F.Paste")
			(net "VR_FET_SW_P12V_STBY_PVCCIN_CPU0")
		)
		(pad "2" smd rect
			(at 0 0.9652 180)
			(size 1.397 1.143)
			(layers "F.Cu" "F.Mask" "F.Paste")
			(net "GND")
		)
	)
	(footprint ""
		(layer "F.Cu")
		(at 193.653918 -80.363568 -90)
		(property "Reference" "R4D71"
			(at 0 0 270)
			(layer "F.SilkS")
			(hide yes)
			(effects
				(font
					(size 1.27 1.27)
				)
			)
		)
		(property "Value" ""
			(at 0 0 270)
			(layer "F.Fab")
			(effects
				(font
					(size 1.27 1.27)
				)
			)
		)
		(duplicate_pad_numbers_are_jumpers no)
		(fp_poly
			(pts
				(xy -0.2794 -0.1016) (xy 0.2794 -0.1016) (xy 0.2794 0.9906) (xy -0.2794 0.9906)
			)
			(stroke
				(width 0)
				(type default)
			)
			(fill no)
			(layer "F.CrtYd")
		)
		(fp_line
			(start -0.2794 0.9906)
			(end 0.2794 0.9906)
			(stroke
				(width 0.1)
				(type default)
			)
			(layer "F.Fab")
		)
		(fp_line
			(start 0.2794 0.9906)
			(end 0.2794 -0.1016)
			(stroke
				(width 0.1)
				(type default)
			)
			(layer "F.Fab")
		)
		(fp_line
			(start -0.2794 -0.1016)
			(end -0.2794 0.9906)
			(stroke
				(width 0.1)
				(type default)
			)
			(layer "F.Fab")
		)
		(fp_line
			(start 0.2794 -0.1016)
			(end -0.2794 -0.1016)
			(stroke
				(width 0.1)
				(type default)
			)
			(layer "F.Fab")
		)
		(pad "1" smd rect
			(at 0 0 270)
			(size 0.508 0.508)
			(layers "F.Cu" "F.Mask" "F.Paste")
			(net "VR_PVCCIN_CPU0_PH4_OCSET")
		)
		(pad "2" smd rect
			(at 0 0.889 270)
			(size 0.508 0.508)
			(layers "F.Cu" "F.Mask" "F.Paste")
			(net "GND")
		)
		(zone
			(layer "F.Cu")
			(hatch none 0.5)
			(connect_pads
				(clearance 0)
			)
			(min_thickness 0.25)
			(keepout
				(tracks not_allowed)
				(vias allowed)
				(pads allowed)
				(copperpour not_allowed)
				(footprints allowed)
			)
			(placement
				(enabled no)
				(sheetname "")
			)
			(fill
				(thermal_gap 0.5)
				(thermal_bridge_width 0.5)
				(island_removal_mode 0)
			)
			(polygon
				(pts
					(xy 193.018918 -80.617568) (xy 193.018918 -80.109568) (xy 193.399918 -80.109568) (xy 193.399918 -80.617568)
				)
			)
		)
		(zone
			(layer "F.Cu")
			(hatch none 0.5)
			(connect_pads
				(clearance 0)
			)
			(min_thickness 0.25)
			(keepout
				(tracks allowed)
				(vias not_allowed)
				(pads allowed)
				(copperpour not_allowed)
				(footprints allowed)
			)
			(placement
				(enabled no)
				(sheetname "")
			)
			(fill
				(thermal_gap 0.5)
				(thermal_bridge_width 0.5)
				(island_removal_mode 0)
			)
			(polygon
				(pts
					(xy 193.399918 -80.617568) (xy 193.399918 -80.109568) (xy 193.018918 -80.109568) (xy 193.018918 -80.617568)
				)
			)
		)
	)
	(footprint ""
		(layer "F.Cu")
		(at 371.877844 -10.916158)
		(property "Reference" "C7G13"
			(at 0 0 0)
			(layer "F.SilkS")
			(hide yes)
			(effects
				(font
					(size 1.27 1.27)
				)
			)
		)
		(property "Value" ""
			(at 0 0 0)
			(layer "F.Fab")
			(effects
				(font
					(size 1.27 1.27)
				)
			)
		)
		(duplicate_pad_numbers_are_jumpers no)
		(fp_rect
			(start -0.3048 0.9906)
			(end 0.3048 -0.1016)
			(stroke
				(width 0)
				(type default)
			)
			(fill no)
			(layer "F.CrtYd")
		)
		(fp_line
			(start -0.3048 -0.1016)
			(end -0.3048 0.9906)
			(stroke
				(width 0.1)
				(type default)
			)
			(layer "F.Fab")
		)
		(fp_line
			(start -0.3048 0.9906)
			(end 0.3048 0.9906)
			(stroke
				(width 0.1)
				(type default)
			)
			(layer "F.Fab")
		)
		(fp_line
			(start 0.3048 -0.1016)
			(end -0.3048 -0.1016)
			(stroke
				(width 0.1)
				(type default)
			)
			(layer "F.Fab")
		)
		(fp_line
			(start 0.3048 0.9906)
			(end 0.3048 -0.1016)
			(stroke
				(width 0.1)
				(type default)
			)
			(layer "F.Fab")
		)
		(pad "1" smd rect
			(at 0 0)
			(size 0.508 0.508)
			(layers "F.Cu" "F.Mask" "F.Paste")
			(net "P3E_CPU0_PE2_SS_TXN<11>")
		)
		(pad "2" smd rect
			(at 0 0.889)
			(size 0.508 0.508)
			(layers "F.Cu" "F.Mask" "F.Paste")
			(net "P3E_CPU0_PE2_SS_C_TXN<11>")
		)
		(zone
			(layer "F.Cu")
			(hatch none 0.5)
			(connect_pads
				(clearance 0)
			)
			(min_thickness 0.25)
			(keepout
				(tracks allowed)
				(vias not_allowed)
				(pads allowed)
				(copperpour not_allowed)
				(footprints allowed)
			)
			(placement
				(enabled no)
				(sheetname "")
			)
			(fill
				(thermal_gap 0.5)
				(thermal_bridge_width 0.5)
				(island_removal_mode 0)
			)
			(polygon
				(pts
					(xy 371.623844 -10.281158) (xy 372.131844 -10.281158) (xy 372.131844 -10.662158) (xy 371.623844 -10.662158)
				)
			)
		)
		(zone
			(layer "F.Cu")
			(hatch none 0.5)
			(connect_pads
				(clearance 0)
			)
			(min_thickness 0.25)
			(keepout
				(tracks not_allowed)
				(vias allowed)
				(pads allowed)
				(copperpour not_allowed)
				(footprints allowed)
			)
			(placement
				(enabled no)
				(sheetname "")
			)
			(fill
				(thermal_gap 0.5)
				(thermal_bridge_width 0.5)
				(island_removal_mode 0)
			)
			(polygon
				(pts
					(xy 371.623844 -10.281158) (xy 372.131844 -10.281158) (xy 372.131844 -10.662158) (xy 371.623844 -10.662158)
				)
			)
		)
	)
	(footprint ""
		(layer "F.Cu")
		(at 29.213556 -31.141162 90)
		(property "Reference" "Q12W3"
			(at 0 0 90)
			(layer "F.SilkS")
			(hide yes)
			(effects
				(font
					(size 1.27 1.27)
				)
			)
		)
		(property "Value" "*"
			(at -4.572 -7.6835 90)
			(unlocked yes)
			(layer "F.Fab")
			(hide yes)
			(effects
				(font
					(size 1.27 1.016)
					(thickness 0.1524)
				)
			)
		)
		(property "Device Type" "BSL308C-H6327-GP_DISCRET-GB1-BA"
			(at -4.572 -9.2075 90)
			(unlocked yes)
			(layer "F.Fab")
			(hide yes)
			(effects
				(font
					(size 1.27 1.016)
					(thickness 0.1524)
				)
			)
		)
		(duplicate_pad_numbers_are_jumpers no)
		(fp_line
			(start 1.102868 -0.081534)
			(end 1.102868 0.081534)
			(stroke
				(width 0.1524)
				(type default)
			)
			(layer "F.SilkS")
		)
		(fp_line
			(start -1.8796 -0.081534)
			(end 1.102868 -0.081534)
			(stroke
				(width 0.1524)
				(type default)
			)
			(layer "F.SilkS")
		)
		(fp_line
			(start -1.8796 -0.081534)
			(end -1.524 0)
			(stroke
				(width 0.1524)
				(type default)
			)
			(layer "F.SilkS")
		)
		(fp_line
			(start -1.524 0)
			(end -1.8796 0.081534)
			(stroke
				(width 0.1524)
				(type default)
			)
			(layer "F.SilkS")
		)
		(fp_line
			(start 1.102868 0.081534)
			(end -1.8796 0.081534)
			(stroke
				(width 0.1524)
				(type default)
			)
			(layer "F.SilkS")
		)
		(fp_line
			(start -1.8796 0.081534)
			(end -1.8796 -0.081534)
			(stroke
				(width 0.1524)
				(type default)
			)
			(layer "F.SilkS")
		)
		(fp_line
			(start -1.7018 0.3048)
			(end -1.7018 1.8796)
			(stroke
				(width 0.508)
				(type default)
			)
			(layer "F.SilkS")
		)
		(fp_poly
			(pts
				(xy -1.179068 0.081534) (xy -1.179068 -0.081534) (xy 1.102868 -0.081534) (xy 1.102868 0.081534)
			)
			(stroke
				(width 0)
				(type default)
			)
			(fill yes)
			(layer "F.SilkS")
		)
		(fp_rect
			(start -1.4478 1.2446)
			(end 1.4478 -1.2446)
			(stroke
				(width 0)
				(type default)
			)
			(fill no)
			(layer "F.CrtYd")
		)
		(fp_poly
			(pts
				(xy -1.4478 -1.23952) (xy -1.9558 -1.23952) (xy -1.9558 2.1336) (xy 1.9558 2.1336) (xy 1.9558 -2.1336)
				(xy -1.9558 -2.1336) (xy -1.9558 -1.2446) (xy 1.4478 -1.2446) (xy 1.4478 1.2446) (xy -1.4478 1.2446)
			)
			(stroke
				(width 0)
				(type default)
			)
			(fill no)
			(layer "F.CrtYd")
		)
		(fp_rect
			(start -1.9558 2.1336)
			(end 1.9558 -2.1336)
			(stroke
				(width 0)
				(type default)
			)
			(fill no)
			(layer "F.Fab")
		)
		(pad "1" smd rect
			(at -0.950468 0.995934 90)
			(size 0.4572 1.27)
			(layers "F.Cu" "F.Mask" "F.Paste")
			(net "PWRGD_PVDDQ_GHJ")
		)
		(pad "2" smd rect
			(at 0 0.995934 90)
			(size 0.4572 1.27)
			(layers "F.Cu" "F.Mask" "F.Paste")
			(net "P12V_NVDIMM_GHJ")
		)
		(pad "3" smd rect
			(at 0.950468 0.995934 90)
			(size 0.4572 1.27)
			(layers "F.Cu" "F.Mask" "F.Paste")
			(net "PWRGD_PVDDQ_GHJ_N")
		)
		(pad "4" smd rect
			(at 0.950468 -0.995934 90)
			(size 0.4572 1.27)
			(layers "F.Cu" "F.Mask" "F.Paste")
			(net "P12V_NVDIMM_GHJ_D")
		)
		(pad "5" smd rect
			(at 0 -0.995934 90)
			(size 0.4572 1.27)
			(layers "F.Cu" "F.Mask" "F.Paste")
			(net "GND")
		)
		(pad "6" smd rect
			(at -0.950468 -0.995934 90)
			(size 0.4572 1.27)
			(layers "F.Cu" "F.Mask" "F.Paste")
			(net "PWRGD_PVDDQ_GHJ_N")
		)
	)
	(footprint ""
		(layer "F.Cu")
		(at 399.763996 -35.803586 -90)
		(property "Reference" "R8G4"
			(at 0 0 270)
			(layer "F.SilkS")
			(hide yes)
			(effects
				(font
					(size 1.27 1.27)
				)
			)
		)
		(property "Value" ""
			(at 0 0 270)
			(layer "F.Fab")
			(effects
				(font
					(size 1.27 1.27)
				)
			)
		)
		(duplicate_pad_numbers_are_jumpers no)
		(fp_poly
			(pts
				(xy -0.2794 -0.1016) (xy 0.2794 -0.1016) (xy 0.2794 0.9906) (xy -0.2794 0.9906)
			)
			(stroke
				(width 0)
				(type default)
			)
			(fill no)
			(layer "F.CrtYd")
		)
		(fp_line
			(start -0.2794 0.9906)
			(end 0.2794 0.9906)
			(stroke
				(width 0.1)
				(type default)
			)
			(layer "F.Fab")
		)
		(fp_line
			(start 0.2794 0.9906)
			(end 0.2794 -0.1016)
			(stroke
				(width 0.1)
				(type default)
			)
			(layer "F.Fab")
		)
		(fp_line
			(start -0.2794 -0.1016)
			(end -0.2794 0.9906)
			(stroke
				(width 0.1)
				(type default)
			)
			(layer "F.Fab")
		)
		(fp_line
			(start 0.2794 -0.1016)
			(end -0.2794 -0.1016)
			(stroke
				(width 0.1)
				(type default)
			)
			(layer "F.Fab")
		)
		(pad "1" smd rect
			(at 0 0 270)
			(size 0.508 0.508)
			(layers "F.Cu" "F.Mask" "F.Paste")
			(net "SMB_OCP_LAN_STBY_LVC3_SCL_R")
		)
		(pad "2" smd rect
			(at 0 0.889 270)
			(size 0.508 0.508)
			(layers "F.Cu" "F.Mask" "F.Paste")
			(net "SMB_OCP_LAN_STBY_LVC3_SCL")
		)
		(zone
			(layer "F.Cu")
			(hatch none 0.5)
			(connect_pads
				(clearance 0)
			)
			(min_thickness 0.25)
			(keepout
				(tracks not_allowed)
				(vias allowed)
				(pads allowed)
				(copperpour not_allowed)
				(footprints allowed)
			)
			(placement
				(enabled no)
				(sheetname "")
			)
			(fill
				(thermal_gap 0.5)
				(thermal_bridge_width 0.5)
				(island_removal_mode 0)
			)
			(polygon
				(pts
					(xy 399.128996 -36.057586) (xy 399.128996 -35.549586) (xy 399.509996 -35.549586) (xy 399.509996 -36.057586)
				)
			)
		)
		(zone
			(layer "F.Cu")
			(hatch none 0.5)
			(connect_pads
				(clearance 0)
			)
			(min_thickness 0.25)
			(keepout
				(tracks allowed)
				(vias not_allowed)
				(pads allowed)
				(copperpour not_allowed)
				(footprints allowed)
			)
			(placement
				(enabled no)
				(sheetname "")
			)
			(fill
				(thermal_gap 0.5)
				(thermal_bridge_width 0.5)
				(island_removal_mode 0)
			)
			(polygon
				(pts
					(xy 399.509996 -36.057586) (xy 399.509996 -35.549586) (xy 399.128996 -35.549586) (xy 399.128996 -36.057586)
				)
			)
		)
	)
	(footprint ""
		(layer "F.Cu")
		(at 418.6428 -86.4235)
		(property "Reference" "C8E2"
			(at 0 0 0)
			(layer "F.SilkS")
			(hide yes)
			(effects
				(font
					(size 1.27 1.27)
				)
			)
		)
		(property "Value" ""
			(at 0 0 0)
			(layer "F.Fab")
			(effects
				(font
					(size 1.27 1.27)
				)
			)
		)
		(duplicate_pad_numbers_are_jumpers no)
		(fp_poly
			(pts
				(xy 0.3048 -0.1016) (xy 0.3048 0.9906) (xy -0.3048 0.9906) (xy -0.3048 -0.1016)
			)
			(stroke
				(width 0)
				(type default)
			)
			(fill no)
			(layer "F.CrtYd")
		)
		(fp_line
			(start -0.3048 -0.1016)
			(end -0.3048 0.9906)
			(stroke
				(width 0.1)
				(type default)
			)
			(layer "F.Fab")
		)
		(fp_line
			(start -0.3048 0.9906)
			(end 0.3048 0.9906)
			(stroke
				(width 0.1)
				(type default)
			)
			(layer "F.Fab")
		)
		(fp_line
			(start 0.3048 -0.1016)
			(end -0.3048 -0.1016)
			(stroke
				(width 0.1)
				(type default)
			)
			(layer "F.Fab")
		)
		(fp_line
			(start 0.3048 0.9906)
			(end 0.3048 -0.1016)
			(stroke
				(width 0.1)
				(type default)
			)
			(layer "F.Fab")
		)
		(pad "1" smd rect
			(at 0 0)
			(size 0.508 0.508)
			(layers "F.Cu" "F.Mask" "F.Paste")
			(net "P3V3_STBY")
		)
		(pad "2" smd rect
			(at 0 0.889)
			(size 0.508 0.508)
			(layers "F.Cu" "F.Mask" "F.Paste")
			(net "GND")
		)
		(zone
			(layer "F.Cu")
			(hatch none 0.5)
			(connect_pads
				(clearance 0)
			)
			(min_thickness 0.25)
			(keepout
				(tracks allowed)
				(vias not_allowed)
				(pads allowed)
				(copperpour not_allowed)
				(footprints allowed)
			)
			(placement
				(enabled no)
				(sheetname "")
			)
			(fill
				(thermal_gap 0.5)
				(thermal_bridge_width 0.5)
				(island_removal_mode 0)
			)
			(polygon
				(pts
					(xy 418.3888 -86.1695) (xy 418.8968 -86.1695) (xy 418.8968 -85.7885) (xy 418.3888 -85.7885)
				)
			)
		)
		(zone
			(layer "F.Cu")
			(hatch none 0.5)
			(connect_pads
				(clearance 0)
			)
			(min_thickness 0.25)
			(keepout
				(tracks not_allowed)
				(vias allowed)
				(pads allowed)
				(copperpour not_allowed)
				(footprints allowed)
			)
			(placement
				(enabled no)
				(sheetname "")
			)
			(fill
				(thermal_gap 0.5)
				(thermal_bridge_width 0.5)
				(island_removal_mode 0)
			)
			(polygon
				(pts
					(xy 418.3888 -85.7885) (xy 418.8968 -85.7885) (xy 418.8968 -86.1695) (xy 418.3888 -86.1695)
				)
			)
		)
	)
	(footprint ""
		(layer "F.Cu")
		(at 450.1642 -147.7645 180)
		(property "Reference" "U25W11"
			(at 2.159 -1.57988 180)
			(unlocked yes)
			(layer "F.SilkS")
			(effects
				(font
					(size 0.4064 0.254)
					(thickness 0.1524)
				)
				(justify left)
			)
		)
		(property "Value" ""
			(at 0 0 180)
			(layer "F.Fab")
			(effects
				(font
					(size 1.27 1.27)
				)
			)
		)
		(duplicate_pad_numbers_are_jumpers no)
		(fp_line
			(start 4.4323 4.52628)
			(end 1.5367 4.52628)
			(stroke
				(width 0.1524)
				(type default)
			)
			(layer "F.SilkS")
		)
		(fp_line
			(start 4.4323 -0.64008)
			(end 4.4323 4.52628)
			(stroke
				(width 0.1524)
				(type default)
			)
			(layer "F.SilkS")
		)
		(fp_line
			(start 3.302 0.49022)
			(end 3.302 -0.64008)
			(stroke
				(width 0.1524)
				(type default)
			)
			(layer "F.SilkS")
		)
		(fp_line
			(start 2.667 0.49022)
			(end 3.302 0.49022)
			(stroke
				(width 0.1524)
				(type default)
			)
			(layer "F.SilkS")
		)
		(fp_line
			(start 2.667 -0.64008)
			(end 2.667 0.49022)
			(stroke
				(width 0.1524)
				(type default)
			)
			(layer "F.SilkS")
		)
		(fp_line
			(start 1.5367 4.52628)
			(end 1.5367 -0.64008)
			(stroke
				(width 0.1524)
				(type default)
			)
			(layer "F.SilkS")
		)
		(fp_line
			(start 1.5367 -0.64008)
			(end 4.4323 -0.64008)
			(stroke
				(width 0.1524)
				(type default)
			)
			(layer "F.SilkS")
		)
		(fp_circle
			(center -1.224788 -0.581152)
			(end -1.351788 -0.581152)
			(stroke
				(width 0.254)
				(type default)
			)
			(fill no)
			(layer "F.SilkS")
		)
		(fp_poly
			(pts
				(xy 0.7366 4.54152) (xy 0.7366 -0.64008) (xy 4.7244 -0.64008) (xy 5.2324 -0.64008) (xy 5.2324 4.54152)
				(xy 4.7244 4.54152)
			)
			(stroke
				(width 0)
				(type default)
			)
			(fill no)
			(layer "F.CrtYd")
		)
		(fp_line
			(start 5.2324 4.54152)
			(end 0.7366 4.54152)
			(stroke
				(width 0.1)
				(type default)
			)
			(layer "F.Fab")
		)
		(fp_line
			(start 5.2324 -0.64008)
			(end 5.2324 4.54152)
			(stroke
				(width 0.1)
				(type default)
			)
			(layer "F.Fab")
		)
		(fp_line
			(start 3.302 0.49022)
			(end 3.302 -0.64008)
			(stroke
				(width 0.1)
				(type default)
			)
			(layer "F.Fab")
		)
		(fp_line
			(start 2.667 0.49022)
			(end 3.302 0.49022)
			(stroke
				(width 0.1)
				(type default)
			)
			(layer "F.Fab")
		)
		(fp_line
			(start 2.667 -0.64008)
			(end 2.667 0.49022)
			(stroke
				(width 0.1)
				(type default)
			)
			(layer "F.Fab")
		)
		(fp_line
			(start 0.7366 4.54152)
			(end 0.7366 -0.64008)
			(stroke
				(width 0.1)
				(type default)
			)
			(layer "F.Fab")
		)
		(fp_line
			(start 0.7366 -0.64008)
			(end 5.2324 -0.64008)
			(stroke
				(width 0.1)
				(type default)
			)
			(layer "F.Fab")
		)
		(fp_circle
			(center -1.612138 -0.684784)
			(end -1.739138 -0.684784)
			(stroke
				(width 0.254)
				(type default)
			)
			(fill no)
			(layer "F.Fab")
		)
		(pad "1" smd rect
			(at 0 0 180)
			(size 2.159 0.381)
			(layers "F.Cu" "F.Mask" "F.Paste")
			(net "PD_GTL2014_DIR_6")
		)
		(pad "2" smd rect
			(at 0 0.65024 180)
			(size 2.159 0.381)
			(layers "F.Cu" "F.Mask" "F.Paste")
			(net "PD_GTL2014_6_B0")
		)
		(pad "3" smd rect
			(at 0 1.30048 180)
			(size 2.159 0.381)
			(layers "F.Cu" "F.Mask" "F.Paste")
			(net "XDP_PRDY_N")
		)
		(pad "4" smd rect
			(at 0 1.95072 180)
			(size 2.159 0.381)
			(layers "F.Cu" "F.Mask" "F.Paste")
			(net "P0V7_GTL2014_VREF_6")
		)
		(pad "5" smd rect
			(at 0 2.60096 180)
			(size 2.159 0.381)
			(layers "F.Cu" "F.Mask" "F.Paste")
			(net "PD_GTL2014_6_B2")
		)
		(pad "6" smd rect
			(at 0 3.2512 180)
			(size 2.159 0.381)
			(layers "F.Cu" "F.Mask" "F.Paste")
			(net "XDP_TDO")
		)
		(pad "7" smd rect
			(at 0 3.90144 180)
			(size 2.159 0.381)
			(layers "F.Cu" "F.Mask" "F.Paste")
			(net "GND")
		)
		(pad "8" smd rect
			(at 5.969 3.90144 180)
			(size 2.159 0.381)
			(layers "F.Cu" "F.Mask" "F.Paste")
			(net "GND")
		)
		(pad "9" smd rect
			(at 5.969 3.2512 180)
			(size 2.159 0.381)
			(layers "F.Cu" "F.Mask" "F.Paste")
			(net "JTAG_BMC_BUF_TDO_R")
		)
		(pad "10" smd rect
			(at 5.969 2.60096 180)
			(size 2.159 0.381)
			(layers "F.Cu" "F.Mask" "F.Paste")
			(net "TP_GTL2014_6_A2")
		)
		(pad "11" smd rect
			(at 5.969 1.95072 180)
			(size 2.159 0.381)
			(layers "F.Cu" "F.Mask" "F.Paste")
			(net "GND")
		)
		(pad "12" smd rect
			(at 5.969 1.30048 180)
			(size 2.159 0.381)
			(layers "F.Cu" "F.Mask" "F.Paste")
			(net "BMC_PRDY_N")
		)
		(pad "13" smd rect
			(at 5.969 0.65024 180)
			(size 2.159 0.381)
			(layers "F.Cu" "F.Mask" "F.Paste")
			(net "TP_GTL2014_6_A0")
		)
		(pad "14" smd rect
			(at 5.969 0 180)
			(size 2.159 0.381)
			(layers "F.Cu" "F.Mask" "F.Paste")
			(net "P3V3_STBY")
		)
	)
	(footprint ""
		(layer "F.Cu")
		(at 490.2581 -46.7614 90)
		(property "Reference" "R9E8"
			(at 0 0 90)
			(layer "F.SilkS")
			(hide yes)
			(effects
				(font
					(size 1.27 1.27)
				)
			)
		)
		(property "Value" ""
			(at 0 0 90)
			(layer "F.Fab")
			(effects
				(font
					(size 1.27 1.27)
				)
			)
		)
		(duplicate_pad_numbers_are_jumpers no)
		(fp_poly
			(pts
				(xy -0.2794 -0.1016) (xy 0.2794 -0.1016) (xy 0.2794 0.9906) (xy -0.2794 0.9906)
			)
			(stroke
				(width 0)
				(type default)
			)
			(fill no)
			(layer "F.CrtYd")
		)
		(fp_line
			(start 0.2794 -0.1016)
			(end -0.2794 -0.1016)
			(stroke
				(width 0.1)
				(type default)
			)
			(layer "F.Fab")
		)
		(fp_line
			(start -0.2794 -0.1016)
			(end -0.2794 0.9906)
			(stroke
				(width 0.1)
				(type default)
			)
			(layer "F.Fab")
		)
		(fp_line
			(start 0.2794 0.9906)
			(end 0.2794 -0.1016)
			(stroke
				(width 0.1)
				(type default)
			)
			(layer "F.Fab")
		)
		(fp_line
			(start -0.2794 0.9906)
			(end 0.2794 0.9906)
			(stroke
				(width 0.1)
				(type default)
			)
			(layer "F.Fab")
		)
		(pad "1" smd rect
			(at 0 0 90)
			(size 0.508 0.508)
			(layers "F.Cu" "F.Mask" "F.Paste")
			(net "SPI_NIC_SCLK_R")
		)
		(pad "2" smd rect
			(at 0 0.889 90)
			(size 0.508 0.508)
			(layers "F.Cu" "F.Mask" "F.Paste")
			(net "SPI_NIC_SCLK")
		)
		(zone
			(layer "F.Cu")
			(hatch none 0.5)
			(connect_pads
				(clearance 0)
			)
			(min_thickness 0.25)
			(keepout
				(tracks allowed)
				(vias not_allowed)
				(pads allowed)
				(copperpour not_allowed)
				(footprints allowed)
			)
			(placement
				(enabled no)
				(sheetname "")
			)
			(fill
				(thermal_gap 0.5)
				(thermal_bridge_width 0.5)
				(island_removal_mode 0)
			)
			(polygon
				(pts
					(xy 490.5121 -46.5074) (xy 490.5121 -47.0154) (xy 490.8931 -47.0154) (xy 490.8931 -46.5074)
				)
			)
		)
		(zone
			(layer "F.Cu")
			(hatch none 0.5)
			(connect_pads
				(clearance 0)
			)
			(min_thickness 0.25)
			(keepout
				(tracks not_allowed)
				(vias allowed)
				(pads allowed)
				(copperpour not_allowed)
				(footprints allowed)
			)
			(placement
				(enabled no)
				(sheetname "")
			)
			(fill
				(thermal_gap 0.5)
				(thermal_bridge_width 0.5)
				(island_removal_mode 0)
			)
			(polygon
				(pts
					(xy 490.8931 -46.5074) (xy 490.8931 -47.0154) (xy 490.5121 -47.0154) (xy 490.5121 -46.5074)
				)
			)
		)
	)
	(footprint ""
		(layer "F.Cu")
		(at 402.830792 -10.917936)
		(property "Reference" "C8G3"
			(at 0 0 0)
			(layer "F.SilkS")
			(hide yes)
			(effects
				(font
					(size 1.27 1.27)
				)
			)
		)
		(property "Value" ""
			(at 0 0 0)
			(layer "F.Fab")
			(effects
				(font
					(size 1.27 1.27)
				)
			)
		)
		(duplicate_pad_numbers_are_jumpers no)
		(fp_rect
			(start -0.3048 0.9906)
			(end 0.3048 -0.1016)
			(stroke
				(width 0)
				(type default)
			)
			(fill no)
			(layer "F.CrtYd")
		)
		(fp_line
			(start -0.3048 -0.1016)
			(end -0.3048 0.9906)
			(stroke
				(width 0.1)
				(type default)
			)
			(layer "F.Fab")
		)
		(fp_line
			(start -0.3048 0.9906)
			(end 0.3048 0.9906)
			(stroke
				(width 0.1)
				(type default)
			)
			(layer "F.Fab")
		)
		(fp_line
			(start 0.3048 -0.1016)
			(end -0.3048 -0.1016)
			(stroke
				(width 0.1)
				(type default)
			)
			(layer "F.Fab")
		)
		(fp_line
			(start 0.3048 0.9906)
			(end 0.3048 -0.1016)
			(stroke
				(width 0.1)
				(type default)
			)
			(layer "F.Fab")
		)
		(pad "1" smd rect
			(at 0 0)
			(size 0.508 0.508)
			(layers "F.Cu" "F.Mask" "F.Paste")
			(net "P3E_CPU0_PE2_SS_TXP<3>")
		)
		(pad "2" smd rect
			(at 0 0.889)
			(size 0.508 0.508)
			(layers "F.Cu" "F.Mask" "F.Paste")
			(net "P3E_CPU0_PE2_SS_C_TXP<3>")
		)
		(zone
			(layer "F.Cu")
			(hatch none 0.5)
			(connect_pads
				(clearance 0)
			)
			(min_thickness 0.25)
			(keepout
				(tracks not_allowed)
				(vias allowed)
				(pads allowed)
				(copperpour not_allowed)
				(footprints allowed)
			)
			(placement
				(enabled no)
				(sheetname "")
			)
			(fill
				(thermal_gap 0.5)
				(thermal_bridge_width 0.5)
				(island_removal_mode 0)
			)
			(polygon
				(pts
					(xy 402.576792 -10.282936) (xy 403.084792 -10.282936) (xy 403.084792 -10.663936) (xy 402.576792 -10.663936)
				)
			)
		)
		(zone
			(layer "F.Cu")
			(hatch none 0.5)
			(connect_pads
				(clearance 0)
			)
			(min_thickness 0.25)
			(keepout
				(tracks allowed)
				(vias not_allowed)
				(pads allowed)
				(copperpour not_allowed)
				(footprints allowed)
			)
			(placement
				(enabled no)
				(sheetname "")
			)
			(fill
				(thermal_gap 0.5)
				(thermal_bridge_width 0.5)
				(island_removal_mode 0)
			)
			(polygon
				(pts
					(xy 402.576792 -10.282936) (xy 403.084792 -10.282936) (xy 403.084792 -10.663936) (xy 402.576792 -10.663936)
				)
			)
		)
	)
	(footprint ""
		(layer "F.Cu")
		(at 271.898872 -77.636116)
		(property "Reference" "C5D35"
			(at 0 0 0)
			(layer "F.SilkS")
			(hide yes)
			(effects
				(font
					(size 1.27 1.27)
				)
			)
		)
		(property "Value" ""
			(at 0 0 0)
			(layer "F.Fab")
			(effects
				(font
					(size 1.27 1.27)
				)
			)
		)
		(duplicate_pad_numbers_are_jumpers no)
		(fp_poly
			(pts
				(xy -0.4953 -0.2032) (xy 0.4953 -0.2032) (xy 0.4953 1.6002) (xy -0.4953 1.6002)
			)
			(stroke
				(width 0)
				(type default)
			)
			(fill no)
			(layer "F.CrtYd")
		)
		(fp_line
			(start -0.4953 -0.2032)
			(end 0.4953 -0.2032)
			(stroke
				(width 0.1)
				(type default)
			)
			(layer "F.Fab")
		)
		(fp_line
			(start -0.4953 1.6002)
			(end -0.4953 -0.2032)
			(stroke
				(width 0.1)
				(type default)
			)
			(layer "F.Fab")
		)
		(fp_line
			(start 0.4953 -0.2032)
			(end 0.4953 1.6002)
			(stroke
				(width 0.1)
				(type default)
			)
			(layer "F.Fab")
		)
		(fp_line
			(start 0.4953 1.6002)
			(end -0.4953 1.6002)
			(stroke
				(width 0.1)
				(type default)
			)
			(layer "F.Fab")
		)
		(pad "1" smd rect
			(at 0 0)
			(size 0.762 0.889)
			(layers "F.Cu" "F.Mask" "F.Paste")
			(net "PVCCMCP_CPU0")
		)
		(pad "2" smd rect
			(at 0 1.397)
			(size 0.762 0.889)
			(layers "F.Cu" "F.Mask" "F.Paste")
			(net "GND")
		)
		(zone
			(layer "F.Cu")
			(hatch none 0.5)
			(connect_pads
				(clearance 0)
			)
			(min_thickness 0.25)
			(keepout
				(tracks not_allowed)
				(vias allowed)
				(pads allowed)
				(copperpour not_allowed)
				(footprints allowed)
			)
			(placement
				(enabled no)
				(sheetname "")
			)
			(fill
				(thermal_gap 0.5)
				(thermal_bridge_width 0.5)
				(island_removal_mode 0)
			)
			(polygon
				(pts
					(xy 271.517872 -77.191616) (xy 272.279872 -77.191616) (xy 272.279872 -76.683616) (xy 271.517872 -76.683616)
				)
			)
		)
	)
	(footprint ""
		(layer "F.Cu")
		(at 124.222002 -77.449934 180)
		(property "Reference" "XRU2"
			(at -17.763998 32.632396 0)
			(unlocked yes)
			(layer "F.SilkS")
			(effects
				(font
					(size 0.7874 0.5842)
					(thickness 0.1524)
				)
				(justify left)
			)
		)
		(property "Value" ""
			(at 0 0 180)
			(layer "F.Fab")
			(effects
				(font
					(size 1.27 1.27)
				)
			)
		)
		(duplicate_pad_numbers_are_jumpers no)
		(fp_line
			(start 19.221958 -10.649966)
			(end 19.221958 -29.399992)
			(stroke
				(width 0.1524)
				(type default)
			)
			(layer "F.SilkS")
		)
		(fp_line
			(start 19.221958 -29.399992)
			(end 18.62201 -29.399992)
			(stroke
				(width 0.1524)
				(type default)
			)
			(layer "F.SilkS")
		)
		(fp_line
			(start 18.62201 28.599892)
			(end 18.62201 8.850122)
			(stroke
				(width 0.1524)
				(type default)
			)
			(layer "F.SilkS")
		)
		(fp_line
			(start 18.62201 27.599894)
			(end 18.62201 8.850122)
			(stroke
				(width 0.1524)
				(type default)
			)
			(layer "F.SilkS")
		)
		(fp_line
			(start 18.62201 8.850122)
			(end 12.761976 8.850122)
			(stroke
				(width 0.1524)
				(type default)
			)
			(layer "F.SilkS")
		)
		(fp_line
			(start 18.62201 8.850122)
			(end 12.761976 8.850122)
			(stroke
				(width 0.1524)
				(type default)
			)
			(layer "F.SilkS")
		)
		(fp_line
			(start 18.62201 -29.399992)
			(end 18.62201 -30.39999)
			(stroke
				(width 0.1524)
				(type default)
			)
			(layer "F.SilkS")
		)
		(fp_line
			(start 18.62201 -30.39999)
			(end 17.622012 -30.39999)
			(stroke
				(width 0.1524)
				(type default)
			)
			(layer "F.SilkS")
		)
		(fp_line
			(start 17.622012 28.599892)
			(end 18.62201 28.599892)
			(stroke
				(width 0.1524)
				(type default)
			)
			(layer "F.SilkS")
		)
		(fp_line
			(start 17.622012 27.599894)
			(end 17.622012 28.599892)
			(stroke
				(width 0.1524)
				(type default)
			)
			(layer "F.SilkS")
		)
		(fp_line
			(start 17.622012 -29.399992)
			(end -14.777974 -29.399992)
			(stroke
				(width 0.1524)
				(type default)
			)
			(layer "F.SilkS")
		)
		(fp_line
			(start 17.622012 -30.39999)
			(end 17.622012 -29.399992)
			(stroke
				(width 0.1524)
				(type default)
			)
			(layer "F.SilkS")
		)
		(fp_line
			(start 12.761976 8.850122)
			(end 6.171946 4.890008)
			(stroke
				(width 0.1524)
				(type default)
			)
			(layer "F.SilkS")
		)
		(fp_line
			(start 12.761976 8.850122)
			(end 6.171946 4.890008)
			(stroke
				(width 0.1524)
				(type default)
			)
			(layer "F.SilkS")
		)
		(fp_line
			(start 12.761976 -10.649966)
			(end 19.221958 -10.649966)
			(stroke
				(width 0.1524)
				(type default)
			)
			(layer "F.SilkS")
		)
		(fp_line
			(start 12.761976 -10.649966)
			(end 19.221958 -10.649966)
			(stroke
				(width 0.1524)
				(type default)
			)
			(layer "F.SilkS")
		)
		(fp_line
			(start 6.171946 4.890008)
			(end 6.171946 -6.690106)
			(stroke
				(width 0.1524)
				(type default)
			)
			(layer "F.SilkS")
		)
		(fp_line
			(start 6.171946 4.890008)
			(end 6.171946 -6.690106)
			(stroke
				(width 0.1524)
				(type default)
			)
			(layer "F.SilkS")
		)
		(fp_line
			(start 6.171946 -6.690106)
			(end 12.761976 -10.649966)
			(stroke
				(width 0.1524)
				(type default)
			)
			(layer "F.SilkS")
		)
		(fp_line
			(start 6.171946 -6.690106)
			(end 12.761976 -10.649966)
			(stroke
				(width 0.1524)
				(type default)
			)
			(layer "F.SilkS")
		)
		(fp_line
			(start -14.777974 30.150054)
			(end -14.777974 27.599894)
			(stroke
				(width 0.1524)
				(type default)
			)
			(layer "F.SilkS")
		)
		(fp_line
			(start -14.777974 27.599894)
			(end 17.622012 27.599894)
			(stroke
				(width 0.1524)
				(type default)
			)
			(layer "F.SilkS")
		)
		(fp_line
			(start -14.777974 -29.399992)
			(end -14.777974 -31.949898)
			(stroke
				(width 0.1524)
				(type default)
			)
			(layer "F.SilkS")
		)
		(fp_line
			(start -14.777974 -31.949898)
			(end -21.77796 -31.949898)
			(stroke
				(width 0.1524)
				(type default)
			)
			(layer "F.SilkS")
		)
		(fp_line
			(start -17.777968 2.100072)
			(end -18.278094 2.100072)
			(stroke
				(width 0.1524)
				(type default)
			)
			(layer "F.SilkS")
		)
		(fp_line
			(start -17.777968 -3.899916)
			(end -17.777968 2.100072)
			(stroke
				(width 0.1524)
				(type default)
			)
			(layer "F.SilkS")
		)
		(fp_line
			(start -18.278094 3.599942)
			(end -21.77796 7.100062)
			(stroke
				(width 0.1524)
				(type default)
			)
			(layer "F.SilkS")
		)
		(fp_line
			(start -18.278094 2.100072)
			(end -18.278094 3.599942)
			(stroke
				(width 0.1524)
				(type default)
			)
			(layer "F.SilkS")
		)
		(fp_line
			(start -18.278094 -3.899916)
			(end -17.777968 -3.899916)
			(stroke
				(width 0.1524)
				(type default)
			)
			(layer "F.SilkS")
		)
		(fp_line
			(start -18.278094 -5.40004)
			(end -18.278094 -3.899916)
			(stroke
				(width 0.1524)
				(type default)
			)
			(layer "F.SilkS")
		)
		(fp_line
			(start -21.77796 30.150054)
			(end -14.777974 30.150054)
			(stroke
				(width 0.1524)
				(type default)
			)
			(layer "F.SilkS")
		)
		(fp_line
			(start -21.77796 7.100062)
			(end -21.77796 30.150054)
			(stroke
				(width 0.1524)
				(type default)
			)
			(layer "F.SilkS")
		)
		(fp_line
			(start -21.77796 -8.899906)
			(end -18.278094 -5.40004)
			(stroke
				(width 0.1524)
				(type default)
			)
			(layer "F.SilkS")
		)
		(fp_line
			(start -21.77796 -31.949898)
			(end -21.77796 -8.899906)
			(stroke
				(width 0.1524)
				(type default)
			)
			(layer "F.SilkS")
		)
		(fp_circle
			(center -28.829 -29.215334)
			(end -28.956 -29.215334)
			(stroke
				(width 0.254)
				(type default)
			)
			(fill no)
			(layer "F.SilkS")
		)
		(fp_poly
			(pts
				(xy -21.762212 30.150054) (xy -14.777974 30.150054) (xy -14.777974 27.599894) (xy 17.622012 27.599894)
				(xy 17.622012 28.599892) (xy 18.62201 28.599892) (xy 18.62201 8.850122) (xy 12.761976 8.850122)
				(xy 6.171946 4.890008) (xy 6.171946 -6.690106) (xy 12.761976 -10.649966) (xy 19.221958 -10.649966)
				(xy 19.221958 -29.399992) (xy 18.62201 -29.399992) (xy 18.62201 -30.39999) (xy 17.622012 -30.39999)
				(xy 17.622012 -29.399992) (xy -14.777974 -29.399992) (xy -14.777974 -31.949898) (xy -21.77796 -31.949898)
				(xy -21.77796 -8.899906) (xy -18.278094 -5.40004) (xy -18.278094 -3.899916) (xy -17.777968 -3.899916)
				(xy -17.777968 2.100072) (xy -18.278094 2.100072) (xy -18.278094 3.599942) (xy -21.77796 7.100062)
				(xy -21.77796 15.059406) (xy -20.051776 15.059406) (xy -20.048728 15.001748) (xy -20.04441 14.966442)
				(xy -20.036282 14.912086) (xy -20.02536 14.859762) (xy -20.007326 14.788134) (xy -19.98345 14.720062)
				(xy -19.96821 14.680692) (xy -19.937222 14.614144) (xy -19.910552 14.565376) (xy -19.878294 14.512544)
				(xy -19.833082 14.449044) (xy -19.790918 14.396466) (xy -19.746468 14.348714) (xy -19.70151 14.305026)
				(xy -19.629628 14.236954) (xy -19.548856 14.18336) (xy -19.442684 14.125956) (xy -19.368516 14.092936)
				(xy -19.202654 14.039342) (xy -19.046698 14.018514) (xy -18.893282 14.020546) (xy -18.758662 14.041882)
				(xy -18.615152 14.083792) (xy -18.402554 14.173962) (xy -18.269712 14.279118) (xy -18.178018 14.370558)
				(xy -18.112232 14.437614) (xy -18.027396 14.586204) (xy -17.924272 14.817598) (xy -17.897348 15.018766)
				(xy -17.888458 15.160498) (xy -17.906238 15.300198) (xy -17.959832 15.489936) (xy -18.057114 15.682976)
				(xy -18.231358 15.893034) (xy -18.479008 16.060928) (xy -18.689574 16.13916) (xy -18.864834 16.174466)
				(xy -19.001994 16.17726) (xy -19.118326 16.169894) (xy -19.228816 16.147542) (xy -19.45767 16.08074)
				(xy -19.611086 15.978886) (xy -19.714972 15.893034) (xy -19.798792 15.807182) (xy -19.89709 15.676372)
				(xy -19.983196 15.507716) (xy -20.0279 15.380462) (xy -20.056856 15.181834) (xy -20.051776 15.059914)
				(xy -21.77796 15.059914)
			)
			(stroke
				(width 0)
				(type default)
			)
			(fill no)
			(layer "F.CrtYd")
		)
		(fp_line
			(start -14.777974 30.150054)
			(end -21.77796 30.150054)
			(stroke
				(width 0.1)
				(type default)
			)
			(layer "F.Fab")
		)
		(fp_line
			(start -14.777974 27.420062)
			(end -14.777974 30.150054)
			(stroke
				(width 0.1)
				(type default)
			)
			(layer "F.Fab")
		)
		(fp_line
			(start -14.777974 -29.219906)
			(end -18.840958 -29.219906)
			(stroke
				(width 0.1)
				(type default)
			)
			(layer "F.Fab")
		)
		(fp_line
			(start -14.777974 -31.949898)
			(end -14.777974 -29.219906)
			(stroke
				(width 0.1)
				(type default)
			)
			(layer "F.Fab")
		)
		(fp_line
			(start -18.840958 27.420062)
			(end -14.777974 27.420062)
			(stroke
				(width 0.1)
				(type default)
			)
			(layer "F.Fab")
		)
		(fp_line
			(start -18.840958 22.649942)
			(end -18.840958 27.420062)
			(stroke
				(width 0.1)
				(type default)
			)
			(layer "F.Fab")
		)
		(fp_line
			(start -18.840958 22.649942)
			(end -19.777964 22.649942)
			(stroke
				(width 0.1)
				(type default)
			)
			(layer "F.Fab")
		)
		(fp_line
			(start -18.840958 -24.45004)
			(end -19.777964 -24.45004)
			(stroke
				(width 0.1)
				(type default)
			)
			(layer "F.Fab")
		)
		(fp_line
			(start -18.840958 -29.219906)
			(end -18.840958 -24.45004)
			(stroke
				(width 0.1)
				(type default)
			)
			(layer "F.Fab")
		)
		(fp_line
			(start -19.777964 22.649942)
			(end -18.840958 22.649942)
			(stroke
				(width 0.1)
				(type default)
			)
			(layer "F.Fab")
		)
		(fp_line
			(start -19.777964 22.649942)
			(end -19.777964 15.81658)
			(stroke
				(width 0.1)
				(type default)
			)
			(layer "F.Fab")
		)
		(fp_line
			(start -19.777964 15.81658)
			(end -19.777964 22.649942)
			(stroke
				(width 0.1)
				(type default)
			)
			(layer "F.Fab")
		)
		(fp_line
			(start -19.777964 5.100066)
			(end -19.777964 14.383258)
			(stroke
				(width 0.1)
				(type default)
			)
			(layer "F.Fab")
		)
		(fp_line
			(start -19.777964 -6.89991)
			(end -21.77796 -8.899906)
			(stroke
				(width 0.1)
				(type default)
			)
			(layer "F.Fab")
		)
		(fp_line
			(start -19.777964 -24.45004)
			(end -19.777964 -6.89991)
			(stroke
				(width 0.1)
				(type default)
			)
			(layer "F.Fab")
		)
		(fp_line
			(start -21.77796 30.150054)
			(end -21.77796 7.100062)
			(stroke
				(width 0.1)
				(type default)
			)
			(layer "F.Fab")
		)
		(fp_line
			(start -21.77796 7.100062)
			(end -19.777964 5.100066)
			(stroke
				(width 0.1)
				(type default)
			)
			(layer "F.Fab")
		)
		(fp_line
			(start -21.77796 -8.899906)
			(end -21.77796 -31.949898)
			(stroke
				(width 0.1)
				(type default)
			)
			(layer "F.Fab")
		)
		(fp_line
			(start -21.77796 -31.949898)
			(end -14.777974 -31.949898)
			(stroke
				(width 0.1)
				(type default)
			)
			(layer "F.Fab")
		)
		(fp_arc
			(start -19.777964 15.81658)
			(mid -20.051913 15.099951)
			(end -19.777964 14.383258)
			(stroke
				(width 0.1)
				(type default)
			)
			(layer "F.Fab")
		)
	)
	(footprint ""
		(layer "F.Cu")
		(at 281.178 -75.946 90)
		(property "Reference" "R6D6"
			(at 0 0 90)
			(layer "F.SilkS")
			(hide yes)
			(effects
				(font
					(size 1.27 1.27)
				)
			)
		)
		(property "Value" ""
			(at 0 0 90)
			(layer "F.Fab")
			(effects
				(font
					(size 1.27 1.27)
				)
			)
		)
		(duplicate_pad_numbers_are_jumpers no)
		(fp_rect
			(start -0.2794 -0.1016)
			(end 0.2794 0.9906)
			(stroke
				(width 0)
				(type default)
			)
			(fill no)
			(layer "F.CrtYd")
		)
		(fp_line
			(start 0.2794 -0.1016)
			(end -0.2794 -0.1016)
			(stroke
				(width 0.1)
				(type default)
			)
			(layer "F.Fab")
		)
		(fp_line
			(start -0.2794 -0.1016)
			(end -0.2794 0.9906)
			(stroke
				(width 0.1)
				(type default)
			)
			(layer "F.Fab")
		)
		(fp_line
			(start 0.2794 0.9906)
			(end 0.2794 -0.1016)
			(stroke
				(width 0.1)
				(type default)
			)
			(layer "F.Fab")
		)
		(fp_line
			(start -0.2794 0.9906)
			(end 0.2794 0.9906)
			(stroke
				(width 0.1)
				(type default)
			)
			(layer "F.Fab")
		)
		(pad "1" smd rect
			(at 0 0 90)
			(size 0.508 0.508)
			(layers "F.Cu" "F.Mask" "F.Paste")
			(net "GND")
		)
		(pad "2" smd rect
			(at 0 0.889 90)
			(size 0.508 0.508)
			(layers "F.Cu" "F.Mask" "F.Paste")
			(net "PD_CPU0_TXT_PLTEN")
		)
		(zone
			(layer "F.Cu")
			(hatch none 0.5)
			(connect_pads
				(clearance 0)
			)
			(min_thickness 0.25)
			(keepout
				(tracks allowed)
				(vias not_allowed)
				(pads allowed)
				(copperpour not_allowed)
				(footprints allowed)
			)
			(placement
				(enabled no)
				(sheetname "")
			)
			(fill
				(thermal_gap 0.5)
				(thermal_bridge_width 0.5)
				(island_removal_mode 0)
			)
			(polygon
				(pts
					(xy 281.432 -75.692) (xy 281.813 -75.692) (xy 281.813 -76.2) (xy 281.432 -76.2)
				)
			)
		)
		(zone
			(layer "F.Cu")
			(hatch none 0.5)
			(connect_pads
				(clearance 0)
			)
			(min_thickness 0.25)
			(keepout
				(tracks not_allowed)
				(vias allowed)
				(pads allowed)
				(copperpour not_allowed)
				(footprints allowed)
			)
			(placement
				(enabled no)
				(sheetname "")
			)
			(fill
				(thermal_gap 0.5)
				(thermal_bridge_width 0.5)
				(island_removal_mode 0)
			)
			(polygon
				(pts
					(xy 281.432 -75.692) (xy 281.813 -75.692) (xy 281.813 -76.2) (xy 281.432 -76.2)
				)
			)
		)
	)
	(footprint ""
		(layer "F.Cu")
		(at 261.942072 -77.636116)
		(property "Reference" "C5D27"
			(at 0 0 0)
			(layer "F.SilkS")
			(hide yes)
			(effects
				(font
					(size 1.27 1.27)
				)
			)
		)
		(property "Value" ""
			(at 0 0 0)
			(layer "F.Fab")
			(effects
				(font
					(size 1.27 1.27)
				)
			)
		)
		(duplicate_pad_numbers_are_jumpers no)
		(fp_poly
			(pts
				(xy -0.4953 -0.2032) (xy 0.4953 -0.2032) (xy 0.4953 1.6002) (xy -0.4953 1.6002)
			)
			(stroke
				(width 0)
				(type default)
			)
			(fill no)
			(layer "F.CrtYd")
		)
		(fp_line
			(start -0.4953 -0.2032)
			(end 0.4953 -0.2032)
			(stroke
				(width 0.1)
				(type default)
			)
			(layer "F.Fab")
		)
		(fp_line
			(start -0.4953 1.6002)
			(end -0.4953 -0.2032)
			(stroke
				(width 0.1)
				(type default)
			)
			(layer "F.Fab")
		)
		(fp_line
			(start 0.4953 -0.2032)
			(end 0.4953 1.6002)
			(stroke
				(width 0.1)
				(type default)
			)
			(layer "F.Fab")
		)
		(fp_line
			(start 0.4953 1.6002)
			(end -0.4953 1.6002)
			(stroke
				(width 0.1)
				(type default)
			)
			(layer "F.Fab")
		)
		(pad "1" smd rect
			(at 0 0)
			(size 0.762 0.889)
			(layers "F.Cu" "F.Mask" "F.Paste")
			(net "PVCCIN_CPU0")
		)
		(pad "2" smd rect
			(at 0 1.397)
			(size 0.762 0.889)
			(layers "F.Cu" "F.Mask" "F.Paste")
			(net "GND")
		)
		(zone
			(layer "F.Cu")
			(hatch none 0.5)
			(connect_pads
				(clearance 0)
			)
			(min_thickness 0.25)
			(keepout
				(tracks not_allowed)
				(vias allowed)
				(pads allowed)
				(copperpour not_allowed)
				(footprints allowed)
			)
			(placement
				(enabled no)
				(sheetname "")
			)
			(fill
				(thermal_gap 0.5)
				(thermal_bridge_width 0.5)
				(island_removal_mode 0)
			)
			(polygon
				(pts
					(xy 261.561072 -77.191616) (xy 262.323072 -77.191616) (xy 262.323072 -76.683616) (xy 261.561072 -76.683616)
				)
			)
		)
	)
	(footprint ""
		(layer "F.Cu")
		(at 163.576 -81.788 -90)
		(property "Reference" "R4D16"
			(at 0 0 270)
			(layer "F.SilkS")
			(hide yes)
			(effects
				(font
					(size 1.27 1.27)
				)
			)
		)
		(property "Value" ""
			(at 0 0 270)
			(layer "F.Fab")
			(effects
				(font
					(size 1.27 1.27)
				)
			)
		)
		(duplicate_pad_numbers_are_jumpers no)
		(fp_poly
			(pts
				(xy -0.2794 -0.1016) (xy 0.2794 -0.1016) (xy 0.2794 0.9906) (xy -0.2794 0.9906)
			)
			(stroke
				(width 0)
				(type default)
			)
			(fill no)
			(layer "F.CrtYd")
		)
		(fp_line
			(start -0.2794 0.9906)
			(end 0.2794 0.9906)
			(stroke
				(width 0.1)
				(type default)
			)
			(layer "F.Fab")
		)
		(fp_line
			(start 0.2794 0.9906)
			(end 0.2794 -0.1016)
			(stroke
				(width 0.1)
				(type default)
			)
			(layer "F.Fab")
		)
		(fp_line
			(start -0.2794 -0.1016)
			(end -0.2794 0.9906)
			(stroke
				(width 0.1)
				(type default)
			)
			(layer "F.Fab")
		)
		(fp_line
			(start 0.2794 -0.1016)
			(end -0.2794 -0.1016)
			(stroke
				(width 0.1)
				(type default)
			)
			(layer "F.Fab")
		)
		(pad "1" smd rect
			(at 0 0 270)
			(size 0.508 0.508)
			(layers "F.Cu" "F.Mask" "F.Paste")
			(net "CLK_100M_CPU1_PE_REFCLK_R_DN")
		)
		(pad "2" smd rect
			(at 0 0.889 270)
			(size 0.508 0.508)
			(layers "F.Cu" "F.Mask" "F.Paste")
			(net "CLK_100M_CPU1_PE_REFCLK_DN")
		)
		(zone
			(layer "F.Cu")
			(hatch none 0.5)
			(connect_pads
				(clearance 0)
			)
			(min_thickness 0.25)
			(keepout
				(tracks not_allowed)
				(vias allowed)
				(pads allowed)
				(copperpour not_allowed)
				(footprints allowed)
			)
			(placement
				(enabled no)
				(sheetname "")
			)
			(fill
				(thermal_gap 0.5)
				(thermal_bridge_width 0.5)
				(island_removal_mode 0)
			)
			(polygon
				(pts
					(xy 162.941 -82.042) (xy 162.941 -81.534) (xy 163.322 -81.534) (xy 163.322 -82.042)
				)
			)
		)
		(zone
			(layer "F.Cu")
			(hatch none 0.5)
			(connect_pads
				(clearance 0)
			)
			(min_thickness 0.25)
			(keepout
				(tracks allowed)
				(vias not_allowed)
				(pads allowed)
				(copperpour not_allowed)
				(footprints allowed)
			)
			(placement
				(enabled no)
				(sheetname "")
			)
			(fill
				(thermal_gap 0.5)
				(thermal_bridge_width 0.5)
				(island_removal_mode 0)
			)
			(polygon
				(pts
					(xy 163.322 -82.042) (xy 163.322 -81.534) (xy 162.941 -81.534) (xy 162.941 -82.042)
				)
			)
		)
	)
	(footprint ""
		(layer "F.Cu")
		(at 458.39888 -26.17978 180)
		(property "Reference" "R9F30"
			(at 0 0 180)
			(layer "F.SilkS")
			(hide yes)
			(effects
				(font
					(size 1.27 1.27)
				)
			)
		)
		(property "Value" ""
			(at 0 0 180)
			(layer "F.Fab")
			(effects
				(font
					(size 1.27 1.27)
				)
			)
		)
		(duplicate_pad_numbers_are_jumpers no)
		(fp_poly
			(pts
				(xy -0.2794 -0.1016) (xy 0.2794 -0.1016) (xy 0.2794 0.9906) (xy -0.2794 0.9906)
			)
			(stroke
				(width 0)
				(type default)
			)
			(fill no)
			(layer "F.CrtYd")
		)
		(fp_line
			(start 0.2794 0.9906)
			(end 0.2794 -0.1016)
			(stroke
				(width 0.1)
				(type default)
			)
			(layer "F.Fab")
		)
		(fp_line
			(start 0.2794 -0.1016)
			(end -0.2794 -0.1016)
			(stroke
				(width 0.1)
				(type default)
			)
			(layer "F.Fab")
		)
		(fp_line
			(start -0.2794 0.9906)
			(end 0.2794 0.9906)
			(stroke
				(width 0.1)
				(type default)
			)
			(layer "F.Fab")
		)
		(fp_line
			(start -0.2794 -0.1016)
			(end -0.2794 0.9906)
			(stroke
				(width 0.1)
				(type default)
			)
			(layer "F.Fab")
		)
		(pad "1" smd rect
			(at 0 0 180)
			(size 0.508 0.508)
			(layers "F.Cu" "F.Mask" "F.Paste")
			(net "P3V3_STBY")
		)
		(pad "2" smd rect
			(at 0 0.889 180)
			(size 0.508 0.508)
			(layers "F.Cu" "F.Mask" "F.Paste")
			(net "FM_BMC_FAULT_LED_N")
		)
		(zone
			(layer "F.Cu")
			(hatch none 0.5)
			(connect_pads
				(clearance 0)
			)
			(min_thickness 0.25)
			(keepout
				(tracks not_allowed)
				(vias allowed)
				(pads allowed)
				(copperpour not_allowed)
				(footprints allowed)
			)
			(placement
				(enabled no)
				(sheetname "")
			)
			(fill
				(thermal_gap 0.5)
				(thermal_bridge_width 0.5)
				(island_removal_mode 0)
			)
			(polygon
				(pts
					(xy 458.65288 -26.81478) (xy 458.14488 -26.81478) (xy 458.14488 -26.43378) (xy 458.65288 -26.43378)
				)
			)
		)
		(zone
			(layer "F.Cu")
			(hatch none 0.5)
			(connect_pads
				(clearance 0)
			)
			(min_thickness 0.25)
			(keepout
				(tracks allowed)
				(vias not_allowed)
				(pads allowed)
				(copperpour not_allowed)
				(footprints allowed)
			)
			(placement
				(enabled no)
				(sheetname "")
			)
			(fill
				(thermal_gap 0.5)
				(thermal_bridge_width 0.5)
				(island_removal_mode 0)
			)
			(polygon
				(pts
					(xy 458.65288 -26.43378) (xy 458.14488 -26.43378) (xy 458.14488 -26.81478) (xy 458.65288 -26.81478)
				)
			)
		)
	)
	(footprint ""
		(layer "F.Cu")
		(at 132.650484 12.014454 -90)
		(property "Reference" "T1P10"
			(at 0 0 270)
			(layer "F.SilkS")
			(hide yes)
			(effects
				(font
					(size 1.27 1.27)
				)
			)
		)
		(property "Value" "*"
			(at -3.302 1.12395 270)
			(unlocked yes)
			(layer "F.Fab")
			(hide yes)
			(effects
				(font
					(size 0.889 0.889)
					(thickness 0.1524)
				)
			)
		)
		(property "Device Type" "TPAD-DIFF-4P-GP_DISCRET-GB3-TPA"
			(at -3.302 -0.40005 270)
			(unlocked yes)
			(layer "F.Fab")
			(hide yes)
			(effects
				(font
					(size 0.889 0.889)
					(thickness 0.1524)
				)
			)
		)
		(duplicate_pad_numbers_are_jumpers no)
		(fp_line
			(start -2.286 2.286)
			(end 2.286 2.286)
			(stroke
				(width 0.1524)
				(type default)
			)
			(layer "F.SilkS")
		)
		(fp_line
			(start 2.286 2.286)
			(end 2.286 -2.286)
			(stroke
				(width 0.1524)
				(type default)
			)
			(layer "F.SilkS")
		)
		(fp_line
			(start -2.286 -2.286)
			(end -2.286 2.286)
			(stroke
				(width 0.1524)
				(type default)
			)
			(layer "F.SilkS")
		)
		(fp_line
			(start 2.286 -2.286)
			(end -2.286 -2.286)
			(stroke
				(width 0.1524)
				(type default)
			)
			(layer "F.SilkS")
		)
		(fp_line
			(start -2.413 -2.413)
			(end -2.413 -1.143)
			(stroke
				(width 0.4064)
				(type default)
			)
			(layer "F.SilkS")
		)
		(fp_line
			(start -1.143 -2.413)
			(end -2.413 -2.413)
			(stroke
				(width 0.4064)
				(type default)
			)
			(layer "F.SilkS")
		)
		(fp_rect
			(start -2.54 2.54)
			(end 2.54 -2.54)
			(stroke
				(width 0)
				(type default)
			)
			(fill no)
			(layer "F.CrtYd")
		)
		(fp_rect
			(start -2.54 2.54)
			(end 2.54 -2.54)
			(stroke
				(width 0)
				(type default)
			)
			(fill no)
			(layer "F.Fab")
		)
		(pad "1" thru_hole circle
			(at -1.27 -1.27 270)
			(size 1.524 1.524)
			(drill 0.9144)
			(layers "*.Cu" "*.Mask")
			(remove_unused_layers no)
			(net "L10_73OHM_6INCH_DP")
			(clearance -0.0508)
			(thermal_gap 0.127)
			(padstack
				(mode front_inner_back)
				(layer "Inner"
					(shape circle)
					(size 1.1684 1.1684)
					(clearance 0.127)
				)
				(layer "B.Cu"
					(shape circle)
					(size 1.524 1.524)
					(clearance -0.0508)
				)
			)
		)
		(pad "2" thru_hole circle
			(at 1.27 -1.27 270)
			(size 1.524 1.524)
			(drill 0.9144)
			(layers "*.Cu" "*.Mask")
			(remove_unused_layers no)
			(net "L10_73OHM_6INCH_DN")
			(clearance -0.0508)
			(thermal_gap 0.127)
			(padstack
				(mode front_inner_back)
				(layer "Inner"
					(shape circle)
					(size 1.1684 1.1684)
					(clearance 0.127)
				)
				(layer "B.Cu"
					(shape circle)
					(size 1.524 1.524)
					(clearance -0.0508)
				)
			)
		)
		(pad "GND1" thru_hole rect
			(at -1.27 1.27 270)
			(size 1.524 1.524)
			(drill 0.9144)
			(layers "*.Cu" "*.Mask")
			(remove_unused_layers no)
			(net "GND")
			(clearance -0.0508)
			(thermal_gap 0.127)
			(padstack
				(mode front_inner_back)
				(layer "Inner"
					(shape circle)
					(size 1.1684 1.1684)
					(clearance 0.127)
				)
				(layer "B.Cu"
					(shape rect)
					(size 1.524 1.524)
					(clearance -0.0508)
				)
			)
		)
		(pad "GND2" thru_hole rect
			(at 1.27 1.27 270)
			(size 1.524 1.524)
			(drill 0.9144)
			(layers "*.Cu" "*.Mask")
			(remove_unused_layers no)
			(net "GND")
			(clearance -0.0508)
			(thermal_gap 0.127)
			(padstack
				(mode front_inner_back)
				(layer "Inner"
					(shape circle)
					(size 1.1684 1.1684)
					(clearance 0.127)
				)
				(layer "B.Cu"
					(shape rect)
					(size 1.524 1.524)
					(clearance -0.0508)
				)
			)
		)
	)
	(footprint ""
		(layer "F.Cu")
		(at 13.716 -54.917848 90)
		(property "Reference" "C1E12"
			(at 0 0 90)
			(layer "F.SilkS")
			(hide yes)
			(effects
				(font
					(size 1.27 1.27)
				)
			)
		)
		(property "Value" ""
			(at 0 0 90)
			(layer "F.Fab")
			(effects
				(font
					(size 1.27 1.27)
				)
			)
		)
		(duplicate_pad_numbers_are_jumpers no)
		(fp_rect
			(start 0.7239 -0.2159)
			(end -0.7239 1.9939)
			(stroke
				(width 0)
				(type default)
			)
			(fill no)
			(layer "F.CrtYd")
		)
		(fp_line
			(start 0.7239 -0.2159)
			(end -0.7239 -0.2159)
			(stroke
				(width 0.1)
				(type default)
			)
			(layer "F.Fab")
		)
		(fp_line
			(start -0.7239 -0.2159)
			(end -0.7239 1.9939)
			(stroke
				(width 0.1)
				(type default)
			)
			(layer "F.Fab")
		)
		(fp_line
			(start 0.7239 1.9939)
			(end 0.7239 -0.2159)
			(stroke
				(width 0.1)
				(type default)
			)
			(layer "F.Fab")
		)
		(fp_line
			(start -0.7239 1.9939)
			(end 0.7239 1.9939)
			(stroke
				(width 0.1)
				(type default)
			)
			(layer "F.Fab")
		)
		(pad "1" smd rect
			(at 0 0 90)
			(size 1.27 1.016)
			(layers "F.Cu" "F.Mask" "F.Paste")
			(net "P12V_PSU")
		)
		(pad "2" smd rect
			(at 0 1.778 90)
			(size 1.27 1.016)
			(layers "F.Cu" "F.Mask" "F.Paste")
			(net "GND")
		)
		(zone
			(layer "F.Cu")
			(hatch none 0.5)
			(connect_pads
				(clearance 0)
			)
			(min_thickness 0.25)
			(keepout
				(tracks not_allowed)
				(vias allowed)
				(pads allowed)
				(copperpour not_allowed)
				(footprints allowed)
			)
			(placement
				(enabled no)
				(sheetname "")
			)
			(fill
				(thermal_gap 0.5)
				(thermal_bridge_width 0.5)
				(island_removal_mode 0)
			)
			(polygon
				(pts
					(xy 14.224 -55.552848) (xy 14.224 -54.282848) (xy 14.986 -54.282848) (xy 14.986 -55.552848)
				)
			)
		)
	)
	(footprint ""
		(layer "F.Cu")
		(at 392.176 -67.691)
		(property "Reference" "EU7E2"
			(at 2.90195 0.67056 90)
			(unlocked yes)
			(layer "F.SilkS")
			(effects
				(font
					(size 0.7874 0.5842)
					(thickness 0.1524)
				)
				(justify left)
			)
		)
		(property "Value" ""
			(at 0 0 0)
			(layer "F.Fab")
			(effects
				(font
					(size 1.27 1.27)
				)
			)
		)
		(duplicate_pad_numbers_are_jumpers no)
		(fp_line
			(start -1.82499 -1.82499)
			(end -1.82499 -1.571498)
			(stroke
				(width 0.1524)
				(type default)
			)
			(layer "F.SilkS")
		)
		(fp_line
			(start -1.82499 1.571498)
			(end -1.82499 1.82499)
			(stroke
				(width 0.1524)
				(type default)
			)
			(layer "F.SilkS")
		)
		(fp_line
			(start -1.82499 1.82499)
			(end -1.321562 1.82499)
			(stroke
				(width 0.1524)
				(type default)
			)
			(layer "F.SilkS")
		)
		(fp_line
			(start -1.321562 -1.82499)
			(end -1.82499 -1.82499)
			(stroke
				(width 0.1524)
				(type default)
			)
			(layer "F.SilkS")
		)
		(fp_line
			(start 1.321562 1.82499)
			(end 1.82499 1.82499)
			(stroke
				(width 0.1524)
				(type default)
			)
			(layer "F.SilkS")
		)
		(fp_line
			(start 1.82499 -1.82499)
			(end 1.321562 -1.82499)
			(stroke
				(width 0.1524)
				(type default)
			)
			(layer "F.SilkS")
		)
		(fp_line
			(start 1.82499 -1.571498)
			(end 1.82499 -1.82499)
			(stroke
				(width 0.1524)
				(type default)
			)
			(layer "F.SilkS")
		)
		(fp_line
			(start 1.82499 1.82499)
			(end 1.82499 1.571498)
			(stroke
				(width 0.1524)
				(type default)
			)
			(layer "F.SilkS")
		)
		(fp_circle
			(center -1.287272 -2.56667)
			(end -1.160272 -2.56667)
			(stroke
				(width 0.254)
				(type default)
			)
			(fill no)
			(layer "F.SilkS")
		)
		(fp_poly
			(pts
				(xy -2.09169 -2.09169) (xy -2.09169 -1.32969) (xy -1.32969 -2.09169)
			)
			(stroke
				(width 0)
				(type default)
			)
			(fill yes)
			(layer "F.SilkS")
		)
		(fp_poly
			(pts
				(xy -1.0287 1.0287) (xy -1.0287 -1.0287) (xy -0.381 -1.0287) (xy -0.381 -2.1336) (xy -0.1905 -2.1336)
				(xy -0.1905 -1.397) (xy 0.1905 -1.397) (xy 0.1905 -2.1336) (xy 0.381 -2.1336) (xy 0.381 -1.0287)
				(xy 1.0287 -1.0287) (xy 1.0287 1.0287) (xy 0.381 1.0287) (xy 0.381 2.1336) (xy 0.1905 2.1336) (xy 0.1905 1.397)
				(xy -0.1905 1.397) (xy -0.1905 2.1336) (xy -0.381 2.1336) (xy -0.381 1.0287)
			)
			(stroke
				(width 0)
				(type default)
			)
			(fill yes)
			(layer "F.Paste")
		)
		(fp_rect
			(start -1.82499 1.82499)
			(end 1.82499 -1.82499)
			(stroke
				(width 0)
				(type default)
			)
			(fill no)
			(layer "F.CrtYd")
		)
		(fp_line
			(start -1.82499 -1.82499)
			(end 1.82499 -1.82499)
			(stroke
				(width 0.1)
				(type default)
			)
			(layer "F.Fab")
		)
		(fp_line
			(start -1.82499 1.82499)
			(end -1.82499 -1.82499)
			(stroke
				(width 0.1)
				(type default)
			)
			(layer "F.Fab")
		)
		(fp_line
			(start 1.82499 -1.82499)
			(end 1.82499 1.82499)
			(stroke
				(width 0.1)
				(type default)
			)
			(layer "F.Fab")
		)
		(fp_line
			(start 1.82499 1.82499)
			(end -1.82499 1.82499)
			(stroke
				(width 0.1)
				(type default)
			)
			(layer "F.Fab")
		)
		(fp_circle
			(center -1.287272 -2.56667)
			(end -1.160272 -2.56667)
			(stroke
				(width 0.254)
				(type default)
			)
			(fill no)
			(layer "F.Fab")
		)
		(pad "1" smd rect
			(at -0.750062 -1.7145)
			(size 0.2794 0.8382)
			(layers "F.Cu" "F.Mask" "F.Paste")
			(net "VR_P5V_STBY_RT")
		)
		(pad "2" smd rect
			(at -1.7145 -0.999998)
			(size 0.8382 0.2794)
			(layers "F.Cu" "F.Mask" "F.Paste")
			(net "GND")
		)
		(pad "3" smd rect
			(at -1.7145 -0.500126)
			(size 0.8382 0.2794)
			(layers "F.Cu" "F.Mask" "F.Paste")
			(net "GND")
		)
		(pad "4" smd rect
			(at -1.7145 0)
			(size 0.8382 0.2794)
			(layers "F.Cu" "F.Mask" "F.Paste")
			(net "VR_FET_SW_P5V_STBY_PVIN")
		)
		(pad "5" smd rect
			(at -1.7145 0.500126)
			(size 0.8382 0.2794)
			(layers "F.Cu" "F.Mask" "F.Paste")
			(net "VR_FET_SW_P5V_STBY_PVIN")
		)
		(pad "6" smd rect
			(at -1.7145 0.999998)
			(size 0.8382 0.2794)
			(layers "F.Cu" "F.Mask" "F.Paste")
			(net "VR_P5V_STBY_VIN")
		)
		(pad "7" smd rect
			(at -0.750062 1.7145)
			(size 0.2794 0.8382)
			(layers "F.Cu" "F.Mask" "F.Paste")
			(net "VR_P5V_STBY_VSENSE")
		)
		(pad "8" smd rect
			(at 0.750062 1.7145)
			(size 0.2794 0.8382)
			(layers "F.Cu" "F.Mask" "F.Paste")
			(net "VR_P5V_STBY_COMP")
		)
		(pad "9" smd rect
			(at 1.7145 0.999998)
			(size 0.8382 0.2794)
			(layers "F.Cu" "F.Mask" "F.Paste")
			(net "VR_P5V_STBY_SS")
		)
		(pad "10" smd rect
			(at 1.7145 0.500126)
			(size 0.8382 0.2794)
			(layers "F.Cu" "F.Mask" "F.Paste")
			(net "VR_P5V_STBY_EN")
		)
		(pad "11" smd rect
			(at 1.7145 0)
			(size 0.8382 0.2794)
			(layers "F.Cu" "F.Mask" "F.Paste")
			(net "VR_P5V_STBY_PHASE")
		)
		(pad "12" smd rect
			(at 1.7145 -0.500126)
			(size 0.8382 0.2794)
			(layers "F.Cu" "F.Mask" "F.Paste")
			(net "VR_P5V_STBY_PHASE")
		)
		(pad "13" smd rect
			(at 1.7145 -0.999998)
			(size 0.8382 0.2794)
			(layers "F.Cu" "F.Mask" "F.Paste")
			(net "VR_P5V_STBY_BOOT")
		)
		(pad "14" smd rect
			(at 0.750062 -1.7145)
			(size 0.2794 0.8382)
			(layers "F.Cu" "F.Mask" "F.Paste")
			(net "PWRGD_P5V_STBY_R")
		)
		(pad "15" smd custom
			(at 0 0)
			(size 0.51435 0.51435)
			(layers "F.Cu" "F.Mask" "F.Paste")
			(net "GND")
			(options
				(clearance outline)
				(anchor circle)
			)
			(primitives
				(gr_poly
					(pts
						(xy -0.381 -2.1336) (xy -0.381 -1.0287) (xy -1.0287 -1.0287) (xy -1.0287 1.0287) (xy -0.381 1.0287)
						(xy -0.381 2.1336) (xy -0.1905 2.1336) (xy -0.1905 1.397) (xy 0.1905 1.397) (xy 0.1905 2.1336)
						(xy 0.381 2.1336) (xy 0.381 1.0287) (xy 1.0287 1.0287) (xy 1.0287 -1.0287) (xy 0.381 -1.0287)
						(xy 0.381 -2.1336) (xy 0.1905 -2.1336) (xy 0.1905 -1.397) (xy -0.1905 -1.397) (xy -0.1905 -2.1336)
					)
					(width 0)
					(fill yes)
				)
			)
		)
	)
	(footprint ""
		(layer "F.Cu")
		(at 252.1585 -140.208 -90)
		(property "Reference" "C5A13"
			(at 1.848866 0.752348 270)
			(unlocked yes)
			(layer "F.SilkS")
			(effects
				(font
					(size 1.27 0.9652)
					(thickness 0.1524)
				)
			)
		)
		(property "Value" ""
			(at 0 0 270)
			(layer "F.Fab")
			(effects
				(font
					(size 1.27 1.27)
				)
			)
		)
		(duplicate_pad_numbers_are_jumpers no)
		(fp_rect
			(start -0.500126 1.598422)
			(end 0.500126 -0.201422)
			(stroke
				(width 0)
				(type default)
			)
			(fill no)
			(layer "F.CrtYd")
		)
		(fp_line
			(start -0.500126 1.598422)
			(end -0.500126 -0.201422)
			(stroke
				(width 0.1)
				(type default)
			)
			(layer "F.Fab")
		)
		(fp_line
			(start 0.500126 1.598422)
			(end -0.500126 1.598422)
			(stroke
				(width 0.1)
				(type default)
			)
			(layer "F.Fab")
		)
		(fp_line
			(start -0.500126 -0.201422)
			(end 0.500126 -0.201422)
			(stroke
				(width 0.1)
				(type default)
			)
			(layer "F.Fab")
		)
		(fp_line
			(start 0.500126 -0.201422)
			(end 0.500126 1.598422)
			(stroke
				(width 0.1)
				(type default)
			)
			(layer "F.Fab")
		)
		(pad "1" smd rect
			(at 0 0 180)
			(size 0.889 0.9906)
			(layers "F.Cu" "F.Mask" "F.Paste")
			(net "PVDDQ_DEF")
		)
		(pad "2" smd rect
			(at 0 1.397 180)
			(size 0.889 0.9906)
			(layers "F.Cu" "F.Mask" "F.Paste")
			(net "GND")
		)
		(zone
			(layer "F.Cu")
			(hatch none 0.5)
			(connect_pads
				(clearance 0)
			)
			(min_thickness 0.25)
			(keepout
				(tracks not_allowed)
				(vias allowed)
				(pads allowed)
				(copperpour not_allowed)
				(footprints allowed)
			)
			(placement
				(enabled no)
				(sheetname "")
			)
			(fill
				(thermal_gap 0.5)
				(thermal_bridge_width 0.5)
				(island_removal_mode 0)
			)
			(polygon
				(pts
					(xy 251.206 -140.7033) (xy 251.206 -139.7127) (xy 251.714 -139.7127) (xy 251.714 -140.7033)
				)
			)
		)
		(zone
			(layer "F.Cu")
			(hatch none 0.5)
			(connect_pads
				(clearance 0)
			)
			(min_thickness 0.25)
			(keepout
				(tracks allowed)
				(vias not_allowed)
				(pads allowed)
				(copperpour not_allowed)
				(footprints allowed)
			)
			(placement
				(enabled no)
				(sheetname "")
			)
			(fill
				(thermal_gap 0.5)
				(thermal_bridge_width 0.5)
				(island_removal_mode 0)
			)
			(polygon
				(pts
					(xy 251.206 -140.7033) (xy 251.206 -139.7127) (xy 251.714 -139.7127) (xy 251.714 -140.7033)
				)
			)
		)
	)
	(footprint ""
		(layer "F.Cu")
		(at 194.564 -22.507194 180)
		(property "Reference" "R4F5"
			(at 0 0 180)
			(layer "F.SilkS")
			(hide yes)
			(effects
				(font
					(size 1.27 1.27)
				)
			)
		)
		(property "Value" ""
			(at 0 0 180)
			(layer "F.Fab")
			(effects
				(font
					(size 1.27 1.27)
				)
			)
		)
		(duplicate_pad_numbers_are_jumpers no)
		(fp_poly
			(pts
				(xy -0.2794 -0.1016) (xy 0.2794 -0.1016) (xy 0.2794 0.9906) (xy -0.2794 0.9906)
			)
			(stroke
				(width 0)
				(type default)
			)
			(fill no)
			(layer "F.CrtYd")
		)
		(fp_line
			(start 0.2794 0.9906)
			(end 0.2794 -0.1016)
			(stroke
				(width 0.1)
				(type default)
			)
			(layer "F.Fab")
		)
		(fp_line
			(start 0.2794 -0.1016)
			(end -0.2794 -0.1016)
			(stroke
				(width 0.1)
				(type default)
			)
			(layer "F.Fab")
		)
		(fp_line
			(start -0.2794 0.9906)
			(end 0.2794 0.9906)
			(stroke
				(width 0.1)
				(type default)
			)
			(layer "F.Fab")
		)
		(fp_line
			(start -0.2794 -0.1016)
			(end -0.2794 0.9906)
			(stroke
				(width 0.1)
				(type default)
			)
			(layer "F.Fab")
		)
		(pad "1" smd rect
			(at 0 0 180)
			(size 0.508 0.508)
			(layers "F.Cu" "F.Mask" "F.Paste")
			(net "M_A_VREF")
		)
		(pad "2" smd rect
			(at 0 0.889 180)
			(size 0.508 0.508)
			(layers "F.Cu" "F.Mask" "F.Paste")
			(net "GND")
		)
		(zone
			(layer "F.Cu")
			(hatch none 0.5)
			(connect_pads
				(clearance 0)
			)
			(min_thickness 0.25)
			(keepout
				(tracks not_allowed)
				(vias allowed)
				(pads allowed)
				(copperpour not_allowed)
				(footprints allowed)
			)
			(placement
				(enabled no)
				(sheetname "")
			)
			(fill
				(thermal_gap 0.5)
				(thermal_bridge_width 0.5)
				(island_removal_mode 0)
			)
			(polygon
				(pts
					(xy 194.818 -23.142194) (xy 194.31 -23.142194) (xy 194.31 -22.761194) (xy 194.818 -22.761194)
				)
			)
		)
		(zone
			(layer "F.Cu")
			(hatch none 0.5)
			(connect_pads
				(clearance 0)
			)
			(min_thickness 0.25)
			(keepout
				(tracks allowed)
				(vias not_allowed)
				(pads allowed)
				(copperpour not_allowed)
				(footprints allowed)
			)
			(placement
				(enabled no)
				(sheetname "")
			)
			(fill
				(thermal_gap 0.5)
				(thermal_bridge_width 0.5)
				(island_removal_mode 0)
			)
			(polygon
				(pts
					(xy 194.818 -22.761194) (xy 194.31 -22.761194) (xy 194.31 -23.142194) (xy 194.818 -23.142194)
				)
			)
		)
	)
	(footprint ""
		(layer "F.Cu")
		(at 411.086046 -22.196552)
		(property "Reference" "C25W7"
			(at -0.8382 -0.67818 0)
			(unlocked yes)
			(layer "F.SilkS")
			(effects
				(font
					(size 0.4064 0.254)
					(thickness 0.1524)
				)
				(justify left)
			)
		)
		(property "Value" ""
			(at 0 0 0)
			(layer "F.Fab")
			(effects
				(font
					(size 1.27 1.27)
				)
			)
		)
		(duplicate_pad_numbers_are_jumpers no)
		(fp_poly
			(pts
				(xy 0.3048 -0.1016) (xy 0.3048 0.9906) (xy -0.3048 0.9906) (xy -0.3048 -0.1016)
			)
			(stroke
				(width 0)
				(type default)
			)
			(fill no)
			(layer "F.CrtYd")
		)
		(fp_line
			(start -0.3048 -0.1016)
			(end -0.3048 0.9906)
			(stroke
				(width 0.1)
				(type default)
			)
			(layer "F.Fab")
		)
		(fp_line
			(start -0.3048 0.9906)
			(end 0.3048 0.9906)
			(stroke
				(width 0.1)
				(type default)
			)
			(layer "F.Fab")
		)
		(fp_line
			(start 0.3048 -0.1016)
			(end -0.3048 -0.1016)
			(stroke
				(width 0.1)
				(type default)
			)
			(layer "F.Fab")
		)
		(fp_line
			(start 0.3048 0.9906)
			(end 0.3048 -0.1016)
			(stroke
				(width 0.1)
				(type default)
			)
			(layer "F.Fab")
		)
		(pad "1" smd rect
			(at 0 0)
			(size 0.508 0.508)
			(layers "F.Cu" "F.Mask" "F.Paste")
			(net "P3V3_STBY_BMC_ADCVREFP")
		)
		(pad "2" smd rect
			(at 0 0.889)
			(size 0.508 0.508)
			(layers "F.Cu" "F.Mask" "F.Paste")
			(net "VCC_ADCAV3V3")
		)
		(zone
			(layer "F.Cu")
			(hatch none 0.5)
			(connect_pads
				(clearance 0)
			)
			(min_thickness 0.25)
			(keepout
				(tracks allowed)
				(vias not_allowed)
				(pads allowed)
				(copperpour not_allowed)
				(footprints allowed)
			)
			(placement
				(enabled no)
				(sheetname "")
			)
			(fill
				(thermal_gap 0.5)
				(thermal_bridge_width 0.5)
				(island_removal_mode 0)
			)
			(polygon
				(pts
					(xy 410.832046 -21.942552) (xy 411.340046 -21.942552) (xy 411.340046 -21.561552) (xy 410.832046 -21.561552)
				)
			)
		)
		(zone
			(layer "F.Cu")
			(hatch none 0.5)
			(connect_pads
				(clearance 0)
			)
			(min_thickness 0.25)
			(keepout
				(tracks not_allowed)
				(vias allowed)
				(pads allowed)
				(copperpour not_allowed)
				(footprints allowed)
			)
			(placement
				(enabled no)
				(sheetname "")
			)
			(fill
				(thermal_gap 0.5)
				(thermal_bridge_width 0.5)
				(island_removal_mode 0)
			)
			(polygon
				(pts
					(xy 410.832046 -21.561552) (xy 411.340046 -21.561552) (xy 411.340046 -21.942552) (xy 410.832046 -21.942552)
				)
			)
		)
	)
	(footprint ""
		(layer "F.Cu")
		(at 264.453624 -69.885814 -90)
		(property "Reference" "C5D54"
			(at 0 0 270)
			(layer "F.SilkS")
			(hide yes)
			(effects
				(font
					(size 1.27 1.27)
				)
			)
		)
		(property "Value" ""
			(at 0 0 270)
			(layer "F.Fab")
			(effects
				(font
					(size 1.27 1.27)
				)
			)
		)
		(duplicate_pad_numbers_are_jumpers no)
		(fp_poly
			(pts
				(xy -0.4953 -0.2032) (xy 0.4953 -0.2032) (xy 0.4953 1.6002) (xy -0.4953 1.6002)
			)
			(stroke
				(width 0)
				(type default)
			)
			(fill no)
			(layer "F.CrtYd")
		)
		(fp_line
			(start -0.4953 1.6002)
			(end -0.4953 -0.2032)
			(stroke
				(width 0.1)
				(type default)
			)
			(layer "F.Fab")
		)
		(fp_line
			(start 0.4953 1.6002)
			(end -0.4953 1.6002)
			(stroke
				(width 0.1)
				(type default)
			)
			(layer "F.Fab")
		)
		(fp_line
			(start -0.4953 -0.2032)
			(end 0.4953 -0.2032)
			(stroke
				(width 0.1)
				(type default)
			)
			(layer "F.Fab")
		)
		(fp_line
			(start 0.4953 -0.2032)
			(end 0.4953 1.6002)
			(stroke
				(width 0.1)
				(type default)
			)
			(layer "F.Fab")
		)
		(pad "1" smd rect
			(at 0 0 270)
			(size 0.762 0.889)
			(layers "F.Cu" "F.Mask" "F.Paste")
			(net "PVDDQ_ABC")
		)
		(pad "2" smd rect
			(at 0 1.397 270)
			(size 0.762 0.889)
			(layers "F.Cu" "F.Mask" "F.Paste")
			(net "GND")
		)
		(zone
			(layer "F.Cu")
			(hatch none 0.5)
			(connect_pads
				(clearance 0)
			)
			(min_thickness 0.25)
			(keepout
				(tracks not_allowed)
				(vias allowed)
				(pads allowed)
				(copperpour not_allowed)
				(footprints allowed)
			)
			(placement
				(enabled no)
				(sheetname "")
			)
			(fill
				(thermal_gap 0.5)
				(thermal_bridge_width 0.5)
				(island_removal_mode 0)
			)
			(polygon
				(pts
					(xy 264.009124 -70.266814) (xy 264.009124 -69.504814) (xy 263.501124 -69.504814) (xy 263.501124 -70.266814)
				)
			)
		)
	)
	(footprint ""
		(layer "F.Cu")
		(at 401.8915 -37.9984 90)
		(property "Reference" "R1L7"
			(at 0 0 90)
			(layer "F.SilkS")
			(hide yes)
			(effects
				(font
					(size 1.27 1.27)
				)
			)
		)
		(property "Value" ""
			(at 0 0 90)
			(layer "F.Fab")
			(effects
				(font
					(size 1.27 1.27)
				)
			)
		)
		(duplicate_pad_numbers_are_jumpers no)
		(fp_poly
			(pts
				(xy -0.2794 -0.1016) (xy 0.2794 -0.1016) (xy 0.2794 0.9906) (xy -0.2794 0.9906)
			)
			(stroke
				(width 0)
				(type default)
			)
			(fill no)
			(layer "F.CrtYd")
		)
		(fp_line
			(start 0.2794 -0.1016)
			(end -0.2794 -0.1016)
			(stroke
				(width 0.1)
				(type default)
			)
			(layer "F.Fab")
		)
		(fp_line
			(start -0.2794 -0.1016)
			(end -0.2794 0.9906)
			(stroke
				(width 0.1)
				(type default)
			)
			(layer "F.Fab")
		)
		(fp_line
			(start 0.2794 0.9906)
			(end 0.2794 -0.1016)
			(stroke
				(width 0.1)
				(type default)
			)
			(layer "F.Fab")
		)
		(fp_line
			(start -0.2794 0.9906)
			(end 0.2794 0.9906)
			(stroke
				(width 0.1)
				(type default)
			)
			(layer "F.Fab")
		)
		(pad "1" smd rect
			(at 0 0 90)
			(size 0.508 0.508)
			(layers "F.Cu" "F.Mask" "F.Paste")
			(net "P3V3_STBY")
		)
		(pad "2" smd rect
			(at 0 0.889 90)
			(size 0.508 0.508)
			(layers "F.Cu" "F.Mask" "F.Paste")
			(net "FM_BMC_CPLD_MP_RST_N")
		)
		(zone
			(layer "F.Cu")
			(hatch none 0.5)
			(connect_pads
				(clearance 0)
			)
			(min_thickness 0.25)
			(keepout
				(tracks allowed)
				(vias not_allowed)
				(pads allowed)
				(copperpour not_allowed)
				(footprints allowed)
			)
			(placement
				(enabled no)
				(sheetname "")
			)
			(fill
				(thermal_gap 0.5)
				(thermal_bridge_width 0.5)
				(island_removal_mode 0)
			)
			(polygon
				(pts
					(xy 402.1455 -37.7444) (xy 402.1455 -38.2524) (xy 402.5265 -38.2524) (xy 402.5265 -37.7444)
				)
			)
		)
		(zone
			(layer "F.Cu")
			(hatch none 0.5)
			(connect_pads
				(clearance 0)
			)
			(min_thickness 0.25)
			(keepout
				(tracks not_allowed)
				(vias allowed)
				(pads allowed)
				(copperpour not_allowed)
				(footprints allowed)
			)
			(placement
				(enabled no)
				(sheetname "")
			)
			(fill
				(thermal_gap 0.5)
				(thermal_bridge_width 0.5)
				(island_removal_mode 0)
			)
			(polygon
				(pts
					(xy 402.5265 -37.7444) (xy 402.5265 -38.2524) (xy 402.1455 -38.2524) (xy 402.1455 -37.7444)
				)
			)
		)
	)
	(footprint ""
		(layer "F.Cu")
		(at 365.5568 -134.8994 180)
		(property "Reference" "R7A9"
			(at -0.8382 -0.67818 180)
			(unlocked yes)
			(layer "F.SilkS")
			(effects
				(font
					(size 0.4064 0.254)
					(thickness 0.1524)
				)
				(justify left)
			)
		)
		(property "Value" ""
			(at 0 0 180)
			(layer "F.Fab")
			(effects
				(font
					(size 1.27 1.27)
				)
			)
		)
		(duplicate_pad_numbers_are_jumpers no)
		(fp_poly
			(pts
				(xy -0.2794 -0.1016) (xy 0.2794 -0.1016) (xy 0.2794 0.9906) (xy -0.2794 0.9906)
			)
			(stroke
				(width 0)
				(type default)
			)
			(fill no)
			(layer "F.CrtYd")
		)
		(fp_line
			(start 0.2794 0.9906)
			(end 0.2794 -0.1016)
			(stroke
				(width 0.1)
				(type default)
			)
			(layer "F.Fab")
		)
		(fp_line
			(start 0.2794 -0.1016)
			(end -0.2794 -0.1016)
			(stroke
				(width 0.1)
				(type default)
			)
			(layer "F.Fab")
		)
		(fp_line
			(start -0.2794 0.9906)
			(end 0.2794 0.9906)
			(stroke
				(width 0.1)
				(type default)
			)
			(layer "F.Fab")
		)
		(fp_line
			(start -0.2794 -0.1016)
			(end -0.2794 0.9906)
			(stroke
				(width 0.1)
				(type default)
			)
			(layer "F.Fab")
		)
		(pad "1" smd rect
			(at 0 0 180)
			(size 0.508 0.508)
			(layers "F.Cu" "F.Mask" "F.Paste")
			(net "P3V3_STBY")
		)
		(pad "2" smd rect
			(at 0 0.889 180)
			(size 0.508 0.508)
			(layers "F.Cu" "F.Mask" "F.Paste")
			(net "PWRGD_PVDDQ_DEF")
		)
		(zone
			(layer "F.Cu")
			(hatch none 0.5)
			(connect_pads
				(clearance 0)
			)
			(min_thickness 0.25)
			(keepout
				(tracks not_allowed)
				(vias allowed)
				(pads allowed)
				(copperpour not_allowed)
				(footprints allowed)
			)
			(placement
				(enabled no)
				(sheetname "")
			)
			(fill
				(thermal_gap 0.5)
				(thermal_bridge_width 0.5)
				(island_removal_mode 0)
			)
			(polygon
				(pts
					(xy 365.8108 -135.5344) (xy 365.3028 -135.5344) (xy 365.3028 -135.1534) (xy 365.8108 -135.1534)
				)
			)
		)
		(zone
			(layer "F.Cu")
			(hatch none 0.5)
			(connect_pads
				(clearance 0)
			)
			(min_thickness 0.25)
			(keepout
				(tracks allowed)
				(vias not_allowed)
				(pads allowed)
				(copperpour not_allowed)
				(footprints allowed)
			)
			(placement
				(enabled no)
				(sheetname "")
			)
			(fill
				(thermal_gap 0.5)
				(thermal_bridge_width 0.5)
				(island_removal_mode 0)
			)
			(polygon
				(pts
					(xy 365.8108 -135.1534) (xy 365.3028 -135.1534) (xy 365.3028 -135.5344) (xy 365.8108 -135.5344)
				)
			)
		)
	)
	(footprint ""
		(layer "F.Cu")
		(at 386.464302 -83.223608)
		(property "Reference" "U14E3"
			(at -0.14986 2.621788 0)
			(unlocked yes)
			(layer "F.SilkS")
			(effects
				(font
					(size 1.27 0.964946)
					(thickness 0.000001)
				)
				(justify left)
			)
		)
		(property "Value" ""
			(at 0 0 0)
			(layer "F.Fab")
			(effects
				(font
					(size 1.27 1.27)
				)
			)
		)
		(duplicate_pad_numbers_are_jumpers no)
		(fp_circle
			(center -0.4699 -0.8382)
			(end -0.3429 -0.8382)
			(stroke
				(width 0.254)
				(type default)
			)
			(fill no)
			(layer "F.SilkS")
		)
		(fp_poly
			(pts
				(xy 0.21463 -0.450088) (xy 1.56337 -0.450088) (xy 1.56337 1.75006) (xy 0.21463 1.75006)
			)
			(stroke
				(width 0)
				(type default)
			)
			(fill no)
			(layer "F.CrtYd")
		)
		(fp_line
			(start 0.21463 -0.450088)
			(end 1.56337 -0.450088)
			(stroke
				(width 0.1)
				(type default)
			)
			(layer "F.Fab")
		)
		(fp_line
			(start 0.21463 1.75006)
			(end 0.21463 -0.450088)
			(stroke
				(width 0.1)
				(type default)
			)
			(layer "F.Fab")
		)
		(fp_line
			(start 1.56337 -0.450088)
			(end 1.56337 1.75006)
			(stroke
				(width 0.1)
				(type default)
			)
			(layer "F.Fab")
		)
		(fp_line
			(start 1.56337 1.75006)
			(end 0.21463 1.75006)
			(stroke
				(width 0.1)
				(type default)
			)
			(layer "F.Fab")
		)
		(fp_circle
			(center -0.4699 -0.8382)
			(end -0.3429 -0.8382)
			(stroke
				(width 0.254)
				(type default)
			)
			(fill no)
			(layer "F.Fab")
		)
		(pad "1" smd rect
			(at 0 0)
			(size 1.016 0.381)
			(layers "F.Cu" "F.Mask" "F.Paste")
			(net "PWRGD_P12V_HSC_DLY")
		)
		(pad "2" smd rect
			(at 0 0.649986)
			(size 1.016 0.381)
			(layers "F.Cu" "F.Mask" "F.Paste")
			(net "PWRGD_P3V3")
		)
		(pad "3" smd rect
			(at 0 1.299972)
			(size 1.016 0.381)
			(layers "F.Cu" "F.Mask" "F.Paste")
			(net "GND")
		)
		(pad "4" smd rect
			(at 1.778 1.299972)
			(size 1.016 0.381)
			(layers "F.Cu" "F.Mask" "F.Paste")
			(net "RST_PCIE_M2_DEV_AND")
		)
		(pad "5" smd rect
			(at 1.778 0)
			(size 1.016 0.381)
			(layers "F.Cu" "F.Mask" "F.Paste")
			(net "P3V3")
		)
	)
	(footprint ""
		(layer "F.Cu")
		(at 478.30486 -18.48739)
		(property "Reference" "C9G4"
			(at 0 0 0)
			(layer "F.SilkS")
			(hide yes)
			(effects
				(font
					(size 1.27 1.27)
				)
			)
		)
		(property "Value" ""
			(at 0 0 0)
			(layer "F.Fab")
			(effects
				(font
					(size 1.27 1.27)
				)
			)
		)
		(duplicate_pad_numbers_are_jumpers no)
		(fp_poly
			(pts
				(xy 0.3048 -0.1016) (xy 0.3048 0.9906) (xy -0.3048 0.9906) (xy -0.3048 -0.1016)
			)
			(stroke
				(width 0)
				(type default)
			)
			(fill no)
			(layer "F.CrtYd")
		)
		(fp_line
			(start -0.3048 -0.1016)
			(end -0.3048 0.9906)
			(stroke
				(width 0.1)
				(type default)
			)
			(layer "F.Fab")
		)
		(fp_line
			(start -0.3048 0.9906)
			(end 0.3048 0.9906)
			(stroke
				(width 0.1)
				(type default)
			)
			(layer "F.Fab")
		)
		(fp_line
			(start 0.3048 -0.1016)
			(end -0.3048 -0.1016)
			(stroke
				(width 0.1)
				(type default)
			)
			(layer "F.Fab")
		)
		(fp_line
			(start 0.3048 0.9906)
			(end 0.3048 -0.1016)
			(stroke
				(width 0.1)
				(type default)
			)
			(layer "F.Fab")
		)
		(pad "1" smd rect
			(at 0 0)
			(size 0.508 0.508)
			(layers "F.Cu" "F.Mask" "F.Paste")
			(net "GND_LAN_TRCT1234_C")
		)
		(pad "2" smd rect
			(at 0 0.889)
			(size 0.508 0.508)
			(layers "F.Cu" "F.Mask" "F.Paste")
			(net "GND")
		)
		(zone
			(layer "F.Cu")
			(hatch none 0.5)
			(connect_pads
				(clearance 0)
			)
			(min_thickness 0.25)
			(keepout
				(tracks allowed)
				(vias not_allowed)
				(pads allowed)
				(copperpour not_allowed)
				(footprints allowed)
			)
			(placement
				(enabled no)
				(sheetname "")
			)
			(fill
				(thermal_gap 0.5)
				(thermal_bridge_width 0.5)
				(island_removal_mode 0)
			)
			(polygon
				(pts
					(xy 478.05086 -18.23339) (xy 478.55886 -18.23339) (xy 478.55886 -17.85239) (xy 478.05086 -17.85239)
				)
			)
		)
		(zone
			(layer "F.Cu")
			(hatch none 0.5)
			(connect_pads
				(clearance 0)
			)
			(min_thickness 0.25)
			(keepout
				(tracks not_allowed)
				(vias allowed)
				(pads allowed)
				(copperpour not_allowed)
				(footprints allowed)
			)
			(placement
				(enabled no)
				(sheetname "")
			)
			(fill
				(thermal_gap 0.5)
				(thermal_bridge_width 0.5)
				(island_removal_mode 0)
			)
			(polygon
				(pts
					(xy 478.05086 -17.85239) (xy 478.55886 -17.85239) (xy 478.55886 -18.23339) (xy 478.05086 -18.23339)
				)
			)
		)
	)
	(footprint ""
		(layer "F.Cu")
		(at 274.639024 -77.429614)
		(property "Reference" "C5D37"
			(at 0 0 0)
			(layer "F.SilkS")
			(hide yes)
			(effects
				(font
					(size 1.27 1.27)
				)
			)
		)
		(property "Value" ""
			(at 0 0 0)
			(layer "F.Fab")
			(effects
				(font
					(size 1.27 1.27)
				)
			)
		)
		(duplicate_pad_numbers_are_jumpers no)
		(fp_poly
			(pts
				(xy -0.4953 -0.2032) (xy 0.4953 -0.2032) (xy 0.4953 1.6002) (xy -0.4953 1.6002)
			)
			(stroke
				(width 0)
				(type default)
			)
			(fill no)
			(layer "F.CrtYd")
		)
		(fp_line
			(start -0.4953 -0.2032)
			(end 0.4953 -0.2032)
			(stroke
				(width 0.1)
				(type default)
			)
			(layer "F.Fab")
		)
		(fp_line
			(start -0.4953 1.6002)
			(end -0.4953 -0.2032)
			(stroke
				(width 0.1)
				(type default)
			)
			(layer "F.Fab")
		)
		(fp_line
			(start 0.4953 -0.2032)
			(end 0.4953 1.6002)
			(stroke
				(width 0.1)
				(type default)
			)
			(layer "F.Fab")
		)
		(fp_line
			(start 0.4953 1.6002)
			(end -0.4953 1.6002)
			(stroke
				(width 0.1)
				(type default)
			)
			(layer "F.Fab")
		)
		(pad "1" smd rect
			(at 0 0)
			(size 0.762 0.889)
			(layers "F.Cu" "F.Mask" "F.Paste")
			(net "PVCCMCP_CPU0")
		)
		(pad "2" smd rect
			(at 0 1.397)
			(size 0.762 0.889)
			(layers "F.Cu" "F.Mask" "F.Paste")
			(net "GND")
		)
		(zone
			(layer "F.Cu")
			(hatch none 0.5)
			(connect_pads
				(clearance 0)
			)
			(min_thickness 0.25)
			(keepout
				(tracks not_allowed)
				(vias allowed)
				(pads allowed)
				(copperpour not_allowed)
				(footprints allowed)
			)
			(placement
				(enabled no)
				(sheetname "")
			)
			(fill
				(thermal_gap 0.5)
				(thermal_bridge_width 0.5)
				(island_removal_mode 0)
			)
			(polygon
				(pts
					(xy 274.258024 -76.985114) (xy 275.020024 -76.985114) (xy 275.020024 -76.477114) (xy 274.258024 -76.477114)
				)
			)
		)
	)
	(footprint ""
		(layer "F.Cu")
		(at 386.08 -87.3125 180)
		(property "Reference" "R8E3"
			(at 0 0 180)
			(layer "F.SilkS")
			(hide yes)
			(effects
				(font
					(size 1.27 1.27)
				)
			)
		)
		(property "Value" ""
			(at 0 0 180)
			(layer "F.Fab")
			(effects
				(font
					(size 1.27 1.27)
				)
			)
		)
		(duplicate_pad_numbers_are_jumpers no)
		(fp_poly
			(pts
				(xy -0.2794 -0.1016) (xy 0.2794 -0.1016) (xy 0.2794 0.9906) (xy -0.2794 0.9906)
			)
			(stroke
				(width 0)
				(type default)
			)
			(fill no)
			(layer "F.CrtYd")
		)
		(fp_line
			(start 0.2794 0.9906)
			(end 0.2794 -0.1016)
			(stroke
				(width 0.1)
				(type default)
			)
			(layer "F.Fab")
		)
		(fp_line
			(start 0.2794 -0.1016)
			(end -0.2794 -0.1016)
			(stroke
				(width 0.1)
				(type default)
			)
			(layer "F.Fab")
		)
		(fp_line
			(start -0.2794 0.9906)
			(end 0.2794 0.9906)
			(stroke
				(width 0.1)
				(type default)
			)
			(layer "F.Fab")
		)
		(fp_line
			(start -0.2794 -0.1016)
			(end -0.2794 0.9906)
			(stroke
				(width 0.1)
				(type default)
			)
			(layer "F.Fab")
		)
		(pad "1" smd rect
			(at 0 0 180)
			(size 0.508 0.508)
			(layers "F.Cu" "F.Mask" "F.Paste")
			(net "P3V3_STBY")
		)
		(pad "2" smd rect
			(at 0 0.889 180)
			(size 0.508 0.508)
			(layers "F.Cu" "F.Mask" "F.Paste")
			(net "FM_TPM_PRES_N")
		)
		(zone
			(layer "F.Cu")
			(hatch none 0.5)
			(connect_pads
				(clearance 0)
			)
			(min_thickness 0.25)
			(keepout
				(tracks not_allowed)
				(vias allowed)
				(pads allowed)
				(copperpour not_allowed)
				(footprints allowed)
			)
			(placement
				(enabled no)
				(sheetname "")
			)
			(fill
				(thermal_gap 0.5)
				(thermal_bridge_width 0.5)
				(island_removal_mode 0)
			)
			(polygon
				(pts
					(xy 386.334 -87.9475) (xy 385.826 -87.9475) (xy 385.826 -87.5665) (xy 386.334 -87.5665)
				)
			)
		)
		(zone
			(layer "F.Cu")
			(hatch none 0.5)
			(connect_pads
				(clearance 0)
			)
			(min_thickness 0.25)
			(keepout
				(tracks allowed)
				(vias not_allowed)
				(pads allowed)
				(copperpour not_allowed)
				(footprints allowed)
			)
			(placement
				(enabled no)
				(sheetname "")
			)
			(fill
				(thermal_gap 0.5)
				(thermal_bridge_width 0.5)
				(island_removal_mode 0)
			)
			(polygon
				(pts
					(xy 386.334 -87.5665) (xy 385.826 -87.5665) (xy 385.826 -87.9475) (xy 386.334 -87.9475)
				)
			)
		)
	)
	(footprint ""
		(layer "F.Cu")
		(at 161.798 -104.14)
		(property "Reference" "C3C1"
			(at 0 0 0)
			(layer "F.SilkS")
			(hide yes)
			(effects
				(font
					(size 1.27 1.27)
				)
			)
		)
		(property "Value" ""
			(at 0 0 0)
			(layer "F.Fab")
			(effects
				(font
					(size 1.27 1.27)
				)
			)
		)
		(duplicate_pad_numbers_are_jumpers no)
		(fp_poly
			(pts
				(xy 0.3048 -0.1016) (xy 0.3048 0.9906) (xy -0.3048 0.9906) (xy -0.3048 -0.1016)
			)
			(stroke
				(width 0)
				(type default)
			)
			(fill no)
			(layer "F.CrtYd")
		)
		(fp_line
			(start -0.3048 -0.1016)
			(end -0.3048 0.9906)
			(stroke
				(width 0.1)
				(type default)
			)
			(layer "F.Fab")
		)
		(fp_line
			(start -0.3048 0.9906)
			(end 0.3048 0.9906)
			(stroke
				(width 0.1)
				(type default)
			)
			(layer "F.Fab")
		)
		(fp_line
			(start 0.3048 -0.1016)
			(end -0.3048 -0.1016)
			(stroke
				(width 0.1)
				(type default)
			)
			(layer "F.Fab")
		)
		(fp_line
			(start 0.3048 0.9906)
			(end 0.3048 -0.1016)
			(stroke
				(width 0.1)
				(type default)
			)
			(layer "F.Fab")
		)
		(pad "1" smd rect
			(at 0 0)
			(size 0.508 0.508)
			(layers "F.Cu" "F.Mask" "F.Paste")
			(net "PVCCIOMCP_CPU1")
		)
		(pad "2" smd rect
			(at 0 0.889)
			(size 0.508 0.508)
			(layers "F.Cu" "F.Mask" "F.Paste")
			(net "GND")
		)
		(zone
			(layer "F.Cu")
			(hatch none 0.5)
			(connect_pads
				(clearance 0)
			)
			(min_thickness 0.25)
			(keepout
				(tracks allowed)
				(vias not_allowed)
				(pads allowed)
				(copperpour not_allowed)
				(footprints allowed)
			)
			(placement
				(enabled no)
				(sheetname "")
			)
			(fill
				(thermal_gap 0.5)
				(thermal_bridge_width 0.5)
				(island_removal_mode 0)
			)
			(polygon
				(pts
					(xy 161.544 -103.886) (xy 162.052 -103.886) (xy 162.052 -103.505) (xy 161.544 -103.505)
				)
			)
		)
		(zone
			(layer "F.Cu")
			(hatch none 0.5)
			(connect_pads
				(clearance 0)
			)
			(min_thickness 0.25)
			(keepout
				(tracks not_allowed)
				(vias allowed)
				(pads allowed)
				(copperpour not_allowed)
				(footprints allowed)
			)
			(placement
				(enabled no)
				(sheetname "")
			)
			(fill
				(thermal_gap 0.5)
				(thermal_bridge_width 0.5)
				(island_removal_mode 0)
			)
			(polygon
				(pts
					(xy 161.544 -103.505) (xy 162.052 -103.505) (xy 162.052 -103.886) (xy 161.544 -103.886)
				)
			)
		)
	)
	(footprint ""
		(layer "F.Cu")
		(at 172.18152 -150.25624 -90)
		(property "Reference" "C4A3"
			(at 0 0 270)
			(layer "F.SilkS")
			(hide yes)
			(effects
				(font
					(size 1.27 1.27)
				)
			)
		)
		(property "Value" ""
			(at 0 0 270)
			(layer "F.Fab")
			(effects
				(font
					(size 1.27 1.27)
				)
			)
		)
		(duplicate_pad_numbers_are_jumpers no)
		(fp_rect
			(start 0.3048 0.9906)
			(end -0.3048 -0.1016)
			(stroke
				(width 0)
				(type default)
			)
			(fill no)
			(layer "F.CrtYd")
		)
		(fp_line
			(start -0.3048 0.9906)
			(end 0.3048 0.9906)
			(stroke
				(width 0.1)
				(type default)
			)
			(layer "F.Fab")
		)
		(fp_line
			(start 0.3048 0.9906)
			(end 0.3048 -0.1016)
			(stroke
				(width 0.1)
				(type default)
			)
			(layer "F.Fab")
		)
		(fp_line
			(start -0.3048 -0.1016)
			(end -0.3048 0.9906)
			(stroke
				(width 0.1)
				(type default)
			)
			(layer "F.Fab")
		)
		(fp_line
			(start 0.3048 -0.1016)
			(end -0.3048 -0.1016)
			(stroke
				(width 0.1)
				(type default)
			)
			(layer "F.Fab")
		)
		(pad "1" smd rect
			(at 0 0 270)
			(size 0.508 0.508)
			(layers "F.Cu" "F.Mask" "F.Paste")
			(net "PWRGD_PVTT_KLM_CPU1_R")
		)
		(pad "2" smd rect
			(at 0 0.889 270)
			(size 0.508 0.508)
			(layers "F.Cu" "F.Mask" "F.Paste")
			(net "GND")
		)
		(zone
			(layer "F.Cu")
			(hatch none 0.5)
			(connect_pads
				(clearance 0)
			)
			(min_thickness 0.25)
			(keepout
				(tracks not_allowed)
				(vias allowed)
				(pads allowed)
				(copperpour not_allowed)
				(footprints allowed)
			)
			(placement
				(enabled no)
				(sheetname "")
			)
			(fill
				(thermal_gap 0.5)
				(thermal_bridge_width 0.5)
				(island_removal_mode 0)
			)
			(polygon
				(pts
					(xy 171.54652 -150.00224) (xy 171.92752 -150.00224) (xy 171.92752 -150.51024) (xy 171.54652 -150.51024)
				)
			)
		)
		(zone
			(layer "F.Cu")
			(hatch none 0.5)
			(connect_pads
				(clearance 0)
			)
			(min_thickness 0.25)
			(keepout
				(tracks allowed)
				(vias not_allowed)
				(pads allowed)
				(copperpour not_allowed)
				(footprints allowed)
			)
			(placement
				(enabled no)
				(sheetname "")
			)
			(fill
				(thermal_gap 0.5)
				(thermal_bridge_width 0.5)
				(island_removal_mode 0)
			)
			(polygon
				(pts
					(xy 171.54652 -150.00224) (xy 171.92752 -150.00224) (xy 171.92752 -150.51024) (xy 171.54652 -150.51024)
				)
			)
		)
	)
	(footprint ""
		(layer "F.Cu")
		(at 401.17014 -30.67304 -90)
		(property "Reference" "R1T25"
			(at 0 0 270)
			(layer "F.SilkS")
			(hide yes)
			(effects
				(font
					(size 1.27 1.27)
				)
			)
		)
		(property "Value" ""
			(at 0 0 270)
			(layer "F.Fab")
			(effects
				(font
					(size 1.27 1.27)
				)
			)
		)
		(duplicate_pad_numbers_are_jumpers no)
		(fp_poly
			(pts
				(xy -0.2794 -0.1016) (xy 0.2794 -0.1016) (xy 0.2794 0.9906) (xy -0.2794 0.9906)
			)
			(stroke
				(width 0)
				(type default)
			)
			(fill no)
			(layer "F.CrtYd")
		)
		(fp_line
			(start -0.2794 0.9906)
			(end 0.2794 0.9906)
			(stroke
				(width 0.1)
				(type default)
			)
			(layer "F.Fab")
		)
		(fp_line
			(start 0.2794 0.9906)
			(end 0.2794 -0.1016)
			(stroke
				(width 0.1)
				(type default)
			)
			(layer "F.Fab")
		)
		(fp_line
			(start -0.2794 -0.1016)
			(end -0.2794 0.9906)
			(stroke
				(width 0.1)
				(type default)
			)
			(layer "F.Fab")
		)
		(fp_line
			(start 0.2794 -0.1016)
			(end -0.2794 -0.1016)
			(stroke
				(width 0.1)
				(type default)
			)
			(layer "F.Fab")
		)
		(pad "1" smd rect
			(at 0 0 270)
			(size 0.508 0.508)
			(layers "F.Cu" "F.Mask" "F.Paste")
			(net "A_USB2BVRES")
		)
		(pad "2" smd rect
			(at 0 0.889 270)
			(size 0.508 0.508)
			(layers "F.Cu" "F.Mask" "F.Paste")
			(net "GND")
		)
		(zone
			(layer "F.Cu")
			(hatch none 0.5)
			(connect_pads
				(clearance 0)
			)
			(min_thickness 0.25)
			(keepout
				(tracks not_allowed)
				(vias allowed)
				(pads allowed)
				(copperpour not_allowed)
				(footprints allowed)
			)
			(placement
				(enabled no)
				(sheetname "")
			)
			(fill
				(thermal_gap 0.5)
				(thermal_bridge_width 0.5)
				(island_removal_mode 0)
			)
			(polygon
				(pts
					(xy 400.53514 -30.92704) (xy 400.53514 -30.41904) (xy 400.91614 -30.41904) (xy 400.91614 -30.92704)
				)
			)
		)
		(zone
			(layer "F.Cu")
			(hatch none 0.5)
			(connect_pads
				(clearance 0)
			)
			(min_thickness 0.25)
			(keepout
				(tracks allowed)
				(vias not_allowed)
				(pads allowed)
				(copperpour not_allowed)
				(footprints allowed)
			)
			(placement
				(enabled no)
				(sheetname "")
			)
			(fill
				(thermal_gap 0.5)
				(thermal_bridge_width 0.5)
				(island_removal_mode 0)
			)
			(polygon
				(pts
					(xy 400.91614 -30.92704) (xy 400.91614 -30.41904) (xy 400.53514 -30.41904) (xy 400.53514 -30.92704)
				)
			)
		)
	)
	(footprint ""
		(layer "F.Cu")
		(at 401.2438 -130.1496 180)
		(property "Reference" "C8B3"
			(at 0 0 180)
			(layer "F.SilkS")
			(hide yes)
			(effects
				(font
					(size 1.27 1.27)
				)
			)
		)
		(property "Value" ""
			(at 0 0 180)
			(layer "F.Fab")
			(effects
				(font
					(size 1.27 1.27)
				)
			)
		)
		(duplicate_pad_numbers_are_jumpers no)
		(fp_poly
			(pts
				(xy -0.4953 -0.2032) (xy 0.4953 -0.2032) (xy 0.4953 1.6002) (xy -0.4953 1.6002)
			)
			(stroke
				(width 0)
				(type default)
			)
			(fill no)
			(layer "F.CrtYd")
		)
		(fp_line
			(start 0.4953 1.6002)
			(end -0.4953 1.6002)
			(stroke
				(width 0.1)
				(type default)
			)
			(layer "F.Fab")
		)
		(fp_line
			(start 0.4953 -0.2032)
			(end 0.4953 1.6002)
			(stroke
				(width 0.1)
				(type default)
			)
			(layer "F.Fab")
		)
		(fp_line
			(start -0.4953 1.6002)
			(end -0.4953 -0.2032)
			(stroke
				(width 0.1)
				(type default)
			)
			(layer "F.Fab")
		)
		(fp_line
			(start -0.4953 -0.2032)
			(end 0.4953 -0.2032)
			(stroke
				(width 0.1)
				(type default)
			)
			(layer "F.Fab")
		)
		(pad "1" smd rect
			(at 0 0 180)
			(size 0.762 0.889)
			(layers "F.Cu" "F.Mask" "F.Paste")
			(net "P1V8_PCH_STBY")
		)
		(pad "2" smd rect
			(at 0 1.397 180)
			(size 0.762 0.889)
			(layers "F.Cu" "F.Mask" "F.Paste")
			(net "GND")
		)
		(zone
			(layer "F.Cu")
			(hatch none 0.5)
			(connect_pads
				(clearance 0)
			)
			(min_thickness 0.25)
			(keepout
				(tracks not_allowed)
				(vias allowed)
				(pads allowed)
				(copperpour not_allowed)
				(footprints allowed)
			)
			(placement
				(enabled no)
				(sheetname "")
			)
			(fill
				(thermal_gap 0.5)
				(thermal_bridge_width 0.5)
				(island_removal_mode 0)
			)
			(polygon
				(pts
					(xy 401.6248 -130.5941) (xy 400.8628 -130.5941) (xy 400.8628 -131.1021) (xy 401.6248 -131.1021)
				)
			)
		)
	)
	(footprint ""
		(layer "F.Cu")
		(at 245.7323 -149.8092 -90)
		(property "Reference" "C5A1"
			(at 1.848866 0.752348 270)
			(unlocked yes)
			(layer "F.SilkS")
			(effects
				(font
					(size 1.27 0.9652)
					(thickness 0.1524)
				)
			)
		)
		(property "Value" ""
			(at 0 0 270)
			(layer "F.Fab")
			(effects
				(font
					(size 1.27 1.27)
				)
			)
		)
		(duplicate_pad_numbers_are_jumpers no)
		(fp_rect
			(start -0.500126 1.598422)
			(end 0.500126 -0.201422)
			(stroke
				(width 0)
				(type default)
			)
			(fill no)
			(layer "F.CrtYd")
		)
		(fp_line
			(start -0.500126 1.598422)
			(end -0.500126 -0.201422)
			(stroke
				(width 0.1)
				(type default)
			)
			(layer "F.Fab")
		)
		(fp_line
			(start 0.500126 1.598422)
			(end -0.500126 1.598422)
			(stroke
				(width 0.1)
				(type default)
			)
			(layer "F.Fab")
		)
		(fp_line
			(start -0.500126 -0.201422)
			(end 0.500126 -0.201422)
			(stroke
				(width 0.1)
				(type default)
			)
			(layer "F.Fab")
		)
		(fp_line
			(start 0.500126 -0.201422)
			(end 0.500126 1.598422)
			(stroke
				(width 0.1)
				(type default)
			)
			(layer "F.Fab")
		)
		(pad "1" smd rect
			(at 0 0 180)
			(size 0.889 0.9906)
			(layers "F.Cu" "F.Mask" "F.Paste")
			(net "PVDDQ_DEF")
		)
		(pad "2" smd rect
			(at 0 1.397 180)
			(size 0.889 0.9906)
			(layers "F.Cu" "F.Mask" "F.Paste")
			(net "GND")
		)
		(zone
			(layer "F.Cu")
			(hatch none 0.5)
			(connect_pads
				(clearance 0)
			)
			(min_thickness 0.25)
			(keepout
				(tracks allowed)
				(vias not_allowed)
				(pads allowed)
				(copperpour not_allowed)
				(footprints allowed)
			)
			(placement
				(enabled no)
				(sheetname "")
			)
			(fill
				(thermal_gap 0.5)
				(thermal_bridge_width 0.5)
				(island_removal_mode 0)
			)
			(polygon
				(pts
					(xy 244.7798 -150.3045) (xy 244.7798 -149.3139) (xy 245.2878 -149.3139) (xy 245.2878 -150.3045)
				)
			)
		)
		(zone
			(layer "F.Cu")
			(hatch none 0.5)
			(connect_pads
				(clearance 0)
			)
			(min_thickness 0.25)
			(keepout
				(tracks not_allowed)
				(vias allowed)
				(pads allowed)
				(copperpour not_allowed)
				(footprints allowed)
			)
			(placement
				(enabled no)
				(sheetname "")
			)
			(fill
				(thermal_gap 0.5)
				(thermal_bridge_width 0.5)
				(island_removal_mode 0)
			)
			(polygon
				(pts
					(xy 244.7798 -150.3045) (xy 244.7798 -149.3139) (xy 245.2878 -149.3139) (xy 245.2878 -150.3045)
				)
			)
		)
	)
	(footprint ""
		(layer "F.Cu")
		(at 352.9838 -99.50323 90)
		(property "Reference" "R7C25"
			(at 0 0 90)
			(layer "F.SilkS")
			(hide yes)
			(effects
				(font
					(size 1.27 1.27)
				)
			)
		)
		(property "Value" ""
			(at 0 0 90)
			(layer "F.Fab")
			(effects
				(font
					(size 1.27 1.27)
				)
			)
		)
		(duplicate_pad_numbers_are_jumpers no)
		(fp_poly
			(pts
				(xy -0.2794 -0.1016) (xy 0.2794 -0.1016) (xy 0.2794 0.9906) (xy -0.2794 0.9906)
			)
			(stroke
				(width 0)
				(type default)
			)
			(fill no)
			(layer "F.CrtYd")
		)
		(fp_line
			(start 0.2794 -0.1016)
			(end -0.2794 -0.1016)
			(stroke
				(width 0.1)
				(type default)
			)
			(layer "F.Fab")
		)
		(fp_line
			(start -0.2794 -0.1016)
			(end -0.2794 0.9906)
			(stroke
				(width 0.1)
				(type default)
			)
			(layer "F.Fab")
		)
		(fp_line
			(start 0.2794 0.9906)
			(end 0.2794 -0.1016)
			(stroke
				(width 0.1)
				(type default)
			)
			(layer "F.Fab")
		)
		(fp_line
			(start -0.2794 0.9906)
			(end 0.2794 0.9906)
			(stroke
				(width 0.1)
				(type default)
			)
			(layer "F.Fab")
		)
		(pad "1" smd rect
			(at 0 0 90)
			(size 0.508 0.508)
			(layers "F.Cu" "F.Mask" "F.Paste")
			(net "VR_PVCCIO_CPU0_OCSET")
		)
		(pad "2" smd rect
			(at 0 0.889 90)
			(size 0.508 0.508)
			(layers "F.Cu" "F.Mask" "F.Paste")
			(net "GND")
		)
		(zone
			(layer "F.Cu")
			(hatch none 0.5)
			(connect_pads
				(clearance 0)
			)
			(min_thickness 0.25)
			(keepout
				(tracks allowed)
				(vias not_allowed)
				(pads allowed)
				(copperpour not_allowed)
				(footprints allowed)
			)
			(placement
				(enabled no)
				(sheetname "")
			)
			(fill
				(thermal_gap 0.5)
				(thermal_bridge_width 0.5)
				(island_removal_mode 0)
			)
			(polygon
				(pts
					(xy 353.2378 -99.24923) (xy 353.2378 -99.75723) (xy 353.6188 -99.75723) (xy 353.6188 -99.24923)
				)
			)
		)
		(zone
			(layer "F.Cu")
			(hatch none 0.5)
			(connect_pads
				(clearance 0)
			)
			(min_thickness 0.25)
			(keepout
				(tracks not_allowed)
				(vias allowed)
				(pads allowed)
				(copperpour not_allowed)
				(footprints allowed)
			)
			(placement
				(enabled no)
				(sheetname "")
			)
			(fill
				(thermal_gap 0.5)
				(thermal_bridge_width 0.5)
				(island_removal_mode 0)
			)
			(polygon
				(pts
					(xy 353.6188 -99.24923) (xy 353.6188 -99.75723) (xy 353.2378 -99.75723) (xy 353.2378 -99.24923)
				)
			)
		)
	)
	(footprint ""
		(layer "F.Cu")
		(at 345.316048 -11.210036 180)
		(property "Reference" "CF16"
			(at 0 0 180)
			(layer "F.SilkS")
			(hide yes)
			(effects
				(font
					(size 1.27 1.27)
				)
			)
		)
		(property "Value" "*"
			(at 1.1811 -2.8194 180)
			(unlocked yes)
			(layer "F.Fab")
			(hide yes)
			(effects
				(font
					(size 1.27 1.016)
					(thickness 0.1524)
				)
			)
		)
		(property "Device Type" "SC22P50V2JN-4GP_SMD-BCG-SC22P5A"
			(at 1.1811 -4.3434 180)
			(unlocked yes)
			(layer "F.Fab")
			(hide yes)
			(effects
				(font
					(size 1.27 1.016)
					(thickness 0.1524)
				)
			)
		)
		(duplicate_pad_numbers_are_jumpers no)
		(fp_rect
			(start -0.4318 0.9525)
			(end 0.4318 -0.9525)
			(stroke
				(width 0)
				(type default)
			)
			(fill no)
			(layer "F.CrtYd")
		)
		(fp_rect
			(start -0.4318 0.9525)
			(end 0.4318 -0.9525)
			(stroke
				(width 0)
				(type default)
			)
			(fill no)
			(layer "F.Fab")
		)
		(pad "1" smd custom
			(at 0 -0.4445 180)
			(size 0.1524 0.1524)
			(layers "F.Cu" "F.Mask" "F.Paste")
			(net "VR_PVDDQ_ABC_AIREF2")
			(options
				(clearance outline)
				(anchor circle)
			)
			(primitives
				(gr_poly
					(pts
						(arc
							(start 0.3048 -0.2032)
							(mid 0.275042 -0.275042)
							(end 0.2032 -0.3048)
						)
						(arc
							(start -0.2032 -0.3048)
							(mid -0.275042 -0.275042)
							(end -0.3048 -0.2032)
						)
						(arc
							(start -0.3048 0.2032)
							(mid -0.275042 0.275042)
							(end -0.2032 0.3048)
						)
						(arc
							(start 0.2032 0.3048)
							(mid 0.275042 0.275042)
							(end 0.3048 0.2032)
						)
					)
					(width 0)
					(fill yes)
				)
			)
		)
		(pad "2" smd custom
			(at 0 0.4445 180)
			(size 0.1524 0.1524)
			(layers "F.Cu" "F.Mask" "F.Paste")
			(net "ISENSE_PVDDQ_ABC_PH2_IMON")
			(options
				(clearance outline)
				(anchor circle)
			)
			(primitives
				(gr_poly
					(pts
						(arc
							(start 0.3048 -0.2032)
							(mid 0.275042 -0.275042)
							(end 0.2032 -0.3048)
						)
						(arc
							(start -0.2032 -0.3048)
							(mid -0.275042 -0.275042)
							(end -0.3048 -0.2032)
						)
						(arc
							(start -0.3048 0.2032)
							(mid -0.275042 0.275042)
							(end -0.2032 0.3048)
						)
						(arc
							(start 0.2032 0.3048)
							(mid 0.275042 0.275042)
							(end 0.3048 0.2032)
						)
					)
					(width 0)
					(fill yes)
				)
			)
		)
	)
	(footprint ""
		(layer "F.Cu")
		(at 338.836 -20.5232 -90)
		(property "Reference" "R7F23"
			(at 0 0 270)
			(layer "F.SilkS")
			(hide yes)
			(effects
				(font
					(size 1.27 1.27)
				)
			)
		)
		(property "Value" ""
			(at 0 0 270)
			(layer "F.Fab")
			(effects
				(font
					(size 1.27 1.27)
				)
			)
		)
		(duplicate_pad_numbers_are_jumpers no)
		(fp_poly
			(pts
				(xy -0.2794 -0.1016) (xy 0.2794 -0.1016) (xy 0.2794 0.9906) (xy -0.2794 0.9906)
			)
			(stroke
				(width 0)
				(type default)
			)
			(fill no)
			(layer "F.CrtYd")
		)
		(fp_line
			(start -0.2794 0.9906)
			(end 0.2794 0.9906)
			(stroke
				(width 0.1)
				(type default)
			)
			(layer "F.Fab")
		)
		(fp_line
			(start 0.2794 0.9906)
			(end 0.2794 -0.1016)
			(stroke
				(width 0.1)
				(type default)
			)
			(layer "F.Fab")
		)
		(fp_line
			(start -0.2794 -0.1016)
			(end -0.2794 0.9906)
			(stroke
				(width 0.1)
				(type default)
			)
			(layer "F.Fab")
		)
		(fp_line
			(start 0.2794 -0.1016)
			(end -0.2794 -0.1016)
			(stroke
				(width 0.1)
				(type default)
			)
			(layer "F.Fab")
		)
		(pad "1" smd rect
			(at 0 0 270)
			(size 0.508 0.508)
			(layers "F.Cu" "F.Mask" "F.Paste")
			(net "IRQ_PVDDQ_ABC_VRHOT_LVT3_R_N")
		)
		(pad "2" smd rect
			(at 0 0.889 270)
			(size 0.508 0.508)
			(layers "F.Cu" "F.Mask" "F.Paste")
			(net "IRQ_PVDDQ_ABC_VRHOT_LVT3_N")
		)
		(zone
			(layer "F.Cu")
			(hatch none 0.5)
			(connect_pads
				(clearance 0)
			)
			(min_thickness 0.25)
			(keepout
				(tracks not_allowed)
				(vias allowed)
				(pads allowed)
				(copperpour not_allowed)
				(footprints allowed)
			)
			(placement
				(enabled no)
				(sheetname "")
			)
			(fill
				(thermal_gap 0.5)
				(thermal_bridge_width 0.5)
				(island_removal_mode 0)
			)
			(polygon
				(pts
					(xy 338.201 -20.7772) (xy 338.201 -20.2692) (xy 338.582 -20.2692) (xy 338.582 -20.7772)
				)
			)
		)
		(zone
			(layer "F.Cu")
			(hatch none 0.5)
			(connect_pads
				(clearance 0)
			)
			(min_thickness 0.25)
			(keepout
				(tracks allowed)
				(vias not_allowed)
				(pads allowed)
				(copperpour not_allowed)
				(footprints allowed)
			)
			(placement
				(enabled no)
				(sheetname "")
			)
			(fill
				(thermal_gap 0.5)
				(thermal_bridge_width 0.5)
				(island_removal_mode 0)
			)
			(polygon
				(pts
					(xy 338.582 -20.7772) (xy 338.582 -20.2692) (xy 338.201 -20.2692) (xy 338.201 -20.7772)
				)
			)
		)
	)
	(footprint ""
		(layer "F.Cu")
		(at 137.730484 12.014454 -90)
		(property "Reference" "T1P11"
			(at 0 0 270)
			(layer "F.SilkS")
			(hide yes)
			(effects
				(font
					(size 1.27 1.27)
				)
			)
		)
		(property "Value" "*"
			(at -3.302 1.12395 270)
			(unlocked yes)
			(layer "F.Fab")
			(hide yes)
			(effects
				(font
					(size 0.889 0.889)
					(thickness 0.1524)
				)
			)
		)
		(property "Device Type" "TPAD-DIFF-4P-GP_DISCRET-GB3-TPA"
			(at -3.302 -0.40005 270)
			(unlocked yes)
			(layer "F.Fab")
			(hide yes)
			(effects
				(font
					(size 0.889 0.889)
					(thickness 0.1524)
				)
			)
		)
		(duplicate_pad_numbers_are_jumpers no)
		(fp_line
			(start -2.286 2.286)
			(end 2.286 2.286)
			(stroke
				(width 0.1524)
				(type default)
			)
			(layer "F.SilkS")
		)
		(fp_line
			(start 2.286 2.286)
			(end 2.286 -2.286)
			(stroke
				(width 0.1524)
				(type default)
			)
			(layer "F.SilkS")
		)
		(fp_line
			(start -2.286 -2.286)
			(end -2.286 2.286)
			(stroke
				(width 0.1524)
				(type default)
			)
			(layer "F.SilkS")
		)
		(fp_line
			(start 2.286 -2.286)
			(end -2.286 -2.286)
			(stroke
				(width 0.1524)
				(type default)
			)
			(layer "F.SilkS")
		)
		(fp_line
			(start -2.413 -2.413)
			(end -2.413 -1.143)
			(stroke
				(width 0.4064)
				(type default)
			)
			(layer "F.SilkS")
		)
		(fp_line
			(start -1.143 -2.413)
			(end -2.413 -2.413)
			(stroke
				(width 0.4064)
				(type default)
			)
			(layer "F.SilkS")
		)
		(fp_rect
			(start -2.54 2.54)
			(end 2.54 -2.54)
			(stroke
				(width 0)
				(type default)
			)
			(fill no)
			(layer "F.CrtYd")
		)
		(fp_rect
			(start -2.54 2.54)
			(end 2.54 -2.54)
			(stroke
				(width 0)
				(type default)
			)
			(fill no)
			(layer "F.Fab")
		)
		(pad "1" thru_hole circle
			(at -1.27 -1.27 270)
			(size 1.524 1.524)
			(drill 0.9144)
			(layers "*.Cu" "*.Mask")
			(remove_unused_layers no)
			(net "L12_73OHM_6INCH_DP")
			(clearance -0.0508)
			(thermal_gap 0.127)
			(padstack
				(mode front_inner_back)
				(layer "Inner"
					(shape circle)
					(size 1.1684 1.1684)
					(clearance 0.127)
				)
				(layer "B.Cu"
					(shape circle)
					(size 1.524 1.524)
					(clearance -0.0508)
				)
			)
		)
		(pad "2" thru_hole circle
			(at 1.27 -1.27 270)
			(size 1.524 1.524)
			(drill 0.9144)
			(layers "*.Cu" "*.Mask")
			(remove_unused_layers no)
			(net "L12_73OHM_6INCH_DN")
			(clearance -0.0508)
			(thermal_gap 0.127)
			(padstack
				(mode front_inner_back)
				(layer "Inner"
					(shape circle)
					(size 1.1684 1.1684)
					(clearance 0.127)
				)
				(layer "B.Cu"
					(shape circle)
					(size 1.524 1.524)
					(clearance -0.0508)
				)
			)
		)
		(pad "GND1" thru_hole rect
			(at -1.27 1.27 270)
			(size 1.524 1.524)
			(drill 0.9144)
			(layers "*.Cu" "*.Mask")
			(remove_unused_layers no)
			(net "GND")
			(clearance -0.0508)
			(thermal_gap 0.127)
			(padstack
				(mode front_inner_back)
				(layer "Inner"
					(shape circle)
					(size 1.1684 1.1684)
					(clearance 0.127)
				)
				(layer "B.Cu"
					(shape rect)
					(size 1.524 1.524)
					(clearance -0.0508)
				)
			)
		)
		(pad "GND2" thru_hole rect
			(at 1.27 1.27 270)
			(size 1.524 1.524)
			(drill 0.9144)
			(layers "*.Cu" "*.Mask")
			(remove_unused_layers no)
			(net "GND")
			(clearance -0.0508)
			(thermal_gap 0.127)
			(padstack
				(mode front_inner_back)
				(layer "Inner"
					(shape circle)
					(size 1.1684 1.1684)
					(clearance 0.127)
				)
				(layer "B.Cu"
					(shape rect)
					(size 1.524 1.524)
					(clearance -0.0508)
				)
			)
		)
	)
	(footprint ""
		(layer "F.Cu")
		(at 174.244 -131.5085)
		(property "Reference" "R4B4"
			(at 0 0 0)
			(layer "F.SilkS")
			(hide yes)
			(effects
				(font
					(size 1.27 1.27)
				)
			)
		)
		(property "Value" ""
			(at 0 0 0)
			(layer "F.Fab")
			(effects
				(font
					(size 1.27 1.27)
				)
			)
		)
		(duplicate_pad_numbers_are_jumpers no)
		(fp_poly
			(pts
				(xy -0.2794 -0.1016) (xy 0.2794 -0.1016) (xy 0.2794 0.9906) (xy -0.2794 0.9906)
			)
			(stroke
				(width 0)
				(type default)
			)
			(fill no)
			(layer "F.CrtYd")
		)
		(fp_line
			(start -0.2794 -0.1016)
			(end -0.2794 0.9906)
			(stroke
				(width 0.1)
				(type default)
			)
			(layer "F.Fab")
		)
		(fp_line
			(start -0.2794 0.9906)
			(end 0.2794 0.9906)
			(stroke
				(width 0.1)
				(type default)
			)
			(layer "F.Fab")
		)
		(fp_line
			(start 0.2794 -0.1016)
			(end -0.2794 -0.1016)
			(stroke
				(width 0.1)
				(type default)
			)
			(layer "F.Fab")
		)
		(fp_line
			(start 0.2794 0.9906)
			(end 0.2794 -0.1016)
			(stroke
				(width 0.1)
				(type default)
			)
			(layer "F.Fab")
		)
		(pad "1" smd rect
			(at 0 0)
			(size 0.508 0.508)
			(layers "F.Cu" "F.Mask" "F.Paste")
			(net "VR_FB_PVPP_KLM")
		)
		(pad "2" smd rect
			(at 0 0.889)
			(size 0.508 0.508)
			(layers "F.Cu" "F.Mask" "F.Paste")
			(net "AGND_PVPP_KLM")
		)
		(zone
			(layer "F.Cu")
			(hatch none 0.5)
			(connect_pads
				(clearance 0)
			)
			(min_thickness 0.25)
			(keepout
				(tracks allowed)
				(vias not_allowed)
				(pads allowed)
				(copperpour not_allowed)
				(footprints allowed)
			)
			(placement
				(enabled no)
				(sheetname "")
			)
			(fill
				(thermal_gap 0.5)
				(thermal_bridge_width 0.5)
				(island_removal_mode 0)
			)
			(polygon
				(pts
					(xy 173.99 -131.2545) (xy 174.498 -131.2545) (xy 174.498 -130.8735) (xy 173.99 -130.8735)
				)
			)
		)
		(zone
			(layer "F.Cu")
			(hatch none 0.5)
			(connect_pads
				(clearance 0)
			)
			(min_thickness 0.25)
			(keepout
				(tracks not_allowed)
				(vias allowed)
				(pads allowed)
				(copperpour not_allowed)
				(footprints allowed)
			)
			(placement
				(enabled no)
				(sheetname "")
			)
			(fill
				(thermal_gap 0.5)
				(thermal_bridge_width 0.5)
				(island_removal_mode 0)
			)
			(polygon
				(pts
					(xy 173.99 -130.8735) (xy 174.498 -130.8735) (xy 174.498 -131.2545) (xy 173.99 -131.2545)
				)
			)
		)
	)
	(footprint ""
		(layer "F.Cu")
		(at 398.874996 -36.565586 90)
		(property "Reference" "R8G3"
			(at 0 0 90)
			(layer "F.SilkS")
			(hide yes)
			(effects
				(font
					(size 1.27 1.27)
				)
			)
		)
		(property "Value" ""
			(at 0 0 90)
			(layer "F.Fab")
			(effects
				(font
					(size 1.27 1.27)
				)
			)
		)
		(duplicate_pad_numbers_are_jumpers no)
		(fp_poly
			(pts
				(xy -0.2794 -0.1016) (xy 0.2794 -0.1016) (xy 0.2794 0.9906) (xy -0.2794 0.9906)
			)
			(stroke
				(width 0)
				(type default)
			)
			(fill no)
			(layer "F.CrtYd")
		)
		(fp_line
			(start 0.2794 -0.1016)
			(end -0.2794 -0.1016)
			(stroke
				(width 0.1)
				(type default)
			)
			(layer "F.Fab")
		)
		(fp_line
			(start -0.2794 -0.1016)
			(end -0.2794 0.9906)
			(stroke
				(width 0.1)
				(type default)
			)
			(layer "F.Fab")
		)
		(fp_line
			(start 0.2794 0.9906)
			(end 0.2794 -0.1016)
			(stroke
				(width 0.1)
				(type default)
			)
			(layer "F.Fab")
		)
		(fp_line
			(start -0.2794 0.9906)
			(end 0.2794 0.9906)
			(stroke
				(width 0.1)
				(type default)
			)
			(layer "F.Fab")
		)
		(pad "1" smd rect
			(at 0 0 90)
			(size 0.508 0.508)
			(layers "F.Cu" "F.Mask" "F.Paste")
			(net "P3V3_STBY")
		)
		(pad "2" smd rect
			(at 0 0.889 90)
			(size 0.508 0.508)
			(layers "F.Cu" "F.Mask" "F.Paste")
			(net "SMB_OCP_LAN_STBY_LVC3_SCL_R")
		)
		(zone
			(layer "F.Cu")
			(hatch none 0.5)
			(connect_pads
				(clearance 0)
			)
			(min_thickness 0.25)
			(keepout
				(tracks allowed)
				(vias not_allowed)
				(pads allowed)
				(copperpour not_allowed)
				(footprints allowed)
			)
			(placement
				(enabled no)
				(sheetname "")
			)
			(fill
				(thermal_gap 0.5)
				(thermal_bridge_width 0.5)
				(island_removal_mode 0)
			)
			(polygon
				(pts
					(xy 399.128996 -36.311586) (xy 399.128996 -36.819586) (xy 399.509996 -36.819586) (xy 399.509996 -36.311586)
				)
			)
		)
		(zone
			(layer "F.Cu")
			(hatch none 0.5)
			(connect_pads
				(clearance 0)
			)
			(min_thickness 0.25)
			(keepout
				(tracks not_allowed)
				(vias allowed)
				(pads allowed)
				(copperpour not_allowed)
				(footprints allowed)
			)
			(placement
				(enabled no)
				(sheetname "")
			)
			(fill
				(thermal_gap 0.5)
				(thermal_bridge_width 0.5)
				(island_removal_mode 0)
			)
			(polygon
				(pts
					(xy 399.509996 -36.311586) (xy 399.509996 -36.819586) (xy 399.128996 -36.819586) (xy 399.128996 -36.311586)
				)
			)
		)
	)
	(footprint ""
		(layer "F.Cu")
		(at 350.05518 -3.146552)
		(property "Reference" "C7G30"
			(at 0 0 0)
			(layer "F.SilkS")
			(hide yes)
			(effects
				(font
					(size 1.27 1.27)
				)
			)
		)
		(property "Value" ""
			(at 0 0 0)
			(layer "F.Fab")
			(effects
				(font
					(size 1.27 1.27)
				)
			)
		)
		(duplicate_pad_numbers_are_jumpers no)
		(fp_poly
			(pts
				(xy 0.3048 -0.1016) (xy 0.3048 0.9906) (xy -0.3048 0.9906) (xy -0.3048 -0.1016)
			)
			(stroke
				(width 0)
				(type default)
			)
			(fill no)
			(layer "F.CrtYd")
		)
		(fp_line
			(start -0.3048 -0.1016)
			(end -0.3048 0.9906)
			(stroke
				(width 0.1)
				(type default)
			)
			(layer "F.Fab")
		)
		(fp_line
			(start -0.3048 0.9906)
			(end 0.3048 0.9906)
			(stroke
				(width 0.1)
				(type default)
			)
			(layer "F.Fab")
		)
		(fp_line
			(start 0.3048 -0.1016)
			(end -0.3048 -0.1016)
			(stroke
				(width 0.1)
				(type default)
			)
			(layer "F.Fab")
		)
		(fp_line
			(start 0.3048 0.9906)
			(end 0.3048 -0.1016)
			(stroke
				(width 0.1)
				(type default)
			)
			(layer "F.Fab")
		)
		(pad "1" smd rect
			(at 0 0)
			(size 0.508 0.508)
			(layers "F.Cu" "F.Mask" "F.Paste")
			(net "VR_FET_SW_P12V_STBY_PVDDQ_ABC")
		)
		(pad "2" smd rect
			(at 0 0.889)
			(size 0.508 0.508)
			(layers "F.Cu" "F.Mask" "F.Paste")
			(net "GND")
		)
		(zone
			(layer "F.Cu")
			(hatch none 0.5)
			(connect_pads
				(clearance 0)
			)
			(min_thickness 0.25)
			(keepout
				(tracks allowed)
				(vias not_allowed)
				(pads allowed)
				(copperpour not_allowed)
				(footprints allowed)
			)
			(placement
				(enabled no)
				(sheetname "")
			)
			(fill
				(thermal_gap 0.5)
				(thermal_bridge_width 0.5)
				(island_removal_mode 0)
			)
			(polygon
				(pts
					(xy 349.80118 -2.892552) (xy 350.30918 -2.892552) (xy 350.30918 -2.511552) (xy 349.80118 -2.511552)
				)
			)
		)
		(zone
			(layer "F.Cu")
			(hatch none 0.5)
			(connect_pads
				(clearance 0)
			)
			(min_thickness 0.25)
			(keepout
				(tracks not_allowed)
				(vias allowed)
				(pads allowed)
				(copperpour not_allowed)
				(footprints allowed)
			)
			(placement
				(enabled no)
				(sheetname "")
			)
			(fill
				(thermal_gap 0.5)
				(thermal_bridge_width 0.5)
				(island_removal_mode 0)
			)
			(polygon
				(pts
					(xy 349.80118 -2.511552) (xy 350.30918 -2.511552) (xy 350.30918 -2.892552) (xy 349.80118 -2.892552)
				)
			)
		)
	)
	(footprint ""
		(layer "F.Cu")
		(at 318.543432 -12.954 -90)
		(property "Reference" "C6G1"
			(at 0 0 270)
			(layer "F.SilkS")
			(hide yes)
			(effects
				(font
					(size 1.27 1.27)
				)
			)
		)
		(property "Value" ""
			(at 0 0 270)
			(layer "F.Fab")
			(effects
				(font
					(size 1.27 1.27)
				)
			)
		)
		(duplicate_pad_numbers_are_jumpers no)
		(fp_poly
			(pts
				(xy -0.4953 -0.2032) (xy 0.4953 -0.2032) (xy 0.4953 1.6002) (xy -0.4953 1.6002)
			)
			(stroke
				(width 0)
				(type default)
			)
			(fill no)
			(layer "F.CrtYd")
		)
		(fp_line
			(start -0.4953 1.6002)
			(end -0.4953 -0.2032)
			(stroke
				(width 0.1)
				(type default)
			)
			(layer "F.Fab")
		)
		(fp_line
			(start 0.4953 1.6002)
			(end -0.4953 1.6002)
			(stroke
				(width 0.1)
				(type default)
			)
			(layer "F.Fab")
		)
		(fp_line
			(start -0.4953 -0.2032)
			(end 0.4953 -0.2032)
			(stroke
				(width 0.1)
				(type default)
			)
			(layer "F.Fab")
		)
		(fp_line
			(start 0.4953 -0.2032)
			(end 0.4953 1.6002)
			(stroke
				(width 0.1)
				(type default)
			)
			(layer "F.Fab")
		)
		(pad "1" smd rect
			(at 0 0 270)
			(size 0.762 0.889)
			(layers "F.Cu" "F.Mask" "F.Paste")
			(net "PVPP_ABC")
		)
		(pad "2" smd rect
			(at 0 1.397 270)
			(size 0.762 0.889)
			(layers "F.Cu" "F.Mask" "F.Paste")
			(net "GND")
		)
		(zone
			(layer "F.Cu")
			(hatch none 0.5)
			(connect_pads
				(clearance 0)
			)
			(min_thickness 0.25)
			(keepout
				(tracks not_allowed)
				(vias allowed)
				(pads allowed)
				(copperpour not_allowed)
				(footprints allowed)
			)
			(placement
				(enabled no)
				(sheetname "")
			)
			(fill
				(thermal_gap 0.5)
				(thermal_bridge_width 0.5)
				(island_removal_mode 0)
			)
			(polygon
				(pts
					(xy 318.098932 -13.335) (xy 318.098932 -12.573) (xy 317.590932 -12.573) (xy 317.590932 -13.335)
				)
			)
		)
	)
	(footprint ""
		(layer "F.Cu")
		(at 355.666548 -22.035516 -90)
		(property "Reference" "L7F2"
			(at 0 0 270)
			(layer "F.SilkS")
			(hide yes)
			(effects
				(font
					(size 1.27 1.27)
				)
			)
		)
		(property "Value" "*"
			(at -3.5941 0.3429 270)
			(unlocked yes)
			(layer "F.Fab")
			(hide yes)
			(effects
				(font
					(size 1.27 1.016)
					(thickness 0.1524)
				)
			)
		)
		(property "Device Type" "IND-100NH-35-GP_DISCRET-G8-INDA"
			(at -3.5941 -1.1811 270)
			(unlocked yes)
			(layer "F.Fab")
			(hide yes)
			(effects
				(font
					(size 1.27 1.016)
					(thickness 0.1524)
				)
			)
		)
		(duplicate_pad_numbers_are_jumpers no)
		(fp_line
			(start -2.2479 2.794)
			(end -2.2479 -2.794)
			(stroke
				(width 0.1524)
				(type default)
			)
			(layer "F.SilkS")
		)
		(fp_line
			(start 2.2479 2.794)
			(end -2.2479 2.794)
			(stroke
				(width 0.1524)
				(type default)
			)
			(layer "F.SilkS")
		)
		(fp_line
			(start -2.2479 -2.794)
			(end 2.2479 -2.794)
			(stroke
				(width 0.1524)
				(type default)
			)
			(layer "F.SilkS")
		)
		(fp_line
			(start 2.2479 -2.794)
			(end 2.2479 2.794)
			(stroke
				(width 0.1524)
				(type default)
			)
			(layer "F.SilkS")
		)
		(fp_rect
			(start -1.9939 1.9939)
			(end 1.9939 -1.9939)
			(stroke
				(width 0)
				(type default)
			)
			(fill no)
			(layer "F.CrtYd")
		)
		(fp_poly
			(pts
				(xy -2.5019 2.8702) (xy -2.5019 1.9939) (xy 1.9939 1.9939) (xy 1.9939 -1.9939) (xy -1.9939 -1.9939)
				(xy -1.9939 1.9812) (xy -2.5019 1.9812) (xy -2.5019 -2.8702) (xy 2.5019 -2.8702) (xy 2.5019 2.8702)
			)
			(stroke
				(width 0)
				(type default)
			)
			(fill no)
			(layer "F.CrtYd")
		)
		(fp_rect
			(start -2.5019 2.8702)
			(end 2.5019 -2.8702)
			(stroke
				(width 0)
				(type default)
			)
			(fill no)
			(layer "F.Fab")
		)
		(pad "1" smd rect
			(at 0 -1.745996 270)
			(size 1.5494 1.6002)
			(layers "F.Cu" "F.Mask" "F.Paste")
			(net "P12V_STBY")
		)
		(pad "2" smd rect
			(at 0 1.745996 270)
			(size 1.5494 1.6002)
			(layers "F.Cu" "F.Mask" "F.Paste")
			(net "VR_FET_SW_P12V_STBY_PVDDQ_ABC")
		)
	)
	(footprint ""
		(layer "F.Cu")
		(at 13.8938 -33.02 90)
		(property "Reference" "C1F6"
			(at 0 0 90)
			(layer "F.SilkS")
			(hide yes)
			(effects
				(font
					(size 1.27 1.27)
				)
			)
		)
		(property "Value" ""
			(at 0 0 90)
			(layer "F.Fab")
			(effects
				(font
					(size 1.27 1.27)
				)
			)
		)
		(duplicate_pad_numbers_are_jumpers no)
		(fp_rect
			(start -0.3048 -0.1016)
			(end 0.3048 0.9906)
			(stroke
				(width 0)
				(type default)
			)
			(fill no)
			(layer "F.CrtYd")
		)
		(fp_line
			(start 0.3048 -0.1016)
			(end -0.3048 -0.1016)
			(stroke
				(width 0.1)
				(type default)
			)
			(layer "F.Fab")
		)
		(fp_line
			(start -0.3048 -0.1016)
			(end -0.3048 0.9906)
			(stroke
				(width 0.1)
				(type default)
			)
			(layer "F.Fab")
		)
		(fp_line
			(start 0.3048 0.9906)
			(end 0.3048 -0.1016)
			(stroke
				(width 0.1)
				(type default)
			)
			(layer "F.Fab")
		)
		(fp_line
			(start -0.3048 0.9906)
			(end 0.3048 0.9906)
			(stroke
				(width 0.1)
				(type default)
			)
			(layer "F.Fab")
		)
		(pad "1" smd rect
			(at 0 0 90)
			(size 0.508 0.508)
			(layers "F.Cu" "F.Mask" "F.Paste")
			(net "P3E_CPU1_PE3_MP_C_TXP<5>")
		)
		(pad "2" smd rect
			(at 0 0.889 90)
			(size 0.508 0.508)
			(layers "F.Cu" "F.Mask" "F.Paste")
			(net "P3E_CPU1_PE3_MP_TXP<5>")
		)
		(zone
			(layer "F.Cu")
			(hatch none 0.5)
			(connect_pads
				(clearance 0)
			)
			(min_thickness 0.25)
			(keepout
				(tracks not_allowed)
				(vias allowed)
				(pads allowed)
				(copperpour not_allowed)
				(footprints allowed)
			)
			(placement
				(enabled no)
				(sheetname "")
			)
			(fill
				(thermal_gap 0.5)
				(thermal_bridge_width 0.5)
				(island_removal_mode 0)
			)
			(polygon
				(pts
					(xy 14.1478 -32.766) (xy 14.5288 -32.766) (xy 14.5288 -33.274) (xy 14.1478 -33.274)
				)
			)
		)
		(zone
			(layer "F.Cu")
			(hatch none 0.5)
			(connect_pads
				(clearance 0)
			)
			(min_thickness 0.25)
			(keepout
				(tracks allowed)
				(vias not_allowed)
				(pads allowed)
				(copperpour not_allowed)
				(footprints allowed)
			)
			(placement
				(enabled no)
				(sheetname "")
			)
			(fill
				(thermal_gap 0.5)
				(thermal_bridge_width 0.5)
				(island_removal_mode 0)
			)
			(polygon
				(pts
					(xy 14.1478 -32.766) (xy 14.5288 -32.766) (xy 14.5288 -33.274) (xy 14.1478 -33.274)
				)
			)
		)
	)
	(footprint ""
		(layer "F.Cu")
		(at 407.7335 -22.987 90)
		(property "Reference" "R25W80"
			(at -0.8382 -0.67818 90)
			(unlocked yes)
			(layer "F.SilkS")
			(effects
				(font
					(size 0.4064 0.254)
					(thickness 0.1524)
				)
				(justify left)
			)
		)
		(property "Value" ""
			(at 0 0 90)
			(layer "F.Fab")
			(effects
				(font
					(size 1.27 1.27)
				)
			)
		)
		(duplicate_pad_numbers_are_jumpers no)
		(fp_poly
			(pts
				(xy -0.2794 -0.1016) (xy 0.2794 -0.1016) (xy 0.2794 0.9906) (xy -0.2794 0.9906)
			)
			(stroke
				(width 0)
				(type default)
			)
			(fill no)
			(layer "F.CrtYd")
		)
		(fp_line
			(start 0.2794 -0.1016)
			(end -0.2794 -0.1016)
			(stroke
				(width 0.1)
				(type default)
			)
			(layer "F.Fab")
		)
		(fp_line
			(start -0.2794 -0.1016)
			(end -0.2794 0.9906)
			(stroke
				(width 0.1)
				(type default)
			)
			(layer "F.Fab")
		)
		(fp_line
			(start 0.2794 0.9906)
			(end 0.2794 -0.1016)
			(stroke
				(width 0.1)
				(type default)
			)
			(layer "F.Fab")
		)
		(fp_line
			(start -0.2794 0.9906)
			(end 0.2794 0.9906)
			(stroke
				(width 0.1)
				(type default)
			)
			(layer "F.Fab")
		)
		(pad "1" smd rect
			(at 0 0 90)
			(size 0.508 0.508)
			(layers "F.Cu" "F.Mask" "F.Paste")
			(net "P3V3_STBY")
		)
		(pad "2" smd rect
			(at 0 0.889 90)
			(size 0.508 0.508)
			(layers "F.Cu" "F.Mask" "F.Paste")
			(net "RMII_SPRNGVLLE_BMC_PCH_RXD1")
		)
		(zone
			(layer "F.Cu")
			(hatch none 0.5)
			(connect_pads
				(clearance 0)
			)
			(min_thickness 0.25)
			(keepout
				(tracks allowed)
				(vias not_allowed)
				(pads allowed)
				(copperpour not_allowed)
				(footprints allowed)
			)
			(placement
				(enabled no)
				(sheetname "")
			)
			(fill
				(thermal_gap 0.5)
				(thermal_bridge_width 0.5)
				(island_removal_mode 0)
			)
			(polygon
				(pts
					(xy 407.9875 -22.733) (xy 407.9875 -23.241) (xy 408.3685 -23.241) (xy 408.3685 -22.733)
				)
			)
		)
		(zone
			(layer "F.Cu")
			(hatch none 0.5)
			(connect_pads
				(clearance 0)
			)
			(min_thickness 0.25)
			(keepout
				(tracks not_allowed)
				(vias allowed)
				(pads allowed)
				(copperpour not_allowed)
				(footprints allowed)
			)
			(placement
				(enabled no)
				(sheetname "")
			)
			(fill
				(thermal_gap 0.5)
				(thermal_bridge_width 0.5)
				(island_removal_mode 0)
			)
			(polygon
				(pts
					(xy 408.3685 -22.733) (xy 408.3685 -23.241) (xy 407.9875 -23.241) (xy 407.9875 -22.733)
				)
			)
		)
	)
	(footprint ""
		(layer "F.Cu")
		(at 449.69938 -33.5915 90)
		(property "Reference" "R25W11"
			(at 0 0 90)
			(layer "F.SilkS")
			(hide yes)
			(effects
				(font
					(size 1.27 1.27)
				)
			)
		)
		(property "Value" "*"
			(at 0.064008 -4.108196 90)
			(unlocked yes)
			(layer "F.Fab")
			(hide yes)
			(effects
				(font
					(size 1.27 1.016)
					(thickness 0.1524)
				)
			)
		)
		(property "Device Type" "120R2F-GP_RCL_GP-120R2F-GP,64.A"
			(at 0.064008 -5.632196 90)
			(unlocked yes)
			(layer "F.Fab")
			(hide yes)
			(effects
				(font
					(size 1.27 1.016)
					(thickness 0.1524)
				)
			)
		)
		(duplicate_pad_numbers_are_jumpers no)
		(fp_line
			(start 0.508 -0.9398)
			(end -0.508 -0.9398)
			(stroke
				(width 0.1524)
				(type default)
			)
			(layer "F.SilkS")
		)
		(fp_line
			(start -0.508 -0.9398)
			(end -0.508 0.9398)
			(stroke
				(width 0.1524)
				(type default)
			)
			(layer "F.SilkS")
		)
		(fp_rect
			(start -0.508 0.9398)
			(end 0.508 -0.9398)
			(stroke
				(width 0)
				(type default)
			)
			(fill no)
			(layer "F.CrtYd")
		)
		(fp_rect
			(start -0.508 0.9398)
			(end 0.508 -0.9398)
			(stroke
				(width 0)
				(type default)
			)
			(fill no)
			(layer "F.Fab")
		)
		(pad "1" smd custom
			(at 0 -0.4445 90)
			(size 0.1397 0.1397)
			(layers "F.Cu" "F.Mask" "F.Paste")
			(net "GND")
			(options
				(clearance outline)
				(anchor circle)
			)
			(primitives
				(gr_poly
					(pts
						(arc
							(start -0.1778 -0.2794)
							(mid -0.249642 -0.249642)
							(end -0.2794 -0.1778)
						)
						(arc
							(start -0.2794 0.1778)
							(mid -0.249642 0.249642)
							(end -0.1778 0.2794)
						)
						(arc
							(start 0.1778 0.2794)
							(mid 0.249642 0.249642)
							(end 0.2794 0.1778)
						)
						(arc
							(start 0.2794 -0.1778)
							(mid 0.249642 -0.249642)
							(end 0.1778 -0.2794)
						)
					)
					(width 0)
					(fill yes)
				)
			)
		)
		(pad "2" smd custom
			(at 0 0.4445 90)
			(size 0.1397 0.1397)
			(layers "F.Cu" "F.Mask" "F.Paste")
			(net "BMC_M_BG0")
			(options
				(clearance outline)
				(anchor circle)
			)
			(primitives
				(gr_poly
					(pts
						(arc
							(start -0.1778 -0.2794)
							(mid -0.249642 -0.249642)
							(end -0.2794 -0.1778)
						)
						(arc
							(start -0.2794 0.1778)
							(mid -0.249642 0.249642)
							(end -0.1778 0.2794)
						)
						(arc
							(start 0.1778 0.2794)
							(mid 0.249642 0.249642)
							(end 0.2794 0.1778)
						)
						(arc
							(start 0.2794 -0.1778)
							(mid 0.249642 -0.249642)
							(end 0.1778 -0.2794)
						)
					)
					(width 0)
					(fill yes)
				)
			)
		)
	)
	(footprint ""
		(layer "F.Cu")
		(at 172.681138 -96.310704 90)
		(property "Reference" "U4C2"
			(at -2.076704 5.272532 90)
			(unlocked yes)
			(layer "F.SilkS")
			(effects
				(font
					(size 0.7874 0.5842)
					(thickness 0.1524)
				)
				(justify left)
			)
		)
		(property "Value" ""
			(at 0 0 90)
			(layer "F.Fab")
			(effects
				(font
					(size 1.27 1.27)
				)
			)
		)
		(duplicate_pad_numbers_are_jumpers no)
		(fp_line
			(start 4.4323 -0.64008)
			(end 4.4323 4.52628)
			(stroke
				(width 0.1524)
				(type default)
			)
			(layer "F.SilkS")
		)
		(fp_line
			(start 2.667 -0.64008)
			(end 2.667 0.49022)
			(stroke
				(width 0.1524)
				(type default)
			)
			(layer "F.SilkS")
		)
		(fp_line
			(start 1.5367 -0.64008)
			(end 4.4323 -0.64008)
			(stroke
				(width 0.1524)
				(type default)
			)
			(layer "F.SilkS")
		)
		(fp_line
			(start 3.302 0.49022)
			(end 3.302 -0.64008)
			(stroke
				(width 0.1524)
				(type default)
			)
			(layer "F.SilkS")
		)
		(fp_line
			(start 2.667 0.49022)
			(end 3.302 0.49022)
			(stroke
				(width 0.1524)
				(type default)
			)
			(layer "F.SilkS")
		)
		(fp_line
			(start 4.4323 4.52628)
			(end 1.5367 4.52628)
			(stroke
				(width 0.1524)
				(type default)
			)
			(layer "F.SilkS")
		)
		(fp_line
			(start 1.5367 4.52628)
			(end 1.5367 -0.64008)
			(stroke
				(width 0.1524)
				(type default)
			)
			(layer "F.SilkS")
		)
		(fp_circle
			(center -1.612138 -0.684784)
			(end -1.612138 -0.557784)
			(stroke
				(width 0.254)
				(type default)
			)
			(fill no)
			(layer "F.SilkS")
		)
		(fp_poly
			(pts
				(xy 0.7366 4.54152) (xy 0.7366 -0.64008) (xy 4.7244 -0.64008) (xy 5.2324 -0.64008) (xy 5.2324 4.54152)
				(xy 4.7244 4.54152)
			)
			(stroke
				(width 0)
				(type default)
			)
			(fill no)
			(layer "F.CrtYd")
		)
		(fp_line
			(start 5.2324 -0.64008)
			(end 5.2324 4.54152)
			(stroke
				(width 0.1)
				(type default)
			)
			(layer "F.Fab")
		)
		(fp_line
			(start 2.667 -0.64008)
			(end 2.667 0.49022)
			(stroke
				(width 0.1)
				(type default)
			)
			(layer "F.Fab")
		)
		(fp_line
			(start 0.7366 -0.64008)
			(end 5.2324 -0.64008)
			(stroke
				(width 0.1)
				(type default)
			)
			(layer "F.Fab")
		)
		(fp_line
			(start 3.302 0.49022)
			(end 3.302 -0.64008)
			(stroke
				(width 0.1)
				(type default)
			)
			(layer "F.Fab")
		)
		(fp_line
			(start 2.667 0.49022)
			(end 3.302 0.49022)
			(stroke
				(width 0.1)
				(type default)
			)
			(layer "F.Fab")
		)
		(fp_line
			(start 5.2324 4.54152)
			(end 0.7366 4.54152)
			(stroke
				(width 0.1)
				(type default)
			)
			(layer "F.Fab")
		)
		(fp_line
			(start 0.7366 4.54152)
			(end 0.7366 -0.64008)
			(stroke
				(width 0.1)
				(type default)
			)
			(layer "F.Fab")
		)
		(fp_circle
			(center -1.612138 -0.684784)
			(end -1.612138 -0.557784)
			(stroke
				(width 0.635)
				(type default)
			)
			(fill no)
			(layer "F.Fab")
		)
		(pad "1" smd rect
			(at 0 0 90)
			(size 2.159 0.381)
			(layers "F.Cu" "F.Mask" "F.Paste")
			(net "PU_GTL2014_2_DIR")
		)
		(pad "2" smd rect
			(at 0 0.65024 90)
			(size 2.159 0.381)
			(layers "F.Cu" "F.Mask" "F.Paste")
			(net "PWRGD_CPU1_DRAMPWROK_KLM_G")
		)
		(pad "3" smd rect
			(at 0 1.30048 90)
			(size 2.159 0.381)
			(layers "F.Cu" "F.Mask" "F.Paste")
			(net "PWRGD_CPU1_DRAMPWROK_GHJ_G")
		)
		(pad "4" smd rect
			(at 0 1.95072 90)
			(size 2.159 0.381)
			(layers "F.Cu" "F.Mask" "F.Paste")
			(net "PD_GTL2014_2_VREF")
		)
		(pad "5" smd rect
			(at 0 2.60096 90)
			(size 2.159 0.381)
			(layers "F.Cu" "F.Mask" "F.Paste")
			(net "RST_CPU1_G_N")
		)
		(pad "6" smd rect
			(at 0 3.2512 90)
			(size 2.159 0.381)
			(layers "F.Cu" "F.Mask" "F.Paste")
			(net "PWRGD_CPU1_G")
		)
		(pad "7" smd rect
			(at 0 3.90144 90)
			(size 2.159 0.381)
			(layers "F.Cu" "F.Mask" "F.Paste")
			(net "GND")
		)
		(pad "8" smd rect
			(at 5.969 3.90144 90)
			(size 2.159 0.381)
			(layers "F.Cu" "F.Mask" "F.Paste")
			(net "GND")
		)
		(pad "9" smd rect
			(at 5.969 3.2512 90)
			(size 2.159 0.381)
			(layers "F.Cu" "F.Mask" "F.Paste")
			(net "PWRGD_CPU1_LVC3")
		)
		(pad "10" smd rect
			(at 5.969 2.60096 90)
			(size 2.159 0.381)
			(layers "F.Cu" "F.Mask" "F.Paste")
			(net "RST_CPU1_LVC3_N")
		)
		(pad "11" smd rect
			(at 5.969 1.95072 90)
			(size 2.159 0.381)
			(layers "F.Cu" "F.Mask" "F.Paste")
			(net "GND")
		)
		(pad "12" smd rect
			(at 5.969 1.30048 90)
			(size 2.159 0.381)
			(layers "F.Cu" "F.Mask" "F.Paste")
			(net "PWRGD_DRAMPWRGD")
		)
		(pad "13" smd rect
			(at 5.969 0.65024 90)
			(size 2.159 0.381)
			(layers "F.Cu" "F.Mask" "F.Paste")
			(net "PWRGD_DRAMPWRGD")
		)
		(pad "14" smd rect
			(at 5.969 0 90)
			(size 2.159 0.381)
			(layers "F.Cu" "F.Mask" "F.Paste")
			(net "P3V3_STBY")
		)
	)
	(footprint ""
		(layer "F.Cu")
		(at 12.7127 -5.197856 -90)
		(property "Reference" "R1G6"
			(at -0.8382 -0.67818 270)
			(unlocked yes)
			(layer "F.SilkS")
			(effects
				(font
					(size 0.4064 0.254)
					(thickness 0.1524)
				)
				(justify left)
			)
		)
		(property "Value" ""
			(at 0 0 270)
			(layer "F.Fab")
			(effects
				(font
					(size 1.27 1.27)
				)
			)
		)
		(duplicate_pad_numbers_are_jumpers no)
		(fp_poly
			(pts
				(xy -0.2794 -0.1016) (xy 0.2794 -0.1016) (xy 0.2794 0.9906) (xy -0.2794 0.9906)
			)
			(stroke
				(width 0)
				(type default)
			)
			(fill no)
			(layer "F.CrtYd")
		)
		(fp_line
			(start -0.2794 0.9906)
			(end 0.2794 0.9906)
			(stroke
				(width 0.1)
				(type default)
			)
			(layer "F.Fab")
		)
		(fp_line
			(start 0.2794 0.9906)
			(end 0.2794 -0.1016)
			(stroke
				(width 0.1)
				(type default)
			)
			(layer "F.Fab")
		)
		(fp_line
			(start -0.2794 -0.1016)
			(end -0.2794 0.9906)
			(stroke
				(width 0.1)
				(type default)
			)
			(layer "F.Fab")
		)
		(fp_line
			(start 0.2794 -0.1016)
			(end -0.2794 -0.1016)
			(stroke
				(width 0.1)
				(type default)
			)
			(layer "F.Fab")
		)
		(pad "1" smd rect
			(at 0 0 270)
			(size 0.508 0.508)
			(layers "F.Cu" "F.Mask" "F.Paste")
			(net "P3V3_STBY")
		)
		(pad "2" smd rect
			(at 0 0.889 270)
			(size 0.508 0.508)
			(layers "F.Cu" "F.Mask" "F.Paste")
			(net "PWRGD_PVDDQ_GHJ")
		)
		(zone
			(layer "F.Cu")
			(hatch none 0.5)
			(connect_pads
				(clearance 0)
			)
			(min_thickness 0.25)
			(keepout
				(tracks not_allowed)
				(vias allowed)
				(pads allowed)
				(copperpour not_allowed)
				(footprints allowed)
			)
			(placement
				(enabled no)
				(sheetname "")
			)
			(fill
				(thermal_gap 0.5)
				(thermal_bridge_width 0.5)
				(island_removal_mode 0)
			)
			(polygon
				(pts
					(xy 12.0777 -5.451856) (xy 12.0777 -4.943856) (xy 12.4587 -4.943856) (xy 12.4587 -5.451856)
				)
			)
		)
		(zone
			(layer "F.Cu")
			(hatch none 0.5)
			(connect_pads
				(clearance 0)
			)
			(min_thickness 0.25)
			(keepout
				(tracks allowed)
				(vias not_allowed)
				(pads allowed)
				(copperpour not_allowed)
				(footprints allowed)
			)
			(placement
				(enabled no)
				(sheetname "")
			)
			(fill
				(thermal_gap 0.5)
				(thermal_bridge_width 0.5)
				(island_removal_mode 0)
			)
			(polygon
				(pts
					(xy 12.4587 -5.451856) (xy 12.4587 -4.943856) (xy 12.0777 -4.943856) (xy 12.0777 -5.451856)
				)
			)
		)
	)
	(footprint ""
		(layer "F.Cu")
		(at 179.07 -84.328 180)
		(property "Reference" "R4D70"
			(at 0 0 180)
			(layer "F.SilkS")
			(hide yes)
			(effects
				(font
					(size 1.27 1.27)
				)
			)
		)
		(property "Value" ""
			(at 0 0 180)
			(layer "F.Fab")
			(effects
				(font
					(size 1.27 1.27)
				)
			)
		)
		(duplicate_pad_numbers_are_jumpers no)
		(fp_poly
			(pts
				(xy -0.2794 -0.1016) (xy 0.2794 -0.1016) (xy 0.2794 0.9906) (xy -0.2794 0.9906)
			)
			(stroke
				(width 0)
				(type default)
			)
			(fill no)
			(layer "F.CrtYd")
		)
		(fp_line
			(start 0.2794 0.9906)
			(end 0.2794 -0.1016)
			(stroke
				(width 0.1)
				(type default)
			)
			(layer "F.Fab")
		)
		(fp_line
			(start 0.2794 -0.1016)
			(end -0.2794 -0.1016)
			(stroke
				(width 0.1)
				(type default)
			)
			(layer "F.Fab")
		)
		(fp_line
			(start -0.2794 0.9906)
			(end 0.2794 0.9906)
			(stroke
				(width 0.1)
				(type default)
			)
			(layer "F.Fab")
		)
		(fp_line
			(start -0.2794 -0.1016)
			(end -0.2794 0.9906)
			(stroke
				(width 0.1)
				(type default)
			)
			(layer "F.Fab")
		)
		(pad "1" smd rect
			(at 0 0 180)
			(size 0.508 0.508)
			(layers "F.Cu" "F.Mask" "F.Paste")
			(net "P3V3")
		)
		(pad "2" smd rect
			(at 0 0.889 180)
			(size 0.508 0.508)
			(layers "F.Cu" "F.Mask" "F.Paste")
			(net "FM_CPU0_MCP_CLK_EN_N")
		)
		(zone
			(layer "F.Cu")
			(hatch none 0.5)
			(connect_pads
				(clearance 0)
			)
			(min_thickness 0.25)
			(keepout
				(tracks not_allowed)
				(vias allowed)
				(pads allowed)
				(copperpour not_allowed)
				(footprints allowed)
			)
			(placement
				(enabled no)
				(sheetname "")
			)
			(fill
				(thermal_gap 0.5)
				(thermal_bridge_width 0.5)
				(island_removal_mode 0)
			)
			(polygon
				(pts
					(xy 179.324 -84.963) (xy 178.816 -84.963) (xy 178.816 -84.582) (xy 179.324 -84.582)
				)
			)
		)
		(zone
			(layer "F.Cu")
			(hatch none 0.5)
			(connect_pads
				(clearance 0)
			)
			(min_thickness 0.25)
			(keepout
				(tracks allowed)
				(vias not_allowed)
				(pads allowed)
				(copperpour not_allowed)
				(footprints allowed)
			)
			(placement
				(enabled no)
				(sheetname "")
			)
			(fill
				(thermal_gap 0.5)
				(thermal_bridge_width 0.5)
				(island_removal_mode 0)
			)
			(polygon
				(pts
					(xy 179.324 -84.582) (xy 178.816 -84.582) (xy 178.816 -84.963) (xy 179.324 -84.963)
				)
			)
		)
	)
	(footprint ""
		(layer "F.Cu")
		(at 438.4675 -15.367 90)
		(property "Reference" "R1U53"
			(at 0 0 90)
			(layer "F.SilkS")
			(hide yes)
			(effects
				(font
					(size 1.27 1.27)
				)
			)
		)
		(property "Value" ""
			(at 0 0 90)
			(layer "F.Fab")
			(effects
				(font
					(size 1.27 1.27)
				)
			)
		)
		(duplicate_pad_numbers_are_jumpers no)
		(fp_poly
			(pts
				(xy -0.2794 -0.1016) (xy 0.2794 -0.1016) (xy 0.2794 0.9906) (xy -0.2794 0.9906)
			)
			(stroke
				(width 0)
				(type default)
			)
			(fill no)
			(layer "F.CrtYd")
		)
		(fp_line
			(start 0.2794 -0.1016)
			(end -0.2794 -0.1016)
			(stroke
				(width 0.1)
				(type default)
			)
			(layer "F.Fab")
		)
		(fp_line
			(start -0.2794 -0.1016)
			(end -0.2794 0.9906)
			(stroke
				(width 0.1)
				(type default)
			)
			(layer "F.Fab")
		)
		(fp_line
			(start 0.2794 0.9906)
			(end 0.2794 -0.1016)
			(stroke
				(width 0.1)
				(type default)
			)
			(layer "F.Fab")
		)
		(fp_line
			(start -0.2794 0.9906)
			(end 0.2794 0.9906)
			(stroke
				(width 0.1)
				(type default)
			)
			(layer "F.Fab")
		)
		(pad "1" smd rect
			(at 0 0 90)
			(size 0.508 0.508)
			(layers "F.Cu" "F.Mask" "F.Paste")
			(net "H_CPU1_MEMGHJ_MEMHOT_G_N")
		)
		(pad "2" smd rect
			(at 0 0.889 90)
			(size 0.508 0.508)
			(layers "F.Cu" "F.Mask" "F.Paste")
			(net "H_CPU1_MEMGHJ_MEMHOT_G_R_N")
		)
		(zone
			(layer "F.Cu")
			(hatch none 0.5)
			(connect_pads
				(clearance 0)
			)
			(min_thickness 0.25)
			(keepout
				(tracks allowed)
				(vias not_allowed)
				(pads allowed)
				(copperpour not_allowed)
				(footprints allowed)
			)
			(placement
				(enabled no)
				(sheetname "")
			)
			(fill
				(thermal_gap 0.5)
				(thermal_bridge_width 0.5)
				(island_removal_mode 0)
			)
			(polygon
				(pts
					(xy 438.7215 -15.113) (xy 438.7215 -15.621) (xy 439.1025 -15.621) (xy 439.1025 -15.113)
				)
			)
		)
		(zone
			(layer "F.Cu")
			(hatch none 0.5)
			(connect_pads
				(clearance 0)
			)
			(min_thickness 0.25)
			(keepout
				(tracks not_allowed)
				(vias allowed)
				(pads allowed)
				(copperpour not_allowed)
				(footprints allowed)
			)
			(placement
				(enabled no)
				(sheetname "")
			)
			(fill
				(thermal_gap 0.5)
				(thermal_bridge_width 0.5)
				(island_removal_mode 0)
			)
			(polygon
				(pts
					(xy 439.1025 -15.113) (xy 439.1025 -15.621) (xy 438.7215 -15.621) (xy 438.7215 -15.113)
				)
			)
		)
	)
	(footprint ""
		(layer "F.Cu")
		(at 497.120926 -20.703286 90)
		(property "Reference" "C7E9"
			(at 0 0 90)
			(layer "F.SilkS")
			(hide yes)
			(effects
				(font
					(size 1.27 1.27)
				)
			)
		)
		(property "Value" ""
			(at 0 0 90)
			(layer "F.Fab")
			(effects
				(font
					(size 1.27 1.27)
				)
			)
		)
		(duplicate_pad_numbers_are_jumpers no)
		(fp_rect
			(start 0.3048 0.9906)
			(end -0.3048 -0.1016)
			(stroke
				(width 0)
				(type default)
			)
			(fill no)
			(layer "F.CrtYd")
		)
		(fp_line
			(start 0.3048 -0.1016)
			(end -0.3048 -0.1016)
			(stroke
				(width 0.1)
				(type default)
			)
			(layer "F.Fab")
		)
		(fp_line
			(start -0.3048 -0.1016)
			(end -0.3048 0.9906)
			(stroke
				(width 0.1)
				(type default)
			)
			(layer "F.Fab")
		)
		(fp_line
			(start 0.3048 0.9906)
			(end 0.3048 -0.1016)
			(stroke
				(width 0.1)
				(type default)
			)
			(layer "F.Fab")
		)
		(fp_line
			(start -0.3048 0.9906)
			(end 0.3048 0.9906)
			(stroke
				(width 0.1)
				(type default)
			)
			(layer "F.Fab")
		)
		(pad "1" smd rect
			(at 0 0 90)
			(size 0.508 0.508)
			(layers "F.Cu" "F.Mask" "F.Paste")
			(net "P12V")
		)
		(pad "2" smd rect
			(at 0 0.889 90)
			(size 0.508 0.508)
			(layers "F.Cu" "F.Mask" "F.Paste")
			(net "GND")
		)
		(zone
			(layer "F.Cu")
			(hatch none 0.5)
			(connect_pads
				(clearance 0)
			)
			(min_thickness 0.25)
			(keepout
				(tracks allowed)
				(vias not_allowed)
				(pads allowed)
				(copperpour not_allowed)
				(footprints allowed)
			)
			(placement
				(enabled no)
				(sheetname "")
			)
			(fill
				(thermal_gap 0.5)
				(thermal_bridge_width 0.5)
				(island_removal_mode 0)
			)
			(polygon
				(pts
					(xy 497.755926 -20.957286) (xy 497.374926 -20.957286) (xy 497.374926 -20.449286) (xy 497.755926 -20.449286)
				)
			)
		)
		(zone
			(layer "F.Cu")
			(hatch none 0.5)
			(connect_pads
				(clearance 0)
			)
			(min_thickness 0.25)
			(keepout
				(tracks not_allowed)
				(vias allowed)
				(pads allowed)
				(copperpour not_allowed)
				(footprints allowed)
			)
			(placement
				(enabled no)
				(sheetname "")
			)
			(fill
				(thermal_gap 0.5)
				(thermal_bridge_width 0.5)
				(island_removal_mode 0)
			)
			(polygon
				(pts
					(xy 497.755926 -20.957286) (xy 497.374926 -20.957286) (xy 497.374926 -20.449286) (xy 497.755926 -20.449286)
				)
			)
		)
	)
	(footprint ""
		(layer "F.Cu")
		(at 181.8132 -57.785 -90)
		(property "Reference" "CT63"
			(at -1.19253 2.8956 0)
			(unlocked yes)
			(layer "F.SilkS")
			(effects
				(font
					(size 0.7874 0.5842)
					(thickness 0.1524)
				)
				(justify left)
			)
		)
		(property "Value" ""
			(at 0 0 270)
			(layer "F.Fab")
			(effects
				(font
					(size 1.27 1.27)
				)
			)
		)
		(duplicate_pad_numbers_are_jumpers no)
		(fp_poly
			(pts
				(xy 0.3048 -0.1016) (xy 0.3048 0.9906) (xy -0.3048 0.9906) (xy -0.3048 -0.1016)
			)
			(stroke
				(width 0)
				(type default)
			)
			(fill no)
			(layer "F.CrtYd")
		)
		(fp_line
			(start -0.3048 0.9906)
			(end 0.3048 0.9906)
			(stroke
				(width 0.1)
				(type default)
			)
			(layer "F.Fab")
		)
		(fp_line
			(start 0.3048 0.9906)
			(end 0.3048 -0.1016)
			(stroke
				(width 0.1)
				(type default)
			)
			(layer "F.Fab")
		)
		(fp_line
			(start -0.3048 -0.1016)
			(end -0.3048 0.9906)
			(stroke
				(width 0.1)
				(type default)
			)
			(layer "F.Fab")
		)
		(fp_line
			(start 0.3048 -0.1016)
			(end -0.3048 -0.1016)
			(stroke
				(width 0.1)
				(type default)
			)
			(layer "F.Fab")
		)
		(pad "1" smd rect
			(at 0 0 270)
			(size 0.508 0.508)
			(layers "F.Cu" "F.Mask" "F.Paste")
			(net "VR_PVCCIO_CPU1_AIREF1")
		)
		(pad "2" smd rect
			(at 0 0.889 270)
			(size 0.508 0.508)
			(layers "F.Cu" "F.Mask" "F.Paste")
			(net "GND")
		)
		(zone
			(layer "F.Cu")
			(hatch none 0.5)
			(connect_pads
				(clearance 0)
			)
			(min_thickness 0.25)
			(keepout
				(tracks not_allowed)
				(vias allowed)
				(pads allowed)
				(copperpour not_allowed)
				(footprints allowed)
			)
			(placement
				(enabled no)
				(sheetname "")
			)
			(fill
				(thermal_gap 0.5)
				(thermal_bridge_width 0.5)
				(island_removal_mode 0)
			)
			(polygon
				(pts
					(xy 181.1782 -58.039) (xy 181.1782 -57.531) (xy 181.5592 -57.531) (xy 181.5592 -58.039)
				)
			)
		)
		(zone
			(layer "F.Cu")
			(hatch none 0.5)
			(connect_pads
				(clearance 0)
			)
			(min_thickness 0.25)
			(keepout
				(tracks allowed)
				(vias not_allowed)
				(pads allowed)
				(copperpour not_allowed)
				(footprints allowed)
			)
			(placement
				(enabled no)
				(sheetname "")
			)
			(fill
				(thermal_gap 0.5)
				(thermal_bridge_width 0.5)
				(island_removal_mode 0)
			)
			(polygon
				(pts
					(xy 181.5592 -58.039) (xy 181.5592 -57.531) (xy 181.1782 -57.531) (xy 181.1782 -58.039)
				)
			)
		)
	)
	(footprint ""
		(layer "F.Cu")
		(at 169.422826 -80.961992 90)
		(property "Reference" "EU4D2"
			(at -8.471662 1.773174 0)
			(unlocked yes)
			(layer "F.SilkS")
			(effects
				(font
					(size 0.7874 0.5842)
					(thickness 0.1524)
				)
				(justify left)
			)
		)
		(property "Value" ""
			(at 0 0 90)
			(layer "F.Fab")
			(effects
				(font
					(size 1.27 1.27)
				)
			)
		)
		(duplicate_pad_numbers_are_jumpers no)
		(fp_line
			(start 5.0038 -5.0038)
			(end 5.0038 5.0038)
			(stroke
				(width 0.1524)
				(type default)
			)
			(layer "F.SilkS")
		)
		(fp_line
			(start -5.0038 -5.0038)
			(end 5.0038 -5.0038)
			(stroke
				(width 0.1524)
				(type default)
			)
			(layer "F.SilkS")
		)
		(fp_line
			(start 5.0038 5.0038)
			(end -5.0038 5.0038)
			(stroke
				(width 0.1524)
				(type default)
			)
			(layer "F.SilkS")
		)
		(fp_line
			(start -5.0038 5.0038)
			(end -5.0038 -5.0038)
			(stroke
				(width 0.1524)
				(type default)
			)
			(layer "F.SilkS")
		)
		(fp_circle
			(center -5.531612 -3.84556)
			(end -5.531612 -3.71856)
			(stroke
				(width 0.254)
				(type default)
			)
			(fill no)
			(layer "F.SilkS")
		)
		(fp_poly
			(pts
				(xy -5.0038 -5.0038) (xy -5.0038 -4.0894) (xy -4.0894 -5.0038)
			)
			(stroke
				(width 0)
				(type default)
			)
			(fill yes)
			(layer "F.SilkS")
		)
		(fp_poly
			(pts
				(xy -3.1242 -3.1242) (xy -3.1242 3.1242) (xy 3.1242 3.1242) (xy 3.1242 -3.1242)
			)
			(stroke
				(width 0)
				(type default)
			)
			(fill yes)
			(layer "F.Paste")
		)
		(fp_rect
			(start -4.52501 4.52501)
			(end 4.52501 -4.52501)
			(stroke
				(width 0)
				(type default)
			)
			(fill no)
			(layer "F.CrtYd")
		)
		(fp_line
			(start 4.52501 -4.52501)
			(end 4.52501 4.52501)
			(stroke
				(width 0.1)
				(type default)
			)
			(layer "F.Fab")
		)
		(fp_line
			(start -4.52501 -4.52501)
			(end 4.52501 -4.52501)
			(stroke
				(width 0.1)
				(type default)
			)
			(layer "F.Fab")
		)
		(fp_line
			(start 4.52501 4.52501)
			(end -4.52501 4.52501)
			(stroke
				(width 0.1)
				(type default)
			)
			(layer "F.Fab")
		)
		(fp_line
			(start -4.52501 4.52501)
			(end -4.52501 -4.52501)
			(stroke
				(width 0.1)
				(type default)
			)
			(layer "F.Fab")
		)
		(fp_circle
			(center -5.531612 -3.84556)
			(end -5.531612 -3.71856)
			(stroke
				(width 0.254)
				(type default)
			)
			(fill no)
			(layer "F.Fab")
		)
		(pad "1" smd custom
			(at -4.3688 -3.750818 90)
			(size 0.0762 0.0762)
			(layers "F.Cu" "F.Mask" "F.Paste")
			(net "P3V3_DB1200_A")
			(options
				(clearance outline)
				(anchor circle)
			)
			(primitives
				(gr_poly
					(pts
						(xy -0.381 -0.1524)
						(arc
							(start 0.2286 -0.1524)
							(mid 0.381 0)
							(end 0.2286 0.1524)
						)
						(xy -0.381 0.1524)
					)
					(width 0)
					(fill yes)
				)
			)
		)
		(pad "2" smd custom
			(at -4.3688 -3.250692 90)
			(size 0.0762 0.0762)
			(layers "F.Cu" "F.Mask" "F.Paste")
			(net "GND")
			(options
				(clearance outline)
				(anchor circle)
			)
			(primitives
				(gr_poly
					(pts
						(xy -0.381 -0.1524)
						(arc
							(start 0.2286 -0.1524)
							(mid 0.381 0)
							(end 0.2286 0.1524)
						)
						(xy -0.381 0.1524)
					)
					(width 0)
					(fill yes)
				)
			)
		)
		(pad "3" smd custom
			(at -4.3688 -2.750566 90)
			(size 0.0762 0.0762)
			(layers "F.Cu" "F.Mask" "F.Paste")
			(net "Net_341")
			(options
				(clearance outline)
				(anchor circle)
			)
			(primitives
				(gr_poly
					(pts
						(xy -0.381 -0.1524)
						(arc
							(start 0.2286 -0.1524)
							(mid 0.381 0)
							(end 0.2286 0.1524)
						)
						(xy -0.381 0.1524)
					)
					(width 0)
					(fill yes)
				)
			)
		)
		(pad "4" smd custom
			(at -4.3688 -2.25044 90)
			(size 0.0762 0.0762)
			(layers "F.Cu" "F.Mask" "F.Paste")
			(net "FM_100M_N")
			(options
				(clearance outline)
				(anchor circle)
			)
			(primitives
				(gr_poly
					(pts
						(xy -0.381 -0.1524)
						(arc
							(start 0.2286 -0.1524)
							(mid 0.381 0)
							(end 0.2286 0.1524)
						)
						(xy -0.381 0.1524)
					)
					(width 0)
					(fill yes)
				)
			)
		)
		(pad "5" smd custom
			(at -4.3688 -1.750314 90)
			(size 0.0762 0.0762)
			(layers "F.Cu" "F.Mask" "F.Paste")
			(net "FM_HBW_BYPASS_LOWBW_N")
			(options
				(clearance outline)
				(anchor circle)
			)
			(primitives
				(gr_poly
					(pts
						(xy -0.381 -0.1524)
						(arc
							(start 0.2286 -0.1524)
							(mid 0.381 0)
							(end 0.2286 0.1524)
						)
						(xy -0.381 0.1524)
					)
					(width 0)
					(fill yes)
				)
			)
		)
		(pad "6" smd custom
			(at -4.3688 -1.250188 90)
			(size 0.0762 0.0762)
			(layers "F.Cu" "F.Mask" "F.Paste")
			(net "FM_DB1200_PWRGD_R")
			(options
				(clearance outline)
				(anchor circle)
			)
			(primitives
				(gr_poly
					(pts
						(xy -0.381 -0.1524)
						(arc
							(start 0.2286 -0.1524)
							(mid 0.381 0)
							(end 0.2286 0.1524)
						)
						(xy -0.381 0.1524)
					)
					(width 0)
					(fill yes)
				)
			)
		)
		(pad "7" smd custom
			(at -4.3688 -0.750062 90)
			(size 0.0762 0.0762)
			(layers "F.Cu" "F.Mask" "F.Paste")
			(net "GND")
			(options
				(clearance outline)
				(anchor circle)
			)
			(primitives
				(gr_poly
					(pts
						(xy -0.381 -0.1524)
						(arc
							(start 0.2286 -0.1524)
							(mid 0.381 0)
							(end 0.2286 0.1524)
						)
						(xy -0.381 0.1524)
					)
					(width 0)
					(fill yes)
				)
			)
		)
		(pad "8" smd custom
			(at -4.3688 -0.249936 90)
			(size 0.0762 0.0762)
			(layers "F.Cu" "F.Mask" "F.Paste")
			(net "P3V3_DB1200_R")
			(options
				(clearance outline)
				(anchor circle)
			)
			(primitives
				(gr_poly
					(pts
						(xy -0.381 -0.1524)
						(arc
							(start 0.2286 -0.1524)
							(mid 0.381 0)
							(end 0.2286 0.1524)
						)
						(xy -0.381 0.1524)
					)
					(width 0)
					(fill yes)
				)
			)
		)
		(pad "9" smd custom
			(at -4.3688 0.25019 90)
			(size 0.0762 0.0762)
			(layers "F.Cu" "F.Mask" "F.Paste")
			(net "CLK_100M_DB1200_DP")
			(options
				(clearance outline)
				(anchor circle)
			)
			(primitives
				(gr_poly
					(pts
						(xy -0.381 -0.1524)
						(arc
							(start 0.2286 -0.1524)
							(mid 0.381 0)
							(end 0.2286 0.1524)
						)
						(xy -0.381 0.1524)
					)
					(width 0)
					(fill yes)
				)
			)
		)
		(pad "10" smd custom
			(at -4.3688 0.750316 90)
			(size 0.0762 0.0762)
			(layers "F.Cu" "F.Mask" "F.Paste")
			(net "CLK_100M_DB1200_DN")
			(options
				(clearance outline)
				(anchor circle)
			)
			(primitives
				(gr_poly
					(pts
						(xy -0.381 -0.1524)
						(arc
							(start 0.2286 -0.1524)
							(mid 0.381 0)
							(end 0.2286 0.1524)
						)
						(xy -0.381 0.1524)
					)
					(width 0)
					(fill yes)
				)
			)
		)
		(pad "11" smd custom
			(at -4.3688 1.250442 90)
			(size 0.0762 0.0762)
			(layers "F.Cu" "F.Mask" "F.Paste")
			(net "FM_DB1200_SMB_SA0")
			(options
				(clearance outline)
				(anchor circle)
			)
			(primitives
				(gr_poly
					(pts
						(xy -0.381 -0.1524)
						(arc
							(start 0.2286 -0.1524)
							(mid 0.381 0)
							(end 0.2286 0.1524)
						)
						(xy -0.381 0.1524)
					)
					(width 0)
					(fill yes)
				)
			)
		)
		(pad "12" smd custom
			(at -4.3688 1.750568 90)
			(size 0.0762 0.0762)
			(layers "F.Cu" "F.Mask" "F.Paste")
			(net "SMB_HOST_STBY_LVC3_SDA_R2")
			(options
				(clearance outline)
				(anchor circle)
			)
			(primitives
				(gr_poly
					(pts
						(xy -0.381 -0.1524)
						(arc
							(start 0.2286 -0.1524)
							(mid 0.381 0)
							(end 0.2286 0.1524)
						)
						(xy -0.381 0.1524)
					)
					(width 0)
					(fill yes)
				)
			)
		)
		(pad "13" smd custom
			(at -4.3688 2.250694 90)
			(size 0.0762 0.0762)
			(layers "F.Cu" "F.Mask" "F.Paste")
			(net "SMB_HOST_STBY_LVC3_SCL_R2")
			(options
				(clearance outline)
				(anchor circle)
			)
			(primitives
				(gr_poly
					(pts
						(xy -0.381 -0.1524)
						(arc
							(start 0.2286 -0.1524)
							(mid 0.381 0)
							(end 0.2286 0.1524)
						)
						(xy -0.381 0.1524)
					)
					(width 0)
					(fill yes)
				)
			)
		)
		(pad "14" smd custom
			(at -4.3688 2.75082 90)
			(size 0.0762 0.0762)
			(layers "F.Cu" "F.Mask" "F.Paste")
			(net "FM_DB1200_SMB_SA1")
			(options
				(clearance outline)
				(anchor circle)
			)
			(primitives
				(gr_poly
					(pts
						(xy -0.381 -0.1524)
						(arc
							(start 0.2286 -0.1524)
							(mid 0.381 0)
							(end 0.2286 0.1524)
						)
						(xy -0.381 0.1524)
					)
					(width 0)
					(fill yes)
				)
			)
		)
		(pad "15" smd custom
			(at -4.3688 3.250946 90)
			(size 0.0762 0.0762)
			(layers "F.Cu" "F.Mask" "F.Paste")
			(net "Net_342")
			(options
				(clearance outline)
				(anchor circle)
			)
			(primitives
				(gr_poly
					(pts
						(xy -0.381 -0.1524)
						(arc
							(start 0.2286 -0.1524)
							(mid 0.381 0)
							(end 0.2286 0.1524)
						)
						(xy -0.381 0.1524)
					)
					(width 0)
					(fill yes)
				)
			)
		)
		(pad "16" smd custom
			(at -4.3688 3.751072 90)
			(size 0.0762 0.0762)
			(layers "F.Cu" "F.Mask" "F.Paste")
			(net "Net_343")
			(options
				(clearance outline)
				(anchor circle)
			)
			(primitives
				(gr_poly
					(pts
						(xy -0.381 -0.1524)
						(arc
							(start 0.2286 -0.1524)
							(mid 0.381 0)
							(end 0.2286 0.1524)
						)
						(xy -0.381 0.1524)
					)
					(width 0)
					(fill yes)
				)
			)
		)
		(pad "17" smd custom
			(at -3.750818 4.3688 90)
			(size 0.0762 0.0762)
			(layers "F.Cu" "F.Mask" "F.Paste")
			(net "CLK_100M_CPU0_BCLK0_R_DP")
			(options
				(clearance outline)
				(anchor circle)
			)
			(primitives
				(gr_poly
					(pts
						(xy -0.1524 0.381)
						(arc
							(start -0.1524 -0.2286)
							(mid 0 -0.381)
							(end 0.1524 -0.2286)
						)
						(xy 0.1524 0.381)
					)
					(width 0)
					(fill yes)
				)
			)
		)
		(pad "18" smd custom
			(at -3.250692 4.3688 90)
			(size 0.0762 0.0762)
			(layers "F.Cu" "F.Mask" "F.Paste")
			(net "CLK_100M_CPU0_BCLK0_R_DN")
			(options
				(clearance outline)
				(anchor circle)
			)
			(primitives
				(gr_poly
					(pts
						(xy -0.1524 0.381)
						(arc
							(start -0.1524 -0.2286)
							(mid 0 -0.381)
							(end 0.1524 -0.2286)
						)
						(xy 0.1524 0.381)
					)
					(width 0)
					(fill yes)
				)
			)
		)
		(pad "19" smd custom
			(at -2.750566 4.3688 90)
			(size 0.0762 0.0762)
			(layers "F.Cu" "F.Mask" "F.Paste")
			(net "FM_DB1200ZL_BCLKS_EN_N")
			(options
				(clearance outline)
				(anchor circle)
			)
			(primitives
				(gr_poly
					(pts
						(xy -0.1524 0.381)
						(arc
							(start -0.1524 -0.2286)
							(mid 0 -0.381)
							(end 0.1524 -0.2286)
						)
						(xy 0.1524 0.381)
					)
					(width 0)
					(fill yes)
				)
			)
		)
		(pad "20" smd custom
			(at -2.25044 4.3688 90)
			(size 0.0762 0.0762)
			(layers "F.Cu" "F.Mask" "F.Paste")
			(net "FM_DB1200ZL_BCLKS_EN_N")
			(options
				(clearance outline)
				(anchor circle)
			)
			(primitives
				(gr_poly
					(pts
						(xy -0.1524 0.381)
						(arc
							(start -0.1524 -0.2286)
							(mid 0 -0.381)
							(end 0.1524 -0.2286)
						)
						(xy 0.1524 0.381)
					)
					(width 0)
					(fill yes)
				)
			)
		)
		(pad "21" smd custom
			(at -1.750314 4.3688 90)
			(size 0.0762 0.0762)
			(layers "F.Cu" "F.Mask" "F.Paste")
			(net "CLK_100M_CPU0_BCLK1_R_DP")
			(options
				(clearance outline)
				(anchor circle)
			)
			(primitives
				(gr_poly
					(pts
						(xy -0.1524 0.381)
						(arc
							(start -0.1524 -0.2286)
							(mid 0 -0.381)
							(end 0.1524 -0.2286)
						)
						(xy 0.1524 0.381)
					)
					(width 0)
					(fill yes)
				)
			)
		)
		(pad "22" smd custom
			(at -1.250188 4.3688 90)
			(size 0.0762 0.0762)
			(layers "F.Cu" "F.Mask" "F.Paste")
			(net "CLK_100M_CPU0_BCLK1_R_DN")
			(options
				(clearance outline)
				(anchor circle)
			)
			(primitives
				(gr_poly
					(pts
						(xy -0.1524 0.381)
						(arc
							(start -0.1524 -0.2286)
							(mid 0 -0.381)
							(end 0.1524 -0.2286)
						)
						(xy 0.1524 0.381)
					)
					(width 0)
					(fill yes)
				)
			)
		)
		(pad "23" smd custom
			(at -0.750062 4.3688 90)
			(size 0.0762 0.0762)
			(layers "F.Cu" "F.Mask" "F.Paste")
			(net "GND")
			(options
				(clearance outline)
				(anchor circle)
			)
			(primitives
				(gr_poly
					(pts
						(xy -0.1524 0.381)
						(arc
							(start -0.1524 -0.2286)
							(mid 0 -0.381)
							(end 0.1524 -0.2286)
						)
						(xy 0.1524 0.381)
					)
					(width 0)
					(fill yes)
				)
			)
		)
		(pad "24" smd custom
			(at -0.249936 4.3688 90)
			(size 0.0762 0.0762)
			(layers "F.Cu" "F.Mask" "F.Paste")
			(net "P3V3_DB1200")
			(options
				(clearance outline)
				(anchor circle)
			)
			(primitives
				(gr_poly
					(pts
						(xy -0.1524 0.381)
						(arc
							(start -0.1524 -0.2286)
							(mid 0 -0.381)
							(end 0.1524 -0.2286)
						)
						(xy 0.1524 0.381)
					)
					(width 0)
					(fill yes)
				)
			)
		)
		(pad "25" smd custom
			(at 0.25019 4.3688 90)
			(size 0.0762 0.0762)
			(layers "F.Cu" "F.Mask" "F.Paste")
			(net "P3V3_DB1200")
			(options
				(clearance outline)
				(anchor circle)
			)
			(primitives
				(gr_poly
					(pts
						(xy -0.1524 0.381)
						(arc
							(start -0.1524 -0.2286)
							(mid 0 -0.381)
							(end 0.1524 -0.2286)
						)
						(xy 0.1524 0.381)
					)
					(width 0)
					(fill yes)
				)
			)
		)
		(pad "26" smd custom
			(at 0.750316 4.3688 90)
			(size 0.0762 0.0762)
			(layers "F.Cu" "F.Mask" "F.Paste")
			(net "CLK_100M_CPU0_BCLK2_R_DP")
			(options
				(clearance outline)
				(anchor circle)
			)
			(primitives
				(gr_poly
					(pts
						(xy -0.1524 0.381)
						(arc
							(start -0.1524 -0.2286)
							(mid 0 -0.381)
							(end 0.1524 -0.2286)
						)
						(xy 0.1524 0.381)
					)
					(width 0)
					(fill yes)
				)
			)
		)
		(pad "27" smd custom
			(at 1.250442 4.3688 90)
			(size 0.0762 0.0762)
			(layers "F.Cu" "F.Mask" "F.Paste")
			(net "CLK_100M_CPU0_BCLK2_R_DN")
			(options
				(clearance outline)
				(anchor circle)
			)
			(primitives
				(gr_poly
					(pts
						(xy -0.1524 0.381)
						(arc
							(start -0.1524 -0.2286)
							(mid 0 -0.381)
							(end 0.1524 -0.2286)
						)
						(xy 0.1524 0.381)
					)
					(width 0)
					(fill yes)
				)
			)
		)
		(pad "28" smd custom
			(at 1.750568 4.3688 90)
			(size 0.0762 0.0762)
			(layers "F.Cu" "F.Mask" "F.Paste")
			(net "FM_DB1200ZL_BCLKS_EN_N")
			(options
				(clearance outline)
				(anchor circle)
			)
			(primitives
				(gr_poly
					(pts
						(xy -0.1524 0.381)
						(arc
							(start -0.1524 -0.2286)
							(mid 0 -0.381)
							(end 0.1524 -0.2286)
						)
						(xy 0.1524 0.381)
					)
					(width 0)
					(fill yes)
				)
			)
		)
		(pad "29" smd custom
			(at 2.250694 4.3688 90)
			(size 0.0762 0.0762)
			(layers "F.Cu" "F.Mask" "F.Paste")
			(net "FM_CPU0_MCP_CLK_EN_N")
			(options
				(clearance outline)
				(anchor circle)
			)
			(primitives
				(gr_poly
					(pts
						(xy -0.1524 0.381)
						(arc
							(start -0.1524 -0.2286)
							(mid 0 -0.381)
							(end 0.1524 -0.2286)
						)
						(xy 0.1524 0.381)
					)
					(width 0)
					(fill yes)
				)
			)
		)
		(pad "30" smd custom
			(at 2.75082 4.3688 90)
			(size 0.0762 0.0762)
			(layers "F.Cu" "F.Mask" "F.Paste")
			(net "CLK_100M_CPU0_PE_REFCLK_R_DP")
			(options
				(clearance outline)
				(anchor circle)
			)
			(primitives
				(gr_poly
					(pts
						(xy -0.1524 0.381)
						(arc
							(start -0.1524 -0.2286)
							(mid 0 -0.381)
							(end 0.1524 -0.2286)
						)
						(xy 0.1524 0.381)
					)
					(width 0)
					(fill yes)
				)
			)
		)
		(pad "31" smd custom
			(at 3.250946 4.3688 90)
			(size 0.0762 0.0762)
			(layers "F.Cu" "F.Mask" "F.Paste")
			(net "CLK_100M_CPU0_PE_REFCLK_R_DN")
			(options
				(clearance outline)
				(anchor circle)
			)
			(primitives
				(gr_poly
					(pts
						(xy -0.1524 0.381)
						(arc
							(start -0.1524 -0.2286)
							(mid 0 -0.381)
							(end 0.1524 -0.2286)
						)
						(xy 0.1524 0.381)
					)
					(width 0)
					(fill yes)
				)
			)
		)
		(pad "32" smd custom
			(at 3.751072 4.3688 90)
			(size 0.0762 0.0762)
			(layers "F.Cu" "F.Mask" "F.Paste")
			(net "P3V3_DB1200")
			(options
				(clearance outline)
				(anchor circle)
			)
			(primitives
				(gr_poly
					(pts
						(xy -0.1524 0.381)
						(arc
							(start -0.1524 -0.2286)
							(mid 0 -0.381)
							(end 0.1524 -0.2286)
						)
						(xy 0.1524 0.381)
					)
					(width 0)
					(fill yes)
				)
			)
		)
		(pad "33" smd custom
			(at 4.3688 3.751072 90)
			(size 0.0762 0.0762)
			(layers "F.Cu" "F.Mask" "F.Paste")
			(net "GND")
			(options
				(clearance outline)
				(anchor circle)
			)
			(primitives
				(gr_poly
					(pts
						(xy 0.381 0.1524)
						(arc
							(start -0.2286 0.1524)
							(mid -0.381 0)
							(end -0.2286 -0.1524)
						)
						(xy 0.381 -0.1524)
					)
					(width 0)
					(fill yes)
				)
			)
		)
		(pad "34" smd custom
			(at 4.3688 3.250946 90)
			(size 0.0762 0.0762)
			(layers "F.Cu" "F.Mask" "F.Paste")
			(net "CLK_100M_CPU0_RC_REFCLK0_R_DP")
			(options
				(clearance outline)
				(anchor circle)
			)
			(primitives
				(gr_poly
					(pts
						(xy 0.381 0.1524)
						(arc
							(start -0.2286 0.1524)
							(mid -0.381 0)
							(end -0.2286 -0.1524)
						)
						(xy 0.381 -0.1524)
					)
					(width 0)
					(fill yes)
				)
			)
		)
		(pad "35" smd custom
			(at 4.3688 2.75082 90)
			(size 0.0762 0.0762)
			(layers "F.Cu" "F.Mask" "F.Paste")
			(net "CLK_100M_CPU0_RC_REFCLK0_R_DN")
			(options
				(clearance outline)
				(anchor circle)
			)
			(primitives
				(gr_poly
					(pts
						(xy 0.381 0.1524)
						(arc
							(start -0.2286 0.1524)
							(mid -0.381 0)
							(end -0.2286 -0.1524)
						)
						(xy 0.381 -0.1524)
					)
					(width 0)
					(fill yes)
				)
			)
		)
		(pad "36" smd custom
			(at 4.3688 2.250694 90)
			(size 0.0762 0.0762)
			(layers "F.Cu" "F.Mask" "F.Paste")
			(net "FM_CPU0_MCP_CLK_EN_N")
			(options
				(clearance outline)
				(anchor circle)
			)
			(primitives
				(gr_poly
					(pts
						(xy 0.381 0.1524)
						(arc
							(start -0.2286 0.1524)
							(mid -0.381 0)
							(end -0.2286 -0.1524)
						)
						(xy 0.381 -0.1524)
					)
					(width 0)
					(fill yes)
				)
			)
		)
		(pad "37" smd custom
			(at 4.3688 1.750568 90)
			(size 0.0762 0.0762)
			(layers "F.Cu" "F.Mask" "F.Paste")
			(net "FM_CPU0_MCP_CLK_EN_N")
			(options
				(clearance outline)
				(anchor circle)
			)
			(primitives
				(gr_poly
					(pts
						(xy 0.381 0.1524)
						(arc
							(start -0.2286 0.1524)
							(mid -0.381 0)
							(end -0.2286 -0.1524)
						)
						(xy 0.381 -0.1524)
					)
					(width 0)
					(fill yes)
				)
			)
		)
		(pad "38" smd custom
			(at 4.3688 1.250442 90)
			(size 0.0762 0.0762)
			(layers "F.Cu" "F.Mask" "F.Paste")
			(net "CLK_100M_CPU0_RC_REFCLK1_R_DP")
			(options
				(clearance outline)
				(anchor circle)
			)
			(primitives
				(gr_poly
					(pts
						(xy 0.381 0.1524)
						(arc
							(start -0.2286 0.1524)
							(mid -0.381 0)
							(end -0.2286 -0.1524)
						)
						(xy 0.381 -0.1524)
					)
					(width 0)
					(fill yes)
				)
			)
		)
		(pad "39" smd custom
			(at 4.3688 0.750316 90)
			(size 0.0762 0.0762)
			(layers "F.Cu" "F.Mask" "F.Paste")
			(net "CLK_100M_CPU0_RC_REFCLK1_R_DN")
			(options
				(clearance outline)
				(anchor circle)
			)
			(primitives
				(gr_poly
					(pts
						(xy 0.381 0.1524)
						(arc
							(start -0.2286 0.1524)
							(mid -0.381 0)
							(end -0.2286 -0.1524)
						)
						(xy 0.381 -0.1524)
					)
					(width 0)
					(fill yes)
				)
			)
		)
		(pad "40" smd custom
			(at 4.3688 0.25019 90)
			(size 0.0762 0.0762)
			(layers "F.Cu" "F.Mask" "F.Paste")
			(net "P3V3_DB1200")
			(options
				(clearance outline)
				(anchor circle)
			)
			(primitives
				(gr_poly
					(pts
						(xy 0.381 0.1524)
						(arc
							(start -0.2286 0.1524)
							(mid -0.381 0)
							(end -0.2286 -0.1524)
						)
						(xy 0.381 -0.1524)
					)
					(width 0)
					(fill yes)
				)
			)
		)
		(pad "41" smd custom
			(at 4.3688 -0.249936 90)
			(size 0.0762 0.0762)
			(layers "F.Cu" "F.Mask" "F.Paste")
			(net "GND")
			(options
				(clearance outline)
				(anchor circle)
			)
			(primitives
				(gr_poly
					(pts
						(xy 0.381 0.1524)
						(arc
							(start -0.2286 0.1524)
							(mid -0.381 0)
							(end -0.2286 -0.1524)
						)
						(xy 0.381 -0.1524)
					)
					(width 0)
					(fill yes)
				)
			)
		)
		(pad "42" smd custom
			(at 4.3688 -0.750062 90)
			(size 0.0762 0.0762)
			(layers "F.Cu" "F.Mask" "F.Paste")
			(net "CLK_100M_CPU1_BCLK0_R_DP")
			(options
				(clearance outline)
				(anchor circle)
			)
			(primitives
				(gr_poly
					(pts
						(xy 0.381 0.1524)
						(arc
							(start -0.2286 0.1524)
							(mid -0.381 0)
							(end -0.2286 -0.1524)
						)
						(xy 0.381 -0.1524)
					)
					(width 0)
					(fill yes)
				)
			)
		)
		(pad "43" smd custom
			(at 4.3688 -1.250188 90)
			(size 0.0762 0.0762)
			(layers "F.Cu" "F.Mask" "F.Paste")
			(net "CLK_100M_CPU1_BCLK0_R_DN")
			(options
				(clearance outline)
				(anchor circle)
			)
			(primitives
				(gr_poly
					(pts
						(xy 0.381 0.1524)
						(arc
							(start -0.2286 0.1524)
							(mid -0.381 0)
							(end -0.2286 -0.1524)
						)
						(xy 0.381 -0.1524)
					)
					(width 0)
					(fill yes)
				)
			)
		)
		(pad "44" smd custom
			(at 4.3688 -1.750314 90)
			(size 0.0762 0.0762)
			(layers "F.Cu" "F.Mask" "F.Paste")
			(net "FM_DB1200ZL_BCLKS_EN_N")
			(options
				(clearance outline)
				(anchor circle)
			)
			(primitives
				(gr_poly
					(pts
						(xy 0.381 0.1524)
						(arc
							(start -0.2286 0.1524)
							(mid -0.381 0)
							(end -0.2286 -0.1524)
						)
						(xy 0.381 -0.1524)
					)
					(width 0)
					(fill yes)
				)
			)
		)
		(pad "45" smd custom
			(at 4.3688 -2.25044 90)
			(size 0.0762 0.0762)
			(layers "F.Cu" "F.Mask" "F.Paste")
			(net "FM_DB1200ZL_BCLKS_EN_N")
			(options
				(clearance outline)
				(anchor circle)
			)
			(primitives
				(gr_poly
					(pts
						(xy 0.381 0.1524)
						(arc
							(start -0.2286 0.1524)
							(mid -0.381 0)
							(end -0.2286 -0.1524)
						)
						(xy 0.381 -0.1524)
					)
					(width 0)
					(fill yes)
				)
			)
		)
		(pad "46" smd custom
			(at 4.3688 -2.750566 90)
			(size 0.0762 0.0762)
			(layers "F.Cu" "F.Mask" "F.Paste")
			(net "CLK_100M_CPU1_BCLK1_R_DP")
			(options
				(clearance outline)
				(anchor circle)
			)
			(primitives
				(gr_poly
					(pts
						(xy 0.381 0.1524)
						(arc
							(start -0.2286 0.1524)
							(mid -0.381 0)
							(end -0.2286 -0.1524)
						)
						(xy 0.381 -0.1524)
					)
					(width 0)
					(fill yes)
				)
			)
		)
		(pad "47" smd custom
			(at 4.3688 -3.250692 90)
			(size 0.0762 0.0762)
			(layers "F.Cu" "F.Mask" "F.Paste")
			(net "CLK_100M_CPU1_BCLK1_R_DN")
			(options
				(clearance outline)
				(anchor circle)
			)
			(primitives
				(gr_poly
					(pts
						(xy 0.381 0.1524)
						(arc
							(start -0.2286 0.1524)
							(mid -0.381 0)
							(end -0.2286 -0.1524)
						)
						(xy 0.381 -0.1524)
					)
					(width 0)
					(fill yes)
				)
			)
		)
		(pad "48" smd custom
			(at 4.3688 -3.750818 90)
			(size 0.0762 0.0762)
			(layers "F.Cu" "F.Mask" "F.Paste")
			(net "GND")
			(options
				(clearance outline)
				(anchor circle)
			)
			(primitives
				(gr_poly
					(pts
						(xy 0.381 0.1524)
						(arc
							(start -0.2286 0.1524)
							(mid -0.381 0)
							(end -0.2286 -0.1524)
						)
						(xy 0.381 -0.1524)
					)
					(width 0)
					(fill yes)
				)
			)
		)
		(pad "49" smd custom
			(at 3.751072 -4.3688 90)
			(size 0.0762 0.0762)
			(layers "F.Cu" "F.Mask" "F.Paste")
			(net "P3V3_DB1200")
			(options
				(clearance outline)
				(anchor circle)
			)
			(primitives
				(gr_poly
					(pts
						(xy 0.1524 -0.381)
						(arc
							(start 0.1524 0.2286)
							(mid 0 0.381)
							(end -0.1524 0.2286)
						)
						(xy -0.1524 -0.381)
					)
					(width 0)
					(fill yes)
				)
			)
		)
		(pad "50" smd custom
			(at 3.250946 -4.3688 90)
			(size 0.0762 0.0762)
			(layers "F.Cu" "F.Mask" "F.Paste")
			(net "CLK_100M_CPU1_BCLK2_R_DP")
			(options
				(clearance outline)
				(anchor circle)
			)
			(primitives
				(gr_poly
					(pts
						(xy 0.1524 -0.381)
						(arc
							(start 0.1524 0.2286)
							(mid 0 0.381)
							(end -0.1524 0.2286)
						)
						(xy -0.1524 -0.381)
					)
					(width 0)
					(fill yes)
				)
			)
		)
		(pad "51" smd custom
			(at 2.75082 -4.3688 90)
			(size 0.0762 0.0762)
			(layers "F.Cu" "F.Mask" "F.Paste")
			(net "CLK_100M_CPU1_BCLK2_R_DN")
			(options
				(clearance outline)
				(anchor circle)
			)
			(primitives
				(gr_poly
					(pts
						(xy 0.1524 -0.381)
						(arc
							(start 0.1524 0.2286)
							(mid 0 0.381)
							(end -0.1524 0.2286)
						)
						(xy -0.1524 -0.381)
					)
					(width 0)
					(fill yes)
				)
			)
		)
		(pad "52" smd custom
			(at 2.250694 -4.3688 90)
			(size 0.0762 0.0762)
			(layers "F.Cu" "F.Mask" "F.Paste")
			(net "FM_DB1200ZL_BCLKS_EN_N")
			(options
				(clearance outline)
				(anchor circle)
			)
			(primitives
				(gr_poly
					(pts
						(xy 0.1524 -0.381)
						(arc
							(start 0.1524 0.2286)
							(mid 0 0.381)
							(end -0.1524 0.2286)
						)
						(xy -0.1524 -0.381)
					)
					(width 0)
					(fill yes)
				)
			)
		)
		(pad "53" smd custom
			(at 1.750568 -4.3688 90)
			(size 0.0762 0.0762)
			(layers "F.Cu" "F.Mask" "F.Paste")
			(net "FM_CPU1_MCP_CLK_EN_N")
			(options
				(clearance outline)
				(anchor circle)
			)
			(primitives
				(gr_poly
					(pts
						(xy 0.1524 -0.381)
						(arc
							(start 0.1524 0.2286)
							(mid 0 0.381)
							(end -0.1524 0.2286)
						)
						(xy -0.1524 -0.381)
					)
					(width 0)
					(fill yes)
				)
			)
		)
		(pad "54" smd custom
			(at 1.250442 -4.3688 90)
			(size 0.0762 0.0762)
			(layers "F.Cu" "F.Mask" "F.Paste")
			(net "CLK_100M_CPU1_PE_REFCLK_R_DP")
			(options
				(clearance outline)
				(anchor circle)
			)
			(primitives
				(gr_poly
					(pts
						(xy 0.1524 -0.381)
						(arc
							(start 0.1524 0.2286)
							(mid 0 0.381)
							(end -0.1524 0.2286)
						)
						(xy -0.1524 -0.381)
					)
					(width 0)
					(fill yes)
				)
			)
		)
		(pad "55" smd custom
			(at 0.750316 -4.3688 90)
			(size 0.0762 0.0762)
			(layers "F.Cu" "F.Mask" "F.Paste")
			(net "CLK_100M_CPU1_PE_REFCLK_R_DN")
			(options
				(clearance outline)
				(anchor circle)
			)
			(primitives
				(gr_poly
					(pts
						(xy 0.1524 -0.381)
						(arc
							(start 0.1524 0.2286)
							(mid 0 0.381)
							(end -0.1524 0.2286)
						)
						(xy -0.1524 -0.381)
					)
					(width 0)
					(fill yes)
				)
			)
		)
		(pad "56" smd custom
			(at 0.25019 -4.3688 90)
			(size 0.0762 0.0762)
			(layers "F.Cu" "F.Mask" "F.Paste")
			(net "P3V3_DB1200")
			(options
				(clearance outline)
				(anchor circle)
			)
			(primitives
				(gr_poly
					(pts
						(xy 0.1524 -0.381)
						(arc
							(start 0.1524 0.2286)
							(mid 0 0.381)
							(end -0.1524 0.2286)
						)
						(xy -0.1524 -0.381)
					)
					(width 0)
					(fill yes)
				)
			)
		)
		(pad "57" smd custom
			(at -0.249936 -4.3688 90)
			(size 0.0762 0.0762)
			(layers "F.Cu" "F.Mask" "F.Paste")
			(net "P3V3_DB1200")
			(options
				(clearance outline)
				(anchor circle)
			)
			(primitives
				(gr_poly
					(pts
						(xy 0.1524 -0.381)
						(arc
							(start 0.1524 0.2286)
							(mid 0 0.381)
							(end -0.1524 0.2286)
						)
						(xy -0.1524 -0.381)
					)
					(width 0)
					(fill yes)
				)
			)
		)
		(pad "58" smd custom
			(at -0.750062 -4.3688 90)
			(size 0.0762 0.0762)
			(layers "F.Cu" "F.Mask" "F.Paste")
			(net "GND")
			(options
				(clearance outline)
				(anchor circle)
			)
			(primitives
				(gr_poly
					(pts
						(xy 0.1524 -0.381)
						(arc
							(start 0.1524 0.2286)
							(mid 0 0.381)
							(end -0.1524 0.2286)
						)
						(xy -0.1524 -0.381)
					)
					(width 0)
					(fill yes)
				)
			)
		)
		(pad "59" smd custom
			(at -1.250188 -4.3688 90)
			(size 0.0762 0.0762)
			(layers "F.Cu" "F.Mask" "F.Paste")
			(net "CLK_100M_CPU1_RC_REFCLK0_R_DP")
			(options
				(clearance outline)
				(anchor circle)
			)
			(primitives
				(gr_poly
					(pts
						(xy 0.1524 -0.381)
						(arc
							(start 0.1524 0.2286)
							(mid 0 0.381)
							(end -0.1524 0.2286)
						)
						(xy -0.1524 -0.381)
					)
					(width 0)
					(fill yes)
				)
			)
		)
		(pad "60" smd custom
			(at -1.750314 -4.3688 90)
			(size 0.0762 0.0762)
			(layers "F.Cu" "F.Mask" "F.Paste")
			(net "CLK_100M_CPU1_RC_REFCLK0_R_DN")
			(options
				(clearance outline)
				(anchor circle)
			)
			(primitives
				(gr_poly
					(pts
						(xy 0.1524 -0.381)
						(arc
							(start 0.1524 0.2286)
							(mid 0 0.381)
							(end -0.1524 0.2286)
						)
						(xy -0.1524 -0.381)
					)
					(width 0)
					(fill yes)
				)
			)
		)
		(pad "61" smd custom
			(at -2.25044 -4.3688 90)
			(size 0.0762 0.0762)
			(layers "F.Cu" "F.Mask" "F.Paste")
			(net "FM_CPU1_MCP_CLK_EN_N")
			(options
				(clearance outline)
				(anchor circle)
			)
			(primitives
				(gr_poly
					(pts
						(xy 0.1524 -0.381)
						(arc
							(start 0.1524 0.2286)
							(mid 0 0.381)
							(end -0.1524 0.2286)
						)
						(xy -0.1524 -0.381)
					)
					(width 0)
					(fill yes)
				)
			)
		)
		(pad "62" smd custom
			(at -2.750566 -4.3688 90)
			(size 0.0762 0.0762)
			(layers "F.Cu" "F.Mask" "F.Paste")
			(net "FM_CPU1_MCP_CLK_EN_N")
			(options
				(clearance outline)
				(anchor circle)
			)
			(primitives
				(gr_poly
					(pts
						(xy 0.1524 -0.381)
						(arc
							(start 0.1524 0.2286)
							(mid 0 0.381)
							(end -0.1524 0.2286)
						)
						(xy -0.1524 -0.381)
					)
					(width 0)
					(fill yes)
				)
			)
		)
		(pad "63" smd custom
			(at -3.250692 -4.3688 90)
			(size 0.0762 0.0762)
			(layers "F.Cu" "F.Mask" "F.Paste")
			(net "CLK_100M_CPU1_RC_REFCLK1_R_DP")
			(options
				(clearance outline)
				(anchor circle)
			)
			(primitives
				(gr_poly
					(pts
						(xy 0.1524 -0.381)
						(arc
							(start 0.1524 0.2286)
							(mid 0 0.381)
							(end -0.1524 0.2286)
						)
						(xy -0.1524 -0.381)
					)
					(width 0)
					(fill yes)
				)
			)
		)
		(pad "64" smd custom
			(at -3.750818 -4.3688 90)
			(size 0.0762 0.0762)
			(layers "F.Cu" "F.Mask" "F.Paste")
			(net "CLK_100M_CPU1_RC_REFCLK1_R_DN")
			(options
				(clearance outline)
				(anchor circle)
			)
			(primitives
				(gr_poly
					(pts
						(xy 0.1524 -0.381)
						(arc
							(start 0.1524 0.2286)
							(mid 0 0.381)
							(end -0.1524 0.2286)
						)
						(xy -0.1524 -0.381)
					)
					(width 0)
					(fill yes)
				)
			)
		)
		(pad "65" smd rect
			(at 0 0 90)
			(size 6.2484 6.2484)
			(layers "F.Cu" "F.Mask" "F.Paste")
			(net "GND")
		)
	)
	(footprint ""
		(layer "F.Cu")
		(at 320.6115 -123.317 -90)
		(property "Reference" "C831"
			(at -0.8382 -0.67818 270)
			(unlocked yes)
			(layer "F.SilkS")
			(effects
				(font
					(size 0.4064 0.254)
					(thickness 0.1524)
				)
				(justify left)
			)
		)
		(property "Value" ""
			(at 0 0 270)
			(layer "F.Fab")
			(effects
				(font
					(size 1.27 1.27)
				)
			)
		)
		(duplicate_pad_numbers_are_jumpers no)
		(fp_poly
			(pts
				(xy 0.3048 -0.1016) (xy 0.3048 0.9906) (xy -0.3048 0.9906) (xy -0.3048 -0.1016)
			)
			(stroke
				(width 0)
				(type default)
			)
			(fill no)
			(layer "F.CrtYd")
		)
		(fp_line
			(start -0.3048 0.9906)
			(end 0.3048 0.9906)
			(stroke
				(width 0.1)
				(type default)
			)
			(layer "F.Fab")
		)
		(fp_line
			(start 0.3048 0.9906)
			(end 0.3048 -0.1016)
			(stroke
				(width 0.1)
				(type default)
			)
			(layer "F.Fab")
		)
		(fp_line
			(start -0.3048 -0.1016)
			(end -0.3048 0.9906)
			(stroke
				(width 0.1)
				(type default)
			)
			(layer "F.Fab")
		)
		(fp_line
			(start 0.3048 -0.1016)
			(end -0.3048 -0.1016)
			(stroke
				(width 0.1)
				(type default)
			)
			(layer "F.Fab")
		)
		(pad "1" smd rect
			(at 0 0 270)
			(size 0.508 0.508)
			(layers "F.Cu" "F.Mask" "F.Paste")
			(net "P3E_CPU0_PE1_PCH_TXP<15>")
		)
		(pad "2" smd rect
			(at 0 0.889 270)
			(size 0.508 0.508)
			(layers "F.Cu" "F.Mask" "F.Paste")
			(net "P3E_CPU0_PE1_PCH_CON_TXP<15>")
		)
		(zone
			(layer "F.Cu")
			(hatch none 0.5)
			(connect_pads
				(clearance 0)
			)
			(min_thickness 0.25)
			(keepout
				(tracks not_allowed)
				(vias allowed)
				(pads allowed)
				(copperpour not_allowed)
				(footprints allowed)
			)
			(placement
				(enabled no)
				(sheetname "")
			)
			(fill
				(thermal_gap 0.5)
				(thermal_bridge_width 0.5)
				(island_removal_mode 0)
			)
			(polygon
				(pts
					(xy 319.9765 -123.571) (xy 319.9765 -123.063) (xy 320.3575 -123.063) (xy 320.3575 -123.571)
				)
			)
		)
		(zone
			(layer "F.Cu")
			(hatch none 0.5)
			(connect_pads
				(clearance 0)
			)
			(min_thickness 0.25)
			(keepout
				(tracks allowed)
				(vias not_allowed)
				(pads allowed)
				(copperpour not_allowed)
				(footprints allowed)
			)
			(placement
				(enabled no)
				(sheetname "")
			)
			(fill
				(thermal_gap 0.5)
				(thermal_bridge_width 0.5)
				(island_removal_mode 0)
			)
			(polygon
				(pts
					(xy 320.3575 -123.571) (xy 320.3575 -123.063) (xy 319.9765 -123.063) (xy 319.9765 -123.571)
				)
			)
		)
	)
	(footprint ""
		(layer "F.Cu")
		(at 394.457682 -144.255998 90)
		(property "Reference" "C8A13"
			(at 0 0 90)
			(layer "F.SilkS")
			(hide yes)
			(effects
				(font
					(size 1.27 1.27)
				)
			)
		)
		(property "Value" ""
			(at 0 0 90)
			(layer "F.Fab")
			(effects
				(font
					(size 1.27 1.27)
				)
			)
		)
		(duplicate_pad_numbers_are_jumpers no)
		(fp_poly
			(pts
				(xy -0.7239 -0.2159) (xy 0.7239 -0.2159) (xy 0.7239 1.9939) (xy -0.7239 1.9939)
			)
			(stroke
				(width 0)
				(type default)
			)
			(fill no)
			(layer "F.CrtYd")
		)
		(fp_line
			(start 0.7239 -0.2159)
			(end -0.7239 -0.2159)
			(stroke
				(width 0.1)
				(type default)
			)
			(layer "F.Fab")
		)
		(fp_line
			(start -0.7239 -0.2159)
			(end -0.7239 1.9939)
			(stroke
				(width 0.1)
				(type default)
			)
			(layer "F.Fab")
		)
		(fp_line
			(start 0.7239 1.9939)
			(end 0.7239 -0.2159)
			(stroke
				(width 0.1)
				(type default)
			)
			(layer "F.Fab")
		)
		(fp_line
			(start -0.7239 1.9939)
			(end 0.7239 1.9939)
			(stroke
				(width 0.1)
				(type default)
			)
			(layer "F.Fab")
		)
		(pad "1" smd rect
			(at 0 0 90)
			(size 1.27 1.016)
			(layers "F.Cu" "F.Mask" "F.Paste")
			(net "P1V05_PCH_STBY")
		)
		(pad "2" smd rect
			(at 0 1.778 90)
			(size 1.27 1.016)
			(layers "F.Cu" "F.Mask" "F.Paste")
			(net "GND")
		)
		(zone
			(layer "F.Cu")
			(hatch none 0.5)
			(connect_pads
				(clearance 0)
			)
			(min_thickness 0.25)
			(keepout
				(tracks not_allowed)
				(vias allowed)
				(pads allowed)
				(copperpour not_allowed)
				(footprints allowed)
			)
			(placement
				(enabled no)
				(sheetname "")
			)
			(fill
				(thermal_gap 0.5)
				(thermal_bridge_width 0.5)
				(island_removal_mode 0)
			)
			(polygon
				(pts
					(xy 394.965682 -143.620998) (xy 394.965682 -144.890998) (xy 395.727682 -144.890998) (xy 395.727682 -143.620998)
				)
			)
		)
	)
	(footprint ""
		(layer "F.Cu")
		(at 15.875 -71.247 -90)
		(property "Reference" "C1D22"
			(at 0 0 270)
			(layer "F.SilkS")
			(hide yes)
			(effects
				(font
					(size 1.27 1.27)
				)
			)
		)
		(property "Value" ""
			(at 0 0 270)
			(layer "F.Fab")
			(effects
				(font
					(size 1.27 1.27)
				)
			)
		)
		(duplicate_pad_numbers_are_jumpers no)
		(fp_rect
			(start 0.3048 0.9906)
			(end -0.3048 -0.1016)
			(stroke
				(width 0)
				(type default)
			)
			(fill no)
			(layer "F.CrtYd")
		)
		(fp_line
			(start -0.3048 0.9906)
			(end 0.3048 0.9906)
			(stroke
				(width 0.1)
				(type default)
			)
			(layer "F.Fab")
		)
		(fp_line
			(start 0.3048 0.9906)
			(end 0.3048 -0.1016)
			(stroke
				(width 0.1)
				(type default)
			)
			(layer "F.Fab")
		)
		(fp_line
			(start -0.3048 -0.1016)
			(end -0.3048 0.9906)
			(stroke
				(width 0.1)
				(type default)
			)
			(layer "F.Fab")
		)
		(fp_line
			(start 0.3048 -0.1016)
			(end -0.3048 -0.1016)
			(stroke
				(width 0.1)
				(type default)
			)
			(layer "F.Fab")
		)
		(pad "1" smd rect
			(at 0 0 270)
			(size 0.508 0.508)
			(layers "F.Cu" "F.Mask" "F.Paste")
			(net "A_HSC_MON")
		)
		(pad "2" smd rect
			(at 0 0.889 270)
			(size 0.508 0.508)
			(layers "F.Cu" "F.Mask" "F.Paste")
			(net "A_HSC_MOP")
		)
		(zone
			(layer "F.Cu")
			(hatch none 0.5)
			(connect_pads
				(clearance 0)
			)
			(min_thickness 0.25)
			(keepout
				(tracks allowed)
				(vias not_allowed)
				(pads allowed)
				(copperpour not_allowed)
				(footprints allowed)
			)
			(placement
				(enabled no)
				(sheetname "")
			)
			(fill
				(thermal_gap 0.5)
				(thermal_bridge_width 0.5)
				(island_removal_mode 0)
			)
			(polygon
				(pts
					(xy 15.24 -70.993) (xy 15.621 -70.993) (xy 15.621 -71.501) (xy 15.24 -71.501)
				)
			)
		)
		(zone
			(layer "F.Cu")
			(hatch none 0.5)
			(connect_pads
				(clearance 0)
			)
			(min_thickness 0.25)
			(keepout
				(tracks not_allowed)
				(vias allowed)
				(pads allowed)
				(copperpour not_allowed)
				(footprints allowed)
			)
			(placement
				(enabled no)
				(sheetname "")
			)
			(fill
				(thermal_gap 0.5)
				(thermal_bridge_width 0.5)
				(island_removal_mode 0)
			)
			(polygon
				(pts
					(xy 15.24 -70.993) (xy 15.621 -70.993) (xy 15.621 -71.501) (xy 15.24 -71.501)
				)
			)
		)
	)
	(footprint ""
		(layer "F.Cu")
		(at 194.457828 -78.000352)
		(property "Reference" "CT40"
			(at -0.56007 -5.2324 270)
			(unlocked yes)
			(layer "F.SilkS")
			(effects
				(font
					(size 0.7874 0.5842)
					(thickness 0.1524)
				)
				(justify left)
			)
		)
		(property "Value" ""
			(at 0 0 0)
			(layer "F.Fab")
			(effects
				(font
					(size 1.27 1.27)
				)
			)
		)
		(duplicate_pad_numbers_are_jumpers no)
		(fp_poly
			(pts
				(xy 0.3048 -0.1016) (xy 0.3048 0.9906) (xy -0.3048 0.9906) (xy -0.3048 -0.1016)
			)
			(stroke
				(width 0)
				(type default)
			)
			(fill no)
			(layer "F.CrtYd")
		)
		(fp_line
			(start -0.3048 -0.1016)
			(end -0.3048 0.9906)
			(stroke
				(width 0.1)
				(type default)
			)
			(layer "F.Fab")
		)
		(fp_line
			(start -0.3048 0.9906)
			(end 0.3048 0.9906)
			(stroke
				(width 0.1)
				(type default)
			)
			(layer "F.Fab")
		)
		(fp_line
			(start 0.3048 -0.1016)
			(end -0.3048 -0.1016)
			(stroke
				(width 0.1)
				(type default)
			)
			(layer "F.Fab")
		)
		(fp_line
			(start 0.3048 0.9906)
			(end 0.3048 -0.1016)
			(stroke
				(width 0.1)
				(type default)
			)
			(layer "F.Fab")
		)
		(pad "1" smd rect
			(at 0 0)
			(size 0.508 0.508)
			(layers "F.Cu" "F.Mask" "F.Paste")
			(net "VR_PVCCIN_CPU0_AIREF4")
		)
		(pad "2" smd rect
			(at 0 0.889)
			(size 0.508 0.508)
			(layers "F.Cu" "F.Mask" "F.Paste")
			(net "GND")
		)
		(zone
			(layer "F.Cu")
			(hatch none 0.5)
			(connect_pads
				(clearance 0)
			)
			(min_thickness 0.25)
			(keepout
				(tracks allowed)
				(vias not_allowed)
				(pads allowed)
				(copperpour not_allowed)
				(footprints allowed)
			)
			(placement
				(enabled no)
				(sheetname "")
			)
			(fill
				(thermal_gap 0.5)
				(thermal_bridge_width 0.5)
				(island_removal_mode 0)
			)
			(polygon
				(pts
					(xy 194.203828 -77.746352) (xy 194.711828 -77.746352) (xy 194.711828 -77.365352) (xy 194.203828 -77.365352)
				)
			)
		)
		(zone
			(layer "F.Cu")
			(hatch none 0.5)
			(connect_pads
				(clearance 0)
			)
			(min_thickness 0.25)
			(keepout
				(tracks not_allowed)
				(vias allowed)
				(pads allowed)
				(copperpour not_allowed)
				(footprints allowed)
			)
			(placement
				(enabled no)
				(sheetname "")
			)
			(fill
				(thermal_gap 0.5)
				(thermal_bridge_width 0.5)
				(island_removal_mode 0)
			)
			(polygon
				(pts
					(xy 194.203828 -77.365352) (xy 194.711828 -77.365352) (xy 194.711828 -77.746352) (xy 194.203828 -77.746352)
				)
			)
		)
	)
	(footprint ""
		(layer "F.Cu")
		(at 18.9484 -118.239794 90)
		(property "Reference" "R1B22"
			(at 0 0 90)
			(layer "F.SilkS")
			(hide yes)
			(effects
				(font
					(size 1.27 1.27)
				)
			)
		)
		(property "Value" ""
			(at 0 0 90)
			(layer "F.Fab")
			(effects
				(font
					(size 1.27 1.27)
				)
			)
		)
		(duplicate_pad_numbers_are_jumpers no)
		(fp_rect
			(start -0.2794 -0.1016)
			(end 0.2794 0.9906)
			(stroke
				(width 0)
				(type default)
			)
			(fill no)
			(layer "F.CrtYd")
		)
		(fp_line
			(start 0.2794 -0.1016)
			(end -0.2794 -0.1016)
			(stroke
				(width 0.1)
				(type default)
			)
			(layer "F.Fab")
		)
		(fp_line
			(start -0.2794 -0.1016)
			(end -0.2794 0.9906)
			(stroke
				(width 0.1)
				(type default)
			)
			(layer "F.Fab")
		)
		(fp_line
			(start 0.2794 0.9906)
			(end 0.2794 -0.1016)
			(stroke
				(width 0.1)
				(type default)
			)
			(layer "F.Fab")
		)
		(fp_line
			(start -0.2794 0.9906)
			(end 0.2794 0.9906)
			(stroke
				(width 0.1)
				(type default)
			)
			(layer "F.Fab")
		)
		(pad "1" smd rect
			(at 0 0 90)
			(size 0.508 0.508)
			(layers "F.Cu" "F.Mask" "F.Paste")
			(net "FAN_TACH2")
		)
		(pad "2" smd rect
			(at 0 0.889 90)
			(size 0.508 0.508)
			(layers "F.Cu" "F.Mask" "F.Paste")
			(net "FAN_TACH2_CPU1_D2")
		)
		(zone
			(layer "F.Cu")
			(hatch none 0.5)
			(connect_pads
				(clearance 0)
			)
			(min_thickness 0.25)
			(keepout
				(tracks allowed)
				(vias not_allowed)
				(pads allowed)
				(copperpour not_allowed)
				(footprints allowed)
			)
			(placement
				(enabled no)
				(sheetname "")
			)
			(fill
				(thermal_gap 0.5)
				(thermal_bridge_width 0.5)
				(island_removal_mode 0)
			)
			(polygon
				(pts
					(xy 19.2024 -117.985794) (xy 19.5834 -117.985794) (xy 19.5834 -118.493794) (xy 19.2024 -118.493794)
				)
			)
		)
		(zone
			(layer "F.Cu")
			(hatch none 0.5)
			(connect_pads
				(clearance 0)
			)
			(min_thickness 0.25)
			(keepout
				(tracks not_allowed)
				(vias allowed)
				(pads allowed)
				(copperpour not_allowed)
				(footprints allowed)
			)
			(placement
				(enabled no)
				(sheetname "")
			)
			(fill
				(thermal_gap 0.5)
				(thermal_bridge_width 0.5)
				(island_removal_mode 0)
			)
			(polygon
				(pts
					(xy 19.2024 -117.985794) (xy 19.5834 -117.985794) (xy 19.5834 -118.493794) (xy 19.2024 -118.493794)
				)
			)
		)
	)
	(footprint ""
		(layer "F.Cu")
		(at 485.875076 -26.326084 180)
		(property "Reference" "R9F70"
			(at 0 0 180)
			(layer "F.SilkS")
			(hide yes)
			(effects
				(font
					(size 1.27 1.27)
				)
			)
		)
		(property "Value" ""
			(at 0 0 180)
			(layer "F.Fab")
			(effects
				(font
					(size 1.27 1.27)
				)
			)
		)
		(duplicate_pad_numbers_are_jumpers no)
		(fp_poly
			(pts
				(xy -0.2794 -0.1016) (xy 0.2794 -0.1016) (xy 0.2794 0.9906) (xy -0.2794 0.9906)
			)
			(stroke
				(width 0)
				(type default)
			)
			(fill no)
			(layer "F.CrtYd")
		)
		(fp_line
			(start 0.2794 0.9906)
			(end 0.2794 -0.1016)
			(stroke
				(width 0.1)
				(type default)
			)
			(layer "F.Fab")
		)
		(fp_line
			(start 0.2794 -0.1016)
			(end -0.2794 -0.1016)
			(stroke
				(width 0.1)
				(type default)
			)
			(layer "F.Fab")
		)
		(fp_line
			(start -0.2794 0.9906)
			(end 0.2794 0.9906)
			(stroke
				(width 0.1)
				(type default)
			)
			(layer "F.Fab")
		)
		(fp_line
			(start -0.2794 -0.1016)
			(end -0.2794 0.9906)
			(stroke
				(width 0.1)
				(type default)
			)
			(layer "F.Fab")
		)
		(pad "1" smd rect
			(at 0 0 180)
			(size 0.508 0.508)
			(layers "F.Cu" "F.Mask" "F.Paste")
			(net "SPA_MID_DBG_TX")
		)
		(pad "2" smd rect
			(at 0 0.889 180)
			(size 0.508 0.508)
			(layers "F.Cu" "F.Mask" "F.Paste")
			(net "SPA_MID_DBG_TX_R")
		)
		(zone
			(layer "F.Cu")
			(hatch none 0.5)
			(connect_pads
				(clearance 0)
			)
			(min_thickness 0.25)
			(keepout
				(tracks not_allowed)
				(vias allowed)
				(pads allowed)
				(copperpour not_allowed)
				(footprints allowed)
			)
			(placement
				(enabled no)
				(sheetname "")
			)
			(fill
				(thermal_gap 0.5)
				(thermal_bridge_width 0.5)
				(island_removal_mode 0)
			)
			(polygon
				(pts
					(xy 486.129076 -26.961084) (xy 485.621076 -26.961084) (xy 485.621076 -26.580084) (xy 486.129076 -26.580084)
				)
			)
		)
		(zone
			(layer "F.Cu")
			(hatch none 0.5)
			(connect_pads
				(clearance 0)
			)
			(min_thickness 0.25)
			(keepout
				(tracks allowed)
				(vias not_allowed)
				(pads allowed)
				(copperpour not_allowed)
				(footprints allowed)
			)
			(placement
				(enabled no)
				(sheetname "")
			)
			(fill
				(thermal_gap 0.5)
				(thermal_bridge_width 0.5)
				(island_removal_mode 0)
			)
			(polygon
				(pts
					(xy 486.129076 -26.580084) (xy 485.621076 -26.580084) (xy 485.621076 -26.961084) (xy 486.129076 -26.961084)
				)
			)
		)
	)
	(footprint ""
		(layer "F.Cu")
		(at 447.3829 -40.2971 90)
		(property "Reference" "R25W94"
			(at -0.8382 -0.67818 90)
			(unlocked yes)
			(layer "F.SilkS")
			(effects
				(font
					(size 0.4064 0.254)
					(thickness 0.1524)
				)
				(justify left)
			)
		)
		(property "Value" ""
			(at 0 0 90)
			(layer "F.Fab")
			(effects
				(font
					(size 1.27 1.27)
				)
			)
		)
		(duplicate_pad_numbers_are_jumpers no)
		(fp_poly
			(pts
				(xy -0.2794 -0.1016) (xy 0.2794 -0.1016) (xy 0.2794 0.9906) (xy -0.2794 0.9906)
			)
			(stroke
				(width 0)
				(type default)
			)
			(fill no)
			(layer "F.CrtYd")
		)
		(fp_line
			(start 0.2794 -0.1016)
			(end -0.2794 -0.1016)
			(stroke
				(width 0.1)
				(type default)
			)
			(layer "F.Fab")
		)
		(fp_line
			(start -0.2794 -0.1016)
			(end -0.2794 0.9906)
			(stroke
				(width 0.1)
				(type default)
			)
			(layer "F.Fab")
		)
		(fp_line
			(start 0.2794 0.9906)
			(end 0.2794 -0.1016)
			(stroke
				(width 0.1)
				(type default)
			)
			(layer "F.Fab")
		)
		(fp_line
			(start -0.2794 0.9906)
			(end 0.2794 0.9906)
			(stroke
				(width 0.1)
				(type default)
			)
			(layer "F.Fab")
		)
		(pad "1" smd rect
			(at 0 0 90)
			(size 0.508 0.508)
			(layers "F.Cu" "F.Mask" "F.Paste")
			(net "GND")
		)
		(pad "2" smd rect
			(at 0 0.889 90)
			(size 0.508 0.508)
			(layers "F.Cu" "F.Mask" "F.Paste")
			(net "PD_SPI_BMC_BT_CS0_N")
		)
		(zone
			(layer "F.Cu")
			(hatch none 0.5)
			(connect_pads
				(clearance 0)
			)
			(min_thickness 0.25)
			(keepout
				(tracks allowed)
				(vias not_allowed)
				(pads allowed)
				(copperpour not_allowed)
				(footprints allowed)
			)
			(placement
				(enabled no)
				(sheetname "")
			)
			(fill
				(thermal_gap 0.5)
				(thermal_bridge_width 0.5)
				(island_removal_mode 0)
			)
			(polygon
				(pts
					(xy 447.6369 -40.0431) (xy 447.6369 -40.5511) (xy 448.0179 -40.5511) (xy 448.0179 -40.0431)
				)
			)
		)
		(zone
			(layer "F.Cu")
			(hatch none 0.5)
			(connect_pads
				(clearance 0)
			)
			(min_thickness 0.25)
			(keepout
				(tracks not_allowed)
				(vias allowed)
				(pads allowed)
				(copperpour not_allowed)
				(footprints allowed)
			)
			(placement
				(enabled no)
				(sheetname "")
			)
			(fill
				(thermal_gap 0.5)
				(thermal_bridge_width 0.5)
				(island_removal_mode 0)
			)
			(polygon
				(pts
					(xy 448.0179 -40.0431) (xy 448.0179 -40.5511) (xy 447.6369 -40.5511) (xy 447.6369 -40.0431)
				)
			)
		)
	)
	(footprint ""
		(layer "F.Cu")
		(at 425.919646 -48.968152)
		(property "Reference" "R25W100"
			(at -0.8382 -0.67818 0)
			(unlocked yes)
			(layer "F.SilkS")
			(effects
				(font
					(size 0.4064 0.254)
					(thickness 0.1524)
				)
				(justify left)
			)
		)
		(property "Value" ""
			(at 0 0 0)
			(layer "F.Fab")
			(effects
				(font
					(size 1.27 1.27)
				)
			)
		)
		(duplicate_pad_numbers_are_jumpers no)
		(fp_poly
			(pts
				(xy -0.2794 -0.1016) (xy 0.2794 -0.1016) (xy 0.2794 0.9906) (xy -0.2794 0.9906)
			)
			(stroke
				(width 0)
				(type default)
			)
			(fill no)
			(layer "F.CrtYd")
		)
		(fp_line
			(start -0.2794 -0.1016)
			(end -0.2794 0.9906)
			(stroke
				(width 0.1)
				(type default)
			)
			(layer "F.Fab")
		)
		(fp_line
			(start -0.2794 0.9906)
			(end 0.2794 0.9906)
			(stroke
				(width 0.1)
				(type default)
			)
			(layer "F.Fab")
		)
		(fp_line
			(start 0.2794 -0.1016)
			(end -0.2794 -0.1016)
			(stroke
				(width 0.1)
				(type default)
			)
			(layer "F.Fab")
		)
		(fp_line
			(start 0.2794 0.9906)
			(end 0.2794 -0.1016)
			(stroke
				(width 0.1)
				(type default)
			)
			(layer "F.Fab")
		)
		(pad "1" smd rect
			(at 0 0)
			(size 0.508 0.508)
			(layers "F.Cu" "F.Mask" "F.Paste")
			(net "P3V3_STBY")
		)
		(pad "2" smd rect
			(at 0 0.889)
			(size 0.508 0.508)
			(layers "F.Cu" "F.Mask" "F.Paste")
			(net "GPIOS7")
		)
		(zone
			(layer "F.Cu")
			(hatch none 0.5)
			(connect_pads
				(clearance 0)
			)
			(min_thickness 0.25)
			(keepout
				(tracks allowed)
				(vias not_allowed)
				(pads allowed)
				(copperpour not_allowed)
				(footprints allowed)
			)
			(placement
				(enabled no)
				(sheetname "")
			)
			(fill
				(thermal_gap 0.5)
				(thermal_bridge_width 0.5)
				(island_removal_mode 0)
			)
			(polygon
				(pts
					(xy 425.665646 -48.714152) (xy 426.173646 -48.714152) (xy 426.173646 -48.333152) (xy 425.665646 -48.333152)
				)
			)
		)
		(zone
			(layer "F.Cu")
			(hatch none 0.5)
			(connect_pads
				(clearance 0)
			)
			(min_thickness 0.25)
			(keepout
				(tracks not_allowed)
				(vias allowed)
				(pads allowed)
				(copperpour not_allowed)
				(footprints allowed)
			)
			(placement
				(enabled no)
				(sheetname "")
			)
			(fill
				(thermal_gap 0.5)
				(thermal_bridge_width 0.5)
				(island_removal_mode 0)
			)
			(polygon
				(pts
					(xy 425.665646 -48.333152) (xy 426.173646 -48.333152) (xy 426.173646 -48.714152) (xy 425.665646 -48.714152)
				)
			)
		)
	)
	(footprint ""
		(layer "F.Cu")
		(at 99.769168 -84.7598)
		(property "Reference" "C2D4"
			(at 0 0 0)
			(layer "F.SilkS")
			(hide yes)
			(effects
				(font
					(size 1.27 1.27)
				)
			)
		)
		(property "Value" ""
			(at 0 0 0)
			(layer "F.Fab")
			(effects
				(font
					(size 1.27 1.27)
				)
			)
		)
		(duplicate_pad_numbers_are_jumpers no)
		(fp_poly
			(pts
				(xy -0.4953 -0.2032) (xy 0.4953 -0.2032) (xy 0.4953 1.6002) (xy -0.4953 1.6002)
			)
			(stroke
				(width 0)
				(type default)
			)
			(fill no)
			(layer "F.CrtYd")
		)
		(fp_line
			(start -0.4953 -0.2032)
			(end 0.4953 -0.2032)
			(stroke
				(width 0.1)
				(type default)
			)
			(layer "F.Fab")
		)
		(fp_line
			(start -0.4953 1.6002)
			(end -0.4953 -0.2032)
			(stroke
				(width 0.1)
				(type default)
			)
			(layer "F.Fab")
		)
		(fp_line
			(start 0.4953 -0.2032)
			(end 0.4953 1.6002)
			(stroke
				(width 0.1)
				(type default)
			)
			(layer "F.Fab")
		)
		(fp_line
			(start 0.4953 1.6002)
			(end -0.4953 1.6002)
			(stroke
				(width 0.1)
				(type default)
			)
			(layer "F.Fab")
		)
		(pad "1" smd rect
			(at 0 0)
			(size 0.762 0.889)
			(layers "F.Cu" "F.Mask" "F.Paste")
			(net "PVDDQ_KLM")
		)
		(pad "2" smd rect
			(at 0 1.397)
			(size 0.762 0.889)
			(layers "F.Cu" "F.Mask" "F.Paste")
			(net "GND")
		)
		(zone
			(layer "F.Cu")
			(hatch none 0.5)
			(connect_pads
				(clearance 0)
			)
			(min_thickness 0.25)
			(keepout
				(tracks not_allowed)
				(vias allowed)
				(pads allowed)
				(copperpour not_allowed)
				(footprints allowed)
			)
			(placement
				(enabled no)
				(sheetname "")
			)
			(fill
				(thermal_gap 0.5)
				(thermal_bridge_width 0.5)
				(island_removal_mode 0)
			)
			(polygon
				(pts
					(xy 99.388168 -84.3153) (xy 100.150168 -84.3153) (xy 100.150168 -83.8073) (xy 99.388168 -83.8073)
				)
			)
		)
	)
	(footprint ""
		(layer "F.Cu")
		(at 387.96976 -139.5222)
		(property "Reference" "C7A42"
			(at 0 0 0)
			(layer "F.SilkS")
			(hide yes)
			(effects
				(font
					(size 1.27 1.27)
				)
			)
		)
		(property "Value" ""
			(at 0 0 0)
			(layer "F.Fab")
			(effects
				(font
					(size 1.27 1.27)
				)
			)
		)
		(duplicate_pad_numbers_are_jumpers no)
		(fp_rect
			(start 0.7239 1.9939)
			(end -0.7239 -0.2159)
			(stroke
				(width 0)
				(type default)
			)
			(fill no)
			(layer "F.CrtYd")
		)
		(fp_line
			(start -0.7239 -0.2159)
			(end -0.7239 1.9939)
			(stroke
				(width 0.1)
				(type default)
			)
			(layer "F.Fab")
		)
		(fp_line
			(start -0.7239 1.9939)
			(end 0.7239 1.9939)
			(stroke
				(width 0.1)
				(type default)
			)
			(layer "F.Fab")
		)
		(fp_line
			(start 0.7239 -0.2159)
			(end -0.7239 -0.2159)
			(stroke
				(width 0.1)
				(type default)
			)
			(layer "F.Fab")
		)
		(fp_line
			(start 0.7239 1.9939)
			(end 0.7239 -0.2159)
			(stroke
				(width 0.1)
				(type default)
			)
			(layer "F.Fab")
		)
		(pad "1" smd rect
			(at 0 0)
			(size 1.27 1.016)
			(layers "F.Cu" "F.Mask" "F.Paste")
			(net "P1V05_PCH_STBY")
		)
		(pad "2" smd rect
			(at 0 1.778)
			(size 1.27 1.016)
			(layers "F.Cu" "F.Mask" "F.Paste")
			(net "GND")
		)
		(zone
			(layer "F.Cu")
			(hatch none 0.5)
			(connect_pads
				(clearance 0)
			)
			(min_thickness 0.25)
			(keepout
				(tracks not_allowed)
				(vias allowed)
				(pads allowed)
				(copperpour not_allowed)
				(footprints allowed)
			)
			(placement
				(enabled no)
				(sheetname "")
			)
			(fill
				(thermal_gap 0.5)
				(thermal_bridge_width 0.5)
				(island_removal_mode 0)
			)
			(polygon
				(pts
					(xy 388.60476 -138.2522) (xy 388.60476 -139.0142) (xy 387.33476 -139.0142) (xy 387.33476 -138.2522)
				)
			)
		)
	)
	(footprint ""
		(layer "F.Cu")
		(at 386.45338 -140.14704 -90)
		(property "Reference" "C7B15"
			(at 0 0 270)
			(layer "F.SilkS")
			(hide yes)
			(effects
				(font
					(size 1.27 1.27)
				)
			)
		)
		(property "Value" ""
			(at 0 0 270)
			(layer "F.Fab")
			(effects
				(font
					(size 1.27 1.27)
				)
			)
		)
		(duplicate_pad_numbers_are_jumpers no)
		(fp_rect
			(start -0.4953 1.6002)
			(end 0.4953 -0.2032)
			(stroke
				(width 0)
				(type default)
			)
			(fill no)
			(layer "F.CrtYd")
		)
		(fp_line
			(start -0.4953 1.6002)
			(end -0.4953 -0.2032)
			(stroke
				(width 0.1)
				(type default)
			)
			(layer "F.Fab")
		)
		(fp_line
			(start 0.4953 1.6002)
			(end -0.4953 1.6002)
			(stroke
				(width 0.1)
				(type default)
			)
			(layer "F.Fab")
		)
		(fp_line
			(start -0.4953 -0.2032)
			(end 0.4953 -0.2032)
			(stroke
				(width 0.1)
				(type default)
			)
			(layer "F.Fab")
		)
		(fp_line
			(start 0.4953 -0.2032)
			(end 0.4953 1.6002)
			(stroke
				(width 0.1)
				(type default)
			)
			(layer "F.Fab")
		)
		(pad "1" smd rect
			(at 0 0 270)
			(size 0.762 0.889)
			(layers "F.Cu" "F.Mask" "F.Paste")
			(net "P1V05_PCH_STBY")
		)
		(pad "2" smd rect
			(at 0 1.397 270)
			(size 0.762 0.889)
			(layers "F.Cu" "F.Mask" "F.Paste")
			(net "GND")
		)
		(zone
			(layer "F.Cu")
			(hatch none 0.5)
			(connect_pads
				(clearance 0)
			)
			(min_thickness 0.25)
			(keepout
				(tracks not_allowed)
				(vias allowed)
				(pads allowed)
				(copperpour not_allowed)
				(footprints allowed)
			)
			(placement
				(enabled no)
				(sheetname "")
			)
			(fill
				(thermal_gap 0.5)
				(thermal_bridge_width 0.5)
				(island_removal_mode 0)
			)
			(polygon
				(pts
					(xy 385.50088 -140.52804) (xy 385.50088 -139.76604) (xy 386.00888 -139.76604) (xy 386.00888 -140.52804)
				)
			)
		)
	)
	(footprint ""
		(layer "F.Cu")
		(at 167.294052 -73.056242 180)
		(property "Reference" "R4D41"
			(at 0 0 180)
			(layer "F.SilkS")
			(hide yes)
			(effects
				(font
					(size 1.27 1.27)
				)
			)
		)
		(property "Value" ""
			(at 0 0 180)
			(layer "F.Fab")
			(effects
				(font
					(size 1.27 1.27)
				)
			)
		)
		(duplicate_pad_numbers_are_jumpers no)
		(fp_poly
			(pts
				(xy -0.2794 -0.1016) (xy 0.2794 -0.1016) (xy 0.2794 0.9906) (xy -0.2794 0.9906)
			)
			(stroke
				(width 0)
				(type default)
			)
			(fill no)
			(layer "F.CrtYd")
		)
		(fp_line
			(start 0.2794 0.9906)
			(end 0.2794 -0.1016)
			(stroke
				(width 0.1)
				(type default)
			)
			(layer "F.Fab")
		)
		(fp_line
			(start 0.2794 -0.1016)
			(end -0.2794 -0.1016)
			(stroke
				(width 0.1)
				(type default)
			)
			(layer "F.Fab")
		)
		(fp_line
			(start -0.2794 0.9906)
			(end 0.2794 0.9906)
			(stroke
				(width 0.1)
				(type default)
			)
			(layer "F.Fab")
		)
		(fp_line
			(start -0.2794 -0.1016)
			(end -0.2794 0.9906)
			(stroke
				(width 0.1)
				(type default)
			)
			(layer "F.Fab")
		)
		(pad "1" smd rect
			(at 0 0 180)
			(size 0.508 0.508)
			(layers "F.Cu" "F.Mask" "F.Paste")
			(net "P3V3_DB1200")
		)
		(pad "2" smd rect
			(at 0 0.889 180)
			(size 0.508 0.508)
			(layers "F.Cu" "F.Mask" "F.Paste")
			(net "FM_HBW_BYPASS_LOWBW_N")
		)
		(zone
			(layer "F.Cu")
			(hatch none 0.5)
			(connect_pads
				(clearance 0)
			)
			(min_thickness 0.25)
			(keepout
				(tracks not_allowed)
				(vias allowed)
				(pads allowed)
				(copperpour not_allowed)
				(footprints allowed)
			)
			(placement
				(enabled no)
				(sheetname "")
			)
			(fill
				(thermal_gap 0.5)
				(thermal_bridge_width 0.5)
				(island_removal_mode 0)
			)
			(polygon
				(pts
					(xy 167.548052 -73.691242) (xy 167.040052 -73.691242) (xy 167.040052 -73.310242) (xy 167.548052 -73.310242)
				)
			)
		)
		(zone
			(layer "F.Cu")
			(hatch none 0.5)
			(connect_pads
				(clearance 0)
			)
			(min_thickness 0.25)
			(keepout
				(tracks allowed)
				(vias not_allowed)
				(pads allowed)
				(copperpour not_allowed)
				(footprints allowed)
			)
			(placement
				(enabled no)
				(sheetname "")
			)
			(fill
				(thermal_gap 0.5)
				(thermal_bridge_width 0.5)
				(island_removal_mode 0)
			)
			(polygon
				(pts
					(xy 167.548052 -73.310242) (xy 167.040052 -73.310242) (xy 167.040052 -73.691242) (xy 167.548052 -73.691242)
				)
			)
		)
	)
	(footprint ""
		(layer "F.Cu")
		(at 437.769 -13.843)
		(property "Reference" "R1U58"
			(at 0 0 0)
			(layer "F.SilkS")
			(hide yes)
			(effects
				(font
					(size 1.27 1.27)
				)
			)
		)
		(property "Value" ""
			(at 0 0 0)
			(layer "F.Fab")
			(effects
				(font
					(size 1.27 1.27)
				)
			)
		)
		(duplicate_pad_numbers_are_jumpers no)
		(fp_poly
			(pts
				(xy -0.2794 -0.1016) (xy 0.2794 -0.1016) (xy 0.2794 0.9906) (xy -0.2794 0.9906)
			)
			(stroke
				(width 0)
				(type default)
			)
			(fill no)
			(layer "F.CrtYd")
		)
		(fp_line
			(start -0.2794 -0.1016)
			(end -0.2794 0.9906)
			(stroke
				(width 0.1)
				(type default)
			)
			(layer "F.Fab")
		)
		(fp_line
			(start -0.2794 0.9906)
			(end 0.2794 0.9906)
			(stroke
				(width 0.1)
				(type default)
			)
			(layer "F.Fab")
		)
		(fp_line
			(start 0.2794 -0.1016)
			(end -0.2794 -0.1016)
			(stroke
				(width 0.1)
				(type default)
			)
			(layer "F.Fab")
		)
		(fp_line
			(start 0.2794 0.9906)
			(end 0.2794 -0.1016)
			(stroke
				(width 0.1)
				(type default)
			)
			(layer "F.Fab")
		)
		(pad "1" smd rect
			(at 0 0)
			(size 0.508 0.508)
			(layers "F.Cu" "F.Mask" "F.Paste")
			(net "H_CPU0_MEMDEF_MEMHOT_G_N")
		)
		(pad "2" smd rect
			(at 0 0.889)
			(size 0.508 0.508)
			(layers "F.Cu" "F.Mask" "F.Paste")
			(net "H_CPU0_MEMDEF_MEMHOT_G_R_N")
		)
		(zone
			(layer "F.Cu")
			(hatch none 0.5)
			(connect_pads
				(clearance 0)
			)
			(min_thickness 0.25)
			(keepout
				(tracks allowed)
				(vias not_allowed)
				(pads allowed)
				(copperpour not_allowed)
				(footprints allowed)
			)
			(placement
				(enabled no)
				(sheetname "")
			)
			(fill
				(thermal_gap 0.5)
				(thermal_bridge_width 0.5)
				(island_removal_mode 0)
			)
			(polygon
				(pts
					(xy 437.515 -13.589) (xy 438.023 -13.589) (xy 438.023 -13.208) (xy 437.515 -13.208)
				)
			)
		)
		(zone
			(layer "F.Cu")
			(hatch none 0.5)
			(connect_pads
				(clearance 0)
			)
			(min_thickness 0.25)
			(keepout
				(tracks not_allowed)
				(vias allowed)
				(pads allowed)
				(copperpour not_allowed)
				(footprints allowed)
			)
			(placement
				(enabled no)
				(sheetname "")
			)
			(fill
				(thermal_gap 0.5)
				(thermal_bridge_width 0.5)
				(island_removal_mode 0)
			)
			(polygon
				(pts
					(xy 437.515 -13.208) (xy 438.023 -13.208) (xy 438.023 -13.589) (xy 437.515 -13.589)
				)
			)
		)
	)
	(footprint ""
		(layer "F.Cu")
		(at 183.007 -61.976 180)
		(property "Reference" "R4E9"
			(at 0 0 180)
			(layer "F.SilkS")
			(hide yes)
			(effects
				(font
					(size 1.27 1.27)
				)
			)
		)
		(property "Value" ""
			(at 0 0 180)
			(layer "F.Fab")
			(effects
				(font
					(size 1.27 1.27)
				)
			)
		)
		(duplicate_pad_numbers_are_jumpers no)
		(fp_rect
			(start 0.2794 -0.1016)
			(end -0.2794 0.9906)
			(stroke
				(width 0)
				(type default)
			)
			(fill no)
			(layer "F.CrtYd")
		)
		(fp_line
			(start 0.2794 0.9906)
			(end 0.2794 -0.1016)
			(stroke
				(width 0.1)
				(type default)
			)
			(layer "F.Fab")
		)
		(fp_line
			(start 0.2794 -0.1016)
			(end -0.2794 -0.1016)
			(stroke
				(width 0.1)
				(type default)
			)
			(layer "F.Fab")
		)
		(fp_line
			(start -0.2794 0.9906)
			(end 0.2794 0.9906)
			(stroke
				(width 0.1)
				(type default)
			)
			(layer "F.Fab")
		)
		(fp_line
			(start -0.2794 -0.1016)
			(end -0.2794 0.9906)
			(stroke
				(width 0.1)
				(type default)
			)
			(layer "F.Fab")
		)
		(pad "1" smd rect
			(at 0 0 180)
			(size 0.508 0.508)
			(layers "F.Cu" "F.Mask" "F.Paste")
			(net "PVCCIO_CPU0")
		)
		(pad "2" smd rect
			(at 0 0.889 180)
			(size 0.508 0.508)
			(layers "F.Cu" "F.Mask" "F.Paste")
			(net "SVID_CLK0_CPU0_R")
		)
		(zone
			(layer "F.Cu")
			(hatch none 0.5)
			(connect_pads
				(clearance 0)
			)
			(min_thickness 0.25)
			(keepout
				(tracks not_allowed)
				(vias allowed)
				(pads allowed)
				(copperpour not_allowed)
				(footprints allowed)
			)
			(placement
				(enabled no)
				(sheetname "")
			)
			(fill
				(thermal_gap 0.5)
				(thermal_bridge_width 0.5)
				(island_removal_mode 0)
			)
			(polygon
				(pts
					(xy 182.753 -62.23) (xy 183.261 -62.23) (xy 183.261 -62.611) (xy 182.753 -62.611)
				)
			)
		)
		(zone
			(layer "F.Cu")
			(hatch none 0.5)
			(connect_pads
				(clearance 0)
			)
			(min_thickness 0.25)
			(keepout
				(tracks allowed)
				(vias not_allowed)
				(pads allowed)
				(copperpour not_allowed)
				(footprints allowed)
			)
			(placement
				(enabled no)
				(sheetname "")
			)
			(fill
				(thermal_gap 0.5)
				(thermal_bridge_width 0.5)
				(island_removal_mode 0)
			)
			(polygon
				(pts
					(xy 182.753 -62.23) (xy 183.261 -62.23) (xy 183.261 -62.611) (xy 182.753 -62.611)
				)
			)
		)
	)
	(footprint ""
		(layer "F.Cu")
		(at 102.145592 -68.412614 180)
		(property "Reference" "C2D44"
			(at 0 0 180)
			(layer "F.SilkS")
			(hide yes)
			(effects
				(font
					(size 1.27 1.27)
				)
			)
		)
		(property "Value" ""
			(at 0 0 180)
			(layer "F.Fab")
			(effects
				(font
					(size 1.27 1.27)
				)
			)
		)
		(duplicate_pad_numbers_are_jumpers no)
		(fp_poly
			(pts
				(xy -0.4953 -0.2032) (xy 0.4953 -0.2032) (xy 0.4953 1.6002) (xy -0.4953 1.6002)
			)
			(stroke
				(width 0)
				(type default)
			)
			(fill no)
			(layer "F.CrtYd")
		)
		(fp_line
			(start 0.4953 1.6002)
			(end -0.4953 1.6002)
			(stroke
				(width 0.1)
				(type default)
			)
			(layer "F.Fab")
		)
		(fp_line
			(start 0.4953 -0.2032)
			(end 0.4953 1.6002)
			(stroke
				(width 0.1)
				(type default)
			)
			(layer "F.Fab")
		)
		(fp_line
			(start -0.4953 1.6002)
			(end -0.4953 -0.2032)
			(stroke
				(width 0.1)
				(type default)
			)
			(layer "F.Fab")
		)
		(fp_line
			(start -0.4953 -0.2032)
			(end 0.4953 -0.2032)
			(stroke
				(width 0.1)
				(type default)
			)
			(layer "F.Fab")
		)
		(pad "1" smd rect
			(at 0 0 180)
			(size 0.762 0.889)
			(layers "F.Cu" "F.Mask" "F.Paste")
			(net "PVDDQ_GHJ")
		)
		(pad "2" smd rect
			(at 0 1.397 180)
			(size 0.762 0.889)
			(layers "F.Cu" "F.Mask" "F.Paste")
			(net "GND")
		)
		(zone
			(layer "F.Cu")
			(hatch none 0.5)
			(connect_pads
				(clearance 0)
			)
			(min_thickness 0.25)
			(keepout
				(tracks not_allowed)
				(vias allowed)
				(pads allowed)
				(copperpour not_allowed)
				(footprints allowed)
			)
			(placement
				(enabled no)
				(sheetname "")
			)
			(fill
				(thermal_gap 0.5)
				(thermal_bridge_width 0.5)
				(island_removal_mode 0)
			)
			(polygon
				(pts
					(xy 102.526592 -68.857114) (xy 101.764592 -68.857114) (xy 101.764592 -69.365114) (xy 102.526592 -69.365114)
				)
			)
		)
	)
	(footprint ""
		(layer "F.Cu")
		(at 396.367 -88.2015)
		(property "Reference" "R2N27"
			(at 0 0 0)
			(layer "F.SilkS")
			(hide yes)
			(effects
				(font
					(size 1.27 1.27)
				)
			)
		)
		(property "Value" ""
			(at 0 0 0)
			(layer "F.Fab")
			(effects
				(font
					(size 1.27 1.27)
				)
			)
		)
		(duplicate_pad_numbers_are_jumpers no)
		(fp_poly
			(pts
				(xy -0.2794 -0.1016) (xy 0.2794 -0.1016) (xy 0.2794 0.9906) (xy -0.2794 0.9906)
			)
			(stroke
				(width 0)
				(type default)
			)
			(fill no)
			(layer "F.CrtYd")
		)
		(fp_line
			(start -0.2794 -0.1016)
			(end -0.2794 0.9906)
			(stroke
				(width 0.1)
				(type default)
			)
			(layer "F.Fab")
		)
		(fp_line
			(start -0.2794 0.9906)
			(end 0.2794 0.9906)
			(stroke
				(width 0.1)
				(type default)
			)
			(layer "F.Fab")
		)
		(fp_line
			(start 0.2794 -0.1016)
			(end -0.2794 -0.1016)
			(stroke
				(width 0.1)
				(type default)
			)
			(layer "F.Fab")
		)
		(fp_line
			(start 0.2794 0.9906)
			(end 0.2794 -0.1016)
			(stroke
				(width 0.1)
				(type default)
			)
			(layer "F.Fab")
		)
		(pad "1" smd rect
			(at 0 0)
			(size 0.508 0.508)
			(layers "F.Cu" "F.Mask" "F.Paste")
			(net "P3V3")
		)
		(pad "2" smd rect
			(at 0 0.889)
			(size 0.508 0.508)
			(layers "F.Cu" "F.Mask" "F.Paste")
			(net "FM_BMC_NMI_N")
		)
		(zone
			(layer "F.Cu")
			(hatch none 0.5)
			(connect_pads
				(clearance 0)
			)
			(min_thickness 0.25)
			(keepout
				(tracks allowed)
				(vias not_allowed)
				(pads allowed)
				(copperpour not_allowed)
				(footprints allowed)
			)
			(placement
				(enabled no)
				(sheetname "")
			)
			(fill
				(thermal_gap 0.5)
				(thermal_bridge_width 0.5)
				(island_removal_mode 0)
			)
			(polygon
				(pts
					(xy 396.113 -87.9475) (xy 396.621 -87.9475) (xy 396.621 -87.5665) (xy 396.113 -87.5665)
				)
			)
		)
		(zone
			(layer "F.Cu")
			(hatch none 0.5)
			(connect_pads
				(clearance 0)
			)
			(min_thickness 0.25)
			(keepout
				(tracks not_allowed)
				(vias allowed)
				(pads allowed)
				(copperpour not_allowed)
				(footprints allowed)
			)
			(placement
				(enabled no)
				(sheetname "")
			)
			(fill
				(thermal_gap 0.5)
				(thermal_bridge_width 0.5)
				(island_removal_mode 0)
			)
			(polygon
				(pts
					(xy 396.113 -87.5665) (xy 396.621 -87.5665) (xy 396.621 -87.9475) (xy 396.113 -87.9475)
				)
			)
		)
	)
	(footprint ""
		(layer "F.Cu")
		(at 342.265 -19.558 180)
		(property "Reference" "R7F24"
			(at 0 0 180)
			(layer "F.SilkS")
			(hide yes)
			(effects
				(font
					(size 1.27 1.27)
				)
			)
		)
		(property "Value" ""
			(at 0 0 180)
			(layer "F.Fab")
			(effects
				(font
					(size 1.27 1.27)
				)
			)
		)
		(duplicate_pad_numbers_are_jumpers no)
		(fp_rect
			(start 0.2794 -0.1016)
			(end -0.2794 0.9906)
			(stroke
				(width 0)
				(type default)
			)
			(fill no)
			(layer "F.CrtYd")
		)
		(fp_line
			(start 0.2794 0.9906)
			(end 0.2794 -0.1016)
			(stroke
				(width 0.1)
				(type default)
			)
			(layer "F.Fab")
		)
		(fp_line
			(start 0.2794 -0.1016)
			(end -0.2794 -0.1016)
			(stroke
				(width 0.1)
				(type default)
			)
			(layer "F.Fab")
		)
		(fp_line
			(start -0.2794 0.9906)
			(end 0.2794 0.9906)
			(stroke
				(width 0.1)
				(type default)
			)
			(layer "F.Fab")
		)
		(fp_line
			(start -0.2794 -0.1016)
			(end -0.2794 0.9906)
			(stroke
				(width 0.1)
				(type default)
			)
			(layer "F.Fab")
		)
		(pad "1" smd rect
			(at 0 0 180)
			(size 0.508 0.508)
			(layers "F.Cu" "F.Mask" "F.Paste")
			(net "PWRGD_PVDDQ_ABC_R")
		)
		(pad "2" smd rect
			(at 0 0.889 180)
			(size 0.508 0.508)
			(layers "F.Cu" "F.Mask" "F.Paste")
			(net "PWRGD_PVDDQ_ABC")
		)
		(zone
			(layer "F.Cu")
			(hatch none 0.5)
			(connect_pads
				(clearance 0)
			)
			(min_thickness 0.25)
			(keepout
				(tracks not_allowed)
				(vias allowed)
				(pads allowed)
				(copperpour not_allowed)
				(footprints allowed)
			)
			(placement
				(enabled no)
				(sheetname "")
			)
			(fill
				(thermal_gap 0.5)
				(thermal_bridge_width 0.5)
				(island_removal_mode 0)
			)
			(polygon
				(pts
					(xy 342.011 -19.812) (xy 342.519 -19.812) (xy 342.519 -20.193) (xy 342.011 -20.193)
				)
			)
		)
		(zone
			(layer "F.Cu")
			(hatch none 0.5)
			(connect_pads
				(clearance 0)
			)
			(min_thickness 0.25)
			(keepout
				(tracks allowed)
				(vias not_allowed)
				(pads allowed)
				(copperpour not_allowed)
				(footprints allowed)
			)
			(placement
				(enabled no)
				(sheetname "")
			)
			(fill
				(thermal_gap 0.5)
				(thermal_bridge_width 0.5)
				(island_removal_mode 0)
			)
			(polygon
				(pts
					(xy 342.011 -19.812) (xy 342.519 -19.812) (xy 342.519 -20.193) (xy 342.011 -20.193)
				)
			)
		)
	)
	(footprint ""
		(layer "F.Cu")
		(at 323.98716 -131.31546)
		(property "Reference" "R6B2"
			(at 0 0 0)
			(layer "F.SilkS")
			(hide yes)
			(effects
				(font
					(size 1.27 1.27)
				)
			)
		)
		(property "Value" ""
			(at 0 0 0)
			(layer "F.Fab")
			(effects
				(font
					(size 1.27 1.27)
				)
			)
		)
		(duplicate_pad_numbers_are_jumpers no)
		(fp_poly
			(pts
				(xy -0.2794 -0.1016) (xy 0.2794 -0.1016) (xy 0.2794 0.9906) (xy -0.2794 0.9906)
			)
			(stroke
				(width 0)
				(type default)
			)
			(fill no)
			(layer "F.CrtYd")
		)
		(fp_line
			(start -0.2794 -0.1016)
			(end -0.2794 0.9906)
			(stroke
				(width 0.1)
				(type default)
			)
			(layer "F.Fab")
		)
		(fp_line
			(start -0.2794 0.9906)
			(end 0.2794 0.9906)
			(stroke
				(width 0.1)
				(type default)
			)
			(layer "F.Fab")
		)
		(fp_line
			(start 0.2794 -0.1016)
			(end -0.2794 -0.1016)
			(stroke
				(width 0.1)
				(type default)
			)
			(layer "F.Fab")
		)
		(fp_line
			(start 0.2794 0.9906)
			(end 0.2794 -0.1016)
			(stroke
				(width 0.1)
				(type default)
			)
			(layer "F.Fab")
		)
		(pad "1" smd rect
			(at 0 0)
			(size 0.508 0.508)
			(layers "F.Cu" "F.Mask" "F.Paste")
			(net "PVCCIO_CPU0")
		)
		(pad "2" smd rect
			(at 0 0.889)
			(size 0.508 0.508)
			(layers "F.Cu" "F.Mask" "F.Paste")
			(net "SVID_DIO1_CPU0_R")
		)
		(zone
			(layer "F.Cu")
			(hatch none 0.5)
			(connect_pads
				(clearance 0)
			)
			(min_thickness 0.25)
			(keepout
				(tracks allowed)
				(vias not_allowed)
				(pads allowed)
				(copperpour not_allowed)
				(footprints allowed)
			)
			(placement
				(enabled no)
				(sheetname "")
			)
			(fill
				(thermal_gap 0.5)
				(thermal_bridge_width 0.5)
				(island_removal_mode 0)
			)
			(polygon
				(pts
					(xy 323.73316 -131.06146) (xy 324.24116 -131.06146) (xy 324.24116 -130.68046) (xy 323.73316 -130.68046)
				)
			)
		)
		(zone
			(layer "F.Cu")
			(hatch none 0.5)
			(connect_pads
				(clearance 0)
			)
			(min_thickness 0.25)
			(keepout
				(tracks not_allowed)
				(vias allowed)
				(pads allowed)
				(copperpour not_allowed)
				(footprints allowed)
			)
			(placement
				(enabled no)
				(sheetname "")
			)
			(fill
				(thermal_gap 0.5)
				(thermal_bridge_width 0.5)
				(island_removal_mode 0)
			)
			(polygon
				(pts
					(xy 323.73316 -130.68046) (xy 324.24116 -130.68046) (xy 324.24116 -131.06146) (xy 323.73316 -131.06146)
				)
			)
		)
	)
	(footprint ""
		(layer "F.Cu")
		(at 394.8176 -66.6242)
		(property "Reference" "C8E15"
			(at 0 0 0)
			(layer "F.SilkS")
			(hide yes)
			(effects
				(font
					(size 1.27 1.27)
				)
			)
		)
		(property "Value" ""
			(at 0 0 0)
			(layer "F.Fab")
			(effects
				(font
					(size 1.27 1.27)
				)
			)
		)
		(duplicate_pad_numbers_are_jumpers no)
		(fp_poly
			(pts
				(xy 0.3048 -0.1016) (xy 0.3048 0.9906) (xy -0.3048 0.9906) (xy -0.3048 -0.1016)
			)
			(stroke
				(width 0)
				(type default)
			)
			(fill no)
			(layer "F.CrtYd")
		)
		(fp_line
			(start -0.3048 -0.1016)
			(end -0.3048 0.9906)
			(stroke
				(width 0.1)
				(type default)
			)
			(layer "F.Fab")
		)
		(fp_line
			(start -0.3048 0.9906)
			(end 0.3048 0.9906)
			(stroke
				(width 0.1)
				(type default)
			)
			(layer "F.Fab")
		)
		(fp_line
			(start 0.3048 -0.1016)
			(end -0.3048 -0.1016)
			(stroke
				(width 0.1)
				(type default)
			)
			(layer "F.Fab")
		)
		(fp_line
			(start 0.3048 0.9906)
			(end 0.3048 -0.1016)
			(stroke
				(width 0.1)
				(type default)
			)
			(layer "F.Fab")
		)
		(pad "1" smd rect
			(at 0 0)
			(size 0.508 0.508)
			(layers "F.Cu" "F.Mask" "F.Paste")
			(net "VR_P5V_STBY_SS")
		)
		(pad "2" smd rect
			(at 0 0.889)
			(size 0.508 0.508)
			(layers "F.Cu" "F.Mask" "F.Paste")
			(net "AGND_P5V_STBY")
		)
		(zone
			(layer "F.Cu")
			(hatch none 0.5)
			(connect_pads
				(clearance 0)
			)
			(min_thickness 0.25)
			(keepout
				(tracks allowed)
				(vias not_allowed)
				(pads allowed)
				(copperpour not_allowed)
				(footprints allowed)
			)
			(placement
				(enabled no)
				(sheetname "")
			)
			(fill
				(thermal_gap 0.5)
				(thermal_bridge_width 0.5)
				(island_removal_mode 0)
			)
			(polygon
				(pts
					(xy 394.5636 -66.3702) (xy 395.0716 -66.3702) (xy 395.0716 -65.9892) (xy 394.5636 -65.9892)
				)
			)
		)
		(zone
			(layer "F.Cu")
			(hatch none 0.5)
			(connect_pads
				(clearance 0)
			)
			(min_thickness 0.25)
			(keepout
				(tracks not_allowed)
				(vias allowed)
				(pads allowed)
				(copperpour not_allowed)
				(footprints allowed)
			)
			(placement
				(enabled no)
				(sheetname "")
			)
			(fill
				(thermal_gap 0.5)
				(thermal_bridge_width 0.5)
				(island_removal_mode 0)
			)
			(polygon
				(pts
					(xy 394.5636 -65.9892) (xy 395.0716 -65.9892) (xy 395.0716 -66.3702) (xy 394.5636 -66.3702)
				)
			)
		)
	)
	(footprint ""
		(layer "F.Cu")
		(at 19.177 13.2715 -90)
		(property "Reference" "T1P33"
			(at 0 0 270)
			(layer "F.SilkS")
			(hide yes)
			(effects
				(font
					(size 1.27 1.27)
				)
			)
		)
		(property "Value" "*"
			(at 0 -3.44805 270)
			(unlocked yes)
			(layer "F.Fab")
			(hide yes)
			(effects
				(font
					(size 0.889 0.889)
					(thickness 0.1524)
				)
			)
		)
		(property "Device Type" "TPAD-SE-2P-GP_DISCRET-GA1-TPADA"
			(at 0 -4.97205 270)
			(unlocked yes)
			(layer "F.Fab")
			(hide yes)
			(effects
				(font
					(size 0.889 0.889)
					(thickness 0.1524)
				)
			)
		)
		(duplicate_pad_numbers_are_jumpers no)
		(fp_line
			(start -1.016 2.286)
			(end -1.016 -2.286)
			(stroke
				(width 0.1524)
				(type default)
			)
			(layer "F.SilkS")
		)
		(fp_line
			(start 1.016 2.286)
			(end -1.016 2.286)
			(stroke
				(width 0.1524)
				(type default)
			)
			(layer "F.SilkS")
		)
		(fp_line
			(start -1.016 -2.286)
			(end 1.016 -2.286)
			(stroke
				(width 0.1524)
				(type default)
			)
			(layer "F.SilkS")
		)
		(fp_line
			(start 1.016 -2.286)
			(end 1.016 2.286)
			(stroke
				(width 0.1524)
				(type default)
			)
			(layer "F.SilkS")
		)
		(fp_rect
			(start -1.27 2.54)
			(end 1.27 -2.54)
			(stroke
				(width 0)
				(type default)
			)
			(fill no)
			(layer "F.CrtYd")
		)
		(fp_rect
			(start -1.27 2.54)
			(end 1.27 -2.54)
			(stroke
				(width 0)
				(type default)
			)
			(fill no)
			(layer "F.Fab")
		)
		(pad "1" thru_hole circle
			(at 0 -1.27 270)
			(size 1.524 1.524)
			(drill 0.9144)
			(layers "*.Cu" "*.Mask")
			(remove_unused_layers no)
			(net "L5_50OHM_6INCH")
			(clearance -0.0508)
			(thermal_gap 0.127)
			(padstack
				(mode front_inner_back)
				(layer "Inner"
					(shape circle)
					(size 1.1684 1.1684)
					(clearance 0.127)
				)
				(layer "B.Cu"
					(shape circle)
					(size 1.524 1.524)
					(clearance -0.0508)
				)
			)
		)
		(pad "GND1" thru_hole rect
			(at 0 1.27 270)
			(size 1.524 1.524)
			(drill 0.9144)
			(layers "*.Cu" "*.Mask")
			(remove_unused_layers no)
			(net "GND")
			(clearance -0.0508)
			(thermal_gap 0.127)
			(padstack
				(mode front_inner_back)
				(layer "Inner"
					(shape circle)
					(size 1.1684 1.1684)
					(clearance 0.127)
				)
				(layer "B.Cu"
					(shape rect)
					(size 1.524 1.524)
					(clearance -0.0508)
				)
			)
		)
	)
	(footprint ""
		(layer "F.Cu")
		(at 24.518112 -98.003868 180)
		(property "Reference" "CF12"
			(at 0 0 180)
			(layer "F.SilkS")
			(hide yes)
			(effects
				(font
					(size 1.27 1.27)
				)
			)
		)
		(property "Value" "*"
			(at 1.1811 -2.8194 180)
			(unlocked yes)
			(layer "F.Fab")
			(hide yes)
			(effects
				(font
					(size 1.27 1.016)
					(thickness 0.1524)
				)
			)
		)
		(property "Device Type" "SC22P50V2JN-4GP_SMD-BCG-SC22P5A"
			(at 1.1811 -4.3434 180)
			(unlocked yes)
			(layer "F.Fab")
			(hide yes)
			(effects
				(font
					(size 1.27 1.016)
					(thickness 0.1524)
				)
			)
		)
		(duplicate_pad_numbers_are_jumpers no)
		(fp_rect
			(start -0.4318 0.9525)
			(end 0.4318 -0.9525)
			(stroke
				(width 0)
				(type default)
			)
			(fill no)
			(layer "F.CrtYd")
		)
		(fp_rect
			(start -0.4318 0.9525)
			(end 0.4318 -0.9525)
			(stroke
				(width 0)
				(type default)
			)
			(fill no)
			(layer "F.Fab")
		)
		(pad "1" smd custom
			(at 0 -0.4445 180)
			(size 0.1524 0.1524)
			(layers "F.Cu" "F.Mask" "F.Paste")
			(net "VR_PVSA_CPU1_BIREF1")
			(options
				(clearance outline)
				(anchor circle)
			)
			(primitives
				(gr_poly
					(pts
						(arc
							(start 0.3048 -0.2032)
							(mid 0.275042 -0.275042)
							(end 0.2032 -0.3048)
						)
						(arc
							(start -0.2032 -0.3048)
							(mid -0.275042 -0.275042)
							(end -0.3048 -0.2032)
						)
						(arc
							(start -0.3048 0.2032)
							(mid -0.275042 0.275042)
							(end -0.2032 0.3048)
						)
						(arc
							(start 0.2032 0.3048)
							(mid 0.275042 0.275042)
							(end 0.3048 0.2032)
						)
					)
					(width 0)
					(fill yes)
				)
			)
		)
		(pad "2" smd custom
			(at 0 0.4445 180)
			(size 0.1524 0.1524)
			(layers "F.Cu" "F.Mask" "F.Paste")
			(net "ISENSE_PVSA_CPU1_IMON")
			(options
				(clearance outline)
				(anchor circle)
			)
			(primitives
				(gr_poly
					(pts
						(arc
							(start 0.3048 -0.2032)
							(mid 0.275042 -0.275042)
							(end 0.2032 -0.3048)
						)
						(arc
							(start -0.2032 -0.3048)
							(mid -0.275042 -0.275042)
							(end -0.3048 -0.2032)
						)
						(arc
							(start -0.3048 0.2032)
							(mid -0.275042 0.275042)
							(end -0.2032 0.3048)
						)
						(arc
							(start 0.2032 0.3048)
							(mid 0.275042 0.275042)
							(end 0.3048 0.2032)
						)
					)
					(width 0)
					(fill yes)
				)
			)
		)
	)
	(footprint ""
		(layer "F.Cu")
		(at 173.507146 -145.667222 90)
		(property "Reference" "C4A14"
			(at 0 0 90)
			(layer "F.SilkS")
			(hide yes)
			(effects
				(font
					(size 1.27 1.27)
				)
			)
		)
		(property "Value" ""
			(at 0 0 90)
			(layer "F.Fab")
			(effects
				(font
					(size 1.27 1.27)
				)
			)
		)
		(duplicate_pad_numbers_are_jumpers no)
		(fp_rect
			(start 0.3048 0.9906)
			(end -0.3048 -0.1016)
			(stroke
				(width 0)
				(type default)
			)
			(fill no)
			(layer "F.CrtYd")
		)
		(fp_line
			(start 0.3048 -0.1016)
			(end -0.3048 -0.1016)
			(stroke
				(width 0.1)
				(type default)
			)
			(layer "F.Fab")
		)
		(fp_line
			(start -0.3048 -0.1016)
			(end -0.3048 0.9906)
			(stroke
				(width 0.1)
				(type default)
			)
			(layer "F.Fab")
		)
		(fp_line
			(start 0.3048 0.9906)
			(end 0.3048 -0.1016)
			(stroke
				(width 0.1)
				(type default)
			)
			(layer "F.Fab")
		)
		(fp_line
			(start -0.3048 0.9906)
			(end 0.3048 0.9906)
			(stroke
				(width 0.1)
				(type default)
			)
			(layer "F.Fab")
		)
		(pad "1" smd rect
			(at 0 0 90)
			(size 0.508 0.508)
			(layers "F.Cu" "F.Mask" "F.Paste")
			(net "VR_PVTT_KLM_VREF")
		)
		(pad "2" smd rect
			(at 0 0.889 90)
			(size 0.508 0.508)
			(layers "F.Cu" "F.Mask" "F.Paste")
			(net "GND")
		)
		(zone
			(layer "F.Cu")
			(hatch none 0.5)
			(connect_pads
				(clearance 0)
			)
			(min_thickness 0.25)
			(keepout
				(tracks allowed)
				(vias not_allowed)
				(pads allowed)
				(copperpour not_allowed)
				(footprints allowed)
			)
			(placement
				(enabled no)
				(sheetname "")
			)
			(fill
				(thermal_gap 0.5)
				(thermal_bridge_width 0.5)
				(island_removal_mode 0)
			)
			(polygon
				(pts
					(xy 174.142146 -145.921222) (xy 173.761146 -145.921222) (xy 173.761146 -145.413222) (xy 174.142146 -145.413222)
				)
			)
		)
		(zone
			(layer "F.Cu")
			(hatch none 0.5)
			(connect_pads
				(clearance 0)
			)
			(min_thickness 0.25)
			(keepout
				(tracks not_allowed)
				(vias allowed)
				(pads allowed)
				(copperpour not_allowed)
				(footprints allowed)
			)
			(placement
				(enabled no)
				(sheetname "")
			)
			(fill
				(thermal_gap 0.5)
				(thermal_bridge_width 0.5)
				(island_removal_mode 0)
			)
			(polygon
				(pts
					(xy 174.142146 -145.921222) (xy 173.761146 -145.921222) (xy 173.761146 -145.413222) (xy 174.142146 -145.413222)
				)
			)
		)
	)
	(footprint ""
		(layer "F.Cu")
		(at 339.3948 -102.6922 90)
		(property "Reference" "C7C10"
			(at 0 0 90)
			(layer "F.SilkS")
			(hide yes)
			(effects
				(font
					(size 1.27 1.27)
				)
			)
		)
		(property "Value" ""
			(at 0 0 90)
			(layer "F.Fab")
			(effects
				(font
					(size 1.27 1.27)
				)
			)
		)
		(duplicate_pad_numbers_are_jumpers no)
		(fp_poly
			(pts
				(xy -0.4953 -0.2032) (xy 0.4953 -0.2032) (xy 0.4953 1.6002) (xy -0.4953 1.6002)
			)
			(stroke
				(width 0)
				(type default)
			)
			(fill no)
			(layer "F.CrtYd")
		)
		(fp_line
			(start 0.4953 -0.2032)
			(end 0.4953 1.6002)
			(stroke
				(width 0.1)
				(type default)
			)
			(layer "F.Fab")
		)
		(fp_line
			(start -0.4953 -0.2032)
			(end 0.4953 -0.2032)
			(stroke
				(width 0.1)
				(type default)
			)
			(layer "F.Fab")
		)
		(fp_line
			(start 0.4953 1.6002)
			(end -0.4953 1.6002)
			(stroke
				(width 0.1)
				(type default)
			)
			(layer "F.Fab")
		)
		(fp_line
			(start -0.4953 1.6002)
			(end -0.4953 -0.2032)
			(stroke
				(width 0.1)
				(type default)
			)
			(layer "F.Fab")
		)
		(pad "1" smd rect
			(at 0 0 90)
			(size 0.762 0.889)
			(layers "F.Cu" "F.Mask" "F.Paste")
			(net "PVCCIO_CPU0")
		)
		(pad "2" smd rect
			(at 0 1.397 90)
			(size 0.762 0.889)
			(layers "F.Cu" "F.Mask" "F.Paste")
			(net "GND")
		)
		(zone
			(layer "F.Cu")
			(hatch none 0.5)
			(connect_pads
				(clearance 0)
			)
			(min_thickness 0.25)
			(keepout
				(tracks not_allowed)
				(vias allowed)
				(pads allowed)
				(copperpour not_allowed)
				(footprints allowed)
			)
			(placement
				(enabled no)
				(sheetname "")
			)
			(fill
				(thermal_gap 0.5)
				(thermal_bridge_width 0.5)
				(island_removal_mode 0)
			)
			(polygon
				(pts
					(xy 339.8393 -102.3112) (xy 339.8393 -103.0732) (xy 340.3473 -103.0732) (xy 340.3473 -102.3112)
				)
			)
		)
	)
	(footprint ""
		(layer "F.Cu")
		(at 198.11619 -61.118242 90)
		(property "Reference" "C4E27"
			(at 0 0 90)
			(layer "F.SilkS")
			(hide yes)
			(effects
				(font
					(size 1.27 1.27)
				)
			)
		)
		(property "Value" ""
			(at 0 0 90)
			(layer "F.Fab")
			(effects
				(font
					(size 1.27 1.27)
				)
			)
		)
		(duplicate_pad_numbers_are_jumpers no)
		(fp_rect
			(start 0.3048 0.9906)
			(end -0.3048 -0.1016)
			(stroke
				(width 0)
				(type default)
			)
			(fill no)
			(layer "F.CrtYd")
		)
		(fp_line
			(start 0.3048 -0.1016)
			(end -0.3048 -0.1016)
			(stroke
				(width 0.1)
				(type default)
			)
			(layer "F.Fab")
		)
		(fp_line
			(start -0.3048 -0.1016)
			(end -0.3048 0.9906)
			(stroke
				(width 0.1)
				(type default)
			)
			(layer "F.Fab")
		)
		(fp_line
			(start 0.3048 0.9906)
			(end 0.3048 -0.1016)
			(stroke
				(width 0.1)
				(type default)
			)
			(layer "F.Fab")
		)
		(fp_line
			(start -0.3048 0.9906)
			(end 0.3048 0.9906)
			(stroke
				(width 0.1)
				(type default)
			)
			(layer "F.Fab")
		)
		(pad "1" smd rect
			(at 0 0 90)
			(size 0.508 0.508)
			(layers "F.Cu" "F.Mask" "F.Paste")
			(net "P5V_STBY")
		)
		(pad "2" smd rect
			(at 0 0.889 90)
			(size 0.508 0.508)
			(layers "F.Cu" "F.Mask" "F.Paste")
			(net "GND")
		)
		(zone
			(layer "F.Cu")
			(hatch none 0.5)
			(connect_pads
				(clearance 0)
			)
			(min_thickness 0.25)
			(keepout
				(tracks not_allowed)
				(vias allowed)
				(pads allowed)
				(copperpour not_allowed)
				(footprints allowed)
			)
			(placement
				(enabled no)
				(sheetname "")
			)
			(fill
				(thermal_gap 0.5)
				(thermal_bridge_width 0.5)
				(island_removal_mode 0)
			)
			(polygon
				(pts
					(xy 198.75119 -61.372242) (xy 198.37019 -61.372242) (xy 198.37019 -60.864242) (xy 198.75119 -60.864242)
				)
			)
		)
		(zone
			(layer "F.Cu")
			(hatch none 0.5)
			(connect_pads
				(clearance 0)
			)
			(min_thickness 0.25)
			(keepout
				(tracks allowed)
				(vias not_allowed)
				(pads allowed)
				(copperpour not_allowed)
				(footprints allowed)
			)
			(placement
				(enabled no)
				(sheetname "")
			)
			(fill
				(thermal_gap 0.5)
				(thermal_bridge_width 0.5)
				(island_removal_mode 0)
			)
			(polygon
				(pts
					(xy 198.75119 -61.372242) (xy 198.37019 -61.372242) (xy 198.37019 -60.864242) (xy 198.75119 -60.864242)
				)
			)
		)
	)
	(footprint ""
		(layer "F.Cu")
		(at 270.99641 -84.890102)
		(property "Reference" "C5D3"
			(at 0 0 0)
			(layer "F.SilkS")
			(hide yes)
			(effects
				(font
					(size 1.27 1.27)
				)
			)
		)
		(property "Value" ""
			(at 0 0 0)
			(layer "F.Fab")
			(effects
				(font
					(size 1.27 1.27)
				)
			)
		)
		(duplicate_pad_numbers_are_jumpers no)
		(fp_poly
			(pts
				(xy -0.4953 -0.2032) (xy 0.4953 -0.2032) (xy 0.4953 1.6002) (xy -0.4953 1.6002)
			)
			(stroke
				(width 0)
				(type default)
			)
			(fill no)
			(layer "F.CrtYd")
		)
		(fp_line
			(start -0.4953 -0.2032)
			(end 0.4953 -0.2032)
			(stroke
				(width 0.1)
				(type default)
			)
			(layer "F.Fab")
		)
		(fp_line
			(start -0.4953 1.6002)
			(end -0.4953 -0.2032)
			(stroke
				(width 0.1)
				(type default)
			)
			(layer "F.Fab")
		)
		(fp_line
			(start 0.4953 -0.2032)
			(end 0.4953 1.6002)
			(stroke
				(width 0.1)
				(type default)
			)
			(layer "F.Fab")
		)
		(fp_line
			(start 0.4953 1.6002)
			(end -0.4953 1.6002)
			(stroke
				(width 0.1)
				(type default)
			)
			(layer "F.Fab")
		)
		(pad "1" smd rect
			(at 0 0)
			(size 0.762 0.889)
			(layers "F.Cu" "F.Mask" "F.Paste")
			(net "PVDDQ_DEF")
		)
		(pad "2" smd rect
			(at 0 1.397)
			(size 0.762 0.889)
			(layers "F.Cu" "F.Mask" "F.Paste")
			(net "GND")
		)
		(zone
			(layer "F.Cu")
			(hatch none 0.5)
			(connect_pads
				(clearance 0)
			)
			(min_thickness 0.25)
			(keepout
				(tracks not_allowed)
				(vias allowed)
				(pads allowed)
				(copperpour not_allowed)
				(footprints allowed)
			)
			(placement
				(enabled no)
				(sheetname "")
			)
			(fill
				(thermal_gap 0.5)
				(thermal_bridge_width 0.5)
				(island_removal_mode 0)
			)
			(polygon
				(pts
					(xy 270.61541 -84.445602) (xy 271.37741 -84.445602) (xy 271.37741 -83.937602) (xy 270.61541 -83.937602)
				)
			)
		)
	)
	(footprint ""
		(layer "F.Cu")
		(at 365.489744 -10.916158)
		(property "Reference" "C7G8"
			(at 0 0 0)
			(layer "F.SilkS")
			(hide yes)
			(effects
				(font
					(size 1.27 1.27)
				)
			)
		)
		(property "Value" ""
			(at 0 0 0)
			(layer "F.Fab")
			(effects
				(font
					(size 1.27 1.27)
				)
			)
		)
		(duplicate_pad_numbers_are_jumpers no)
		(fp_rect
			(start -0.3048 0.9906)
			(end 0.3048 -0.1016)
			(stroke
				(width 0)
				(type default)
			)
			(fill no)
			(layer "F.CrtYd")
		)
		(fp_line
			(start -0.3048 -0.1016)
			(end -0.3048 0.9906)
			(stroke
				(width 0.1)
				(type default)
			)
			(layer "F.Fab")
		)
		(fp_line
			(start -0.3048 0.9906)
			(end 0.3048 0.9906)
			(stroke
				(width 0.1)
				(type default)
			)
			(layer "F.Fab")
		)
		(fp_line
			(start 0.3048 -0.1016)
			(end -0.3048 -0.1016)
			(stroke
				(width 0.1)
				(type default)
			)
			(layer "F.Fab")
		)
		(fp_line
			(start 0.3048 0.9906)
			(end 0.3048 -0.1016)
			(stroke
				(width 0.1)
				(type default)
			)
			(layer "F.Fab")
		)
		(pad "1" smd rect
			(at 0 0)
			(size 0.508 0.508)
			(layers "F.Cu" "F.Mask" "F.Paste")
			(net "P3E_CPU0_PE2_SS_TXP<14>")
		)
		(pad "2" smd rect
			(at 0 0.889)
			(size 0.508 0.508)
			(layers "F.Cu" "F.Mask" "F.Paste")
			(net "P3E_CPU0_PE2_SS_C_TXP<14>")
		)
		(zone
			(layer "F.Cu")
			(hatch none 0.5)
			(connect_pads
				(clearance 0)
			)
			(min_thickness 0.25)
			(keepout
				(tracks allowed)
				(vias not_allowed)
				(pads allowed)
				(copperpour not_allowed)
				(footprints allowed)
			)
			(placement
				(enabled no)
				(sheetname "")
			)
			(fill
				(thermal_gap 0.5)
				(thermal_bridge_width 0.5)
				(island_removal_mode 0)
			)
			(polygon
				(pts
					(xy 365.235744 -10.281158) (xy 365.743744 -10.281158) (xy 365.743744 -10.662158) (xy 365.235744 -10.662158)
				)
			)
		)
		(zone
			(layer "F.Cu")
			(hatch none 0.5)
			(connect_pads
				(clearance 0)
			)
			(min_thickness 0.25)
			(keepout
				(tracks not_allowed)
				(vias allowed)
				(pads allowed)
				(copperpour not_allowed)
				(footprints allowed)
			)
			(placement
				(enabled no)
				(sheetname "")
			)
			(fill
				(thermal_gap 0.5)
				(thermal_bridge_width 0.5)
				(island_removal_mode 0)
			)
			(polygon
				(pts
					(xy 365.235744 -10.281158) (xy 365.743744 -10.281158) (xy 365.743744 -10.662158) (xy 365.235744 -10.662158)
				)
			)
		)
	)
	(footprint ""
		(layer "F.Cu")
		(at 34.71418 -40.59936)
		(property "Reference" ""
			(at 0 0 0)
			(layer "F.SilkS")
			(hide yes)
			(effects
				(font
					(size 1.27 1.27)
				)
			)
		)
		(property "Value" ""
			(at 0 0 0)
			(layer "F.Fab")
			(effects
				(font
					(size 1.27 1.27)
				)
			)
		)
		(duplicate_pad_numbers_are_jumpers no)
		(fp_poly
			(pts
				(arc
					(start 2.032 0)
					(mid -2.032 0)
					(end 2.032 0)
				)
			)
			(stroke
				(width 0)
				(type default)
			)
			(fill no)
			(layer "F.CrtYd")
		)
		(pad "1" smd circle
			(at 0 0)
			(size 1.016 1.016)
			(layers "F.Cu" "F.Mask" "F.Paste")
			(net "Net_304")
		)
		(zone
			(layer "F.Cu")
			(hatch none 0.5)
			(connect_pads
				(clearance 0)
			)
			(min_thickness 0.25)
			(keepout
				(tracks not_allowed)
				(vias allowed)
				(pads allowed)
				(copperpour not_allowed)
				(footprints allowed)
			)
			(placement
				(enabled no)
				(sheetname "")
			)
			(fill
				(thermal_gap 0.5)
				(thermal_bridge_width 0.5)
				(island_removal_mode 0)
			)
			(polygon
				(pts
					(arc
						(start 36.23818 -40.59936)
						(mid 33.19018 -40.59936)
						(end 36.23818 -40.59936)
					)
				)
			)
		)
		(zone
			(layers "F.Cu" "B.Cu" "In1.Cu" "In2.Cu" "In3.Cu" "In4.Cu" "In5.Cu" "In6.Cu"
				"In7.Cu" "In8.Cu" "In9.Cu" "In10.Cu" "In11.Cu" "In12.Cu"
			)
			(hatch none 0.5)
			(connect_pads
				(clearance 0)
			)
			(min_thickness 0.25)
			(keepout
				(tracks allowed)
				(vias not_allowed)
				(pads allowed)
				(copperpour not_allowed)
				(footprints allowed)
			)
			(placement
				(enabled no)
				(sheetname "")
			)
			(fill
				(thermal_gap 0.5)
				(thermal_bridge_width 0.5)
				(island_removal_mode 0)
			)
			(polygon
				(pts
					(arc
						(start 36.23818 -40.59936)
						(mid 33.19018 -40.59936)
						(end 36.23818 -40.59936)
					)
				)
			)
		)
	)
	(footprint ""
		(layer "F.Cu")
		(at 33.925002 -89.551764 90)
		(property "Reference" "EU1C3"
			(at 1.226566 -8.144002 0)
			(unlocked yes)
			(layer "F.SilkS")
			(effects
				(font
					(size 0.7874 0.5842)
					(thickness 0.1524)
				)
			)
		)
		(property "Value" ""
			(at 0 0 90)
			(layer "F.Fab")
			(effects
				(font
					(size 1.27 1.27)
				)
			)
		)
		(duplicate_pad_numbers_are_jumpers no)
		(fp_line
			(start 2.9718 -3.5052)
			(end 2.9718 3.429)
			(stroke
				(width 0.1524)
				(type default)
			)
			(layer "F.SilkS")
		)
		(fp_line
			(start -3.0099 -3.5052)
			(end 2.9718 -3.5052)
			(stroke
				(width 0.1524)
				(type default)
			)
			(layer "F.SilkS")
		)
		(fp_line
			(start 2.9718 3.429)
			(end -3.0099 3.429)
			(stroke
				(width 0.1524)
				(type default)
			)
			(layer "F.SilkS")
		)
		(fp_line
			(start -3.0099 3.429)
			(end -3.0099 -3.5052)
			(stroke
				(width 0.1524)
				(type default)
			)
			(layer "F.SilkS")
		)
		(fp_circle
			(center -3.057398 -2.678684)
			(end -3.057398 -2.551684)
			(stroke
				(width 0.254)
				(type default)
			)
			(fill no)
			(layer "F.SilkS")
		)
		(fp_poly
			(pts
				(xy -2.9972 -3.4925) (xy -2.9972 -2.6924) (xy -2.1971 -3.4925)
			)
			(stroke
				(width 0)
				(type default)
			)
			(fill yes)
			(layer "F.SilkS")
		)
		(fp_poly
			(pts
				(xy -2.549906 -3.050032) (xy -2.549906 3.050032) (xy 2.549906 3.050032) (xy 2.549906 -3.050032)
			)
			(stroke
				(width 0)
				(type default)
			)
			(fill no)
			(layer "F.CrtYd")
		)
		(fp_line
			(start 2.549906 -3.050032)
			(end 2.549906 3.050032)
			(stroke
				(width 0.1)
				(type default)
			)
			(layer "F.Fab")
		)
		(fp_line
			(start -2.549906 -3.050032)
			(end 2.549906 -3.050032)
			(stroke
				(width 0.1)
				(type default)
			)
			(layer "F.Fab")
		)
		(fp_line
			(start 2.549906 3.050032)
			(end -2.549906 3.050032)
			(stroke
				(width 0.1)
				(type default)
			)
			(layer "F.Fab")
		)
		(fp_line
			(start -2.549906 3.050032)
			(end -2.549906 -3.050032)
			(stroke
				(width 0.1)
				(type default)
			)
			(layer "F.Fab")
		)
		(fp_circle
			(center -3.057398 -2.678684)
			(end -3.057398 -2.551684)
			(stroke
				(width 0.254)
				(type default)
			)
			(fill no)
			(layer "F.Fab")
		)
		(pad "1" smd rect
			(at -2.39522 -2.279904 90)
			(size 0.7112 0.254)
			(layers "F.Cu" "F.Mask" "F.Paste")
			(net "PVCCIN_CPU1")
		)
		(pad "2" smd rect
			(at -2.39522 -1.83007 90)
			(size 0.7112 0.254)
			(layers "F.Cu" "F.Mask" "F.Paste")
			(net "GND")
		)
		(pad "3" smd rect
			(at -2.39522 -1.379982 90)
			(size 0.7112 0.254)
			(layers "F.Cu" "F.Mask" "F.Paste")
			(net "VR_PVCCIN_CPU1_PH5_VCIN")
		)
		(pad "4" smd rect
			(at -2.39522 -0.929894 90)
			(size 0.7112 0.254)
			(layers "F.Cu" "F.Mask" "F.Paste")
			(net "P5V_STBY")
		)
		(pad "5" smd rect
			(at -2.39522 -0.48006 90)
			(size 0.7112 0.254)
			(layers "F.Cu" "F.Mask" "F.Paste")
			(net "GND")
		)
		(pad "6" smd rect
			(at -2.39522 -0.029972 90)
			(size 0.7112 0.254)
			(layers "F.Cu" "F.Mask" "F.Paste")
			(net "TP_PVCCIN_CPU1_PH5_GL_0")
		)
		(pad "7" smd custom
			(at 0.016764 1.145032 90)
			(size 0.53975 0.53975)
			(layers "F.Cu" "F.Mask" "F.Paste")
			(net "GND")
			(options
				(clearance outline)
				(anchor circle)
			)
			(primitives
				(gr_poly
					(pts
						(xy -2.7051 1.0795) (xy -2.7051 -0.3683) (xy -0.9271 -0.3683) (xy -0.9271 -1.0795) (xy 2.7051 -1.0795)
						(xy 2.7051 1.0795)
					)
					(width 0)
					(fill yes)
				)
			)
		)
		(pad "10" smd rect
			(at -0.008382 2.874772 90)
			(size 4.3434 0.6096)
			(layers "F.Cu" "F.Mask" "F.Paste")
			(net "VR_PVCCIN_CPU1_PHASE5")
		)
		(pad "25" smd rect
			(at 1.548384 -1.283208 90)
			(size 2.3368 2.0066)
			(layers "F.Cu" "F.Mask" "F.Paste")
			(net "VR_FET_SW_P12V_STBY_PVCCIN_CPU1")
		)
		(pad "30" smd rect
			(at 2.050034 -2.895092 90)
			(size 0.254 0.7112)
			(layers "F.Cu" "F.Mask" "F.Paste")
			(net "VR_FET_SW_P12V_STBY_PVCCIN_CPU1")
		)
		(pad "31" smd rect
			(at 1.599946 -2.895092 90)
			(size 0.254 0.7112)
			(layers "F.Cu" "F.Mask" "F.Paste")
			(net "Net_359")
		)
		(pad "32" smd rect
			(at 1.150112 -2.895092 90)
			(size 0.254 0.7112)
			(layers "F.Cu" "F.Mask" "F.Paste")
			(net "VR_PVCCIN_CPU1_PH5_PHASE")
		)
		(pad "33" smd rect
			(at 0.700024 -2.895092 90)
			(size 0.254 0.7112)
			(layers "F.Cu" "F.Mask" "F.Paste")
			(net "VR_PVCCIN_CPU1_PH5_BOOT_R")
		)
		(pad "34" smd rect
			(at 0.249936 -2.895092 90)
			(size 0.254 0.7112)
			(layers "F.Cu" "F.Mask" "F.Paste")
			(net "VR_PVCCIN_CPU1_PWM5")
		)
		(pad "35" smd rect
			(at -0.199898 -2.895092 90)
			(size 0.254 0.7112)
			(layers "F.Cu" "F.Mask" "F.Paste")
			(net "P5V_STBY")
		)
		(pad "36" smd rect
			(at -0.649986 -2.895092 90)
			(size 0.254 0.7112)
			(layers "F.Cu" "F.Mask" "F.Paste")
			(net "A_TSENSE_PVCCIN_CPU1")
		)
		(pad "37" smd rect
			(at -1.100074 -2.895092 90)
			(size 0.254 0.7112)
			(layers "F.Cu" "F.Mask" "F.Paste")
			(net "VR_PVCCIN_CPU1_PH5_OCSET")
		)
		(pad "38" smd rect
			(at -1.549908 -2.895092 90)
			(size 0.254 0.7112)
			(layers "F.Cu" "F.Mask" "F.Paste")
			(net "ISENSE_PVCCIN_CPU1_PH5_IMON")
		)
		(pad "39" smd rect
			(at -1.999996 -2.895092 90)
			(size 0.254 0.7112)
			(layers "F.Cu" "F.Mask" "F.Paste")
			(net "VR_PVCCIN_CPU1_AIREF5")
		)
		(pad "40" smd rect
			(at -0.871728 -1.283208 90)
			(size 1.8034 2.0066)
			(layers "F.Cu" "F.Mask" "F.Paste")
			(net "GND")
		)
		(pad "41" smd rect
			(at -1.533906 0.247904 90)
			(size 0.508 0.3556)
			(layers "F.Cu" "F.Mask" "F.Paste")
			(net "TP_PVCCIN_CPU1_PH5_GL_1")
		)
	)
	(footprint ""
		(layer "F.Cu")
		(at 175.387 -82.677 90)
		(property "Reference" "R4D14"
			(at 0 0 90)
			(layer "F.SilkS")
			(hide yes)
			(effects
				(font
					(size 1.27 1.27)
				)
			)
		)
		(property "Value" ""
			(at 0 0 90)
			(layer "F.Fab")
			(effects
				(font
					(size 1.27 1.27)
				)
			)
		)
		(duplicate_pad_numbers_are_jumpers no)
		(fp_poly
			(pts
				(xy -0.2794 -0.1016) (xy 0.2794 -0.1016) (xy 0.2794 0.9906) (xy -0.2794 0.9906)
			)
			(stroke
				(width 0)
				(type default)
			)
			(fill no)
			(layer "F.CrtYd")
		)
		(fp_line
			(start 0.2794 -0.1016)
			(end -0.2794 -0.1016)
			(stroke
				(width 0.1)
				(type default)
			)
			(layer "F.Fab")
		)
		(fp_line
			(start -0.2794 -0.1016)
			(end -0.2794 0.9906)
			(stroke
				(width 0.1)
				(type default)
			)
			(layer "F.Fab")
		)
		(fp_line
			(start 0.2794 0.9906)
			(end 0.2794 -0.1016)
			(stroke
				(width 0.1)
				(type default)
			)
			(layer "F.Fab")
		)
		(fp_line
			(start -0.2794 0.9906)
			(end 0.2794 0.9906)
			(stroke
				(width 0.1)
				(type default)
			)
			(layer "F.Fab")
		)
		(pad "1" smd rect
			(at 0 0 90)
			(size 0.508 0.508)
			(layers "F.Cu" "F.Mask" "F.Paste")
			(net "CLK_100M_CPU0_BCLK2_R_DN")
		)
		(pad "2" smd rect
			(at 0 0.889 90)
			(size 0.508 0.508)
			(layers "F.Cu" "F.Mask" "F.Paste")
			(net "CLK_100M_CPU0_BCLK2_DN")
		)
		(zone
			(layer "F.Cu")
			(hatch none 0.5)
			(connect_pads
				(clearance 0)
			)
			(min_thickness 0.25)
			(keepout
				(tracks allowed)
				(vias not_allowed)
				(pads allowed)
				(copperpour not_allowed)
				(footprints allowed)
			)
			(placement
				(enabled no)
				(sheetname "")
			)
			(fill
				(thermal_gap 0.5)
				(thermal_bridge_width 0.5)
				(island_removal_mode 0)
			)
			(polygon
				(pts
					(xy 175.641 -82.423) (xy 175.641 -82.931) (xy 176.022 -82.931) (xy 176.022 -82.423)
				)
			)
		)
		(zone
			(layer "F.Cu")
			(hatch none 0.5)
			(connect_pads
				(clearance 0)
			)
			(min_thickness 0.25)
			(keepout
				(tracks not_allowed)
				(vias allowed)
				(pads allowed)
				(copperpour not_allowed)
				(footprints allowed)
			)
			(placement
				(enabled no)
				(sheetname "")
			)
			(fill
				(thermal_gap 0.5)
				(thermal_bridge_width 0.5)
				(island_removal_mode 0)
			)
			(polygon
				(pts
					(xy 176.022 -82.423) (xy 176.022 -82.931) (xy 175.641 -82.931) (xy 175.641 -82.423)
				)
			)
		)
	)
	(footprint ""
		(layer "F.Cu")
		(at 352.759518 -143.483076 -90)
		(property "Reference" "C7A22"
			(at 0 0 270)
			(layer "F.SilkS")
			(hide yes)
			(effects
				(font
					(size 1.27 1.27)
				)
			)
		)
		(property "Value" ""
			(at 0 0 270)
			(layer "F.Fab")
			(effects
				(font
					(size 1.27 1.27)
				)
			)
		)
		(duplicate_pad_numbers_are_jumpers no)
		(fp_poly
			(pts
				(xy 0.3048 -0.1016) (xy 0.3048 0.9906) (xy -0.3048 0.9906) (xy -0.3048 -0.1016)
			)
			(stroke
				(width 0)
				(type default)
			)
			(fill no)
			(layer "F.CrtYd")
		)
		(fp_line
			(start -0.3048 0.9906)
			(end 0.3048 0.9906)
			(stroke
				(width 0.1)
				(type default)
			)
			(layer "F.Fab")
		)
		(fp_line
			(start 0.3048 0.9906)
			(end 0.3048 -0.1016)
			(stroke
				(width 0.1)
				(type default)
			)
			(layer "F.Fab")
		)
		(fp_line
			(start -0.3048 -0.1016)
			(end -0.3048 0.9906)
			(stroke
				(width 0.1)
				(type default)
			)
			(layer "F.Fab")
		)
		(fp_line
			(start 0.3048 -0.1016)
			(end -0.3048 -0.1016)
			(stroke
				(width 0.1)
				(type default)
			)
			(layer "F.Fab")
		)
		(pad "1" smd rect
			(at 0 0 270)
			(size 0.508 0.508)
			(layers "F.Cu" "F.Mask" "F.Paste")
			(net "VR_PVDDQ_DEF_PH2_BOOT")
		)
		(pad "2" smd rect
			(at 0 0.889 270)
			(size 0.508 0.508)
			(layers "F.Cu" "F.Mask" "F.Paste")
			(net "VR_PVDDQ_DEF_PH2_PHASE")
		)
		(zone
			(layer "F.Cu")
			(hatch none 0.5)
			(connect_pads
				(clearance 0)
			)
			(min_thickness 0.25)
			(keepout
				(tracks not_allowed)
				(vias allowed)
				(pads allowed)
				(copperpour not_allowed)
				(footprints allowed)
			)
			(placement
				(enabled no)
				(sheetname "")
			)
			(fill
				(thermal_gap 0.5)
				(thermal_bridge_width 0.5)
				(island_removal_mode 0)
			)
			(polygon
				(pts
					(xy 352.124518 -143.737076) (xy 352.124518 -143.229076) (xy 352.505518 -143.229076) (xy 352.505518 -143.737076)
				)
			)
		)
		(zone
			(layer "F.Cu")
			(hatch none 0.5)
			(connect_pads
				(clearance 0)
			)
			(min_thickness 0.25)
			(keepout
				(tracks allowed)
				(vias not_allowed)
				(pads allowed)
				(copperpour not_allowed)
				(footprints allowed)
			)
			(placement
				(enabled no)
				(sheetname "")
			)
			(fill
				(thermal_gap 0.5)
				(thermal_bridge_width 0.5)
				(island_removal_mode 0)
			)
			(polygon
				(pts
					(xy 352.505518 -143.737076) (xy 352.505518 -143.229076) (xy 352.124518 -143.229076) (xy 352.124518 -143.737076)
				)
			)
		)
	)
	(footprint ""
		(layer "F.Cu")
		(at 419.5445 -113.03 90)
		(property "Reference" "R9W17"
			(at -0.8382 -0.67818 90)
			(unlocked yes)
			(layer "F.SilkS")
			(effects
				(font
					(size 0.4064 0.254)
					(thickness 0.1524)
				)
				(justify left)
			)
		)
		(property "Value" ""
			(at 0 0 90)
			(layer "F.Fab")
			(effects
				(font
					(size 1.27 1.27)
				)
			)
		)
		(duplicate_pad_numbers_are_jumpers no)
		(fp_poly
			(pts
				(xy -0.2794 -0.1016) (xy 0.2794 -0.1016) (xy 0.2794 0.9906) (xy -0.2794 0.9906)
			)
			(stroke
				(width 0)
				(type default)
			)
			(fill no)
			(layer "F.CrtYd")
		)
		(fp_line
			(start 0.2794 -0.1016)
			(end -0.2794 -0.1016)
			(stroke
				(width 0.1)
				(type default)
			)
			(layer "F.Fab")
		)
		(fp_line
			(start -0.2794 -0.1016)
			(end -0.2794 0.9906)
			(stroke
				(width 0.1)
				(type default)
			)
			(layer "F.Fab")
		)
		(fp_line
			(start 0.2794 0.9906)
			(end 0.2794 -0.1016)
			(stroke
				(width 0.1)
				(type default)
			)
			(layer "F.Fab")
		)
		(fp_line
			(start -0.2794 0.9906)
			(end 0.2794 0.9906)
			(stroke
				(width 0.1)
				(type default)
			)
			(layer "F.Fab")
		)
		(pad "1" smd rect
			(at 0 0 90)
			(size 0.508 0.508)
			(layers "F.Cu" "F.Mask" "F.Paste")
			(net "P3V3_STBY")
		)
		(pad "2" smd rect
			(at 0 0.889 90)
			(size 0.508 0.508)
			(layers "F.Cu" "F.Mask" "F.Paste")
			(net "SMB_PEHPCPU0_STBY_LVC3_R_SCL")
		)
		(zone
			(layer "F.Cu")
			(hatch none 0.5)
			(connect_pads
				(clearance 0)
			)
			(min_thickness 0.25)
			(keepout
				(tracks allowed)
				(vias not_allowed)
				(pads allowed)
				(copperpour not_allowed)
				(footprints allowed)
			)
			(placement
				(enabled no)
				(sheetname "")
			)
			(fill
				(thermal_gap 0.5)
				(thermal_bridge_width 0.5)
				(island_removal_mode 0)
			)
			(polygon
				(pts
					(xy 419.7985 -112.776) (xy 419.7985 -113.284) (xy 420.1795 -113.284) (xy 420.1795 -112.776)
				)
			)
		)
		(zone
			(layer "F.Cu")
			(hatch none 0.5)
			(connect_pads
				(clearance 0)
			)
			(min_thickness 0.25)
			(keepout
				(tracks not_allowed)
				(vias allowed)
				(pads allowed)
				(copperpour not_allowed)
				(footprints allowed)
			)
			(placement
				(enabled no)
				(sheetname "")
			)
			(fill
				(thermal_gap 0.5)
				(thermal_bridge_width 0.5)
				(island_removal_mode 0)
			)
			(polygon
				(pts
					(xy 420.1795 -112.776) (xy 420.1795 -113.284) (xy 419.7985 -113.284) (xy 419.7985 -112.776)
				)
			)
		)
	)
	(footprint ""
		(layer "F.Cu")
		(at 496.678204 -26.555192)
		(property "Reference" "EU7E1"
			(at 1.8415 2.376932 180)
			(unlocked yes)
			(layer "F.SilkS")
			(effects
				(font
					(size 0.7874 0.5842)
					(thickness 0.1524)
				)
				(justify left)
			)
		)
		(property "Value" ""
			(at 0 0 0)
			(layer "F.Fab")
			(effects
				(font
					(size 1.27 1.27)
				)
			)
		)
		(duplicate_pad_numbers_are_jumpers no)
		(fp_circle
			(center -0.702056 -0.595376)
			(end -0.575056 -0.595376)
			(stroke
				(width 0.254)
				(type default)
			)
			(fill no)
			(layer "F.SilkS")
		)
		(fp_rect
			(start 0.5842 1.549908)
			(end 1.4732 -0.050292)
			(stroke
				(width 0)
				(type default)
			)
			(fill yes)
			(layer "F.Paste")
		)
		(fp_rect
			(start -0.021336 1.799844)
			(end 2.078736 -0.300228)
			(stroke
				(width 0)
				(type default)
			)
			(fill no)
			(layer "F.CrtYd")
		)
		(fp_line
			(start -0.021336 -0.300228)
			(end 2.078736 -0.300228)
			(stroke
				(width 0.1)
				(type default)
			)
			(layer "F.Fab")
		)
		(fp_line
			(start -0.021336 1.799844)
			(end -0.021336 -0.300228)
			(stroke
				(width 0.1)
				(type default)
			)
			(layer "F.Fab")
		)
		(fp_line
			(start 2.078736 -0.300228)
			(end 2.078736 1.799844)
			(stroke
				(width 0.1)
				(type default)
			)
			(layer "F.Fab")
		)
		(fp_line
			(start 2.078736 1.799844)
			(end -0.021336 1.799844)
			(stroke
				(width 0.1)
				(type default)
			)
			(layer "F.Fab")
		)
		(fp_circle
			(center -0.702056 -0.595376)
			(end -0.575056 -0.595376)
			(stroke
				(width 0.254)
				(type default)
			)
			(fill no)
			(layer "F.Fab")
		)
		(pad "1" smd rect
			(at 0 0)
			(size 0.6604 0.3048)
			(layers "F.Cu" "F.Mask" "F.Paste")
			(net "P5V_STBY")
		)
		(pad "2" smd rect
			(at 0 0.499872)
			(size 0.6604 0.3048)
			(layers "F.Cu" "F.Mask" "F.Paste")
			(net "FM_P12V_MAIN_SW_EN")
		)
		(pad "3" smd rect
			(at 0 0.999744)
			(size 0.6604 0.3048)
			(layers "F.Cu" "F.Mask" "F.Paste")
			(net "P5V_STBY")
		)
		(pad "4" smd rect
			(at 0 1.499616)
			(size 0.6604 0.3048)
			(layers "F.Cu" "F.Mask" "F.Paste")
			(net "GND")
		)
		(pad "5" smd rect
			(at 2.0574 1.499616)
			(size 0.6604 0.3048)
			(layers "F.Cu" "F.Mask" "F.Paste")
			(net "P12V_STBY")
		)
		(pad "6" smd rect
			(at 2.0574 0.999744)
			(size 0.6604 0.3048)
			(layers "F.Cu" "F.Mask" "F.Paste")
			(net "P12V")
		)
		(pad "7" smd rect
			(at 2.0574 0.499872)
			(size 0.6604 0.3048)
			(layers "F.Cu" "F.Mask" "F.Paste")
			(net "P12V_SWITCH_G")
		)
		(pad "8" smd rect
			(at 2.0574 0)
			(size 0.6604 0.3048)
			(layers "F.Cu" "F.Mask" "F.Paste")
			(net "TP_SLG55021_P12V_MAIN_8")
		)
		(pad "9" smd rect
			(at 1.0287 0.749808)
			(size 0.889 1.6002)
			(layers "F.Cu" "F.Mask" "F.Paste")
			(net "GND")
		)
	)
	(footprint ""
		(layer "F.Cu")
		(at 184.531 -4.2545 180)
		(property "Reference" "C4G16"
			(at 0 0 180)
			(layer "F.SilkS")
			(hide yes)
			(effects
				(font
					(size 1.27 1.27)
				)
			)
		)
		(property "Value" ""
			(at 0 0 180)
			(layer "F.Fab")
			(effects
				(font
					(size 1.27 1.27)
				)
			)
		)
		(duplicate_pad_numbers_are_jumpers no)
		(fp_rect
			(start 0.3048 -0.1016)
			(end -0.3048 0.9906)
			(stroke
				(width 0)
				(type default)
			)
			(fill no)
			(layer "F.CrtYd")
		)
		(fp_line
			(start 0.3048 0.9906)
			(end 0.3048 -0.1016)
			(stroke
				(width 0.1)
				(type default)
			)
			(layer "F.Fab")
		)
		(fp_line
			(start 0.3048 -0.1016)
			(end -0.3048 -0.1016)
			(stroke
				(width 0.1)
				(type default)
			)
			(layer "F.Fab")
		)
		(fp_line
			(start -0.3048 0.9906)
			(end 0.3048 0.9906)
			(stroke
				(width 0.1)
				(type default)
			)
			(layer "F.Fab")
		)
		(fp_line
			(start -0.3048 -0.1016)
			(end -0.3048 0.9906)
			(stroke
				(width 0.1)
				(type default)
			)
			(layer "F.Fab")
		)
		(pad "1" smd rect
			(at 0 0 180)
			(size 0.508 0.508)
			(layers "F.Cu" "F.Mask" "F.Paste")
			(net "VR_PVTT_ABC_VREF")
		)
		(pad "2" smd rect
			(at 0 0.889 180)
			(size 0.508 0.508)
			(layers "F.Cu" "F.Mask" "F.Paste")
			(net "GND")
		)
		(zone
			(layer "F.Cu")
			(hatch none 0.5)
			(connect_pads
				(clearance 0)
			)
			(min_thickness 0.25)
			(keepout
				(tracks not_allowed)
				(vias allowed)
				(pads allowed)
				(copperpour not_allowed)
				(footprints allowed)
			)
			(placement
				(enabled no)
				(sheetname "")
			)
			(fill
				(thermal_gap 0.5)
				(thermal_bridge_width 0.5)
				(island_removal_mode 0)
			)
			(polygon
				(pts
					(xy 184.277 -4.5085) (xy 184.785 -4.5085) (xy 184.785 -4.8895) (xy 184.277 -4.8895)
				)
			)
		)
		(zone
			(layer "F.Cu")
			(hatch none 0.5)
			(connect_pads
				(clearance 0)
			)
			(min_thickness 0.25)
			(keepout
				(tracks allowed)
				(vias not_allowed)
				(pads allowed)
				(copperpour not_allowed)
				(footprints allowed)
			)
			(placement
				(enabled no)
				(sheetname "")
			)
			(fill
				(thermal_gap 0.5)
				(thermal_bridge_width 0.5)
				(island_removal_mode 0)
			)
			(polygon
				(pts
					(xy 184.277 -4.5085) (xy 184.785 -4.5085) (xy 184.785 -4.8895) (xy 184.277 -4.8895)
				)
			)
		)
	)
	(footprint ""
		(layer "F.Cu")
		(at 381.4572 -140.4366 90)
		(property "Reference" "C3M7"
			(at 0 0 90)
			(layer "F.SilkS")
			(hide yes)
			(effects
				(font
					(size 1.27 1.27)
				)
			)
		)
		(property "Value" ""
			(at 0 0 90)
			(layer "F.Fab")
			(effects
				(font
					(size 1.27 1.27)
				)
			)
		)
		(duplicate_pad_numbers_are_jumpers no)
		(fp_rect
			(start -0.4953 -0.2032)
			(end 0.4953 1.6002)
			(stroke
				(width 0)
				(type default)
			)
			(fill no)
			(layer "F.CrtYd")
		)
		(fp_line
			(start 0.4953 -0.2032)
			(end 0.4953 1.6002)
			(stroke
				(width 0.1)
				(type default)
			)
			(layer "F.Fab")
		)
		(fp_line
			(start -0.4953 -0.2032)
			(end 0.4953 -0.2032)
			(stroke
				(width 0.1)
				(type default)
			)
			(layer "F.Fab")
		)
		(fp_line
			(start 0.4953 1.6002)
			(end -0.4953 1.6002)
			(stroke
				(width 0.1)
				(type default)
			)
			(layer "F.Fab")
		)
		(fp_line
			(start -0.4953 1.6002)
			(end -0.4953 -0.2032)
			(stroke
				(width 0.1)
				(type default)
			)
			(layer "F.Fab")
		)
		(pad "1" smd rect
			(at 0 0 90)
			(size 0.762 0.889)
			(layers "F.Cu" "F.Mask" "F.Paste")
			(net "PVNN_PCH_STBY")
		)
		(pad "2" smd rect
			(at 0 1.397 90)
			(size 0.762 0.889)
			(layers "F.Cu" "F.Mask" "F.Paste")
			(net "GND")
		)
		(zone
			(layer "F.Cu")
			(hatch none 0.5)
			(connect_pads
				(clearance 0)
			)
			(min_thickness 0.25)
			(keepout
				(tracks not_allowed)
				(vias allowed)
				(pads allowed)
				(copperpour not_allowed)
				(footprints allowed)
			)
			(placement
				(enabled no)
				(sheetname "")
			)
			(fill
				(thermal_gap 0.5)
				(thermal_bridge_width 0.5)
				(island_removal_mode 0)
			)
			(polygon
				(pts
					(xy 381.9017 -140.0556) (xy 382.4097 -140.0556) (xy 382.4097 -140.8176) (xy 381.9017 -140.8176)
				)
			)
		)
	)
	(footprint ""
		(layer "F.Cu")
		(at 175.2346 -93.3958 180)
		(property "Reference" "R4C9"
			(at 0 0 180)
			(layer "F.SilkS")
			(hide yes)
			(effects
				(font
					(size 1.27 1.27)
				)
			)
		)
		(property "Value" ""
			(at 0 0 180)
			(layer "F.Fab")
			(effects
				(font
					(size 1.27 1.27)
				)
			)
		)
		(duplicate_pad_numbers_are_jumpers no)
		(fp_poly
			(pts
				(xy -0.2794 -0.1016) (xy 0.2794 -0.1016) (xy 0.2794 0.9906) (xy -0.2794 0.9906)
			)
			(stroke
				(width 0)
				(type default)
			)
			(fill no)
			(layer "F.CrtYd")
		)
		(fp_line
			(start 0.2794 0.9906)
			(end 0.2794 -0.1016)
			(stroke
				(width 0.1)
				(type default)
			)
			(layer "F.Fab")
		)
		(fp_line
			(start 0.2794 -0.1016)
			(end -0.2794 -0.1016)
			(stroke
				(width 0.1)
				(type default)
			)
			(layer "F.Fab")
		)
		(fp_line
			(start -0.2794 0.9906)
			(end 0.2794 0.9906)
			(stroke
				(width 0.1)
				(type default)
			)
			(layer "F.Fab")
		)
		(fp_line
			(start -0.2794 -0.1016)
			(end -0.2794 0.9906)
			(stroke
				(width 0.1)
				(type default)
			)
			(layer "F.Fab")
		)
		(pad "1" smd rect
			(at 0 0 180)
			(size 0.508 0.508)
			(layers "F.Cu" "F.Mask" "F.Paste")
			(net "GND")
		)
		(pad "2" smd rect
			(at 0 0.889 180)
			(size 0.508 0.508)
			(layers "F.Cu" "F.Mask" "F.Paste")
			(net "PD_GTL2014_2_VREF")
		)
		(zone
			(layer "F.Cu")
			(hatch none 0.5)
			(connect_pads
				(clearance 0)
			)
			(min_thickness 0.25)
			(keepout
				(tracks not_allowed)
				(vias allowed)
				(pads allowed)
				(copperpour not_allowed)
				(footprints allowed)
			)
			(placement
				(enabled no)
				(sheetname "")
			)
			(fill
				(thermal_gap 0.5)
				(thermal_bridge_width 0.5)
				(island_removal_mode 0)
			)
			(polygon
				(pts
					(xy 175.4886 -94.0308) (xy 174.9806 -94.0308) (xy 174.9806 -93.6498) (xy 175.4886 -93.6498)
				)
			)
		)
		(zone
			(layer "F.Cu")
			(hatch none 0.5)
			(connect_pads
				(clearance 0)
			)
			(min_thickness 0.25)
			(keepout
				(tracks allowed)
				(vias not_allowed)
				(pads allowed)
				(copperpour not_allowed)
				(footprints allowed)
			)
			(placement
				(enabled no)
				(sheetname "")
			)
			(fill
				(thermal_gap 0.5)
				(thermal_bridge_width 0.5)
				(island_removal_mode 0)
			)
			(polygon
				(pts
					(xy 175.4886 -93.6498) (xy 174.9806 -93.6498) (xy 174.9806 -94.0308) (xy 175.4886 -94.0308)
				)
			)
		)
	)
	(footprint ""
		(layer "F.Cu")
		(at 318.543432 -149.86 -90)
		(property "Reference" "C6A2"
			(at 0 0 270)
			(layer "F.SilkS")
			(hide yes)
			(effects
				(font
					(size 1.27 1.27)
				)
			)
		)
		(property "Value" ""
			(at 0 0 270)
			(layer "F.Fab")
			(effects
				(font
					(size 1.27 1.27)
				)
			)
		)
		(duplicate_pad_numbers_are_jumpers no)
		(fp_poly
			(pts
				(xy -0.4953 -0.2032) (xy 0.4953 -0.2032) (xy 0.4953 1.6002) (xy -0.4953 1.6002)
			)
			(stroke
				(width 0)
				(type default)
			)
			(fill no)
			(layer "F.CrtYd")
		)
		(fp_line
			(start -0.4953 1.6002)
			(end -0.4953 -0.2032)
			(stroke
				(width 0.1)
				(type default)
			)
			(layer "F.Fab")
		)
		(fp_line
			(start 0.4953 1.6002)
			(end -0.4953 1.6002)
			(stroke
				(width 0.1)
				(type default)
			)
			(layer "F.Fab")
		)
		(fp_line
			(start -0.4953 -0.2032)
			(end 0.4953 -0.2032)
			(stroke
				(width 0.1)
				(type default)
			)
			(layer "F.Fab")
		)
		(fp_line
			(start 0.4953 -0.2032)
			(end 0.4953 1.6002)
			(stroke
				(width 0.1)
				(type default)
			)
			(layer "F.Fab")
		)
		(pad "1" smd rect
			(at 0 0 270)
			(size 0.762 0.889)
			(layers "F.Cu" "F.Mask" "F.Paste")
			(net "PVPP_DEF")
		)
		(pad "2" smd rect
			(at 0 1.397 270)
			(size 0.762 0.889)
			(layers "F.Cu" "F.Mask" "F.Paste")
			(net "GND")
		)
		(zone
			(layer "F.Cu")
			(hatch none 0.5)
			(connect_pads
				(clearance 0)
			)
			(min_thickness 0.25)
			(keepout
				(tracks not_allowed)
				(vias allowed)
				(pads allowed)
				(copperpour not_allowed)
				(footprints allowed)
			)
			(placement
				(enabled no)
				(sheetname "")
			)
			(fill
				(thermal_gap 0.5)
				(thermal_bridge_width 0.5)
				(island_removal_mode 0)
			)
			(polygon
				(pts
					(xy 318.098932 -150.241) (xy 318.098932 -149.479) (xy 317.590932 -149.479) (xy 317.590932 -150.241)
				)
			)
		)
	)
	(footprint ""
		(layer "F.Cu")
		(at 348.384114 -23.486618)
		(property "Reference" "R7F16"
			(at 0 0 0)
			(layer "F.SilkS")
			(hide yes)
			(effects
				(font
					(size 1.27 1.27)
				)
			)
		)
		(property "Value" ""
			(at 0 0 0)
			(layer "F.Fab")
			(effects
				(font
					(size 1.27 1.27)
				)
			)
		)
		(duplicate_pad_numbers_are_jumpers no)
		(fp_poly
			(pts
				(xy -0.2794 -0.1016) (xy 0.2794 -0.1016) (xy 0.2794 0.9906) (xy -0.2794 0.9906)
			)
			(stroke
				(width 0)
				(type default)
			)
			(fill no)
			(layer "F.CrtYd")
		)
		(fp_line
			(start -0.2794 -0.1016)
			(end -0.2794 0.9906)
			(stroke
				(width 0.1)
				(type default)
			)
			(layer "F.Fab")
		)
		(fp_line
			(start -0.2794 0.9906)
			(end 0.2794 0.9906)
			(stroke
				(width 0.1)
				(type default)
			)
			(layer "F.Fab")
		)
		(fp_line
			(start 0.2794 -0.1016)
			(end -0.2794 -0.1016)
			(stroke
				(width 0.1)
				(type default)
			)
			(layer "F.Fab")
		)
		(fp_line
			(start 0.2794 0.9906)
			(end 0.2794 -0.1016)
			(stroke
				(width 0.1)
				(type default)
			)
			(layer "F.Fab")
		)
		(pad "1" smd rect
			(at 0 0)
			(size 0.508 0.508)
			(layers "F.Cu" "F.Mask" "F.Paste")
			(net "PWRGD_PVPP_ABC_R")
		)
		(pad "2" smd rect
			(at 0 0.889)
			(size 0.508 0.508)
			(layers "F.Cu" "F.Mask" "F.Paste")
			(net "PWRGD_PVPP_ABC")
		)
		(zone
			(layer "F.Cu")
			(hatch none 0.5)
			(connect_pads
				(clearance 0)
			)
			(min_thickness 0.25)
			(keepout
				(tracks allowed)
				(vias not_allowed)
				(pads allowed)
				(copperpour not_allowed)
				(footprints allowed)
			)
			(placement
				(enabled no)
				(sheetname "")
			)
			(fill
				(thermal_gap 0.5)
				(thermal_bridge_width 0.5)
				(island_removal_mode 0)
			)
			(polygon
				(pts
					(xy 348.130114 -23.232618) (xy 348.638114 -23.232618) (xy 348.638114 -22.851618) (xy 348.130114 -22.851618)
				)
			)
		)
		(zone
			(layer "F.Cu")
			(hatch none 0.5)
			(connect_pads
				(clearance 0)
			)
			(min_thickness 0.25)
			(keepout
				(tracks not_allowed)
				(vias allowed)
				(pads allowed)
				(copperpour not_allowed)
				(footprints allowed)
			)
			(placement
				(enabled no)
				(sheetname "")
			)
			(fill
				(thermal_gap 0.5)
				(thermal_bridge_width 0.5)
				(island_removal_mode 0)
			)
			(polygon
				(pts
					(xy 348.130114 -22.851618) (xy 348.638114 -22.851618) (xy 348.638114 -23.232618) (xy 348.130114 -23.232618)
				)
			)
		)
	)
	(footprint ""
		(layer "F.Cu")
		(at 339.258656 -131.977384)
		(property "Reference" "R7B19"
			(at 1.01473 0.656336 270)
			(unlocked yes)
			(layer "F.SilkS")
			(effects
				(font
					(size 0.4064 0.254)
					(thickness 0.1524)
				)
			)
		)
		(property "Value" ""
			(at 0 0 0)
			(layer "F.Fab")
			(effects
				(font
					(size 1.27 1.27)
				)
			)
		)
		(duplicate_pad_numbers_are_jumpers no)
		(fp_poly
			(pts
				(xy -0.4953 -0.2032) (xy 0.4953 -0.2032) (xy 0.4953 1.6002) (xy -0.4953 1.6002)
			)
			(stroke
				(width 0)
				(type default)
			)
			(fill no)
			(layer "F.CrtYd")
		)
		(fp_line
			(start -0.4953 -0.2032)
			(end 0.4953 -0.2032)
			(stroke
				(width 0.1)
				(type default)
			)
			(layer "F.Fab")
		)
		(fp_line
			(start -0.4953 1.6002)
			(end -0.4953 -0.2032)
			(stroke
				(width 0.1)
				(type default)
			)
			(layer "F.Fab")
		)
		(fp_line
			(start 0.4953 -0.2032)
			(end 0.4953 1.6002)
			(stroke
				(width 0.1)
				(type default)
			)
			(layer "F.Fab")
		)
		(fp_line
			(start 0.4953 1.6002)
			(end -0.4953 1.6002)
			(stroke
				(width 0.1)
				(type default)
			)
			(layer "F.Fab")
		)
		(pad "1" smd rect
			(at 0 0)
			(size 0.762 0.889)
			(layers "F.Cu" "F.Mask" "F.Paste")
			(net "VR_PVPP_DEF_BOOT")
		)
		(pad "2" smd rect
			(at 0 1.397)
			(size 0.762 0.889)
			(layers "F.Cu" "F.Mask" "F.Paste")
			(net "VR_PVPP_DEF_BOOT_R")
		)
		(zone
			(layer "F.Cu")
			(hatch none 0.5)
			(connect_pads
				(clearance 0)
			)
			(min_thickness 0.25)
			(keepout
				(tracks not_allowed)
				(vias allowed)
				(pads allowed)
				(copperpour not_allowed)
				(footprints allowed)
			)
			(placement
				(enabled no)
				(sheetname "")
			)
			(fill
				(thermal_gap 0.5)
				(thermal_bridge_width 0.5)
				(island_removal_mode 0)
			)
			(polygon
				(pts
					(xy 338.877656 -131.024884) (xy 339.639656 -131.024884) (xy 339.639656 -131.532884) (xy 338.877656 -131.532884)
				)
			)
		)
		(zone
			(layer "F.Cu")
			(hatch none 0.5)
			(connect_pads
				(clearance 0)
			)
			(min_thickness 0.25)
			(keepout
				(tracks allowed)
				(vias not_allowed)
				(pads allowed)
				(copperpour not_allowed)
				(footprints allowed)
			)
			(placement
				(enabled no)
				(sheetname "")
			)
			(fill
				(thermal_gap 0.5)
				(thermal_bridge_width 0.5)
				(island_removal_mode 0)
			)
			(polygon
				(pts
					(xy 339.639656 -131.024884) (xy 339.639656 -131.532884) (xy 338.877656 -131.532884) (xy 338.877656 -131.024884)
				)
			)
		)
	)
	(footprint ""
		(layer "F.Cu")
		(at 13.8938 -28.575 90)
		(property "Reference" "C1F13"
			(at 0 0 90)
			(layer "F.SilkS")
			(hide yes)
			(effects
				(font
					(size 1.27 1.27)
				)
			)
		)
		(property "Value" ""
			(at 0 0 90)
			(layer "F.Fab")
			(effects
				(font
					(size 1.27 1.27)
				)
			)
		)
		(duplicate_pad_numbers_are_jumpers no)
		(fp_rect
			(start -0.3048 -0.1016)
			(end 0.3048 0.9906)
			(stroke
				(width 0)
				(type default)
			)
			(fill no)
			(layer "F.CrtYd")
		)
		(fp_line
			(start 0.3048 -0.1016)
			(end -0.3048 -0.1016)
			(stroke
				(width 0.1)
				(type default)
			)
			(layer "F.Fab")
		)
		(fp_line
			(start -0.3048 -0.1016)
			(end -0.3048 0.9906)
			(stroke
				(width 0.1)
				(type default)
			)
			(layer "F.Fab")
		)
		(fp_line
			(start 0.3048 0.9906)
			(end 0.3048 -0.1016)
			(stroke
				(width 0.1)
				(type default)
			)
			(layer "F.Fab")
		)
		(fp_line
			(start -0.3048 0.9906)
			(end 0.3048 0.9906)
			(stroke
				(width 0.1)
				(type default)
			)
			(layer "F.Fab")
		)
		(pad "1" smd rect
			(at 0 0 90)
			(size 0.508 0.508)
			(layers "F.Cu" "F.Mask" "F.Paste")
			(net "P3E_CPU1_PE3_MP_C_TXN<3>")
		)
		(pad "2" smd rect
			(at 0 0.889 90)
			(size 0.508 0.508)
			(layers "F.Cu" "F.Mask" "F.Paste")
			(net "P3E_CPU1_PE3_MP_TXN<3>")
		)
		(zone
			(layer "F.Cu")
			(hatch none 0.5)
			(connect_pads
				(clearance 0)
			)
			(min_thickness 0.25)
			(keepout
				(tracks allowed)
				(vias not_allowed)
				(pads allowed)
				(copperpour not_allowed)
				(footprints allowed)
			)
			(placement
				(enabled no)
				(sheetname "")
			)
			(fill
				(thermal_gap 0.5)
				(thermal_bridge_width 0.5)
				(island_removal_mode 0)
			)
			(polygon
				(pts
					(xy 14.1478 -28.321) (xy 14.5288 -28.321) (xy 14.5288 -28.829) (xy 14.1478 -28.829)
				)
			)
		)
		(zone
			(layer "F.Cu")
			(hatch none 0.5)
			(connect_pads
				(clearance 0)
			)
			(min_thickness 0.25)
			(keepout
				(tracks not_allowed)
				(vias allowed)
				(pads allowed)
				(copperpour not_allowed)
				(footprints allowed)
			)
			(placement
				(enabled no)
				(sheetname "")
			)
			(fill
				(thermal_gap 0.5)
				(thermal_bridge_width 0.5)
				(island_removal_mode 0)
			)
			(polygon
				(pts
					(xy 14.1478 -28.321) (xy 14.5288 -28.321) (xy 14.5288 -28.829) (xy 14.1478 -28.829)
				)
			)
		)
	)
	(footprint ""
		(layer "F.Cu")
		(at 426.5041 -125.6792 -90)
		(property "Reference" "R8B13"
			(at 0 0 270)
			(layer "F.SilkS")
			(hide yes)
			(effects
				(font
					(size 1.27 1.27)
				)
			)
		)
		(property "Value" ""
			(at 0 0 270)
			(layer "F.Fab")
			(effects
				(font
					(size 1.27 1.27)
				)
			)
		)
		(duplicate_pad_numbers_are_jumpers no)
		(fp_poly
			(pts
				(xy -0.2794 -0.1016) (xy 0.2794 -0.1016) (xy 0.2794 0.9906) (xy -0.2794 0.9906)
			)
			(stroke
				(width 0)
				(type default)
			)
			(fill no)
			(layer "F.CrtYd")
		)
		(fp_line
			(start -0.2794 0.9906)
			(end 0.2794 0.9906)
			(stroke
				(width 0.1)
				(type default)
			)
			(layer "F.Fab")
		)
		(fp_line
			(start 0.2794 0.9906)
			(end 0.2794 -0.1016)
			(stroke
				(width 0.1)
				(type default)
			)
			(layer "F.Fab")
		)
		(fp_line
			(start -0.2794 -0.1016)
			(end -0.2794 0.9906)
			(stroke
				(width 0.1)
				(type default)
			)
			(layer "F.Fab")
		)
		(fp_line
			(start 0.2794 -0.1016)
			(end -0.2794 -0.1016)
			(stroke
				(width 0.1)
				(type default)
			)
			(layer "F.Fab")
		)
		(pad "1" smd rect
			(at 0 0 270)
			(size 0.508 0.508)
			(layers "F.Cu" "F.Mask" "F.Paste")
			(net "PVPP_ABC")
		)
		(pad "2" smd rect
			(at 0 0.889 270)
			(size 0.508 0.508)
			(layers "F.Cu" "F.Mask" "F.Paste")
			(net "SMB_HFI1_CPU0_LVC2_SDA")
		)
		(zone
			(layer "F.Cu")
			(hatch none 0.5)
			(connect_pads
				(clearance 0)
			)
			(min_thickness 0.25)
			(keepout
				(tracks not_allowed)
				(vias allowed)
				(pads allowed)
				(copperpour not_allowed)
				(footprints allowed)
			)
			(placement
				(enabled no)
				(sheetname "")
			)
			(fill
				(thermal_gap 0.5)
				(thermal_bridge_width 0.5)
				(island_removal_mode 0)
			)
			(polygon
				(pts
					(xy 425.8691 -125.9332) (xy 425.8691 -125.4252) (xy 426.2501 -125.4252) (xy 426.2501 -125.9332)
				)
			)
		)
		(zone
			(layer "F.Cu")
			(hatch none 0.5)
			(connect_pads
				(clearance 0)
			)
			(min_thickness 0.25)
			(keepout
				(tracks allowed)
				(vias not_allowed)
				(pads allowed)
				(copperpour not_allowed)
				(footprints allowed)
			)
			(placement
				(enabled no)
				(sheetname "")
			)
			(fill
				(thermal_gap 0.5)
				(thermal_bridge_width 0.5)
				(island_removal_mode 0)
			)
			(polygon
				(pts
					(xy 426.2501 -125.9332) (xy 426.2501 -125.4252) (xy 425.8691 -125.4252) (xy 425.8691 -125.9332)
				)
			)
		)
	)
	(footprint ""
		(layer "F.Cu")
		(at 414.8836 -94.7166)
		(property "Reference" "R7W18"
			(at -0.8382 -0.67818 0)
			(unlocked yes)
			(layer "F.SilkS")
			(effects
				(font
					(size 0.4064 0.254)
					(thickness 0.1524)
				)
				(justify left)
			)
		)
		(property "Value" ""
			(at 0 0 0)
			(layer "F.Fab")
			(effects
				(font
					(size 1.27 1.27)
				)
			)
		)
		(duplicate_pad_numbers_are_jumpers no)
		(fp_poly
			(pts
				(xy -0.2794 -0.1016) (xy 0.2794 -0.1016) (xy 0.2794 0.9906) (xy -0.2794 0.9906)
			)
			(stroke
				(width 0)
				(type default)
			)
			(fill no)
			(layer "F.CrtYd")
		)
		(fp_line
			(start -0.2794 -0.1016)
			(end -0.2794 0.9906)
			(stroke
				(width 0.1)
				(type default)
			)
			(layer "F.Fab")
		)
		(fp_line
			(start -0.2794 0.9906)
			(end 0.2794 0.9906)
			(stroke
				(width 0.1)
				(type default)
			)
			(layer "F.Fab")
		)
		(fp_line
			(start 0.2794 -0.1016)
			(end -0.2794 -0.1016)
			(stroke
				(width 0.1)
				(type default)
			)
			(layer "F.Fab")
		)
		(fp_line
			(start 0.2794 0.9906)
			(end 0.2794 -0.1016)
			(stroke
				(width 0.1)
				(type default)
			)
			(layer "F.Fab")
		)
		(pad "1" smd rect
			(at 0 0)
			(size 0.508 0.508)
			(layers "F.Cu" "F.Mask" "F.Paste")
			(net "IRQ_SML1_PMBUS_ALERT_N")
		)
		(pad "2" smd rect
			(at 0 0.889)
			(size 0.508 0.508)
			(layers "F.Cu" "F.Mask" "F.Paste")
			(net "IRQ_SML1_PMBUS_ALERT_R1_N")
		)
		(zone
			(layer "F.Cu")
			(hatch none 0.5)
			(connect_pads
				(clearance 0)
			)
			(min_thickness 0.25)
			(keepout
				(tracks allowed)
				(vias not_allowed)
				(pads allowed)
				(copperpour not_allowed)
				(footprints allowed)
			)
			(placement
				(enabled no)
				(sheetname "")
			)
			(fill
				(thermal_gap 0.5)
				(thermal_bridge_width 0.5)
				(island_removal_mode 0)
			)
			(polygon
				(pts
					(xy 414.6296 -94.4626) (xy 415.1376 -94.4626) (xy 415.1376 -94.0816) (xy 414.6296 -94.0816)
				)
			)
		)
		(zone
			(layer "F.Cu")
			(hatch none 0.5)
			(connect_pads
				(clearance 0)
			)
			(min_thickness 0.25)
			(keepout
				(tracks not_allowed)
				(vias allowed)
				(pads allowed)
				(copperpour not_allowed)
				(footprints allowed)
			)
			(placement
				(enabled no)
				(sheetname "")
			)
			(fill
				(thermal_gap 0.5)
				(thermal_bridge_width 0.5)
				(island_removal_mode 0)
			)
			(polygon
				(pts
					(xy 414.6296 -94.0816) (xy 415.1376 -94.0816) (xy 415.1376 -94.4626) (xy 414.6296 -94.4626)
				)
			)
		)
	)
	(footprint ""
		(layer "F.Cu")
		(at 472.7575 -138.43 90)
		(property "Reference" "R9A21"
			(at 0 0 90)
			(layer "F.SilkS")
			(hide yes)
			(effects
				(font
					(size 1.27 1.27)
				)
			)
		)
		(property "Value" ""
			(at 0 0 90)
			(layer "F.Fab")
			(effects
				(font
					(size 1.27 1.27)
				)
			)
		)
		(duplicate_pad_numbers_are_jumpers no)
		(fp_poly
			(pts
				(xy -0.2794 -0.1016) (xy 0.2794 -0.1016) (xy 0.2794 0.9906) (xy -0.2794 0.9906)
			)
			(stroke
				(width 0)
				(type default)
			)
			(fill no)
			(layer "F.CrtYd")
		)
		(fp_line
			(start 0.2794 -0.1016)
			(end -0.2794 -0.1016)
			(stroke
				(width 0.1)
				(type default)
			)
			(layer "F.Fab")
		)
		(fp_line
			(start -0.2794 -0.1016)
			(end -0.2794 0.9906)
			(stroke
				(width 0.1)
				(type default)
			)
			(layer "F.Fab")
		)
		(fp_line
			(start 0.2794 0.9906)
			(end 0.2794 -0.1016)
			(stroke
				(width 0.1)
				(type default)
			)
			(layer "F.Fab")
		)
		(fp_line
			(start -0.2794 0.9906)
			(end 0.2794 0.9906)
			(stroke
				(width 0.1)
				(type default)
			)
			(layer "F.Fab")
		)
		(pad "1" smd rect
			(at 0 0 90)
			(size 0.508 0.508)
			(layers "F.Cu" "F.Mask" "F.Paste")
			(net "P3V3_STBY")
		)
		(pad "2" smd rect
			(at 0 0.889 90)
			(size 0.508 0.508)
			(layers "F.Cu" "F.Mask" "F.Paste")
			(net "FM_PWR_LED_N")
		)
		(zone
			(layer "F.Cu")
			(hatch none 0.5)
			(connect_pads
				(clearance 0)
			)
			(min_thickness 0.25)
			(keepout
				(tracks allowed)
				(vias not_allowed)
				(pads allowed)
				(copperpour not_allowed)
				(footprints allowed)
			)
			(placement
				(enabled no)
				(sheetname "")
			)
			(fill
				(thermal_gap 0.5)
				(thermal_bridge_width 0.5)
				(island_removal_mode 0)
			)
			(polygon
				(pts
					(xy 473.0115 -138.176) (xy 473.0115 -138.684) (xy 473.3925 -138.684) (xy 473.3925 -138.176)
				)
			)
		)
		(zone
			(layer "F.Cu")
			(hatch none 0.5)
			(connect_pads
				(clearance 0)
			)
			(min_thickness 0.25)
			(keepout
				(tracks not_allowed)
				(vias allowed)
				(pads allowed)
				(copperpour not_allowed)
				(footprints allowed)
			)
			(placement
				(enabled no)
				(sheetname "")
			)
			(fill
				(thermal_gap 0.5)
				(thermal_bridge_width 0.5)
				(island_removal_mode 0)
			)
			(polygon
				(pts
					(xy 473.3925 -138.176) (xy 473.3925 -138.684) (xy 473.0115 -138.684) (xy 473.0115 -138.176)
				)
			)
		)
	)
	(footprint ""
		(layer "F.Cu")
		(at 480.22764 -137.328402 -90)
		(property "Reference" "DS9A5"
			(at -0.9017 3.57505 90)
			(unlocked yes)
			(layer "F.SilkS")
			(effects
				(font
					(size 0.7874 0.5842)
					(thickness 0.1524)
				)
			)
		)
		(property "Value" ""
			(at 0 0 270)
			(layer "F.Fab")
			(effects
				(font
					(size 1.27 1.27)
				)
			)
		)
		(duplicate_pad_numbers_are_jumpers no)
		(fp_line
			(start -0.1016 5.61213)
			(end -0.1016 4.488688)
			(stroke
				(width 0.1524)
				(type default)
			)
			(layer "F.SilkS")
		)
		(fp_line
			(start -0.582422 4.488688)
			(end 0.379222 4.488688)
			(stroke
				(width 0.1524)
				(type default)
			)
			(layer "F.SilkS")
		)
		(fp_line
			(start -0.1016 4.488688)
			(end -0.582422 3.655822)
			(stroke
				(width 0.1524)
				(type default)
			)
			(layer "F.SilkS")
		)
		(fp_line
			(start -0.582422 3.655822)
			(end -0.1016 3.655822)
			(stroke
				(width 0.1524)
				(type default)
			)
			(layer "F.SilkS")
		)
		(fp_line
			(start -0.1016 3.655822)
			(end 0.379222 3.655822)
			(stroke
				(width 0.1524)
				(type default)
			)
			(layer "F.SilkS")
		)
		(fp_line
			(start 0.379222 3.655822)
			(end -0.1016 4.488688)
			(stroke
				(width 0.1524)
				(type default)
			)
			(layer "F.SilkS")
		)
		(fp_line
			(start -0.1016 2.744216)
			(end -0.1016 3.655822)
			(stroke
				(width 0.1524)
				(type default)
			)
			(layer "F.SilkS")
		)
		(fp_poly
			(pts
				(xy 0.6223 2.032) (xy -0.6223 2.032) (xy -0.6223 0.0254) (xy 0.6223 0.0254)
			)
			(stroke
				(width 0)
				(type default)
			)
			(fill no)
			(layer "F.CrtYd")
		)
		(fp_line
			(start -0.582422 4.488688)
			(end 0.379222 4.488688)
			(stroke
				(width 0.1)
				(type default)
			)
			(layer "F.Fab")
		)
		(fp_line
			(start -0.1016 4.488688)
			(end -0.1016 5.61213)
			(stroke
				(width 0.1)
				(type default)
			)
			(layer "F.Fab")
		)
		(fp_line
			(start -0.1016 4.488688)
			(end -0.582422 3.655822)
			(stroke
				(width 0.1)
				(type default)
			)
			(layer "F.Fab")
		)
		(fp_line
			(start -0.582422 3.655822)
			(end 0.379222 3.655822)
			(stroke
				(width 0.1)
				(type default)
			)
			(layer "F.Fab")
		)
		(fp_line
			(start -0.1016 3.655822)
			(end -0.1016 2.744216)
			(stroke
				(width 0.1)
				(type default)
			)
			(layer "F.Fab")
		)
		(fp_line
			(start 0.379222 3.655822)
			(end -0.1016 4.488688)
			(stroke
				(width 0.1)
				(type default)
			)
			(layer "F.Fab")
		)
		(fp_line
			(start -0.6223 2.032)
			(end -0.6223 0.0254)
			(stroke
				(width 0.1)
				(type default)
			)
			(layer "F.Fab")
		)
		(fp_line
			(start 0.6223 2.032)
			(end -0.6223 2.032)
			(stroke
				(width 0.1)
				(type default)
			)
			(layer "F.Fab")
		)
		(fp_line
			(start -0.6223 0.0254)
			(end 0.6223 0.0254)
			(stroke
				(width 0.1)
				(type default)
			)
			(layer "F.Fab")
		)
		(fp_line
			(start 0.6223 0.0254)
			(end 0.6223 2.032)
			(stroke
				(width 0.1)
				(type default)
			)
			(layer "F.Fab")
		)
		(pad "1" smd rect
			(at 0 0 270)
			(size 1.27 1.27)
			(layers "F.Cu" "F.Mask" "F.Paste")
			(net "FM_PWR_LED_A")
		)
		(pad "2" smd rect
			(at 0 2.032 270)
			(size 1.27 1.27)
			(layers "F.Cu" "F.Mask" "F.Paste")
			(net "FM_PWR_LED_K")
		)
		(zone
			(layer "F.Cu")
			(hatch none 0.5)
			(connect_pads
				(clearance 0)
			)
			(min_thickness 0.25)
			(keepout
				(tracks not_allowed)
				(vias allowed)
				(pads allowed)
				(copperpour not_allowed)
				(footprints allowed)
			)
			(placement
				(enabled no)
				(sheetname "")
			)
			(fill
				(thermal_gap 0.5)
				(thermal_bridge_width 0.5)
				(island_removal_mode 0)
			)
			(polygon
				(pts
					(xy 478.83064 -137.963402) (xy 478.83064 -136.693402) (xy 479.59264 -136.693402) (xy 479.59264 -137.963402)
				)
			)
		)
		(zone
			(layer "F.Cu")
			(hatch none 0.5)
			(connect_pads
				(clearance 0)
			)
			(min_thickness 0.25)
			(keepout
				(tracks allowed)
				(vias not_allowed)
				(pads allowed)
				(copperpour not_allowed)
				(footprints allowed)
			)
			(placement
				(enabled no)
				(sheetname "")
			)
			(fill
				(thermal_gap 0.5)
				(thermal_bridge_width 0.5)
				(island_removal_mode 0)
			)
			(polygon
				(pts
					(xy 478.83064 -137.963402) (xy 478.83064 -136.693402) (xy 479.59264 -136.693402) (xy 479.59264 -137.963402)
				)
			)
		)
	)
	(footprint ""
		(layer "F.Cu")
		(at 17.0434 -41.5036 -90)
		(property "Reference" "C1E22"
			(at 0 0 270)
			(layer "F.SilkS")
			(hide yes)
			(effects
				(font
					(size 1.27 1.27)
				)
			)
		)
		(property "Value" ""
			(at 0 0 270)
			(layer "F.Fab")
			(effects
				(font
					(size 1.27 1.27)
				)
			)
		)
		(duplicate_pad_numbers_are_jumpers no)
		(fp_poly
			(pts
				(xy 0.3048 -0.1016) (xy 0.3048 0.9906) (xy -0.3048 0.9906) (xy -0.3048 -0.1016)
			)
			(stroke
				(width 0)
				(type default)
			)
			(fill no)
			(layer "F.CrtYd")
		)
		(fp_line
			(start -0.3048 0.9906)
			(end 0.3048 0.9906)
			(stroke
				(width 0.1)
				(type default)
			)
			(layer "F.Fab")
		)
		(fp_line
			(start 0.3048 0.9906)
			(end 0.3048 -0.1016)
			(stroke
				(width 0.1)
				(type default)
			)
			(layer "F.Fab")
		)
		(fp_line
			(start -0.3048 -0.1016)
			(end -0.3048 0.9906)
			(stroke
				(width 0.1)
				(type default)
			)
			(layer "F.Fab")
		)
		(fp_line
			(start 0.3048 -0.1016)
			(end -0.3048 -0.1016)
			(stroke
				(width 0.1)
				(type default)
			)
			(layer "F.Fab")
		)
		(pad "1" smd rect
			(at 0 0 270)
			(size 0.508 0.508)
			(layers "F.Cu" "F.Mask" "F.Paste")
			(net "P3V3_STBY")
		)
		(pad "2" smd rect
			(at 0 0.889 270)
			(size 0.508 0.508)
			(layers "F.Cu" "F.Mask" "F.Paste")
			(net "GND")
		)
		(zone
			(layer "F.Cu")
			(hatch none 0.5)
			(connect_pads
				(clearance 0)
			)
			(min_thickness 0.25)
			(keepout
				(tracks not_allowed)
				(vias allowed)
				(pads allowed)
				(copperpour not_allowed)
				(footprints allowed)
			)
			(placement
				(enabled no)
				(sheetname "")
			)
			(fill
				(thermal_gap 0.5)
				(thermal_bridge_width 0.5)
				(island_removal_mode 0)
			)
			(polygon
				(pts
					(xy 16.4084 -41.7576) (xy 16.4084 -41.2496) (xy 16.7894 -41.2496) (xy 16.7894 -41.7576)
				)
			)
		)
		(zone
			(layer "F.Cu")
			(hatch none 0.5)
			(connect_pads
				(clearance 0)
			)
			(min_thickness 0.25)
			(keepout
				(tracks allowed)
				(vias not_allowed)
				(pads allowed)
				(copperpour not_allowed)
				(footprints allowed)
			)
			(placement
				(enabled no)
				(sheetname "")
			)
			(fill
				(thermal_gap 0.5)
				(thermal_bridge_width 0.5)
				(island_removal_mode 0)
			)
			(polygon
				(pts
					(xy 16.7894 -41.7576) (xy 16.7894 -41.2496) (xy 16.4084 -41.2496) (xy 16.4084 -41.7576)
				)
			)
		)
	)
	(footprint ""
		(layer "F.Cu")
		(at 406.9461 -62.611 90)
		(property "Reference" "R8E13"
			(at 0 0 90)
			(layer "F.SilkS")
			(hide yes)
			(effects
				(font
					(size 1.27 1.27)
				)
			)
		)
		(property "Value" ""
			(at 0 0 90)
			(layer "F.Fab")
			(effects
				(font
					(size 1.27 1.27)
				)
			)
		)
		(duplicate_pad_numbers_are_jumpers no)
		(fp_poly
			(pts
				(xy -0.2794 -0.1016) (xy 0.2794 -0.1016) (xy 0.2794 0.9906) (xy -0.2794 0.9906)
			)
			(stroke
				(width 0)
				(type default)
			)
			(fill no)
			(layer "F.CrtYd")
		)
		(pad "1" smd rect
			(at 0 0 90)
			(size 0.508 0.508)
			(layers "F.Cu" "F.Mask" "F.Paste")
			(net "SPI_PCH_MISO")
		)
		(pad "2" smd rect
			(at 0 0.889 90)
			(size 0.508 0.508)
			(layers "F.Cu" "F.Mask" "F.Paste")
			(net "SPI_PCH_TPM_MISO_R")
		)
		(zone
			(layer "F.Cu")
			(hatch none 0.5)
			(connect_pads
				(clearance 0)
			)
			(min_thickness 0.25)
			(keepout
				(tracks allowed)
				(vias not_allowed)
				(pads allowed)
				(copperpour not_allowed)
				(footprints allowed)
			)
			(placement
				(enabled no)
				(sheetname "")
			)
			(fill
				(thermal_gap 0.5)
				(thermal_bridge_width 0.5)
				(island_removal_mode 0)
			)
			(polygon
				(pts
					(xy 407.2001 -62.357) (xy 407.2001 -62.865) (xy 407.5811 -62.865) (xy 407.5811 -62.357)
				)
			)
		)
		(zone
			(layer "F.Cu")
			(hatch none 0.5)
			(connect_pads
				(clearance 0)
			)
			(min_thickness 0.25)
			(keepout
				(tracks not_allowed)
				(vias allowed)
				(pads allowed)
				(copperpour not_allowed)
				(footprints allowed)
			)
			(placement
				(enabled no)
				(sheetname "")
			)
			(fill
				(thermal_gap 0.5)
				(thermal_bridge_width 0.5)
				(island_removal_mode 0)
			)
			(polygon
				(pts
					(xy 407.5811 -62.357) (xy 407.5811 -62.865) (xy 407.2001 -62.865) (xy 407.2001 -62.357)
				)
			)
		)
	)
	(footprint ""
		(layer "F.Cu")
		(at 389.0645 -80.6196 -90)
		(property "Reference" "C7D5"
			(at 0 0 270)
			(layer "F.SilkS")
			(hide yes)
			(effects
				(font
					(size 1.27 1.27)
				)
			)
		)
		(property "Value" ""
			(at 0 0 270)
			(layer "F.Fab")
			(effects
				(font
					(size 1.27 1.27)
				)
			)
		)
		(duplicate_pad_numbers_are_jumpers no)
		(fp_poly
			(pts
				(xy 0.3048 -0.1016) (xy 0.3048 0.9906) (xy -0.3048 0.9906) (xy -0.3048 -0.1016)
			)
			(stroke
				(width 0)
				(type default)
			)
			(fill no)
			(layer "F.CrtYd")
		)
		(fp_line
			(start -0.3048 0.9906)
			(end 0.3048 0.9906)
			(stroke
				(width 0.1)
				(type default)
			)
			(layer "F.Fab")
		)
		(fp_line
			(start 0.3048 0.9906)
			(end 0.3048 -0.1016)
			(stroke
				(width 0.1)
				(type default)
			)
			(layer "F.Fab")
		)
		(fp_line
			(start -0.3048 -0.1016)
			(end -0.3048 0.9906)
			(stroke
				(width 0.1)
				(type default)
			)
			(layer "F.Fab")
		)
		(fp_line
			(start 0.3048 -0.1016)
			(end -0.3048 -0.1016)
			(stroke
				(width 0.1)
				(type default)
			)
			(layer "F.Fab")
		)
		(pad "1" smd rect
			(at 0 0 270)
			(size 0.508 0.508)
			(layers "F.Cu" "F.Mask" "F.Paste")
			(net "P0V7_GTL2104_VREF_0")
		)
		(pad "2" smd rect
			(at 0 0.889 270)
			(size 0.508 0.508)
			(layers "F.Cu" "F.Mask" "F.Paste")
			(net "GND")
		)
		(zone
			(layer "F.Cu")
			(hatch none 0.5)
			(connect_pads
				(clearance 0)
			)
			(min_thickness 0.25)
			(keepout
				(tracks not_allowed)
				(vias allowed)
				(pads allowed)
				(copperpour not_allowed)
				(footprints allowed)
			)
			(placement
				(enabled no)
				(sheetname "")
			)
			(fill
				(thermal_gap 0.5)
				(thermal_bridge_width 0.5)
				(island_removal_mode 0)
			)
			(polygon
				(pts
					(xy 388.4295 -80.8736) (xy 388.4295 -80.3656) (xy 388.8105 -80.3656) (xy 388.8105 -80.8736)
				)
			)
		)
		(zone
			(layer "F.Cu")
			(hatch none 0.5)
			(connect_pads
				(clearance 0)
			)
			(min_thickness 0.25)
			(keepout
				(tracks allowed)
				(vias not_allowed)
				(pads allowed)
				(copperpour not_allowed)
				(footprints allowed)
			)
			(placement
				(enabled no)
				(sheetname "")
			)
			(fill
				(thermal_gap 0.5)
				(thermal_bridge_width 0.5)
				(island_removal_mode 0)
			)
			(polygon
				(pts
					(xy 388.8105 -80.8736) (xy 388.8105 -80.3656) (xy 388.4295 -80.3656) (xy 388.4295 -80.8736)
				)
			)
		)
	)
	(footprint ""
		(layer "F.Cu")
		(at 205.0288 -49.6824 90)
		(property "Reference" "R4E17"
			(at 0 0 90)
			(layer "F.SilkS")
			(hide yes)
			(effects
				(font
					(size 1.27 1.27)
				)
			)
		)
		(property "Value" ""
			(at 0 0 90)
			(layer "F.Fab")
			(effects
				(font
					(size 1.27 1.27)
				)
			)
		)
		(duplicate_pad_numbers_are_jumpers no)
		(fp_poly
			(pts
				(xy -0.2794 -0.1016) (xy 0.2794 -0.1016) (xy 0.2794 0.9906) (xy -0.2794 0.9906)
			)
			(stroke
				(width 0)
				(type default)
			)
			(fill no)
			(layer "F.CrtYd")
		)
		(fp_line
			(start 0.2794 -0.1016)
			(end -0.2794 -0.1016)
			(stroke
				(width 0.1)
				(type default)
			)
			(layer "F.Fab")
		)
		(fp_line
			(start -0.2794 -0.1016)
			(end -0.2794 0.9906)
			(stroke
				(width 0.1)
				(type default)
			)
			(layer "F.Fab")
		)
		(fp_line
			(start 0.2794 0.9906)
			(end 0.2794 -0.1016)
			(stroke
				(width 0.1)
				(type default)
			)
			(layer "F.Fab")
		)
		(fp_line
			(start -0.2794 0.9906)
			(end 0.2794 0.9906)
			(stroke
				(width 0.1)
				(type default)
			)
			(layer "F.Fab")
		)
		(pad "1" smd rect
			(at 0 0 90)
			(size 0.508 0.508)
			(layers "F.Cu" "F.Mask" "F.Paste")
			(net "VSENSE_PVCCIN_CPU0_N")
		)
		(pad "2" smd rect
			(at 0 0.889 90)
			(size 0.508 0.508)
			(layers "F.Cu" "F.Mask" "F.Paste")
			(net "VSENSE_PVCCIN_CPU0_SKT_VRTN")
		)
		(zone
			(layer "F.Cu")
			(hatch none 0.5)
			(connect_pads
				(clearance 0)
			)
			(min_thickness 0.25)
			(keepout
				(tracks allowed)
				(vias not_allowed)
				(pads allowed)
				(copperpour not_allowed)
				(footprints allowed)
			)
			(placement
				(enabled no)
				(sheetname "")
			)
			(fill
				(thermal_gap 0.5)
				(thermal_bridge_width 0.5)
				(island_removal_mode 0)
			)
			(polygon
				(pts
					(xy 205.2828 -49.4284) (xy 205.2828 -49.9364) (xy 205.6638 -49.9364) (xy 205.6638 -49.4284)
				)
			)
		)
		(zone
			(layer "F.Cu")
			(hatch none 0.5)
			(connect_pads
				(clearance 0)
			)
			(min_thickness 0.25)
			(keepout
				(tracks not_allowed)
				(vias allowed)
				(pads allowed)
				(copperpour not_allowed)
				(footprints allowed)
			)
			(placement
				(enabled no)
				(sheetname "")
			)
			(fill
				(thermal_gap 0.5)
				(thermal_bridge_width 0.5)
				(island_removal_mode 0)
			)
			(polygon
				(pts
					(xy 205.6638 -49.4284) (xy 205.6638 -49.9364) (xy 205.2828 -49.9364) (xy 205.2828 -49.4284)
				)
			)
		)
	)
	(footprint ""
		(layer "F.Cu")
		(at 339.6742 -105.029 90)
		(property "Reference" "R7C3"
			(at 0 0 90)
			(layer "F.SilkS")
			(hide yes)
			(effects
				(font
					(size 1.27 1.27)
				)
			)
		)
		(property "Value" ""
			(at 0 0 90)
			(layer "F.Fab")
			(effects
				(font
					(size 1.27 1.27)
				)
			)
		)
		(duplicate_pad_numbers_are_jumpers no)
		(fp_poly
			(pts
				(xy -0.2794 -0.1016) (xy 0.2794 -0.1016) (xy 0.2794 0.9906) (xy -0.2794 0.9906)
			)
			(stroke
				(width 0)
				(type default)
			)
			(fill no)
			(layer "F.CrtYd")
		)
		(fp_line
			(start 0.2794 -0.1016)
			(end -0.2794 -0.1016)
			(stroke
				(width 0.1)
				(type default)
			)
			(layer "F.Fab")
		)
		(fp_line
			(start -0.2794 -0.1016)
			(end -0.2794 0.9906)
			(stroke
				(width 0.1)
				(type default)
			)
			(layer "F.Fab")
		)
		(fp_line
			(start 0.2794 0.9906)
			(end 0.2794 -0.1016)
			(stroke
				(width 0.1)
				(type default)
			)
			(layer "F.Fab")
		)
		(fp_line
			(start -0.2794 0.9906)
			(end 0.2794 0.9906)
			(stroke
				(width 0.1)
				(type default)
			)
			(layer "F.Fab")
		)
		(pad "1" smd rect
			(at 0 0 90)
			(size 0.508 0.508)
			(layers "F.Cu" "F.Mask" "F.Paste")
			(net "PVCCIO_CPU0")
		)
		(pad "2" smd rect
			(at 0 0.889 90)
			(size 0.508 0.508)
			(layers "F.Cu" "F.Mask" "F.Paste")
			(net "GND")
		)
		(zone
			(layer "F.Cu")
			(hatch none 0.5)
			(connect_pads
				(clearance 0)
			)
			(min_thickness 0.25)
			(keepout
				(tracks allowed)
				(vias not_allowed)
				(pads allowed)
				(copperpour not_allowed)
				(footprints allowed)
			)
			(placement
				(enabled no)
				(sheetname "")
			)
			(fill
				(thermal_gap 0.5)
				(thermal_bridge_width 0.5)
				(island_removal_mode 0)
			)
			(polygon
				(pts
					(xy 339.9282 -104.775) (xy 339.9282 -105.283) (xy 340.3092 -105.283) (xy 340.3092 -104.775)
				)
			)
		)
		(zone
			(layer "F.Cu")
			(hatch none 0.5)
			(connect_pads
				(clearance 0)
			)
			(min_thickness 0.25)
			(keepout
				(tracks not_allowed)
				(vias allowed)
				(pads allowed)
				(copperpour not_allowed)
				(footprints allowed)
			)
			(placement
				(enabled no)
				(sheetname "")
			)
			(fill
				(thermal_gap 0.5)
				(thermal_bridge_width 0.5)
				(island_removal_mode 0)
			)
			(polygon
				(pts
					(xy 340.3092 -104.775) (xy 340.3092 -105.283) (xy 339.9282 -105.283) (xy 339.9282 -104.775)
				)
			)
		)
	)
	(footprint ""
		(layer "F.Cu")
		(at 181.991 -32.893 90)
		(property "Reference" "C4F4"
			(at -3.20167 3.429 0)
			(unlocked yes)
			(layer "F.SilkS")
			(effects
				(font
					(size 0.7874 0.5842)
					(thickness 0.1524)
				)
			)
		)
		(property "Value" ""
			(at 0 0 90)
			(layer "F.Fab")
			(effects
				(font
					(size 1.27 1.27)
				)
			)
		)
		(duplicate_pad_numbers_are_jumpers no)
		(fp_line
			(start 2.504948 -1.616456)
			(end 2.504948 1.633728)
			(stroke
				(width 0.1524)
				(type default)
			)
			(layer "F.SilkS")
		)
		(fp_line
			(start 1.6002 -1.616456)
			(end 2.504948 -1.616456)
			(stroke
				(width 0.1524)
				(type default)
			)
			(layer "F.SilkS")
		)
		(fp_line
			(start -1.6002 -1.616456)
			(end -2.563114 -1.616456)
			(stroke
				(width 0.1524)
				(type default)
			)
			(layer "F.SilkS")
		)
		(fp_line
			(start -2.563114 -1.616456)
			(end -2.563114 1.633728)
			(stroke
				(width 0.1524)
				(type default)
			)
			(layer "F.SilkS")
		)
		(fp_line
			(start 2.504948 1.633728)
			(end 1.6002 1.633728)
			(stroke
				(width 0.1524)
				(type default)
			)
			(layer "F.SilkS")
		)
		(fp_line
			(start -2.563114 1.633728)
			(end -1.6002 1.633728)
			(stroke
				(width 0.1524)
				(type default)
			)
			(layer "F.SilkS")
		)
		(fp_line
			(start 2.286 7.366)
			(end 2.286 1.63195)
			(stroke
				(width 0.1524)
				(type default)
			)
			(layer "F.SilkS")
		)
		(fp_line
			(start 2.286 7.366)
			(end 1.600708 7.366)
			(stroke
				(width 0.1524)
				(type default)
			)
			(layer "F.SilkS")
		)
		(fp_line
			(start -2.286 7.366)
			(end -2.286 1.632712)
			(stroke
				(width 0.1524)
				(type default)
			)
			(layer "F.SilkS")
		)
		(fp_line
			(start -2.286 7.366)
			(end -1.60147 7.366)
			(stroke
				(width 0.1524)
				(type default)
			)
			(layer "F.SilkS")
		)
		(fp_rect
			(start -2.286 7.366)
			(end 2.286 -0.254)
			(stroke
				(width 0)
				(type default)
			)
			(fill no)
			(layer "F.CrtYd")
		)
		(fp_line
			(start 2.286 -0.254)
			(end 2.286 7.366)
			(stroke
				(width 0.1)
				(type default)
			)
			(layer "F.Fab")
		)
		(fp_line
			(start -2.286 -0.254)
			(end 2.286 -0.254)
			(stroke
				(width 0.1)
				(type default)
			)
			(layer "F.Fab")
		)
		(fp_line
			(start 2.286 7.366)
			(end -2.286 7.366)
			(stroke
				(width 0.1)
				(type default)
			)
			(layer "F.Fab")
		)
		(fp_line
			(start -2.286 7.366)
			(end -2.286 -0.254)
			(stroke
				(width 0.1)
				(type default)
			)
			(layer "F.Fab")
		)
		(pad "1" smd rect
			(at 0 0 90)
			(size 2.54 3.048)
			(layers "F.Cu" "F.Mask" "F.Paste")
			(net "P12V_STBY")
		)
		(pad "2" smd rect
			(at 0 7.112 90)
			(size 2.54 3.048)
			(layers "F.Cu" "F.Mask" "F.Paste")
			(net "GND")
		)
	)
	(footprint ""
		(layer "F.Cu")
		(at 184.531 -146.685)
		(property "Reference" "C4A12"
			(at 0 0 0)
			(layer "F.SilkS")
			(hide yes)
			(effects
				(font
					(size 1.27 1.27)
				)
			)
		)
		(property "Value" ""
			(at 0 0 0)
			(layer "F.Fab")
			(effects
				(font
					(size 1.27 1.27)
				)
			)
		)
		(duplicate_pad_numbers_are_jumpers no)
		(fp_rect
			(start 0.3048 0.9906)
			(end -0.3048 -0.1016)
			(stroke
				(width 0)
				(type default)
			)
			(fill no)
			(layer "F.CrtYd")
		)
		(fp_line
			(start -0.3048 -0.1016)
			(end -0.3048 0.9906)
			(stroke
				(width 0.1)
				(type default)
			)
			(layer "F.Fab")
		)
		(fp_line
			(start -0.3048 0.9906)
			(end 0.3048 0.9906)
			(stroke
				(width 0.1)
				(type default)
			)
			(layer "F.Fab")
		)
		(fp_line
			(start 0.3048 -0.1016)
			(end -0.3048 -0.1016)
			(stroke
				(width 0.1)
				(type default)
			)
			(layer "F.Fab")
		)
		(fp_line
			(start 0.3048 0.9906)
			(end 0.3048 -0.1016)
			(stroke
				(width 0.1)
				(type default)
			)
			(layer "F.Fab")
		)
		(pad "1" smd rect
			(at 0 0)
			(size 0.508 0.508)
			(layers "F.Cu" "F.Mask" "F.Paste")
			(net "PWRGD_PVTT_DEF_CPU0_R")
		)
		(pad "2" smd rect
			(at 0 0.889)
			(size 0.508 0.508)
			(layers "F.Cu" "F.Mask" "F.Paste")
			(net "GND")
		)
		(zone
			(layer "F.Cu")
			(hatch none 0.5)
			(connect_pads
				(clearance 0)
			)
			(min_thickness 0.25)
			(keepout
				(tracks not_allowed)
				(vias allowed)
				(pads allowed)
				(copperpour not_allowed)
				(footprints allowed)
			)
			(placement
				(enabled no)
				(sheetname "")
			)
			(fill
				(thermal_gap 0.5)
				(thermal_bridge_width 0.5)
				(island_removal_mode 0)
			)
			(polygon
				(pts
					(xy 184.785 -146.05) (xy 184.785 -146.431) (xy 184.277 -146.431) (xy 184.277 -146.05)
				)
			)
		)
		(zone
			(layer "F.Cu")
			(hatch none 0.5)
			(connect_pads
				(clearance 0)
			)
			(min_thickness 0.25)
			(keepout
				(tracks allowed)
				(vias not_allowed)
				(pads allowed)
				(copperpour not_allowed)
				(footprints allowed)
			)
			(placement
				(enabled no)
				(sheetname "")
			)
			(fill
				(thermal_gap 0.5)
				(thermal_bridge_width 0.5)
				(island_removal_mode 0)
			)
			(polygon
				(pts
					(xy 184.785 -146.05) (xy 184.785 -146.431) (xy 184.277 -146.431) (xy 184.277 -146.05)
				)
			)
		)
	)
	(footprint ""
		(layer "F.Cu")
		(at 277.15972 -83.86064)
		(property "Reference" "R6D1"
			(at 0 0 0)
			(layer "F.SilkS")
			(hide yes)
			(effects
				(font
					(size 1.27 1.27)
				)
			)
		)
		(property "Value" ""
			(at 0 0 0)
			(layer "F.Fab")
			(effects
				(font
					(size 1.27 1.27)
				)
			)
		)
		(duplicate_pad_numbers_are_jumpers no)
		(fp_poly
			(pts
				(xy -0.2794 -0.1016) (xy 0.2794 -0.1016) (xy 0.2794 0.9906) (xy -0.2794 0.9906)
			)
			(stroke
				(width 0)
				(type default)
			)
			(fill no)
			(layer "F.CrtYd")
		)
		(fp_line
			(start -0.2794 -0.1016)
			(end -0.2794 0.9906)
			(stroke
				(width 0.1)
				(type default)
			)
			(layer "F.Fab")
		)
		(fp_line
			(start -0.2794 0.9906)
			(end 0.2794 0.9906)
			(stroke
				(width 0.1)
				(type default)
			)
			(layer "F.Fab")
		)
		(fp_line
			(start 0.2794 -0.1016)
			(end -0.2794 -0.1016)
			(stroke
				(width 0.1)
				(type default)
			)
			(layer "F.Fab")
		)
		(fp_line
			(start 0.2794 0.9906)
			(end 0.2794 -0.1016)
			(stroke
				(width 0.1)
				(type default)
			)
			(layer "F.Fab")
		)
		(pad "1" smd rect
			(at 0 0)
			(size 0.508 0.508)
			(layers "F.Cu" "F.Mask" "F.Paste")
			(net "A_CPU0_DEF_RCOMP2")
		)
		(pad "2" smd rect
			(at 0 0.889)
			(size 0.508 0.508)
			(layers "F.Cu" "F.Mask" "F.Paste")
			(net "GND")
		)
		(zone
			(layer "F.Cu")
			(hatch none 0.5)
			(connect_pads
				(clearance 0)
			)
			(min_thickness 0.25)
			(keepout
				(tracks allowed)
				(vias not_allowed)
				(pads allowed)
				(copperpour not_allowed)
				(footprints allowed)
			)
			(placement
				(enabled no)
				(sheetname "")
			)
			(fill
				(thermal_gap 0.5)
				(thermal_bridge_width 0.5)
				(island_removal_mode 0)
			)
			(polygon
				(pts
					(xy 276.90572 -83.60664) (xy 277.41372 -83.60664) (xy 277.41372 -83.22564) (xy 276.90572 -83.22564)
				)
			)
		)
		(zone
			(layer "F.Cu")
			(hatch none 0.5)
			(connect_pads
				(clearance 0)
			)
			(min_thickness 0.25)
			(keepout
				(tracks not_allowed)
				(vias allowed)
				(pads allowed)
				(copperpour not_allowed)
				(footprints allowed)
			)
			(placement
				(enabled no)
				(sheetname "")
			)
			(fill
				(thermal_gap 0.5)
				(thermal_bridge_width 0.5)
				(island_removal_mode 0)
			)
			(polygon
				(pts
					(xy 276.90572 -83.22564) (xy 277.41372 -83.22564) (xy 277.41372 -83.60664) (xy 276.90572 -83.60664)
				)
			)
		)
	)
	(footprint ""
		(layer "F.Cu")
		(at 34.417 10.7315 -90)
		(property "Reference" "T1P30"
			(at 0 0 270)
			(layer "F.SilkS")
			(hide yes)
			(effects
				(font
					(size 1.27 1.27)
				)
			)
		)
		(property "Value" "*"
			(at 0 -3.44805 270)
			(unlocked yes)
			(layer "F.Fab")
			(hide yes)
			(effects
				(font
					(size 0.889 0.889)
					(thickness 0.1524)
				)
			)
		)
		(property "Device Type" "TPAD-SE-2P-GP_DISCRET-GA1-TPADA"
			(at 0 -4.97205 270)
			(unlocked yes)
			(layer "F.Fab")
			(hide yes)
			(effects
				(font
					(size 0.889 0.889)
					(thickness 0.1524)
				)
			)
		)
		(duplicate_pad_numbers_are_jumpers no)
		(fp_line
			(start -1.016 2.286)
			(end -1.016 -2.286)
			(stroke
				(width 0.1524)
				(type default)
			)
			(layer "F.SilkS")
		)
		(fp_line
			(start 1.016 2.286)
			(end -1.016 2.286)
			(stroke
				(width 0.1524)
				(type default)
			)
			(layer "F.SilkS")
		)
		(fp_line
			(start -1.016 -2.286)
			(end 1.016 -2.286)
			(stroke
				(width 0.1524)
				(type default)
			)
			(layer "F.SilkS")
		)
		(fp_line
			(start 1.016 -2.286)
			(end 1.016 2.286)
			(stroke
				(width 0.1524)
				(type default)
			)
			(layer "F.SilkS")
		)
		(fp_rect
			(start -1.27 2.54)
			(end 1.27 -2.54)
			(stroke
				(width 0)
				(type default)
			)
			(fill no)
			(layer "F.CrtYd")
		)
		(fp_rect
			(start -1.27 2.54)
			(end 1.27 -2.54)
			(stroke
				(width 0)
				(type default)
			)
			(fill no)
			(layer "F.Fab")
		)
		(pad "1" thru_hole circle
			(at 0 -1.27 270)
			(size 1.524 1.524)
			(drill 0.9144)
			(layers "*.Cu" "*.Mask")
			(remove_unused_layers no)
			(net "L14_40OHM_6INCH")
			(clearance -0.0508)
			(thermal_gap 0.127)
			(padstack
				(mode front_inner_back)
				(layer "Inner"
					(shape circle)
					(size 1.1684 1.1684)
					(clearance 0.127)
				)
				(layer "B.Cu"
					(shape circle)
					(size 1.524 1.524)
					(clearance -0.0508)
				)
			)
		)
		(pad "GND1" thru_hole rect
			(at 0 1.27 270)
			(size 1.524 1.524)
			(drill 0.9144)
			(layers "*.Cu" "*.Mask")
			(remove_unused_layers no)
			(net "GND")
			(clearance -0.0508)
			(thermal_gap 0.127)
			(padstack
				(mode front_inner_back)
				(layer "Inner"
					(shape circle)
					(size 1.1684 1.1684)
					(clearance 0.127)
				)
				(layer "B.Cu"
					(shape rect)
					(size 1.524 1.524)
					(clearance -0.0508)
				)
			)
		)
	)
	(footprint ""
		(layer "F.Cu")
		(at 308.874414 -164.908992 90)
		(property "Reference" "T1D22"
			(at 0 0 90)
			(layer "F.SilkS")
			(hide yes)
			(effects
				(font
					(size 1.27 1.27)
				)
			)
		)
		(property "Value" "*"
			(at -3.4036 -4.46405 90)
			(unlocked yes)
			(layer "F.Fab")
			(hide yes)
			(effects
				(font
					(size 0.889 0.889)
					(thickness 0.1524)
				)
			)
		)
		(property "Device Type" "TEST-PAD-12P-1-GP-U_DISCRET-GBA"
			(at -3.4036 -5.98805 90)
			(unlocked yes)
			(layer "F.Fab")
			(hide yes)
			(effects
				(font
					(size 0.889 0.889)
					(thickness 0.1524)
				)
			)
		)
		(duplicate_pad_numbers_are_jumpers no)
		(fp_line
			(start 2.3622 -4.826)
			(end 2.3622 3.4798)
			(stroke
				(width 0.1524)
				(type default)
			)
			(layer "F.SilkS")
		)
		(fp_line
			(start -2.3876 -4.826)
			(end 2.3622 -4.826)
			(stroke
				(width 0.1524)
				(type default)
			)
			(layer "F.SilkS")
		)
		(fp_line
			(start 2.3622 3.4798)
			(end -2.3876 3.4798)
			(stroke
				(width 0.1524)
				(type default)
			)
			(layer "F.SilkS")
		)
		(fp_line
			(start -2.3876 3.4798)
			(end -2.3876 -4.826)
			(stroke
				(width 0.1524)
				(type default)
			)
			(layer "F.SilkS")
		)
		(fp_rect
			(start -2.6416 3.7338)
			(end 2.6162 -5.08)
			(stroke
				(width 0)
				(type default)
			)
			(fill no)
			(layer "F.CrtYd")
		)
		(fp_rect
			(start -2.6416 3.7338)
			(end 2.6162 -5.08)
			(stroke
				(width 0)
				(type default)
			)
			(fill no)
			(layer "F.Fab")
		)
		(pad "1" smd circle
			(at 0.496824 -1.301496 90)
			(size 0.6604 0.6604)
			(layers "F.Cu" "F.Mask" "F.Paste")
			(net "L12_85OHM_10INCH_DN")
		)
		(pad "2" smd circle
			(at -0.503936 -1.301496 90)
			(size 0.6604 0.6604)
			(layers "F.Cu" "F.Mask" "F.Paste")
			(net "L12_85OHM_10INCH_DP")
		)
		(pad "3" smd custom
			(at -0.00889 0.370078 90)
			(size 0.74295 0.74295)
			(layers "F.Cu" "F.Mask" "F.Paste")
			(net "GND")
			(options
				(clearance outline)
				(anchor circle)
			)
			(primitives
				(gr_poly
					(pts
						(xy -2.1209 1.4859) (xy 2.1209 1.4859) (xy 2.1209 -1.4859) (xy 1.08585 -1.4859) (xy 1.08585 -0.4699)
						(xy -1.08585 -0.4699) (xy -1.08585 -1.4859) (xy -2.1209 -1.4859)
					)
					(width 0)
					(fill yes)
				)
			)
		)
		(pad "4" thru_hole circle
			(at 1.266444 -3.851656 90)
			(size 1.4478 1.4478)
			(drill 1.0414)
			(layers "*.Cu" "*.Mask")
			(remove_unused_layers no)
			(net "GND")
			(clearance 0.1524)
			(thermal_gap 0.1524)
		)
		(pad "5" thru_hole circle
			(at -1.273556 -3.851656 90)
			(size 1.4478 1.4478)
			(drill 1.0414)
			(layers "*.Cu" "*.Mask")
			(remove_unused_layers no)
			(net "GND")
			(clearance 0.1524)
			(thermal_gap 0.1524)
		)
		(pad "6" thru_hole circle
			(at 1.266444 2.498344 90)
			(size 1.4478 1.4478)
			(drill 1.0414)
			(layers "*.Cu" "*.Mask")
			(remove_unused_layers no)
			(net "GND")
			(clearance 0.1524)
			(thermal_gap 0.1524)
		)
		(pad "7" thru_hole circle
			(at -1.273556 2.498344 90)
			(size 1.4478 1.4478)
			(drill 1.0414)
			(layers "*.Cu" "*.Mask")
			(remove_unused_layers no)
			(net "GND")
			(clearance 0.1524)
			(thermal_gap 0.1524)
		)
		(pad "8" thru_hole circle
			(at 1.27 -0.4572 90)
			(size 0.7112 0.7112)
			(drill 0.4064)
			(layers "*.Cu" "*.Mask")
			(remove_unused_layers no)
			(net "GND")
			(clearance 0.1016)
			(thermal_gap 0.1016)
		)
		(pad "9" thru_hole circle
			(at 1.27 0.762 90)
			(size 0.7112 0.7112)
			(drill 0.4064)
			(layers "*.Cu" "*.Mask")
			(remove_unused_layers no)
			(net "GND")
			(clearance 0.1016)
			(thermal_gap 0.1016)
		)
		(pad "10" thru_hole circle
			(at -0.0254 0.762 90)
			(size 0.7112 0.7112)
			(drill 0.4064)
			(layers "*.Cu" "*.Mask")
			(remove_unused_layers no)
			(net "GND")
			(clearance 0.1016)
			(thermal_gap 0.1016)
		)
		(pad "11" thru_hole circle
			(at -1.27 0.762 90)
			(size 0.7112 0.7112)
			(drill 0.4064)
			(layers "*.Cu" "*.Mask")
			(remove_unused_layers no)
			(net "GND")
			(clearance 0.1016)
			(thermal_gap 0.1016)
		)
		(pad "12" thru_hole circle
			(at -1.27 -0.4572 90)
			(size 0.7112 0.7112)
			(drill 0.4064)
			(layers "*.Cu" "*.Mask")
			(remove_unused_layers no)
			(net "GND")
			(clearance 0.1016)
			(thermal_gap 0.1016)
		)
	)
	(footprint ""
		(layer "F.Cu")
		(at 198.925434 -57.039764 90)
		(property "Reference" "EU4E1"
			(at 3.360166 -1.643634 0)
			(unlocked yes)
			(layer "F.SilkS")
			(effects
				(font
					(size 0.7874 0.5842)
					(thickness 0.1524)
				)
			)
		)
		(property "Value" ""
			(at 0 0 90)
			(layer "F.Fab")
			(effects
				(font
					(size 1.27 1.27)
				)
			)
		)
		(duplicate_pad_numbers_are_jumpers no)
		(fp_line
			(start 2.9718 -3.5052)
			(end 2.9718 3.429)
			(stroke
				(width 0.1524)
				(type default)
			)
			(layer "F.SilkS")
		)
		(fp_line
			(start -3.0099 -3.5052)
			(end 2.9718 -3.5052)
			(stroke
				(width 0.1524)
				(type default)
			)
			(layer "F.SilkS")
		)
		(fp_line
			(start 2.9718 3.429)
			(end -3.0099 3.429)
			(stroke
				(width 0.1524)
				(type default)
			)
			(layer "F.SilkS")
		)
		(fp_line
			(start -3.0099 3.429)
			(end -3.0099 -3.5052)
			(stroke
				(width 0.1524)
				(type default)
			)
			(layer "F.SilkS")
		)
		(fp_circle
			(center -3.057398 -2.678684)
			(end -3.057398 -2.551684)
			(stroke
				(width 0.254)
				(type default)
			)
			(fill no)
			(layer "F.SilkS")
		)
		(fp_poly
			(pts
				(xy -2.9972 -3.4925) (xy -2.9972 -2.6924) (xy -2.1971 -3.4925)
			)
			(stroke
				(width 0)
				(type default)
			)
			(fill yes)
			(layer "F.SilkS")
		)
		(fp_poly
			(pts
				(xy -2.549906 -3.050032) (xy -2.549906 3.050032) (xy 2.549906 3.050032) (xy 2.549906 -3.050032)
			)
			(stroke
				(width 0)
				(type default)
			)
			(fill no)
			(layer "F.CrtYd")
		)
		(fp_line
			(start 2.549906 -3.050032)
			(end 2.549906 3.050032)
			(stroke
				(width 0.1)
				(type default)
			)
			(layer "F.Fab")
		)
		(fp_line
			(start -2.549906 -3.050032)
			(end 2.549906 -3.050032)
			(stroke
				(width 0.1)
				(type default)
			)
			(layer "F.Fab")
		)
		(fp_line
			(start 2.549906 3.050032)
			(end -2.549906 3.050032)
			(stroke
				(width 0.1)
				(type default)
			)
			(layer "F.Fab")
		)
		(fp_line
			(start -2.549906 3.050032)
			(end -2.549906 -3.050032)
			(stroke
				(width 0.1)
				(type default)
			)
			(layer "F.Fab")
		)
		(fp_circle
			(center -3.057398 -2.678684)
			(end -3.057398 -2.551684)
			(stroke
				(width 0.254)
				(type default)
			)
			(fill no)
			(layer "F.Fab")
		)
		(pad "1" smd rect
			(at -2.39522 -2.279904 90)
			(size 0.7112 0.254)
			(layers "F.Cu" "F.Mask" "F.Paste")
			(net "PVCCIN_CPU0")
		)
		(pad "2" smd rect
			(at -2.39522 -1.83007 90)
			(size 0.7112 0.254)
			(layers "F.Cu" "F.Mask" "F.Paste")
			(net "GND")
		)
		(pad "3" smd rect
			(at -2.39522 -1.379982 90)
			(size 0.7112 0.254)
			(layers "F.Cu" "F.Mask" "F.Paste")
			(net "VR_PVCCIN_CPU0_PH1_VCIN")
		)
		(pad "4" smd rect
			(at -2.39522 -0.929894 90)
			(size 0.7112 0.254)
			(layers "F.Cu" "F.Mask" "F.Paste")
			(net "P5V_STBY")
		)
		(pad "5" smd rect
			(at -2.39522 -0.48006 90)
			(size 0.7112 0.254)
			(layers "F.Cu" "F.Mask" "F.Paste")
			(net "GND")
		)
		(pad "6" smd rect
			(at -2.39522 -0.029972 90)
			(size 0.7112 0.254)
			(layers "F.Cu" "F.Mask" "F.Paste")
			(net "TP_PVCCIN_CPU0_PH1_GL_0")
		)
		(pad "7" smd custom
			(at 0.016764 1.145032 90)
			(size 0.53975 0.53975)
			(layers "F.Cu" "F.Mask" "F.Paste")
			(net "GND")
			(options
				(clearance outline)
				(anchor circle)
			)
			(primitives
				(gr_poly
					(pts
						(xy -2.7051 1.0795) (xy -2.7051 -0.3683) (xy -0.9271 -0.3683) (xy -0.9271 -1.0795) (xy 2.7051 -1.0795)
						(xy 2.7051 1.0795)
					)
					(width 0)
					(fill yes)
				)
			)
		)
		(pad "10" smd rect
			(at -0.008382 2.874772 90)
			(size 4.3434 0.6096)
			(layers "F.Cu" "F.Mask" "F.Paste")
			(net "VR_PVCCIN_CPU0_PHASE1")
		)
		(pad "25" smd rect
			(at 1.548384 -1.283208 90)
			(size 2.3368 2.0066)
			(layers "F.Cu" "F.Mask" "F.Paste")
			(net "VR_FET_SW_P12V_STBY_PVCCIN_CPU0")
		)
		(pad "30" smd rect
			(at 2.050034 -2.895092 90)
			(size 0.254 0.7112)
			(layers "F.Cu" "F.Mask" "F.Paste")
			(net "VR_FET_SW_P12V_STBY_PVCCIN_CPU0")
		)
		(pad "31" smd rect
			(at 1.599946 -2.895092 90)
			(size 0.254 0.7112)
			(layers "F.Cu" "F.Mask" "F.Paste")
			(net "Net_361")
		)
		(pad "32" smd rect
			(at 1.150112 -2.895092 90)
			(size 0.254 0.7112)
			(layers "F.Cu" "F.Mask" "F.Paste")
			(net "VR_PVCCIN_CPU0_PH1_PHASE")
		)
		(pad "33" smd rect
			(at 0.700024 -2.895092 90)
			(size 0.254 0.7112)
			(layers "F.Cu" "F.Mask" "F.Paste")
			(net "VR_PVCCIN_CPU0_PH1_BOOT_R")
		)
		(pad "34" smd rect
			(at 0.249936 -2.895092 90)
			(size 0.254 0.7112)
			(layers "F.Cu" "F.Mask" "F.Paste")
			(net "VR_PVCCIN_CPU0_PWM1")
		)
		(pad "35" smd rect
			(at -0.199898 -2.895092 90)
			(size 0.254 0.7112)
			(layers "F.Cu" "F.Mask" "F.Paste")
			(net "P5V_STBY")
		)
		(pad "36" smd rect
			(at -0.649986 -2.895092 90)
			(size 0.254 0.7112)
			(layers "F.Cu" "F.Mask" "F.Paste")
			(net "A_TSENSE_PVCCIN_CPU0")
		)
		(pad "37" smd rect
			(at -1.100074 -2.895092 90)
			(size 0.254 0.7112)
			(layers "F.Cu" "F.Mask" "F.Paste")
			(net "VR_PVCCIN_CPU0_PH1_OCSET")
		)
		(pad "38" smd rect
			(at -1.549908 -2.895092 90)
			(size 0.254 0.7112)
			(layers "F.Cu" "F.Mask" "F.Paste")
			(net "ISENSE_PVCCIN_CPU0_PH1_IMON")
		)
		(pad "39" smd rect
			(at -1.999996 -2.895092 90)
			(size 0.254 0.7112)
			(layers "F.Cu" "F.Mask" "F.Paste")
			(net "VR_PVCCIN_CPU0_AIREF1")
		)
		(pad "40" smd rect
			(at -0.871728 -1.283208 90)
			(size 1.8034 2.0066)
			(layers "F.Cu" "F.Mask" "F.Paste")
			(net "GND")
		)
		(pad "41" smd rect
			(at -1.533906 0.247904 90)
			(size 0.508 0.3556)
			(layers "F.Cu" "F.Mask" "F.Paste")
			(net "TP_PVCCIN_CPU0_PH1_GL_1")
		)
	)
	(footprint ""
		(layer "F.Cu")
		(at 2.032 -69.088 180)
		(property "Reference" "R1E10"
			(at 0 0 180)
			(layer "F.SilkS")
			(hide yes)
			(effects
				(font
					(size 1.27 1.27)
				)
			)
		)
		(property "Value" ""
			(at 0 0 180)
			(layer "F.Fab")
			(effects
				(font
					(size 1.27 1.27)
				)
			)
		)
		(duplicate_pad_numbers_are_jumpers no)
		(fp_poly
			(pts
				(xy -0.2794 -0.1016) (xy 0.2794 -0.1016) (xy 0.2794 0.9906) (xy -0.2794 0.9906)
			)
			(stroke
				(width 0)
				(type default)
			)
			(fill no)
			(layer "F.CrtYd")
		)
		(fp_line
			(start 0.2794 0.9906)
			(end 0.2794 -0.1016)
			(stroke
				(width 0.1)
				(type default)
			)
			(layer "F.Fab")
		)
		(fp_line
			(start 0.2794 -0.1016)
			(end -0.2794 -0.1016)
			(stroke
				(width 0.1)
				(type default)
			)
			(layer "F.Fab")
		)
		(fp_line
			(start -0.2794 0.9906)
			(end 0.2794 0.9906)
			(stroke
				(width 0.1)
				(type default)
			)
			(layer "F.Fab")
		)
		(fp_line
			(start -0.2794 -0.1016)
			(end -0.2794 0.9906)
			(stroke
				(width 0.1)
				(type default)
			)
			(layer "F.Fab")
		)
		(pad "1" smd rect
			(at 0 0 180)
			(size 0.508 0.508)
			(layers "F.Cu" "F.Mask" "F.Paste")
			(net "P3V3_STBY")
		)
		(pad "2" smd rect
			(at 0 0.889 180)
			(size 0.508 0.508)
			(layers "F.Cu" "F.Mask" "F.Paste")
			(net "PD_TMP421_2_A1")
		)
		(zone
			(layer "F.Cu")
			(hatch none 0.5)
			(connect_pads
				(clearance 0)
			)
			(min_thickness 0.25)
			(keepout
				(tracks not_allowed)
				(vias allowed)
				(pads allowed)
				(copperpour not_allowed)
				(footprints allowed)
			)
			(placement
				(enabled no)
				(sheetname "")
			)
			(fill
				(thermal_gap 0.5)
				(thermal_bridge_width 0.5)
				(island_removal_mode 0)
			)
			(polygon
				(pts
					(xy 2.286 -69.723) (xy 1.778 -69.723) (xy 1.778 -69.342) (xy 2.286 -69.342)
				)
			)
		)
		(zone
			(layer "F.Cu")
			(hatch none 0.5)
			(connect_pads
				(clearance 0)
			)
			(min_thickness 0.25)
			(keepout
				(tracks allowed)
				(vias not_allowed)
				(pads allowed)
				(copperpour not_allowed)
				(footprints allowed)
			)
			(placement
				(enabled no)
				(sheetname "")
			)
			(fill
				(thermal_gap 0.5)
				(thermal_bridge_width 0.5)
				(island_removal_mode 0)
			)
			(polygon
				(pts
					(xy 2.286 -69.342) (xy 1.778 -69.342) (xy 1.778 -69.723) (xy 2.286 -69.723)
				)
			)
		)
	)
	(footprint ""
		(layer "F.Cu")
		(at 28.829 -66.929 90)
		(property "Reference" "C1D36"
			(at 0 0 90)
			(layer "F.SilkS")
			(hide yes)
			(effects
				(font
					(size 1.27 1.27)
				)
			)
		)
		(property "Value" ""
			(at 0 0 90)
			(layer "F.Fab")
			(effects
				(font
					(size 1.27 1.27)
				)
			)
		)
		(duplicate_pad_numbers_are_jumpers no)
		(fp_rect
			(start -0.3048 0.9906)
			(end 0.3048 -0.1016)
			(stroke
				(width 0)
				(type default)
			)
			(fill no)
			(layer "F.CrtYd")
		)
		(fp_line
			(start 0.3048 -0.1016)
			(end -0.3048 -0.1016)
			(stroke
				(width 0.1)
				(type default)
			)
			(layer "F.Fab")
		)
		(fp_line
			(start -0.3048 -0.1016)
			(end -0.3048 0.9906)
			(stroke
				(width 0.1)
				(type default)
			)
			(layer "F.Fab")
		)
		(fp_line
			(start 0.3048 0.9906)
			(end 0.3048 -0.1016)
			(stroke
				(width 0.1)
				(type default)
			)
			(layer "F.Fab")
		)
		(fp_line
			(start -0.3048 0.9906)
			(end 0.3048 0.9906)
			(stroke
				(width 0.1)
				(type default)
			)
			(layer "F.Fab")
		)
		(pad "1" smd rect
			(at 0 0 90)
			(size 0.508 0.508)
			(layers "F.Cu" "F.Mask" "F.Paste")
			(net "VR_PVCCIN_CPU1_PH2_BOOT")
		)
		(pad "2" smd rect
			(at 0 0.889 90)
			(size 0.508 0.508)
			(layers "F.Cu" "F.Mask" "F.Paste")
			(net "VR_PVCCIN_CPU1_PH2_PHASE")
		)
		(zone
			(layer "F.Cu")
			(hatch none 0.5)
			(connect_pads
				(clearance 0)
			)
			(min_thickness 0.25)
			(keepout
				(tracks allowed)
				(vias not_allowed)
				(pads allowed)
				(copperpour not_allowed)
				(footprints allowed)
			)
			(placement
				(enabled no)
				(sheetname "")
			)
			(fill
				(thermal_gap 0.5)
				(thermal_bridge_width 0.5)
				(island_removal_mode 0)
			)
			(polygon
				(pts
					(xy 29.464 -66.675) (xy 29.464 -67.183) (xy 29.083 -67.183) (xy 29.083 -66.675)
				)
			)
		)
		(zone
			(layer "F.Cu")
			(hatch none 0.5)
			(connect_pads
				(clearance 0)
			)
			(min_thickness 0.25)
			(keepout
				(tracks not_allowed)
				(vias allowed)
				(pads allowed)
				(copperpour not_allowed)
				(footprints allowed)
			)
			(placement
				(enabled no)
				(sheetname "")
			)
			(fill
				(thermal_gap 0.5)
				(thermal_bridge_width 0.5)
				(island_removal_mode 0)
			)
			(polygon
				(pts
					(xy 29.464 -66.675) (xy 29.464 -67.183) (xy 29.083 -67.183) (xy 29.083 -66.675)
				)
			)
		)
	)
	(footprint ""
		(layer "F.Cu")
		(at 20.701 -32.258)
		(property "Reference" "CR1F3"
			(at -3.429 -1.24333 0)
			(unlocked yes)
			(layer "F.SilkS")
			(effects
				(font
					(size 0.7874 0.5842)
					(thickness 0.1524)
				)
				(justify left)
			)
		)
		(property "Value" ""
			(at 0 0 0)
			(layer "F.Fab")
			(effects
				(font
					(size 1.27 1.27)
				)
			)
		)
		(duplicate_pad_numbers_are_jumpers no)
		(fp_line
			(start -1.8161 1.664462)
			(end -1.335278 0.831596)
			(stroke
				(width 0.1524)
				(type default)
			)
			(layer "F.SilkS")
		)
		(fp_line
			(start -1.335278 -0.291846)
			(end -1.335278 0.831596)
			(stroke
				(width 0.1524)
				(type default)
			)
			(layer "F.SilkS")
		)
		(fp_line
			(start -1.335278 0.831596)
			(end -0.854456 1.664462)
			(stroke
				(width 0.1524)
				(type default)
			)
			(layer "F.SilkS")
		)
		(fp_line
			(start -1.335278 1.664462)
			(end -1.8161 1.664462)
			(stroke
				(width 0.1524)
				(type default)
			)
			(layer "F.SilkS")
		)
		(fp_line
			(start -1.335278 2.576068)
			(end -1.335278 1.664462)
			(stroke
				(width 0.1524)
				(type default)
			)
			(layer "F.SilkS")
		)
		(fp_line
			(start -0.854456 0.831596)
			(end -1.8161 0.831596)
			(stroke
				(width 0.1524)
				(type default)
			)
			(layer "F.SilkS")
		)
		(fp_line
			(start -0.854456 1.664462)
			(end -1.335278 1.664462)
			(stroke
				(width 0.1524)
				(type default)
			)
			(layer "F.SilkS")
		)
		(fp_rect
			(start -0.67437 2.04216)
			(end 0.67437 0.24384)
			(stroke
				(width 0)
				(type default)
			)
			(fill no)
			(layer "F.CrtYd")
		)
		(fp_line
			(start -1.8161 1.664462)
			(end -1.335278 0.831596)
			(stroke
				(width 0.1)
				(type default)
			)
			(layer "F.Fab")
		)
		(fp_line
			(start -1.335278 0.831596)
			(end -1.335278 -0.291846)
			(stroke
				(width 0.1)
				(type default)
			)
			(layer "F.Fab")
		)
		(fp_line
			(start -1.335278 0.831596)
			(end -0.854456 1.664462)
			(stroke
				(width 0.1)
				(type default)
			)
			(layer "F.Fab")
		)
		(fp_line
			(start -1.335278 1.664462)
			(end -1.335278 2.576068)
			(stroke
				(width 0.1)
				(type default)
			)
			(layer "F.Fab")
		)
		(fp_line
			(start -0.854456 0.831596)
			(end -1.8161 0.831596)
			(stroke
				(width 0.1)
				(type default)
			)
			(layer "F.Fab")
		)
		(fp_line
			(start -0.854456 1.664462)
			(end -1.8161 1.664462)
			(stroke
				(width 0.1)
				(type default)
			)
			(layer "F.Fab")
		)
		(fp_line
			(start -0.67437 0.24384)
			(end -0.67437 2.04216)
			(stroke
				(width 0.1)
				(type default)
			)
			(layer "F.Fab")
		)
		(fp_line
			(start -0.67437 2.04216)
			(end 0.67437 2.04216)
			(stroke
				(width 0.1)
				(type default)
			)
			(layer "F.Fab")
		)
		(fp_line
			(start 0.67437 0.24384)
			(end -0.67437 0.24384)
			(stroke
				(width 0.1)
				(type default)
			)
			(layer "F.Fab")
		)
		(fp_line
			(start 0.67437 2.04216)
			(end 0.67437 0.24384)
			(stroke
				(width 0.1)
				(type default)
			)
			(layer "F.Fab")
		)
		(pad "1" smd rect
			(at 0 0)
			(size 0.4064 1.016)
			(layers "F.Cu" "F.Mask" "F.Paste")
			(net "FM_MATED_IN_D2_N")
		)
		(pad "2" smd rect
			(at 0 2.286)
			(size 0.4064 1.016)
			(layers "F.Cu" "F.Mask" "F.Paste")
			(net "FM_MATED_IN_D1_N")
		)
	)
	(footprint ""
		(layer "F.Cu")
		(at 324.5485 -123.825 90)
		(property "Reference" "C6B6"
			(at -0.8382 -0.67818 90)
			(unlocked yes)
			(layer "F.SilkS")
			(effects
				(font
					(size 0.4064 0.254)
					(thickness 0.1524)
				)
				(justify left)
			)
		)
		(property "Value" ""
			(at 0 0 90)
			(layer "F.Fab")
			(effects
				(font
					(size 1.27 1.27)
				)
			)
		)
		(duplicate_pad_numbers_are_jumpers no)
		(fp_poly
			(pts
				(xy 0.3048 -0.1016) (xy 0.3048 0.9906) (xy -0.3048 0.9906) (xy -0.3048 -0.1016)
			)
			(stroke
				(width 0)
				(type default)
			)
			(fill no)
			(layer "F.CrtYd")
		)
		(fp_line
			(start 0.3048 -0.1016)
			(end -0.3048 -0.1016)
			(stroke
				(width 0.1)
				(type default)
			)
			(layer "F.Fab")
		)
		(fp_line
			(start -0.3048 -0.1016)
			(end -0.3048 0.9906)
			(stroke
				(width 0.1)
				(type default)
			)
			(layer "F.Fab")
		)
		(fp_line
			(start 0.3048 0.9906)
			(end 0.3048 -0.1016)
			(stroke
				(width 0.1)
				(type default)
			)
			(layer "F.Fab")
		)
		(fp_line
			(start -0.3048 0.9906)
			(end 0.3048 0.9906)
			(stroke
				(width 0.1)
				(type default)
			)
			(layer "F.Fab")
		)
		(pad "1" smd rect
			(at 0 0 90)
			(size 0.508 0.508)
			(layers "F.Cu" "F.Mask" "F.Paste")
			(net "P3E_CPU0_PE1_PCH_TXN<14>")
		)
		(pad "2" smd rect
			(at 0 0.889 90)
			(size 0.508 0.508)
			(layers "F.Cu" "F.Mask" "F.Paste")
			(net "P3E_CPU0_PE1_PCH_C_TXN<14>")
		)
		(zone
			(layer "F.Cu")
			(hatch none 0.5)
			(connect_pads
				(clearance 0)
			)
			(min_thickness 0.25)
			(keepout
				(tracks allowed)
				(vias not_allowed)
				(pads allowed)
				(copperpour not_allowed)
				(footprints allowed)
			)
			(placement
				(enabled no)
				(sheetname "")
			)
			(fill
				(thermal_gap 0.5)
				(thermal_bridge_width 0.5)
				(island_removal_mode 0)
			)
			(polygon
				(pts
					(xy 324.8025 -123.571) (xy 324.8025 -124.079) (xy 325.1835 -124.079) (xy 325.1835 -123.571)
				)
			)
		)
		(zone
			(layer "F.Cu")
			(hatch none 0.5)
			(connect_pads
				(clearance 0)
			)
			(min_thickness 0.25)
			(keepout
				(tracks not_allowed)
				(vias allowed)
				(pads allowed)
				(copperpour not_allowed)
				(footprints allowed)
			)
			(placement
				(enabled no)
				(sheetname "")
			)
			(fill
				(thermal_gap 0.5)
				(thermal_bridge_width 0.5)
				(island_removal_mode 0)
			)
			(polygon
				(pts
					(xy 325.1835 -123.571) (xy 325.1835 -124.079) (xy 324.8025 -124.079) (xy 324.8025 -123.571)
				)
			)
		)
	)
	(footprint ""
		(layer "F.Cu")
		(at 491.423706 -151.39416 -90)
		(property "Reference" "R6W19"
			(at -0.8382 -0.67818 270)
			(unlocked yes)
			(layer "F.SilkS")
			(effects
				(font
					(size 0.4064 0.254)
					(thickness 0.1524)
				)
				(justify left)
			)
		)
		(property "Value" ""
			(at 0 0 270)
			(layer "F.Fab")
			(effects
				(font
					(size 1.27 1.27)
				)
			)
		)
		(duplicate_pad_numbers_are_jumpers no)
		(fp_poly
			(pts
				(xy -0.2794 -0.1016) (xy 0.2794 -0.1016) (xy 0.2794 0.9906) (xy -0.2794 0.9906)
			)
			(stroke
				(width 0)
				(type default)
			)
			(fill no)
			(layer "F.CrtYd")
		)
		(fp_line
			(start -0.2794 0.9906)
			(end 0.2794 0.9906)
			(stroke
				(width 0.1)
				(type default)
			)
			(layer "F.Fab")
		)
		(fp_line
			(start 0.2794 0.9906)
			(end 0.2794 -0.1016)
			(stroke
				(width 0.1)
				(type default)
			)
			(layer "F.Fab")
		)
		(fp_line
			(start -0.2794 -0.1016)
			(end -0.2794 0.9906)
			(stroke
				(width 0.1)
				(type default)
			)
			(layer "F.Fab")
		)
		(fp_line
			(start 0.2794 -0.1016)
			(end -0.2794 -0.1016)
			(stroke
				(width 0.1)
				(type default)
			)
			(layer "F.Fab")
		)
		(pad "1" smd rect
			(at 0 0 270)
			(size 0.508 0.508)
			(layers "F.Cu" "F.Mask" "F.Paste")
			(net "SPA_5V_SIN_SW_D")
		)
		(pad "2" smd rect
			(at 0 0.889 270)
			(size 0.508 0.508)
			(layers "F.Cu" "F.Mask" "F.Paste")
			(net "SPA_SIN_SW_R")
		)
		(zone
			(layer "F.Cu")
			(hatch none 0.5)
			(connect_pads
				(clearance 0)
			)
			(min_thickness 0.25)
			(keepout
				(tracks not_allowed)
				(vias allowed)
				(pads allowed)
				(copperpour not_allowed)
				(footprints allowed)
			)
			(placement
				(enabled no)
				(sheetname "")
			)
			(fill
				(thermal_gap 0.5)
				(thermal_bridge_width 0.5)
				(island_removal_mode 0)
			)
			(polygon
				(pts
					(xy 490.788706 -151.64816) (xy 490.788706 -151.14016) (xy 491.169706 -151.14016) (xy 491.169706 -151.64816)
				)
			)
		)
		(zone
			(layer "F.Cu")
			(hatch none 0.5)
			(connect_pads
				(clearance 0)
			)
			(min_thickness 0.25)
			(keepout
				(tracks allowed)
				(vias not_allowed)
				(pads allowed)
				(copperpour not_allowed)
				(footprints allowed)
			)
			(placement
				(enabled no)
				(sheetname "")
			)
			(fill
				(thermal_gap 0.5)
				(thermal_bridge_width 0.5)
				(island_removal_mode 0)
			)
			(polygon
				(pts
					(xy 491.169706 -151.64816) (xy 491.169706 -151.14016) (xy 490.788706 -151.14016) (xy 490.788706 -151.64816)
				)
			)
		)
	)
	(footprint ""
		(layer "F.Cu")
		(at 407.8605 -108.966 90)
		(property "Reference" "R8C11"
			(at 0 0 90)
			(layer "F.SilkS")
			(hide yes)
			(effects
				(font
					(size 1.27 1.27)
				)
			)
		)
		(property "Value" ""
			(at 0 0 90)
			(layer "F.Fab")
			(effects
				(font
					(size 1.27 1.27)
				)
			)
		)
		(duplicate_pad_numbers_are_jumpers no)
		(fp_poly
			(pts
				(xy -0.2794 -0.1016) (xy 0.2794 -0.1016) (xy 0.2794 0.9906) (xy -0.2794 0.9906)
			)
			(stroke
				(width 0)
				(type default)
			)
			(fill no)
			(layer "F.CrtYd")
		)
		(fp_line
			(start 0.2794 -0.1016)
			(end -0.2794 -0.1016)
			(stroke
				(width 0.1)
				(type default)
			)
			(layer "F.Fab")
		)
		(fp_line
			(start -0.2794 -0.1016)
			(end -0.2794 0.9906)
			(stroke
				(width 0.1)
				(type default)
			)
			(layer "F.Fab")
		)
		(fp_line
			(start 0.2794 0.9906)
			(end 0.2794 -0.1016)
			(stroke
				(width 0.1)
				(type default)
			)
			(layer "F.Fab")
		)
		(fp_line
			(start -0.2794 0.9906)
			(end 0.2794 0.9906)
			(stroke
				(width 0.1)
				(type default)
			)
			(layer "F.Fab")
		)
		(pad "1" smd rect
			(at 0 0 90)
			(size 0.508 0.508)
			(layers "F.Cu" "F.Mask" "F.Paste")
			(net "SMB_SMLINK0_STBY_LVC3_SDA_R1")
		)
		(pad "2" smd rect
			(at 0 0.889 90)
			(size 0.508 0.508)
			(layers "F.Cu" "F.Mask" "F.Paste")
			(net "SMB_SMLINK0_STBY_LVC3_SDA")
		)
		(zone
			(layer "F.Cu")
			(hatch none 0.5)
			(connect_pads
				(clearance 0)
			)
			(min_thickness 0.25)
			(keepout
				(tracks allowed)
				(vias not_allowed)
				(pads allowed)
				(copperpour not_allowed)
				(footprints allowed)
			)
			(placement
				(enabled no)
				(sheetname "")
			)
			(fill
				(thermal_gap 0.5)
				(thermal_bridge_width 0.5)
				(island_removal_mode 0)
			)
			(polygon
				(pts
					(xy 408.1145 -108.712) (xy 408.1145 -109.22) (xy 408.4955 -109.22) (xy 408.4955 -108.712)
				)
			)
		)
		(zone
			(layer "F.Cu")
			(hatch none 0.5)
			(connect_pads
				(clearance 0)
			)
			(min_thickness 0.25)
			(keepout
				(tracks not_allowed)
				(vias allowed)
				(pads allowed)
				(copperpour not_allowed)
				(footprints allowed)
			)
			(placement
				(enabled no)
				(sheetname "")
			)
			(fill
				(thermal_gap 0.5)
				(thermal_bridge_width 0.5)
				(island_removal_mode 0)
			)
			(polygon
				(pts
					(xy 408.4955 -108.712) (xy 408.4955 -109.22) (xy 408.1145 -109.22) (xy 408.1145 -108.712)
				)
			)
		)
	)
	(footprint ""
		(layer "F.Cu")
		(at -4.3688 -131.2672)
		(property "Reference" "R1B13"
			(at -0.8382 -0.67818 0)
			(unlocked yes)
			(layer "F.SilkS")
			(effects
				(font
					(size 0.4064 0.254)
					(thickness 0.1524)
				)
				(justify left)
			)
		)
		(property "Value" ""
			(at 0 0 0)
			(layer "F.Fab")
			(effects
				(font
					(size 1.27 1.27)
				)
			)
		)
		(duplicate_pad_numbers_are_jumpers no)
		(fp_poly
			(pts
				(xy -0.2794 -0.1016) (xy 0.2794 -0.1016) (xy 0.2794 0.9906) (xy -0.2794 0.9906)
			)
			(stroke
				(width 0)
				(type default)
			)
			(fill no)
			(layer "F.CrtYd")
		)
		(fp_line
			(start -0.2794 -0.1016)
			(end -0.2794 0.9906)
			(stroke
				(width 0.1)
				(type default)
			)
			(layer "F.Fab")
		)
		(fp_line
			(start -0.2794 0.9906)
			(end 0.2794 0.9906)
			(stroke
				(width 0.1)
				(type default)
			)
			(layer "F.Fab")
		)
		(fp_line
			(start 0.2794 -0.1016)
			(end -0.2794 -0.1016)
			(stroke
				(width 0.1)
				(type default)
			)
			(layer "F.Fab")
		)
		(fp_line
			(start 0.2794 0.9906)
			(end 0.2794 -0.1016)
			(stroke
				(width 0.1)
				(type default)
			)
			(layer "F.Fab")
		)
		(pad "1" smd rect
			(at 0 0)
			(size 0.508 0.508)
			(layers "F.Cu" "F.Mask" "F.Paste")
			(net "P3V3_STBY")
		)
		(pad "2" smd rect
			(at 0 0.889)
			(size 0.508 0.508)
			(layers "F.Cu" "F.Mask" "F.Paste")
			(net "PWRGD_PVDDQ_KLM")
		)
		(zone
			(layer "F.Cu")
			(hatch none 0.5)
			(connect_pads
				(clearance 0)
			)
			(min_thickness 0.25)
			(keepout
				(tracks allowed)
				(vias not_allowed)
				(pads allowed)
				(copperpour not_allowed)
				(footprints allowed)
			)
			(placement
				(enabled no)
				(sheetname "")
			)
			(fill
				(thermal_gap 0.5)
				(thermal_bridge_width 0.5)
				(island_removal_mode 0)
			)
			(polygon
				(pts
					(xy -4.6228 -131.0132) (xy -4.1148 -131.0132) (xy -4.1148 -130.6322) (xy -4.6228 -130.6322)
				)
			)
		)
		(zone
			(layer "F.Cu")
			(hatch none 0.5)
			(connect_pads
				(clearance 0)
			)
			(min_thickness 0.25)
			(keepout
				(tracks not_allowed)
				(vias allowed)
				(pads allowed)
				(copperpour not_allowed)
				(footprints allowed)
			)
			(placement
				(enabled no)
				(sheetname "")
			)
			(fill
				(thermal_gap 0.5)
				(thermal_bridge_width 0.5)
				(island_removal_mode 0)
			)
			(polygon
				(pts
					(xy -4.6228 -130.6322) (xy -4.1148 -130.6322) (xy -4.1148 -131.0132) (xy -4.6228 -131.0132)
				)
			)
		)
	)
	(footprint ""
		(layer "F.Cu")
		(at 4.2164 -5.675376 90)
		(property "Reference" "C1G5"
			(at 0 0 90)
			(layer "F.SilkS")
			(hide yes)
			(effects
				(font
					(size 1.27 1.27)
				)
			)
		)
		(property "Value" ""
			(at 0 0 90)
			(layer "F.Fab")
			(effects
				(font
					(size 1.27 1.27)
				)
			)
		)
		(duplicate_pad_numbers_are_jumpers no)
		(fp_rect
			(start 0.3048 0.9906)
			(end -0.3048 -0.1016)
			(stroke
				(width 0)
				(type default)
			)
			(fill no)
			(layer "F.CrtYd")
		)
		(fp_line
			(start 0.3048 -0.1016)
			(end -0.3048 -0.1016)
			(stroke
				(width 0.1)
				(type default)
			)
			(layer "F.Fab")
		)
		(fp_line
			(start -0.3048 -0.1016)
			(end -0.3048 0.9906)
			(stroke
				(width 0.1)
				(type default)
			)
			(layer "F.Fab")
		)
		(fp_line
			(start 0.3048 0.9906)
			(end 0.3048 -0.1016)
			(stroke
				(width 0.1)
				(type default)
			)
			(layer "F.Fab")
		)
		(fp_line
			(start -0.3048 0.9906)
			(end 0.3048 0.9906)
			(stroke
				(width 0.1)
				(type default)
			)
			(layer "F.Fab")
		)
		(pad "1" smd rect
			(at 0 0 90)
			(size 0.508 0.508)
			(layers "F.Cu" "F.Mask" "F.Paste")
			(net "P5V_STBY")
		)
		(pad "2" smd rect
			(at 0 0.889 90)
			(size 0.508 0.508)
			(layers "F.Cu" "F.Mask" "F.Paste")
			(net "GND")
		)
		(zone
			(layer "F.Cu")
			(hatch none 0.5)
			(connect_pads
				(clearance 0)
			)
			(min_thickness 0.25)
			(keepout
				(tracks not_allowed)
				(vias allowed)
				(pads allowed)
				(copperpour not_allowed)
				(footprints allowed)
			)
			(placement
				(enabled no)
				(sheetname "")
			)
			(fill
				(thermal_gap 0.5)
				(thermal_bridge_width 0.5)
				(island_removal_mode 0)
			)
			(polygon
				(pts
					(xy 4.8514 -5.929376) (xy 4.4704 -5.929376) (xy 4.4704 -5.421376) (xy 4.8514 -5.421376)
				)
			)
		)
		(zone
			(layer "F.Cu")
			(hatch none 0.5)
			(connect_pads
				(clearance 0)
			)
			(min_thickness 0.25)
			(keepout
				(tracks allowed)
				(vias not_allowed)
				(pads allowed)
				(copperpour not_allowed)
				(footprints allowed)
			)
			(placement
				(enabled no)
				(sheetname "")
			)
			(fill
				(thermal_gap 0.5)
				(thermal_bridge_width 0.5)
				(island_removal_mode 0)
			)
			(polygon
				(pts
					(xy 4.8514 -5.929376) (xy 4.4704 -5.929376) (xy 4.4704 -5.421376) (xy 4.8514 -5.421376)
				)
			)
		)
	)
	(footprint ""
		(layer "F.Cu")
		(at 452.12 -153.543 -90)
		(property "Reference" "R9A1"
			(at 0 0 270)
			(layer "F.SilkS")
			(hide yes)
			(effects
				(font
					(size 1.27 1.27)
				)
			)
		)
		(property "Value" ""
			(at 0 0 270)
			(layer "F.Fab")
			(effects
				(font
					(size 1.27 1.27)
				)
			)
		)
		(duplicate_pad_numbers_are_jumpers no)
		(fp_poly
			(pts
				(xy -0.2794 -0.1016) (xy 0.2794 -0.1016) (xy 0.2794 0.9906) (xy -0.2794 0.9906)
			)
			(stroke
				(width 0)
				(type default)
			)
			(fill no)
			(layer "F.CrtYd")
		)
		(fp_line
			(start -0.2794 0.9906)
			(end 0.2794 0.9906)
			(stroke
				(width 0.1)
				(type default)
			)
			(layer "F.Fab")
		)
		(fp_line
			(start 0.2794 0.9906)
			(end 0.2794 -0.1016)
			(stroke
				(width 0.1)
				(type default)
			)
			(layer "F.Fab")
		)
		(fp_line
			(start -0.2794 -0.1016)
			(end -0.2794 0.9906)
			(stroke
				(width 0.1)
				(type default)
			)
			(layer "F.Fab")
		)
		(fp_line
			(start 0.2794 -0.1016)
			(end -0.2794 -0.1016)
			(stroke
				(width 0.1)
				(type default)
			)
			(layer "F.Fab")
		)
		(pad "1" smd rect
			(at 0 0 270)
			(size 0.508 0.508)
			(layers "F.Cu" "F.Mask" "F.Paste")
			(net "P3V3")
		)
		(pad "2" smd rect
			(at 0 0.889 270)
			(size 0.508 0.508)
			(layers "F.Cu" "F.Mask" "F.Paste")
			(net "XDP_CPU_TCK_BUF")
		)
		(zone
			(layer "F.Cu")
			(hatch none 0.5)
			(connect_pads
				(clearance 0)
			)
			(min_thickness 0.25)
			(keepout
				(tracks not_allowed)
				(vias allowed)
				(pads allowed)
				(copperpour not_allowed)
				(footprints allowed)
			)
			(placement
				(enabled no)
				(sheetname "")
			)
			(fill
				(thermal_gap 0.5)
				(thermal_bridge_width 0.5)
				(island_removal_mode 0)
			)
			(polygon
				(pts
					(xy 451.485 -153.797) (xy 451.485 -153.289) (xy 451.866 -153.289) (xy 451.866 -153.797)
				)
			)
		)
		(zone
			(layer "F.Cu")
			(hatch none 0.5)
			(connect_pads
				(clearance 0)
			)
			(min_thickness 0.25)
			(keepout
				(tracks allowed)
				(vias not_allowed)
				(pads allowed)
				(copperpour not_allowed)
				(footprints allowed)
			)
			(placement
				(enabled no)
				(sheetname "")
			)
			(fill
				(thermal_gap 0.5)
				(thermal_bridge_width 0.5)
				(island_removal_mode 0)
			)
			(polygon
				(pts
					(xy 451.866 -153.797) (xy 451.866 -153.289) (xy 451.485 -153.289) (xy 451.485 -153.797)
				)
			)
		)
	)
	(footprint ""
		(layer "F.Cu")
		(at 257.8608 -149.733 -90)
		(property "Reference" "C5A5"
			(at 0 0 270)
			(layer "F.SilkS")
			(hide yes)
			(effects
				(font
					(size 1.27 1.27)
				)
			)
		)
		(property "Value" ""
			(at 0 0 270)
			(layer "F.Fab")
			(effects
				(font
					(size 1.27 1.27)
				)
			)
		)
		(duplicate_pad_numbers_are_jumpers no)
		(fp_rect
			(start -0.500126 1.598422)
			(end 0.500126 -0.201422)
			(stroke
				(width 0)
				(type default)
			)
			(fill no)
			(layer "F.CrtYd")
		)
		(fp_line
			(start -0.500126 1.598422)
			(end -0.500126 -0.201422)
			(stroke
				(width 0.1)
				(type default)
			)
			(layer "F.Fab")
		)
		(fp_line
			(start 0.500126 1.598422)
			(end -0.500126 1.598422)
			(stroke
				(width 0.1)
				(type default)
			)
			(layer "F.Fab")
		)
		(fp_line
			(start -0.500126 -0.201422)
			(end 0.500126 -0.201422)
			(stroke
				(width 0.1)
				(type default)
			)
			(layer "F.Fab")
		)
		(fp_line
			(start 0.500126 -0.201422)
			(end 0.500126 1.598422)
			(stroke
				(width 0.1)
				(type default)
			)
			(layer "F.Fab")
		)
		(pad "1" smd rect
			(at 0 0 180)
			(size 0.889 0.9906)
			(layers "F.Cu" "F.Mask" "F.Paste")
			(net "PVDDQ_DEF")
		)
		(pad "2" smd rect
			(at 0 1.397 180)
			(size 0.889 0.9906)
			(layers "F.Cu" "F.Mask" "F.Paste")
			(net "GND")
		)
		(zone
			(layer "F.Cu")
			(hatch none 0.5)
			(connect_pads
				(clearance 0)
			)
			(min_thickness 0.25)
			(keepout
				(tracks allowed)
				(vias not_allowed)
				(pads allowed)
				(copperpour not_allowed)
				(footprints allowed)
			)
			(placement
				(enabled no)
				(sheetname "")
			)
			(fill
				(thermal_gap 0.5)
				(thermal_bridge_width 0.5)
				(island_removal_mode 0)
			)
			(polygon
				(pts
					(xy 256.9083 -150.2283) (xy 256.9083 -149.2377) (xy 257.4163 -149.2377) (xy 257.4163 -150.2283)
				)
			)
		)
		(zone
			(layer "F.Cu")
			(hatch none 0.5)
			(connect_pads
				(clearance 0)
			)
			(min_thickness 0.25)
			(keepout
				(tracks not_allowed)
				(vias allowed)
				(pads allowed)
				(copperpour not_allowed)
				(footprints allowed)
			)
			(placement
				(enabled no)
				(sheetname "")
			)
			(fill
				(thermal_gap 0.5)
				(thermal_bridge_width 0.5)
				(island_removal_mode 0)
			)
			(polygon
				(pts
					(xy 256.9083 -150.2283) (xy 256.9083 -149.2377) (xy 257.4163 -149.2377) (xy 257.4163 -150.2283)
				)
			)
		)
	)
	(footprint ""
		(layer "F.Cu")
		(at 400.685 -84.0105 180)
		(property "Reference" "R2P14"
			(at 0 0 180)
			(layer "F.SilkS")
			(hide yes)
			(effects
				(font
					(size 1.27 1.27)
				)
			)
		)
		(property "Value" ""
			(at 0 0 180)
			(layer "F.Fab")
			(effects
				(font
					(size 1.27 1.27)
				)
			)
		)
		(duplicate_pad_numbers_are_jumpers no)
		(fp_poly
			(pts
				(xy -0.2794 -0.1016) (xy 0.2794 -0.1016) (xy 0.2794 0.9906) (xy -0.2794 0.9906)
			)
			(stroke
				(width 0)
				(type default)
			)
			(fill no)
			(layer "F.CrtYd")
		)
		(fp_line
			(start 0.2794 0.9906)
			(end 0.2794 -0.1016)
			(stroke
				(width 0.1)
				(type default)
			)
			(layer "F.Fab")
		)
		(fp_line
			(start 0.2794 -0.1016)
			(end -0.2794 -0.1016)
			(stroke
				(width 0.1)
				(type default)
			)
			(layer "F.Fab")
		)
		(fp_line
			(start -0.2794 0.9906)
			(end 0.2794 0.9906)
			(stroke
				(width 0.1)
				(type default)
			)
			(layer "F.Fab")
		)
		(fp_line
			(start -0.2794 -0.1016)
			(end -0.2794 0.9906)
			(stroke
				(width 0.1)
				(type default)
			)
			(layer "F.Fab")
		)
		(pad "1" smd rect
			(at 0 0 180)
			(size 0.508 0.508)
			(layers "F.Cu" "F.Mask" "F.Paste")
			(net "FM_M2_DET_LVC3")
		)
		(pad "2" smd rect
			(at 0 0.889 180)
			(size 0.508 0.508)
			(layers "F.Cu" "F.Mask" "F.Paste")
			(net "FM_SSATA_PCIE_M2_SEL")
		)
		(zone
			(layer "F.Cu")
			(hatch none 0.5)
			(connect_pads
				(clearance 0)
			)
			(min_thickness 0.25)
			(keepout
				(tracks not_allowed)
				(vias allowed)
				(pads allowed)
				(copperpour not_allowed)
				(footprints allowed)
			)
			(placement
				(enabled no)
				(sheetname "")
			)
			(fill
				(thermal_gap 0.5)
				(thermal_bridge_width 0.5)
				(island_removal_mode 0)
			)
			(polygon
				(pts
					(xy 400.939 -84.6455) (xy 400.431 -84.6455) (xy 400.431 -84.2645) (xy 400.939 -84.2645)
				)
			)
		)
		(zone
			(layer "F.Cu")
			(hatch none 0.5)
			(connect_pads
				(clearance 0)
			)
			(min_thickness 0.25)
			(keepout
				(tracks allowed)
				(vias not_allowed)
				(pads allowed)
				(copperpour not_allowed)
				(footprints allowed)
			)
			(placement
				(enabled no)
				(sheetname "")
			)
			(fill
				(thermal_gap 0.5)
				(thermal_bridge_width 0.5)
				(island_removal_mode 0)
			)
			(polygon
				(pts
					(xy 400.939 -84.2645) (xy 400.431 -84.2645) (xy 400.431 -84.6455) (xy 400.939 -84.6455)
				)
			)
		)
	)
	(footprint ""
		(layer "F.Cu")
		(at 410.817822 -11.436858)
		(property "Reference" "C8G10"
			(at 0 0 0)
			(layer "F.SilkS")
			(hide yes)
			(effects
				(font
					(size 1.27 1.27)
				)
			)
		)
		(property "Value" ""
			(at 0 0 0)
			(layer "F.Fab")
			(effects
				(font
					(size 1.27 1.27)
				)
			)
		)
		(duplicate_pad_numbers_are_jumpers no)
		(fp_rect
			(start -0.3048 0.9906)
			(end 0.3048 -0.1016)
			(stroke
				(width 0)
				(type default)
			)
			(fill no)
			(layer "F.CrtYd")
		)
		(fp_line
			(start -0.3048 -0.1016)
			(end -0.3048 0.9906)
			(stroke
				(width 0.1)
				(type default)
			)
			(layer "F.Fab")
		)
		(fp_line
			(start -0.3048 0.9906)
			(end 0.3048 0.9906)
			(stroke
				(width 0.1)
				(type default)
			)
			(layer "F.Fab")
		)
		(fp_line
			(start 0.3048 -0.1016)
			(end -0.3048 -0.1016)
			(stroke
				(width 0.1)
				(type default)
			)
			(layer "F.Fab")
		)
		(fp_line
			(start 0.3048 0.9906)
			(end 0.3048 -0.1016)
			(stroke
				(width 0.1)
				(type default)
			)
			(layer "F.Fab")
		)
		(pad "1" smd rect
			(at 0 0)
			(size 0.508 0.508)
			(layers "F.Cu" "F.Mask" "F.Paste")
			(net "P3E_CPU0_PE2_SS_TXN<0>")
		)
		(pad "2" smd rect
			(at 0 0.889)
			(size 0.508 0.508)
			(layers "F.Cu" "F.Mask" "F.Paste")
			(net "P3E_CPU0_PE2_SS_C_TXN<0>")
		)
		(zone
			(layer "F.Cu")
			(hatch none 0.5)
			(connect_pads
				(clearance 0)
			)
			(min_thickness 0.25)
			(keepout
				(tracks allowed)
				(vias not_allowed)
				(pads allowed)
				(copperpour not_allowed)
				(footprints allowed)
			)
			(placement
				(enabled no)
				(sheetname "")
			)
			(fill
				(thermal_gap 0.5)
				(thermal_bridge_width 0.5)
				(island_removal_mode 0)
			)
			(polygon
				(pts
					(xy 410.563822 -10.801858) (xy 411.071822 -10.801858) (xy 411.071822 -11.182858) (xy 410.563822 -11.182858)
				)
			)
		)
		(zone
			(layer "F.Cu")
			(hatch none 0.5)
			(connect_pads
				(clearance 0)
			)
			(min_thickness 0.25)
			(keepout
				(tracks not_allowed)
				(vias allowed)
				(pads allowed)
				(copperpour not_allowed)
				(footprints allowed)
			)
			(placement
				(enabled no)
				(sheetname "")
			)
			(fill
				(thermal_gap 0.5)
				(thermal_bridge_width 0.5)
				(island_removal_mode 0)
			)
			(polygon
				(pts
					(xy 410.563822 -10.801858) (xy 411.071822 -10.801858) (xy 411.071822 -11.182858) (xy 410.563822 -11.182858)
				)
			)
		)
	)
	(footprint ""
		(layer "F.Cu")
		(at 491.1471 -48.2854 -90)
		(property "Reference" "R9E6"
			(at 0 0 270)
			(layer "F.SilkS")
			(hide yes)
			(effects
				(font
					(size 1.27 1.27)
				)
			)
		)
		(property "Value" ""
			(at 0 0 270)
			(layer "F.Fab")
			(effects
				(font
					(size 1.27 1.27)
				)
			)
		)
		(duplicate_pad_numbers_are_jumpers no)
		(fp_poly
			(pts
				(xy -0.2794 -0.1016) (xy 0.2794 -0.1016) (xy 0.2794 0.9906) (xy -0.2794 0.9906)
			)
			(stroke
				(width 0)
				(type default)
			)
			(fill no)
			(layer "F.CrtYd")
		)
		(fp_line
			(start -0.2794 0.9906)
			(end 0.2794 0.9906)
			(stroke
				(width 0.1)
				(type default)
			)
			(layer "F.Fab")
		)
		(fp_line
			(start 0.2794 0.9906)
			(end 0.2794 -0.1016)
			(stroke
				(width 0.1)
				(type default)
			)
			(layer "F.Fab")
		)
		(fp_line
			(start -0.2794 -0.1016)
			(end -0.2794 0.9906)
			(stroke
				(width 0.1)
				(type default)
			)
			(layer "F.Fab")
		)
		(fp_line
			(start 0.2794 -0.1016)
			(end -0.2794 -0.1016)
			(stroke
				(width 0.1)
				(type default)
			)
			(layer "F.Fab")
		)
		(pad "1" smd rect
			(at 0 0 270)
			(size 0.508 0.508)
			(layers "F.Cu" "F.Mask" "F.Paste")
			(net "SPI_NIC_MISO_R")
		)
		(pad "2" smd rect
			(at 0 0.889 270)
			(size 0.508 0.508)
			(layers "F.Cu" "F.Mask" "F.Paste")
			(net "SPI_NIC_MISO")
		)
		(zone
			(layer "F.Cu")
			(hatch none 0.5)
			(connect_pads
				(clearance 0)
			)
			(min_thickness 0.25)
			(keepout
				(tracks not_allowed)
				(vias allowed)
				(pads allowed)
				(copperpour not_allowed)
				(footprints allowed)
			)
			(placement
				(enabled no)
				(sheetname "")
			)
			(fill
				(thermal_gap 0.5)
				(thermal_bridge_width 0.5)
				(island_removal_mode 0)
			)
			(polygon
				(pts
					(xy 490.5121 -48.5394) (xy 490.5121 -48.0314) (xy 490.8931 -48.0314) (xy 490.8931 -48.5394)
				)
			)
		)
		(zone
			(layer "F.Cu")
			(hatch none 0.5)
			(connect_pads
				(clearance 0)
			)
			(min_thickness 0.25)
			(keepout
				(tracks allowed)
				(vias not_allowed)
				(pads allowed)
				(copperpour not_allowed)
				(footprints allowed)
			)
			(placement
				(enabled no)
				(sheetname "")
			)
			(fill
				(thermal_gap 0.5)
				(thermal_bridge_width 0.5)
				(island_removal_mode 0)
			)
			(polygon
				(pts
					(xy 490.8931 -48.5394) (xy 490.8931 -48.0314) (xy 490.5121 -48.0314) (xy 490.5121 -48.5394)
				)
			)
		)
	)
	(footprint ""
		(layer "F.Cu")
		(at -3.22326 -132.86486)
		(property "Reference" "R1B1"
			(at 0 0 0)
			(layer "F.SilkS")
			(hide yes)
			(effects
				(font
					(size 1.27 1.27)
				)
			)
		)
		(property "Value" ""
			(at 0 0 0)
			(layer "F.Fab")
			(effects
				(font
					(size 1.27 1.27)
				)
			)
		)
		(duplicate_pad_numbers_are_jumpers no)
		(fp_poly
			(pts
				(xy -0.2794 -0.1016) (xy 0.2794 -0.1016) (xy 0.2794 0.9906) (xy -0.2794 0.9906)
			)
			(stroke
				(width 0)
				(type default)
			)
			(fill no)
			(layer "F.CrtYd")
		)
		(fp_line
			(start -0.2794 -0.1016)
			(end -0.2794 0.9906)
			(stroke
				(width 0.1)
				(type default)
			)
			(layer "F.Fab")
		)
		(fp_line
			(start -0.2794 0.9906)
			(end 0.2794 0.9906)
			(stroke
				(width 0.1)
				(type default)
			)
			(layer "F.Fab")
		)
		(fp_line
			(start 0.2794 -0.1016)
			(end -0.2794 -0.1016)
			(stroke
				(width 0.1)
				(type default)
			)
			(layer "F.Fab")
		)
		(fp_line
			(start 0.2794 0.9906)
			(end 0.2794 -0.1016)
			(stroke
				(width 0.1)
				(type default)
			)
			(layer "F.Fab")
		)
		(pad "1" smd rect
			(at 0 0)
			(size 0.508 0.508)
			(layers "F.Cu" "F.Mask" "F.Paste")
			(net "P3V3_STBY")
		)
		(pad "2" smd rect
			(at 0 0.889)
			(size 0.508 0.508)
			(layers "F.Cu" "F.Mask" "F.Paste")
			(net "IRQ_PVDDQ_KLM_VRHOT_LVT3_R_N")
		)
		(zone
			(layer "F.Cu")
			(hatch none 0.5)
			(connect_pads
				(clearance 0)
			)
			(min_thickness 0.25)
			(keepout
				(tracks allowed)
				(vias not_allowed)
				(pads allowed)
				(copperpour not_allowed)
				(footprints allowed)
			)
			(placement
				(enabled no)
				(sheetname "")
			)
			(fill
				(thermal_gap 0.5)
				(thermal_bridge_width 0.5)
				(island_removal_mode 0)
			)
			(polygon
				(pts
					(xy -3.47726 -132.61086) (xy -2.96926 -132.61086) (xy -2.96926 -132.22986) (xy -3.47726 -132.22986)
				)
			)
		)
		(zone
			(layer "F.Cu")
			(hatch none 0.5)
			(connect_pads
				(clearance 0)
			)
			(min_thickness 0.25)
			(keepout
				(tracks not_allowed)
				(vias allowed)
				(pads allowed)
				(copperpour not_allowed)
				(footprints allowed)
			)
			(placement
				(enabled no)
				(sheetname "")
			)
			(fill
				(thermal_gap 0.5)
				(thermal_bridge_width 0.5)
				(island_removal_mode 0)
			)
			(polygon
				(pts
					(xy -3.47726 -132.22986) (xy -2.96926 -132.22986) (xy -2.96926 -132.61086) (xy -3.47726 -132.61086)
				)
			)
		)
	)
	(footprint ""
		(layer "F.Cu")
		(at 341.9348 -32.8803 90)
		(property "Reference" "C7F3"
			(at 0 0 90)
			(layer "F.SilkS")
			(hide yes)
			(effects
				(font
					(size 1.27 1.27)
				)
			)
		)
		(property "Value" ""
			(at 0 0 90)
			(layer "F.Fab")
			(effects
				(font
					(size 1.27 1.27)
				)
			)
		)
		(duplicate_pad_numbers_are_jumpers no)
		(fp_rect
			(start -0.3048 -0.1016)
			(end 0.3048 0.9906)
			(stroke
				(width 0)
				(type default)
			)
			(fill no)
			(layer "F.CrtYd")
		)
		(fp_line
			(start 0.3048 -0.1016)
			(end -0.3048 -0.1016)
			(stroke
				(width 0.1)
				(type default)
			)
			(layer "F.Fab")
		)
		(fp_line
			(start -0.3048 -0.1016)
			(end -0.3048 0.9906)
			(stroke
				(width 0.1)
				(type default)
			)
			(layer "F.Fab")
		)
		(fp_line
			(start 0.3048 0.9906)
			(end 0.3048 -0.1016)
			(stroke
				(width 0.1)
				(type default)
			)
			(layer "F.Fab")
		)
		(fp_line
			(start -0.3048 0.9906)
			(end 0.3048 0.9906)
			(stroke
				(width 0.1)
				(type default)
			)
			(layer "F.Fab")
		)
		(pad "1" smd rect
			(at 0 0 90)
			(size 0.508 0.508)
			(layers "F.Cu" "F.Mask" "F.Paste")
			(net "VR_PVPP_ABC_PHASE")
		)
		(pad "2" smd rect
			(at 0 0.889 90)
			(size 0.508 0.508)
			(layers "F.Cu" "F.Mask" "F.Paste")
			(net "VR_PVPP_ABC_SNUB")
		)
		(zone
			(layer "F.Cu")
			(hatch none 0.5)
			(connect_pads
				(clearance 0)
			)
			(min_thickness 0.25)
			(keepout
				(tracks allowed)
				(vias not_allowed)
				(pads allowed)
				(copperpour not_allowed)
				(footprints allowed)
			)
			(placement
				(enabled no)
				(sheetname "")
			)
			(fill
				(thermal_gap 0.5)
				(thermal_bridge_width 0.5)
				(island_removal_mode 0)
			)
			(polygon
				(pts
					(xy 342.1888 -32.6263) (xy 342.5698 -32.6263) (xy 342.5698 -33.1343) (xy 342.1888 -33.1343)
				)
			)
		)
		(zone
			(layer "F.Cu")
			(hatch none 0.5)
			(connect_pads
				(clearance 0)
			)
			(min_thickness 0.25)
			(keepout
				(tracks not_allowed)
				(vias allowed)
				(pads allowed)
				(copperpour not_allowed)
				(footprints allowed)
			)
			(placement
				(enabled no)
				(sheetname "")
			)
			(fill
				(thermal_gap 0.5)
				(thermal_bridge_width 0.5)
				(island_removal_mode 0)
			)
			(polygon
				(pts
					(xy 342.1888 -32.6263) (xy 342.5698 -32.6263) (xy 342.5698 -33.1343) (xy 342.1888 -33.1343)
				)
			)
		)
	)
	(footprint ""
		(layer "F.Cu")
		(at 491.0455 -41.0464 90)
		(property "Reference" "R9E22"
			(at 0 0 90)
			(layer "F.SilkS")
			(hide yes)
			(effects
				(font
					(size 1.27 1.27)
				)
			)
		)
		(property "Value" ""
			(at 0 0 90)
			(layer "F.Fab")
			(effects
				(font
					(size 1.27 1.27)
				)
			)
		)
		(duplicate_pad_numbers_are_jumpers no)
		(fp_poly
			(pts
				(xy -0.2794 -0.1016) (xy 0.2794 -0.1016) (xy 0.2794 0.9906) (xy -0.2794 0.9906)
			)
			(stroke
				(width 0)
				(type default)
			)
			(fill no)
			(layer "F.CrtYd")
		)
		(fp_line
			(start 0.2794 -0.1016)
			(end -0.2794 -0.1016)
			(stroke
				(width 0.1)
				(type default)
			)
			(layer "F.Fab")
		)
		(fp_line
			(start -0.2794 -0.1016)
			(end -0.2794 0.9906)
			(stroke
				(width 0.1)
				(type default)
			)
			(layer "F.Fab")
		)
		(fp_line
			(start 0.2794 0.9906)
			(end 0.2794 -0.1016)
			(stroke
				(width 0.1)
				(type default)
			)
			(layer "F.Fab")
		)
		(fp_line
			(start -0.2794 0.9906)
			(end 0.2794 0.9906)
			(stroke
				(width 0.1)
				(type default)
			)
			(layer "F.Fab")
		)
		(pad "1" smd rect
			(at 0 0 90)
			(size 0.508 0.508)
			(layers "F.Cu" "F.Mask" "F.Paste")
			(net "PU_JTAG_SPRV_TDO")
		)
		(pad "2" smd rect
			(at 0 0.889 90)
			(size 0.508 0.508)
			(layers "F.Cu" "F.Mask" "F.Paste")
			(net "P3V3_STBY")
		)
		(zone
			(layer "F.Cu")
			(hatch none 0.5)
			(connect_pads
				(clearance 0)
			)
			(min_thickness 0.25)
			(keepout
				(tracks allowed)
				(vias not_allowed)
				(pads allowed)
				(copperpour not_allowed)
				(footprints allowed)
			)
			(placement
				(enabled no)
				(sheetname "")
			)
			(fill
				(thermal_gap 0.5)
				(thermal_bridge_width 0.5)
				(island_removal_mode 0)
			)
			(polygon
				(pts
					(xy 491.2995 -40.7924) (xy 491.2995 -41.3004) (xy 491.6805 -41.3004) (xy 491.6805 -40.7924)
				)
			)
		)
		(zone
			(layer "F.Cu")
			(hatch none 0.5)
			(connect_pads
				(clearance 0)
			)
			(min_thickness 0.25)
			(keepout
				(tracks not_allowed)
				(vias allowed)
				(pads allowed)
				(copperpour not_allowed)
				(footprints allowed)
			)
			(placement
				(enabled no)
				(sheetname "")
			)
			(fill
				(thermal_gap 0.5)
				(thermal_bridge_width 0.5)
				(island_removal_mode 0)
			)
			(polygon
				(pts
					(xy 491.6805 -40.7924) (xy 491.6805 -41.3004) (xy 491.2995 -41.3004) (xy 491.2995 -40.7924)
				)
			)
		)
	)
	(footprint ""
		(layer "F.Cu")
		(at 113.1824 -69.4182 90)
		(property "Reference" "R3D25"
			(at 0 0 90)
			(layer "F.SilkS")
			(hide yes)
			(effects
				(font
					(size 1.27 1.27)
				)
			)
		)
		(property "Value" ""
			(at 0 0 90)
			(layer "F.Fab")
			(effects
				(font
					(size 1.27 1.27)
				)
			)
		)
		(duplicate_pad_numbers_are_jumpers no)
		(fp_poly
			(pts
				(xy -0.2794 -0.1016) (xy 0.2794 -0.1016) (xy 0.2794 0.9906) (xy -0.2794 0.9906)
			)
			(stroke
				(width 0)
				(type default)
			)
			(fill no)
			(layer "F.CrtYd")
		)
		(fp_line
			(start 0.2794 -0.1016)
			(end -0.2794 -0.1016)
			(stroke
				(width 0.1)
				(type default)
			)
			(layer "F.Fab")
		)
		(fp_line
			(start -0.2794 -0.1016)
			(end -0.2794 0.9906)
			(stroke
				(width 0.1)
				(type default)
			)
			(layer "F.Fab")
		)
		(fp_line
			(start 0.2794 0.9906)
			(end 0.2794 -0.1016)
			(stroke
				(width 0.1)
				(type default)
			)
			(layer "F.Fab")
		)
		(fp_line
			(start -0.2794 0.9906)
			(end 0.2794 0.9906)
			(stroke
				(width 0.1)
				(type default)
			)
			(layer "F.Fab")
		)
		(pad "1" smd rect
			(at 0 0 90)
			(size 0.508 0.508)
			(layers "F.Cu" "F.Mask" "F.Paste")
			(net "GND")
		)
		(pad "2" smd rect
			(at 0 0.889 90)
			(size 0.508 0.508)
			(layers "F.Cu" "F.Mask" "F.Paste")
			(net "PD_CPU1_EAR_N")
		)
		(zone
			(layer "F.Cu")
			(hatch none 0.5)
			(connect_pads
				(clearance 0)
			)
			(min_thickness 0.25)
			(keepout
				(tracks allowed)
				(vias not_allowed)
				(pads allowed)
				(copperpour not_allowed)
				(footprints allowed)
			)
			(placement
				(enabled no)
				(sheetname "")
			)
			(fill
				(thermal_gap 0.5)
				(thermal_bridge_width 0.5)
				(island_removal_mode 0)
			)
			(polygon
				(pts
					(xy 113.4364 -69.1642) (xy 113.4364 -69.6722) (xy 113.8174 -69.6722) (xy 113.8174 -69.1642)
				)
			)
		)
		(zone
			(layer "F.Cu")
			(hatch none 0.5)
			(connect_pads
				(clearance 0)
			)
			(min_thickness 0.25)
			(keepout
				(tracks not_allowed)
				(vias allowed)
				(pads allowed)
				(copperpour not_allowed)
				(footprints allowed)
			)
			(placement
				(enabled no)
				(sheetname "")
			)
			(fill
				(thermal_gap 0.5)
				(thermal_bridge_width 0.5)
				(island_removal_mode 0)
			)
			(polygon
				(pts
					(xy 113.8174 -69.1642) (xy 113.8174 -69.6722) (xy 113.4364 -69.6722) (xy 113.4364 -69.1642)
				)
			)
		)
	)
	(footprint ""
		(layer "F.Cu")
		(at 39.322756 -107.355132 -90)
		(property "Reference" "R9N1"
			(at 0 0 270)
			(layer "F.SilkS")
			(hide yes)
			(effects
				(font
					(size 1.27 1.27)
				)
			)
		)
		(property "Value" ""
			(at 0 0 270)
			(layer "F.Fab")
			(effects
				(font
					(size 1.27 1.27)
				)
			)
		)
		(duplicate_pad_numbers_are_jumpers no)
		(fp_poly
			(pts
				(xy -0.2794 -0.1016) (xy 0.2794 -0.1016) (xy 0.2794 0.9906) (xy -0.2794 0.9906)
			)
			(stroke
				(width 0)
				(type default)
			)
			(fill no)
			(layer "F.CrtYd")
		)
		(fp_line
			(start -0.2794 0.9906)
			(end 0.2794 0.9906)
			(stroke
				(width 0.1)
				(type default)
			)
			(layer "F.Fab")
		)
		(fp_line
			(start 0.2794 0.9906)
			(end 0.2794 -0.1016)
			(stroke
				(width 0.1)
				(type default)
			)
			(layer "F.Fab")
		)
		(fp_line
			(start -0.2794 -0.1016)
			(end -0.2794 0.9906)
			(stroke
				(width 0.1)
				(type default)
			)
			(layer "F.Fab")
		)
		(fp_line
			(start 0.2794 -0.1016)
			(end -0.2794 -0.1016)
			(stroke
				(width 0.1)
				(type default)
			)
			(layer "F.Fab")
		)
		(pad "1" smd rect
			(at 0 0 270)
			(size 0.508 0.508)
			(layers "F.Cu" "F.Mask" "F.Paste")
			(net "PVCCIO_CPU1")
		)
		(pad "2" smd rect
			(at 0 0.889 270)
			(size 0.508 0.508)
			(layers "F.Cu" "F.Mask" "F.Paste")
			(net "SVID_ALERT1_CPU1_R_N")
		)
		(zone
			(layer "F.Cu")
			(hatch none 0.5)
			(connect_pads
				(clearance 0)
			)
			(min_thickness 0.25)
			(keepout
				(tracks not_allowed)
				(vias allowed)
				(pads allowed)
				(copperpour not_allowed)
				(footprints allowed)
			)
			(placement
				(enabled no)
				(sheetname "")
			)
			(fill
				(thermal_gap 0.5)
				(thermal_bridge_width 0.5)
				(island_removal_mode 0)
			)
			(polygon
				(pts
					(xy 38.687756 -107.609132) (xy 38.687756 -107.101132) (xy 39.068756 -107.101132) (xy 39.068756 -107.609132)
				)
			)
		)
		(zone
			(layer "F.Cu")
			(hatch none 0.5)
			(connect_pads
				(clearance 0)
			)
			(min_thickness 0.25)
			(keepout
				(tracks allowed)
				(vias not_allowed)
				(pads allowed)
				(copperpour not_allowed)
				(footprints allowed)
			)
			(placement
				(enabled no)
				(sheetname "")
			)
			(fill
				(thermal_gap 0.5)
				(thermal_bridge_width 0.5)
				(island_removal_mode 0)
			)
			(polygon
				(pts
					(xy 39.068756 -107.609132) (xy 39.068756 -107.101132) (xy 38.687756 -107.101132) (xy 38.687756 -107.609132)
				)
			)
		)
	)
	(footprint ""
		(layer "F.Cu")
		(at 372.528338 -146.561048 180)
		(property "Reference" "CT65"
			(at -0.8382 -0.67818 180)
			(unlocked yes)
			(layer "F.SilkS")
			(effects
				(font
					(size 0.4064 0.254)
					(thickness 0.1524)
				)
				(justify left)
			)
		)
		(property "Value" ""
			(at 0 0 180)
			(layer "F.Fab")
			(effects
				(font
					(size 1.27 1.27)
				)
			)
		)
		(duplicate_pad_numbers_are_jumpers no)
		(fp_poly
			(pts
				(xy 0.3048 -0.1016) (xy 0.3048 0.9906) (xy -0.3048 0.9906) (xy -0.3048 -0.1016)
			)
			(stroke
				(width 0)
				(type default)
			)
			(fill no)
			(layer "F.CrtYd")
		)
		(fp_line
			(start 0.3048 0.9906)
			(end 0.3048 -0.1016)
			(stroke
				(width 0.1)
				(type default)
			)
			(layer "F.Fab")
		)
		(fp_line
			(start 0.3048 -0.1016)
			(end -0.3048 -0.1016)
			(stroke
				(width 0.1)
				(type default)
			)
			(layer "F.Fab")
		)
		(fp_line
			(start -0.3048 0.9906)
			(end 0.3048 0.9906)
			(stroke
				(width 0.1)
				(type default)
			)
			(layer "F.Fab")
		)
		(fp_line
			(start -0.3048 -0.1016)
			(end -0.3048 0.9906)
			(stroke
				(width 0.1)
				(type default)
			)
			(layer "F.Fab")
		)
		(pad "1" smd rect
			(at 0 0 180)
			(size 0.508 0.508)
			(layers "F.Cu" "F.Mask" "F.Paste")
			(net "VR_PVNN_PCH_PH1_PHASE_SW")
		)
		(pad "2" smd rect
			(at 0 0.889 180)
			(size 0.508 0.508)
			(layers "F.Cu" "F.Mask" "F.Paste")
			(net "VR_PVNN_PCH_PH1_PHASE_SW_RC")
		)
		(zone
			(layer "F.Cu")
			(hatch none 0.5)
			(connect_pads
				(clearance 0)
			)
			(min_thickness 0.25)
			(keepout
				(tracks not_allowed)
				(vias allowed)
				(pads allowed)
				(copperpour not_allowed)
				(footprints allowed)
			)
			(placement
				(enabled no)
				(sheetname "")
			)
			(fill
				(thermal_gap 0.5)
				(thermal_bridge_width 0.5)
				(island_removal_mode 0)
			)
			(polygon
				(pts
					(xy 372.782338 -147.196048) (xy 372.274338 -147.196048) (xy 372.274338 -146.815048) (xy 372.782338 -146.815048)
				)
			)
		)
		(zone
			(layer "F.Cu")
			(hatch none 0.5)
			(connect_pads
				(clearance 0)
			)
			(min_thickness 0.25)
			(keepout
				(tracks allowed)
				(vias not_allowed)
				(pads allowed)
				(copperpour not_allowed)
				(footprints allowed)
			)
			(placement
				(enabled no)
				(sheetname "")
			)
			(fill
				(thermal_gap 0.5)
				(thermal_bridge_width 0.5)
				(island_removal_mode 0)
			)
			(polygon
				(pts
					(xy 372.782338 -146.815048) (xy 372.274338 -146.815048) (xy 372.274338 -147.196048) (xy 372.782338 -147.196048)
				)
			)
		)
	)
	(footprint ""
		(layer "F.Cu")
		(at 320.194432 -3.302 90)
		(property "Reference" "C6G5"
			(at 0 0 90)
			(layer "F.SilkS")
			(hide yes)
			(effects
				(font
					(size 1.27 1.27)
				)
			)
		)
		(property "Value" ""
			(at 0 0 90)
			(layer "F.Fab")
			(effects
				(font
					(size 1.27 1.27)
				)
			)
		)
		(duplicate_pad_numbers_are_jumpers no)
		(fp_poly
			(pts
				(xy -0.4953 -0.2032) (xy 0.4953 -0.2032) (xy 0.4953 1.6002) (xy -0.4953 1.6002)
			)
			(stroke
				(width 0)
				(type default)
			)
			(fill no)
			(layer "F.CrtYd")
		)
		(fp_line
			(start 0.4953 -0.2032)
			(end 0.4953 1.6002)
			(stroke
				(width 0.1)
				(type default)
			)
			(layer "F.Fab")
		)
		(fp_line
			(start -0.4953 -0.2032)
			(end 0.4953 -0.2032)
			(stroke
				(width 0.1)
				(type default)
			)
			(layer "F.Fab")
		)
		(fp_line
			(start 0.4953 1.6002)
			(end -0.4953 1.6002)
			(stroke
				(width 0.1)
				(type default)
			)
			(layer "F.Fab")
		)
		(fp_line
			(start -0.4953 1.6002)
			(end -0.4953 -0.2032)
			(stroke
				(width 0.1)
				(type default)
			)
			(layer "F.Fab")
		)
		(pad "1" smd rect
			(at 0 0 90)
			(size 0.762 0.889)
			(layers "F.Cu" "F.Mask" "F.Paste")
			(net "PVPP_ABC")
		)
		(pad "2" smd rect
			(at 0 1.397 90)
			(size 0.762 0.889)
			(layers "F.Cu" "F.Mask" "F.Paste")
			(net "GND")
		)
		(zone
			(layer "F.Cu")
			(hatch none 0.5)
			(connect_pads
				(clearance 0)
			)
			(min_thickness 0.25)
			(keepout
				(tracks not_allowed)
				(vias allowed)
				(pads allowed)
				(copperpour not_allowed)
				(footprints allowed)
			)
			(placement
				(enabled no)
				(sheetname "")
			)
			(fill
				(thermal_gap 0.5)
				(thermal_bridge_width 0.5)
				(island_removal_mode 0)
			)
			(polygon
				(pts
					(xy 320.638932 -2.921) (xy 320.638932 -3.683) (xy 321.146932 -3.683) (xy 321.146932 -2.921)
				)
			)
		)
	)
	(footprint ""
		(layer "F.Cu")
		(at 438.833006 -41.663874 180)
		(property "Reference" "R25W21"
			(at 0 0 180)
			(layer "F.SilkS")
			(hide yes)
			(effects
				(font
					(size 1.27 1.27)
				)
			)
		)
		(property "Value" "*"
			(at 0.064008 -4.108196 180)
			(unlocked yes)
			(layer "F.Fab")
			(hide yes)
			(effects
				(font
					(size 1.27 1.016)
					(thickness 0.1524)
				)
			)
		)
		(property "Device Type" "120R2F-GP_RCL_GP-120R2F-GP,64.A"
			(at 0.064008 -5.632196 180)
			(unlocked yes)
			(layer "F.Fab")
			(hide yes)
			(effects
				(font
					(size 1.27 1.016)
					(thickness 0.1524)
				)
			)
		)
		(duplicate_pad_numbers_are_jumpers no)
		(fp_line
			(start 0.508 -0.9398)
			(end -0.508 -0.9398)
			(stroke
				(width 0.1524)
				(type default)
			)
			(layer "F.SilkS")
		)
		(fp_line
			(start -0.508 -0.9398)
			(end -0.508 0.9398)
			(stroke
				(width 0.1524)
				(type default)
			)
			(layer "F.SilkS")
		)
		(fp_rect
			(start -0.508 0.9398)
			(end 0.508 -0.9398)
			(stroke
				(width 0)
				(type default)
			)
			(fill no)
			(layer "F.CrtYd")
		)
		(fp_rect
			(start -0.508 0.9398)
			(end 0.508 -0.9398)
			(stroke
				(width 0)
				(type default)
			)
			(fill no)
			(layer "F.Fab")
		)
		(pad "1" smd custom
			(at 0 -0.4445 180)
			(size 0.1397 0.1397)
			(layers "F.Cu" "F.Mask" "F.Paste")
			(net "GND")
			(options
				(clearance outline)
				(anchor circle)
			)
			(primitives
				(gr_poly
					(pts
						(arc
							(start -0.1778 -0.2794)
							(mid -0.249642 -0.249642)
							(end -0.2794 -0.1778)
						)
						(arc
							(start -0.2794 0.1778)
							(mid -0.249642 0.249642)
							(end -0.1778 0.2794)
						)
						(arc
							(start 0.1778 0.2794)
							(mid 0.249642 0.249642)
							(end 0.2794 0.1778)
						)
						(arc
							(start 0.2794 -0.1778)
							(mid 0.249642 -0.249642)
							(end 0.1778 -0.2794)
						)
					)
					(width 0)
					(fill yes)
				)
			)
		)
		(pad "2" smd custom
			(at 0 0.4445 180)
			(size 0.1397 0.1397)
			(layers "F.Cu" "F.Mask" "F.Paste")
			(net "BMC_M_A9")
			(options
				(clearance outline)
				(anchor circle)
			)
			(primitives
				(gr_poly
					(pts
						(arc
							(start -0.1778 -0.2794)
							(mid -0.249642 -0.249642)
							(end -0.2794 -0.1778)
						)
						(arc
							(start -0.2794 0.1778)
							(mid -0.249642 0.249642)
							(end -0.1778 0.2794)
						)
						(arc
							(start 0.1778 0.2794)
							(mid 0.249642 0.249642)
							(end 0.2794 0.1778)
						)
						(arc
							(start 0.2794 -0.1778)
							(mid 0.249642 -0.249642)
							(end 0.1778 -0.2794)
						)
					)
					(width 0)
					(fill yes)
				)
			)
		)
	)
	(footprint ""
		(layer "F.Cu")
		(at 261.942072 -73.318116)
		(property "Reference" "C5D42"
			(at 0 0 0)
			(layer "F.SilkS")
			(hide yes)
			(effects
				(font
					(size 1.27 1.27)
				)
			)
		)
		(property "Value" ""
			(at 0 0 0)
			(layer "F.Fab")
			(effects
				(font
					(size 1.27 1.27)
				)
			)
		)
		(duplicate_pad_numbers_are_jumpers no)
		(fp_poly
			(pts
				(xy -0.4953 -0.2032) (xy 0.4953 -0.2032) (xy 0.4953 1.6002) (xy -0.4953 1.6002)
			)
			(stroke
				(width 0)
				(type default)
			)
			(fill no)
			(layer "F.CrtYd")
		)
		(fp_line
			(start -0.4953 -0.2032)
			(end 0.4953 -0.2032)
			(stroke
				(width 0.1)
				(type default)
			)
			(layer "F.Fab")
		)
		(fp_line
			(start -0.4953 1.6002)
			(end -0.4953 -0.2032)
			(stroke
				(width 0.1)
				(type default)
			)
			(layer "F.Fab")
		)
		(fp_line
			(start 0.4953 -0.2032)
			(end 0.4953 1.6002)
			(stroke
				(width 0.1)
				(type default)
			)
			(layer "F.Fab")
		)
		(fp_line
			(start 0.4953 1.6002)
			(end -0.4953 1.6002)
			(stroke
				(width 0.1)
				(type default)
			)
			(layer "F.Fab")
		)
		(pad "1" smd rect
			(at 0 0)
			(size 0.762 0.889)
			(layers "F.Cu" "F.Mask" "F.Paste")
			(net "PVCCIN_CPU0")
		)
		(pad "2" smd rect
			(at 0 1.397)
			(size 0.762 0.889)
			(layers "F.Cu" "F.Mask" "F.Paste")
			(net "GND")
		)
		(zone
			(layer "F.Cu")
			(hatch none 0.5)
			(connect_pads
				(clearance 0)
			)
			(min_thickness 0.25)
			(keepout
				(tracks not_allowed)
				(vias allowed)
				(pads allowed)
				(copperpour not_allowed)
				(footprints allowed)
			)
			(placement
				(enabled no)
				(sheetname "")
			)
			(fill
				(thermal_gap 0.5)
				(thermal_bridge_width 0.5)
				(island_removal_mode 0)
			)
			(polygon
				(pts
					(xy 261.561072 -72.873616) (xy 262.323072 -72.873616) (xy 262.323072 -72.365616) (xy 261.561072 -72.365616)
				)
			)
		)
	)
	(footprint ""
		(layer "F.Cu")
		(at 167.00627 -34.1503 90)
		(property "Reference" "C4F3"
			(at 0 0 90)
			(layer "F.SilkS")
			(hide yes)
			(effects
				(font
					(size 1.27 1.27)
				)
			)
		)
		(property "Value" ""
			(at 0 0 90)
			(layer "F.Fab")
			(effects
				(font
					(size 1.27 1.27)
				)
			)
		)
		(duplicate_pad_numbers_are_jumpers no)
		(fp_poly
			(pts
				(xy 0.3048 -0.1016) (xy 0.3048 0.9906) (xy -0.3048 0.9906) (xy -0.3048 -0.1016)
			)
			(stroke
				(width 0)
				(type default)
			)
			(fill no)
			(layer "F.CrtYd")
		)
		(fp_line
			(start 0.3048 -0.1016)
			(end -0.3048 -0.1016)
			(stroke
				(width 0.1)
				(type default)
			)
			(layer "F.Fab")
		)
		(fp_line
			(start -0.3048 -0.1016)
			(end -0.3048 0.9906)
			(stroke
				(width 0.1)
				(type default)
			)
			(layer "F.Fab")
		)
		(fp_line
			(start 0.3048 0.9906)
			(end 0.3048 -0.1016)
			(stroke
				(width 0.1)
				(type default)
			)
			(layer "F.Fab")
		)
		(fp_line
			(start -0.3048 0.9906)
			(end 0.3048 0.9906)
			(stroke
				(width 0.1)
				(type default)
			)
			(layer "F.Fab")
		)
		(pad "1" smd rect
			(at 0 0 90)
			(size 0.508 0.508)
			(layers "F.Cu" "F.Mask" "F.Paste")
			(net "P1V8_MCP_CPU1")
		)
		(pad "2" smd rect
			(at 0 0.889 90)
			(size 0.508 0.508)
			(layers "F.Cu" "F.Mask" "F.Paste")
			(net "GND")
		)
		(zone
			(layer "F.Cu")
			(hatch none 0.5)
			(connect_pads
				(clearance 0)
			)
			(min_thickness 0.25)
			(keepout
				(tracks allowed)
				(vias not_allowed)
				(pads allowed)
				(copperpour not_allowed)
				(footprints allowed)
			)
			(placement
				(enabled no)
				(sheetname "")
			)
			(fill
				(thermal_gap 0.5)
				(thermal_bridge_width 0.5)
				(island_removal_mode 0)
			)
			(polygon
				(pts
					(xy 167.26027 -33.8963) (xy 167.26027 -34.4043) (xy 167.64127 -34.4043) (xy 167.64127 -33.8963)
				)
			)
		)
		(zone
			(layer "F.Cu")
			(hatch none 0.5)
			(connect_pads
				(clearance 0)
			)
			(min_thickness 0.25)
			(keepout
				(tracks not_allowed)
				(vias allowed)
				(pads allowed)
				(copperpour not_allowed)
				(footprints allowed)
			)
			(placement
				(enabled no)
				(sheetname "")
			)
			(fill
				(thermal_gap 0.5)
				(thermal_bridge_width 0.5)
				(island_removal_mode 0)
			)
			(polygon
				(pts
					(xy 167.64127 -33.8963) (xy 167.64127 -34.4043) (xy 167.26027 -34.4043) (xy 167.26027 -33.8963)
				)
			)
		)
	)
	(footprint ""
		(layer "F.Cu")
		(at 29.699458 -152.273 90)
		(property "Reference" "J1A1"
			(at -2.572512 42.563542 0)
			(unlocked yes)
			(layer "F.SilkS")
			(effects
				(font
					(size 0.7874 0.5842)
					(thickness 0.1524)
				)
				(justify left)
			)
		)
		(property "Value" ""
			(at 0 0 90)
			(layer "F.Fab")
			(effects
				(font
					(size 1.27 1.27)
				)
			)
		)
		(duplicate_pad_numbers_are_jumpers no)
		(fp_line
			(start 5.5499 -7.675118)
			(end 5.5499 -1.480058)
			(stroke
				(width 0.1524)
				(type default)
			)
			(layer "F.SilkS")
		)
		(fp_line
			(start -0.94996 -7.675118)
			(end 5.5499 -7.675118)
			(stroke
				(width 0.1524)
				(type default)
			)
			(layer "F.SilkS")
		)
		(fp_line
			(start -0.94996 -1.480058)
			(end -0.94996 -7.675118)
			(stroke
				(width 0.1524)
				(type default)
			)
			(layer "F.SilkS")
		)
		(fp_line
			(start 5.5499 128.130046)
			(end 5.5499 134.325106)
			(stroke
				(width 0.1524)
				(type default)
			)
			(layer "F.SilkS")
		)
		(fp_line
			(start 5.5499 134.325106)
			(end -0.94996 134.325106)
			(stroke
				(width 0.1524)
				(type default)
			)
			(layer "F.SilkS")
		)
		(fp_line
			(start -0.94996 134.325106)
			(end -0.94996 128.130046)
			(stroke
				(width 0.1524)
				(type default)
			)
			(layer "F.SilkS")
		)
		(fp_poly
			(pts
				(xy -3.029458 -0.611632) (xy -3.029458 0.404368) (xy -1.759458 -0.103632)
			)
			(stroke
				(width 0)
				(type default)
			)
			(fill yes)
			(layer "F.SilkS")
		)
		(fp_poly
			(pts
				(xy -0.94996 -7.675118) (xy -0.94996 134.325106) (xy 5.5499 134.325106) (xy 5.5499 -7.675118)
			)
			(stroke
				(width 0)
				(type default)
			)
			(fill no)
			(layer "F.CrtYd")
		)
		(fp_line
			(start 5.5499 -7.675118)
			(end 5.5499 134.325106)
			(stroke
				(width 0.1)
				(type default)
			)
			(layer "F.Fab")
		)
		(fp_line
			(start -0.94996 -7.675118)
			(end 5.5499 -7.675118)
			(stroke
				(width 0.1)
				(type default)
			)
			(layer "F.Fab")
		)
		(fp_line
			(start 5.5499 134.325106)
			(end -0.94996 134.325106)
			(stroke
				(width 0.1)
				(type default)
			)
			(layer "F.Fab")
		)
		(fp_line
			(start -0.94996 134.325106)
			(end -0.94996 -7.675118)
			(stroke
				(width 0.1)
				(type default)
			)
			(layer "F.Fab")
		)
		(fp_poly
			(pts
				(xy -2.984246 -0.461264) (xy -2.984246 0.554736) (xy -1.714246 0.046736)
			)
			(stroke
				(width 0)
				(type default)
			)
			(fill yes)
			(layer "F.Fab")
		)
		(fp_text user "145"
			(at 6.144768 -1.144778 0)
			(unlocked yes)
			(layer "F.SilkS")
			(effects
				(font
					(size 0.7874 0.5842)
					(thickness 0.1524)
				)
				(justify left)
			)
		)
		(fp_text user "221"
			(at 6.035548 64.031622 0)
			(unlocked yes)
			(layer "F.SilkS")
			(effects
				(font
					(size 0.7874 0.5842)
					(thickness 0.1524)
				)
				(justify left)
			)
		)
		(fp_text user "77"
			(at -1.405128 65.934082 0)
			(unlocked yes)
			(layer "F.SilkS")
			(effects
				(font
					(size 0.7874 0.5842)
					(thickness 0.1524)
				)
				(justify left)
			)
		)
		(fp_text user "78"
			(at -1.600708 69.732652 0)
			(unlocked yes)
			(layer "F.SilkS")
			(effects
				(font
					(size 0.7874 0.5842)
					(thickness 0.1524)
				)
				(justify left)
			)
		)
		(fp_text user "222"
			(at 6.038088 70.046342 0)
			(unlocked yes)
			(layer "F.SilkS")
			(effects
				(font
					(size 0.7874 0.5842)
					(thickness 0.1524)
				)
				(justify left)
			)
		)
		(fp_text user "288"
			(at 6.172708 126.901702 0)
			(unlocked yes)
			(layer "F.SilkS")
			(effects
				(font
					(size 0.7874 0.5842)
					(thickness 0.1524)
				)
				(justify left)
			)
		)
		(fp_text user "144"
			(at -1.988312 128.288542 0)
			(unlocked yes)
			(layer "F.SilkS")
			(effects
				(font
					(size 0.7874 0.5842)
					(thickness 0.1524)
				)
				(justify left)
			)
		)
		(fp_text user "145"
			(at 3.296158 -0.843788 90)
			(unlocked yes)
			(layer "F.Fab")
			(effects
				(font
					(size 0.7874 0.5842)
					(thickness 0.1524)
				)
				(justify left)
			)
		)
		(fp_text user "221"
			(at 3.296158 65.831212 90)
			(unlocked yes)
			(layer "F.Fab")
			(effects
				(font
					(size 0.7874 0.5842)
					(thickness 0.1524)
				)
				(justify left)
			)
		)
		(fp_text user "77"
			(at -0.513842 65.831212 90)
			(unlocked yes)
			(layer "F.Fab")
			(effects
				(font
					(size 0.7874 0.5842)
					(thickness 0.1524)
				)
				(justify left)
			)
		)
		(fp_text user "78"
			(at -0.513842 69.006212 90)
			(unlocked yes)
			(layer "F.Fab")
			(effects
				(font
					(size 0.7874 0.5842)
					(thickness 0.1524)
				)
				(justify left)
			)
		)
		(fp_text user "222"
			(at 4.0005 69.268848 90)
			(unlocked yes)
			(layer "F.Fab")
			(effects
				(font
					(size 0.7874 0.5842)
					(thickness 0.1524)
				)
				(justify left)
			)
		)
		(fp_text user "288"
			(at 3.296158 128.061212 90)
			(unlocked yes)
			(layer "F.Fab")
			(effects
				(font
					(size 0.7874 0.5842)
					(thickness 0.1524)
				)
				(justify left)
			)
		)
		(fp_text user "144"
			(at -0.513842 128.061212 90)
			(unlocked yes)
			(layer "F.Fab")
			(effects
				(font
					(size 0.7874 0.5842)
					(thickness 0.1524)
				)
				(justify left)
			)
		)
		(pad "" thru_hole circle
			(at 2.29997 -5.649976 90)
			(size 2.8194 2.8194)
			(drill 2.4384)
			(layers "*.Cu" "*.Mask")
			(remove_unused_layers no)
			(clearance 0.127)
			(thermal_gap 0.127)
		)
		(pad "" thru_hole oval
			(at 2.29997 68.90004 90)
			(size 2.8194 1.5748)
			(drill oval 2.4384 1.1938)
			(layers "*.Cu" "*.Mask")
			(remove_unused_layers no)
			(clearance 0.127)
			(thermal_gap 0.127)
		)
		(pad "" thru_hole circle
			(at 2.29997 132.299964 90)
			(size 2.8194 2.8194)
			(drill 2.4384)
			(layers "*.Cu" "*.Mask")
			(remove_unused_layers no)
			(clearance 0.127)
			(thermal_gap 0.127)
		)
		(pad "1" smd rect
			(at 0 0 90)
			(size 1.8034 0.508)
			(layers "F.Cu" "F.Mask" "F.Paste")
			(net "P12V_NVDIMM_KLM")
		)
		(pad "2" smd rect
			(at 0 0.849884 90)
			(size 1.8034 0.508)
			(layers "F.Cu" "F.Mask" "F.Paste")
			(net "GND")
		)
		(pad "3" smd rect
			(at 0 1.700022 90)
			(size 1.8034 0.508)
			(layers "F.Cu" "F.Mask" "F.Paste")
			(net "M_M_DQ<5>")
		)
		(pad "4" smd rect
			(at 0 2.549906 90)
			(size 1.8034 0.508)
			(layers "F.Cu" "F.Mask" "F.Paste")
			(net "GND")
		)
		(pad "5" smd rect
			(at 0 3.400044 90)
			(size 1.8034 0.508)
			(layers "F.Cu" "F.Mask" "F.Paste")
			(net "M_M_DQ<1>")
		)
		(pad "6" smd rect
			(at 0 4.249928 90)
			(size 1.8034 0.508)
			(layers "F.Cu" "F.Mask" "F.Paste")
			(net "GND")
		)
		(pad "7" smd rect
			(at 0 5.100066 90)
			(size 1.8034 0.508)
			(layers "F.Cu" "F.Mask" "F.Paste")
			(net "M_M_DQS_DP<9>")
		)
		(pad "8" smd rect
			(at 0 5.94995 90)
			(size 1.8034 0.508)
			(layers "F.Cu" "F.Mask" "F.Paste")
			(net "M_M_DQS_DN<9>")
		)
		(pad "9" smd rect
			(at 0 6.800088 90)
			(size 1.8034 0.508)
			(layers "F.Cu" "F.Mask" "F.Paste")
			(net "GND")
		)
		(pad "10" smd rect
			(at 0 7.649972 90)
			(size 1.8034 0.508)
			(layers "F.Cu" "F.Mask" "F.Paste")
			(net "M_M_DQ<7>")
		)
		(pad "11" smd rect
			(at 0 8.50011 90)
			(size 1.8034 0.508)
			(layers "F.Cu" "F.Mask" "F.Paste")
			(net "GND")
		)
		(pad "12" smd rect
			(at 0 9.349994 90)
			(size 1.8034 0.508)
			(layers "F.Cu" "F.Mask" "F.Paste")
			(net "M_M_DQ<3>")
		)
		(pad "13" smd rect
			(at 0 10.199878 90)
			(size 1.8034 0.508)
			(layers "F.Cu" "F.Mask" "F.Paste")
			(net "GND")
		)
		(pad "14" smd rect
			(at 0 11.050016 90)
			(size 1.8034 0.508)
			(layers "F.Cu" "F.Mask" "F.Paste")
			(net "M_M_DQ<13>")
		)
		(pad "15" smd rect
			(at 0 11.8999 90)
			(size 1.8034 0.508)
			(layers "F.Cu" "F.Mask" "F.Paste")
			(net "GND")
		)
		(pad "16" smd rect
			(at 0 12.750038 90)
			(size 1.8034 0.508)
			(layers "F.Cu" "F.Mask" "F.Paste")
			(net "M_M_DQ<9>")
		)
		(pad "17" smd rect
			(at 0 13.599922 90)
			(size 1.8034 0.508)
			(layers "F.Cu" "F.Mask" "F.Paste")
			(net "GND")
		)
		(pad "18" smd rect
			(at 0 14.45006 90)
			(size 1.8034 0.508)
			(layers "F.Cu" "F.Mask" "F.Paste")
			(net "M_M_DQS_DP<10>")
		)
		(pad "19" smd rect
			(at 0 15.299944 90)
			(size 1.8034 0.508)
			(layers "F.Cu" "F.Mask" "F.Paste")
			(net "M_M_DQS_DN<10>")
		)
		(pad "20" smd rect
			(at 0 16.150082 90)
			(size 1.8034 0.508)
			(layers "F.Cu" "F.Mask" "F.Paste")
			(net "GND")
		)
		(pad "21" smd rect
			(at 0 16.999966 90)
			(size 1.8034 0.508)
			(layers "F.Cu" "F.Mask" "F.Paste")
			(net "M_M_DQ<15>")
		)
		(pad "22" smd rect
			(at 0 17.850104 90)
			(size 1.8034 0.508)
			(layers "F.Cu" "F.Mask" "F.Paste")
			(net "GND")
		)
		(pad "23" smd rect
			(at 0 18.699988 90)
			(size 1.8034 0.508)
			(layers "F.Cu" "F.Mask" "F.Paste")
			(net "M_M_DQ<11>")
		)
		(pad "24" smd rect
			(at 0 19.550126 90)
			(size 1.8034 0.508)
			(layers "F.Cu" "F.Mask" "F.Paste")
			(net "GND")
		)
		(pad "25" smd rect
			(at 0 20.40001 90)
			(size 1.8034 0.508)
			(layers "F.Cu" "F.Mask" "F.Paste")
			(net "M_M_DQ<21>")
		)
		(pad "26" smd rect
			(at 0 21.249894 90)
			(size 1.8034 0.508)
			(layers "F.Cu" "F.Mask" "F.Paste")
			(net "GND")
		)
		(pad "27" smd rect
			(at 0 22.100032 90)
			(size 1.8034 0.508)
			(layers "F.Cu" "F.Mask" "F.Paste")
			(net "M_M_DQ<17>")
		)
		(pad "28" smd rect
			(at 0 22.949916 90)
			(size 1.8034 0.508)
			(layers "F.Cu" "F.Mask" "F.Paste")
			(net "GND")
		)
		(pad "29" smd rect
			(at 0 23.800054 90)
			(size 1.8034 0.508)
			(layers "F.Cu" "F.Mask" "F.Paste")
			(net "M_M_DQS_DP<11>")
		)
		(pad "30" smd rect
			(at 0 24.649938 90)
			(size 1.8034 0.508)
			(layers "F.Cu" "F.Mask" "F.Paste")
			(net "M_M_DQS_DN<11>")
		)
		(pad "31" smd rect
			(at 0 25.500076 90)
			(size 1.8034 0.508)
			(layers "F.Cu" "F.Mask" "F.Paste")
			(net "GND")
		)
		(pad "32" smd rect
			(at 0 26.34996 90)
			(size 1.8034 0.508)
			(layers "F.Cu" "F.Mask" "F.Paste")
			(net "M_M_DQ<23>")
		)
		(pad "33" smd rect
			(at 0 27.200098 90)
			(size 1.8034 0.508)
			(layers "F.Cu" "F.Mask" "F.Paste")
			(net "GND")
		)
		(pad "34" smd rect
			(at 0 28.049982 90)
			(size 1.8034 0.508)
			(layers "F.Cu" "F.Mask" "F.Paste")
			(net "M_M_DQ<19>")
		)
		(pad "35" smd rect
			(at 0 28.90012 90)
			(size 1.8034 0.508)
			(layers "F.Cu" "F.Mask" "F.Paste")
			(net "GND")
		)
		(pad "36" smd rect
			(at 0 29.750004 90)
			(size 1.8034 0.508)
			(layers "F.Cu" "F.Mask" "F.Paste")
			(net "M_M_DQ<29>")
		)
		(pad "37" smd rect
			(at 0 30.599888 90)
			(size 1.8034 0.508)
			(layers "F.Cu" "F.Mask" "F.Paste")
			(net "GND")
		)
		(pad "38" smd rect
			(at 0 31.450026 90)
			(size 1.8034 0.508)
			(layers "F.Cu" "F.Mask" "F.Paste")
			(net "M_M_DQ<25>")
		)
		(pad "39" smd rect
			(at 0 32.29991 90)
			(size 1.8034 0.508)
			(layers "F.Cu" "F.Mask" "F.Paste")
			(net "GND")
		)
		(pad "40" smd rect
			(at 0 33.150048 90)
			(size 1.8034 0.508)
			(layers "F.Cu" "F.Mask" "F.Paste")
			(net "M_M_DQS_DP<12>")
		)
		(pad "41" smd rect
			(at 0 33.999932 90)
			(size 1.8034 0.508)
			(layers "F.Cu" "F.Mask" "F.Paste")
			(net "M_M_DQS_DN<12>")
		)
		(pad "42" smd rect
			(at 0 34.85007 90)
			(size 1.8034 0.508)
			(layers "F.Cu" "F.Mask" "F.Paste")
			(net "GND")
		)
		(pad "43" smd rect
			(at 0 35.699954 90)
			(size 1.8034 0.508)
			(layers "F.Cu" "F.Mask" "F.Paste")
			(net "M_M_DQ<31>")
		)
		(pad "44" smd rect
			(at 0 36.550092 90)
			(size 1.8034 0.508)
			(layers "F.Cu" "F.Mask" "F.Paste")
			(net "GND")
		)
		(pad "45" smd rect
			(at 0 37.399976 90)
			(size 1.8034 0.508)
			(layers "F.Cu" "F.Mask" "F.Paste")
			(net "M_M_DQ<27>")
		)
		(pad "46" smd rect
			(at 0 38.250114 90)
			(size 1.8034 0.508)
			(layers "F.Cu" "F.Mask" "F.Paste")
			(net "GND")
		)
		(pad "47" smd rect
			(at 0 39.099998 90)
			(size 1.8034 0.508)
			(layers "F.Cu" "F.Mask" "F.Paste")
			(net "M_M_ECC<5>")
		)
		(pad "48" smd rect
			(at 0 39.949882 90)
			(size 1.8034 0.508)
			(layers "F.Cu" "F.Mask" "F.Paste")
			(net "GND")
		)
		(pad "49" smd rect
			(at 0 40.80002 90)
			(size 1.8034 0.508)
			(layers "F.Cu" "F.Mask" "F.Paste")
			(net "M_M_ECC<1>")
		)
		(pad "50" smd rect
			(at 0 41.649904 90)
			(size 1.8034 0.508)
			(layers "F.Cu" "F.Mask" "F.Paste")
			(net "GND")
		)
		(pad "51" smd rect
			(at 0 42.500042 90)
			(size 1.8034 0.508)
			(layers "F.Cu" "F.Mask" "F.Paste")
			(net "M_M_DQS_DP<17>")
		)
		(pad "52" smd rect
			(at 0 43.349926 90)
			(size 1.8034 0.508)
			(layers "F.Cu" "F.Mask" "F.Paste")
			(net "M_M_DQS_DN<17>")
		)
		(pad "53" smd rect
			(at 0 44.200064 90)
			(size 1.8034 0.508)
			(layers "F.Cu" "F.Mask" "F.Paste")
			(net "GND")
		)
		(pad "54" smd rect
			(at 0 45.049948 90)
			(size 1.8034 0.508)
			(layers "F.Cu" "F.Mask" "F.Paste")
			(net "M_M_ECC<7>")
		)
		(pad "55" smd rect
			(at 0 45.900086 90)
			(size 1.8034 0.508)
			(layers "F.Cu" "F.Mask" "F.Paste")
			(net "GND")
		)
		(pad "56" smd rect
			(at 0 46.74997 90)
			(size 1.8034 0.508)
			(layers "F.Cu" "F.Mask" "F.Paste")
			(net "M_M_ECC<3>")
		)
		(pad "57" smd rect
			(at 0 47.600108 90)
			(size 1.8034 0.508)
			(layers "F.Cu" "F.Mask" "F.Paste")
			(net "GND")
		)
		(pad "58" smd rect
			(at 0 48.449992 90)
			(size 1.8034 0.508)
			(layers "F.Cu" "F.Mask" "F.Paste")
			(net "M_KLM_RST_N")
		)
		(pad "59" smd rect
			(at 0 49.299876 90)
			(size 1.8034 0.508)
			(layers "F.Cu" "F.Mask" "F.Paste")
			(net "PVDDQ_KLM")
		)
		(pad "60" smd rect
			(at 0 50.150014 90)
			(size 1.8034 0.508)
			(layers "F.Cu" "F.Mask" "F.Paste")
			(net "M_M_CKE<0>")
		)
		(pad "61" smd rect
			(at 0 50.999898 90)
			(size 1.8034 0.508)
			(layers "F.Cu" "F.Mask" "F.Paste")
			(net "PVDDQ_KLM")
		)
		(pad "62" smd rect
			(at 0 51.850036 90)
			(size 1.8034 0.508)
			(layers "F.Cu" "F.Mask" "F.Paste")
			(net "M_M_ACT_N")
		)
		(pad "63" smd rect
			(at 0 52.69992 90)
			(size 1.8034 0.508)
			(layers "F.Cu" "F.Mask" "F.Paste")
			(net "M_M_BG<0>")
		)
		(pad "64" smd rect
			(at 0 53.550058 90)
			(size 1.8034 0.508)
			(layers "F.Cu" "F.Mask" "F.Paste")
			(net "PVDDQ_KLM")
		)
		(pad "65" smd rect
			(at 0 54.399942 90)
			(size 1.8034 0.508)
			(layers "F.Cu" "F.Mask" "F.Paste")
			(net "M_M_MA<12>")
		)
		(pad "66" smd rect
			(at 0 55.25008 90)
			(size 1.8034 0.508)
			(layers "F.Cu" "F.Mask" "F.Paste")
			(net "M_M_MA<9>")
		)
		(pad "67" smd rect
			(at 0 56.099964 90)
			(size 1.8034 0.508)
			(layers "F.Cu" "F.Mask" "F.Paste")
			(net "PVDDQ_KLM")
		)
		(pad "68" smd rect
			(at 0 56.950102 90)
			(size 1.8034 0.508)
			(layers "F.Cu" "F.Mask" "F.Paste")
			(net "M_M_MA<8>")
		)
		(pad "69" smd rect
			(at 0 57.799986 90)
			(size 1.8034 0.508)
			(layers "F.Cu" "F.Mask" "F.Paste")
			(net "M_M_MA<6>")
		)
		(pad "70" smd rect
			(at 0 58.650124 90)
			(size 1.8034 0.508)
			(layers "F.Cu" "F.Mask" "F.Paste")
			(net "PVDDQ_KLM")
		)
		(pad "71" smd rect
			(at 0 59.500008 90)
			(size 1.8034 0.508)
			(layers "F.Cu" "F.Mask" "F.Paste")
			(net "M_M_MA<3>")
		)
		(pad "72" smd rect
			(at 0 60.349892 90)
			(size 1.8034 0.508)
			(layers "F.Cu" "F.Mask" "F.Paste")
			(net "M_M_MA<1>")
		)
		(pad "73" smd rect
			(at 0 61.20003 90)
			(size 1.8034 0.508)
			(layers "F.Cu" "F.Mask" "F.Paste")
			(net "PVDDQ_KLM")
		)
		(pad "74" smd rect
			(at 0 62.049914 90)
			(size 1.8034 0.508)
			(layers "F.Cu" "F.Mask" "F.Paste")
			(net "M_M_CLK_DP<0>")
		)
		(pad "75" smd rect
			(at 0 62.900052 90)
			(size 1.8034 0.508)
			(layers "F.Cu" "F.Mask" "F.Paste")
			(net "M_M_CLK_DN<0>")
		)
		(pad "76" smd rect
			(at 0 63.749936 90)
			(size 1.8034 0.508)
			(layers "F.Cu" "F.Mask" "F.Paste")
			(net "PVDDQ_KLM")
		)
		(pad "77" smd rect
			(at 0 64.600074 90)
			(size 1.8034 0.508)
			(layers "F.Cu" "F.Mask" "F.Paste")
			(net "PVTT_KLM")
		)
		(pad "78" smd rect
			(at 0 70.550024 90)
			(size 1.8034 0.508)
			(layers "F.Cu" "F.Mask" "F.Paste")
			(net "FM_DIMM_EVENT_COD_N")
		)
		(pad "79" smd rect
			(at 0 71.399908 90)
			(size 1.8034 0.508)
			(layers "F.Cu" "F.Mask" "F.Paste")
			(net "M_M_MA<0>")
		)
		(pad "80" smd rect
			(at 0 72.250046 90)
			(size 1.8034 0.508)
			(layers "F.Cu" "F.Mask" "F.Paste")
			(net "PVDDQ_KLM")
		)
		(pad "81" smd rect
			(at 0 73.09993 90)
			(size 1.8034 0.508)
			(layers "F.Cu" "F.Mask" "F.Paste")
			(net "M_M_BA<0>")
		)
		(pad "82" smd rect
			(at 0 73.950068 90)
			(size 1.8034 0.508)
			(layers "F.Cu" "F.Mask" "F.Paste")
			(net "M_M_MA<16>")
		)
		(pad "83" smd rect
			(at 0 74.799952 90)
			(size 1.8034 0.508)
			(layers "F.Cu" "F.Mask" "F.Paste")
			(net "PVDDQ_KLM")
		)
		(pad "84" smd rect
			(at 0 75.65009 90)
			(size 1.8034 0.508)
			(layers "F.Cu" "F.Mask" "F.Paste")
			(net "M_M_CS_N<0>")
		)
		(pad "85" smd rect
			(at 0 76.499974 90)
			(size 1.8034 0.508)
			(layers "F.Cu" "F.Mask" "F.Paste")
			(net "PVDDQ_KLM")
		)
		(pad "86" smd rect
			(at 0 77.350112 90)
			(size 1.8034 0.508)
			(layers "F.Cu" "F.Mask" "F.Paste")
			(net "M_M_MA<15>")
		)
		(pad "87" smd rect
			(at 0 78.199996 90)
			(size 1.8034 0.508)
			(layers "F.Cu" "F.Mask" "F.Paste")
			(net "M_M_ODT<0>")
		)
		(pad "88" smd rect
			(at 0 79.04988 90)
			(size 1.8034 0.508)
			(layers "F.Cu" "F.Mask" "F.Paste")
			(net "PVDDQ_KLM")
		)
		(pad "89" smd rect
			(at 0 79.900018 90)
			(size 1.8034 0.508)
			(layers "F.Cu" "F.Mask" "F.Paste")
			(net "M_M_CS_N<1>")
		)
		(pad "90" smd rect
			(at 0 80.749902 90)
			(size 1.8034 0.508)
			(layers "F.Cu" "F.Mask" "F.Paste")
			(net "PVDDQ_KLM")
		)
		(pad "91" smd rect
			(at 0 81.60004 90)
			(size 1.8034 0.508)
			(layers "F.Cu" "F.Mask" "F.Paste")
			(net "M_M_ODT<1>")
		)
		(pad "92" smd rect
			(at 0 82.449924 90)
			(size 1.8034 0.508)
			(layers "F.Cu" "F.Mask" "F.Paste")
			(net "PVDDQ_KLM")
		)
		(pad "93" smd rect
			(at 0 83.300062 90)
			(size 1.8034 0.508)
			(layers "F.Cu" "F.Mask" "F.Paste")
			(net "M_M_CS_N<2>")
		)
		(pad "94" smd rect
			(at 0 84.149946 90)
			(size 1.8034 0.508)
			(layers "F.Cu" "F.Mask" "F.Paste")
			(net "GND")
		)
		(pad "95" smd rect
			(at 0 85.000084 90)
			(size 1.8034 0.508)
			(layers "F.Cu" "F.Mask" "F.Paste")
			(net "M_M_DQ<37>")
		)
		(pad "96" smd rect
			(at 0 85.849968 90)
			(size 1.8034 0.508)
			(layers "F.Cu" "F.Mask" "F.Paste")
			(net "GND")
		)
		(pad "97" smd rect
			(at 0 86.700106 90)
			(size 1.8034 0.508)
			(layers "F.Cu" "F.Mask" "F.Paste")
			(net "M_M_DQ<33>")
		)
		(pad "98" smd rect
			(at 0 87.54999 90)
			(size 1.8034 0.508)
			(layers "F.Cu" "F.Mask" "F.Paste")
			(net "GND")
		)
		(pad "99" smd rect
			(at 0 88.399874 90)
			(size 1.8034 0.508)
			(layers "F.Cu" "F.Mask" "F.Paste")
			(net "M_M_DQS_DP<13>")
		)
		(pad "100" smd rect
			(at 0 89.250012 90)
			(size 1.8034 0.508)
			(layers "F.Cu" "F.Mask" "F.Paste")
			(net "M_M_DQS_DN<13>")
		)
		(pad "101" smd rect
			(at 0 90.099896 90)
			(size 1.8034 0.508)
			(layers "F.Cu" "F.Mask" "F.Paste")
			(net "GND")
		)
		(pad "102" smd rect
			(at 0 90.950034 90)
			(size 1.8034 0.508)
			(layers "F.Cu" "F.Mask" "F.Paste")
			(net "M_M_DQ<39>")
		)
		(pad "103" smd rect
			(at 0 91.799918 90)
			(size 1.8034 0.508)
			(layers "F.Cu" "F.Mask" "F.Paste")
			(net "GND")
		)
		(pad "104" smd rect
			(at 0 92.650056 90)
			(size 1.8034 0.508)
			(layers "F.Cu" "F.Mask" "F.Paste")
			(net "M_M_DQ<35>")
		)
		(pad "105" smd rect
			(at 0 93.49994 90)
			(size 1.8034 0.508)
			(layers "F.Cu" "F.Mask" "F.Paste")
			(net "GND")
		)
		(pad "106" smd rect
			(at 0 94.350078 90)
			(size 1.8034 0.508)
			(layers "F.Cu" "F.Mask" "F.Paste")
			(net "M_M_DQ<45>")
		)
		(pad "107" smd rect
			(at 0 95.199962 90)
			(size 1.8034 0.508)
			(layers "F.Cu" "F.Mask" "F.Paste")
			(net "GND")
		)
		(pad "108" smd rect
			(at 0 96.0501 90)
			(size 1.8034 0.508)
			(layers "F.Cu" "F.Mask" "F.Paste")
			(net "M_M_DQ<41>")
		)
		(pad "109" smd rect
			(at 0 96.899984 90)
			(size 1.8034 0.508)
			(layers "F.Cu" "F.Mask" "F.Paste")
			(net "GND")
		)
		(pad "110" smd rect
			(at 0 97.750122 90)
			(size 1.8034 0.508)
			(layers "F.Cu" "F.Mask" "F.Paste")
			(net "M_M_DQS_DP<14>")
		)
		(pad "111" smd rect
			(at 0 98.600006 90)
			(size 1.8034 0.508)
			(layers "F.Cu" "F.Mask" "F.Paste")
			(net "M_M_DQS_DN<14>")
		)
		(pad "112" smd rect
			(at 0 99.44989 90)
			(size 1.8034 0.508)
			(layers "F.Cu" "F.Mask" "F.Paste")
			(net "GND")
		)
		(pad "113" smd rect
			(at 0 100.300028 90)
			(size 1.8034 0.508)
			(layers "F.Cu" "F.Mask" "F.Paste")
			(net "M_M_DQ<47>")
		)
		(pad "114" smd rect
			(at 0 101.149912 90)
			(size 1.8034 0.508)
			(layers "F.Cu" "F.Mask" "F.Paste")
			(net "GND")
		)
		(pad "115" smd rect
			(at 0 102.00005 90)
			(size 1.8034 0.508)
			(layers "F.Cu" "F.Mask" "F.Paste")
			(net "M_M_DQ<43>")
		)
		(pad "116" smd rect
			(at 0 102.849934 90)
			(size 1.8034 0.508)
			(layers "F.Cu" "F.Mask" "F.Paste")
			(net "GND")
		)
		(pad "117" smd rect
			(at 0 103.700072 90)
			(size 1.8034 0.508)
			(layers "F.Cu" "F.Mask" "F.Paste")
			(net "M_M_DQ<53>")
		)
		(pad "118" smd rect
			(at 0 104.549956 90)
			(size 1.8034 0.508)
			(layers "F.Cu" "F.Mask" "F.Paste")
			(net "GND")
		)
		(pad "119" smd rect
			(at 0 105.400094 90)
			(size 1.8034 0.508)
			(layers "F.Cu" "F.Mask" "F.Paste")
			(net "M_M_DQ<49>")
		)
		(pad "120" smd rect
			(at 0 106.249978 90)
			(size 1.8034 0.508)
			(layers "F.Cu" "F.Mask" "F.Paste")
			(net "GND")
		)
		(pad "121" smd rect
			(at 0 107.100116 90)
			(size 1.8034 0.508)
			(layers "F.Cu" "F.Mask" "F.Paste")
			(net "M_M_DQS_DP<15>")
		)
		(pad "122" smd rect
			(at 0 107.95 90)
			(size 1.8034 0.508)
			(layers "F.Cu" "F.Mask" "F.Paste")
			(net "M_M_DQS_DN<15>")
		)
		(pad "123" smd rect
			(at 0 108.799884 90)
			(size 1.8034 0.508)
			(layers "F.Cu" "F.Mask" "F.Paste")
			(net "GND")
		)
		(pad "124" smd rect
			(at 0 109.650022 90)
			(size 1.8034 0.508)
			(layers "F.Cu" "F.Mask" "F.Paste")
			(net "M_M_DQ<55>")
		)
		(pad "125" smd rect
			(at 0 110.499906 90)
			(size 1.8034 0.508)
			(layers "F.Cu" "F.Mask" "F.Paste")
			(net "GND")
		)
		(pad "126" smd rect
			(at 0 111.350044 90)
			(size 1.8034 0.508)
			(layers "F.Cu" "F.Mask" "F.Paste")
			(net "M_M_DQ<51>")
		)
		(pad "127" smd rect
			(at 0 112.199928 90)
			(size 1.8034 0.508)
			(layers "F.Cu" "F.Mask" "F.Paste")
			(net "GND")
		)
		(pad "128" smd rect
			(at 0 113.050066 90)
			(size 1.8034 0.508)
			(layers "F.Cu" "F.Mask" "F.Paste")
			(net "M_M_DQ<61>")
		)
		(pad "129" smd rect
			(at 0 113.89995 90)
			(size 1.8034 0.508)
			(layers "F.Cu" "F.Mask" "F.Paste")
			(net "GND")
		)
		(pad "130" smd rect
			(at 0 114.750088 90)
			(size 1.8034 0.508)
			(layers "F.Cu" "F.Mask" "F.Paste")
			(net "M_M_DQ<57>")
		)
		(pad "131" smd rect
			(at 0 115.599972 90)
			(size 1.8034 0.508)
			(layers "F.Cu" "F.Mask" "F.Paste")
			(net "GND")
		)
		(pad "132" smd rect
			(at 0 116.45011 90)
			(size 1.8034 0.508)
			(layers "F.Cu" "F.Mask" "F.Paste")
			(net "M_M_DQS_DP<16>")
		)
		(pad "133" smd rect
			(at 0 117.299994 90)
			(size 1.8034 0.508)
			(layers "F.Cu" "F.Mask" "F.Paste")
			(net "M_M_DQS_DN<16>")
		)
		(pad "134" smd rect
			(at 0 118.149878 90)
			(size 1.8034 0.508)
			(layers "F.Cu" "F.Mask" "F.Paste")
			(net "GND")
		)
		(pad "135" smd rect
			(at 0 119.000016 90)
			(size 1.8034 0.508)
			(layers "F.Cu" "F.Mask" "F.Paste")
			(net "M_M_DQ<63>")
		)
		(pad "136" smd rect
			(at 0 119.8499 90)
			(size 1.8034 0.508)
			(layers "F.Cu" "F.Mask" "F.Paste")
			(net "GND")
		)
		(pad "137" smd rect
			(at 0 120.700038 90)
			(size 1.8034 0.508)
			(layers "F.Cu" "F.Mask" "F.Paste")
			(net "M_M_DQ<59>")
		)
		(pad "138" smd rect
			(at 0 121.549922 90)
			(size 1.8034 0.508)
			(layers "F.Cu" "F.Mask" "F.Paste")
			(net "GND")
		)
		(pad "139" smd rect
			(at 0 122.40006 90)
			(size 1.8034 0.508)
			(layers "F.Cu" "F.Mask" "F.Paste")
			(net "GND")
		)
		(pad "140" smd rect
			(at 0 123.249944 90)
			(size 1.8034 0.508)
			(layers "F.Cu" "F.Mask" "F.Paste")
			(net "GND")
		)
		(pad "141" smd rect
			(at 0 124.100082 90)
			(size 1.8034 0.508)
			(layers "F.Cu" "F.Mask" "F.Paste")
			(net "SMB_DDR_KLM_VPP_SCL")
		)
		(pad "142" smd rect
			(at 0 124.949966 90)
			(size 1.8034 0.508)
			(layers "F.Cu" "F.Mask" "F.Paste")
			(net "PVPP_KLM")
		)
		(pad "143" smd rect
			(at 0 125.800104 90)
			(size 1.8034 0.508)
			(layers "F.Cu" "F.Mask" "F.Paste")
			(net "PVPP_KLM")
		)
		(pad "144" smd rect
			(at 0 126.649988 90)
			(size 1.8034 0.508)
			(layers "F.Cu" "F.Mask" "F.Paste")
			(net "TP_CH_M_DIMM_M0_RFU_2")
		)
		(pad "145" smd rect
			(at 4.59994 0 90)
			(size 1.8034 0.508)
			(layers "F.Cu" "F.Mask" "F.Paste")
			(net "P12V_NVDIMM_KLM")
		)
		(pad "146" smd rect
			(at 4.59994 0.849884 90)
			(size 1.8034 0.508)
			(layers "F.Cu" "F.Mask" "F.Paste")
			(net "M_M_VREF")
		)
		(pad "147" smd rect
			(at 4.59994 1.700022 90)
			(size 1.8034 0.508)
			(layers "F.Cu" "F.Mask" "F.Paste")
			(net "GND")
		)
		(pad "148" smd rect
			(at 4.59994 2.549906 90)
			(size 1.8034 0.508)
			(layers "F.Cu" "F.Mask" "F.Paste")
			(net "M_M_DQ<4>")
		)
		(pad "149" smd rect
			(at 4.59994 3.400044 90)
			(size 1.8034 0.508)
			(layers "F.Cu" "F.Mask" "F.Paste")
			(net "GND")
		)
		(pad "150" smd rect
			(at 4.59994 4.249928 90)
			(size 1.8034 0.508)
			(layers "F.Cu" "F.Mask" "F.Paste")
			(net "M_M_DQ<0>")
		)
		(pad "151" smd rect
			(at 4.59994 5.100066 90)
			(size 1.8034 0.508)
			(layers "F.Cu" "F.Mask" "F.Paste")
			(net "GND")
		)
		(pad "152" smd rect
			(at 4.59994 5.94995 90)
			(size 1.8034 0.508)
			(layers "F.Cu" "F.Mask" "F.Paste")
			(net "M_M_DQS_DN<0>")
		)
		(pad "153" smd rect
			(at 4.59994 6.800088 90)
			(size 1.8034 0.508)
			(layers "F.Cu" "F.Mask" "F.Paste")
			(net "M_M_DQS_DP<0>")
		)
		(pad "154" smd rect
			(at 4.59994 7.649972 90)
			(size 1.8034 0.508)
			(layers "F.Cu" "F.Mask" "F.Paste")
			(net "GND")
		)
		(pad "155" smd rect
			(at 4.59994 8.50011 90)
			(size 1.8034 0.508)
			(layers "F.Cu" "F.Mask" "F.Paste")
			(net "M_M_DQ<6>")
		)
		(pad "156" smd rect
			(at 4.59994 9.349994 90)
			(size 1.8034 0.508)
			(layers "F.Cu" "F.Mask" "F.Paste")
			(net "GND")
		)
		(pad "157" smd rect
			(at 4.59994 10.199878 90)
			(size 1.8034 0.508)
			(layers "F.Cu" "F.Mask" "F.Paste")
			(net "M_M_DQ<2>")
		)
		(pad "158" smd rect
			(at 4.59994 11.050016 90)
			(size 1.8034 0.508)
			(layers "F.Cu" "F.Mask" "F.Paste")
			(net "GND")
		)
		(pad "159" smd rect
			(at 4.59994 11.8999 90)
			(size 1.8034 0.508)
			(layers "F.Cu" "F.Mask" "F.Paste")
			(net "M_M_DQ<12>")
		)
		(pad "160" smd rect
			(at 4.59994 12.750038 90)
			(size 1.8034 0.508)
			(layers "F.Cu" "F.Mask" "F.Paste")
			(net "GND")
		)
		(pad "161" smd rect
			(at 4.59994 13.599922 90)
			(size 1.8034 0.508)
			(layers "F.Cu" "F.Mask" "F.Paste")
			(net "M_M_DQ<8>")
		)
		(pad "162" smd rect
			(at 4.59994 14.45006 90)
			(size 1.8034 0.508)
			(layers "F.Cu" "F.Mask" "F.Paste")
			(net "GND")
		)
		(pad "163" smd rect
			(at 4.59994 15.299944 90)
			(size 1.8034 0.508)
			(layers "F.Cu" "F.Mask" "F.Paste")
			(net "M_M_DQS_DN<1>")
		)
		(pad "164" smd rect
			(at 4.59994 16.150082 90)
			(size 1.8034 0.508)
			(layers "F.Cu" "F.Mask" "F.Paste")
			(net "M_M_DQS_DP<1>")
		)
		(pad "165" smd rect
			(at 4.59994 16.999966 90)
			(size 1.8034 0.508)
			(layers "F.Cu" "F.Mask" "F.Paste")
			(net "GND")
		)
		(pad "166" smd rect
			(at 4.59994 17.850104 90)
			(size 1.8034 0.508)
			(layers "F.Cu" "F.Mask" "F.Paste")
			(net "M_M_DQ<14>")
		)
		(pad "167" smd rect
			(at 4.59994 18.699988 90)
			(size 1.8034 0.508)
			(layers "F.Cu" "F.Mask" "F.Paste")
			(net "GND")
		)
		(pad "168" smd rect
			(at 4.59994 19.550126 90)
			(size 1.8034 0.508)
			(layers "F.Cu" "F.Mask" "F.Paste")
			(net "M_M_DQ<10>")
		)
		(pad "169" smd rect
			(at 4.59994 20.40001 90)
			(size 1.8034 0.508)
			(layers "F.Cu" "F.Mask" "F.Paste")
			(net "GND")
		)
		(pad "170" smd rect
			(at 4.59994 21.249894 90)
			(size 1.8034 0.508)
			(layers "F.Cu" "F.Mask" "F.Paste")
			(net "M_M_DQ<20>")
		)
		(pad "171" smd rect
			(at 4.59994 22.100032 90)
			(size 1.8034 0.508)
			(layers "F.Cu" "F.Mask" "F.Paste")
			(net "GND")
		)
		(pad "172" smd rect
			(at 4.59994 22.949916 90)
			(size 1.8034 0.508)
			(layers "F.Cu" "F.Mask" "F.Paste")
			(net "M_M_DQ<16>")
		)
		(pad "173" smd rect
			(at 4.59994 23.800054 90)
			(size 1.8034 0.508)
			(layers "F.Cu" "F.Mask" "F.Paste")
			(net "GND")
		)
		(pad "174" smd rect
			(at 4.59994 24.649938 90)
			(size 1.8034 0.508)
			(layers "F.Cu" "F.Mask" "F.Paste")
			(net "M_M_DQS_DN<2>")
		)
		(pad "175" smd rect
			(at 4.59994 25.500076 90)
			(size 1.8034 0.508)
			(layers "F.Cu" "F.Mask" "F.Paste")
			(net "M_M_DQS_DP<2>")
		)
		(pad "176" smd rect
			(at 4.59994 26.34996 90)
			(size 1.8034 0.508)
			(layers "F.Cu" "F.Mask" "F.Paste")
			(net "GND")
		)
		(pad "177" smd rect
			(at 4.59994 27.200098 90)
			(size 1.8034 0.508)
			(layers "F.Cu" "F.Mask" "F.Paste")
			(net "M_M_DQ<22>")
		)
		(pad "178" smd rect
			(at 4.59994 28.049982 90)
			(size 1.8034 0.508)
			(layers "F.Cu" "F.Mask" "F.Paste")
			(net "GND")
		)
		(pad "179" smd rect
			(at 4.59994 28.90012 90)
			(size 1.8034 0.508)
			(layers "F.Cu" "F.Mask" "F.Paste")
			(net "M_M_DQ<18>")
		)
		(pad "180" smd rect
			(at 4.59994 29.750004 90)
			(size 1.8034 0.508)
			(layers "F.Cu" "F.Mask" "F.Paste")
			(net "GND")
		)
		(pad "181" smd rect
			(at 4.59994 30.599888 90)
			(size 1.8034 0.508)
			(layers "F.Cu" "F.Mask" "F.Paste")
			(net "M_M_DQ<28>")
		)
		(pad "182" smd rect
			(at 4.59994 31.450026 90)
			(size 1.8034 0.508)
			(layers "F.Cu" "F.Mask" "F.Paste")
			(net "GND")
		)
		(pad "183" smd rect
			(at 4.59994 32.29991 90)
			(size 1.8034 0.508)
			(layers "F.Cu" "F.Mask" "F.Paste")
			(net "M_M_DQ<24>")
		)
		(pad "184" smd rect
			(at 4.59994 33.150048 90)
			(size 1.8034 0.508)
			(layers "F.Cu" "F.Mask" "F.Paste")
			(net "GND")
		)
		(pad "185" smd rect
			(at 4.59994 33.999932 90)
			(size 1.8034 0.508)
			(layers "F.Cu" "F.Mask" "F.Paste")
			(net "M_M_DQS_DN<3>")
		)
		(pad "186" smd rect
			(at 4.59994 34.85007 90)
			(size 1.8034 0.508)
			(layers "F.Cu" "F.Mask" "F.Paste")
			(net "M_M_DQS_DP<3>")
		)
		(pad "187" smd rect
			(at 4.59994 35.699954 90)
			(size 1.8034 0.508)
			(layers "F.Cu" "F.Mask" "F.Paste")
			(net "GND")
		)
		(pad "188" smd rect
			(at 4.59994 36.550092 90)
			(size 1.8034 0.508)
			(layers "F.Cu" "F.Mask" "F.Paste")
			(net "M_M_DQ<30>")
		)
		(pad "189" smd rect
			(at 4.59994 37.399976 90)
			(size 1.8034 0.508)
			(layers "F.Cu" "F.Mask" "F.Paste")
			(net "GND")
		)
		(pad "190" smd rect
			(at 4.59994 38.250114 90)
			(size 1.8034 0.508)
			(layers "F.Cu" "F.Mask" "F.Paste")
			(net "M_M_DQ<26>")
		)
		(pad "191" smd rect
			(at 4.59994 39.099998 90)
			(size 1.8034 0.508)
			(layers "F.Cu" "F.Mask" "F.Paste")
			(net "GND")
		)
		(pad "192" smd rect
			(at 4.59994 39.949882 90)
			(size 1.8034 0.508)
			(layers "F.Cu" "F.Mask" "F.Paste")
			(net "M_M_ECC<4>")
		)
		(pad "193" smd rect
			(at 4.59994 40.80002 90)
			(size 1.8034 0.508)
			(layers "F.Cu" "F.Mask" "F.Paste")
			(net "GND")
		)
		(pad "194" smd rect
			(at 4.59994 41.649904 90)
			(size 1.8034 0.508)
			(layers "F.Cu" "F.Mask" "F.Paste")
			(net "M_M_ECC<0>")
		)
		(pad "195" smd rect
			(at 4.59994 42.500042 90)
			(size 1.8034 0.508)
			(layers "F.Cu" "F.Mask" "F.Paste")
			(net "GND")
		)
		(pad "196" smd rect
			(at 4.59994 43.349926 90)
			(size 1.8034 0.508)
			(layers "F.Cu" "F.Mask" "F.Paste")
			(net "M_M_DQS_DN<8>")
		)
		(pad "197" smd rect
			(at 4.59994 44.200064 90)
			(size 1.8034 0.508)
			(layers "F.Cu" "F.Mask" "F.Paste")
			(net "M_M_DQS_DP<8>")
		)
		(pad "198" smd rect
			(at 4.59994 45.049948 90)
			(size 1.8034 0.508)
			(layers "F.Cu" "F.Mask" "F.Paste")
			(net "GND")
		)
		(pad "199" smd rect
			(at 4.59994 45.900086 90)
			(size 1.8034 0.508)
			(layers "F.Cu" "F.Mask" "F.Paste")
			(net "M_M_ECC<6>")
		)
		(pad "200" smd rect
			(at 4.59994 46.74997 90)
			(size 1.8034 0.508)
			(layers "F.Cu" "F.Mask" "F.Paste")
			(net "GND")
		)
		(pad "201" smd rect
			(at 4.59994 47.600108 90)
			(size 1.8034 0.508)
			(layers "F.Cu" "F.Mask" "F.Paste")
			(net "M_M_ECC<2>")
		)
		(pad "202" smd rect
			(at 4.59994 48.449992 90)
			(size 1.8034 0.508)
			(layers "F.Cu" "F.Mask" "F.Paste")
			(net "GND")
		)
		(pad "203" smd rect
			(at 4.59994 49.299876 90)
			(size 1.8034 0.508)
			(layers "F.Cu" "F.Mask" "F.Paste")
			(net "M_M_CKE<1>")
		)
		(pad "204" smd rect
			(at 4.59994 50.150014 90)
			(size 1.8034 0.508)
			(layers "F.Cu" "F.Mask" "F.Paste")
			(net "PVDDQ_KLM")
		)
		(pad "205" smd rect
			(at 4.59994 50.999898 90)
			(size 1.8034 0.508)
			(layers "F.Cu" "F.Mask" "F.Paste")
			(net "TP_CH_M_DIMM_M0_RFU_0")
		)
		(pad "206" smd rect
			(at 4.59994 51.850036 90)
			(size 1.8034 0.508)
			(layers "F.Cu" "F.Mask" "F.Paste")
			(net "PVDDQ_KLM")
		)
		(pad "207" smd rect
			(at 4.59994 52.69992 90)
			(size 1.8034 0.508)
			(layers "F.Cu" "F.Mask" "F.Paste")
			(net "M_M_BG<1>")
		)
		(pad "208" smd rect
			(at 4.59994 53.550058 90)
			(size 1.8034 0.508)
			(layers "F.Cu" "F.Mask" "F.Paste")
			(net "M_M_ALERT_N")
		)
		(pad "209" smd rect
			(at 4.59994 54.399942 90)
			(size 1.8034 0.508)
			(layers "F.Cu" "F.Mask" "F.Paste")
			(net "PVDDQ_KLM")
		)
		(pad "210" smd rect
			(at 4.59994 55.25008 90)
			(size 1.8034 0.508)
			(layers "F.Cu" "F.Mask" "F.Paste")
			(net "M_M_MA<11>")
		)
		(pad "211" smd rect
			(at 4.59994 56.099964 90)
			(size 1.8034 0.508)
			(layers "F.Cu" "F.Mask" "F.Paste")
			(net "M_M_MA<7>")
		)
		(pad "212" smd rect
			(at 4.59994 56.950102 90)
			(size 1.8034 0.508)
			(layers "F.Cu" "F.Mask" "F.Paste")
			(net "PVDDQ_KLM")
		)
		(pad "213" smd rect
			(at 4.59994 57.799986 90)
			(size 1.8034 0.508)
			(layers "F.Cu" "F.Mask" "F.Paste")
			(net "M_M_MA<5>")
		)
		(pad "214" smd rect
			(at 4.59994 58.650124 90)
			(size 1.8034 0.508)
			(layers "F.Cu" "F.Mask" "F.Paste")
			(net "M_M_MA<4>")
		)
		(pad "215" smd rect
			(at 4.59994 59.500008 90)
			(size 1.8034 0.508)
			(layers "F.Cu" "F.Mask" "F.Paste")
			(net "PVDDQ_KLM")
		)
		(pad "216" smd rect
			(at 4.59994 60.349892 90)
			(size 1.8034 0.508)
			(layers "F.Cu" "F.Mask" "F.Paste")
			(net "M_M_MA<2>")
		)
		(pad "217" smd rect
			(at 4.59994 61.20003 90)
			(size 1.8034 0.508)
			(layers "F.Cu" "F.Mask" "F.Paste")
			(net "PVDDQ_KLM")
		)
		(pad "218" smd rect
			(at 4.59994 62.049914 90)
			(size 1.8034 0.508)
			(layers "F.Cu" "F.Mask" "F.Paste")
			(net "M_M_CLK_DP<1>")
		)
		(pad "219" smd rect
			(at 4.59994 62.900052 90)
			(size 1.8034 0.508)
			(layers "F.Cu" "F.Mask" "F.Paste")
			(net "M_M_CLK_DN<1>")
		)
		(pad "220" smd rect
			(at 4.59994 63.749936 90)
			(size 1.8034 0.508)
			(layers "F.Cu" "F.Mask" "F.Paste")
			(net "PVDDQ_KLM")
		)
		(pad "221" smd rect
			(at 4.59994 64.600074 90)
			(size 1.8034 0.508)
			(layers "F.Cu" "F.Mask" "F.Paste")
			(net "PVTT_KLM")
		)
		(pad "222" smd rect
			(at 4.59994 70.550024 90)
			(size 1.8034 0.508)
			(layers "F.Cu" "F.Mask" "F.Paste")
			(net "M_M_PAR")
		)
		(pad "223" smd rect
			(at 4.59994 71.399908 90)
			(size 1.8034 0.508)
			(layers "F.Cu" "F.Mask" "F.Paste")
			(net "PVDDQ_KLM")
		)
		(pad "224" smd rect
			(at 4.59994 72.250046 90)
			(size 1.8034 0.508)
			(layers "F.Cu" "F.Mask" "F.Paste")
			(net "M_M_BA<1>")
		)
		(pad "225" smd rect
			(at 4.59994 73.09993 90)
			(size 1.8034 0.508)
			(layers "F.Cu" "F.Mask" "F.Paste")
			(net "M_M_MA<10>")
		)
		(pad "226" smd rect
			(at 4.59994 73.950068 90)
			(size 1.8034 0.508)
			(layers "F.Cu" "F.Mask" "F.Paste")
			(net "PVDDQ_KLM")
		)
		(pad "227" smd rect
			(at 4.59994 74.799952 90)
			(size 1.8034 0.508)
			(layers "F.Cu" "F.Mask" "F.Paste")
			(net "TP_CH_M_DIMM_M0_RFU_1")
		)
		(pad "228" smd rect
			(at 4.59994 75.65009 90)
			(size 1.8034 0.508)
			(layers "F.Cu" "F.Mask" "F.Paste")
			(net "M_M_MA<14>")
		)
		(pad "229" smd rect
			(at 4.59994 76.499974 90)
			(size 1.8034 0.508)
			(layers "F.Cu" "F.Mask" "F.Paste")
			(net "PVDDQ_KLM")
		)
		(pad "230" smd rect
			(at 4.59994 77.350112 90)
			(size 1.8034 0.508)
			(layers "F.Cu" "F.Mask" "F.Paste")
			(net "FM_ADR_COMPLETE_KLM_N")
		)
		(pad "231" smd rect
			(at 4.59994 78.199996 90)
			(size 1.8034 0.508)
			(layers "F.Cu" "F.Mask" "F.Paste")
			(net "PVDDQ_KLM")
		)
		(pad "232" smd rect
			(at 4.59994 79.04988 90)
			(size 1.8034 0.508)
			(layers "F.Cu" "F.Mask" "F.Paste")
			(net "M_M_MA<13>")
		)
		(pad "233" smd rect
			(at 4.59994 79.900018 90)
			(size 1.8034 0.508)
			(layers "F.Cu" "F.Mask" "F.Paste")
			(net "PVDDQ_KLM")
		)
		(pad "234" smd rect
			(at 4.59994 80.749902 90)
			(size 1.8034 0.508)
			(layers "F.Cu" "F.Mask" "F.Paste")
			(net "M_M_MA<17>")
		)
		(pad "235" smd rect
			(at 4.59994 81.60004 90)
			(size 1.8034 0.508)
			(layers "F.Cu" "F.Mask" "F.Paste")
			(net "M_M_C<2>")
		)
		(pad "236" smd rect
			(at 4.59994 82.449924 90)
			(size 1.8034 0.508)
			(layers "F.Cu" "F.Mask" "F.Paste")
			(net "PVDDQ_KLM")
		)
		(pad "237" smd rect
			(at 4.59994 83.300062 90)
			(size 1.8034 0.508)
			(layers "F.Cu" "F.Mask" "F.Paste")
			(net "M_M_CS_N<3>")
		)
		(pad "238" smd rect
			(at 4.59994 84.149946 90)
			(size 1.8034 0.508)
			(layers "F.Cu" "F.Mask" "F.Paste")
			(net "PVPP_KLM")
		)
		(pad "239" smd rect
			(at 4.59994 85.000084 90)
			(size 1.8034 0.508)
			(layers "F.Cu" "F.Mask" "F.Paste")
			(net "GND")
		)
		(pad "240" smd rect
			(at 4.59994 85.849968 90)
			(size 1.8034 0.508)
			(layers "F.Cu" "F.Mask" "F.Paste")
			(net "M_M_DQ<36>")
		)
		(pad "241" smd rect
			(at 4.59994 86.700106 90)
			(size 1.8034 0.508)
			(layers "F.Cu" "F.Mask" "F.Paste")
			(net "GND")
		)
		(pad "242" smd rect
			(at 4.59994 87.54999 90)
			(size 1.8034 0.508)
			(layers "F.Cu" "F.Mask" "F.Paste")
			(net "M_M_DQ<32>")
		)
		(pad "243" smd rect
			(at 4.59994 88.399874 90)
			(size 1.8034 0.508)
			(layers "F.Cu" "F.Mask" "F.Paste")
			(net "GND")
		)
		(pad "244" smd rect
			(at 4.59994 89.250012 90)
			(size 1.8034 0.508)
			(layers "F.Cu" "F.Mask" "F.Paste")
			(net "M_M_DQS_DN<4>")
		)
		(pad "245" smd rect
			(at 4.59994 90.099896 90)
			(size 1.8034 0.508)
			(layers "F.Cu" "F.Mask" "F.Paste")
			(net "M_M_DQS_DP<4>")
		)
		(pad "246" smd rect
			(at 4.59994 90.950034 90)
			(size 1.8034 0.508)
			(layers "F.Cu" "F.Mask" "F.Paste")
			(net "GND")
		)
		(pad "247" smd rect
			(at 4.59994 91.799918 90)
			(size 1.8034 0.508)
			(layers "F.Cu" "F.Mask" "F.Paste")
			(net "M_M_DQ<38>")
		)
		(pad "248" smd rect
			(at 4.59994 92.650056 90)
			(size 1.8034 0.508)
			(layers "F.Cu" "F.Mask" "F.Paste")
			(net "GND")
		)
		(pad "249" smd rect
			(at 4.59994 93.49994 90)
			(size 1.8034 0.508)
			(layers "F.Cu" "F.Mask" "F.Paste")
			(net "M_M_DQ<34>")
		)
		(pad "250" smd rect
			(at 4.59994 94.350078 90)
			(size 1.8034 0.508)
			(layers "F.Cu" "F.Mask" "F.Paste")
			(net "GND")
		)
		(pad "251" smd rect
			(at 4.59994 95.199962 90)
			(size 1.8034 0.508)
			(layers "F.Cu" "F.Mask" "F.Paste")
			(net "M_M_DQ<44>")
		)
		(pad "252" smd rect
			(at 4.59994 96.0501 90)
			(size 1.8034 0.508)
			(layers "F.Cu" "F.Mask" "F.Paste")
			(net "GND")
		)
		(pad "253" smd rect
			(at 4.59994 96.899984 90)
			(size 1.8034 0.508)
			(layers "F.Cu" "F.Mask" "F.Paste")
			(net "M_M_DQ<40>")
		)
		(pad "254" smd rect
			(at 4.59994 97.750122 90)
			(size 1.8034 0.508)
			(layers "F.Cu" "F.Mask" "F.Paste")
			(net "GND")
		)
		(pad "255" smd rect
			(at 4.59994 98.600006 90)
			(size 1.8034 0.508)
			(layers "F.Cu" "F.Mask" "F.Paste")
			(net "M_M_DQS_DN<5>")
		)
		(pad "256" smd rect
			(at 4.59994 99.44989 90)
			(size 1.8034 0.508)
			(layers "F.Cu" "F.Mask" "F.Paste")
			(net "M_M_DQS_DP<5>")
		)
		(pad "257" smd rect
			(at 4.59994 100.300028 90)
			(size 1.8034 0.508)
			(layers "F.Cu" "F.Mask" "F.Paste")
			(net "GND")
		)
		(pad "258" smd rect
			(at 4.59994 101.149912 90)
			(size 1.8034 0.508)
			(layers "F.Cu" "F.Mask" "F.Paste")
			(net "M_M_DQ<46>")
		)
		(pad "259" smd rect
			(at 4.59994 102.00005 90)
			(size 1.8034 0.508)
			(layers "F.Cu" "F.Mask" "F.Paste")
			(net "GND")
		)
		(pad "260" smd rect
			(at 4.59994 102.849934 90)
			(size 1.8034 0.508)
			(layers "F.Cu" "F.Mask" "F.Paste")
			(net "M_M_DQ<42>")
		)
		(pad "261" smd rect
			(at 4.59994 103.700072 90)
			(size 1.8034 0.508)
			(layers "F.Cu" "F.Mask" "F.Paste")
			(net "GND")
		)
		(pad "262" smd rect
			(at 4.59994 104.549956 90)
			(size 1.8034 0.508)
			(layers "F.Cu" "F.Mask" "F.Paste")
			(net "M_M_DQ<52>")
		)
		(pad "263" smd rect
			(at 4.59994 105.400094 90)
			(size 1.8034 0.508)
			(layers "F.Cu" "F.Mask" "F.Paste")
			(net "GND")
		)
		(pad "264" smd rect
			(at 4.59994 106.249978 90)
			(size 1.8034 0.508)
			(layers "F.Cu" "F.Mask" "F.Paste")
			(net "M_M_DQ<48>")
		)
		(pad "265" smd rect
			(at 4.59994 107.100116 90)
			(size 1.8034 0.508)
			(layers "F.Cu" "F.Mask" "F.Paste")
			(net "GND")
		)
		(pad "266" smd rect
			(at 4.59994 107.95 90)
			(size 1.8034 0.508)
			(layers "F.Cu" "F.Mask" "F.Paste")
			(net "M_M_DQS_DN<6>")
		)
		(pad "267" smd rect
			(at 4.59994 108.799884 90)
			(size 1.8034 0.508)
			(layers "F.Cu" "F.Mask" "F.Paste")
			(net "M_M_DQS_DP<6>")
		)
		(pad "268" smd rect
			(at 4.59994 109.650022 90)
			(size 1.8034 0.508)
			(layers "F.Cu" "F.Mask" "F.Paste")
			(net "GND")
		)
		(pad "269" smd rect
			(at 4.59994 110.499906 90)
			(size 1.8034 0.508)
			(layers "F.Cu" "F.Mask" "F.Paste")
			(net "M_M_DQ<54>")
		)
		(pad "270" smd rect
			(at 4.59994 111.350044 90)
			(size 1.8034 0.508)
			(layers "F.Cu" "F.Mask" "F.Paste")
			(net "GND")
		)
		(pad "271" smd rect
			(at 4.59994 112.199928 90)
			(size 1.8034 0.508)
			(layers "F.Cu" "F.Mask" "F.Paste")
			(net "M_M_DQ<50>")
		)
		(pad "272" smd rect
			(at 4.59994 113.050066 90)
			(size 1.8034 0.508)
			(layers "F.Cu" "F.Mask" "F.Paste")
			(net "GND")
		)
		(pad "273" smd rect
			(at 4.59994 113.89995 90)
			(size 1.8034 0.508)
			(layers "F.Cu" "F.Mask" "F.Paste")
			(net "M_M_DQ<60>")
		)
		(pad "274" smd rect
			(at 4.59994 114.750088 90)
			(size 1.8034 0.508)
			(layers "F.Cu" "F.Mask" "F.Paste")
			(net "GND")
		)
		(pad "275" smd rect
			(at 4.59994 115.599972 90)
			(size 1.8034 0.508)
			(layers "F.Cu" "F.Mask" "F.Paste")
			(net "M_M_DQ<56>")
		)
		(pad "276" smd rect
			(at 4.59994 116.45011 90)
			(size 1.8034 0.508)
			(layers "F.Cu" "F.Mask" "F.Paste")
			(net "GND")
		)
		(pad "277" smd rect
			(at 4.59994 117.299994 90)
			(size 1.8034 0.508)
			(layers "F.Cu" "F.Mask" "F.Paste")
			(net "M_M_DQS_DN<7>")
		)
		(pad "278" smd rect
			(at 4.59994 118.149878 90)
			(size 1.8034 0.508)
			(layers "F.Cu" "F.Mask" "F.Paste")
			(net "M_M_DQS_DP<7>")
		)
		(pad "279" smd rect
			(at 4.59994 119.000016 90)
			(size 1.8034 0.508)
			(layers "F.Cu" "F.Mask" "F.Paste")
			(net "GND")
		)
		(pad "280" smd rect
			(at 4.59994 119.8499 90)
			(size 1.8034 0.508)
			(layers "F.Cu" "F.Mask" "F.Paste")
			(net "M_M_DQ<62>")
		)
		(pad "281" smd rect
			(at 4.59994 120.700038 90)
			(size 1.8034 0.508)
			(layers "F.Cu" "F.Mask" "F.Paste")
			(net "GND")
		)
		(pad "282" smd rect
			(at 4.59994 121.549922 90)
			(size 1.8034 0.508)
			(layers "F.Cu" "F.Mask" "F.Paste")
			(net "M_M_DQ<58>")
		)
		(pad "283" smd rect
			(at 4.59994 122.40006 90)
			(size 1.8034 0.508)
			(layers "F.Cu" "F.Mask" "F.Paste")
			(net "GND")
		)
		(pad "284" smd rect
			(at 4.59994 123.249944 90)
			(size 1.8034 0.508)
			(layers "F.Cu" "F.Mask" "F.Paste")
			(net "PVPP_KLM")
		)
		(pad "285" smd rect
			(at 4.59994 124.100082 90)
			(size 1.8034 0.508)
			(layers "F.Cu" "F.Mask" "F.Paste")
			(net "SMB_DDR_KLM_VPP_SDA")
		)
		(pad "286" smd rect
			(at 4.59994 124.949966 90)
			(size 1.8034 0.508)
			(layers "F.Cu" "F.Mask" "F.Paste")
			(net "PVPP_KLM")
		)
		(pad "287" smd rect
			(at 4.59994 125.800104 90)
			(size 1.8034 0.508)
			(layers "F.Cu" "F.Mask" "F.Paste")
			(net "PVPP_KLM")
		)
		(pad "288" smd rect
			(at 4.59994 126.649988 90)
			(size 1.8034 0.508)
			(layers "F.Cu" "F.Mask" "F.Paste")
			(net "PVPP_KLM")
		)
	)
	(footprint ""
		(layer "F.Cu")
		(at 335.788 -23.241)
		(property "Reference" "R7F17"
			(at 0 0 0)
			(layer "F.SilkS")
			(hide yes)
			(effects
				(font
					(size 1.27 1.27)
				)
			)
		)
		(property "Value" ""
			(at 0 0 0)
			(layer "F.Fab")
			(effects
				(font
					(size 1.27 1.27)
				)
			)
		)
		(duplicate_pad_numbers_are_jumpers no)
		(fp_poly
			(pts
				(xy -0.2794 -0.1016) (xy 0.2794 -0.1016) (xy 0.2794 0.9906) (xy -0.2794 0.9906)
			)
			(stroke
				(width 0)
				(type default)
			)
			(fill no)
			(layer "F.CrtYd")
		)
		(fp_line
			(start -0.2794 -0.1016)
			(end -0.2794 0.9906)
			(stroke
				(width 0.1)
				(type default)
			)
			(layer "F.Fab")
		)
		(fp_line
			(start -0.2794 0.9906)
			(end 0.2794 0.9906)
			(stroke
				(width 0.1)
				(type default)
			)
			(layer "F.Fab")
		)
		(fp_line
			(start 0.2794 -0.1016)
			(end -0.2794 -0.1016)
			(stroke
				(width 0.1)
				(type default)
			)
			(layer "F.Fab")
		)
		(fp_line
			(start 0.2794 0.9906)
			(end 0.2794 -0.1016)
			(stroke
				(width 0.1)
				(type default)
			)
			(layer "F.Fab")
		)
		(pad "1" smd rect
			(at 0 0)
			(size 0.508 0.508)
			(layers "F.Cu" "F.Mask" "F.Paste")
			(net "VSENSE_PVPP_ABC")
		)
		(pad "2" smd rect
			(at 0 0.889)
			(size 0.508 0.508)
			(layers "F.Cu" "F.Mask" "F.Paste")
			(net "VR_COMP_PVPP_ABC")
		)
		(zone
			(layer "F.Cu")
			(hatch none 0.5)
			(connect_pads
				(clearance 0)
			)
			(min_thickness 0.25)
			(keepout
				(tracks allowed)
				(vias not_allowed)
				(pads allowed)
				(copperpour not_allowed)
				(footprints allowed)
			)
			(placement
				(enabled no)
				(sheetname "")
			)
			(fill
				(thermal_gap 0.5)
				(thermal_bridge_width 0.5)
				(island_removal_mode 0)
			)
			(polygon
				(pts
					(xy 335.534 -22.987) (xy 336.042 -22.987) (xy 336.042 -22.606) (xy 335.534 -22.606)
				)
			)
		)
		(zone
			(layer "F.Cu")
			(hatch none 0.5)
			(connect_pads
				(clearance 0)
			)
			(min_thickness 0.25)
			(keepout
				(tracks not_allowed)
				(vias allowed)
				(pads allowed)
				(copperpour not_allowed)
				(footprints allowed)
			)
			(placement
				(enabled no)
				(sheetname "")
			)
			(fill
				(thermal_gap 0.5)
				(thermal_bridge_width 0.5)
				(island_removal_mode 0)
			)
			(polygon
				(pts
					(xy 335.534 -22.606) (xy 336.042 -22.606) (xy 336.042 -22.987) (xy 335.534 -22.987)
				)
			)
		)
	)
	(footprint ""
		(layer "F.Cu")
		(at 467.36 -132.715 180)
		(property "Reference" "R9B12"
			(at 0 0 180)
			(layer "F.SilkS")
			(hide yes)
			(effects
				(font
					(size 1.27 1.27)
				)
			)
		)
		(property "Value" ""
			(at 0 0 180)
			(layer "F.Fab")
			(effects
				(font
					(size 1.27 1.27)
				)
			)
		)
		(duplicate_pad_numbers_are_jumpers no)
		(fp_poly
			(pts
				(xy -0.2794 -0.1016) (xy 0.2794 -0.1016) (xy 0.2794 0.9906) (xy -0.2794 0.9906)
			)
			(stroke
				(width 0)
				(type default)
			)
			(fill no)
			(layer "F.CrtYd")
		)
		(fp_line
			(start 0.2794 0.9906)
			(end 0.2794 -0.1016)
			(stroke
				(width 0.1)
				(type default)
			)
			(layer "F.Fab")
		)
		(fp_line
			(start 0.2794 -0.1016)
			(end -0.2794 -0.1016)
			(stroke
				(width 0.1)
				(type default)
			)
			(layer "F.Fab")
		)
		(fp_line
			(start -0.2794 0.9906)
			(end 0.2794 0.9906)
			(stroke
				(width 0.1)
				(type default)
			)
			(layer "F.Fab")
		)
		(fp_line
			(start -0.2794 -0.1016)
			(end -0.2794 0.9906)
			(stroke
				(width 0.1)
				(type default)
			)
			(layer "F.Fab")
		)
		(pad "1" smd rect
			(at 0 0 180)
			(size 0.508 0.508)
			(layers "F.Cu" "F.Mask" "F.Paste")
			(net "P1V8_MCP_CPU0")
		)
		(pad "2" smd rect
			(at 0 0.889 180)
			(size 0.508 0.508)
			(layers "F.Cu" "F.Mask" "F.Paste")
			(net "JTAG_MCP_MUX_TDO")
		)
		(zone
			(layer "F.Cu")
			(hatch none 0.5)
			(connect_pads
				(clearance 0)
			)
			(min_thickness 0.25)
			(keepout
				(tracks not_allowed)
				(vias allowed)
				(pads allowed)
				(copperpour not_allowed)
				(footprints allowed)
			)
			(placement
				(enabled no)
				(sheetname "")
			)
			(fill
				(thermal_gap 0.5)
				(thermal_bridge_width 0.5)
				(island_removal_mode 0)
			)
			(polygon
				(pts
					(xy 467.614 -133.35) (xy 467.106 -133.35) (xy 467.106 -132.969) (xy 467.614 -132.969)
				)
			)
		)
		(zone
			(layer "F.Cu")
			(hatch none 0.5)
			(connect_pads
				(clearance 0)
			)
			(min_thickness 0.25)
			(keepout
				(tracks allowed)
				(vias not_allowed)
				(pads allowed)
				(copperpour not_allowed)
				(footprints allowed)
			)
			(placement
				(enabled no)
				(sheetname "")
			)
			(fill
				(thermal_gap 0.5)
				(thermal_bridge_width 0.5)
				(island_removal_mode 0)
			)
			(polygon
				(pts
					(xy 467.614 -132.969) (xy 467.106 -132.969) (xy 467.106 -133.35) (xy 467.614 -133.35)
				)
			)
		)
	)
	(footprint ""
		(layer "F.Cu")
		(at 437.388 -19.4945)
		(property "Reference" "R10W1"
			(at -0.8382 -0.67818 0)
			(unlocked yes)
			(layer "F.SilkS")
			(effects
				(font
					(size 0.4064 0.254)
					(thickness 0.1524)
				)
				(justify left)
			)
		)
		(property "Value" ""
			(at 0 0 0)
			(layer "F.Fab")
			(effects
				(font
					(size 1.27 1.27)
				)
			)
		)
		(duplicate_pad_numbers_are_jumpers no)
		(fp_poly
			(pts
				(xy -0.2794 -0.1016) (xy 0.2794 -0.1016) (xy 0.2794 0.9906) (xy -0.2794 0.9906)
			)
			(stroke
				(width 0)
				(type default)
			)
			(fill no)
			(layer "F.CrtYd")
		)
		(fp_line
			(start -0.2794 -0.1016)
			(end -0.2794 0.9906)
			(stroke
				(width 0.1)
				(type default)
			)
			(layer "F.Fab")
		)
		(fp_line
			(start -0.2794 0.9906)
			(end 0.2794 0.9906)
			(stroke
				(width 0.1)
				(type default)
			)
			(layer "F.Fab")
		)
		(fp_line
			(start 0.2794 -0.1016)
			(end -0.2794 -0.1016)
			(stroke
				(width 0.1)
				(type default)
			)
			(layer "F.Fab")
		)
		(fp_line
			(start 0.2794 0.9906)
			(end 0.2794 -0.1016)
			(stroke
				(width 0.1)
				(type default)
			)
			(layer "F.Fab")
		)
		(pad "1" smd rect
			(at 0 0)
			(size 0.508 0.508)
			(layers "F.Cu" "F.Mask" "F.Paste")
			(net "PUMP_TACH0")
		)
		(pad "2" smd rect
			(at 0 0.889)
			(size 0.508 0.508)
			(layers "F.Cu" "F.Mask" "F.Paste")
			(net "PUMP_TACH_R")
		)
		(zone
			(layer "F.Cu")
			(hatch none 0.5)
			(connect_pads
				(clearance 0)
			)
			(min_thickness 0.25)
			(keepout
				(tracks allowed)
				(vias not_allowed)
				(pads allowed)
				(copperpour not_allowed)
				(footprints allowed)
			)
			(placement
				(enabled no)
				(sheetname "")
			)
			(fill
				(thermal_gap 0.5)
				(thermal_bridge_width 0.5)
				(island_removal_mode 0)
			)
			(polygon
				(pts
					(xy 437.134 -19.2405) (xy 437.642 -19.2405) (xy 437.642 -18.8595) (xy 437.134 -18.8595)
				)
			)
		)
		(zone
			(layer "F.Cu")
			(hatch none 0.5)
			(connect_pads
				(clearance 0)
			)
			(min_thickness 0.25)
			(keepout
				(tracks not_allowed)
				(vias allowed)
				(pads allowed)
				(copperpour not_allowed)
				(footprints allowed)
			)
			(placement
				(enabled no)
				(sheetname "")
			)
			(fill
				(thermal_gap 0.5)
				(thermal_bridge_width 0.5)
				(island_removal_mode 0)
			)
			(polygon
				(pts
					(xy 437.134 -18.8595) (xy 437.642 -18.8595) (xy 437.642 -19.2405) (xy 437.134 -19.2405)
				)
			)
		)
	)
	(footprint ""
		(layer "F.Cu")
		(at 179.578 -67.437 -90)
		(property "Reference" "C4D42"
			(at 0 0 270)
			(layer "F.SilkS")
			(hide yes)
			(effects
				(font
					(size 1.27 1.27)
				)
			)
		)
		(property "Value" ""
			(at 0 0 270)
			(layer "F.Fab")
			(effects
				(font
					(size 1.27 1.27)
				)
			)
		)
		(duplicate_pad_numbers_are_jumpers no)
		(fp_poly
			(pts
				(xy 0.3048 -0.1016) (xy 0.3048 0.9906) (xy -0.3048 0.9906) (xy -0.3048 -0.1016)
			)
			(stroke
				(width 0)
				(type default)
			)
			(fill no)
			(layer "F.CrtYd")
		)
		(fp_line
			(start -0.3048 0.9906)
			(end 0.3048 0.9906)
			(stroke
				(width 0.1)
				(type default)
			)
			(layer "F.Fab")
		)
		(fp_line
			(start 0.3048 0.9906)
			(end 0.3048 -0.1016)
			(stroke
				(width 0.1)
				(type default)
			)
			(layer "F.Fab")
		)
		(fp_line
			(start -0.3048 -0.1016)
			(end -0.3048 0.9906)
			(stroke
				(width 0.1)
				(type default)
			)
			(layer "F.Fab")
		)
		(fp_line
			(start 0.3048 -0.1016)
			(end -0.3048 -0.1016)
			(stroke
				(width 0.1)
				(type default)
			)
			(layer "F.Fab")
		)
		(pad "1" smd rect
			(at 0 0 270)
			(size 0.508 0.508)
			(layers "F.Cu" "F.Mask" "F.Paste")
			(net "VR_VRRDY_PVCCIN_CPU0")
		)
		(pad "2" smd rect
			(at 0 0.889 270)
			(size 0.508 0.508)
			(layers "F.Cu" "F.Mask" "F.Paste")
			(net "GND")
		)
		(zone
			(layer "F.Cu")
			(hatch none 0.5)
			(connect_pads
				(clearance 0)
			)
			(min_thickness 0.25)
			(keepout
				(tracks not_allowed)
				(vias allowed)
				(pads allowed)
				(copperpour not_allowed)
				(footprints allowed)
			)
			(placement
				(enabled no)
				(sheetname "")
			)
			(fill
				(thermal_gap 0.5)
				(thermal_bridge_width 0.5)
				(island_removal_mode 0)
			)
			(polygon
				(pts
					(xy 178.943 -67.691) (xy 178.943 -67.183) (xy 179.324 -67.183) (xy 179.324 -67.691)
				)
			)
		)
		(zone
			(layer "F.Cu")
			(hatch none 0.5)
			(connect_pads
				(clearance 0)
			)
			(min_thickness 0.25)
			(keepout
				(tracks allowed)
				(vias not_allowed)
				(pads allowed)
				(copperpour not_allowed)
				(footprints allowed)
			)
			(placement
				(enabled no)
				(sheetname "")
			)
			(fill
				(thermal_gap 0.5)
				(thermal_bridge_width 0.5)
				(island_removal_mode 0)
			)
			(polygon
				(pts
					(xy 179.324 -67.691) (xy 179.324 -67.183) (xy 178.943 -67.183) (xy 178.943 -67.691)
				)
			)
		)
	)
	(footprint ""
		(layer "F.Cu")
		(at 24.03602 -89.7509 180)
		(property "Reference" "RF9"
			(at -0.8382 -0.67818 180)
			(unlocked yes)
			(layer "F.SilkS")
			(effects
				(font
					(size 0.4064 0.254)
					(thickness 0.1524)
				)
				(justify left)
			)
		)
		(property "Value" ""
			(at 0 0 180)
			(layer "F.Fab")
			(effects
				(font
					(size 1.27 1.27)
				)
			)
		)
		(duplicate_pad_numbers_are_jumpers no)
		(fp_poly
			(pts
				(xy -0.2794 -0.1016) (xy 0.2794 -0.1016) (xy 0.2794 0.9906) (xy -0.2794 0.9906)
			)
			(stroke
				(width 0)
				(type default)
			)
			(fill no)
			(layer "F.CrtYd")
		)
		(fp_line
			(start 0.2794 0.9906)
			(end 0.2794 -0.1016)
			(stroke
				(width 0.1)
				(type default)
			)
			(layer "F.Fab")
		)
		(fp_line
			(start 0.2794 -0.1016)
			(end -0.2794 -0.1016)
			(stroke
				(width 0.1)
				(type default)
			)
			(layer "F.Fab")
		)
		(fp_line
			(start -0.2794 0.9906)
			(end 0.2794 0.9906)
			(stroke
				(width 0.1)
				(type default)
			)
			(layer "F.Fab")
		)
		(fp_line
			(start -0.2794 -0.1016)
			(end -0.2794 0.9906)
			(stroke
				(width 0.1)
				(type default)
			)
			(layer "F.Fab")
		)
		(pad "1" smd rect
			(at 0 0 180)
			(size 0.508 0.508)
			(layers "F.Cu" "F.Mask" "F.Paste")
			(net "VR_PVCCIN_CPU1_AIREF3")
		)
		(pad "2" smd rect
			(at 0 0.889 180)
			(size 0.508 0.508)
			(layers "F.Cu" "F.Mask" "F.Paste")
			(net "ISENSE_PVCCIN_CPU1_PH3_IMON")
		)
		(zone
			(layer "F.Cu")
			(hatch none 0.5)
			(connect_pads
				(clearance 0)
			)
			(min_thickness 0.25)
			(keepout
				(tracks not_allowed)
				(vias allowed)
				(pads allowed)
				(copperpour not_allowed)
				(footprints allowed)
			)
			(placement
				(enabled no)
				(sheetname "")
			)
			(fill
				(thermal_gap 0.5)
				(thermal_bridge_width 0.5)
				(island_removal_mode 0)
			)
			(polygon
				(pts
					(xy 24.29002 -90.3859) (xy 23.78202 -90.3859) (xy 23.78202 -90.0049) (xy 24.29002 -90.0049)
				)
			)
		)
		(zone
			(layer "F.Cu")
			(hatch none 0.5)
			(connect_pads
				(clearance 0)
			)
			(min_thickness 0.25)
			(keepout
				(tracks allowed)
				(vias not_allowed)
				(pads allowed)
				(copperpour not_allowed)
				(footprints allowed)
			)
			(placement
				(enabled no)
				(sheetname "")
			)
			(fill
				(thermal_gap 0.5)
				(thermal_bridge_width 0.5)
				(island_removal_mode 0)
			)
			(polygon
				(pts
					(xy 24.29002 -90.0049) (xy 23.78202 -90.0049) (xy 23.78202 -90.3859) (xy 24.29002 -90.3859)
				)
			)
		)
	)
	(footprint ""
		(layer "F.Cu")
		(at -2.8702 -10.8077 -90)
		(property "Reference" "C1G12"
			(at 0 0 270)
			(layer "F.SilkS")
			(hide yes)
			(effects
				(font
					(size 1.27 1.27)
				)
			)
		)
		(property "Value" "*"
			(at -2.3114 0.10795 270)
			(unlocked yes)
			(layer "F.Fab")
			(hide yes)
			(effects
				(font
					(size 0.889 0.889)
					(thickness 0.1524)
				)
			)
		)
		(property "Device Type" "ST270U2D5VBM-GP_SMD-TCG2-ST270A"
			(at -2.3114 -1.41605 270)
			(unlocked yes)
			(layer "F.Fab")
			(hide yes)
			(effects
				(font
					(size 0.889 0.889)
					(thickness 0.1524)
				)
			)
		)
		(duplicate_pad_numbers_are_jumpers no)
		(fp_line
			(start -1.5494 0.4826)
			(end -1.5494 -0.4826)
			(stroke
				(width 0.1524)
				(type default)
			)
			(layer "F.SilkS")
		)
		(fp_line
			(start 1.5494 -0.4826)
			(end 1.5494 0.4826)
			(stroke
				(width 0.1524)
				(type default)
			)
			(layer "F.SilkS")
		)
		(fp_line
			(start -1.0922 -2.35458)
			(end 1.0922 -2.35458)
			(stroke
				(width 0.508)
				(type default)
			)
			(layer "F.SilkS")
		)
		(fp_poly
			(pts
				(xy -1.3462 1.9558) (xy -1.3462 1.905) (xy -1.5494 1.905) (xy -1.5494 -1.905) (xy -1.3462 -1.905)
				(xy -1.3462 -1.9558) (xy 1.3462 -1.9558) (xy 1.3462 -1.905) (xy 1.5494 -1.905) (xy 1.5494 1.905)
				(xy 1.3462 1.905) (xy 1.3462 1.9558)
			)
			(stroke
				(width 0)
				(type default)
			)
			(fill no)
			(layer "F.CrtYd")
		)
		(fp_poly
			(pts
				(xy -1.3462 1.9558) (xy -1.3462 1.905) (xy -1.5494 1.905) (xy -1.5494 -1.905) (xy -1.3462 -1.905)
				(xy -1.3462 -1.9558) (xy 1.3462 -1.9558) (xy 1.3462 -1.905) (xy 1.5494 -1.905) (xy 1.5494 1.905)
				(xy 1.3462 1.905) (xy 1.3462 1.9558)
			)
			(stroke
				(width 0)
				(type default)
			)
			(fill no)
			(layer "F.Fab")
		)
		(pad "1" smd rect
			(at 0 -1.27508 270)
			(size 2.6924 1.3462)
			(layers "F.Cu" "F.Mask" "F.Paste")
			(net "VR_FET_SW_P12V_STBY_PVDDQ_GHJ")
		)
		(pad "2" smd rect
			(at 0 1.27508 270)
			(size 2.6924 1.3462)
			(layers "F.Cu" "F.Mask" "F.Paste")
			(net "GND")
		)
	)
	(footprint ""
		(layer "F.Cu")
		(at 483.38486 -28.14828 90)
		(property "Reference" "R8F25"
			(at 0 0 90)
			(layer "F.SilkS")
			(hide yes)
			(effects
				(font
					(size 1.27 1.27)
				)
			)
		)
		(property "Value" ""
			(at 0 0 90)
			(layer "F.Fab")
			(effects
				(font
					(size 1.27 1.27)
				)
			)
		)
		(duplicate_pad_numbers_are_jumpers no)
		(fp_poly
			(pts
				(xy -0.2794 -0.1016) (xy 0.2794 -0.1016) (xy 0.2794 0.9906) (xy -0.2794 0.9906)
			)
			(stroke
				(width 0)
				(type default)
			)
			(fill no)
			(layer "F.CrtYd")
		)
		(fp_line
			(start 0.2794 -0.1016)
			(end -0.2794 -0.1016)
			(stroke
				(width 0.1)
				(type default)
			)
			(layer "F.Fab")
		)
		(fp_line
			(start -0.2794 -0.1016)
			(end -0.2794 0.9906)
			(stroke
				(width 0.1)
				(type default)
			)
			(layer "F.Fab")
		)
		(fp_line
			(start 0.2794 0.9906)
			(end 0.2794 -0.1016)
			(stroke
				(width 0.1)
				(type default)
			)
			(layer "F.Fab")
		)
		(fp_line
			(start -0.2794 0.9906)
			(end 0.2794 0.9906)
			(stroke
				(width 0.1)
				(type default)
			)
			(layer "F.Fab")
		)
		(pad "1" smd rect
			(at 0 0 90)
			(size 0.508 0.508)
			(layers "F.Cu" "F.Mask" "F.Paste")
			(net "A_COMP_CKMNG")
		)
		(pad "2" smd rect
			(at 0 0.889 90)
			(size 0.508 0.508)
			(layers "F.Cu" "F.Mask" "F.Paste")
			(net "GND")
		)
		(zone
			(layer "F.Cu")
			(hatch none 0.5)
			(connect_pads
				(clearance 0)
			)
			(min_thickness 0.25)
			(keepout
				(tracks allowed)
				(vias not_allowed)
				(pads allowed)
				(copperpour not_allowed)
				(footprints allowed)
			)
			(placement
				(enabled no)
				(sheetname "")
			)
			(fill
				(thermal_gap 0.5)
				(thermal_bridge_width 0.5)
				(island_removal_mode 0)
			)
			(polygon
				(pts
					(xy 483.63886 -27.89428) (xy 483.63886 -28.40228) (xy 484.01986 -28.40228) (xy 484.01986 -27.89428)
				)
			)
		)
		(zone
			(layer "F.Cu")
			(hatch none 0.5)
			(connect_pads
				(clearance 0)
			)
			(min_thickness 0.25)
			(keepout
				(tracks not_allowed)
				(vias allowed)
				(pads allowed)
				(copperpour not_allowed)
				(footprints allowed)
			)
			(placement
				(enabled no)
				(sheetname "")
			)
			(fill
				(thermal_gap 0.5)
				(thermal_bridge_width 0.5)
				(island_removal_mode 0)
			)
			(polygon
				(pts
					(xy 484.01986 -27.89428) (xy 484.01986 -28.40228) (xy 483.63886 -28.40228) (xy 483.63886 -27.89428)
				)
			)
		)
	)
	(footprint ""
		(layer "F.Cu")
		(at 205.486 -102.616 180)
		(property "Reference" "R4C3"
			(at 0 0 180)
			(layer "F.SilkS")
			(hide yes)
			(effects
				(font
					(size 1.27 1.27)
				)
			)
		)
		(property "Value" ""
			(at 0 0 180)
			(layer "F.Fab")
			(effects
				(font
					(size 1.27 1.27)
				)
			)
		)
		(duplicate_pad_numbers_are_jumpers no)
		(fp_poly
			(pts
				(xy -0.2794 -0.1016) (xy 0.2794 -0.1016) (xy 0.2794 0.9906) (xy -0.2794 0.9906)
			)
			(stroke
				(width 0)
				(type default)
			)
			(fill no)
			(layer "F.CrtYd")
		)
		(fp_line
			(start 0.2794 0.9906)
			(end 0.2794 -0.1016)
			(stroke
				(width 0.1)
				(type default)
			)
			(layer "F.Fab")
		)
		(fp_line
			(start 0.2794 -0.1016)
			(end -0.2794 -0.1016)
			(stroke
				(width 0.1)
				(type default)
			)
			(layer "F.Fab")
		)
		(fp_line
			(start -0.2794 0.9906)
			(end 0.2794 0.9906)
			(stroke
				(width 0.1)
				(type default)
			)
			(layer "F.Fab")
		)
		(fp_line
			(start -0.2794 -0.1016)
			(end -0.2794 0.9906)
			(stroke
				(width 0.1)
				(type default)
			)
			(layer "F.Fab")
		)
		(pad "1" smd rect
			(at 0 0 180)
			(size 0.508 0.508)
			(layers "F.Cu" "F.Mask" "F.Paste")
			(net "VSENSE_PVSA_CPU0_P")
		)
		(pad "2" smd rect
			(at 0 0.889 180)
			(size 0.508 0.508)
			(layers "F.Cu" "F.Mask" "F.Paste")
			(net "VSENSE_PVSA_CPU0_N")
		)
		(zone
			(layer "F.Cu")
			(hatch none 0.5)
			(connect_pads
				(clearance 0)
			)
			(min_thickness 0.25)
			(keepout
				(tracks not_allowed)
				(vias allowed)
				(pads allowed)
				(copperpour not_allowed)
				(footprints allowed)
			)
			(placement
				(enabled no)
				(sheetname "")
			)
			(fill
				(thermal_gap 0.5)
				(thermal_bridge_width 0.5)
				(island_removal_mode 0)
			)
			(polygon
				(pts
					(xy 205.74 -103.251) (xy 205.232 -103.251) (xy 205.232 -102.87) (xy 205.74 -102.87)
				)
			)
		)
		(zone
			(layer "F.Cu")
			(hatch none 0.5)
			(connect_pads
				(clearance 0)
			)
			(min_thickness 0.25)
			(keepout
				(tracks allowed)
				(vias not_allowed)
				(pads allowed)
				(copperpour not_allowed)
				(footprints allowed)
			)
			(placement
				(enabled no)
				(sheetname "")
			)
			(fill
				(thermal_gap 0.5)
				(thermal_bridge_width 0.5)
				(island_removal_mode 0)
			)
			(polygon
				(pts
					(xy 205.74 -102.87) (xy 205.232 -102.87) (xy 205.232 -103.251) (xy 205.74 -103.251)
				)
			)
		)
	)
	(footprint ""
		(layer "F.Cu")
		(at 266.397232 -3.3528 90)
		(property "Reference" "C5G15"
			(at 1.848866 0.752348 90)
			(unlocked yes)
			(layer "F.SilkS")
			(effects
				(font
					(size 1.27 0.9652)
					(thickness 0.1524)
				)
			)
		)
		(property "Value" ""
			(at 0 0 90)
			(layer "F.Fab")
			(effects
				(font
					(size 1.27 1.27)
				)
			)
		)
		(duplicate_pad_numbers_are_jumpers no)
		(fp_rect
			(start -0.500126 1.598422)
			(end 0.500126 -0.201422)
			(stroke
				(width 0)
				(type default)
			)
			(fill no)
			(layer "F.CrtYd")
		)
		(fp_line
			(start 0.500126 -0.201422)
			(end 0.500126 1.598422)
			(stroke
				(width 0.1)
				(type default)
			)
			(layer "F.Fab")
		)
		(fp_line
			(start -0.500126 -0.201422)
			(end 0.500126 -0.201422)
			(stroke
				(width 0.1)
				(type default)
			)
			(layer "F.Fab")
		)
		(fp_line
			(start 0.500126 1.598422)
			(end -0.500126 1.598422)
			(stroke
				(width 0.1)
				(type default)
			)
			(layer "F.Fab")
		)
		(fp_line
			(start -0.500126 1.598422)
			(end -0.500126 -0.201422)
			(stroke
				(width 0.1)
				(type default)
			)
			(layer "F.Fab")
		)
		(pad "1" smd rect
			(at 0 0)
			(size 0.889 0.9906)
			(layers "F.Cu" "F.Mask" "F.Paste")
			(net "PVDDQ_ABC")
		)
		(pad "2" smd rect
			(at 0 1.397)
			(size 0.889 0.9906)
			(layers "F.Cu" "F.Mask" "F.Paste")
			(net "GND")
		)
		(zone
			(layer "F.Cu")
			(hatch none 0.5)
			(connect_pads
				(clearance 0)
			)
			(min_thickness 0.25)
			(keepout
				(tracks not_allowed)
				(vias allowed)
				(pads allowed)
				(copperpour not_allowed)
				(footprints allowed)
			)
			(placement
				(enabled no)
				(sheetname "")
			)
			(fill
				(thermal_gap 0.5)
				(thermal_bridge_width 0.5)
				(island_removal_mode 0)
			)
			(polygon
				(pts
					(xy 267.349732 -2.8575) (xy 267.349732 -3.8481) (xy 266.841732 -3.8481) (xy 266.841732 -2.8575)
				)
			)
		)
		(zone
			(layer "F.Cu")
			(hatch none 0.5)
			(connect_pads
				(clearance 0)
			)
			(min_thickness 0.25)
			(keepout
				(tracks allowed)
				(vias not_allowed)
				(pads allowed)
				(copperpour not_allowed)
				(footprints allowed)
			)
			(placement
				(enabled no)
				(sheetname "")
			)
			(fill
				(thermal_gap 0.5)
				(thermal_bridge_width 0.5)
				(island_removal_mode 0)
			)
			(polygon
				(pts
					(xy 267.349732 -2.8575) (xy 267.349732 -3.8481) (xy 266.841732 -3.8481) (xy 266.841732 -2.8575)
				)
			)
		)
	)
	(footprint ""
		(layer "F.Cu")
		(at 324.5485 -122.555 -90)
		(property "Reference" "C827"
			(at -0.8382 -0.67818 270)
			(unlocked yes)
			(layer "F.SilkS")
			(effects
				(font
					(size 0.4064 0.254)
					(thickness 0.1524)
				)
				(justify left)
			)
		)
		(property "Value" ""
			(at 0 0 270)
			(layer "F.Fab")
			(effects
				(font
					(size 1.27 1.27)
				)
			)
		)
		(duplicate_pad_numbers_are_jumpers no)
		(fp_poly
			(pts
				(xy 0.3048 -0.1016) (xy 0.3048 0.9906) (xy -0.3048 0.9906) (xy -0.3048 -0.1016)
			)
			(stroke
				(width 0)
				(type default)
			)
			(fill no)
			(layer "F.CrtYd")
		)
		(fp_line
			(start -0.3048 0.9906)
			(end 0.3048 0.9906)
			(stroke
				(width 0.1)
				(type default)
			)
			(layer "F.Fab")
		)
		(fp_line
			(start 0.3048 0.9906)
			(end 0.3048 -0.1016)
			(stroke
				(width 0.1)
				(type default)
			)
			(layer "F.Fab")
		)
		(fp_line
			(start -0.3048 -0.1016)
			(end -0.3048 0.9906)
			(stroke
				(width 0.1)
				(type default)
			)
			(layer "F.Fab")
		)
		(fp_line
			(start 0.3048 -0.1016)
			(end -0.3048 -0.1016)
			(stroke
				(width 0.1)
				(type default)
			)
			(layer "F.Fab")
		)
		(pad "1" smd rect
			(at 0 0 270)
			(size 0.508 0.508)
			(layers "F.Cu" "F.Mask" "F.Paste")
			(net "P3E_CPU0_PE1_PCH_TXP<14>")
		)
		(pad "2" smd rect
			(at 0 0.889 270)
			(size 0.508 0.508)
			(layers "F.Cu" "F.Mask" "F.Paste")
			(net "P3E_CPU0_PE1_PCH_CON_TXP<14>")
		)
		(zone
			(layer "F.Cu")
			(hatch none 0.5)
			(connect_pads
				(clearance 0)
			)
			(min_thickness 0.25)
			(keepout
				(tracks not_allowed)
				(vias allowed)
				(pads allowed)
				(copperpour not_allowed)
				(footprints allowed)
			)
			(placement
				(enabled no)
				(sheetname "")
			)
			(fill
				(thermal_gap 0.5)
				(thermal_bridge_width 0.5)
				(island_removal_mode 0)
			)
			(polygon
				(pts
					(xy 323.9135 -122.809) (xy 323.9135 -122.301) (xy 324.2945 -122.301) (xy 324.2945 -122.809)
				)
			)
		)
		(zone
			(layer "F.Cu")
			(hatch none 0.5)
			(connect_pads
				(clearance 0)
			)
			(min_thickness 0.25)
			(keepout
				(tracks allowed)
				(vias not_allowed)
				(pads allowed)
				(copperpour not_allowed)
				(footprints allowed)
			)
			(placement
				(enabled no)
				(sheetname "")
			)
			(fill
				(thermal_gap 0.5)
				(thermal_bridge_width 0.5)
				(island_removal_mode 0)
			)
			(polygon
				(pts
					(xy 324.2945 -122.809) (xy 324.2945 -122.301) (xy 323.9135 -122.301) (xy 323.9135 -122.809)
				)
			)
		)
	)
	(footprint ""
		(layer "F.Cu")
		(at 197.162928 -85.733382 -90)
		(property "Reference" "C4D46"
			(at 0 0 270)
			(layer "F.SilkS")
			(hide yes)
			(effects
				(font
					(size 1.27 1.27)
				)
			)
		)
		(property "Value" ""
			(at 0 0 270)
			(layer "F.Fab")
			(effects
				(font
					(size 1.27 1.27)
				)
			)
		)
		(duplicate_pad_numbers_are_jumpers no)
		(fp_poly
			(pts
				(xy 0.3048 -0.1016) (xy 0.3048 0.9906) (xy -0.3048 0.9906) (xy -0.3048 -0.1016)
			)
			(stroke
				(width 0)
				(type default)
			)
			(fill no)
			(layer "F.CrtYd")
		)
		(fp_line
			(start -0.3048 0.9906)
			(end 0.3048 0.9906)
			(stroke
				(width 0.1)
				(type default)
			)
			(layer "F.Fab")
		)
		(fp_line
			(start 0.3048 0.9906)
			(end 0.3048 -0.1016)
			(stroke
				(width 0.1)
				(type default)
			)
			(layer "F.Fab")
		)
		(fp_line
			(start -0.3048 -0.1016)
			(end -0.3048 0.9906)
			(stroke
				(width 0.1)
				(type default)
			)
			(layer "F.Fab")
		)
		(fp_line
			(start 0.3048 -0.1016)
			(end -0.3048 -0.1016)
			(stroke
				(width 0.1)
				(type default)
			)
			(layer "F.Fab")
		)
		(pad "1" smd rect
			(at 0 0 270)
			(size 0.508 0.508)
			(layers "F.Cu" "F.Mask" "F.Paste")
			(net "VR_PVCCIN_CPU0_PH5_VCIN")
		)
		(pad "2" smd rect
			(at 0 0.889 270)
			(size 0.508 0.508)
			(layers "F.Cu" "F.Mask" "F.Paste")
			(net "GND")
		)
		(zone
			(layer "F.Cu")
			(hatch none 0.5)
			(connect_pads
				(clearance 0)
			)
			(min_thickness 0.25)
			(keepout
				(tracks not_allowed)
				(vias allowed)
				(pads allowed)
				(copperpour not_allowed)
				(footprints allowed)
			)
			(placement
				(enabled no)
				(sheetname "")
			)
			(fill
				(thermal_gap 0.5)
				(thermal_bridge_width 0.5)
				(island_removal_mode 0)
			)
			(polygon
				(pts
					(xy 196.527928 -85.987382) (xy 196.527928 -85.479382) (xy 196.908928 -85.479382) (xy 196.908928 -85.987382)
				)
			)
		)
		(zone
			(layer "F.Cu")
			(hatch none 0.5)
			(connect_pads
				(clearance 0)
			)
			(min_thickness 0.25)
			(keepout
				(tracks allowed)
				(vias not_allowed)
				(pads allowed)
				(copperpour not_allowed)
				(footprints allowed)
			)
			(placement
				(enabled no)
				(sheetname "")
			)
			(fill
				(thermal_gap 0.5)
				(thermal_bridge_width 0.5)
				(island_removal_mode 0)
			)
			(polygon
				(pts
					(xy 196.908928 -85.987382) (xy 196.908928 -85.479382) (xy 196.527928 -85.479382) (xy 196.527928 -85.987382)
				)
			)
		)
	)
	(footprint ""
		(layer "F.Cu")
		(at 106.982768 -79.6036 180)
		(property "Reference" "C3W4"
			(at 0.97536 0.76708 90)
			(unlocked yes)
			(layer "F.SilkS")
			(effects
				(font
					(size 0.4064 0.254)
					(thickness 0.1524)
				)
			)
		)
		(property "Value" ""
			(at 0 0 180)
			(layer "F.Fab")
			(effects
				(font
					(size 1.27 1.27)
				)
			)
		)
		(duplicate_pad_numbers_are_jumpers no)
		(fp_poly
			(pts
				(xy -0.4953 -0.2032) (xy 0.4953 -0.2032) (xy 0.4953 1.6002) (xy -0.4953 1.6002)
			)
			(stroke
				(width 0)
				(type default)
			)
			(fill no)
			(layer "F.CrtYd")
		)
		(fp_line
			(start 0.4953 1.6002)
			(end -0.4953 1.6002)
			(stroke
				(width 0.1)
				(type default)
			)
			(layer "F.Fab")
		)
		(fp_line
			(start 0.4953 -0.2032)
			(end 0.4953 1.6002)
			(stroke
				(width 0.1)
				(type default)
			)
			(layer "F.Fab")
		)
		(fp_line
			(start -0.4953 1.6002)
			(end -0.4953 -0.2032)
			(stroke
				(width 0.1)
				(type default)
			)
			(layer "F.Fab")
		)
		(fp_line
			(start -0.4953 -0.2032)
			(end 0.4953 -0.2032)
			(stroke
				(width 0.1)
				(type default)
			)
			(layer "F.Fab")
		)
		(pad "1" smd rect
			(at 0 0 180)
			(size 0.762 0.889)
			(layers "F.Cu" "F.Mask" "F.Paste")
			(net "PVCCMCP_CPU1")
		)
		(pad "2" smd rect
			(at 0 1.397 180)
			(size 0.762 0.889)
			(layers "F.Cu" "F.Mask" "F.Paste")
			(net "GND")
		)
		(zone
			(layer "F.Cu")
			(hatch none 0.5)
			(connect_pads
				(clearance 0)
			)
			(min_thickness 0.25)
			(keepout
				(tracks not_allowed)
				(vias allowed)
				(pads allowed)
				(copperpour not_allowed)
				(footprints allowed)
			)
			(placement
				(enabled no)
				(sheetname "")
			)
			(fill
				(thermal_gap 0.5)
				(thermal_bridge_width 0.5)
				(island_removal_mode 0)
			)
			(polygon
				(pts
					(xy 107.363768 -80.0481) (xy 106.601768 -80.0481) (xy 106.601768 -80.5561) (xy 107.363768 -80.5561)
				)
			)
		)
	)
	(footprint ""
		(layer "F.Cu")
		(at 127.570484 12.014454 -90)
		(property "Reference" "T1P9"
			(at 0 0 270)
			(layer "F.SilkS")
			(hide yes)
			(effects
				(font
					(size 1.27 1.27)
				)
			)
		)
		(property "Value" "*"
			(at -3.302 1.12395 270)
			(unlocked yes)
			(layer "F.Fab")
			(hide yes)
			(effects
				(font
					(size 0.889 0.889)
					(thickness 0.1524)
				)
			)
		)
		(property "Device Type" "TPAD-DIFF-4P-GP_DISCRET-GB3-TPA"
			(at -3.302 -0.40005 270)
			(unlocked yes)
			(layer "F.Fab")
			(hide yes)
			(effects
				(font
					(size 0.889 0.889)
					(thickness 0.1524)
				)
			)
		)
		(duplicate_pad_numbers_are_jumpers no)
		(fp_line
			(start -2.286 2.286)
			(end 2.286 2.286)
			(stroke
				(width 0.1524)
				(type default)
			)
			(layer "F.SilkS")
		)
		(fp_line
			(start 2.286 2.286)
			(end 2.286 -2.286)
			(stroke
				(width 0.1524)
				(type default)
			)
			(layer "F.SilkS")
		)
		(fp_line
			(start -2.286 -2.286)
			(end -2.286 2.286)
			(stroke
				(width 0.1524)
				(type default)
			)
			(layer "F.SilkS")
		)
		(fp_line
			(start 2.286 -2.286)
			(end -2.286 -2.286)
			(stroke
				(width 0.1524)
				(type default)
			)
			(layer "F.SilkS")
		)
		(fp_line
			(start -2.413 -2.413)
			(end -2.413 -1.143)
			(stroke
				(width 0.4064)
				(type default)
			)
			(layer "F.SilkS")
		)
		(fp_line
			(start -1.143 -2.413)
			(end -2.413 -2.413)
			(stroke
				(width 0.4064)
				(type default)
			)
			(layer "F.SilkS")
		)
		(fp_rect
			(start -2.54 2.54)
			(end 2.54 -2.54)
			(stroke
				(width 0)
				(type default)
			)
			(fill no)
			(layer "F.CrtYd")
		)
		(fp_rect
			(start -2.54 2.54)
			(end 2.54 -2.54)
			(stroke
				(width 0)
				(type default)
			)
			(fill no)
			(layer "F.Fab")
		)
		(pad "1" thru_hole circle
			(at -1.27 -1.27 270)
			(size 1.524 1.524)
			(drill 0.9144)
			(layers "*.Cu" "*.Mask")
			(remove_unused_layers no)
			(net "L5_73OHM_6INCH_DP")
			(clearance -0.0508)
			(thermal_gap 0.127)
			(padstack
				(mode front_inner_back)
				(layer "Inner"
					(shape circle)
					(size 1.1684 1.1684)
					(clearance 0.127)
				)
				(layer "B.Cu"
					(shape circle)
					(size 1.524 1.524)
					(clearance -0.0508)
				)
			)
		)
		(pad "2" thru_hole circle
			(at 1.27 -1.27 270)
			(size 1.524 1.524)
			(drill 0.9144)
			(layers "*.Cu" "*.Mask")
			(remove_unused_layers no)
			(net "L5_73OHM_6INCH_DN")
			(clearance -0.0508)
			(thermal_gap 0.127)
			(padstack
				(mode front_inner_back)
				(layer "Inner"
					(shape circle)
					(size 1.1684 1.1684)
					(clearance 0.127)
				)
				(layer "B.Cu"
					(shape circle)
					(size 1.524 1.524)
					(clearance -0.0508)
				)
			)
		)
		(pad "GND1" thru_hole rect
			(at -1.27 1.27 270)
			(size 1.524 1.524)
			(drill 0.9144)
			(layers "*.Cu" "*.Mask")
			(remove_unused_layers no)
			(net "GND")
			(clearance -0.0508)
			(thermal_gap 0.127)
			(padstack
				(mode front_inner_back)
				(layer "Inner"
					(shape circle)
					(size 1.1684 1.1684)
					(clearance 0.127)
				)
				(layer "B.Cu"
					(shape rect)
					(size 1.524 1.524)
					(clearance -0.0508)
				)
			)
		)
		(pad "GND2" thru_hole rect
			(at 1.27 1.27 270)
			(size 1.524 1.524)
			(drill 0.9144)
			(layers "*.Cu" "*.Mask")
			(remove_unused_layers no)
			(net "GND")
			(clearance -0.0508)
			(thermal_gap 0.127)
			(padstack
				(mode front_inner_back)
				(layer "Inner"
					(shape circle)
					(size 1.1684 1.1684)
					(clearance 0.127)
				)
				(layer "B.Cu"
					(shape rect)
					(size 1.524 1.524)
					(clearance -0.0508)
				)
			)
		)
	)
	(footprint ""
		(layer "F.Cu")
		(at 273.8628 -68.072 90)
		(property "Reference" "R5D5"
			(at 0 0 90)
			(layer "F.SilkS")
			(hide yes)
			(effects
				(font
					(size 1.27 1.27)
				)
			)
		)
		(property "Value" ""
			(at 0 0 90)
			(layer "F.Fab")
			(effects
				(font
					(size 1.27 1.27)
				)
			)
		)
		(duplicate_pad_numbers_are_jumpers no)
		(fp_poly
			(pts
				(xy -0.2794 -0.1016) (xy 0.2794 -0.1016) (xy 0.2794 0.9906) (xy -0.2794 0.9906)
			)
			(stroke
				(width 0)
				(type default)
			)
			(fill no)
			(layer "F.CrtYd")
		)
		(fp_line
			(start 0.2794 -0.1016)
			(end -0.2794 -0.1016)
			(stroke
				(width 0.1)
				(type default)
			)
			(layer "F.Fab")
		)
		(fp_line
			(start -0.2794 -0.1016)
			(end -0.2794 0.9906)
			(stroke
				(width 0.1)
				(type default)
			)
			(layer "F.Fab")
		)
		(fp_line
			(start 0.2794 0.9906)
			(end 0.2794 -0.1016)
			(stroke
				(width 0.1)
				(type default)
			)
			(layer "F.Fab")
		)
		(fp_line
			(start -0.2794 0.9906)
			(end 0.2794 0.9906)
			(stroke
				(width 0.1)
				(type default)
			)
			(layer "F.Fab")
		)
		(pad "1" smd rect
			(at 0 0 90)
			(size 0.508 0.508)
			(layers "F.Cu" "F.Mask" "F.Paste")
			(net "VSENSE_PMAX_CPU0")
		)
		(pad "2" smd rect
			(at 0 0.889 90)
			(size 0.508 0.508)
			(layers "F.Cu" "F.Mask" "F.Paste")
			(net "GND")
		)
		(zone
			(layer "F.Cu")
			(hatch none 0.5)
			(connect_pads
				(clearance 0)
			)
			(min_thickness 0.25)
			(keepout
				(tracks allowed)
				(vias not_allowed)
				(pads allowed)
				(copperpour not_allowed)
				(footprints allowed)
			)
			(placement
				(enabled no)
				(sheetname "")
			)
			(fill
				(thermal_gap 0.5)
				(thermal_bridge_width 0.5)
				(island_removal_mode 0)
			)
			(polygon
				(pts
					(xy 274.1168 -67.818) (xy 274.1168 -68.326) (xy 274.4978 -68.326) (xy 274.4978 -67.818)
				)
			)
		)
		(zone
			(layer "F.Cu")
			(hatch none 0.5)
			(connect_pads
				(clearance 0)
			)
			(min_thickness 0.25)
			(keepout
				(tracks not_allowed)
				(vias allowed)
				(pads allowed)
				(copperpour not_allowed)
				(footprints allowed)
			)
			(placement
				(enabled no)
				(sheetname "")
			)
			(fill
				(thermal_gap 0.5)
				(thermal_bridge_width 0.5)
				(island_removal_mode 0)
			)
			(polygon
				(pts
					(xy 274.4978 -67.818) (xy 274.4978 -68.326) (xy 274.1168 -68.326) (xy 274.1168 -67.818)
				)
			)
		)
	)
	(footprint ""
		(layer "F.Cu")
		(at 197.19798 -77.216 -90)
		(property "Reference" "C4D7"
			(at -0.8382 -0.67818 270)
			(unlocked yes)
			(layer "F.SilkS")
			(effects
				(font
					(size 0.4064 0.254)
					(thickness 0.1524)
				)
				(justify left)
			)
		)
		(property "Value" ""
			(at 0 0 270)
			(layer "F.Fab")
			(effects
				(font
					(size 1.27 1.27)
				)
			)
		)
		(duplicate_pad_numbers_are_jumpers no)
		(fp_poly
			(pts
				(xy 0.3048 -0.1016) (xy 0.3048 0.9906) (xy -0.3048 0.9906) (xy -0.3048 -0.1016)
			)
			(stroke
				(width 0)
				(type default)
			)
			(fill no)
			(layer "F.CrtYd")
		)
		(fp_line
			(start -0.3048 0.9906)
			(end 0.3048 0.9906)
			(stroke
				(width 0.1)
				(type default)
			)
			(layer "F.Fab")
		)
		(fp_line
			(start 0.3048 0.9906)
			(end 0.3048 -0.1016)
			(stroke
				(width 0.1)
				(type default)
			)
			(layer "F.Fab")
		)
		(fp_line
			(start -0.3048 -0.1016)
			(end -0.3048 0.9906)
			(stroke
				(width 0.1)
				(type default)
			)
			(layer "F.Fab")
		)
		(fp_line
			(start 0.3048 -0.1016)
			(end -0.3048 -0.1016)
			(stroke
				(width 0.1)
				(type default)
			)
			(layer "F.Fab")
		)
		(pad "1" smd rect
			(at 0 0 270)
			(size 0.508 0.508)
			(layers "F.Cu" "F.Mask" "F.Paste")
			(net "VR_PVCCIN_CPU0_PH4_VCIN")
		)
		(pad "2" smd rect
			(at 0 0.889 270)
			(size 0.508 0.508)
			(layers "F.Cu" "F.Mask" "F.Paste")
			(net "GND")
		)
		(zone
			(layer "F.Cu")
			(hatch none 0.5)
			(connect_pads
				(clearance 0)
			)
			(min_thickness 0.25)
			(keepout
				(tracks not_allowed)
				(vias allowed)
				(pads allowed)
				(copperpour not_allowed)
				(footprints allowed)
			)
			(placement
				(enabled no)
				(sheetname "")
			)
			(fill
				(thermal_gap 0.5)
				(thermal_bridge_width 0.5)
				(island_removal_mode 0)
			)
			(polygon
				(pts
					(xy 196.56298 -77.47) (xy 196.56298 -76.962) (xy 196.94398 -76.962) (xy 196.94398 -77.47)
				)
			)
		)
		(zone
			(layer "F.Cu")
			(hatch none 0.5)
			(connect_pads
				(clearance 0)
			)
			(min_thickness 0.25)
			(keepout
				(tracks allowed)
				(vias not_allowed)
				(pads allowed)
				(copperpour not_allowed)
				(footprints allowed)
			)
			(placement
				(enabled no)
				(sheetname "")
			)
			(fill
				(thermal_gap 0.5)
				(thermal_bridge_width 0.5)
				(island_removal_mode 0)
			)
			(polygon
				(pts
					(xy 196.94398 -77.47) (xy 196.94398 -76.962) (xy 196.56298 -76.962) (xy 196.56298 -77.47)
				)
			)
		)
	)
	(footprint ""
		(layer "F.Cu")
		(at 409.719526 -76.883768)
		(property "Reference" "RM8D1"
			(at -4.496562 1.28778 90)
			(unlocked yes)
			(layer "F.SilkS")
			(effects
				(font
					(size 0.7874 0.5842)
					(thickness 0.1524)
				)
				(justify left)
			)
		)
		(property "Value" ""
			(at 0 0 0)
			(layer "F.Fab")
			(effects
				(font
					(size 1.27 1.27)
				)
			)
		)
		(duplicate_pad_numbers_are_jumpers no)
		(fp_poly
			(pts
				(arc
					(start 3.5052 0)
					(mid -3.5052 0)
					(end 3.5052 0)
				)
			)
			(stroke
				(width 0)
				(type default)
			)
			(fill yes)
			(layer "F.Paste")
		)
		(fp_poly
			(pts
				(arc
					(start 3.050032 0)
					(mid -3.050032 0)
					(end 3.050032 0)
				)
			)
			(stroke
				(width 0)
				(type default)
			)
			(fill no)
			(layer "F.CrtYd")
		)
		(fp_circle
			(center 0 0)
			(end 3.050032 0)
			(stroke
				(width 0.1)
				(type default)
			)
			(fill no)
			(layer "F.Fab")
		)
		(pad "1" thru_hole circle
			(at 0 0)
			(size 7.0104 7.0104)
			(drill 4.4958)
			(layers "*.Cu" "*.Mask")
			(remove_unused_layers no)
			(net "GND")
			(clearance -0.9398)
		)
	)
	(footprint ""
		(layer "F.Cu")
		(at 389.636 -0.254)
		(property "Reference" "R7G18"
			(at 0 0 0)
			(layer "F.SilkS")
			(hide yes)
			(effects
				(font
					(size 1.27 1.27)
				)
			)
		)
		(property "Value" ""
			(at 0 0 0)
			(layer "F.Fab")
			(effects
				(font
					(size 1.27 1.27)
				)
			)
		)
		(duplicate_pad_numbers_are_jumpers no)
		(fp_poly
			(pts
				(xy -0.2794 -0.1016) (xy 0.2794 -0.1016) (xy 0.2794 0.9906) (xy -0.2794 0.9906)
			)
			(stroke
				(width 0)
				(type default)
			)
			(fill no)
			(layer "F.CrtYd")
		)
		(fp_line
			(start -0.2794 -0.1016)
			(end -0.2794 0.9906)
			(stroke
				(width 0.1)
				(type default)
			)
			(layer "F.Fab")
		)
		(fp_line
			(start -0.2794 0.9906)
			(end 0.2794 0.9906)
			(stroke
				(width 0.1)
				(type default)
			)
			(layer "F.Fab")
		)
		(fp_line
			(start 0.2794 -0.1016)
			(end -0.2794 -0.1016)
			(stroke
				(width 0.1)
				(type default)
			)
			(layer "F.Fab")
		)
		(fp_line
			(start 0.2794 0.9906)
			(end 0.2794 -0.1016)
			(stroke
				(width 0.1)
				(type default)
			)
			(layer "F.Fab")
		)
		(pad "1" smd rect
			(at 0 0)
			(size 0.508 0.508)
			(layers "F.Cu" "F.Mask" "F.Paste")
			(net "JTAG_PCH_PLD_TDI")
		)
		(pad "2" smd rect
			(at 0 0.889)
			(size 0.508 0.508)
			(layers "F.Cu" "F.Mask" "F.Paste")
			(net "JTAG_TDI")
		)
		(zone
			(layer "F.Cu")
			(hatch none 0.5)
			(connect_pads
				(clearance 0)
			)
			(min_thickness 0.25)
			(keepout
				(tracks allowed)
				(vias not_allowed)
				(pads allowed)
				(copperpour not_allowed)
				(footprints allowed)
			)
			(placement
				(enabled no)
				(sheetname "")
			)
			(fill
				(thermal_gap 0.5)
				(thermal_bridge_width 0.5)
				(island_removal_mode 0)
			)
			(polygon
				(pts
					(xy 389.382 0) (xy 389.89 0) (xy 389.89 0.381) (xy 389.382 0.381)
				)
			)
		)
		(zone
			(layer "F.Cu")
			(hatch none 0.5)
			(connect_pads
				(clearance 0)
			)
			(min_thickness 0.25)
			(keepout
				(tracks not_allowed)
				(vias allowed)
				(pads allowed)
				(copperpour not_allowed)
				(footprints allowed)
			)
			(placement
				(enabled no)
				(sheetname "")
			)
			(fill
				(thermal_gap 0.5)
				(thermal_bridge_width 0.5)
				(island_removal_mode 0)
			)
			(polygon
				(pts
					(xy 389.382 0.381) (xy 389.89 0.381) (xy 389.89 0) (xy 389.382 0)
				)
			)
		)
	)
	(footprint ""
		(layer "F.Cu")
		(at 4.445 -134.3914 -90)
		(property "Reference" "RT6"
			(at 0 0 270)
			(layer "F.SilkS")
			(hide yes)
			(effects
				(font
					(size 1.27 1.27)
				)
			)
		)
		(property "Value" "*"
			(at -0.0254 -2.6289 270)
			(unlocked yes)
			(layer "F.Fab")
			(hide yes)
			(effects
				(font
					(size 1.27 1.016)
					(thickness 0.1524)
				)
			)
		)
		(property "Device Type" "1R3F-GP_RCL_GP-1R3F-GP,64.1R00A"
			(at -0.0254 -4.1529 270)
			(unlocked yes)
			(layer "F.Fab")
			(hide yes)
			(effects
				(font
					(size 1.27 1.016)
					(thickness 0.1524)
				)
			)
		)
		(duplicate_pad_numbers_are_jumpers no)
		(fp_line
			(start -0.4826 0)
			(end -0.2032 0)
			(stroke
				(width 0.2032)
				(type default)
			)
			(layer "F.SilkS")
		)
		(fp_line
			(start 0.2032 0)
			(end 0.4826 0)
			(stroke
				(width 0.2032)
				(type default)
			)
			(layer "F.SilkS")
		)
		(fp_rect
			(start -0.5842 1.3335)
			(end 0.5842 -1.3335)
			(stroke
				(width 0)
				(type default)
			)
			(fill no)
			(layer "F.CrtYd")
		)
		(fp_rect
			(start -0.5842 1.3335)
			(end 0.5842 -1.3335)
			(stroke
				(width 0)
				(type default)
			)
			(fill no)
			(layer "F.Fab")
		)
		(pad "1" smd custom
			(at 0 -0.762 270)
			(size 0.2159 0.2159)
			(layers "F.Cu" "F.Mask" "F.Paste")
			(net "VR_PVDDQ_KLM_PH1_RC")
			(options
				(clearance outline)
				(anchor circle)
			)
			(primitives
				(gr_poly
					(pts
						(arc
							(start -0.3302 -0.4318)
							(mid -0.402042 -0.402042)
							(end -0.4318 -0.3302)
						)
						(arc
							(start -0.4318 0.3302)
							(mid -0.402042 0.402042)
							(end -0.3302 0.4318)
						)
						(arc
							(start 0.3302 0.4318)
							(mid 0.402042 0.402042)
							(end 0.4318 0.3302)
						)
						(arc
							(start 0.4318 -0.3302)
							(mid 0.402042 -0.402042)
							(end 0.3302 -0.4318)
						)
					)
					(width 0)
					(fill yes)
				)
			)
		)
		(pad "2" smd custom
			(at 0 0.762 270)
			(size 0.2159 0.2159)
			(layers "F.Cu" "F.Mask" "F.Paste")
			(net "GND")
			(options
				(clearance outline)
				(anchor circle)
			)
			(primitives
				(gr_poly
					(pts
						(arc
							(start -0.3302 -0.4318)
							(mid -0.402042 -0.402042)
							(end -0.4318 -0.3302)
						)
						(arc
							(start -0.4318 0.3302)
							(mid -0.402042 0.402042)
							(end -0.3302 0.4318)
						)
						(arc
							(start 0.3302 0.4318)
							(mid 0.402042 0.402042)
							(end 0.4318 0.3302)
						)
						(arc
							(start 0.4318 -0.3302)
							(mid 0.402042 -0.402042)
							(end 0.3302 -0.4318)
						)
					)
					(width 0)
					(fill yes)
				)
			)
		)
	)
	(footprint ""
		(layer "F.Cu")
		(at 167.4876 -149.225 -90)
		(property "Reference" "C4A6"
			(at 0 0 270)
			(layer "F.SilkS")
			(hide yes)
			(effects
				(font
					(size 1.27 1.27)
				)
			)
		)
		(property "Value" ""
			(at 0 0 270)
			(layer "F.Fab")
			(effects
				(font
					(size 1.27 1.27)
				)
			)
		)
		(duplicate_pad_numbers_are_jumpers no)
		(fp_rect
			(start -0.3048 -0.1016)
			(end 0.3048 0.9906)
			(stroke
				(width 0)
				(type default)
			)
			(fill no)
			(layer "F.CrtYd")
		)
		(fp_line
			(start -0.3048 0.9906)
			(end 0.3048 0.9906)
			(stroke
				(width 0.1)
				(type default)
			)
			(layer "F.Fab")
		)
		(fp_line
			(start 0.3048 0.9906)
			(end 0.3048 -0.1016)
			(stroke
				(width 0.1)
				(type default)
			)
			(layer "F.Fab")
		)
		(fp_line
			(start -0.3048 -0.1016)
			(end -0.3048 0.9906)
			(stroke
				(width 0.1)
				(type default)
			)
			(layer "F.Fab")
		)
		(fp_line
			(start 0.3048 -0.1016)
			(end -0.3048 -0.1016)
			(stroke
				(width 0.1)
				(type default)
			)
			(layer "F.Fab")
		)
		(pad "1" smd rect
			(at 0 0 270)
			(size 0.508 0.508)
			(layers "F.Cu" "F.Mask" "F.Paste")
			(net "FM_PVTT_KLM_EN_R")
		)
		(pad "2" smd rect
			(at 0 0.889 270)
			(size 0.508 0.508)
			(layers "F.Cu" "F.Mask" "F.Paste")
			(net "GND")
		)
		(zone
			(layer "F.Cu")
			(hatch none 0.5)
			(connect_pads
				(clearance 0)
			)
			(min_thickness 0.25)
			(keepout
				(tracks allowed)
				(vias not_allowed)
				(pads allowed)
				(copperpour not_allowed)
				(footprints allowed)
			)
			(placement
				(enabled no)
				(sheetname "")
			)
			(fill
				(thermal_gap 0.5)
				(thermal_bridge_width 0.5)
				(island_removal_mode 0)
			)
			(polygon
				(pts
					(xy 167.2336 -149.479) (xy 166.8526 -149.479) (xy 166.8526 -148.971) (xy 167.2336 -148.971)
				)
			)
		)
		(zone
			(layer "F.Cu")
			(hatch none 0.5)
			(connect_pads
				(clearance 0)
			)
			(min_thickness 0.25)
			(keepout
				(tracks not_allowed)
				(vias allowed)
				(pads allowed)
				(copperpour not_allowed)
				(footprints allowed)
			)
			(placement
				(enabled no)
				(sheetname "")
			)
			(fill
				(thermal_gap 0.5)
				(thermal_bridge_width 0.5)
				(island_removal_mode 0)
			)
			(polygon
				(pts
					(xy 167.2336 -149.479) (xy 166.8526 -149.479) (xy 166.8526 -148.971) (xy 167.2336 -148.971)
				)
			)
		)
	)
	(footprint ""
		(layer "F.Cu")
		(at 192.786 -66.06667 90)
		(property "Reference" "RT3"
			(at 1.01473 0.656336 0)
			(unlocked yes)
			(layer "F.SilkS")
			(effects
				(font
					(size 0.4064 0.254)
					(thickness 0.1524)
				)
			)
		)
		(property "Value" ""
			(at 0 0 90)
			(layer "F.Fab")
			(effects
				(font
					(size 1.27 1.27)
				)
			)
		)
		(duplicate_pad_numbers_are_jumpers no)
		(fp_poly
			(pts
				(xy -0.4953 -0.2032) (xy 0.4953 -0.2032) (xy 0.4953 1.6002) (xy -0.4953 1.6002)
			)
			(stroke
				(width 0)
				(type default)
			)
			(fill no)
			(layer "F.CrtYd")
		)
		(fp_line
			(start 0.4953 -0.2032)
			(end 0.4953 1.6002)
			(stroke
				(width 0.1)
				(type default)
			)
			(layer "F.Fab")
		)
		(fp_line
			(start -0.4953 -0.2032)
			(end 0.4953 -0.2032)
			(stroke
				(width 0.1)
				(type default)
			)
			(layer "F.Fab")
		)
		(fp_line
			(start 0.4953 1.6002)
			(end -0.4953 1.6002)
			(stroke
				(width 0.1)
				(type default)
			)
			(layer "F.Fab")
		)
		(fp_line
			(start -0.4953 1.6002)
			(end -0.4953 -0.2032)
			(stroke
				(width 0.1)
				(type default)
			)
			(layer "F.Fab")
		)
		(pad "1" smd rect
			(at 0 0 90)
			(size 0.762 0.889)
			(layers "F.Cu" "F.Mask" "F.Paste")
			(net "VR_PVCCIN_CPU0_PH2_BOOT")
		)
		(pad "2" smd rect
			(at 0 1.397 90)
			(size 0.762 0.889)
			(layers "F.Cu" "F.Mask" "F.Paste")
			(net "VR_PVCCIN_CPU0_PH2_BOOT_R")
		)
		(zone
			(layer "F.Cu")
			(hatch none 0.5)
			(connect_pads
				(clearance 0)
			)
			(min_thickness 0.25)
			(keepout
				(tracks allowed)
				(vias not_allowed)
				(pads allowed)
				(copperpour not_allowed)
				(footprints allowed)
			)
			(placement
				(enabled no)
				(sheetname "")
			)
			(fill
				(thermal_gap 0.5)
				(thermal_bridge_width 0.5)
				(island_removal_mode 0)
			)
			(polygon
				(pts
					(xy 193.7385 -66.44767) (xy 193.2305 -66.44767) (xy 193.2305 -65.68567) (xy 193.7385 -65.68567)
				)
			)
		)
		(zone
			(layer "F.Cu")
			(hatch none 0.5)
			(connect_pads
				(clearance 0)
			)
			(min_thickness 0.25)
			(keepout
				(tracks not_allowed)
				(vias allowed)
				(pads allowed)
				(copperpour not_allowed)
				(footprints allowed)
			)
			(placement
				(enabled no)
				(sheetname "")
			)
			(fill
				(thermal_gap 0.5)
				(thermal_bridge_width 0.5)
				(island_removal_mode 0)
			)
			(polygon
				(pts
					(xy 193.7385 -65.68567) (xy 193.7385 -66.44767) (xy 193.2305 -66.44767) (xy 193.2305 -65.68567)
				)
			)
		)
	)
	(footprint ""
		(layer "F.Cu")
		(at 397.750538 -75.050396)
		(property "Reference" "U8E2"
			(at 2.79908 2.95783 180)
			(unlocked yes)
			(layer "F.SilkS")
			(effects
				(font
					(size 0.7874 0.5842)
					(thickness 0.1524)
				)
				(justify left)
			)
		)
		(property "Value" ""
			(at 0 0 0)
			(layer "F.Fab")
			(effects
				(font
					(size 1.27 1.27)
				)
			)
		)
		(duplicate_pad_numbers_are_jumpers no)
		(fp_line
			(start 0.381 0.635)
			(end 0.381 1.27)
			(stroke
				(width 0.1524)
				(type default)
			)
			(layer "F.SilkS")
		)
		(fp_line
			(start 0.9525 -0.5715)
			(end 1.778 -0.5715)
			(stroke
				(width 0.1524)
				(type default)
			)
			(layer "F.SilkS")
		)
		(fp_line
			(start 0.9525 2.4765)
			(end 1.778 2.4765)
			(stroke
				(width 0.1524)
				(type default)
			)
			(layer "F.SilkS")
		)
		(fp_line
			(start 1.778 -0.5715)
			(end 1.778 0.3175)
			(stroke
				(width 0.1524)
				(type default)
			)
			(layer "F.SilkS")
		)
		(fp_line
			(start 1.778 2.4765)
			(end 1.778 1.5875)
			(stroke
				(width 0.1524)
				(type default)
			)
			(layer "F.SilkS")
		)
		(fp_circle
			(center -0.9525 -0.9271)
			(end -0.8255 -0.9271)
			(stroke
				(width 0.254)
				(type default)
			)
			(fill no)
			(layer "F.SilkS")
		)
		(fp_poly
			(pts
				(xy 1.778 2.4765) (xy 0.381 2.4765) (xy 0.381 -0.5715) (xy 1.778 -0.5715)
			)
			(stroke
				(width 0)
				(type default)
			)
			(fill no)
			(layer "F.CrtYd")
		)
		(fp_line
			(start 0.381 -0.5715)
			(end 0.381 2.4765)
			(stroke
				(width 0.1)
				(type default)
			)
			(layer "F.Fab")
		)
		(fp_line
			(start 0.381 2.4765)
			(end 1.778 2.4765)
			(stroke
				(width 0.1)
				(type default)
			)
			(layer "F.Fab")
		)
		(fp_line
			(start 1.778 -0.5715)
			(end 0.381 -0.5715)
			(stroke
				(width 0.1)
				(type default)
			)
			(layer "F.Fab")
		)
		(fp_line
			(start 1.778 2.4765)
			(end 1.778 -0.5715)
			(stroke
				(width 0.1)
				(type default)
			)
			(layer "F.Fab")
		)
		(fp_circle
			(center -0.9525 -0.9271)
			(end -0.8255 -0.9271)
			(stroke
				(width 0.254)
				(type default)
			)
			(fill no)
			(layer "F.Fab")
		)
		(pad "1" smd rect
			(at 0 0)
			(size 1.143 0.508)
			(layers "F.Cu" "F.Mask" "F.Paste")
			(net "GND")
		)
		(pad "2" smd rect
			(at 0 1.905)
			(size 1.143 0.508)
			(layers "F.Cu" "F.Mask" "F.Paste")
			(net "PWRGD_P12V_HSC_DLY_R")
		)
		(pad "3" smd rect
			(at 2.159 0.9525)
			(size 1.143 0.508)
			(layers "F.Cu" "F.Mask" "F.Paste")
			(net "PWRGD_P12V_HSC")
		)
	)
	(footprint ""
		(layer "F.Cu")
		(at 410.806138 -106.384598 90)
		(property "Reference" "R8C20"
			(at 0 0 90)
			(layer "F.SilkS")
			(hide yes)
			(effects
				(font
					(size 1.27 1.27)
				)
			)
		)
		(property "Value" ""
			(at 0 0 90)
			(layer "F.Fab")
			(effects
				(font
					(size 1.27 1.27)
				)
			)
		)
		(duplicate_pad_numbers_are_jumpers no)
		(fp_poly
			(pts
				(xy -0.2794 -0.1016) (xy 0.2794 -0.1016) (xy 0.2794 0.9906) (xy -0.2794 0.9906)
			)
			(stroke
				(width 0)
				(type default)
			)
			(fill no)
			(layer "F.CrtYd")
		)
		(fp_line
			(start 0.2794 -0.1016)
			(end -0.2794 -0.1016)
			(stroke
				(width 0.1)
				(type default)
			)
			(layer "F.Fab")
		)
		(fp_line
			(start -0.2794 -0.1016)
			(end -0.2794 0.9906)
			(stroke
				(width 0.1)
				(type default)
			)
			(layer "F.Fab")
		)
		(fp_line
			(start 0.2794 0.9906)
			(end 0.2794 -0.1016)
			(stroke
				(width 0.1)
				(type default)
			)
			(layer "F.Fab")
		)
		(fp_line
			(start -0.2794 0.9906)
			(end 0.2794 0.9906)
			(stroke
				(width 0.1)
				(type default)
			)
			(layer "F.Fab")
		)
		(pad "1" smd rect
			(at 0 0 90)
			(size 0.508 0.508)
			(layers "F.Cu" "F.Mask" "F.Paste")
			(net "SMB_HOST_STBY_LVC3_SDA_R1")
		)
		(pad "2" smd rect
			(at 0 0.889 90)
			(size 0.508 0.508)
			(layers "F.Cu" "F.Mask" "F.Paste")
			(net "SMB_HOST_STBY_LVC3_SDA")
		)
		(zone
			(layer "F.Cu")
			(hatch none 0.5)
			(connect_pads
				(clearance 0)
			)
			(min_thickness 0.25)
			(keepout
				(tracks allowed)
				(vias not_allowed)
				(pads allowed)
				(copperpour not_allowed)
				(footprints allowed)
			)
			(placement
				(enabled no)
				(sheetname "")
			)
			(fill
				(thermal_gap 0.5)
				(thermal_bridge_width 0.5)
				(island_removal_mode 0)
			)
			(polygon
				(pts
					(xy 411.060138 -106.130598) (xy 411.060138 -106.638598) (xy 411.441138 -106.638598) (xy 411.441138 -106.130598)
				)
			)
		)
		(zone
			(layer "F.Cu")
			(hatch none 0.5)
			(connect_pads
				(clearance 0)
			)
			(min_thickness 0.25)
			(keepout
				(tracks not_allowed)
				(vias allowed)
				(pads allowed)
				(copperpour not_allowed)
				(footprints allowed)
			)
			(placement
				(enabled no)
				(sheetname "")
			)
			(fill
				(thermal_gap 0.5)
				(thermal_bridge_width 0.5)
				(island_removal_mode 0)
			)
			(polygon
				(pts
					(xy 411.441138 -106.130598) (xy 411.441138 -106.638598) (xy 411.060138 -106.638598) (xy 411.060138 -106.130598)
				)
			)
		)
	)
	(footprint ""
		(layer "F.Cu")
		(at 398.39392 -68.59016 90)
		(property "Reference" "L8E1"
			(at -4.3434 7.72287 90)
			(unlocked yes)
			(layer "F.SilkS")
			(effects
				(font
					(size 0.7874 0.5842)
					(thickness 0.1524)
				)
				(justify left)
			)
		)
		(property "Value" ""
			(at 0 0 90)
			(layer "F.Fab")
			(effects
				(font
					(size 1.27 1.27)
				)
			)
		)
		(duplicate_pad_numbers_are_jumpers no)
		(fp_line
			(start 3.4036 -0.6731)
			(end 3.4036 6.1341)
			(stroke
				(width 0.1524)
				(type default)
			)
			(layer "F.SilkS")
		)
		(fp_line
			(start 2.5654 -0.6731)
			(end 3.4036 -0.6731)
			(stroke
				(width 0.1524)
				(type default)
			)
			(layer "F.SilkS")
		)
		(fp_line
			(start -3.4036 -0.6731)
			(end -2.5654 -0.6731)
			(stroke
				(width 0.1524)
				(type default)
			)
			(layer "F.SilkS")
		)
		(fp_line
			(start 3.4036 6.1341)
			(end 2.5654 6.1341)
			(stroke
				(width 0.1524)
				(type default)
			)
			(layer "F.SilkS")
		)
		(fp_line
			(start -2.5654 6.1341)
			(end -3.4036 6.1341)
			(stroke
				(width 0.1524)
				(type default)
			)
			(layer "F.SilkS")
		)
		(fp_line
			(start -3.4036 6.1341)
			(end -3.4036 -0.6731)
			(stroke
				(width 0.1524)
				(type default)
			)
			(layer "F.SilkS")
		)
		(fp_poly
			(pts
				(xy -3.4036 -0.6731) (xy -3.4036 6.1341) (xy 3.4036 6.1341) (xy 3.4036 -0.6731)
			)
			(stroke
				(width 0)
				(type default)
			)
			(fill no)
			(layer "F.CrtYd")
		)
		(fp_line
			(start 3.4036 -0.6731)
			(end 3.4036 6.1341)
			(stroke
				(width 0.1)
				(type default)
			)
			(layer "F.Fab")
		)
		(fp_line
			(start -3.4036 -0.6731)
			(end 3.4036 -0.6731)
			(stroke
				(width 0.1)
				(type default)
			)
			(layer "F.Fab")
		)
		(fp_line
			(start 3.4036 6.1341)
			(end -3.4036 6.1341)
			(stroke
				(width 0.1)
				(type default)
			)
			(layer "F.Fab")
		)
		(fp_line
			(start -3.4036 6.1341)
			(end -3.4036 -0.6731)
			(stroke
				(width 0.1)
				(type default)
			)
			(layer "F.Fab")
		)
		(pad "1" smd rect
			(at 0 0 90)
			(size 3.556 3.175)
			(layers "F.Cu" "F.Mask" "F.Paste")
			(net "VR_P5V_STBY_PHASE")
		)
		(pad "2" smd rect
			(at 0 5.461 90)
			(size 3.556 3.175)
			(layers "F.Cu" "F.Mask" "F.Paste")
			(net "P5V_STBY")
		)
	)
	(footprint ""
		(layer "F.Cu")
		(at 180.2257 -77.31125 90)
		(property "Reference" "R4D26"
			(at 0 0 90)
			(layer "F.SilkS")
			(hide yes)
			(effects
				(font
					(size 1.27 1.27)
				)
			)
		)
		(property "Value" ""
			(at 0 0 90)
			(layer "F.Fab")
			(effects
				(font
					(size 1.27 1.27)
				)
			)
		)
		(duplicate_pad_numbers_are_jumpers no)
		(fp_rect
			(start -0.2794 -0.1016)
			(end 0.2794 0.9906)
			(stroke
				(width 0)
				(type default)
			)
			(fill no)
			(layer "F.CrtYd")
		)
		(fp_line
			(start 0.2794 -0.1016)
			(end -0.2794 -0.1016)
			(stroke
				(width 0.1)
				(type default)
			)
			(layer "F.Fab")
		)
		(fp_line
			(start -0.2794 -0.1016)
			(end -0.2794 0.9906)
			(stroke
				(width 0.1)
				(type default)
			)
			(layer "F.Fab")
		)
		(fp_line
			(start 0.2794 0.9906)
			(end 0.2794 -0.1016)
			(stroke
				(width 0.1)
				(type default)
			)
			(layer "F.Fab")
		)
		(fp_line
			(start -0.2794 0.9906)
			(end 0.2794 0.9906)
			(stroke
				(width 0.1)
				(type default)
			)
			(layer "F.Fab")
		)
		(pad "1" smd rect
			(at 0 0 90)
			(size 0.508 0.508)
			(layers "F.Cu" "F.Mask" "F.Paste")
			(net "P3V3_STBY")
		)
		(pad "2" smd rect
			(at 0 0.889 90)
			(size 0.508 0.508)
			(layers "F.Cu" "F.Mask" "F.Paste")
			(net "VR_PVCCIN_CPU0_VDD")
		)
		(zone
			(layer "F.Cu")
			(hatch none 0.5)
			(connect_pads
				(clearance 0)
			)
			(min_thickness 0.25)
			(keepout
				(tracks not_allowed)
				(vias allowed)
				(pads allowed)
				(copperpour not_allowed)
				(footprints allowed)
			)
			(placement
				(enabled no)
				(sheetname "")
			)
			(fill
				(thermal_gap 0.5)
				(thermal_bridge_width 0.5)
				(island_removal_mode 0)
			)
			(polygon
				(pts
					(xy 180.4797 -77.05725) (xy 180.8607 -77.05725) (xy 180.8607 -77.56525) (xy 180.4797 -77.56525)
				)
			)
		)
		(zone
			(layer "F.Cu")
			(hatch none 0.5)
			(connect_pads
				(clearance 0)
			)
			(min_thickness 0.25)
			(keepout
				(tracks allowed)
				(vias not_allowed)
				(pads allowed)
				(copperpour not_allowed)
				(footprints allowed)
			)
			(placement
				(enabled no)
				(sheetname "")
			)
			(fill
				(thermal_gap 0.5)
				(thermal_bridge_width 0.5)
				(island_removal_mode 0)
			)
			(polygon
				(pts
					(xy 180.4797 -77.05725) (xy 180.8607 -77.05725) (xy 180.8607 -77.56525) (xy 180.4797 -77.56525)
				)
			)
		)
	)
	(footprint ""
		(layer "F.Cu")
		(at 181.991 -12.6365 180)
		(property "Reference" "C4G4"
			(at 0 0 180)
			(layer "F.SilkS")
			(hide yes)
			(effects
				(font
					(size 1.27 1.27)
				)
			)
		)
		(property "Value" ""
			(at 0 0 180)
			(layer "F.Fab")
			(effects
				(font
					(size 1.27 1.27)
				)
			)
		)
		(duplicate_pad_numbers_are_jumpers no)
		(fp_poly
			(pts
				(xy 0.3048 -0.1016) (xy 0.3048 0.9906) (xy -0.3048 0.9906) (xy -0.3048 -0.1016)
			)
			(stroke
				(width 0)
				(type default)
			)
			(fill no)
			(layer "F.CrtYd")
		)
		(fp_line
			(start 0.3048 0.9906)
			(end 0.3048 -0.1016)
			(stroke
				(width 0.1)
				(type default)
			)
			(layer "F.Fab")
		)
		(fp_line
			(start 0.3048 -0.1016)
			(end -0.3048 -0.1016)
			(stroke
				(width 0.1)
				(type default)
			)
			(layer "F.Fab")
		)
		(fp_line
			(start -0.3048 0.9906)
			(end 0.3048 0.9906)
			(stroke
				(width 0.1)
				(type default)
			)
			(layer "F.Fab")
		)
		(fp_line
			(start -0.3048 -0.1016)
			(end -0.3048 0.9906)
			(stroke
				(width 0.1)
				(type default)
			)
			(layer "F.Fab")
		)
		(pad "1" smd rect
			(at 0 0 180)
			(size 0.508 0.508)
			(layers "F.Cu" "F.Mask" "F.Paste")
			(net "VR_FET_SW_P12V_STBY_PVPP_GHJ")
		)
		(pad "2" smd rect
			(at 0 0.889 180)
			(size 0.508 0.508)
			(layers "F.Cu" "F.Mask" "F.Paste")
			(net "GND")
		)
		(zone
			(layer "F.Cu")
			(hatch none 0.5)
			(connect_pads
				(clearance 0)
			)
			(min_thickness 0.25)
			(keepout
				(tracks not_allowed)
				(vias allowed)
				(pads allowed)
				(copperpour not_allowed)
				(footprints allowed)
			)
			(placement
				(enabled no)
				(sheetname "")
			)
			(fill
				(thermal_gap 0.5)
				(thermal_bridge_width 0.5)
				(island_removal_mode 0)
			)
			(polygon
				(pts
					(xy 182.245 -13.2715) (xy 181.737 -13.2715) (xy 181.737 -12.8905) (xy 182.245 -12.8905)
				)
			)
		)
		(zone
			(layer "F.Cu")
			(hatch none 0.5)
			(connect_pads
				(clearance 0)
			)
			(min_thickness 0.25)
			(keepout
				(tracks allowed)
				(vias not_allowed)
				(pads allowed)
				(copperpour not_allowed)
				(footprints allowed)
			)
			(placement
				(enabled no)
				(sheetname "")
			)
			(fill
				(thermal_gap 0.5)
				(thermal_bridge_width 0.5)
				(island_removal_mode 0)
			)
			(polygon
				(pts
					(xy 182.245 -12.8905) (xy 181.737 -12.8905) (xy 181.737 -13.2715) (xy 182.245 -13.2715)
				)
			)
		)
	)
	(footprint ""
		(layer "F.Cu")
		(at 167.00627 -34.9631 90)
		(property "Reference" "C4F1"
			(at 0 0 90)
			(layer "F.SilkS")
			(hide yes)
			(effects
				(font
					(size 1.27 1.27)
				)
			)
		)
		(property "Value" ""
			(at 0 0 90)
			(layer "F.Fab")
			(effects
				(font
					(size 1.27 1.27)
				)
			)
		)
		(duplicate_pad_numbers_are_jumpers no)
		(fp_poly
			(pts
				(xy 0.3048 -0.1016) (xy 0.3048 0.9906) (xy -0.3048 0.9906) (xy -0.3048 -0.1016)
			)
			(stroke
				(width 0)
				(type default)
			)
			(fill no)
			(layer "F.CrtYd")
		)
		(fp_line
			(start 0.3048 -0.1016)
			(end -0.3048 -0.1016)
			(stroke
				(width 0.1)
				(type default)
			)
			(layer "F.Fab")
		)
		(fp_line
			(start -0.3048 -0.1016)
			(end -0.3048 0.9906)
			(stroke
				(width 0.1)
				(type default)
			)
			(layer "F.Fab")
		)
		(fp_line
			(start 0.3048 0.9906)
			(end 0.3048 -0.1016)
			(stroke
				(width 0.1)
				(type default)
			)
			(layer "F.Fab")
		)
		(fp_line
			(start -0.3048 0.9906)
			(end 0.3048 0.9906)
			(stroke
				(width 0.1)
				(type default)
			)
			(layer "F.Fab")
		)
		(pad "1" smd rect
			(at 0 0 90)
			(size 0.508 0.508)
			(layers "F.Cu" "F.Mask" "F.Paste")
			(net "P1V8_MCP_CPU1")
		)
		(pad "2" smd rect
			(at 0 0.889 90)
			(size 0.508 0.508)
			(layers "F.Cu" "F.Mask" "F.Paste")
			(net "GND")
		)
		(zone
			(layer "F.Cu")
			(hatch none 0.5)
			(connect_pads
				(clearance 0)
			)
			(min_thickness 0.25)
			(keepout
				(tracks allowed)
				(vias not_allowed)
				(pads allowed)
				(copperpour not_allowed)
				(footprints allowed)
			)
			(placement
				(enabled no)
				(sheetname "")
			)
			(fill
				(thermal_gap 0.5)
				(thermal_bridge_width 0.5)
				(island_removal_mode 0)
			)
			(polygon
				(pts
					(xy 167.26027 -34.7091) (xy 167.26027 -35.2171) (xy 167.64127 -35.2171) (xy 167.64127 -34.7091)
				)
			)
		)
		(zone
			(layer "F.Cu")
			(hatch none 0.5)
			(connect_pads
				(clearance 0)
			)
			(min_thickness 0.25)
			(keepout
				(tracks not_allowed)
				(vias allowed)
				(pads allowed)
				(copperpour not_allowed)
				(footprints allowed)
			)
			(placement
				(enabled no)
				(sheetname "")
			)
			(fill
				(thermal_gap 0.5)
				(thermal_bridge_width 0.5)
				(island_removal_mode 0)
			)
			(polygon
				(pts
					(xy 167.64127 -34.7091) (xy 167.64127 -35.2171) (xy 167.26027 -35.2171) (xy 167.26027 -34.7091)
				)
			)
		)
	)
	(footprint ""
		(layer "F.Cu")
		(at 28.438348 -80.3148 -90)
		(property "Reference" "R1D54"
			(at 0 0 270)
			(layer "F.SilkS")
			(hide yes)
			(effects
				(font
					(size 1.27 1.27)
				)
			)
		)
		(property "Value" ""
			(at 0 0 270)
			(layer "F.Fab")
			(effects
				(font
					(size 1.27 1.27)
				)
			)
		)
		(duplicate_pad_numbers_are_jumpers no)
		(fp_poly
			(pts
				(xy -0.2794 -0.1016) (xy 0.2794 -0.1016) (xy 0.2794 0.9906) (xy -0.2794 0.9906)
			)
			(stroke
				(width 0)
				(type default)
			)
			(fill no)
			(layer "F.CrtYd")
		)
		(fp_line
			(start -0.2794 0.9906)
			(end 0.2794 0.9906)
			(stroke
				(width 0.1)
				(type default)
			)
			(layer "F.Fab")
		)
		(fp_line
			(start 0.2794 0.9906)
			(end 0.2794 -0.1016)
			(stroke
				(width 0.1)
				(type default)
			)
			(layer "F.Fab")
		)
		(fp_line
			(start -0.2794 -0.1016)
			(end -0.2794 0.9906)
			(stroke
				(width 0.1)
				(type default)
			)
			(layer "F.Fab")
		)
		(fp_line
			(start 0.2794 -0.1016)
			(end -0.2794 -0.1016)
			(stroke
				(width 0.1)
				(type default)
			)
			(layer "F.Fab")
		)
		(pad "1" smd rect
			(at 0 0 270)
			(size 0.508 0.508)
			(layers "F.Cu" "F.Mask" "F.Paste")
			(net "VR_PVCCIN_CPU1_PH4_OCSET")
		)
		(pad "2" smd rect
			(at 0 0.889 270)
			(size 0.508 0.508)
			(layers "F.Cu" "F.Mask" "F.Paste")
			(net "GND")
		)
		(zone
			(layer "F.Cu")
			(hatch none 0.5)
			(connect_pads
				(clearance 0)
			)
			(min_thickness 0.25)
			(keepout
				(tracks not_allowed)
				(vias allowed)
				(pads allowed)
				(copperpour not_allowed)
				(footprints allowed)
			)
			(placement
				(enabled no)
				(sheetname "")
			)
			(fill
				(thermal_gap 0.5)
				(thermal_bridge_width 0.5)
				(island_removal_mode 0)
			)
			(polygon
				(pts
					(xy 27.803348 -80.5688) (xy 27.803348 -80.0608) (xy 28.184348 -80.0608) (xy 28.184348 -80.5688)
				)
			)
		)
		(zone
			(layer "F.Cu")
			(hatch none 0.5)
			(connect_pads
				(clearance 0)
			)
			(min_thickness 0.25)
			(keepout
				(tracks allowed)
				(vias not_allowed)
				(pads allowed)
				(copperpour not_allowed)
				(footprints allowed)
			)
			(placement
				(enabled no)
				(sheetname "")
			)
			(fill
				(thermal_gap 0.5)
				(thermal_bridge_width 0.5)
				(island_removal_mode 0)
			)
			(polygon
				(pts
					(xy 28.184348 -80.5688) (xy 28.184348 -80.0608) (xy 27.803348 -80.0608) (xy 27.803348 -80.5688)
				)
			)
		)
	)
	(footprint ""
		(layer "F.Cu")
		(at 164.615114 -115.55095 90)
		(property "Reference" "J4B2"
			(at -3.59283 -5.018024 90)
			(unlocked yes)
			(layer "F.SilkS")
			(effects
				(font
					(size 0.7874 0.5842)
					(thickness 0.1524)
				)
			)
		)
		(property "Value" ""
			(at 0 0 90)
			(layer "F.Fab")
			(effects
				(font
					(size 1.27 1.27)
				)
			)
		)
		(duplicate_pad_numbers_are_jumpers no)
		(fp_line
			(start -0.381 -3.81)
			(end -5.969 -3.81)
			(stroke
				(width 0.1524)
				(type default)
			)
			(layer "F.SilkS")
		)
		(fp_line
			(start -5.969 -3.81)
			(end -5.969 -3.048)
			(stroke
				(width 0.1524)
				(type default)
			)
			(layer "F.SilkS")
		)
		(fp_line
			(start -5.969 -3.048)
			(end -7.2771 -3.048)
			(stroke
				(width 0.1524)
				(type default)
			)
			(layer "F.SilkS")
		)
		(fp_line
			(start -7.2771 -3.048)
			(end -7.2771 28.194)
			(stroke
				(width 0.1524)
				(type default)
			)
			(layer "F.SilkS")
		)
		(fp_line
			(start 0.9271 28.194)
			(end 0.9271 -1.703832)
			(stroke
				(width 0.1524)
				(type default)
			)
			(layer "F.SilkS")
		)
		(fp_line
			(start -7.2771 28.194)
			(end 0.9271 28.194)
			(stroke
				(width 0.1524)
				(type default)
			)
			(layer "F.SilkS")
		)
		(fp_poly
			(pts
				(xy 1.661668 0.048006) (xy 2.931668 0.556006) (xy 2.931668 -0.459994)
			)
			(stroke
				(width 0)
				(type default)
			)
			(fill yes)
			(layer "F.SilkS")
		)
		(fp_poly
			(pts
				(xy -7.2771 28.194) (xy -7.2771 -3.048) (xy -5.969 -3.048) (xy -5.969 -3.81) (xy -0.381 -3.81) (xy -0.381 -3.048)
				(xy 0.9271 -3.048) (xy 0.9271 28.194)
			)
			(stroke
				(width 0)
				(type default)
			)
			(fill no)
			(layer "F.CrtYd")
		)
		(fp_line
			(start -0.381 -3.81)
			(end -0.381 -3.048)
			(stroke
				(width 0.1)
				(type default)
			)
			(layer "F.Fab")
		)
		(fp_line
			(start -5.969 -3.81)
			(end -0.381 -3.81)
			(stroke
				(width 0.1)
				(type default)
			)
			(layer "F.Fab")
		)
		(fp_line
			(start 0.9271 -3.048)
			(end 0.9271 28.194)
			(stroke
				(width 0.1)
				(type default)
			)
			(layer "F.Fab")
		)
		(fp_line
			(start -0.381 -3.048)
			(end 0.9271 -3.048)
			(stroke
				(width 0.1)
				(type default)
			)
			(layer "F.Fab")
		)
		(fp_line
			(start -5.969 -3.048)
			(end -5.969 -3.81)
			(stroke
				(width 0.1)
				(type default)
			)
			(layer "F.Fab")
		)
		(fp_line
			(start -7.2771 -3.048)
			(end -5.969 -3.048)
			(stroke
				(width 0.1)
				(type default)
			)
			(layer "F.Fab")
		)
		(fp_line
			(start -7.2771 28.1686)
			(end -7.2771 -3.048)
			(stroke
				(width 0.1)
				(type default)
			)
			(layer "F.Fab")
		)
		(fp_line
			(start 0.9271 28.194)
			(end -7.2771 28.194)
			(stroke
				(width 0.1)
				(type default)
			)
			(layer "F.Fab")
		)
		(fp_line
			(start -7.2771 28.194)
			(end -7.2771 28.1686)
			(stroke
				(width 0.1)
				(type default)
			)
			(layer "F.Fab")
		)
		(fp_poly
			(pts
				(xy 1.661668 0.048006) (xy 2.931668 -0.459994) (xy 2.931668 0.556006)
			)
			(stroke
				(width 0)
				(type default)
			)
			(fill yes)
			(layer "F.Fab")
		)
		(fp_text user "F1"
			(at -1.541018 -5.556758 0)
			(unlocked yes)
			(layer "F.SilkS")
			(effects
				(font
					(size 0.7874 0.5842)
					(thickness 0.1524)
				)
				(justify left)
			)
		)
		(fp_text user "F20"
			(at 1.772666 -3.46456 0)
			(unlocked yes)
			(layer "F.SilkS")
			(effects
				(font
					(size 0.7874 0.5842)
					(thickness 0.1524)
				)
				(justify left)
			)
		)
		(fp_text user "A20"
			(at 3.587496 -1.564386 0)
			(unlocked yes)
			(layer "F.SilkS")
			(effects
				(font
					(size 0.7874 0.5842)
					(thickness 0.1524)
				)
				(justify left)
			)
		)
		(fp_text user "F1"
			(at -7.72287 -0.8636 0)
			(unlocked yes)
			(layer "F.Fab")
			(effects
				(font
					(size 0.7874 0.5842)
					(thickness 0.1524)
				)
				(justify left)
			)
		)
		(fp_text user "A20"
			(at 1.95453 24.2824 0)
			(unlocked yes)
			(layer "F.Fab")
			(effects
				(font
					(size 0.7874 0.5842)
					(thickness 0.1524)
				)
				(justify left)
			)
		)
		(fp_text user "F20"
			(at -7.57047 24.9936 0)
			(unlocked yes)
			(layer "F.Fab")
			(effects
				(font
					(size 0.7874 0.5842)
					(thickness 0.1524)
				)
				(justify left)
			)
		)
		(pad "" np_thru_hole circle
			(at -3.175 26.5557 90)
			(size 0.254 0.254)
			(drill 1.27)
			(layers "*.Cu" "*.Mask")
			(clearance 0.8255)
			(thermal_gap 0.8255)
		)
		(pad "" np_thru_hole circle
			(at -0.127 -2.4257 90)
			(size 0.254 0.254)
			(drill 1.27)
			(layers "*.Cu" "*.Mask")
			(clearance 0.8255)
			(thermal_gap 0.8255)
		)
		(pad "A1" smd circle
			(at 0 0 90)
			(size 0.635 0.635)
			(layers "F.Cu" "F.Mask" "F.Paste")
			(net "P12V_STBY")
		)
		(pad "A2" smd circle
			(at 0 1.27 90)
			(size 0.635 0.635)
			(layers "F.Cu" "F.Mask" "F.Paste")
			(net "P12V_STBY")
		)
		(pad "A3" smd circle
			(at 0 2.54 90)
			(size 0.635 0.635)
			(layers "F.Cu" "F.Mask" "F.Paste")
			(net "P12V_STBY")
		)
		(pad "A4" smd circle
			(at 0 3.81 90)
			(size 0.635 0.635)
			(layers "F.Cu" "F.Mask" "F.Paste")
			(net "P12V_STBY")
		)
		(pad "A5" smd circle
			(at 0 5.08 90)
			(size 0.635 0.635)
			(layers "F.Cu" "F.Mask" "F.Paste")
			(net "P12V_STBY")
		)
		(pad "A6" smd circle
			(at 0 6.35 90)
			(size 0.635 0.635)
			(layers "F.Cu" "F.Mask" "F.Paste")
			(net "P12V_STBY")
		)
		(pad "A7" smd circle
			(at 0 7.62 90)
			(size 0.635 0.635)
			(layers "F.Cu" "F.Mask" "F.Paste")
			(net "P12V_STBY")
		)
		(pad "A8" smd circle
			(at 0 8.89 90)
			(size 0.635 0.635)
			(layers "F.Cu" "F.Mask" "F.Paste")
			(net "P12V_STBY")
		)
		(pad "A9" smd circle
			(at 0 10.16 90)
			(size 0.635 0.635)
			(layers "F.Cu" "F.Mask" "F.Paste")
			(net "GND")
		)
		(pad "A10" smd circle
			(at 0 11.43 90)
			(size 0.635 0.635)
			(layers "F.Cu" "F.Mask" "F.Paste")
			(net "GND")
		)
		(pad "A11" smd circle
			(at 0 12.7 90)
			(size 0.635 0.635)
			(layers "F.Cu" "F.Mask" "F.Paste")
			(net "P3V3_STBY")
		)
		(pad "A12" smd circle
			(at 0 13.97 90)
			(size 0.635 0.635)
			(layers "F.Cu" "F.Mask" "F.Paste")
			(net "GND")
		)
		(pad "A13" smd circle
			(at 0 15.24 90)
			(size 0.635 0.635)
			(layers "F.Cu" "F.Mask" "F.Paste")
			(net "P5V_STBY")
		)
		(pad "A14" smd circle
			(at 0 16.51 90)
			(size 0.635 0.635)
			(layers "F.Cu" "F.Mask" "F.Paste")
			(net "GND")
		)
		(pad "A15" smd circle
			(at 0 17.78 90)
			(size 0.635 0.635)
			(layers "F.Cu" "F.Mask" "F.Paste")
			(net "FM_P1V8MCP_CPU1_EN")
		)
		(pad "A16" smd circle
			(at 0 19.05 90)
			(size 0.635 0.635)
			(layers "F.Cu" "F.Mask" "F.Paste")
			(net "FM_PVCCIOMCP_CPU1_EN")
		)
		(pad "A17" smd circle
			(at 0 20.32 90)
			(size 0.635 0.635)
			(layers "F.Cu" "F.Mask" "F.Paste")
			(net "GND")
		)
		(pad "A18" smd circle
			(at 0 21.59 90)
			(size 0.635 0.635)
			(layers "F.Cu" "F.Mask" "F.Paste")
			(net "SMB_VR_STBY_LVC3_SCL")
		)
		(pad "A19" smd circle
			(at 0 22.86 90)
			(size 0.635 0.635)
			(layers "F.Cu" "F.Mask" "F.Paste")
			(net "SVID_ALERT0_CPU1_R_N")
		)
		(pad "A20" smd circle
			(at 0 24.13 90)
			(size 0.635 0.635)
			(layers "F.Cu" "F.Mask" "F.Paste")
			(net "SVID_CLK0_CPU1_R")
		)
		(pad "B1" smd circle
			(at -1.27 0 90)
			(size 0.635 0.635)
			(layers "F.Cu" "F.Mask" "F.Paste")
			(net "P12V_STBY")
		)
		(pad "B2" smd circle
			(at -1.27 1.27 90)
			(size 0.635 0.635)
			(layers "F.Cu" "F.Mask" "F.Paste")
			(net "P12V_STBY")
		)
		(pad "B3" smd circle
			(at -1.27 2.54 90)
			(size 0.635 0.635)
			(layers "F.Cu" "F.Mask" "F.Paste")
			(net "P12V_STBY")
		)
		(pad "B4" smd circle
			(at -1.27 3.81 90)
			(size 0.635 0.635)
			(layers "F.Cu" "F.Mask" "F.Paste")
			(net "P12V_STBY")
		)
		(pad "B5" smd circle
			(at -1.27 5.08 90)
			(size 0.635 0.635)
			(layers "F.Cu" "F.Mask" "F.Paste")
			(net "P12V_STBY")
		)
		(pad "B6" smd circle
			(at -1.27 6.35 90)
			(size 0.635 0.635)
			(layers "F.Cu" "F.Mask" "F.Paste")
			(net "P12V_STBY")
		)
		(pad "B7" smd circle
			(at -1.27 7.62 90)
			(size 0.635 0.635)
			(layers "F.Cu" "F.Mask" "F.Paste")
			(net "P12V_STBY")
		)
		(pad "B8" smd circle
			(at -1.27 8.89 90)
			(size 0.635 0.635)
			(layers "F.Cu" "F.Mask" "F.Paste")
			(net "P12V_STBY")
		)
		(pad "B9" smd circle
			(at -1.27 10.16 90)
			(size 0.635 0.635)
			(layers "F.Cu" "F.Mask" "F.Paste")
			(net "GND")
		)
		(pad "B10" smd circle
			(at -1.27 11.43 90)
			(size 0.635 0.635)
			(layers "F.Cu" "F.Mask" "F.Paste")
			(net "GND")
		)
		(pad "B11" smd circle
			(at -1.27 12.7 90)
			(size 0.635 0.635)
			(layers "F.Cu" "F.Mask" "F.Paste")
			(net "P3V3_STBY")
		)
		(pad "B12" smd circle
			(at -1.27 13.97 90)
			(size 0.635 0.635)
			(layers "F.Cu" "F.Mask" "F.Paste")
			(net "GND")
		)
		(pad "B13" smd circle
			(at -1.27 15.24 90)
			(size 0.635 0.635)
			(layers "F.Cu" "F.Mask" "F.Paste")
			(net "P5V_STBY")
		)
		(pad "B14" smd circle
			(at -1.27 16.51 90)
			(size 0.635 0.635)
			(layers "F.Cu" "F.Mask" "F.Paste")
			(net "GND")
		)
		(pad "B15" smd circle
			(at -1.27 17.78 90)
			(size 0.635 0.635)
			(layers "F.Cu" "F.Mask" "F.Paste")
			(net "PWRGD_P1V8MCP_CPU1")
		)
		(pad "B16" smd circle
			(at -1.27 19.05 90)
			(size 0.635 0.635)
			(layers "F.Cu" "F.Mask" "F.Paste")
			(net "PWRGD_PVCCIOMCP_CPU1")
		)
		(pad "B17" smd circle
			(at -1.27 20.32 90)
			(size 0.635 0.635)
			(layers "F.Cu" "F.Mask" "F.Paste")
			(net "GND")
		)
		(pad "B18" smd circle
			(at -1.27 21.59 90)
			(size 0.635 0.635)
			(layers "F.Cu" "F.Mask" "F.Paste")
			(net "SMB_VR_STBY_LVC3_SDA")
		)
		(pad "B19" smd circle
			(at -1.27 22.86 90)
			(size 0.635 0.635)
			(layers "F.Cu" "F.Mask" "F.Paste")
			(net "SVID_ALERT1_CPU1_R_N")
		)
		(pad "B20" smd circle
			(at -1.27 24.13 90)
			(size 0.635 0.635)
			(layers "F.Cu" "F.Mask" "F.Paste")
			(net "SVID_DIO0_CPU1_R")
		)
		(pad "C1" smd circle
			(at -2.54 0 90)
			(size 0.635 0.635)
			(layers "F.Cu" "F.Mask" "F.Paste")
			(net "GND")
		)
		(pad "C2" smd circle
			(at -2.54 1.27 90)
			(size 0.635 0.635)
			(layers "F.Cu" "F.Mask" "F.Paste")
			(net "GND")
		)
		(pad "C3" smd circle
			(at -2.54 2.54 90)
			(size 0.635 0.635)
			(layers "F.Cu" "F.Mask" "F.Paste")
			(net "GND")
		)
		(pad "C4" smd circle
			(at -2.54 3.81 90)
			(size 0.635 0.635)
			(layers "F.Cu" "F.Mask" "F.Paste")
			(net "GND")
		)
		(pad "C5" smd circle
			(at -2.54 5.08 90)
			(size 0.635 0.635)
			(layers "F.Cu" "F.Mask" "F.Paste")
			(net "GND")
		)
		(pad "C6" smd circle
			(at -2.54 6.35 90)
			(size 0.635 0.635)
			(layers "F.Cu" "F.Mask" "F.Paste")
			(net "GND")
		)
		(pad "C7" smd circle
			(at -2.54 7.62 90)
			(size 0.635 0.635)
			(layers "F.Cu" "F.Mask" "F.Paste")
			(net "GND")
		)
		(pad "C8" smd circle
			(at -2.54 8.89 90)
			(size 0.635 0.635)
			(layers "F.Cu" "F.Mask" "F.Paste")
			(net "GND")
		)
		(pad "C9" smd circle
			(at -2.54 10.16 90)
			(size 0.635 0.635)
			(layers "F.Cu" "F.Mask" "F.Paste")
			(net "GND")
		)
		(pad "C10" smd circle
			(at -2.54 11.43 90)
			(size 0.635 0.635)
			(layers "F.Cu" "F.Mask" "F.Paste")
			(net "GND")
		)
		(pad "C11" smd circle
			(at -2.54 12.7 90)
			(size 0.635 0.635)
			(layers "F.Cu" "F.Mask" "F.Paste")
			(net "P3V3_STBY")
		)
		(pad "C12" smd circle
			(at -2.54 13.97 90)
			(size 0.635 0.635)
			(layers "F.Cu" "F.Mask" "F.Paste")
			(net "GND")
		)
		(pad "C13" smd circle
			(at -2.54 15.24 90)
			(size 0.635 0.635)
			(layers "F.Cu" "F.Mask" "F.Paste")
			(net "P5V_STBY")
		)
		(pad "C14" smd circle
			(at -2.54 16.51 90)
			(size 0.635 0.635)
			(layers "F.Cu" "F.Mask" "F.Paste")
			(net "GND")
		)
		(pad "C15" smd circle
			(at -2.54 17.78 90)
			(size 0.635 0.635)
			(layers "F.Cu" "F.Mask" "F.Paste")
			(net "GND")
		)
		(pad "C16" smd circle
			(at -2.54 19.05 90)
			(size 0.635 0.635)
			(layers "F.Cu" "F.Mask" "F.Paste")
			(net "GND")
		)
		(pad "C17" smd circle
			(at -2.54 20.32 90)
			(size 0.635 0.635)
			(layers "F.Cu" "F.Mask" "F.Paste")
			(net "PVCCIOMCP_CPU1")
		)
		(pad "C18" smd circle
			(at -2.54 21.59 90)
			(size 0.635 0.635)
			(layers "F.Cu" "F.Mask" "F.Paste")
			(net "PVCCIOMCP_CPU1")
		)
		(pad "C19" smd circle
			(at -2.54 22.86 90)
			(size 0.635 0.635)
			(layers "F.Cu" "F.Mask" "F.Paste")
			(net "PVCCIOMCP_CPU1")
		)
		(pad "C20" smd circle
			(at -2.54 24.13 90)
			(size 0.635 0.635)
			(layers "F.Cu" "F.Mask" "F.Paste")
			(net "FM_PVCCMCP_CPU1_EN")
		)
		(pad "D1" smd circle
			(at -3.81 0 90)
			(size 0.635 0.635)
			(layers "F.Cu" "F.Mask" "F.Paste")
			(net "P3V3")
		)
		(pad "D2" smd circle
			(at -3.81 1.27 90)
			(size 0.635 0.635)
			(layers "F.Cu" "F.Mask" "F.Paste")
			(net "GND")
		)
		(pad "D3" smd circle
			(at -3.81 2.54 90)
			(size 0.635 0.635)
			(layers "F.Cu" "F.Mask" "F.Paste")
			(net "GND")
		)
		(pad "D4" smd circle
			(at -3.81 3.81 90)
			(size 0.635 0.635)
			(layers "F.Cu" "F.Mask" "F.Paste")
			(net "GND")
		)
		(pad "D5" smd circle
			(at -3.81 5.08 90)
			(size 0.635 0.635)
			(layers "F.Cu" "F.Mask" "F.Paste")
			(net "GND")
		)
		(pad "D6" smd circle
			(at -3.81 6.35 90)
			(size 0.635 0.635)
			(layers "F.Cu" "F.Mask" "F.Paste")
			(net "GND")
		)
		(pad "D7" smd circle
			(at -3.81 7.62 90)
			(size 0.635 0.635)
			(layers "F.Cu" "F.Mask" "F.Paste")
			(net "GND")
		)
		(pad "D8" smd circle
			(at -3.81 8.89 90)
			(size 0.635 0.635)
			(layers "F.Cu" "F.Mask" "F.Paste")
			(net "GND")
		)
		(pad "D9" smd circle
			(at -3.81 10.16 90)
			(size 0.635 0.635)
			(layers "F.Cu" "F.Mask" "F.Paste")
			(net "GND")
		)
		(pad "D10" smd circle
			(at -3.81 11.43 90)
			(size 0.635 0.635)
			(layers "F.Cu" "F.Mask" "F.Paste")
			(net "GND")
		)
		(pad "D11" smd circle
			(at -3.81 12.7 90)
			(size 0.635 0.635)
			(layers "F.Cu" "F.Mask" "F.Paste")
			(net "GND")
		)
		(pad "D12" smd circle
			(at -3.81 13.97 90)
			(size 0.635 0.635)
			(layers "F.Cu" "F.Mask" "F.Paste")
			(net "GND")
		)
		(pad "D13" smd circle
			(at -3.81 15.24 90)
			(size 0.635 0.635)
			(layers "F.Cu" "F.Mask" "F.Paste")
			(net "GND")
		)
		(pad "D14" smd circle
			(at -3.81 16.51 90)
			(size 0.635 0.635)
			(layers "F.Cu" "F.Mask" "F.Paste")
			(net "GND")
		)
		(pad "D15" smd circle
			(at -3.81 17.78 90)
			(size 0.635 0.635)
			(layers "F.Cu" "F.Mask" "F.Paste")
			(net "GND")
		)
		(pad "D16" smd circle
			(at -3.81 19.05 90)
			(size 0.635 0.635)
			(layers "F.Cu" "F.Mask" "F.Paste")
			(net "GND")
		)
		(pad "D17" smd circle
			(at -3.81 20.32 90)
			(size 0.635 0.635)
			(layers "F.Cu" "F.Mask" "F.Paste")
			(net "PVCCIOMCP_CPU1")
		)
		(pad "D18" smd circle
			(at -3.81 21.59 90)
			(size 0.635 0.635)
			(layers "F.Cu" "F.Mask" "F.Paste")
			(net "PVCCIOMCP_CPU1")
		)
		(pad "D19" smd circle
			(at -3.81 22.86 90)
			(size 0.635 0.635)
			(layers "F.Cu" "F.Mask" "F.Paste")
			(net "PVCCIOMCP_CPU1")
		)
		(pad "D20" smd circle
			(at -3.81 24.13 90)
			(size 0.635 0.635)
			(layers "F.Cu" "F.Mask" "F.Paste")
			(net "PWRGD_PVCCMCP_CPU1")
		)
		(pad "E1" smd circle
			(at -5.08 0 90)
			(size 0.635 0.635)
			(layers "F.Cu" "F.Mask" "F.Paste")
			(net "FM_CPU1_VRM_322M_156M_OSC_EN")
		)
		(pad "E2" smd circle
			(at -5.08 1.27 90)
			(size 0.635 0.635)
			(layers "F.Cu" "F.Mask" "F.Paste")
			(net "GND")
		)
		(pad "E3" smd circle
			(at -5.08 2.54 90)
			(size 0.635 0.635)
			(layers "F.Cu" "F.Mask" "F.Paste")
			(net "GND")
		)
		(pad "E4" smd circle
			(at -5.08 3.81 90)
			(size 0.635 0.635)
			(layers "F.Cu" "F.Mask" "F.Paste")
			(net "GND")
		)
		(pad "E5" smd circle
			(at -5.08 5.08 90)
			(size 0.635 0.635)
			(layers "F.Cu" "F.Mask" "F.Paste")
			(net "GND")
		)
		(pad "E6" smd circle
			(at -5.08 6.35 90)
			(size 0.635 0.635)
			(layers "F.Cu" "F.Mask" "F.Paste")
			(net "GND")
		)
		(pad "E7" smd circle
			(at -5.08 7.62 90)
			(size 0.635 0.635)
			(layers "F.Cu" "F.Mask" "F.Paste")
			(net "GND")
		)
		(pad "E8" smd circle
			(at -5.08 8.89 90)
			(size 0.635 0.635)
			(layers "F.Cu" "F.Mask" "F.Paste")
			(net "VSENSE_PVCCIOMCP_CPU1_SKT_VSEN")
		)
		(pad "E9" smd circle
			(at -5.08 10.16 90)
			(size 0.635 0.635)
			(layers "F.Cu" "F.Mask" "F.Paste")
			(net "GND")
		)
		(pad "E10" smd circle
			(at -5.08 11.43 90)
			(size 0.635 0.635)
			(layers "F.Cu" "F.Mask" "F.Paste")
			(net "VR_PVCCIOMCP_CPU1_XADDR1")
		)
		(pad "E11" smd circle
			(at -5.08 12.7 90)
			(size 0.635 0.635)
			(layers "F.Cu" "F.Mask" "F.Paste")
			(net "GND")
		)
		(pad "E12" smd circle
			(at -5.08 13.97 90)
			(size 0.635 0.635)
			(layers "F.Cu" "F.Mask" "F.Paste")
			(net "GND")
		)
		(pad "E13" smd circle
			(at -5.08 15.24 90)
			(size 0.635 0.635)
			(layers "F.Cu" "F.Mask" "F.Paste")
			(net "GND")
		)
		(pad "E14" smd circle
			(at -5.08 16.51 90)
			(size 0.635 0.635)
			(layers "F.Cu" "F.Mask" "F.Paste")
			(net "GND")
		)
		(pad "E15" smd circle
			(at -5.08 17.78 90)
			(size 0.635 0.635)
			(layers "F.Cu" "F.Mask" "F.Paste")
			(net "PVCCIOMCP_CPU1")
		)
		(pad "E16" smd circle
			(at -5.08 19.05 90)
			(size 0.635 0.635)
			(layers "F.Cu" "F.Mask" "F.Paste")
			(net "PVCCIOMCP_CPU1")
		)
		(pad "E17" smd circle
			(at -5.08 20.32 90)
			(size 0.635 0.635)
			(layers "F.Cu" "F.Mask" "F.Paste")
			(net "PVCCIOMCP_CPU1")
		)
		(pad "E18" smd circle
			(at -5.08 21.59 90)
			(size 0.635 0.635)
			(layers "F.Cu" "F.Mask" "F.Paste")
			(net "PVCCIOMCP_CPU1")
		)
		(pad "E19" smd circle
			(at -5.08 22.86 90)
			(size 0.635 0.635)
			(layers "F.Cu" "F.Mask" "F.Paste")
			(net "PVCCIOMCP_CPU1")
		)
		(pad "E20" smd circle
			(at -5.08 24.13 90)
			(size 0.635 0.635)
			(layers "F.Cu" "F.Mask" "F.Paste")
			(net "SVID_CLK1_CPU1_R")
		)
		(pad "F1" smd circle
			(at -6.35 0 90)
			(size 0.635 0.635)
			(layers "F.Cu" "F.Mask" "F.Paste")
			(net "PVCCIO_CPU1")
		)
		(pad "F2" smd circle
			(at -6.35 1.27 90)
			(size 0.635 0.635)
			(layers "F.Cu" "F.Mask" "F.Paste")
			(net "GND")
		)
		(pad "F3" smd circle
			(at -6.35 2.54 90)
			(size 0.635 0.635)
			(layers "F.Cu" "F.Mask" "F.Paste")
			(net "GND")
		)
		(pad "F4" smd circle
			(at -6.35 3.81 90)
			(size 0.635 0.635)
			(layers "F.Cu" "F.Mask" "F.Paste")
			(net "GND")
		)
		(pad "F5" smd circle
			(at -6.35 5.08 90)
			(size 0.635 0.635)
			(layers "F.Cu" "F.Mask" "F.Paste")
			(net "GND")
		)
		(pad "F6" smd circle
			(at -6.35 6.35 90)
			(size 0.635 0.635)
			(layers "F.Cu" "F.Mask" "F.Paste")
			(net "GND")
		)
		(pad "F7" smd circle
			(at -6.35 7.62 90)
			(size 0.635 0.635)
			(layers "F.Cu" "F.Mask" "F.Paste")
			(net "GND")
		)
		(pad "F8" smd circle
			(at -6.35 8.89 90)
			(size 0.635 0.635)
			(layers "F.Cu" "F.Mask" "F.Paste")
			(net "VSENSE_PVCCIOMCP_CPU1_SKT_VRTN")
		)
		(pad "F9" smd circle
			(at -6.35 10.16 90)
			(size 0.635 0.635)
			(layers "F.Cu" "F.Mask" "F.Paste")
			(net "GND")
		)
		(pad "F10" smd circle
			(at -6.35 11.43 90)
			(size 0.635 0.635)
			(layers "F.Cu" "F.Mask" "F.Paste")
			(net "VR_PVCCMCP_CPU1_XADDR2")
		)
		(pad "F11" smd circle
			(at -6.35 12.7 90)
			(size 0.635 0.635)
			(layers "F.Cu" "F.Mask" "F.Paste")
			(net "GND")
		)
		(pad "F12" smd circle
			(at -6.35 13.97 90)
			(size 0.635 0.635)
			(layers "F.Cu" "F.Mask" "F.Paste")
			(net "GND")
		)
		(pad "F13" smd circle
			(at -6.35 15.24 90)
			(size 0.635 0.635)
			(layers "F.Cu" "F.Mask" "F.Paste")
			(net "GND")
		)
		(pad "F14" smd circle
			(at -6.35 16.51 90)
			(size 0.635 0.635)
			(layers "F.Cu" "F.Mask" "F.Paste")
			(net "GND")
		)
		(pad "F15" smd circle
			(at -6.35 17.78 90)
			(size 0.635 0.635)
			(layers "F.Cu" "F.Mask" "F.Paste")
			(net "PVCCIOMCP_CPU1")
		)
		(pad "F16" smd circle
			(at -6.35 19.05 90)
			(size 0.635 0.635)
			(layers "F.Cu" "F.Mask" "F.Paste")
			(net "PVCCIOMCP_CPU1")
		)
		(pad "F17" smd circle
			(at -6.35 20.32 90)
			(size 0.635 0.635)
			(layers "F.Cu" "F.Mask" "F.Paste")
			(net "PVCCIOMCP_CPU1")
		)
		(pad "F18" smd circle
			(at -6.35 21.59 90)
			(size 0.635 0.635)
			(layers "F.Cu" "F.Mask" "F.Paste")
			(net "PVCCIOMCP_CPU1")
		)
		(pad "F19" smd circle
			(at -6.35 22.86 90)
			(size 0.635 0.635)
			(layers "F.Cu" "F.Mask" "F.Paste")
			(net "PVCCIOMCP_CPU1")
		)
		(pad "F20" smd circle
			(at -6.35 24.13 90)
			(size 0.635 0.635)
			(layers "F.Cu" "F.Mask" "F.Paste")
			(net "SVID_DIO1_CPU1_R")
		)
		(zone
			(layers "F.Cu" "B.Cu" "In1.Cu" "In2.Cu" "In3.Cu" "In4.Cu" "In5.Cu" "In6.Cu"
				"In7.Cu" "In8.Cu" "In9.Cu" "In10.Cu" "In11.Cu" "In12.Cu"
			)
			(hatch none 0.5)
			(connect_pads
				(clearance 0)
			)
			(min_thickness 0.25)
			(keepout
				(tracks not_allowed)
				(vias allowed)
				(pads allowed)
				(copperpour not_allowed)
				(footprints allowed)
			)
			(placement
				(enabled no)
				(sheetname "")
			)
			(fill
				(thermal_gap 0.5)
				(thermal_bridge_width 0.5)
				(island_removal_mode 0)
			)
			(polygon
				(pts
					(arc
						(start 163.141914 -115.42395)
						(mid 161.236914 -115.42395)
						(end 163.141914 -115.42395)
					)
				)
			)
		)
		(zone
			(layers "F.Cu" "B.Cu" "In1.Cu" "In2.Cu" "In3.Cu" "In4.Cu" "In5.Cu" "In6.Cu"
				"In7.Cu" "In8.Cu" "In9.Cu" "In10.Cu" "In11.Cu" "In12.Cu"
			)
			(hatch none 0.5)
			(connect_pads
				(clearance 0)
			)
			(min_thickness 0.25)
			(keepout
				(tracks not_allowed)
				(vias allowed)
				(pads allowed)
				(copperpour not_allowed)
				(footprints allowed)
			)
			(placement
				(enabled no)
				(sheetname "")
			)
			(fill
				(thermal_gap 0.5)
				(thermal_bridge_width 0.5)
				(island_removal_mode 0)
			)
			(polygon
				(pts
					(arc
						(start 192.123314 -112.37595)
						(mid 190.218314 -112.37595)
						(end 192.123314 -112.37595)
					)
				)
			)
		)
	)
	(footprint ""
		(layer "F.Cu")
		(at 193.6369 -88.19642)
		(property "Reference" "R4D68"
			(at 0 0 0)
			(layer "F.SilkS")
			(hide yes)
			(effects
				(font
					(size 1.27 1.27)
				)
			)
		)
		(property "Value" ""
			(at 0 0 0)
			(layer "F.Fab")
			(effects
				(font
					(size 1.27 1.27)
				)
			)
		)
		(duplicate_pad_numbers_are_jumpers no)
		(fp_poly
			(pts
				(xy -0.2794 -0.1016) (xy 0.2794 -0.1016) (xy 0.2794 0.9906) (xy -0.2794 0.9906)
			)
			(stroke
				(width 0)
				(type default)
			)
			(fill no)
			(layer "F.CrtYd")
		)
		(fp_line
			(start -0.2794 -0.1016)
			(end -0.2794 0.9906)
			(stroke
				(width 0.1)
				(type default)
			)
			(layer "F.Fab")
		)
		(fp_line
			(start -0.2794 0.9906)
			(end 0.2794 0.9906)
			(stroke
				(width 0.1)
				(type default)
			)
			(layer "F.Fab")
		)
		(fp_line
			(start 0.2794 -0.1016)
			(end -0.2794 -0.1016)
			(stroke
				(width 0.1)
				(type default)
			)
			(layer "F.Fab")
		)
		(fp_line
			(start 0.2794 0.9906)
			(end 0.2794 -0.1016)
			(stroke
				(width 0.1)
				(type default)
			)
			(layer "F.Fab")
		)
		(pad "1" smd rect
			(at 0 0)
			(size 0.508 0.508)
			(layers "F.Cu" "F.Mask" "F.Paste")
			(net "VR_PVCCIN_CPU0_PH5_OCSET")
		)
		(pad "2" smd rect
			(at 0 0.889)
			(size 0.508 0.508)
			(layers "F.Cu" "F.Mask" "F.Paste")
			(net "GND")
		)
		(zone
			(layer "F.Cu")
			(hatch none 0.5)
			(connect_pads
				(clearance 0)
			)
			(min_thickness 0.25)
			(keepout
				(tracks allowed)
				(vias not_allowed)
				(pads allowed)
				(copperpour not_allowed)
				(footprints allowed)
			)
			(placement
				(enabled no)
				(sheetname "")
			)
			(fill
				(thermal_gap 0.5)
				(thermal_bridge_width 0.5)
				(island_removal_mode 0)
			)
			(polygon
				(pts
					(xy 193.3829 -87.94242) (xy 193.8909 -87.94242) (xy 193.8909 -87.56142) (xy 193.3829 -87.56142)
				)
			)
		)
		(zone
			(layer "F.Cu")
			(hatch none 0.5)
			(connect_pads
				(clearance 0)
			)
			(min_thickness 0.25)
			(keepout
				(tracks not_allowed)
				(vias allowed)
				(pads allowed)
				(copperpour not_allowed)
				(footprints allowed)
			)
			(placement
				(enabled no)
				(sheetname "")
			)
			(fill
				(thermal_gap 0.5)
				(thermal_bridge_width 0.5)
				(island_removal_mode 0)
			)
			(polygon
				(pts
					(xy 193.3829 -87.56142) (xy 193.8909 -87.56142) (xy 193.8909 -87.94242) (xy 193.3829 -87.94242)
				)
			)
		)
	)
	(footprint ""
		(layer "F.Cu")
		(at 496.000024 -141.849856 180)
		(property "Reference" "J9A2"
			(at -0.48768 -1.76403 0)
			(unlocked yes)
			(layer "B.SilkS")
			(effects
				(font
					(size 0.7874 0.5842)
					(thickness 0.1524)
				)
				(justify left mirror)
			)
		)
		(property "Value" ""
			(at 0 0 180)
			(layer "F.Fab")
			(effects
				(font
					(size 1.27 1.27)
				)
			)
		)
		(duplicate_pad_numbers_are_jumpers no)
		(fp_line
			(start 4.586478 14.254988)
			(end -2.078482 14.254988)
			(stroke
				(width 0.1524)
				(type default)
			)
			(layer "F.SilkS")
		)
		(fp_line
			(start 4.586478 13.302488)
			(end 4.586478 14.254988)
			(stroke
				(width 0.1524)
				(type default)
			)
			(layer "F.SilkS")
		)
		(fp_line
			(start 4.586478 7.777988)
			(end 4.078478 7.777988)
			(stroke
				(width 0.1524)
				(type default)
			)
			(layer "F.SilkS")
		)
		(fp_line
			(start 4.586478 4.221988)
			(end 4.586478 7.777988)
			(stroke
				(width 0.1524)
				(type default)
			)
			(layer "F.SilkS")
		)
		(fp_line
			(start 4.586478 -1.302512)
			(end 4.078478 -1.302512)
			(stroke
				(width 0.1524)
				(type default)
			)
			(layer "F.SilkS")
		)
		(fp_line
			(start 4.586478 -2.255012)
			(end 4.586478 -1.302512)
			(stroke
				(width 0.1524)
				(type default)
			)
			(layer "F.SilkS")
		)
		(fp_line
			(start 4.078478 13.302488)
			(end 4.586478 13.302488)
			(stroke
				(width 0.1524)
				(type default)
			)
			(layer "F.SilkS")
		)
		(fp_line
			(start 4.078478 7.777988)
			(end 4.078478 13.302488)
			(stroke
				(width 0.1524)
				(type default)
			)
			(layer "F.SilkS")
		)
		(fp_line
			(start 4.078478 4.221988)
			(end 4.586478 4.221988)
			(stroke
				(width 0.1524)
				(type default)
			)
			(layer "F.SilkS")
		)
		(fp_line
			(start 4.078478 -1.302512)
			(end 4.078478 4.221988)
			(stroke
				(width 0.1524)
				(type default)
			)
			(layer "F.SilkS")
		)
		(fp_line
			(start -2.078482 14.254988)
			(end -2.078482 -2.255012)
			(stroke
				(width 0.1524)
				(type default)
			)
			(layer "F.SilkS")
		)
		(fp_line
			(start -2.078482 -2.255012)
			(end 4.586478 -2.255012)
			(stroke
				(width 0.1524)
				(type default)
			)
			(layer "F.SilkS")
		)
		(fp_poly
			(pts
				(xy -4.7371 -0.247904) (xy -4.7371 0.77216) (xy -3.4671 0.262128)
			)
			(stroke
				(width 0)
				(type default)
			)
			(fill yes)
			(layer "F.SilkS")
		)
		(fp_poly
			(pts
				(xy -4.413758 -0.548894) (xy -4.413758 0.47117) (xy -3.143758 -0.038862)
			)
			(stroke
				(width 0)
				(type default)
			)
			(fill yes)
			(layer "B.SilkS")
		)
		(fp_poly
			(pts
				(xy -2.078482 14.254988) (xy -2.078482 -2.255012) (xy 4.586478 -2.255012) (xy 4.586478 -1.302512)
				(xy 4.078478 -1.302512) (xy 4.078478 4.221988) (xy 4.586478 4.221988) (xy 4.586478 7.777988) (xy 4.078478 7.777988)
				(xy 4.078478 13.302488) (xy 4.586478 13.302488) (xy 4.586478 14.254988)
			)
			(stroke
				(width 0)
				(type default)
			)
			(fill no)
			(layer "F.CrtYd")
		)
		(fp_poly
			(pts
				(xy -4.413758 -0.548894) (xy -4.413758 0.47117) (xy -3.143758 -0.038862)
			)
			(stroke
				(width 0)
				(type default)
			)
			(fill yes)
			(layer "B.Fab")
		)
		(fp_line
			(start 4.586478 14.254988)
			(end -2.078482 14.254988)
			(stroke
				(width 0.1)
				(type default)
			)
			(layer "F.Fab")
		)
		(fp_line
			(start 4.586478 13.302488)
			(end 4.586478 14.254988)
			(stroke
				(width 0.1)
				(type default)
			)
			(layer "F.Fab")
		)
		(fp_line
			(start 4.586478 7.777988)
			(end 4.078478 7.777988)
			(stroke
				(width 0.1)
				(type default)
			)
			(layer "F.Fab")
		)
		(fp_line
			(start 4.586478 4.221988)
			(end 4.586478 7.777988)
			(stroke
				(width 0.1)
				(type default)
			)
			(layer "F.Fab")
		)
		(fp_line
			(start 4.586478 -1.302512)
			(end 4.078478 -1.302512)
			(stroke
				(width 0.1)
				(type default)
			)
			(layer "F.Fab")
		)
		(fp_line
			(start 4.586478 -2.255012)
			(end 4.586478 -1.302512)
			(stroke
				(width 0.1)
				(type default)
			)
			(layer "F.Fab")
		)
		(fp_line
			(start 4.078478 13.302488)
			(end 4.586478 13.302488)
			(stroke
				(width 0.1)
				(type default)
			)
			(layer "F.Fab")
		)
		(fp_line
			(start 4.078478 7.777988)
			(end 4.078478 13.302488)
			(stroke
				(width 0.1)
				(type default)
			)
			(layer "F.Fab")
		)
		(fp_line
			(start 4.078478 4.221988)
			(end 4.586478 4.221988)
			(stroke
				(width 0.1)
				(type default)
			)
			(layer "F.Fab")
		)
		(fp_line
			(start 4.078478 -1.302512)
			(end 4.078478 4.221988)
			(stroke
				(width 0.1)
				(type default)
			)
			(layer "F.Fab")
		)
		(fp_line
			(start -2.078482 14.254988)
			(end -2.078482 -2.255012)
			(stroke
				(width 0.1)
				(type default)
			)
			(layer "F.Fab")
		)
		(fp_line
			(start -2.078482 -2.255012)
			(end 4.586478 -2.255012)
			(stroke
				(width 0.1)
				(type default)
			)
			(layer "F.Fab")
		)
		(fp_poly
			(pts
				(xy -4.413758 -0.548894) (xy -4.413758 0.47117) (xy -3.143758 -0.038862)
			)
			(stroke
				(width 0)
				(type default)
			)
			(fill yes)
			(layer "F.Fab")
		)
		(fp_text user "14"
			(at 3.575304 15.148814 0)
			(unlocked yes)
			(layer "F.SilkS")
			(effects
				(font
					(size 0.7874 0.5842)
					(thickness 0.1524)
				)
				(justify left)
			)
		)
		(fp_text user "13"
			(at -0.070866 15.158212 0)
			(unlocked yes)
			(layer "F.SilkS")
			(effects
				(font
					(size 0.635 0.635)
					(thickness 0.1524)
				)
				(justify left)
			)
		)
		(fp_text user "2"
			(at -2.446274 -0.19304 0)
			(unlocked yes)
			(layer "F.SilkS")
			(effects
				(font
					(size 0.635 0.635)
					(thickness 0.1524)
				)
				(justify left)
			)
		)
		(fp_text user "2"
			(at 3.468624 0.874014 180)
			(unlocked yes)
			(layer "B.SilkS")
			(effects
				(font
					(size 0.7874 0.5842)
					(thickness 0.1524)
				)
				(justify left mirror)
			)
		)
		(fp_text user "14"
			(at 1.72974 13.92809 0)
			(unlocked yes)
			(layer "B.SilkS")
			(effects
				(font
					(size 0.7874 0.5842)
					(thickness 0.1524)
				)
				(justify left mirror)
			)
		)
		(fp_text user "13"
			(at -1.53162 13.89761 0)
			(unlocked yes)
			(layer "B.SilkS")
			(effects
				(font
					(size 0.7874 0.5842)
					(thickness 0.1524)
				)
				(justify left mirror)
			)
		)
		(fp_text user "14"
			(at 6.467348 12.166219 180)
			(unlocked yes)
			(layer "B.Fab")
			(effects
				(font
					(size 0.78994 0.579882)
					(thickness 0.000001)
				)
				(justify left mirror)
			)
		)
		(fp_text user "2"
			(at 5.705602 -0.255397 180)
			(unlocked yes)
			(layer "B.Fab")
			(effects
				(font
					(size 0.78994 0.579882)
					(thickness 0.000001)
				)
				(justify left mirror)
			)
		)
		(fp_text user "13"
			(at -2.924048 12.094845 180)
			(unlocked yes)
			(layer "B.Fab")
			(effects
				(font
					(size 0.78994 0.579882)
					(thickness 0.000001)
				)
				(justify left mirror)
			)
		)
		(fp_text user "14"
			(at 5.82295 0.990346 0)
			(unlocked yes)
			(layer "F.Fab")
			(effects
				(font
					(size 0.635 0.635)
					(thickness 0.1524)
				)
				(justify left)
			)
		)
		(fp_text user "13"
			(at -0.069088 15.159482 0)
			(unlocked yes)
			(layer "F.Fab")
			(effects
				(font
					(size 0.635 0.635)
					(thickness 0.1524)
				)
				(justify left)
			)
		)
		(fp_text user "2"
			(at -0.148082 -3.03784 0)
			(unlocked yes)
			(layer "F.Fab")
			(effects
				(font
					(size 0.635 0.635)
					(thickness 0.1524)
				)
				(justify left)
			)
		)
		(pad "1" thru_hole rect
			(at 0 0 180)
			(size 1.397 1.397)
			(drill 1.016)
			(layers "*.Cu" "*.Mask")
			(remove_unused_layers no)
			(net "LED_POSTCODE_0_R")
			(clearance 0.127)
			(thermal_gap 0.127)
			(padstack
				(mode front_inner_back)
				(layer "Inner"
					(shape circle)
					(size 1.397 1.397)
					(clearance 0.127)
				)
				(layer "B.Cu"
					(shape rect)
					(size 1.397 1.397)
					(clearance 0.127)
				)
			)
		)
		(pad "2" thru_hole circle
			(at 1.999996 0 180)
			(size 1.397 1.397)
			(drill 1.016)
			(layers "*.Cu" "*.Mask")
			(remove_unused_layers no)
			(net "LED_POSTCODE_1_R")
			(clearance 0.127)
			(thermal_gap 0.127)
		)
		(pad "3" thru_hole circle
			(at 0 1.999996 180)
			(size 1.397 1.397)
			(drill 1.016)
			(layers "*.Cu" "*.Mask")
			(remove_unused_layers no)
			(net "LED_POSTCODE_2_R")
			(clearance 0.127)
			(thermal_gap 0.127)
		)
		(pad "4" thru_hole circle
			(at 1.999996 1.999996 180)
			(size 1.397 1.397)
			(drill 1.016)
			(layers "*.Cu" "*.Mask")
			(remove_unused_layers no)
			(net "LED_POSTCODE_3_R")
			(clearance 0.127)
			(thermal_gap 0.127)
		)
		(pad "5" thru_hole circle
			(at 0 3.999992 180)
			(size 1.397 1.397)
			(drill 1.016)
			(layers "*.Cu" "*.Mask")
			(remove_unused_layers no)
			(net "LED_POSTCODE_4_R")
			(clearance 0.127)
			(thermal_gap 0.127)
		)
		(pad "6" thru_hole circle
			(at 1.999996 3.999992 180)
			(size 1.397 1.397)
			(drill 1.016)
			(layers "*.Cu" "*.Mask")
			(remove_unused_layers no)
			(net "LED_POSTCODE_5_R")
			(clearance 0.127)
			(thermal_gap 0.127)
		)
		(pad "7" thru_hole circle
			(at 0 5.999988 180)
			(size 1.397 1.397)
			(drill 1.016)
			(layers "*.Cu" "*.Mask")
			(remove_unused_layers no)
			(net "LED_POSTCODE_6_R")
			(clearance 0.127)
			(thermal_gap 0.127)
		)
		(pad "8" thru_hole circle
			(at 1.999996 5.999988 180)
			(size 1.397 1.397)
			(drill 1.016)
			(layers "*.Cu" "*.Mask")
			(remove_unused_layers no)
			(net "LED_POSTCODE_7_R")
			(clearance 0.127)
			(thermal_gap 0.127)
		)
		(pad "9" thru_hole circle
			(at 0 7.999984 180)
			(size 1.397 1.397)
			(drill 1.016)
			(layers "*.Cu" "*.Mask")
			(remove_unused_layers no)
			(net "SPA_MID_DBG1_TX")
			(clearance 0.127)
			(thermal_gap 0.127)
		)
		(pad "10" thru_hole circle
			(at 1.999996 7.999984 180)
			(size 1.397 1.397)
			(drill 1.016)
			(layers "*.Cu" "*.Mask")
			(remove_unused_layers no)
			(net "SPA_5V_SIN_SW")
			(clearance 0.127)
			(thermal_gap 0.127)
		)
		(pad "11" thru_hole circle
			(at 0 9.99998 180)
			(size 1.397 1.397)
			(drill 1.016)
			(layers "*.Cu" "*.Mask")
			(remove_unused_layers no)
			(net "FM_DEBUG_RST_BTN_N")
			(clearance 0.127)
			(thermal_gap 0.127)
		)
		(pad "12" thru_hole circle
			(at 1.999996 9.99998 180)
			(size 1.397 1.397)
			(drill 1.016)
			(layers "*.Cu" "*.Mask")
			(remove_unused_layers no)
			(net "FM_UART_SWITCH_N")
			(clearance 0.127)
			(thermal_gap 0.127)
		)
		(pad "13" thru_hole circle
			(at 0 11.999976 180)
			(size 1.397 1.397)
			(drill 1.016)
			(layers "*.Cu" "*.Mask")
			(remove_unused_layers no)
			(net "GND")
			(clearance 0.127)
			(thermal_gap 0.127)
		)
		(pad "14" thru_hole circle
			(at 1.999996 11.999976 180)
			(size 1.397 1.397)
			(drill 1.016)
			(layers "*.Cu" "*.Mask")
			(remove_unused_layers no)
			(net "P5V_STBY_DGB_FS")
			(clearance 0.127)
			(thermal_gap 0.127)
		)
	)
	(footprint ""
		(layer "F.Cu")
		(at 391.403078 -86.569042)
		(property "Reference" "R8D5"
			(at 0 0 0)
			(layer "F.SilkS")
			(hide yes)
			(effects
				(font
					(size 1.27 1.27)
				)
			)
		)
		(property "Value" ""
			(at 0 0 0)
			(layer "F.Fab")
			(effects
				(font
					(size 1.27 1.27)
				)
			)
		)
		(duplicate_pad_numbers_are_jumpers no)
		(fp_poly
			(pts
				(xy -0.2794 -0.1016) (xy 0.2794 -0.1016) (xy 0.2794 0.9906) (xy -0.2794 0.9906)
			)
			(stroke
				(width 0)
				(type default)
			)
			(fill no)
			(layer "F.CrtYd")
		)
		(fp_line
			(start -0.2794 -0.1016)
			(end -0.2794 0.9906)
			(stroke
				(width 0.1)
				(type default)
			)
			(layer "F.Fab")
		)
		(fp_line
			(start -0.2794 0.9906)
			(end 0.2794 0.9906)
			(stroke
				(width 0.1)
				(type default)
			)
			(layer "F.Fab")
		)
		(fp_line
			(start 0.2794 -0.1016)
			(end -0.2794 -0.1016)
			(stroke
				(width 0.1)
				(type default)
			)
			(layer "F.Fab")
		)
		(fp_line
			(start 0.2794 0.9906)
			(end 0.2794 -0.1016)
			(stroke
				(width 0.1)
				(type default)
			)
			(layer "F.Fab")
		)
		(pad "1" smd rect
			(at 0 0)
			(size 0.508 0.508)
			(layers "F.Cu" "F.Mask" "F.Paste")
			(net "PU_ADR_TIMER_HOLD_OFF_N")
		)
		(pad "2" smd rect
			(at 0 0.889)
			(size 0.508 0.508)
			(layers "F.Cu" "F.Mask" "F.Paste")
			(net "GND")
		)
		(zone
			(layer "F.Cu")
			(hatch none 0.5)
			(connect_pads
				(clearance 0)
			)
			(min_thickness 0.25)
			(keepout
				(tracks allowed)
				(vias not_allowed)
				(pads allowed)
				(copperpour not_allowed)
				(footprints allowed)
			)
			(placement
				(enabled no)
				(sheetname "")
			)
			(fill
				(thermal_gap 0.5)
				(thermal_bridge_width 0.5)
				(island_removal_mode 0)
			)
			(polygon
				(pts
					(xy 391.149078 -86.315042) (xy 391.657078 -86.315042) (xy 391.657078 -85.934042) (xy 391.149078 -85.934042)
				)
			)
		)
		(zone
			(layer "F.Cu")
			(hatch none 0.5)
			(connect_pads
				(clearance 0)
			)
			(min_thickness 0.25)
			(keepout
				(tracks not_allowed)
				(vias allowed)
				(pads allowed)
				(copperpour not_allowed)
				(footprints allowed)
			)
			(placement
				(enabled no)
				(sheetname "")
			)
			(fill
				(thermal_gap 0.5)
				(thermal_bridge_width 0.5)
				(island_removal_mode 0)
			)
			(polygon
				(pts
					(xy 391.149078 -85.934042) (xy 391.657078 -85.934042) (xy 391.657078 -86.315042) (xy 391.149078 -86.315042)
				)
			)
		)
	)
	(footprint ""
		(layer "F.Cu")
		(at 369.2652 -92.1766 180)
		(property "Reference" "U7D1"
			(at 0.28194 -1.71323 180)
			(unlocked yes)
			(layer "F.SilkS")
			(effects
				(font
					(size 0.7874 0.5842)
					(thickness 0.1524)
				)
				(justify left)
			)
		)
		(property "Value" ""
			(at 0 0 180)
			(layer "F.Fab")
			(effects
				(font
					(size 1.27 1.27)
				)
			)
		)
		(duplicate_pad_numbers_are_jumpers no)
		(fp_circle
			(center -0.4699 -0.8382)
			(end -0.5969 -0.8382)
			(stroke
				(width 0.254)
				(type default)
			)
			(fill no)
			(layer "F.SilkS")
		)
		(fp_poly
			(pts
				(xy 0.21463 -0.450088) (xy 1.56337 -0.450088) (xy 1.56337 1.75006) (xy 0.21463 1.75006)
			)
			(stroke
				(width 0)
				(type default)
			)
			(fill no)
			(layer "F.CrtYd")
		)
		(fp_line
			(start 1.56337 1.75006)
			(end 0.21463 1.75006)
			(stroke
				(width 0.1)
				(type default)
			)
			(layer "F.Fab")
		)
		(fp_line
			(start 1.56337 -0.450088)
			(end 1.56337 1.75006)
			(stroke
				(width 0.1)
				(type default)
			)
			(layer "F.Fab")
		)
		(fp_line
			(start 0.21463 1.75006)
			(end 0.21463 -0.450088)
			(stroke
				(width 0.1)
				(type default)
			)
			(layer "F.Fab")
		)
		(fp_line
			(start 0.21463 -0.450088)
			(end 1.56337 -0.450088)
			(stroke
				(width 0.1)
				(type default)
			)
			(layer "F.Fab")
		)
		(fp_circle
			(center -0.4699 -0.8382)
			(end -0.5969 -0.8382)
			(stroke
				(width 0.254)
				(type default)
			)
			(fill no)
			(layer "F.Fab")
		)
		(pad "1" smd rect
			(at 0 0 180)
			(size 1.016 0.381)
			(layers "F.Cu" "F.Mask" "F.Paste")
			(net "PWRGD_PVCCIO_CPU0")
		)
		(pad "2" smd rect
			(at 0 0.649986 180)
			(size 1.016 0.381)
			(layers "F.Cu" "F.Mask" "F.Paste")
			(net "XDP_PCH_PWR_DEBUG_N")
		)
		(pad "3" smd rect
			(at 0 1.299972 180)
			(size 1.016 0.381)
			(layers "F.Cu" "F.Mask" "F.Paste")
			(net "GND")
		)
		(pad "4" smd rect
			(at 1.778 1.299972 180)
			(size 1.016 0.381)
			(layers "F.Cu" "F.Mask" "F.Paste")
			(net "XDP_CPU_PWR_DEBUG_N")
		)
		(pad "5" smd rect
			(at 1.778 0 180)
			(size 1.016 0.381)
			(layers "F.Cu" "F.Mask" "F.Paste")
			(net "P3V3_STBY")
		)
	)
	(footprint ""
		(layer "F.Cu")
		(at 157.988 -119.166386 90)
		(property "Reference" "R3B4"
			(at 0 0 90)
			(layer "F.SilkS")
			(hide yes)
			(effects
				(font
					(size 1.27 1.27)
				)
			)
		)
		(property "Value" ""
			(at 0 0 90)
			(layer "F.Fab")
			(effects
				(font
					(size 1.27 1.27)
				)
			)
		)
		(duplicate_pad_numbers_are_jumpers no)
		(fp_poly
			(pts
				(xy -0.2794 -0.1016) (xy 0.2794 -0.1016) (xy 0.2794 0.9906) (xy -0.2794 0.9906)
			)
			(stroke
				(width 0)
				(type default)
			)
			(fill no)
			(layer "F.CrtYd")
		)
		(fp_line
			(start 0.2794 -0.1016)
			(end -0.2794 -0.1016)
			(stroke
				(width 0.1)
				(type default)
			)
			(layer "F.Fab")
		)
		(fp_line
			(start -0.2794 -0.1016)
			(end -0.2794 0.9906)
			(stroke
				(width 0.1)
				(type default)
			)
			(layer "F.Fab")
		)
		(fp_line
			(start 0.2794 0.9906)
			(end 0.2794 -0.1016)
			(stroke
				(width 0.1)
				(type default)
			)
			(layer "F.Fab")
		)
		(fp_line
			(start -0.2794 0.9906)
			(end 0.2794 0.9906)
			(stroke
				(width 0.1)
				(type default)
			)
			(layer "F.Fab")
		)
		(pad "1" smd rect
			(at 0 0 90)
			(size 0.508 0.508)
			(layers "F.Cu" "F.Mask" "F.Paste")
			(net "SVID_DIO0_CPU1_R")
		)
		(pad "2" smd rect
			(at 0 0.889 90)
			(size 0.508 0.508)
			(layers "F.Cu" "F.Mask" "F.Paste")
			(net "PVCCIO_CPU1")
		)
		(zone
			(layer "F.Cu")
			(hatch none 0.5)
			(connect_pads
				(clearance 0)
			)
			(min_thickness 0.25)
			(keepout
				(tracks allowed)
				(vias not_allowed)
				(pads allowed)
				(copperpour not_allowed)
				(footprints allowed)
			)
			(placement
				(enabled no)
				(sheetname "")
			)
			(fill
				(thermal_gap 0.5)
				(thermal_bridge_width 0.5)
				(island_removal_mode 0)
			)
			(polygon
				(pts
					(xy 158.242 -118.912386) (xy 158.242 -119.420386) (xy 158.623 -119.420386) (xy 158.623 -118.912386)
				)
			)
		)
		(zone
			(layer "F.Cu")
			(hatch none 0.5)
			(connect_pads
				(clearance 0)
			)
			(min_thickness 0.25)
			(keepout
				(tracks not_allowed)
				(vias allowed)
				(pads allowed)
				(copperpour not_allowed)
				(footprints allowed)
			)
			(placement
				(enabled no)
				(sheetname "")
			)
			(fill
				(thermal_gap 0.5)
				(thermal_bridge_width 0.5)
				(island_removal_mode 0)
			)
			(polygon
				(pts
					(xy 158.623 -118.912386) (xy 158.623 -119.420386) (xy 158.242 -119.420386) (xy 158.242 -118.912386)
				)
			)
		)
	)
	(footprint ""
		(layer "F.Cu")
		(at 198.925434 -65.167764 90)
		(property "Reference" "EU4D6"
			(at 3.334766 -1.542034 0)
			(unlocked yes)
			(layer "F.SilkS")
			(effects
				(font
					(size 0.7874 0.5842)
					(thickness 0.1524)
				)
			)
		)
		(property "Value" ""
			(at 0 0 90)
			(layer "F.Fab")
			(effects
				(font
					(size 1.27 1.27)
				)
			)
		)
		(duplicate_pad_numbers_are_jumpers no)
		(fp_line
			(start 2.9718 -3.5052)
			(end 2.9718 3.429)
			(stroke
				(width 0.1524)
				(type default)
			)
			(layer "F.SilkS")
		)
		(fp_line
			(start -3.0099 -3.5052)
			(end 2.9718 -3.5052)
			(stroke
				(width 0.1524)
				(type default)
			)
			(layer "F.SilkS")
		)
		(fp_line
			(start 2.9718 3.429)
			(end -3.0099 3.429)
			(stroke
				(width 0.1524)
				(type default)
			)
			(layer "F.SilkS")
		)
		(fp_line
			(start -3.0099 3.429)
			(end -3.0099 -3.5052)
			(stroke
				(width 0.1524)
				(type default)
			)
			(layer "F.SilkS")
		)
		(fp_circle
			(center -3.057398 -2.678684)
			(end -3.057398 -2.551684)
			(stroke
				(width 0.254)
				(type default)
			)
			(fill no)
			(layer "F.SilkS")
		)
		(fp_poly
			(pts
				(xy -2.9972 -3.4925) (xy -2.9972 -2.6924) (xy -2.1971 -3.4925)
			)
			(stroke
				(width 0)
				(type default)
			)
			(fill yes)
			(layer "F.SilkS")
		)
		(fp_poly
			(pts
				(xy -2.549906 -3.050032) (xy -2.549906 3.050032) (xy 2.549906 3.050032) (xy 2.549906 -3.050032)
			)
			(stroke
				(width 0)
				(type default)
			)
			(fill no)
			(layer "F.CrtYd")
		)
		(fp_line
			(start 2.549906 -3.050032)
			(end 2.549906 3.050032)
			(stroke
				(width 0.1)
				(type default)
			)
			(layer "F.Fab")
		)
		(fp_line
			(start -2.549906 -3.050032)
			(end 2.549906 -3.050032)
			(stroke
				(width 0.1)
				(type default)
			)
			(layer "F.Fab")
		)
		(fp_line
			(start 2.549906 3.050032)
			(end -2.549906 3.050032)
			(stroke
				(width 0.1)
				(type default)
			)
			(layer "F.Fab")
		)
		(fp_line
			(start -2.549906 3.050032)
			(end -2.549906 -3.050032)
			(stroke
				(width 0.1)
				(type default)
			)
			(layer "F.Fab")
		)
		(fp_circle
			(center -3.057398 -2.678684)
			(end -3.057398 -2.551684)
			(stroke
				(width 0.254)
				(type default)
			)
			(fill no)
			(layer "F.Fab")
		)
		(pad "1" smd rect
			(at -2.39522 -2.279904 90)
			(size 0.7112 0.254)
			(layers "F.Cu" "F.Mask" "F.Paste")
			(net "PVCCIN_CPU0")
		)
		(pad "2" smd rect
			(at -2.39522 -1.83007 90)
			(size 0.7112 0.254)
			(layers "F.Cu" "F.Mask" "F.Paste")
			(net "GND")
		)
		(pad "3" smd rect
			(at -2.39522 -1.379982 90)
			(size 0.7112 0.254)
			(layers "F.Cu" "F.Mask" "F.Paste")
			(net "VR_PVCCIN_CPU0_PH2_VCIN")
		)
		(pad "4" smd rect
			(at -2.39522 -0.929894 90)
			(size 0.7112 0.254)
			(layers "F.Cu" "F.Mask" "F.Paste")
			(net "P5V_STBY")
		)
		(pad "5" smd rect
			(at -2.39522 -0.48006 90)
			(size 0.7112 0.254)
			(layers "F.Cu" "F.Mask" "F.Paste")
			(net "GND")
		)
		(pad "6" smd rect
			(at -2.39522 -0.029972 90)
			(size 0.7112 0.254)
			(layers "F.Cu" "F.Mask" "F.Paste")
			(net "TP_PVCCIN_CPU0_PH2_GL_0")
		)
		(pad "7" smd custom
			(at 0.016764 1.145032 90)
			(size 0.53975 0.53975)
			(layers "F.Cu" "F.Mask" "F.Paste")
			(net "GND")
			(options
				(clearance outline)
				(anchor circle)
			)
			(primitives
				(gr_poly
					(pts
						(xy -2.7051 1.0795) (xy -2.7051 -0.3683) (xy -0.9271 -0.3683) (xy -0.9271 -1.0795) (xy 2.7051 -1.0795)
						(xy 2.7051 1.0795)
					)
					(width 0)
					(fill yes)
				)
			)
		)
		(pad "10" smd rect
			(at -0.008382 2.874772 90)
			(size 4.3434 0.6096)
			(layers "F.Cu" "F.Mask" "F.Paste")
			(net "VR_PVCCIN_CPU0_PHASE2")
		)
		(pad "25" smd rect
			(at 1.548384 -1.283208 90)
			(size 2.3368 2.0066)
			(layers "F.Cu" "F.Mask" "F.Paste")
			(net "VR_FET_SW_P12V_STBY_PVCCIN_CPU0")
		)
		(pad "30" smd rect
			(at 2.050034 -2.895092 90)
			(size 0.254 0.7112)
			(layers "F.Cu" "F.Mask" "F.Paste")
			(net "VR_FET_SW_P12V_STBY_PVCCIN_CPU0")
		)
		(pad "31" smd rect
			(at 1.599946 -2.895092 90)
			(size 0.254 0.7112)
			(layers "F.Cu" "F.Mask" "F.Paste")
			(net "Net_362")
		)
		(pad "32" smd rect
			(at 1.150112 -2.895092 90)
			(size 0.254 0.7112)
			(layers "F.Cu" "F.Mask" "F.Paste")
			(net "VR_PVCCIN_CPU0_PH2_PHASE")
		)
		(pad "33" smd rect
			(at 0.700024 -2.895092 90)
			(size 0.254 0.7112)
			(layers "F.Cu" "F.Mask" "F.Paste")
			(net "VR_PVCCIN_CPU0_PH2_BOOT_R")
		)
		(pad "34" smd rect
			(at 0.249936 -2.895092 90)
			(size 0.254 0.7112)
			(layers "F.Cu" "F.Mask" "F.Paste")
			(net "VR_PVCCIN_CPU0_PWM2")
		)
		(pad "35" smd rect
			(at -0.199898 -2.895092 90)
			(size 0.254 0.7112)
			(layers "F.Cu" "F.Mask" "F.Paste")
			(net "P5V_STBY")
		)
		(pad "36" smd rect
			(at -0.649986 -2.895092 90)
			(size 0.254 0.7112)
			(layers "F.Cu" "F.Mask" "F.Paste")
			(net "A_TSENSE_PVCCIN_CPU0")
		)
		(pad "37" smd rect
			(at -1.100074 -2.895092 90)
			(size 0.254 0.7112)
			(layers "F.Cu" "F.Mask" "F.Paste")
			(net "VR_PVCCIN_CPU0_PH2_OCSET")
		)
		(pad "38" smd rect
			(at -1.549908 -2.895092 90)
			(size 0.254 0.7112)
			(layers "F.Cu" "F.Mask" "F.Paste")
			(net "ISENSE_PVCCIN_CPU0_PH2_IMON")
		)
		(pad "39" smd rect
			(at -1.999996 -2.895092 90)
			(size 0.254 0.7112)
			(layers "F.Cu" "F.Mask" "F.Paste")
			(net "VR_PVCCIN_CPU0_AIREF2")
		)
		(pad "40" smd rect
			(at -0.871728 -1.283208 90)
			(size 1.8034 2.0066)
			(layers "F.Cu" "F.Mask" "F.Paste")
			(net "GND")
		)
		(pad "41" smd rect
			(at -1.533906 0.247904 90)
			(size 0.508 0.3556)
			(layers "F.Cu" "F.Mask" "F.Paste")
			(net "TP_PVCCIN_CPU0_PH2_GL_1")
		)
	)
	(footprint ""
		(layer "F.Cu")
		(at 369.085114 -6.089904 180)
		(property "Reference" "CONX8"
			(at 0 0 180)
			(layer "F.SilkS")
			(hide yes)
			(effects
				(font
					(size 1.27 1.27)
				)
			)
		)
		(property "Value" "*"
			(at -14.3129 -7.5565 180)
			(unlocked yes)
			(layer "F.Fab")
			(hide yes)
			(effects
				(font
					(size 1.27 1.016)
					(thickness 0.1524)
				)
			)
		)
		(property "Device Type" "SMC-CONN60A-22-GP_CONN-G7-SMC-A"
			(at -14.3129 -9.0805 180)
			(unlocked yes)
			(layer "F.Fab")
			(hide yes)
			(effects
				(font
					(size 1.27 1.016)
					(thickness 0.1524)
				)
			)
		)
		(duplicate_pad_numbers_are_jumpers no)
		(fp_line
			(start 16.8529 3.7592)
			(end 11.3411 3.7592)
			(stroke
				(width 0.1524)
				(type default)
			)
			(layer "F.SilkS")
		)
		(fp_line
			(start 16.8529 -3.7592)
			(end 16.8529 3.7592)
			(stroke
				(width 0.1524)
				(type default)
			)
			(layer "F.SilkS")
		)
		(fp_line
			(start 11.3411 3.7592)
			(end 11.3411 3.048)
			(stroke
				(width 0.1524)
				(type default)
			)
			(layer "F.SilkS")
		)
		(fp_line
			(start 11.3411 3.048)
			(end -11.3411 3.048)
			(stroke
				(width 0.1524)
				(type default)
			)
			(layer "F.SilkS")
		)
		(fp_line
			(start 11.3411 -3.048)
			(end 11.3411 -3.7592)
			(stroke
				(width 0.1524)
				(type default)
			)
			(layer "F.SilkS")
		)
		(fp_line
			(start 11.3411 -3.7592)
			(end 16.8529 -3.7592)
			(stroke
				(width 0.1524)
				(type default)
			)
			(layer "F.SilkS")
		)
		(fp_line
			(start -11.3411 3.7592)
			(end -16.8529 3.7592)
			(stroke
				(width 0.1524)
				(type default)
			)
			(layer "F.SilkS")
		)
		(fp_line
			(start -11.3411 3.048)
			(end -11.3411 3.7592)
			(stroke
				(width 0.1524)
				(type default)
			)
			(layer "F.SilkS")
		)
		(fp_line
			(start -11.3411 -3.048)
			(end 11.3411 -3.048)
			(stroke
				(width 0.1524)
				(type default)
			)
			(layer "F.SilkS")
		)
		(fp_line
			(start -11.3411 -3.7592)
			(end -11.3411 -3.048)
			(stroke
				(width 0.1524)
				(type default)
			)
			(layer "F.SilkS")
		)
		(fp_line
			(start -11.8872 3.8481)
			(end -11.2522 3.8481)
			(stroke
				(width 0.3302)
				(type default)
			)
			(layer "F.SilkS")
		)
		(fp_line
			(start -16.8529 3.7592)
			(end -16.8529 -3.7592)
			(stroke
				(width 0.1524)
				(type default)
			)
			(layer "F.SilkS")
		)
		(fp_line
			(start -16.8529 -3.7592)
			(end -11.3411 -3.7592)
			(stroke
				(width 0.1524)
				(type default)
			)
			(layer "F.SilkS")
		)
		(fp_circle
			(center 15.450058 0)
			(end 14.459458 0)
			(stroke
				(width 0.3048)
				(type default)
			)
			(fill no)
			(layer "F.SilkS")
		)
		(fp_circle
			(center -15.450058 0)
			(end -16.440658 0)
			(stroke
				(width 0.3048)
				(type default)
			)
			(fill no)
			(layer "F.SilkS")
		)
		(fp_poly
			(pts
				(xy -11.64209 3.843528) (xy -12.27709 4.478528) (xy -11.00709 4.478528)
			)
			(stroke
				(width 0)
				(type default)
			)
			(fill yes)
			(layer "F.SilkS")
		)
		(fp_poly
			(pts
				(xy -11.853926 -0.899922) (xy -11.853926 0.899922) (xy 11.853926 0.899922) (xy 11.853926 -0.899922)
			)
			(stroke
				(width 0)
				(type default)
			)
			(fill yes)
			(layer "F.SilkS")
		)
		(fp_poly
			(pts
				(xy -16.5989 3.5052) (xy -16.5989 -3.5052) (xy -11.5951 -3.5052) (xy -11.5951 -2.794) (xy 11.5951 -2.794)
				(xy 11.5951 -3.5052) (xy 16.5989 -3.5052) (xy 16.5989 3.5052) (xy 11.5951 3.5052) (xy 11.5951 2.794)
				(xy -11.5951 2.794) (xy -11.5951 3.5052)
			)
			(stroke
				(width 0)
				(type default)
			)
			(fill no)
			(layer "F.CrtYd")
		)
		(fp_poly
			(pts
				(xy -17.1069 4.0132) (xy -17.1069 -4.0132) (xy -11.0871 -4.0132) (xy -11.0871 -3.5052) (xy 11.0871 -3.5052)
				(xy 11.0871 -4.0132) (xy 17.1069 -4.0132) (xy 17.1069 4.0132) (xy 11.0871 4.0132) (xy 11.0871 3.5052)
				(xy 0.0127 3.5052) (xy 0.0127 2.794) (xy 11.5951 2.794) (xy 11.5951 3.5052) (xy 16.5989 3.5052)
				(xy 16.5989 -3.5052) (xy 11.5951 -3.5052) (xy 11.5951 -2.794) (xy -11.5951 -2.794) (xy -11.5951 -3.5052)
				(xy -16.5989 -3.5052) (xy -16.5989 3.5052) (xy -11.5951 3.5052) (xy -11.5951 2.794) (xy 0 2.794)
				(xy 0 3.5052) (xy -11.0871 3.5052) (xy -11.0871 4.0132)
			)
			(stroke
				(width 0)
				(type default)
			)
			(fill no)
			(layer "F.CrtYd")
		)
		(fp_poly
			(pts
				(xy -17.1069 4.0132) (xy -17.1069 -4.0132) (xy -11.0871 -4.0132) (xy -11.0871 -3.5052) (xy 11.0871 -3.5052)
				(xy 11.0871 -4.0132) (xy 17.1069 -4.0132) (xy 17.1069 4.0132) (xy 11.0871 4.0132) (xy 11.0871 3.5052)
				(xy -11.0871 3.5052) (xy -11.0871 4.0132)
			)
			(stroke
				(width 0)
				(type default)
			)
			(fill no)
			(layer "F.Fab")
		)
		(pad "" np_thru_hole circle
			(at -13.10005 1.500124 180)
			(size 0.254 0.254)
			(drill 1.27)
			(layers "*.Cu" "*.Mask")
			(clearance 0.8636)
			(thermal_gap 0.8636)
		)
		(pad "" np_thru_hole circle
			(at 13.10005 0 180)
			(size 0.254 0.254)
			(drill 1.27)
			(layers "*.Cu" "*.Mask")
			(clearance 0.8636)
			(thermal_gap 0.8636)
		)
		(pad "1" smd rect
			(at -11.599926 1.700022 180)
			(size 0.508 1.1938)
			(layers "F.Cu" "F.Mask" "F.Paste")
			(net "GND")
		)
		(pad "2" smd rect
			(at -11.599926 -1.700022 180)
			(size 0.508 1.1938)
			(layers "F.Cu" "F.Mask" "F.Paste")
			(net "Net_545")
		)
		(pad "3" smd rect
			(at -10.80008 1.700022 180)
			(size 0.508 1.1938)
			(layers "F.Cu" "F.Mask" "F.Paste")
			(net "P3E_CPU0_PE2_SS_C_TXN<8>")
		)
		(pad "4" smd rect
			(at -10.80008 -1.700022 180)
			(size 0.508 1.1938)
			(layers "F.Cu" "F.Mask" "F.Paste")
			(net "GND")
		)
		(pad "5" smd rect
			(at -9.99998 1.700022 180)
			(size 0.508 1.1938)
			(layers "F.Cu" "F.Mask" "F.Paste")
			(net "P3E_CPU0_PE2_SS_C_TXP<8>")
		)
		(pad "6" smd rect
			(at -9.99998 -1.700022 180)
			(size 0.508 1.1938)
			(layers "F.Cu" "F.Mask" "F.Paste")
			(net "P3E_CPU0_PE2_SS_RXN<8>")
		)
		(pad "7" smd rect
			(at -9.19988 1.700022 180)
			(size 0.508 1.1938)
			(layers "F.Cu" "F.Mask" "F.Paste")
			(net "GND")
		)
		(pad "8" smd rect
			(at -9.19988 -1.700022 180)
			(size 0.508 1.1938)
			(layers "F.Cu" "F.Mask" "F.Paste")
			(net "P3E_CPU0_PE2_SS_RXP<8>")
		)
		(pad "9" smd rect
			(at -8.400034 1.700022 180)
			(size 0.508 1.1938)
			(layers "F.Cu" "F.Mask" "F.Paste")
			(net "P3E_CPU0_PE2_SS_C_TXN<9>")
		)
		(pad "10" smd rect
			(at -8.400034 -1.700022 180)
			(size 0.508 1.1938)
			(layers "F.Cu" "F.Mask" "F.Paste")
			(net "GND")
		)
		(pad "11" smd rect
			(at -7.599934 1.700022 180)
			(size 0.508 1.1938)
			(layers "F.Cu" "F.Mask" "F.Paste")
			(net "P3E_CPU0_PE2_SS_C_TXP<9>")
		)
		(pad "12" smd rect
			(at -7.599934 -1.700022 180)
			(size 0.508 1.1938)
			(layers "F.Cu" "F.Mask" "F.Paste")
			(net "P3E_CPU0_PE2_SS_RXN<9>")
		)
		(pad "13" smd rect
			(at -6.800088 1.700022 180)
			(size 0.508 1.1938)
			(layers "F.Cu" "F.Mask" "F.Paste")
			(net "GND")
		)
		(pad "14" smd rect
			(at -6.800088 -1.700022 180)
			(size 0.508 1.1938)
			(layers "F.Cu" "F.Mask" "F.Paste")
			(net "P3E_CPU0_PE2_SS_RXP<9>")
		)
		(pad "15" smd rect
			(at -5.999988 1.700022 180)
			(size 0.508 1.1938)
			(layers "F.Cu" "F.Mask" "F.Paste")
			(net "P3E_CPU0_PE2_SS_C_TXN<10>")
		)
		(pad "16" smd rect
			(at -5.999988 -1.700022 180)
			(size 0.508 1.1938)
			(layers "F.Cu" "F.Mask" "F.Paste")
			(net "GND")
		)
		(pad "17" smd rect
			(at -5.199888 1.700022 180)
			(size 0.508 1.1938)
			(layers "F.Cu" "F.Mask" "F.Paste")
			(net "P3E_CPU0_PE2_SS_C_TXP<10>")
		)
		(pad "18" smd rect
			(at -5.199888 -1.700022 180)
			(size 0.508 1.1938)
			(layers "F.Cu" "F.Mask" "F.Paste")
			(net "P3E_CPU0_PE2_SS_RXN<10>")
		)
		(pad "19" smd rect
			(at -4.400042 1.700022 180)
			(size 0.508 1.1938)
			(layers "F.Cu" "F.Mask" "F.Paste")
			(net "GND")
		)
		(pad "20" smd rect
			(at -4.400042 -1.700022 180)
			(size 0.508 1.1938)
			(layers "F.Cu" "F.Mask" "F.Paste")
			(net "P3E_CPU0_PE2_SS_RXP<10>")
		)
		(pad "21" smd rect
			(at -3.599942 1.700022 180)
			(size 0.508 1.1938)
			(layers "F.Cu" "F.Mask" "F.Paste")
			(net "P3E_CPU0_PE2_SS_C_TXP<11>")
		)
		(pad "22" smd rect
			(at -3.599942 -1.700022 180)
			(size 0.508 1.1938)
			(layers "F.Cu" "F.Mask" "F.Paste")
			(net "GND")
		)
		(pad "23" smd rect
			(at -2.800096 1.700022 180)
			(size 0.508 1.1938)
			(layers "F.Cu" "F.Mask" "F.Paste")
			(net "P3E_CPU0_PE2_SS_C_TXN<11>")
		)
		(pad "24" smd rect
			(at -2.800096 -1.700022 180)
			(size 0.508 1.1938)
			(layers "F.Cu" "F.Mask" "F.Paste")
			(net "P3E_CPU0_PE2_SS_RXN<11>")
		)
		(pad "25" smd rect
			(at -1.999996 1.700022 180)
			(size 0.508 1.1938)
			(layers "F.Cu" "F.Mask" "F.Paste")
			(net "GND")
		)
		(pad "26" smd rect
			(at -1.999996 -1.700022 180)
			(size 0.508 1.1938)
			(layers "F.Cu" "F.Mask" "F.Paste")
			(net "P3E_CPU0_PE2_SS_RXP<11>")
		)
		(pad "27" smd rect
			(at -1.199896 1.700022 180)
			(size 0.508 1.1938)
			(layers "F.Cu" "F.Mask" "F.Paste")
			(net "P3E_CPU0_PE2_SS_C_TXN<12>")
		)
		(pad "28" smd rect
			(at -1.199896 -1.700022 180)
			(size 0.508 1.1938)
			(layers "F.Cu" "F.Mask" "F.Paste")
			(net "GND")
		)
		(pad "29" smd rect
			(at -0.40005 1.700022 180)
			(size 0.508 1.1938)
			(layers "F.Cu" "F.Mask" "F.Paste")
			(net "P3E_CPU0_PE2_SS_C_TXP<12>")
		)
		(pad "30" smd rect
			(at -0.40005 -1.700022 180)
			(size 0.508 1.1938)
			(layers "F.Cu" "F.Mask" "F.Paste")
			(net "P3E_CPU0_PE2_SS_RXN<12>")
		)
		(pad "31" smd rect
			(at 0.40005 1.700022 180)
			(size 0.508 1.1938)
			(layers "F.Cu" "F.Mask" "F.Paste")
			(net "GND")
		)
		(pad "32" smd rect
			(at 0.40005 -1.700022 180)
			(size 0.508 1.1938)
			(layers "F.Cu" "F.Mask" "F.Paste")
			(net "P3E_CPU0_PE2_SS_RXP<12>")
		)
		(pad "33" smd rect
			(at 1.199896 1.700022 180)
			(size 0.508 1.1938)
			(layers "F.Cu" "F.Mask" "F.Paste")
			(net "P3E_CPU0_PE2_SS_C_TXN<13>")
		)
		(pad "34" smd rect
			(at 1.199896 -1.700022 180)
			(size 0.508 1.1938)
			(layers "F.Cu" "F.Mask" "F.Paste")
			(net "GND")
		)
		(pad "35" smd rect
			(at 1.999996 1.700022 180)
			(size 0.508 1.1938)
			(layers "F.Cu" "F.Mask" "F.Paste")
			(net "P3E_CPU0_PE2_SS_C_TXP<13>")
		)
		(pad "36" smd rect
			(at 1.999996 -1.700022 180)
			(size 0.508 1.1938)
			(layers "F.Cu" "F.Mask" "F.Paste")
			(net "P3E_CPU0_PE2_SS_RXP<13>")
		)
		(pad "37" smd rect
			(at 2.800096 1.700022 180)
			(size 0.508 1.1938)
			(layers "F.Cu" "F.Mask" "F.Paste")
			(net "GND")
		)
		(pad "38" smd rect
			(at 2.800096 -1.700022 180)
			(size 0.508 1.1938)
			(layers "F.Cu" "F.Mask" "F.Paste")
			(net "P3E_CPU0_PE2_SS_RXN<13>")
		)
		(pad "39" smd rect
			(at 3.599942 1.700022 180)
			(size 0.508 1.1938)
			(layers "F.Cu" "F.Mask" "F.Paste")
			(net "P3E_CPU0_PE2_SS_C_TXP<14>")
		)
		(pad "40" smd rect
			(at 3.599942 -1.700022 180)
			(size 0.508 1.1938)
			(layers "F.Cu" "F.Mask" "F.Paste")
			(net "GND")
		)
		(pad "41" smd rect
			(at 4.400042 1.700022 180)
			(size 0.508 1.1938)
			(layers "F.Cu" "F.Mask" "F.Paste")
			(net "P3E_CPU0_PE2_SS_C_TXN<14>")
		)
		(pad "42" smd rect
			(at 4.400042 -1.700022 180)
			(size 0.508 1.1938)
			(layers "F.Cu" "F.Mask" "F.Paste")
			(net "P3E_CPU0_PE2_SS_RXN<14>")
		)
		(pad "43" smd rect
			(at 5.199888 1.700022 180)
			(size 0.508 1.1938)
			(layers "F.Cu" "F.Mask" "F.Paste")
			(net "GND")
		)
		(pad "44" smd rect
			(at 5.199888 -1.700022 180)
			(size 0.508 1.1938)
			(layers "F.Cu" "F.Mask" "F.Paste")
			(net "P3E_CPU0_PE2_SS_RXP<14>")
		)
		(pad "45" smd rect
			(at 5.999988 1.700022 180)
			(size 0.508 1.1938)
			(layers "F.Cu" "F.Mask" "F.Paste")
			(net "P3E_CPU0_PE2_SS_C_TXN<15>")
		)
		(pad "46" smd rect
			(at 5.999988 -1.700022 180)
			(size 0.508 1.1938)
			(layers "F.Cu" "F.Mask" "F.Paste")
			(net "GND")
		)
		(pad "47" smd rect
			(at 6.800088 1.700022 180)
			(size 0.508 1.1938)
			(layers "F.Cu" "F.Mask" "F.Paste")
			(net "P3E_CPU0_PE2_SS_C_TXP<15>")
		)
		(pad "48" smd rect
			(at 6.800088 -1.700022 180)
			(size 0.508 1.1938)
			(layers "F.Cu" "F.Mask" "F.Paste")
			(net "P3E_CPU0_PE2_SS_RXN<15>")
		)
		(pad "49" smd rect
			(at 7.599934 1.700022 180)
			(size 0.508 1.1938)
			(layers "F.Cu" "F.Mask" "F.Paste")
			(net "GND")
		)
		(pad "50" smd rect
			(at 7.599934 -1.700022 180)
			(size 0.508 1.1938)
			(layers "F.Cu" "F.Mask" "F.Paste")
			(net "P3E_CPU0_PE2_SS_RXP<15>")
		)
		(pad "51" smd rect
			(at 8.400034 1.700022 180)
			(size 0.508 1.1938)
			(layers "F.Cu" "F.Mask" "F.Paste")
			(net "JTAG_RISER_TDI")
		)
		(pad "52" smd rect
			(at 8.400034 -1.700022 180)
			(size 0.508 1.1938)
			(layers "F.Cu" "F.Mask" "F.Paste")
			(net "GND")
		)
		(pad "53" smd rect
			(at 9.19988 1.700022 180)
			(size 0.508 1.1938)
			(layers "F.Cu" "F.Mask" "F.Paste")
			(net "JTAG_RISER_TDO")
		)
		(pad "54" smd rect
			(at 9.19988 -1.700022 180)
			(size 0.508 1.1938)
			(layers "F.Cu" "F.Mask" "F.Paste")
			(net "JTAG_RISER_TMS")
		)
		(pad "55" smd rect
			(at 9.99998 1.700022 180)
			(size 0.508 1.1938)
			(layers "F.Cu" "F.Mask" "F.Paste")
			(net "GND")
		)
		(pad "56" smd rect
			(at 9.99998 -1.700022 180)
			(size 0.508 1.1938)
			(layers "F.Cu" "F.Mask" "F.Paste")
			(net "JTAG_RISER_TCK")
		)
		(pad "57" smd rect
			(at 10.80008 1.700022 180)
			(size 0.508 1.1938)
			(layers "F.Cu" "F.Mask" "F.Paste")
			(net "USB2_P02_DN")
		)
		(pad "58" smd rect
			(at 10.80008 -1.700022 180)
			(size 0.508 1.1938)
			(layers "F.Cu" "F.Mask" "F.Paste")
			(net "GND")
		)
		(pad "59" smd rect
			(at 11.599926 1.700022 180)
			(size 0.508 1.1938)
			(layers "F.Cu" "F.Mask" "F.Paste")
			(net "USB2_P02_DP")
		)
		(pad "60" smd rect
			(at 11.599926 -1.700022 180)
			(size 0.508 1.1938)
			(layers "F.Cu" "F.Mask" "F.Paste")
			(net "JTAG_RISER_TRST")
		)
		(pad "PTH1" thru_hole circle
			(at -15.450058 0 180)
			(size 1.27 1.27)
			(drill 0.8636)
			(layers "*.Cu" "*.Mask")
			(remove_unused_layers no)
			(net "GND")
			(clearance 0.1524)
			(thermal_gap 0.1524)
		)
		(pad "PTH2" thru_hole circle
			(at 15.450058 0 180)
			(size 1.27 1.27)
			(drill 0.8636)
			(layers "*.Cu" "*.Mask")
			(remove_unused_layers no)
			(net "GND")
			(clearance 0.1524)
			(thermal_gap 0.1524)
		)
		(zone
			(layer "F.Cu")
			(hatch none 0.5)
			(connect_pads
				(clearance 0)
			)
			(min_thickness 0.25)
			(keepout
				(tracks not_allowed)
				(vias allowed)
				(pads allowed)
				(copperpour not_allowed)
				(footprints allowed)
			)
			(placement
				(enabled no)
				(sheetname "")
			)
			(fill
				(thermal_gap 0.5)
				(thermal_bridge_width 0.5)
				(island_removal_mode 0)
			)
			(polygon
				(pts
					(xy 380.93904 -7.193026) (xy 357.231188 -7.193026) (xy 357.231188 -4.986782) (xy 380.93904 -4.986782)
				)
			)
		)
		(zone
			(layer "F.Cu")
			(hatch none 0.5)
			(connect_pads
				(clearance 0)
			)
			(min_thickness 0.25)
			(keepout
				(tracks allowed)
				(vias not_allowed)
				(pads allowed)
				(copperpour not_allowed)
				(footprints allowed)
			)
			(placement
				(enabled no)
				(sheetname "")
			)
			(fill
				(thermal_gap 0.5)
				(thermal_bridge_width 0.5)
				(island_removal_mode 0)
			)
			(polygon
				(pts
					(xy 380.93904 -6.685026) (xy 380.93904 -7.193026) (xy 357.231188 -7.193026) (xy 357.231188 -6.685026)
				)
			)
		)
		(zone
			(layer "F.Cu")
			(hatch none 0.5)
			(connect_pads
				(clearance 0)
			)
			(min_thickness 0.25)
			(keepout
				(tracks allowed)
				(vias not_allowed)
				(pads allowed)
				(copperpour not_allowed)
				(footprints allowed)
			)
			(placement
				(enabled no)
				(sheetname "")
			)
			(fill
				(thermal_gap 0.5)
				(thermal_bridge_width 0.5)
				(island_removal_mode 0)
			)
			(polygon
				(pts
					(xy 380.93904 -4.986782) (xy 380.93904 -7.193026) (xy 357.231188 -7.193026) (xy 357.231188 -4.986782)
				)
			)
		)
		(zone
			(layer "F.Cu")
			(hatch none 0.5)
			(connect_pads
				(clearance 0)
			)
			(min_thickness 0.25)
			(keepout
				(tracks allowed)
				(vias not_allowed)
				(pads allowed)
				(copperpour not_allowed)
				(footprints allowed)
			)
			(placement
				(enabled no)
				(sheetname "")
			)
			(fill
				(thermal_gap 0.5)
				(thermal_bridge_width 0.5)
				(island_removal_mode 0)
			)
			(polygon
				(pts
					(xy 380.93904 -4.986782) (xy 380.93904 -5.494782) (xy 357.231188 -5.494782) (xy 357.231188 -4.986782)
				)
			)
		)
		(zone
			(layers "F.Cu" "B.Cu" "In1.Cu" "In2.Cu" "In3.Cu" "In4.Cu" "In5.Cu" "In6.Cu"
				"In7.Cu" "In8.Cu" "In9.Cu" "In10.Cu" "In11.Cu" "In12.Cu"
			)
			(hatch none 0.5)
			(connect_pads
				(clearance 0)
			)
			(min_thickness 0.25)
			(keepout
				(tracks not_allowed)
				(vias allowed)
				(pads allowed)
				(copperpour not_allowed)
				(footprints allowed)
			)
			(placement
				(enabled no)
				(sheetname "")
			)
			(fill
				(thermal_gap 0.5)
				(thermal_bridge_width 0.5)
				(island_removal_mode 0)
			)
			(polygon
				(pts
					(arc
						(start 356.924864 -6.089904)
						(mid 355.045264 -6.089904)
						(end 356.924864 -6.089904)
					)
				)
			)
		)
		(zone
			(layers "F.Cu" "B.Cu" "In1.Cu" "In2.Cu" "In3.Cu" "In4.Cu" "In5.Cu" "In6.Cu"
				"In7.Cu" "In8.Cu" "In9.Cu" "In10.Cu" "In11.Cu" "In12.Cu"
			)
			(hatch none 0.5)
			(connect_pads
				(clearance 0)
			)
			(min_thickness 0.25)
			(keepout
				(tracks not_allowed)
				(vias allowed)
				(pads allowed)
				(copperpour not_allowed)
				(footprints allowed)
			)
			(placement
				(enabled no)
				(sheetname "")
			)
			(fill
				(thermal_gap 0.5)
				(thermal_bridge_width 0.5)
				(island_removal_mode 0)
			)
			(polygon
				(pts
					(arc
						(start 383.124964 -7.590028)
						(mid 381.245364 -7.590028)
						(end 383.124964 -7.590028)
					)
				)
			)
		)
	)
	(footprint ""
		(layer "F.Cu")
		(at 175.387 -76.327 90)
		(property "Reference" "R4D29"
			(at 0 0 90)
			(layer "F.SilkS")
			(hide yes)
			(effects
				(font
					(size 1.27 1.27)
				)
			)
		)
		(property "Value" ""
			(at 0 0 90)
			(layer "F.Fab")
			(effects
				(font
					(size 1.27 1.27)
				)
			)
		)
		(duplicate_pad_numbers_are_jumpers no)
		(fp_poly
			(pts
				(xy -0.2794 -0.1016) (xy 0.2794 -0.1016) (xy 0.2794 0.9906) (xy -0.2794 0.9906)
			)
			(stroke
				(width 0)
				(type default)
			)
			(fill no)
			(layer "F.CrtYd")
		)
		(fp_line
			(start 0.2794 -0.1016)
			(end -0.2794 -0.1016)
			(stroke
				(width 0.1)
				(type default)
			)
			(layer "F.Fab")
		)
		(fp_line
			(start -0.2794 -0.1016)
			(end -0.2794 0.9906)
			(stroke
				(width 0.1)
				(type default)
			)
			(layer "F.Fab")
		)
		(fp_line
			(start 0.2794 0.9906)
			(end 0.2794 -0.1016)
			(stroke
				(width 0.1)
				(type default)
			)
			(layer "F.Fab")
		)
		(fp_line
			(start -0.2794 0.9906)
			(end 0.2794 0.9906)
			(stroke
				(width 0.1)
				(type default)
			)
			(layer "F.Fab")
		)
		(pad "1" smd rect
			(at 0 0 90)
			(size 0.508 0.508)
			(layers "F.Cu" "F.Mask" "F.Paste")
			(net "CLK_100M_CPU0_BCLK0_R_DP")
		)
		(pad "2" smd rect
			(at 0 0.889 90)
			(size 0.508 0.508)
			(layers "F.Cu" "F.Mask" "F.Paste")
			(net "CLK_100M_CPU0_BCLK0_DP")
		)
		(zone
			(layer "F.Cu")
			(hatch none 0.5)
			(connect_pads
				(clearance 0)
			)
			(min_thickness 0.25)
			(keepout
				(tracks allowed)
				(vias not_allowed)
				(pads allowed)
				(copperpour not_allowed)
				(footprints allowed)
			)
			(placement
				(enabled no)
				(sheetname "")
			)
			(fill
				(thermal_gap 0.5)
				(thermal_bridge_width 0.5)
				(island_removal_mode 0)
			)
			(polygon
				(pts
					(xy 175.641 -76.073) (xy 175.641 -76.581) (xy 176.022 -76.581) (xy 176.022 -76.073)
				)
			)
		)
		(zone
			(layer "F.Cu")
			(hatch none 0.5)
			(connect_pads
				(clearance 0)
			)
			(min_thickness 0.25)
			(keepout
				(tracks not_allowed)
				(vias allowed)
				(pads allowed)
				(copperpour not_allowed)
				(footprints allowed)
			)
			(placement
				(enabled no)
				(sheetname "")
			)
			(fill
				(thermal_gap 0.5)
				(thermal_bridge_width 0.5)
				(island_removal_mode 0)
			)
			(polygon
				(pts
					(xy 176.022 -76.073) (xy 176.022 -76.581) (xy 175.641 -76.581) (xy 175.641 -76.073)
				)
			)
		)
	)
	(footprint ""
		(layer "F.Cu")
		(at 462.980532 -135.71982 90.001)
		(property "Reference" "J9A3"
			(at 3.15304 -8.221925 90.001)
			(unlocked yes)
			(layer "F.SilkS")
			(effects
				(font
					(size 0.7874 0.5842)
					(thickness 0.1524)
				)
				(justify left)
			)
		)
		(property "Value" ""
			(at 0 0 90.001)
			(layer "F.Fab")
			(effects
				(font
					(size 1.27 1.27)
				)
			)
		)
		(duplicate_pad_numbers_are_jumpers no)
		(fp_line
			(start 14.981542 -6.508743)
			(end 16.939628 -6.508708)
			(stroke
				(width 0.1524)
				(type default)
			)
			(layer "F.SilkS")
		)
		(fp_line
			(start -2.146948 -6.508787)
			(end -0.473088 -6.508758)
			(stroke
				(width 0.1524)
				(type default)
			)
			(layer "F.SilkS")
		)
		(fp_line
			(start 17.911812 0.781109)
			(end 17.911906 -4.573465)
			(stroke
				(width 0.1524)
				(type default)
			)
			(layer "F.SilkS")
		)
		(fp_line
			(start 17.911812 0.781109)
			(end 14.973794 0.781057)
			(stroke
				(width 0.1524)
				(type default)
			)
			(layer "F.SilkS")
		)
		(fp_line
			(start -3.411742 0.78099)
			(end -3.411648 -4.59111)
			(stroke
				(width 0.1524)
				(type default)
			)
			(layer "F.SilkS")
		)
		(fp_line
			(start -3.411742 0.78099)
			(end -0.517412 0.781041)
			(stroke
				(width 0.1524)
				(type default)
			)
			(layer "F.SilkS")
		)
		(fp_poly
			(pts
				(xy -0.862117 2.348977) (xy 0.153883 2.348995) (xy -0.354095 1.078986)
			)
			(stroke
				(width 0)
				(type default)
			)
			(fill yes)
			(layer "F.SilkS")
		)
		(fp_poly
			(pts
				(xy -3.411741 -6.50881) (xy 17.911813 -6.508809) (xy 17.911812 0.780991) (xy -3.411742 0.78099)
			)
			(stroke
				(width 0)
				(type default)
			)
			(fill no)
			(layer "F.CrtYd")
		)
		(fp_line
			(start 17.91194 -6.508691)
			(end -3.411614 -6.50881)
			(stroke
				(width 0.1)
				(type default)
			)
			(layer "F.Fab")
		)
		(fp_line
			(start -3.411614 -6.50881)
			(end -3.411742 0.78099)
			(stroke
				(width 0.1)
				(type default)
			)
			(layer "F.Fab")
		)
		(fp_line
			(start 17.911812 0.781109)
			(end 17.91194 -6.508691)
			(stroke
				(width 0.1)
				(type default)
			)
			(layer "F.Fab")
		)
		(fp_line
			(start -3.411742 0.78099)
			(end 17.911812 0.781109)
			(stroke
				(width 0.1)
				(type default)
			)
			(layer "F.Fab")
		)
		(fp_poly
			(pts
				(xy -0.508302 2.770115) (xy 0.507698 2.770133) (xy -0.00028 1.500124)
			)
			(stroke
				(width 0)
				(type default)
			)
			(fill yes)
			(layer "F.Fab")
		)
		(fp_text user "60"
			(at 19.142806 -5.526204 0.001)
			(unlocked yes)
			(layer "F.SilkS")
			(effects
				(font
					(size 0.7874 0.5842)
					(thickness 0.1524)
				)
				(justify left)
			)
		)
		(fp_text user "2"
			(at -4.098208 -4.71381 0.001)
			(unlocked yes)
			(layer "F.SilkS")
			(effects
				(font
					(size 0.7874 0.5842)
					(thickness 0.1524)
				)
				(justify left)
			)
		)
		(fp_text user "59"
			(at -2.150904 1.508722 90.001)
			(unlocked yes)
			(layer "F.SilkS")
			(effects
				(font
					(size 0.7874 0.5842)
					(thickness 0.1524)
				)
				(justify left)
			)
		)
		(fp_text user "60"
			(at 18.363061 -7.479478 0.001)
			(unlocked yes)
			(layer "F.Fab")
			(effects
				(font
					(size 0.7874 0.5842)
					(thickness 0.1524)
				)
				(justify left)
			)
		)
		(fp_text user "2"
			(at -4.005214 -6.406972 0.001)
			(unlocked yes)
			(layer "F.Fab")
			(effects
				(font
					(size 0.7874 0.5842)
					(thickness 0.1524)
				)
				(justify left)
			)
		)
		(fp_text user "59"
			(at 14.926285 1.407923 0.001)
			(unlocked yes)
			(layer "F.Fab")
			(effects
				(font
					(size 0.7874 0.5842)
					(thickness 0.1524)
				)
				(justify left)
			)
		)
		(pad "" np_thru_hole circle
			(at -2.810002 -5.530088 90.001)
			(size 0.254 0.254)
			(drill 1.0414)
			(layers "*.Cu" "*.Mask")
			(clearance 0.7112)
			(thermal_gap 0.7112)
		)
		(pad "" np_thru_hole circle
			(at 17.315942 -5.530088 90.001)
			(size 0.254 0.254)
			(drill 1.0414)
			(layers "*.Cu" "*.Mask")
			(clearance 0.7112)
			(thermal_gap 0.7112)
		)
		(pad "1" smd rect
			(at 0 0 90.001)
			(size 0.2794 2.286)
			(layers "F.Cu" "F.Mask" "F.Paste")
			(net "XDP_DEBUG_CONSENT_N")
		)
		(pad "2" smd rect
			(at 0 -5.727954 90.001)
			(size 0.2794 2.286)
			(layers "F.Cu" "F.Mask" "F.Paste")
			(net "GND")
		)
		(pad "3" smd rect
			(at 0.500126 0 90.001)
			(size 0.2794 2.286)
			(layers "F.Cu" "F.Mask" "F.Paste")
			(net "XDP_PREQ_N")
		)
		(pad "4" smd rect
			(at 0.500126 -5.727954 90.001)
			(size 0.2794 2.286)
			(layers "F.Cu" "F.Mask" "F.Paste")
			(net "TP_XDP_CPU_OBSFN_C0")
		)
		(pad "5" smd rect
			(at 0.999998 0 90.001)
			(size 0.2794 2.286)
			(layers "F.Cu" "F.Mask" "F.Paste")
			(net "XDP_PRDY_N")
		)
		(pad "6" smd rect
			(at 0.999998 -5.727954 90.001)
			(size 0.2794 2.286)
			(layers "F.Cu" "F.Mask" "F.Paste")
			(net "XDP_SPI_PCH_MOSI_BOOT_HALT_N")
		)
		(pad "7" smd rect
			(at 1.500124 0 90.001)
			(size 0.2794 2.286)
			(layers "F.Cu" "F.Mask" "F.Paste")
			(net "GND")
		)
		(pad "8" smd rect
			(at 1.500124 -5.727954 90.001)
			(size 0.2794 2.286)
			(layers "F.Cu" "F.Mask" "F.Paste")
			(net "GND")
		)
		(pad "9" smd rect
			(at 1.999996 0 90.001)
			(size 0.2794 2.286)
			(layers "F.Cu" "F.Mask" "F.Paste")
			(net "TP_XDP_OBSDATA_A0")
		)
		(pad "10" smd rect
			(at 1.999996 -5.727954 90.001)
			(size 0.2794 2.286)
			(layers "F.Cu" "F.Mask" "F.Paste")
			(net "TP_XDP_CPU_OBSDATA_C0")
		)
		(pad "11" smd rect
			(at 2.500122 0 90.001)
			(size 0.2794 2.286)
			(layers "F.Cu" "F.Mask" "F.Paste")
			(net "TP_XDP_OBSDATA_A1")
		)
		(pad "12" smd rect
			(at 2.500122 -5.727954 90.001)
			(size 0.2794 2.286)
			(layers "F.Cu" "F.Mask" "F.Paste")
			(net "TP_XDP_CPU_OBSDATA_C1")
		)
		(pad "13" smd rect
			(at 2.999994 0 90.001)
			(size 0.2794 2.286)
			(layers "F.Cu" "F.Mask" "F.Paste")
			(net "GND")
		)
		(pad "14" smd rect
			(at 2.999994 -5.727954 90.001)
			(size 0.2794 2.286)
			(layers "F.Cu" "F.Mask" "F.Paste")
			(net "GND")
		)
		(pad "15" smd rect
			(at 3.50012 0 90.001)
			(size 0.2794 2.286)
			(layers "F.Cu" "F.Mask" "F.Paste")
			(net "TP_XDP_OBSDATA_A2")
		)
		(pad "16" smd rect
			(at 3.50012 -5.727954 90.001)
			(size 0.2794 2.286)
			(layers "F.Cu" "F.Mask" "F.Paste")
			(net "TP_XDP_CPU_OBSDATA_C2")
		)
		(pad "17" smd rect
			(at 3.999992 0 90.001)
			(size 0.2794 2.286)
			(layers "F.Cu" "F.Mask" "F.Paste")
			(net "TP_XDP_OBSDATA_A3")
		)
		(pad "18" smd rect
			(at 3.999992 -5.727954 90.001)
			(size 0.2794 2.286)
			(layers "F.Cu" "F.Mask" "F.Paste")
			(net "TP_XDP_CPU_OBSDATA_C3")
		)
		(pad "19" smd rect
			(at 4.500118 0 90.001)
			(size 0.2794 2.286)
			(layers "F.Cu" "F.Mask" "F.Paste")
			(net "GND")
		)
		(pad "20" smd rect
			(at 4.500118 -5.727954 90.001)
			(size 0.2794 2.286)
			(layers "F.Cu" "F.Mask" "F.Paste")
			(net "GND")
		)
		(pad "21" smd rect
			(at 4.99999 0 90.001)
			(size 0.2794 2.286)
			(layers "F.Cu" "F.Mask" "F.Paste")
			(net "TP_XDP_OBSFN_B0")
		)
		(pad "22" smd rect
			(at 4.99999 -5.727954 90.001)
			(size 0.2794 2.286)
			(layers "F.Cu" "F.Mask" "F.Paste")
			(net "XDP_OBSFN_B0_MBP6_N")
		)
		(pad "23" smd rect
			(at 5.500116 0 90.001)
			(size 0.2794 2.286)
			(layers "F.Cu" "F.Mask" "F.Paste")
			(net "TP_XDP_OBSFN_B1")
		)
		(pad "24" smd rect
			(at 5.500116 -5.727954 90.001)
			(size 0.2794 2.286)
			(layers "F.Cu" "F.Mask" "F.Paste")
			(net "XDP_OBSFN_B1_MBP7_N")
		)
		(pad "25" smd rect
			(at 5.999988 0 90.001)
			(size 0.2794 2.286)
			(layers "F.Cu" "F.Mask" "F.Paste")
			(net "GND")
		)
		(pad "26" smd rect
			(at 5.999988 -5.727954 90.001)
			(size 0.2794 2.286)
			(layers "F.Cu" "F.Mask" "F.Paste")
			(net "GND")
		)
		(pad "27" smd rect
			(at 6.500114 0 90.001)
			(size 0.2794 2.286)
			(layers "F.Cu" "F.Mask" "F.Paste")
			(net "TP_XDP_OBSDATA_B0")
		)
		(pad "28" smd rect
			(at 6.500114 -5.727954 90.001)
			(size 0.2794 2.286)
			(layers "F.Cu" "F.Mask" "F.Paste")
			(net "TP_XDP_CPU_OBSDATA_D0")
		)
		(pad "29" smd rect
			(at 6.999986 0 90.001)
			(size 0.2794 2.286)
			(layers "F.Cu" "F.Mask" "F.Paste")
			(net "TP_XDP_OBSDATA_B1")
		)
		(pad "30" smd rect
			(at 6.999986 -5.727954 90.001)
			(size 0.2794 2.286)
			(layers "F.Cu" "F.Mask" "F.Paste")
			(net "TP_XDP_CPU_OBSDATA_D1")
		)
		(pad "31" smd rect
			(at 7.500112 0 90.001)
			(size 0.2794 2.286)
			(layers "F.Cu" "F.Mask" "F.Paste")
			(net "GND")
		)
		(pad "32" smd rect
			(at 7.500112 -5.727954 90.001)
			(size 0.2794 2.286)
			(layers "F.Cu" "F.Mask" "F.Paste")
			(net "GND")
		)
		(pad "33" smd rect
			(at 7.999984 0 90.001)
			(size 0.2794 2.286)
			(layers "F.Cu" "F.Mask" "F.Paste")
			(net "TP_XDP_OBSDATA_B2")
		)
		(pad "34" smd rect
			(at 7.999984 -5.727954 90.001)
			(size 0.2794 2.286)
			(layers "F.Cu" "F.Mask" "F.Paste")
			(net "TP_XDP_CPU_OBSDATA_D2")
		)
		(pad "35" smd rect
			(at 8.50011 0 90.001)
			(size 0.2794 2.286)
			(layers "F.Cu" "F.Mask" "F.Paste")
			(net "TP_XDP_OBSDATA_B3")
		)
		(pad "36" smd rect
			(at 8.50011 -5.727954 90.001)
			(size 0.2794 2.286)
			(layers "F.Cu" "F.Mask" "F.Paste")
			(net "TP_XDP_CPU_OBSDATA_D3")
		)
		(pad "37" smd rect
			(at 8.999982 0 90.001)
			(size 0.2794 2.286)
			(layers "F.Cu" "F.Mask" "F.Paste")
			(net "GND")
		)
		(pad "38" smd rect
			(at 8.999982 -5.727954 90.001)
			(size 0.2794 2.286)
			(layers "F.Cu" "F.Mask" "F.Paste")
			(net "GND")
		)
		(pad "39" smd rect
			(at 9.500108 0 90.001)
			(size 0.2794 2.286)
			(layers "F.Cu" "F.Mask" "F.Paste")
			(net "XDP_RSMRST_N")
		)
		(pad "40" smd rect
			(at 9.500108 -5.727954 90.001)
			(size 0.2794 2.286)
			(layers "F.Cu" "F.Mask" "F.Paste")
			(net "CLK_100M_PCH_XDP_DP")
		)
		(pad "41" smd rect
			(at 9.99998 0 90.001)
			(size 0.2794 2.286)
			(layers "F.Cu" "F.Mask" "F.Paste")
			(net "XDP_PWRGD_RST_N")
		)
		(pad "42" smd rect
			(at 9.99998 -5.727954 90.001)
			(size 0.2794 2.286)
			(layers "F.Cu" "F.Mask" "F.Paste")
			(net "CLK_100M_PCH_XDP_DN")
		)
		(pad "43" smd rect
			(at 10.500106 0 90.001)
			(size 0.2794 2.286)
			(layers "F.Cu" "F.Mask" "F.Paste")
			(net "P1V05_PCH_STBY")
		)
		(pad "44" smd rect
			(at 10.500106 -5.727954 90.001)
			(size 0.2794 2.286)
			(layers "F.Cu" "F.Mask" "F.Paste")
			(net "P1V05_PCH_STBY")
		)
		(pad "45" smd rect
			(at 10.999978 0 90.001)
			(size 0.2794 2.286)
			(layers "F.Cu" "F.Mask" "F.Paste")
			(net "XDP_CPU_PWR_DEBUG_N")
		)
		(pad "46" smd rect
			(at 10.999978 -5.727954 90.001)
			(size 0.2794 2.286)
			(layers "F.Cu" "F.Mask" "F.Paste")
			(net "XDP_ITP_PMODE")
		)
		(pad "47" smd rect
			(at 11.500104 0 90.001)
			(size 0.2794 2.286)
			(layers "F.Cu" "F.Mask" "F.Paste")
			(net "XDP_SYSPWROK")
		)
		(pad "48" smd rect
			(at 11.500104 -5.727954 90.001)
			(size 0.2794 2.286)
			(layers "F.Cu" "F.Mask" "F.Paste")
			(net "XDP_RST_CO_N")
		)
		(pad "49" smd rect
			(at 11.999976 0 90.001)
			(size 0.2794 2.286)
			(layers "F.Cu" "F.Mask" "F.Paste")
			(net "GND")
		)
		(pad "50" smd rect
			(at 11.999976 -5.727954 90.001)
			(size 0.2794 2.286)
			(layers "F.Cu" "F.Mask" "F.Paste")
			(net "GND")
		)
		(pad "51" smd rect
			(at 12.500102 0 90.001)
			(size 0.2794 2.286)
			(layers "F.Cu" "F.Mask" "F.Paste")
			(net "SMB_HOST_STBY_LVC3_SDA")
		)
		(pad "52" smd rect
			(at 12.500102 -5.727954 90.001)
			(size 0.2794 2.286)
			(layers "F.Cu" "F.Mask" "F.Paste")
			(net "XDP_TDO")
		)
		(pad "53" smd rect
			(at 12.999974 0 90.001)
			(size 0.2794 2.286)
			(layers "F.Cu" "F.Mask" "F.Paste")
			(net "SMB_HOST_STBY_LVC3_SCL")
		)
		(pad "54" smd rect
			(at 12.999974 -5.727954 90.001)
			(size 0.2794 2.286)
			(layers "F.Cu" "F.Mask" "F.Paste")
			(net "XDP_TRST_N")
		)
		(pad "55" smd rect
			(at 13.5001 0 90.001)
			(size 0.2794 2.286)
			(layers "F.Cu" "F.Mask" "F.Paste")
			(net "XDP_PCH_TCK1")
		)
		(pad "56" smd rect
			(at 13.5001 -5.727954 90.001)
			(size 0.2794 2.286)
			(layers "F.Cu" "F.Mask" "F.Paste")
			(net "XDP_TDI")
		)
		(pad "57" smd rect
			(at 13.999972 0 90.001)
			(size 0.2794 2.286)
			(layers "F.Cu" "F.Mask" "F.Paste")
			(net "XDP_CPU_TCK0")
		)
		(pad "58" smd rect
			(at 13.999972 -5.727954 90.001)
			(size 0.2794 2.286)
			(layers "F.Cu" "F.Mask" "F.Paste")
			(net "XDP_TMS")
		)
		(pad "59" smd rect
			(at 14.500098 0 90.001)
			(size 0.2794 2.286)
			(layers "F.Cu" "F.Mask" "F.Paste")
			(net "GND")
		)
		(pad "60" smd rect
			(at 14.500098 -5.727954 90.001)
			(size 0.2794 2.286)
			(layers "F.Cu" "F.Mask" "F.Paste")
			(net "XDP_PRESENT_N")
		)
		(zone
			(layers "F.Cu" "B.Cu" "In1.Cu" "In2.Cu" "In3.Cu" "In4.Cu" "In5.Cu" "In6.Cu"
				"In7.Cu" "In8.Cu" "In9.Cu" "In10.Cu" "In11.Cu" "In12.Cu"
			)
			(hatch none 0.5)
			(connect_pads
				(clearance 0)
			)
			(min_thickness 0.25)
			(keepout
				(tracks not_allowed)
				(vias allowed)
				(pads allowed)
				(copperpour not_allowed)
				(footprints allowed)
			)
			(placement
				(enabled no)
				(sheetname "")
			)
			(fill
				(thermal_gap 0.5)
				(thermal_bridge_width 0.5)
				(island_removal_mode 0)
			)
			(polygon
				(pts
					(arc
						(start 458.22489 -153.035762)
						(mid 456.67549 -153.035762)
						(end 458.22489 -153.035762)
					)
				)
			)
		)
		(zone
			(layers "F.Cu" "B.Cu" "In1.Cu" "In2.Cu" "In3.Cu" "In4.Cu" "In5.Cu" "In6.Cu"
				"In7.Cu" "In8.Cu" "In9.Cu" "In10.Cu" "In11.Cu" "In12.Cu"
			)
			(hatch none 0.5)
			(connect_pads
				(clearance 0)
			)
			(min_thickness 0.25)
			(keepout
				(tracks not_allowed)
				(vias allowed)
				(pads allowed)
				(copperpour not_allowed)
				(footprints allowed)
			)
			(placement
				(enabled no)
				(sheetname "")
			)
			(fill
				(thermal_gap 0.5)
				(thermal_bridge_width 0.5)
				(island_removal_mode 0)
			)
			(polygon
				(pts
					(arc
						(start 458.225144 -132.909818)
						(mid 456.675744 -132.909818)
						(end 458.225144 -132.909818)
					)
				)
			)
		)
	)
	(footprint ""
		(layer "F.Cu")
		(at 404.241 -82.7405 180)
		(property "Reference" "R2P15"
			(at 0 0 180)
			(layer "F.SilkS")
			(hide yes)
			(effects
				(font
					(size 1.27 1.27)
				)
			)
		)
		(property "Value" ""
			(at 0 0 180)
			(layer "F.Fab")
			(effects
				(font
					(size 1.27 1.27)
				)
			)
		)
		(duplicate_pad_numbers_are_jumpers no)
		(fp_poly
			(pts
				(xy -0.2794 -0.1016) (xy 0.2794 -0.1016) (xy 0.2794 0.9906) (xy -0.2794 0.9906)
			)
			(stroke
				(width 0)
				(type default)
			)
			(fill no)
			(layer "F.CrtYd")
		)
		(fp_line
			(start 0.2794 0.9906)
			(end 0.2794 -0.1016)
			(stroke
				(width 0.1)
				(type default)
			)
			(layer "F.Fab")
		)
		(fp_line
			(start 0.2794 -0.1016)
			(end -0.2794 -0.1016)
			(stroke
				(width 0.1)
				(type default)
			)
			(layer "F.Fab")
		)
		(fp_line
			(start -0.2794 0.9906)
			(end 0.2794 0.9906)
			(stroke
				(width 0.1)
				(type default)
			)
			(layer "F.Fab")
		)
		(fp_line
			(start -0.2794 -0.1016)
			(end -0.2794 0.9906)
			(stroke
				(width 0.1)
				(type default)
			)
			(layer "F.Fab")
		)
		(pad "1" smd rect
			(at 0 0 180)
			(size 0.508 0.508)
			(layers "F.Cu" "F.Mask" "F.Paste")
			(net "P3V3")
		)
		(pad "2" smd rect
			(at 0 0.889 180)
			(size 0.508 0.508)
			(layers "F.Cu" "F.Mask" "F.Paste")
			(net "FM_M2_SSD_PEDET")
		)
		(zone
			(layer "F.Cu")
			(hatch none 0.5)
			(connect_pads
				(clearance 0)
			)
			(min_thickness 0.25)
			(keepout
				(tracks not_allowed)
				(vias allowed)
				(pads allowed)
				(copperpour not_allowed)
				(footprints allowed)
			)
			(placement
				(enabled no)
				(sheetname "")
			)
			(fill
				(thermal_gap 0.5)
				(thermal_bridge_width 0.5)
				(island_removal_mode 0)
			)
			(polygon
				(pts
					(xy 404.495 -83.3755) (xy 403.987 -83.3755) (xy 403.987 -82.9945) (xy 404.495 -82.9945)
				)
			)
		)
		(zone
			(layer "F.Cu")
			(hatch none 0.5)
			(connect_pads
				(clearance 0)
			)
			(min_thickness 0.25)
			(keepout
				(tracks allowed)
				(vias not_allowed)
				(pads allowed)
				(copperpour not_allowed)
				(footprints allowed)
			)
			(placement
				(enabled no)
				(sheetname "")
			)
			(fill
				(thermal_gap 0.5)
				(thermal_bridge_width 0.5)
				(island_removal_mode 0)
			)
			(polygon
				(pts
					(xy 404.495 -82.9945) (xy 403.987 -82.9945) (xy 403.987 -83.3755) (xy 404.495 -83.3755)
				)
			)
		)
	)
	(footprint ""
		(layer "F.Cu")
		(at 309.18785 -32.492696 90)
		(property "Reference" "Q1F1"
			(at -0.229362 -1.2065 90)
			(unlocked yes)
			(layer "F.SilkS")
			(effects
				(font
					(size 0.4064 0.254)
					(thickness 0.1524)
				)
				(justify left)
			)
		)
		(property "Value" ""
			(at 0 0 90)
			(layer "F.Fab")
			(effects
				(font
					(size 1.27 1.27)
				)
			)
		)
		(duplicate_pad_numbers_are_jumpers no)
		(fp_line
			(start 1.778 -0.5715)
			(end 1.778 0.3175)
			(stroke
				(width 0.1524)
				(type default)
			)
			(layer "F.SilkS")
		)
		(fp_line
			(start 0.9525 -0.5715)
			(end 1.778 -0.5715)
			(stroke
				(width 0.1524)
				(type default)
			)
			(layer "F.SilkS")
		)
		(fp_line
			(start 0.381 0.635)
			(end 0.381 1.27)
			(stroke
				(width 0.1524)
				(type default)
			)
			(layer "F.SilkS")
		)
		(fp_line
			(start 1.778 2.4765)
			(end 1.778 1.5875)
			(stroke
				(width 0.1524)
				(type default)
			)
			(layer "F.SilkS")
		)
		(fp_line
			(start 0.9525 2.4765)
			(end 1.778 2.4765)
			(stroke
				(width 0.1524)
				(type default)
			)
			(layer "F.SilkS")
		)
		(fp_circle
			(center -0.9525 -0.9271)
			(end -0.9525 -0.8001)
			(stroke
				(width 0.254)
				(type default)
			)
			(fill no)
			(layer "F.SilkS")
		)
		(fp_poly
			(pts
				(xy 1.778 2.4765) (xy 0.381 2.4765) (xy 0.381 -0.5715) (xy 1.778 -0.5715)
			)
			(stroke
				(width 0)
				(type default)
			)
			(fill no)
			(layer "F.CrtYd")
		)
		(fp_line
			(start 1.778 -0.5715)
			(end 0.381 -0.5715)
			(stroke
				(width 0.1)
				(type default)
			)
			(layer "F.Fab")
		)
		(fp_line
			(start 0.381 -0.5715)
			(end 0.381 2.4765)
			(stroke
				(width 0.1)
				(type default)
			)
			(layer "F.Fab")
		)
		(fp_line
			(start 1.778 2.4765)
			(end 1.778 -0.5715)
			(stroke
				(width 0.1)
				(type default)
			)
			(layer "F.Fab")
		)
		(fp_line
			(start 0.381 2.4765)
			(end 1.778 2.4765)
			(stroke
				(width 0.1)
				(type default)
			)
			(layer "F.Fab")
		)
		(fp_circle
			(center -0.9525 -0.9271)
			(end -0.9525 -0.8001)
			(stroke
				(width 0.254)
				(type default)
			)
			(fill no)
			(layer "F.Fab")
		)
		(pad "1" smd rect
			(at 0 0 90)
			(size 1.143 0.508)
			(layers "F.Cu" "F.Mask" "F.Paste")
			(net "FM_ADR_COMPLETE_CPU0_R")
		)
		(pad "2" smd rect
			(at 0 1.905 90)
			(size 1.143 0.508)
			(layers "F.Cu" "F.Mask" "F.Paste")
			(net "GND")
		)
		(pad "3" smd rect
			(at 2.159 0.9525 90)
			(size 1.143 0.508)
			(layers "F.Cu" "F.Mask" "F.Paste")
			(net "IRQ_DIMM_SAVE_N")
		)
	)
	(footprint ""
		(layer "F.Cu")
		(at 414.962594 -48.083216 180)
		(property "Reference" "C25W20"
			(at -0.8382 -0.67818 180)
			(unlocked yes)
			(layer "F.SilkS")
			(effects
				(font
					(size 0.4064 0.254)
					(thickness 0.1524)
				)
				(justify left)
			)
		)
		(property "Value" ""
			(at 0 0 180)
			(layer "F.Fab")
			(effects
				(font
					(size 1.27 1.27)
				)
			)
		)
		(duplicate_pad_numbers_are_jumpers no)
		(fp_poly
			(pts
				(xy 0.3048 -0.1016) (xy 0.3048 0.9906) (xy -0.3048 0.9906) (xy -0.3048 -0.1016)
			)
			(stroke
				(width 0)
				(type default)
			)
			(fill no)
			(layer "F.CrtYd")
		)
		(fp_line
			(start 0.3048 0.9906)
			(end 0.3048 -0.1016)
			(stroke
				(width 0.1)
				(type default)
			)
			(layer "F.Fab")
		)
		(fp_line
			(start 0.3048 -0.1016)
			(end -0.3048 -0.1016)
			(stroke
				(width 0.1)
				(type default)
			)
			(layer "F.Fab")
		)
		(fp_line
			(start -0.3048 0.9906)
			(end 0.3048 0.9906)
			(stroke
				(width 0.1)
				(type default)
			)
			(layer "F.Fab")
		)
		(fp_line
			(start -0.3048 -0.1016)
			(end -0.3048 0.9906)
			(stroke
				(width 0.1)
				(type default)
			)
			(layer "F.Fab")
		)
		(pad "1" smd rect
			(at 0 0 180)
			(size 0.508 0.508)
			(layers "F.Cu" "F.Mask" "F.Paste")
			(net "P2E_SSB_BMC_RX_DP")
		)
		(pad "2" smd rect
			(at 0 0.889 180)
			(size 0.508 0.508)
			(layers "F.Cu" "F.Mask" "F.Paste")
			(net "P2E_SSB_BMC_RX_C_DP")
		)
		(zone
			(layer "F.Cu")
			(hatch none 0.5)
			(connect_pads
				(clearance 0)
			)
			(min_thickness 0.25)
			(keepout
				(tracks not_allowed)
				(vias allowed)
				(pads allowed)
				(copperpour not_allowed)
				(footprints allowed)
			)
			(placement
				(enabled no)
				(sheetname "")
			)
			(fill
				(thermal_gap 0.5)
				(thermal_bridge_width 0.5)
				(island_removal_mode 0)
			)
			(polygon
				(pts
					(xy 415.216594 -48.718216) (xy 414.708594 -48.718216) (xy 414.708594 -48.337216) (xy 415.216594 -48.337216)
				)
			)
		)
		(zone
			(layer "F.Cu")
			(hatch none 0.5)
			(connect_pads
				(clearance 0)
			)
			(min_thickness 0.25)
			(keepout
				(tracks allowed)
				(vias not_allowed)
				(pads allowed)
				(copperpour not_allowed)
				(footprints allowed)
			)
			(placement
				(enabled no)
				(sheetname "")
			)
			(fill
				(thermal_gap 0.5)
				(thermal_bridge_width 0.5)
				(island_removal_mode 0)
			)
			(polygon
				(pts
					(xy 415.216594 -48.337216) (xy 414.708594 -48.337216) (xy 414.708594 -48.718216) (xy 415.216594 -48.718216)
				)
			)
		)
	)
	(footprint ""
		(layer "F.Cu")
		(at 116.332 -75.565 90)
		(property "Reference" "R3D13"
			(at 0 0 90)
			(layer "F.SilkS")
			(hide yes)
			(effects
				(font
					(size 1.27 1.27)
				)
			)
		)
		(property "Value" ""
			(at 0 0 90)
			(layer "F.Fab")
			(effects
				(font
					(size 1.27 1.27)
				)
			)
		)
		(duplicate_pad_numbers_are_jumpers no)
		(fp_poly
			(pts
				(xy -0.2794 -0.1016) (xy 0.2794 -0.1016) (xy 0.2794 0.9906) (xy -0.2794 0.9906)
			)
			(stroke
				(width 0)
				(type default)
			)
			(fill no)
			(layer "F.CrtYd")
		)
		(fp_line
			(start 0.2794 -0.1016)
			(end -0.2794 -0.1016)
			(stroke
				(width 0.1)
				(type default)
			)
			(layer "F.Fab")
		)
		(fp_line
			(start -0.2794 -0.1016)
			(end -0.2794 0.9906)
			(stroke
				(width 0.1)
				(type default)
			)
			(layer "F.Fab")
		)
		(fp_line
			(start 0.2794 0.9906)
			(end 0.2794 -0.1016)
			(stroke
				(width 0.1)
				(type default)
			)
			(layer "F.Fab")
		)
		(fp_line
			(start -0.2794 0.9906)
			(end 0.2794 0.9906)
			(stroke
				(width 0.1)
				(type default)
			)
			(layer "F.Fab")
		)
		(pad "1" smd rect
			(at 0 0 90)
			(size 0.508 0.508)
			(layers "F.Cu" "F.Mask" "F.Paste")
			(net "GND")
		)
		(pad "2" smd rect
			(at 0 0.889 90)
			(size 0.508 0.508)
			(layers "F.Cu" "F.Mask" "F.Paste")
			(net "PD_CPU1_BIST_ENABLE")
		)
		(zone
			(layer "F.Cu")
			(hatch none 0.5)
			(connect_pads
				(clearance 0)
			)
			(min_thickness 0.25)
			(keepout
				(tracks allowed)
				(vias not_allowed)
				(pads allowed)
				(copperpour not_allowed)
				(footprints allowed)
			)
			(placement
				(enabled no)
				(sheetname "")
			)
			(fill
				(thermal_gap 0.5)
				(thermal_bridge_width 0.5)
				(island_removal_mode 0)
			)
			(polygon
				(pts
					(xy 116.586 -75.311) (xy 116.586 -75.819) (xy 116.967 -75.819) (xy 116.967 -75.311)
				)
			)
		)
		(zone
			(layer "F.Cu")
			(hatch none 0.5)
			(connect_pads
				(clearance 0)
			)
			(min_thickness 0.25)
			(keepout
				(tracks not_allowed)
				(vias allowed)
				(pads allowed)
				(copperpour not_allowed)
				(footprints allowed)
			)
			(placement
				(enabled no)
				(sheetname "")
			)
			(fill
				(thermal_gap 0.5)
				(thermal_bridge_width 0.5)
				(island_removal_mode 0)
			)
			(polygon
				(pts
					(xy 116.967 -75.311) (xy 116.967 -75.819) (xy 116.586 -75.819) (xy 116.586 -75.311)
				)
			)
		)
	)
	(footprint ""
		(layer "F.Cu")
		(at 454.914 -29.337)
		(property "Reference" "DS9F1"
			(at 0.29083 4.3307 90)
			(unlocked yes)
			(layer "F.SilkS")
			(effects
				(font
					(size 0.7874 0.5842)
					(thickness 0.1524)
				)
			)
		)
		(property "Value" ""
			(at 0 0 0)
			(layer "F.Fab")
			(effects
				(font
					(size 1.27 1.27)
				)
			)
		)
		(duplicate_pad_numbers_are_jumpers no)
		(fp_line
			(start -1.46558 0.060452)
			(end -0.984758 0.060452)
			(stroke
				(width 0.1524)
				(type default)
			)
			(layer "F.SilkS")
		)
		(fp_line
			(start -1.46558 0.893318)
			(end -0.503936 0.893318)
			(stroke
				(width 0.1524)
				(type default)
			)
			(layer "F.SilkS")
		)
		(fp_line
			(start -0.984758 -0.851154)
			(end -0.984758 0.060452)
			(stroke
				(width 0.1524)
				(type default)
			)
			(layer "F.SilkS")
		)
		(fp_line
			(start -0.984758 0.060452)
			(end -0.503936 0.060452)
			(stroke
				(width 0.1524)
				(type default)
			)
			(layer "F.SilkS")
		)
		(fp_line
			(start -0.984758 0.893318)
			(end -1.46558 0.060452)
			(stroke
				(width 0.1524)
				(type default)
			)
			(layer "F.SilkS")
		)
		(fp_line
			(start -0.984758 2.01676)
			(end -0.984758 0.893318)
			(stroke
				(width 0.1524)
				(type default)
			)
			(layer "F.SilkS")
		)
		(fp_line
			(start -0.503936 0.060452)
			(end -0.984758 0.893318)
			(stroke
				(width 0.1524)
				(type default)
			)
			(layer "F.SilkS")
		)
		(fp_rect
			(start -0.4064 1.6891)
			(end 0.4064 0.0889)
			(stroke
				(width 0)
				(type default)
			)
			(fill no)
			(layer "F.CrtYd")
		)
		(fp_line
			(start -1.554734 0.007112)
			(end -0.59309 0.007112)
			(stroke
				(width 0.1)
				(type default)
			)
			(layer "F.Fab")
		)
		(fp_line
			(start -1.554734 0.839978)
			(end -0.59309 0.839978)
			(stroke
				(width 0.1)
				(type default)
			)
			(layer "F.Fab")
		)
		(fp_line
			(start -1.073912 0.007112)
			(end -1.073912 -0.904494)
			(stroke
				(width 0.1)
				(type default)
			)
			(layer "F.Fab")
		)
		(fp_line
			(start -1.073912 0.839978)
			(end -1.554734 0.007112)
			(stroke
				(width 0.1)
				(type default)
			)
			(layer "F.Fab")
		)
		(fp_line
			(start -1.073912 0.839978)
			(end -1.073912 1.96342)
			(stroke
				(width 0.1)
				(type default)
			)
			(layer "F.Fab")
		)
		(fp_line
			(start -0.59309 0.007112)
			(end -1.073912 0.839978)
			(stroke
				(width 0.1)
				(type default)
			)
			(layer "F.Fab")
		)
		(fp_line
			(start -0.4064 0.0889)
			(end 0.4064 0.0889)
			(stroke
				(width 0.1)
				(type default)
			)
			(layer "F.Fab")
		)
		(fp_line
			(start -0.4064 1.6891)
			(end -0.4064 0.0889)
			(stroke
				(width 0.1)
				(type default)
			)
			(layer "F.Fab")
		)
		(fp_line
			(start 0.4064 0.0889)
			(end 0.4064 1.6891)
			(stroke
				(width 0.1)
				(type default)
			)
			(layer "F.Fab")
		)
		(fp_line
			(start 0.4064 1.6891)
			(end -0.4064 1.6891)
			(stroke
				(width 0.1)
				(type default)
			)
			(layer "F.Fab")
		)
		(pad "1" smd rect
			(at 0 0)
			(size 0.762 1.27)
			(layers "F.Cu" "F.Mask" "F.Paste")
			(net "FM_RED_LED_ANODE")
		)
		(pad "2" smd rect
			(at 0 1.778)
			(size 0.762 1.27)
			(layers "F.Cu" "F.Mask" "F.Paste")
			(net "FM_RED_LED_CATHODE")
		)
		(zone
			(layer "F.Cu")
			(hatch none 0.5)
			(connect_pads
				(clearance 0)
			)
			(min_thickness 0.25)
			(keepout
				(tracks not_allowed)
				(vias allowed)
				(pads allowed)
				(copperpour not_allowed)
				(footprints allowed)
			)
			(placement
				(enabled no)
				(sheetname "")
			)
			(fill
				(thermal_gap 0.5)
				(thermal_bridge_width 0.5)
				(island_removal_mode 0)
			)
			(polygon
				(pts
					(xy 454.533 -28.6766) (xy 455.295 -28.6766) (xy 455.295 -28.2194) (xy 454.533 -28.2194)
				)
			)
		)
		(zone
			(layer "F.Cu")
			(hatch none 0.5)
			(connect_pads
				(clearance 0)
			)
			(min_thickness 0.25)
			(keepout
				(tracks allowed)
				(vias not_allowed)
				(pads allowed)
				(copperpour not_allowed)
				(footprints allowed)
			)
			(placement
				(enabled no)
				(sheetname "")
			)
			(fill
				(thermal_gap 0.5)
				(thermal_bridge_width 0.5)
				(island_removal_mode 0)
			)
			(polygon
				(pts
					(xy 454.533 -28.2194) (xy 455.295 -28.2194) (xy 455.295 -28.6766) (xy 454.533 -28.6766)
				)
			)
		)
	)
	(footprint ""
		(layer "F.Cu")
		(at 103.172768 -79.6036 180)
		(property "Reference" "C2D17"
			(at 0 0 180)
			(layer "F.SilkS")
			(hide yes)
			(effects
				(font
					(size 1.27 1.27)
				)
			)
		)
		(property "Value" ""
			(at 0 0 180)
			(layer "F.Fab")
			(effects
				(font
					(size 1.27 1.27)
				)
			)
		)
		(duplicate_pad_numbers_are_jumpers no)
		(fp_poly
			(pts
				(xy -0.4953 -0.2032) (xy 0.4953 -0.2032) (xy 0.4953 1.6002) (xy -0.4953 1.6002)
			)
			(stroke
				(width 0)
				(type default)
			)
			(fill no)
			(layer "F.CrtYd")
		)
		(fp_line
			(start 0.4953 1.6002)
			(end -0.4953 1.6002)
			(stroke
				(width 0.1)
				(type default)
			)
			(layer "F.Fab")
		)
		(fp_line
			(start 0.4953 -0.2032)
			(end 0.4953 1.6002)
			(stroke
				(width 0.1)
				(type default)
			)
			(layer "F.Fab")
		)
		(fp_line
			(start -0.4953 1.6002)
			(end -0.4953 -0.2032)
			(stroke
				(width 0.1)
				(type default)
			)
			(layer "F.Fab")
		)
		(fp_line
			(start -0.4953 -0.2032)
			(end 0.4953 -0.2032)
			(stroke
				(width 0.1)
				(type default)
			)
			(layer "F.Fab")
		)
		(pad "1" smd rect
			(at 0 0 180)
			(size 0.762 0.889)
			(layers "F.Cu" "F.Mask" "F.Paste")
			(net "PVCCIN_CPU1")
		)
		(pad "2" smd rect
			(at 0 1.397 180)
			(size 0.762 0.889)
			(layers "F.Cu" "F.Mask" "F.Paste")
			(net "GND")
		)
		(zone
			(layer "F.Cu")
			(hatch none 0.5)
			(connect_pads
				(clearance 0)
			)
			(min_thickness 0.25)
			(keepout
				(tracks not_allowed)
				(vias allowed)
				(pads allowed)
				(copperpour not_allowed)
				(footprints allowed)
			)
			(placement
				(enabled no)
				(sheetname "")
			)
			(fill
				(thermal_gap 0.5)
				(thermal_bridge_width 0.5)
				(island_removal_mode 0)
			)
			(polygon
				(pts
					(xy 103.553768 -80.0481) (xy 102.791768 -80.0481) (xy 102.791768 -80.5561) (xy 103.553768 -80.5561)
				)
			)
		)
	)
	(footprint ""
		(layer "F.Cu")
		(at 324.5485 -123.825 -90)
		(property "Reference" "C826"
			(at -0.8382 -0.67818 270)
			(unlocked yes)
			(layer "F.SilkS")
			(effects
				(font
					(size 0.4064 0.254)
					(thickness 0.1524)
				)
				(justify left)
			)
		)
		(property "Value" ""
			(at 0 0 270)
			(layer "F.Fab")
			(effects
				(font
					(size 1.27 1.27)
				)
			)
		)
		(duplicate_pad_numbers_are_jumpers no)
		(fp_poly
			(pts
				(xy 0.3048 -0.1016) (xy 0.3048 0.9906) (xy -0.3048 0.9906) (xy -0.3048 -0.1016)
			)
			(stroke
				(width 0)
				(type default)
			)
			(fill no)
			(layer "F.CrtYd")
		)
		(fp_line
			(start -0.3048 0.9906)
			(end 0.3048 0.9906)
			(stroke
				(width 0.1)
				(type default)
			)
			(layer "F.Fab")
		)
		(fp_line
			(start 0.3048 0.9906)
			(end 0.3048 -0.1016)
			(stroke
				(width 0.1)
				(type default)
			)
			(layer "F.Fab")
		)
		(fp_line
			(start -0.3048 -0.1016)
			(end -0.3048 0.9906)
			(stroke
				(width 0.1)
				(type default)
			)
			(layer "F.Fab")
		)
		(fp_line
			(start 0.3048 -0.1016)
			(end -0.3048 -0.1016)
			(stroke
				(width 0.1)
				(type default)
			)
			(layer "F.Fab")
		)
		(pad "1" smd rect
			(at 0 0 270)
			(size 0.508 0.508)
			(layers "F.Cu" "F.Mask" "F.Paste")
			(net "P3E_CPU0_PE1_PCH_TXN<14>")
		)
		(pad "2" smd rect
			(at 0 0.889 270)
			(size 0.508 0.508)
			(layers "F.Cu" "F.Mask" "F.Paste")
			(net "P3E_CPU0_PE1_PCH_CON_TXN<14>")
		)
		(zone
			(layer "F.Cu")
			(hatch none 0.5)
			(connect_pads
				(clearance 0)
			)
			(min_thickness 0.25)
			(keepout
				(tracks not_allowed)
				(vias allowed)
				(pads allowed)
				(copperpour not_allowed)
				(footprints allowed)
			)
			(placement
				(enabled no)
				(sheetname "")
			)
			(fill
				(thermal_gap 0.5)
				(thermal_bridge_width 0.5)
				(island_removal_mode 0)
			)
			(polygon
				(pts
					(xy 323.9135 -124.079) (xy 323.9135 -123.571) (xy 324.2945 -123.571) (xy 324.2945 -124.079)
				)
			)
		)
		(zone
			(layer "F.Cu")
			(hatch none 0.5)
			(connect_pads
				(clearance 0)
			)
			(min_thickness 0.25)
			(keepout
				(tracks allowed)
				(vias not_allowed)
				(pads allowed)
				(copperpour not_allowed)
				(footprints allowed)
			)
			(placement
				(enabled no)
				(sheetname "")
			)
			(fill
				(thermal_gap 0.5)
				(thermal_bridge_width 0.5)
				(island_removal_mode 0)
			)
			(polygon
				(pts
					(xy 324.2945 -124.079) (xy 324.2945 -123.571) (xy 323.9135 -123.571) (xy 323.9135 -124.079)
				)
			)
		)
	)
	(footprint ""
		(layer "F.Cu")
		(at 185.166 -15.113)
		(property "Reference" "FB4G1"
			(at 0 0 0)
			(layer "F.SilkS")
			(hide yes)
			(effects
				(font
					(size 1.27 1.27)
				)
			)
		)
		(property "Value" ""
			(at 0 0 0)
			(layer "F.Fab")
			(effects
				(font
					(size 1.27 1.27)
				)
			)
		)
		(duplicate_pad_numbers_are_jumpers no)
		(fp_rect
			(start -0.7239 2.03835)
			(end 0.7239 -0.26035)
			(stroke
				(width 0)
				(type default)
			)
			(fill no)
			(layer "F.CrtYd")
		)
		(fp_line
			(start -0.7239 -0.26035)
			(end 0.7239 -0.26035)
			(stroke
				(width 0.1)
				(type default)
			)
			(layer "F.Fab")
		)
		(fp_line
			(start -0.7239 2.03835)
			(end -0.7239 -0.26035)
			(stroke
				(width 0.1)
				(type default)
			)
			(layer "F.Fab")
		)
		(fp_line
			(start 0.7239 -0.26035)
			(end 0.7239 2.03835)
			(stroke
				(width 0.1)
				(type default)
			)
			(layer "F.Fab")
		)
		(fp_line
			(start 0.7239 2.03835)
			(end -0.7239 2.03835)
			(stroke
				(width 0.1)
				(type default)
			)
			(layer "F.Fab")
		)
		(pad "1" smd rect
			(at 0 0)
			(size 1.27 1.016)
			(layers "F.Cu" "F.Mask" "F.Paste")
			(net "P12V_STBY")
		)
		(pad "2" smd rect
			(at 0 1.778)
			(size 1.27 1.016)
			(layers "F.Cu" "F.Mask" "F.Paste")
			(net "VR_FET_SW_P12V_STBY_PVPP_GHJ")
		)
		(zone
			(layer "F.Cu")
			(hatch none 0.5)
			(connect_pads
				(clearance 0)
			)
			(min_thickness 0.25)
			(keepout
				(tracks not_allowed)
				(vias allowed)
				(pads allowed)
				(copperpour not_allowed)
				(footprints allowed)
			)
			(placement
				(enabled no)
				(sheetname "")
			)
			(fill
				(thermal_gap 0.5)
				(thermal_bridge_width 0.5)
				(island_removal_mode 0)
			)
			(polygon
				(pts
					(xy 185.801 -14.605) (xy 185.801 -13.843) (xy 185.7121 -13.843) (xy 184.531 -13.843) (xy 184.531 -14.605)
				)
			)
		)
	)
	(footprint ""
		(layer "F.Cu")
		(at 396.468092 -10.968736)
		(property "Reference" "C7G24"
			(at 0 0 0)
			(layer "F.SilkS")
			(hide yes)
			(effects
				(font
					(size 1.27 1.27)
				)
			)
		)
		(property "Value" ""
			(at 0 0 0)
			(layer "F.Fab")
			(effects
				(font
					(size 1.27 1.27)
				)
			)
		)
		(duplicate_pad_numbers_are_jumpers no)
		(fp_rect
			(start -0.3048 0.9906)
			(end 0.3048 -0.1016)
			(stroke
				(width 0)
				(type default)
			)
			(fill no)
			(layer "F.CrtYd")
		)
		(fp_line
			(start -0.3048 -0.1016)
			(end -0.3048 0.9906)
			(stroke
				(width 0.1)
				(type default)
			)
			(layer "F.Fab")
		)
		(fp_line
			(start -0.3048 0.9906)
			(end 0.3048 0.9906)
			(stroke
				(width 0.1)
				(type default)
			)
			(layer "F.Fab")
		)
		(fp_line
			(start 0.3048 -0.1016)
			(end -0.3048 -0.1016)
			(stroke
				(width 0.1)
				(type default)
			)
			(layer "F.Fab")
		)
		(fp_line
			(start 0.3048 0.9906)
			(end 0.3048 -0.1016)
			(stroke
				(width 0.1)
				(type default)
			)
			(layer "F.Fab")
		)
		(pad "1" smd rect
			(at 0 0)
			(size 0.508 0.508)
			(layers "F.Cu" "F.Mask" "F.Paste")
			(net "P3E_CPU0_PE2_SS_TXN<6>")
		)
		(pad "2" smd rect
			(at 0 0.889)
			(size 0.508 0.508)
			(layers "F.Cu" "F.Mask" "F.Paste")
			(net "P3E_CPU0_PE2_SS_C_TXN<6>")
		)
		(zone
			(layer "F.Cu")
			(hatch none 0.5)
			(connect_pads
				(clearance 0)
			)
			(min_thickness 0.25)
			(keepout
				(tracks not_allowed)
				(vias allowed)
				(pads allowed)
				(copperpour not_allowed)
				(footprints allowed)
			)
			(placement
				(enabled no)
				(sheetname "")
			)
			(fill
				(thermal_gap 0.5)
				(thermal_bridge_width 0.5)
				(island_removal_mode 0)
			)
			(polygon
				(pts
					(xy 396.214092 -10.333736) (xy 396.722092 -10.333736) (xy 396.722092 -10.714736) (xy 396.214092 -10.714736)
				)
			)
		)
		(zone
			(layer "F.Cu")
			(hatch none 0.5)
			(connect_pads
				(clearance 0)
			)
			(min_thickness 0.25)
			(keepout
				(tracks allowed)
				(vias not_allowed)
				(pads allowed)
				(copperpour not_allowed)
				(footprints allowed)
			)
			(placement
				(enabled no)
				(sheetname "")
			)
			(fill
				(thermal_gap 0.5)
				(thermal_bridge_width 0.5)
				(island_removal_mode 0)
			)
			(polygon
				(pts
					(xy 396.214092 -10.333736) (xy 396.722092 -10.333736) (xy 396.722092 -10.714736) (xy 396.214092 -10.714736)
				)
			)
		)
	)
	(footprint ""
		(layer "F.Cu")
		(at 198.046594 -76.698856 90)
		(property "Reference" "C4D35"
			(at -0.8382 -0.67818 90)
			(unlocked yes)
			(layer "F.SilkS")
			(effects
				(font
					(size 0.4064 0.254)
					(thickness 0.1524)
				)
				(justify left)
			)
		)
		(property "Value" ""
			(at 0 0 90)
			(layer "F.Fab")
			(effects
				(font
					(size 1.27 1.27)
				)
			)
		)
		(duplicate_pad_numbers_are_jumpers no)
		(fp_poly
			(pts
				(xy 0.3048 -0.1016) (xy 0.3048 0.9906) (xy -0.3048 0.9906) (xy -0.3048 -0.1016)
			)
			(stroke
				(width 0)
				(type default)
			)
			(fill no)
			(layer "F.CrtYd")
		)
		(fp_line
			(start 0.3048 -0.1016)
			(end -0.3048 -0.1016)
			(stroke
				(width 0.1)
				(type default)
			)
			(layer "F.Fab")
		)
		(fp_line
			(start -0.3048 -0.1016)
			(end -0.3048 0.9906)
			(stroke
				(width 0.1)
				(type default)
			)
			(layer "F.Fab")
		)
		(fp_line
			(start 0.3048 0.9906)
			(end 0.3048 -0.1016)
			(stroke
				(width 0.1)
				(type default)
			)
			(layer "F.Fab")
		)
		(fp_line
			(start -0.3048 0.9906)
			(end 0.3048 0.9906)
			(stroke
				(width 0.1)
				(type default)
			)
			(layer "F.Fab")
		)
		(pad "1" smd rect
			(at 0 0 90)
			(size 0.508 0.508)
			(layers "F.Cu" "F.Mask" "F.Paste")
			(net "VR_FET_SW_P12V_STBY_PVCCIN_CPU0")
		)
		(pad "2" smd rect
			(at 0 0.889 90)
			(size 0.508 0.508)
			(layers "F.Cu" "F.Mask" "F.Paste")
			(net "GND")
		)
		(zone
			(layer "F.Cu")
			(hatch none 0.5)
			(connect_pads
				(clearance 0)
			)
			(min_thickness 0.25)
			(keepout
				(tracks allowed)
				(vias not_allowed)
				(pads allowed)
				(copperpour not_allowed)
				(footprints allowed)
			)
			(placement
				(enabled no)
				(sheetname "")
			)
			(fill
				(thermal_gap 0.5)
				(thermal_bridge_width 0.5)
				(island_removal_mode 0)
			)
			(polygon
				(pts
					(xy 198.300594 -76.444856) (xy 198.300594 -76.952856) (xy 198.681594 -76.952856) (xy 198.681594 -76.444856)
				)
			)
		)
		(zone
			(layer "F.Cu")
			(hatch none 0.5)
			(connect_pads
				(clearance 0)
			)
			(min_thickness 0.25)
			(keepout
				(tracks not_allowed)
				(vias allowed)
				(pads allowed)
				(copperpour not_allowed)
				(footprints allowed)
			)
			(placement
				(enabled no)
				(sheetname "")
			)
			(fill
				(thermal_gap 0.5)
				(thermal_bridge_width 0.5)
				(island_removal_mode 0)
			)
			(polygon
				(pts
					(xy 198.681594 -76.444856) (xy 198.681594 -76.952856) (xy 198.300594 -76.952856) (xy 198.300594 -76.444856)
				)
			)
		)
	)
	(footprint ""
		(layer "F.Cu")
		(at -3.175 -144.8562 -90)
		(property "Reference" "R1A2"
			(at 0 0 270)
			(layer "F.SilkS")
			(hide yes)
			(effects
				(font
					(size 1.27 1.27)
				)
			)
		)
		(property "Value" ""
			(at 0 0 270)
			(layer "F.Fab")
			(effects
				(font
					(size 1.27 1.27)
				)
			)
		)
		(duplicate_pad_numbers_are_jumpers no)
		(fp_poly
			(pts
				(xy -0.2794 -0.1016) (xy 0.2794 -0.1016) (xy 0.2794 0.9906) (xy -0.2794 0.9906)
			)
			(stroke
				(width 0)
				(type default)
			)
			(fill no)
			(layer "F.CrtYd")
		)
		(fp_line
			(start -0.2794 0.9906)
			(end 0.2794 0.9906)
			(stroke
				(width 0.1)
				(type default)
			)
			(layer "F.Fab")
		)
		(fp_line
			(start 0.2794 0.9906)
			(end 0.2794 -0.1016)
			(stroke
				(width 0.1)
				(type default)
			)
			(layer "F.Fab")
		)
		(fp_line
			(start -0.2794 -0.1016)
			(end -0.2794 0.9906)
			(stroke
				(width 0.1)
				(type default)
			)
			(layer "F.Fab")
		)
		(fp_line
			(start 0.2794 -0.1016)
			(end -0.2794 -0.1016)
			(stroke
				(width 0.1)
				(type default)
			)
			(layer "F.Fab")
		)
		(pad "1" smd rect
			(at 0 0 270)
			(size 0.508 0.508)
			(layers "F.Cu" "F.Mask" "F.Paste")
			(net "VR_PVDDQ_KLM_PH2_OCSET")
		)
		(pad "2" smd rect
			(at 0 0.889 270)
			(size 0.508 0.508)
			(layers "F.Cu" "F.Mask" "F.Paste")
			(net "GND")
		)
		(zone
			(layer "F.Cu")
			(hatch none 0.5)
			(connect_pads
				(clearance 0)
			)
			(min_thickness 0.25)
			(keepout
				(tracks not_allowed)
				(vias allowed)
				(pads allowed)
				(copperpour not_allowed)
				(footprints allowed)
			)
			(placement
				(enabled no)
				(sheetname "")
			)
			(fill
				(thermal_gap 0.5)
				(thermal_bridge_width 0.5)
				(island_removal_mode 0)
			)
			(polygon
				(pts
					(xy -3.81 -145.1102) (xy -3.81 -144.6022) (xy -3.429 -144.6022) (xy -3.429 -145.1102)
				)
			)
		)
		(zone
			(layer "F.Cu")
			(hatch none 0.5)
			(connect_pads
				(clearance 0)
			)
			(min_thickness 0.25)
			(keepout
				(tracks allowed)
				(vias not_allowed)
				(pads allowed)
				(copperpour not_allowed)
				(footprints allowed)
			)
			(placement
				(enabled no)
				(sheetname "")
			)
			(fill
				(thermal_gap 0.5)
				(thermal_bridge_width 0.5)
				(island_removal_mode 0)
			)
			(polygon
				(pts
					(xy -3.429 -145.1102) (xy -3.429 -144.6022) (xy -3.81 -144.6022) (xy -3.81 -145.1102)
				)
			)
		)
	)
	(footprint ""
		(layer "F.Cu")
		(at 168.07942 -73.662032 180)
		(property "Reference" "R4W5"
			(at -0.8382 -0.67818 180)
			(unlocked yes)
			(layer "F.SilkS")
			(effects
				(font
					(size 0.4064 0.254)
					(thickness 0.1524)
				)
				(justify left)
			)
		)
		(property "Value" ""
			(at 0 0 180)
			(layer "F.Fab")
			(effects
				(font
					(size 1.27 1.27)
				)
			)
		)
		(duplicate_pad_numbers_are_jumpers no)
		(fp_poly
			(pts
				(xy -0.2794 -0.1016) (xy 0.2794 -0.1016) (xy 0.2794 0.9906) (xy -0.2794 0.9906)
			)
			(stroke
				(width 0)
				(type default)
			)
			(fill no)
			(layer "F.CrtYd")
		)
		(fp_line
			(start 0.2794 0.9906)
			(end 0.2794 -0.1016)
			(stroke
				(width 0.1)
				(type default)
			)
			(layer "F.Fab")
		)
		(fp_line
			(start 0.2794 -0.1016)
			(end -0.2794 -0.1016)
			(stroke
				(width 0.1)
				(type default)
			)
			(layer "F.Fab")
		)
		(fp_line
			(start -0.2794 0.9906)
			(end 0.2794 0.9906)
			(stroke
				(width 0.1)
				(type default)
			)
			(layer "F.Fab")
		)
		(fp_line
			(start -0.2794 -0.1016)
			(end -0.2794 0.9906)
			(stroke
				(width 0.1)
				(type default)
			)
			(layer "F.Fab")
		)
		(pad "1" smd rect
			(at 0 0 180)
			(size 0.508 0.508)
			(layers "F.Cu" "F.Mask" "F.Paste")
			(net "FM_DB1200_PWRGD")
		)
		(pad "2" smd rect
			(at 0 0.889 180)
			(size 0.508 0.508)
			(layers "F.Cu" "F.Mask" "F.Paste")
			(net "FM_DB1200_PWRGD_R")
		)
		(zone
			(layer "F.Cu")
			(hatch none 0.5)
			(connect_pads
				(clearance 0)
			)
			(min_thickness 0.25)
			(keepout
				(tracks not_allowed)
				(vias allowed)
				(pads allowed)
				(copperpour not_allowed)
				(footprints allowed)
			)
			(placement
				(enabled no)
				(sheetname "")
			)
			(fill
				(thermal_gap 0.5)
				(thermal_bridge_width 0.5)
				(island_removal_mode 0)
			)
			(polygon
				(pts
					(xy 168.33342 -74.297032) (xy 167.82542 -74.297032) (xy 167.82542 -73.916032) (xy 168.33342 -73.916032)
				)
			)
		)
		(zone
			(layer "F.Cu")
			(hatch none 0.5)
			(connect_pads
				(clearance 0)
			)
			(min_thickness 0.25)
			(keepout
				(tracks allowed)
				(vias not_allowed)
				(pads allowed)
				(copperpour not_allowed)
				(footprints allowed)
			)
			(placement
				(enabled no)
				(sheetname "")
			)
			(fill
				(thermal_gap 0.5)
				(thermal_bridge_width 0.5)
				(island_removal_mode 0)
			)
			(polygon
				(pts
					(xy 168.33342 -73.916032) (xy 167.82542 -73.916032) (xy 167.82542 -74.297032) (xy 168.33342 -74.297032)
				)
			)
		)
	)
	(footprint ""
		(layer "F.Cu")
		(at 194.749928 -92.210382 -90)
		(property "Reference" "C4C18"
			(at 0 0 270)
			(layer "F.SilkS")
			(hide yes)
			(effects
				(font
					(size 1.27 1.27)
				)
			)
		)
		(property "Value" ""
			(at 0 0 270)
			(layer "F.Fab")
			(effects
				(font
					(size 1.27 1.27)
				)
			)
		)
		(duplicate_pad_numbers_are_jumpers no)
		(fp_poly
			(pts
				(xy 0.3048 -0.1016) (xy 0.3048 0.9906) (xy -0.3048 0.9906) (xy -0.3048 -0.1016)
			)
			(stroke
				(width 0)
				(type default)
			)
			(fill no)
			(layer "F.CrtYd")
		)
		(fp_line
			(start -0.3048 0.9906)
			(end 0.3048 0.9906)
			(stroke
				(width 0.1)
				(type default)
			)
			(layer "F.Fab")
		)
		(fp_line
			(start 0.3048 0.9906)
			(end 0.3048 -0.1016)
			(stroke
				(width 0.1)
				(type default)
			)
			(layer "F.Fab")
		)
		(fp_line
			(start -0.3048 -0.1016)
			(end -0.3048 0.9906)
			(stroke
				(width 0.1)
				(type default)
			)
			(layer "F.Fab")
		)
		(fp_line
			(start 0.3048 -0.1016)
			(end -0.3048 -0.1016)
			(stroke
				(width 0.1)
				(type default)
			)
			(layer "F.Fab")
		)
		(pad "1" smd rect
			(at 0 0 270)
			(size 0.508 0.508)
			(layers "F.Cu" "F.Mask" "F.Paste")
			(net "VR_FET_SW_P12V_STBY_PVCCIN_CPU0")
		)
		(pad "2" smd rect
			(at 0 0.889 270)
			(size 0.508 0.508)
			(layers "F.Cu" "F.Mask" "F.Paste")
			(net "GND")
		)
		(zone
			(layer "F.Cu")
			(hatch none 0.5)
			(connect_pads
				(clearance 0)
			)
			(min_thickness 0.25)
			(keepout
				(tracks not_allowed)
				(vias allowed)
				(pads allowed)
				(copperpour not_allowed)
				(footprints allowed)
			)
			(placement
				(enabled no)
				(sheetname "")
			)
			(fill
				(thermal_gap 0.5)
				(thermal_bridge_width 0.5)
				(island_removal_mode 0)
			)
			(polygon
				(pts
					(xy 194.114928 -92.464382) (xy 194.114928 -91.956382) (xy 194.495928 -91.956382) (xy 194.495928 -92.464382)
				)
			)
		)
		(zone
			(layer "F.Cu")
			(hatch none 0.5)
			(connect_pads
				(clearance 0)
			)
			(min_thickness 0.25)
			(keepout
				(tracks allowed)
				(vias not_allowed)
				(pads allowed)
				(copperpour not_allowed)
				(footprints allowed)
			)
			(placement
				(enabled no)
				(sheetname "")
			)
			(fill
				(thermal_gap 0.5)
				(thermal_bridge_width 0.5)
				(island_removal_mode 0)
			)
			(polygon
				(pts
					(xy 194.495928 -92.464382) (xy 194.495928 -91.956382) (xy 194.114928 -91.956382) (xy 194.114928 -92.464382)
				)
			)
		)
	)
	(footprint ""
		(layer "F.Cu")
		(at 357.000048 -155.10002 90)
		(property "Reference" "TH7A1"
			(at -4.27609 8.277352 0)
			(unlocked yes)
			(layer "F.SilkS")
			(effects
				(font
					(size 0.7874 0.5842)
					(thickness 0.1524)
				)
				(justify left)
			)
		)
		(property "Value" ""
			(at 0 0 90)
			(layer "F.Fab")
			(effects
				(font
					(size 1.27 1.27)
				)
			)
		)
		(duplicate_pad_numbers_are_jumpers no)
		(fp_poly
			(pts
				(arc
					(start 3.0226 0.68834)
					(mid 3.042235 0.827855)
					(end 3.099562 0.956564)
				)
				(arc
					(start 3.099562 0.956564)
					(mid 4.012804 3.550073)
					(end 3.042158 6.12267)
				)
				(arc
					(start 3.042158 6.12267)
					(mid 0 7.518589)
					(end -3.042158 6.12267)
				)
				(arc
					(start -3.042158 6.12267)
					(mid -4.012854 3.55061)
					(end -3.100324 0.957326)
				)
				(arc
					(start -3.100324 0.957326)
					(mid -3.042498 0.827518)
					(end -3.0226 0.686816)
				)
				(arc
					(start -3.0226 -0.000254)
					(mid -2.137121 -2.137227)
					(end 0 -3.022346)
				)
				(arc
					(start 0 -3.022346)
					(mid 2.137227 -2.136973)
					(end 3.0226 0.000254)
				)
			)
			(stroke
				(width 0)
				(type default)
			)
			(fill no)
			(layer "F.CrtYd")
		)
		(pad "1" thru_hole custom
			(at 0 0 90)
			(size 2.00667 2.00667)
			(drill 0.3048)
			(layers "*.Cu" "*.Mask")
			(remove_unused_layers no)
			(net "GND")
			(clearance -0.889)
			(options
				(clearance outline)
				(anchor circle)
			)
			(primitives
				(gr_poly
					(pts
						(arc
							(start 3.042158 3.874516)
							(mid 0 5.270435)
							(end -3.042158 3.874516)
						)
						(arc
							(start -3.042158 3.874516)
							(mid -4.012854 1.302456)
							(end -3.100324 -1.290828)
						)
						(arc
							(start -3.100324 -1.290828)
							(mid -3.042498 -1.420636)
							(end -3.0226 -1.561338)
						)
						(arc
							(start -3.0226 -2.248408)
							(mid -2.137121 -4.385381)
							(end 0 -5.2705)
						)
						(arc
							(start 0 -5.2705)
							(mid 2.137227 -4.385127)
							(end 3.0226 -2.2479)
						)
						(arc
							(start 3.0226 -1.55956)
							(mid 3.04227 -1.420177)
							(end 3.099562 -1.29159)
						)
						(arc
							(start 3.099562 -1.29159)
							(mid 4.012804 1.301919)
							(end 3.042158 3.874516)
						)
					)
					(width 0)
					(fill yes)
				)
			)
		)
	)
	(footprint ""
		(layer "F.Cu")
		(at 271.9832 -79.6036 180)
		(property "Reference" "C5W2"
			(at 0.97536 0.76708 90)
			(unlocked yes)
			(layer "F.SilkS")
			(effects
				(font
					(size 0.4064 0.254)
					(thickness 0.1524)
				)
			)
		)
		(property "Value" ""
			(at 0 0 180)
			(layer "F.Fab")
			(effects
				(font
					(size 1.27 1.27)
				)
			)
		)
		(duplicate_pad_numbers_are_jumpers no)
		(fp_poly
			(pts
				(xy -0.4953 -0.2032) (xy 0.4953 -0.2032) (xy 0.4953 1.6002) (xy -0.4953 1.6002)
			)
			(stroke
				(width 0)
				(type default)
			)
			(fill no)
			(layer "F.CrtYd")
		)
		(fp_line
			(start 0.4953 1.6002)
			(end -0.4953 1.6002)
			(stroke
				(width 0.1)
				(type default)
			)
			(layer "F.Fab")
		)
		(fp_line
			(start 0.4953 -0.2032)
			(end 0.4953 1.6002)
			(stroke
				(width 0.1)
				(type default)
			)
			(layer "F.Fab")
		)
		(fp_line
			(start -0.4953 1.6002)
			(end -0.4953 -0.2032)
			(stroke
				(width 0.1)
				(type default)
			)
			(layer "F.Fab")
		)
		(fp_line
			(start -0.4953 -0.2032)
			(end 0.4953 -0.2032)
			(stroke
				(width 0.1)
				(type default)
			)
			(layer "F.Fab")
		)
		(pad "1" smd rect
			(at 0 0 180)
			(size 0.762 0.889)
			(layers "F.Cu" "F.Mask" "F.Paste")
			(net "PVCCMCP_CPU0")
		)
		(pad "2" smd rect
			(at 0 1.397 180)
			(size 0.762 0.889)
			(layers "F.Cu" "F.Mask" "F.Paste")
			(net "GND")
		)
		(zone
			(layer "F.Cu")
			(hatch none 0.5)
			(connect_pads
				(clearance 0)
			)
			(min_thickness 0.25)
			(keepout
				(tracks not_allowed)
				(vias allowed)
				(pads allowed)
				(copperpour not_allowed)
				(footprints allowed)
			)
			(placement
				(enabled no)
				(sheetname "")
			)
			(fill
				(thermal_gap 0.5)
				(thermal_bridge_width 0.5)
				(island_removal_mode 0)
			)
			(polygon
				(pts
					(xy 272.3642 -80.0481) (xy 271.6022 -80.0481) (xy 271.6022 -80.5561) (xy 272.3642 -80.5561)
				)
			)
		)
	)
	(footprint ""
		(layer "F.Cu")
		(at -0.342138 -6.936486)
		(property "Reference" "R1G26"
			(at 0 0 0)
			(layer "F.SilkS")
			(hide yes)
			(effects
				(font
					(size 1.27 1.27)
				)
			)
		)
		(property "Value" ""
			(at 0 0 0)
			(layer "F.Fab")
			(effects
				(font
					(size 1.27 1.27)
				)
			)
		)
		(duplicate_pad_numbers_are_jumpers no)
		(fp_poly
			(pts
				(xy -0.2794 -0.1016) (xy 0.2794 -0.1016) (xy 0.2794 0.9906) (xy -0.2794 0.9906)
			)
			(stroke
				(width 0)
				(type default)
			)
			(fill no)
			(layer "F.CrtYd")
		)
		(fp_line
			(start -0.2794 -0.1016)
			(end -0.2794 0.9906)
			(stroke
				(width 0.1)
				(type default)
			)
			(layer "F.Fab")
		)
		(fp_line
			(start -0.2794 0.9906)
			(end 0.2794 0.9906)
			(stroke
				(width 0.1)
				(type default)
			)
			(layer "F.Fab")
		)
		(fp_line
			(start 0.2794 -0.1016)
			(end -0.2794 -0.1016)
			(stroke
				(width 0.1)
				(type default)
			)
			(layer "F.Fab")
		)
		(fp_line
			(start 0.2794 0.9906)
			(end 0.2794 -0.1016)
			(stroke
				(width 0.1)
				(type default)
			)
			(layer "F.Fab")
		)
		(pad "1" smd rect
			(at 0 0)
			(size 0.508 0.508)
			(layers "F.Cu" "F.Mask" "F.Paste")
			(net "VR_PVDDQ_GHJ_PH1_OCSET")
		)
		(pad "2" smd rect
			(at 0 0.889)
			(size 0.508 0.508)
			(layers "F.Cu" "F.Mask" "F.Paste")
			(net "GND")
		)
		(zone
			(layer "F.Cu")
			(hatch none 0.5)
			(connect_pads
				(clearance 0)
			)
			(min_thickness 0.25)
			(keepout
				(tracks allowed)
				(vias not_allowed)
				(pads allowed)
				(copperpour not_allowed)
				(footprints allowed)
			)
			(placement
				(enabled no)
				(sheetname "")
			)
			(fill
				(thermal_gap 0.5)
				(thermal_bridge_width 0.5)
				(island_removal_mode 0)
			)
			(polygon
				(pts
					(xy -0.596138 -6.682486) (xy -0.088138 -6.682486) (xy -0.088138 -6.301486) (xy -0.596138 -6.301486)
				)
			)
		)
		(zone
			(layer "F.Cu")
			(hatch none 0.5)
			(connect_pads
				(clearance 0)
			)
			(min_thickness 0.25)
			(keepout
				(tracks not_allowed)
				(vias allowed)
				(pads allowed)
				(copperpour not_allowed)
				(footprints allowed)
			)
			(placement
				(enabled no)
				(sheetname "")
			)
			(fill
				(thermal_gap 0.5)
				(thermal_bridge_width 0.5)
				(island_removal_mode 0)
			)
			(polygon
				(pts
					(xy -0.596138 -6.301486) (xy -0.088138 -6.301486) (xy -0.088138 -6.682486) (xy -0.596138 -6.682486)
				)
			)
		)
	)
	(footprint ""
		(layer "F.Cu")
		(at 489.3945 -144.638268 90)
		(property "Reference" "R1L24"
			(at 0 0 90)
			(layer "F.SilkS")
			(hide yes)
			(effects
				(font
					(size 1.27 1.27)
				)
			)
		)
		(property "Value" ""
			(at 0 0 90)
			(layer "F.Fab")
			(effects
				(font
					(size 1.27 1.27)
				)
			)
		)
		(duplicate_pad_numbers_are_jumpers no)
		(fp_poly
			(pts
				(xy -0.2794 -0.1016) (xy 0.2794 -0.1016) (xy 0.2794 0.9906) (xy -0.2794 0.9906)
			)
			(stroke
				(width 0)
				(type default)
			)
			(fill no)
			(layer "F.CrtYd")
		)
		(fp_line
			(start 0.2794 -0.1016)
			(end -0.2794 -0.1016)
			(stroke
				(width 0.1)
				(type default)
			)
			(layer "F.Fab")
		)
		(fp_line
			(start -0.2794 -0.1016)
			(end -0.2794 0.9906)
			(stroke
				(width 0.1)
				(type default)
			)
			(layer "F.Fab")
		)
		(fp_line
			(start 0.2794 0.9906)
			(end 0.2794 -0.1016)
			(stroke
				(width 0.1)
				(type default)
			)
			(layer "F.Fab")
		)
		(fp_line
			(start -0.2794 0.9906)
			(end 0.2794 0.9906)
			(stroke
				(width 0.1)
				(type default)
			)
			(layer "F.Fab")
		)
		(pad "1" smd rect
			(at 0 0 90)
			(size 0.508 0.508)
			(layers "F.Cu" "F.Mask" "F.Paste")
			(net "LED_POSTCODE_3")
		)
		(pad "2" smd rect
			(at 0 0.889 90)
			(size 0.508 0.508)
			(layers "F.Cu" "F.Mask" "F.Paste")
			(net "LED_POSTCODE_3_R")
		)
		(zone
			(layer "F.Cu")
			(hatch none 0.5)
			(connect_pads
				(clearance 0)
			)
			(min_thickness 0.25)
			(keepout
				(tracks allowed)
				(vias not_allowed)
				(pads allowed)
				(copperpour not_allowed)
				(footprints allowed)
			)
			(placement
				(enabled no)
				(sheetname "")
			)
			(fill
				(thermal_gap 0.5)
				(thermal_bridge_width 0.5)
				(island_removal_mode 0)
			)
			(polygon
				(pts
					(xy 489.6485 -144.384268) (xy 489.6485 -144.892268) (xy 490.0295 -144.892268) (xy 490.0295 -144.384268)
				)
			)
		)
		(zone
			(layer "F.Cu")
			(hatch none 0.5)
			(connect_pads
				(clearance 0)
			)
			(min_thickness 0.25)
			(keepout
				(tracks not_allowed)
				(vias allowed)
				(pads allowed)
				(copperpour not_allowed)
				(footprints allowed)
			)
			(placement
				(enabled no)
				(sheetname "")
			)
			(fill
				(thermal_gap 0.5)
				(thermal_bridge_width 0.5)
				(island_removal_mode 0)
			)
			(polygon
				(pts
					(xy 490.0295 -144.384268) (xy 490.0295 -144.892268) (xy 489.6485 -144.892268) (xy 489.6485 -144.384268)
				)
			)
		)
	)
	(footprint ""
		(layer "F.Cu")
		(at 496.581684 -19.373088 90)
		(property "Reference" "C7E8"
			(at 0 0 90)
			(layer "F.SilkS")
			(hide yes)
			(effects
				(font
					(size 1.27 1.27)
				)
			)
		)
		(property "Value" ""
			(at 0 0 90)
			(layer "F.Fab")
			(effects
				(font
					(size 1.27 1.27)
				)
			)
		)
		(duplicate_pad_numbers_are_jumpers no)
		(fp_rect
			(start -0.7239 1.9939)
			(end 0.7239 -0.2159)
			(stroke
				(width 0)
				(type default)
			)
			(fill no)
			(layer "F.CrtYd")
		)
		(fp_line
			(start 0.7239 -0.2159)
			(end -0.7239 -0.2159)
			(stroke
				(width 0.1)
				(type default)
			)
			(layer "F.Fab")
		)
		(fp_line
			(start -0.7239 -0.2159)
			(end -0.7239 1.9939)
			(stroke
				(width 0.1)
				(type default)
			)
			(layer "F.Fab")
		)
		(fp_line
			(start 0.7239 1.9939)
			(end 0.7239 -0.2159)
			(stroke
				(width 0.1)
				(type default)
			)
			(layer "F.Fab")
		)
		(fp_line
			(start -0.7239 1.9939)
			(end 0.7239 1.9939)
			(stroke
				(width 0.1)
				(type default)
			)
			(layer "F.Fab")
		)
		(pad "1" smd rect
			(at 0 0 90)
			(size 1.27 1.016)
			(layers "F.Cu" "F.Mask" "F.Paste")
			(net "P12V")
		)
		(pad "2" smd rect
			(at 0 1.778 90)
			(size 1.27 1.016)
			(layers "F.Cu" "F.Mask" "F.Paste")
			(net "GND")
		)
		(zone
			(layer "F.Cu")
			(hatch none 0.5)
			(connect_pads
				(clearance 0)
			)
			(min_thickness 0.25)
			(keepout
				(tracks not_allowed)
				(vias allowed)
				(pads allowed)
				(copperpour not_allowed)
				(footprints allowed)
			)
			(placement
				(enabled no)
				(sheetname "")
			)
			(fill
				(thermal_gap 0.5)
				(thermal_bridge_width 0.5)
				(island_removal_mode 0)
			)
			(polygon
				(pts
					(xy 497.851684 -18.738088) (xy 497.851684 -20.008088) (xy 497.089684 -20.008088) (xy 497.089684 -18.738088)
				)
			)
		)
	)
	(footprint ""
		(layer "F.Cu")
		(at 16.383 -97.8916 -90)
		(property "Reference" "C1C9"
			(at 0 0 270)
			(layer "F.SilkS")
			(hide yes)
			(effects
				(font
					(size 1.27 1.27)
				)
			)
		)
		(property "Value" ""
			(at 0 0 270)
			(layer "F.Fab")
			(effects
				(font
					(size 1.27 1.27)
				)
			)
		)
		(duplicate_pad_numbers_are_jumpers no)
		(fp_rect
			(start 0.3048 0.9906)
			(end -0.3048 -0.1016)
			(stroke
				(width 0)
				(type default)
			)
			(fill no)
			(layer "F.CrtYd")
		)
		(fp_line
			(start -0.3048 0.9906)
			(end 0.3048 0.9906)
			(stroke
				(width 0.1)
				(type default)
			)
			(layer "F.Fab")
		)
		(fp_line
			(start 0.3048 0.9906)
			(end 0.3048 -0.1016)
			(stroke
				(width 0.1)
				(type default)
			)
			(layer "F.Fab")
		)
		(fp_line
			(start -0.3048 -0.1016)
			(end -0.3048 0.9906)
			(stroke
				(width 0.1)
				(type default)
			)
			(layer "F.Fab")
		)
		(fp_line
			(start 0.3048 -0.1016)
			(end -0.3048 -0.1016)
			(stroke
				(width 0.1)
				(type default)
			)
			(layer "F.Fab")
		)
		(pad "1" smd rect
			(at 0 0 270)
			(size 0.508 0.508)
			(layers "F.Cu" "F.Mask" "F.Paste")
			(net "VR_PVCCIN_CPU1_VDD")
		)
		(pad "2" smd rect
			(at 0 0.889 270)
			(size 0.508 0.508)
			(layers "F.Cu" "F.Mask" "F.Paste")
			(net "GND")
		)
		(zone
			(layer "F.Cu")
			(hatch none 0.5)
			(connect_pads
				(clearance 0)
			)
			(min_thickness 0.25)
			(keepout
				(tracks not_allowed)
				(vias allowed)
				(pads allowed)
				(copperpour not_allowed)
				(footprints allowed)
			)
			(placement
				(enabled no)
				(sheetname "")
			)
			(fill
				(thermal_gap 0.5)
				(thermal_bridge_width 0.5)
				(island_removal_mode 0)
			)
			(polygon
				(pts
					(xy 15.748 -97.6376) (xy 16.129 -97.6376) (xy 16.129 -98.1456) (xy 15.748 -98.1456)
				)
			)
		)
		(zone
			(layer "F.Cu")
			(hatch none 0.5)
			(connect_pads
				(clearance 0)
			)
			(min_thickness 0.25)
			(keepout
				(tracks allowed)
				(vias not_allowed)
				(pads allowed)
				(copperpour not_allowed)
				(footprints allowed)
			)
			(placement
				(enabled no)
				(sheetname "")
			)
			(fill
				(thermal_gap 0.5)
				(thermal_bridge_width 0.5)
				(island_removal_mode 0)
			)
			(polygon
				(pts
					(xy 15.748 -97.6376) (xy 16.129 -97.6376) (xy 16.129 -98.1456) (xy 15.748 -98.1456)
				)
			)
		)
	)
	(footprint ""
		(layer "F.Cu")
		(at 499.872 -155.321)
		(property "Reference" "DS9A1"
			(at -0.49276 -1.47447 0)
			(unlocked yes)
			(layer "F.SilkS")
			(effects
				(font
					(size 0.7874 0.5842)
					(thickness 0.1524)
				)
			)
		)
		(property "Value" ""
			(at 0 0 0)
			(layer "F.Fab")
			(effects
				(font
					(size 1.27 1.27)
				)
			)
		)
		(duplicate_pad_numbers_are_jumpers no)
		(fp_line
			(start -1.728978 -0.9525)
			(end -1.248156 -1.785366)
			(stroke
				(width 0.1524)
				(type default)
			)
			(layer "F.SilkS")
		)
		(fp_line
			(start -1.248156 -2.908808)
			(end -1.248156 -1.785366)
			(stroke
				(width 0.1524)
				(type default)
			)
			(layer "F.SilkS")
		)
		(fp_line
			(start -1.248156 -1.785366)
			(end -0.767334 -0.9525)
			(stroke
				(width 0.1524)
				(type default)
			)
			(layer "F.SilkS")
		)
		(fp_line
			(start -1.248156 -0.9525)
			(end -1.728978 -0.9525)
			(stroke
				(width 0.1524)
				(type default)
			)
			(layer "F.SilkS")
		)
		(fp_line
			(start -1.248156 -0.040894)
			(end -1.248156 -0.9525)
			(stroke
				(width 0.1524)
				(type default)
			)
			(layer "F.SilkS")
		)
		(fp_line
			(start -0.767334 -1.785366)
			(end -1.728978 -1.785366)
			(stroke
				(width 0.1524)
				(type default)
			)
			(layer "F.SilkS")
		)
		(fp_line
			(start -0.767334 -0.9525)
			(end -1.248156 -0.9525)
			(stroke
				(width 0.1524)
				(type default)
			)
			(layer "F.SilkS")
		)
		(fp_poly
			(pts
				(xy -0.5715 2.2098) (xy -0.5715 0.2032) (xy 0.5715 0.2032) (xy 0.5715 0.6985)
				(arc
					(start 0.726948 0.6985)
					(mid 1.29058 0.932279)
					(end 1.524 1.49606)
				)
				(arc
					(start 1.524 2.05994)
					(mid 1.2904 2.6239)
					(end 0.72644 2.8575)
				)
				(xy 0.5715 2.8575) (xy 0.5715 3.3528) (xy -0.5715 3.3528)
			)
			(stroke
				(width 0)
				(type default)
			)
			(fill no)
			(layer "F.CrtYd")
		)
		(fp_line
			(start -1.720088 -0.958342)
			(end -1.239266 -1.791208)
			(stroke
				(width 0.1)
				(type default)
			)
			(layer "F.Fab")
		)
		(fp_line
			(start -1.239266 -1.791208)
			(end -1.239266 -2.91465)
			(stroke
				(width 0.1)
				(type default)
			)
			(layer "F.Fab")
		)
		(fp_line
			(start -1.239266 -1.791208)
			(end -0.758444 -0.958342)
			(stroke
				(width 0.1)
				(type default)
			)
			(layer "F.Fab")
		)
		(fp_line
			(start -1.239266 -0.958342)
			(end -1.239266 -0.046736)
			(stroke
				(width 0.1)
				(type default)
			)
			(layer "F.Fab")
		)
		(fp_line
			(start -0.758444 -1.791208)
			(end -1.720088 -1.791208)
			(stroke
				(width 0.1)
				(type default)
			)
			(layer "F.Fab")
		)
		(fp_line
			(start -0.758444 -0.958342)
			(end -1.720088 -0.958342)
			(stroke
				(width 0.1)
				(type default)
			)
			(layer "F.Fab")
		)
		(fp_line
			(start -0.5715 0.2032)
			(end 0.5715 0.2032)
			(stroke
				(width 0.1)
				(type default)
			)
			(layer "F.Fab")
		)
		(fp_line
			(start -0.5715 0.7112)
			(end 0.5715 0.7112)
			(stroke
				(width 0.1)
				(type default)
			)
			(layer "F.Fab")
		)
		(fp_line
			(start -0.5715 2.8448)
			(end 0.5715 2.8448)
			(stroke
				(width 0.1)
				(type default)
			)
			(layer "F.Fab")
		)
		(fp_line
			(start -0.5715 3.3528)
			(end -0.5715 0.2032)
			(stroke
				(width 0.1)
				(type default)
			)
			(layer "F.Fab")
		)
		(fp_line
			(start 0.5715 0.2032)
			(end 0.5715 3.3528)
			(stroke
				(width 0.1)
				(type default)
			)
			(layer "F.Fab")
		)
		(fp_line
			(start 0.5715 2.8575)
			(end 0.72644 2.8575)
			(stroke
				(width 0.1)
				(type default)
			)
			(layer "F.Fab")
		)
		(fp_line
			(start 0.5715 3.3528)
			(end -0.5715 3.3528)
			(stroke
				(width 0.1)
				(type default)
			)
			(layer "F.Fab")
		)
		(fp_line
			(start 0.72644 0.6985)
			(end 0.5715 0.6985)
			(stroke
				(width 0.1)
				(type default)
			)
			(layer "F.Fab")
		)
		(fp_line
			(start 1.524 2.05994)
			(end 1.524 1.49606)
			(stroke
				(width 0.1)
				(type default)
			)
			(layer "F.Fab")
		)
		(fp_arc
			(start 0.72644 0.6985)
			(mid 1.290388 0.932112)
			(end 1.524 1.49606)
			(stroke
				(width 0.1)
				(type default)
			)
			(layer "F.Fab")
		)
		(fp_arc
			(start 1.524 2.05994)
			(mid 1.290388 2.623888)
			(end 0.72644 2.8575)
			(stroke
				(width 0.1)
				(type default)
			)
			(layer "F.Fab")
		)
		(pad "1" smd rect
			(at 0 0)
			(size 1.524 1.524)
			(layers "F.Cu" "F.Mask" "F.Paste")
			(net "FP_ID_LED_P5V_STBY_N")
		)
		(pad "2" smd rect
			(at 0 3.556)
			(size 1.524 1.524)
			(layers "F.Cu" "F.Mask" "F.Paste")
			(net "FP_ID_LED_XOR_R")
		)
		(pad "3" smd rect
			(at -0.762 1.778)
			(size 0.889 0.889)
			(layers "F.Cu" "F.Mask" "F.Paste")
			(net "Net_6474")
		)
		(zone
			(layer "F.Cu")
			(hatch none 0.5)
			(connect_pads
				(clearance 0)
			)
			(min_thickness 0.25)
			(keepout
				(tracks allowed)
				(vias not_allowed)
				(pads allowed)
				(copperpour not_allowed)
				(footprints allowed)
			)
			(placement
				(enabled no)
				(sheetname "")
			)
			(fill
				(thermal_gap 0.5)
				(thermal_bridge_width 0.5)
				(island_removal_mode 0)
			)
			(polygon
				(pts
					(xy 500.4435 -154.5082) (xy 500.4435 -152.5778) (xy 499.3005 -152.5778) (xy 499.3005 -154.5082)
				)
			)
		)
	)
	(footprint ""
		(layer "F.Cu")
		(at 359.876598 -10.916158)
		(property "Reference" "R8W14"
			(at -0.8382 -0.67818 0)
			(unlocked yes)
			(layer "F.SilkS")
			(effects
				(font
					(size 0.4064 0.254)
					(thickness 0.1524)
				)
				(justify left)
			)
		)
		(property "Value" ""
			(at 0 0 0)
			(layer "F.Fab")
			(effects
				(font
					(size 1.27 1.27)
				)
			)
		)
		(duplicate_pad_numbers_are_jumpers no)
		(fp_poly
			(pts
				(xy -0.2794 -0.1016) (xy 0.2794 -0.1016) (xy 0.2794 0.9906) (xy -0.2794 0.9906)
			)
			(stroke
				(width 0)
				(type default)
			)
			(fill no)
			(layer "F.CrtYd")
		)
		(fp_line
			(start -0.2794 -0.1016)
			(end -0.2794 0.9906)
			(stroke
				(width 0.1)
				(type default)
			)
			(layer "F.Fab")
		)
		(fp_line
			(start -0.2794 0.9906)
			(end 0.2794 0.9906)
			(stroke
				(width 0.1)
				(type default)
			)
			(layer "F.Fab")
		)
		(fp_line
			(start 0.2794 -0.1016)
			(end -0.2794 -0.1016)
			(stroke
				(width 0.1)
				(type default)
			)
			(layer "F.Fab")
		)
		(fp_line
			(start 0.2794 0.9906)
			(end 0.2794 -0.1016)
			(stroke
				(width 0.1)
				(type default)
			)
			(layer "F.Fab")
		)
		(pad "1" smd rect
			(at 0 0)
			(size 0.508 0.508)
			(layers "F.Cu" "F.Mask" "F.Paste")
			(net "JTAG_RISER_TDO_R")
		)
		(pad "2" smd rect
			(at 0 0.889)
			(size 0.508 0.508)
			(layers "F.Cu" "F.Mask" "F.Paste")
			(net "JTAG_RISER_TDO")
		)
		(zone
			(layer "F.Cu")
			(hatch none 0.5)
			(connect_pads
				(clearance 0)
			)
			(min_thickness 0.25)
			(keepout
				(tracks allowed)
				(vias not_allowed)
				(pads allowed)
				(copperpour not_allowed)
				(footprints allowed)
			)
			(placement
				(enabled no)
				(sheetname "")
			)
			(fill
				(thermal_gap 0.5)
				(thermal_bridge_width 0.5)
				(island_removal_mode 0)
			)
			(polygon
				(pts
					(xy 359.622598 -10.662158) (xy 360.130598 -10.662158) (xy 360.130598 -10.281158) (xy 359.622598 -10.281158)
				)
			)
		)
		(zone
			(layer "F.Cu")
			(hatch none 0.5)
			(connect_pads
				(clearance 0)
			)
			(min_thickness 0.25)
			(keepout
				(tracks not_allowed)
				(vias allowed)
				(pads allowed)
				(copperpour not_allowed)
				(footprints allowed)
			)
			(placement
				(enabled no)
				(sheetname "")
			)
			(fill
				(thermal_gap 0.5)
				(thermal_bridge_width 0.5)
				(island_removal_mode 0)
			)
			(polygon
				(pts
					(xy 359.622598 -10.281158) (xy 360.130598 -10.281158) (xy 360.130598 -10.662158) (xy 359.622598 -10.662158)
				)
			)
		)
	)
	(footprint ""
		(layer "F.Cu")
		(at 169.0878 -74.93 90)
		(property "Reference" "C4D22"
			(at 0 0 90)
			(layer "F.SilkS")
			(hide yes)
			(effects
				(font
					(size 1.27 1.27)
				)
			)
		)
		(property "Value" ""
			(at 0 0 90)
			(layer "F.Fab")
			(effects
				(font
					(size 1.27 1.27)
				)
			)
		)
		(duplicate_pad_numbers_are_jumpers no)
		(fp_poly
			(pts
				(xy 0.3048 -0.1016) (xy 0.3048 0.9906) (xy -0.3048 0.9906) (xy -0.3048 -0.1016)
			)
			(stroke
				(width 0)
				(type default)
			)
			(fill no)
			(layer "F.CrtYd")
		)
		(fp_line
			(start 0.3048 -0.1016)
			(end -0.3048 -0.1016)
			(stroke
				(width 0.1)
				(type default)
			)
			(layer "F.Fab")
		)
		(fp_line
			(start -0.3048 -0.1016)
			(end -0.3048 0.9906)
			(stroke
				(width 0.1)
				(type default)
			)
			(layer "F.Fab")
		)
		(fp_line
			(start 0.3048 0.9906)
			(end 0.3048 -0.1016)
			(stroke
				(width 0.1)
				(type default)
			)
			(layer "F.Fab")
		)
		(fp_line
			(start -0.3048 0.9906)
			(end 0.3048 0.9906)
			(stroke
				(width 0.1)
				(type default)
			)
			(layer "F.Fab")
		)
		(pad "1" smd rect
			(at 0 0 90)
			(size 0.508 0.508)
			(layers "F.Cu" "F.Mask" "F.Paste")
			(net "P3V3_DB1200_R")
		)
		(pad "2" smd rect
			(at 0 0.889 90)
			(size 0.508 0.508)
			(layers "F.Cu" "F.Mask" "F.Paste")
			(net "GND")
		)
		(zone
			(layer "F.Cu")
			(hatch none 0.5)
			(connect_pads
				(clearance 0)
			)
			(min_thickness 0.25)
			(keepout
				(tracks allowed)
				(vias not_allowed)
				(pads allowed)
				(copperpour not_allowed)
				(footprints allowed)
			)
			(placement
				(enabled no)
				(sheetname "")
			)
			(fill
				(thermal_gap 0.5)
				(thermal_bridge_width 0.5)
				(island_removal_mode 0)
			)
			(polygon
				(pts
					(xy 169.3418 -74.676) (xy 169.3418 -75.184) (xy 169.7228 -75.184) (xy 169.7228 -74.676)
				)
			)
		)
		(zone
			(layer "F.Cu")
			(hatch none 0.5)
			(connect_pads
				(clearance 0)
			)
			(min_thickness 0.25)
			(keepout
				(tracks not_allowed)
				(vias allowed)
				(pads allowed)
				(copperpour not_allowed)
				(footprints allowed)
			)
			(placement
				(enabled no)
				(sheetname "")
			)
			(fill
				(thermal_gap 0.5)
				(thermal_bridge_width 0.5)
				(island_removal_mode 0)
			)
			(polygon
				(pts
					(xy 169.7228 -74.676) (xy 169.7228 -75.184) (xy 169.3418 -75.184) (xy 169.3418 -74.676)
				)
			)
		)
	)
	(footprint ""
		(layer "F.Cu")
		(at 24.728932 -61.0362 -90)
		(property "Reference" "R1E1"
			(at 0 0 270)
			(layer "F.SilkS")
			(hide yes)
			(effects
				(font
					(size 1.27 1.27)
				)
			)
		)
		(property "Value" ""
			(at 0 0 270)
			(layer "F.Fab")
			(effects
				(font
					(size 1.27 1.27)
				)
			)
		)
		(duplicate_pad_numbers_are_jumpers no)
		(fp_rect
			(start 0.2794 -0.1016)
			(end -0.2794 0.9906)
			(stroke
				(width 0)
				(type default)
			)
			(fill no)
			(layer "F.CrtYd")
		)
		(fp_line
			(start -0.2794 0.9906)
			(end 0.2794 0.9906)
			(stroke
				(width 0.1)
				(type default)
			)
			(layer "F.Fab")
		)
		(fp_line
			(start 0.2794 0.9906)
			(end 0.2794 -0.1016)
			(stroke
				(width 0.1)
				(type default)
			)
			(layer "F.Fab")
		)
		(fp_line
			(start -0.2794 -0.1016)
			(end -0.2794 0.9906)
			(stroke
				(width 0.1)
				(type default)
			)
			(layer "F.Fab")
		)
		(fp_line
			(start 0.2794 -0.1016)
			(end -0.2794 -0.1016)
			(stroke
				(width 0.1)
				(type default)
			)
			(layer "F.Fab")
		)
		(pad "1" smd rect
			(at 0 0 270)
			(size 0.508 0.508)
			(layers "F.Cu" "F.Mask" "F.Paste")
			(net "A_HSC_GATE")
		)
		(pad "2" smd rect
			(at 0 0.889 270)
			(size 0.508 0.508)
			(layers "F.Cu" "F.Mask" "F.Paste")
			(net "A_HSC_GATE1_R")
		)
		(zone
			(layer "F.Cu")
			(hatch none 0.5)
			(connect_pads
				(clearance 0)
			)
			(min_thickness 0.25)
			(keepout
				(tracks not_allowed)
				(vias allowed)
				(pads allowed)
				(copperpour not_allowed)
				(footprints allowed)
			)
			(placement
				(enabled no)
				(sheetname "")
			)
			(fill
				(thermal_gap 0.5)
				(thermal_bridge_width 0.5)
				(island_removal_mode 0)
			)
			(polygon
				(pts
					(xy 24.474932 -60.7822) (xy 24.474932 -61.2902) (xy 24.093932 -61.2902) (xy 24.093932 -60.7822)
				)
			)
		)
		(zone
			(layer "F.Cu")
			(hatch none 0.5)
			(connect_pads
				(clearance 0)
			)
			(min_thickness 0.25)
			(keepout
				(tracks allowed)
				(vias not_allowed)
				(pads allowed)
				(copperpour not_allowed)
				(footprints allowed)
			)
			(placement
				(enabled no)
				(sheetname "")
			)
			(fill
				(thermal_gap 0.5)
				(thermal_bridge_width 0.5)
				(island_removal_mode 0)
			)
			(polygon
				(pts
					(xy 24.474932 -60.7822) (xy 24.474932 -61.2902) (xy 24.093932 -61.2902) (xy 24.093932 -60.7822)
				)
			)
		)
	)
	(footprint ""
		(layer "F.Cu")
		(at 462.19491 -157.140402 180)
		(property "Reference" "J8D4"
			(at 0 0 180)
			(layer "F.SilkS")
			(hide yes)
			(effects
				(font
					(size 1.27 1.27)
				)
			)
		)
		(property "Value" "*"
			(at -5.103876 -0.820166 180)
			(unlocked yes)
			(layer "F.Fab")
			(hide yes)
			(effects
				(font
					(size 1.27 1.016)
					(thickness 0.1524)
				)
			)
		)
		(property "Device Type" "PIN-CON3-27-GP_CONN-G7-PIN-CONA"
			(at -5.103876 -2.344166 180)
			(unlocked yes)
			(layer "F.Fab")
			(hide yes)
			(effects
				(font
					(size 1.27 1.016)
					(thickness 0.1524)
				)
			)
		)
		(duplicate_pad_numbers_are_jumpers no)
		(fp_line
			(start 3.937 1.4986)
			(end -3.937 1.4986)
			(stroke
				(width 0.1524)
				(type default)
			)
			(layer "F.SilkS")
		)
		(fp_line
			(start 3.937 -1.4986)
			(end 3.937 1.4986)
			(stroke
				(width 0.1524)
				(type default)
			)
			(layer "F.SilkS")
		)
		(fp_line
			(start -2.794 -1.6256)
			(end -4.064 -1.6256)
			(stroke
				(width 0.4064)
				(type default)
			)
			(layer "F.SilkS")
		)
		(fp_line
			(start -3.937 1.4986)
			(end -3.937 -1.4986)
			(stroke
				(width 0.1524)
				(type default)
			)
			(layer "F.SilkS")
		)
		(fp_line
			(start -3.937 -1.4986)
			(end 3.937 -1.4986)
			(stroke
				(width 0.1524)
				(type default)
			)
			(layer "F.SilkS")
		)
		(fp_line
			(start -4.064 -1.6256)
			(end -4.064 -0.3556)
			(stroke
				(width 0.4064)
				(type default)
			)
			(layer "F.SilkS")
		)
		(fp_circle
			(center 2.54 0)
			(end 1.4732 0)
			(stroke
				(width 0.3048)
				(type default)
			)
			(fill no)
			(layer "F.SilkS")
		)
		(fp_circle
			(center 0 0)
			(end -1.0668 0)
			(stroke
				(width 0.3048)
				(type default)
			)
			(fill no)
			(layer "F.SilkS")
		)
		(fp_circle
			(center -2.54 0)
			(end -3.6068 0)
			(stroke
				(width 0.3048)
				(type default)
			)
			(fill no)
			(layer "F.SilkS")
		)
		(fp_rect
			(start -3.683 1.2446)
			(end 3.683 -1.2446)
			(stroke
				(width 0)
				(type default)
			)
			(fill no)
			(layer "F.CrtYd")
		)
		(fp_poly
			(pts
				(xy -4.191 1.7526) (xy -4.191 -1.7526) (xy 4.191 -1.7526) (xy 4.191 1.7526) (xy 0.00254 1.7526)
				(xy 0.00254 1.2446) (xy 3.683 1.2446) (xy 3.683 -1.2446) (xy -3.683 -1.2446) (xy -3.683 1.2446)
				(xy -0.00254 1.2446) (xy -0.00254 1.7526)
			)
			(stroke
				(width 0)
				(type default)
			)
			(fill no)
			(layer "F.CrtYd")
		)
		(fp_rect
			(start -4.191 1.7526)
			(end 4.191 -1.7526)
			(stroke
				(width 0)
				(type default)
			)
			(fill no)
			(layer "F.Fab")
		)
		(pad "1" thru_hole circle
			(at -2.54 0 180)
			(size 1.4224 1.4224)
			(drill 1.016)
			(layers "*.Cu" "*.Mask")
			(remove_unused_layers no)
			(net "SMB_VR_STBY_LVC3_SDA")
			(clearance 0.1524)
			(thermal_gap 0.1524)
		)
		(pad "2" thru_hole circle
			(at 0 0 180)
			(size 1.4224 1.4224)
			(drill 1.016)
			(layers "*.Cu" "*.Mask")
			(remove_unused_layers no)
			(net "GND")
			(clearance 0.1524)
			(thermal_gap 0.1524)
		)
		(pad "3" thru_hole circle
			(at 2.54 0 180)
			(size 1.4224 1.4224)
			(drill 1.016)
			(layers "*.Cu" "*.Mask")
			(remove_unused_layers no)
			(net "SMB_VR_STBY_LVC3_SCL")
			(clearance 0.1524)
			(thermal_gap 0.1524)
		)
	)
	(footprint ""
		(layer "F.Cu")
		(at 276.000464 -149.8092 90)
		(property "Reference" "C5A9"
			(at 1.848866 0.752348 90)
			(unlocked yes)
			(layer "F.SilkS")
			(effects
				(font
					(size 1.27 0.9652)
					(thickness 0.1524)
				)
			)
		)
		(property "Value" ""
			(at 0 0 90)
			(layer "F.Fab")
			(effects
				(font
					(size 1.27 1.27)
				)
			)
		)
		(duplicate_pad_numbers_are_jumpers no)
		(fp_rect
			(start -0.500126 1.598422)
			(end 0.500126 -0.201422)
			(stroke
				(width 0)
				(type default)
			)
			(fill no)
			(layer "F.CrtYd")
		)
		(fp_line
			(start 0.500126 -0.201422)
			(end 0.500126 1.598422)
			(stroke
				(width 0.1)
				(type default)
			)
			(layer "F.Fab")
		)
		(fp_line
			(start -0.500126 -0.201422)
			(end 0.500126 -0.201422)
			(stroke
				(width 0.1)
				(type default)
			)
			(layer "F.Fab")
		)
		(fp_line
			(start 0.500126 1.598422)
			(end -0.500126 1.598422)
			(stroke
				(width 0.1)
				(type default)
			)
			(layer "F.Fab")
		)
		(fp_line
			(start -0.500126 1.598422)
			(end -0.500126 -0.201422)
			(stroke
				(width 0.1)
				(type default)
			)
			(layer "F.Fab")
		)
		(pad "1" smd rect
			(at 0 0)
			(size 0.889 0.9906)
			(layers "F.Cu" "F.Mask" "F.Paste")
			(net "PVDDQ_DEF")
		)
		(pad "2" smd rect
			(at 0 1.397)
			(size 0.889 0.9906)
			(layers "F.Cu" "F.Mask" "F.Paste")
			(net "GND")
		)
		(zone
			(layer "F.Cu")
			(hatch none 0.5)
			(connect_pads
				(clearance 0)
			)
			(min_thickness 0.25)
			(keepout
				(tracks allowed)
				(vias not_allowed)
				(pads allowed)
				(copperpour not_allowed)
				(footprints allowed)
			)
			(placement
				(enabled no)
				(sheetname "")
			)
			(fill
				(thermal_gap 0.5)
				(thermal_bridge_width 0.5)
				(island_removal_mode 0)
			)
			(polygon
				(pts
					(xy 276.952964 -149.3139) (xy 276.952964 -150.3045) (xy 276.444964 -150.3045) (xy 276.444964 -149.3139)
				)
			)
		)
		(zone
			(layer "F.Cu")
			(hatch none 0.5)
			(connect_pads
				(clearance 0)
			)
			(min_thickness 0.25)
			(keepout
				(tracks not_allowed)
				(vias allowed)
				(pads allowed)
				(copperpour not_allowed)
				(footprints allowed)
			)
			(placement
				(enabled no)
				(sheetname "")
			)
			(fill
				(thermal_gap 0.5)
				(thermal_bridge_width 0.5)
				(island_removal_mode 0)
			)
			(polygon
				(pts
					(xy 276.952964 -149.3139) (xy 276.952964 -150.3045) (xy 276.444964 -150.3045) (xy 276.444964 -149.3139)
				)
			)
		)
	)
	(footprint ""
		(layer "F.Cu")
		(at 370.967 -152.019 90)
		(property "Reference" "C22W22"
			(at 0 0 90)
			(layer "F.SilkS")
			(hide yes)
			(effects
				(font
					(size 1.27 1.27)
				)
			)
		)
		(property "Value" "*"
			(at -0.0762 -6.2357 90)
			(unlocked yes)
			(layer "F.Fab")
			(hide yes)
			(effects
				(font
					(size 1.27 1.016)
					(thickness 0.1524)
				)
			)
		)
		(property "Device Type" "SC22U16V5MX-4-GP_SMD-BCG5-SC22A"
			(at -0.0762 -8.2677 90)
			(unlocked yes)
			(layer "F.Fab")
			(hide yes)
			(effects
				(font
					(size 1.27 1.016)
					(thickness 0.1524)
				)
			)
		)
		(duplicate_pad_numbers_are_jumpers no)
		(fp_line
			(start 0.635 0)
			(end -0.635 0)
			(stroke
				(width 0.508)
				(type default)
			)
			(layer "F.SilkS")
		)
		(fp_rect
			(start -0.9652 1.778)
			(end 0.9652 -1.778)
			(stroke
				(width 0)
				(type default)
			)
			(fill no)
			(layer "F.CrtYd")
		)
		(fp_poly
			(pts
				(xy -0.9652 -1.778) (xy 0.9652 -1.778) (xy 0.9652 1.778) (xy -0.9652 1.778)
			)
			(stroke
				(width 0)
				(type default)
			)
			(fill no)
			(layer "F.Fab")
		)
		(pad "1" smd rect
			(at 0 -0.9652 90)
			(size 1.397 1.143)
			(layers "F.Cu" "F.Mask" "F.Paste")
			(net "VR_FET_SW_P12V_STBY_PVDDQ_DEF")
		)
		(pad "2" smd rect
			(at 0 0.9652 90)
			(size 1.397 1.143)
			(layers "F.Cu" "F.Mask" "F.Paste")
			(net "GND")
		)
	)
	(footprint ""
		(layer "F.Cu")
		(at 388.072376 -30.520894 90)
		(property "Reference" "J8F1"
			(at 0 0 90)
			(layer "F.SilkS")
			(hide yes)
			(effects
				(font
					(size 1.27 1.27)
				)
			)
		)
		(property "Value" "*"
			(at 12.319 -1.3335 90)
			(unlocked yes)
			(layer "F.Fab")
			(hide yes)
			(effects
				(font
					(size 1.27 1.016)
					(thickness 0.1524)
				)
			)
		)
		(property "Device Type" "SKT-MINI67P-41-GP_SOCKET-G4-SKA"
			(at 12.319 -2.8575 90)
			(unlocked yes)
			(layer "F.Fab")
			(hide yes)
			(effects
				(font
					(size 1.27 1.016)
					(thickness 0.1524)
				)
			)
		)
		(duplicate_pad_numbers_are_jumpers no)
		(fp_line
			(start -9.4234 -6.3881)
			(end -9.0678 -6.3881)
			(stroke
				(width 0.3302)
				(type default)
			)
			(layer "F.SilkS")
		)
		(fp_line
			(start 11.2014 -6.2992)
			(end 11.2014 3.302)
			(stroke
				(width 0.1524)
				(type default)
			)
			(layer "F.SilkS")
		)
		(fp_line
			(start -11.2014 -6.2992)
			(end 11.2014 -6.2992)
			(stroke
				(width 0.1524)
				(type default)
			)
			(layer "F.SilkS")
		)
		(fp_line
			(start 11.2014 3.302)
			(end -11.2014 3.302)
			(stroke
				(width 0.1524)
				(type default)
			)
			(layer "F.SilkS")
		)
		(fp_line
			(start -11.2014 3.302)
			(end -11.2014 -6.2992)
			(stroke
				(width 0.1524)
				(type default)
			)
			(layer "F.SilkS")
		)
		(fp_poly
			(pts
				(xy -9.218168 -6.38175) (xy -8.583168 -7.01675) (xy -9.853168 -7.01675)
			)
			(stroke
				(width 0)
				(type default)
			)
			(fill yes)
			(layer "F.SilkS")
		)
		(fp_rect
			(start -10.9474 2.7051)
			(end 10.9474 -5.7023)
			(stroke
				(width 0)
				(type default)
			)
			(fill no)
			(layer "F.CrtYd")
		)
		(fp_poly
			(pts
				(xy -11.4554 3.556) (xy -11.4554 -6.5532) (xy 11.4554 -6.5532) (xy 11.4554 3.556) (xy 0.508 3.556)
				(xy 0.508 2.7051) (xy 10.9474 2.7051) (xy 10.9474 -5.7023) (xy -10.9474 -5.7023) (xy -10.9474 2.7051)
				(xy 0.4953 2.7051) (xy 0.4953 3.556)
			)
			(stroke
				(width 0)
				(type default)
			)
			(fill no)
			(layer "F.CrtYd")
		)
		(fp_rect
			(start -11.4554 3.556)
			(end 11.4554 -6.5532)
			(stroke
				(width 0)
				(type default)
			)
			(fill no)
			(layer "F.Fab")
		)
		(pad "" np_thru_hole circle
			(at -9.99998 0 90)
			(size 0.254 0.254)
			(drill 1.1176)
			(layers "*.Cu" "*.Mask")
			(clearance 0.7874)
			(thermal_gap 0.7874)
		)
		(pad "" np_thru_hole circle
			(at 9.99998 0 90)
			(size 0.254 0.254)
			(drill 1.6002)
			(layers "*.Cu" "*.Mask")
			(clearance 1.0287)
			(thermal_gap 1.0287)
		)
		(pad "1" smd rect
			(at -9.249918 -5.275072 90)
			(size 0.3048 1.5494)
			(layers "F.Cu" "F.Mask" "F.Paste")
			(net "GND")
		)
		(pad "2" smd rect
			(at -8.999982 2.275078 90)
			(size 0.3048 1.5494)
			(layers "F.Cu" "F.Mask" "F.Paste")
			(net "P3V3")
		)
		(pad "3" smd rect
			(at -8.750046 -5.275072 90)
			(size 0.3048 1.5494)
			(layers "F.Cu" "F.Mask" "F.Paste")
			(net "GND")
		)
		(pad "4" smd rect
			(at -8.50011 2.275078 90)
			(size 0.3048 1.5494)
			(layers "F.Cu" "F.Mask" "F.Paste")
			(net "P3V3")
		)
		(pad "5" smd rect
			(at -8.24992 -5.275072 90)
			(size 0.3048 1.5494)
			(layers "F.Cu" "F.Mask" "F.Paste")
			(net "P3E_PCH_M2_RX_DN<3>")
		)
		(pad "6" smd rect
			(at -7.999984 2.275078 90)
			(size 0.3048 1.5494)
			(layers "F.Cu" "F.Mask" "F.Paste")
			(net "NC_M2<0>")
		)
		(pad "7" smd rect
			(at -7.750048 -5.275072 90)
			(size 0.3048 1.5494)
			(layers "F.Cu" "F.Mask" "F.Paste")
			(net "P3E_PCH_M2_RX_DP<3>")
		)
		(pad "8" smd rect
			(at -7.500112 2.275078 90)
			(size 0.3048 1.5494)
			(layers "F.Cu" "F.Mask" "F.Paste")
			(net "NC_M2<1>")
		)
		(pad "9" smd rect
			(at -7.249922 -5.275072 90)
			(size 0.3048 1.5494)
			(layers "F.Cu" "F.Mask" "F.Paste")
			(net "GND")
		)
		(pad "10" smd rect
			(at -6.999986 2.275078 90)
			(size 0.3048 1.5494)
			(layers "F.Cu" "F.Mask" "F.Paste")
			(net "TP_LED_M2_ACT_N")
		)
		(pad "11" smd rect
			(at -6.75005 -5.275072 90)
			(size 0.3048 1.5494)
			(layers "F.Cu" "F.Mask" "F.Paste")
			(net "P3E_PCH_M2_TX_C_DN<3>")
		)
		(pad "12" smd rect
			(at -6.500114 2.275078 90)
			(size 0.3048 1.5494)
			(layers "F.Cu" "F.Mask" "F.Paste")
			(net "P3V3")
		)
		(pad "13" smd rect
			(at -6.249924 -5.275072 90)
			(size 0.3048 1.5494)
			(layers "F.Cu" "F.Mask" "F.Paste")
			(net "P3E_PCH_M2_TX_C_DP<3>")
		)
		(pad "14" smd rect
			(at -5.999988 2.275078 90)
			(size 0.3048 1.5494)
			(layers "F.Cu" "F.Mask" "F.Paste")
			(net "P3V3")
		)
		(pad "15" smd rect
			(at -5.750052 -5.275072 90)
			(size 0.3048 1.5494)
			(layers "F.Cu" "F.Mask" "F.Paste")
			(net "GND")
		)
		(pad "16" smd rect
			(at -5.500116 2.275078 90)
			(size 0.3048 1.5494)
			(layers "F.Cu" "F.Mask" "F.Paste")
			(net "P3V3")
		)
		(pad "17" smd rect
			(at -5.249926 -5.275072 90)
			(size 0.3048 1.5494)
			(layers "F.Cu" "F.Mask" "F.Paste")
			(net "P3E_PCH_M2_RX_DN<2>")
		)
		(pad "18" smd rect
			(at -4.99999 2.275078 90)
			(size 0.3048 1.5494)
			(layers "F.Cu" "F.Mask" "F.Paste")
			(net "P3V3")
		)
		(pad "19" smd rect
			(at -4.750054 -5.275072 90)
			(size 0.3048 1.5494)
			(layers "F.Cu" "F.Mask" "F.Paste")
			(net "P3E_PCH_M2_RX_DP<2>")
		)
		(pad "20" smd rect
			(at -4.500118 2.275078 90)
			(size 0.3048 1.5494)
			(layers "F.Cu" "F.Mask" "F.Paste")
			(net "Net_317")
		)
		(pad "21" smd rect
			(at -4.249928 -5.275072 90)
			(size 0.3048 1.5494)
			(layers "F.Cu" "F.Mask" "F.Paste")
			(net "GND")
		)
		(pad "22" smd rect
			(at -3.999992 2.275078 90)
			(size 0.3048 1.5494)
			(layers "F.Cu" "F.Mask" "F.Paste")
			(net "Net_318")
		)
		(pad "23" smd rect
			(at -3.750056 -5.275072 90)
			(size 0.3048 1.5494)
			(layers "F.Cu" "F.Mask" "F.Paste")
			(net "P3E_PCH_M2_TX_C_DN<2>")
		)
		(pad "24" smd rect
			(at -3.50012 2.275078 90)
			(size 0.3048 1.5494)
			(layers "F.Cu" "F.Mask" "F.Paste")
			(net "Net_319")
		)
		(pad "25" smd rect
			(at -3.24993 -5.275072 90)
			(size 0.3048 1.5494)
			(layers "F.Cu" "F.Mask" "F.Paste")
			(net "P3E_PCH_M2_TX_C_DP<2>")
		)
		(pad "26" smd rect
			(at -2.999994 2.275078 90)
			(size 0.3048 1.5494)
			(layers "F.Cu" "F.Mask" "F.Paste")
			(net "Net_320")
		)
		(pad "27" smd rect
			(at -2.750058 -5.275072 90)
			(size 0.3048 1.5494)
			(layers "F.Cu" "F.Mask" "F.Paste")
			(net "GND")
		)
		(pad "28" smd rect
			(at -2.500122 2.275078 90)
			(size 0.3048 1.5494)
			(layers "F.Cu" "F.Mask" "F.Paste")
			(net "Net_321")
		)
		(pad "29" smd rect
			(at -2.249932 -5.275072 90)
			(size 0.3048 1.5494)
			(layers "F.Cu" "F.Mask" "F.Paste")
			(net "P3E_PCH_M2_RX_DN<1>")
		)
		(pad "30" smd rect
			(at -1.999996 2.275078 90)
			(size 0.3048 1.5494)
			(layers "F.Cu" "F.Mask" "F.Paste")
			(net "Net_322")
		)
		(pad "31" smd rect
			(at -1.75006 -5.275072 90)
			(size 0.3048 1.5494)
			(layers "F.Cu" "F.Mask" "F.Paste")
			(net "P3E_PCH_M2_RX_DP<1>")
		)
		(pad "32" smd rect
			(at -1.500124 2.275078 90)
			(size 0.3048 1.5494)
			(layers "F.Cu" "F.Mask" "F.Paste")
			(net "Net_323")
		)
		(pad "33" smd rect
			(at -1.249934 -5.275072 90)
			(size 0.3048 1.5494)
			(layers "F.Cu" "F.Mask" "F.Paste")
			(net "GND")
		)
		(pad "34" smd rect
			(at -0.999998 2.275078 90)
			(size 0.3048 1.5494)
			(layers "F.Cu" "F.Mask" "F.Paste")
			(net "Net_324")
		)
		(pad "35" smd rect
			(at -0.750062 -5.275072 90)
			(size 0.3048 1.5494)
			(layers "F.Cu" "F.Mask" "F.Paste")
			(net "P3E_PCH_M2_TX_C_DN<1>")
		)
		(pad "36" smd rect
			(at -0.500126 2.275078 90)
			(size 0.3048 1.5494)
			(layers "F.Cu" "F.Mask" "F.Paste")
			(net "Net_325")
		)
		(pad "37" smd rect
			(at -0.249936 -5.275072 90)
			(size 0.3048 1.5494)
			(layers "F.Cu" "F.Mask" "F.Paste")
			(net "P3E_PCH_M2_TX_C_DP<1>")
		)
		(pad "38" smd rect
			(at 0 2.275078 90)
			(size 0.3048 1.5494)
			(layers "F.Cu" "F.Mask" "F.Paste")
			(net "TP_M2_DEVSLP")
		)
		(pad "39" smd rect
			(at 0.249936 -5.275072 90)
			(size 0.3048 1.5494)
			(layers "F.Cu" "F.Mask" "F.Paste")
			(net "GND")
		)
		(pad "40" smd rect
			(at 0.500126 2.275078 90)
			(size 0.3048 1.5494)
			(layers "F.Cu" "F.Mask" "F.Paste")
			(net "SMB_M2_SCL")
		)
		(pad "41" smd rect
			(at 0.750062 -5.275072 90)
			(size 0.3048 1.5494)
			(layers "F.Cu" "F.Mask" "F.Paste")
			(net "P3E_PCH_M2_SATA6G_RX_R_DP")
		)
		(pad "42" smd rect
			(at 0.999998 2.275078 90)
			(size 0.3048 1.5494)
			(layers "F.Cu" "F.Mask" "F.Paste")
			(net "SMB_M2_SDA")
		)
		(pad "43" smd rect
			(at 1.249934 -5.275072 90)
			(size 0.3048 1.5494)
			(layers "F.Cu" "F.Mask" "F.Paste")
			(net "P3E_PCH_M2_SATA6G_RX_R_DN")
		)
		(pad "44" smd rect
			(at 1.500124 2.275078 90)
			(size 0.3048 1.5494)
			(layers "F.Cu" "F.Mask" "F.Paste")
			(net "SMB_M2_ALT_N")
		)
		(pad "45" smd rect
			(at 1.75006 -5.275072 90)
			(size 0.3048 1.5494)
			(layers "F.Cu" "F.Mask" "F.Paste")
			(net "GND")
		)
		(pad "46" smd rect
			(at 1.999996 2.275078 90)
			(size 0.3048 1.5494)
			(layers "F.Cu" "F.Mask" "F.Paste")
			(net "Net_326")
		)
		(pad "47" smd rect
			(at 2.249932 -5.275072 90)
			(size 0.3048 1.5494)
			(layers "F.Cu" "F.Mask" "F.Paste")
			(net "P3E_PCH_M2_SATA6G_TX_R_DN")
		)
		(pad "48" smd rect
			(at 2.500122 2.275078 90)
			(size 0.3048 1.5494)
			(layers "F.Cu" "F.Mask" "F.Paste")
			(net "Net_327")
		)
		(pad "49" smd rect
			(at 2.750058 -5.275072 90)
			(size 0.3048 1.5494)
			(layers "F.Cu" "F.Mask" "F.Paste")
			(net "P3E_PCH_M2_SATA6G_TX_R_DP")
		)
		(pad "50" smd rect
			(at 2.999994 2.275078 90)
			(size 0.3048 1.5494)
			(layers "F.Cu" "F.Mask" "F.Paste")
			(net "RST_PCIE_M2_DEV_IC_N")
		)
		(pad "51" smd rect
			(at 3.24993 -5.275072 90)
			(size 0.3048 1.5494)
			(layers "F.Cu" "F.Mask" "F.Paste")
			(net "GND")
		)
		(pad "52" smd rect
			(at 3.50012 2.275078 90)
			(size 0.3048 1.5494)
			(layers "F.Cu" "F.Mask" "F.Paste")
			(net "PU_M2_CLK_REQ_N")
		)
		(pad "53" smd rect
			(at 3.750056 -5.275072 90)
			(size 0.3048 1.5494)
			(layers "F.Cu" "F.Mask" "F.Paste")
			(net "CLK_100M_M2_DN")
		)
		(pad "54" smd rect
			(at 3.999992 2.275078 90)
			(size 0.3048 1.5494)
			(layers "F.Cu" "F.Mask" "F.Paste")
			(net "FM_PE_M2_WAKE_N")
		)
		(pad "55" smd rect
			(at 4.249928 -5.275072 90)
			(size 0.3048 1.5494)
			(layers "F.Cu" "F.Mask" "F.Paste")
			(net "CLK_100M_M2_DP")
		)
		(pad "56" smd rect
			(at 4.500118 2.275078 90)
			(size 0.3048 1.5494)
			(layers "F.Cu" "F.Mask" "F.Paste")
			(net "Net_328")
		)
		(pad "57" smd rect
			(at 4.750054 -5.275072 90)
			(size 0.3048 1.5494)
			(layers "F.Cu" "F.Mask" "F.Paste")
			(net "GND")
		)
		(pad "58" smd rect
			(at 4.99999 2.275078 90)
			(size 0.3048 1.5494)
			(layers "F.Cu" "F.Mask" "F.Paste")
			(net "Net_329")
		)
		(pad "67" smd rect
			(at 7.249922 -5.275072 90)
			(size 0.3048 1.5494)
			(layers "F.Cu" "F.Mask" "F.Paste")
			(net "Net_330")
		)
		(pad "68" smd rect
			(at 7.500112 2.275078 90)
			(size 0.3048 1.5494)
			(layers "F.Cu" "F.Mask" "F.Paste")
			(net "TP_M2_32M_SUSCLK")
		)
		(pad "69" smd rect
			(at 7.750048 -5.275072 90)
			(size 0.3048 1.5494)
			(layers "F.Cu" "F.Mask" "F.Paste")
			(net "FM_M2_SSD_PEDET")
		)
		(pad "70" smd rect
			(at 7.999984 2.275078 90)
			(size 0.3048 1.5494)
			(layers "F.Cu" "F.Mask" "F.Paste")
			(net "P3V3")
		)
		(pad "71" smd rect
			(at 8.24992 -5.275072 90)
			(size 0.3048 1.5494)
			(layers "F.Cu" "F.Mask" "F.Paste")
			(net "GND")
		)
		(pad "72" smd rect
			(at 8.50011 2.275078 90)
			(size 0.3048 1.5494)
			(layers "F.Cu" "F.Mask" "F.Paste")
			(net "P3V3")
		)
		(pad "73" smd rect
			(at 8.750046 -5.275072 90)
			(size 0.3048 1.5494)
			(layers "F.Cu" "F.Mask" "F.Paste")
			(net "GND")
		)
		(pad "74" smd rect
			(at 8.999982 2.275078 90)
			(size 0.3048 1.5494)
			(layers "F.Cu" "F.Mask" "F.Paste")
			(net "P3V3")
		)
		(pad "75" smd rect
			(at 9.249918 -5.275072 90)
			(size 0.3048 1.5494)
			(layers "F.Cu" "F.Mask" "F.Paste")
			(net "GND")
		)
		(pad "76" smd rect
			(at -10.349992 -4.500118 90)
			(size 1.1938 2.7432)
			(layers "F.Cu" "F.Mask" "F.Paste")
			(net "GND")
		)
		(pad "77" smd rect
			(at 10.349992 -4.500118 90)
			(size 1.1938 2.7432)
			(layers "F.Cu" "F.Mask" "F.Paste")
			(net "GND")
		)
		(zone
			(layer "F.Cu")
			(hatch none 0.5)
			(connect_pads
				(clearance 0)
			)
			(min_thickness 0.25)
			(keepout
				(tracks allowed)
				(vias not_allowed)
				(pads allowed)
				(copperpour not_allowed)
				(footprints allowed)
			)
			(placement
				(enabled no)
				(sheetname "")
			)
			(fill
				(thermal_gap 0.5)
				(thermal_bridge_width 0.5)
				(island_removal_mode 0)
			)
			(polygon
				(pts
					(xy 383.572004 -37.618416) (xy 383.699004 -37.618416) (xy 383.699004 -39.923212) (xy 383.572004 -39.923212)
				)
			)
		)
		(zone
			(layer "F.Cu")
			(hatch none 0.5)
			(connect_pads
				(clearance 0)
			)
			(min_thickness 0.25)
			(keepout
				(tracks allowed)
				(vias not_allowed)
				(pads allowed)
				(copperpour not_allowed)
				(footprints allowed)
			)
			(placement
				(enabled no)
				(sheetname "")
			)
			(fill
				(thermal_gap 0.5)
				(thermal_bridge_width 0.5)
				(island_removal_mode 0)
			)
			(polygon
				(pts
					(xy 383.572004 -21.118576) (xy 383.699004 -21.118576) (xy 383.699004 -35.423348) (xy 383.572004 -35.423348)
				)
			)
		)
		(zone
			(layer "F.Cu")
			(hatch none 0.5)
			(connect_pads
				(clearance 0)
			)
			(min_thickness 0.25)
			(keepout
				(tracks allowed)
				(vias not_allowed)
				(pads allowed)
				(copperpour not_allowed)
				(footprints allowed)
			)
			(placement
				(enabled no)
				(sheetname "")
			)
			(fill
				(thermal_gap 0.5)
				(thermal_bridge_width 0.5)
				(island_removal_mode 0)
			)
			(polygon
				(pts
					(xy 389.445754 -37.868606) (xy 389.572754 -37.868606) (xy 389.572754 -39.673276) (xy 389.445754 -39.673276)
				)
			)
		)
		(zone
			(layer "F.Cu")
			(hatch none 0.5)
			(connect_pads
				(clearance 0)
			)
			(min_thickness 0.25)
			(keepout
				(tracks allowed)
				(vias not_allowed)
				(pads allowed)
				(copperpour not_allowed)
				(footprints allowed)
			)
			(placement
				(enabled no)
				(sheetname "")
			)
			(fill
				(thermal_gap 0.5)
				(thermal_bridge_width 0.5)
				(island_removal_mode 0)
			)
			(polygon
				(pts
					(xy 389.445754 -21.368512) (xy 389.572754 -21.368512) (xy 389.572754 -35.673284) (xy 389.445754 -35.673284)
				)
			)
		)
		(zone
			(layers "F.Cu" "B.Cu" "In1.Cu" "In2.Cu" "In3.Cu" "In4.Cu" "In5.Cu" "In6.Cu"
				"In7.Cu" "In8.Cu" "In9.Cu" "In10.Cu" "In11.Cu" "In12.Cu"
			)
			(hatch none 0.5)
			(connect_pads
				(clearance 0)
			)
			(min_thickness 0.25)
			(keepout
				(tracks not_allowed)
				(vias allowed)
				(pads allowed)
				(copperpour not_allowed)
				(footprints allowed)
			)
			(placement
				(enabled no)
				(sheetname "")
			)
			(fill
				(thermal_gap 0.5)
				(thermal_bridge_width 0.5)
				(island_removal_mode 0)
			)
			(polygon
				(pts
					(arc
						(start 388.935976 -20.520914)
						(mid 387.208776 -20.520914)
						(end 388.935976 -20.520914)
					)
				)
			)
		)
		(zone
			(layers "F.Cu" "B.Cu" "In1.Cu" "In2.Cu" "In3.Cu" "In4.Cu" "In5.Cu" "In6.Cu"
				"In7.Cu" "In8.Cu" "In9.Cu" "In10.Cu" "In11.Cu" "In12.Cu"
			)
			(hatch none 0.5)
			(connect_pads
				(clearance 0)
			)
			(min_thickness 0.25)
			(keepout
				(tracks not_allowed)
				(vias allowed)
				(pads allowed)
				(copperpour not_allowed)
				(footprints allowed)
			)
			(placement
				(enabled no)
				(sheetname "")
			)
			(fill
				(thermal_gap 0.5)
				(thermal_bridge_width 0.5)
				(island_removal_mode 0)
			)
			(polygon
				(pts
					(arc
						(start 389.177276 -40.520874)
						(mid 386.967476 -40.520874)
						(end 389.177276 -40.520874)
					)
				)
			)
		)
	)
	(footprint ""
		(layer "F.Cu")
		(at 194.564 -12.5095 180)
		(property "Reference" "R4G3"
			(at 0 0 180)
			(layer "F.SilkS")
			(hide yes)
			(effects
				(font
					(size 1.27 1.27)
				)
			)
		)
		(property "Value" ""
			(at 0 0 180)
			(layer "F.Fab")
			(effects
				(font
					(size 1.27 1.27)
				)
			)
		)
		(duplicate_pad_numbers_are_jumpers no)
		(fp_poly
			(pts
				(xy -0.2794 -0.1016) (xy 0.2794 -0.1016) (xy 0.2794 0.9906) (xy -0.2794 0.9906)
			)
			(stroke
				(width 0)
				(type default)
			)
			(fill no)
			(layer "F.CrtYd")
		)
		(fp_line
			(start 0.2794 0.9906)
			(end 0.2794 -0.1016)
			(stroke
				(width 0.1)
				(type default)
			)
			(layer "F.Fab")
		)
		(fp_line
			(start 0.2794 -0.1016)
			(end -0.2794 -0.1016)
			(stroke
				(width 0.1)
				(type default)
			)
			(layer "F.Fab")
		)
		(fp_line
			(start -0.2794 0.9906)
			(end 0.2794 0.9906)
			(stroke
				(width 0.1)
				(type default)
			)
			(layer "F.Fab")
		)
		(fp_line
			(start -0.2794 -0.1016)
			(end -0.2794 0.9906)
			(stroke
				(width 0.1)
				(type default)
			)
			(layer "F.Fab")
		)
		(pad "1" smd rect
			(at 0 0 180)
			(size 0.508 0.508)
			(layers "F.Cu" "F.Mask" "F.Paste")
			(net "M_B_VREF")
		)
		(pad "2" smd rect
			(at 0 0.889 180)
			(size 0.508 0.508)
			(layers "F.Cu" "F.Mask" "F.Paste")
			(net "GND")
		)
		(zone
			(layer "F.Cu")
			(hatch none 0.5)
			(connect_pads
				(clearance 0)
			)
			(min_thickness 0.25)
			(keepout
				(tracks not_allowed)
				(vias allowed)
				(pads allowed)
				(copperpour not_allowed)
				(footprints allowed)
			)
			(placement
				(enabled no)
				(sheetname "")
			)
			(fill
				(thermal_gap 0.5)
				(thermal_bridge_width 0.5)
				(island_removal_mode 0)
			)
			(polygon
				(pts
					(xy 194.818 -13.1445) (xy 194.31 -13.1445) (xy 194.31 -12.7635) (xy 194.818 -12.7635)
				)
			)
		)
		(zone
			(layer "F.Cu")
			(hatch none 0.5)
			(connect_pads
				(clearance 0)
			)
			(min_thickness 0.25)
			(keepout
				(tracks allowed)
				(vias not_allowed)
				(pads allowed)
				(copperpour not_allowed)
				(footprints allowed)
			)
			(placement
				(enabled no)
				(sheetname "")
			)
			(fill
				(thermal_gap 0.5)
				(thermal_bridge_width 0.5)
				(island_removal_mode 0)
			)
			(polygon
				(pts
					(xy 194.818 -12.7635) (xy 194.31 -12.7635) (xy 194.31 -13.1445) (xy 194.818 -13.1445)
				)
			)
		)
	)
	(footprint ""
		(layer "F.Cu")
		(at 167.6273 -133.1976)
		(property "Reference" "C4B3"
			(at 0 0 0)
			(layer "F.SilkS")
			(hide yes)
			(effects
				(font
					(size 1.27 1.27)
				)
			)
		)
		(property "Value" ""
			(at 0 0 0)
			(layer "F.Fab")
			(effects
				(font
					(size 1.27 1.27)
				)
			)
		)
		(duplicate_pad_numbers_are_jumpers no)
		(fp_poly
			(pts
				(xy -0.7239 -0.2159) (xy 0.7239 -0.2159) (xy 0.7239 1.9939) (xy -0.7239 1.9939)
			)
			(stroke
				(width 0)
				(type default)
			)
			(fill no)
			(layer "F.CrtYd")
		)
		(fp_line
			(start -0.7239 -0.2159)
			(end -0.7239 1.9939)
			(stroke
				(width 0.1)
				(type default)
			)
			(layer "F.Fab")
		)
		(fp_line
			(start -0.7239 1.9939)
			(end 0.7239 1.9939)
			(stroke
				(width 0.1)
				(type default)
			)
			(layer "F.Fab")
		)
		(fp_line
			(start 0.7239 -0.2159)
			(end -0.7239 -0.2159)
			(stroke
				(width 0.1)
				(type default)
			)
			(layer "F.Fab")
		)
		(fp_line
			(start 0.7239 1.9939)
			(end 0.7239 -0.2159)
			(stroke
				(width 0.1)
				(type default)
			)
			(layer "F.Fab")
		)
		(pad "1" smd rect
			(at 0 0)
			(size 1.27 1.016)
			(layers "F.Cu" "F.Mask" "F.Paste")
			(net "PVPP_KLM")
		)
		(pad "2" smd rect
			(at 0 1.778)
			(size 1.27 1.016)
			(layers "F.Cu" "F.Mask" "F.Paste")
			(net "GND")
		)
		(zone
			(layer "F.Cu")
			(hatch none 0.5)
			(connect_pads
				(clearance 0)
			)
			(min_thickness 0.25)
			(keepout
				(tracks not_allowed)
				(vias allowed)
				(pads allowed)
				(copperpour not_allowed)
				(footprints allowed)
			)
			(placement
				(enabled no)
				(sheetname "")
			)
			(fill
				(thermal_gap 0.5)
				(thermal_bridge_width 0.5)
				(island_removal_mode 0)
			)
			(polygon
				(pts
					(xy 166.9923 -132.6896) (xy 168.2623 -132.6896) (xy 168.2623 -131.9276) (xy 166.9923 -131.9276)
				)
			)
		)
	)
	(footprint ""
		(layer "F.Cu")
		(at 19.05 -87.63)
		(property "Reference" "R1D3"
			(at 0 0 0)
			(layer "F.SilkS")
			(hide yes)
			(effects
				(font
					(size 1.27 1.27)
				)
			)
		)
		(property "Value" ""
			(at 0 0 0)
			(layer "F.Fab")
			(effects
				(font
					(size 1.27 1.27)
				)
			)
		)
		(duplicate_pad_numbers_are_jumpers no)
		(fp_rect
			(start -0.2794 0.9906)
			(end 0.2794 -0.1016)
			(stroke
				(width 0)
				(type default)
			)
			(fill no)
			(layer "F.CrtYd")
		)
		(fp_line
			(start -0.2794 -0.1016)
			(end -0.2794 0.9906)
			(stroke
				(width 0.1)
				(type default)
			)
			(layer "F.Fab")
		)
		(fp_line
			(start -0.2794 0.9906)
			(end 0.2794 0.9906)
			(stroke
				(width 0.1)
				(type default)
			)
			(layer "F.Fab")
		)
		(fp_line
			(start 0.2794 -0.1016)
			(end -0.2794 -0.1016)
			(stroke
				(width 0.1)
				(type default)
			)
			(layer "F.Fab")
		)
		(fp_line
			(start 0.2794 0.9906)
			(end 0.2794 -0.1016)
			(stroke
				(width 0.1)
				(type default)
			)
			(layer "F.Fab")
		)
		(pad "1" smd rect
			(at 0 0)
			(size 0.508 0.508)
			(layers "F.Cu" "F.Mask" "F.Paste")
			(net "SVID_VALERT_VCCIN_CPU1")
		)
		(pad "2" smd rect
			(at 0 0.889)
			(size 0.508 0.508)
			(layers "F.Cu" "F.Mask" "F.Paste")
			(net "SVID_ALERT0_CPU1_R_N")
		)
		(zone
			(layer "F.Cu")
			(hatch none 0.5)
			(connect_pads
				(clearance 0)
			)
			(min_thickness 0.25)
			(keepout
				(tracks not_allowed)
				(vias allowed)
				(pads allowed)
				(copperpour not_allowed)
				(footprints allowed)
			)
			(placement
				(enabled no)
				(sheetname "")
			)
			(fill
				(thermal_gap 0.5)
				(thermal_bridge_width 0.5)
				(island_removal_mode 0)
			)
			(polygon
				(pts
					(xy 18.796 -86.995) (xy 19.304 -86.995) (xy 19.304 -87.376) (xy 18.796 -87.376)
				)
			)
		)
		(zone
			(layer "F.Cu")
			(hatch none 0.5)
			(connect_pads
				(clearance 0)
			)
			(min_thickness 0.25)
			(keepout
				(tracks allowed)
				(vias not_allowed)
				(pads allowed)
				(copperpour not_allowed)
				(footprints allowed)
			)
			(placement
				(enabled no)
				(sheetname "")
			)
			(fill
				(thermal_gap 0.5)
				(thermal_bridge_width 0.5)
				(island_removal_mode 0)
			)
			(polygon
				(pts
					(xy 18.796 -86.995) (xy 19.304 -86.995) (xy 19.304 -87.376) (xy 18.796 -87.376)
				)
			)
		)
	)
	(footprint ""
		(layer "F.Cu")
		(at 493.168686 -46.569884 180)
		(property "Reference" "C25W82"
			(at -0.8382 -0.67818 180)
			(unlocked yes)
			(layer "F.SilkS")
			(effects
				(font
					(size 0.4064 0.254)
					(thickness 0.1524)
				)
				(justify left)
			)
		)
		(property "Value" ""
			(at 0 0 180)
			(layer "F.Fab")
			(effects
				(font
					(size 1.27 1.27)
				)
			)
		)
		(duplicate_pad_numbers_are_jumpers no)
		(fp_poly
			(pts
				(xy 0.3048 -0.1016) (xy 0.3048 0.9906) (xy -0.3048 0.9906) (xy -0.3048 -0.1016)
			)
			(stroke
				(width 0)
				(type default)
			)
			(fill no)
			(layer "F.CrtYd")
		)
		(fp_line
			(start 0.3048 0.9906)
			(end 0.3048 -0.1016)
			(stroke
				(width 0.1)
				(type default)
			)
			(layer "F.Fab")
		)
		(fp_line
			(start 0.3048 -0.1016)
			(end -0.3048 -0.1016)
			(stroke
				(width 0.1)
				(type default)
			)
			(layer "F.Fab")
		)
		(fp_line
			(start -0.3048 0.9906)
			(end 0.3048 0.9906)
			(stroke
				(width 0.1)
				(type default)
			)
			(layer "F.Fab")
		)
		(fp_line
			(start -0.3048 -0.1016)
			(end -0.3048 0.9906)
			(stroke
				(width 0.1)
				(type default)
			)
			(layer "F.Fab")
		)
		(pad "1" smd rect
			(at 0 0 180)
			(size 0.508 0.508)
			(layers "F.Cu" "F.Mask" "F.Paste")
			(net "V_IO_VSYNC_J")
		)
		(pad "2" smd rect
			(at 0 0.889 180)
			(size 0.508 0.508)
			(layers "F.Cu" "F.Mask" "F.Paste")
			(net "GND")
		)
		(zone
			(layer "F.Cu")
			(hatch none 0.5)
			(connect_pads
				(clearance 0)
			)
			(min_thickness 0.25)
			(keepout
				(tracks not_allowed)
				(vias allowed)
				(pads allowed)
				(copperpour not_allowed)
				(footprints allowed)
			)
			(placement
				(enabled no)
				(sheetname "")
			)
			(fill
				(thermal_gap 0.5)
				(thermal_bridge_width 0.5)
				(island_removal_mode 0)
			)
			(polygon
				(pts
					(xy 493.422686 -47.204884) (xy 492.914686 -47.204884) (xy 492.914686 -46.823884) (xy 493.422686 -46.823884)
				)
			)
		)
		(zone
			(layer "F.Cu")
			(hatch none 0.5)
			(connect_pads
				(clearance 0)
			)
			(min_thickness 0.25)
			(keepout
				(tracks allowed)
				(vias not_allowed)
				(pads allowed)
				(copperpour not_allowed)
				(footprints allowed)
			)
			(placement
				(enabled no)
				(sheetname "")
			)
			(fill
				(thermal_gap 0.5)
				(thermal_bridge_width 0.5)
				(island_removal_mode 0)
			)
			(polygon
				(pts
					(xy 493.422686 -46.823884) (xy 492.914686 -46.823884) (xy 492.914686 -47.204884) (xy 493.422686 -47.204884)
				)
			)
		)
	)
	(footprint ""
		(layer "F.Cu")
		(at 184.785 -26.416)
		(property "Reference" "R4F2"
			(at 0 0 0)
			(layer "F.SilkS")
			(hide yes)
			(effects
				(font
					(size 1.27 1.27)
				)
			)
		)
		(property "Value" ""
			(at 0 0 0)
			(layer "F.Fab")
			(effects
				(font
					(size 1.27 1.27)
				)
			)
		)
		(duplicate_pad_numbers_are_jumpers no)
		(fp_line
			(start -0.9017 1.951736)
			(end -0.9017 0.823468)
			(stroke
				(width 0.1524)
				(type default)
			)
			(layer "F.SilkS")
		)
		(fp_line
			(start 0.9017 1.952498)
			(end 0.9017 0.853948)
			(stroke
				(width 0.1524)
				(type default)
			)
			(layer "F.SilkS")
		)
		(fp_poly
			(pts
				(xy -0.9017 3.0988) (xy 0.9017 3.0988) (xy 0.9017 -0.3048) (xy -0.9017 -0.3048)
			)
			(stroke
				(width 0)
				(type default)
			)
			(fill no)
			(layer "F.CrtYd")
		)
		(fp_line
			(start -0.9017 -0.3048)
			(end -0.9017 3.0988)
			(stroke
				(width 0.1)
				(type default)
			)
			(layer "F.Fab")
		)
		(fp_line
			(start -0.9017 3.0988)
			(end 0.9017 3.0988)
			(stroke
				(width 0.1)
				(type default)
			)
			(layer "F.Fab")
		)
		(fp_line
			(start 0.9017 -0.3048)
			(end -0.9017 -0.3048)
			(stroke
				(width 0.1)
				(type default)
			)
			(layer "F.Fab")
		)
		(fp_line
			(start 0.9017 3.0988)
			(end 0.9017 -0.3048)
			(stroke
				(width 0.1)
				(type default)
			)
			(layer "F.Fab")
		)
		(pad "1" smd rect
			(at 0 0)
			(size 1.524 1.016)
			(layers "F.Cu" "F.Mask" "F.Paste")
			(net "P12V_STBY")
		)
		(pad "2" smd rect
			(at 0 2.794)
			(size 1.524 1.016)
			(layers "F.Cu" "F.Mask" "F.Paste")
			(net "P12V_NVDIMM_ABC")
		)
		(zone
			(layer "F.Cu")
			(hatch none 0.5)
			(connect_pads
				(clearance 0)
			)
			(min_thickness 0.25)
			(keepout
				(tracks allowed)
				(vias not_allowed)
				(pads allowed)
				(copperpour not_allowed)
				(footprints allowed)
			)
			(placement
				(enabled no)
				(sheetname "")
			)
			(fill
				(thermal_gap 0.5)
				(thermal_bridge_width 0.5)
				(island_removal_mode 0)
			)
			(polygon
				(pts
					(xy 184.023 -24.13) (xy 185.547 -24.13) (xy 185.547 -25.908) (xy 184.023 -25.908)
				)
			)
		)
	)
	(footprint ""
		(layer "F.Cu")
		(at 449.69938 -32.4485 90)
		(property "Reference" "R25W26"
			(at 0 0 90)
			(layer "F.SilkS")
			(hide yes)
			(effects
				(font
					(size 1.27 1.27)
				)
			)
		)
		(property "Value" "*"
			(at 0.064008 -4.108196 90)
			(unlocked yes)
			(layer "F.Fab")
			(hide yes)
			(effects
				(font
					(size 1.27 1.016)
					(thickness 0.1524)
				)
			)
		)
		(property "Device Type" "120R2F-GP_RCL_GP-120R2F-GP,64.A"
			(at 0.064008 -5.632196 90)
			(unlocked yes)
			(layer "F.Fab")
			(hide yes)
			(effects
				(font
					(size 1.27 1.016)
					(thickness 0.1524)
				)
			)
		)
		(duplicate_pad_numbers_are_jumpers no)
		(fp_line
			(start 0.508 -0.9398)
			(end -0.508 -0.9398)
			(stroke
				(width 0.1524)
				(type default)
			)
			(layer "F.SilkS")
		)
		(fp_line
			(start -0.508 -0.9398)
			(end -0.508 0.9398)
			(stroke
				(width 0.1524)
				(type default)
			)
			(layer "F.SilkS")
		)
		(fp_rect
			(start -0.508 0.9398)
			(end 0.508 -0.9398)
			(stroke
				(width 0)
				(type default)
			)
			(fill no)
			(layer "F.CrtYd")
		)
		(fp_rect
			(start -0.508 0.9398)
			(end 0.508 -0.9398)
			(stroke
				(width 0)
				(type default)
			)
			(fill no)
			(layer "F.Fab")
		)
		(pad "1" smd custom
			(at 0 -0.4445 90)
			(size 0.1397 0.1397)
			(layers "F.Cu" "F.Mask" "F.Paste")
			(net "GND")
			(options
				(clearance outline)
				(anchor circle)
			)
			(primitives
				(gr_poly
					(pts
						(arc
							(start -0.1778 -0.2794)
							(mid -0.249642 -0.249642)
							(end -0.2794 -0.1778)
						)
						(arc
							(start -0.2794 0.1778)
							(mid -0.249642 0.249642)
							(end -0.1778 0.2794)
						)
						(arc
							(start 0.1778 0.2794)
							(mid 0.249642 0.249642)
							(end 0.2794 0.1778)
						)
						(arc
							(start 0.2794 -0.1778)
							(mid 0.249642 -0.249642)
							(end 0.1778 -0.2794)
						)
					)
					(width 0)
					(fill yes)
				)
			)
		)
		(pad "2" smd custom
			(at 0 0.4445 90)
			(size 0.1397 0.1397)
			(layers "F.Cu" "F.Mask" "F.Paste")
			(net "BMC_M_MACT_N")
			(options
				(clearance outline)
				(anchor circle)
			)
			(primitives
				(gr_poly
					(pts
						(arc
							(start -0.1778 -0.2794)
							(mid -0.249642 -0.249642)
							(end -0.2794 -0.1778)
						)
						(arc
							(start -0.2794 0.1778)
							(mid -0.249642 0.249642)
							(end -0.1778 0.2794)
						)
						(arc
							(start 0.1778 0.2794)
							(mid 0.249642 0.249642)
							(end 0.2794 0.1778)
						)
						(arc
							(start 0.2794 -0.1778)
							(mid 0.249642 -0.249642)
							(end 0.1778 -0.2794)
						)
					)
					(width 0)
					(fill yes)
				)
			)
		)
	)
	(footprint ""
		(layer "F.Cu")
		(at 1.315212 -150.678896 90)
		(property "Reference" "C1A20"
			(at 0 0 90)
			(layer "F.SilkS")
			(hide yes)
			(effects
				(font
					(size 1.27 1.27)
				)
			)
		)
		(property "Value" ""
			(at 0 0 90)
			(layer "F.Fab")
			(effects
				(font
					(size 1.27 1.27)
				)
			)
		)
		(duplicate_pad_numbers_are_jumpers no)
		(fp_rect
			(start 0.3048 -0.1016)
			(end -0.3048 0.9906)
			(stroke
				(width 0)
				(type default)
			)
			(fill no)
			(layer "F.CrtYd")
		)
		(fp_line
			(start 0.3048 -0.1016)
			(end -0.3048 -0.1016)
			(stroke
				(width 0.1)
				(type default)
			)
			(layer "F.Fab")
		)
		(fp_line
			(start -0.3048 -0.1016)
			(end -0.3048 0.9906)
			(stroke
				(width 0.1)
				(type default)
			)
			(layer "F.Fab")
		)
		(fp_line
			(start 0.3048 0.9906)
			(end 0.3048 -0.1016)
			(stroke
				(width 0.1)
				(type default)
			)
			(layer "F.Fab")
		)
		(fp_line
			(start -0.3048 0.9906)
			(end 0.3048 0.9906)
			(stroke
				(width 0.1)
				(type default)
			)
			(layer "F.Fab")
		)
		(pad "1" smd rect
			(at 0 0 90)
			(size 0.508 0.508)
			(layers "F.Cu" "F.Mask" "F.Paste")
			(net "VR_FET_SW_P12V_STBY_PVDDQ_KLM")
		)
		(pad "2" smd rect
			(at 0 0.889 90)
			(size 0.508 0.508)
			(layers "F.Cu" "F.Mask" "F.Paste")
			(net "GND")
		)
		(zone
			(layer "F.Cu")
			(hatch none 0.5)
			(connect_pads
				(clearance 0)
			)
			(min_thickness 0.25)
			(keepout
				(tracks allowed)
				(vias not_allowed)
				(pads allowed)
				(copperpour not_allowed)
				(footprints allowed)
			)
			(placement
				(enabled no)
				(sheetname "")
			)
			(fill
				(thermal_gap 0.5)
				(thermal_bridge_width 0.5)
				(island_removal_mode 0)
			)
			(polygon
				(pts
					(xy 1.569212 -150.932896) (xy 1.569212 -150.424896) (xy 1.950212 -150.424896) (xy 1.950212 -150.932896)
				)
			)
		)
		(zone
			(layer "F.Cu")
			(hatch none 0.5)
			(connect_pads
				(clearance 0)
			)
			(min_thickness 0.25)
			(keepout
				(tracks not_allowed)
				(vias allowed)
				(pads allowed)
				(copperpour not_allowed)
				(footprints allowed)
			)
			(placement
				(enabled no)
				(sheetname "")
			)
			(fill
				(thermal_gap 0.5)
				(thermal_bridge_width 0.5)
				(island_removal_mode 0)
			)
			(polygon
				(pts
					(xy 1.569212 -150.932896) (xy 1.569212 -150.424896) (xy 1.950212 -150.424896) (xy 1.950212 -150.932896)
				)
			)
		)
	)
	(footprint ""
		(layer "F.Cu")
		(at 98.18624 -77.636116)
		(property "Reference" "C2D23"
			(at 0 0 0)
			(layer "F.SilkS")
			(hide yes)
			(effects
				(font
					(size 1.27 1.27)
				)
			)
		)
		(property "Value" ""
			(at 0 0 0)
			(layer "F.Fab")
			(effects
				(font
					(size 1.27 1.27)
				)
			)
		)
		(duplicate_pad_numbers_are_jumpers no)
		(fp_poly
			(pts
				(xy -0.4953 -0.2032) (xy 0.4953 -0.2032) (xy 0.4953 1.6002) (xy -0.4953 1.6002)
			)
			(stroke
				(width 0)
				(type default)
			)
			(fill no)
			(layer "F.CrtYd")
		)
		(fp_line
			(start -0.4953 -0.2032)
			(end 0.4953 -0.2032)
			(stroke
				(width 0.1)
				(type default)
			)
			(layer "F.Fab")
		)
		(fp_line
			(start -0.4953 1.6002)
			(end -0.4953 -0.2032)
			(stroke
				(width 0.1)
				(type default)
			)
			(layer "F.Fab")
		)
		(fp_line
			(start 0.4953 -0.2032)
			(end 0.4953 1.6002)
			(stroke
				(width 0.1)
				(type default)
			)
			(layer "F.Fab")
		)
		(fp_line
			(start 0.4953 1.6002)
			(end -0.4953 1.6002)
			(stroke
				(width 0.1)
				(type default)
			)
			(layer "F.Fab")
		)
		(pad "1" smd rect
			(at 0 0)
			(size 0.762 0.889)
			(layers "F.Cu" "F.Mask" "F.Paste")
			(net "PVCCIN_CPU1")
		)
		(pad "2" smd rect
			(at 0 1.397)
			(size 0.762 0.889)
			(layers "F.Cu" "F.Mask" "F.Paste")
			(net "GND")
		)
		(zone
			(layer "F.Cu")
			(hatch none 0.5)
			(connect_pads
				(clearance 0)
			)
			(min_thickness 0.25)
			(keepout
				(tracks not_allowed)
				(vias allowed)
				(pads allowed)
				(copperpour not_allowed)
				(footprints allowed)
			)
			(placement
				(enabled no)
				(sheetname "")
			)
			(fill
				(thermal_gap 0.5)
				(thermal_bridge_width 0.5)
				(island_removal_mode 0)
			)
			(polygon
				(pts
					(xy 97.80524 -77.191616) (xy 98.56724 -77.191616) (xy 98.56724 -76.683616) (xy 97.80524 -76.683616)
				)
			)
		)
	)
	(footprint ""
		(layer "F.Cu")
		(at 482.6508 -32.2834)
		(property "Reference" "C8F18"
			(at 0 0 0)
			(layer "F.SilkS")
			(hide yes)
			(effects
				(font
					(size 1.27 1.27)
				)
			)
		)
		(property "Value" ""
			(at 0 0 0)
			(layer "F.Fab")
			(effects
				(font
					(size 1.27 1.27)
				)
			)
		)
		(duplicate_pad_numbers_are_jumpers no)
		(fp_poly
			(pts
				(xy 0.3048 -0.1016) (xy 0.3048 0.9906) (xy -0.3048 0.9906) (xy -0.3048 -0.1016)
			)
			(stroke
				(width 0)
				(type default)
			)
			(fill no)
			(layer "F.CrtYd")
		)
		(fp_line
			(start -0.3048 -0.1016)
			(end -0.3048 0.9906)
			(stroke
				(width 0.1)
				(type default)
			)
			(layer "F.Fab")
		)
		(fp_line
			(start -0.3048 0.9906)
			(end 0.3048 0.9906)
			(stroke
				(width 0.1)
				(type default)
			)
			(layer "F.Fab")
		)
		(fp_line
			(start 0.3048 -0.1016)
			(end -0.3048 -0.1016)
			(stroke
				(width 0.1)
				(type default)
			)
			(layer "F.Fab")
		)
		(fp_line
			(start 0.3048 0.9906)
			(end 0.3048 -0.1016)
			(stroke
				(width 0.1)
				(type default)
			)
			(layer "F.Fab")
		)
		(pad "1" smd rect
			(at 0 0)
			(size 0.508 0.508)
			(layers "F.Cu" "F.Mask" "F.Paste")
			(net "XTAL_CK_MNG_IN")
		)
		(pad "2" smd rect
			(at 0 0.889)
			(size 0.508 0.508)
			(layers "F.Cu" "F.Mask" "F.Paste")
			(net "GND")
		)
		(zone
			(layer "F.Cu")
			(hatch none 0.5)
			(connect_pads
				(clearance 0)
			)
			(min_thickness 0.25)
			(keepout
				(tracks allowed)
				(vias not_allowed)
				(pads allowed)
				(copperpour not_allowed)
				(footprints allowed)
			)
			(placement
				(enabled no)
				(sheetname "")
			)
			(fill
				(thermal_gap 0.5)
				(thermal_bridge_width 0.5)
				(island_removal_mode 0)
			)
			(polygon
				(pts
					(xy 482.3968 -32.0294) (xy 482.9048 -32.0294) (xy 482.9048 -31.6484) (xy 482.3968 -31.6484)
				)
			)
		)
		(zone
			(layer "F.Cu")
			(hatch none 0.5)
			(connect_pads
				(clearance 0)
			)
			(min_thickness 0.25)
			(keepout
				(tracks not_allowed)
				(vias allowed)
				(pads allowed)
				(copperpour not_allowed)
				(footprints allowed)
			)
			(placement
				(enabled no)
				(sheetname "")
			)
			(fill
				(thermal_gap 0.5)
				(thermal_bridge_width 0.5)
				(island_removal_mode 0)
			)
			(polygon
				(pts
					(xy 482.3968 -31.6484) (xy 482.9048 -31.6484) (xy 482.9048 -32.0294) (xy 482.3968 -32.0294)
				)
			)
		)
	)
	(footprint ""
		(layer "F.Cu")
		(at 93.20784 -77.636116)
		(property "Reference" "C2D19"
			(at 0 0 0)
			(layer "F.SilkS")
			(hide yes)
			(effects
				(font
					(size 1.27 1.27)
				)
			)
		)
		(property "Value" ""
			(at 0 0 0)
			(layer "F.Fab")
			(effects
				(font
					(size 1.27 1.27)
				)
			)
		)
		(duplicate_pad_numbers_are_jumpers no)
		(fp_poly
			(pts
				(xy -0.4953 -0.2032) (xy 0.4953 -0.2032) (xy 0.4953 1.6002) (xy -0.4953 1.6002)
			)
			(stroke
				(width 0)
				(type default)
			)
			(fill no)
			(layer "F.CrtYd")
		)
		(fp_line
			(start -0.4953 -0.2032)
			(end 0.4953 -0.2032)
			(stroke
				(width 0.1)
				(type default)
			)
			(layer "F.Fab")
		)
		(fp_line
			(start -0.4953 1.6002)
			(end -0.4953 -0.2032)
			(stroke
				(width 0.1)
				(type default)
			)
			(layer "F.Fab")
		)
		(fp_line
			(start 0.4953 -0.2032)
			(end 0.4953 1.6002)
			(stroke
				(width 0.1)
				(type default)
			)
			(layer "F.Fab")
		)
		(fp_line
			(start 0.4953 1.6002)
			(end -0.4953 1.6002)
			(stroke
				(width 0.1)
				(type default)
			)
			(layer "F.Fab")
		)
		(pad "1" smd rect
			(at 0 0)
			(size 0.762 0.889)
			(layers "F.Cu" "F.Mask" "F.Paste")
			(net "PVCCIN_CPU1")
		)
		(pad "2" smd rect
			(at 0 1.397)
			(size 0.762 0.889)
			(layers "F.Cu" "F.Mask" "F.Paste")
			(net "GND")
		)
		(zone
			(layer "F.Cu")
			(hatch none 0.5)
			(connect_pads
				(clearance 0)
			)
			(min_thickness 0.25)
			(keepout
				(tracks not_allowed)
				(vias allowed)
				(pads allowed)
				(copperpour not_allowed)
				(footprints allowed)
			)
			(placement
				(enabled no)
				(sheetname "")
			)
			(fill
				(thermal_gap 0.5)
				(thermal_bridge_width 0.5)
				(island_removal_mode 0)
			)
			(polygon
				(pts
					(xy 92.82684 -77.191616) (xy 93.58884 -77.191616) (xy 93.58884 -76.683616) (xy 92.82684 -76.683616)
				)
			)
		)
	)
	(footprint ""
		(layer "F.Cu")
		(at 491.0455 -43.0784 90)
		(property "Reference" "R9E17"
			(at 0 0 90)
			(layer "F.SilkS")
			(hide yes)
			(effects
				(font
					(size 1.27 1.27)
				)
			)
		)
		(property "Value" ""
			(at 0 0 90)
			(layer "F.Fab")
			(effects
				(font
					(size 1.27 1.27)
				)
			)
		)
		(duplicate_pad_numbers_are_jumpers no)
		(fp_poly
			(pts
				(xy -0.2794 -0.1016) (xy 0.2794 -0.1016) (xy 0.2794 0.9906) (xy -0.2794 0.9906)
			)
			(stroke
				(width 0)
				(type default)
			)
			(fill no)
			(layer "F.CrtYd")
		)
		(fp_line
			(start 0.2794 -0.1016)
			(end -0.2794 -0.1016)
			(stroke
				(width 0.1)
				(type default)
			)
			(layer "F.Fab")
		)
		(fp_line
			(start -0.2794 -0.1016)
			(end -0.2794 0.9906)
			(stroke
				(width 0.1)
				(type default)
			)
			(layer "F.Fab")
		)
		(fp_line
			(start 0.2794 0.9906)
			(end 0.2794 -0.1016)
			(stroke
				(width 0.1)
				(type default)
			)
			(layer "F.Fab")
		)
		(fp_line
			(start -0.2794 0.9906)
			(end 0.2794 0.9906)
			(stroke
				(width 0.1)
				(type default)
			)
			(layer "F.Fab")
		)
		(pad "1" smd rect
			(at 0 0 90)
			(size 0.508 0.508)
			(layers "F.Cu" "F.Mask" "F.Paste")
			(net "RMII_SPRNGVLLE_BMC_PCH_RXD0_R")
		)
		(pad "2" smd rect
			(at 0 0.889 90)
			(size 0.508 0.508)
			(layers "F.Cu" "F.Mask" "F.Paste")
			(net "RMII_SPRNGVLLE_BMC_PCH_RXD0")
		)
		(zone
			(layer "F.Cu")
			(hatch none 0.5)
			(connect_pads
				(clearance 0)
			)
			(min_thickness 0.25)
			(keepout
				(tracks allowed)
				(vias not_allowed)
				(pads allowed)
				(copperpour not_allowed)
				(footprints allowed)
			)
			(placement
				(enabled no)
				(sheetname "")
			)
			(fill
				(thermal_gap 0.5)
				(thermal_bridge_width 0.5)
				(island_removal_mode 0)
			)
			(polygon
				(pts
					(xy 491.2995 -42.8244) (xy 491.2995 -43.3324) (xy 491.6805 -43.3324) (xy 491.6805 -42.8244)
				)
			)
		)
		(zone
			(layer "F.Cu")
			(hatch none 0.5)
			(connect_pads
				(clearance 0)
			)
			(min_thickness 0.25)
			(keepout
				(tracks not_allowed)
				(vias allowed)
				(pads allowed)
				(copperpour not_allowed)
				(footprints allowed)
			)
			(placement
				(enabled no)
				(sheetname "")
			)
			(fill
				(thermal_gap 0.5)
				(thermal_bridge_width 0.5)
				(island_removal_mode 0)
			)
			(polygon
				(pts
					(xy 491.6805 -42.8244) (xy 491.6805 -43.3324) (xy 491.2995 -43.3324) (xy 491.2995 -42.8244)
				)
			)
		)
	)
	(footprint ""
		(layer "F.Cu")
		(at 465.582 -20.4343 180)
		(property "Reference" "R8F5"
			(at 0 0 180)
			(layer "F.SilkS")
			(hide yes)
			(effects
				(font
					(size 1.27 1.27)
				)
			)
		)
		(property "Value" ""
			(at 0 0 180)
			(layer "F.Fab")
			(effects
				(font
					(size 1.27 1.27)
				)
			)
		)
		(duplicate_pad_numbers_are_jumpers no)
		(fp_rect
			(start -0.2794 -0.1016)
			(end 0.2794 0.9906)
			(stroke
				(width 0)
				(type default)
			)
			(fill no)
			(layer "F.CrtYd")
		)
		(fp_line
			(start 0.2794 0.9906)
			(end 0.2794 -0.1016)
			(stroke
				(width 0.1)
				(type default)
			)
			(layer "F.Fab")
		)
		(fp_line
			(start 0.2794 -0.1016)
			(end -0.2794 -0.1016)
			(stroke
				(width 0.1)
				(type default)
			)
			(layer "F.Fab")
		)
		(fp_line
			(start -0.2794 0.9906)
			(end 0.2794 0.9906)
			(stroke
				(width 0.1)
				(type default)
			)
			(layer "F.Fab")
		)
		(fp_line
			(start -0.2794 -0.1016)
			(end -0.2794 0.9906)
			(stroke
				(width 0.1)
				(type default)
			)
			(layer "F.Fab")
		)
		(pad "1" smd rect
			(at 0 0 180)
			(size 0.508 0.508)
			(layers "F.Cu" "F.Mask" "F.Paste")
			(net "P3V3_STBY")
		)
		(pad "2" smd rect
			(at 0 0.889 180)
			(size 0.508 0.508)
			(layers "F.Cu" "F.Mask" "F.Paste")
			(net "PWRGD_P3V3_STBY_R")
		)
		(zone
			(layer "F.Cu")
			(hatch none 0.5)
			(connect_pads
				(clearance 0)
			)
			(min_thickness 0.25)
			(keepout
				(tracks not_allowed)
				(vias allowed)
				(pads allowed)
				(copperpour not_allowed)
				(footprints allowed)
			)
			(placement
				(enabled no)
				(sheetname "")
			)
			(fill
				(thermal_gap 0.5)
				(thermal_bridge_width 0.5)
				(island_removal_mode 0)
			)
			(polygon
				(pts
					(xy 465.836 -20.6883) (xy 465.836 -21.0693) (xy 465.328 -21.0693) (xy 465.328 -20.6883)
				)
			)
		)
		(zone
			(layer "F.Cu")
			(hatch none 0.5)
			(connect_pads
				(clearance 0)
			)
			(min_thickness 0.25)
			(keepout
				(tracks allowed)
				(vias not_allowed)
				(pads allowed)
				(copperpour not_allowed)
				(footprints allowed)
			)
			(placement
				(enabled no)
				(sheetname "")
			)
			(fill
				(thermal_gap 0.5)
				(thermal_bridge_width 0.5)
				(island_removal_mode 0)
			)
			(polygon
				(pts
					(xy 465.836 -20.6883) (xy 465.836 -21.0693) (xy 465.328 -21.0693) (xy 465.328 -20.6883)
				)
			)
		)
	)
	(footprint ""
		(layer "F.Cu")
		(at 368.554 -110.998 90)
		(property "Reference" "C7C2"
			(at 0 0 90)
			(layer "F.SilkS")
			(hide yes)
			(effects
				(font
					(size 1.27 1.27)
				)
			)
		)
		(property "Value" ""
			(at 0 0 90)
			(layer "F.Fab")
			(effects
				(font
					(size 1.27 1.27)
				)
			)
		)
		(duplicate_pad_numbers_are_jumpers no)
		(fp_poly
			(pts
				(xy 0.3048 -0.1016) (xy 0.3048 0.9906) (xy -0.3048 0.9906) (xy -0.3048 -0.1016)
			)
			(stroke
				(width 0)
				(type default)
			)
			(fill no)
			(layer "F.CrtYd")
		)
		(fp_line
			(start 0.3048 -0.1016)
			(end -0.3048 -0.1016)
			(stroke
				(width 0.1)
				(type default)
			)
			(layer "F.Fab")
		)
		(fp_line
			(start -0.3048 -0.1016)
			(end -0.3048 0.9906)
			(stroke
				(width 0.1)
				(type default)
			)
			(layer "F.Fab")
		)
		(fp_line
			(start 0.3048 0.9906)
			(end 0.3048 -0.1016)
			(stroke
				(width 0.1)
				(type default)
			)
			(layer "F.Fab")
		)
		(fp_line
			(start -0.3048 0.9906)
			(end 0.3048 0.9906)
			(stroke
				(width 0.1)
				(type default)
			)
			(layer "F.Fab")
		)
		(pad "1" smd rect
			(at 0 0 90)
			(size 0.508 0.508)
			(layers "F.Cu" "F.Mask" "F.Paste")
			(net "DMI_CPU0_PCH_TX_DP<0>")
		)
		(pad "2" smd rect
			(at 0 0.889 90)
			(size 0.508 0.508)
			(layers "F.Cu" "F.Mask" "F.Paste")
			(net "DMI_CPU0_PCH_TX_C_DP<0>")
		)
		(zone
			(layer "F.Cu")
			(hatch none 0.5)
			(connect_pads
				(clearance 0)
			)
			(min_thickness 0.25)
			(keepout
				(tracks allowed)
				(vias not_allowed)
				(pads allowed)
				(copperpour not_allowed)
				(footprints allowed)
			)
			(placement
				(enabled no)
				(sheetname "")
			)
			(fill
				(thermal_gap 0.5)
				(thermal_bridge_width 0.5)
				(island_removal_mode 0)
			)
			(polygon
				(pts
					(xy 368.808 -110.744) (xy 368.808 -111.252) (xy 369.189 -111.252) (xy 369.189 -110.744)
				)
			)
		)
		(zone
			(layer "F.Cu")
			(hatch none 0.5)
			(connect_pads
				(clearance 0)
			)
			(min_thickness 0.25)
			(keepout
				(tracks not_allowed)
				(vias allowed)
				(pads allowed)
				(copperpour not_allowed)
				(footprints allowed)
			)
			(placement
				(enabled no)
				(sheetname "")
			)
			(fill
				(thermal_gap 0.5)
				(thermal_bridge_width 0.5)
				(island_removal_mode 0)
			)
			(polygon
				(pts
					(xy 369.189 -110.744) (xy 369.189 -111.252) (xy 368.808 -111.252) (xy 368.808 -110.744)
				)
			)
		)
	)
	(footprint ""
		(layer "F.Cu")
		(at 364.78464 -141.77137)
		(property "Reference" "R7A7"
			(at 0 0 0)
			(layer "F.SilkS")
			(hide yes)
			(effects
				(font
					(size 1.27 1.27)
				)
			)
		)
		(property "Value" ""
			(at 0 0 0)
			(layer "F.Fab")
			(effects
				(font
					(size 1.27 1.27)
				)
			)
		)
		(duplicate_pad_numbers_are_jumpers no)
		(fp_poly
			(pts
				(xy -0.2794 -0.1016) (xy 0.2794 -0.1016) (xy 0.2794 0.9906) (xy -0.2794 0.9906)
			)
			(stroke
				(width 0)
				(type default)
			)
			(fill no)
			(layer "F.CrtYd")
		)
		(fp_line
			(start -0.2794 -0.1016)
			(end -0.2794 0.9906)
			(stroke
				(width 0.1)
				(type default)
			)
			(layer "F.Fab")
		)
		(fp_line
			(start -0.2794 0.9906)
			(end 0.2794 0.9906)
			(stroke
				(width 0.1)
				(type default)
			)
			(layer "F.Fab")
		)
		(fp_line
			(start 0.2794 -0.1016)
			(end -0.2794 -0.1016)
			(stroke
				(width 0.1)
				(type default)
			)
			(layer "F.Fab")
		)
		(fp_line
			(start 0.2794 0.9906)
			(end 0.2794 -0.1016)
			(stroke
				(width 0.1)
				(type default)
			)
			(layer "F.Fab")
		)
		(pad "1" smd rect
			(at 0 0)
			(size 0.508 0.508)
			(layers "F.Cu" "F.Mask" "F.Paste")
			(net "VSENSE_PVDDQ_DEF_P")
		)
		(pad "2" smd rect
			(at 0 0.889)
			(size 0.508 0.508)
			(layers "F.Cu" "F.Mask" "F.Paste")
			(net "VR_PVDDQ_DEF_AVSP")
		)
		(zone
			(layer "F.Cu")
			(hatch none 0.5)
			(connect_pads
				(clearance 0)
			)
			(min_thickness 0.25)
			(keepout
				(tracks allowed)
				(vias not_allowed)
				(pads allowed)
				(copperpour not_allowed)
				(footprints allowed)
			)
			(placement
				(enabled no)
				(sheetname "")
			)
			(fill
				(thermal_gap 0.5)
				(thermal_bridge_width 0.5)
				(island_removal_mode 0)
			)
			(polygon
				(pts
					(xy 364.53064 -141.51737) (xy 365.03864 -141.51737) (xy 365.03864 -141.13637) (xy 364.53064 -141.13637)
				)
			)
		)
		(zone
			(layer "F.Cu")
			(hatch none 0.5)
			(connect_pads
				(clearance 0)
			)
			(min_thickness 0.25)
			(keepout
				(tracks not_allowed)
				(vias allowed)
				(pads allowed)
				(copperpour not_allowed)
				(footprints allowed)
			)
			(placement
				(enabled no)
				(sheetname "")
			)
			(fill
				(thermal_gap 0.5)
				(thermal_bridge_width 0.5)
				(island_removal_mode 0)
			)
			(polygon
				(pts
					(xy 364.53064 -141.13637) (xy 365.03864 -141.13637) (xy 365.03864 -141.51737) (xy 364.53064 -141.51737)
				)
			)
		)
	)
	(footprint ""
		(layer "F.Cu")
		(at 101.3968 -140.208 90)
		(property "Reference" "C2A14"
			(at 1.848866 0.752348 90)
			(unlocked yes)
			(layer "F.SilkS")
			(effects
				(font
					(size 1.27 0.9652)
					(thickness 0.1524)
				)
			)
		)
		(property "Value" ""
			(at 0 0 90)
			(layer "F.Fab")
			(effects
				(font
					(size 1.27 1.27)
				)
			)
		)
		(duplicate_pad_numbers_are_jumpers no)
		(fp_rect
			(start -0.500126 1.598422)
			(end 0.500126 -0.201422)
			(stroke
				(width 0)
				(type default)
			)
			(fill no)
			(layer "F.CrtYd")
		)
		(fp_line
			(start 0.500126 -0.201422)
			(end 0.500126 1.598422)
			(stroke
				(width 0.1)
				(type default)
			)
			(layer "F.Fab")
		)
		(fp_line
			(start -0.500126 -0.201422)
			(end 0.500126 -0.201422)
			(stroke
				(width 0.1)
				(type default)
			)
			(layer "F.Fab")
		)
		(fp_line
			(start 0.500126 1.598422)
			(end -0.500126 1.598422)
			(stroke
				(width 0.1)
				(type default)
			)
			(layer "F.Fab")
		)
		(fp_line
			(start -0.500126 1.598422)
			(end -0.500126 -0.201422)
			(stroke
				(width 0.1)
				(type default)
			)
			(layer "F.Fab")
		)
		(pad "1" smd rect
			(at 0 0)
			(size 0.889 0.9906)
			(layers "F.Cu" "F.Mask" "F.Paste")
			(net "PVDDQ_KLM")
		)
		(pad "2" smd rect
			(at 0 1.397)
			(size 0.889 0.9906)
			(layers "F.Cu" "F.Mask" "F.Paste")
			(net "GND")
		)
		(zone
			(layer "F.Cu")
			(hatch none 0.5)
			(connect_pads
				(clearance 0)
			)
			(min_thickness 0.25)
			(keepout
				(tracks not_allowed)
				(vias allowed)
				(pads allowed)
				(copperpour not_allowed)
				(footprints allowed)
			)
			(placement
				(enabled no)
				(sheetname "")
			)
			(fill
				(thermal_gap 0.5)
				(thermal_bridge_width 0.5)
				(island_removal_mode 0)
			)
			(polygon
				(pts
					(xy 102.3493 -139.7127) (xy 102.3493 -140.7033) (xy 101.8413 -140.7033) (xy 101.8413 -139.7127)
				)
			)
		)
		(zone
			(layer "F.Cu")
			(hatch none 0.5)
			(connect_pads
				(clearance 0)
			)
			(min_thickness 0.25)
			(keepout
				(tracks allowed)
				(vias not_allowed)
				(pads allowed)
				(copperpour not_allowed)
				(footprints allowed)
			)
			(placement
				(enabled no)
				(sheetname "")
			)
			(fill
				(thermal_gap 0.5)
				(thermal_bridge_width 0.5)
				(island_removal_mode 0)
			)
			(polygon
				(pts
					(xy 102.3493 -139.7127) (xy 102.3493 -140.7033) (xy 101.8413 -140.7033) (xy 101.8413 -139.7127)
				)
			)
		)
	)
	(footprint ""
		(layer "F.Cu")
		(at 14.097 10.7315 -90)
		(property "Reference" "T1P26"
			(at 0 0 270)
			(layer "F.SilkS")
			(hide yes)
			(effects
				(font
					(size 1.27 1.27)
				)
			)
		)
		(property "Value" "*"
			(at 0 -3.44805 270)
			(unlocked yes)
			(layer "F.Fab")
			(hide yes)
			(effects
				(font
					(size 0.889 0.889)
					(thickness 0.1524)
				)
			)
		)
		(property "Device Type" "TPAD-SE-2P-GP_DISCRET-GA1-TPADA"
			(at 0 -4.97205 270)
			(unlocked yes)
			(layer "F.Fab")
			(hide yes)
			(effects
				(font
					(size 0.889 0.889)
					(thickness 0.1524)
				)
			)
		)
		(duplicate_pad_numbers_are_jumpers no)
		(fp_line
			(start -1.016 2.286)
			(end -1.016 -2.286)
			(stroke
				(width 0.1524)
				(type default)
			)
			(layer "F.SilkS")
		)
		(fp_line
			(start 1.016 2.286)
			(end -1.016 2.286)
			(stroke
				(width 0.1524)
				(type default)
			)
			(layer "F.SilkS")
		)
		(fp_line
			(start -1.016 -2.286)
			(end 1.016 -2.286)
			(stroke
				(width 0.1524)
				(type default)
			)
			(layer "F.SilkS")
		)
		(fp_line
			(start 1.016 -2.286)
			(end 1.016 2.286)
			(stroke
				(width 0.1524)
				(type default)
			)
			(layer "F.SilkS")
		)
		(fp_rect
			(start -1.27 2.54)
			(end 1.27 -2.54)
			(stroke
				(width 0)
				(type default)
			)
			(fill no)
			(layer "F.CrtYd")
		)
		(fp_rect
			(start -1.27 2.54)
			(end 1.27 -2.54)
			(stroke
				(width 0)
				(type default)
			)
			(fill no)
			(layer "F.Fab")
		)
		(pad "1" thru_hole circle
			(at 0 -1.27 270)
			(size 1.524 1.524)
			(drill 0.9144)
			(layers "*.Cu" "*.Mask")
			(remove_unused_layers no)
			(net "L3_40OHM_6INCH")
			(clearance -0.0508)
			(thermal_gap 0.127)
			(padstack
				(mode front_inner_back)
				(layer "Inner"
					(shape circle)
					(size 1.1684 1.1684)
					(clearance 0.127)
				)
				(layer "B.Cu"
					(shape circle)
					(size 1.524 1.524)
					(clearance -0.0508)
				)
			)
		)
		(pad "GND1" thru_hole rect
			(at 0 1.27 270)
			(size 1.524 1.524)
			(drill 0.9144)
			(layers "*.Cu" "*.Mask")
			(remove_unused_layers no)
			(net "GND")
			(clearance -0.0508)
			(thermal_gap 0.127)
			(padstack
				(mode front_inner_back)
				(layer "Inner"
					(shape circle)
					(size 1.1684 1.1684)
					(clearance 0.127)
				)
				(layer "B.Cu"
					(shape rect)
					(size 1.524 1.524)
					(clearance -0.0508)
				)
			)
		)
	)
	(footprint ""
		(layer "F.Cu")
		(at 40.036496 -57.031382)
		(property "Reference" "L1E1"
			(at 3.378708 -4.251706 0)
			(unlocked yes)
			(layer "F.SilkS")
			(effects
				(font
					(size 0.4064 0.254)
					(thickness 0.1524)
				)
			)
		)
		(property "Value" ""
			(at 0 0 0)
			(layer "F.Fab")
			(effects
				(font
					(size 1.27 1.27)
				)
			)
		)
		(duplicate_pad_numbers_are_jumpers no)
		(fp_line
			(start -1.1303 -3.199892)
			(end 8.3693 -3.199892)
			(stroke
				(width 0.1524)
				(type default)
			)
			(layer "F.SilkS")
		)
		(fp_line
			(start -1.1303 -1.6637)
			(end -1.1303 -3.199892)
			(stroke
				(width 0.1524)
				(type default)
			)
			(layer "F.SilkS")
		)
		(fp_line
			(start -1.1303 3.199892)
			(end -1.1303 1.6637)
			(stroke
				(width 0.1524)
				(type default)
			)
			(layer "F.SilkS")
		)
		(fp_line
			(start 8.3693 -3.199892)
			(end 8.3693 -1.6637)
			(stroke
				(width 0.1524)
				(type default)
			)
			(layer "F.SilkS")
		)
		(fp_line
			(start 8.3693 1.6637)
			(end 8.3693 3.199892)
			(stroke
				(width 0.1524)
				(type default)
			)
			(layer "F.SilkS")
		)
		(fp_line
			(start 8.3693 3.199892)
			(end -1.1303 3.199892)
			(stroke
				(width 0.1524)
				(type default)
			)
			(layer "F.SilkS")
		)
		(fp_rect
			(start -1.1303 3.199892)
			(end 8.3693 -3.199892)
			(stroke
				(width 0)
				(type default)
			)
			(fill no)
			(layer "F.CrtYd")
		)
		(fp_line
			(start -1.1303 -3.199892)
			(end 8.3693 -3.199892)
			(stroke
				(width 0.1)
				(type default)
			)
			(layer "F.Fab")
		)
		(fp_line
			(start -1.1303 3.199892)
			(end -1.1303 -3.199892)
			(stroke
				(width 0.1)
				(type default)
			)
			(layer "F.Fab")
		)
		(fp_line
			(start 8.3693 -3.199892)
			(end 8.3693 3.199892)
			(stroke
				(width 0.1)
				(type default)
			)
			(layer "F.Fab")
		)
		(fp_line
			(start 8.3693 3.199892)
			(end -1.1303 3.199892)
			(stroke
				(width 0.1)
				(type default)
			)
			(layer "F.Fab")
		)
		(pad "1" smd rect
			(at 0 0)
			(size 3.683 2.667)
			(layers "F.Cu" "F.Mask" "F.Paste")
			(net "VR_PVCCIN_CPU1_PHASE1")
		)
		(pad "2" smd rect
			(at 7.239 0)
			(size 3.683 2.667)
			(layers "F.Cu" "F.Mask" "F.Paste")
			(net "PVCCIN_CPU1")
		)
	)
	(footprint ""
		(layer "F.Cu")
		(at 172.466 -86.868 180)
		(property "Reference" "R4D7"
			(at 0 0 180)
			(layer "F.SilkS")
			(hide yes)
			(effects
				(font
					(size 1.27 1.27)
				)
			)
		)
		(property "Value" ""
			(at 0 0 180)
			(layer "F.Fab")
			(effects
				(font
					(size 1.27 1.27)
				)
			)
		)
		(duplicate_pad_numbers_are_jumpers no)
		(fp_poly
			(pts
				(xy -0.2794 -0.1016) (xy 0.2794 -0.1016) (xy 0.2794 0.9906) (xy -0.2794 0.9906)
			)
			(stroke
				(width 0)
				(type default)
			)
			(fill no)
			(layer "F.CrtYd")
		)
		(fp_line
			(start 0.2794 0.9906)
			(end 0.2794 -0.1016)
			(stroke
				(width 0.1)
				(type default)
			)
			(layer "F.Fab")
		)
		(fp_line
			(start 0.2794 -0.1016)
			(end -0.2794 -0.1016)
			(stroke
				(width 0.1)
				(type default)
			)
			(layer "F.Fab")
		)
		(fp_line
			(start -0.2794 0.9906)
			(end 0.2794 0.9906)
			(stroke
				(width 0.1)
				(type default)
			)
			(layer "F.Fab")
		)
		(fp_line
			(start -0.2794 -0.1016)
			(end -0.2794 0.9906)
			(stroke
				(width 0.1)
				(type default)
			)
			(layer "F.Fab")
		)
		(pad "1" smd rect
			(at 0 0 180)
			(size 0.508 0.508)
			(layers "F.Cu" "F.Mask" "F.Paste")
			(net "CLK_100M_CPU0_RC_REFCLK0_R_DN")
		)
		(pad "2" smd rect
			(at 0 0.889 180)
			(size 0.508 0.508)
			(layers "F.Cu" "F.Mask" "F.Paste")
			(net "CLK_100M_CPU0_RC_REFCLK0_DN")
		)
		(zone
			(layer "F.Cu")
			(hatch none 0.5)
			(connect_pads
				(clearance 0)
			)
			(min_thickness 0.25)
			(keepout
				(tracks not_allowed)
				(vias allowed)
				(pads allowed)
				(copperpour not_allowed)
				(footprints allowed)
			)
			(placement
				(enabled no)
				(sheetname "")
			)
			(fill
				(thermal_gap 0.5)
				(thermal_bridge_width 0.5)
				(island_removal_mode 0)
			)
			(polygon
				(pts
					(xy 172.72 -87.503) (xy 172.212 -87.503) (xy 172.212 -87.122) (xy 172.72 -87.122)
				)
			)
		)
		(zone
			(layer "F.Cu")
			(hatch none 0.5)
			(connect_pads
				(clearance 0)
			)
			(min_thickness 0.25)
			(keepout
				(tracks allowed)
				(vias not_allowed)
				(pads allowed)
				(copperpour not_allowed)
				(footprints allowed)
			)
			(placement
				(enabled no)
				(sheetname "")
			)
			(fill
				(thermal_gap 0.5)
				(thermal_bridge_width 0.5)
				(island_removal_mode 0)
			)
			(polygon
				(pts
					(xy 172.72 -87.122) (xy 172.212 -87.122) (xy 172.212 -87.503) (xy 172.72 -87.503)
				)
			)
		)
	)
	(footprint ""
		(layer "F.Cu")
		(at 369.062 -96.8375)
		(property "Reference" "C7C15"
			(at 0 0 0)
			(layer "F.SilkS")
			(hide yes)
			(effects
				(font
					(size 1.27 1.27)
				)
			)
		)
		(property "Value" ""
			(at 0 0 0)
			(layer "F.Fab")
			(effects
				(font
					(size 1.27 1.27)
				)
			)
		)
		(duplicate_pad_numbers_are_jumpers no)
		(fp_poly
			(pts
				(xy 0.3048 -0.1016) (xy 0.3048 0.9906) (xy -0.3048 0.9906) (xy -0.3048 -0.1016)
			)
			(stroke
				(width 0)
				(type default)
			)
			(fill no)
			(layer "F.CrtYd")
		)
		(fp_line
			(start -0.3048 -0.1016)
			(end -0.3048 0.9906)
			(stroke
				(width 0.1)
				(type default)
			)
			(layer "F.Fab")
		)
		(fp_line
			(start -0.3048 0.9906)
			(end 0.3048 0.9906)
			(stroke
				(width 0.1)
				(type default)
			)
			(layer "F.Fab")
		)
		(fp_line
			(start 0.3048 -0.1016)
			(end -0.3048 -0.1016)
			(stroke
				(width 0.1)
				(type default)
			)
			(layer "F.Fab")
		)
		(fp_line
			(start 0.3048 0.9906)
			(end 0.3048 -0.1016)
			(stroke
				(width 0.1)
				(type default)
			)
			(layer "F.Fab")
		)
		(pad "1" smd rect
			(at 0 0)
			(size 0.508 0.508)
			(layers "F.Cu" "F.Mask" "F.Paste")
			(net "XTAL_33K_RTC2")
		)
		(pad "2" smd rect
			(at 0 0.889)
			(size 0.508 0.508)
			(layers "F.Cu" "F.Mask" "F.Paste")
			(net "GND")
		)
		(zone
			(layer "F.Cu")
			(hatch none 0.5)
			(connect_pads
				(clearance 0)
			)
			(min_thickness 0.25)
			(keepout
				(tracks allowed)
				(vias not_allowed)
				(pads allowed)
				(copperpour not_allowed)
				(footprints allowed)
			)
			(placement
				(enabled no)
				(sheetname "")
			)
			(fill
				(thermal_gap 0.5)
				(thermal_bridge_width 0.5)
				(island_removal_mode 0)
			)
			(polygon
				(pts
					(xy 368.808 -96.5835) (xy 369.316 -96.5835) (xy 369.316 -96.2025) (xy 368.808 -96.2025)
				)
			)
		)
		(zone
			(layer "F.Cu")
			(hatch none 0.5)
			(connect_pads
				(clearance 0)
			)
			(min_thickness 0.25)
			(keepout
				(tracks not_allowed)
				(vias allowed)
				(pads allowed)
				(copperpour not_allowed)
				(footprints allowed)
			)
			(placement
				(enabled no)
				(sheetname "")
			)
			(fill
				(thermal_gap 0.5)
				(thermal_bridge_width 0.5)
				(island_removal_mode 0)
			)
			(polygon
				(pts
					(xy 368.808 -96.2025) (xy 369.316 -96.2025) (xy 369.316 -96.5835) (xy 368.808 -96.5835)
				)
			)
		)
	)
	(footprint ""
		(layer "F.Cu")
		(at 13.7541 -152.3111 -90)
		(property "Reference" "C1A1"
			(at 0 0 270)
			(layer "F.SilkS")
			(hide yes)
			(effects
				(font
					(size 1.27 1.27)
				)
			)
		)
		(property "Value" ""
			(at 0 0 270)
			(layer "F.Fab")
			(effects
				(font
					(size 1.27 1.27)
				)
			)
		)
		(duplicate_pad_numbers_are_jumpers no)
		(fp_poly
			(pts
				(xy -0.7239 -0.2159) (xy 0.7239 -0.2159) (xy 0.7239 1.9939) (xy -0.7239 1.9939)
			)
			(stroke
				(width 0)
				(type default)
			)
			(fill no)
			(layer "F.CrtYd")
		)
		(fp_line
			(start -0.7239 1.9939)
			(end 0.7239 1.9939)
			(stroke
				(width 0.1)
				(type default)
			)
			(layer "F.Fab")
		)
		(fp_line
			(start 0.7239 1.9939)
			(end 0.7239 -0.2159)
			(stroke
				(width 0.1)
				(type default)
			)
			(layer "F.Fab")
		)
		(fp_line
			(start -0.7239 -0.2159)
			(end -0.7239 1.9939)
			(stroke
				(width 0.1)
				(type default)
			)
			(layer "F.Fab")
		)
		(fp_line
			(start 0.7239 -0.2159)
			(end -0.7239 -0.2159)
			(stroke
				(width 0.1)
				(type default)
			)
			(layer "F.Fab")
		)
		(pad "1" smd rect
			(at 0 0 270)
			(size 1.27 1.016)
			(layers "F.Cu" "F.Mask" "F.Paste")
			(net "PVDDQ_KLM")
		)
		(pad "2" smd rect
			(at 0 1.778 270)
			(size 1.27 1.016)
			(layers "F.Cu" "F.Mask" "F.Paste")
			(net "GND")
		)
		(zone
			(layer "F.Cu")
			(hatch none 0.5)
			(connect_pads
				(clearance 0)
			)
			(min_thickness 0.25)
			(keepout
				(tracks not_allowed)
				(vias allowed)
				(pads allowed)
				(copperpour not_allowed)
				(footprints allowed)
			)
			(placement
				(enabled no)
				(sheetname "")
			)
			(fill
				(thermal_gap 0.5)
				(thermal_bridge_width 0.5)
				(island_removal_mode 0)
			)
			(polygon
				(pts
					(xy 13.2461 -152.9461) (xy 13.2461 -151.6761) (xy 12.4841 -151.6761) (xy 12.4841 -152.9461)
				)
			)
		)
	)
	(footprint ""
		(layer "F.Cu")
		(at 382.131062 -76.019406 180)
		(property "Reference" "R2T44"
			(at 0 0 180)
			(layer "F.SilkS")
			(hide yes)
			(effects
				(font
					(size 1.27 1.27)
				)
			)
		)
		(property "Value" ""
			(at 0 0 180)
			(layer "F.Fab")
			(effects
				(font
					(size 1.27 1.27)
				)
			)
		)
		(duplicate_pad_numbers_are_jumpers no)
		(fp_poly
			(pts
				(xy -0.2794 -0.1016) (xy 0.2794 -0.1016) (xy 0.2794 0.9906) (xy -0.2794 0.9906)
			)
			(stroke
				(width 0)
				(type default)
			)
			(fill no)
			(layer "F.CrtYd")
		)
		(fp_line
			(start 0.2794 0.9906)
			(end 0.2794 -0.1016)
			(stroke
				(width 0.1)
				(type default)
			)
			(layer "F.Fab")
		)
		(fp_line
			(start 0.2794 -0.1016)
			(end -0.2794 -0.1016)
			(stroke
				(width 0.1)
				(type default)
			)
			(layer "F.Fab")
		)
		(fp_line
			(start -0.2794 0.9906)
			(end 0.2794 0.9906)
			(stroke
				(width 0.1)
				(type default)
			)
			(layer "F.Fab")
		)
		(fp_line
			(start -0.2794 -0.1016)
			(end -0.2794 0.9906)
			(stroke
				(width 0.1)
				(type default)
			)
			(layer "F.Fab")
		)
		(pad "1" smd rect
			(at 0 0 180)
			(size 0.508 0.508)
			(layers "F.Cu" "F.Mask" "F.Paste")
			(net "H_CPU1_ERR2_G_N")
		)
		(pad "2" smd rect
			(at 0 0.889 180)
			(size 0.508 0.508)
			(layers "F.Cu" "F.Mask" "F.Paste")
			(net "H_CPU_ERR2_G_R_N")
		)
		(zone
			(layer "F.Cu")
			(hatch none 0.5)
			(connect_pads
				(clearance 0)
			)
			(min_thickness 0.25)
			(keepout
				(tracks not_allowed)
				(vias allowed)
				(pads allowed)
				(copperpour not_allowed)
				(footprints allowed)
			)
			(placement
				(enabled no)
				(sheetname "")
			)
			(fill
				(thermal_gap 0.5)
				(thermal_bridge_width 0.5)
				(island_removal_mode 0)
			)
			(polygon
				(pts
					(xy 382.385062 -76.654406) (xy 381.877062 -76.654406) (xy 381.877062 -76.273406) (xy 382.385062 -76.273406)
				)
			)
		)
		(zone
			(layer "F.Cu")
			(hatch none 0.5)
			(connect_pads
				(clearance 0)
			)
			(min_thickness 0.25)
			(keepout
				(tracks allowed)
				(vias not_allowed)
				(pads allowed)
				(copperpour not_allowed)
				(footprints allowed)
			)
			(placement
				(enabled no)
				(sheetname "")
			)
			(fill
				(thermal_gap 0.5)
				(thermal_bridge_width 0.5)
				(island_removal_mode 0)
			)
			(polygon
				(pts
					(xy 382.385062 -76.273406) (xy 381.877062 -76.273406) (xy 381.877062 -76.654406) (xy 382.385062 -76.654406)
				)
			)
		)
	)
	(footprint ""
		(layer "F.Cu")
		(at 349.2246 -149.112224 90)
		(property "Reference" "C7A24"
			(at 0 0 90)
			(layer "F.SilkS")
			(hide yes)
			(effects
				(font
					(size 1.27 1.27)
				)
			)
		)
		(property "Value" ""
			(at 0 0 90)
			(layer "F.Fab")
			(effects
				(font
					(size 1.27 1.27)
				)
			)
		)
		(duplicate_pad_numbers_are_jumpers no)
		(fp_poly
			(pts
				(xy 0.3048 -0.1016) (xy 0.3048 0.9906) (xy -0.3048 0.9906) (xy -0.3048 -0.1016)
			)
			(stroke
				(width 0)
				(type default)
			)
			(fill no)
			(layer "F.CrtYd")
		)
		(fp_line
			(start 0.3048 -0.1016)
			(end -0.3048 -0.1016)
			(stroke
				(width 0.1)
				(type default)
			)
			(layer "F.Fab")
		)
		(fp_line
			(start -0.3048 -0.1016)
			(end -0.3048 0.9906)
			(stroke
				(width 0.1)
				(type default)
			)
			(layer "F.Fab")
		)
		(fp_line
			(start 0.3048 0.9906)
			(end 0.3048 -0.1016)
			(stroke
				(width 0.1)
				(type default)
			)
			(layer "F.Fab")
		)
		(fp_line
			(start -0.3048 0.9906)
			(end 0.3048 0.9906)
			(stroke
				(width 0.1)
				(type default)
			)
			(layer "F.Fab")
		)
		(pad "1" smd rect
			(at 0 0 90)
			(size 0.508 0.508)
			(layers "F.Cu" "F.Mask" "F.Paste")
			(net "VR_PVDDQ_DEF_PH2_VCIN")
		)
		(pad "2" smd rect
			(at 0 0.889 90)
			(size 0.508 0.508)
			(layers "F.Cu" "F.Mask" "F.Paste")
			(net "GND")
		)
		(zone
			(layer "F.Cu")
			(hatch none 0.5)
			(connect_pads
				(clearance 0)
			)
			(min_thickness 0.25)
			(keepout
				(tracks allowed)
				(vias not_allowed)
				(pads allowed)
				(copperpour not_allowed)
				(footprints allowed)
			)
			(placement
				(enabled no)
				(sheetname "")
			)
			(fill
				(thermal_gap 0.5)
				(thermal_bridge_width 0.5)
				(island_removal_mode 0)
			)
			(polygon
				(pts
					(xy 349.4786 -148.858224) (xy 349.4786 -149.366224) (xy 349.8596 -149.366224) (xy 349.8596 -148.858224)
				)
			)
		)
		(zone
			(layer "F.Cu")
			(hatch none 0.5)
			(connect_pads
				(clearance 0)
			)
			(min_thickness 0.25)
			(keepout
				(tracks not_allowed)
				(vias allowed)
				(pads allowed)
				(copperpour not_allowed)
				(footprints allowed)
			)
			(placement
				(enabled no)
				(sheetname "")
			)
			(fill
				(thermal_gap 0.5)
				(thermal_bridge_width 0.5)
				(island_removal_mode 0)
			)
			(polygon
				(pts
					(xy 349.8596 -148.858224) (xy 349.8596 -149.366224) (xy 349.4786 -149.366224) (xy 349.4786 -148.858224)
				)
			)
		)
	)
	(footprint ""
		(layer "F.Cu")
		(at 108.9025 -164.973 -90)
		(property "Reference" "T1D7"
			(at 0 0 270)
			(layer "F.SilkS")
			(hide yes)
			(effects
				(font
					(size 1.27 1.27)
				)
			)
		)
		(property "Value" "*"
			(at -3.4036 -4.46405 270)
			(unlocked yes)
			(layer "F.Fab")
			(hide yes)
			(effects
				(font
					(size 0.889 0.889)
					(thickness 0.1524)
				)
			)
		)
		(property "Device Type" "TEST-PAD-12P-1-GP-U_DISCRET-GBA"
			(at -3.4036 -5.98805 270)
			(unlocked yes)
			(layer "F.Fab")
			(hide yes)
			(effects
				(font
					(size 0.889 0.889)
					(thickness 0.1524)
				)
			)
		)
		(duplicate_pad_numbers_are_jumpers no)
		(fp_line
			(start -2.3876 3.4798)
			(end -2.3876 -4.826)
			(stroke
				(width 0.1524)
				(type default)
			)
			(layer "F.SilkS")
		)
		(fp_line
			(start 2.3622 3.4798)
			(end -2.3876 3.4798)
			(stroke
				(width 0.1524)
				(type default)
			)
			(layer "F.SilkS")
		)
		(fp_line
			(start -2.3876 -4.826)
			(end 2.3622 -4.826)
			(stroke
				(width 0.1524)
				(type default)
			)
			(layer "F.SilkS")
		)
		(fp_line
			(start 2.3622 -4.826)
			(end 2.3622 3.4798)
			(stroke
				(width 0.1524)
				(type default)
			)
			(layer "F.SilkS")
		)
		(fp_rect
			(start -2.6416 3.7338)
			(end 2.6162 -5.08)
			(stroke
				(width 0)
				(type default)
			)
			(fill no)
			(layer "F.CrtYd")
		)
		(fp_rect
			(start -2.6416 3.7338)
			(end 2.6162 -5.08)
			(stroke
				(width 0)
				(type default)
			)
			(fill no)
			(layer "F.Fab")
		)
		(pad "1" smd circle
			(at 0.496824 -1.301496 270)
			(size 0.6604 0.6604)
			(layers "F.Cu" "F.Mask" "F.Paste")
			(net "L10_85OHM_5INCH_DP")
		)
		(pad "2" smd circle
			(at -0.503936 -1.301496 270)
			(size 0.6604 0.6604)
			(layers "F.Cu" "F.Mask" "F.Paste")
			(net "L10_85OHM_5INCH_DN")
		)
		(pad "3" smd custom
			(at -0.00889 0.370078 270)
			(size 0.74295 0.74295)
			(layers "F.Cu" "F.Mask" "F.Paste")
			(net "GND")
			(options
				(clearance outline)
				(anchor circle)
			)
			(primitives
				(gr_poly
					(pts
						(xy -2.1209 1.4859) (xy 2.1209 1.4859) (xy 2.1209 -1.4859) (xy 1.08585 -1.4859) (xy 1.08585 -0.4699)
						(xy -1.08585 -0.4699) (xy -1.08585 -1.4859) (xy -2.1209 -1.4859)
					)
					(width 0)
					(fill yes)
				)
			)
		)
		(pad "4" thru_hole circle
			(at 1.266444 -3.851656 270)
			(size 1.4478 1.4478)
			(drill 1.0414)
			(layers "*.Cu" "*.Mask")
			(remove_unused_layers no)
			(net "GND")
			(clearance 0.1524)
			(thermal_gap 0.1524)
		)
		(pad "5" thru_hole circle
			(at -1.273556 -3.851656 270)
			(size 1.4478 1.4478)
			(drill 1.0414)
			(layers "*.Cu" "*.Mask")
			(remove_unused_layers no)
			(net "GND")
			(clearance 0.1524)
			(thermal_gap 0.1524)
		)
		(pad "6" thru_hole circle
			(at 1.266444 2.498344 270)
			(size 1.4478 1.4478)
			(drill 1.0414)
			(layers "*.Cu" "*.Mask")
			(remove_unused_layers no)
			(net "GND")
			(clearance 0.1524)
			(thermal_gap 0.1524)
		)
		(pad "7" thru_hole circle
			(at -1.273556 2.498344 270)
			(size 1.4478 1.4478)
			(drill 1.0414)
			(layers "*.Cu" "*.Mask")
			(remove_unused_layers no)
			(net "GND")
			(clearance 0.1524)
			(thermal_gap 0.1524)
		)
		(pad "8" thru_hole circle
			(at 1.27 -0.4572 270)
			(size 0.7112 0.7112)
			(drill 0.4064)
			(layers "*.Cu" "*.Mask")
			(remove_unused_layers no)
			(net "GND")
			(clearance 0.1016)
			(thermal_gap 0.1016)
		)
		(pad "9" thru_hole circle
			(at 1.27 0.762 270)
			(size 0.7112 0.7112)
			(drill 0.4064)
			(layers "*.Cu" "*.Mask")
			(remove_unused_layers no)
			(net "GND")
			(clearance 0.1016)
			(thermal_gap 0.1016)
		)
		(pad "10" thru_hole circle
			(at -0.0254 0.762 270)
			(size 0.7112 0.7112)
			(drill 0.4064)
			(layers "*.Cu" "*.Mask")
			(remove_unused_layers no)
			(net "GND")
			(clearance 0.1016)
			(thermal_gap 0.1016)
		)
		(pad "11" thru_hole circle
			(at -1.27 0.762 270)
			(size 0.7112 0.7112)
			(drill 0.4064)
			(layers "*.Cu" "*.Mask")
			(remove_unused_layers no)
			(net "GND")
			(clearance 0.1016)
			(thermal_gap 0.1016)
		)
		(pad "12" thru_hole circle
			(at -1.27 -0.4572 270)
			(size 0.7112 0.7112)
			(drill 0.4064)
			(layers "*.Cu" "*.Mask")
			(remove_unused_layers no)
			(net "GND")
			(clearance 0.1016)
			(thermal_gap 0.1016)
		)
	)
	(footprint ""
		(layer "F.Cu")
		(at 372.550182 -149.543262 180)
		(property "Reference" "RT43"
			(at 0 0 180)
			(layer "F.SilkS")
			(hide yes)
			(effects
				(font
					(size 1.27 1.27)
				)
			)
		)
		(property "Value" "*"
			(at -0.0254 -2.6289 180)
			(unlocked yes)
			(layer "F.Fab")
			(hide yes)
			(effects
				(font
					(size 1.27 1.016)
					(thickness 0.1524)
				)
			)
		)
		(property "Device Type" "1R3F-GP_RCL_GP-1R3F-GP,64.1R00A"
			(at -0.0254 -4.1529 180)
			(unlocked yes)
			(layer "F.Fab")
			(hide yes)
			(effects
				(font
					(size 1.27 1.016)
					(thickness 0.1524)
				)
			)
		)
		(duplicate_pad_numbers_are_jumpers no)
		(fp_line
			(start 0.2032 0)
			(end 0.4826 0)
			(stroke
				(width 0.2032)
				(type default)
			)
			(layer "F.SilkS")
		)
		(fp_line
			(start -0.4826 0)
			(end -0.2032 0)
			(stroke
				(width 0.2032)
				(type default)
			)
			(layer "F.SilkS")
		)
		(fp_rect
			(start -0.5842 1.3335)
			(end 0.5842 -1.3335)
			(stroke
				(width 0)
				(type default)
			)
			(fill no)
			(layer "F.CrtYd")
		)
		(fp_rect
			(start -0.5842 1.3335)
			(end 0.5842 -1.3335)
			(stroke
				(width 0)
				(type default)
			)
			(fill no)
			(layer "F.Fab")
		)
		(pad "1" smd custom
			(at 0 -0.762 180)
			(size 0.2159 0.2159)
			(layers "F.Cu" "F.Mask" "F.Paste")
			(net "VR_PVNN_PCH_PH1_PHASE_SW_RC")
			(options
				(clearance outline)
				(anchor circle)
			)
			(primitives
				(gr_poly
					(pts
						(arc
							(start -0.3302 -0.4318)
							(mid -0.402042 -0.402042)
							(end -0.4318 -0.3302)
						)
						(arc
							(start -0.4318 0.3302)
							(mid -0.402042 0.402042)
							(end -0.3302 0.4318)
						)
						(arc
							(start 0.3302 0.4318)
							(mid 0.402042 0.402042)
							(end 0.4318 0.3302)
						)
						(arc
							(start 0.4318 -0.3302)
							(mid 0.402042 -0.402042)
							(end 0.3302 -0.4318)
						)
					)
					(width 0)
					(fill yes)
				)
			)
		)
		(pad "2" smd custom
			(at 0 0.762 180)
			(size 0.2159 0.2159)
			(layers "F.Cu" "F.Mask" "F.Paste")
			(net "GND")
			(options
				(clearance outline)
				(anchor circle)
			)
			(primitives
				(gr_poly
					(pts
						(arc
							(start -0.3302 -0.4318)
							(mid -0.402042 -0.402042)
							(end -0.4318 -0.3302)
						)
						(arc
							(start -0.4318 0.3302)
							(mid -0.402042 0.402042)
							(end -0.3302 0.4318)
						)
						(arc
							(start 0.3302 0.4318)
							(mid 0.402042 0.402042)
							(end 0.4318 0.3302)
						)
						(arc
							(start 0.4318 -0.3302)
							(mid 0.402042 -0.402042)
							(end 0.3302 -0.4318)
						)
					)
					(width 0)
					(fill yes)
				)
			)
		)
	)
	(footprint ""
		(layer "F.Cu")
		(at 402.590254 -40.985948 90)
		(property "Reference" "R1T37"
			(at 0 0 90)
			(layer "F.SilkS")
			(hide yes)
			(effects
				(font
					(size 1.27 1.27)
				)
			)
		)
		(property "Value" ""
			(at 0 0 90)
			(layer "F.Fab")
			(effects
				(font
					(size 1.27 1.27)
				)
			)
		)
		(duplicate_pad_numbers_are_jumpers no)
		(fp_poly
			(pts
				(xy -0.2794 -0.1016) (xy 0.2794 -0.1016) (xy 0.2794 0.9906) (xy -0.2794 0.9906)
			)
			(stroke
				(width 0)
				(type default)
			)
			(fill no)
			(layer "F.CrtYd")
		)
		(fp_line
			(start 0.2794 -0.1016)
			(end -0.2794 -0.1016)
			(stroke
				(width 0.1)
				(type default)
			)
			(layer "F.Fab")
		)
		(fp_line
			(start -0.2794 -0.1016)
			(end -0.2794 0.9906)
			(stroke
				(width 0.1)
				(type default)
			)
			(layer "F.Fab")
		)
		(fp_line
			(start 0.2794 0.9906)
			(end 0.2794 -0.1016)
			(stroke
				(width 0.1)
				(type default)
			)
			(layer "F.Fab")
		)
		(fp_line
			(start -0.2794 0.9906)
			(end 0.2794 0.9906)
			(stroke
				(width 0.1)
				(type default)
			)
			(layer "F.Fab")
		)
		(pad "1" smd rect
			(at 0 0 90)
			(size 0.508 0.508)
			(layers "F.Cu" "F.Mask" "F.Paste")
			(net "FM_CPU1_PROCHOT_LVT3_N")
		)
		(pad "2" smd rect
			(at 0 0.889 90)
			(size 0.508 0.508)
			(layers "F.Cu" "F.Mask" "F.Paste")
			(net "FM_CPU1_PROCHOT_LVT3_BMC_N")
		)
		(zone
			(layer "F.Cu")
			(hatch none 0.5)
			(connect_pads
				(clearance 0)
			)
			(min_thickness 0.25)
			(keepout
				(tracks allowed)
				(vias not_allowed)
				(pads allowed)
				(copperpour not_allowed)
				(footprints allowed)
			)
			(placement
				(enabled no)
				(sheetname "")
			)
			(fill
				(thermal_gap 0.5)
				(thermal_bridge_width 0.5)
				(island_removal_mode 0)
			)
			(polygon
				(pts
					(xy 402.844254 -40.731948) (xy 402.844254 -41.239948) (xy 403.225254 -41.239948) (xy 403.225254 -40.731948)
				)
			)
		)
		(zone
			(layer "F.Cu")
			(hatch none 0.5)
			(connect_pads
				(clearance 0)
			)
			(min_thickness 0.25)
			(keepout
				(tracks not_allowed)
				(vias allowed)
				(pads allowed)
				(copperpour not_allowed)
				(footprints allowed)
			)
			(placement
				(enabled no)
				(sheetname "")
			)
			(fill
				(thermal_gap 0.5)
				(thermal_bridge_width 0.5)
				(island_removal_mode 0)
			)
			(polygon
				(pts
					(xy 403.225254 -40.731948) (xy 403.225254 -41.239948) (xy 402.844254 -41.239948) (xy 402.844254 -40.731948)
				)
			)
		)
	)
	(footprint ""
		(layer "F.Cu")
		(at 18.071592 -117.145054 90)
		(property "Reference" "R1B21"
			(at 0 0 90)
			(layer "F.SilkS")
			(hide yes)
			(effects
				(font
					(size 1.27 1.27)
				)
			)
		)
		(property "Value" ""
			(at 0 0 90)
			(layer "F.Fab")
			(effects
				(font
					(size 1.27 1.27)
				)
			)
		)
		(duplicate_pad_numbers_are_jumpers no)
		(fp_rect
			(start -0.2794 0.9906)
			(end 0.2794 -0.1016)
			(stroke
				(width 0)
				(type default)
			)
			(fill no)
			(layer "F.CrtYd")
		)
		(fp_line
			(start 0.2794 -0.1016)
			(end -0.2794 -0.1016)
			(stroke
				(width 0.1)
				(type default)
			)
			(layer "F.Fab")
		)
		(fp_line
			(start -0.2794 -0.1016)
			(end -0.2794 0.9906)
			(stroke
				(width 0.1)
				(type default)
			)
			(layer "F.Fab")
		)
		(fp_line
			(start 0.2794 0.9906)
			(end 0.2794 -0.1016)
			(stroke
				(width 0.1)
				(type default)
			)
			(layer "F.Fab")
		)
		(fp_line
			(start -0.2794 0.9906)
			(end 0.2794 0.9906)
			(stroke
				(width 0.1)
				(type default)
			)
			(layer "F.Fab")
		)
		(pad "1" smd rect
			(at 0 0 90)
			(size 0.508 0.508)
			(layers "F.Cu" "F.Mask" "F.Paste")
			(net "P3V3_STBY")
		)
		(pad "2" smd rect
			(at 0 0.889 90)
			(size 0.508 0.508)
			(layers "F.Cu" "F.Mask" "F.Paste")
			(net "FAN_TACH2")
		)
		(zone
			(layer "F.Cu")
			(hatch none 0.5)
			(connect_pads
				(clearance 0)
			)
			(min_thickness 0.25)
			(keepout
				(tracks allowed)
				(vias not_allowed)
				(pads allowed)
				(copperpour not_allowed)
				(footprints allowed)
			)
			(placement
				(enabled no)
				(sheetname "")
			)
			(fill
				(thermal_gap 0.5)
				(thermal_bridge_width 0.5)
				(island_removal_mode 0)
			)
			(polygon
				(pts
					(xy 18.706592 -116.891054) (xy 18.706592 -117.399054) (xy 18.325592 -117.399054) (xy 18.325592 -116.891054)
				)
			)
		)
		(zone
			(layer "F.Cu")
			(hatch none 0.5)
			(connect_pads
				(clearance 0)
			)
			(min_thickness 0.25)
			(keepout
				(tracks not_allowed)
				(vias allowed)
				(pads allowed)
				(copperpour not_allowed)
				(footprints allowed)
			)
			(placement
				(enabled no)
				(sheetname "")
			)
			(fill
				(thermal_gap 0.5)
				(thermal_bridge_width 0.5)
				(island_removal_mode 0)
			)
			(polygon
				(pts
					(xy 18.706592 -116.891054) (xy 18.706592 -117.399054) (xy 18.325592 -117.399054) (xy 18.325592 -116.891054)
				)
			)
		)
	)
	(footprint ""
		(layer "F.Cu")
		(at 384.422904 -76.915264)
		(property "Reference" "R2T43"
			(at 0 0 0)
			(layer "F.SilkS")
			(hide yes)
			(effects
				(font
					(size 1.27 1.27)
				)
			)
		)
		(property "Value" ""
			(at 0 0 0)
			(layer "F.Fab")
			(effects
				(font
					(size 1.27 1.27)
				)
			)
		)
		(duplicate_pad_numbers_are_jumpers no)
		(fp_poly
			(pts
				(xy -0.2794 -0.1016) (xy 0.2794 -0.1016) (xy 0.2794 0.9906) (xy -0.2794 0.9906)
			)
			(stroke
				(width 0)
				(type default)
			)
			(fill no)
			(layer "F.CrtYd")
		)
		(fp_line
			(start -0.2794 -0.1016)
			(end -0.2794 0.9906)
			(stroke
				(width 0.1)
				(type default)
			)
			(layer "F.Fab")
		)
		(fp_line
			(start -0.2794 0.9906)
			(end 0.2794 0.9906)
			(stroke
				(width 0.1)
				(type default)
			)
			(layer "F.Fab")
		)
		(fp_line
			(start 0.2794 -0.1016)
			(end -0.2794 -0.1016)
			(stroke
				(width 0.1)
				(type default)
			)
			(layer "F.Fab")
		)
		(fp_line
			(start 0.2794 0.9906)
			(end 0.2794 -0.1016)
			(stroke
				(width 0.1)
				(type default)
			)
			(layer "F.Fab")
		)
		(pad "1" smd rect
			(at 0 0)
			(size 0.508 0.508)
			(layers "F.Cu" "F.Mask" "F.Paste")
			(net "H_CPU_ERR2_G_R_N")
		)
		(pad "2" smd rect
			(at 0 0.889)
			(size 0.508 0.508)
			(layers "F.Cu" "F.Mask" "F.Paste")
			(net "H_CPU_ERR2_GTL_N")
		)
		(zone
			(layer "F.Cu")
			(hatch none 0.5)
			(connect_pads
				(clearance 0)
			)
			(min_thickness 0.25)
			(keepout
				(tracks allowed)
				(vias not_allowed)
				(pads allowed)
				(copperpour not_allowed)
				(footprints allowed)
			)
			(placement
				(enabled no)
				(sheetname "")
			)
			(fill
				(thermal_gap 0.5)
				(thermal_bridge_width 0.5)
				(island_removal_mode 0)
			)
			(polygon
				(pts
					(xy 384.168904 -76.661264) (xy 384.676904 -76.661264) (xy 384.676904 -76.280264) (xy 384.168904 -76.280264)
				)
			)
		)
		(zone
			(layer "F.Cu")
			(hatch none 0.5)
			(connect_pads
				(clearance 0)
			)
			(min_thickness 0.25)
			(keepout
				(tracks not_allowed)
				(vias allowed)
				(pads allowed)
				(copperpour not_allowed)
				(footprints allowed)
			)
			(placement
				(enabled no)
				(sheetname "")
			)
			(fill
				(thermal_gap 0.5)
				(thermal_bridge_width 0.5)
				(island_removal_mode 0)
			)
			(polygon
				(pts
					(xy 384.168904 -76.280264) (xy 384.676904 -76.280264) (xy 384.676904 -76.661264) (xy 384.168904 -76.661264)
				)
			)
		)
	)
	(footprint ""
		(layer "F.Cu")
		(at 264.431272 -77.636116)
		(property "Reference" "C5D29"
			(at 0 0 0)
			(layer "F.SilkS")
			(hide yes)
			(effects
				(font
					(size 1.27 1.27)
				)
			)
		)
		(property "Value" ""
			(at 0 0 0)
			(layer "F.Fab")
			(effects
				(font
					(size 1.27 1.27)
				)
			)
		)
		(duplicate_pad_numbers_are_jumpers no)
		(fp_poly
			(pts
				(xy -0.4953 -0.2032) (xy 0.4953 -0.2032) (xy 0.4953 1.6002) (xy -0.4953 1.6002)
			)
			(stroke
				(width 0)
				(type default)
			)
			(fill no)
			(layer "F.CrtYd")
		)
		(fp_line
			(start -0.4953 -0.2032)
			(end 0.4953 -0.2032)
			(stroke
				(width 0.1)
				(type default)
			)
			(layer "F.Fab")
		)
		(fp_line
			(start -0.4953 1.6002)
			(end -0.4953 -0.2032)
			(stroke
				(width 0.1)
				(type default)
			)
			(layer "F.Fab")
		)
		(fp_line
			(start 0.4953 -0.2032)
			(end 0.4953 1.6002)
			(stroke
				(width 0.1)
				(type default)
			)
			(layer "F.Fab")
		)
		(fp_line
			(start 0.4953 1.6002)
			(end -0.4953 1.6002)
			(stroke
				(width 0.1)
				(type default)
			)
			(layer "F.Fab")
		)
		(pad "1" smd rect
			(at 0 0)
			(size 0.762 0.889)
			(layers "F.Cu" "F.Mask" "F.Paste")
			(net "PVCCIN_CPU0")
		)
		(pad "2" smd rect
			(at 0 1.397)
			(size 0.762 0.889)
			(layers "F.Cu" "F.Mask" "F.Paste")
			(net "GND")
		)
		(zone
			(layer "F.Cu")
			(hatch none 0.5)
			(connect_pads
				(clearance 0)
			)
			(min_thickness 0.25)
			(keepout
				(tracks not_allowed)
				(vias allowed)
				(pads allowed)
				(copperpour not_allowed)
				(footprints allowed)
			)
			(placement
				(enabled no)
				(sheetname "")
			)
			(fill
				(thermal_gap 0.5)
				(thermal_bridge_width 0.5)
				(island_removal_mode 0)
			)
			(polygon
				(pts
					(xy 264.050272 -77.191616) (xy 264.812272 -77.191616) (xy 264.812272 -76.683616) (xy 264.050272 -76.683616)
				)
			)
		)
	)
	(footprint ""
		(layer "F.Cu")
		(at 368.554 -112.395 90)
		(property "Reference" "C7B29"
			(at 0 0 90)
			(layer "F.SilkS")
			(hide yes)
			(effects
				(font
					(size 1.27 1.27)
				)
			)
		)
		(property "Value" ""
			(at 0 0 90)
			(layer "F.Fab")
			(effects
				(font
					(size 1.27 1.27)
				)
			)
		)
		(duplicate_pad_numbers_are_jumpers no)
		(fp_poly
			(pts
				(xy 0.3048 -0.1016) (xy 0.3048 0.9906) (xy -0.3048 0.9906) (xy -0.3048 -0.1016)
			)
			(stroke
				(width 0)
				(type default)
			)
			(fill no)
			(layer "F.CrtYd")
		)
		(fp_line
			(start 0.3048 -0.1016)
			(end -0.3048 -0.1016)
			(stroke
				(width 0.1)
				(type default)
			)
			(layer "F.Fab")
		)
		(fp_line
			(start -0.3048 -0.1016)
			(end -0.3048 0.9906)
			(stroke
				(width 0.1)
				(type default)
			)
			(layer "F.Fab")
		)
		(fp_line
			(start 0.3048 0.9906)
			(end 0.3048 -0.1016)
			(stroke
				(width 0.1)
				(type default)
			)
			(layer "F.Fab")
		)
		(fp_line
			(start -0.3048 0.9906)
			(end 0.3048 0.9906)
			(stroke
				(width 0.1)
				(type default)
			)
			(layer "F.Fab")
		)
		(pad "1" smd rect
			(at 0 0 90)
			(size 0.508 0.508)
			(layers "F.Cu" "F.Mask" "F.Paste")
			(net "DMI_CPU0_PCH_TX_DN<2>")
		)
		(pad "2" smd rect
			(at 0 0.889 90)
			(size 0.508 0.508)
			(layers "F.Cu" "F.Mask" "F.Paste")
			(net "DMI_CPU0_PCH_TX_C_DN<2>")
		)
		(zone
			(layer "F.Cu")
			(hatch none 0.5)
			(connect_pads
				(clearance 0)
			)
			(min_thickness 0.25)
			(keepout
				(tracks allowed)
				(vias not_allowed)
				(pads allowed)
				(copperpour not_allowed)
				(footprints allowed)
			)
			(placement
				(enabled no)
				(sheetname "")
			)
			(fill
				(thermal_gap 0.5)
				(thermal_bridge_width 0.5)
				(island_removal_mode 0)
			)
			(polygon
				(pts
					(xy 368.808 -112.141) (xy 368.808 -112.649) (xy 369.189 -112.649) (xy 369.189 -112.141)
				)
			)
		)
		(zone
			(layer "F.Cu")
			(hatch none 0.5)
			(connect_pads
				(clearance 0)
			)
			(min_thickness 0.25)
			(keepout
				(tracks not_allowed)
				(vias allowed)
				(pads allowed)
				(copperpour not_allowed)
				(footprints allowed)
			)
			(placement
				(enabled no)
				(sheetname "")
			)
			(fill
				(thermal_gap 0.5)
				(thermal_bridge_width 0.5)
				(island_removal_mode 0)
			)
			(polygon
				(pts
					(xy 369.189 -112.141) (xy 369.189 -112.649) (xy 368.808 -112.649) (xy 368.808 -112.141)
				)
			)
		)
	)
	(footprint ""
		(layer "F.Cu")
		(at 14.605 -97.028 180)
		(property "Reference" "C1C14"
			(at 0 0 180)
			(layer "F.SilkS")
			(hide yes)
			(effects
				(font
					(size 1.27 1.27)
				)
			)
		)
		(property "Value" ""
			(at 0 0 180)
			(layer "F.Fab")
			(effects
				(font
					(size 1.27 1.27)
				)
			)
		)
		(duplicate_pad_numbers_are_jumpers no)
		(fp_rect
			(start 0.3048 -0.1016)
			(end -0.3048 0.9906)
			(stroke
				(width 0)
				(type default)
			)
			(fill no)
			(layer "F.CrtYd")
		)
		(fp_line
			(start 0.3048 0.9906)
			(end 0.3048 -0.1016)
			(stroke
				(width 0.1)
				(type default)
			)
			(layer "F.Fab")
		)
		(fp_line
			(start 0.3048 -0.1016)
			(end -0.3048 -0.1016)
			(stroke
				(width 0.1)
				(type default)
			)
			(layer "F.Fab")
		)
		(fp_line
			(start -0.3048 0.9906)
			(end 0.3048 0.9906)
			(stroke
				(width 0.1)
				(type default)
			)
			(layer "F.Fab")
		)
		(fp_line
			(start -0.3048 -0.1016)
			(end -0.3048 0.9906)
			(stroke
				(width 0.1)
				(type default)
			)
			(layer "F.Fab")
		)
		(pad "1" smd rect
			(at 0 0 180)
			(size 0.508 0.508)
			(layers "F.Cu" "F.Mask" "F.Paste")
			(net "VR_PVCCIN_CPU1_VD12")
		)
		(pad "2" smd rect
			(at 0 0.889 180)
			(size 0.508 0.508)
			(layers "F.Cu" "F.Mask" "F.Paste")
			(net "GND")
		)
		(zone
			(layer "F.Cu")
			(hatch none 0.5)
			(connect_pads
				(clearance 0)
			)
			(min_thickness 0.25)
			(keepout
				(tracks allowed)
				(vias not_allowed)
				(pads allowed)
				(copperpour not_allowed)
				(footprints allowed)
			)
			(placement
				(enabled no)
				(sheetname "")
			)
			(fill
				(thermal_gap 0.5)
				(thermal_bridge_width 0.5)
				(island_removal_mode 0)
			)
			(polygon
				(pts
					(xy 14.351 -97.282) (xy 14.859 -97.282) (xy 14.859 -97.663) (xy 14.351 -97.663)
				)
			)
		)
		(zone
			(layer "F.Cu")
			(hatch none 0.5)
			(connect_pads
				(clearance 0)
			)
			(min_thickness 0.25)
			(keepout
				(tracks not_allowed)
				(vias allowed)
				(pads allowed)
				(copperpour not_allowed)
				(footprints allowed)
			)
			(placement
				(enabled no)
				(sheetname "")
			)
			(fill
				(thermal_gap 0.5)
				(thermal_bridge_width 0.5)
				(island_removal_mode 0)
			)
			(polygon
				(pts
					(xy 14.351 -97.282) (xy 14.859 -97.282) (xy 14.859 -97.663) (xy 14.351 -97.663)
				)
			)
		)
	)
	(footprint ""
		(layer "F.Cu")
		(at 202.184 -26.162)
		(property "Reference" ""
			(at 0 0 0)
			(layer "F.SilkS")
			(hide yes)
			(effects
				(font
					(size 1.27 1.27)
				)
			)
		)
		(property "Value" ""
			(at 0 0 0)
			(layer "F.Fab")
			(effects
				(font
					(size 1.27 1.27)
				)
			)
		)
		(duplicate_pad_numbers_are_jumpers no)
		(fp_poly
			(pts
				(arc
					(start 2.032 0)
					(mid -2.032 0)
					(end 2.032 0)
				)
			)
			(stroke
				(width 0)
				(type default)
			)
			(fill no)
			(layer "F.CrtYd")
		)
		(pad "1" smd circle
			(at 0 0)
			(size 1.016 1.016)
			(layers "F.Cu" "F.Mask" "F.Paste")
			(net "Net_391")
		)
		(zone
			(layer "F.Cu")
			(hatch none 0.5)
			(connect_pads
				(clearance 0)
			)
			(min_thickness 0.25)
			(keepout
				(tracks not_allowed)
				(vias allowed)
				(pads allowed)
				(copperpour not_allowed)
				(footprints allowed)
			)
			(placement
				(enabled no)
				(sheetname "")
			)
			(fill
				(thermal_gap 0.5)
				(thermal_bridge_width 0.5)
				(island_removal_mode 0)
			)
			(polygon
				(pts
					(arc
						(start 203.708 -26.162)
						(mid 200.66 -26.162)
						(end 203.708 -26.162)
					)
				)
			)
		)
		(zone
			(layers "F.Cu" "B.Cu" "In1.Cu" "In2.Cu" "In3.Cu" "In4.Cu" "In5.Cu" "In6.Cu"
				"In7.Cu" "In8.Cu" "In9.Cu" "In10.Cu" "In11.Cu" "In12.Cu"
			)
			(hatch none 0.5)
			(connect_pads
				(clearance 0)
			)
			(min_thickness 0.25)
			(keepout
				(tracks allowed)
				(vias not_allowed)
				(pads allowed)
				(copperpour not_allowed)
				(footprints allowed)
			)
			(placement
				(enabled no)
				(sheetname "")
			)
			(fill
				(thermal_gap 0.5)
				(thermal_bridge_width 0.5)
				(island_removal_mode 0)
			)
			(polygon
				(pts
					(arc
						(start 203.708 -26.162)
						(mid 200.66 -26.162)
						(end 203.708 -26.162)
					)
				)
			)
		)
	)
	(footprint ""
		(layer "F.Cu")
		(at 100.683568 -79.6036 180)
		(property "Reference" "C2D15"
			(at 0 0 180)
			(layer "F.SilkS")
			(hide yes)
			(effects
				(font
					(size 1.27 1.27)
				)
			)
		)
		(property "Value" ""
			(at 0 0 180)
			(layer "F.Fab")
			(effects
				(font
					(size 1.27 1.27)
				)
			)
		)
		(duplicate_pad_numbers_are_jumpers no)
		(fp_poly
			(pts
				(xy -0.4953 -0.2032) (xy 0.4953 -0.2032) (xy 0.4953 1.6002) (xy -0.4953 1.6002)
			)
			(stroke
				(width 0)
				(type default)
			)
			(fill no)
			(layer "F.CrtYd")
		)
		(fp_line
			(start 0.4953 1.6002)
			(end -0.4953 1.6002)
			(stroke
				(width 0.1)
				(type default)
			)
			(layer "F.Fab")
		)
		(fp_line
			(start 0.4953 -0.2032)
			(end 0.4953 1.6002)
			(stroke
				(width 0.1)
				(type default)
			)
			(layer "F.Fab")
		)
		(fp_line
			(start -0.4953 1.6002)
			(end -0.4953 -0.2032)
			(stroke
				(width 0.1)
				(type default)
			)
			(layer "F.Fab")
		)
		(fp_line
			(start -0.4953 -0.2032)
			(end 0.4953 -0.2032)
			(stroke
				(width 0.1)
				(type default)
			)
			(layer "F.Fab")
		)
		(pad "1" smd rect
			(at 0 0 180)
			(size 0.762 0.889)
			(layers "F.Cu" "F.Mask" "F.Paste")
			(net "PVCCIN_CPU1")
		)
		(pad "2" smd rect
			(at 0 1.397 180)
			(size 0.762 0.889)
			(layers "F.Cu" "F.Mask" "F.Paste")
			(net "GND")
		)
		(zone
			(layer "F.Cu")
			(hatch none 0.5)
			(connect_pads
				(clearance 0)
			)
			(min_thickness 0.25)
			(keepout
				(tracks not_allowed)
				(vias allowed)
				(pads allowed)
				(copperpour not_allowed)
				(footprints allowed)
			)
			(placement
				(enabled no)
				(sheetname "")
			)
			(fill
				(thermal_gap 0.5)
				(thermal_bridge_width 0.5)
				(island_removal_mode 0)
			)
			(polygon
				(pts
					(xy 101.064568 -80.0481) (xy 100.302568 -80.0481) (xy 100.302568 -80.5561) (xy 101.064568 -80.5561)
				)
			)
		)
	)
	(footprint ""
		(layer "F.Cu")
		(at 189.963044 -66.080386 180)
		(property "Reference" "RF2"
			(at -0.8382 -0.67818 180)
			(unlocked yes)
			(layer "F.SilkS")
			(effects
				(font
					(size 0.4064 0.254)
					(thickness 0.1524)
				)
				(justify left)
			)
		)
		(property "Value" ""
			(at 0 0 180)
			(layer "F.Fab")
			(effects
				(font
					(size 1.27 1.27)
				)
			)
		)
		(duplicate_pad_numbers_are_jumpers no)
		(fp_poly
			(pts
				(xy -0.2794 -0.1016) (xy 0.2794 -0.1016) (xy 0.2794 0.9906) (xy -0.2794 0.9906)
			)
			(stroke
				(width 0)
				(type default)
			)
			(fill no)
			(layer "F.CrtYd")
		)
		(fp_line
			(start 0.2794 0.9906)
			(end 0.2794 -0.1016)
			(stroke
				(width 0.1)
				(type default)
			)
			(layer "F.Fab")
		)
		(fp_line
			(start 0.2794 -0.1016)
			(end -0.2794 -0.1016)
			(stroke
				(width 0.1)
				(type default)
			)
			(layer "F.Fab")
		)
		(fp_line
			(start -0.2794 0.9906)
			(end 0.2794 0.9906)
			(stroke
				(width 0.1)
				(type default)
			)
			(layer "F.Fab")
		)
		(fp_line
			(start -0.2794 -0.1016)
			(end -0.2794 0.9906)
			(stroke
				(width 0.1)
				(type default)
			)
			(layer "F.Fab")
		)
		(pad "1" smd rect
			(at 0 0 180)
			(size 0.508 0.508)
			(layers "F.Cu" "F.Mask" "F.Paste")
			(net "VR_PVCCIN_CPU0_AIREF2")
		)
		(pad "2" smd rect
			(at 0 0.889 180)
			(size 0.508 0.508)
			(layers "F.Cu" "F.Mask" "F.Paste")
			(net "ISENSE_PVCCIN_CPU0_PH2_IMON")
		)
		(zone
			(layer "F.Cu")
			(hatch none 0.5)
			(connect_pads
				(clearance 0)
			)
			(min_thickness 0.25)
			(keepout
				(tracks not_allowed)
				(vias allowed)
				(pads allowed)
				(copperpour not_allowed)
				(footprints allowed)
			)
			(placement
				(enabled no)
				(sheetname "")
			)
			(fill
				(thermal_gap 0.5)
				(thermal_bridge_width 0.5)
				(island_removal_mode 0)
			)
			(polygon
				(pts
					(xy 190.217044 -66.715386) (xy 189.709044 -66.715386) (xy 189.709044 -66.334386) (xy 190.217044 -66.334386)
				)
			)
		)
		(zone
			(layer "F.Cu")
			(hatch none 0.5)
			(connect_pads
				(clearance 0)
			)
			(min_thickness 0.25)
			(keepout
				(tracks allowed)
				(vias not_allowed)
				(pads allowed)
				(copperpour not_allowed)
				(footprints allowed)
			)
			(placement
				(enabled no)
				(sheetname "")
			)
			(fill
				(thermal_gap 0.5)
				(thermal_bridge_width 0.5)
				(island_removal_mode 0)
			)
			(polygon
				(pts
					(xy 190.217044 -66.334386) (xy 189.709044 -66.334386) (xy 189.709044 -66.715386) (xy 190.217044 -66.715386)
				)
			)
		)
	)
	(footprint ""
		(layer "F.Cu")
		(at 23.241 -81.6102)
		(property "Reference" "R1D20"
			(at 0 0 0)
			(layer "F.SilkS")
			(hide yes)
			(effects
				(font
					(size 1.27 1.27)
				)
			)
		)
		(property "Value" ""
			(at 0 0 0)
			(layer "F.Fab")
			(effects
				(font
					(size 1.27 1.27)
				)
			)
		)
		(duplicate_pad_numbers_are_jumpers no)
		(fp_poly
			(pts
				(xy -0.2794 -0.1016) (xy 0.2794 -0.1016) (xy 0.2794 0.9906) (xy -0.2794 0.9906)
			)
			(stroke
				(width 0)
				(type default)
			)
			(fill no)
			(layer "F.CrtYd")
		)
		(fp_line
			(start -0.2794 -0.1016)
			(end -0.2794 0.9906)
			(stroke
				(width 0.1)
				(type default)
			)
			(layer "F.Fab")
		)
		(fp_line
			(start -0.2794 0.9906)
			(end 0.2794 0.9906)
			(stroke
				(width 0.1)
				(type default)
			)
			(layer "F.Fab")
		)
		(fp_line
			(start 0.2794 -0.1016)
			(end -0.2794 -0.1016)
			(stroke
				(width 0.1)
				(type default)
			)
			(layer "F.Fab")
		)
		(fp_line
			(start 0.2794 0.9906)
			(end 0.2794 -0.1016)
			(stroke
				(width 0.1)
				(type default)
			)
			(layer "F.Fab")
		)
		(pad "1" smd rect
			(at 0 0)
			(size 0.508 0.508)
			(layers "F.Cu" "F.Mask" "F.Paste")
			(net "A_HSC_CSOUT")
		)
		(pad "2" smd rect
			(at 0 0.889)
			(size 0.508 0.508)
			(layers "F.Cu" "F.Mask" "F.Paste")
			(net "A_HSC_HIGH")
		)
		(zone
			(layer "F.Cu")
			(hatch none 0.5)
			(connect_pads
				(clearance 0)
			)
			(min_thickness 0.25)
			(keepout
				(tracks allowed)
				(vias not_allowed)
				(pads allowed)
				(copperpour not_allowed)
				(footprints allowed)
			)
			(placement
				(enabled no)
				(sheetname "")
			)
			(fill
				(thermal_gap 0.5)
				(thermal_bridge_width 0.5)
				(island_removal_mode 0)
			)
			(polygon
				(pts
					(xy 22.987 -81.3562) (xy 23.495 -81.3562) (xy 23.495 -80.9752) (xy 22.987 -80.9752)
				)
			)
		)
		(zone
			(layer "F.Cu")
			(hatch none 0.5)
			(connect_pads
				(clearance 0)
			)
			(min_thickness 0.25)
			(keepout
				(tracks not_allowed)
				(vias allowed)
				(pads allowed)
				(copperpour not_allowed)
				(footprints allowed)
			)
			(placement
				(enabled no)
				(sheetname "")
			)
			(fill
				(thermal_gap 0.5)
				(thermal_bridge_width 0.5)
				(island_removal_mode 0)
			)
			(polygon
				(pts
					(xy 22.987 -80.9752) (xy 23.495 -80.9752) (xy 23.495 -81.3562) (xy 22.987 -81.3562)
				)
			)
		)
	)
	(footprint ""
		(layer "F.Cu")
		(at 401.066 -47.9425)
		(property "Reference" "R7F32"
			(at 0 0 0)
			(layer "F.SilkS")
			(hide yes)
			(effects
				(font
					(size 1.27 1.27)
				)
			)
		)
		(property "Value" ""
			(at 0 0 0)
			(layer "F.Fab")
			(effects
				(font
					(size 1.27 1.27)
				)
			)
		)
		(duplicate_pad_numbers_are_jumpers no)
		(fp_poly
			(pts
				(xy -0.2794 -0.1016) (xy 0.2794 -0.1016) (xy 0.2794 0.9906) (xy -0.2794 0.9906)
			)
			(stroke
				(width 0)
				(type default)
			)
			(fill no)
			(layer "F.CrtYd")
		)
		(fp_line
			(start -0.2794 -0.1016)
			(end -0.2794 0.9906)
			(stroke
				(width 0.1)
				(type default)
			)
			(layer "F.Fab")
		)
		(fp_line
			(start -0.2794 0.9906)
			(end 0.2794 0.9906)
			(stroke
				(width 0.1)
				(type default)
			)
			(layer "F.Fab")
		)
		(fp_line
			(start 0.2794 -0.1016)
			(end -0.2794 -0.1016)
			(stroke
				(width 0.1)
				(type default)
			)
			(layer "F.Fab")
		)
		(fp_line
			(start 0.2794 0.9906)
			(end 0.2794 -0.1016)
			(stroke
				(width 0.1)
				(type default)
			)
			(layer "F.Fab")
		)
		(pad "1" smd rect
			(at 0 0)
			(size 0.508 0.508)
			(layers "F.Cu" "F.Mask" "F.Paste")
			(net "P3V3_STBY")
		)
		(pad "2" smd rect
			(at 0 0.889)
			(size 0.508 0.508)
			(layers "F.Cu" "F.Mask" "F.Paste")
			(net "PU_BIOS_SPI_HOLD0_N")
		)
		(zone
			(layer "F.Cu")
			(hatch none 0.5)
			(connect_pads
				(clearance 0)
			)
			(min_thickness 0.25)
			(keepout
				(tracks allowed)
				(vias not_allowed)
				(pads allowed)
				(copperpour not_allowed)
				(footprints allowed)
			)
			(placement
				(enabled no)
				(sheetname "")
			)
			(fill
				(thermal_gap 0.5)
				(thermal_bridge_width 0.5)
				(island_removal_mode 0)
			)
			(polygon
				(pts
					(xy 400.812 -47.6885) (xy 401.32 -47.6885) (xy 401.32 -47.3075) (xy 400.812 -47.3075)
				)
			)
		)
		(zone
			(layer "F.Cu")
			(hatch none 0.5)
			(connect_pads
				(clearance 0)
			)
			(min_thickness 0.25)
			(keepout
				(tracks not_allowed)
				(vias allowed)
				(pads allowed)
				(copperpour not_allowed)
				(footprints allowed)
			)
			(placement
				(enabled no)
				(sheetname "")
			)
			(fill
				(thermal_gap 0.5)
				(thermal_bridge_width 0.5)
				(island_removal_mode 0)
			)
			(polygon
				(pts
					(xy 400.812 -47.3075) (xy 401.32 -47.3075) (xy 401.32 -47.6885) (xy 400.812 -47.6885)
				)
			)
		)
	)
	(footprint ""
		(layer "F.Cu")
		(at 13.843 -142.875 -90)
		(property "Reference" "C1A12"
			(at 1.47828 0.78994 180)
			(unlocked yes)
			(layer "F.SilkS")
			(effects
				(font
					(size 0.4064 0.254)
					(thickness 0.1524)
				)
			)
		)
		(property "Value" ""
			(at 0 0 270)
			(layer "F.Fab")
			(effects
				(font
					(size 1.27 1.27)
				)
			)
		)
		(duplicate_pad_numbers_are_jumpers no)
		(fp_poly
			(pts
				(xy -0.7239 -0.2159) (xy 0.7239 -0.2159) (xy 0.7239 1.9939) (xy -0.7239 1.9939)
			)
			(stroke
				(width 0)
				(type default)
			)
			(fill no)
			(layer "F.CrtYd")
		)
		(fp_line
			(start -0.7239 1.9939)
			(end 0.7239 1.9939)
			(stroke
				(width 0.1)
				(type default)
			)
			(layer "F.Fab")
		)
		(fp_line
			(start 0.7239 1.9939)
			(end 0.7239 -0.2159)
			(stroke
				(width 0.1)
				(type default)
			)
			(layer "F.Fab")
		)
		(fp_line
			(start -0.7239 -0.2159)
			(end -0.7239 1.9939)
			(stroke
				(width 0.1)
				(type default)
			)
			(layer "F.Fab")
		)
		(fp_line
			(start 0.7239 -0.2159)
			(end -0.7239 -0.2159)
			(stroke
				(width 0.1)
				(type default)
			)
			(layer "F.Fab")
		)
		(pad "1" smd rect
			(at 0 0 270)
			(size 1.27 1.016)
			(layers "F.Cu" "F.Mask" "F.Paste")
			(net "PVDDQ_KLM")
		)
		(pad "2" smd rect
			(at 0 1.778 270)
			(size 1.27 1.016)
			(layers "F.Cu" "F.Mask" "F.Paste")
			(net "GND")
		)
		(zone
			(layer "F.Cu")
			(hatch none 0.5)
			(connect_pads
				(clearance 0)
			)
			(min_thickness 0.25)
			(keepout
				(tracks not_allowed)
				(vias allowed)
				(pads allowed)
				(copperpour not_allowed)
				(footprints allowed)
			)
			(placement
				(enabled no)
				(sheetname "")
			)
			(fill
				(thermal_gap 0.5)
				(thermal_bridge_width 0.5)
				(island_removal_mode 0)
			)
			(polygon
				(pts
					(xy 13.335 -143.51) (xy 13.335 -142.24) (xy 12.573 -142.24) (xy 12.573 -143.51)
				)
			)
		)
	)
	(footprint ""
		(layer "F.Cu")
		(at 448.35572 -153.54046 -90)
		(property "Reference" "R25W187"
			(at -0.8382 -0.67818 270)
			(unlocked yes)
			(layer "F.SilkS")
			(effects
				(font
					(size 0.4064 0.254)
					(thickness 0.1524)
				)
				(justify left)
			)
		)
		(property "Value" ""
			(at 0 0 270)
			(layer "F.Fab")
			(effects
				(font
					(size 1.27 1.27)
				)
			)
		)
		(duplicate_pad_numbers_are_jumpers no)
		(fp_poly
			(pts
				(xy -0.2794 -0.1016) (xy 0.2794 -0.1016) (xy 0.2794 0.9906) (xy -0.2794 0.9906)
			)
			(stroke
				(width 0)
				(type default)
			)
			(fill no)
			(layer "F.CrtYd")
		)
		(fp_line
			(start -0.2794 0.9906)
			(end 0.2794 0.9906)
			(stroke
				(width 0.1)
				(type default)
			)
			(layer "F.Fab")
		)
		(fp_line
			(start 0.2794 0.9906)
			(end 0.2794 -0.1016)
			(stroke
				(width 0.1)
				(type default)
			)
			(layer "F.Fab")
		)
		(fp_line
			(start -0.2794 -0.1016)
			(end -0.2794 0.9906)
			(stroke
				(width 0.1)
				(type default)
			)
			(layer "F.Fab")
		)
		(fp_line
			(start 0.2794 -0.1016)
			(end -0.2794 -0.1016)
			(stroke
				(width 0.1)
				(type default)
			)
			(layer "F.Fab")
		)
		(pad "1" smd rect
			(at 0 0 270)
			(size 0.508 0.508)
			(layers "F.Cu" "F.Mask" "F.Paste")
			(net "JTAG_BMC_BUF_TDO_R")
		)
		(pad "2" smd rect
			(at 0 0.889 270)
			(size 0.508 0.508)
			(layers "F.Cu" "F.Mask" "F.Paste")
			(net "JTAG_BMC_BUF_TDO")
		)
		(zone
			(layer "F.Cu")
			(hatch none 0.5)
			(connect_pads
				(clearance 0)
			)
			(min_thickness 0.25)
			(keepout
				(tracks not_allowed)
				(vias allowed)
				(pads allowed)
				(copperpour not_allowed)
				(footprints allowed)
			)
			(placement
				(enabled no)
				(sheetname "")
			)
			(fill
				(thermal_gap 0.5)
				(thermal_bridge_width 0.5)
				(island_removal_mode 0)
			)
			(polygon
				(pts
					(xy 447.72072 -153.79446) (xy 447.72072 -153.28646) (xy 448.10172 -153.28646) (xy 448.10172 -153.79446)
				)
			)
		)
		(zone
			(layer "F.Cu")
			(hatch none 0.5)
			(connect_pads
				(clearance 0)
			)
			(min_thickness 0.25)
			(keepout
				(tracks allowed)
				(vias not_allowed)
				(pads allowed)
				(copperpour not_allowed)
				(footprints allowed)
			)
			(placement
				(enabled no)
				(sheetname "")
			)
			(fill
				(thermal_gap 0.5)
				(thermal_bridge_width 0.5)
				(island_removal_mode 0)
			)
			(polygon
				(pts
					(xy 448.10172 -153.79446) (xy 448.10172 -153.28646) (xy 447.72072 -153.28646) (xy 447.72072 -153.79446)
				)
			)
		)
	)
	(footprint ""
		(layer "F.Cu")
		(at 453.644 -41.021)
		(property "Reference" "R9F34"
			(at 0 0 0)
			(layer "F.SilkS")
			(hide yes)
			(effects
				(font
					(size 1.27 1.27)
				)
			)
		)
		(property "Value" ""
			(at 0 0 0)
			(layer "F.Fab")
			(effects
				(font
					(size 1.27 1.27)
				)
			)
		)
		(duplicate_pad_numbers_are_jumpers no)
		(fp_poly
			(pts
				(xy -0.2794 -0.1016) (xy 0.2794 -0.1016) (xy 0.2794 0.9906) (xy -0.2794 0.9906)
			)
			(stroke
				(width 0)
				(type default)
			)
			(fill no)
			(layer "F.CrtYd")
		)
		(fp_line
			(start -0.2794 -0.1016)
			(end -0.2794 0.9906)
			(stroke
				(width 0.1)
				(type default)
			)
			(layer "F.Fab")
		)
		(fp_line
			(start -0.2794 0.9906)
			(end 0.2794 0.9906)
			(stroke
				(width 0.1)
				(type default)
			)
			(layer "F.Fab")
		)
		(fp_line
			(start 0.2794 -0.1016)
			(end -0.2794 -0.1016)
			(stroke
				(width 0.1)
				(type default)
			)
			(layer "F.Fab")
		)
		(fp_line
			(start 0.2794 0.9906)
			(end 0.2794 -0.1016)
			(stroke
				(width 0.1)
				(type default)
			)
			(layer "F.Fab")
		)
		(pad "1" smd rect
			(at 0 0)
			(size 0.508 0.508)
			(layers "F.Cu" "F.Mask" "F.Paste")
			(net "RST_BMC_DDR3_R_N")
		)
		(pad "2" smd rect
			(at 0 0.889)
			(size 0.508 0.508)
			(layers "F.Cu" "F.Mask" "F.Paste")
			(net "BMC_M_RST_N")
		)
		(zone
			(layer "F.Cu")
			(hatch none 0.5)
			(connect_pads
				(clearance 0)
			)
			(min_thickness 0.25)
			(keepout
				(tracks allowed)
				(vias not_allowed)
				(pads allowed)
				(copperpour not_allowed)
				(footprints allowed)
			)
			(placement
				(enabled no)
				(sheetname "")
			)
			(fill
				(thermal_gap 0.5)
				(thermal_bridge_width 0.5)
				(island_removal_mode 0)
			)
			(polygon
				(pts
					(xy 453.39 -40.767) (xy 453.898 -40.767) (xy 453.898 -40.386) (xy 453.39 -40.386)
				)
			)
		)
		(zone
			(layer "F.Cu")
			(hatch none 0.5)
			(connect_pads
				(clearance 0)
			)
			(min_thickness 0.25)
			(keepout
				(tracks not_allowed)
				(vias allowed)
				(pads allowed)
				(copperpour not_allowed)
				(footprints allowed)
			)
			(placement
				(enabled no)
				(sheetname "")
			)
			(fill
				(thermal_gap 0.5)
				(thermal_bridge_width 0.5)
				(island_removal_mode 0)
			)
			(polygon
				(pts
					(xy 453.39 -40.386) (xy 453.898 -40.386) (xy 453.898 -40.767) (xy 453.39 -40.767)
				)
			)
		)
	)
	(footprint ""
		(layer "F.Cu")
		(at 477.3041 -42.1894 90)
		(property "Reference" "R9E18"
			(at 0 0 90)
			(layer "F.SilkS")
			(hide yes)
			(effects
				(font
					(size 1.27 1.27)
				)
			)
		)
		(property "Value" ""
			(at 0 0 90)
			(layer "F.Fab")
			(effects
				(font
					(size 1.27 1.27)
				)
			)
		)
		(duplicate_pad_numbers_are_jumpers no)
		(fp_poly
			(pts
				(xy -0.2794 -0.1016) (xy 0.2794 -0.1016) (xy 0.2794 0.9906) (xy -0.2794 0.9906)
			)
			(stroke
				(width 0)
				(type default)
			)
			(fill no)
			(layer "F.CrtYd")
		)
		(fp_line
			(start 0.2794 -0.1016)
			(end -0.2794 -0.1016)
			(stroke
				(width 0.1)
				(type default)
			)
			(layer "F.Fab")
		)
		(fp_line
			(start -0.2794 -0.1016)
			(end -0.2794 0.9906)
			(stroke
				(width 0.1)
				(type default)
			)
			(layer "F.Fab")
		)
		(fp_line
			(start 0.2794 0.9906)
			(end 0.2794 -0.1016)
			(stroke
				(width 0.1)
				(type default)
			)
			(layer "F.Fab")
		)
		(fp_line
			(start -0.2794 0.9906)
			(end 0.2794 0.9906)
			(stroke
				(width 0.1)
				(type default)
			)
			(layer "F.Fab")
		)
		(pad "1" smd rect
			(at 0 0 90)
			(size 0.508 0.508)
			(layers "F.Cu" "F.Mask" "F.Paste")
			(net "XTAL_25MHZ_OUT_R")
		)
		(pad "2" smd rect
			(at 0 0.889 90)
			(size 0.508 0.508)
			(layers "F.Cu" "F.Mask" "F.Paste")
			(net "XTAL_25MHZ_OUT")
		)
		(zone
			(layer "F.Cu")
			(hatch none 0.5)
			(connect_pads
				(clearance 0)
			)
			(min_thickness 0.25)
			(keepout
				(tracks allowed)
				(vias not_allowed)
				(pads allowed)
				(copperpour not_allowed)
				(footprints allowed)
			)
			(placement
				(enabled no)
				(sheetname "")
			)
			(fill
				(thermal_gap 0.5)
				(thermal_bridge_width 0.5)
				(island_removal_mode 0)
			)
			(polygon
				(pts
					(xy 477.5581 -41.9354) (xy 477.5581 -42.4434) (xy 477.9391 -42.4434) (xy 477.9391 -41.9354)
				)
			)
		)
		(zone
			(layer "F.Cu")
			(hatch none 0.5)
			(connect_pads
				(clearance 0)
			)
			(min_thickness 0.25)
			(keepout
				(tracks not_allowed)
				(vias allowed)
				(pads allowed)
				(copperpour not_allowed)
				(footprints allowed)
			)
			(placement
				(enabled no)
				(sheetname "")
			)
			(fill
				(thermal_gap 0.5)
				(thermal_bridge_width 0.5)
				(island_removal_mode 0)
			)
			(polygon
				(pts
					(xy 477.9391 -41.9354) (xy 477.9391 -42.4434) (xy 477.5581 -42.4434) (xy 477.5581 -41.9354)
				)
			)
		)
	)
	(footprint ""
		(layer "F.Cu")
		(at 198.337932 -60.305442 90)
		(property "Reference" "C4E20"
			(at 0 0 90)
			(layer "F.SilkS")
			(hide yes)
			(effects
				(font
					(size 1.27 1.27)
				)
			)
		)
		(property "Value" ""
			(at 0 0 90)
			(layer "F.Fab")
			(effects
				(font
					(size 1.27 1.27)
				)
			)
		)
		(duplicate_pad_numbers_are_jumpers no)
		(fp_rect
			(start 0.3048 0.9906)
			(end -0.3048 -0.1016)
			(stroke
				(width 0)
				(type default)
			)
			(fill no)
			(layer "F.CrtYd")
		)
		(fp_line
			(start 0.3048 -0.1016)
			(end -0.3048 -0.1016)
			(stroke
				(width 0.1)
				(type default)
			)
			(layer "F.Fab")
		)
		(fp_line
			(start -0.3048 -0.1016)
			(end -0.3048 0.9906)
			(stroke
				(width 0.1)
				(type default)
			)
			(layer "F.Fab")
		)
		(fp_line
			(start 0.3048 0.9906)
			(end 0.3048 -0.1016)
			(stroke
				(width 0.1)
				(type default)
			)
			(layer "F.Fab")
		)
		(fp_line
			(start -0.3048 0.9906)
			(end 0.3048 0.9906)
			(stroke
				(width 0.1)
				(type default)
			)
			(layer "F.Fab")
		)
		(pad "1" smd rect
			(at 0 0 90)
			(size 0.508 0.508)
			(layers "F.Cu" "F.Mask" "F.Paste")
			(net "VR_FET_SW_P12V_STBY_PVCCIN_CPU0")
		)
		(pad "2" smd rect
			(at 0 0.889 90)
			(size 0.508 0.508)
			(layers "F.Cu" "F.Mask" "F.Paste")
			(net "GND")
		)
		(zone
			(layer "F.Cu")
			(hatch none 0.5)
			(connect_pads
				(clearance 0)
			)
			(min_thickness 0.25)
			(keepout
				(tracks not_allowed)
				(vias allowed)
				(pads allowed)
				(copperpour not_allowed)
				(footprints allowed)
			)
			(placement
				(enabled no)
				(sheetname "")
			)
			(fill
				(thermal_gap 0.5)
				(thermal_bridge_width 0.5)
				(island_removal_mode 0)
			)
			(polygon
				(pts
					(xy 198.972932 -60.559442) (xy 198.591932 -60.559442) (xy 198.591932 -60.051442) (xy 198.972932 -60.051442)
				)
			)
		)
		(zone
			(layer "F.Cu")
			(hatch none 0.5)
			(connect_pads
				(clearance 0)
			)
			(min_thickness 0.25)
			(keepout
				(tracks allowed)
				(vias not_allowed)
				(pads allowed)
				(copperpour not_allowed)
				(footprints allowed)
			)
			(placement
				(enabled no)
				(sheetname "")
			)
			(fill
				(thermal_gap 0.5)
				(thermal_bridge_width 0.5)
				(island_removal_mode 0)
			)
			(polygon
				(pts
					(xy 198.972932 -60.559442) (xy 198.591932 -60.559442) (xy 198.591932 -60.051442) (xy 198.972932 -60.051442)
				)
			)
		)
	)
	(footprint ""
		(layer "F.Cu")
		(at 365.890556 -156.250894 180)
		(property "Reference" "C7A13"
			(at 0 0 180)
			(layer "F.SilkS")
			(hide yes)
			(effects
				(font
					(size 1.27 1.27)
				)
			)
		)
		(property "Value" "*"
			(at -0.0762 -6.2357 180)
			(unlocked yes)
			(layer "F.Fab")
			(hide yes)
			(effects
				(font
					(size 1.27 1.016)
					(thickness 0.1524)
				)
			)
		)
		(property "Device Type" "SC22U16V5MX-4-GP_SMD-BCG5-SC22A"
			(at -0.0762 -8.2677 180)
			(unlocked yes)
			(layer "F.Fab")
			(hide yes)
			(effects
				(font
					(size 1.27 1.016)
					(thickness 0.1524)
				)
			)
		)
		(duplicate_pad_numbers_are_jumpers no)
		(fp_line
			(start 0.635 0)
			(end -0.635 0)
			(stroke
				(width 0.508)
				(type default)
			)
			(layer "F.SilkS")
		)
		(fp_rect
			(start -0.9652 1.778)
			(end 0.9652 -1.778)
			(stroke
				(width 0)
				(type default)
			)
			(fill no)
			(layer "F.CrtYd")
		)
		(fp_poly
			(pts
				(xy -0.9652 -1.778) (xy 0.9652 -1.778) (xy 0.9652 1.778) (xy -0.9652 1.778)
			)
			(stroke
				(width 0)
				(type default)
			)
			(fill no)
			(layer "F.Fab")
		)
		(pad "1" smd rect
			(at 0 -0.9652 180)
			(size 1.397 1.143)
			(layers "F.Cu" "F.Mask" "F.Paste")
			(net "VR_FET_SW_P12V_STBY_PVDDQ_DEF")
		)
		(pad "2" smd rect
			(at 0 0.9652 180)
			(size 1.397 1.143)
			(layers "F.Cu" "F.Mask" "F.Paste")
			(net "GND")
		)
	)
	(footprint ""
		(layer "F.Cu")
		(at 30.579568 -12.923012 90)
		(property "Reference" "C1G10"
			(at 0 0 90)
			(layer "F.SilkS")
			(hide yes)
			(effects
				(font
					(size 1.27 1.27)
				)
			)
		)
		(property "Value" ""
			(at 0 0 90)
			(layer "F.Fab")
			(effects
				(font
					(size 1.27 1.27)
				)
			)
		)
		(duplicate_pad_numbers_are_jumpers no)
		(fp_poly
			(pts
				(xy 0.3048 -0.1016) (xy 0.3048 0.9906) (xy -0.3048 0.9906) (xy -0.3048 -0.1016)
			)
			(stroke
				(width 0)
				(type default)
			)
			(fill no)
			(layer "F.CrtYd")
		)
		(fp_line
			(start 0.3048 -0.1016)
			(end -0.3048 -0.1016)
			(stroke
				(width 0.1)
				(type default)
			)
			(layer "F.Fab")
		)
		(fp_line
			(start -0.3048 -0.1016)
			(end -0.3048 0.9906)
			(stroke
				(width 0.1)
				(type default)
			)
			(layer "F.Fab")
		)
		(fp_line
			(start 0.3048 0.9906)
			(end 0.3048 -0.1016)
			(stroke
				(width 0.1)
				(type default)
			)
			(layer "F.Fab")
		)
		(fp_line
			(start -0.3048 0.9906)
			(end 0.3048 0.9906)
			(stroke
				(width 0.1)
				(type default)
			)
			(layer "F.Fab")
		)
		(pad "1" smd rect
			(at 0 0 90)
			(size 0.508 0.508)
			(layers "F.Cu" "F.Mask" "F.Paste")
			(net "M_H_VREF")
		)
		(pad "2" smd rect
			(at 0 0.889 90)
			(size 0.508 0.508)
			(layers "F.Cu" "F.Mask" "F.Paste")
			(net "GND")
		)
		(zone
			(layer "F.Cu")
			(hatch none 0.5)
			(connect_pads
				(clearance 0)
			)
			(min_thickness 0.25)
			(keepout
				(tracks allowed)
				(vias not_allowed)
				(pads allowed)
				(copperpour not_allowed)
				(footprints allowed)
			)
			(placement
				(enabled no)
				(sheetname "")
			)
			(fill
				(thermal_gap 0.5)
				(thermal_bridge_width 0.5)
				(island_removal_mode 0)
			)
			(polygon
				(pts
					(xy 30.833568 -12.669012) (xy 30.833568 -13.177012) (xy 31.214568 -13.177012) (xy 31.214568 -12.669012)
				)
			)
		)
		(zone
			(layer "F.Cu")
			(hatch none 0.5)
			(connect_pads
				(clearance 0)
			)
			(min_thickness 0.25)
			(keepout
				(tracks not_allowed)
				(vias allowed)
				(pads allowed)
				(copperpour not_allowed)
				(footprints allowed)
			)
			(placement
				(enabled no)
				(sheetname "")
			)
			(fill
				(thermal_gap 0.5)
				(thermal_bridge_width 0.5)
				(island_removal_mode 0)
			)
			(polygon
				(pts
					(xy 31.214568 -12.669012) (xy 31.214568 -13.177012) (xy 30.833568 -13.177012) (xy 30.833568 -12.669012)
				)
			)
		)
	)
	(footprint ""
		(layer "F.Cu")
		(at 341.249 -23.749)
		(property "Reference" "C7F8"
			(at 0 0 0)
			(layer "F.SilkS")
			(hide yes)
			(effects
				(font
					(size 1.27 1.27)
				)
			)
		)
		(property "Value" ""
			(at 0 0 0)
			(layer "F.Fab")
			(effects
				(font
					(size 1.27 1.27)
				)
			)
		)
		(duplicate_pad_numbers_are_jumpers no)
		(fp_rect
			(start 0.3048 0.9906)
			(end -0.3048 -0.1016)
			(stroke
				(width 0)
				(type default)
			)
			(fill no)
			(layer "F.CrtYd")
		)
		(fp_line
			(start -0.3048 -0.1016)
			(end -0.3048 0.9906)
			(stroke
				(width 0.1)
				(type default)
			)
			(layer "F.Fab")
		)
		(fp_line
			(start -0.3048 0.9906)
			(end 0.3048 0.9906)
			(stroke
				(width 0.1)
				(type default)
			)
			(layer "F.Fab")
		)
		(fp_line
			(start 0.3048 -0.1016)
			(end -0.3048 -0.1016)
			(stroke
				(width 0.1)
				(type default)
			)
			(layer "F.Fab")
		)
		(fp_line
			(start 0.3048 0.9906)
			(end 0.3048 -0.1016)
			(stroke
				(width 0.1)
				(type default)
			)
			(layer "F.Fab")
		)
		(pad "1" smd rect
			(at 0 0)
			(size 0.508 0.508)
			(layers "F.Cu" "F.Mask" "F.Paste")
			(net "FM_PVPP_CPU0_EN")
		)
		(pad "2" smd rect
			(at 0 0.889)
			(size 0.508 0.508)
			(layers "F.Cu" "F.Mask" "F.Paste")
			(net "AGND_PVPP_ABC")
		)
		(zone
			(layer "F.Cu")
			(hatch none 0.5)
			(connect_pads
				(clearance 0)
			)
			(min_thickness 0.25)
			(keepout
				(tracks allowed)
				(vias not_allowed)
				(pads allowed)
				(copperpour not_allowed)
				(footprints allowed)
			)
			(placement
				(enabled no)
				(sheetname "")
			)
			(fill
				(thermal_gap 0.5)
				(thermal_bridge_width 0.5)
				(island_removal_mode 0)
			)
			(polygon
				(pts
					(xy 341.503 -23.114) (xy 341.503 -23.495) (xy 340.995 -23.495) (xy 340.995 -23.114)
				)
			)
		)
		(zone
			(layer "F.Cu")
			(hatch none 0.5)
			(connect_pads
				(clearance 0)
			)
			(min_thickness 0.25)
			(keepout
				(tracks not_allowed)
				(vias allowed)
				(pads allowed)
				(copperpour not_allowed)
				(footprints allowed)
			)
			(placement
				(enabled no)
				(sheetname "")
			)
			(fill
				(thermal_gap 0.5)
				(thermal_bridge_width 0.5)
				(island_removal_mode 0)
			)
			(polygon
				(pts
					(xy 341.503 -23.114) (xy 341.503 -23.495) (xy 340.995 -23.495) (xy 340.995 -23.114)
				)
			)
		)
	)
	(footprint ""
		(layer "F.Cu")
		(at 394.143992 -10.917936)
		(property "Reference" "C7G22"
			(at 0 0 0)
			(layer "F.SilkS")
			(hide yes)
			(effects
				(font
					(size 1.27 1.27)
				)
			)
		)
		(property "Value" ""
			(at 0 0 0)
			(layer "F.Fab")
			(effects
				(font
					(size 1.27 1.27)
				)
			)
		)
		(duplicate_pad_numbers_are_jumpers no)
		(fp_rect
			(start -0.3048 0.9906)
			(end 0.3048 -0.1016)
			(stroke
				(width 0)
				(type default)
			)
			(fill no)
			(layer "F.CrtYd")
		)
		(fp_line
			(start -0.3048 -0.1016)
			(end -0.3048 0.9906)
			(stroke
				(width 0.1)
				(type default)
			)
			(layer "F.Fab")
		)
		(fp_line
			(start -0.3048 0.9906)
			(end 0.3048 0.9906)
			(stroke
				(width 0.1)
				(type default)
			)
			(layer "F.Fab")
		)
		(fp_line
			(start 0.3048 -0.1016)
			(end -0.3048 -0.1016)
			(stroke
				(width 0.1)
				(type default)
			)
			(layer "F.Fab")
		)
		(fp_line
			(start 0.3048 0.9906)
			(end 0.3048 -0.1016)
			(stroke
				(width 0.1)
				(type default)
			)
			(layer "F.Fab")
		)
		(pad "1" smd rect
			(at 0 0)
			(size 0.508 0.508)
			(layers "F.Cu" "F.Mask" "F.Paste")
			(net "P3E_CPU0_PE2_SS_TXN<7>")
		)
		(pad "2" smd rect
			(at 0 0.889)
			(size 0.508 0.508)
			(layers "F.Cu" "F.Mask" "F.Paste")
			(net "P3E_CPU0_PE2_SS_C_TXN<7>")
		)
		(zone
			(layer "F.Cu")
			(hatch none 0.5)
			(connect_pads
				(clearance 0)
			)
			(min_thickness 0.25)
			(keepout
				(tracks allowed)
				(vias not_allowed)
				(pads allowed)
				(copperpour not_allowed)
				(footprints allowed)
			)
			(placement
				(enabled no)
				(sheetname "")
			)
			(fill
				(thermal_gap 0.5)
				(thermal_bridge_width 0.5)
				(island_removal_mode 0)
			)
			(polygon
				(pts
					(xy 393.889992 -10.282936) (xy 394.397992 -10.282936) (xy 394.397992 -10.663936) (xy 393.889992 -10.663936)
				)
			)
		)
		(zone
			(layer "F.Cu")
			(hatch none 0.5)
			(connect_pads
				(clearance 0)
			)
			(min_thickness 0.25)
			(keepout
				(tracks not_allowed)
				(vias allowed)
				(pads allowed)
				(copperpour not_allowed)
				(footprints allowed)
			)
			(placement
				(enabled no)
				(sheetname "")
			)
			(fill
				(thermal_gap 0.5)
				(thermal_bridge_width 0.5)
				(island_removal_mode 0)
			)
			(polygon
				(pts
					(xy 393.889992 -10.282936) (xy 394.397992 -10.282936) (xy 394.397992 -10.663936) (xy 393.889992 -10.663936)
				)
			)
		)
	)
	(footprint ""
		(layer "F.Cu")
		(at 352.5012 -11.1506 -90)
		(property "Reference" "R7G25"
			(at 0 0 270)
			(layer "F.SilkS")
			(hide yes)
			(effects
				(font
					(size 1.27 1.27)
				)
			)
		)
		(property "Value" ""
			(at 0 0 270)
			(layer "F.Fab")
			(effects
				(font
					(size 1.27 1.27)
				)
			)
		)
		(duplicate_pad_numbers_are_jumpers no)
		(fp_poly
			(pts
				(xy -0.2794 -0.1016) (xy 0.2794 -0.1016) (xy 0.2794 0.9906) (xy -0.2794 0.9906)
			)
			(stroke
				(width 0)
				(type default)
			)
			(fill no)
			(layer "F.CrtYd")
		)
		(fp_line
			(start -0.2794 0.9906)
			(end 0.2794 0.9906)
			(stroke
				(width 0.1)
				(type default)
			)
			(layer "F.Fab")
		)
		(fp_line
			(start 0.2794 0.9906)
			(end 0.2794 -0.1016)
			(stroke
				(width 0.1)
				(type default)
			)
			(layer "F.Fab")
		)
		(fp_line
			(start -0.2794 -0.1016)
			(end -0.2794 0.9906)
			(stroke
				(width 0.1)
				(type default)
			)
			(layer "F.Fab")
		)
		(fp_line
			(start 0.2794 -0.1016)
			(end -0.2794 -0.1016)
			(stroke
				(width 0.1)
				(type default)
			)
			(layer "F.Fab")
		)
		(pad "1" smd rect
			(at 0 0 270)
			(size 0.508 0.508)
			(layers "F.Cu" "F.Mask" "F.Paste")
			(net "VR_PVDDQ_ABC_PH1_OCSET")
		)
		(pad "2" smd rect
			(at 0 0.889 270)
			(size 0.508 0.508)
			(layers "F.Cu" "F.Mask" "F.Paste")
			(net "GND")
		)
		(zone
			(layer "F.Cu")
			(hatch none 0.5)
			(connect_pads
				(clearance 0)
			)
			(min_thickness 0.25)
			(keepout
				(tracks not_allowed)
				(vias allowed)
				(pads allowed)
				(copperpour not_allowed)
				(footprints allowed)
			)
			(placement
				(enabled no)
				(sheetname "")
			)
			(fill
				(thermal_gap 0.5)
				(thermal_bridge_width 0.5)
				(island_removal_mode 0)
			)
			(polygon
				(pts
					(xy 351.8662 -11.4046) (xy 351.8662 -10.8966) (xy 352.2472 -10.8966) (xy 352.2472 -11.4046)
				)
			)
		)
		(zone
			(layer "F.Cu")
			(hatch none 0.5)
			(connect_pads
				(clearance 0)
			)
			(min_thickness 0.25)
			(keepout
				(tracks allowed)
				(vias not_allowed)
				(pads allowed)
				(copperpour not_allowed)
				(footprints allowed)
			)
			(placement
				(enabled no)
				(sheetname "")
			)
			(fill
				(thermal_gap 0.5)
				(thermal_bridge_width 0.5)
				(island_removal_mode 0)
			)
			(polygon
				(pts
					(xy 352.2472 -11.4046) (xy 352.2472 -10.8966) (xy 351.8662 -10.8966) (xy 351.8662 -11.4046)
				)
			)
		)
	)
	(footprint ""
		(layer "F.Cu")
		(at 419.3032 -18.7452)
		(property "Reference" "R9G14"
			(at 0 0 0)
			(layer "F.SilkS")
			(hide yes)
			(effects
				(font
					(size 1.27 1.27)
				)
			)
		)
		(property "Value" ""
			(at 0 0 0)
			(layer "F.Fab")
			(effects
				(font
					(size 1.27 1.27)
				)
			)
		)
		(duplicate_pad_numbers_are_jumpers no)
		(fp_poly
			(pts
				(xy -0.2794 -0.1016) (xy 0.2794 -0.1016) (xy 0.2794 0.9906) (xy -0.2794 0.9906)
			)
			(stroke
				(width 0)
				(type default)
			)
			(fill no)
			(layer "F.CrtYd")
		)
		(fp_line
			(start -0.2794 -0.1016)
			(end -0.2794 0.9906)
			(stroke
				(width 0.1)
				(type default)
			)
			(layer "F.Fab")
		)
		(fp_line
			(start -0.2794 0.9906)
			(end 0.2794 0.9906)
			(stroke
				(width 0.1)
				(type default)
			)
			(layer "F.Fab")
		)
		(fp_line
			(start 0.2794 -0.1016)
			(end -0.2794 -0.1016)
			(stroke
				(width 0.1)
				(type default)
			)
			(layer "F.Fab")
		)
		(fp_line
			(start 0.2794 0.9906)
			(end 0.2794 -0.1016)
			(stroke
				(width 0.1)
				(type default)
			)
			(layer "F.Fab")
		)
		(pad "1" smd rect
			(at 0 0)
			(size 0.508 0.508)
			(layers "F.Cu" "F.Mask" "F.Paste")
			(net "SMB_SENSOR_BMC_STBY_LVC3_SCL")
		)
		(pad "2" smd rect
			(at 0 0.889)
			(size 0.508 0.508)
			(layers "F.Cu" "F.Mask" "F.Paste")
			(net "SMB_SENSOR_STBY_LVC3_SCL")
		)
		(zone
			(layer "F.Cu")
			(hatch none 0.5)
			(connect_pads
				(clearance 0)
			)
			(min_thickness 0.25)
			(keepout
				(tracks allowed)
				(vias not_allowed)
				(pads allowed)
				(copperpour not_allowed)
				(footprints allowed)
			)
			(placement
				(enabled no)
				(sheetname "")
			)
			(fill
				(thermal_gap 0.5)
				(thermal_bridge_width 0.5)
				(island_removal_mode 0)
			)
			(polygon
				(pts
					(xy 419.0492 -18.4912) (xy 419.5572 -18.4912) (xy 419.5572 -18.1102) (xy 419.0492 -18.1102)
				)
			)
		)
		(zone
			(layer "F.Cu")
			(hatch none 0.5)
			(connect_pads
				(clearance 0)
			)
			(min_thickness 0.25)
			(keepout
				(tracks not_allowed)
				(vias allowed)
				(pads allowed)
				(copperpour not_allowed)
				(footprints allowed)
			)
			(placement
				(enabled no)
				(sheetname "")
			)
			(fill
				(thermal_gap 0.5)
				(thermal_bridge_width 0.5)
				(island_removal_mode 0)
			)
			(polygon
				(pts
					(xy 419.0492 -18.1102) (xy 419.5572 -18.1102) (xy 419.5572 -18.4912) (xy 419.0492 -18.4912)
				)
			)
		)
	)
	(footprint ""
		(layer "F.Cu")
		(at 383.286 1.651 90)
		(property "Reference" "R7G21"
			(at 0 0 90)
			(layer "F.SilkS")
			(hide yes)
			(effects
				(font
					(size 1.27 1.27)
				)
			)
		)
		(property "Value" ""
			(at 0 0 90)
			(layer "F.Fab")
			(effects
				(font
					(size 1.27 1.27)
				)
			)
		)
		(duplicate_pad_numbers_are_jumpers no)
		(fp_poly
			(pts
				(xy -0.2794 -0.1016) (xy 0.2794 -0.1016) (xy 0.2794 0.9906) (xy -0.2794 0.9906)
			)
			(stroke
				(width 0)
				(type default)
			)
			(fill no)
			(layer "F.CrtYd")
		)
		(fp_line
			(start 0.2794 -0.1016)
			(end -0.2794 -0.1016)
			(stroke
				(width 0.1)
				(type default)
			)
			(layer "F.Fab")
		)
		(fp_line
			(start -0.2794 -0.1016)
			(end -0.2794 0.9906)
			(stroke
				(width 0.1)
				(type default)
			)
			(layer "F.Fab")
		)
		(fp_line
			(start 0.2794 0.9906)
			(end 0.2794 -0.1016)
			(stroke
				(width 0.1)
				(type default)
			)
			(layer "F.Fab")
		)
		(fp_line
			(start -0.2794 0.9906)
			(end 0.2794 0.9906)
			(stroke
				(width 0.1)
				(type default)
			)
			(layer "F.Fab")
		)
		(pad "1" smd rect
			(at 0 0 90)
			(size 0.508 0.508)
			(layers "F.Cu" "F.Mask" "F.Paste")
			(net "JTAG_TDO")
		)
		(pad "2" smd rect
			(at 0 0.889 90)
			(size 0.508 0.508)
			(layers "F.Cu" "F.Mask" "F.Paste")
			(net "JTAG_TDO_R")
		)
		(zone
			(layer "F.Cu")
			(hatch none 0.5)
			(connect_pads
				(clearance 0)
			)
			(min_thickness 0.25)
			(keepout
				(tracks allowed)
				(vias not_allowed)
				(pads allowed)
				(copperpour not_allowed)
				(footprints allowed)
			)
			(placement
				(enabled no)
				(sheetname "")
			)
			(fill
				(thermal_gap 0.5)
				(thermal_bridge_width 0.5)
				(island_removal_mode 0)
			)
			(polygon
				(pts
					(xy 383.54 1.905) (xy 383.54 1.397) (xy 383.921 1.397) (xy 383.921 1.905)
				)
			)
		)
		(zone
			(layer "F.Cu")
			(hatch none 0.5)
			(connect_pads
				(clearance 0)
			)
			(min_thickness 0.25)
			(keepout
				(tracks not_allowed)
				(vias allowed)
				(pads allowed)
				(copperpour not_allowed)
				(footprints allowed)
			)
			(placement
				(enabled no)
				(sheetname "")
			)
			(fill
				(thermal_gap 0.5)
				(thermal_bridge_width 0.5)
				(island_removal_mode 0)
			)
			(polygon
				(pts
					(xy 383.921 1.905) (xy 383.921 1.397) (xy 383.54 1.397) (xy 383.54 1.905)
				)
			)
		)
	)
	(footprint ""
		(layer "F.Cu")
		(at 206.248 -102.616 90)
		(property "Reference" "R4C4"
			(at 0 0 90)
			(layer "F.SilkS")
			(hide yes)
			(effects
				(font
					(size 1.27 1.27)
				)
			)
		)
		(property "Value" ""
			(at 0 0 90)
			(layer "F.Fab")
			(effects
				(font
					(size 1.27 1.27)
				)
			)
		)
		(duplicate_pad_numbers_are_jumpers no)
		(fp_poly
			(pts
				(xy -0.2794 -0.1016) (xy 0.2794 -0.1016) (xy 0.2794 0.9906) (xy -0.2794 0.9906)
			)
			(stroke
				(width 0)
				(type default)
			)
			(fill no)
			(layer "F.CrtYd")
		)
		(fp_line
			(start 0.2794 -0.1016)
			(end -0.2794 -0.1016)
			(stroke
				(width 0.1)
				(type default)
			)
			(layer "F.Fab")
		)
		(fp_line
			(start -0.2794 -0.1016)
			(end -0.2794 0.9906)
			(stroke
				(width 0.1)
				(type default)
			)
			(layer "F.Fab")
		)
		(fp_line
			(start 0.2794 0.9906)
			(end 0.2794 -0.1016)
			(stroke
				(width 0.1)
				(type default)
			)
			(layer "F.Fab")
		)
		(fp_line
			(start -0.2794 0.9906)
			(end 0.2794 0.9906)
			(stroke
				(width 0.1)
				(type default)
			)
			(layer "F.Fab")
		)
		(pad "1" smd rect
			(at 0 0 90)
			(size 0.508 0.508)
			(layers "F.Cu" "F.Mask" "F.Paste")
			(net "VSENSE_PVSA_CPU0_P")
		)
		(pad "2" smd rect
			(at 0 0.889 90)
			(size 0.508 0.508)
			(layers "F.Cu" "F.Mask" "F.Paste")
			(net "VSENSE_PVSA_CPU0_SKT_VSEN")
		)
		(zone
			(layer "F.Cu")
			(hatch none 0.5)
			(connect_pads
				(clearance 0)
			)
			(min_thickness 0.25)
			(keepout
				(tracks allowed)
				(vias not_allowed)
				(pads allowed)
				(copperpour not_allowed)
				(footprints allowed)
			)
			(placement
				(enabled no)
				(sheetname "")
			)
			(fill
				(thermal_gap 0.5)
				(thermal_bridge_width 0.5)
				(island_removal_mode 0)
			)
			(polygon
				(pts
					(xy 206.502 -102.362) (xy 206.502 -102.87) (xy 206.883 -102.87) (xy 206.883 -102.362)
				)
			)
		)
		(zone
			(layer "F.Cu")
			(hatch none 0.5)
			(connect_pads
				(clearance 0)
			)
			(min_thickness 0.25)
			(keepout
				(tracks not_allowed)
				(vias allowed)
				(pads allowed)
				(copperpour not_allowed)
				(footprints allowed)
			)
			(placement
				(enabled no)
				(sheetname "")
			)
			(fill
				(thermal_gap 0.5)
				(thermal_bridge_width 0.5)
				(island_removal_mode 0)
			)
			(polygon
				(pts
					(xy 206.883 -102.362) (xy 206.883 -102.87) (xy 206.502 -102.87) (xy 206.502 -102.362)
				)
			)
		)
	)
	(footprint ""
		(layer "F.Cu")
		(at 412.085282 -125.863604)
		(property "Reference" "R8B15"
			(at 0 0 0)
			(layer "F.SilkS")
			(hide yes)
			(effects
				(font
					(size 1.27 1.27)
				)
			)
		)
		(property "Value" ""
			(at 0 0 0)
			(layer "F.Fab")
			(effects
				(font
					(size 1.27 1.27)
				)
			)
		)
		(duplicate_pad_numbers_are_jumpers no)
		(fp_poly
			(pts
				(xy -0.2794 -0.1016) (xy 0.2794 -0.1016) (xy 0.2794 0.9906) (xy -0.2794 0.9906)
			)
			(stroke
				(width 0)
				(type default)
			)
			(fill no)
			(layer "F.CrtYd")
		)
		(fp_line
			(start -0.2794 -0.1016)
			(end -0.2794 0.9906)
			(stroke
				(width 0.1)
				(type default)
			)
			(layer "F.Fab")
		)
		(fp_line
			(start -0.2794 0.9906)
			(end 0.2794 0.9906)
			(stroke
				(width 0.1)
				(type default)
			)
			(layer "F.Fab")
		)
		(fp_line
			(start 0.2794 -0.1016)
			(end -0.2794 -0.1016)
			(stroke
				(width 0.1)
				(type default)
			)
			(layer "F.Fab")
		)
		(fp_line
			(start 0.2794 0.9906)
			(end 0.2794 -0.1016)
			(stroke
				(width 0.1)
				(type default)
			)
			(layer "F.Fab")
		)
		(pad "1" smd rect
			(at 0 0)
			(size 0.508 0.508)
			(layers "F.Cu" "F.Mask" "F.Paste")
			(net "VSENSE_P1V05_PCH_STBY_AVSP")
		)
		(pad "2" smd rect
			(at 0 0.889)
			(size 0.508 0.508)
			(layers "F.Cu" "F.Mask" "F.Paste")
			(net "VSENSE_P1V05_PCH_STBY_AVSN")
		)
		(zone
			(layer "F.Cu")
			(hatch none 0.5)
			(connect_pads
				(clearance 0)
			)
			(min_thickness 0.25)
			(keepout
				(tracks allowed)
				(vias not_allowed)
				(pads allowed)
				(copperpour not_allowed)
				(footprints allowed)
			)
			(placement
				(enabled no)
				(sheetname "")
			)
			(fill
				(thermal_gap 0.5)
				(thermal_bridge_width 0.5)
				(island_removal_mode 0)
			)
			(polygon
				(pts
					(xy 411.831282 -125.609604) (xy 412.339282 -125.609604) (xy 412.339282 -125.228604) (xy 411.831282 -125.228604)
				)
			)
		)
		(zone
			(layer "F.Cu")
			(hatch none 0.5)
			(connect_pads
				(clearance 0)
			)
			(min_thickness 0.25)
			(keepout
				(tracks not_allowed)
				(vias allowed)
				(pads allowed)
				(copperpour not_allowed)
				(footprints allowed)
			)
			(placement
				(enabled no)
				(sheetname "")
			)
			(fill
				(thermal_gap 0.5)
				(thermal_bridge_width 0.5)
				(island_removal_mode 0)
			)
			(polygon
				(pts
					(xy 411.831282 -125.228604) (xy 412.339282 -125.228604) (xy 412.339282 -125.609604) (xy 411.831282 -125.609604)
				)
			)
		)
	)
	(footprint ""
		(layer "F.Cu")
		(at 363.87024 -139.30757 90)
		(property "Reference" "R7A11"
			(at 0 0 90)
			(layer "F.SilkS")
			(hide yes)
			(effects
				(font
					(size 1.27 1.27)
				)
			)
		)
		(property "Value" ""
			(at 0 0 90)
			(layer "F.Fab")
			(effects
				(font
					(size 1.27 1.27)
				)
			)
		)
		(duplicate_pad_numbers_are_jumpers no)
		(fp_rect
			(start -0.2794 -0.1016)
			(end 0.2794 0.9906)
			(stroke
				(width 0)
				(type default)
			)
			(fill no)
			(layer "F.CrtYd")
		)
		(fp_line
			(start 0.2794 -0.1016)
			(end -0.2794 -0.1016)
			(stroke
				(width 0.1)
				(type default)
			)
			(layer "F.Fab")
		)
		(fp_line
			(start -0.2794 -0.1016)
			(end -0.2794 0.9906)
			(stroke
				(width 0.1)
				(type default)
			)
			(layer "F.Fab")
		)
		(fp_line
			(start 0.2794 0.9906)
			(end 0.2794 -0.1016)
			(stroke
				(width 0.1)
				(type default)
			)
			(layer "F.Fab")
		)
		(fp_line
			(start -0.2794 0.9906)
			(end 0.2794 0.9906)
			(stroke
				(width 0.1)
				(type default)
			)
			(layer "F.Fab")
		)
		(pad "1" smd rect
			(at 0 0 90)
			(size 0.508 0.508)
			(layers "F.Cu" "F.Mask" "F.Paste")
			(net "SVID_ALERT_PVDDQ_DEF")
		)
		(pad "2" smd rect
			(at 0 0.889 90)
			(size 0.508 0.508)
			(layers "F.Cu" "F.Mask" "F.Paste")
			(net "SVID_ALERT1_CPU0_R_N")
		)
		(zone
			(layer "F.Cu")
			(hatch none 0.5)
			(connect_pads
				(clearance 0)
			)
			(min_thickness 0.25)
			(keepout
				(tracks allowed)
				(vias not_allowed)
				(pads allowed)
				(copperpour not_allowed)
				(footprints allowed)
			)
			(placement
				(enabled no)
				(sheetname "")
			)
			(fill
				(thermal_gap 0.5)
				(thermal_bridge_width 0.5)
				(island_removal_mode 0)
			)
			(polygon
				(pts
					(xy 364.12424 -139.05357) (xy 364.50524 -139.05357) (xy 364.50524 -139.56157) (xy 364.12424 -139.56157)
				)
			)
		)
		(zone
			(layer "F.Cu")
			(hatch none 0.5)
			(connect_pads
				(clearance 0)
			)
			(min_thickness 0.25)
			(keepout
				(tracks not_allowed)
				(vias allowed)
				(pads allowed)
				(copperpour not_allowed)
				(footprints allowed)
			)
			(placement
				(enabled no)
				(sheetname "")
			)
			(fill
				(thermal_gap 0.5)
				(thermal_bridge_width 0.5)
				(island_removal_mode 0)
			)
			(polygon
				(pts
					(xy 364.12424 -139.05357) (xy 364.50524 -139.05357) (xy 364.50524 -139.56157) (xy 364.12424 -139.56157)
				)
			)
		)
	)
	(footprint ""
		(layer "F.Cu")
		(at 423.421048 3.679952 180)
		(property "Reference" "XBT8G1"
			(at 7.65556 5.53847 0)
			(unlocked yes)
			(layer "F.SilkS")
			(effects
				(font
					(size 0.7874 0.5842)
					(thickness 0.1524)
				)
				(justify left)
			)
		)
		(property "Value" ""
			(at 0 0 180)
			(layer "F.Fab")
			(effects
				(font
					(size 1.27 1.27)
				)
			)
		)
		(duplicate_pad_numbers_are_jumpers no)
		(fp_line
			(start 16.774922 4.824984)
			(end -6.774942 4.824984)
			(stroke
				(width 0.1524)
				(type default)
			)
			(layer "F.SilkS")
		)
		(fp_line
			(start 16.774922 -1.225042)
			(end 16.774922 4.824984)
			(stroke
				(width 0.1524)
				(type default)
			)
			(layer "F.SilkS")
		)
		(fp_line
			(start -2.2098 -3.2512)
			(end -2.2098 -1.9812)
			(stroke
				(width 0.1524)
				(type default)
			)
			(layer "F.SilkS")
		)
		(fp_line
			(start -2.8448 -2.6162)
			(end -1.5748 -2.6162)
			(stroke
				(width 0.1524)
				(type default)
			)
			(layer "F.SilkS")
		)
		(fp_line
			(start -6.774942 4.824984)
			(end -6.774942 -1.225042)
			(stroke
				(width 0.1524)
				(type default)
			)
			(layer "F.SilkS")
		)
		(fp_line
			(start -6.774942 -1.225042)
			(end 16.774922 -1.225042)
			(stroke
				(width 0.1524)
				(type default)
			)
			(layer "F.SilkS")
		)
		(fp_poly
			(pts
				(xy -6.774942 -1.225042) (xy -6.774942 4.824984) (xy 16.774922 4.824984) (xy 16.774922 -1.225042)
			)
			(stroke
				(width 0)
				(type default)
			)
			(fill no)
			(layer "F.CrtYd")
		)
		(fp_line
			(start 16.774922 4.824984)
			(end 16.774922 -1.225042)
			(stroke
				(width 0.1)
				(type default)
			)
			(layer "F.Fab")
		)
		(fp_line
			(start 16.774922 -1.225042)
			(end -6.774942 -1.225042)
			(stroke
				(width 0.1)
				(type default)
			)
			(layer "F.Fab")
		)
		(fp_line
			(start -2.2098 -3.2512)
			(end -2.2098 -1.9812)
			(stroke
				(width 0.1)
				(type default)
			)
			(layer "F.Fab")
		)
		(fp_line
			(start -2.8448 -2.6162)
			(end -1.5748 -2.6162)
			(stroke
				(width 0.1)
				(type default)
			)
			(layer "F.Fab")
		)
		(fp_line
			(start -6.774942 4.824984)
			(end 16.774922 4.824984)
			(stroke
				(width 0.1)
				(type default)
			)
			(layer "F.Fab")
		)
		(fp_line
			(start -6.774942 -1.225042)
			(end -6.774942 4.824984)
			(stroke
				(width 0.1)
				(type default)
			)
			(layer "F.Fab")
		)
		(pad "1" thru_hole rect
			(at 0 0 180)
			(size 1.3716 1.3716)
			(drill 0.9906)
			(layers "*.Cu" "*.Mask")
			(remove_unused_layers no)
			(net "P3V_BAT_SOURCE")
			(clearance 0.127)
			(thermal_gap 0.127)
			(padstack
				(mode front_inner_back)
				(layer "Inner"
					(shape circle)
					(size 1.3716 1.3716)
					(clearance 0.127)
				)
				(layer "B.Cu"
					(shape rect)
					(size 1.3716 1.3716)
					(clearance 0.127)
				)
			)
		)
		(pad "2" thru_hole circle
			(at 9.99998 0 180)
			(size 1.3716 1.3716)
			(drill 0.9906)
			(layers "*.Cu" "*.Mask")
			(remove_unused_layers no)
			(net "P3V_BAT_SOURCE")
			(clearance 0.127)
			(thermal_gap 0.127)
		)
		(pad "3" thru_hole circle
			(at 4.99999 3.599942 180)
			(size 1.3716 1.3716)
			(drill 0.9906)
			(layers "*.Cu" "*.Mask")
			(remove_unused_layers no)
			(net "GND")
			(clearance 0.127)
			(thermal_gap 0.127)
		)
	)
	(footprint ""
		(layer "F.Cu")
		(at 171.983146 -146.429222 180)
		(property "Reference" "EU4A2"
			(at 0.787146 -1.904492 0)
			(unlocked yes)
			(layer "F.SilkS")
			(effects
				(font
					(size 0.7874 0.5842)
					(thickness 0.1524)
				)
				(justify left)
			)
		)
		(property "Value" ""
			(at 0 0 180)
			(layer "F.Fab")
			(effects
				(font
					(size 1.27 1.27)
				)
			)
		)
		(duplicate_pad_numbers_are_jumpers no)
		(fp_circle
			(center -0.835152 -0.417322)
			(end -0.962152 -0.417322)
			(stroke
				(width 0.254)
				(type default)
			)
			(fill no)
			(layer "F.SilkS")
		)
		(fp_poly
			(pts
				(xy -0.064516 -1.0922) (xy -0.064516 -0.3302) (xy 0.697484 -1.0922)
			)
			(stroke
				(width 0)
				(type default)
			)
			(fill yes)
			(layer "F.SilkS")
		)
		(fp_rect
			(start 0.597408 2.295398)
			(end 2.273808 -0.295402)
			(stroke
				(width 0)
				(type default)
			)
			(fill yes)
			(layer "F.Paste")
		)
		(fp_rect
			(start -0.064516 2.500122)
			(end 2.935478 -0.500126)
			(stroke
				(width 0)
				(type default)
			)
			(fill no)
			(layer "F.CrtYd")
		)
		(fp_line
			(start 2.935478 2.500122)
			(end -0.064516 2.500122)
			(stroke
				(width 0.1)
				(type default)
			)
			(layer "F.Fab")
		)
		(fp_line
			(start 2.935478 -0.500126)
			(end 2.935478 2.500122)
			(stroke
				(width 0.1)
				(type default)
			)
			(layer "F.Fab")
		)
		(fp_line
			(start -0.064516 2.500122)
			(end -0.064516 -0.500126)
			(stroke
				(width 0.1)
				(type default)
			)
			(layer "F.Fab")
		)
		(fp_line
			(start -0.064516 -0.500126)
			(end 2.935478 -0.500126)
			(stroke
				(width 0.1)
				(type default)
			)
			(layer "F.Fab")
		)
		(fp_circle
			(center -0.835152 -0.417322)
			(end -0.962152 -0.417322)
			(stroke
				(width 0.254)
				(type default)
			)
			(fill no)
			(layer "F.Fab")
		)
		(pad "1" smd rect
			(at 0 0 180)
			(size 0.6858 0.3048)
			(layers "F.Cu" "F.Mask" "F.Paste")
			(net "VR_PVTT_KLM_VREF")
		)
		(pad "2" smd rect
			(at 0 0.500126 180)
			(size 0.6858 0.3048)
			(layers "F.Cu" "F.Mask" "F.Paste")
			(net "VR_PVTT_KLM_BIAS")
		)
		(pad "3" smd rect
			(at 0 0.999998 180)
			(size 0.6858 0.3048)
			(layers "F.Cu" "F.Mask" "F.Paste")
			(net "GND")
		)
		(pad "4" smd rect
			(at 0 1.500124 180)
			(size 0.6858 0.3048)
			(layers "F.Cu" "F.Mask" "F.Paste")
			(net "VSENSE_PVDDQ_KLM_VTT")
		)
		(pad "5" smd rect
			(at 0 1.999996 180)
			(size 0.6858 0.3048)
			(layers "F.Cu" "F.Mask" "F.Paste")
			(net "PWRGD_PVTT_KLM_CPU1_R")
		)
		(pad "6" smd rect
			(at 2.871216 1.999996 180)
			(size 0.6858 0.3048)
			(layers "F.Cu" "F.Mask" "F.Paste")
			(net "VR_PVTT_KLM_SNS")
		)
		(pad "7" smd rect
			(at 2.871216 1.500124 180)
			(size 0.6858 0.3048)
			(layers "F.Cu" "F.Mask" "F.Paste")
			(net "FM_PVTT_KLM_EN_R")
		)
		(pad "8" smd rect
			(at 2.871216 0.999998 180)
			(size 0.6858 0.3048)
			(layers "F.Cu" "F.Mask" "F.Paste")
			(net "GND")
		)
		(pad "9" smd rect
			(at 2.871216 0.500126 180)
			(size 0.6858 0.3048)
			(layers "F.Cu" "F.Mask" "F.Paste")
			(net "PVTT_KLM")
		)
		(pad "10" smd rect
			(at 2.871216 0 180)
			(size 0.6858 0.3048)
			(layers "F.Cu" "F.Mask" "F.Paste")
			(net "PVDDQ_KLM")
		)
		(pad "11" smd rect
			(at 1.435608 0.999998 180)
			(size 1.6764 2.5908)
			(layers "F.Cu" "F.Mask" "F.Paste")
			(net "GND")
		)
	)
	(footprint ""
		(layer "F.Cu")
		(at 14.097 13.2715 -90)
		(property "Reference" "T1P32"
			(at 0 0 270)
			(layer "F.SilkS")
			(hide yes)
			(effects
				(font
					(size 1.27 1.27)
				)
			)
		)
		(property "Value" "*"
			(at 0 -3.44805 270)
			(unlocked yes)
			(layer "F.Fab")
			(hide yes)
			(effects
				(font
					(size 0.889 0.889)
					(thickness 0.1524)
				)
			)
		)
		(property "Device Type" "TPAD-SE-2P-GP_DISCRET-GA1-TPADA"
			(at 0 -4.97205 270)
			(unlocked yes)
			(layer "F.Fab")
			(hide yes)
			(effects
				(font
					(size 0.889 0.889)
					(thickness 0.1524)
				)
			)
		)
		(duplicate_pad_numbers_are_jumpers no)
		(fp_line
			(start -1.016 2.286)
			(end -1.016 -2.286)
			(stroke
				(width 0.1524)
				(type default)
			)
			(layer "F.SilkS")
		)
		(fp_line
			(start 1.016 2.286)
			(end -1.016 2.286)
			(stroke
				(width 0.1524)
				(type default)
			)
			(layer "F.SilkS")
		)
		(fp_line
			(start -1.016 -2.286)
			(end 1.016 -2.286)
			(stroke
				(width 0.1524)
				(type default)
			)
			(layer "F.SilkS")
		)
		(fp_line
			(start 1.016 -2.286)
			(end 1.016 2.286)
			(stroke
				(width 0.1524)
				(type default)
			)
			(layer "F.SilkS")
		)
		(fp_rect
			(start -1.27 2.54)
			(end 1.27 -2.54)
			(stroke
				(width 0)
				(type default)
			)
			(fill no)
			(layer "F.CrtYd")
		)
		(fp_rect
			(start -1.27 2.54)
			(end 1.27 -2.54)
			(stroke
				(width 0)
				(type default)
			)
			(fill no)
			(layer "F.Fab")
		)
		(pad "1" thru_hole circle
			(at 0 -1.27 270)
			(size 1.524 1.524)
			(drill 0.9144)
			(layers "*.Cu" "*.Mask")
			(remove_unused_layers no)
			(net "L3_50OHM_6INCH")
			(clearance -0.0508)
			(thermal_gap 0.127)
			(padstack
				(mode front_inner_back)
				(layer "Inner"
					(shape circle)
					(size 1.1684 1.1684)
					(clearance 0.127)
				)
				(layer "B.Cu"
					(shape circle)
					(size 1.524 1.524)
					(clearance -0.0508)
				)
			)
		)
		(pad "GND1" thru_hole rect
			(at 0 1.27 270)
			(size 1.524 1.524)
			(drill 0.9144)
			(layers "*.Cu" "*.Mask")
			(remove_unused_layers no)
			(net "GND")
			(clearance -0.0508)
			(thermal_gap 0.127)
			(padstack
				(mode front_inner_back)
				(layer "Inner"
					(shape circle)
					(size 1.1684 1.1684)
					(clearance 0.127)
				)
				(layer "B.Cu"
					(shape rect)
					(size 1.524 1.524)
					(clearance -0.0508)
				)
			)
		)
	)
	(footprint ""
		(layer "F.Cu")
		(at 460.2226 -30.734)
		(property "Reference" "R1U2"
			(at 0 0 0)
			(layer "F.SilkS")
			(hide yes)
			(effects
				(font
					(size 1.27 1.27)
				)
			)
		)
		(property "Value" ""
			(at 0 0 0)
			(layer "F.Fab")
			(effects
				(font
					(size 1.27 1.27)
				)
			)
		)
		(duplicate_pad_numbers_are_jumpers no)
		(fp_poly
			(pts
				(xy -0.2794 -0.1016) (xy 0.2794 -0.1016) (xy 0.2794 0.9906) (xy -0.2794 0.9906)
			)
			(stroke
				(width 0)
				(type default)
			)
			(fill no)
			(layer "F.CrtYd")
		)
		(fp_line
			(start -0.2794 -0.1016)
			(end -0.2794 0.9906)
			(stroke
				(width 0.1)
				(type default)
			)
			(layer "F.Fab")
		)
		(fp_line
			(start -0.2794 0.9906)
			(end 0.2794 0.9906)
			(stroke
				(width 0.1)
				(type default)
			)
			(layer "F.Fab")
		)
		(fp_line
			(start 0.2794 -0.1016)
			(end -0.2794 -0.1016)
			(stroke
				(width 0.1)
				(type default)
			)
			(layer "F.Fab")
		)
		(fp_line
			(start 0.2794 0.9906)
			(end 0.2794 -0.1016)
			(stroke
				(width 0.1)
				(type default)
			)
			(layer "F.Fab")
		)
		(pad "1" smd rect
			(at 0 0)
			(size 0.508 0.508)
			(layers "F.Cu" "F.Mask" "F.Paste")
			(net "FAN_TACH2")
		)
		(pad "2" smd rect
			(at 0 0.889)
			(size 0.508 0.508)
			(layers "F.Cu" "F.Mask" "F.Paste")
			(net "GND")
		)
		(zone
			(layer "F.Cu")
			(hatch none 0.5)
			(connect_pads
				(clearance 0)
			)
			(min_thickness 0.25)
			(keepout
				(tracks allowed)
				(vias not_allowed)
				(pads allowed)
				(copperpour not_allowed)
				(footprints allowed)
			)
			(placement
				(enabled no)
				(sheetname "")
			)
			(fill
				(thermal_gap 0.5)
				(thermal_bridge_width 0.5)
				(island_removal_mode 0)
			)
			(polygon
				(pts
					(xy 459.9686 -30.48) (xy 460.4766 -30.48) (xy 460.4766 -30.099) (xy 459.9686 -30.099)
				)
			)
		)
		(zone
			(layer "F.Cu")
			(hatch none 0.5)
			(connect_pads
				(clearance 0)
			)
			(min_thickness 0.25)
			(keepout
				(tracks not_allowed)
				(vias allowed)
				(pads allowed)
				(copperpour not_allowed)
				(footprints allowed)
			)
			(placement
				(enabled no)
				(sheetname "")
			)
			(fill
				(thermal_gap 0.5)
				(thermal_bridge_width 0.5)
				(island_removal_mode 0)
			)
			(polygon
				(pts
					(xy 459.9686 -30.099) (xy 460.4766 -30.099) (xy 460.4766 -30.48) (xy 459.9686 -30.48)
				)
			)
		)
	)
	(footprint ""
		(layer "F.Cu")
		(at 474.080078 -7.789672 -90)
		(property "Reference" "J8G1"
			(at -3.126486 25.39111 0)
			(unlocked yes)
			(layer "F.SilkS")
			(effects
				(font
					(size 0.7874 0.5842)
					(thickness 0.1524)
				)
				(justify left)
			)
		)
		(property "Value" ""
			(at 0 0 270)
			(layer "F.Fab")
			(effects
				(font
					(size 1.27 1.27)
				)
			)
		)
		(duplicate_pad_numbers_are_jumpers no)
		(fp_line
			(start -1.838198 87.444834)
			(end -1.838198 -5.035042)
			(stroke
				(width 0.1524)
				(type default)
			)
			(layer "F.SilkS")
		)
		(fp_line
			(start 5.241798 87.444834)
			(end -1.838198 87.444834)
			(stroke
				(width 0.1524)
				(type default)
			)
			(layer "F.SilkS")
		)
		(fp_line
			(start -1.838198 -5.035042)
			(end 5.241798 -5.035042)
			(stroke
				(width 0.1524)
				(type default)
			)
			(layer "F.SilkS")
		)
		(fp_line
			(start 5.241798 -5.035042)
			(end 5.241798 87.444834)
			(stroke
				(width 0.1524)
				(type default)
			)
			(layer "F.SilkS")
		)
		(fp_poly
			(pts
				(xy -3.493516 -0.447294) (xy -3.493516 0.568706) (xy -2.223516 0.060706)
			)
			(stroke
				(width 0)
				(type default)
			)
			(fill yes)
			(layer "F.SilkS")
		)
		(fp_poly
			(pts
				(arc
					(start 1.7018 85.734144)
					(mid 1.7018 86.775544)
					(end 1.7018 85.734144)
				)
			)
			(stroke
				(width 0)
				(type default)
			)
			(fill yes)
			(layer "F.Paste")
		)
		(fp_poly
			(pts
				(arc
					(start 1.7018 -4.365752)
					(mid 1.7018 -3.324352)
					(end 1.7018 -4.365752)
				)
			)
			(stroke
				(width 0)
				(type default)
			)
			(fill yes)
			(layer "F.Paste")
		)
		(fp_poly
			(pts
				(xy -1.838198 -5.035042) (xy -1.838198 87.444834) (xy 5.241798 87.444834) (xy 5.241798 -5.035042)
			)
			(stroke
				(width 0)
				(type default)
			)
			(fill no)
			(layer "F.CrtYd")
		)
		(fp_line
			(start -1.838198 87.444834)
			(end -1.838198 -5.035042)
			(stroke
				(width 0.1)
				(type default)
			)
			(layer "F.Fab")
		)
		(fp_line
			(start 5.241798 87.444834)
			(end -1.838198 87.444834)
			(stroke
				(width 0.1)
				(type default)
			)
			(layer "F.Fab")
		)
		(fp_line
			(start -1.838198 -5.035042)
			(end 5.241798 -5.035042)
			(stroke
				(width 0.1)
				(type default)
			)
			(layer "F.Fab")
		)
		(fp_line
			(start 5.241798 -5.035042)
			(end 5.241798 87.444834)
			(stroke
				(width 0.1)
				(type default)
			)
			(layer "F.Fab")
		)
		(fp_poly
			(pts
				(xy -3.493516 -0.447294) (xy -3.493516 0.568706) (xy -2.223516 0.060706)
			)
			(stroke
				(width 0)
				(type default)
			)
			(fill yes)
			(layer "F.Fab")
		)
		(fp_text user "199"
			(at -3.02768 83.622388 0)
			(unlocked yes)
			(layer "F.SilkS")
			(effects
				(font
					(size 0.7874 0.5842)
					(thickness 0.1524)
				)
				(justify left)
			)
		)
		(fp_text user "200"
			(at 5.913374 81.83499 0)
			(unlocked yes)
			(layer "F.SilkS")
			(effects
				(font
					(size 0.7874 0.5842)
					(thickness 0.1524)
				)
				(justify left)
			)
		)
		(fp_text user "2"
			(at 6.030214 -2.97561 0)
			(unlocked yes)
			(layer "F.SilkS")
			(effects
				(font
					(size 0.7874 0.5842)
					(thickness 0.1524)
				)
				(justify left)
			)
		)
		(fp_text user "200"
			(at 5.186172 83.647026 90)
			(unlocked yes)
			(layer "F.Fab")
			(effects
				(font
					(size 0.7874 0.5842)
					(thickness 0.1524)
				)
				(justify left)
			)
		)
		(fp_text user "199"
			(at -1.733296 83.38566 270)
			(unlocked yes)
			(layer "F.Fab")
			(effects
				(font
					(size 0.7874 0.5842)
					(thickness 0.1524)
				)
				(justify left)
			)
		)
		(fp_text user "2"
			(at 6.030214 -2.972054 0)
			(unlocked yes)
			(layer "F.Fab")
			(effects
				(font
					(size 0.7874 0.5842)
					(thickness 0.1524)
				)
				(justify left)
			)
		)
		(pad "" np_thru_hole circle
			(at 0.201676 -1.495044 270)
			(size 0.254 0.254)
			(drill 1.27)
			(layers "*.Cu" "*.Mask")
			(clearance 0.8255)
			(thermal_gap 0.8255)
		)
		(pad "" np_thru_hole circle
			(at 1.7018 83.904836 270)
			(size 0.254 0.254)
			(drill 1.27)
			(layers "*.Cu" "*.Mask")
			(clearance 0.8255)
			(thermal_gap 0.8255)
		)
		(pad "1" smd rect
			(at 0 0 270)
			(size 1.1938 0.508)
			(layers "F.Cu" "F.Mask" "F.Paste")
			(net "P12V")
		)
		(pad "2" smd rect
			(at 3.4036 0 270)
			(size 1.1938 0.508)
			(layers "F.Cu" "F.Mask" "F.Paste")
			(net "P12V")
		)
		(pad "3" smd rect
			(at 0 0.8001 270)
			(size 1.1938 0.508)
			(layers "F.Cu" "F.Mask" "F.Paste")
			(net "P12V")
		)
		(pad "4" smd rect
			(at 3.4036 0.8001 270)
			(size 1.1938 0.508)
			(layers "F.Cu" "F.Mask" "F.Paste")
			(net "P12V")
		)
		(pad "5" smd rect
			(at 0 1.6002 270)
			(size 1.1938 0.508)
			(layers "F.Cu" "F.Mask" "F.Paste")
			(net "P12V")
		)
		(pad "6" smd rect
			(at 3.4036 1.6002 270)
			(size 1.1938 0.508)
			(layers "F.Cu" "F.Mask" "F.Paste")
			(net "P12V")
		)
		(pad "7" smd rect
			(at 0 2.4003 270)
			(size 1.1938 0.508)
			(layers "F.Cu" "F.Mask" "F.Paste")
			(net "P12V")
		)
		(pad "8" smd rect
			(at 3.4036 2.4003 270)
			(size 1.1938 0.508)
			(layers "F.Cu" "F.Mask" "F.Paste")
			(net "P12V")
		)
		(pad "9" smd rect
			(at 0 3.2004 270)
			(size 1.1938 0.508)
			(layers "F.Cu" "F.Mask" "F.Paste")
			(net "P12V")
		)
		(pad "10" smd rect
			(at 3.4036 3.2004 270)
			(size 1.1938 0.508)
			(layers "F.Cu" "F.Mask" "F.Paste")
			(net "P12V")
		)
		(pad "11" smd rect
			(at 0 4.0005 270)
			(size 1.1938 0.508)
			(layers "F.Cu" "F.Mask" "F.Paste")
			(net "P12V")
		)
		(pad "12" smd rect
			(at 3.4036 4.0005 270)
			(size 1.1938 0.508)
			(layers "F.Cu" "F.Mask" "F.Paste")
			(net "P12V")
		)
		(pad "13" smd rect
			(at 0 4.8006 270)
			(size 1.1938 0.508)
			(layers "F.Cu" "F.Mask" "F.Paste")
			(net "GND")
		)
		(pad "14" smd rect
			(at 3.4036 4.8006 270)
			(size 1.1938 0.508)
			(layers "F.Cu" "F.Mask" "F.Paste")
			(net "GND")
		)
		(pad "15" smd rect
			(at 0 5.6007 270)
			(size 1.1938 0.508)
			(layers "F.Cu" "F.Mask" "F.Paste")
			(net "SMB_SLOTX24_STBY_LVC3_SDA_R2")
		)
		(pad "16" smd rect
			(at 3.4036 5.6007 270)
			(size 1.1938 0.508)
			(layers "F.Cu" "F.Mask" "F.Paste")
			(net "IRQ_OOB_MGMT_RISER_ALERT_N")
		)
		(pad "17" smd rect
			(at 0 6.4008 270)
			(size 1.1938 0.508)
			(layers "F.Cu" "F.Mask" "F.Paste")
			(net "SMB_SLOTX24_STBY_LVC3_SCL_R2")
		)
		(pad "18" smd rect
			(at 3.4036 6.4008 270)
			(size 1.1938 0.508)
			(layers "F.Cu" "F.Mask" "F.Paste")
			(net "FM_SLT_CFG1")
		)
		(pad "19" smd rect
			(at 0 7.2009 270)
			(size 1.1938 0.508)
			(layers "F.Cu" "F.Mask" "F.Paste")
			(net "FM_SLT_CFG0")
		)
		(pad "20" smd rect
			(at 3.4036 7.2009 270)
			(size 1.1938 0.508)
			(layers "F.Cu" "F.Mask" "F.Paste")
			(net "FM_PWRBRK_SLOT_N")
		)
		(pad "21" smd rect
			(at 0 8.001 270)
			(size 1.1938 0.508)
			(layers "F.Cu" "F.Mask" "F.Paste")
			(net "P3V3")
		)
		(pad "22" smd rect
			(at 3.4036 8.001 270)
			(size 1.1938 0.508)
			(layers "F.Cu" "F.Mask" "F.Paste")
			(net "P3V3")
		)
		(pad "23" smd rect
			(at 0 8.8011 270)
			(size 1.1938 0.508)
			(layers "F.Cu" "F.Mask" "F.Paste")
			(net "P3V3")
		)
		(pad "24" smd rect
			(at 3.4036 8.8011 270)
			(size 1.1938 0.508)
			(layers "F.Cu" "F.Mask" "F.Paste")
			(net "P3V3")
		)
		(pad "25" smd rect
			(at 0 9.6012 270)
			(size 1.1938 0.508)
			(layers "F.Cu" "F.Mask" "F.Paste")
			(net "P3V3_STBY")
		)
		(pad "26" smd rect
			(at 3.4036 9.6012 270)
			(size 1.1938 0.508)
			(layers "F.Cu" "F.Mask" "F.Paste")
			(net "GND")
		)
		(pad "27" smd rect
			(at 0 10.4013 270)
			(size 1.1938 0.508)
			(layers "F.Cu" "F.Mask" "F.Paste")
			(net "PU_PCH_TLS_ENABLE_STRAP")
		)
		(pad "28" smd rect
			(at 3.4036 10.4013 270)
			(size 1.1938 0.508)
			(layers "F.Cu" "F.Mask" "F.Paste")
			(net "FM_PE_SLOTX24_WAKE_N")
		)
		(pad "29" smd rect
			(at 0 11.2014 270)
			(size 1.1938 0.508)
			(layers "F.Cu" "F.Mask" "F.Paste")
			(net "RST_PCIE_RISER1_PERST_R_N")
		)
		(pad "30" smd rect
			(at 3.4036 11.2014 270)
			(size 1.1938 0.508)
			(layers "F.Cu" "F.Mask" "F.Paste")
			(net "SMB_HOST_STBY_LVC3_SDA_R5")
		)
		(pad "31" smd rect
			(at 0 12.0015 270)
			(size 1.1938 0.508)
			(layers "F.Cu" "F.Mask" "F.Paste")
			(net "GND")
		)
		(pad "32" smd rect
			(at 3.4036 12.0015 270)
			(size 1.1938 0.508)
			(layers "F.Cu" "F.Mask" "F.Paste")
			(net "SMB_HOST_STBY_LVC3_SCL_R5")
		)
		(pad "33" smd rect
			(at 0 12.8016 270)
			(size 1.1938 0.508)
			(layers "F.Cu" "F.Mask" "F.Paste")
			(net "CLK_100M_PCH_SLOTX24_S5_DP")
		)
		(pad "34" smd rect
			(at 3.4036 12.8016 270)
			(size 1.1938 0.508)
			(layers "F.Cu" "F.Mask" "F.Paste")
			(net "GND")
		)
		(pad "35" smd rect
			(at 0 13.6017 270)
			(size 1.1938 0.508)
			(layers "F.Cu" "F.Mask" "F.Paste")
			(net "CLK_100M_PCH_SLOTX24_S5_DN")
		)
		(pad "36" smd rect
			(at 3.4036 13.6017 270)
			(size 1.1938 0.508)
			(layers "F.Cu" "F.Mask" "F.Paste")
			(net "CLK_100M_PCH_SLOTX24_S4_DP")
		)
		(pad "37" smd rect
			(at 0 14.4018 270)
			(size 1.1938 0.508)
			(layers "F.Cu" "F.Mask" "F.Paste")
			(net "GND")
		)
		(pad "38" smd rect
			(at 3.4036 14.4018 270)
			(size 1.1938 0.508)
			(layers "F.Cu" "F.Mask" "F.Paste")
			(net "CLK_100M_PCH_SLOTX24_S4_DN")
		)
		(pad "39" smd rect
			(at 0 15.2019 270)
			(size 1.1938 0.508)
			(layers "F.Cu" "F.Mask" "F.Paste")
			(net "CLK_100M_PCH_SLOTX24_S0_DP")
		)
		(pad "40" smd rect
			(at 3.4036 15.2019 270)
			(size 1.1938 0.508)
			(layers "F.Cu" "F.Mask" "F.Paste")
			(net "GND")
		)
		(pad "41" smd rect
			(at 0 16.002 270)
			(size 1.1938 0.508)
			(layers "F.Cu" "F.Mask" "F.Paste")
			(net "CLK_100M_PCH_SLOTX24_S0_DN")
		)
		(pad "42" smd rect
			(at 3.4036 16.002 270)
			(size 1.1938 0.508)
			(layers "F.Cu" "F.Mask" "F.Paste")
			(net "CLK_100M_PCH_SLOTX24_S1_DP")
		)
		(pad "43" smd rect
			(at 0 16.8021 270)
			(size 1.1938 0.508)
			(layers "F.Cu" "F.Mask" "F.Paste")
			(net "GND")
		)
		(pad "44" smd rect
			(at 3.4036 16.8021 270)
			(size 1.1938 0.508)
			(layers "F.Cu" "F.Mask" "F.Paste")
			(net "CLK_100M_PCH_SLOTX24_S1_DN")
		)
		(pad "45" smd rect
			(at 0 17.6022 270)
			(size 1.1938 0.508)
			(layers "F.Cu" "F.Mask" "F.Paste")
			(net "CLK_100M_PCH_SLOTX24_S3_DP")
		)
		(pad "46" smd rect
			(at 3.4036 17.6022 270)
			(size 1.1938 0.508)
			(layers "F.Cu" "F.Mask" "F.Paste")
			(net "GND")
		)
		(pad "47" smd rect
			(at 0 18.4023 270)
			(size 1.1938 0.508)
			(layers "F.Cu" "F.Mask" "F.Paste")
			(net "CLK_100M_PCH_SLOTX24_S3_DN")
		)
		(pad "48" smd rect
			(at 3.4036 18.4023 270)
			(size 1.1938 0.508)
			(layers "F.Cu" "F.Mask" "F.Paste")
			(net "CLK_100M_PCH_SLOTX24_S2_DP")
		)
		(pad "49" smd rect
			(at 0 19.2024 270)
			(size 1.1938 0.508)
			(layers "F.Cu" "F.Mask" "F.Paste")
			(net "GND")
		)
		(pad "50" smd rect
			(at 3.4036 19.2024 270)
			(size 1.1938 0.508)
			(layers "F.Cu" "F.Mask" "F.Paste")
			(net "CLK_100M_PCH_SLOTX24_S2_DN")
		)
		(pad "51" smd rect
			(at 0 20.0025 270)
			(size 1.1938 0.508)
			(layers "F.Cu" "F.Mask" "F.Paste")
			(net "P3E_CPU0_PE1_PCH_CON_TXN<15>")
		)
		(pad "52" smd rect
			(at 3.4036 20.0025 270)
			(size 1.1938 0.508)
			(layers "F.Cu" "F.Mask" "F.Paste")
			(net "GND")
		)
		(pad "53" smd rect
			(at 0 20.8026 270)
			(size 1.1938 0.508)
			(layers "F.Cu" "F.Mask" "F.Paste")
			(net "P3E_CPU0_PE1_PCH_CON_TXP<15>")
		)
		(pad "54" smd rect
			(at 3.4036 20.8026 270)
			(size 1.1938 0.508)
			(layers "F.Cu" "F.Mask" "F.Paste")
			(net "P3E_CPU0_PE1_PCH_CON_RXN<15>")
		)
		(pad "55" smd rect
			(at 0 21.6027 270)
			(size 1.1938 0.508)
			(layers "F.Cu" "F.Mask" "F.Paste")
			(net "GND")
		)
		(pad "56" smd rect
			(at 3.4036 21.6027 270)
			(size 1.1938 0.508)
			(layers "F.Cu" "F.Mask" "F.Paste")
			(net "P3E_CPU0_PE1_PCH_CON_RXP<15>")
		)
		(pad "57" smd rect
			(at 0 22.4028 270)
			(size 1.1938 0.508)
			(layers "F.Cu" "F.Mask" "F.Paste")
			(net "P3E_CPU0_PE1_PCH_CON_TXP<14>")
		)
		(pad "58" smd rect
			(at 3.4036 22.4028 270)
			(size 1.1938 0.508)
			(layers "F.Cu" "F.Mask" "F.Paste")
			(net "GND")
		)
		(pad "59" smd rect
			(at 0 23.2029 270)
			(size 1.1938 0.508)
			(layers "F.Cu" "F.Mask" "F.Paste")
			(net "P3E_CPU0_PE1_PCH_CON_TXN<14>")
		)
		(pad "60" smd rect
			(at 3.4036 23.2029 270)
			(size 1.1938 0.508)
			(layers "F.Cu" "F.Mask" "F.Paste")
			(net "P3E_CPU0_PE1_PCH_CON_RXN<14>")
		)
		(pad "61" smd rect
			(at 0 24.003 270)
			(size 1.1938 0.508)
			(layers "F.Cu" "F.Mask" "F.Paste")
			(net "GND")
		)
		(pad "62" smd rect
			(at 3.4036 24.003 270)
			(size 1.1938 0.508)
			(layers "F.Cu" "F.Mask" "F.Paste")
			(net "P3E_CPU0_PE1_PCH_CON_RXP<14>")
		)
		(pad "63" smd rect
			(at 0 24.8031 270)
			(size 1.1938 0.508)
			(layers "F.Cu" "F.Mask" "F.Paste")
			(net "TP_SLOTX24_RSVD63")
		)
		(pad "64" smd rect
			(at 3.4036 24.8031 270)
			(size 1.1938 0.508)
			(layers "F.Cu" "F.Mask" "F.Paste")
			(net "GND")
		)
		(pad "65" smd rect
			(at 0 28.803092 270)
			(size 1.1938 0.508)
			(layers "F.Cu" "F.Mask" "F.Paste")
			(net "GND")
		)
		(pad "66" smd rect
			(at 3.4036 28.803092 270)
			(size 1.1938 0.508)
			(layers "F.Cu" "F.Mask" "F.Paste")
			(net "TP_SLOTX24_RSVD66")
		)
		(pad "67" smd rect
			(at 0 29.603192 270)
			(size 1.1938 0.508)
			(layers "F.Cu" "F.Mask" "F.Paste")
			(net "P3E_CPU0_PE1_PCH_CON_TXN<13>")
		)
		(pad "68" smd rect
			(at 3.4036 29.603192 270)
			(size 1.1938 0.508)
			(layers "F.Cu" "F.Mask" "F.Paste")
			(net "GND")
		)
		(pad "69" smd rect
			(at 0 30.403292 270)
			(size 1.1938 0.508)
			(layers "F.Cu" "F.Mask" "F.Paste")
			(net "P3E_CPU0_PE1_PCH_CON_TXP<13>")
		)
		(pad "70" smd rect
			(at 3.4036 30.403292 270)
			(size 1.1938 0.508)
			(layers "F.Cu" "F.Mask" "F.Paste")
			(net "P3E_CPU0_PE1_PCH_CON_RXN<13>")
		)
		(pad "71" smd rect
			(at 0 31.203392 270)
			(size 1.1938 0.508)
			(layers "F.Cu" "F.Mask" "F.Paste")
			(net "GND")
		)
		(pad "72" smd rect
			(at 3.4036 31.203392 270)
			(size 1.1938 0.508)
			(layers "F.Cu" "F.Mask" "F.Paste")
			(net "P3E_CPU0_PE1_PCH_CON_RXP<13>")
		)
		(pad "73" smd rect
			(at 0 32.003492 270)
			(size 1.1938 0.508)
			(layers "F.Cu" "F.Mask" "F.Paste")
			(net "P3E_CPU0_PE1_PCH_CON_TXN<12>")
		)
		(pad "74" smd rect
			(at 3.4036 32.003492 270)
			(size 1.1938 0.508)
			(layers "F.Cu" "F.Mask" "F.Paste")
			(net "GND")
		)
		(pad "75" smd rect
			(at 0 32.803592 270)
			(size 1.1938 0.508)
			(layers "F.Cu" "F.Mask" "F.Paste")
			(net "P3E_CPU0_PE1_PCH_CON_TXP<12>")
		)
		(pad "76" smd rect
			(at 3.4036 32.803592 270)
			(size 1.1938 0.508)
			(layers "F.Cu" "F.Mask" "F.Paste")
			(net "P3E_CPU0_PE1_PCH_CON_RXN<12>")
		)
		(pad "77" smd rect
			(at 0 33.603692 270)
			(size 1.1938 0.508)
			(layers "F.Cu" "F.Mask" "F.Paste")
			(net "GND")
		)
		(pad "78" smd rect
			(at 3.4036 33.603692 270)
			(size 1.1938 0.508)
			(layers "F.Cu" "F.Mask" "F.Paste")
			(net "P3E_CPU0_PE1_PCH_CON_RXP<12>")
		)
		(pad "79" smd rect
			(at 0 34.403792 270)
			(size 1.1938 0.508)
			(layers "F.Cu" "F.Mask" "F.Paste")
			(net "P3E_CPU0_PE1_PCH_CON_TXN<11>")
		)
		(pad "80" smd rect
			(at 3.4036 34.403792 270)
			(size 1.1938 0.508)
			(layers "F.Cu" "F.Mask" "F.Paste")
			(net "GND")
		)
		(pad "81" smd rect
			(at 0 35.203892 270)
			(size 1.1938 0.508)
			(layers "F.Cu" "F.Mask" "F.Paste")
			(net "P3E_CPU0_PE1_PCH_CON_TXP<11>")
		)
		(pad "82" smd rect
			(at 3.4036 35.203892 270)
			(size 1.1938 0.508)
			(layers "F.Cu" "F.Mask" "F.Paste")
			(net "P3E_CPU0_PE1_PCH_CON_RXN<11>")
		)
		(pad "83" smd rect
			(at 0 36.003992 270)
			(size 1.1938 0.508)
			(layers "F.Cu" "F.Mask" "F.Paste")
			(net "GND")
		)
		(pad "84" smd rect
			(at 3.4036 36.003992 270)
			(size 1.1938 0.508)
			(layers "F.Cu" "F.Mask" "F.Paste")
			(net "P3E_CPU0_PE1_PCH_CON_RXP<11>")
		)
		(pad "85" smd rect
			(at 0 36.804092 270)
			(size 1.1938 0.508)
			(layers "F.Cu" "F.Mask" "F.Paste")
			(net "P3E_CPU0_PE1_PCH_CON_TXN<10>")
		)
		(pad "86" smd rect
			(at 3.4036 36.804092 270)
			(size 1.1938 0.508)
			(layers "F.Cu" "F.Mask" "F.Paste")
			(net "GND")
		)
		(pad "87" smd rect
			(at 0 37.604192 270)
			(size 1.1938 0.508)
			(layers "F.Cu" "F.Mask" "F.Paste")
			(net "P3E_CPU0_PE1_PCH_CON_TXP<10>")
		)
		(pad "88" smd rect
			(at 3.4036 37.604192 270)
			(size 1.1938 0.508)
			(layers "F.Cu" "F.Mask" "F.Paste")
			(net "P3E_CPU0_PE1_PCH_CON_RXN<10>")
		)
		(pad "89" smd rect
			(at 0 38.404292 270)
			(size 1.1938 0.508)
			(layers "F.Cu" "F.Mask" "F.Paste")
			(net "GND")
		)
		(pad "90" smd rect
			(at 3.4036 38.404292 270)
			(size 1.1938 0.508)
			(layers "F.Cu" "F.Mask" "F.Paste")
			(net "P3E_CPU0_PE1_PCH_CON_RXP<10>")
		)
		(pad "91" smd rect
			(at 0 39.204392 270)
			(size 1.1938 0.508)
			(layers "F.Cu" "F.Mask" "F.Paste")
			(net "P3E_CPU0_PE1_PCH_CON_TXN<9>")
		)
		(pad "92" smd rect
			(at 3.4036 39.204392 270)
			(size 1.1938 0.508)
			(layers "F.Cu" "F.Mask" "F.Paste")
			(net "GND")
		)
		(pad "93" smd rect
			(at 0 40.004492 270)
			(size 1.1938 0.508)
			(layers "F.Cu" "F.Mask" "F.Paste")
			(net "P3E_CPU0_PE1_PCH_CON_TXP<9>")
		)
		(pad "94" smd rect
			(at 3.4036 40.004492 270)
			(size 1.1938 0.508)
			(layers "F.Cu" "F.Mask" "F.Paste")
			(net "P3E_CPU0_PE1_PCH_CON_RXN<9>")
		)
		(pad "95" smd rect
			(at 0 40.804592 270)
			(size 1.1938 0.508)
			(layers "F.Cu" "F.Mask" "F.Paste")
			(net "GND")
		)
		(pad "96" smd rect
			(at 3.4036 40.804592 270)
			(size 1.1938 0.508)
			(layers "F.Cu" "F.Mask" "F.Paste")
			(net "P3E_CPU0_PE1_PCH_CON_RXP<9>")
		)
		(pad "97" smd rect
			(at 0 41.604692 270)
			(size 1.1938 0.508)
			(layers "F.Cu" "F.Mask" "F.Paste")
			(net "P3E_CPU0_PE1_PCH_CON_TXN<8>")
		)
		(pad "98" smd rect
			(at 3.4036 41.604692 270)
			(size 1.1938 0.508)
			(layers "F.Cu" "F.Mask" "F.Paste")
			(net "GND")
		)
		(pad "99" smd rect
			(at 0 42.404792 270)
			(size 1.1938 0.508)
			(layers "F.Cu" "F.Mask" "F.Paste")
			(net "P3E_CPU0_PE1_PCH_CON_TXP<8>")
		)
		(pad "100" smd rect
			(at 3.4036 42.404792 270)
			(size 1.1938 0.508)
			(layers "F.Cu" "F.Mask" "F.Paste")
			(net "P3E_CPU0_PE1_PCH_CON_RXN<8>")
		)
		(pad "101" smd rect
			(at 0 43.204892 270)
			(size 1.1938 0.508)
			(layers "F.Cu" "F.Mask" "F.Paste")
			(net "GND")
		)
		(pad "102" smd rect
			(at 3.4036 43.204892 270)
			(size 1.1938 0.508)
			(layers "F.Cu" "F.Mask" "F.Paste")
			(net "P3E_CPU0_PE1_PCH_CON_RXP<8>")
		)
		(pad "103" smd rect
			(at 0 44.004992 270)
			(size 1.1938 0.508)
			(layers "F.Cu" "F.Mask" "F.Paste")
			(net "P3E_CPU0_PE1_SS_C_TXP<7>")
		)
		(pad "104" smd rect
			(at 3.4036 44.004992 270)
			(size 1.1938 0.508)
			(layers "F.Cu" "F.Mask" "F.Paste")
			(net "GND")
		)
		(pad "105" smd rect
			(at 0 44.805092 270)
			(size 1.1938 0.508)
			(layers "F.Cu" "F.Mask" "F.Paste")
			(net "P3E_CPU0_PE1_SS_C_TXN<7>")
		)
		(pad "106" smd rect
			(at 3.4036 44.805092 270)
			(size 1.1938 0.508)
			(layers "F.Cu" "F.Mask" "F.Paste")
			(net "P3E_CPU0_PE1_SS_R_RXN<7>")
		)
		(pad "107" smd rect
			(at 0 45.605192 270)
			(size 1.1938 0.508)
			(layers "F.Cu" "F.Mask" "F.Paste")
			(net "GND")
		)
		(pad "108" smd rect
			(at 3.4036 45.605192 270)
			(size 1.1938 0.508)
			(layers "F.Cu" "F.Mask" "F.Paste")
			(net "P3E_CPU0_PE1_SS_R_RXP<7>")
		)
		(pad "109" smd rect
			(at 0 46.405292 270)
			(size 1.1938 0.508)
			(layers "F.Cu" "F.Mask" "F.Paste")
			(net "P3E_CPU0_PE1_SS_C_TXN<6>")
		)
		(pad "110" smd rect
			(at 3.4036 46.405292 270)
			(size 1.1938 0.508)
			(layers "F.Cu" "F.Mask" "F.Paste")
			(net "GND")
		)
		(pad "111" smd rect
			(at 0 47.205392 270)
			(size 1.1938 0.508)
			(layers "F.Cu" "F.Mask" "F.Paste")
			(net "P3E_CPU0_PE1_SS_C_TXP<6>")
		)
		(pad "112" smd rect
			(at 3.4036 47.205392 270)
			(size 1.1938 0.508)
			(layers "F.Cu" "F.Mask" "F.Paste")
			(net "P3E_CPU0_PE1_SS_R_RXN<6>")
		)
		(pad "113" smd rect
			(at 0 48.005492 270)
			(size 1.1938 0.508)
			(layers "F.Cu" "F.Mask" "F.Paste")
			(net "GND")
		)
		(pad "114" smd rect
			(at 3.4036 48.005492 270)
			(size 1.1938 0.508)
			(layers "F.Cu" "F.Mask" "F.Paste")
			(net "P3E_CPU0_PE1_SS_R_RXP<6>")
		)
		(pad "115" smd rect
			(at 0 48.805592 270)
			(size 1.1938 0.508)
			(layers "F.Cu" "F.Mask" "F.Paste")
			(net "P3E_CPU0_PE1_SS_C_TXN<5>")
		)
		(pad "116" smd rect
			(at 3.4036 48.805592 270)
			(size 1.1938 0.508)
			(layers "F.Cu" "F.Mask" "F.Paste")
			(net "GND")
		)
		(pad "117" smd rect
			(at 0 49.605692 270)
			(size 1.1938 0.508)
			(layers "F.Cu" "F.Mask" "F.Paste")
			(net "P3E_CPU0_PE1_SS_C_TXP<5>")
		)
		(pad "118" smd rect
			(at 3.4036 49.605692 270)
			(size 1.1938 0.508)
			(layers "F.Cu" "F.Mask" "F.Paste")
			(net "P3E_CPU0_PE1_SS_R_RXN<5>")
		)
		(pad "119" smd rect
			(at 0 50.405792 270)
			(size 1.1938 0.508)
			(layers "F.Cu" "F.Mask" "F.Paste")
			(net "GND")
		)
		(pad "120" smd rect
			(at 3.4036 50.405792 270)
			(size 1.1938 0.508)
			(layers "F.Cu" "F.Mask" "F.Paste")
			(net "P3E_CPU0_PE1_SS_R_RXP<5>")
		)
		(pad "121" smd rect
			(at 0 51.205892 270)
			(size 1.1938 0.508)
			(layers "F.Cu" "F.Mask" "F.Paste")
			(net "P3E_CPU0_PE1_SS_C_TXN<4>")
		)
		(pad "122" smd rect
			(at 3.4036 51.205892 270)
			(size 1.1938 0.508)
			(layers "F.Cu" "F.Mask" "F.Paste")
			(net "GND")
		)
		(pad "123" smd rect
			(at 0 52.005992 270)
			(size 1.1938 0.508)
			(layers "F.Cu" "F.Mask" "F.Paste")
			(net "P3E_CPU0_PE1_SS_C_TXP<4>")
		)
		(pad "124" smd rect
			(at 3.4036 52.005992 270)
			(size 1.1938 0.508)
			(layers "F.Cu" "F.Mask" "F.Paste")
			(net "P3E_CPU0_PE1_SS_R_RXN<4>")
		)
		(pad "125" smd rect
			(at 0 52.806092 270)
			(size 1.1938 0.508)
			(layers "F.Cu" "F.Mask" "F.Paste")
			(net "GND")
		)
		(pad "126" smd rect
			(at 3.4036 52.806092 270)
			(size 1.1938 0.508)
			(layers "F.Cu" "F.Mask" "F.Paste")
			(net "P3E_CPU0_PE1_SS_R_RXP<4>")
		)
		(pad "127" smd rect
			(at 0 53.606192 270)
			(size 1.1938 0.508)
			(layers "F.Cu" "F.Mask" "F.Paste")
			(net "P3E_CPU0_PE1_SS_C_TXN<3>")
		)
		(pad "128" smd rect
			(at 3.4036 53.606192 270)
			(size 1.1938 0.508)
			(layers "F.Cu" "F.Mask" "F.Paste")
			(net "GND")
		)
		(pad "129" smd rect
			(at 0 54.406292 270)
			(size 1.1938 0.508)
			(layers "F.Cu" "F.Mask" "F.Paste")
			(net "P3E_CPU0_PE1_SS_C_TXP<3>")
		)
		(pad "130" smd rect
			(at 3.4036 54.406292 270)
			(size 1.1938 0.508)
			(layers "F.Cu" "F.Mask" "F.Paste")
			(net "P3E_CPU0_PE1_SS_R_RXN<3>")
		)
		(pad "131" smd rect
			(at 0 55.206392 270)
			(size 1.1938 0.508)
			(layers "F.Cu" "F.Mask" "F.Paste")
			(net "GND")
		)
		(pad "132" smd rect
			(at 3.4036 55.206392 270)
			(size 1.1938 0.508)
			(layers "F.Cu" "F.Mask" "F.Paste")
			(net "P3E_CPU0_PE1_SS_R_RXP<3>")
		)
		(pad "133" smd rect
			(at 0 56.006492 270)
			(size 1.1938 0.508)
			(layers "F.Cu" "F.Mask" "F.Paste")
			(net "P3E_CPU0_PE1_SS_C_TXN<2>")
		)
		(pad "134" smd rect
			(at 3.4036 56.006492 270)
			(size 1.1938 0.508)
			(layers "F.Cu" "F.Mask" "F.Paste")
			(net "GND")
		)
		(pad "135" smd rect
			(at 0 56.806592 270)
			(size 1.1938 0.508)
			(layers "F.Cu" "F.Mask" "F.Paste")
			(net "P3E_CPU0_PE1_SS_C_TXP<2>")
		)
		(pad "136" smd rect
			(at 3.4036 56.806592 270)
			(size 1.1938 0.508)
			(layers "F.Cu" "F.Mask" "F.Paste")
			(net "P3E_CPU0_PE1_SS_R_RXN<2>")
		)
		(pad "137" smd rect
			(at 0 57.606692 270)
			(size 1.1938 0.508)
			(layers "F.Cu" "F.Mask" "F.Paste")
			(net "GND")
		)
		(pad "138" smd rect
			(at 3.4036 57.606692 270)
			(size 1.1938 0.508)
			(layers "F.Cu" "F.Mask" "F.Paste")
			(net "P3E_CPU0_PE1_SS_R_RXP<2>")
		)
		(pad "139" smd rect
			(at 0 58.406792 270)
			(size 1.1938 0.508)
			(layers "F.Cu" "F.Mask" "F.Paste")
			(net "P3E_CPU0_PE1_SS_C_TXN<1>")
		)
		(pad "140" smd rect
			(at 3.4036 58.406792 270)
			(size 1.1938 0.508)
			(layers "F.Cu" "F.Mask" "F.Paste")
			(net "GND")
		)
		(pad "141" smd rect
			(at 0 59.206892 270)
			(size 1.1938 0.508)
			(layers "F.Cu" "F.Mask" "F.Paste")
			(net "P3E_CPU0_PE1_SS_C_TXP<1>")
		)
		(pad "142" smd rect
			(at 3.4036 59.206892 270)
			(size 1.1938 0.508)
			(layers "F.Cu" "F.Mask" "F.Paste")
			(net "P3E_CPU0_PE1_SS_R_RXN<1>")
		)
		(pad "143" smd rect
			(at 0 60.006992 270)
			(size 1.1938 0.508)
			(layers "F.Cu" "F.Mask" "F.Paste")
			(net "GND")
		)
		(pad "144" smd rect
			(at 3.4036 60.006992 270)
			(size 1.1938 0.508)
			(layers "F.Cu" "F.Mask" "F.Paste")
			(net "P3E_CPU0_PE1_SS_R_RXP<1>")
		)
		(pad "145" smd rect
			(at 0 60.807092 270)
			(size 1.1938 0.508)
			(layers "F.Cu" "F.Mask" "F.Paste")
			(net "P3E_CPU0_PE1_SS_C_TXN<0>")
		)
		(pad "146" smd rect
			(at 3.4036 60.807092 270)
			(size 1.1938 0.508)
			(layers "F.Cu" "F.Mask" "F.Paste")
			(net "GND")
		)
		(pad "147" smd rect
			(at 0 61.607192 270)
			(size 1.1938 0.508)
			(layers "F.Cu" "F.Mask" "F.Paste")
			(net "P3E_CPU0_PE1_SS_C_TXP<0>")
		)
		(pad "148" smd rect
			(at 3.4036 61.607192 270)
			(size 1.1938 0.508)
			(layers "F.Cu" "F.Mask" "F.Paste")
			(net "P3E_CPU0_PE1_SS_R_RXN<0>")
		)
		(pad "149" smd rect
			(at 0 62.407292 270)
			(size 1.1938 0.508)
			(layers "F.Cu" "F.Mask" "F.Paste")
			(net "GND")
		)
		(pad "150" smd rect
			(at 3.4036 62.407292 270)
			(size 1.1938 0.508)
			(layers "F.Cu" "F.Mask" "F.Paste")
			(net "P3E_CPU0_PE1_SS_R_RXP<0>")
		)
		(pad "151" smd rect
			(at 0 63.207392 270)
			(size 1.1938 0.508)
			(layers "F.Cu" "F.Mask" "F.Paste")
			(net "P3E_CPU0_PE2_SS_C_TXN<0>")
		)
		(pad "152" smd rect
			(at 3.4036 63.207392 270)
			(size 1.1938 0.508)
			(layers "F.Cu" "F.Mask" "F.Paste")
			(net "GND")
		)
		(pad "153" smd rect
			(at 0 64.007492 270)
			(size 1.1938 0.508)
			(layers "F.Cu" "F.Mask" "F.Paste")
			(net "P3E_CPU0_PE2_SS_C_TXP<0>")
		)
		(pad "154" smd rect
			(at 3.4036 64.007492 270)
			(size 1.1938 0.508)
			(layers "F.Cu" "F.Mask" "F.Paste")
			(net "P3E_CPU0_PE2_SS_RXN<0>")
		)
		(pad "155" smd rect
			(at 0 64.807592 270)
			(size 1.1938 0.508)
			(layers "F.Cu" "F.Mask" "F.Paste")
			(net "GND")
		)
		(pad "156" smd rect
			(at 3.4036 64.807592 270)
			(size 1.1938 0.508)
			(layers "F.Cu" "F.Mask" "F.Paste")
			(net "P3E_CPU0_PE2_SS_RXP<0>")
		)
		(pad "157" smd rect
			(at 0 65.607692 270)
			(size 1.1938 0.508)
			(layers "F.Cu" "F.Mask" "F.Paste")
			(net "P3E_CPU0_PE2_SS_C_TXP<1>")
		)
		(pad "158" smd rect
			(at 3.4036 65.607692 270)
			(size 1.1938 0.508)
			(layers "F.Cu" "F.Mask" "F.Paste")
			(net "GND")
		)
		(pad "159" smd rect
			(at 0 66.407792 270)
			(size 1.1938 0.508)
			(layers "F.Cu" "F.Mask" "F.Paste")
			(net "P3E_CPU0_PE2_SS_C_TXN<1>")
		)
		(pad "160" smd rect
			(at 3.4036 66.407792 270)
			(size 1.1938 0.508)
			(layers "F.Cu" "F.Mask" "F.Paste")
			(net "P3E_CPU0_PE2_SS_RXN<1>")
		)
		(pad "161" smd rect
			(at 0 67.207892 270)
			(size 1.1938 0.508)
			(layers "F.Cu" "F.Mask" "F.Paste")
			(net "GND")
		)
		(pad "162" smd rect
			(at 3.4036 67.207892 270)
			(size 1.1938 0.508)
			(layers "F.Cu" "F.Mask" "F.Paste")
			(net "P3E_CPU0_PE2_SS_RXP<1>")
		)
		(pad "163" smd rect
			(at 0 68.007992 270)
			(size 1.1938 0.508)
			(layers "F.Cu" "F.Mask" "F.Paste")
			(net "P3E_CPU0_PE2_SS_C_TXN<2>")
		)
		(pad "164" smd rect
			(at 3.4036 68.007992 270)
			(size 1.1938 0.508)
			(layers "F.Cu" "F.Mask" "F.Paste")
			(net "GND")
		)
		(pad "165" smd rect
			(at 0 68.808092 270)
			(size 1.1938 0.508)
			(layers "F.Cu" "F.Mask" "F.Paste")
			(net "P3E_CPU0_PE2_SS_C_TXP<2>")
		)
		(pad "166" smd rect
			(at 3.4036 68.808092 270)
			(size 1.1938 0.508)
			(layers "F.Cu" "F.Mask" "F.Paste")
			(net "P3E_CPU0_PE2_SS_RXN<2>")
		)
		(pad "167" smd rect
			(at 0 69.608192 270)
			(size 1.1938 0.508)
			(layers "F.Cu" "F.Mask" "F.Paste")
			(net "GND")
		)
		(pad "168" smd rect
			(at 3.4036 69.608192 270)
			(size 1.1938 0.508)
			(layers "F.Cu" "F.Mask" "F.Paste")
			(net "P3E_CPU0_PE2_SS_RXP<2>")
		)
		(pad "169" smd rect
			(at 0 70.408292 270)
			(size 1.1938 0.508)
			(layers "F.Cu" "F.Mask" "F.Paste")
			(net "P3E_CPU0_PE2_SS_C_TXN<3>")
		)
		(pad "170" smd rect
			(at 3.4036 70.408292 270)
			(size 1.1938 0.508)
			(layers "F.Cu" "F.Mask" "F.Paste")
			(net "GND")
		)
		(pad "171" smd rect
			(at 0 71.208392 270)
			(size 1.1938 0.508)
			(layers "F.Cu" "F.Mask" "F.Paste")
			(net "P3E_CPU0_PE2_SS_C_TXP<3>")
		)
		(pad "172" smd rect
			(at 3.4036 71.208392 270)
			(size 1.1938 0.508)
			(layers "F.Cu" "F.Mask" "F.Paste")
			(net "P3E_CPU0_PE2_SS_RXN<3>")
		)
		(pad "173" smd rect
			(at 0 72.008492 270)
			(size 1.1938 0.508)
			(layers "F.Cu" "F.Mask" "F.Paste")
			(net "GND")
		)
		(pad "174" smd rect
			(at 3.4036 72.008492 270)
			(size 1.1938 0.508)
			(layers "F.Cu" "F.Mask" "F.Paste")
			(net "P3E_CPU0_PE2_SS_RXP<3>")
		)
		(pad "175" smd rect
			(at 0 72.808592 270)
			(size 1.1938 0.508)
			(layers "F.Cu" "F.Mask" "F.Paste")
			(net "P3E_CPU0_PE2_SS_C_TXN<4>")
		)
		(pad "176" smd rect
			(at 3.4036 72.808592 270)
			(size 1.1938 0.508)
			(layers "F.Cu" "F.Mask" "F.Paste")
			(net "GND")
		)
		(pad "177" smd rect
			(at 0 73.608692 270)
			(size 1.1938 0.508)
			(layers "F.Cu" "F.Mask" "F.Paste")
			(net "P3E_CPU0_PE2_SS_C_TXP<4>")
		)
		(pad "178" smd rect
			(at 3.4036 73.608692 270)
			(size 1.1938 0.508)
			(layers "F.Cu" "F.Mask" "F.Paste")
			(net "P3E_CPU0_PE2_SS_RXN<4>")
		)
		(pad "179" smd rect
			(at 0 74.408792 270)
			(size 1.1938 0.508)
			(layers "F.Cu" "F.Mask" "F.Paste")
			(net "GND")
		)
		(pad "180" smd rect
			(at 3.4036 74.408792 270)
			(size 1.1938 0.508)
			(layers "F.Cu" "F.Mask" "F.Paste")
			(net "P3E_CPU0_PE2_SS_RXP<4>")
		)
		(pad "181" smd rect
			(at 0 75.208892 270)
			(size 1.1938 0.508)
			(layers "F.Cu" "F.Mask" "F.Paste")
			(net "P3E_CPU0_PE2_SS_C_TXN<5>")
		)
		(pad "182" smd rect
			(at 3.4036 75.208892 270)
			(size 1.1938 0.508)
			(layers "F.Cu" "F.Mask" "F.Paste")
			(net "GND")
		)
		(pad "183" smd rect
			(at 0 76.008992 270)
			(size 1.1938 0.508)
			(layers "F.Cu" "F.Mask" "F.Paste")
			(net "P3E_CPU0_PE2_SS_C_TXP<5>")
		)
		(pad "184" smd rect
			(at 3.4036 76.008992 270)
			(size 1.1938 0.508)
			(layers "F.Cu" "F.Mask" "F.Paste")
			(net "P3E_CPU0_PE2_SS_RXN<5>")
		)
		(pad "185" smd rect
			(at 0 76.809092 270)
			(size 1.1938 0.508)
			(layers "F.Cu" "F.Mask" "F.Paste")
			(net "GND")
		)
		(pad "186" smd rect
			(at 3.4036 76.809092 270)
			(size 1.1938 0.508)
			(layers "F.Cu" "F.Mask" "F.Paste")
			(net "P3E_CPU0_PE2_SS_RXP<5>")
		)
		(pad "187" smd rect
			(at 0 77.609192 270)
			(size 1.1938 0.508)
			(layers "F.Cu" "F.Mask" "F.Paste")
			(net "P3E_CPU0_PE2_SS_C_TXN<6>")
		)
		(pad "188" smd rect
			(at 3.4036 77.609192 270)
			(size 1.1938 0.508)
			(layers "F.Cu" "F.Mask" "F.Paste")
			(net "GND")
		)
		(pad "189" smd rect
			(at 0 78.409292 270)
			(size 1.1938 0.508)
			(layers "F.Cu" "F.Mask" "F.Paste")
			(net "P3E_CPU0_PE2_SS_C_TXP<6>")
		)
		(pad "190" smd rect
			(at 3.4036 78.409292 270)
			(size 1.1938 0.508)
			(layers "F.Cu" "F.Mask" "F.Paste")
			(net "P3E_CPU0_PE2_SS_RXP<6>")
		)
		(pad "191" smd rect
			(at 0 79.209392 270)
			(size 1.1938 0.508)
			(layers "F.Cu" "F.Mask" "F.Paste")
			(net "GND")
		)
		(pad "192" smd rect
			(at 3.4036 79.209392 270)
			(size 1.1938 0.508)
			(layers "F.Cu" "F.Mask" "F.Paste")
			(net "P3E_CPU0_PE2_SS_RXN<6>")
		)
		(pad "193" smd rect
			(at 0 80.009492 270)
			(size 1.1938 0.508)
			(layers "F.Cu" "F.Mask" "F.Paste")
			(net "P3E_CPU0_PE2_SS_C_TXN<7>")
		)
		(pad "194" smd rect
			(at 3.4036 80.009492 270)
			(size 1.1938 0.508)
			(layers "F.Cu" "F.Mask" "F.Paste")
			(net "GND")
		)
		(pad "195" smd rect
			(at 0 80.809592 270)
			(size 1.1938 0.508)
			(layers "F.Cu" "F.Mask" "F.Paste")
			(net "P3E_CPU0_PE2_SS_C_TXP<7>")
		)
		(pad "196" smd rect
			(at 3.4036 80.809592 270)
			(size 1.1938 0.508)
			(layers "F.Cu" "F.Mask" "F.Paste")
			(net "P3E_CPU0_PE2_SS_RXN<7>")
		)
		(pad "197" smd rect
			(at 0 81.609692 270)
			(size 1.1938 0.508)
			(layers "F.Cu" "F.Mask" "F.Paste")
			(net "GND")
		)
		(pad "198" smd rect
			(at 3.4036 81.609692 270)
			(size 1.1938 0.508)
			(layers "F.Cu" "F.Mask" "F.Paste")
			(net "P3E_CPU0_PE2_SS_RXP<7>")
		)
		(pad "199" smd rect
			(at 0 82.409792 270)
			(size 1.1938 0.508)
			(layers "F.Cu" "F.Mask" "F.Paste")
			(net "FM_PRSNT_2_6_N")
		)
		(pad "200" smd rect
			(at 3.4036 82.409792 270)
			(size 1.1938 0.508)
			(layers "F.Cu" "F.Mask" "F.Paste")
			(net "GND")
		)
		(pad "MH1" thru_hole circle
			(at 1.7018 -3.845052 270)
			(size 1.4224 1.4224)
			(drill 1.0414)
			(layers "*.Cu" "*.Mask")
			(remove_unused_layers no)
			(net "GND")
			(clearance 0.127)
			(thermal_gap 0.127)
		)
		(pad "MH2" thru_hole circle
			(at 1.7018 86.254844 270)
			(size 1.4224 1.4224)
			(drill 1.0414)
			(layers "*.Cu" "*.Mask")
			(remove_unused_layers no)
			(net "GND")
			(clearance 0.127)
			(thermal_gap 0.127)
		)
		(zone
			(layers "F.Cu" "B.Cu" "In1.Cu" "In2.Cu" "In3.Cu" "In4.Cu" "In5.Cu" "In6.Cu"
				"In7.Cu" "In8.Cu" "In9.Cu" "In10.Cu" "In11.Cu" "In12.Cu"
			)
			(hatch none 0.5)
			(connect_pads
				(clearance 0)
			)
			(min_thickness 0.25)
			(keepout
				(tracks not_allowed)
				(vias allowed)
				(pads allowed)
				(copperpour not_allowed)
				(footprints allowed)
			)
			(placement
				(enabled no)
				(sheetname "")
			)
			(fill
				(thermal_gap 0.5)
				(thermal_bridge_width 0.5)
				(island_removal_mode 0)
			)
			(polygon
				(pts
					(arc
						(start 391.127742 -6.087872)
						(mid 389.222742 -6.087872)
						(end 391.127742 -6.087872)
					)
				)
			)
		)
		(zone
			(layers "F.Cu" "B.Cu" "In1.Cu" "In2.Cu" "In3.Cu" "In4.Cu" "In5.Cu" "In6.Cu"
				"In7.Cu" "In8.Cu" "In9.Cu" "In10.Cu" "In11.Cu" "In12.Cu"
			)
			(hatch none 0.5)
			(connect_pads
				(clearance 0)
			)
			(min_thickness 0.25)
			(keepout
				(tracks not_allowed)
				(vias allowed)
				(pads allowed)
				(copperpour not_allowed)
				(footprints allowed)
			)
			(placement
				(enabled no)
				(sheetname "")
			)
			(fill
				(thermal_gap 0.5)
				(thermal_bridge_width 0.5)
				(island_removal_mode 0)
			)
			(polygon
				(pts
					(arc
						(start 476.527622 -7.587996)
						(mid 474.622622 -7.587996)
						(end 476.527622 -7.587996)
					)
				)
			)
		)
	)
	(footprint ""
		(layer "F.Cu")
		(at 477.9264 -138.7094 90)
		(property "Reference" "R6W30"
			(at 1.01473 0.656336 0)
			(unlocked yes)
			(layer "F.SilkS")
			(effects
				(font
					(size 0.4064 0.254)
					(thickness 0.1524)
				)
			)
		)
		(property "Value" ""
			(at 0 0 90)
			(layer "F.Fab")
			(effects
				(font
					(size 1.27 1.27)
				)
			)
		)
		(duplicate_pad_numbers_are_jumpers no)
		(fp_poly
			(pts
				(xy -0.4953 -0.2032) (xy 0.4953 -0.2032) (xy 0.4953 1.6002) (xy -0.4953 1.6002)
			)
			(stroke
				(width 0)
				(type default)
			)
			(fill no)
			(layer "F.CrtYd")
		)
		(fp_line
			(start 0.4953 -0.2032)
			(end 0.4953 1.6002)
			(stroke
				(width 0.1)
				(type default)
			)
			(layer "F.Fab")
		)
		(fp_line
			(start -0.4953 -0.2032)
			(end 0.4953 -0.2032)
			(stroke
				(width 0.1)
				(type default)
			)
			(layer "F.Fab")
		)
		(fp_line
			(start 0.4953 1.6002)
			(end -0.4953 1.6002)
			(stroke
				(width 0.1)
				(type default)
			)
			(layer "F.Fab")
		)
		(fp_line
			(start -0.4953 1.6002)
			(end -0.4953 -0.2032)
			(stroke
				(width 0.1)
				(type default)
			)
			(layer "F.Fab")
		)
		(pad "1" smd rect
			(at 0 0 90)
			(size 0.762 0.889)
			(layers "F.Cu" "F.Mask" "F.Paste")
			(net "P3V3_STBY")
		)
		(pad "2" smd rect
			(at 0 1.397 90)
			(size 0.762 0.889)
			(layers "F.Cu" "F.Mask" "F.Paste")
			(net "SPA_MID_DBG2_RX_BUF")
		)
		(zone
			(layer "F.Cu")
			(hatch none 0.5)
			(connect_pads
				(clearance 0)
			)
			(min_thickness 0.25)
			(keepout
				(tracks allowed)
				(vias not_allowed)
				(pads allowed)
				(copperpour not_allowed)
				(footprints allowed)
			)
			(placement
				(enabled no)
				(sheetname "")
			)
			(fill
				(thermal_gap 0.5)
				(thermal_bridge_width 0.5)
				(island_removal_mode 0)
			)
			(polygon
				(pts
					(xy 478.8789 -139.0904) (xy 478.3709 -139.0904) (xy 478.3709 -138.3284) (xy 478.8789 -138.3284)
				)
			)
		)
		(zone
			(layer "F.Cu")
			(hatch none 0.5)
			(connect_pads
				(clearance 0)
			)
			(min_thickness 0.25)
			(keepout
				(tracks not_allowed)
				(vias allowed)
				(pads allowed)
				(copperpour not_allowed)
				(footprints allowed)
			)
			(placement
				(enabled no)
				(sheetname "")
			)
			(fill
				(thermal_gap 0.5)
				(thermal_bridge_width 0.5)
				(island_removal_mode 0)
			)
			(polygon
				(pts
					(xy 478.8789 -138.3284) (xy 478.8789 -139.0904) (xy 478.3709 -139.0904) (xy 478.3709 -138.3284)
				)
			)
		)
	)
	(footprint ""
		(layer "F.Cu")
		(at 373.2784 -131.7498 180)
		(property "Reference" "C7B24"
			(at 0 0 180)
			(layer "F.SilkS")
			(hide yes)
			(effects
				(font
					(size 1.27 1.27)
				)
			)
		)
		(property "Value" ""
			(at 0 0 180)
			(layer "F.Fab")
			(effects
				(font
					(size 1.27 1.27)
				)
			)
		)
		(duplicate_pad_numbers_are_jumpers no)
		(fp_rect
			(start -0.4953 1.6002)
			(end 0.4953 -0.2032)
			(stroke
				(width 0)
				(type default)
			)
			(fill no)
			(layer "F.CrtYd")
		)
		(fp_line
			(start 0.4953 1.6002)
			(end -0.4953 1.6002)
			(stroke
				(width 0.1)
				(type default)
			)
			(layer "F.Fab")
		)
		(fp_line
			(start 0.4953 -0.2032)
			(end 0.4953 1.6002)
			(stroke
				(width 0.1)
				(type default)
			)
			(layer "F.Fab")
		)
		(fp_line
			(start -0.4953 1.6002)
			(end -0.4953 -0.2032)
			(stroke
				(width 0.1)
				(type default)
			)
			(layer "F.Fab")
		)
		(fp_line
			(start -0.4953 -0.2032)
			(end 0.4953 -0.2032)
			(stroke
				(width 0.1)
				(type default)
			)
			(layer "F.Fab")
		)
		(pad "1" smd rect
			(at 0 0 180)
			(size 0.762 0.889)
			(layers "F.Cu" "F.Mask" "F.Paste")
			(net "P1V05_PCH_STBY")
		)
		(pad "2" smd rect
			(at 0 1.397 180)
			(size 0.762 0.889)
			(layers "F.Cu" "F.Mask" "F.Paste")
			(net "GND")
		)
		(zone
			(layer "F.Cu")
			(hatch none 0.5)
			(connect_pads
				(clearance 0)
			)
			(min_thickness 0.25)
			(keepout
				(tracks not_allowed)
				(vias allowed)
				(pads allowed)
				(copperpour not_allowed)
				(footprints allowed)
			)
			(placement
				(enabled no)
				(sheetname "")
			)
			(fill
				(thermal_gap 0.5)
				(thermal_bridge_width 0.5)
				(island_removal_mode 0)
			)
			(polygon
				(pts
					(xy 373.6594 -132.7023) (xy 372.8974 -132.7023) (xy 372.8974 -132.1943) (xy 373.6594 -132.1943)
				)
			)
		)
	)
	(footprint ""
		(layer "F.Cu")
		(at 164.973 -65.8114)
		(property "Reference" "C4D44"
			(at 0 0 0)
			(layer "F.SilkS")
			(hide yes)
			(effects
				(font
					(size 1.27 1.27)
				)
			)
		)
		(property "Value" ""
			(at 0 0 0)
			(layer "F.Fab")
			(effects
				(font
					(size 1.27 1.27)
				)
			)
		)
		(duplicate_pad_numbers_are_jumpers no)
		(fp_poly
			(pts
				(xy 0.3048 -0.1016) (xy 0.3048 0.9906) (xy -0.3048 0.9906) (xy -0.3048 -0.1016)
			)
			(stroke
				(width 0)
				(type default)
			)
			(fill no)
			(layer "F.CrtYd")
		)
		(fp_line
			(start -0.3048 -0.1016)
			(end -0.3048 0.9906)
			(stroke
				(width 0.1)
				(type default)
			)
			(layer "F.Fab")
		)
		(fp_line
			(start -0.3048 0.9906)
			(end 0.3048 0.9906)
			(stroke
				(width 0.1)
				(type default)
			)
			(layer "F.Fab")
		)
		(fp_line
			(start 0.3048 -0.1016)
			(end -0.3048 -0.1016)
			(stroke
				(width 0.1)
				(type default)
			)
			(layer "F.Fab")
		)
		(fp_line
			(start 0.3048 0.9906)
			(end 0.3048 -0.1016)
			(stroke
				(width 0.1)
				(type default)
			)
			(layer "F.Fab")
		)
		(pad "1" smd rect
			(at 0 0)
			(size 0.508 0.508)
			(layers "F.Cu" "F.Mask" "F.Paste")
			(net "VR_PVCCIO_CPU1_AVSP")
		)
		(pad "2" smd rect
			(at 0 0.889)
			(size 0.508 0.508)
			(layers "F.Cu" "F.Mask" "F.Paste")
			(net "VSENSE_PVCCIO_CPU1_AVSN")
		)
		(zone
			(layer "F.Cu")
			(hatch none 0.5)
			(connect_pads
				(clearance 0)
			)
			(min_thickness 0.25)
			(keepout
				(tracks allowed)
				(vias not_allowed)
				(pads allowed)
				(copperpour not_allowed)
				(footprints allowed)
			)
			(placement
				(enabled no)
				(sheetname "")
			)
			(fill
				(thermal_gap 0.5)
				(thermal_bridge_width 0.5)
				(island_removal_mode 0)
			)
			(polygon
				(pts
					(xy 164.719 -65.5574) (xy 165.227 -65.5574) (xy 165.227 -65.1764) (xy 164.719 -65.1764)
				)
			)
		)
		(zone
			(layer "F.Cu")
			(hatch none 0.5)
			(connect_pads
				(clearance 0)
			)
			(min_thickness 0.25)
			(keepout
				(tracks not_allowed)
				(vias allowed)
				(pads allowed)
				(copperpour not_allowed)
				(footprints allowed)
			)
			(placement
				(enabled no)
				(sheetname "")
			)
			(fill
				(thermal_gap 0.5)
				(thermal_bridge_width 0.5)
				(island_removal_mode 0)
			)
			(polygon
				(pts
					(xy 164.719 -65.1764) (xy 165.227 -65.1764) (xy 165.227 -65.5574) (xy 164.719 -65.5574)
				)
			)
		)
	)
	(footprint ""
		(layer "F.Cu")
		(at 198.042276 -92.967048 90)
		(property "Reference" "C4C19"
			(at 0 0 90)
			(layer "F.SilkS")
			(hide yes)
			(effects
				(font
					(size 1.27 1.27)
				)
			)
		)
		(property "Value" ""
			(at 0 0 90)
			(layer "F.Fab")
			(effects
				(font
					(size 1.27 1.27)
				)
			)
		)
		(duplicate_pad_numbers_are_jumpers no)
		(fp_rect
			(start 0.3048 0.9906)
			(end -0.3048 -0.1016)
			(stroke
				(width 0)
				(type default)
			)
			(fill no)
			(layer "F.CrtYd")
		)
		(fp_line
			(start 0.3048 -0.1016)
			(end -0.3048 -0.1016)
			(stroke
				(width 0.1)
				(type default)
			)
			(layer "F.Fab")
		)
		(fp_line
			(start -0.3048 -0.1016)
			(end -0.3048 0.9906)
			(stroke
				(width 0.1)
				(type default)
			)
			(layer "F.Fab")
		)
		(fp_line
			(start 0.3048 0.9906)
			(end 0.3048 -0.1016)
			(stroke
				(width 0.1)
				(type default)
			)
			(layer "F.Fab")
		)
		(fp_line
			(start -0.3048 0.9906)
			(end 0.3048 0.9906)
			(stroke
				(width 0.1)
				(type default)
			)
			(layer "F.Fab")
		)
		(pad "1" smd rect
			(at 0 0 90)
			(size 0.508 0.508)
			(layers "F.Cu" "F.Mask" "F.Paste")
			(net "VR_FET_SW_P12V_STBY_PVCCIN_CPU0")
		)
		(pad "2" smd rect
			(at 0 0.889 90)
			(size 0.508 0.508)
			(layers "F.Cu" "F.Mask" "F.Paste")
			(net "GND")
		)
		(zone
			(layer "F.Cu")
			(hatch none 0.5)
			(connect_pads
				(clearance 0)
			)
			(min_thickness 0.25)
			(keepout
				(tracks allowed)
				(vias not_allowed)
				(pads allowed)
				(copperpour not_allowed)
				(footprints allowed)
			)
			(placement
				(enabled no)
				(sheetname "")
			)
			(fill
				(thermal_gap 0.5)
				(thermal_bridge_width 0.5)
				(island_removal_mode 0)
			)
			(polygon
				(pts
					(xy 198.677276 -93.221048) (xy 198.296276 -93.221048) (xy 198.296276 -92.713048) (xy 198.677276 -92.713048)
				)
			)
		)
		(zone
			(layer "F.Cu")
			(hatch none 0.5)
			(connect_pads
				(clearance 0)
			)
			(min_thickness 0.25)
			(keepout
				(tracks not_allowed)
				(vias allowed)
				(pads allowed)
				(copperpour not_allowed)
				(footprints allowed)
			)
			(placement
				(enabled no)
				(sheetname "")
			)
			(fill
				(thermal_gap 0.5)
				(thermal_bridge_width 0.5)
				(island_removal_mode 0)
			)
			(polygon
				(pts
					(xy 198.677276 -93.221048) (xy 198.296276 -93.221048) (xy 198.296276 -92.713048) (xy 198.677276 -92.713048)
				)
			)
		)
	)
	(footprint ""
		(layer "F.Cu")
		(at 94.45244 -73.318116)
		(property "Reference" "C2D31"
			(at 0 0 0)
			(layer "F.SilkS")
			(hide yes)
			(effects
				(font
					(size 1.27 1.27)
				)
			)
		)
		(property "Value" ""
			(at 0 0 0)
			(layer "F.Fab")
			(effects
				(font
					(size 1.27 1.27)
				)
			)
		)
		(duplicate_pad_numbers_are_jumpers no)
		(fp_poly
			(pts
				(xy -0.4953 -0.2032) (xy 0.4953 -0.2032) (xy 0.4953 1.6002) (xy -0.4953 1.6002)
			)
			(stroke
				(width 0)
				(type default)
			)
			(fill no)
			(layer "F.CrtYd")
		)
		(fp_line
			(start -0.4953 -0.2032)
			(end 0.4953 -0.2032)
			(stroke
				(width 0.1)
				(type default)
			)
			(layer "F.Fab")
		)
		(fp_line
			(start -0.4953 1.6002)
			(end -0.4953 -0.2032)
			(stroke
				(width 0.1)
				(type default)
			)
			(layer "F.Fab")
		)
		(fp_line
			(start 0.4953 -0.2032)
			(end 0.4953 1.6002)
			(stroke
				(width 0.1)
				(type default)
			)
			(layer "F.Fab")
		)
		(fp_line
			(start 0.4953 1.6002)
			(end -0.4953 1.6002)
			(stroke
				(width 0.1)
				(type default)
			)
			(layer "F.Fab")
		)
		(pad "1" smd rect
			(at 0 0)
			(size 0.762 0.889)
			(layers "F.Cu" "F.Mask" "F.Paste")
			(net "PVCCIN_CPU1")
		)
		(pad "2" smd rect
			(at 0 1.397)
			(size 0.762 0.889)
			(layers "F.Cu" "F.Mask" "F.Paste")
			(net "GND")
		)
		(zone
			(layer "F.Cu")
			(hatch none 0.5)
			(connect_pads
				(clearance 0)
			)
			(min_thickness 0.25)
			(keepout
				(tracks not_allowed)
				(vias allowed)
				(pads allowed)
				(copperpour not_allowed)
				(footprints allowed)
			)
			(placement
				(enabled no)
				(sheetname "")
			)
			(fill
				(thermal_gap 0.5)
				(thermal_bridge_width 0.5)
				(island_removal_mode 0)
			)
			(polygon
				(pts
					(xy 94.07144 -72.873616) (xy 94.83344 -72.873616) (xy 94.83344 -72.365616) (xy 94.07144 -72.365616)
				)
			)
		)
	)
	(footprint ""
		(layer "F.Cu")
		(at 437.690006 -41.663874 180)
		(property "Reference" "R25W25"
			(at 0 0 180)
			(layer "F.SilkS")
			(hide yes)
			(effects
				(font
					(size 1.27 1.27)
				)
			)
		)
		(property "Value" "*"
			(at 0.064008 -4.108196 180)
			(unlocked yes)
			(layer "F.Fab")
			(hide yes)
			(effects
				(font
					(size 1.27 1.016)
					(thickness 0.1524)
				)
			)
		)
		(property "Device Type" "120R2F-GP_RCL_GP-120R2F-GP,64.A"
			(at 0.064008 -5.632196 180)
			(unlocked yes)
			(layer "F.Fab")
			(hide yes)
			(effects
				(font
					(size 1.27 1.016)
					(thickness 0.1524)
				)
			)
		)
		(duplicate_pad_numbers_are_jumpers no)
		(fp_line
			(start 0.508 -0.9398)
			(end -0.508 -0.9398)
			(stroke
				(width 0.1524)
				(type default)
			)
			(layer "F.SilkS")
		)
		(fp_line
			(start -0.508 -0.9398)
			(end -0.508 0.9398)
			(stroke
				(width 0.1524)
				(type default)
			)
			(layer "F.SilkS")
		)
		(fp_rect
			(start -0.508 0.9398)
			(end 0.508 -0.9398)
			(stroke
				(width 0)
				(type default)
			)
			(fill no)
			(layer "F.CrtYd")
		)
		(fp_rect
			(start -0.508 0.9398)
			(end 0.508 -0.9398)
			(stroke
				(width 0)
				(type default)
			)
			(fill no)
			(layer "F.Fab")
		)
		(pad "1" smd custom
			(at 0 -0.4445 180)
			(size 0.1397 0.1397)
			(layers "F.Cu" "F.Mask" "F.Paste")
			(net "GND")
			(options
				(clearance outline)
				(anchor circle)
			)
			(primitives
				(gr_poly
					(pts
						(arc
							(start -0.1778 -0.2794)
							(mid -0.249642 -0.249642)
							(end -0.2794 -0.1778)
						)
						(arc
							(start -0.2794 0.1778)
							(mid -0.249642 0.249642)
							(end -0.1778 0.2794)
						)
						(arc
							(start 0.1778 0.2794)
							(mid 0.249642 0.249642)
							(end 0.2794 0.1778)
						)
						(arc
							(start 0.2794 -0.1778)
							(mid 0.249642 -0.249642)
							(end 0.1778 -0.2794)
						)
					)
					(width 0)
					(fill yes)
				)
			)
		)
		(pad "2" smd custom
			(at 0 0.4445 180)
			(size 0.1397 0.1397)
			(layers "F.Cu" "F.Mask" "F.Paste")
			(net "BMC_M_A13")
			(options
				(clearance outline)
				(anchor circle)
			)
			(primitives
				(gr_poly
					(pts
						(arc
							(start -0.1778 -0.2794)
							(mid -0.249642 -0.249642)
							(end -0.2794 -0.1778)
						)
						(arc
							(start -0.2794 0.1778)
							(mid -0.249642 0.249642)
							(end -0.1778 0.2794)
						)
						(arc
							(start 0.1778 0.2794)
							(mid 0.249642 0.249642)
							(end 0.2794 0.1778)
						)
						(arc
							(start 0.2794 -0.1778)
							(mid 0.249642 -0.249642)
							(end 0.1778 -0.2794)
						)
					)
					(width 0)
					(fill yes)
				)
			)
		)
	)
	(footprint ""
		(layer "F.Cu")
		(at 353.2505 -152.273 -90)
		(property "Reference" "RT30"
			(at 1.01473 0.656336 180)
			(unlocked yes)
			(layer "F.SilkS")
			(effects
				(font
					(size 0.4064 0.254)
					(thickness 0.1524)
				)
			)
		)
		(property "Value" ""
			(at 0 0 270)
			(layer "F.Fab")
			(effects
				(font
					(size 1.27 1.27)
				)
			)
		)
		(duplicate_pad_numbers_are_jumpers no)
		(fp_poly
			(pts
				(xy -0.4953 -0.2032) (xy 0.4953 -0.2032) (xy 0.4953 1.6002) (xy -0.4953 1.6002)
			)
			(stroke
				(width 0)
				(type default)
			)
			(fill no)
			(layer "F.CrtYd")
		)
		(fp_line
			(start -0.4953 1.6002)
			(end -0.4953 -0.2032)
			(stroke
				(width 0.1)
				(type default)
			)
			(layer "F.Fab")
		)
		(fp_line
			(start 0.4953 1.6002)
			(end -0.4953 1.6002)
			(stroke
				(width 0.1)
				(type default)
			)
			(layer "F.Fab")
		)
		(fp_line
			(start -0.4953 -0.2032)
			(end 0.4953 -0.2032)
			(stroke
				(width 0.1)
				(type default)
			)
			(layer "F.Fab")
		)
		(fp_line
			(start 0.4953 -0.2032)
			(end 0.4953 1.6002)
			(stroke
				(width 0.1)
				(type default)
			)
			(layer "F.Fab")
		)
		(pad "1" smd rect
			(at 0 0 270)
			(size 0.762 0.889)
			(layers "F.Cu" "F.Mask" "F.Paste")
			(net "VR_PVDDQ_DEF_PH1_BOOT")
		)
		(pad "2" smd rect
			(at 0 1.397 270)
			(size 0.762 0.889)
			(layers "F.Cu" "F.Mask" "F.Paste")
			(net "VR_PVDDQ_DEF_PH1_BOOT_R")
		)
		(zone
			(layer "F.Cu")
			(hatch none 0.5)
			(connect_pads
				(clearance 0)
			)
			(min_thickness 0.25)
			(keepout
				(tracks not_allowed)
				(vias allowed)
				(pads allowed)
				(copperpour not_allowed)
				(footprints allowed)
			)
			(placement
				(enabled no)
				(sheetname "")
			)
			(fill
				(thermal_gap 0.5)
				(thermal_bridge_width 0.5)
				(island_removal_mode 0)
			)
			(polygon
				(pts
					(xy 352.298 -152.654) (xy 352.298 -151.892) (xy 352.806 -151.892) (xy 352.806 -152.654)
				)
			)
		)
		(zone
			(layer "F.Cu")
			(hatch none 0.5)
			(connect_pads
				(clearance 0)
			)
			(min_thickness 0.25)
			(keepout
				(tracks allowed)
				(vias not_allowed)
				(pads allowed)
				(copperpour not_allowed)
				(footprints allowed)
			)
			(placement
				(enabled no)
				(sheetname "")
			)
			(fill
				(thermal_gap 0.5)
				(thermal_bridge_width 0.5)
				(island_removal_mode 0)
			)
			(polygon
				(pts
					(xy 352.298 -151.892) (xy 352.806 -151.892) (xy 352.806 -152.654) (xy 352.298 -152.654)
				)
			)
		)
	)
	(footprint ""
		(layer "F.Cu")
		(at 40.036496 -81.415382)
		(property "Reference" "L1D1"
			(at 3.378708 -4.251706 0)
			(unlocked yes)
			(layer "F.SilkS")
			(effects
				(font
					(size 0.4064 0.254)
					(thickness 0.1524)
				)
			)
		)
		(property "Value" ""
			(at 0 0 0)
			(layer "F.Fab")
			(effects
				(font
					(size 1.27 1.27)
				)
			)
		)
		(duplicate_pad_numbers_are_jumpers no)
		(fp_line
			(start -1.1303 -3.199892)
			(end 8.3693 -3.199892)
			(stroke
				(width 0.1524)
				(type default)
			)
			(layer "F.SilkS")
		)
		(fp_line
			(start -1.1303 -1.6637)
			(end -1.1303 -3.199892)
			(stroke
				(width 0.1524)
				(type default)
			)
			(layer "F.SilkS")
		)
		(fp_line
			(start -1.1303 3.199892)
			(end -1.1303 1.6637)
			(stroke
				(width 0.1524)
				(type default)
			)
			(layer "F.SilkS")
		)
		(fp_line
			(start 8.3693 -3.199892)
			(end 8.3693 -1.6637)
			(stroke
				(width 0.1524)
				(type default)
			)
			(layer "F.SilkS")
		)
		(fp_line
			(start 8.3693 1.6637)
			(end 8.3693 3.199892)
			(stroke
				(width 0.1524)
				(type default)
			)
			(layer "F.SilkS")
		)
		(fp_line
			(start 8.3693 3.199892)
			(end -1.1303 3.199892)
			(stroke
				(width 0.1524)
				(type default)
			)
			(layer "F.SilkS")
		)
		(fp_rect
			(start -1.1303 3.199892)
			(end 8.3693 -3.199892)
			(stroke
				(width 0)
				(type default)
			)
			(fill no)
			(layer "F.CrtYd")
		)
		(fp_line
			(start -1.1303 -3.199892)
			(end 8.3693 -3.199892)
			(stroke
				(width 0.1)
				(type default)
			)
			(layer "F.Fab")
		)
		(fp_line
			(start -1.1303 3.199892)
			(end -1.1303 -3.199892)
			(stroke
				(width 0.1)
				(type default)
			)
			(layer "F.Fab")
		)
		(fp_line
			(start 8.3693 -3.199892)
			(end 8.3693 3.199892)
			(stroke
				(width 0.1)
				(type default)
			)
			(layer "F.Fab")
		)
		(fp_line
			(start 8.3693 3.199892)
			(end -1.1303 3.199892)
			(stroke
				(width 0.1)
				(type default)
			)
			(layer "F.Fab")
		)
		(pad "1" smd rect
			(at 0 0)
			(size 3.683 2.667)
			(layers "F.Cu" "F.Mask" "F.Paste")
			(net "VR_PVCCIN_CPU1_PHASE4")
		)
		(pad "2" smd rect
			(at 7.239 0)
			(size 3.683 2.667)
			(layers "F.Cu" "F.Mask" "F.Paste")
			(net "PVCCIN_CPU1")
		)
	)
	(footprint ""
		(layer "F.Cu")
		(at 414.8455 -109.728 90)
		(property "Reference" "R8E24"
			(at 0 0 90)
			(layer "F.SilkS")
			(hide yes)
			(effects
				(font
					(size 1.27 1.27)
				)
			)
		)
		(property "Value" ""
			(at 0 0 90)
			(layer "F.Fab")
			(effects
				(font
					(size 1.27 1.27)
				)
			)
		)
		(duplicate_pad_numbers_are_jumpers no)
		(fp_poly
			(pts
				(xy -0.2794 -0.1016) (xy 0.2794 -0.1016) (xy 0.2794 0.9906) (xy -0.2794 0.9906)
			)
			(stroke
				(width 0)
				(type default)
			)
			(fill no)
			(layer "F.CrtYd")
		)
		(fp_line
			(start 0.2794 -0.1016)
			(end -0.2794 -0.1016)
			(stroke
				(width 0.1)
				(type default)
			)
			(layer "F.Fab")
		)
		(fp_line
			(start -0.2794 -0.1016)
			(end -0.2794 0.9906)
			(stroke
				(width 0.1)
				(type default)
			)
			(layer "F.Fab")
		)
		(fp_line
			(start 0.2794 0.9906)
			(end 0.2794 -0.1016)
			(stroke
				(width 0.1)
				(type default)
			)
			(layer "F.Fab")
		)
		(fp_line
			(start -0.2794 0.9906)
			(end 0.2794 0.9906)
			(stroke
				(width 0.1)
				(type default)
			)
			(layer "F.Fab")
		)
		(pad "1" smd rect
			(at 0 0 90)
			(size 0.508 0.508)
			(layers "F.Cu" "F.Mask" "F.Paste")
			(net "IRQ_BMC_PCH_NMI_STBY_N")
		)
		(pad "2" smd rect
			(at 0 0.889 90)
			(size 0.508 0.508)
			(layers "F.Cu" "F.Mask" "F.Paste")
			(net "IRQ_BMC_PCH_NMI_STBY_R_N")
		)
		(zone
			(layer "F.Cu")
			(hatch none 0.5)
			(connect_pads
				(clearance 0)
			)
			(min_thickness 0.25)
			(keepout
				(tracks allowed)
				(vias not_allowed)
				(pads allowed)
				(copperpour not_allowed)
				(footprints allowed)
			)
			(placement
				(enabled no)
				(sheetname "")
			)
			(fill
				(thermal_gap 0.5)
				(thermal_bridge_width 0.5)
				(island_removal_mode 0)
			)
			(polygon
				(pts
					(xy 415.0995 -109.474) (xy 415.0995 -109.982) (xy 415.4805 -109.982) (xy 415.4805 -109.474)
				)
			)
		)
		(zone
			(layer "F.Cu")
			(hatch none 0.5)
			(connect_pads
				(clearance 0)
			)
			(min_thickness 0.25)
			(keepout
				(tracks not_allowed)
				(vias allowed)
				(pads allowed)
				(copperpour not_allowed)
				(footprints allowed)
			)
			(placement
				(enabled no)
				(sheetname "")
			)
			(fill
				(thermal_gap 0.5)
				(thermal_bridge_width 0.5)
				(island_removal_mode 0)
			)
			(polygon
				(pts
					(xy 415.4805 -109.474) (xy 415.4805 -109.982) (xy 415.0995 -109.982) (xy 415.0995 -109.474)
				)
			)
		)
	)
	(footprint ""
		(layer "F.Cu")
		(at 349.886016 -16.19631)
		(property "Reference" "R12W5"
			(at 0 0 0)
			(layer "F.SilkS")
			(hide yes)
			(effects
				(font
					(size 1.27 1.27)
				)
			)
		)
		(property "Value" "*"
			(at 0.064008 -4.108196 0)
			(unlocked yes)
			(layer "F.Fab")
			(hide yes)
			(effects
				(font
					(size 1.27 1.016)
					(thickness 0.1524)
				)
			)
		)
		(property "Device Type" "665KR2B-GP_SMD-RG2-665KR2B-GP,A"
			(at 0.064008 -5.632196 0)
			(unlocked yes)
			(layer "F.Fab")
			(hide yes)
			(effects
				(font
					(size 1.27 1.016)
					(thickness 0.1524)
				)
			)
		)
		(duplicate_pad_numbers_are_jumpers no)
		(fp_line
			(start -0.508 -0.9398)
			(end -0.508 0.9398)
			(stroke
				(width 0.1524)
				(type default)
			)
			(layer "F.SilkS")
		)
		(fp_line
			(start 0.508 -0.9398)
			(end -0.508 -0.9398)
			(stroke
				(width 0.1524)
				(type default)
			)
			(layer "F.SilkS")
		)
		(fp_rect
			(start -0.508 0.9398)
			(end 0.508 -0.9398)
			(stroke
				(width 0)
				(type default)
			)
			(fill no)
			(layer "F.CrtYd")
		)
		(fp_rect
			(start -0.508 0.9398)
			(end 0.508 -0.9398)
			(stroke
				(width 0)
				(type default)
			)
			(fill no)
			(layer "F.Fab")
		)
		(pad "1" smd custom
			(at 0 -0.4445)
			(size 0.1397 0.1397)
			(layers "F.Cu" "F.Mask" "F.Paste")
			(net "VR_PVDDQ_ABC_AIINSEN")
			(options
				(clearance outline)
				(anchor circle)
			)
			(primitives
				(gr_poly
					(pts
						(arc
							(start -0.1778 -0.2794)
							(mid -0.249642 -0.249642)
							(end -0.2794 -0.1778)
						)
						(arc
							(start -0.2794 0.1778)
							(mid -0.249642 0.249642)
							(end -0.1778 0.2794)
						)
						(arc
							(start 0.1778 0.2794)
							(mid 0.249642 0.249642)
							(end 0.2794 0.1778)
						)
						(arc
							(start 0.2794 -0.1778)
							(mid 0.249642 -0.249642)
							(end 0.1778 -0.2794)
						)
					)
					(width 0)
					(fill yes)
				)
			)
		)
		(pad "2" smd custom
			(at 0 0.4445)
			(size 0.1397 0.1397)
			(layers "F.Cu" "F.Mask" "F.Paste")
			(net "VR_PVDDQ_ABC_VINSEN")
			(options
				(clearance outline)
				(anchor circle)
			)
			(primitives
				(gr_poly
					(pts
						(arc
							(start -0.1778 -0.2794)
							(mid -0.249642 -0.249642)
							(end -0.2794 -0.1778)
						)
						(arc
							(start -0.2794 0.1778)
							(mid -0.249642 0.249642)
							(end -0.1778 0.2794)
						)
						(arc
							(start 0.1778 0.2794)
							(mid 0.249642 0.249642)
							(end 0.2794 0.1778)
						)
						(arc
							(start 0.2794 -0.1778)
							(mid 0.249642 -0.249642)
							(end 0.1778 -0.2794)
						)
					)
					(width 0)
					(fill yes)
				)
			)
		)
	)
	(footprint ""
		(layer "F.Cu")
		(at 171.704 -70.6374 180)
		(property "Reference" "C4D32"
			(at 0 0 180)
			(layer "F.SilkS")
			(hide yes)
			(effects
				(font
					(size 1.27 1.27)
				)
			)
		)
		(property "Value" ""
			(at 0 0 180)
			(layer "F.Fab")
			(effects
				(font
					(size 1.27 1.27)
				)
			)
		)
		(duplicate_pad_numbers_are_jumpers no)
		(fp_poly
			(pts
				(xy 0.3048 -0.1016) (xy 0.3048 0.9906) (xy -0.3048 0.9906) (xy -0.3048 -0.1016)
			)
			(stroke
				(width 0)
				(type default)
			)
			(fill no)
			(layer "F.CrtYd")
		)
		(fp_line
			(start 0.3048 0.9906)
			(end 0.3048 -0.1016)
			(stroke
				(width 0.1)
				(type default)
			)
			(layer "F.Fab")
		)
		(fp_line
			(start 0.3048 -0.1016)
			(end -0.3048 -0.1016)
			(stroke
				(width 0.1)
				(type default)
			)
			(layer "F.Fab")
		)
		(fp_line
			(start -0.3048 0.9906)
			(end 0.3048 0.9906)
			(stroke
				(width 0.1)
				(type default)
			)
			(layer "F.Fab")
		)
		(fp_line
			(start -0.3048 -0.1016)
			(end -0.3048 0.9906)
			(stroke
				(width 0.1)
				(type default)
			)
			(layer "F.Fab")
		)
		(pad "1" smd rect
			(at 0 0 180)
			(size 0.508 0.508)
			(layers "F.Cu" "F.Mask" "F.Paste")
			(net "VR_PVCCIO_CPU1_VD12")
		)
		(pad "2" smd rect
			(at 0 0.889 180)
			(size 0.508 0.508)
			(layers "F.Cu" "F.Mask" "F.Paste")
			(net "GND")
		)
		(zone
			(layer "F.Cu")
			(hatch none 0.5)
			(connect_pads
				(clearance 0)
			)
			(min_thickness 0.25)
			(keepout
				(tracks not_allowed)
				(vias allowed)
				(pads allowed)
				(copperpour not_allowed)
				(footprints allowed)
			)
			(placement
				(enabled no)
				(sheetname "")
			)
			(fill
				(thermal_gap 0.5)
				(thermal_bridge_width 0.5)
				(island_removal_mode 0)
			)
			(polygon
				(pts
					(xy 171.958 -71.2724) (xy 171.45 -71.2724) (xy 171.45 -70.8914) (xy 171.958 -70.8914)
				)
			)
		)
		(zone
			(layer "F.Cu")
			(hatch none 0.5)
			(connect_pads
				(clearance 0)
			)
			(min_thickness 0.25)
			(keepout
				(tracks allowed)
				(vias not_allowed)
				(pads allowed)
				(copperpour not_allowed)
				(footprints allowed)
			)
			(placement
				(enabled no)
				(sheetname "")
			)
			(fill
				(thermal_gap 0.5)
				(thermal_bridge_width 0.5)
				(island_removal_mode 0)
			)
			(polygon
				(pts
					(xy 171.958 -70.8914) (xy 171.45 -70.8914) (xy 171.45 -71.2724) (xy 171.958 -71.2724)
				)
			)
		)
	)
	(footprint ""
		(layer "F.Cu")
		(at 26.66492 -36.964874)
		(property "Reference" "J1F2"
			(at 0 0 0)
			(layer "F.SilkS")
			(hide yes)
			(effects
				(font
					(size 1.27 1.27)
				)
			)
		)
		(property "Value" "*"
			(at -6.3881 -0.97155 0)
			(unlocked yes)
			(layer "F.Fab")
			(hide yes)
			(effects
				(font
					(size 0.889 0.889)
					(thickness 0.1524)
				)
			)
		)
		(property "Device Type" "LOTES-CON4-S1-GP_CONN-G7-LOTESA"
			(at -6.3881 -2.49555 0)
			(unlocked yes)
			(layer "F.Fab")
			(hide yes)
			(effects
				(font
					(size 0.889 0.889)
					(thickness 0.1524)
				)
			)
		)
		(duplicate_pad_numbers_are_jumpers no)
		(fp_line
			(start -5.334 -3.302)
			(end 5.334 -3.302)
			(stroke
				(width 0.508)
				(type default)
			)
			(layer "F.SilkS")
		)
		(fp_line
			(start -5.334 -3.1242)
			(end 5.334 -3.1242)
			(stroke
				(width 0.1524)
				(type default)
			)
			(layer "F.SilkS")
		)
		(fp_line
			(start -5.334 3.0226)
			(end -5.334 -3.1242)
			(stroke
				(width 0.1524)
				(type default)
			)
			(layer "F.SilkS")
		)
		(fp_line
			(start 4.191 3.16484)
			(end 5.461 3.16484)
			(stroke
				(width 0.4064)
				(type default)
			)
			(layer "F.SilkS")
		)
		(fp_line
			(start 5.334 -3.1242)
			(end 5.334 3.0226)
			(stroke
				(width 0.1524)
				(type default)
			)
			(layer "F.SilkS")
		)
		(fp_line
			(start 5.334 3.0226)
			(end -5.334 3.0226)
			(stroke
				(width 0.1524)
				(type default)
			)
			(layer "F.SilkS")
		)
		(fp_line
			(start 5.461 3.16484)
			(end 5.461 1.89484)
			(stroke
				(width 0.4064)
				(type default)
			)
			(layer "F.SilkS")
		)
		(fp_circle
			(center -3.81 0)
			(end -2.5527 0)
			(stroke
				(width 0.3048)
				(type default)
			)
			(fill no)
			(layer "F.SilkS")
		)
		(fp_circle
			(center -1.27 0)
			(end -0.0127 0)
			(stroke
				(width 0.3048)
				(type default)
			)
			(fill no)
			(layer "F.SilkS")
		)
		(fp_circle
			(center 1.27 0)
			(end 2.5273 0)
			(stroke
				(width 0.3048)
				(type default)
			)
			(fill no)
			(layer "F.SilkS")
		)
		(fp_circle
			(center 3.81 0)
			(end 5.0673 0)
			(stroke
				(width 0.3048)
				(type default)
			)
			(fill no)
			(layer "F.SilkS")
		)
		(fp_rect
			(start -5.08 2.54)
			(end 5.08 -2.8702)
			(stroke
				(width 0)
				(type default)
			)
			(fill no)
			(layer "F.CrtYd")
		)
		(fp_poly
			(pts
				(xy -5.588 3.2766) (xy -5.588 -3.3782) (xy 5.588 -3.3782) (xy 5.588 -0.00635) (xy 5.08 -0.00635)
				(xy 5.08 -2.8702) (xy -5.08 -2.8702) (xy -5.08 2.54) (xy 5.08 2.54) (xy 5.08 0.00635) (xy 5.588 0.00635)
				(xy 5.588 3.2766)
			)
			(stroke
				(width 0)
				(type default)
			)
			(fill no)
			(layer "F.CrtYd")
		)
		(fp_rect
			(start -5.588 3.2766)
			(end 5.588 -3.3782)
			(stroke
				(width 0)
				(type default)
			)
			(fill no)
			(layer "F.Fab")
		)
		(pad "" np_thru_hole circle
			(at -1.27 2.189988)
			(size 0.254 0.254)
			(drill 1.1684)
			(layers "*.Cu" "*.Mask")
			(clearance 0.8128)
			(thermal_gap 0.8128)
		)
		(pad "1" thru_hole circle
			(at 3.81 0)
			(size 1.8034 1.8034)
			(drill 1.1684)
			(layers "*.Cu" "*.Mask")
			(remove_unused_layers no)
			(net "GND")
			(clearance 0.1905)
			(thermal_gap 0.1905)
		)
		(pad "2" thru_hole circle
			(at 1.27 0)
			(size 1.8034 1.8034)
			(drill 1.1684)
			(layers "*.Cu" "*.Mask")
			(remove_unused_layers no)
			(net "P12V_FAN")
			(clearance 0.1905)
			(thermal_gap 0.1905)
		)
		(pad "3" thru_hole circle
			(at -1.27 0)
			(size 1.8034 1.8034)
			(drill 1.1684)
			(layers "*.Cu" "*.Mask")
			(remove_unused_layers no)
			(net "FAN_TACH0_CPU0_D1")
			(clearance 0.1905)
			(thermal_gap 0.1905)
		)
		(pad "4" thru_hole circle
			(at -3.81 0)
			(size 1.8034 1.8034)
			(drill 1.1684)
			(layers "*.Cu" "*.Mask")
			(remove_unused_layers no)
			(net "FAN_PWM_OUT_SYS0_R")
			(clearance 0.1905)
			(thermal_gap 0.1905)
		)
		(zone
			(layers "F.Cu" "B.Cu" "In1.Cu" "In2.Cu" "In3.Cu" "In4.Cu" "In5.Cu" "In6.Cu"
				"In7.Cu" "In8.Cu" "In9.Cu" "In10.Cu" "In11.Cu" "In12.Cu"
			)
			(hatch none 0.5)
			(connect_pads
				(clearance 0)
			)
			(min_thickness 0.25)
			(keepout
				(tracks not_allowed)
				(vias allowed)
				(pads allowed)
				(copperpour not_allowed)
				(footprints allowed)
			)
			(placement
				(enabled no)
				(sheetname "")
			)
			(fill
				(thermal_gap 0.5)
				(thermal_bridge_width 0.5)
				(island_removal_mode 0)
			)
			(polygon
				(pts
					(arc
						(start 26.28392 -34.774886)
						(mid 24.50592 -34.774886)
						(end 26.28392 -34.774886)
					)
				)
			)
		)
	)
	(footprint ""
		(layer "F.Cu")
		(at 183.769 -53.594 -90)
		(property "Reference" "RT41"
			(at 1.01473 0.656336 180)
			(unlocked yes)
			(layer "F.SilkS")
			(effects
				(font
					(size 0.4064 0.254)
					(thickness 0.1524)
				)
			)
		)
		(property "Value" ""
			(at 0 0 270)
			(layer "F.Fab")
			(effects
				(font
					(size 1.27 1.27)
				)
			)
		)
		(duplicate_pad_numbers_are_jumpers no)
		(fp_poly
			(pts
				(xy -0.4953 -0.2032) (xy 0.4953 -0.2032) (xy 0.4953 1.6002) (xy -0.4953 1.6002)
			)
			(stroke
				(width 0)
				(type default)
			)
			(fill no)
			(layer "F.CrtYd")
		)
		(fp_line
			(start -0.4953 1.6002)
			(end -0.4953 -0.2032)
			(stroke
				(width 0.1)
				(type default)
			)
			(layer "F.Fab")
		)
		(fp_line
			(start 0.4953 1.6002)
			(end -0.4953 1.6002)
			(stroke
				(width 0.1)
				(type default)
			)
			(layer "F.Fab")
		)
		(fp_line
			(start -0.4953 -0.2032)
			(end 0.4953 -0.2032)
			(stroke
				(width 0.1)
				(type default)
			)
			(layer "F.Fab")
		)
		(fp_line
			(start 0.4953 -0.2032)
			(end 0.4953 1.6002)
			(stroke
				(width 0.1)
				(type default)
			)
			(layer "F.Fab")
		)
		(pad "1" smd rect
			(at 0 0 270)
			(size 0.762 0.889)
			(layers "F.Cu" "F.Mask" "F.Paste")
			(net "VR_PVCCIO_CPU1_PH1_BOOT")
		)
		(pad "2" smd rect
			(at 0 1.397 270)
			(size 0.762 0.889)
			(layers "F.Cu" "F.Mask" "F.Paste")
			(net "VR_PVCCIO_CPU1_PH1_BOOT_R")
		)
		(zone
			(layer "F.Cu")
			(hatch none 0.5)
			(connect_pads
				(clearance 0)
			)
			(min_thickness 0.25)
			(keepout
				(tracks not_allowed)
				(vias allowed)
				(pads allowed)
				(copperpour not_allowed)
				(footprints allowed)
			)
			(placement
				(enabled no)
				(sheetname "")
			)
			(fill
				(thermal_gap 0.5)
				(thermal_bridge_width 0.5)
				(island_removal_mode 0)
			)
			(polygon
				(pts
					(xy 182.8165 -53.975) (xy 182.8165 -53.213) (xy 183.3245 -53.213) (xy 183.3245 -53.975)
				)
			)
		)
		(zone
			(layer "F.Cu")
			(hatch none 0.5)
			(connect_pads
				(clearance 0)
			)
			(min_thickness 0.25)
			(keepout
				(tracks allowed)
				(vias not_allowed)
				(pads allowed)
				(copperpour not_allowed)
				(footprints allowed)
			)
			(placement
				(enabled no)
				(sheetname "")
			)
			(fill
				(thermal_gap 0.5)
				(thermal_bridge_width 0.5)
				(island_removal_mode 0)
			)
			(polygon
				(pts
					(xy 182.8165 -53.213) (xy 183.3245 -53.213) (xy 183.3245 -53.975) (xy 182.8165 -53.975)
				)
			)
		)
	)
	(footprint ""
		(layer "F.Cu")
		(at 174.6377 -66.191638 -90)
		(property "Reference" "R4D60"
			(at 0 0 270)
			(layer "F.SilkS")
			(hide yes)
			(effects
				(font
					(size 1.27 1.27)
				)
			)
		)
		(property "Value" ""
			(at 0 0 270)
			(layer "F.Fab")
			(effects
				(font
					(size 1.27 1.27)
				)
			)
		)
		(duplicate_pad_numbers_are_jumpers no)
		(fp_poly
			(pts
				(xy -0.2794 -0.1016) (xy 0.2794 -0.1016) (xy 0.2794 0.9906) (xy -0.2794 0.9906)
			)
			(stroke
				(width 0)
				(type default)
			)
			(fill no)
			(layer "F.CrtYd")
		)
		(fp_line
			(start -0.2794 0.9906)
			(end 0.2794 0.9906)
			(stroke
				(width 0.1)
				(type default)
			)
			(layer "F.Fab")
		)
		(fp_line
			(start 0.2794 0.9906)
			(end 0.2794 -0.1016)
			(stroke
				(width 0.1)
				(type default)
			)
			(layer "F.Fab")
		)
		(fp_line
			(start -0.2794 -0.1016)
			(end -0.2794 0.9906)
			(stroke
				(width 0.1)
				(type default)
			)
			(layer "F.Fab")
		)
		(fp_line
			(start 0.2794 -0.1016)
			(end -0.2794 -0.1016)
			(stroke
				(width 0.1)
				(type default)
			)
			(layer "F.Fab")
		)
		(pad "1" smd rect
			(at 0 0 270)
			(size 0.508 0.508)
			(layers "F.Cu" "F.Mask" "F.Paste")
			(net "VR_FET_SW_P12V_STBY_PVCCIN_CPU0")
		)
		(pad "2" smd rect
			(at 0 0.889 270)
			(size 0.508 0.508)
			(layers "F.Cu" "F.Mask" "F.Paste")
			(net "VR_PVCCIO_CPU1_VINSEN")
		)
		(zone
			(layer "F.Cu")
			(hatch none 0.5)
			(connect_pads
				(clearance 0)
			)
			(min_thickness 0.25)
			(keepout
				(tracks not_allowed)
				(vias allowed)
				(pads allowed)
				(copperpour not_allowed)
				(footprints allowed)
			)
			(placement
				(enabled no)
				(sheetname "")
			)
			(fill
				(thermal_gap 0.5)
				(thermal_bridge_width 0.5)
				(island_removal_mode 0)
			)
			(polygon
				(pts
					(xy 174.0027 -66.445638) (xy 174.0027 -65.937638) (xy 174.3837 -65.937638) (xy 174.3837 -66.445638)
				)
			)
		)
		(zone
			(layer "F.Cu")
			(hatch none 0.5)
			(connect_pads
				(clearance 0)
			)
			(min_thickness 0.25)
			(keepout
				(tracks allowed)
				(vias not_allowed)
				(pads allowed)
				(copperpour not_allowed)
				(footprints allowed)
			)
			(placement
				(enabled no)
				(sheetname "")
			)
			(fill
				(thermal_gap 0.5)
				(thermal_bridge_width 0.5)
				(island_removal_mode 0)
			)
			(polygon
				(pts
					(xy 174.3837 -66.445638) (xy 174.3837 -65.937638) (xy 174.0027 -65.937638) (xy 174.0027 -66.445638)
				)
			)
		)
	)
	(footprint ""
		(layer "F.Cu")
		(at 455.6125 -30.48 -90)
		(property "Reference" "R9F28"
			(at 0 0 270)
			(layer "F.SilkS")
			(hide yes)
			(effects
				(font
					(size 1.27 1.27)
				)
			)
		)
		(property "Value" ""
			(at 0 0 270)
			(layer "F.Fab")
			(effects
				(font
					(size 1.27 1.27)
				)
			)
		)
		(duplicate_pad_numbers_are_jumpers no)
		(fp_poly
			(pts
				(xy -0.2794 -0.1016) (xy 0.2794 -0.1016) (xy 0.2794 0.9906) (xy -0.2794 0.9906)
			)
			(stroke
				(width 0)
				(type default)
			)
			(fill no)
			(layer "F.CrtYd")
		)
		(fp_line
			(start -0.2794 0.9906)
			(end 0.2794 0.9906)
			(stroke
				(width 0.1)
				(type default)
			)
			(layer "F.Fab")
		)
		(fp_line
			(start 0.2794 0.9906)
			(end 0.2794 -0.1016)
			(stroke
				(width 0.1)
				(type default)
			)
			(layer "F.Fab")
		)
		(fp_line
			(start -0.2794 -0.1016)
			(end -0.2794 0.9906)
			(stroke
				(width 0.1)
				(type default)
			)
			(layer "F.Fab")
		)
		(fp_line
			(start 0.2794 -0.1016)
			(end -0.2794 -0.1016)
			(stroke
				(width 0.1)
				(type default)
			)
			(layer "F.Fab")
		)
		(pad "1" smd rect
			(at 0 0 270)
			(size 0.508 0.508)
			(layers "F.Cu" "F.Mask" "F.Paste")
			(net "P3V3_STBY")
		)
		(pad "2" smd rect
			(at 0 0.889 270)
			(size 0.508 0.508)
			(layers "F.Cu" "F.Mask" "F.Paste")
			(net "FM_RED_LED_ANODE")
		)
		(zone
			(layer "F.Cu")
			(hatch none 0.5)
			(connect_pads
				(clearance 0)
			)
			(min_thickness 0.25)
			(keepout
				(tracks not_allowed)
				(vias allowed)
				(pads allowed)
				(copperpour not_allowed)
				(footprints allowed)
			)
			(placement
				(enabled no)
				(sheetname "")
			)
			(fill
				(thermal_gap 0.5)
				(thermal_bridge_width 0.5)
				(island_removal_mode 0)
			)
			(polygon
				(pts
					(xy 454.9775 -30.734) (xy 454.9775 -30.226) (xy 455.3585 -30.226) (xy 455.3585 -30.734)
				)
			)
		)
		(zone
			(layer "F.Cu")
			(hatch none 0.5)
			(connect_pads
				(clearance 0)
			)
			(min_thickness 0.25)
			(keepout
				(tracks allowed)
				(vias not_allowed)
				(pads allowed)
				(copperpour not_allowed)
				(footprints allowed)
			)
			(placement
				(enabled no)
				(sheetname "")
			)
			(fill
				(thermal_gap 0.5)
				(thermal_bridge_width 0.5)
				(island_removal_mode 0)
			)
			(polygon
				(pts
					(xy 455.3585 -30.734) (xy 455.3585 -30.226) (xy 454.9775 -30.226) (xy 454.9775 -30.734)
				)
			)
		)
	)
	(footprint ""
		(layer "F.Cu")
		(at 102.258368 -84.7598)
		(property "Reference" "C2D6"
			(at 0 0 0)
			(layer "F.SilkS")
			(hide yes)
			(effects
				(font
					(size 1.27 1.27)
				)
			)
		)
		(property "Value" ""
			(at 0 0 0)
			(layer "F.Fab")
			(effects
				(font
					(size 1.27 1.27)
				)
			)
		)
		(duplicate_pad_numbers_are_jumpers no)
		(fp_poly
			(pts
				(xy -0.4953 -0.2032) (xy 0.4953 -0.2032) (xy 0.4953 1.6002) (xy -0.4953 1.6002)
			)
			(stroke
				(width 0)
				(type default)
			)
			(fill no)
			(layer "F.CrtYd")
		)
		(fp_line
			(start -0.4953 -0.2032)
			(end 0.4953 -0.2032)
			(stroke
				(width 0.1)
				(type default)
			)
			(layer "F.Fab")
		)
		(fp_line
			(start -0.4953 1.6002)
			(end -0.4953 -0.2032)
			(stroke
				(width 0.1)
				(type default)
			)
			(layer "F.Fab")
		)
		(fp_line
			(start 0.4953 -0.2032)
			(end 0.4953 1.6002)
			(stroke
				(width 0.1)
				(type default)
			)
			(layer "F.Fab")
		)
		(fp_line
			(start 0.4953 1.6002)
			(end -0.4953 1.6002)
			(stroke
				(width 0.1)
				(type default)
			)
			(layer "F.Fab")
		)
		(pad "1" smd rect
			(at 0 0)
			(size 0.762 0.889)
			(layers "F.Cu" "F.Mask" "F.Paste")
			(net "PVDDQ_KLM")
		)
		(pad "2" smd rect
			(at 0 1.397)
			(size 0.762 0.889)
			(layers "F.Cu" "F.Mask" "F.Paste")
			(net "GND")
		)
		(zone
			(layer "F.Cu")
			(hatch none 0.5)
			(connect_pads
				(clearance 0)
			)
			(min_thickness 0.25)
			(keepout
				(tracks not_allowed)
				(vias allowed)
				(pads allowed)
				(copperpour not_allowed)
				(footprints allowed)
			)
			(placement
				(enabled no)
				(sheetname "")
			)
			(fill
				(thermal_gap 0.5)
				(thermal_bridge_width 0.5)
				(island_removal_mode 0)
			)
			(polygon
				(pts
					(xy 101.877368 -84.3153) (xy 102.639368 -84.3153) (xy 102.639368 -83.8073) (xy 101.877368 -83.8073)
				)
			)
		)
	)
	(footprint ""
		(layer "F.Cu")
		(at 369.2906 -99.2124)
		(property "Reference" "R7C6"
			(at 0 0 0)
			(layer "F.SilkS")
			(hide yes)
			(effects
				(font
					(size 1.27 1.27)
				)
			)
		)
		(property "Value" ""
			(at 0 0 0)
			(layer "F.Fab")
			(effects
				(font
					(size 1.27 1.27)
				)
			)
		)
		(duplicate_pad_numbers_are_jumpers no)
		(fp_poly
			(pts
				(xy -0.4953 -0.2032) (xy 0.4953 -0.2032) (xy 0.4953 1.6002) (xy -0.4953 1.6002)
			)
			(stroke
				(width 0)
				(type default)
			)
			(fill no)
			(layer "F.CrtYd")
		)
		(fp_line
			(start -0.4953 -0.2032)
			(end 0.4953 -0.2032)
			(stroke
				(width 0.1)
				(type default)
			)
			(layer "F.Fab")
		)
		(fp_line
			(start -0.4953 1.6002)
			(end -0.4953 -0.2032)
			(stroke
				(width 0.1)
				(type default)
			)
			(layer "F.Fab")
		)
		(fp_line
			(start 0.4953 -0.2032)
			(end 0.4953 1.6002)
			(stroke
				(width 0.1)
				(type default)
			)
			(layer "F.Fab")
		)
		(fp_line
			(start 0.4953 1.6002)
			(end -0.4953 1.6002)
			(stroke
				(width 0.1)
				(type default)
			)
			(layer "F.Fab")
		)
		(pad "1" smd rect
			(at 0 0)
			(size 0.762 0.889)
			(layers "F.Cu" "F.Mask" "F.Paste")
			(net "XTAL_33K_RTC1")
		)
		(pad "2" smd rect
			(at 0 1.397)
			(size 0.762 0.889)
			(layers "F.Cu" "F.Mask" "F.Paste")
			(net "XTAL_33K_RTC2")
		)
		(zone
			(layer "F.Cu")
			(hatch none 0.5)
			(connect_pads
				(clearance 0)
			)
			(min_thickness 0.25)
			(keepout
				(tracks not_allowed)
				(vias allowed)
				(pads allowed)
				(copperpour not_allowed)
				(footprints allowed)
			)
			(placement
				(enabled no)
				(sheetname "")
			)
			(fill
				(thermal_gap 0.5)
				(thermal_bridge_width 0.5)
				(island_removal_mode 0)
			)
			(polygon
				(pts
					(xy 368.9096 -98.2599) (xy 369.6716 -98.2599) (xy 369.6716 -98.7679) (xy 368.9096 -98.7679)
				)
			)
		)
		(zone
			(layer "F.Cu")
			(hatch none 0.5)
			(connect_pads
				(clearance 0)
			)
			(min_thickness 0.25)
			(keepout
				(tracks allowed)
				(vias not_allowed)
				(pads allowed)
				(copperpour not_allowed)
				(footprints allowed)
			)
			(placement
				(enabled no)
				(sheetname "")
			)
			(fill
				(thermal_gap 0.5)
				(thermal_bridge_width 0.5)
				(island_removal_mode 0)
			)
			(polygon
				(pts
					(xy 369.6716 -98.2599) (xy 369.6716 -98.7679) (xy 368.9096 -98.7679) (xy 368.9096 -98.2599)
				)
			)
		)
	)
	(footprint ""
		(layer "F.Cu")
		(at 28.829 -83.1342 90)
		(property "Reference" "C1D10"
			(at 0 0 90)
			(layer "F.SilkS")
			(hide yes)
			(effects
				(font
					(size 1.27 1.27)
				)
			)
		)
		(property "Value" ""
			(at 0 0 90)
			(layer "F.Fab")
			(effects
				(font
					(size 1.27 1.27)
				)
			)
		)
		(duplicate_pad_numbers_are_jumpers no)
		(fp_rect
			(start -0.3048 0.9906)
			(end 0.3048 -0.1016)
			(stroke
				(width 0)
				(type default)
			)
			(fill no)
			(layer "F.CrtYd")
		)
		(fp_line
			(start 0.3048 -0.1016)
			(end -0.3048 -0.1016)
			(stroke
				(width 0.1)
				(type default)
			)
			(layer "F.Fab")
		)
		(fp_line
			(start -0.3048 -0.1016)
			(end -0.3048 0.9906)
			(stroke
				(width 0.1)
				(type default)
			)
			(layer "F.Fab")
		)
		(fp_line
			(start 0.3048 0.9906)
			(end 0.3048 -0.1016)
			(stroke
				(width 0.1)
				(type default)
			)
			(layer "F.Fab")
		)
		(fp_line
			(start -0.3048 0.9906)
			(end 0.3048 0.9906)
			(stroke
				(width 0.1)
				(type default)
			)
			(layer "F.Fab")
		)
		(pad "1" smd rect
			(at 0 0 90)
			(size 0.508 0.508)
			(layers "F.Cu" "F.Mask" "F.Paste")
			(net "VR_PVCCIN_CPU1_PH4_BOOT")
		)
		(pad "2" smd rect
			(at 0 0.889 90)
			(size 0.508 0.508)
			(layers "F.Cu" "F.Mask" "F.Paste")
			(net "VR_PVCCIN_CPU1_PH4_PHASE")
		)
		(zone
			(layer "F.Cu")
			(hatch none 0.5)
			(connect_pads
				(clearance 0)
			)
			(min_thickness 0.25)
			(keepout
				(tracks not_allowed)
				(vias allowed)
				(pads allowed)
				(copperpour not_allowed)
				(footprints allowed)
			)
			(placement
				(enabled no)
				(sheetname "")
			)
			(fill
				(thermal_gap 0.5)
				(thermal_bridge_width 0.5)
				(island_removal_mode 0)
			)
			(polygon
				(pts
					(xy 29.464 -82.8802) (xy 29.464 -83.3882) (xy 29.083 -83.3882) (xy 29.083 -82.8802)
				)
			)
		)
		(zone
			(layer "F.Cu")
			(hatch none 0.5)
			(connect_pads
				(clearance 0)
			)
			(min_thickness 0.25)
			(keepout
				(tracks allowed)
				(vias not_allowed)
				(pads allowed)
				(copperpour not_allowed)
				(footprints allowed)
			)
			(placement
				(enabled no)
				(sheetname "")
			)
			(fill
				(thermal_gap 0.5)
				(thermal_bridge_width 0.5)
				(island_removal_mode 0)
			)
			(polygon
				(pts
					(xy 29.464 -82.8802) (xy 29.464 -83.3882) (xy 29.083 -83.3882) (xy 29.083 -82.8802)
				)
			)
		)
	)
	(footprint ""
		(layer "F.Cu")
		(at 179.959 -7.366 180)
		(property "Reference" "R4G14"
			(at 0 0 180)
			(layer "F.SilkS")
			(hide yes)
			(effects
				(font
					(size 1.27 1.27)
				)
			)
		)
		(property "Value" ""
			(at 0 0 180)
			(layer "F.Fab")
			(effects
				(font
					(size 1.27 1.27)
				)
			)
		)
		(duplicate_pad_numbers_are_jumpers no)
		(fp_rect
			(start 0.2794 -0.1016)
			(end -0.2794 0.9906)
			(stroke
				(width 0)
				(type default)
			)
			(fill no)
			(layer "F.CrtYd")
		)
		(fp_line
			(start 0.2794 0.9906)
			(end 0.2794 -0.1016)
			(stroke
				(width 0.1)
				(type default)
			)
			(layer "F.Fab")
		)
		(fp_line
			(start 0.2794 -0.1016)
			(end -0.2794 -0.1016)
			(stroke
				(width 0.1)
				(type default)
			)
			(layer "F.Fab")
		)
		(fp_line
			(start -0.2794 0.9906)
			(end 0.2794 0.9906)
			(stroke
				(width 0.1)
				(type default)
			)
			(layer "F.Fab")
		)
		(fp_line
			(start -0.2794 -0.1016)
			(end -0.2794 0.9906)
			(stroke
				(width 0.1)
				(type default)
			)
			(layer "F.Fab")
		)
		(pad "1" smd rect
			(at 0 0 180)
			(size 0.508 0.508)
			(layers "F.Cu" "F.Mask" "F.Paste")
			(net "P3V3_STBY")
		)
		(pad "2" smd rect
			(at 0 0.889 180)
			(size 0.508 0.508)
			(layers "F.Cu" "F.Mask" "F.Paste")
			(net "PWRGD_PVPP_GHJ_R")
		)
		(zone
			(layer "F.Cu")
			(hatch none 0.5)
			(connect_pads
				(clearance 0)
			)
			(min_thickness 0.25)
			(keepout
				(tracks not_allowed)
				(vias allowed)
				(pads allowed)
				(copperpour not_allowed)
				(footprints allowed)
			)
			(placement
				(enabled no)
				(sheetname "")
			)
			(fill
				(thermal_gap 0.5)
				(thermal_bridge_width 0.5)
				(island_removal_mode 0)
			)
			(polygon
				(pts
					(xy 179.705 -7.62) (xy 180.213 -7.62) (xy 180.213 -8.001) (xy 179.705 -8.001)
				)
			)
		)
		(zone
			(layer "F.Cu")
			(hatch none 0.5)
			(connect_pads
				(clearance 0)
			)
			(min_thickness 0.25)
			(keepout
				(tracks allowed)
				(vias not_allowed)
				(pads allowed)
				(copperpour not_allowed)
				(footprints allowed)
			)
			(placement
				(enabled no)
				(sheetname "")
			)
			(fill
				(thermal_gap 0.5)
				(thermal_bridge_width 0.5)
				(island_removal_mode 0)
			)
			(polygon
				(pts
					(xy 179.705 -7.62) (xy 180.213 -7.62) (xy 180.213 -8.001) (xy 179.705 -8.001)
				)
			)
		)
	)
	(footprint ""
		(layer "F.Cu")
		(at 337.1215 -127.254 90)
		(property "Reference" "R7B18"
			(at 0 0 90)
			(layer "F.SilkS")
			(hide yes)
			(effects
				(font
					(size 1.27 1.27)
				)
			)
		)
		(property "Value" ""
			(at 0 0 90)
			(layer "F.Fab")
			(effects
				(font
					(size 1.27 1.27)
				)
			)
		)
		(duplicate_pad_numbers_are_jumpers no)
		(fp_poly
			(pts
				(xy -0.2794 -0.1016) (xy 0.2794 -0.1016) (xy 0.2794 0.9906) (xy -0.2794 0.9906)
			)
			(stroke
				(width 0)
				(type default)
			)
			(fill no)
			(layer "F.CrtYd")
		)
		(fp_line
			(start 0.2794 -0.1016)
			(end -0.2794 -0.1016)
			(stroke
				(width 0.1)
				(type default)
			)
			(layer "F.Fab")
		)
		(fp_line
			(start -0.2794 -0.1016)
			(end -0.2794 0.9906)
			(stroke
				(width 0.1)
				(type default)
			)
			(layer "F.Fab")
		)
		(fp_line
			(start 0.2794 0.9906)
			(end 0.2794 -0.1016)
			(stroke
				(width 0.1)
				(type default)
			)
			(layer "F.Fab")
		)
		(fp_line
			(start -0.2794 0.9906)
			(end 0.2794 0.9906)
			(stroke
				(width 0.1)
				(type default)
			)
			(layer "F.Fab")
		)
		(pad "1" smd rect
			(at 0 0 90)
			(size 0.508 0.508)
			(layers "F.Cu" "F.Mask" "F.Paste")
			(net "VSENSE_PVPP_DEF")
		)
		(pad "2" smd rect
			(at 0 0.889 90)
			(size 0.508 0.508)
			(layers "F.Cu" "F.Mask" "F.Paste")
			(net "VR_COMP_PVPP_DEF")
		)
		(zone
			(layer "F.Cu")
			(hatch none 0.5)
			(connect_pads
				(clearance 0)
			)
			(min_thickness 0.25)
			(keepout
				(tracks allowed)
				(vias not_allowed)
				(pads allowed)
				(copperpour not_allowed)
				(footprints allowed)
			)
			(placement
				(enabled no)
				(sheetname "")
			)
			(fill
				(thermal_gap 0.5)
				(thermal_bridge_width 0.5)
				(island_removal_mode 0)
			)
			(polygon
				(pts
					(xy 337.3755 -127) (xy 337.3755 -127.508) (xy 337.7565 -127.508) (xy 337.7565 -127)
				)
			)
		)
		(zone
			(layer "F.Cu")
			(hatch none 0.5)
			(connect_pads
				(clearance 0)
			)
			(min_thickness 0.25)
			(keepout
				(tracks not_allowed)
				(vias allowed)
				(pads allowed)
				(copperpour not_allowed)
				(footprints allowed)
			)
			(placement
				(enabled no)
				(sheetname "")
			)
			(fill
				(thermal_gap 0.5)
				(thermal_bridge_width 0.5)
				(island_removal_mode 0)
			)
			(polygon
				(pts
					(xy 337.7565 -127) (xy 337.7565 -127.508) (xy 337.3755 -127.508) (xy 337.3755 -127)
				)
			)
		)
	)
	(footprint ""
		(layer "F.Cu")
		(at 466.311996 2.8194 180)
		(property "Reference" "Q9G1"
			(at 2.54254 2.20091 0)
			(unlocked yes)
			(layer "F.SilkS")
			(effects
				(font
					(size 0.7874 0.5842)
					(thickness 0.1524)
				)
				(justify left)
			)
		)
		(property "Value" ""
			(at 0 0 180)
			(layer "F.Fab")
			(effects
				(font
					(size 1.27 1.27)
				)
			)
		)
		(duplicate_pad_numbers_are_jumpers no)
		(fp_circle
			(center -0.48641 -0.538734)
			(end -0.61341 -0.538734)
			(stroke
				(width 0.254)
				(type default)
			)
			(fill no)
			(layer "F.SilkS")
		)
		(fp_poly
			(pts
				(xy 0.2159 1.7526) (xy 1.5621 1.7526) (xy 1.5621 -0.4572) (xy 0.2159 -0.4572)
			)
			(stroke
				(width 0)
				(type default)
			)
			(fill no)
			(layer "F.CrtYd")
		)
		(fp_line
			(start 1.5621 1.75514)
			(end 1.5621 -0.45466)
			(stroke
				(width 0.1)
				(type default)
			)
			(layer "F.Fab")
		)
		(fp_line
			(start 1.5621 -0.45466)
			(end 0.2159 -0.45466)
			(stroke
				(width 0.1)
				(type default)
			)
			(layer "F.Fab")
		)
		(fp_line
			(start 0.2159 1.75514)
			(end 1.5621 1.75514)
			(stroke
				(width 0.1)
				(type default)
			)
			(layer "F.Fab")
		)
		(fp_line
			(start 0.2159 -0.45466)
			(end 0.2159 1.75514)
			(stroke
				(width 0.1)
				(type default)
			)
			(layer "F.Fab")
		)
		(fp_circle
			(center -0.508 -0.7874)
			(end -0.635 -0.7874)
			(stroke
				(width 0.254)
				(type default)
			)
			(fill no)
			(layer "F.Fab")
		)
		(pad "1" smd rect
			(at 0 0 180)
			(size 1.016 0.381)
			(layers "F.Cu" "F.Mask" "F.Paste")
			(net "GND")
		)
		(pad "2" smd rect
			(at 0 0.65024 180)
			(size 1.016 0.381)
			(layers "F.Cu" "F.Mask" "F.Paste")
			(net "FM_BATTERY_SENSE_EN_N")
		)
		(pad "3" smd rect
			(at 0 1.30048 180)
			(size 1.016 0.381)
			(layers "F.Cu" "F.Mask" "F.Paste")
			(net "P3V_BAT_SOURCE_R")
		)
		(pad "4" smd rect
			(at 1.778 1.30048 180)
			(size 1.016 0.381)
			(layers "F.Cu" "F.Mask" "F.Paste")
			(net "A_P3V_BAT_SCALED")
		)
		(pad "5" smd rect
			(at 1.778 0.65024 180)
			(size 1.016 0.381)
			(layers "F.Cu" "F.Mask" "F.Paste")
			(net "FM_BATTERY_SENSE_EN")
		)
		(pad "6" smd rect
			(at 1.778 0 180)
			(size 1.016 0.381)
			(layers "F.Cu" "F.Mask" "F.Paste")
			(net "FM_BATTERY_SENSE_EN")
		)
		(zone
			(layer "F.Cu")
			(hatch none 0.5)
			(connect_pads
				(clearance 0)
			)
			(min_thickness 0.25)
			(keepout
				(tracks allowed)
				(vias not_allowed)
				(pads allowed)
				(copperpour not_allowed)
				(footprints allowed)
			)
			(placement
				(enabled no)
				(sheetname "")
			)
			(fill
				(thermal_gap 0.5)
				(thermal_bridge_width 0.5)
				(island_removal_mode 0)
			)
			(polygon
				(pts
					(xy 465.041996 3.0099) (xy 464.025996 3.0099) (xy 464.025996 1.3208) (xy 465.041996 1.3208)
				)
			)
		)
		(zone
			(layer "F.Cu")
			(hatch none 0.5)
			(connect_pads
				(clearance 0)
			)
			(min_thickness 0.25)
			(keepout
				(tracks allowed)
				(vias not_allowed)
				(pads allowed)
				(copperpour not_allowed)
				(footprints allowed)
			)
			(placement
				(enabled no)
				(sheetname "")
			)
			(fill
				(thermal_gap 0.5)
				(thermal_bridge_width 0.5)
				(island_removal_mode 0)
			)
			(polygon
				(pts
					(xy 466.819996 3.0099) (xy 465.803996 3.0099) (xy 465.803996 1.3208) (xy 466.819996 1.3208)
				)
			)
		)
	)
	(footprint ""
		(layer "F.Cu")
		(at 441.119006 -43.568874 180)
		(property "Reference" "R25W31"
			(at 0 0 180)
			(layer "F.SilkS")
			(hide yes)
			(effects
				(font
					(size 1.27 1.27)
				)
			)
		)
		(property "Value" "*"
			(at 0.064008 -4.108196 180)
			(unlocked yes)
			(layer "F.Fab")
			(hide yes)
			(effects
				(font
					(size 1.27 1.016)
					(thickness 0.1524)
				)
			)
		)
		(property "Device Type" "120R2F-GP_RCL_GP-120R2F-GP,64.A"
			(at 0.064008 -5.632196 180)
			(unlocked yes)
			(layer "F.Fab")
			(hide yes)
			(effects
				(font
					(size 1.27 1.016)
					(thickness 0.1524)
				)
			)
		)
		(duplicate_pad_numbers_are_jumpers no)
		(fp_line
			(start 0.508 -0.9398)
			(end -0.508 -0.9398)
			(stroke
				(width 0.1524)
				(type default)
			)
			(layer "F.SilkS")
		)
		(fp_line
			(start -0.508 -0.9398)
			(end -0.508 0.9398)
			(stroke
				(width 0.1524)
				(type default)
			)
			(layer "F.SilkS")
		)
		(fp_rect
			(start -0.508 0.9398)
			(end 0.508 -0.9398)
			(stroke
				(width 0)
				(type default)
			)
			(fill no)
			(layer "F.CrtYd")
		)
		(fp_rect
			(start -0.508 0.9398)
			(end 0.508 -0.9398)
			(stroke
				(width 0)
				(type default)
			)
			(fill no)
			(layer "F.Fab")
		)
		(pad "1" smd custom
			(at 0 -0.4445 180)
			(size 0.1397 0.1397)
			(layers "F.Cu" "F.Mask" "F.Paste")
			(net "BMC_M_CS_N")
			(options
				(clearance outline)
				(anchor circle)
			)
			(primitives
				(gr_poly
					(pts
						(arc
							(start -0.1778 -0.2794)
							(mid -0.249642 -0.249642)
							(end -0.2794 -0.1778)
						)
						(arc
							(start -0.2794 0.1778)
							(mid -0.249642 0.249642)
							(end -0.1778 0.2794)
						)
						(arc
							(start 0.1778 0.2794)
							(mid 0.249642 0.249642)
							(end 0.2794 0.1778)
						)
						(arc
							(start 0.2794 -0.1778)
							(mid 0.249642 -0.249642)
							(end 0.1778 -0.2794)
						)
					)
					(width 0)
					(fill yes)
				)
			)
		)
		(pad "2" smd custom
			(at 0 0.4445 180)
			(size 0.1397 0.1397)
			(layers "F.Cu" "F.Mask" "F.Paste")
			(net "P1V2_AUX_BMC")
			(options
				(clearance outline)
				(anchor circle)
			)
			(primitives
				(gr_poly
					(pts
						(arc
							(start -0.1778 -0.2794)
							(mid -0.249642 -0.249642)
							(end -0.2794 -0.1778)
						)
						(arc
							(start -0.2794 0.1778)
							(mid -0.249642 0.249642)
							(end -0.1778 0.2794)
						)
						(arc
							(start 0.1778 0.2794)
							(mid 0.249642 0.249642)
							(end 0.2794 0.1778)
						)
						(arc
							(start 0.2794 -0.1778)
							(mid 0.249642 -0.249642)
							(end 0.1778 -0.2794)
						)
					)
					(width 0)
					(fill yes)
				)
			)
		)
	)
	(footprint ""
		(layer "F.Cu")
		(at 412.1277 -90.0938 180)
		(property "Reference" "R8E5"
			(at 0 0 180)
			(layer "F.SilkS")
			(hide yes)
			(effects
				(font
					(size 1.27 1.27)
				)
			)
		)
		(property "Value" ""
			(at 0 0 180)
			(layer "F.Fab")
			(effects
				(font
					(size 1.27 1.27)
				)
			)
		)
		(duplicate_pad_numbers_are_jumpers no)
		(fp_poly
			(pts
				(xy -0.2794 -0.1016) (xy 0.2794 -0.1016) (xy 0.2794 0.9906) (xy -0.2794 0.9906)
			)
			(stroke
				(width 0)
				(type default)
			)
			(fill no)
			(layer "F.CrtYd")
		)
		(fp_line
			(start 0.2794 0.9906)
			(end 0.2794 -0.1016)
			(stroke
				(width 0.1)
				(type default)
			)
			(layer "F.Fab")
		)
		(fp_line
			(start 0.2794 -0.1016)
			(end -0.2794 -0.1016)
			(stroke
				(width 0.1)
				(type default)
			)
			(layer "F.Fab")
		)
		(fp_line
			(start -0.2794 0.9906)
			(end 0.2794 0.9906)
			(stroke
				(width 0.1)
				(type default)
			)
			(layer "F.Fab")
		)
		(fp_line
			(start -0.2794 -0.1016)
			(end -0.2794 0.9906)
			(stroke
				(width 0.1)
				(type default)
			)
			(layer "F.Fab")
		)
		(pad "1" smd rect
			(at 0 0 180)
			(size 0.508 0.508)
			(layers "F.Cu" "F.Mask" "F.Paste")
			(net "FM_CTNR_PS_ON_R")
		)
		(pad "2" smd rect
			(at 0 0.889 180)
			(size 0.508 0.508)
			(layers "F.Cu" "F.Mask" "F.Paste")
			(net "FM_CTNR_PS_ON")
		)
		(zone
			(layer "F.Cu")
			(hatch none 0.5)
			(connect_pads
				(clearance 0)
			)
			(min_thickness 0.25)
			(keepout
				(tracks not_allowed)
				(vias allowed)
				(pads allowed)
				(copperpour not_allowed)
				(footprints allowed)
			)
			(placement
				(enabled no)
				(sheetname "")
			)
			(fill
				(thermal_gap 0.5)
				(thermal_bridge_width 0.5)
				(island_removal_mode 0)
			)
			(polygon
				(pts
					(xy 412.3817 -90.7288) (xy 411.8737 -90.7288) (xy 411.8737 -90.3478) (xy 412.3817 -90.3478)
				)
			)
		)
		(zone
			(layer "F.Cu")
			(hatch none 0.5)
			(connect_pads
				(clearance 0)
			)
			(min_thickness 0.25)
			(keepout
				(tracks allowed)
				(vias not_allowed)
				(pads allowed)
				(copperpour not_allowed)
				(footprints allowed)
			)
			(placement
				(enabled no)
				(sheetname "")
			)
			(fill
				(thermal_gap 0.5)
				(thermal_bridge_width 0.5)
				(island_removal_mode 0)
			)
			(polygon
				(pts
					(xy 412.3817 -90.3478) (xy 411.8737 -90.3478) (xy 411.8737 -90.7288) (xy 412.3817 -90.7288)
				)
			)
		)
	)
	(footprint ""
		(layer "F.Cu")
		(at 264.453624 -68.641214 -90)
		(property "Reference" "C5D55"
			(at 0 0 270)
			(layer "F.SilkS")
			(hide yes)
			(effects
				(font
					(size 1.27 1.27)
				)
			)
		)
		(property "Value" ""
			(at 0 0 270)
			(layer "F.Fab")
			(effects
				(font
					(size 1.27 1.27)
				)
			)
		)
		(duplicate_pad_numbers_are_jumpers no)
		(fp_poly
			(pts
				(xy -0.4953 -0.2032) (xy 0.4953 -0.2032) (xy 0.4953 1.6002) (xy -0.4953 1.6002)
			)
			(stroke
				(width 0)
				(type default)
			)
			(fill no)
			(layer "F.CrtYd")
		)
		(fp_line
			(start -0.4953 1.6002)
			(end -0.4953 -0.2032)
			(stroke
				(width 0.1)
				(type default)
			)
			(layer "F.Fab")
		)
		(fp_line
			(start 0.4953 1.6002)
			(end -0.4953 1.6002)
			(stroke
				(width 0.1)
				(type default)
			)
			(layer "F.Fab")
		)
		(fp_line
			(start -0.4953 -0.2032)
			(end 0.4953 -0.2032)
			(stroke
				(width 0.1)
				(type default)
			)
			(layer "F.Fab")
		)
		(fp_line
			(start 0.4953 -0.2032)
			(end 0.4953 1.6002)
			(stroke
				(width 0.1)
				(type default)
			)
			(layer "F.Fab")
		)
		(pad "1" smd rect
			(at 0 0 270)
			(size 0.762 0.889)
			(layers "F.Cu" "F.Mask" "F.Paste")
			(net "PVDDQ_ABC")
		)
		(pad "2" smd rect
			(at 0 1.397 270)
			(size 0.762 0.889)
			(layers "F.Cu" "F.Mask" "F.Paste")
			(net "GND")
		)
		(zone
			(layer "F.Cu")
			(hatch none 0.5)
			(connect_pads
				(clearance 0)
			)
			(min_thickness 0.25)
			(keepout
				(tracks not_allowed)
				(vias allowed)
				(pads allowed)
				(copperpour not_allowed)
				(footprints allowed)
			)
			(placement
				(enabled no)
				(sheetname "")
			)
			(fill
				(thermal_gap 0.5)
				(thermal_bridge_width 0.5)
				(island_removal_mode 0)
			)
			(polygon
				(pts
					(xy 264.009124 -69.022214) (xy 264.009124 -68.260214) (xy 263.501124 -68.260214) (xy 263.501124 -69.022214)
				)
			)
		)
	)
	(footprint ""
		(layer "F.Cu")
		(at 278.3332 -79.6036 180)
		(property "Reference" "C6D3"
			(at 0 0 180)
			(layer "F.SilkS")
			(hide yes)
			(effects
				(font
					(size 1.27 1.27)
				)
			)
		)
		(property "Value" ""
			(at 0 0 180)
			(layer "F.Fab")
			(effects
				(font
					(size 1.27 1.27)
				)
			)
		)
		(duplicate_pad_numbers_are_jumpers no)
		(fp_poly
			(pts
				(xy -0.4953 -0.2032) (xy 0.4953 -0.2032) (xy 0.4953 1.6002) (xy -0.4953 1.6002)
			)
			(stroke
				(width 0)
				(type default)
			)
			(fill no)
			(layer "F.CrtYd")
		)
		(fp_line
			(start 0.4953 1.6002)
			(end -0.4953 1.6002)
			(stroke
				(width 0.1)
				(type default)
			)
			(layer "F.Fab")
		)
		(fp_line
			(start 0.4953 -0.2032)
			(end 0.4953 1.6002)
			(stroke
				(width 0.1)
				(type default)
			)
			(layer "F.Fab")
		)
		(fp_line
			(start -0.4953 1.6002)
			(end -0.4953 -0.2032)
			(stroke
				(width 0.1)
				(type default)
			)
			(layer "F.Fab")
		)
		(fp_line
			(start -0.4953 -0.2032)
			(end 0.4953 -0.2032)
			(stroke
				(width 0.1)
				(type default)
			)
			(layer "F.Fab")
		)
		(pad "1" smd rect
			(at 0 0 180)
			(size 0.762 0.889)
			(layers "F.Cu" "F.Mask" "F.Paste")
			(net "PVCCIO_CPU0")
		)
		(pad "2" smd rect
			(at 0 1.397 180)
			(size 0.762 0.889)
			(layers "F.Cu" "F.Mask" "F.Paste")
			(net "GND")
		)
		(zone
			(layer "F.Cu")
			(hatch none 0.5)
			(connect_pads
				(clearance 0)
			)
			(min_thickness 0.25)
			(keepout
				(tracks not_allowed)
				(vias allowed)
				(pads allowed)
				(copperpour not_allowed)
				(footprints allowed)
			)
			(placement
				(enabled no)
				(sheetname "")
			)
			(fill
				(thermal_gap 0.5)
				(thermal_bridge_width 0.5)
				(island_removal_mode 0)
			)
			(polygon
				(pts
					(xy 278.7142 -80.0481) (xy 277.9522 -80.0481) (xy 277.9522 -80.5561) (xy 278.7142 -80.5561)
				)
			)
		)
	)
	(footprint ""
		(layer "F.Cu")
		(at 322.7324 -34.163 -90)
		(property "Reference" "R6F5"
			(at 0 0 270)
			(layer "F.SilkS")
			(hide yes)
			(effects
				(font
					(size 1.27 1.27)
				)
			)
		)
		(property "Value" ""
			(at 0 0 270)
			(layer "F.Fab")
			(effects
				(font
					(size 1.27 1.27)
				)
			)
		)
		(duplicate_pad_numbers_are_jumpers no)
		(fp_poly
			(pts
				(xy -0.2794 -0.1016) (xy 0.2794 -0.1016) (xy 0.2794 0.9906) (xy -0.2794 0.9906)
			)
			(stroke
				(width 0)
				(type default)
			)
			(fill no)
			(layer "F.CrtYd")
		)
		(fp_line
			(start -0.2794 0.9906)
			(end 0.2794 0.9906)
			(stroke
				(width 0.1)
				(type default)
			)
			(layer "F.Fab")
		)
		(fp_line
			(start 0.2794 0.9906)
			(end 0.2794 -0.1016)
			(stroke
				(width 0.1)
				(type default)
			)
			(layer "F.Fab")
		)
		(fp_line
			(start -0.2794 -0.1016)
			(end -0.2794 0.9906)
			(stroke
				(width 0.1)
				(type default)
			)
			(layer "F.Fab")
		)
		(fp_line
			(start 0.2794 -0.1016)
			(end -0.2794 -0.1016)
			(stroke
				(width 0.1)
				(type default)
			)
			(layer "F.Fab")
		)
		(pad "1" smd rect
			(at 0 0 270)
			(size 0.508 0.508)
			(layers "F.Cu" "F.Mask" "F.Paste")
			(net "FM_ADR_COMPLETE_CPU1_N")
		)
		(pad "2" smd rect
			(at 0 0.889 270)
			(size 0.508 0.508)
			(layers "F.Cu" "F.Mask" "F.Paste")
			(net "FM_ADR_COMPLETE_GHJ_N")
		)
		(zone
			(layer "F.Cu")
			(hatch none 0.5)
			(connect_pads
				(clearance 0)
			)
			(min_thickness 0.25)
			(keepout
				(tracks not_allowed)
				(vias allowed)
				(pads allowed)
				(copperpour not_allowed)
				(footprints allowed)
			)
			(placement
				(enabled no)
				(sheetname "")
			)
			(fill
				(thermal_gap 0.5)
				(thermal_bridge_width 0.5)
				(island_removal_mode 0)
			)
			(polygon
				(pts
					(xy 322.0974 -34.417) (xy 322.0974 -33.909) (xy 322.4784 -33.909) (xy 322.4784 -34.417)
				)
			)
		)
		(zone
			(layer "F.Cu")
			(hatch none 0.5)
			(connect_pads
				(clearance 0)
			)
			(min_thickness 0.25)
			(keepout
				(tracks allowed)
				(vias not_allowed)
				(pads allowed)
				(copperpour not_allowed)
				(footprints allowed)
			)
			(placement
				(enabled no)
				(sheetname "")
			)
			(fill
				(thermal_gap 0.5)
				(thermal_bridge_width 0.5)
				(island_removal_mode 0)
			)
			(polygon
				(pts
					(xy 322.4784 -34.417) (xy 322.4784 -33.909) (xy 322.0974 -33.909) (xy 322.0974 -34.417)
				)
			)
		)
	)
	(footprint ""
		(layer "F.Cu")
		(at 18.4912 -26.67 90)
		(property "Reference" "J1F3"
			(at 1.91643 14.8463 0)
			(unlocked yes)
			(layer "B.SilkS")
			(effects
				(font
					(size 0.7874 0.5842)
					(thickness 0.1524)
				)
				(justify left mirror)
			)
		)
		(property "Value" ""
			(at 0 0 90)
			(layer "F.Fab")
			(effects
				(font
					(size 1.27 1.27)
				)
			)
		)
		(duplicate_pad_numbers_are_jumpers no)
		(fp_line
			(start 2.169922 -1.599946)
			(end 2.169922 10.349992)
			(stroke
				(width 0.1524)
				(type default)
			)
			(layer "F.SilkS")
		)
		(fp_line
			(start -1.230122 -1.599946)
			(end 2.169922 -1.599946)
			(stroke
				(width 0.1524)
				(type default)
			)
			(layer "F.SilkS")
		)
		(fp_line
			(start 2.169922 10.349992)
			(end -1.230122 10.349992)
			(stroke
				(width 0.1524)
				(type default)
			)
			(layer "F.SilkS")
		)
		(fp_line
			(start -1.230122 10.349992)
			(end -1.230122 -1.599946)
			(stroke
				(width 0.1524)
				(type default)
			)
			(layer "F.SilkS")
		)
		(fp_poly
			(pts
				(xy -2.709418 -1.590802) (xy -2.709418 -0.574802) (xy -1.439418 -1.082802)
			)
			(stroke
				(width 0)
				(type default)
			)
			(fill yes)
			(layer "F.SilkS")
		)
		(fp_poly
			(pts
				(xy -3.141218 -0.549402) (xy -3.141218 0.466598) (xy -1.871218 -0.041402)
			)
			(stroke
				(width 0)
				(type default)
			)
			(fill yes)
			(layer "B.SilkS")
		)
		(fp_poly
			(pts
				(xy -1.230122 -1.599946) (xy -1.230122 10.349992) (xy 2.169922 10.349992) (xy 2.169922 -1.599946)
			)
			(stroke
				(width 0)
				(type default)
			)
			(fill no)
			(layer "F.CrtYd")
		)
		(fp_poly
			(pts
				(xy -3.141218 -0.549402) (xy -3.141218 0.466598) (xy -1.871218 -0.041402)
			)
			(stroke
				(width 0)
				(type default)
			)
			(fill yes)
			(layer "B.Fab")
		)
		(fp_line
			(start 2.169922 -1.599946)
			(end 2.169922 10.349992)
			(stroke
				(width 0.1)
				(type default)
			)
			(layer "F.Fab")
		)
		(fp_line
			(start -1.230122 -1.599946)
			(end 2.169922 -1.599946)
			(stroke
				(width 0.1)
				(type default)
			)
			(layer "F.Fab")
		)
		(fp_line
			(start 2.169922 10.349992)
			(end -1.230122 10.349992)
			(stroke
				(width 0.1)
				(type default)
			)
			(layer "F.Fab")
		)
		(fp_line
			(start -1.230122 10.349992)
			(end -1.230122 -1.599946)
			(stroke
				(width 0.1)
				(type default)
			)
			(layer "F.Fab")
		)
		(fp_text user "8"
			(at 2.413 9.22147 90)
			(unlocked yes)
			(layer "F.SilkS")
			(effects
				(font
					(size 0.7874 0.5842)
					(thickness 0.1524)
				)
				(justify left)
			)
		)
		(fp_text user "8"
			(at -1.896618 8.83285 90)
			(unlocked yes)
			(layer "B.SilkS")
			(effects
				(font
					(size 0.7874 0.5842)
					(thickness 0.1524)
				)
				(justify left mirror)
			)
		)
		(fp_text user "8"
			(at -1.896618 8.83285 90)
			(unlocked yes)
			(layer "B.Fab")
			(effects
				(font
					(size 0.7874 0.5842)
					(thickness 0.1524)
				)
				(justify left mirror)
			)
		)
		(fp_text user "8"
			(at -2.03327 -0.381 0)
			(unlocked yes)
			(layer "F.Fab")
			(effects
				(font
					(size 0.7874 0.5842)
					(thickness 0.1524)
				)
				(justify left)
			)
		)
		(pad "1" thru_hole rect
			(at 0 0 90)
			(size 0.9906 0.9906)
			(drill 0.6096)
			(layers "*.Cu" "*.Mask")
			(remove_unused_layers no)
			(net "P3V3_STBY")
			(clearance 0.127)
			(thermal_gap 0.127)
			(padstack
				(mode front_inner_back)
				(layer "Inner"
					(shape circle)
					(size 0.9906 0.9906)
					(clearance 0.127)
				)
				(layer "B.Cu"
					(shape rect)
					(size 0.9906 0.9906)
					(clearance 0.127)
				)
			)
		)
		(pad "2" thru_hole circle
			(at 0 1.249934 90)
			(size 0.9906 0.9906)
			(drill 0.6096)
			(layers "*.Cu" "*.Mask")
			(remove_unused_layers no)
			(net "FM_MP_PS_REDUNDANT_LOST_N")
			(clearance 0.127)
			(thermal_gap 0.127)
		)
		(pad "3" thru_hole circle
			(at 0 2.500122 90)
			(size 0.9906 0.9906)
			(drill 0.6096)
			(layers "*.Cu" "*.Mask")
			(remove_unused_layers no)
			(net "FM_MP_PS_FAIL_N")
			(clearance 0.127)
			(thermal_gap 0.127)
		)
		(pad "4" thru_hole circle
			(at 0 3.750056 90)
			(size 0.9906 0.9906)
			(drill 0.6096)
			(layers "*.Cu" "*.Mask")
			(remove_unused_layers no)
			(net "FM_MATED_IN_N")
			(clearance 0.127)
			(thermal_gap 0.127)
		)
		(pad "5" thru_hole circle
			(at 0 4.99999 90)
			(size 0.9906 0.9906)
			(drill 0.6096)
			(layers "*.Cu" "*.Mask")
			(remove_unused_layers no)
			(net "IRQ_SML1_PMBUS_ALERT_R_N")
			(clearance 0.127)
			(thermal_gap 0.127)
		)
		(pad "6" thru_hole circle
			(at 0 6.249924 90)
			(size 0.9906 0.9906)
			(drill 0.6096)
			(layers "*.Cu" "*.Mask")
			(remove_unused_layers no)
			(net "SMB_BMC_PMBUS_STBY_LVC3_SDA")
			(clearance 0.127)
			(thermal_gap 0.127)
		)
		(pad "7" thru_hole circle
			(at 0 7.500112 90)
			(size 0.9906 0.9906)
			(drill 0.6096)
			(layers "*.Cu" "*.Mask")
			(remove_unused_layers no)
			(net "SMB_BMC_PMBUS_STBY_LVC3_SCL")
			(clearance 0.127)
			(thermal_gap 0.127)
		)
		(pad "8" thru_hole circle
			(at 0 8.750046 90)
			(size 0.9906 0.9906)
			(drill 0.6096)
			(layers "*.Cu" "*.Mask")
			(remove_unused_layers no)
			(net "GND")
			(clearance 0.127)
			(thermal_gap 0.127)
		)
	)
	(footprint ""
		(layer "F.Cu")
		(at 28.702 -3.766312)
		(property "Reference" "R1G15"
			(at 0 0 0)
			(layer "F.SilkS")
			(hide yes)
			(effects
				(font
					(size 1.27 1.27)
				)
			)
		)
		(property "Value" ""
			(at 0 0 0)
			(layer "F.Fab")
			(effects
				(font
					(size 1.27 1.27)
				)
			)
		)
		(duplicate_pad_numbers_are_jumpers no)
		(fp_poly
			(pts
				(xy -0.2794 -0.1016) (xy 0.2794 -0.1016) (xy 0.2794 0.9906) (xy -0.2794 0.9906)
			)
			(stroke
				(width 0)
				(type default)
			)
			(fill no)
			(layer "F.CrtYd")
		)
		(fp_line
			(start -0.2794 -0.1016)
			(end -0.2794 0.9906)
			(stroke
				(width 0.1)
				(type default)
			)
			(layer "F.Fab")
		)
		(fp_line
			(start -0.2794 0.9906)
			(end 0.2794 0.9906)
			(stroke
				(width 0.1)
				(type default)
			)
			(layer "F.Fab")
		)
		(fp_line
			(start 0.2794 -0.1016)
			(end -0.2794 -0.1016)
			(stroke
				(width 0.1)
				(type default)
			)
			(layer "F.Fab")
		)
		(fp_line
			(start 0.2794 0.9906)
			(end 0.2794 -0.1016)
			(stroke
				(width 0.1)
				(type default)
			)
			(layer "F.Fab")
		)
		(pad "1" smd rect
			(at 0 0)
			(size 0.508 0.508)
			(layers "F.Cu" "F.Mask" "F.Paste")
			(net "PVDDQ_GHJ")
		)
		(pad "2" smd rect
			(at 0 0.889)
			(size 0.508 0.508)
			(layers "F.Cu" "F.Mask" "F.Paste")
			(net "M_J_VREF")
		)
		(zone
			(layer "F.Cu")
			(hatch none 0.5)
			(connect_pads
				(clearance 0)
			)
			(min_thickness 0.25)
			(keepout
				(tracks allowed)
				(vias not_allowed)
				(pads allowed)
				(copperpour not_allowed)
				(footprints allowed)
			)
			(placement
				(enabled no)
				(sheetname "")
			)
			(fill
				(thermal_gap 0.5)
				(thermal_bridge_width 0.5)
				(island_removal_mode 0)
			)
			(polygon
				(pts
					(xy 28.448 -3.512312) (xy 28.956 -3.512312) (xy 28.956 -3.131312) (xy 28.448 -3.131312)
				)
			)
		)
		(zone
			(layer "F.Cu")
			(hatch none 0.5)
			(connect_pads
				(clearance 0)
			)
			(min_thickness 0.25)
			(keepout
				(tracks not_allowed)
				(vias allowed)
				(pads allowed)
				(copperpour not_allowed)
				(footprints allowed)
			)
			(placement
				(enabled no)
				(sheetname "")
			)
			(fill
				(thermal_gap 0.5)
				(thermal_bridge_width 0.5)
				(island_removal_mode 0)
			)
			(polygon
				(pts
					(xy 28.448 -3.131312) (xy 28.956 -3.131312) (xy 28.956 -3.512312) (xy 28.448 -3.512312)
				)
			)
		)
	)
	(footprint ""
		(layer "F.Cu")
		(at 13.8938 -34.798 90)
		(property "Reference" "C1F4"
			(at 0 0 90)
			(layer "F.SilkS")
			(hide yes)
			(effects
				(font
					(size 1.27 1.27)
				)
			)
		)
		(property "Value" ""
			(at 0 0 90)
			(layer "F.Fab")
			(effects
				(font
					(size 1.27 1.27)
				)
			)
		)
		(duplicate_pad_numbers_are_jumpers no)
		(fp_rect
			(start -0.3048 -0.1016)
			(end 0.3048 0.9906)
			(stroke
				(width 0)
				(type default)
			)
			(fill no)
			(layer "F.CrtYd")
		)
		(fp_line
			(start 0.3048 -0.1016)
			(end -0.3048 -0.1016)
			(stroke
				(width 0.1)
				(type default)
			)
			(layer "F.Fab")
		)
		(fp_line
			(start -0.3048 -0.1016)
			(end -0.3048 0.9906)
			(stroke
				(width 0.1)
				(type default)
			)
			(layer "F.Fab")
		)
		(fp_line
			(start 0.3048 0.9906)
			(end 0.3048 -0.1016)
			(stroke
				(width 0.1)
				(type default)
			)
			(layer "F.Fab")
		)
		(fp_line
			(start -0.3048 0.9906)
			(end 0.3048 0.9906)
			(stroke
				(width 0.1)
				(type default)
			)
			(layer "F.Fab")
		)
		(pad "1" smd rect
			(at 0 0 90)
			(size 0.508 0.508)
			(layers "F.Cu" "F.Mask" "F.Paste")
			(net "P3E_CPU1_PE3_MP_C_TXN<6>")
		)
		(pad "2" smd rect
			(at 0 0.889 90)
			(size 0.508 0.508)
			(layers "F.Cu" "F.Mask" "F.Paste")
			(net "P3E_CPU1_PE3_MP_TXN<6>")
		)
		(zone
			(layer "F.Cu")
			(hatch none 0.5)
			(connect_pads
				(clearance 0)
			)
			(min_thickness 0.25)
			(keepout
				(tracks not_allowed)
				(vias allowed)
				(pads allowed)
				(copperpour not_allowed)
				(footprints allowed)
			)
			(placement
				(enabled no)
				(sheetname "")
			)
			(fill
				(thermal_gap 0.5)
				(thermal_bridge_width 0.5)
				(island_removal_mode 0)
			)
			(polygon
				(pts
					(xy 14.1478 -34.544) (xy 14.5288 -34.544) (xy 14.5288 -35.052) (xy 14.1478 -35.052)
				)
			)
		)
		(zone
			(layer "F.Cu")
			(hatch none 0.5)
			(connect_pads
				(clearance 0)
			)
			(min_thickness 0.25)
			(keepout
				(tracks allowed)
				(vias not_allowed)
				(pads allowed)
				(copperpour not_allowed)
				(footprints allowed)
			)
			(placement
				(enabled no)
				(sheetname "")
			)
			(fill
				(thermal_gap 0.5)
				(thermal_bridge_width 0.5)
				(island_removal_mode 0)
			)
			(polygon
				(pts
					(xy 14.1478 -34.544) (xy 14.5288 -34.544) (xy 14.5288 -35.052) (xy 14.1478 -35.052)
				)
			)
		)
	)
	(footprint ""
		(layer "F.Cu")
		(at 368.69624 -107.106466)
		(property "Reference" "C7C5"
			(at 0 0 0)
			(layer "F.SilkS")
			(hide yes)
			(effects
				(font
					(size 1.27 1.27)
				)
			)
		)
		(property "Value" ""
			(at 0 0 0)
			(layer "F.Fab")
			(effects
				(font
					(size 1.27 1.27)
				)
			)
		)
		(duplicate_pad_numbers_are_jumpers no)
		(fp_poly
			(pts
				(xy 0.3048 -0.1016) (xy 0.3048 0.9906) (xy -0.3048 0.9906) (xy -0.3048 -0.1016)
			)
			(stroke
				(width 0)
				(type default)
			)
			(fill no)
			(layer "F.CrtYd")
		)
		(fp_line
			(start -0.3048 -0.1016)
			(end -0.3048 0.9906)
			(stroke
				(width 0.1)
				(type default)
			)
			(layer "F.Fab")
		)
		(fp_line
			(start -0.3048 0.9906)
			(end 0.3048 0.9906)
			(stroke
				(width 0.1)
				(type default)
			)
			(layer "F.Fab")
		)
		(fp_line
			(start 0.3048 -0.1016)
			(end -0.3048 -0.1016)
			(stroke
				(width 0.1)
				(type default)
			)
			(layer "F.Fab")
		)
		(fp_line
			(start 0.3048 0.9906)
			(end 0.3048 -0.1016)
			(stroke
				(width 0.1)
				(type default)
			)
			(layer "F.Fab")
		)
		(pad "1" smd rect
			(at 0 0)
			(size 0.508 0.508)
			(layers "F.Cu" "F.Mask" "F.Paste")
			(net "XTAL_PCH_48M_OUT")
		)
		(pad "2" smd rect
			(at 0 0.889)
			(size 0.508 0.508)
			(layers "F.Cu" "F.Mask" "F.Paste")
			(net "GND")
		)
		(zone
			(layer "F.Cu")
			(hatch none 0.5)
			(connect_pads
				(clearance 0)
			)
			(min_thickness 0.25)
			(keepout
				(tracks allowed)
				(vias not_allowed)
				(pads allowed)
				(copperpour not_allowed)
				(footprints allowed)
			)
			(placement
				(enabled no)
				(sheetname "")
			)
			(fill
				(thermal_gap 0.5)
				(thermal_bridge_width 0.5)
				(island_removal_mode 0)
			)
			(polygon
				(pts
					(xy 368.44224 -106.852466) (xy 368.95024 -106.852466) (xy 368.95024 -106.471466) (xy 368.44224 -106.471466)
				)
			)
		)
		(zone
			(layer "F.Cu")
			(hatch none 0.5)
			(connect_pads
				(clearance 0)
			)
			(min_thickness 0.25)
			(keepout
				(tracks not_allowed)
				(vias allowed)
				(pads allowed)
				(copperpour not_allowed)
				(footprints allowed)
			)
			(placement
				(enabled no)
				(sheetname "")
			)
			(fill
				(thermal_gap 0.5)
				(thermal_bridge_width 0.5)
				(island_removal_mode 0)
			)
			(polygon
				(pts
					(xy 368.44224 -106.471466) (xy 368.95024 -106.471466) (xy 368.95024 -106.852466) (xy 368.44224 -106.852466)
				)
			)
		)
	)
	(footprint ""
		(layer "F.Cu")
		(at 408.178 -126.238)
		(property "Reference" "C8B9"
			(at 0 0 0)
			(layer "F.SilkS")
			(hide yes)
			(effects
				(font
					(size 1.27 1.27)
				)
			)
		)
		(property "Value" ""
			(at 0 0 0)
			(layer "F.Fab")
			(effects
				(font
					(size 1.27 1.27)
				)
			)
		)
		(duplicate_pad_numbers_are_jumpers no)
		(fp_poly
			(pts
				(xy -0.4953 -0.2032) (xy 0.4953 -0.2032) (xy 0.4953 1.6002) (xy -0.4953 1.6002)
			)
			(stroke
				(width 0)
				(type default)
			)
			(fill no)
			(layer "F.CrtYd")
		)
		(fp_line
			(start -0.4953 -0.2032)
			(end 0.4953 -0.2032)
			(stroke
				(width 0.1)
				(type default)
			)
			(layer "F.Fab")
		)
		(fp_line
			(start -0.4953 1.6002)
			(end -0.4953 -0.2032)
			(stroke
				(width 0.1)
				(type default)
			)
			(layer "F.Fab")
		)
		(fp_line
			(start 0.4953 -0.2032)
			(end 0.4953 1.6002)
			(stroke
				(width 0.1)
				(type default)
			)
			(layer "F.Fab")
		)
		(fp_line
			(start 0.4953 1.6002)
			(end -0.4953 1.6002)
			(stroke
				(width 0.1)
				(type default)
			)
			(layer "F.Fab")
		)
		(pad "1" smd rect
			(at 0 0)
			(size 0.762 0.889)
			(layers "F.Cu" "F.Mask" "F.Paste")
			(net "P1V05_PCH_STBY")
		)
		(pad "2" smd rect
			(at 0 1.397)
			(size 0.762 0.889)
			(layers "F.Cu" "F.Mask" "F.Paste")
			(net "GND")
		)
		(zone
			(layer "F.Cu")
			(hatch none 0.5)
			(connect_pads
				(clearance 0)
			)
			(min_thickness 0.25)
			(keepout
				(tracks not_allowed)
				(vias allowed)
				(pads allowed)
				(copperpour not_allowed)
				(footprints allowed)
			)
			(placement
				(enabled no)
				(sheetname "")
			)
			(fill
				(thermal_gap 0.5)
				(thermal_bridge_width 0.5)
				(island_removal_mode 0)
			)
			(polygon
				(pts
					(xy 407.797 -125.7935) (xy 408.559 -125.7935) (xy 408.559 -125.2855) (xy 407.797 -125.2855)
				)
			)
		)
	)
	(footprint ""
		(layer "F.Cu")
		(at 324.5485 -120.396 90)
		(property "Reference" "C6B10"
			(at -0.8382 -0.67818 90)
			(unlocked yes)
			(layer "F.SilkS")
			(effects
				(font
					(size 0.4064 0.254)
					(thickness 0.1524)
				)
				(justify left)
			)
		)
		(property "Value" ""
			(at 0 0 90)
			(layer "F.Fab")
			(effects
				(font
					(size 1.27 1.27)
				)
			)
		)
		(duplicate_pad_numbers_are_jumpers no)
		(fp_poly
			(pts
				(xy 0.3048 -0.1016) (xy 0.3048 0.9906) (xy -0.3048 0.9906) (xy -0.3048 -0.1016)
			)
			(stroke
				(width 0)
				(type default)
			)
			(fill no)
			(layer "F.CrtYd")
		)
		(fp_line
			(start 0.3048 -0.1016)
			(end -0.3048 -0.1016)
			(stroke
				(width 0.1)
				(type default)
			)
			(layer "F.Fab")
		)
		(fp_line
			(start -0.3048 -0.1016)
			(end -0.3048 0.9906)
			(stroke
				(width 0.1)
				(type default)
			)
			(layer "F.Fab")
		)
		(fp_line
			(start 0.3048 0.9906)
			(end 0.3048 -0.1016)
			(stroke
				(width 0.1)
				(type default)
			)
			(layer "F.Fab")
		)
		(fp_line
			(start -0.3048 0.9906)
			(end 0.3048 0.9906)
			(stroke
				(width 0.1)
				(type default)
			)
			(layer "F.Fab")
		)
		(pad "1" smd rect
			(at 0 0 90)
			(size 0.508 0.508)
			(layers "F.Cu" "F.Mask" "F.Paste")
			(net "P3E_CPU0_PE1_PCH_TXP<13>")
		)
		(pad "2" smd rect
			(at 0 0.889 90)
			(size 0.508 0.508)
			(layers "F.Cu" "F.Mask" "F.Paste")
			(net "P3E_CPU0_PE1_PCH_C_TXP<13>")
		)
		(zone
			(layer "F.Cu")
			(hatch none 0.5)
			(connect_pads
				(clearance 0)
			)
			(min_thickness 0.25)
			(keepout
				(tracks allowed)
				(vias not_allowed)
				(pads allowed)
				(copperpour not_allowed)
				(footprints allowed)
			)
			(placement
				(enabled no)
				(sheetname "")
			)
			(fill
				(thermal_gap 0.5)
				(thermal_bridge_width 0.5)
				(island_removal_mode 0)
			)
			(polygon
				(pts
					(xy 324.8025 -120.142) (xy 324.8025 -120.65) (xy 325.1835 -120.65) (xy 325.1835 -120.142)
				)
			)
		)
	)
	(footprint ""
		(layer "F.Cu")
		(at 479.6155 -142.875 90)
		(property "Reference" "C1L10"
			(at 0 0 90)
			(layer "F.SilkS")
			(hide yes)
			(effects
				(font
					(size 1.27 1.27)
				)
			)
		)
		(property "Value" ""
			(at 0 0 90)
			(layer "F.Fab")
			(effects
				(font
					(size 1.27 1.27)
				)
			)
		)
		(duplicate_pad_numbers_are_jumpers no)
		(fp_poly
			(pts
				(xy 0.3048 -0.1016) (xy 0.3048 0.9906) (xy -0.3048 0.9906) (xy -0.3048 -0.1016)
			)
			(stroke
				(width 0)
				(type default)
			)
			(fill no)
			(layer "F.CrtYd")
		)
		(fp_line
			(start 0.3048 -0.1016)
			(end -0.3048 -0.1016)
			(stroke
				(width 0.1)
				(type default)
			)
			(layer "F.Fab")
		)
		(fp_line
			(start -0.3048 -0.1016)
			(end -0.3048 0.9906)
			(stroke
				(width 0.1)
				(type default)
			)
			(layer "F.Fab")
		)
		(fp_line
			(start 0.3048 0.9906)
			(end 0.3048 -0.1016)
			(stroke
				(width 0.1)
				(type default)
			)
			(layer "F.Fab")
		)
		(fp_line
			(start -0.3048 0.9906)
			(end 0.3048 0.9906)
			(stroke
				(width 0.1)
				(type default)
			)
			(layer "F.Fab")
		)
		(pad "1" smd rect
			(at 0 0 90)
			(size 0.508 0.508)
			(layers "F.Cu" "F.Mask" "F.Paste")
			(net "FP_RST_BTN_R_N")
		)
		(pad "2" smd rect
			(at 0 0.889 90)
			(size 0.508 0.508)
			(layers "F.Cu" "F.Mask" "F.Paste")
			(net "GND")
		)
		(zone
			(layer "F.Cu")
			(hatch none 0.5)
			(connect_pads
				(clearance 0)
			)
			(min_thickness 0.25)
			(keepout
				(tracks allowed)
				(vias not_allowed)
				(pads allowed)
				(copperpour not_allowed)
				(footprints allowed)
			)
			(placement
				(enabled no)
				(sheetname "")
			)
			(fill
				(thermal_gap 0.5)
				(thermal_bridge_width 0.5)
				(island_removal_mode 0)
			)
			(polygon
				(pts
					(xy 479.8695 -142.621) (xy 479.8695 -143.129) (xy 480.2505 -143.129) (xy 480.2505 -142.621)
				)
			)
		)
		(zone
			(layer "F.Cu")
			(hatch none 0.5)
			(connect_pads
				(clearance 0)
			)
			(min_thickness 0.25)
			(keepout
				(tracks not_allowed)
				(vias allowed)
				(pads allowed)
				(copperpour not_allowed)
				(footprints allowed)
			)
			(placement
				(enabled no)
				(sheetname "")
			)
			(fill
				(thermal_gap 0.5)
				(thermal_bridge_width 0.5)
				(island_removal_mode 0)
			)
			(polygon
				(pts
					(xy 480.2505 -142.621) (xy 480.2505 -143.129) (xy 479.8695 -143.129) (xy 479.8695 -142.621)
				)
			)
		)
	)
	(footprint ""
		(layer "F.Cu")
		(at 351.5868 -8.0518 180)
		(property "Reference" "CT49"
			(at -1.1684 2.18567 180)
			(unlocked yes)
			(layer "F.SilkS")
			(effects
				(font
					(size 0.7874 0.5842)
					(thickness 0.1524)
				)
				(justify left)
			)
		)
		(property "Value" ""
			(at 0 0 180)
			(layer "F.Fab")
			(effects
				(font
					(size 1.27 1.27)
				)
			)
		)
		(duplicate_pad_numbers_are_jumpers no)
		(fp_poly
			(pts
				(xy 0.3048 -0.1016) (xy 0.3048 0.9906) (xy -0.3048 0.9906) (xy -0.3048 -0.1016)
			)
			(stroke
				(width 0)
				(type default)
			)
			(fill no)
			(layer "F.CrtYd")
		)
		(fp_line
			(start 0.3048 0.9906)
			(end 0.3048 -0.1016)
			(stroke
				(width 0.1)
				(type default)
			)
			(layer "F.Fab")
		)
		(fp_line
			(start 0.3048 -0.1016)
			(end -0.3048 -0.1016)
			(stroke
				(width 0.1)
				(type default)
			)
			(layer "F.Fab")
		)
		(fp_line
			(start -0.3048 0.9906)
			(end 0.3048 0.9906)
			(stroke
				(width 0.1)
				(type default)
			)
			(layer "F.Fab")
		)
		(fp_line
			(start -0.3048 -0.1016)
			(end -0.3048 0.9906)
			(stroke
				(width 0.1)
				(type default)
			)
			(layer "F.Fab")
		)
		(pad "1" smd rect
			(at 0 0 180)
			(size 0.508 0.508)
			(layers "F.Cu" "F.Mask" "F.Paste")
			(net "A_TSENSE_PVDDQ_ABC")
		)
		(pad "2" smd rect
			(at 0 0.889 180)
			(size 0.508 0.508)
			(layers "F.Cu" "F.Mask" "F.Paste")
			(net "GND")
		)
		(zone
			(layer "F.Cu")
			(hatch none 0.5)
			(connect_pads
				(clearance 0)
			)
			(min_thickness 0.25)
			(keepout
				(tracks not_allowed)
				(vias allowed)
				(pads allowed)
				(copperpour not_allowed)
				(footprints allowed)
			)
			(placement
				(enabled no)
				(sheetname "")
			)
			(fill
				(thermal_gap 0.5)
				(thermal_bridge_width 0.5)
				(island_removal_mode 0)
			)
			(polygon
				(pts
					(xy 351.8408 -8.6868) (xy 351.3328 -8.6868) (xy 351.3328 -8.3058) (xy 351.8408 -8.3058)
				)
			)
		)
		(zone
			(layer "F.Cu")
			(hatch none 0.5)
			(connect_pads
				(clearance 0)
			)
			(min_thickness 0.25)
			(keepout
				(tracks allowed)
				(vias not_allowed)
				(pads allowed)
				(copperpour not_allowed)
				(footprints allowed)
			)
			(placement
				(enabled no)
				(sheetname "")
			)
			(fill
				(thermal_gap 0.5)
				(thermal_bridge_width 0.5)
				(island_removal_mode 0)
			)
			(polygon
				(pts
					(xy 351.8408 -8.3058) (xy 351.3328 -8.3058) (xy 351.3328 -8.6868) (xy 351.8408 -8.6868)
				)
			)
		)
	)
	(footprint ""
		(layer "F.Cu")
		(at 413.3342 -114.2492 -90)
		(property "Reference" "R7W10"
			(at -0.8382 -0.67818 270)
			(unlocked yes)
			(layer "F.SilkS")
			(effects
				(font
					(size 0.4064 0.254)
					(thickness 0.1524)
				)
				(justify left)
			)
		)
		(property "Value" ""
			(at 0 0 270)
			(layer "F.Fab")
			(effects
				(font
					(size 1.27 1.27)
				)
			)
		)
		(duplicate_pad_numbers_are_jumpers no)
		(fp_poly
			(pts
				(xy -0.2794 -0.1016) (xy 0.2794 -0.1016) (xy 0.2794 0.9906) (xy -0.2794 0.9906)
			)
			(stroke
				(width 0)
				(type default)
			)
			(fill no)
			(layer "F.CrtYd")
		)
		(fp_line
			(start -0.2794 0.9906)
			(end 0.2794 0.9906)
			(stroke
				(width 0.1)
				(type default)
			)
			(layer "F.Fab")
		)
		(fp_line
			(start 0.2794 0.9906)
			(end 0.2794 -0.1016)
			(stroke
				(width 0.1)
				(type default)
			)
			(layer "F.Fab")
		)
		(fp_line
			(start -0.2794 -0.1016)
			(end -0.2794 0.9906)
			(stroke
				(width 0.1)
				(type default)
			)
			(layer "F.Fab")
		)
		(fp_line
			(start 0.2794 -0.1016)
			(end -0.2794 -0.1016)
			(stroke
				(width 0.1)
				(type default)
			)
			(layer "F.Fab")
		)
		(pad "1" smd rect
			(at 0 0 270)
			(size 0.508 0.508)
			(layers "F.Cu" "F.Mask" "F.Paste")
			(net "FM_CPU0_RC_ERROR_N")
		)
		(pad "2" smd rect
			(at 0 0.889 270)
			(size 0.508 0.508)
			(layers "F.Cu" "F.Mask" "F.Paste")
			(net "FM_CPU0_RC_ERROR_R1_N")
		)
		(zone
			(layer "F.Cu")
			(hatch none 0.5)
			(connect_pads
				(clearance 0)
			)
			(min_thickness 0.25)
			(keepout
				(tracks not_allowed)
				(vias allowed)
				(pads allowed)
				(copperpour not_allowed)
				(footprints allowed)
			)
			(placement
				(enabled no)
				(sheetname "")
			)
			(fill
				(thermal_gap 0.5)
				(thermal_bridge_width 0.5)
				(island_removal_mode 0)
			)
			(polygon
				(pts
					(xy 412.6992 -114.5032) (xy 412.6992 -113.9952) (xy 413.0802 -113.9952) (xy 413.0802 -114.5032)
				)
			)
		)
		(zone
			(layer "F.Cu")
			(hatch none 0.5)
			(connect_pads
				(clearance 0)
			)
			(min_thickness 0.25)
			(keepout
				(tracks allowed)
				(vias not_allowed)
				(pads allowed)
				(copperpour not_allowed)
				(footprints allowed)
			)
			(placement
				(enabled no)
				(sheetname "")
			)
			(fill
				(thermal_gap 0.5)
				(thermal_bridge_width 0.5)
				(island_removal_mode 0)
			)
			(polygon
				(pts
					(xy 413.0802 -114.5032) (xy 413.0802 -113.9952) (xy 412.6992 -113.9952) (xy 412.6992 -114.5032)
				)
			)
		)
	)
	(footprint ""
		(layer "F.Cu")
		(at 93.038168 -3.321812 -90)
		(property "Reference" "C2G15"
			(at 0 0 270)
			(layer "F.SilkS")
			(hide yes)
			(effects
				(font
					(size 1.27 1.27)
				)
			)
		)
		(property "Value" ""
			(at 0 0 270)
			(layer "F.Fab")
			(effects
				(font
					(size 1.27 1.27)
				)
			)
		)
		(duplicate_pad_numbers_are_jumpers no)
		(fp_rect
			(start -0.500126 1.598422)
			(end 0.500126 -0.201422)
			(stroke
				(width 0)
				(type default)
			)
			(fill no)
			(layer "F.CrtYd")
		)
		(fp_line
			(start -0.500126 1.598422)
			(end -0.500126 -0.201422)
			(stroke
				(width 0.1)
				(type default)
			)
			(layer "F.Fab")
		)
		(fp_line
			(start 0.500126 1.598422)
			(end -0.500126 1.598422)
			(stroke
				(width 0.1)
				(type default)
			)
			(layer "F.Fab")
		)
		(fp_line
			(start -0.500126 -0.201422)
			(end 0.500126 -0.201422)
			(stroke
				(width 0.1)
				(type default)
			)
			(layer "F.Fab")
		)
		(fp_line
			(start 0.500126 -0.201422)
			(end 0.500126 1.598422)
			(stroke
				(width 0.1)
				(type default)
			)
			(layer "F.Fab")
		)
		(pad "1" smd rect
			(at 0 0 180)
			(size 0.889 0.9906)
			(layers "F.Cu" "F.Mask" "F.Paste")
			(net "PVDDQ_GHJ")
		)
		(pad "2" smd rect
			(at 0 1.397 180)
			(size 0.889 0.9906)
			(layers "F.Cu" "F.Mask" "F.Paste")
			(net "GND")
		)
		(zone
			(layer "F.Cu")
			(hatch none 0.5)
			(connect_pads
				(clearance 0)
			)
			(min_thickness 0.25)
			(keepout
				(tracks not_allowed)
				(vias allowed)
				(pads allowed)
				(copperpour not_allowed)
				(footprints allowed)
			)
			(placement
				(enabled no)
				(sheetname "")
			)
			(fill
				(thermal_gap 0.5)
				(thermal_bridge_width 0.5)
				(island_removal_mode 0)
			)
			(polygon
				(pts
					(xy 92.085668 -3.817112) (xy 92.085668 -2.826512) (xy 92.593668 -2.826512) (xy 92.593668 -3.817112)
				)
			)
		)
		(zone
			(layer "F.Cu")
			(hatch none 0.5)
			(connect_pads
				(clearance 0)
			)
			(min_thickness 0.25)
			(keepout
				(tracks allowed)
				(vias not_allowed)
				(pads allowed)
				(copperpour not_allowed)
				(footprints allowed)
			)
			(placement
				(enabled no)
				(sheetname "")
			)
			(fill
				(thermal_gap 0.5)
				(thermal_bridge_width 0.5)
				(island_removal_mode 0)
			)
			(polygon
				(pts
					(xy 92.085668 -3.817112) (xy 92.085668 -2.826512) (xy 92.593668 -2.826512) (xy 92.593668 -3.817112)
				)
			)
		)
	)
	(footprint ""
		(layer "F.Cu")
		(at 478.1931 -42.9514 -90)
		(property "Reference" "R9E16"
			(at 0 0 270)
			(layer "F.SilkS")
			(hide yes)
			(effects
				(font
					(size 1.27 1.27)
				)
			)
		)
		(property "Value" ""
			(at 0 0 270)
			(layer "F.Fab")
			(effects
				(font
					(size 1.27 1.27)
				)
			)
		)
		(duplicate_pad_numbers_are_jumpers no)
		(fp_poly
			(pts
				(xy -0.2794 -0.1016) (xy 0.2794 -0.1016) (xy 0.2794 0.9906) (xy -0.2794 0.9906)
			)
			(stroke
				(width 0)
				(type default)
			)
			(fill no)
			(layer "F.CrtYd")
		)
		(fp_line
			(start -0.2794 0.9906)
			(end 0.2794 0.9906)
			(stroke
				(width 0.1)
				(type default)
			)
			(layer "F.Fab")
		)
		(fp_line
			(start 0.2794 0.9906)
			(end 0.2794 -0.1016)
			(stroke
				(width 0.1)
				(type default)
			)
			(layer "F.Fab")
		)
		(fp_line
			(start -0.2794 -0.1016)
			(end -0.2794 0.9906)
			(stroke
				(width 0.1)
				(type default)
			)
			(layer "F.Fab")
		)
		(fp_line
			(start 0.2794 -0.1016)
			(end -0.2794 -0.1016)
			(stroke
				(width 0.1)
				(type default)
			)
			(layer "F.Fab")
		)
		(pad "1" smd rect
			(at 0 0 270)
			(size 0.508 0.508)
			(layers "F.Cu" "F.Mask" "F.Paste")
			(net "RMII_PCH_SPRNGVLLE_ARB_IN_R")
		)
		(pad "2" smd rect
			(at 0 0.889 270)
			(size 0.508 0.508)
			(layers "F.Cu" "F.Mask" "F.Paste")
			(net "RMII_PCH_SPRNGVLLE_ARB_IN")
		)
		(zone
			(layer "F.Cu")
			(hatch none 0.5)
			(connect_pads
				(clearance 0)
			)
			(min_thickness 0.25)
			(keepout
				(tracks not_allowed)
				(vias allowed)
				(pads allowed)
				(copperpour not_allowed)
				(footprints allowed)
			)
			(placement
				(enabled no)
				(sheetname "")
			)
			(fill
				(thermal_gap 0.5)
				(thermal_bridge_width 0.5)
				(island_removal_mode 0)
			)
			(polygon
				(pts
					(xy 477.5581 -43.2054) (xy 477.5581 -42.6974) (xy 477.9391 -42.6974) (xy 477.9391 -43.2054)
				)
			)
		)
		(zone
			(layer "F.Cu")
			(hatch none 0.5)
			(connect_pads
				(clearance 0)
			)
			(min_thickness 0.25)
			(keepout
				(tracks allowed)
				(vias not_allowed)
				(pads allowed)
				(copperpour not_allowed)
				(footprints allowed)
			)
			(placement
				(enabled no)
				(sheetname "")
			)
			(fill
				(thermal_gap 0.5)
				(thermal_bridge_width 0.5)
				(island_removal_mode 0)
			)
			(polygon
				(pts
					(xy 477.9391 -43.2054) (xy 477.9391 -42.6974) (xy 477.5581 -42.6974) (xy 477.5581 -43.2054)
				)
			)
		)
	)
	(footprint ""
		(layer "F.Cu")
		(at 155.194 -30.5308 -90)
		(property "Reference" "R3F5"
			(at 0 0 270)
			(layer "F.SilkS")
			(hide yes)
			(effects
				(font
					(size 1.27 1.27)
				)
			)
		)
		(property "Value" ""
			(at 0 0 270)
			(layer "F.Fab")
			(effects
				(font
					(size 1.27 1.27)
				)
			)
		)
		(duplicate_pad_numbers_are_jumpers no)
		(fp_poly
			(pts
				(xy -0.2794 -0.1016) (xy 0.2794 -0.1016) (xy 0.2794 0.9906) (xy -0.2794 0.9906)
			)
			(stroke
				(width 0)
				(type default)
			)
			(fill no)
			(layer "F.CrtYd")
		)
		(fp_line
			(start -0.2794 0.9906)
			(end 0.2794 0.9906)
			(stroke
				(width 0.1)
				(type default)
			)
			(layer "F.Fab")
		)
		(fp_line
			(start 0.2794 0.9906)
			(end 0.2794 -0.1016)
			(stroke
				(width 0.1)
				(type default)
			)
			(layer "F.Fab")
		)
		(fp_line
			(start -0.2794 -0.1016)
			(end -0.2794 0.9906)
			(stroke
				(width 0.1)
				(type default)
			)
			(layer "F.Fab")
		)
		(fp_line
			(start 0.2794 -0.1016)
			(end -0.2794 -0.1016)
			(stroke
				(width 0.1)
				(type default)
			)
			(layer "F.Fab")
		)
		(pad "1" smd rect
			(at 0 0 270)
			(size 0.508 0.508)
			(layers "F.Cu" "F.Mask" "F.Paste")
			(net "CLK_322M_156M_CPU1_OSC_VRM_DN")
		)
		(pad "2" smd rect
			(at 0 0.889 270)
			(size 0.508 0.508)
			(layers "F.Cu" "F.Mask" "F.Paste")
			(net "CLK_322M_OSC_CPU1_RC_DN")
		)
		(zone
			(layer "F.Cu")
			(hatch none 0.5)
			(connect_pads
				(clearance 0)
			)
			(min_thickness 0.25)
			(keepout
				(tracks not_allowed)
				(vias allowed)
				(pads allowed)
				(copperpour not_allowed)
				(footprints allowed)
			)
			(placement
				(enabled no)
				(sheetname "")
			)
			(fill
				(thermal_gap 0.5)
				(thermal_bridge_width 0.5)
				(island_removal_mode 0)
			)
			(polygon
				(pts
					(xy 154.559 -30.7848) (xy 154.559 -30.2768) (xy 154.94 -30.2768) (xy 154.94 -30.7848)
				)
			)
		)
		(zone
			(layer "F.Cu")
			(hatch none 0.5)
			(connect_pads
				(clearance 0)
			)
			(min_thickness 0.25)
			(keepout
				(tracks allowed)
				(vias not_allowed)
				(pads allowed)
				(copperpour not_allowed)
				(footprints allowed)
			)
			(placement
				(enabled no)
				(sheetname "")
			)
			(fill
				(thermal_gap 0.5)
				(thermal_bridge_width 0.5)
				(island_removal_mode 0)
			)
			(polygon
				(pts
					(xy 154.94 -30.7848) (xy 154.94 -30.2768) (xy 154.559 -30.2768) (xy 154.559 -30.7848)
				)
			)
		)
	)
	(footprint ""
		(layer "F.Cu")
		(at 97.72142 -158.1277 -90)
		(property "Reference" "SH8L1"
			(at 0 0 270)
			(layer "F.SilkS")
			(hide yes)
			(effects
				(font
					(size 1.27 1.27)
				)
			)
		)
		(property "Value" ""
			(at 0 0 270)
			(layer "F.Fab")
			(effects
				(font
					(size 1.27 1.27)
				)
			)
		)
		(duplicate_pad_numbers_are_jumpers no)
		(fp_poly
			(pts
				(xy -0.1651 -0.0508) (xy -0.1651 0.5842) (xy 0.1651 0.5842) (xy 0.1651 -0.0508)
			)
			(stroke
				(width 0)
				(type default)
			)
			(fill no)
			(layer "F.CrtYd")
		)
		(fp_line
			(start -0.1651 0.5842)
			(end -0.1651 -0.0508)
			(stroke
				(width 0.1)
				(type default)
			)
			(layer "F.Fab")
		)
		(fp_line
			(start 0.1651 0.5842)
			(end -0.1651 0.5842)
			(stroke
				(width 0.1)
				(type default)
			)
			(layer "F.Fab")
		)
		(fp_line
			(start -0.1651 -0.0508)
			(end 0.1651 -0.0508)
			(stroke
				(width 0.1)
				(type default)
			)
			(layer "F.Fab")
		)
		(fp_line
			(start 0.1651 -0.0508)
			(end 0.1651 0.5842)
			(stroke
				(width 0.1)
				(type default)
			)
			(layer "F.Fab")
		)
		(pad "1" smd custom
			(at 0 0 90)
			(size 0.0762 0.0762)
			(layers "F.Cu" "F.Mask" "F.Paste")
			(net "VR_PVTT_KLM_SNS")
			(options
				(clearance outline)
				(anchor circle)
			)
			(primitives
				(gr_poly
					(pts
						(arc
							(start -0.1524 -0.10795)
							(mid -0.098518 -0.130268)
							(end -0.0762 -0.18415)
						)
						(xy -0.0762 -0.22225) (xy 0.0762 -0.22225)
						(arc
							(start 0.0762 -0.18415)
							(mid 0.098518 -0.130268)
							(end 0.1524 -0.10795)
						)
						(xy 0.1524 0.22225) (xy -0.1524 0.22225)
					)
					(width 0)
					(fill yes)
				)
			)
		)
		(pad "2" smd custom
			(at 0 0.5334 270)
			(size 0.0762 0.0762)
			(layers "F.Cu" "F.Mask" "F.Paste")
			(net "PVTT_KLM")
			(options
				(clearance outline)
				(anchor circle)
			)
			(primitives
				(gr_poly
					(pts
						(arc
							(start -0.1524 -0.10795)
							(mid -0.098518 -0.130268)
							(end -0.0762 -0.18415)
						)
						(xy -0.0762 -0.22225) (xy 0.0762 -0.22225)
						(arc
							(start 0.0762 -0.18415)
							(mid 0.098518 -0.130268)
							(end 0.1524 -0.10795)
						)
						(xy 0.1524 0.22225) (xy -0.1524 0.22225)
					)
					(width 0)
					(fill yes)
				)
			)
		)
	)
	(footprint ""
		(layer "F.Cu")
		(at 280.138124 -71.714614 180)
		(property "Reference" "C6D10"
			(at 0 0 180)
			(layer "F.SilkS")
			(hide yes)
			(effects
				(font
					(size 1.27 1.27)
				)
			)
		)
		(property "Value" ""
			(at 0 0 180)
			(layer "F.Fab")
			(effects
				(font
					(size 1.27 1.27)
				)
			)
		)
		(duplicate_pad_numbers_are_jumpers no)
		(fp_poly
			(pts
				(xy -0.4953 -0.2032) (xy 0.4953 -0.2032) (xy 0.4953 1.6002) (xy -0.4953 1.6002)
			)
			(stroke
				(width 0)
				(type default)
			)
			(fill no)
			(layer "F.CrtYd")
		)
		(fp_line
			(start 0.4953 1.6002)
			(end -0.4953 1.6002)
			(stroke
				(width 0.1)
				(type default)
			)
			(layer "F.Fab")
		)
		(fp_line
			(start 0.4953 -0.2032)
			(end 0.4953 1.6002)
			(stroke
				(width 0.1)
				(type default)
			)
			(layer "F.Fab")
		)
		(fp_line
			(start -0.4953 1.6002)
			(end -0.4953 -0.2032)
			(stroke
				(width 0.1)
				(type default)
			)
			(layer "F.Fab")
		)
		(fp_line
			(start -0.4953 -0.2032)
			(end 0.4953 -0.2032)
			(stroke
				(width 0.1)
				(type default)
			)
			(layer "F.Fab")
		)
		(pad "1" smd rect
			(at 0 0 180)
			(size 0.762 0.889)
			(layers "F.Cu" "F.Mask" "F.Paste")
			(net "PVCCIO_CPU0")
		)
		(pad "2" smd rect
			(at 0 1.397 180)
			(size 0.762 0.889)
			(layers "F.Cu" "F.Mask" "F.Paste")
			(net "GND")
		)
		(zone
			(layer "F.Cu")
			(hatch none 0.5)
			(connect_pads
				(clearance 0)
			)
			(min_thickness 0.25)
			(keepout
				(tracks not_allowed)
				(vias allowed)
				(pads allowed)
				(copperpour not_allowed)
				(footprints allowed)
			)
			(placement
				(enabled no)
				(sheetname "")
			)
			(fill
				(thermal_gap 0.5)
				(thermal_bridge_width 0.5)
				(island_removal_mode 0)
			)
			(polygon
				(pts
					(xy 280.519124 -72.159114) (xy 279.757124 -72.159114) (xy 279.757124 -72.667114) (xy 280.519124 -72.667114)
				)
			)
		)
	)
	(footprint ""
		(layer "F.Cu")
		(at 194.700398 -133.0706 90)
		(property "Reference" "J4B1"
			(at -5.087112 42.28211 0)
			(unlocked yes)
			(layer "F.SilkS")
			(effects
				(font
					(size 0.7874 0.5842)
					(thickness 0.1524)
				)
				(justify left)
			)
		)
		(property "Value" ""
			(at 0 0 90)
			(layer "F.Fab")
			(effects
				(font
					(size 1.27 1.27)
				)
			)
		)
		(duplicate_pad_numbers_are_jumpers no)
		(fp_line
			(start 5.5499 -7.675118)
			(end 5.5499 -1.480058)
			(stroke
				(width 0.1524)
				(type default)
			)
			(layer "F.SilkS")
		)
		(fp_line
			(start -0.94996 -7.675118)
			(end 5.5499 -7.675118)
			(stroke
				(width 0.1524)
				(type default)
			)
			(layer "F.SilkS")
		)
		(fp_line
			(start -0.94996 -1.480058)
			(end -0.94996 -7.675118)
			(stroke
				(width 0.1524)
				(type default)
			)
			(layer "F.SilkS")
		)
		(fp_line
			(start 5.5499 128.130046)
			(end 5.5499 134.325106)
			(stroke
				(width 0.1524)
				(type default)
			)
			(layer "F.SilkS")
		)
		(fp_line
			(start 5.5499 134.325106)
			(end -0.94996 134.325106)
			(stroke
				(width 0.1524)
				(type default)
			)
			(layer "F.SilkS")
		)
		(fp_line
			(start -0.94996 134.325106)
			(end -0.94996 128.130046)
			(stroke
				(width 0.1524)
				(type default)
			)
			(layer "F.SilkS")
		)
		(fp_poly
			(pts
				(xy -2.984246 -0.461264) (xy -2.984246 0.554736) (xy -1.714246 0.046736)
			)
			(stroke
				(width 0)
				(type default)
			)
			(fill yes)
			(layer "F.SilkS")
		)
		(fp_poly
			(pts
				(xy -0.94996 -7.675118) (xy -0.94996 134.325106) (xy 5.5499 134.325106) (xy 5.5499 -7.675118)
			)
			(stroke
				(width 0)
				(type default)
			)
			(fill no)
			(layer "F.CrtYd")
		)
		(fp_line
			(start 5.5499 -7.675118)
			(end 5.5499 134.325106)
			(stroke
				(width 0.1)
				(type default)
			)
			(layer "F.Fab")
		)
		(fp_line
			(start -0.94996 -7.675118)
			(end 5.5499 -7.675118)
			(stroke
				(width 0.1)
				(type default)
			)
			(layer "F.Fab")
		)
		(fp_line
			(start 5.5499 134.325106)
			(end -0.94996 134.325106)
			(stroke
				(width 0.1)
				(type default)
			)
			(layer "F.Fab")
		)
		(fp_line
			(start -0.94996 134.325106)
			(end -0.94996 -7.675118)
			(stroke
				(width 0.1)
				(type default)
			)
			(layer "F.Fab")
		)
		(fp_poly
			(pts
				(xy -2.984246 -0.461264) (xy -2.984246 0.554736) (xy -1.714246 0.046736)
			)
			(stroke
				(width 0)
				(type default)
			)
			(fill yes)
			(layer "F.Fab")
		)
		(fp_text user "145"
			(at 6.038088 -1.02489 0)
			(unlocked yes)
			(layer "F.SilkS")
			(effects
				(font
					(size 0.7874 0.5842)
					(thickness 0.1524)
				)
				(justify left)
			)
		)
		(fp_text user "77"
			(at -1.988312 63.97371 0)
			(unlocked yes)
			(layer "F.SilkS")
			(effects
				(font
					(size 0.7874 0.5842)
					(thickness 0.1524)
				)
				(justify left)
			)
		)
		(fp_text user "221"
			(at 5.479288 65.26911 0)
			(unlocked yes)
			(layer "F.SilkS")
			(effects
				(font
					(size 0.7874 0.5842)
					(thickness 0.1524)
				)
				(justify left)
			)
		)
		(fp_text user "222"
			(at 6.04393 69.840602 0)
			(unlocked yes)
			(layer "F.SilkS")
			(effects
				(font
					(size 0.7874 0.5842)
					(thickness 0.1524)
				)
				(justify left)
			)
		)
		(fp_text user "78"
			(at -1.744726 69.88302 0)
			(unlocked yes)
			(layer "F.SilkS")
			(effects
				(font
					(size 0.7874 0.5842)
					(thickness 0.1524)
				)
				(justify left)
			)
		)
		(fp_text user "144"
			(at -1.663192 125.13945 0)
			(unlocked yes)
			(layer "F.SilkS")
			(effects
				(font
					(size 0.7874 0.5842)
					(thickness 0.1524)
				)
				(justify left)
			)
		)
		(fp_text user "288"
			(at 6.469888 128.21031 0)
			(unlocked yes)
			(layer "F.SilkS")
			(effects
				(font
					(size 0.7874 0.5842)
					(thickness 0.1524)
				)
				(justify left)
			)
		)
		(fp_text user "145"
			(at 6.039866 -1.025144 0)
			(unlocked yes)
			(layer "F.Fab")
			(effects
				(font
					(size 0.7874 0.5842)
					(thickness 0.1524)
				)
				(justify left)
			)
		)
		(fp_text user "221"
			(at 3.448558 65.93078 90)
			(unlocked yes)
			(layer "F.Fab")
			(effects
				(font
					(size 0.7874 0.5842)
					(thickness 0.1524)
				)
				(justify left)
			)
		)
		(fp_text user "77"
			(at -0.361442 65.93078 90)
			(unlocked yes)
			(layer "F.Fab")
			(effects
				(font
					(size 0.7874 0.5842)
					(thickness 0.1524)
				)
				(justify left)
			)
		)
		(fp_text user "78"
			(at -0.640842 68.95338 90)
			(unlocked yes)
			(layer "F.Fab")
			(effects
				(font
					(size 0.7874 0.5842)
					(thickness 0.1524)
				)
				(justify left)
			)
		)
		(fp_text user "222"
			(at 4.083558 69.10578 90)
			(unlocked yes)
			(layer "F.Fab")
			(effects
				(font
					(size 0.7874 0.5842)
					(thickness 0.1524)
				)
				(justify left)
			)
		)
		(fp_text user "288"
			(at 3.448558 128.16078 90)
			(unlocked yes)
			(layer "F.Fab")
			(effects
				(font
					(size 0.7874 0.5842)
					(thickness 0.1524)
				)
				(justify left)
			)
		)
		(fp_text user "144"
			(at -0.361442 128.16078 90)
			(unlocked yes)
			(layer "F.Fab")
			(effects
				(font
					(size 0.7874 0.5842)
					(thickness 0.1524)
				)
				(justify left)
			)
		)
		(pad "" thru_hole circle
			(at 2.29997 -5.649976 90)
			(size 2.8194 2.8194)
			(drill 2.4384)
			(layers "*.Cu" "*.Mask")
			(remove_unused_layers no)
			(clearance 0.127)
			(thermal_gap 0.127)
		)
		(pad "" thru_hole oval
			(at 2.29997 68.90004 90)
			(size 2.8194 1.5748)
			(drill oval 2.4384 1.1938)
			(layers "*.Cu" "*.Mask")
			(remove_unused_layers no)
			(clearance 0.127)
			(thermal_gap 0.127)
		)
		(pad "" thru_hole circle
			(at 2.29997 132.299964 90)
			(size 2.8194 2.8194)
			(drill 2.4384)
			(layers "*.Cu" "*.Mask")
			(remove_unused_layers no)
			(clearance 0.127)
			(thermal_gap 0.127)
		)
		(pad "1" smd rect
			(at 0 0 90)
			(size 1.8034 0.508)
			(layers "F.Cu" "F.Mask" "F.Paste")
			(net "P12V_NVDIMM_DEF")
		)
		(pad "2" smd rect
			(at 0 0.849884 90)
			(size 1.8034 0.508)
			(layers "F.Cu" "F.Mask" "F.Paste")
			(net "GND")
		)
		(pad "3" smd rect
			(at 0 1.700022 90)
			(size 1.8034 0.508)
			(layers "F.Cu" "F.Mask" "F.Paste")
			(net "M_D_DQ<5>")
		)
		(pad "4" smd rect
			(at 0 2.549906 90)
			(size 1.8034 0.508)
			(layers "F.Cu" "F.Mask" "F.Paste")
			(net "GND")
		)
		(pad "5" smd rect
			(at 0 3.400044 90)
			(size 1.8034 0.508)
			(layers "F.Cu" "F.Mask" "F.Paste")
			(net "M_D_DQ<1>")
		)
		(pad "6" smd rect
			(at 0 4.249928 90)
			(size 1.8034 0.508)
			(layers "F.Cu" "F.Mask" "F.Paste")
			(net "GND")
		)
		(pad "7" smd rect
			(at 0 5.100066 90)
			(size 1.8034 0.508)
			(layers "F.Cu" "F.Mask" "F.Paste")
			(net "M_D_DQS_DP<9>")
		)
		(pad "8" smd rect
			(at 0 5.94995 90)
			(size 1.8034 0.508)
			(layers "F.Cu" "F.Mask" "F.Paste")
			(net "M_D_DQS_DN<9>")
		)
		(pad "9" smd rect
			(at 0 6.800088 90)
			(size 1.8034 0.508)
			(layers "F.Cu" "F.Mask" "F.Paste")
			(net "GND")
		)
		(pad "10" smd rect
			(at 0 7.649972 90)
			(size 1.8034 0.508)
			(layers "F.Cu" "F.Mask" "F.Paste")
			(net "M_D_DQ<7>")
		)
		(pad "11" smd rect
			(at 0 8.50011 90)
			(size 1.8034 0.508)
			(layers "F.Cu" "F.Mask" "F.Paste")
			(net "GND")
		)
		(pad "12" smd rect
			(at 0 9.349994 90)
			(size 1.8034 0.508)
			(layers "F.Cu" "F.Mask" "F.Paste")
			(net "M_D_DQ<3>")
		)
		(pad "13" smd rect
			(at 0 10.199878 90)
			(size 1.8034 0.508)
			(layers "F.Cu" "F.Mask" "F.Paste")
			(net "GND")
		)
		(pad "14" smd rect
			(at 0 11.050016 90)
			(size 1.8034 0.508)
			(layers "F.Cu" "F.Mask" "F.Paste")
			(net "M_D_DQ<13>")
		)
		(pad "15" smd rect
			(at 0 11.8999 90)
			(size 1.8034 0.508)
			(layers "F.Cu" "F.Mask" "F.Paste")
			(net "GND")
		)
		(pad "16" smd rect
			(at 0 12.750038 90)
			(size 1.8034 0.508)
			(layers "F.Cu" "F.Mask" "F.Paste")
			(net "M_D_DQ<9>")
		)
		(pad "17" smd rect
			(at 0 13.599922 90)
			(size 1.8034 0.508)
			(layers "F.Cu" "F.Mask" "F.Paste")
			(net "GND")
		)
		(pad "18" smd rect
			(at 0 14.45006 90)
			(size 1.8034 0.508)
			(layers "F.Cu" "F.Mask" "F.Paste")
			(net "M_D_DQS_DP<10>")
		)
		(pad "19" smd rect
			(at 0 15.299944 90)
			(size 1.8034 0.508)
			(layers "F.Cu" "F.Mask" "F.Paste")
			(net "M_D_DQS_DN<10>")
		)
		(pad "20" smd rect
			(at 0 16.150082 90)
			(size 1.8034 0.508)
			(layers "F.Cu" "F.Mask" "F.Paste")
			(net "GND")
		)
		(pad "21" smd rect
			(at 0 16.999966 90)
			(size 1.8034 0.508)
			(layers "F.Cu" "F.Mask" "F.Paste")
			(net "M_D_DQ<15>")
		)
		(pad "22" smd rect
			(at 0 17.850104 90)
			(size 1.8034 0.508)
			(layers "F.Cu" "F.Mask" "F.Paste")
			(net "GND")
		)
		(pad "23" smd rect
			(at 0 18.699988 90)
			(size 1.8034 0.508)
			(layers "F.Cu" "F.Mask" "F.Paste")
			(net "M_D_DQ<11>")
		)
		(pad "24" smd rect
			(at 0 19.550126 90)
			(size 1.8034 0.508)
			(layers "F.Cu" "F.Mask" "F.Paste")
			(net "GND")
		)
		(pad "25" smd rect
			(at 0 20.40001 90)
			(size 1.8034 0.508)
			(layers "F.Cu" "F.Mask" "F.Paste")
			(net "M_D_DQ<21>")
		)
		(pad "26" smd rect
			(at 0 21.249894 90)
			(size 1.8034 0.508)
			(layers "F.Cu" "F.Mask" "F.Paste")
			(net "GND")
		)
		(pad "27" smd rect
			(at 0 22.100032 90)
			(size 1.8034 0.508)
			(layers "F.Cu" "F.Mask" "F.Paste")
			(net "M_D_DQ<17>")
		)
		(pad "28" smd rect
			(at 0 22.949916 90)
			(size 1.8034 0.508)
			(layers "F.Cu" "F.Mask" "F.Paste")
			(net "GND")
		)
		(pad "29" smd rect
			(at 0 23.800054 90)
			(size 1.8034 0.508)
			(layers "F.Cu" "F.Mask" "F.Paste")
			(net "M_D_DQS_DP<11>")
		)
		(pad "30" smd rect
			(at 0 24.649938 90)
			(size 1.8034 0.508)
			(layers "F.Cu" "F.Mask" "F.Paste")
			(net "M_D_DQS_DN<11>")
		)
		(pad "31" smd rect
			(at 0 25.500076 90)
			(size 1.8034 0.508)
			(layers "F.Cu" "F.Mask" "F.Paste")
			(net "GND")
		)
		(pad "32" smd rect
			(at 0 26.34996 90)
			(size 1.8034 0.508)
			(layers "F.Cu" "F.Mask" "F.Paste")
			(net "M_D_DQ<23>")
		)
		(pad "33" smd rect
			(at 0 27.200098 90)
			(size 1.8034 0.508)
			(layers "F.Cu" "F.Mask" "F.Paste")
			(net "GND")
		)
		(pad "34" smd rect
			(at 0 28.049982 90)
			(size 1.8034 0.508)
			(layers "F.Cu" "F.Mask" "F.Paste")
			(net "M_D_DQ<19>")
		)
		(pad "35" smd rect
			(at 0 28.90012 90)
			(size 1.8034 0.508)
			(layers "F.Cu" "F.Mask" "F.Paste")
			(net "GND")
		)
		(pad "36" smd rect
			(at 0 29.750004 90)
			(size 1.8034 0.508)
			(layers "F.Cu" "F.Mask" "F.Paste")
			(net "M_D_DQ<29>")
		)
		(pad "37" smd rect
			(at 0 30.599888 90)
			(size 1.8034 0.508)
			(layers "F.Cu" "F.Mask" "F.Paste")
			(net "GND")
		)
		(pad "38" smd rect
			(at 0 31.450026 90)
			(size 1.8034 0.508)
			(layers "F.Cu" "F.Mask" "F.Paste")
			(net "M_D_DQ<25>")
		)
		(pad "39" smd rect
			(at 0 32.29991 90)
			(size 1.8034 0.508)
			(layers "F.Cu" "F.Mask" "F.Paste")
			(net "GND")
		)
		(pad "40" smd rect
			(at 0 33.150048 90)
			(size 1.8034 0.508)
			(layers "F.Cu" "F.Mask" "F.Paste")
			(net "M_D_DQS_DP<12>")
		)
		(pad "41" smd rect
			(at 0 33.999932 90)
			(size 1.8034 0.508)
			(layers "F.Cu" "F.Mask" "F.Paste")
			(net "M_D_DQS_DN<12>")
		)
		(pad "42" smd rect
			(at 0 34.85007 90)
			(size 1.8034 0.508)
			(layers "F.Cu" "F.Mask" "F.Paste")
			(net "GND")
		)
		(pad "43" smd rect
			(at 0 35.699954 90)
			(size 1.8034 0.508)
			(layers "F.Cu" "F.Mask" "F.Paste")
			(net "M_D_DQ<31>")
		)
		(pad "44" smd rect
			(at 0 36.550092 90)
			(size 1.8034 0.508)
			(layers "F.Cu" "F.Mask" "F.Paste")
			(net "GND")
		)
		(pad "45" smd rect
			(at 0 37.399976 90)
			(size 1.8034 0.508)
			(layers "F.Cu" "F.Mask" "F.Paste")
			(net "M_D_DQ<27>")
		)
		(pad "46" smd rect
			(at 0 38.250114 90)
			(size 1.8034 0.508)
			(layers "F.Cu" "F.Mask" "F.Paste")
			(net "GND")
		)
		(pad "47" smd rect
			(at 0 39.099998 90)
			(size 1.8034 0.508)
			(layers "F.Cu" "F.Mask" "F.Paste")
			(net "M_D_ECC<5>")
		)
		(pad "48" smd rect
			(at 0 39.949882 90)
			(size 1.8034 0.508)
			(layers "F.Cu" "F.Mask" "F.Paste")
			(net "GND")
		)
		(pad "49" smd rect
			(at 0 40.80002 90)
			(size 1.8034 0.508)
			(layers "F.Cu" "F.Mask" "F.Paste")
			(net "M_D_ECC<1>")
		)
		(pad "50" smd rect
			(at 0 41.649904 90)
			(size 1.8034 0.508)
			(layers "F.Cu" "F.Mask" "F.Paste")
			(net "GND")
		)
		(pad "51" smd rect
			(at 0 42.500042 90)
			(size 1.8034 0.508)
			(layers "F.Cu" "F.Mask" "F.Paste")
			(net "M_D_DQS_DP<17>")
		)
		(pad "52" smd rect
			(at 0 43.349926 90)
			(size 1.8034 0.508)
			(layers "F.Cu" "F.Mask" "F.Paste")
			(net "M_D_DQS_DN<17>")
		)
		(pad "53" smd rect
			(at 0 44.200064 90)
			(size 1.8034 0.508)
			(layers "F.Cu" "F.Mask" "F.Paste")
			(net "GND")
		)
		(pad "54" smd rect
			(at 0 45.049948 90)
			(size 1.8034 0.508)
			(layers "F.Cu" "F.Mask" "F.Paste")
			(net "M_D_ECC<7>")
		)
		(pad "55" smd rect
			(at 0 45.900086 90)
			(size 1.8034 0.508)
			(layers "F.Cu" "F.Mask" "F.Paste")
			(net "GND")
		)
		(pad "56" smd rect
			(at 0 46.74997 90)
			(size 1.8034 0.508)
			(layers "F.Cu" "F.Mask" "F.Paste")
			(net "M_D_ECC<3>")
		)
		(pad "57" smd rect
			(at 0 47.600108 90)
			(size 1.8034 0.508)
			(layers "F.Cu" "F.Mask" "F.Paste")
			(net "GND")
		)
		(pad "58" smd rect
			(at 0 48.449992 90)
			(size 1.8034 0.508)
			(layers "F.Cu" "F.Mask" "F.Paste")
			(net "M_DEF_RST_N")
		)
		(pad "59" smd rect
			(at 0 49.299876 90)
			(size 1.8034 0.508)
			(layers "F.Cu" "F.Mask" "F.Paste")
			(net "PVDDQ_DEF")
		)
		(pad "60" smd rect
			(at 0 50.150014 90)
			(size 1.8034 0.508)
			(layers "F.Cu" "F.Mask" "F.Paste")
			(net "M_D_CKE<0>")
		)
		(pad "61" smd rect
			(at 0 50.999898 90)
			(size 1.8034 0.508)
			(layers "F.Cu" "F.Mask" "F.Paste")
			(net "PVDDQ_DEF")
		)
		(pad "62" smd rect
			(at 0 51.850036 90)
			(size 1.8034 0.508)
			(layers "F.Cu" "F.Mask" "F.Paste")
			(net "M_D_ACT_N")
		)
		(pad "63" smd rect
			(at 0 52.69992 90)
			(size 1.8034 0.508)
			(layers "F.Cu" "F.Mask" "F.Paste")
			(net "M_D_BG<0>")
		)
		(pad "64" smd rect
			(at 0 53.550058 90)
			(size 1.8034 0.508)
			(layers "F.Cu" "F.Mask" "F.Paste")
			(net "PVDDQ_DEF")
		)
		(pad "65" smd rect
			(at 0 54.399942 90)
			(size 1.8034 0.508)
			(layers "F.Cu" "F.Mask" "F.Paste")
			(net "M_D_MA<12>")
		)
		(pad "66" smd rect
			(at 0 55.25008 90)
			(size 1.8034 0.508)
			(layers "F.Cu" "F.Mask" "F.Paste")
			(net "M_D_MA<9>")
		)
		(pad "67" smd rect
			(at 0 56.099964 90)
			(size 1.8034 0.508)
			(layers "F.Cu" "F.Mask" "F.Paste")
			(net "PVDDQ_DEF")
		)
		(pad "68" smd rect
			(at 0 56.950102 90)
			(size 1.8034 0.508)
			(layers "F.Cu" "F.Mask" "F.Paste")
			(net "M_D_MA<8>")
		)
		(pad "69" smd rect
			(at 0 57.799986 90)
			(size 1.8034 0.508)
			(layers "F.Cu" "F.Mask" "F.Paste")
			(net "M_D_MA<6>")
		)
		(pad "70" smd rect
			(at 0 58.650124 90)
			(size 1.8034 0.508)
			(layers "F.Cu" "F.Mask" "F.Paste")
			(net "PVDDQ_DEF")
		)
		(pad "71" smd rect
			(at 0 59.500008 90)
			(size 1.8034 0.508)
			(layers "F.Cu" "F.Mask" "F.Paste")
			(net "M_D_MA<3>")
		)
		(pad "72" smd rect
			(at 0 60.349892 90)
			(size 1.8034 0.508)
			(layers "F.Cu" "F.Mask" "F.Paste")
			(net "M_D_MA<1>")
		)
		(pad "73" smd rect
			(at 0 61.20003 90)
			(size 1.8034 0.508)
			(layers "F.Cu" "F.Mask" "F.Paste")
			(net "PVDDQ_DEF")
		)
		(pad "74" smd rect
			(at 0 62.049914 90)
			(size 1.8034 0.508)
			(layers "F.Cu" "F.Mask" "F.Paste")
			(net "M_D_CLK_DP<0>")
		)
		(pad "75" smd rect
			(at 0 62.900052 90)
			(size 1.8034 0.508)
			(layers "F.Cu" "F.Mask" "F.Paste")
			(net "M_D_CLK_DN<0>")
		)
		(pad "76" smd rect
			(at 0 63.749936 90)
			(size 1.8034 0.508)
			(layers "F.Cu" "F.Mask" "F.Paste")
			(net "PVDDQ_DEF")
		)
		(pad "77" smd rect
			(at 0 64.600074 90)
			(size 1.8034 0.508)
			(layers "F.Cu" "F.Mask" "F.Paste")
			(net "PVTT_DEF")
		)
		(pad "78" smd rect
			(at 0 70.550024 90)
			(size 1.8034 0.508)
			(layers "F.Cu" "F.Mask" "F.Paste")
			(net "FM_DIMM_EVENT_COD_N")
		)
		(pad "79" smd rect
			(at 0 71.399908 90)
			(size 1.8034 0.508)
			(layers "F.Cu" "F.Mask" "F.Paste")
			(net "M_D_MA<0>")
		)
		(pad "80" smd rect
			(at 0 72.250046 90)
			(size 1.8034 0.508)
			(layers "F.Cu" "F.Mask" "F.Paste")
			(net "PVDDQ_DEF")
		)
		(pad "81" smd rect
			(at 0 73.09993 90)
			(size 1.8034 0.508)
			(layers "F.Cu" "F.Mask" "F.Paste")
			(net "M_D_BA<0>")
		)
		(pad "82" smd rect
			(at 0 73.950068 90)
			(size 1.8034 0.508)
			(layers "F.Cu" "F.Mask" "F.Paste")
			(net "M_D_MA<16>")
		)
		(pad "83" smd rect
			(at 0 74.799952 90)
			(size 1.8034 0.508)
			(layers "F.Cu" "F.Mask" "F.Paste")
			(net "PVDDQ_DEF")
		)
		(pad "84" smd rect
			(at 0 75.65009 90)
			(size 1.8034 0.508)
			(layers "F.Cu" "F.Mask" "F.Paste")
			(net "M_D_CS_N<0>")
		)
		(pad "85" smd rect
			(at 0 76.499974 90)
			(size 1.8034 0.508)
			(layers "F.Cu" "F.Mask" "F.Paste")
			(net "PVDDQ_DEF")
		)
		(pad "86" smd rect
			(at 0 77.350112 90)
			(size 1.8034 0.508)
			(layers "F.Cu" "F.Mask" "F.Paste")
			(net "M_D_MA<15>")
		)
		(pad "87" smd rect
			(at 0 78.199996 90)
			(size 1.8034 0.508)
			(layers "F.Cu" "F.Mask" "F.Paste")
			(net "M_D_ODT<0>")
		)
		(pad "88" smd rect
			(at 0 79.04988 90)
			(size 1.8034 0.508)
			(layers "F.Cu" "F.Mask" "F.Paste")
			(net "PVDDQ_DEF")
		)
		(pad "89" smd rect
			(at 0 79.900018 90)
			(size 1.8034 0.508)
			(layers "F.Cu" "F.Mask" "F.Paste")
			(net "M_D_CS_N<1>")
		)
		(pad "90" smd rect
			(at 0 80.749902 90)
			(size 1.8034 0.508)
			(layers "F.Cu" "F.Mask" "F.Paste")
			(net "PVDDQ_DEF")
		)
		(pad "91" smd rect
			(at 0 81.60004 90)
			(size 1.8034 0.508)
			(layers "F.Cu" "F.Mask" "F.Paste")
			(net "M_D_ODT<1>")
		)
		(pad "92" smd rect
			(at 0 82.449924 90)
			(size 1.8034 0.508)
			(layers "F.Cu" "F.Mask" "F.Paste")
			(net "PVDDQ_DEF")
		)
		(pad "93" smd rect
			(at 0 83.300062 90)
			(size 1.8034 0.508)
			(layers "F.Cu" "F.Mask" "F.Paste")
			(net "M_D_CS_N<2>")
		)
		(pad "94" smd rect
			(at 0 84.149946 90)
			(size 1.8034 0.508)
			(layers "F.Cu" "F.Mask" "F.Paste")
			(net "GND")
		)
		(pad "95" smd rect
			(at 0 85.000084 90)
			(size 1.8034 0.508)
			(layers "F.Cu" "F.Mask" "F.Paste")
			(net "M_D_DQ<37>")
		)
		(pad "96" smd rect
			(at 0 85.849968 90)
			(size 1.8034 0.508)
			(layers "F.Cu" "F.Mask" "F.Paste")
			(net "GND")
		)
		(pad "97" smd rect
			(at 0 86.700106 90)
			(size 1.8034 0.508)
			(layers "F.Cu" "F.Mask" "F.Paste")
			(net "M_D_DQ<33>")
		)
		(pad "98" smd rect
			(at 0 87.54999 90)
			(size 1.8034 0.508)
			(layers "F.Cu" "F.Mask" "F.Paste")
			(net "GND")
		)
		(pad "99" smd rect
			(at 0 88.399874 90)
			(size 1.8034 0.508)
			(layers "F.Cu" "F.Mask" "F.Paste")
			(net "M_D_DQS_DP<13>")
		)
		(pad "100" smd rect
			(at 0 89.250012 90)
			(size 1.8034 0.508)
			(layers "F.Cu" "F.Mask" "F.Paste")
			(net "M_D_DQS_DN<13>")
		)
		(pad "101" smd rect
			(at 0 90.099896 90)
			(size 1.8034 0.508)
			(layers "F.Cu" "F.Mask" "F.Paste")
			(net "GND")
		)
		(pad "102" smd rect
			(at 0 90.950034 90)
			(size 1.8034 0.508)
			(layers "F.Cu" "F.Mask" "F.Paste")
			(net "M_D_DQ<39>")
		)
		(pad "103" smd rect
			(at 0 91.799918 90)
			(size 1.8034 0.508)
			(layers "F.Cu" "F.Mask" "F.Paste")
			(net "GND")
		)
		(pad "104" smd rect
			(at 0 92.650056 90)
			(size 1.8034 0.508)
			(layers "F.Cu" "F.Mask" "F.Paste")
			(net "M_D_DQ<35>")
		)
		(pad "105" smd rect
			(at 0 93.49994 90)
			(size 1.8034 0.508)
			(layers "F.Cu" "F.Mask" "F.Paste")
			(net "GND")
		)
		(pad "106" smd rect
			(at 0 94.350078 90)
			(size 1.8034 0.508)
			(layers "F.Cu" "F.Mask" "F.Paste")
			(net "M_D_DQ<45>")
		)
		(pad "107" smd rect
			(at 0 95.199962 90)
			(size 1.8034 0.508)
			(layers "F.Cu" "F.Mask" "F.Paste")
			(net "GND")
		)
		(pad "108" smd rect
			(at 0 96.0501 90)
			(size 1.8034 0.508)
			(layers "F.Cu" "F.Mask" "F.Paste")
			(net "M_D_DQ<41>")
		)
		(pad "109" smd rect
			(at 0 96.899984 90)
			(size 1.8034 0.508)
			(layers "F.Cu" "F.Mask" "F.Paste")
			(net "GND")
		)
		(pad "110" smd rect
			(at 0 97.750122 90)
			(size 1.8034 0.508)
			(layers "F.Cu" "F.Mask" "F.Paste")
			(net "M_D_DQS_DP<14>")
		)
		(pad "111" smd rect
			(at 0 98.600006 90)
			(size 1.8034 0.508)
			(layers "F.Cu" "F.Mask" "F.Paste")
			(net "M_D_DQS_DN<14>")
		)
		(pad "112" smd rect
			(at 0 99.44989 90)
			(size 1.8034 0.508)
			(layers "F.Cu" "F.Mask" "F.Paste")
			(net "GND")
		)
		(pad "113" smd rect
			(at 0 100.300028 90)
			(size 1.8034 0.508)
			(layers "F.Cu" "F.Mask" "F.Paste")
			(net "M_D_DQ<47>")
		)
		(pad "114" smd rect
			(at 0 101.149912 90)
			(size 1.8034 0.508)
			(layers "F.Cu" "F.Mask" "F.Paste")
			(net "GND")
		)
		(pad "115" smd rect
			(at 0 102.00005 90)
			(size 1.8034 0.508)
			(layers "F.Cu" "F.Mask" "F.Paste")
			(net "M_D_DQ<43>")
		)
		(pad "116" smd rect
			(at 0 102.849934 90)
			(size 1.8034 0.508)
			(layers "F.Cu" "F.Mask" "F.Paste")
			(net "GND")
		)
		(pad "117" smd rect
			(at 0 103.700072 90)
			(size 1.8034 0.508)
			(layers "F.Cu" "F.Mask" "F.Paste")
			(net "M_D_DQ<53>")
		)
		(pad "118" smd rect
			(at 0 104.549956 90)
			(size 1.8034 0.508)
			(layers "F.Cu" "F.Mask" "F.Paste")
			(net "GND")
		)
		(pad "119" smd rect
			(at 0 105.400094 90)
			(size 1.8034 0.508)
			(layers "F.Cu" "F.Mask" "F.Paste")
			(net "M_D_DQ<49>")
		)
		(pad "120" smd rect
			(at 0 106.249978 90)
			(size 1.8034 0.508)
			(layers "F.Cu" "F.Mask" "F.Paste")
			(net "GND")
		)
		(pad "121" smd rect
			(at 0 107.100116 90)
			(size 1.8034 0.508)
			(layers "F.Cu" "F.Mask" "F.Paste")
			(net "M_D_DQS_DP<15>")
		)
		(pad "122" smd rect
			(at 0 107.95 90)
			(size 1.8034 0.508)
			(layers "F.Cu" "F.Mask" "F.Paste")
			(net "M_D_DQS_DN<15>")
		)
		(pad "123" smd rect
			(at 0 108.799884 90)
			(size 1.8034 0.508)
			(layers "F.Cu" "F.Mask" "F.Paste")
			(net "GND")
		)
		(pad "124" smd rect
			(at 0 109.650022 90)
			(size 1.8034 0.508)
			(layers "F.Cu" "F.Mask" "F.Paste")
			(net "M_D_DQ<55>")
		)
		(pad "125" smd rect
			(at 0 110.499906 90)
			(size 1.8034 0.508)
			(layers "F.Cu" "F.Mask" "F.Paste")
			(net "GND")
		)
		(pad "126" smd rect
			(at 0 111.350044 90)
			(size 1.8034 0.508)
			(layers "F.Cu" "F.Mask" "F.Paste")
			(net "M_D_DQ<51>")
		)
		(pad "127" smd rect
			(at 0 112.199928 90)
			(size 1.8034 0.508)
			(layers "F.Cu" "F.Mask" "F.Paste")
			(net "GND")
		)
		(pad "128" smd rect
			(at 0 113.050066 90)
			(size 1.8034 0.508)
			(layers "F.Cu" "F.Mask" "F.Paste")
			(net "M_D_DQ<61>")
		)
		(pad "129" smd rect
			(at 0 113.89995 90)
			(size 1.8034 0.508)
			(layers "F.Cu" "F.Mask" "F.Paste")
			(net "GND")
		)
		(pad "130" smd rect
			(at 0 114.750088 90)
			(size 1.8034 0.508)
			(layers "F.Cu" "F.Mask" "F.Paste")
			(net "M_D_DQ<57>")
		)
		(pad "131" smd rect
			(at 0 115.599972 90)
			(size 1.8034 0.508)
			(layers "F.Cu" "F.Mask" "F.Paste")
			(net "GND")
		)
		(pad "132" smd rect
			(at 0 116.45011 90)
			(size 1.8034 0.508)
			(layers "F.Cu" "F.Mask" "F.Paste")
			(net "M_D_DQS_DP<16>")
		)
		(pad "133" smd rect
			(at 0 117.299994 90)
			(size 1.8034 0.508)
			(layers "F.Cu" "F.Mask" "F.Paste")
			(net "M_D_DQS_DN<16>")
		)
		(pad "134" smd rect
			(at 0 118.149878 90)
			(size 1.8034 0.508)
			(layers "F.Cu" "F.Mask" "F.Paste")
			(net "GND")
		)
		(pad "135" smd rect
			(at 0 119.000016 90)
			(size 1.8034 0.508)
			(layers "F.Cu" "F.Mask" "F.Paste")
			(net "M_D_DQ<63>")
		)
		(pad "136" smd rect
			(at 0 119.8499 90)
			(size 1.8034 0.508)
			(layers "F.Cu" "F.Mask" "F.Paste")
			(net "GND")
		)
		(pad "137" smd rect
			(at 0 120.700038 90)
			(size 1.8034 0.508)
			(layers "F.Cu" "F.Mask" "F.Paste")
			(net "M_D_DQ<59>")
		)
		(pad "138" smd rect
			(at 0 121.549922 90)
			(size 1.8034 0.508)
			(layers "F.Cu" "F.Mask" "F.Paste")
			(net "GND")
		)
		(pad "139" smd rect
			(at 0 122.40006 90)
			(size 1.8034 0.508)
			(layers "F.Cu" "F.Mask" "F.Paste")
			(net "GND")
		)
		(pad "140" smd rect
			(at 0 123.249944 90)
			(size 1.8034 0.508)
			(layers "F.Cu" "F.Mask" "F.Paste")
			(net "GND")
		)
		(pad "141" smd rect
			(at 0 124.100082 90)
			(size 1.8034 0.508)
			(layers "F.Cu" "F.Mask" "F.Paste")
			(net "SMB_DDR_DEF_VPP_SCL")
		)
		(pad "142" smd rect
			(at 0 124.949966 90)
			(size 1.8034 0.508)
			(layers "F.Cu" "F.Mask" "F.Paste")
			(net "PVPP_DEF")
		)
		(pad "143" smd rect
			(at 0 125.800104 90)
			(size 1.8034 0.508)
			(layers "F.Cu" "F.Mask" "F.Paste")
			(net "PVPP_DEF")
		)
		(pad "144" smd rect
			(at 0 126.649988 90)
			(size 1.8034 0.508)
			(layers "F.Cu" "F.Mask" "F.Paste")
			(net "TP_CH_D_DIMM_D0_RFU_2")
		)
		(pad "145" smd rect
			(at 4.59994 0 90)
			(size 1.8034 0.508)
			(layers "F.Cu" "F.Mask" "F.Paste")
			(net "P12V_NVDIMM_DEF")
		)
		(pad "146" smd rect
			(at 4.59994 0.849884 90)
			(size 1.8034 0.508)
			(layers "F.Cu" "F.Mask" "F.Paste")
			(net "M_D_VREF")
		)
		(pad "147" smd rect
			(at 4.59994 1.700022 90)
			(size 1.8034 0.508)
			(layers "F.Cu" "F.Mask" "F.Paste")
			(net "GND")
		)
		(pad "148" smd rect
			(at 4.59994 2.549906 90)
			(size 1.8034 0.508)
			(layers "F.Cu" "F.Mask" "F.Paste")
			(net "M_D_DQ<4>")
		)
		(pad "149" smd rect
			(at 4.59994 3.400044 90)
			(size 1.8034 0.508)
			(layers "F.Cu" "F.Mask" "F.Paste")
			(net "GND")
		)
		(pad "150" smd rect
			(at 4.59994 4.249928 90)
			(size 1.8034 0.508)
			(layers "F.Cu" "F.Mask" "F.Paste")
			(net "M_D_DQ<0>")
		)
		(pad "151" smd rect
			(at 4.59994 5.100066 90)
			(size 1.8034 0.508)
			(layers "F.Cu" "F.Mask" "F.Paste")
			(net "GND")
		)
		(pad "152" smd rect
			(at 4.59994 5.94995 90)
			(size 1.8034 0.508)
			(layers "F.Cu" "F.Mask" "F.Paste")
			(net "M_D_DQS_DN<0>")
		)
		(pad "153" smd rect
			(at 4.59994 6.800088 90)
			(size 1.8034 0.508)
			(layers "F.Cu" "F.Mask" "F.Paste")
			(net "M_D_DQS_DP<0>")
		)
		(pad "154" smd rect
			(at 4.59994 7.649972 90)
			(size 1.8034 0.508)
			(layers "F.Cu" "F.Mask" "F.Paste")
			(net "GND")
		)
		(pad "155" smd rect
			(at 4.59994 8.50011 90)
			(size 1.8034 0.508)
			(layers "F.Cu" "F.Mask" "F.Paste")
			(net "M_D_DQ<6>")
		)
		(pad "156" smd rect
			(at 4.59994 9.349994 90)
			(size 1.8034 0.508)
			(layers "F.Cu" "F.Mask" "F.Paste")
			(net "GND")
		)
		(pad "157" smd rect
			(at 4.59994 10.199878 90)
			(size 1.8034 0.508)
			(layers "F.Cu" "F.Mask" "F.Paste")
			(net "M_D_DQ<2>")
		)
		(pad "158" smd rect
			(at 4.59994 11.050016 90)
			(size 1.8034 0.508)
			(layers "F.Cu" "F.Mask" "F.Paste")
			(net "GND")
		)
		(pad "159" smd rect
			(at 4.59994 11.8999 90)
			(size 1.8034 0.508)
			(layers "F.Cu" "F.Mask" "F.Paste")
			(net "M_D_DQ<12>")
		)
		(pad "160" smd rect
			(at 4.59994 12.750038 90)
			(size 1.8034 0.508)
			(layers "F.Cu" "F.Mask" "F.Paste")
			(net "GND")
		)
		(pad "161" smd rect
			(at 4.59994 13.599922 90)
			(size 1.8034 0.508)
			(layers "F.Cu" "F.Mask" "F.Paste")
			(net "M_D_DQ<8>")
		)
		(pad "162" smd rect
			(at 4.59994 14.45006 90)
			(size 1.8034 0.508)
			(layers "F.Cu" "F.Mask" "F.Paste")
			(net "GND")
		)
		(pad "163" smd rect
			(at 4.59994 15.299944 90)
			(size 1.8034 0.508)
			(layers "F.Cu" "F.Mask" "F.Paste")
			(net "M_D_DQS_DN<1>")
		)
		(pad "164" smd rect
			(at 4.59994 16.150082 90)
			(size 1.8034 0.508)
			(layers "F.Cu" "F.Mask" "F.Paste")
			(net "M_D_DQS_DP<1>")
		)
		(pad "165" smd rect
			(at 4.59994 16.999966 90)
			(size 1.8034 0.508)
			(layers "F.Cu" "F.Mask" "F.Paste")
			(net "GND")
		)
		(pad "166" smd rect
			(at 4.59994 17.850104 90)
			(size 1.8034 0.508)
			(layers "F.Cu" "F.Mask" "F.Paste")
			(net "M_D_DQ<14>")
		)
		(pad "167" smd rect
			(at 4.59994 18.699988 90)
			(size 1.8034 0.508)
			(layers "F.Cu" "F.Mask" "F.Paste")
			(net "GND")
		)
		(pad "168" smd rect
			(at 4.59994 19.550126 90)
			(size 1.8034 0.508)
			(layers "F.Cu" "F.Mask" "F.Paste")
			(net "M_D_DQ<10>")
		)
		(pad "169" smd rect
			(at 4.59994 20.40001 90)
			(size 1.8034 0.508)
			(layers "F.Cu" "F.Mask" "F.Paste")
			(net "GND")
		)
		(pad "170" smd rect
			(at 4.59994 21.249894 90)
			(size 1.8034 0.508)
			(layers "F.Cu" "F.Mask" "F.Paste")
			(net "M_D_DQ<20>")
		)
		(pad "171" smd rect
			(at 4.59994 22.100032 90)
			(size 1.8034 0.508)
			(layers "F.Cu" "F.Mask" "F.Paste")
			(net "GND")
		)
		(pad "172" smd rect
			(at 4.59994 22.949916 90)
			(size 1.8034 0.508)
			(layers "F.Cu" "F.Mask" "F.Paste")
			(net "M_D_DQ<16>")
		)
		(pad "173" smd rect
			(at 4.59994 23.800054 90)
			(size 1.8034 0.508)
			(layers "F.Cu" "F.Mask" "F.Paste")
			(net "GND")
		)
		(pad "174" smd rect
			(at 4.59994 24.649938 90)
			(size 1.8034 0.508)
			(layers "F.Cu" "F.Mask" "F.Paste")
			(net "M_D_DQS_DN<2>")
		)
		(pad "175" smd rect
			(at 4.59994 25.500076 90)
			(size 1.8034 0.508)
			(layers "F.Cu" "F.Mask" "F.Paste")
			(net "M_D_DQS_DP<2>")
		)
		(pad "176" smd rect
			(at 4.59994 26.34996 90)
			(size 1.8034 0.508)
			(layers "F.Cu" "F.Mask" "F.Paste")
			(net "GND")
		)
		(pad "177" smd rect
			(at 4.59994 27.200098 90)
			(size 1.8034 0.508)
			(layers "F.Cu" "F.Mask" "F.Paste")
			(net "M_D_DQ<22>")
		)
		(pad "178" smd rect
			(at 4.59994 28.049982 90)
			(size 1.8034 0.508)
			(layers "F.Cu" "F.Mask" "F.Paste")
			(net "GND")
		)
		(pad "179" smd rect
			(at 4.59994 28.90012 90)
			(size 1.8034 0.508)
			(layers "F.Cu" "F.Mask" "F.Paste")
			(net "M_D_DQ<18>")
		)
		(pad "180" smd rect
			(at 4.59994 29.750004 90)
			(size 1.8034 0.508)
			(layers "F.Cu" "F.Mask" "F.Paste")
			(net "GND")
		)
		(pad "181" smd rect
			(at 4.59994 30.599888 90)
			(size 1.8034 0.508)
			(layers "F.Cu" "F.Mask" "F.Paste")
			(net "M_D_DQ<28>")
		)
		(pad "182" smd rect
			(at 4.59994 31.450026 90)
			(size 1.8034 0.508)
			(layers "F.Cu" "F.Mask" "F.Paste")
			(net "GND")
		)
		(pad "183" smd rect
			(at 4.59994 32.29991 90)
			(size 1.8034 0.508)
			(layers "F.Cu" "F.Mask" "F.Paste")
			(net "M_D_DQ<24>")
		)
		(pad "184" smd rect
			(at 4.59994 33.150048 90)
			(size 1.8034 0.508)
			(layers "F.Cu" "F.Mask" "F.Paste")
			(net "GND")
		)
		(pad "185" smd rect
			(at 4.59994 33.999932 90)
			(size 1.8034 0.508)
			(layers "F.Cu" "F.Mask" "F.Paste")
			(net "M_D_DQS_DN<3>")
		)
		(pad "186" smd rect
			(at 4.59994 34.85007 90)
			(size 1.8034 0.508)
			(layers "F.Cu" "F.Mask" "F.Paste")
			(net "M_D_DQS_DP<3>")
		)
		(pad "187" smd rect
			(at 4.59994 35.699954 90)
			(size 1.8034 0.508)
			(layers "F.Cu" "F.Mask" "F.Paste")
			(net "GND")
		)
		(pad "188" smd rect
			(at 4.59994 36.550092 90)
			(size 1.8034 0.508)
			(layers "F.Cu" "F.Mask" "F.Paste")
			(net "M_D_DQ<30>")
		)
		(pad "189" smd rect
			(at 4.59994 37.399976 90)
			(size 1.8034 0.508)
			(layers "F.Cu" "F.Mask" "F.Paste")
			(net "GND")
		)
		(pad "190" smd rect
			(at 4.59994 38.250114 90)
			(size 1.8034 0.508)
			(layers "F.Cu" "F.Mask" "F.Paste")
			(net "M_D_DQ<26>")
		)
		(pad "191" smd rect
			(at 4.59994 39.099998 90)
			(size 1.8034 0.508)
			(layers "F.Cu" "F.Mask" "F.Paste")
			(net "GND")
		)
		(pad "192" smd rect
			(at 4.59994 39.949882 90)
			(size 1.8034 0.508)
			(layers "F.Cu" "F.Mask" "F.Paste")
			(net "M_D_ECC<4>")
		)
		(pad "193" smd rect
			(at 4.59994 40.80002 90)
			(size 1.8034 0.508)
			(layers "F.Cu" "F.Mask" "F.Paste")
			(net "GND")
		)
		(pad "194" smd rect
			(at 4.59994 41.649904 90)
			(size 1.8034 0.508)
			(layers "F.Cu" "F.Mask" "F.Paste")
			(net "M_D_ECC<0>")
		)
		(pad "195" smd rect
			(at 4.59994 42.500042 90)
			(size 1.8034 0.508)
			(layers "F.Cu" "F.Mask" "F.Paste")
			(net "GND")
		)
		(pad "196" smd rect
			(at 4.59994 43.349926 90)
			(size 1.8034 0.508)
			(layers "F.Cu" "F.Mask" "F.Paste")
			(net "M_D_DQS_DN<8>")
		)
		(pad "197" smd rect
			(at 4.59994 44.200064 90)
			(size 1.8034 0.508)
			(layers "F.Cu" "F.Mask" "F.Paste")
			(net "M_D_DQS_DP<8>")
		)
		(pad "198" smd rect
			(at 4.59994 45.049948 90)
			(size 1.8034 0.508)
			(layers "F.Cu" "F.Mask" "F.Paste")
			(net "GND")
		)
		(pad "199" smd rect
			(at 4.59994 45.900086 90)
			(size 1.8034 0.508)
			(layers "F.Cu" "F.Mask" "F.Paste")
			(net "M_D_ECC<6>")
		)
		(pad "200" smd rect
			(at 4.59994 46.74997 90)
			(size 1.8034 0.508)
			(layers "F.Cu" "F.Mask" "F.Paste")
			(net "GND")
		)
		(pad "201" smd rect
			(at 4.59994 47.600108 90)
			(size 1.8034 0.508)
			(layers "F.Cu" "F.Mask" "F.Paste")
			(net "M_D_ECC<2>")
		)
		(pad "202" smd rect
			(at 4.59994 48.449992 90)
			(size 1.8034 0.508)
			(layers "F.Cu" "F.Mask" "F.Paste")
			(net "GND")
		)
		(pad "203" smd rect
			(at 4.59994 49.299876 90)
			(size 1.8034 0.508)
			(layers "F.Cu" "F.Mask" "F.Paste")
			(net "M_D_CKE<1>")
		)
		(pad "204" smd rect
			(at 4.59994 50.150014 90)
			(size 1.8034 0.508)
			(layers "F.Cu" "F.Mask" "F.Paste")
			(net "PVDDQ_DEF")
		)
		(pad "205" smd rect
			(at 4.59994 50.999898 90)
			(size 1.8034 0.508)
			(layers "F.Cu" "F.Mask" "F.Paste")
			(net "TP_CH_D_DIMM_D0_RFU_0")
		)
		(pad "206" smd rect
			(at 4.59994 51.850036 90)
			(size 1.8034 0.508)
			(layers "F.Cu" "F.Mask" "F.Paste")
			(net "PVDDQ_DEF")
		)
		(pad "207" smd rect
			(at 4.59994 52.69992 90)
			(size 1.8034 0.508)
			(layers "F.Cu" "F.Mask" "F.Paste")
			(net "M_D_BG<1>")
		)
		(pad "208" smd rect
			(at 4.59994 53.550058 90)
			(size 1.8034 0.508)
			(layers "F.Cu" "F.Mask" "F.Paste")
			(net "M_D_ALERT_N")
		)
		(pad "209" smd rect
			(at 4.59994 54.399942 90)
			(size 1.8034 0.508)
			(layers "F.Cu" "F.Mask" "F.Paste")
			(net "PVDDQ_DEF")
		)
		(pad "210" smd rect
			(at 4.59994 55.25008 90)
			(size 1.8034 0.508)
			(layers "F.Cu" "F.Mask" "F.Paste")
			(net "M_D_MA<11>")
		)
		(pad "211" smd rect
			(at 4.59994 56.099964 90)
			(size 1.8034 0.508)
			(layers "F.Cu" "F.Mask" "F.Paste")
			(net "M_D_MA<7>")
		)
		(pad "212" smd rect
			(at 4.59994 56.950102 90)
			(size 1.8034 0.508)
			(layers "F.Cu" "F.Mask" "F.Paste")
			(net "PVDDQ_DEF")
		)
		(pad "213" smd rect
			(at 4.59994 57.799986 90)
			(size 1.8034 0.508)
			(layers "F.Cu" "F.Mask" "F.Paste")
			(net "M_D_MA<5>")
		)
		(pad "214" smd rect
			(at 4.59994 58.650124 90)
			(size 1.8034 0.508)
			(layers "F.Cu" "F.Mask" "F.Paste")
			(net "M_D_MA<4>")
		)
		(pad "215" smd rect
			(at 4.59994 59.500008 90)
			(size 1.8034 0.508)
			(layers "F.Cu" "F.Mask" "F.Paste")
			(net "PVDDQ_DEF")
		)
		(pad "216" smd rect
			(at 4.59994 60.349892 90)
			(size 1.8034 0.508)
			(layers "F.Cu" "F.Mask" "F.Paste")
			(net "M_D_MA<2>")
		)
		(pad "217" smd rect
			(at 4.59994 61.20003 90)
			(size 1.8034 0.508)
			(layers "F.Cu" "F.Mask" "F.Paste")
			(net "PVDDQ_DEF")
		)
		(pad "218" smd rect
			(at 4.59994 62.049914 90)
			(size 1.8034 0.508)
			(layers "F.Cu" "F.Mask" "F.Paste")
			(net "M_D_CLK_DP<1>")
		)
		(pad "219" smd rect
			(at 4.59994 62.900052 90)
			(size 1.8034 0.508)
			(layers "F.Cu" "F.Mask" "F.Paste")
			(net "M_D_CLK_DN<1>")
		)
		(pad "220" smd rect
			(at 4.59994 63.749936 90)
			(size 1.8034 0.508)
			(layers "F.Cu" "F.Mask" "F.Paste")
			(net "PVDDQ_DEF")
		)
		(pad "221" smd rect
			(at 4.59994 64.600074 90)
			(size 1.8034 0.508)
			(layers "F.Cu" "F.Mask" "F.Paste")
			(net "PVTT_DEF")
		)
		(pad "222" smd rect
			(at 4.59994 70.550024 90)
			(size 1.8034 0.508)
			(layers "F.Cu" "F.Mask" "F.Paste")
			(net "M_D_PAR")
		)
		(pad "223" smd rect
			(at 4.59994 71.399908 90)
			(size 1.8034 0.508)
			(layers "F.Cu" "F.Mask" "F.Paste")
			(net "PVDDQ_DEF")
		)
		(pad "224" smd rect
			(at 4.59994 72.250046 90)
			(size 1.8034 0.508)
			(layers "F.Cu" "F.Mask" "F.Paste")
			(net "M_D_BA<1>")
		)
		(pad "225" smd rect
			(at 4.59994 73.09993 90)
			(size 1.8034 0.508)
			(layers "F.Cu" "F.Mask" "F.Paste")
			(net "M_D_MA<10>")
		)
		(pad "226" smd rect
			(at 4.59994 73.950068 90)
			(size 1.8034 0.508)
			(layers "F.Cu" "F.Mask" "F.Paste")
			(net "PVDDQ_DEF")
		)
		(pad "227" smd rect
			(at 4.59994 74.799952 90)
			(size 1.8034 0.508)
			(layers "F.Cu" "F.Mask" "F.Paste")
			(net "TP_CH_D_DIMM_D0_RFU_1")
		)
		(pad "228" smd rect
			(at 4.59994 75.65009 90)
			(size 1.8034 0.508)
			(layers "F.Cu" "F.Mask" "F.Paste")
			(net "M_D_MA<14>")
		)
		(pad "229" smd rect
			(at 4.59994 76.499974 90)
			(size 1.8034 0.508)
			(layers "F.Cu" "F.Mask" "F.Paste")
			(net "PVDDQ_DEF")
		)
		(pad "230" smd rect
			(at 4.59994 77.350112 90)
			(size 1.8034 0.508)
			(layers "F.Cu" "F.Mask" "F.Paste")
			(net "FM_ADR_COMPLETE_DEF_N")
		)
		(pad "231" smd rect
			(at 4.59994 78.199996 90)
			(size 1.8034 0.508)
			(layers "F.Cu" "F.Mask" "F.Paste")
			(net "PVDDQ_DEF")
		)
		(pad "232" smd rect
			(at 4.59994 79.04988 90)
			(size 1.8034 0.508)
			(layers "F.Cu" "F.Mask" "F.Paste")
			(net "M_D_MA<13>")
		)
		(pad "233" smd rect
			(at 4.59994 79.900018 90)
			(size 1.8034 0.508)
			(layers "F.Cu" "F.Mask" "F.Paste")
			(net "PVDDQ_DEF")
		)
		(pad "234" smd rect
			(at 4.59994 80.749902 90)
			(size 1.8034 0.508)
			(layers "F.Cu" "F.Mask" "F.Paste")
			(net "M_D_MA<17>")
		)
		(pad "235" smd rect
			(at 4.59994 81.60004 90)
			(size 1.8034 0.508)
			(layers "F.Cu" "F.Mask" "F.Paste")
			(net "M_D_C<2>")
		)
		(pad "236" smd rect
			(at 4.59994 82.449924 90)
			(size 1.8034 0.508)
			(layers "F.Cu" "F.Mask" "F.Paste")
			(net "PVDDQ_DEF")
		)
		(pad "237" smd rect
			(at 4.59994 83.300062 90)
			(size 1.8034 0.508)
			(layers "F.Cu" "F.Mask" "F.Paste")
			(net "M_D_CS_N<3>")
		)
		(pad "238" smd rect
			(at 4.59994 84.149946 90)
			(size 1.8034 0.508)
			(layers "F.Cu" "F.Mask" "F.Paste")
			(net "GND")
		)
		(pad "239" smd rect
			(at 4.59994 85.000084 90)
			(size 1.8034 0.508)
			(layers "F.Cu" "F.Mask" "F.Paste")
			(net "GND")
		)
		(pad "240" smd rect
			(at 4.59994 85.849968 90)
			(size 1.8034 0.508)
			(layers "F.Cu" "F.Mask" "F.Paste")
			(net "M_D_DQ<36>")
		)
		(pad "241" smd rect
			(at 4.59994 86.700106 90)
			(size 1.8034 0.508)
			(layers "F.Cu" "F.Mask" "F.Paste")
			(net "GND")
		)
		(pad "242" smd rect
			(at 4.59994 87.54999 90)
			(size 1.8034 0.508)
			(layers "F.Cu" "F.Mask" "F.Paste")
			(net "M_D_DQ<32>")
		)
		(pad "243" smd rect
			(at 4.59994 88.399874 90)
			(size 1.8034 0.508)
			(layers "F.Cu" "F.Mask" "F.Paste")
			(net "GND")
		)
		(pad "244" smd rect
			(at 4.59994 89.250012 90)
			(size 1.8034 0.508)
			(layers "F.Cu" "F.Mask" "F.Paste")
			(net "M_D_DQS_DN<4>")
		)
		(pad "245" smd rect
			(at 4.59994 90.099896 90)
			(size 1.8034 0.508)
			(layers "F.Cu" "F.Mask" "F.Paste")
			(net "M_D_DQS_DP<4>")
		)
		(pad "246" smd rect
			(at 4.59994 90.950034 90)
			(size 1.8034 0.508)
			(layers "F.Cu" "F.Mask" "F.Paste")
			(net "GND")
		)
		(pad "247" smd rect
			(at 4.59994 91.799918 90)
			(size 1.8034 0.508)
			(layers "F.Cu" "F.Mask" "F.Paste")
			(net "M_D_DQ<38>")
		)
		(pad "248" smd rect
			(at 4.59994 92.650056 90)
			(size 1.8034 0.508)
			(layers "F.Cu" "F.Mask" "F.Paste")
			(net "GND")
		)
		(pad "249" smd rect
			(at 4.59994 93.49994 90)
			(size 1.8034 0.508)
			(layers "F.Cu" "F.Mask" "F.Paste")
			(net "M_D_DQ<34>")
		)
		(pad "250" smd rect
			(at 4.59994 94.350078 90)
			(size 1.8034 0.508)
			(layers "F.Cu" "F.Mask" "F.Paste")
			(net "GND")
		)
		(pad "251" smd rect
			(at 4.59994 95.199962 90)
			(size 1.8034 0.508)
			(layers "F.Cu" "F.Mask" "F.Paste")
			(net "M_D_DQ<44>")
		)
		(pad "252" smd rect
			(at 4.59994 96.0501 90)
			(size 1.8034 0.508)
			(layers "F.Cu" "F.Mask" "F.Paste")
			(net "GND")
		)
		(pad "253" smd rect
			(at 4.59994 96.899984 90)
			(size 1.8034 0.508)
			(layers "F.Cu" "F.Mask" "F.Paste")
			(net "M_D_DQ<40>")
		)
		(pad "254" smd rect
			(at 4.59994 97.750122 90)
			(size 1.8034 0.508)
			(layers "F.Cu" "F.Mask" "F.Paste")
			(net "GND")
		)
		(pad "255" smd rect
			(at 4.59994 98.600006 90)
			(size 1.8034 0.508)
			(layers "F.Cu" "F.Mask" "F.Paste")
			(net "M_D_DQS_DN<5>")
		)
		(pad "256" smd rect
			(at 4.59994 99.44989 90)
			(size 1.8034 0.508)
			(layers "F.Cu" "F.Mask" "F.Paste")
			(net "M_D_DQS_DP<5>")
		)
		(pad "257" smd rect
			(at 4.59994 100.300028 90)
			(size 1.8034 0.508)
			(layers "F.Cu" "F.Mask" "F.Paste")
			(net "GND")
		)
		(pad "258" smd rect
			(at 4.59994 101.149912 90)
			(size 1.8034 0.508)
			(layers "F.Cu" "F.Mask" "F.Paste")
			(net "M_D_DQ<46>")
		)
		(pad "259" smd rect
			(at 4.59994 102.00005 90)
			(size 1.8034 0.508)
			(layers "F.Cu" "F.Mask" "F.Paste")
			(net "GND")
		)
		(pad "260" smd rect
			(at 4.59994 102.849934 90)
			(size 1.8034 0.508)
			(layers "F.Cu" "F.Mask" "F.Paste")
			(net "M_D_DQ<42>")
		)
		(pad "261" smd rect
			(at 4.59994 103.700072 90)
			(size 1.8034 0.508)
			(layers "F.Cu" "F.Mask" "F.Paste")
			(net "GND")
		)
		(pad "262" smd rect
			(at 4.59994 104.549956 90)
			(size 1.8034 0.508)
			(layers "F.Cu" "F.Mask" "F.Paste")
			(net "M_D_DQ<52>")
		)
		(pad "263" smd rect
			(at 4.59994 105.400094 90)
			(size 1.8034 0.508)
			(layers "F.Cu" "F.Mask" "F.Paste")
			(net "GND")
		)
		(pad "264" smd rect
			(at 4.59994 106.249978 90)
			(size 1.8034 0.508)
			(layers "F.Cu" "F.Mask" "F.Paste")
			(net "M_D_DQ<48>")
		)
		(pad "265" smd rect
			(at 4.59994 107.100116 90)
			(size 1.8034 0.508)
			(layers "F.Cu" "F.Mask" "F.Paste")
			(net "GND")
		)
		(pad "266" smd rect
			(at 4.59994 107.95 90)
			(size 1.8034 0.508)
			(layers "F.Cu" "F.Mask" "F.Paste")
			(net "M_D_DQS_DN<6>")
		)
		(pad "267" smd rect
			(at 4.59994 108.799884 90)
			(size 1.8034 0.508)
			(layers "F.Cu" "F.Mask" "F.Paste")
			(net "M_D_DQS_DP<6>")
		)
		(pad "268" smd rect
			(at 4.59994 109.650022 90)
			(size 1.8034 0.508)
			(layers "F.Cu" "F.Mask" "F.Paste")
			(net "GND")
		)
		(pad "269" smd rect
			(at 4.59994 110.499906 90)
			(size 1.8034 0.508)
			(layers "F.Cu" "F.Mask" "F.Paste")
			(net "M_D_DQ<54>")
		)
		(pad "270" smd rect
			(at 4.59994 111.350044 90)
			(size 1.8034 0.508)
			(layers "F.Cu" "F.Mask" "F.Paste")
			(net "GND")
		)
		(pad "271" smd rect
			(at 4.59994 112.199928 90)
			(size 1.8034 0.508)
			(layers "F.Cu" "F.Mask" "F.Paste")
			(net "M_D_DQ<50>")
		)
		(pad "272" smd rect
			(at 4.59994 113.050066 90)
			(size 1.8034 0.508)
			(layers "F.Cu" "F.Mask" "F.Paste")
			(net "GND")
		)
		(pad "273" smd rect
			(at 4.59994 113.89995 90)
			(size 1.8034 0.508)
			(layers "F.Cu" "F.Mask" "F.Paste")
			(net "M_D_DQ<60>")
		)
		(pad "274" smd rect
			(at 4.59994 114.750088 90)
			(size 1.8034 0.508)
			(layers "F.Cu" "F.Mask" "F.Paste")
			(net "GND")
		)
		(pad "275" smd rect
			(at 4.59994 115.599972 90)
			(size 1.8034 0.508)
			(layers "F.Cu" "F.Mask" "F.Paste")
			(net "M_D_DQ<56>")
		)
		(pad "276" smd rect
			(at 4.59994 116.45011 90)
			(size 1.8034 0.508)
			(layers "F.Cu" "F.Mask" "F.Paste")
			(net "GND")
		)
		(pad "277" smd rect
			(at 4.59994 117.299994 90)
			(size 1.8034 0.508)
			(layers "F.Cu" "F.Mask" "F.Paste")
			(net "M_D_DQS_DN<7>")
		)
		(pad "278" smd rect
			(at 4.59994 118.149878 90)
			(size 1.8034 0.508)
			(layers "F.Cu" "F.Mask" "F.Paste")
			(net "M_D_DQS_DP<7>")
		)
		(pad "279" smd rect
			(at 4.59994 119.000016 90)
			(size 1.8034 0.508)
			(layers "F.Cu" "F.Mask" "F.Paste")
			(net "GND")
		)
		(pad "280" smd rect
			(at 4.59994 119.8499 90)
			(size 1.8034 0.508)
			(layers "F.Cu" "F.Mask" "F.Paste")
			(net "M_D_DQ<62>")
		)
		(pad "281" smd rect
			(at 4.59994 120.700038 90)
			(size 1.8034 0.508)
			(layers "F.Cu" "F.Mask" "F.Paste")
			(net "GND")
		)
		(pad "282" smd rect
			(at 4.59994 121.549922 90)
			(size 1.8034 0.508)
			(layers "F.Cu" "F.Mask" "F.Paste")
			(net "M_D_DQ<58>")
		)
		(pad "283" smd rect
			(at 4.59994 122.40006 90)
			(size 1.8034 0.508)
			(layers "F.Cu" "F.Mask" "F.Paste")
			(net "GND")
		)
		(pad "284" smd rect
			(at 4.59994 123.249944 90)
			(size 1.8034 0.508)
			(layers "F.Cu" "F.Mask" "F.Paste")
			(net "PVPP_DEF")
		)
		(pad "285" smd rect
			(at 4.59994 124.100082 90)
			(size 1.8034 0.508)
			(layers "F.Cu" "F.Mask" "F.Paste")
			(net "SMB_DDR_DEF_VPP_SDA")
		)
		(pad "286" smd rect
			(at 4.59994 124.949966 90)
			(size 1.8034 0.508)
			(layers "F.Cu" "F.Mask" "F.Paste")
			(net "PVPP_DEF")
		)
		(pad "287" smd rect
			(at 4.59994 125.800104 90)
			(size 1.8034 0.508)
			(layers "F.Cu" "F.Mask" "F.Paste")
			(net "PVPP_DEF")
		)
		(pad "288" smd rect
			(at 4.59994 126.649988 90)
			(size 1.8034 0.508)
			(layers "F.Cu" "F.Mask" "F.Paste")
			(net "PVPP_DEF")
		)
	)
	(footprint ""
		(layer "F.Cu")
		(at 429.847248 -48.813466)
		(property "Reference" "Y9F2"
			(at 4.41071 2.95656 90)
			(unlocked yes)
			(layer "F.SilkS")
			(effects
				(font
					(size 0.7874 0.5842)
					(thickness 0.1524)
				)
				(justify left)
			)
		)
		(property "Value" ""
			(at 0 0 0)
			(layer "F.Fab")
			(effects
				(font
					(size 1.27 1.27)
				)
			)
		)
		(duplicate_pad_numbers_are_jumpers no)
		(fp_circle
			(center -1.088644 0.020066)
			(end -0.961644 0.020066)
			(stroke
				(width 0.254)
				(type default)
			)
			(fill no)
			(layer "F.SilkS")
		)
		(fp_rect
			(start -0.500126 2.750058)
			(end 2.100072 -0.54991)
			(stroke
				(width 0)
				(type default)
			)
			(fill no)
			(layer "F.CrtYd")
		)
		(fp_line
			(start -0.500126 -0.54991)
			(end 2.100072 -0.54991)
			(stroke
				(width 0.1)
				(type default)
			)
			(layer "F.Fab")
		)
		(fp_line
			(start -0.500126 2.750058)
			(end -0.500126 -0.54991)
			(stroke
				(width 0.1)
				(type default)
			)
			(layer "F.Fab")
		)
		(fp_line
			(start 2.100072 -0.54991)
			(end 2.100072 2.750058)
			(stroke
				(width 0.1)
				(type default)
			)
			(layer "F.Fab")
		)
		(fp_line
			(start 2.100072 2.750058)
			(end -0.500126 2.750058)
			(stroke
				(width 0.1)
				(type default)
			)
			(layer "F.Fab")
		)
		(fp_circle
			(center -1.218946 -0.125984)
			(end -1.091946 -0.125984)
			(stroke
				(width 0.254)
				(type default)
			)
			(fill no)
			(layer "F.Fab")
		)
		(pad "1" smd rect
			(at 0 0)
			(size 1.1938 1.397)
			(layers "F.Cu" "F.Mask" "F.Paste")
			(net "PU_24M_OSC_OE")
		)
		(pad "2" smd rect
			(at 0 2.199894)
			(size 1.1938 1.397)
			(layers "F.Cu" "F.Mask" "F.Paste")
			(net "GND")
		)
		(pad "3" smd rect
			(at 1.599946 2.199894)
			(size 1.1938 1.397)
			(layers "F.Cu" "F.Mask" "F.Paste")
			(net "CLK_24M_BMC_CLKIN_R")
		)
		(pad "4" smd rect
			(at 1.599946 0)
			(size 1.1938 1.397)
			(layers "F.Cu" "F.Mask" "F.Paste")
			(net "P3V3_STBY")
		)
	)
	(footprint ""
		(layer "F.Cu")
		(at 162.7886 -72.644 90)
		(property "Reference" "C3D22"
			(at 0 0 90)
			(layer "F.SilkS")
			(hide yes)
			(effects
				(font
					(size 1.27 1.27)
				)
			)
		)
		(property "Value" ""
			(at 0 0 90)
			(layer "F.Fab")
			(effects
				(font
					(size 1.27 1.27)
				)
			)
		)
		(duplicate_pad_numbers_are_jumpers no)
		(fp_poly
			(pts
				(xy -0.7239 -0.2159) (xy 0.7239 -0.2159) (xy 0.7239 1.9939) (xy -0.7239 1.9939)
			)
			(stroke
				(width 0)
				(type default)
			)
			(fill no)
			(layer "F.CrtYd")
		)
		(fp_line
			(start 0.7239 -0.2159)
			(end -0.7239 -0.2159)
			(stroke
				(width 0.1)
				(type default)
			)
			(layer "F.Fab")
		)
		(fp_line
			(start -0.7239 -0.2159)
			(end -0.7239 1.9939)
			(stroke
				(width 0.1)
				(type default)
			)
			(layer "F.Fab")
		)
		(fp_line
			(start 0.7239 1.9939)
			(end 0.7239 -0.2159)
			(stroke
				(width 0.1)
				(type default)
			)
			(layer "F.Fab")
		)
		(fp_line
			(start -0.7239 1.9939)
			(end 0.7239 1.9939)
			(stroke
				(width 0.1)
				(type default)
			)
			(layer "F.Fab")
		)
		(pad "1" smd rect
			(at 0 0 90)
			(size 1.27 1.016)
			(layers "F.Cu" "F.Mask" "F.Paste")
			(net "P3V3_DB1200")
		)
		(pad "2" smd rect
			(at 0 1.778 90)
			(size 1.27 1.016)
			(layers "F.Cu" "F.Mask" "F.Paste")
			(net "GND")
		)
		(zone
			(layer "F.Cu")
			(hatch none 0.5)
			(connect_pads
				(clearance 0)
			)
			(min_thickness 0.25)
			(keepout
				(tracks not_allowed)
				(vias allowed)
				(pads allowed)
				(copperpour not_allowed)
				(footprints allowed)
			)
			(placement
				(enabled no)
				(sheetname "")
			)
			(fill
				(thermal_gap 0.5)
				(thermal_bridge_width 0.5)
				(island_removal_mode 0)
			)
			(polygon
				(pts
					(xy 163.2966 -72.009) (xy 163.2966 -73.279) (xy 164.0586 -73.279) (xy 164.0586 -72.009)
				)
			)
		)
	)
	(footprint ""
		(layer "F.Cu")
		(at 391.16 -64.5795)
		(property "Reference" "R7E16"
			(at 0 0 0)
			(layer "F.SilkS")
			(hide yes)
			(effects
				(font
					(size 1.27 1.27)
				)
			)
		)
		(property "Value" ""
			(at 0 0 0)
			(layer "F.Fab")
			(effects
				(font
					(size 1.27 1.27)
				)
			)
		)
		(duplicate_pad_numbers_are_jumpers no)
		(fp_poly
			(pts
				(xy -0.2794 -0.1016) (xy 0.2794 -0.1016) (xy 0.2794 0.9906) (xy -0.2794 0.9906)
			)
			(stroke
				(width 0)
				(type default)
			)
			(fill no)
			(layer "F.CrtYd")
		)
		(fp_line
			(start -0.2794 -0.1016)
			(end -0.2794 0.9906)
			(stroke
				(width 0.1)
				(type default)
			)
			(layer "F.Fab")
		)
		(fp_line
			(start -0.2794 0.9906)
			(end 0.2794 0.9906)
			(stroke
				(width 0.1)
				(type default)
			)
			(layer "F.Fab")
		)
		(fp_line
			(start 0.2794 -0.1016)
			(end -0.2794 -0.1016)
			(stroke
				(width 0.1)
				(type default)
			)
			(layer "F.Fab")
		)
		(fp_line
			(start 0.2794 0.9906)
			(end 0.2794 -0.1016)
			(stroke
				(width 0.1)
				(type default)
			)
			(layer "F.Fab")
		)
		(pad "1" smd rect
			(at 0 0)
			(size 0.508 0.508)
			(layers "F.Cu" "F.Mask" "F.Paste")
			(net "VR_P5V_STBY_VSENSE")
		)
		(pad "2" smd rect
			(at 0 0.889)
			(size 0.508 0.508)
			(layers "F.Cu" "F.Mask" "F.Paste")
			(net "AGND_P5V_STBY")
		)
		(zone
			(layer "F.Cu")
			(hatch none 0.5)
			(connect_pads
				(clearance 0)
			)
			(min_thickness 0.25)
			(keepout
				(tracks allowed)
				(vias not_allowed)
				(pads allowed)
				(copperpour not_allowed)
				(footprints allowed)
			)
			(placement
				(enabled no)
				(sheetname "")
			)
			(fill
				(thermal_gap 0.5)
				(thermal_bridge_width 0.5)
				(island_removal_mode 0)
			)
			(polygon
				(pts
					(xy 390.906 -64.3255) (xy 391.414 -64.3255) (xy 391.414 -63.9445) (xy 390.906 -63.9445)
				)
			)
		)
		(zone
			(layer "F.Cu")
			(hatch none 0.5)
			(connect_pads
				(clearance 0)
			)
			(min_thickness 0.25)
			(keepout
				(tracks not_allowed)
				(vias allowed)
				(pads allowed)
				(copperpour not_allowed)
				(footprints allowed)
			)
			(placement
				(enabled no)
				(sheetname "")
			)
			(fill
				(thermal_gap 0.5)
				(thermal_bridge_width 0.5)
				(island_removal_mode 0)
			)
			(polygon
				(pts
					(xy 390.906 -63.9445) (xy 391.414 -63.9445) (xy 391.414 -64.3255) (xy 390.906 -64.3255)
				)
			)
		)
	)
	(footprint ""
		(layer "F.Cu")
		(at 191.897 -3.7465)
		(property "Reference" "C4G17"
			(at 0 0 0)
			(layer "F.SilkS")
			(hide yes)
			(effects
				(font
					(size 1.27 1.27)
				)
			)
		)
		(property "Value" ""
			(at 0 0 0)
			(layer "F.Fab")
			(effects
				(font
					(size 1.27 1.27)
				)
			)
		)
		(duplicate_pad_numbers_are_jumpers no)
		(fp_poly
			(pts
				(xy 0.3048 -0.1016) (xy 0.3048 0.9906) (xy -0.3048 0.9906) (xy -0.3048 -0.1016)
			)
			(stroke
				(width 0)
				(type default)
			)
			(fill no)
			(layer "F.CrtYd")
		)
		(fp_line
			(start -0.3048 -0.1016)
			(end -0.3048 0.9906)
			(stroke
				(width 0.1)
				(type default)
			)
			(layer "F.Fab")
		)
		(fp_line
			(start -0.3048 0.9906)
			(end 0.3048 0.9906)
			(stroke
				(width 0.1)
				(type default)
			)
			(layer "F.Fab")
		)
		(fp_line
			(start 0.3048 -0.1016)
			(end -0.3048 -0.1016)
			(stroke
				(width 0.1)
				(type default)
			)
			(layer "F.Fab")
		)
		(fp_line
			(start 0.3048 0.9906)
			(end 0.3048 -0.1016)
			(stroke
				(width 0.1)
				(type default)
			)
			(layer "F.Fab")
		)
		(pad "1" smd rect
			(at 0 0)
			(size 0.508 0.508)
			(layers "F.Cu" "F.Mask" "F.Paste")
			(net "M_C_CPU_VREF")
		)
		(pad "2" smd rect
			(at 0 0.889)
			(size 0.508 0.508)
			(layers "F.Cu" "F.Mask" "F.Paste")
			(net "GND")
		)
		(zone
			(layer "F.Cu")
			(hatch none 0.5)
			(connect_pads
				(clearance 0)
			)
			(min_thickness 0.25)
			(keepout
				(tracks allowed)
				(vias not_allowed)
				(pads allowed)
				(copperpour not_allowed)
				(footprints allowed)
			)
			(placement
				(enabled no)
				(sheetname "")
			)
			(fill
				(thermal_gap 0.5)
				(thermal_bridge_width 0.5)
				(island_removal_mode 0)
			)
			(polygon
				(pts
					(xy 191.643 -3.4925) (xy 192.151 -3.4925) (xy 192.151 -3.1115) (xy 191.643 -3.1115)
				)
			)
		)
		(zone
			(layer "F.Cu")
			(hatch none 0.5)
			(connect_pads
				(clearance 0)
			)
			(min_thickness 0.25)
			(keepout
				(tracks not_allowed)
				(vias allowed)
				(pads allowed)
				(copperpour not_allowed)
				(footprints allowed)
			)
			(placement
				(enabled no)
				(sheetname "")
			)
			(fill
				(thermal_gap 0.5)
				(thermal_bridge_width 0.5)
				(island_removal_mode 0)
			)
			(polygon
				(pts
					(xy 191.643 -3.1115) (xy 192.151 -3.1115) (xy 192.151 -3.4925) (xy 191.643 -3.4925)
				)
			)
		)
	)
	(footprint ""
		(layer "F.Cu")
		(at 440.055 -140.716 90)
		(property "Reference" "R25W177"
			(at -0.8382 -0.67818 90)
			(unlocked yes)
			(layer "F.SilkS")
			(effects
				(font
					(size 0.4064 0.254)
					(thickness 0.1524)
				)
				(justify left)
			)
		)
		(property "Value" ""
			(at 0 0 90)
			(layer "F.Fab")
			(effects
				(font
					(size 1.27 1.27)
				)
			)
		)
		(duplicate_pad_numbers_are_jumpers no)
		(fp_poly
			(pts
				(xy -0.2794 -0.1016) (xy 0.2794 -0.1016) (xy 0.2794 0.9906) (xy -0.2794 0.9906)
			)
			(stroke
				(width 0)
				(type default)
			)
			(fill no)
			(layer "F.CrtYd")
		)
		(fp_line
			(start 0.2794 -0.1016)
			(end -0.2794 -0.1016)
			(stroke
				(width 0.1)
				(type default)
			)
			(layer "F.Fab")
		)
		(fp_line
			(start -0.2794 -0.1016)
			(end -0.2794 0.9906)
			(stroke
				(width 0.1)
				(type default)
			)
			(layer "F.Fab")
		)
		(fp_line
			(start 0.2794 0.9906)
			(end 0.2794 -0.1016)
			(stroke
				(width 0.1)
				(type default)
			)
			(layer "F.Fab")
		)
		(fp_line
			(start -0.2794 0.9906)
			(end 0.2794 0.9906)
			(stroke
				(width 0.1)
				(type default)
			)
			(layer "F.Fab")
		)
		(pad "1" smd rect
			(at 0 0 90)
			(size 0.508 0.508)
			(layers "F.Cu" "F.Mask" "F.Paste")
			(net "P3V3_STBY")
		)
		(pad "2" smd rect
			(at 0 0.889 90)
			(size 0.508 0.508)
			(layers "F.Cu" "F.Mask" "F.Paste")
			(net "BMC_PREQ_BUF_N")
		)
		(zone
			(layer "F.Cu")
			(hatch none 0.5)
			(connect_pads
				(clearance 0)
			)
			(min_thickness 0.25)
			(keepout
				(tracks allowed)
				(vias not_allowed)
				(pads allowed)
				(copperpour not_allowed)
				(footprints allowed)
			)
			(placement
				(enabled no)
				(sheetname "")
			)
			(fill
				(thermal_gap 0.5)
				(thermal_bridge_width 0.5)
				(island_removal_mode 0)
			)
			(polygon
				(pts
					(xy 440.309 -140.462) (xy 440.309 -140.97) (xy 440.69 -140.97) (xy 440.69 -140.462)
				)
			)
		)
		(zone
			(layer "F.Cu")
			(hatch none 0.5)
			(connect_pads
				(clearance 0)
			)
			(min_thickness 0.25)
			(keepout
				(tracks not_allowed)
				(vias allowed)
				(pads allowed)
				(copperpour not_allowed)
				(footprints allowed)
			)
			(placement
				(enabled no)
				(sheetname "")
			)
			(fill
				(thermal_gap 0.5)
				(thermal_bridge_width 0.5)
				(island_removal_mode 0)
			)
			(polygon
				(pts
					(xy 440.69 -140.462) (xy 440.69 -140.97) (xy 440.309 -140.97) (xy 440.309 -140.462)
				)
			)
		)
	)
	(footprint ""
		(layer "F.Cu")
		(at 370.332 -136.4615 180)
		(property "Reference" "R7A14"
			(at 0 0 180)
			(layer "F.SilkS")
			(hide yes)
			(effects
				(font
					(size 1.27 1.27)
				)
			)
		)
		(property "Value" ""
			(at 0 0 180)
			(layer "F.Fab")
			(effects
				(font
					(size 1.27 1.27)
				)
			)
		)
		(duplicate_pad_numbers_are_jumpers no)
		(fp_poly
			(pts
				(xy -0.2794 -0.1016) (xy 0.2794 -0.1016) (xy 0.2794 0.9906) (xy -0.2794 0.9906)
			)
			(stroke
				(width 0)
				(type default)
			)
			(fill no)
			(layer "F.CrtYd")
		)
		(fp_line
			(start 0.2794 0.9906)
			(end 0.2794 -0.1016)
			(stroke
				(width 0.1)
				(type default)
			)
			(layer "F.Fab")
		)
		(fp_line
			(start 0.2794 -0.1016)
			(end -0.2794 -0.1016)
			(stroke
				(width 0.1)
				(type default)
			)
			(layer "F.Fab")
		)
		(fp_line
			(start -0.2794 0.9906)
			(end 0.2794 0.9906)
			(stroke
				(width 0.1)
				(type default)
			)
			(layer "F.Fab")
		)
		(fp_line
			(start -0.2794 -0.1016)
			(end -0.2794 0.9906)
			(stroke
				(width 0.1)
				(type default)
			)
			(layer "F.Fab")
		)
		(pad "1" smd rect
			(at 0 0 180)
			(size 0.508 0.508)
			(layers "F.Cu" "F.Mask" "F.Paste")
			(net "VSENSE_PVNN_PCH_STBY_FPK")
		)
		(pad "2" smd rect
			(at 0 0.889 180)
			(size 0.508 0.508)
			(layers "F.Cu" "F.Mask" "F.Paste")
			(net "VSENSE_PVNN_PCH_STBY_AVSP")
		)
		(zone
			(layer "F.Cu")
			(hatch none 0.5)
			(connect_pads
				(clearance 0)
			)
			(min_thickness 0.25)
			(keepout
				(tracks not_allowed)
				(vias allowed)
				(pads allowed)
				(copperpour not_allowed)
				(footprints allowed)
			)
			(placement
				(enabled no)
				(sheetname "")
			)
			(fill
				(thermal_gap 0.5)
				(thermal_bridge_width 0.5)
				(island_removal_mode 0)
			)
			(polygon
				(pts
					(xy 370.586 -137.0965) (xy 370.078 -137.0965) (xy 370.078 -136.7155) (xy 370.586 -136.7155)
				)
			)
		)
		(zone
			(layer "F.Cu")
			(hatch none 0.5)
			(connect_pads
				(clearance 0)
			)
			(min_thickness 0.25)
			(keepout
				(tracks allowed)
				(vias not_allowed)
				(pads allowed)
				(copperpour not_allowed)
				(footprints allowed)
			)
			(placement
				(enabled no)
				(sheetname "")
			)
			(fill
				(thermal_gap 0.5)
				(thermal_bridge_width 0.5)
				(island_removal_mode 0)
			)
			(polygon
				(pts
					(xy 370.586 -136.7155) (xy 370.078 -136.7155) (xy 370.078 -137.0965) (xy 370.586 -137.0965)
				)
			)
		)
	)
	(footprint ""
		(layer "F.Cu")
		(at 475.64802 -27.7495 90)
		(property "Reference" "EU8F2"
			(at 8.88365 7.29996 180)
			(unlocked yes)
			(layer "F.SilkS")
			(effects
				(font
					(size 0.7874 0.5842)
					(thickness 0.1524)
				)
			)
		)
		(property "Value" ""
			(at 0 0 90)
			(layer "F.Fab")
			(effects
				(font
					(size 1.27 1.27)
				)
			)
		)
		(duplicate_pad_numbers_are_jumpers no)
		(fp_line
			(start 7.0485 -1.6891)
			(end -0.8255 -1.6891)
			(stroke
				(width 0.1524)
				(type default)
			)
			(layer "F.SilkS")
		)
		(fp_line
			(start -0.8255 -1.6891)
			(end -0.8255 6.1976)
			(stroke
				(width 0.1524)
				(type default)
			)
			(layer "F.SilkS")
		)
		(fp_line
			(start 7.0485 6.1976)
			(end 7.0485 -1.6891)
			(stroke
				(width 0.1524)
				(type default)
			)
			(layer "F.SilkS")
		)
		(fp_line
			(start -0.8255 6.1976)
			(end 7.0485 6.1976)
			(stroke
				(width 0.1524)
				(type default)
			)
			(layer "F.SilkS")
		)
		(fp_circle
			(center -0.1143 -0.74422)
			(end -0.1143 -0.59182)
			(stroke
				(width 0.3048)
				(type default)
			)
			(fill no)
			(layer "F.SilkS")
		)
		(fp_poly
			(pts
				(xy -0.8255 -1.6891) (xy -0.8255 -0.6985) (xy 0.1651 -1.6891)
			)
			(stroke
				(width 0)
				(type default)
			)
			(fill yes)
			(layer "F.SilkS")
		)
		(fp_rect
			(start 1.0668 4.29768)
			(end 5.1562 0.20828)
			(stroke
				(width 0)
				(type default)
			)
			(fill yes)
			(layer "F.Paste")
		)
		(fp_poly
			(pts
				(xy 0.1143 5.25018) (xy 6.1087 5.25018) (xy 6.1087 -0.74422) (xy 0.8763 -0.74422) (xy 0.1143 0.01778)
			)
			(stroke
				(width 0)
				(type default)
			)
			(fill no)
			(layer "F.CrtYd")
		)
		(fp_line
			(start 6.1087 -0.74422)
			(end 6.1087 5.25018)
			(stroke
				(width 0.1)
				(type default)
			)
			(layer "F.Fab")
		)
		(fp_line
			(start 0.8763 -0.74422)
			(end 6.1087 -0.74422)
			(stroke
				(width 0.1)
				(type default)
			)
			(layer "F.Fab")
		)
		(fp_line
			(start 0.1143 0.01778)
			(end 0.8763 -0.74422)
			(stroke
				(width 0.1)
				(type default)
			)
			(layer "F.Fab")
		)
		(fp_line
			(start 6.1087 5.25018)
			(end 0.1143 5.25018)
			(stroke
				(width 0.1)
				(type default)
			)
			(layer "F.Fab")
		)
		(fp_line
			(start 0.1143 5.25018)
			(end 0.1143 0.01778)
			(stroke
				(width 0.1)
				(type default)
			)
			(layer "F.Fab")
		)
		(fp_circle
			(center -0.1143 -0.74422)
			(end -0.1143 -0.58928)
			(stroke
				(width 0.3048)
				(type default)
			)
			(fill no)
			(layer "F.Fab")
		)
		(pad "1" smd custom
			(at 0 0 90)
			(size 0.0762 0.0762)
			(layers "F.Cu" "F.Mask" "F.Paste")
			(net "GND")
			(options
				(clearance outline)
				(anchor circle)
			)
			(primitives
				(gr_poly
					(pts
						(xy -0.5715 -0.1524)
						(arc
							(start 0.4191 -0.1524)
							(mid 0.5715 0)
							(end 0.4191 0.1524)
						)
						(xy -0.5715 0.1524)
					)
					(width 0)
					(fill yes)
				)
			)
		)
		(pad "2" smd custom
			(at 0 0.50038 90)
			(size 0.0762 0.0762)
			(layers "F.Cu" "F.Mask" "F.Paste")
			(net "P3V3_STBY_MNG")
			(options
				(clearance outline)
				(anchor circle)
			)
			(primitives
				(gr_poly
					(pts
						(xy -0.5715 -0.1524)
						(arc
							(start 0.4191 -0.1524)
							(mid 0.5715 0)
							(end 0.4191 0.1524)
						)
						(xy -0.5715 0.1524)
					)
					(width 0)
					(fill yes)
				)
			)
		)
		(pad "3" smd custom
			(at 0 1.00076 90)
			(size 0.0762 0.0762)
			(layers "F.Cu" "F.Mask" "F.Paste")
			(net "TP_CLK_96M_CKMNG_P")
			(options
				(clearance outline)
				(anchor circle)
			)
			(primitives
				(gr_poly
					(pts
						(xy -0.5715 -0.1524)
						(arc
							(start 0.4191 -0.1524)
							(mid 0.5715 0)
							(end 0.4191 0.1524)
						)
						(xy -0.5715 0.1524)
					)
					(width 0)
					(fill yes)
				)
			)
		)
		(pad "4" smd custom
			(at 0 1.50114 90)
			(size 0.0762 0.0762)
			(layers "F.Cu" "F.Mask" "F.Paste")
			(net "TP_CLK_96M_CKMNG_N")
			(options
				(clearance outline)
				(anchor circle)
			)
			(primitives
				(gr_poly
					(pts
						(xy -0.5715 -0.1524)
						(arc
							(start 0.4191 -0.1524)
							(mid 0.5715 0)
							(end 0.4191 0.1524)
						)
						(xy -0.5715 0.1524)
					)
					(width 0)
					(fill yes)
				)
			)
		)
		(pad "5" smd custom
			(at 0 2.00152 90)
			(size 0.0762 0.0762)
			(layers "F.Cu" "F.Mask" "F.Paste")
			(net "PD_CKMNG_OE")
			(options
				(clearance outline)
				(anchor circle)
			)
			(primitives
				(gr_poly
					(pts
						(xy -0.5715 -0.1524)
						(arc
							(start 0.4191 -0.1524)
							(mid 0.5715 0)
							(end 0.4191 0.1524)
						)
						(xy -0.5715 0.1524)
					)
					(width 0)
					(fill yes)
				)
			)
		)
		(pad "6" smd custom
			(at 0 2.5019 90)
			(size 0.0762 0.0762)
			(layers "F.Cu" "F.Mask" "F.Paste")
			(net "PD_CKMNG_OE")
			(options
				(clearance outline)
				(anchor circle)
			)
			(primitives
				(gr_poly
					(pts
						(xy -0.5715 -0.1524)
						(arc
							(start 0.4191 -0.1524)
							(mid 0.5715 0)
							(end 0.4191 0.1524)
						)
						(xy -0.5715 0.1524)
					)
					(width 0)
					(fill yes)
				)
			)
		)
		(pad "7" smd custom
			(at 0 3.00228 90)
			(size 0.0762 0.0762)
			(layers "F.Cu" "F.Mask" "F.Paste")
			(net "TP_CLK_100M_R_DP")
			(options
				(clearance outline)
				(anchor circle)
			)
			(primitives
				(gr_poly
					(pts
						(xy -0.5715 -0.1524)
						(arc
							(start 0.4191 -0.1524)
							(mid 0.5715 0)
							(end 0.4191 0.1524)
						)
						(xy -0.5715 0.1524)
					)
					(width 0)
					(fill yes)
				)
			)
		)
		(pad "8" smd custom
			(at 0 3.50266 90)
			(size 0.0762 0.0762)
			(layers "F.Cu" "F.Mask" "F.Paste")
			(net "TP_CLK_100M_R_DN")
			(options
				(clearance outline)
				(anchor circle)
			)
			(primitives
				(gr_poly
					(pts
						(xy -0.5715 -0.1524)
						(arc
							(start 0.4191 -0.1524)
							(mid 0.5715 0)
							(end 0.4191 0.1524)
						)
						(xy -0.5715 0.1524)
					)
					(width 0)
					(fill yes)
				)
			)
		)
		(pad "9" smd custom
			(at 0 4.00304 90)
			(size 0.0762 0.0762)
			(layers "F.Cu" "F.Mask" "F.Paste")
			(net "P3V3_STBY_MNG_CPU")
			(options
				(clearance outline)
				(anchor circle)
			)
			(primitives
				(gr_poly
					(pts
						(xy -0.5715 -0.1524)
						(arc
							(start 0.4191 -0.1524)
							(mid 0.5715 0)
							(end 0.4191 0.1524)
						)
						(xy -0.5715 0.1524)
					)
					(width 0)
					(fill yes)
				)
			)
		)
		(pad "10" smd custom
			(at 0 4.50342 90)
			(size 0.0762 0.0762)
			(layers "F.Cu" "F.Mask" "F.Paste")
			(net "GND")
			(options
				(clearance outline)
				(anchor circle)
			)
			(primitives
				(gr_poly
					(pts
						(xy -0.5715 -0.1524)
						(arc
							(start 0.4191 -0.1524)
							(mid 0.5715 0)
							(end 0.4191 0.1524)
						)
						(xy -0.5715 0.1524)
					)
					(width 0)
					(fill yes)
				)
			)
		)
		(pad "11" smd custom
			(at 0.85852 5.36448 90)
			(size 0.0762 0.0762)
			(layers "F.Cu" "F.Mask" "F.Paste")
			(net "A_COMP_CKMNG")
			(options
				(clearance outline)
				(anchor circle)
			)
			(primitives
				(gr_poly
					(pts
						(xy -0.1524 0.5715)
						(arc
							(start -0.1524 -0.4191)
							(mid 0 -0.5715)
							(end 0.1524 -0.4191)
						)
						(xy 0.1524 0.5715)
					)
					(width 0)
					(fill yes)
				)
			)
		)
		(pad "12" smd custom
			(at 1.3589 5.36448 90)
			(size 0.0762 0.0762)
			(layers "F.Cu" "F.Mask" "F.Paste")
			(net "P3V3_STBY_MNG")
			(options
				(clearance outline)
				(anchor circle)
			)
			(primitives
				(gr_poly
					(pts
						(xy -0.1524 0.5715)
						(arc
							(start -0.1524 -0.4191)
							(mid 0 -0.5715)
							(end 0.1524 -0.4191)
						)
						(xy 0.1524 0.5715)
					)
					(width 0)
					(fill yes)
				)
			)
		)
		(pad "13" smd custom
			(at 1.85928 5.36448 90)
			(size 0.0762 0.0762)
			(layers "F.Cu" "F.Mask" "F.Paste")
			(net "CLK_32K_SUSCLK_PLD_R")
			(options
				(clearance outline)
				(anchor circle)
			)
			(primitives
				(gr_poly
					(pts
						(xy -0.1524 0.5715)
						(arc
							(start -0.1524 -0.4191)
							(mid 0 -0.5715)
							(end 0.1524 -0.4191)
						)
						(xy 0.1524 0.5715)
					)
					(width 0)
					(fill yes)
				)
			)
		)
		(pad "14" smd custom
			(at 2.35966 5.36448 90)
			(size 0.0762 0.0762)
			(layers "F.Cu" "F.Mask" "F.Paste")
			(net "GND")
			(options
				(clearance outline)
				(anchor circle)
			)
			(primitives
				(gr_poly
					(pts
						(xy -0.1524 0.5715)
						(arc
							(start -0.1524 -0.4191)
							(mid 0 -0.5715)
							(end 0.1524 -0.4191)
						)
						(xy 0.1524 0.5715)
					)
					(width 0)
					(fill yes)
				)
			)
		)
		(pad "15" smd custom
			(at 2.86004 5.36448 90)
			(size 0.0762 0.0762)
			(layers "F.Cu" "F.Mask" "F.Paste")
			(net "P3V3_STBY_MNG")
			(options
				(clearance outline)
				(anchor circle)
			)
			(primitives
				(gr_poly
					(pts
						(xy -0.1524 0.5715)
						(arc
							(start -0.1524 -0.4191)
							(mid 0 -0.5715)
							(end 0.1524 -0.4191)
						)
						(xy 0.1524 0.5715)
					)
					(width 0)
					(fill yes)
				)
			)
		)
		(pad "16" smd custom
			(at 3.36042 5.36448 90)
			(size 0.0762 0.0762)
			(layers "F.Cu" "F.Mask" "F.Paste")
			(net "CLK_25M_BMC_R")
			(options
				(clearance outline)
				(anchor circle)
			)
			(primitives
				(gr_poly
					(pts
						(xy -0.1524 0.5715)
						(arc
							(start -0.1524 -0.4191)
							(mid 0 -0.5715)
							(end 0.1524 -0.4191)
						)
						(xy 0.1524 0.5715)
					)
					(width 0)
					(fill yes)
				)
			)
		)
		(pad "17" smd custom
			(at 3.8608 5.36448 90)
			(size 0.0762 0.0762)
			(layers "F.Cu" "F.Mask" "F.Paste")
			(net "CLK_25M_CPLD_R")
			(options
				(clearance outline)
				(anchor circle)
			)
			(primitives
				(gr_poly
					(pts
						(xy -0.1524 0.5715)
						(arc
							(start -0.1524 -0.4191)
							(mid 0 -0.5715)
							(end 0.1524 -0.4191)
						)
						(xy 0.1524 0.5715)
					)
					(width 0)
					(fill yes)
				)
			)
		)
		(pad "18" smd custom
			(at 4.36118 5.36448 90)
			(size 0.0762 0.0762)
			(layers "F.Cu" "F.Mask" "F.Paste")
			(net "GND")
			(options
				(clearance outline)
				(anchor circle)
			)
			(primitives
				(gr_poly
					(pts
						(xy -0.1524 0.5715)
						(arc
							(start -0.1524 -0.4191)
							(mid 0 -0.5715)
							(end 0.1524 -0.4191)
						)
						(xy 0.1524 0.5715)
					)
					(width 0)
					(fill yes)
				)
			)
		)
		(pad "19" smd custom
			(at 4.86156 5.36448 90)
			(size 0.0762 0.0762)
			(layers "F.Cu" "F.Mask" "F.Paste")
			(net "XTAL_CK_MNG_IN")
			(options
				(clearance outline)
				(anchor circle)
			)
			(primitives
				(gr_poly
					(pts
						(xy -0.1524 0.5715)
						(arc
							(start -0.1524 -0.4191)
							(mid 0 -0.5715)
							(end 0.1524 -0.4191)
						)
						(xy 0.1524 0.5715)
					)
					(width 0)
					(fill yes)
				)
			)
		)
		(pad "20" smd custom
			(at 5.36194 5.36448 90)
			(size 0.0762 0.0762)
			(layers "F.Cu" "F.Mask" "F.Paste")
			(net "XTAL_CK_MNG_OUT_R")
			(options
				(clearance outline)
				(anchor circle)
			)
			(primitives
				(gr_poly
					(pts
						(xy -0.1524 0.5715)
						(arc
							(start -0.1524 -0.4191)
							(mid 0 -0.5715)
							(end 0.1524 -0.4191)
						)
						(xy 0.1524 0.5715)
					)
					(width 0)
					(fill yes)
				)
			)
		)
		(pad "21" smd custom
			(at 6.223 4.50342 90)
			(size 0.0762 0.0762)
			(layers "F.Cu" "F.Mask" "F.Paste")
			(net "GND")
			(options
				(clearance outline)
				(anchor circle)
			)
			(primitives
				(gr_poly
					(pts
						(xy 0.5715 0.1524)
						(arc
							(start -0.4191 0.1524)
							(mid -0.5715 0)
							(end -0.4191 -0.1524)
						)
						(xy 0.5715 -0.1524)
					)
					(width 0)
					(fill yes)
				)
			)
		)
		(pad "22" smd custom
			(at 6.223 4.00304 90)
			(size 0.0762 0.0762)
			(layers "F.Cu" "F.Mask" "F.Paste")
			(net "PU_33P_33M_SMBADR")
			(options
				(clearance outline)
				(anchor circle)
			)
			(primitives
				(gr_poly
					(pts
						(xy 0.5715 0.1524)
						(arc
							(start -0.4191 0.1524)
							(mid -0.5715 0)
							(end -0.4191 -0.1524)
						)
						(xy 0.5715 -0.1524)
					)
					(width 0)
					(fill yes)
				)
			)
		)
		(pad "23" smd custom
			(at 6.223 3.50266 90)
			(size 0.0762 0.0762)
			(layers "F.Cu" "F.Mask" "F.Paste")
			(net "P3V3_STBY_MNG")
			(options
				(clearance outline)
				(anchor circle)
			)
			(primitives
				(gr_poly
					(pts
						(xy 0.5715 0.1524)
						(arc
							(start -0.4191 0.1524)
							(mid -0.5715 0)
							(end -0.4191 -0.1524)
						)
						(xy 0.5715 -0.1524)
					)
					(width 0)
					(fill yes)
				)
			)
		)
		(pad "24" smd custom
			(at 6.223 3.00228 90)
			(size 0.0762 0.0762)
			(layers "F.Cu" "F.Mask" "F.Paste")
			(net "TP_CLK5_50M_CKMNG")
			(options
				(clearance outline)
				(anchor circle)
			)
			(primitives
				(gr_poly
					(pts
						(xy 0.5715 0.1524)
						(arc
							(start -0.4191 0.1524)
							(mid -0.5715 0)
							(end -0.4191 -0.1524)
						)
						(xy 0.5715 -0.1524)
					)
					(width 0)
					(fill yes)
				)
			)
		)
		(pad "25" smd custom
			(at 6.223 2.5019 90)
			(size 0.0762 0.0762)
			(layers "F.Cu" "F.Mask" "F.Paste")
			(net "CLK_50M_CKMNG_PCH_10GBE_R")
			(options
				(clearance outline)
				(anchor circle)
			)
			(primitives
				(gr_poly
					(pts
						(xy 0.5715 0.1524)
						(arc
							(start -0.4191 0.1524)
							(mid -0.5715 0)
							(end -0.4191 -0.1524)
						)
						(xy 0.5715 -0.1524)
					)
					(width 0)
					(fill yes)
				)
			)
		)
		(pad "26" smd custom
			(at 6.223 2.00152 90)
			(size 0.0762 0.0762)
			(layers "F.Cu" "F.Mask" "F.Paste")
			(net "P3V3_STBY_MNG_RMII")
			(options
				(clearance outline)
				(anchor circle)
			)
			(primitives
				(gr_poly
					(pts
						(xy 0.5715 0.1524)
						(arc
							(start -0.4191 0.1524)
							(mid -0.5715 0)
							(end -0.4191 -0.1524)
						)
						(xy 0.5715 -0.1524)
					)
					(width 0)
					(fill yes)
				)
			)
		)
		(pad "27" smd custom
			(at 6.223 1.50114 90)
			(size 0.0762 0.0762)
			(layers "F.Cu" "F.Mask" "F.Paste")
			(net "GND")
			(options
				(clearance outline)
				(anchor circle)
			)
			(primitives
				(gr_poly
					(pts
						(xy 0.5715 0.1524)
						(arc
							(start -0.4191 0.1524)
							(mid -0.5715 0)
							(end -0.4191 -0.1524)
						)
						(xy 0.5715 -0.1524)
					)
					(width 0)
					(fill yes)
				)
			)
		)
		(pad "28" smd custom
			(at 6.223 1.00076 90)
			(size 0.0762 0.0762)
			(layers "F.Cu" "F.Mask" "F.Paste")
			(net "CLK_50M_CKMNG_SPRVLLE_R")
			(options
				(clearance outline)
				(anchor circle)
			)
			(primitives
				(gr_poly
					(pts
						(xy 0.5715 0.1524)
						(arc
							(start -0.4191 0.1524)
							(mid -0.5715 0)
							(end -0.4191 -0.1524)
						)
						(xy 0.5715 -0.1524)
					)
					(width 0)
					(fill yes)
				)
			)
		)
		(pad "29" smd custom
			(at 6.223 0.50038 90)
			(size 0.0762 0.0762)
			(layers "F.Cu" "F.Mask" "F.Paste")
			(net "CLK_50M_CKMNG_BMC_2_R")
			(options
				(clearance outline)
				(anchor circle)
			)
			(primitives
				(gr_poly
					(pts
						(xy 0.5715 0.1524)
						(arc
							(start -0.4191 0.1524)
							(mid -0.5715 0)
							(end -0.4191 -0.1524)
						)
						(xy 0.5715 -0.1524)
					)
					(width 0)
					(fill yes)
				)
			)
		)
		(pad "30" smd custom
			(at 6.223 0 90)
			(size 0.0762 0.0762)
			(layers "F.Cu" "F.Mask" "F.Paste")
			(net "GND")
			(options
				(clearance outline)
				(anchor circle)
			)
			(primitives
				(gr_poly
					(pts
						(xy 0.5715 0.1524)
						(arc
							(start -0.4191 0.1524)
							(mid -0.5715 0)
							(end -0.4191 -0.1524)
						)
						(xy 0.5715 -0.1524)
					)
					(width 0)
					(fill yes)
				)
			)
		)
		(pad "31" smd custom
			(at 5.36194 -0.85852 90)
			(size 0.0762 0.0762)
			(layers "F.Cu" "F.Mask" "F.Paste")
			(net "P3V3_STBY_MNG_RMII")
			(options
				(clearance outline)
				(anchor circle)
			)
			(primitives
				(gr_poly
					(pts
						(xy 0.1524 -0.5715)
						(arc
							(start 0.1524 0.4191)
							(mid 0 0.5715)
							(end -0.1524 0.4191)
						)
						(xy -0.1524 -0.5715)
					)
					(width 0)
					(fill yes)
				)
			)
		)
		(pad "32" smd custom
			(at 4.86156 -0.85852 90)
			(size 0.0762 0.0762)
			(layers "F.Cu" "F.Mask" "F.Paste")
			(net "CLK_50M_CKMNG_BMC_1_R")
			(options
				(clearance outline)
				(anchor circle)
			)
			(primitives
				(gr_poly
					(pts
						(xy 0.1524 -0.5715)
						(arc
							(start 0.1524 0.4191)
							(mid 0 0.5715)
							(end -0.1524 0.4191)
						)
						(xy -0.1524 -0.5715)
					)
					(width 0)
					(fill yes)
				)
			)
		)
		(pad "33" smd custom
			(at 4.36118 -0.85852 90)
			(size 0.0762 0.0762)
			(layers "F.Cu" "F.Mask" "F.Paste")
			(net "CLK_50M_CKMNG_OCP_R")
			(options
				(clearance outline)
				(anchor circle)
			)
			(primitives
				(gr_poly
					(pts
						(xy 0.1524 -0.5715)
						(arc
							(start 0.1524 0.4191)
							(mid 0 0.5715)
							(end -0.1524 0.4191)
						)
						(xy -0.1524 -0.5715)
					)
					(width 0)
					(fill yes)
				)
			)
		)
		(pad "34" smd custom
			(at 3.8608 -0.85852 90)
			(size 0.0762 0.0762)
			(layers "F.Cu" "F.Mask" "F.Paste")
			(net "P3V3_STBY_MNG_RGMII")
			(options
				(clearance outline)
				(anchor circle)
			)
			(primitives
				(gr_poly
					(pts
						(xy 0.1524 -0.5715)
						(arc
							(start 0.1524 0.4191)
							(mid 0 0.5715)
							(end -0.1524 0.4191)
						)
						(xy -0.1524 -0.5715)
					)
					(width 0)
					(fill yes)
				)
			)
		)
		(pad "35" smd custom
			(at 3.36042 -0.85852 90)
			(size 0.0762 0.0762)
			(layers "F.Cu" "F.Mask" "F.Paste")
			(net "GND")
			(options
				(clearance outline)
				(anchor circle)
			)
			(primitives
				(gr_poly
					(pts
						(xy 0.1524 -0.5715)
						(arc
							(start 0.1524 0.4191)
							(mid 0 0.5715)
							(end -0.1524 0.4191)
						)
						(xy -0.1524 -0.5715)
					)
					(width 0)
					(fill yes)
				)
			)
		)
		(pad "36" smd custom
			(at 2.86004 -0.85852 90)
			(size 0.0762 0.0762)
			(layers "F.Cu" "F.Mask" "F.Paste")
			(net "TP_CLK_125M")
			(options
				(clearance outline)
				(anchor circle)
			)
			(primitives
				(gr_poly
					(pts
						(xy 0.1524 -0.5715)
						(arc
							(start 0.1524 0.4191)
							(mid 0 0.5715)
							(end -0.1524 0.4191)
						)
						(xy -0.1524 -0.5715)
					)
					(width 0)
					(fill yes)
				)
			)
		)
		(pad "37" smd custom
			(at 2.35966 -0.85852 90)
			(size 0.0762 0.0762)
			(layers "F.Cu" "F.Mask" "F.Paste")
			(net "TP_CLK_125M_BMCA")
			(options
				(clearance outline)
				(anchor circle)
			)
			(primitives
				(gr_poly
					(pts
						(xy 0.1524 -0.5715)
						(arc
							(start 0.1524 0.4191)
							(mid 0 0.5715)
							(end -0.1524 0.4191)
						)
						(xy -0.1524 -0.5715)
					)
					(width 0)
					(fill yes)
				)
			)
		)
		(pad "38" smd custom
			(at 1.85928 -0.85852 90)
			(size 0.0762 0.0762)
			(layers "F.Cu" "F.Mask" "F.Paste")
			(net "SMB_HOST_STBY_LVC3_SCL_R4")
			(options
				(clearance outline)
				(anchor circle)
			)
			(primitives
				(gr_poly
					(pts
						(xy 0.1524 -0.5715)
						(arc
							(start 0.1524 0.4191)
							(mid 0 0.5715)
							(end -0.1524 0.4191)
						)
						(xy -0.1524 -0.5715)
					)
					(width 0)
					(fill yes)
				)
			)
		)
		(pad "39" smd custom
			(at 1.3589 -0.85852 90)
			(size 0.0762 0.0762)
			(layers "F.Cu" "F.Mask" "F.Paste")
			(net "SMB_HOST_STBY_LVC3_SDA_R4")
			(options
				(clearance outline)
				(anchor circle)
			)
			(primitives
				(gr_poly
					(pts
						(xy 0.1524 -0.5715)
						(arc
							(start 0.1524 0.4191)
							(mid 0 0.5715)
							(end -0.1524 0.4191)
						)
						(xy -0.1524 -0.5715)
					)
					(width 0)
					(fill yes)
				)
			)
		)
		(pad "40" smd custom
			(at 0.85852 -0.85852 90)
			(size 0.0762 0.0762)
			(layers "F.Cu" "F.Mask" "F.Paste")
			(net "PWRGD_P3V3_STBY")
			(options
				(clearance outline)
				(anchor circle)
			)
			(primitives
				(gr_poly
					(pts
						(xy 0.1524 -0.5715)
						(arc
							(start 0.1524 0.4191)
							(mid 0 0.5715)
							(end -0.1524 0.4191)
						)
						(xy -0.1524 -0.5715)
					)
					(width 0)
					(fill yes)
				)
			)
		)
		(pad "41" smd rect
			(at 3.1115 2.25298 90)
			(size 4.0894 4.0894)
			(layers "F.Cu" "F.Mask" "F.Paste")
			(net "GND")
		)
	)
	(footprint ""
		(layer "F.Cu")
		(at 402.615146 -41.792652 90)
		(property "Reference" "R1T38"
			(at 0 0 90)
			(layer "F.SilkS")
			(hide yes)
			(effects
				(font
					(size 1.27 1.27)
				)
			)
		)
		(property "Value" ""
			(at 0 0 90)
			(layer "F.Fab")
			(effects
				(font
					(size 1.27 1.27)
				)
			)
		)
		(duplicate_pad_numbers_are_jumpers no)
		(fp_poly
			(pts
				(xy -0.2794 -0.1016) (xy 0.2794 -0.1016) (xy 0.2794 0.9906) (xy -0.2794 0.9906)
			)
			(stroke
				(width 0)
				(type default)
			)
			(fill no)
			(layer "F.CrtYd")
		)
		(fp_line
			(start 0.2794 -0.1016)
			(end -0.2794 -0.1016)
			(stroke
				(width 0.1)
				(type default)
			)
			(layer "F.Fab")
		)
		(fp_line
			(start -0.2794 -0.1016)
			(end -0.2794 0.9906)
			(stroke
				(width 0.1)
				(type default)
			)
			(layer "F.Fab")
		)
		(fp_line
			(start 0.2794 0.9906)
			(end 0.2794 -0.1016)
			(stroke
				(width 0.1)
				(type default)
			)
			(layer "F.Fab")
		)
		(fp_line
			(start -0.2794 0.9906)
			(end 0.2794 0.9906)
			(stroke
				(width 0.1)
				(type default)
			)
			(layer "F.Fab")
		)
		(pad "1" smd rect
			(at 0 0 90)
			(size 0.508 0.508)
			(layers "F.Cu" "F.Mask" "F.Paste")
			(net "FM_CPU1_PROCHOT_LVT3_N")
		)
		(pad "2" smd rect
			(at 0 0.889 90)
			(size 0.508 0.508)
			(layers "F.Cu" "F.Mask" "F.Paste")
			(net "FM_CPU1_PROCHOT_PCH_N")
		)
		(zone
			(layer "F.Cu")
			(hatch none 0.5)
			(connect_pads
				(clearance 0)
			)
			(min_thickness 0.25)
			(keepout
				(tracks allowed)
				(vias not_allowed)
				(pads allowed)
				(copperpour not_allowed)
				(footprints allowed)
			)
			(placement
				(enabled no)
				(sheetname "")
			)
			(fill
				(thermal_gap 0.5)
				(thermal_bridge_width 0.5)
				(island_removal_mode 0)
			)
			(polygon
				(pts
					(xy 402.869146 -41.538652) (xy 402.869146 -42.046652) (xy 403.250146 -42.046652) (xy 403.250146 -41.538652)
				)
			)
		)
		(zone
			(layer "F.Cu")
			(hatch none 0.5)
			(connect_pads
				(clearance 0)
			)
			(min_thickness 0.25)
			(keepout
				(tracks not_allowed)
				(vias allowed)
				(pads allowed)
				(copperpour not_allowed)
				(footprints allowed)
			)
			(placement
				(enabled no)
				(sheetname "")
			)
			(fill
				(thermal_gap 0.5)
				(thermal_bridge_width 0.5)
				(island_removal_mode 0)
			)
			(polygon
				(pts
					(xy 403.250146 -41.538652) (xy 403.250146 -42.046652) (xy 402.869146 -42.046652) (xy 402.869146 -41.538652)
				)
			)
		)
	)
	(footprint ""
		(layer "F.Cu")
		(at 35.028378 -121.59361)
		(property "Reference" "C1B14"
			(at -6.204966 4.045458 270)
			(unlocked yes)
			(layer "F.SilkS")
			(effects
				(font
					(size 0.7874 0.5842)
					(thickness 0.1524)
				)
			)
		)
		(property "Value" ""
			(at 0 0 0)
			(layer "F.Fab")
			(effects
				(font
					(size 1.27 1.27)
				)
			)
		)
		(duplicate_pad_numbers_are_jumpers no)
		(fp_line
			(start -5.1435 -0.127)
			(end -4.3815 -1.016)
			(stroke
				(width 0.1524)
				(type default)
			)
			(layer "F.SilkS")
		)
		(fp_line
			(start -5.1435 9.271)
			(end -5.1435 -0.127)
			(stroke
				(width 0.1524)
				(type default)
			)
			(layer "F.SilkS")
		)
		(fp_line
			(start -4.3815 -1.016)
			(end -1.8415 -1.016)
			(stroke
				(width 0.1524)
				(type default)
			)
			(layer "F.SilkS")
		)
		(fp_line
			(start -1.8415 -2.0955)
			(end -1.8415 2.0955)
			(stroke
				(width 0.1524)
				(type default)
			)
			(layer "F.SilkS")
		)
		(fp_line
			(start -1.8415 2.0955)
			(end -1.4097 2.0955)
			(stroke
				(width 0.1524)
				(type default)
			)
			(layer "F.SilkS")
		)
		(fp_line
			(start -1.4097 -2.0955)
			(end -1.8415 -2.0955)
			(stroke
				(width 0.1524)
				(type default)
			)
			(layer "F.SilkS")
		)
		(fp_line
			(start -1.4097 9.271)
			(end -5.1435 9.271)
			(stroke
				(width 0.1524)
				(type default)
			)
			(layer "F.SilkS")
		)
		(fp_line
			(start 1.4097 -2.0955)
			(end 1.8415 -2.0955)
			(stroke
				(width 0.1524)
				(type default)
			)
			(layer "F.SilkS")
		)
		(fp_line
			(start 1.8415 -2.0955)
			(end 1.8415 2.0955)
			(stroke
				(width 0.1524)
				(type default)
			)
			(layer "F.SilkS")
		)
		(fp_line
			(start 1.8415 -1.016)
			(end 4.3815 -1.016)
			(stroke
				(width 0.1524)
				(type default)
			)
			(layer "F.SilkS")
		)
		(fp_line
			(start 1.8415 2.0955)
			(end 1.4097 2.0955)
			(stroke
				(width 0.1524)
				(type default)
			)
			(layer "F.SilkS")
		)
		(fp_line
			(start 4.3815 -1.016)
			(end 5.1435 -0.127)
			(stroke
				(width 0.1524)
				(type default)
			)
			(layer "F.SilkS")
		)
		(fp_line
			(start 5.1435 -0.127)
			(end 5.1435 9.271)
			(stroke
				(width 0.1524)
				(type default)
			)
			(layer "F.SilkS")
		)
		(fp_line
			(start 5.1435 9.271)
			(end 1.4097 9.271)
			(stroke
				(width 0.1524)
				(type default)
			)
			(layer "F.SilkS")
		)
		(fp_poly
			(pts
				(xy -5.14604 -0.12954) (xy -4.38404 -1.01346) (xy 4.37896 -1.016) (xy 5.1435 -0.12954) (xy 5.14096 9.271)
				(xy -5.14604 9.27354)
			)
			(stroke
				(width 0)
				(type default)
			)
			(fill no)
			(layer "F.CrtYd")
		)
		(fp_line
			(start -5.1435 -0.127)
			(end -4.3815 -1.016)
			(stroke
				(width 0.1)
				(type default)
			)
			(layer "F.Fab")
		)
		(fp_line
			(start -5.1435 9.271)
			(end -5.1435 -0.127)
			(stroke
				(width 0.1)
				(type default)
			)
			(layer "F.Fab")
		)
		(fp_line
			(start -4.3815 -1.016)
			(end 4.3815 -1.016)
			(stroke
				(width 0.1)
				(type default)
			)
			(layer "F.Fab")
		)
		(fp_line
			(start 4.3815 -1.016)
			(end 5.1435 -0.127)
			(stroke
				(width 0.1)
				(type default)
			)
			(layer "F.Fab")
		)
		(fp_line
			(start 5.1435 -0.127)
			(end 5.1435 9.271)
			(stroke
				(width 0.1)
				(type default)
			)
			(layer "F.Fab")
		)
		(fp_line
			(start 5.1435 9.271)
			(end -5.1435 9.271)
			(stroke
				(width 0.1)
				(type default)
			)
			(layer "F.Fab")
		)
		(fp_circle
			(center 0 4.1275)
			(end 4.9911 4.1275)
			(stroke
				(width 0.1)
				(type default)
			)
			(fill no)
			(layer "F.Fab")
		)
		(pad "1" smd rect
			(at 0 0)
			(size 1.905 4.191)
			(layers "F.Cu" "F.Mask" "F.Paste")
			(net "P12V_STBY")
		)
		(pad "2" smd rect
			(at 0 8.255)
			(size 1.905 4.191)
			(layers "F.Cu" "F.Mask" "F.Paste")
			(net "GND")
		)
		(zone
			(layer "F.Cu")
			(hatch none 0.5)
			(connect_pads
				(clearance 0)
			)
			(min_thickness 0.25)
			(keepout
				(tracks allowed)
				(vias not_allowed)
				(pads allowed)
				(copperpour not_allowed)
				(footprints allowed)
			)
			(placement
				(enabled no)
				(sheetname "")
			)
			(fill
				(thermal_gap 0.5)
				(thermal_bridge_width 0.5)
				(island_removal_mode 0)
			)
			(polygon
				(pts
					(xy 29.884878 -112.32261) (xy 40.171878 -112.32261) (xy 40.171878 -121.72061) (xy 39.409878 -122.60961)
					(xy 30.646878 -122.60961) (xy 29.884878 -121.72061)
				)
			)
		)
	)
	(footprint ""
		(layer "F.Cu")
		(at 173.482 -146.939 90)
		(property "Reference" "C4A8"
			(at 0 0 90)
			(layer "F.SilkS")
			(hide yes)
			(effects
				(font
					(size 1.27 1.27)
				)
			)
		)
		(property "Value" ""
			(at 0 0 90)
			(layer "F.Fab")
			(effects
				(font
					(size 1.27 1.27)
				)
			)
		)
		(duplicate_pad_numbers_are_jumpers no)
		(fp_rect
			(start 0.3048 0.9906)
			(end -0.3048 -0.1016)
			(stroke
				(width 0)
				(type default)
			)
			(fill no)
			(layer "F.CrtYd")
		)
		(fp_line
			(start 0.3048 -0.1016)
			(end -0.3048 -0.1016)
			(stroke
				(width 0.1)
				(type default)
			)
			(layer "F.Fab")
		)
		(fp_line
			(start -0.3048 -0.1016)
			(end -0.3048 0.9906)
			(stroke
				(width 0.1)
				(type default)
			)
			(layer "F.Fab")
		)
		(fp_line
			(start 0.3048 0.9906)
			(end 0.3048 -0.1016)
			(stroke
				(width 0.1)
				(type default)
			)
			(layer "F.Fab")
		)
		(fp_line
			(start -0.3048 0.9906)
			(end 0.3048 0.9906)
			(stroke
				(width 0.1)
				(type default)
			)
			(layer "F.Fab")
		)
		(pad "1" smd rect
			(at 0 0 90)
			(size 0.508 0.508)
			(layers "F.Cu" "F.Mask" "F.Paste")
			(net "VR_PVTT_KLM_BIAS")
		)
		(pad "2" smd rect
			(at 0 0.889 90)
			(size 0.508 0.508)
			(layers "F.Cu" "F.Mask" "F.Paste")
			(net "GND")
		)
		(zone
			(layer "F.Cu")
			(hatch none 0.5)
			(connect_pads
				(clearance 0)
			)
			(min_thickness 0.25)
			(keepout
				(tracks not_allowed)
				(vias allowed)
				(pads allowed)
				(copperpour not_allowed)
				(footprints allowed)
			)
			(placement
				(enabled no)
				(sheetname "")
			)
			(fill
				(thermal_gap 0.5)
				(thermal_bridge_width 0.5)
				(island_removal_mode 0)
			)
			(polygon
				(pts
					(xy 174.117 -147.193) (xy 173.736 -147.193) (xy 173.736 -146.685) (xy 174.117 -146.685)
				)
			)
		)
		(zone
			(layer "F.Cu")
			(hatch none 0.5)
			(connect_pads
				(clearance 0)
			)
			(min_thickness 0.25)
			(keepout
				(tracks allowed)
				(vias not_allowed)
				(pads allowed)
				(copperpour not_allowed)
				(footprints allowed)
			)
			(placement
				(enabled no)
				(sheetname "")
			)
			(fill
				(thermal_gap 0.5)
				(thermal_bridge_width 0.5)
				(island_removal_mode 0)
			)
			(polygon
				(pts
					(xy 174.117 -147.193) (xy 173.736 -147.193) (xy 173.736 -146.685) (xy 174.117 -146.685)
				)
			)
		)
	)
	(footprint ""
		(layer "F.Cu")
		(at 49.4284 -86.67242)
		(property "Reference" "C1D3"
			(at 0 0 0)
			(layer "F.SilkS")
			(hide yes)
			(effects
				(font
					(size 1.27 1.27)
				)
			)
		)
		(property "Value" ""
			(at 0 0 0)
			(layer "F.Fab")
			(effects
				(font
					(size 1.27 1.27)
				)
			)
		)
		(duplicate_pad_numbers_are_jumpers no)
		(fp_poly
			(pts
				(xy -0.4953 -0.2032) (xy 0.4953 -0.2032) (xy 0.4953 1.6002) (xy -0.4953 1.6002)
			)
			(stroke
				(width 0)
				(type default)
			)
			(fill no)
			(layer "F.CrtYd")
		)
		(fp_line
			(start -0.4953 -0.2032)
			(end 0.4953 -0.2032)
			(stroke
				(width 0.1)
				(type default)
			)
			(layer "F.Fab")
		)
		(fp_line
			(start -0.4953 1.6002)
			(end -0.4953 -0.2032)
			(stroke
				(width 0.1)
				(type default)
			)
			(layer "F.Fab")
		)
		(fp_line
			(start 0.4953 -0.2032)
			(end 0.4953 1.6002)
			(stroke
				(width 0.1)
				(type default)
			)
			(layer "F.Fab")
		)
		(fp_line
			(start 0.4953 1.6002)
			(end -0.4953 1.6002)
			(stroke
				(width 0.1)
				(type default)
			)
			(layer "F.Fab")
		)
		(pad "1" smd rect
			(at 0 0)
			(size 0.762 0.889)
			(layers "F.Cu" "F.Mask" "F.Paste")
			(net "PVCCIN_CPU1")
		)
		(pad "2" smd rect
			(at 0 1.397)
			(size 0.762 0.889)
			(layers "F.Cu" "F.Mask" "F.Paste")
			(net "GND")
		)
		(zone
			(layer "F.Cu")
			(hatch none 0.5)
			(connect_pads
				(clearance 0)
			)
			(min_thickness 0.25)
			(keepout
				(tracks not_allowed)
				(vias allowed)
				(pads allowed)
				(copperpour not_allowed)
				(footprints allowed)
			)
			(placement
				(enabled no)
				(sheetname "")
			)
			(fill
				(thermal_gap 0.5)
				(thermal_bridge_width 0.5)
				(island_removal_mode 0)
			)
			(polygon
				(pts
					(xy 49.0474 -86.22792) (xy 49.8094 -86.22792) (xy 49.8094 -85.71992) (xy 49.0474 -85.71992)
				)
			)
		)
	)
	(footprint ""
		(layer "F.Cu")
		(at 183.0832 -76.3778 -90)
		(property "Reference" "R4D32"
			(at 0 0 270)
			(layer "F.SilkS")
			(hide yes)
			(effects
				(font
					(size 1.27 1.27)
				)
			)
		)
		(property "Value" ""
			(at 0 0 270)
			(layer "F.Fab")
			(effects
				(font
					(size 1.27 1.27)
				)
			)
		)
		(duplicate_pad_numbers_are_jumpers no)
		(fp_rect
			(start 0.2794 0.9906)
			(end -0.2794 -0.1016)
			(stroke
				(width 0)
				(type default)
			)
			(fill no)
			(layer "F.CrtYd")
		)
		(fp_line
			(start -0.2794 0.9906)
			(end 0.2794 0.9906)
			(stroke
				(width 0.1)
				(type default)
			)
			(layer "F.Fab")
		)
		(fp_line
			(start 0.2794 0.9906)
			(end 0.2794 -0.1016)
			(stroke
				(width 0.1)
				(type default)
			)
			(layer "F.Fab")
		)
		(fp_line
			(start -0.2794 -0.1016)
			(end -0.2794 0.9906)
			(stroke
				(width 0.1)
				(type default)
			)
			(layer "F.Fab")
		)
		(fp_line
			(start 0.2794 -0.1016)
			(end -0.2794 -0.1016)
			(stroke
				(width 0.1)
				(type default)
			)
			(layer "F.Fab")
		)
		(pad "1" smd rect
			(at 0 0 270)
			(size 0.508 0.508)
			(layers "F.Cu" "F.Mask" "F.Paste")
			(net "VR_PVCCIN_CPU0_AVINSEN")
		)
		(pad "2" smd rect
			(at 0 0.889 270)
			(size 0.508 0.508)
			(layers "F.Cu" "F.Mask" "F.Paste")
			(net "GND")
		)
		(zone
			(layer "F.Cu")
			(hatch none 0.5)
			(connect_pads
				(clearance 0)
			)
			(min_thickness 0.25)
			(keepout
				(tracks allowed)
				(vias not_allowed)
				(pads allowed)
				(copperpour not_allowed)
				(footprints allowed)
			)
			(placement
				(enabled no)
				(sheetname "")
			)
			(fill
				(thermal_gap 0.5)
				(thermal_bridge_width 0.5)
				(island_removal_mode 0)
			)
			(polygon
				(pts
					(xy 182.4482 -76.1238) (xy 182.8292 -76.1238) (xy 182.8292 -76.6318) (xy 182.4482 -76.6318)
				)
			)
		)
		(zone
			(layer "F.Cu")
			(hatch none 0.5)
			(connect_pads
				(clearance 0)
			)
			(min_thickness 0.25)
			(keepout
				(tracks not_allowed)
				(vias allowed)
				(pads allowed)
				(copperpour not_allowed)
				(footprints allowed)
			)
			(placement
				(enabled no)
				(sheetname "")
			)
			(fill
				(thermal_gap 0.5)
				(thermal_bridge_width 0.5)
				(island_removal_mode 0)
			)
			(polygon
				(pts
					(xy 182.4482 -76.1238) (xy 182.8292 -76.1238) (xy 182.8292 -76.6318) (xy 182.4482 -76.6318)
				)
			)
		)
	)
	(footprint ""
		(layer "F.Cu")
		(at 162.306 -64.8716 90)
		(property "Reference" "SH3D2"
			(at 0 0 90)
			(layer "F.SilkS")
			(hide yes)
			(effects
				(font
					(size 1.27 1.27)
				)
			)
		)
		(property "Value" ""
			(at 0 0 90)
			(layer "F.Fab")
			(effects
				(font
					(size 1.27 1.27)
				)
			)
		)
		(duplicate_pad_numbers_are_jumpers no)
		(fp_poly
			(pts
				(xy -0.1651 -0.0508) (xy -0.1651 0.5842) (xy 0.1651 0.5842) (xy 0.1651 -0.0508)
			)
			(stroke
				(width 0)
				(type default)
			)
			(fill no)
			(layer "F.CrtYd")
		)
		(fp_line
			(start 0.1651 -0.0508)
			(end 0.1651 0.5842)
			(stroke
				(width 0.1)
				(type default)
			)
			(layer "F.Fab")
		)
		(fp_line
			(start -0.1651 -0.0508)
			(end 0.1651 -0.0508)
			(stroke
				(width 0.1)
				(type default)
			)
			(layer "F.Fab")
		)
		(fp_line
			(start 0.1651 0.5842)
			(end -0.1651 0.5842)
			(stroke
				(width 0.1)
				(type default)
			)
			(layer "F.Fab")
		)
		(fp_line
			(start -0.1651 0.5842)
			(end -0.1651 -0.0508)
			(stroke
				(width 0.1)
				(type default)
			)
			(layer "F.Fab")
		)
		(pad "1" smd custom
			(at 0 0 270)
			(size 0.0762 0.0762)
			(layers "F.Cu" "F.Mask" "F.Paste")
			(net "VSENSE_PVCCIO_CPU1_SKT_VSEN")
			(options
				(clearance outline)
				(anchor circle)
			)
			(primitives
				(gr_poly
					(pts
						(arc
							(start -0.1524 -0.10795)
							(mid -0.098518 -0.130268)
							(end -0.0762 -0.18415)
						)
						(xy -0.0762 -0.22225) (xy 0.0762 -0.22225)
						(arc
							(start 0.0762 -0.18415)
							(mid 0.098518 -0.130268)
							(end 0.1524 -0.10795)
						)
						(xy 0.1524 0.22225) (xy -0.1524 0.22225)
					)
					(width 0)
					(fill yes)
				)
			)
		)
		(pad "2" smd custom
			(at 0 0.5334 90)
			(size 0.0762 0.0762)
			(layers "F.Cu" "F.Mask" "F.Paste")
			(net "VSENSE_PVCCIO_CPU1_AVSP")
			(options
				(clearance outline)
				(anchor circle)
			)
			(primitives
				(gr_poly
					(pts
						(arc
							(start -0.1524 -0.10795)
							(mid -0.098518 -0.130268)
							(end -0.0762 -0.18415)
						)
						(xy -0.0762 -0.22225) (xy 0.0762 -0.22225)
						(arc
							(start 0.0762 -0.18415)
							(mid 0.098518 -0.130268)
							(end 0.1524 -0.10795)
						)
						(xy 0.1524 0.22225) (xy -0.1524 0.22225)
					)
					(width 0)
					(fill yes)
				)
			)
		)
	)
	(footprint ""
		(layer "F.Cu")
		(at 481.369624 -24.552148 -90)
		(property "Reference" "FB9E1"
			(at 0 0 270)
			(layer "F.SilkS")
			(hide yes)
			(effects
				(font
					(size 1.27 1.27)
				)
			)
		)
		(property "Value" "*"
			(at -2.4511 -3.44805 270)
			(unlocked yes)
			(layer "F.Fab")
			(hide yes)
			(effects
				(font
					(size 0.889 0.889)
					(thickness 0.1524)
				)
			)
		)
		(property "Device Type" "BLM31SN500SN1L-GP_DISCRET-GB1-A"
			(at -2.4511 -4.97205 270)
			(unlocked yes)
			(layer "F.Fab")
			(hide yes)
			(effects
				(font
					(size 0.889 0.889)
					(thickness 0.1524)
				)
			)
		)
		(duplicate_pad_numbers_are_jumpers no)
		(fp_line
			(start -1.27 2.2352)
			(end -1.27 -2.2352)
			(stroke
				(width 0.1524)
				(type default)
			)
			(layer "F.SilkS")
		)
		(fp_line
			(start 1.27 2.2352)
			(end -1.27 2.2352)
			(stroke
				(width 0.1524)
				(type default)
			)
			(layer "F.SilkS")
		)
		(fp_line
			(start -1.27 -2.2352)
			(end 1.27 -2.2352)
			(stroke
				(width 0.1524)
				(type default)
			)
			(layer "F.SilkS")
		)
		(fp_line
			(start 1.27 -2.2352)
			(end 1.27 2.2352)
			(stroke
				(width 0.1524)
				(type default)
			)
			(layer "F.SilkS")
		)
		(fp_rect
			(start -0.8001 1.6002)
			(end 0.8001 -1.6002)
			(stroke
				(width 0)
				(type default)
			)
			(fill no)
			(layer "F.CrtYd")
		)
		(fp_poly
			(pts
				(xy -0.8001 -1.6002) (xy 1.524 -1.6002) (xy 1.524 -2.3114) (xy -1.524 -2.3114) (xy -1.524 2.3114)
				(xy 1.524 2.3114) (xy 1.524 -1.5875) (xy 0.8001 -1.5875) (xy 0.8001 1.6002) (xy -0.8001 1.6002)
			)
			(stroke
				(width 0)
				(type default)
			)
			(fill no)
			(layer "F.CrtYd")
		)
		(fp_rect
			(start -1.524 2.3114)
			(end 1.524 -2.3114)
			(stroke
				(width 0)
				(type default)
			)
			(fill no)
			(layer "F.Fab")
		)
		(pad "1" smd rect
			(at 0 -1.5367 270)
			(size 2.032 1.397)
			(drill
				(offset 0 0.2032)
			)
			(layers "F.Cu" "F.Mask" "F.Paste")
			(net "P12V_STBY")
		)
		(pad "2" smd rect
			(at 0 1.5367 270)
			(size 2.032 1.397)
			(drill
				(offset 0 -0.2032)
			)
			(layers "F.Cu" "F.Mask" "F.Paste")
			(net "VR_FET_SW_P12V_STBY_P3V3_STBY")
		)
	)
	(footprint ""
		(layer "F.Cu")
		(at 180.0606 -4.445 180)
		(property "Reference" "R4G19"
			(at 0 0 180)
			(layer "F.SilkS")
			(hide yes)
			(effects
				(font
					(size 1.27 1.27)
				)
			)
		)
		(property "Value" ""
			(at 0 0 180)
			(layer "F.Fab")
			(effects
				(font
					(size 1.27 1.27)
				)
			)
		)
		(duplicate_pad_numbers_are_jumpers no)
		(fp_poly
			(pts
				(xy -0.2794 -0.1016) (xy 0.2794 -0.1016) (xy 0.2794 0.9906) (xy -0.2794 0.9906)
			)
			(stroke
				(width 0)
				(type default)
			)
			(fill no)
			(layer "F.CrtYd")
		)
		(fp_line
			(start 0.2794 0.9906)
			(end 0.2794 -0.1016)
			(stroke
				(width 0.1)
				(type default)
			)
			(layer "F.Fab")
		)
		(fp_line
			(start 0.2794 -0.1016)
			(end -0.2794 -0.1016)
			(stroke
				(width 0.1)
				(type default)
			)
			(layer "F.Fab")
		)
		(fp_line
			(start -0.2794 0.9906)
			(end 0.2794 0.9906)
			(stroke
				(width 0.1)
				(type default)
			)
			(layer "F.Fab")
		)
		(fp_line
			(start -0.2794 -0.1016)
			(end -0.2794 0.9906)
			(stroke
				(width 0.1)
				(type default)
			)
			(layer "F.Fab")
		)
		(pad "1" smd rect
			(at 0 0 180)
			(size 0.508 0.508)
			(layers "F.Cu" "F.Mask" "F.Paste")
			(net "PWRGD_PVTT_ABC_CPU0_R")
		)
		(pad "2" smd rect
			(at 0 0.889 180)
			(size 0.508 0.508)
			(layers "F.Cu" "F.Mask" "F.Paste")
			(net "PWRGD_PVTT_CPU0")
		)
		(zone
			(layer "F.Cu")
			(hatch none 0.5)
			(connect_pads
				(clearance 0)
			)
			(min_thickness 0.25)
			(keepout
				(tracks not_allowed)
				(vias allowed)
				(pads allowed)
				(copperpour not_allowed)
				(footprints allowed)
			)
			(placement
				(enabled no)
				(sheetname "")
			)
			(fill
				(thermal_gap 0.5)
				(thermal_bridge_width 0.5)
				(island_removal_mode 0)
			)
			(polygon
				(pts
					(xy 180.3146 -5.08) (xy 179.8066 -5.08) (xy 179.8066 -4.699) (xy 180.3146 -4.699)
				)
			)
		)
		(zone
			(layer "F.Cu")
			(hatch none 0.5)
			(connect_pads
				(clearance 0)
			)
			(min_thickness 0.25)
			(keepout
				(tracks allowed)
				(vias not_allowed)
				(pads allowed)
				(copperpour not_allowed)
				(footprints allowed)
			)
			(placement
				(enabled no)
				(sheetname "")
			)
			(fill
				(thermal_gap 0.5)
				(thermal_bridge_width 0.5)
				(island_removal_mode 0)
			)
			(polygon
				(pts
					(xy 180.3146 -4.699) (xy 179.8066 -4.699) (xy 179.8066 -5.08) (xy 180.3146 -5.08)
				)
			)
		)
	)
	(footprint ""
		(layer "F.Cu")
		(at 351.83699 -148.646388 -90)
		(property "Reference" "CT46"
			(at 7.03707 4.2418 0)
			(unlocked yes)
			(layer "F.SilkS")
			(effects
				(font
					(size 0.7874 0.5842)
					(thickness 0.1524)
				)
				(justify left)
			)
		)
		(property "Value" ""
			(at 0 0 270)
			(layer "F.Fab")
			(effects
				(font
					(size 1.27 1.27)
				)
			)
		)
		(duplicate_pad_numbers_are_jumpers no)
		(fp_poly
			(pts
				(xy 0.3048 -0.1016) (xy 0.3048 0.9906) (xy -0.3048 0.9906) (xy -0.3048 -0.1016)
			)
			(stroke
				(width 0)
				(type default)
			)
			(fill no)
			(layer "F.CrtYd")
		)
		(fp_line
			(start -0.3048 0.9906)
			(end 0.3048 0.9906)
			(stroke
				(width 0.1)
				(type default)
			)
			(layer "F.Fab")
		)
		(fp_line
			(start 0.3048 0.9906)
			(end 0.3048 -0.1016)
			(stroke
				(width 0.1)
				(type default)
			)
			(layer "F.Fab")
		)
		(fp_line
			(start -0.3048 -0.1016)
			(end -0.3048 0.9906)
			(stroke
				(width 0.1)
				(type default)
			)
			(layer "F.Fab")
		)
		(fp_line
			(start 0.3048 -0.1016)
			(end -0.3048 -0.1016)
			(stroke
				(width 0.1)
				(type default)
			)
			(layer "F.Fab")
		)
		(pad "1" smd rect
			(at 0 0 270)
			(size 0.508 0.508)
			(layers "F.Cu" "F.Mask" "F.Paste")
			(net "VR_PVDDQ_DEF_AIREF2")
		)
		(pad "2" smd rect
			(at 0 0.889 270)
			(size 0.508 0.508)
			(layers "F.Cu" "F.Mask" "F.Paste")
			(net "GND")
		)
		(zone
			(layer "F.Cu")
			(hatch none 0.5)
			(connect_pads
				(clearance 0)
			)
			(min_thickness 0.25)
			(keepout
				(tracks not_allowed)
				(vias allowed)
				(pads allowed)
				(copperpour not_allowed)
				(footprints allowed)
			)
			(placement
				(enabled no)
				(sheetname "")
			)
			(fill
				(thermal_gap 0.5)
				(thermal_bridge_width 0.5)
				(island_removal_mode 0)
			)
			(polygon
				(pts
					(xy 351.20199 -148.900388) (xy 351.20199 -148.392388) (xy 351.58299 -148.392388) (xy 351.58299 -148.900388)
				)
			)
		)
		(zone
			(layer "F.Cu")
			(hatch none 0.5)
			(connect_pads
				(clearance 0)
			)
			(min_thickness 0.25)
			(keepout
				(tracks allowed)
				(vias not_allowed)
				(pads allowed)
				(copperpour not_allowed)
				(footprints allowed)
			)
			(placement
				(enabled no)
				(sheetname "")
			)
			(fill
				(thermal_gap 0.5)
				(thermal_bridge_width 0.5)
				(island_removal_mode 0)
			)
			(polygon
				(pts
					(xy 351.58299 -148.900388) (xy 351.58299 -148.392388) (xy 351.20199 -148.392388) (xy 351.20199 -148.900388)
				)
			)
		)
	)
	(footprint ""
		(layer "F.Cu")
		(at 184.531 -65.024)
		(property "Reference" "R4D67"
			(at 0 0 0)
			(layer "F.SilkS")
			(hide yes)
			(effects
				(font
					(size 1.27 1.27)
				)
			)
		)
		(property "Value" ""
			(at 0 0 0)
			(layer "F.Fab")
			(effects
				(font
					(size 1.27 1.27)
				)
			)
		)
		(duplicate_pad_numbers_are_jumpers no)
		(fp_rect
			(start -0.2794 0.9906)
			(end 0.2794 -0.1016)
			(stroke
				(width 0)
				(type default)
			)
			(fill no)
			(layer "F.CrtYd")
		)
		(fp_line
			(start -0.2794 -0.1016)
			(end -0.2794 0.9906)
			(stroke
				(width 0.1)
				(type default)
			)
			(layer "F.Fab")
		)
		(fp_line
			(start -0.2794 0.9906)
			(end 0.2794 0.9906)
			(stroke
				(width 0.1)
				(type default)
			)
			(layer "F.Fab")
		)
		(fp_line
			(start 0.2794 -0.1016)
			(end -0.2794 -0.1016)
			(stroke
				(width 0.1)
				(type default)
			)
			(layer "F.Fab")
		)
		(fp_line
			(start 0.2794 0.9906)
			(end 0.2794 -0.1016)
			(stroke
				(width 0.1)
				(type default)
			)
			(layer "F.Fab")
		)
		(pad "1" smd rect
			(at 0 0)
			(size 0.508 0.508)
			(layers "F.Cu" "F.Mask" "F.Paste")
			(net "SVID_VALERT_VCCIN_CPU0")
		)
		(pad "2" smd rect
			(at 0 0.889)
			(size 0.508 0.508)
			(layers "F.Cu" "F.Mask" "F.Paste")
			(net "SVID_ALERT0_CPU0_R_N")
		)
		(zone
			(layer "F.Cu")
			(hatch none 0.5)
			(connect_pads
				(clearance 0)
			)
			(min_thickness 0.25)
			(keepout
				(tracks allowed)
				(vias not_allowed)
				(pads allowed)
				(copperpour not_allowed)
				(footprints allowed)
			)
			(placement
				(enabled no)
				(sheetname "")
			)
			(fill
				(thermal_gap 0.5)
				(thermal_bridge_width 0.5)
				(island_removal_mode 0)
			)
			(polygon
				(pts
					(xy 184.277 -64.389) (xy 184.785 -64.389) (xy 184.785 -64.77) (xy 184.277 -64.77)
				)
			)
		)
		(zone
			(layer "F.Cu")
			(hatch none 0.5)
			(connect_pads
				(clearance 0)
			)
			(min_thickness 0.25)
			(keepout
				(tracks not_allowed)
				(vias allowed)
				(pads allowed)
				(copperpour not_allowed)
				(footprints allowed)
			)
			(placement
				(enabled no)
				(sheetname "")
			)
			(fill
				(thermal_gap 0.5)
				(thermal_bridge_width 0.5)
				(island_removal_mode 0)
			)
			(polygon
				(pts
					(xy 184.277 -64.389) (xy 184.785 -64.389) (xy 184.785 -64.77) (xy 184.277 -64.77)
				)
			)
		)
	)
	(footprint ""
		(layer "F.Cu")
		(at 477.8756 -48.9839)
		(property "Reference" "R9E7"
			(at 0 0 0)
			(layer "F.SilkS")
			(hide yes)
			(effects
				(font
					(size 1.27 1.27)
				)
			)
		)
		(property "Value" ""
			(at 0 0 0)
			(layer "F.Fab")
			(effects
				(font
					(size 1.27 1.27)
				)
			)
		)
		(duplicate_pad_numbers_are_jumpers no)
		(fp_poly
			(pts
				(xy -0.2794 -0.1016) (xy 0.2794 -0.1016) (xy 0.2794 0.9906) (xy -0.2794 0.9906)
			)
			(stroke
				(width 0)
				(type default)
			)
			(fill no)
			(layer "F.CrtYd")
		)
		(fp_line
			(start -0.2794 -0.1016)
			(end -0.2794 0.9906)
			(stroke
				(width 0.1)
				(type default)
			)
			(layer "F.Fab")
		)
		(fp_line
			(start -0.2794 0.9906)
			(end 0.2794 0.9906)
			(stroke
				(width 0.1)
				(type default)
			)
			(layer "F.Fab")
		)
		(fp_line
			(start 0.2794 -0.1016)
			(end -0.2794 -0.1016)
			(stroke
				(width 0.1)
				(type default)
			)
			(layer "F.Fab")
		)
		(fp_line
			(start 0.2794 0.9906)
			(end 0.2794 -0.1016)
			(stroke
				(width 0.1)
				(type default)
			)
			(layer "F.Fab")
		)
		(pad "1" smd rect
			(at 0 0)
			(size 0.508 0.508)
			(layers "F.Cu" "F.Mask" "F.Paste")
			(net "P3V3_STBY")
		)
		(pad "2" smd rect
			(at 0 0.889)
			(size 0.508 0.508)
			(layers "F.Cu" "F.Mask" "F.Paste")
			(net "IRQ_LOM_ALERT_N")
		)
		(zone
			(layer "F.Cu")
			(hatch none 0.5)
			(connect_pads
				(clearance 0)
			)
			(min_thickness 0.25)
			(keepout
				(tracks allowed)
				(vias not_allowed)
				(pads allowed)
				(copperpour not_allowed)
				(footprints allowed)
			)
			(placement
				(enabled no)
				(sheetname "")
			)
			(fill
				(thermal_gap 0.5)
				(thermal_bridge_width 0.5)
				(island_removal_mode 0)
			)
			(polygon
				(pts
					(xy 477.6216 -48.7299) (xy 478.1296 -48.7299) (xy 478.1296 -48.3489) (xy 477.6216 -48.3489)
				)
			)
		)
		(zone
			(layer "F.Cu")
			(hatch none 0.5)
			(connect_pads
				(clearance 0)
			)
			(min_thickness 0.25)
			(keepout
				(tracks not_allowed)
				(vias allowed)
				(pads allowed)
				(copperpour not_allowed)
				(footprints allowed)
			)
			(placement
				(enabled no)
				(sheetname "")
			)
			(fill
				(thermal_gap 0.5)
				(thermal_bridge_width 0.5)
				(island_removal_mode 0)
			)
			(polygon
				(pts
					(xy 477.6216 -48.3489) (xy 478.1296 -48.3489) (xy 478.1296 -48.7299) (xy 477.6216 -48.7299)
				)
			)
		)
	)
	(footprint ""
		(layer "F.Cu")
		(at 346.446094 -6.392418 -90)
		(property "Reference" "EU7G2"
			(at -5.112512 -1.254506 0)
			(unlocked yes)
			(layer "F.SilkS")
			(effects
				(font
					(size 0.7874 0.5842)
					(thickness 0.1524)
				)
			)
		)
		(property "Value" ""
			(at 0 0 270)
			(layer "F.Fab")
			(effects
				(font
					(size 1.27 1.27)
				)
			)
		)
		(duplicate_pad_numbers_are_jumpers no)
		(fp_line
			(start -3.0099 3.429)
			(end -3.0099 -3.5052)
			(stroke
				(width 0.1524)
				(type default)
			)
			(layer "F.SilkS")
		)
		(fp_line
			(start 2.9718 3.429)
			(end -3.0099 3.429)
			(stroke
				(width 0.1524)
				(type default)
			)
			(layer "F.SilkS")
		)
		(fp_line
			(start -3.0099 -3.5052)
			(end 2.9718 -3.5052)
			(stroke
				(width 0.1524)
				(type default)
			)
			(layer "F.SilkS")
		)
		(fp_line
			(start 2.9718 -3.5052)
			(end 2.9718 3.429)
			(stroke
				(width 0.1524)
				(type default)
			)
			(layer "F.SilkS")
		)
		(fp_circle
			(center -3.057398 -2.678684)
			(end -3.057398 -2.805684)
			(stroke
				(width 0.254)
				(type default)
			)
			(fill no)
			(layer "F.SilkS")
		)
		(fp_poly
			(pts
				(xy -2.9972 -3.4925) (xy -2.9972 -2.6924) (xy -2.1971 -3.4925)
			)
			(stroke
				(width 0)
				(type default)
			)
			(fill yes)
			(layer "F.SilkS")
		)
		(fp_poly
			(pts
				(xy -2.549906 -3.050032) (xy -2.549906 3.050032) (xy 2.549906 3.050032) (xy 2.549906 -3.050032)
			)
			(stroke
				(width 0)
				(type default)
			)
			(fill no)
			(layer "F.CrtYd")
		)
		(fp_line
			(start -2.549906 3.050032)
			(end -2.549906 -3.050032)
			(stroke
				(width 0.1)
				(type default)
			)
			(layer "F.Fab")
		)
		(fp_line
			(start 2.549906 3.050032)
			(end -2.549906 3.050032)
			(stroke
				(width 0.1)
				(type default)
			)
			(layer "F.Fab")
		)
		(fp_line
			(start -2.549906 -3.050032)
			(end 2.549906 -3.050032)
			(stroke
				(width 0.1)
				(type default)
			)
			(layer "F.Fab")
		)
		(fp_line
			(start 2.549906 -3.050032)
			(end 2.549906 3.050032)
			(stroke
				(width 0.1)
				(type default)
			)
			(layer "F.Fab")
		)
		(fp_circle
			(center -3.057398 -2.678684)
			(end -3.057398 -2.805684)
			(stroke
				(width 0.254)
				(type default)
			)
			(fill no)
			(layer "F.Fab")
		)
		(pad "1" smd rect
			(at -2.39522 -2.279904 270)
			(size 0.7112 0.254)
			(layers "F.Cu" "F.Mask" "F.Paste")
			(net "PVDDQ_ABC")
		)
		(pad "2" smd rect
			(at -2.39522 -1.83007 270)
			(size 0.7112 0.254)
			(layers "F.Cu" "F.Mask" "F.Paste")
			(net "GND")
		)
		(pad "3" smd rect
			(at -2.39522 -1.379982 270)
			(size 0.7112 0.254)
			(layers "F.Cu" "F.Mask" "F.Paste")
			(net "VR_PVDDQ_ABC_PH1_VCIN")
		)
		(pad "4" smd rect
			(at -2.39522 -0.929894 270)
			(size 0.7112 0.254)
			(layers "F.Cu" "F.Mask" "F.Paste")
			(net "P5V_STBY")
		)
		(pad "5" smd rect
			(at -2.39522 -0.48006 270)
			(size 0.7112 0.254)
			(layers "F.Cu" "F.Mask" "F.Paste")
			(net "GND")
		)
		(pad "6" smd rect
			(at -2.39522 -0.029972 270)
			(size 0.7112 0.254)
			(layers "F.Cu" "F.Mask" "F.Paste")
			(net "TP_PVDDQ_ABC_PH1_GL_0")
		)
		(pad "7" smd custom
			(at 0.016764 1.145032 270)
			(size 0.53975 0.53975)
			(layers "F.Cu" "F.Mask" "F.Paste")
			(net "GND")
			(options
				(clearance outline)
				(anchor circle)
			)
			(primitives
				(gr_poly
					(pts
						(xy -2.7051 1.0795) (xy -2.7051 -0.3683) (xy -0.9271 -0.3683) (xy -0.9271 -1.0795) (xy 2.7051 -1.0795)
						(xy 2.7051 1.0795)
					)
					(width 0)
					(fill yes)
				)
			)
		)
		(pad "10" smd rect
			(at -0.008382 2.874772 270)
			(size 4.3434 0.6096)
			(layers "F.Cu" "F.Mask" "F.Paste")
			(net "VR_PVDDQ_ABC_PH1_SW")
		)
		(pad "25" smd rect
			(at 1.548384 -1.283208 270)
			(size 2.3368 2.0066)
			(layers "F.Cu" "F.Mask" "F.Paste")
			(net "VR_FET_SW_P12V_STBY_PVDDQ_ABC")
		)
		(pad "30" smd rect
			(at 2.050034 -2.895092 270)
			(size 0.254 0.7112)
			(layers "F.Cu" "F.Mask" "F.Paste")
			(net "VR_FET_SW_P12V_STBY_PVDDQ_ABC")
		)
		(pad "31" smd rect
			(at 1.599946 -2.895092 270)
			(size 0.254 0.7112)
			(layers "F.Cu" "F.Mask" "F.Paste")
			(net "Net_368")
		)
		(pad "32" smd rect
			(at 1.150112 -2.895092 270)
			(size 0.254 0.7112)
			(layers "F.Cu" "F.Mask" "F.Paste")
			(net "VR_PVDDQ_ABC_PH1_PHASE")
		)
		(pad "33" smd rect
			(at 0.700024 -2.895092 270)
			(size 0.254 0.7112)
			(layers "F.Cu" "F.Mask" "F.Paste")
			(net "VR_PVDDQ_ABC_PH1_BOOT_R")
		)
		(pad "34" smd rect
			(at 0.249936 -2.895092 270)
			(size 0.254 0.7112)
			(layers "F.Cu" "F.Mask" "F.Paste")
			(net "VR_PVDDQ_ABC_PWM1")
		)
		(pad "35" smd rect
			(at -0.199898 -2.895092 270)
			(size 0.254 0.7112)
			(layers "F.Cu" "F.Mask" "F.Paste")
			(net "P5V_STBY")
		)
		(pad "36" smd rect
			(at -0.649986 -2.895092 270)
			(size 0.254 0.7112)
			(layers "F.Cu" "F.Mask" "F.Paste")
			(net "A_TSENSE_PVDDQ_ABC")
		)
		(pad "37" smd rect
			(at -1.100074 -2.895092 270)
			(size 0.254 0.7112)
			(layers "F.Cu" "F.Mask" "F.Paste")
			(net "VR_PVDDQ_ABC_PH1_OCSET")
		)
		(pad "38" smd rect
			(at -1.549908 -2.895092 270)
			(size 0.254 0.7112)
			(layers "F.Cu" "F.Mask" "F.Paste")
			(net "ISENSE_PVDDQ_ABC_PH1_IMON")
		)
		(pad "39" smd rect
			(at -1.999996 -2.895092 270)
			(size 0.254 0.7112)
			(layers "F.Cu" "F.Mask" "F.Paste")
			(net "VR_PVDDQ_ABC_AIREF1")
		)
		(pad "40" smd rect
			(at -0.871728 -1.283208 270)
			(size 1.8034 2.0066)
			(layers "F.Cu" "F.Mask" "F.Paste")
			(net "GND")
		)
		(pad "41" smd rect
			(at -1.533906 0.247904 270)
			(size 0.508 0.3556)
			(layers "F.Cu" "F.Mask" "F.Paste")
			(net "TP_PVDDQ_ABC_PH1_GL_1")
		)
	)
	(footprint ""
		(layer "F.Cu")
		(at 14.224 -75.311 180)
		(property "Reference" "R1D36"
			(at 0 0 180)
			(layer "F.SilkS")
			(hide yes)
			(effects
				(font
					(size 1.27 1.27)
				)
			)
		)
		(property "Value" ""
			(at 0 0 180)
			(layer "F.Fab")
			(effects
				(font
					(size 1.27 1.27)
				)
			)
		)
		(duplicate_pad_numbers_are_jumpers no)
		(fp_rect
			(start -0.2794 -0.1016)
			(end 0.2794 0.9906)
			(stroke
				(width 0)
				(type default)
			)
			(fill no)
			(layer "F.CrtYd")
		)
		(fp_line
			(start 0.2794 0.9906)
			(end 0.2794 -0.1016)
			(stroke
				(width 0.1)
				(type default)
			)
			(layer "F.Fab")
		)
		(fp_line
			(start 0.2794 -0.1016)
			(end -0.2794 -0.1016)
			(stroke
				(width 0.1)
				(type default)
			)
			(layer "F.Fab")
		)
		(fp_line
			(start -0.2794 0.9906)
			(end 0.2794 0.9906)
			(stroke
				(width 0.1)
				(type default)
			)
			(layer "F.Fab")
		)
		(fp_line
			(start -0.2794 -0.1016)
			(end -0.2794 0.9906)
			(stroke
				(width 0.1)
				(type default)
			)
			(layer "F.Fab")
		)
		(pad "1" smd rect
			(at 0 0 180)
			(size 0.508 0.508)
			(layers "F.Cu" "F.Mask" "F.Paste")
			(net "P12V_STBY")
		)
		(pad "2" smd rect
			(at 0 0.889 180)
			(size 0.508 0.508)
			(layers "F.Cu" "F.Mask" "F.Paste")
			(net "A_HSC_VOUT")
		)
		(zone
			(layer "F.Cu")
			(hatch none 0.5)
			(connect_pads
				(clearance 0)
			)
			(min_thickness 0.25)
			(keepout
				(tracks allowed)
				(vias not_allowed)
				(pads allowed)
				(copperpour not_allowed)
				(footprints allowed)
			)
			(placement
				(enabled no)
				(sheetname "")
			)
			(fill
				(thermal_gap 0.5)
				(thermal_bridge_width 0.5)
				(island_removal_mode 0)
			)
			(polygon
				(pts
					(xy 14.478 -75.565) (xy 14.478 -75.946) (xy 13.97 -75.946) (xy 13.97 -75.565)
				)
			)
		)
		(zone
			(layer "F.Cu")
			(hatch none 0.5)
			(connect_pads
				(clearance 0)
			)
			(min_thickness 0.25)
			(keepout
				(tracks not_allowed)
				(vias allowed)
				(pads allowed)
				(copperpour not_allowed)
				(footprints allowed)
			)
			(placement
				(enabled no)
				(sheetname "")
			)
			(fill
				(thermal_gap 0.5)
				(thermal_bridge_width 0.5)
				(island_removal_mode 0)
			)
			(polygon
				(pts
					(xy 14.478 -75.565) (xy 14.478 -75.946) (xy 13.97 -75.946) (xy 13.97 -75.565)
				)
			)
		)
	)
	(footprint ""
		(layer "F.Cu")
		(at 184.421272 -9.119108 90)
		(property "Reference" "C4G5"
			(at 0 0 90)
			(layer "F.SilkS")
			(hide yes)
			(effects
				(font
					(size 1.27 1.27)
				)
			)
		)
		(property "Value" "*"
			(at -0.0762 -6.2357 90)
			(unlocked yes)
			(layer "F.Fab")
			(hide yes)
			(effects
				(font
					(size 1.27 1.016)
					(thickness 0.1524)
				)
			)
		)
		(property "Device Type" "SC22U16V5MX-4-GP_SMD-BCG5-SC22A"
			(at -0.0762 -8.2677 90)
			(unlocked yes)
			(layer "F.Fab")
			(hide yes)
			(effects
				(font
					(size 1.27 1.016)
					(thickness 0.1524)
				)
			)
		)
		(duplicate_pad_numbers_are_jumpers no)
		(fp_line
			(start 0.635 0)
			(end -0.635 0)
			(stroke
				(width 0.508)
				(type default)
			)
			(layer "F.SilkS")
		)
		(fp_rect
			(start -0.9652 1.778)
			(end 0.9652 -1.778)
			(stroke
				(width 0)
				(type default)
			)
			(fill no)
			(layer "F.CrtYd")
		)
		(fp_poly
			(pts
				(xy -0.9652 -1.778) (xy 0.9652 -1.778) (xy 0.9652 1.778) (xy -0.9652 1.778)
			)
			(stroke
				(width 0)
				(type default)
			)
			(fill no)
			(layer "F.Fab")
		)
		(pad "1" smd rect
			(at 0 -0.9652 90)
			(size 1.397 1.143)
			(layers "F.Cu" "F.Mask" "F.Paste")
			(net "VR_FET_SW_P12V_STBY_PVPP_GHJ")
		)
		(pad "2" smd rect
			(at 0 0.9652 90)
			(size 1.397 1.143)
			(layers "F.Cu" "F.Mask" "F.Paste")
			(net "GND")
		)
	)
	(footprint ""
		(layer "F.Cu")
		(at 408.520392 -10.916666)
		(property "Reference" "C8G8"
			(at 0 0 0)
			(layer "F.SilkS")
			(hide yes)
			(effects
				(font
					(size 1.27 1.27)
				)
			)
		)
		(property "Value" ""
			(at 0 0 0)
			(layer "F.Fab")
			(effects
				(font
					(size 1.27 1.27)
				)
			)
		)
		(duplicate_pad_numbers_are_jumpers no)
		(fp_rect
			(start -0.3048 0.9906)
			(end 0.3048 -0.1016)
			(stroke
				(width 0)
				(type default)
			)
			(fill no)
			(layer "F.CrtYd")
		)
		(fp_line
			(start -0.3048 -0.1016)
			(end -0.3048 0.9906)
			(stroke
				(width 0.1)
				(type default)
			)
			(layer "F.Fab")
		)
		(fp_line
			(start -0.3048 0.9906)
			(end 0.3048 0.9906)
			(stroke
				(width 0.1)
				(type default)
			)
			(layer "F.Fab")
		)
		(fp_line
			(start 0.3048 -0.1016)
			(end -0.3048 -0.1016)
			(stroke
				(width 0.1)
				(type default)
			)
			(layer "F.Fab")
		)
		(fp_line
			(start 0.3048 0.9906)
			(end 0.3048 -0.1016)
			(stroke
				(width 0.1)
				(type default)
			)
			(layer "F.Fab")
		)
		(pad "1" smd rect
			(at 0 0)
			(size 0.508 0.508)
			(layers "F.Cu" "F.Mask" "F.Paste")
			(net "P3E_CPU0_PE2_SS_TXP<1>")
		)
		(pad "2" smd rect
			(at 0 0.889)
			(size 0.508 0.508)
			(layers "F.Cu" "F.Mask" "F.Paste")
			(net "P3E_CPU0_PE2_SS_C_TXP<1>")
		)
		(zone
			(layer "F.Cu")
			(hatch none 0.5)
			(connect_pads
				(clearance 0)
			)
			(min_thickness 0.25)
			(keepout
				(tracks not_allowed)
				(vias allowed)
				(pads allowed)
				(copperpour not_allowed)
				(footprints allowed)
			)
			(placement
				(enabled no)
				(sheetname "")
			)
			(fill
				(thermal_gap 0.5)
				(thermal_bridge_width 0.5)
				(island_removal_mode 0)
			)
			(polygon
				(pts
					(xy 408.266392 -10.281666) (xy 408.774392 -10.281666) (xy 408.774392 -10.662666) (xy 408.266392 -10.662666)
				)
			)
		)
		(zone
			(layer "F.Cu")
			(hatch none 0.5)
			(connect_pads
				(clearance 0)
			)
			(min_thickness 0.25)
			(keepout
				(tracks allowed)
				(vias not_allowed)
				(pads allowed)
				(copperpour not_allowed)
				(footprints allowed)
			)
			(placement
				(enabled no)
				(sheetname "")
			)
			(fill
				(thermal_gap 0.5)
				(thermal_bridge_width 0.5)
				(island_removal_mode 0)
			)
			(polygon
				(pts
					(xy 408.266392 -10.281666) (xy 408.774392 -10.281666) (xy 408.774392 -10.662666) (xy 408.266392 -10.662666)
				)
			)
		)
	)
	(footprint ""
		(layer "F.Cu")
		(at 22.225 -81.788)
		(property "Reference" "R1D19"
			(at 0 0 0)
			(layer "F.SilkS")
			(hide yes)
			(effects
				(font
					(size 1.27 1.27)
				)
			)
		)
		(property "Value" ""
			(at 0 0 0)
			(layer "F.Fab")
			(effects
				(font
					(size 1.27 1.27)
				)
			)
		)
		(duplicate_pad_numbers_are_jumpers no)
		(fp_poly
			(pts
				(xy -0.2794 -0.1016) (xy 0.2794 -0.1016) (xy 0.2794 0.9906) (xy -0.2794 0.9906)
			)
			(stroke
				(width 0)
				(type default)
			)
			(fill no)
			(layer "F.CrtYd")
		)
		(fp_line
			(start -0.2794 -0.1016)
			(end -0.2794 0.9906)
			(stroke
				(width 0.1)
				(type default)
			)
			(layer "F.Fab")
		)
		(fp_line
			(start -0.2794 0.9906)
			(end 0.2794 0.9906)
			(stroke
				(width 0.1)
				(type default)
			)
			(layer "F.Fab")
		)
		(fp_line
			(start 0.2794 -0.1016)
			(end -0.2794 -0.1016)
			(stroke
				(width 0.1)
				(type default)
			)
			(layer "F.Fab")
		)
		(fp_line
			(start 0.2794 0.9906)
			(end 0.2794 -0.1016)
			(stroke
				(width 0.1)
				(type default)
			)
			(layer "F.Fab")
		)
		(pad "1" smd rect
			(at 0 0)
			(size 0.508 0.508)
			(layers "F.Cu" "F.Mask" "F.Paste")
			(net "A_HSC_HIGH")
		)
		(pad "2" smd rect
			(at 0 0.889)
			(size 0.508 0.508)
			(layers "F.Cu" "F.Mask" "F.Paste")
			(net "AGND_HSC")
		)
		(zone
			(layer "F.Cu")
			(hatch none 0.5)
			(connect_pads
				(clearance 0)
			)
			(min_thickness 0.25)
			(keepout
				(tracks allowed)
				(vias not_allowed)
				(pads allowed)
				(copperpour not_allowed)
				(footprints allowed)
			)
			(placement
				(enabled no)
				(sheetname "")
			)
			(fill
				(thermal_gap 0.5)
				(thermal_bridge_width 0.5)
				(island_removal_mode 0)
			)
			(polygon
				(pts
					(xy 21.971 -81.534) (xy 22.479 -81.534) (xy 22.479 -81.153) (xy 21.971 -81.153)
				)
			)
		)
		(zone
			(layer "F.Cu")
			(hatch none 0.5)
			(connect_pads
				(clearance 0)
			)
			(min_thickness 0.25)
			(keepout
				(tracks not_allowed)
				(vias allowed)
				(pads allowed)
				(copperpour not_allowed)
				(footprints allowed)
			)
			(placement
				(enabled no)
				(sheetname "")
			)
			(fill
				(thermal_gap 0.5)
				(thermal_bridge_width 0.5)
				(island_removal_mode 0)
			)
			(polygon
				(pts
					(xy 21.971 -81.153) (xy 22.479 -81.153) (xy 22.479 -81.534) (xy 21.971 -81.534)
				)
			)
		)
	)
	(footprint ""
		(layer "F.Cu")
		(at 410.7688 -99.3394 90)
		(property "Reference" "R2P12"
			(at 0 0 90)
			(layer "F.SilkS")
			(hide yes)
			(effects
				(font
					(size 1.27 1.27)
				)
			)
		)
		(property "Value" ""
			(at 0 0 90)
			(layer "F.Fab")
			(effects
				(font
					(size 1.27 1.27)
				)
			)
		)
		(duplicate_pad_numbers_are_jumpers no)
		(fp_poly
			(pts
				(xy -0.2794 -0.1016) (xy 0.2794 -0.1016) (xy 0.2794 0.9906) (xy -0.2794 0.9906)
			)
			(stroke
				(width 0)
				(type default)
			)
			(fill no)
			(layer "F.CrtYd")
		)
		(fp_line
			(start 0.2794 -0.1016)
			(end -0.2794 -0.1016)
			(stroke
				(width 0.1)
				(type default)
			)
			(layer "F.Fab")
		)
		(fp_line
			(start -0.2794 -0.1016)
			(end -0.2794 0.9906)
			(stroke
				(width 0.1)
				(type default)
			)
			(layer "F.Fab")
		)
		(fp_line
			(start 0.2794 0.9906)
			(end 0.2794 -0.1016)
			(stroke
				(width 0.1)
				(type default)
			)
			(layer "F.Fab")
		)
		(fp_line
			(start -0.2794 0.9906)
			(end 0.2794 0.9906)
			(stroke
				(width 0.1)
				(type default)
			)
			(layer "F.Fab")
		)
		(pad "1" smd rect
			(at 0 0 90)
			(size 0.508 0.508)
			(layers "F.Cu" "F.Mask" "F.Paste")
			(net "IRQ_DIMM_SAVE_LVT3_N")
		)
		(pad "2" smd rect
			(at 0 0.889 90)
			(size 0.508 0.508)
			(layers "F.Cu" "F.Mask" "F.Paste")
			(net "FM_ADR_SMI_GPIO_N")
		)
		(zone
			(layer "F.Cu")
			(hatch none 0.5)
			(connect_pads
				(clearance 0)
			)
			(min_thickness 0.25)
			(keepout
				(tracks allowed)
				(vias not_allowed)
				(pads allowed)
				(copperpour not_allowed)
				(footprints allowed)
			)
			(placement
				(enabled no)
				(sheetname "")
			)
			(fill
				(thermal_gap 0.5)
				(thermal_bridge_width 0.5)
				(island_removal_mode 0)
			)
			(polygon
				(pts
					(xy 411.0228 -99.0854) (xy 411.0228 -99.5934) (xy 411.4038 -99.5934) (xy 411.4038 -99.0854)
				)
			)
		)
		(zone
			(layer "F.Cu")
			(hatch none 0.5)
			(connect_pads
				(clearance 0)
			)
			(min_thickness 0.25)
			(keepout
				(tracks not_allowed)
				(vias allowed)
				(pads allowed)
				(copperpour not_allowed)
				(footprints allowed)
			)
			(placement
				(enabled no)
				(sheetname "")
			)
			(fill
				(thermal_gap 0.5)
				(thermal_bridge_width 0.5)
				(island_removal_mode 0)
			)
			(polygon
				(pts
					(xy 411.4038 -99.0854) (xy 411.4038 -99.5934) (xy 411.0228 -99.5934) (xy 411.0228 -99.0854)
				)
			)
		)
	)
	(footprint ""
		(layer "F.Cu")
		(at 391.16 -0.254)
		(property "Reference" "R8G9"
			(at 0 0 0)
			(layer "F.SilkS")
			(hide yes)
			(effects
				(font
					(size 1.27 1.27)
				)
			)
		)
		(property "Value" ""
			(at 0 0 0)
			(layer "F.Fab")
			(effects
				(font
					(size 1.27 1.27)
				)
			)
		)
		(duplicate_pad_numbers_are_jumpers no)
		(fp_poly
			(pts
				(xy -0.2794 -0.1016) (xy 0.2794 -0.1016) (xy 0.2794 0.9906) (xy -0.2794 0.9906)
			)
			(stroke
				(width 0)
				(type default)
			)
			(fill no)
			(layer "F.CrtYd")
		)
		(fp_line
			(start -0.2794 -0.1016)
			(end -0.2794 0.9906)
			(stroke
				(width 0.1)
				(type default)
			)
			(layer "F.Fab")
		)
		(fp_line
			(start -0.2794 0.9906)
			(end 0.2794 0.9906)
			(stroke
				(width 0.1)
				(type default)
			)
			(layer "F.Fab")
		)
		(fp_line
			(start 0.2794 -0.1016)
			(end -0.2794 -0.1016)
			(stroke
				(width 0.1)
				(type default)
			)
			(layer "F.Fab")
		)
		(fp_line
			(start 0.2794 0.9906)
			(end 0.2794 -0.1016)
			(stroke
				(width 0.1)
				(type default)
			)
			(layer "F.Fab")
		)
		(pad "1" smd rect
			(at 0 0)
			(size 0.508 0.508)
			(layers "F.Cu" "F.Mask" "F.Paste")
			(net "JTAG_PCH_GBE_TRST_N")
		)
		(pad "2" smd rect
			(at 0 0.889)
			(size 0.508 0.508)
			(layers "F.Cu" "F.Mask" "F.Paste")
			(net "JTAG_TRST_N")
		)
		(zone
			(layer "F.Cu")
			(hatch none 0.5)
			(connect_pads
				(clearance 0)
			)
			(min_thickness 0.25)
			(keepout
				(tracks allowed)
				(vias not_allowed)
				(pads allowed)
				(copperpour not_allowed)
				(footprints allowed)
			)
			(placement
				(enabled no)
				(sheetname "")
			)
			(fill
				(thermal_gap 0.5)
				(thermal_bridge_width 0.5)
				(island_removal_mode 0)
			)
			(polygon
				(pts
					(xy 390.906 0) (xy 391.414 0) (xy 391.414 0.381) (xy 390.906 0.381)
				)
			)
		)
		(zone
			(layer "F.Cu")
			(hatch none 0.5)
			(connect_pads
				(clearance 0)
			)
			(min_thickness 0.25)
			(keepout
				(tracks not_allowed)
				(vias allowed)
				(pads allowed)
				(copperpour not_allowed)
				(footprints allowed)
			)
			(placement
				(enabled no)
				(sheetname "")
			)
			(fill
				(thermal_gap 0.5)
				(thermal_bridge_width 0.5)
				(island_removal_mode 0)
			)
			(polygon
				(pts
					(xy 390.906 0.381) (xy 391.414 0.381) (xy 391.414 0) (xy 390.906 0)
				)
			)
		)
	)
	(footprint ""
		(layer "F.Cu")
		(at 195.58 -3.321812 90)
		(property "Reference" "C4G19"
			(at 0 0 90)
			(layer "F.SilkS")
			(hide yes)
			(effects
				(font
					(size 1.27 1.27)
				)
			)
		)
		(property "Value" ""
			(at 0 0 90)
			(layer "F.Fab")
			(effects
				(font
					(size 1.27 1.27)
				)
			)
		)
		(duplicate_pad_numbers_are_jumpers no)
		(fp_poly
			(pts
				(xy 0.3048 -0.1016) (xy 0.3048 0.9906) (xy -0.3048 0.9906) (xy -0.3048 -0.1016)
			)
			(stroke
				(width 0)
				(type default)
			)
			(fill no)
			(layer "F.CrtYd")
		)
		(fp_line
			(start 0.3048 -0.1016)
			(end -0.3048 -0.1016)
			(stroke
				(width 0.1)
				(type default)
			)
			(layer "F.Fab")
		)
		(fp_line
			(start -0.3048 -0.1016)
			(end -0.3048 0.9906)
			(stroke
				(width 0.1)
				(type default)
			)
			(layer "F.Fab")
		)
		(fp_line
			(start 0.3048 0.9906)
			(end 0.3048 -0.1016)
			(stroke
				(width 0.1)
				(type default)
			)
			(layer "F.Fab")
		)
		(fp_line
			(start -0.3048 0.9906)
			(end 0.3048 0.9906)
			(stroke
				(width 0.1)
				(type default)
			)
			(layer "F.Fab")
		)
		(pad "1" smd rect
			(at 0 0 90)
			(size 0.508 0.508)
			(layers "F.Cu" "F.Mask" "F.Paste")
			(net "M_C_VREF")
		)
		(pad "2" smd rect
			(at 0 0.889 90)
			(size 0.508 0.508)
			(layers "F.Cu" "F.Mask" "F.Paste")
			(net "GND")
		)
		(zone
			(layer "F.Cu")
			(hatch none 0.5)
			(connect_pads
				(clearance 0)
			)
			(min_thickness 0.25)
			(keepout
				(tracks allowed)
				(vias not_allowed)
				(pads allowed)
				(copperpour not_allowed)
				(footprints allowed)
			)
			(placement
				(enabled no)
				(sheetname "")
			)
			(fill
				(thermal_gap 0.5)
				(thermal_bridge_width 0.5)
				(island_removal_mode 0)
			)
			(polygon
				(pts
					(xy 195.834 -3.067812) (xy 195.834 -3.575812) (xy 196.215 -3.575812) (xy 196.215 -3.067812)
				)
			)
		)
		(zone
			(layer "F.Cu")
			(hatch none 0.5)
			(connect_pads
				(clearance 0)
			)
			(min_thickness 0.25)
			(keepout
				(tracks not_allowed)
				(vias allowed)
				(pads allowed)
				(copperpour not_allowed)
				(footprints allowed)
			)
			(placement
				(enabled no)
				(sheetname "")
			)
			(fill
				(thermal_gap 0.5)
				(thermal_bridge_width 0.5)
				(island_removal_mode 0)
			)
			(polygon
				(pts
					(xy 196.215 -3.067812) (xy 196.215 -3.575812) (xy 195.834 -3.575812) (xy 195.834 -3.067812)
				)
			)
		)
	)
	(footprint ""
		(layer "F.Cu")
		(at 229.23881 -164.911786 90)
		(property "Reference" "T1D14"
			(at 0 0 90)
			(layer "F.SilkS")
			(hide yes)
			(effects
				(font
					(size 1.27 1.27)
				)
			)
		)
		(property "Value" "*"
			(at -3.4036 -4.46405 90)
			(unlocked yes)
			(layer "F.Fab")
			(hide yes)
			(effects
				(font
					(size 0.889 0.889)
					(thickness 0.1524)
				)
			)
		)
		(property "Device Type" "TEST-PAD-12P-1-GP-U_DISCRET-GBA"
			(at -3.4036 -5.98805 90)
			(unlocked yes)
			(layer "F.Fab")
			(hide yes)
			(effects
				(font
					(size 0.889 0.889)
					(thickness 0.1524)
				)
			)
		)
		(duplicate_pad_numbers_are_jumpers no)
		(fp_line
			(start 2.3622 -4.826)
			(end 2.3622 3.4798)
			(stroke
				(width 0.1524)
				(type default)
			)
			(layer "F.SilkS")
		)
		(fp_line
			(start -2.3876 -4.826)
			(end 2.3622 -4.826)
			(stroke
				(width 0.1524)
				(type default)
			)
			(layer "F.SilkS")
		)
		(fp_line
			(start 2.3622 3.4798)
			(end -2.3876 3.4798)
			(stroke
				(width 0.1524)
				(type default)
			)
			(layer "F.SilkS")
		)
		(fp_line
			(start -2.3876 3.4798)
			(end -2.3876 -4.826)
			(stroke
				(width 0.1524)
				(type default)
			)
			(layer "F.SilkS")
		)
		(fp_rect
			(start -2.6416 3.7338)
			(end 2.6162 -5.08)
			(stroke
				(width 0)
				(type default)
			)
			(fill no)
			(layer "F.CrtYd")
		)
		(fp_rect
			(start -2.6416 3.7338)
			(end 2.6162 -5.08)
			(stroke
				(width 0)
				(type default)
			)
			(fill no)
			(layer "F.Fab")
		)
		(pad "1" smd circle
			(at 0.496824 -1.301496 90)
			(size 0.6604 0.6604)
			(layers "F.Cu" "F.Mask" "F.Paste")
			(net "L1_85OHM_10INCH_DN")
		)
		(pad "2" smd circle
			(at -0.503936 -1.301496 90)
			(size 0.6604 0.6604)
			(layers "F.Cu" "F.Mask" "F.Paste")
			(net "L1_85OHM_10INCH_DP")
		)
		(pad "3" smd custom
			(at -0.00889 0.370078 90)
			(size 0.74295 0.74295)
			(layers "F.Cu" "F.Mask" "F.Paste")
			(net "GND")
			(options
				(clearance outline)
				(anchor circle)
			)
			(primitives
				(gr_poly
					(pts
						(xy -2.1209 1.4859) (xy 2.1209 1.4859) (xy 2.1209 -1.4859) (xy 1.08585 -1.4859) (xy 1.08585 -0.4699)
						(xy -1.08585 -0.4699) (xy -1.08585 -1.4859) (xy -2.1209 -1.4859)
					)
					(width 0)
					(fill yes)
				)
			)
		)
		(pad "4" thru_hole circle
			(at 1.266444 -3.851656 90)
			(size 1.4478 1.4478)
			(drill 1.0414)
			(layers "*.Cu" "*.Mask")
			(remove_unused_layers no)
			(net "GND")
			(clearance 0.1524)
			(thermal_gap 0.1524)
		)
		(pad "5" thru_hole circle
			(at -1.273556 -3.851656 90)
			(size 1.4478 1.4478)
			(drill 1.0414)
			(layers "*.Cu" "*.Mask")
			(remove_unused_layers no)
			(net "GND")
			(clearance 0.1524)
			(thermal_gap 0.1524)
		)
		(pad "6" thru_hole circle
			(at 1.266444 2.498344 90)
			(size 1.4478 1.4478)
			(drill 1.0414)
			(layers "*.Cu" "*.Mask")
			(remove_unused_layers no)
			(net "GND")
			(clearance 0.1524)
			(thermal_gap 0.1524)
		)
		(pad "7" thru_hole circle
			(at -1.273556 2.498344 90)
			(size 1.4478 1.4478)
			(drill 1.0414)
			(layers "*.Cu" "*.Mask")
			(remove_unused_layers no)
			(net "GND")
			(clearance 0.1524)
			(thermal_gap 0.1524)
		)
		(pad "8" thru_hole circle
			(at 1.27 -0.4572 90)
			(size 0.7112 0.7112)
			(drill 0.4064)
			(layers "*.Cu" "*.Mask")
			(remove_unused_layers no)
			(net "GND")
			(clearance 0.1016)
			(thermal_gap 0.1016)
		)
		(pad "9" thru_hole circle
			(at 1.27 0.762 90)
			(size 0.7112 0.7112)
			(drill 0.4064)
			(layers "*.Cu" "*.Mask")
			(remove_unused_layers no)
			(net "GND")
			(clearance 0.1016)
			(thermal_gap 0.1016)
		)
		(pad "10" thru_hole circle
			(at -0.0254 0.762 90)
			(size 0.7112 0.7112)
			(drill 0.4064)
			(layers "*.Cu" "*.Mask")
			(remove_unused_layers no)
			(net "GND")
			(clearance 0.1016)
			(thermal_gap 0.1016)
		)
		(pad "11" thru_hole circle
			(at -1.27 0.762 90)
			(size 0.7112 0.7112)
			(drill 0.4064)
			(layers "*.Cu" "*.Mask")
			(remove_unused_layers no)
			(net "GND")
			(clearance 0.1016)
			(thermal_gap 0.1016)
		)
		(pad "12" thru_hole circle
			(at -1.27 -0.4572 90)
			(size 0.7112 0.7112)
			(drill 0.4064)
			(layers "*.Cu" "*.Mask")
			(remove_unused_layers no)
			(net "GND")
			(clearance 0.1016)
			(thermal_gap 0.1016)
		)
	)
	(footprint ""
		(layer "F.Cu")
		(at 33.925002 -65.167764 90)
		(property "Reference" "EU1D4"
			(at 3.334766 -1.844802 0)
			(unlocked yes)
			(layer "F.SilkS")
			(effects
				(font
					(size 0.7874 0.5842)
					(thickness 0.1524)
				)
			)
		)
		(property "Value" ""
			(at 0 0 90)
			(layer "F.Fab")
			(effects
				(font
					(size 1.27 1.27)
				)
			)
		)
		(duplicate_pad_numbers_are_jumpers no)
		(fp_line
			(start 2.9718 -3.5052)
			(end 2.9718 3.429)
			(stroke
				(width 0.1524)
				(type default)
			)
			(layer "F.SilkS")
		)
		(fp_line
			(start -3.0099 -3.5052)
			(end 2.9718 -3.5052)
			(stroke
				(width 0.1524)
				(type default)
			)
			(layer "F.SilkS")
		)
		(fp_line
			(start 2.9718 3.429)
			(end -3.0099 3.429)
			(stroke
				(width 0.1524)
				(type default)
			)
			(layer "F.SilkS")
		)
		(fp_line
			(start -3.0099 3.429)
			(end -3.0099 -3.5052)
			(stroke
				(width 0.1524)
				(type default)
			)
			(layer "F.SilkS")
		)
		(fp_circle
			(center -3.057398 -2.678684)
			(end -3.057398 -2.551684)
			(stroke
				(width 0.254)
				(type default)
			)
			(fill no)
			(layer "F.SilkS")
		)
		(fp_poly
			(pts
				(xy -2.9972 -3.4925) (xy -2.9972 -2.6924) (xy -2.1971 -3.4925)
			)
			(stroke
				(width 0)
				(type default)
			)
			(fill yes)
			(layer "F.SilkS")
		)
		(fp_poly
			(pts
				(xy -2.549906 -3.050032) (xy -2.549906 3.050032) (xy 2.549906 3.050032) (xy 2.549906 -3.050032)
			)
			(stroke
				(width 0)
				(type default)
			)
			(fill no)
			(layer "F.CrtYd")
		)
		(fp_line
			(start 2.549906 -3.050032)
			(end 2.549906 3.050032)
			(stroke
				(width 0.1)
				(type default)
			)
			(layer "F.Fab")
		)
		(fp_line
			(start -2.549906 -3.050032)
			(end 2.549906 -3.050032)
			(stroke
				(width 0.1)
				(type default)
			)
			(layer "F.Fab")
		)
		(fp_line
			(start 2.549906 3.050032)
			(end -2.549906 3.050032)
			(stroke
				(width 0.1)
				(type default)
			)
			(layer "F.Fab")
		)
		(fp_line
			(start -2.549906 3.050032)
			(end -2.549906 -3.050032)
			(stroke
				(width 0.1)
				(type default)
			)
			(layer "F.Fab")
		)
		(fp_circle
			(center -3.057398 -2.678684)
			(end -3.057398 -2.551684)
			(stroke
				(width 0.254)
				(type default)
			)
			(fill no)
			(layer "F.Fab")
		)
		(pad "1" smd rect
			(at -2.39522 -2.279904 90)
			(size 0.7112 0.254)
			(layers "F.Cu" "F.Mask" "F.Paste")
			(net "PVCCIN_CPU1")
		)
		(pad "2" smd rect
			(at -2.39522 -1.83007 90)
			(size 0.7112 0.254)
			(layers "F.Cu" "F.Mask" "F.Paste")
			(net "GND")
		)
		(pad "3" smd rect
			(at -2.39522 -1.379982 90)
			(size 0.7112 0.254)
			(layers "F.Cu" "F.Mask" "F.Paste")
			(net "VR_PVCCIN_CPU1_PH2_VCIN")
		)
		(pad "4" smd rect
			(at -2.39522 -0.929894 90)
			(size 0.7112 0.254)
			(layers "F.Cu" "F.Mask" "F.Paste")
			(net "P5V_STBY")
		)
		(pad "5" smd rect
			(at -2.39522 -0.48006 90)
			(size 0.7112 0.254)
			(layers "F.Cu" "F.Mask" "F.Paste")
			(net "GND")
		)
		(pad "6" smd rect
			(at -2.39522 -0.029972 90)
			(size 0.7112 0.254)
			(layers "F.Cu" "F.Mask" "F.Paste")
			(net "TP_PVCCINC_CPU1_PH2_GL_0")
		)
		(pad "7" smd custom
			(at 0.016764 1.145032 90)
			(size 0.53975 0.53975)
			(layers "F.Cu" "F.Mask" "F.Paste")
			(net "GND")
			(options
				(clearance outline)
				(anchor circle)
			)
			(primitives
				(gr_poly
					(pts
						(xy -2.7051 1.0795) (xy -2.7051 -0.3683) (xy -0.9271 -0.3683) (xy -0.9271 -1.0795) (xy 2.7051 -1.0795)
						(xy 2.7051 1.0795)
					)
					(width 0)
					(fill yes)
				)
			)
		)
		(pad "10" smd rect
			(at -0.008382 2.874772 90)
			(size 4.3434 0.6096)
			(layers "F.Cu" "F.Mask" "F.Paste")
			(net "VR_PVCCIN_CPU1_PHASE2")
		)
		(pad "25" smd rect
			(at 1.548384 -1.283208 90)
			(size 2.3368 2.0066)
			(layers "F.Cu" "F.Mask" "F.Paste")
			(net "VR_FET_SW_P12V_STBY_PVCCIN_CPU1")
		)
		(pad "30" smd rect
			(at 2.050034 -2.895092 90)
			(size 0.254 0.7112)
			(layers "F.Cu" "F.Mask" "F.Paste")
			(net "VR_FET_SW_P12V_STBY_PVCCIN_CPU1")
		)
		(pad "31" smd rect
			(at 1.599946 -2.895092 90)
			(size 0.254 0.7112)
			(layers "F.Cu" "F.Mask" "F.Paste")
			(net "Net_357")
		)
		(pad "32" smd rect
			(at 1.150112 -2.895092 90)
			(size 0.254 0.7112)
			(layers "F.Cu" "F.Mask" "F.Paste")
			(net "VR_PVCCIN_CPU1_PH2_PHASE")
		)
		(pad "33" smd rect
			(at 0.700024 -2.895092 90)
			(size 0.254 0.7112)
			(layers "F.Cu" "F.Mask" "F.Paste")
			(net "VR_PVCCIN_CPU1_PH2_BOOT_R")
		)
		(pad "34" smd rect
			(at 0.249936 -2.895092 90)
			(size 0.254 0.7112)
			(layers "F.Cu" "F.Mask" "F.Paste")
			(net "VR_PVCCIN_CPU1_PWM2")
		)
		(pad "35" smd rect
			(at -0.199898 -2.895092 90)
			(size 0.254 0.7112)
			(layers "F.Cu" "F.Mask" "F.Paste")
			(net "P5V_STBY")
		)
		(pad "36" smd rect
			(at -0.649986 -2.895092 90)
			(size 0.254 0.7112)
			(layers "F.Cu" "F.Mask" "F.Paste")
			(net "A_TSENSE_PVCCIN_CPU1")
		)
		(pad "37" smd rect
			(at -1.100074 -2.895092 90)
			(size 0.254 0.7112)
			(layers "F.Cu" "F.Mask" "F.Paste")
			(net "VR_PVCCIN_CPU1_PH2_OCSET")
		)
		(pad "38" smd rect
			(at -1.549908 -2.895092 90)
			(size 0.254 0.7112)
			(layers "F.Cu" "F.Mask" "F.Paste")
			(net "ISENSE_PVCCIN_CPU1_PH2_IMON")
		)
		(pad "39" smd rect
			(at -1.999996 -2.895092 90)
			(size 0.254 0.7112)
			(layers "F.Cu" "F.Mask" "F.Paste")
			(net "VR_PVCCIN_CPU1_AIREF2")
		)
		(pad "40" smd rect
			(at -0.871728 -1.283208 90)
			(size 1.8034 2.0066)
			(layers "F.Cu" "F.Mask" "F.Paste")
			(net "GND")
		)
		(pad "41" smd rect
			(at -1.533906 0.247904 90)
			(size 0.508 0.3556)
			(layers "F.Cu" "F.Mask" "F.Paste")
			(net "TP_PVCCINC_CPU1_PH2_GL_1")
		)
	)
	(footprint ""
		(layer "F.Cu")
		(at 23.29434 -86.1568 180)
		(property "Reference" "RF7"
			(at -0.8382 -0.67818 180)
			(unlocked yes)
			(layer "F.SilkS")
			(effects
				(font
					(size 0.4064 0.254)
					(thickness 0.1524)
				)
				(justify left)
			)
		)
		(property "Value" ""
			(at 0 0 180)
			(layer "F.Fab")
			(effects
				(font
					(size 1.27 1.27)
				)
			)
		)
		(duplicate_pad_numbers_are_jumpers no)
		(fp_poly
			(pts
				(xy -0.2794 -0.1016) (xy 0.2794 -0.1016) (xy 0.2794 0.9906) (xy -0.2794 0.9906)
			)
			(stroke
				(width 0)
				(type default)
			)
			(fill no)
			(layer "F.CrtYd")
		)
		(fp_line
			(start 0.2794 0.9906)
			(end 0.2794 -0.1016)
			(stroke
				(width 0.1)
				(type default)
			)
			(layer "F.Fab")
		)
		(fp_line
			(start 0.2794 -0.1016)
			(end -0.2794 -0.1016)
			(stroke
				(width 0.1)
				(type default)
			)
			(layer "F.Fab")
		)
		(fp_line
			(start -0.2794 0.9906)
			(end 0.2794 0.9906)
			(stroke
				(width 0.1)
				(type default)
			)
			(layer "F.Fab")
		)
		(fp_line
			(start -0.2794 -0.1016)
			(end -0.2794 0.9906)
			(stroke
				(width 0.1)
				(type default)
			)
			(layer "F.Fab")
		)
		(pad "1" smd rect
			(at 0 0 180)
			(size 0.508 0.508)
			(layers "F.Cu" "F.Mask" "F.Paste")
			(net "VR_PVCCIN_CPU1_AIREF1")
		)
		(pad "2" smd rect
			(at 0 0.889 180)
			(size 0.508 0.508)
			(layers "F.Cu" "F.Mask" "F.Paste")
			(net "ISENSE_PVCCIN_CPU1_PH1_IMON")
		)
		(zone
			(layer "F.Cu")
			(hatch none 0.5)
			(connect_pads
				(clearance 0)
			)
			(min_thickness 0.25)
			(keepout
				(tracks not_allowed)
				(vias allowed)
				(pads allowed)
				(copperpour not_allowed)
				(footprints allowed)
			)
			(placement
				(enabled no)
				(sheetname "")
			)
			(fill
				(thermal_gap 0.5)
				(thermal_bridge_width 0.5)
				(island_removal_mode 0)
			)
			(polygon
				(pts
					(xy 23.54834 -86.7918) (xy 23.04034 -86.7918) (xy 23.04034 -86.4108) (xy 23.54834 -86.4108)
				)
			)
		)
		(zone
			(layer "F.Cu")
			(hatch none 0.5)
			(connect_pads
				(clearance 0)
			)
			(min_thickness 0.25)
			(keepout
				(tracks allowed)
				(vias not_allowed)
				(pads allowed)
				(copperpour not_allowed)
				(footprints allowed)
			)
			(placement
				(enabled no)
				(sheetname "")
			)
			(fill
				(thermal_gap 0.5)
				(thermal_bridge_width 0.5)
				(island_removal_mode 0)
			)
			(polygon
				(pts
					(xy 23.54834 -86.4108) (xy 23.04034 -86.4108) (xy 23.04034 -86.7918) (xy 23.54834 -86.7918)
				)
			)
		)
	)
	(footprint ""
		(layer "F.Cu")
		(at 407.753566 -96.500442 -90)
		(property "Reference" "C8C12"
			(at -0.8382 -0.67818 270)
			(unlocked yes)
			(layer "F.SilkS")
			(effects
				(font
					(size 0.4064 0.254)
					(thickness 0.1524)
				)
				(justify left)
			)
		)
		(property "Value" ""
			(at 0 0 270)
			(layer "F.Fab")
			(effects
				(font
					(size 1.27 1.27)
				)
			)
		)
		(duplicate_pad_numbers_are_jumpers no)
		(fp_poly
			(pts
				(xy 0.3048 -0.1016) (xy 0.3048 0.9906) (xy -0.3048 0.9906) (xy -0.3048 -0.1016)
			)
			(stroke
				(width 0)
				(type default)
			)
			(fill no)
			(layer "F.CrtYd")
		)
		(fp_line
			(start -0.3048 0.9906)
			(end 0.3048 0.9906)
			(stroke
				(width 0.1)
				(type default)
			)
			(layer "F.Fab")
		)
		(fp_line
			(start 0.3048 0.9906)
			(end 0.3048 -0.1016)
			(stroke
				(width 0.1)
				(type default)
			)
			(layer "F.Fab")
		)
		(fp_line
			(start -0.3048 -0.1016)
			(end -0.3048 0.9906)
			(stroke
				(width 0.1)
				(type default)
			)
			(layer "F.Fab")
		)
		(fp_line
			(start 0.3048 -0.1016)
			(end -0.3048 -0.1016)
			(stroke
				(width 0.1)
				(type default)
			)
			(layer "F.Fab")
		)
		(pad "1" smd rect
			(at 0 0 270)
			(size 0.508 0.508)
			(layers "F.Cu" "F.Mask" "F.Paste")
			(net "KR_P1_OCP_RX_DP")
		)
		(pad "2" smd rect
			(at 0 0.889 270)
			(size 0.508 0.508)
			(layers "F.Cu" "F.Mask" "F.Paste")
			(net "KR_P1_OCP_RX_C_DP")
		)
		(zone
			(layer "F.Cu")
			(hatch none 0.5)
			(connect_pads
				(clearance 0)
			)
			(min_thickness 0.25)
			(keepout
				(tracks not_allowed)
				(vias allowed)
				(pads allowed)
				(copperpour not_allowed)
				(footprints allowed)
			)
			(placement
				(enabled no)
				(sheetname "")
			)
			(fill
				(thermal_gap 0.5)
				(thermal_bridge_width 0.5)
				(island_removal_mode 0)
			)
			(polygon
				(pts
					(xy 407.118566 -96.754442) (xy 407.118566 -96.246442) (xy 407.499566 -96.246442) (xy 407.499566 -96.754442)
				)
			)
		)
		(zone
			(layer "F.Cu")
			(hatch none 0.5)
			(connect_pads
				(clearance 0)
			)
			(min_thickness 0.25)
			(keepout
				(tracks allowed)
				(vias not_allowed)
				(pads allowed)
				(copperpour not_allowed)
				(footprints allowed)
			)
			(placement
				(enabled no)
				(sheetname "")
			)
			(fill
				(thermal_gap 0.5)
				(thermal_bridge_width 0.5)
				(island_removal_mode 0)
			)
			(polygon
				(pts
					(xy 407.499566 -96.754442) (xy 407.499566 -96.246442) (xy 407.118566 -96.246442) (xy 407.118566 -96.754442)
				)
			)
		)
	)
	(footprint ""
		(layer "F.Cu")
		(at 13.8938 -35.687 90)
		(property "Reference" "C1F3"
			(at 0 0 90)
			(layer "F.SilkS")
			(hide yes)
			(effects
				(font
					(size 1.27 1.27)
				)
			)
		)
		(property "Value" ""
			(at 0 0 90)
			(layer "F.Fab")
			(effects
				(font
					(size 1.27 1.27)
				)
			)
		)
		(duplicate_pad_numbers_are_jumpers no)
		(fp_rect
			(start -0.3048 -0.1016)
			(end 0.3048 0.9906)
			(stroke
				(width 0)
				(type default)
			)
			(fill no)
			(layer "F.CrtYd")
		)
		(fp_line
			(start 0.3048 -0.1016)
			(end -0.3048 -0.1016)
			(stroke
				(width 0.1)
				(type default)
			)
			(layer "F.Fab")
		)
		(fp_line
			(start -0.3048 -0.1016)
			(end -0.3048 0.9906)
			(stroke
				(width 0.1)
				(type default)
			)
			(layer "F.Fab")
		)
		(fp_line
			(start 0.3048 0.9906)
			(end 0.3048 -0.1016)
			(stroke
				(width 0.1)
				(type default)
			)
			(layer "F.Fab")
		)
		(fp_line
			(start -0.3048 0.9906)
			(end 0.3048 0.9906)
			(stroke
				(width 0.1)
				(type default)
			)
			(layer "F.Fab")
		)
		(pad "1" smd rect
			(at 0 0 90)
			(size 0.508 0.508)
			(layers "F.Cu" "F.Mask" "F.Paste")
			(net "P3E_CPU1_PE3_MP_C_TXN<7>")
		)
		(pad "2" smd rect
			(at 0 0.889 90)
			(size 0.508 0.508)
			(layers "F.Cu" "F.Mask" "F.Paste")
			(net "P3E_CPU1_PE3_MP_TXN<7>")
		)
		(zone
			(layer "F.Cu")
			(hatch none 0.5)
			(connect_pads
				(clearance 0)
			)
			(min_thickness 0.25)
			(keepout
				(tracks not_allowed)
				(vias allowed)
				(pads allowed)
				(copperpour not_allowed)
				(footprints allowed)
			)
			(placement
				(enabled no)
				(sheetname "")
			)
			(fill
				(thermal_gap 0.5)
				(thermal_bridge_width 0.5)
				(island_removal_mode 0)
			)
			(polygon
				(pts
					(xy 14.1478 -35.433) (xy 14.5288 -35.433) (xy 14.5288 -35.941) (xy 14.1478 -35.941)
				)
			)
		)
		(zone
			(layer "F.Cu")
			(hatch none 0.5)
			(connect_pads
				(clearance 0)
			)
			(min_thickness 0.25)
			(keepout
				(tracks allowed)
				(vias not_allowed)
				(pads allowed)
				(copperpour not_allowed)
				(footprints allowed)
			)
			(placement
				(enabled no)
				(sheetname "")
			)
			(fill
				(thermal_gap 0.5)
				(thermal_bridge_width 0.5)
				(island_removal_mode 0)
			)
			(polygon
				(pts
					(xy 14.1478 -35.433) (xy 14.5288 -35.433) (xy 14.5288 -35.941) (xy 14.1478 -35.941)
				)
			)
		)
	)
	(footprint ""
		(layer "F.Cu")
		(at 489.19892 -120.75922 90)
		(property "Reference" "R9B8"
			(at 0 0 90)
			(layer "F.SilkS")
			(hide yes)
			(effects
				(font
					(size 1.27 1.27)
				)
			)
		)
		(property "Value" ""
			(at 0 0 90)
			(layer "F.Fab")
			(effects
				(font
					(size 1.27 1.27)
				)
			)
		)
		(duplicate_pad_numbers_are_jumpers no)
		(fp_rect
			(start -0.2794 -0.1016)
			(end 0.2794 0.9906)
			(stroke
				(width 0)
				(type default)
			)
			(fill no)
			(layer "F.CrtYd")
		)
		(fp_line
			(start 0.2794 -0.1016)
			(end -0.2794 -0.1016)
			(stroke
				(width 0.1)
				(type default)
			)
			(layer "F.Fab")
		)
		(fp_line
			(start -0.2794 -0.1016)
			(end -0.2794 0.9906)
			(stroke
				(width 0.1)
				(type default)
			)
			(layer "F.Fab")
		)
		(fp_line
			(start 0.2794 0.9906)
			(end 0.2794 -0.1016)
			(stroke
				(width 0.1)
				(type default)
			)
			(layer "F.Fab")
		)
		(fp_line
			(start -0.2794 0.9906)
			(end 0.2794 0.9906)
			(stroke
				(width 0.1)
				(type default)
			)
			(layer "F.Fab")
		)
		(pad "1" smd rect
			(at 0 0 90)
			(size 0.508 0.508)
			(layers "F.Cu" "F.Mask" "F.Paste")
			(net "PD_TMP421_1_A0")
		)
		(pad "2" smd rect
			(at 0 0.889 90)
			(size 0.508 0.508)
			(layers "F.Cu" "F.Mask" "F.Paste")
			(net "GND")
		)
		(zone
			(layer "F.Cu")
			(hatch none 0.5)
			(connect_pads
				(clearance 0)
			)
			(min_thickness 0.25)
			(keepout
				(tracks allowed)
				(vias not_allowed)
				(pads allowed)
				(copperpour not_allowed)
				(footprints allowed)
			)
			(placement
				(enabled no)
				(sheetname "")
			)
			(fill
				(thermal_gap 0.5)
				(thermal_bridge_width 0.5)
				(island_removal_mode 0)
			)
			(polygon
				(pts
					(xy 489.45292 -120.50522) (xy 489.83392 -120.50522) (xy 489.83392 -121.01322) (xy 489.45292 -121.01322)
				)
			)
		)
		(zone
			(layer "F.Cu")
			(hatch none 0.5)
			(connect_pads
				(clearance 0)
			)
			(min_thickness 0.25)
			(keepout
				(tracks not_allowed)
				(vias allowed)
				(pads allowed)
				(copperpour not_allowed)
				(footprints allowed)
			)
			(placement
				(enabled no)
				(sheetname "")
			)
			(fill
				(thermal_gap 0.5)
				(thermal_bridge_width 0.5)
				(island_removal_mode 0)
			)
			(polygon
				(pts
					(xy 489.45292 -120.50522) (xy 489.83392 -120.50522) (xy 489.83392 -121.01322) (xy 489.45292 -121.01322)
				)
			)
		)
	)
	(footprint ""
		(layer "F.Cu")
		(at 169.51833 -133.705092 90)
		(property "Reference" "C4B15"
			(at 0 0 90)
			(layer "F.SilkS")
			(hide yes)
			(effects
				(font
					(size 1.27 1.27)
				)
			)
		)
		(property "Value" ""
			(at 0 0 90)
			(layer "F.Fab")
			(effects
				(font
					(size 1.27 1.27)
				)
			)
		)
		(duplicate_pad_numbers_are_jumpers no)
		(fp_poly
			(pts
				(xy -0.4953 -0.2032) (xy 0.4953 -0.2032) (xy 0.4953 1.6002) (xy -0.4953 1.6002)
			)
			(stroke
				(width 0)
				(type default)
			)
			(fill no)
			(layer "F.CrtYd")
		)
		(fp_line
			(start 0.4953 -0.2032)
			(end 0.4953 1.6002)
			(stroke
				(width 0.1)
				(type default)
			)
			(layer "F.Fab")
		)
		(fp_line
			(start -0.4953 -0.2032)
			(end 0.4953 -0.2032)
			(stroke
				(width 0.1)
				(type default)
			)
			(layer "F.Fab")
		)
		(fp_line
			(start 0.4953 1.6002)
			(end -0.4953 1.6002)
			(stroke
				(width 0.1)
				(type default)
			)
			(layer "F.Fab")
		)
		(fp_line
			(start -0.4953 1.6002)
			(end -0.4953 -0.2032)
			(stroke
				(width 0.1)
				(type default)
			)
			(layer "F.Fab")
		)
		(pad "1" smd rect
			(at 0 0 90)
			(size 0.762 0.889)
			(layers "F.Cu" "F.Mask" "F.Paste")
			(net "VR_PVPP_KLM_PHASE")
		)
		(pad "2" smd rect
			(at 0 1.397 90)
			(size 0.762 0.889)
			(layers "F.Cu" "F.Mask" "F.Paste")
			(net "VR_PVPP_KLM_BOOT_R")
		)
		(zone
			(layer "F.Cu")
			(hatch none 0.5)
			(connect_pads
				(clearance 0)
			)
			(min_thickness 0.25)
			(keepout
				(tracks not_allowed)
				(vias allowed)
				(pads allowed)
				(copperpour not_allowed)
				(footprints allowed)
			)
			(placement
				(enabled no)
				(sheetname "")
			)
			(fill
				(thermal_gap 0.5)
				(thermal_bridge_width 0.5)
				(island_removal_mode 0)
			)
			(polygon
				(pts
					(xy 169.96283 -133.324092) (xy 169.96283 -134.086092) (xy 170.47083 -134.086092) (xy 170.47083 -133.324092)
				)
			)
		)
	)
	(footprint ""
		(layer "F.Cu")
		(at 454.279 -157.607)
		(property "Reference" "Q9A1"
			(at 2.28854 2.19075 180)
			(unlocked yes)
			(layer "F.SilkS")
			(effects
				(font
					(size 0.7874 0.5842)
					(thickness 0.1524)
				)
				(justify left)
			)
		)
		(property "Value" ""
			(at 0 0 0)
			(layer "F.Fab")
			(effects
				(font
					(size 1.27 1.27)
				)
			)
		)
		(duplicate_pad_numbers_are_jumpers no)
		(fp_circle
			(center -0.848614 -0.6477)
			(end -0.721614 -0.6477)
			(stroke
				(width 0.254)
				(type default)
			)
			(fill no)
			(layer "F.SilkS")
		)
		(fp_poly
			(pts
				(xy 0.21463 -0.450088) (xy 1.56337 -0.450088) (xy 1.56337 1.75006) (xy 0.21463 1.75006)
			)
			(stroke
				(width 0)
				(type default)
			)
			(fill no)
			(layer "F.CrtYd")
		)
		(fp_line
			(start 0.21463 -0.450088)
			(end 1.56337 -0.450088)
			(stroke
				(width 0.1)
				(type default)
			)
			(layer "F.Fab")
		)
		(fp_line
			(start 0.21463 1.75006)
			(end 0.21463 -0.450088)
			(stroke
				(width 0.1)
				(type default)
			)
			(layer "F.Fab")
		)
		(fp_line
			(start 1.56337 -0.450088)
			(end 1.56337 1.75006)
			(stroke
				(width 0.1)
				(type default)
			)
			(layer "F.Fab")
		)
		(fp_line
			(start 1.56337 1.75006)
			(end 0.21463 1.75006)
			(stroke
				(width 0.1)
				(type default)
			)
			(layer "F.Fab")
		)
		(fp_circle
			(center -0.848614 -0.6477)
			(end -0.721614 -0.6477)
			(stroke
				(width 0.254)
				(type default)
			)
			(fill no)
			(layer "F.Fab")
		)
		(pad "1" smd rect
			(at 0 0)
			(size 1.016 0.381)
			(layers "F.Cu" "F.Mask" "F.Paste")
			(net "XDP_CPU_GTL_TCK_R2")
		)
		(pad "2" smd rect
			(at 0 0.649986)
			(size 1.016 0.381)
			(layers "F.Cu" "F.Mask" "F.Paste")
			(net "XDP_CPU_TCK_BUF")
		)
		(pad "3" smd rect
			(at 0 1.299972)
			(size 1.016 0.381)
			(layers "F.Cu" "F.Mask" "F.Paste")
			(net "P3V3")
		)
		(pad "4" smd rect
			(at 1.778 1.299972)
			(size 1.016 0.381)
			(layers "F.Cu" "F.Mask" "F.Paste")
			(net "XDP_CPU_TCK0")
		)
		(pad "5" smd rect
			(at 1.778 0.649986)
			(size 1.016 0.381)
			(layers "F.Cu" "F.Mask" "F.Paste")
			(net "XDP_CPU_TCK_BUF")
		)
		(pad "6" smd rect
			(at 1.778 0)
			(size 1.016 0.381)
			(layers "F.Cu" "F.Mask" "F.Paste")
			(net "XDP_CPU_TCK_BUF")
		)
	)
	(footprint ""
		(layer "F.Cu")
		(at 28.7274 -105.3338 90)
		(property "Reference" "R1C32"
			(at 0 0 90)
			(layer "F.SilkS")
			(hide yes)
			(effects
				(font
					(size 1.27 1.27)
				)
			)
		)
		(property "Value" ""
			(at 0 0 90)
			(layer "F.Fab")
			(effects
				(font
					(size 1.27 1.27)
				)
			)
		)
		(duplicate_pad_numbers_are_jumpers no)
		(fp_poly
			(pts
				(xy -0.2794 -0.1016) (xy 0.2794 -0.1016) (xy 0.2794 0.9906) (xy -0.2794 0.9906)
			)
			(stroke
				(width 0)
				(type default)
			)
			(fill no)
			(layer "F.CrtYd")
		)
		(fp_line
			(start 0.2794 -0.1016)
			(end -0.2794 -0.1016)
			(stroke
				(width 0.1)
				(type default)
			)
			(layer "F.Fab")
		)
		(fp_line
			(start -0.2794 -0.1016)
			(end -0.2794 0.9906)
			(stroke
				(width 0.1)
				(type default)
			)
			(layer "F.Fab")
		)
		(fp_line
			(start 0.2794 0.9906)
			(end 0.2794 -0.1016)
			(stroke
				(width 0.1)
				(type default)
			)
			(layer "F.Fab")
		)
		(fp_line
			(start -0.2794 0.9906)
			(end 0.2794 0.9906)
			(stroke
				(width 0.1)
				(type default)
			)
			(layer "F.Fab")
		)
		(pad "1" smd rect
			(at 0 0 90)
			(size 0.508 0.508)
			(layers "F.Cu" "F.Mask" "F.Paste")
			(net "GND")
		)
		(pad "2" smd rect
			(at 0 0.889 90)
			(size 0.508 0.508)
			(layers "F.Cu" "F.Mask" "F.Paste")
			(net "PD_PIROM_CPU1_ADDR2")
		)
		(zone
			(layer "F.Cu")
			(hatch none 0.5)
			(connect_pads
				(clearance 0)
			)
			(min_thickness 0.25)
			(keepout
				(tracks allowed)
				(vias not_allowed)
				(pads allowed)
				(copperpour not_allowed)
				(footprints allowed)
			)
			(placement
				(enabled no)
				(sheetname "")
			)
			(fill
				(thermal_gap 0.5)
				(thermal_bridge_width 0.5)
				(island_removal_mode 0)
			)
			(polygon
				(pts
					(xy 28.9814 -105.0798) (xy 28.9814 -105.5878) (xy 29.3624 -105.5878) (xy 29.3624 -105.0798)
				)
			)
		)
		(zone
			(layer "F.Cu")
			(hatch none 0.5)
			(connect_pads
				(clearance 0)
			)
			(min_thickness 0.25)
			(keepout
				(tracks not_allowed)
				(vias allowed)
				(pads allowed)
				(copperpour not_allowed)
				(footprints allowed)
			)
			(placement
				(enabled no)
				(sheetname "")
			)
			(fill
				(thermal_gap 0.5)
				(thermal_bridge_width 0.5)
				(island_removal_mode 0)
			)
			(polygon
				(pts
					(xy 29.3624 -105.0798) (xy 29.3624 -105.5878) (xy 28.9814 -105.5878) (xy 28.9814 -105.0798)
				)
			)
		)
	)
	(footprint ""
		(layer "F.Cu")
		(at 323.10324 -131.34086)
		(property "Reference" "R6B1"
			(at 0 0 0)
			(layer "F.SilkS")
			(hide yes)
			(effects
				(font
					(size 1.27 1.27)
				)
			)
		)
		(property "Value" ""
			(at 0 0 0)
			(layer "F.Fab")
			(effects
				(font
					(size 1.27 1.27)
				)
			)
		)
		(duplicate_pad_numbers_are_jumpers no)
		(fp_poly
			(pts
				(xy -0.2794 -0.1016) (xy 0.2794 -0.1016) (xy 0.2794 0.9906) (xy -0.2794 0.9906)
			)
			(stroke
				(width 0)
				(type default)
			)
			(fill no)
			(layer "F.CrtYd")
		)
		(fp_line
			(start -0.2794 -0.1016)
			(end -0.2794 0.9906)
			(stroke
				(width 0.1)
				(type default)
			)
			(layer "F.Fab")
		)
		(fp_line
			(start -0.2794 0.9906)
			(end 0.2794 0.9906)
			(stroke
				(width 0.1)
				(type default)
			)
			(layer "F.Fab")
		)
		(fp_line
			(start 0.2794 -0.1016)
			(end -0.2794 -0.1016)
			(stroke
				(width 0.1)
				(type default)
			)
			(layer "F.Fab")
		)
		(fp_line
			(start 0.2794 0.9906)
			(end 0.2794 -0.1016)
			(stroke
				(width 0.1)
				(type default)
			)
			(layer "F.Fab")
		)
		(pad "1" smd rect
			(at 0 0)
			(size 0.508 0.508)
			(layers "F.Cu" "F.Mask" "F.Paste")
			(net "PVCCIO_CPU0")
		)
		(pad "2" smd rect
			(at 0 0.889)
			(size 0.508 0.508)
			(layers "F.Cu" "F.Mask" "F.Paste")
			(net "SVID_ALERT1_CPU0_R_N")
		)
		(zone
			(layer "F.Cu")
			(hatch none 0.5)
			(connect_pads
				(clearance 0)
			)
			(min_thickness 0.25)
			(keepout
				(tracks allowed)
				(vias not_allowed)
				(pads allowed)
				(copperpour not_allowed)
				(footprints allowed)
			)
			(placement
				(enabled no)
				(sheetname "")
			)
			(fill
				(thermal_gap 0.5)
				(thermal_bridge_width 0.5)
				(island_removal_mode 0)
			)
			(polygon
				(pts
					(xy 322.84924 -131.08686) (xy 323.35724 -131.08686) (xy 323.35724 -130.70586) (xy 322.84924 -130.70586)
				)
			)
		)
		(zone
			(layer "F.Cu")
			(hatch none 0.5)
			(connect_pads
				(clearance 0)
			)
			(min_thickness 0.25)
			(keepout
				(tracks not_allowed)
				(vias allowed)
				(pads allowed)
				(copperpour not_allowed)
				(footprints allowed)
			)
			(placement
				(enabled no)
				(sheetname "")
			)
			(fill
				(thermal_gap 0.5)
				(thermal_bridge_width 0.5)
				(island_removal_mode 0)
			)
			(polygon
				(pts
					(xy 322.84924 -130.70586) (xy 323.35724 -130.70586) (xy 323.35724 -131.08686) (xy 322.84924 -131.08686)
				)
			)
		)
	)
	(footprint ""
		(layer "F.Cu")
		(at 276.352 -69.977)
		(property "Reference" "R6D13"
			(at 0 0 0)
			(layer "F.SilkS")
			(hide yes)
			(effects
				(font
					(size 1.27 1.27)
				)
			)
		)
		(property "Value" ""
			(at 0 0 0)
			(layer "F.Fab")
			(effects
				(font
					(size 1.27 1.27)
				)
			)
		)
		(duplicate_pad_numbers_are_jumpers no)
		(fp_poly
			(pts
				(xy -0.2794 -0.1016) (xy 0.2794 -0.1016) (xy 0.2794 0.9906) (xy -0.2794 0.9906)
			)
			(stroke
				(width 0)
				(type default)
			)
			(fill no)
			(layer "F.CrtYd")
		)
		(fp_line
			(start -0.2794 -0.1016)
			(end -0.2794 0.9906)
			(stroke
				(width 0.1)
				(type default)
			)
			(layer "F.Fab")
		)
		(fp_line
			(start -0.2794 0.9906)
			(end 0.2794 0.9906)
			(stroke
				(width 0.1)
				(type default)
			)
			(layer "F.Fab")
		)
		(fp_line
			(start 0.2794 -0.1016)
			(end -0.2794 -0.1016)
			(stroke
				(width 0.1)
				(type default)
			)
			(layer "F.Fab")
		)
		(fp_line
			(start 0.2794 0.9906)
			(end 0.2794 -0.1016)
			(stroke
				(width 0.1)
				(type default)
			)
			(layer "F.Fab")
		)
		(pad "1" smd rect
			(at 0 0)
			(size 0.508 0.508)
			(layers "F.Cu" "F.Mask" "F.Paste")
			(net "PVCCIO_CPU0")
		)
		(pad "2" smd rect
			(at 0 0.889)
			(size 0.508 0.508)
			(layers "F.Cu" "F.Mask" "F.Paste")
			(net "PU_CPU0_SAFE_MODE_BOOT")
		)
		(zone
			(layer "F.Cu")
			(hatch none 0.5)
			(connect_pads
				(clearance 0)
			)
			(min_thickness 0.25)
			(keepout
				(tracks allowed)
				(vias not_allowed)
				(pads allowed)
				(copperpour not_allowed)
				(footprints allowed)
			)
			(placement
				(enabled no)
				(sheetname "")
			)
			(fill
				(thermal_gap 0.5)
				(thermal_bridge_width 0.5)
				(island_removal_mode 0)
			)
			(polygon
				(pts
					(xy 276.098 -69.723) (xy 276.606 -69.723) (xy 276.606 -69.342) (xy 276.098 -69.342)
				)
			)
		)
		(zone
			(layer "F.Cu")
			(hatch none 0.5)
			(connect_pads
				(clearance 0)
			)
			(min_thickness 0.25)
			(keepout
				(tracks not_allowed)
				(vias allowed)
				(pads allowed)
				(copperpour not_allowed)
				(footprints allowed)
			)
			(placement
				(enabled no)
				(sheetname "")
			)
			(fill
				(thermal_gap 0.5)
				(thermal_bridge_width 0.5)
				(island_removal_mode 0)
			)
			(polygon
				(pts
					(xy 276.098 -69.342) (xy 276.606 -69.342) (xy 276.606 -69.723) (xy 276.098 -69.723)
				)
			)
		)
	)
	(footprint ""
		(layer "F.Cu")
		(at 469.138 -20.6502 -90)
		(property "Reference" "R8F11"
			(at 0 0 270)
			(layer "F.SilkS")
			(hide yes)
			(effects
				(font
					(size 1.27 1.27)
				)
			)
		)
		(property "Value" ""
			(at 0 0 270)
			(layer "F.Fab")
			(effects
				(font
					(size 1.27 1.27)
				)
			)
		)
		(duplicate_pad_numbers_are_jumpers no)
		(fp_rect
			(start 0.2794 0.9906)
			(end -0.2794 -0.1016)
			(stroke
				(width 0)
				(type default)
			)
			(fill no)
			(layer "F.CrtYd")
		)
		(fp_line
			(start -0.2794 0.9906)
			(end 0.2794 0.9906)
			(stroke
				(width 0.1)
				(type default)
			)
			(layer "F.Fab")
		)
		(fp_line
			(start 0.2794 0.9906)
			(end 0.2794 -0.1016)
			(stroke
				(width 0.1)
				(type default)
			)
			(layer "F.Fab")
		)
		(fp_line
			(start -0.2794 -0.1016)
			(end -0.2794 0.9906)
			(stroke
				(width 0.1)
				(type default)
			)
			(layer "F.Fab")
		)
		(fp_line
			(start 0.2794 -0.1016)
			(end -0.2794 -0.1016)
			(stroke
				(width 0.1)
				(type default)
			)
			(layer "F.Fab")
		)
		(pad "1" smd rect
			(at 0 0 270)
			(size 0.508 0.508)
			(layers "F.Cu" "F.Mask" "F.Paste")
			(net "GND")
		)
		(pad "2" smd rect
			(at 0 0.889 270)
			(size 0.508 0.508)
			(layers "F.Cu" "F.Mask" "F.Paste")
			(net "AGND_P3V3_STBY")
		)
		(zone
			(layer "F.Cu")
			(hatch none 0.5)
			(connect_pads
				(clearance 0)
			)
			(min_thickness 0.25)
			(keepout
				(tracks allowed)
				(vias not_allowed)
				(pads allowed)
				(copperpour not_allowed)
				(footprints allowed)
			)
			(placement
				(enabled no)
				(sheetname "")
			)
			(fill
				(thermal_gap 0.5)
				(thermal_bridge_width 0.5)
				(island_removal_mode 0)
			)
			(polygon
				(pts
					(xy 468.503 -20.3962) (xy 468.884 -20.3962) (xy 468.884 -20.9042) (xy 468.503 -20.9042)
				)
			)
		)
		(zone
			(layer "F.Cu")
			(hatch none 0.5)
			(connect_pads
				(clearance 0)
			)
			(min_thickness 0.25)
			(keepout
				(tracks not_allowed)
				(vias allowed)
				(pads allowed)
				(copperpour not_allowed)
				(footprints allowed)
			)
			(placement
				(enabled no)
				(sheetname "")
			)
			(fill
				(thermal_gap 0.5)
				(thermal_bridge_width 0.5)
				(island_removal_mode 0)
			)
			(polygon
				(pts
					(xy 468.503 -20.3962) (xy 468.884 -20.3962) (xy 468.884 -20.9042) (xy 468.503 -20.9042)
				)
			)
		)
	)
	(footprint ""
		(layer "F.Cu")
		(at 192.0748 -74.168 90)
		(property "Reference" "RT25"
			(at 1.01473 0.656336 0)
			(unlocked yes)
			(layer "F.SilkS")
			(effects
				(font
					(size 0.4064 0.254)
					(thickness 0.1524)
				)
			)
		)
		(property "Value" ""
			(at 0 0 90)
			(layer "F.Fab")
			(effects
				(font
					(size 1.27 1.27)
				)
			)
		)
		(duplicate_pad_numbers_are_jumpers no)
		(fp_poly
			(pts
				(xy -0.4953 -0.2032) (xy 0.4953 -0.2032) (xy 0.4953 1.6002) (xy -0.4953 1.6002)
			)
			(stroke
				(width 0)
				(type default)
			)
			(fill no)
			(layer "F.CrtYd")
		)
		(fp_line
			(start 0.4953 -0.2032)
			(end 0.4953 1.6002)
			(stroke
				(width 0.1)
				(type default)
			)
			(layer "F.Fab")
		)
		(fp_line
			(start -0.4953 -0.2032)
			(end 0.4953 -0.2032)
			(stroke
				(width 0.1)
				(type default)
			)
			(layer "F.Fab")
		)
		(fp_line
			(start 0.4953 1.6002)
			(end -0.4953 1.6002)
			(stroke
				(width 0.1)
				(type default)
			)
			(layer "F.Fab")
		)
		(fp_line
			(start -0.4953 1.6002)
			(end -0.4953 -0.2032)
			(stroke
				(width 0.1)
				(type default)
			)
			(layer "F.Fab")
		)
		(pad "1" smd rect
			(at 0 0 90)
			(size 0.762 0.889)
			(layers "F.Cu" "F.Mask" "F.Paste")
			(net "VR_PVCCIN_CPU0_PH3_BOOT")
		)
		(pad "2" smd rect
			(at 0 1.397 90)
			(size 0.762 0.889)
			(layers "F.Cu" "F.Mask" "F.Paste")
			(net "VR_PVCCIN_CPU0_PH3_BOOT_R")
		)
		(zone
			(layer "F.Cu")
			(hatch none 0.5)
			(connect_pads
				(clearance 0)
			)
			(min_thickness 0.25)
			(keepout
				(tracks allowed)
				(vias not_allowed)
				(pads allowed)
				(copperpour not_allowed)
				(footprints allowed)
			)
			(placement
				(enabled no)
				(sheetname "")
			)
			(fill
				(thermal_gap 0.5)
				(thermal_bridge_width 0.5)
				(island_removal_mode 0)
			)
			(polygon
				(pts
					(xy 193.0273 -74.549) (xy 192.5193 -74.549) (xy 192.5193 -73.787) (xy 193.0273 -73.787)
				)
			)
		)
		(zone
			(layer "F.Cu")
			(hatch none 0.5)
			(connect_pads
				(clearance 0)
			)
			(min_thickness 0.25)
			(keepout
				(tracks not_allowed)
				(vias allowed)
				(pads allowed)
				(copperpour not_allowed)
				(footprints allowed)
			)
			(placement
				(enabled no)
				(sheetname "")
			)
			(fill
				(thermal_gap 0.5)
				(thermal_bridge_width 0.5)
				(island_removal_mode 0)
			)
			(polygon
				(pts
					(xy 193.0273 -73.787) (xy 193.0273 -74.549) (xy 192.5193 -74.549) (xy 192.5193 -73.787)
				)
			)
		)
	)
	(footprint ""
		(layer "F.Cu")
		(at 482.6508 -33.909)
		(property "Reference" "R1W24"
			(at -0.8382 -0.67818 0)
			(unlocked yes)
			(layer "F.SilkS")
			(effects
				(font
					(size 0.4064 0.254)
					(thickness 0.1524)
				)
				(justify left)
			)
		)
		(property "Value" ""
			(at 0 0 0)
			(layer "F.Fab")
			(effects
				(font
					(size 1.27 1.27)
				)
			)
		)
		(duplicate_pad_numbers_are_jumpers no)
		(fp_poly
			(pts
				(xy -0.2794 -0.1016) (xy 0.2794 -0.1016) (xy 0.2794 0.9906) (xy -0.2794 0.9906)
			)
			(stroke
				(width 0)
				(type default)
			)
			(fill no)
			(layer "F.CrtYd")
		)
		(fp_line
			(start -0.2794 -0.1016)
			(end -0.2794 0.9906)
			(stroke
				(width 0.1)
				(type default)
			)
			(layer "F.Fab")
		)
		(fp_line
			(start -0.2794 0.9906)
			(end 0.2794 0.9906)
			(stroke
				(width 0.1)
				(type default)
			)
			(layer "F.Fab")
		)
		(fp_line
			(start 0.2794 -0.1016)
			(end -0.2794 -0.1016)
			(stroke
				(width 0.1)
				(type default)
			)
			(layer "F.Fab")
		)
		(fp_line
			(start 0.2794 0.9906)
			(end 0.2794 -0.1016)
			(stroke
				(width 0.1)
				(type default)
			)
			(layer "F.Fab")
		)
		(pad "1" smd rect
			(at 0 0)
			(size 0.508 0.508)
			(layers "F.Cu" "F.Mask" "F.Paste")
			(net "XTAL_CK_MNG_OUT")
		)
		(pad "2" smd rect
			(at 0 0.889)
			(size 0.508 0.508)
			(layers "F.Cu" "F.Mask" "F.Paste")
			(net "XTAL_CK_MNG_OUT_R")
		)
		(zone
			(layer "F.Cu")
			(hatch none 0.5)
			(connect_pads
				(clearance 0)
			)
			(min_thickness 0.25)
			(keepout
				(tracks allowed)
				(vias not_allowed)
				(pads allowed)
				(copperpour not_allowed)
				(footprints allowed)
			)
			(placement
				(enabled no)
				(sheetname "")
			)
			(fill
				(thermal_gap 0.5)
				(thermal_bridge_width 0.5)
				(island_removal_mode 0)
			)
			(polygon
				(pts
					(xy 482.3968 -33.655) (xy 482.9048 -33.655) (xy 482.9048 -33.274) (xy 482.3968 -33.274)
				)
			)
		)
		(zone
			(layer "F.Cu")
			(hatch none 0.5)
			(connect_pads
				(clearance 0)
			)
			(min_thickness 0.25)
			(keepout
				(tracks not_allowed)
				(vias allowed)
				(pads allowed)
				(copperpour not_allowed)
				(footprints allowed)
			)
			(placement
				(enabled no)
				(sheetname "")
			)
			(fill
				(thermal_gap 0.5)
				(thermal_bridge_width 0.5)
				(island_removal_mode 0)
			)
			(polygon
				(pts
					(xy 482.3968 -33.274) (xy 482.9048 -33.274) (xy 482.9048 -33.655) (xy 482.3968 -33.655)
				)
			)
		)
	)
	(footprint ""
		(layer "F.Cu")
		(at 316.3443 -164.9095 -90)
		(property "Reference" "T1D19"
			(at 0 0 270)
			(layer "F.SilkS")
			(hide yes)
			(effects
				(font
					(size 1.27 1.27)
				)
			)
		)
		(property "Value" "*"
			(at -3.4036 -4.46405 270)
			(unlocked yes)
			(layer "F.Fab")
			(hide yes)
			(effects
				(font
					(size 0.889 0.889)
					(thickness 0.1524)
				)
			)
		)
		(property "Device Type" "TEST-PAD-12P-1-GP-U_DISCRET-GBA"
			(at -3.4036 -5.98805 270)
			(unlocked yes)
			(layer "F.Fab")
			(hide yes)
			(effects
				(font
					(size 0.889 0.889)
					(thickness 0.1524)
				)
			)
		)
		(duplicate_pad_numbers_are_jumpers no)
		(fp_line
			(start -2.3876 3.4798)
			(end -2.3876 -4.826)
			(stroke
				(width 0.1524)
				(type default)
			)
			(layer "F.SilkS")
		)
		(fp_line
			(start 2.3622 3.4798)
			(end -2.3876 3.4798)
			(stroke
				(width 0.1524)
				(type default)
			)
			(layer "F.SilkS")
		)
		(fp_line
			(start -2.3876 -4.826)
			(end 2.3622 -4.826)
			(stroke
				(width 0.1524)
				(type default)
			)
			(layer "F.SilkS")
		)
		(fp_line
			(start 2.3622 -4.826)
			(end 2.3622 3.4798)
			(stroke
				(width 0.1524)
				(type default)
			)
			(layer "F.SilkS")
		)
		(fp_rect
			(start -2.6416 3.7338)
			(end 2.6162 -5.08)
			(stroke
				(width 0)
				(type default)
			)
			(fill no)
			(layer "F.CrtYd")
		)
		(fp_rect
			(start -2.6416 3.7338)
			(end 2.6162 -5.08)
			(stroke
				(width 0)
				(type default)
			)
			(fill no)
			(layer "F.Fab")
		)
		(pad "1" smd circle
			(at 0.496824 -1.301496 270)
			(size 0.6604 0.6604)
			(layers "F.Cu" "F.Mask" "F.Paste")
			(net "L10_85OHM_10INCH_DP")
		)
		(pad "2" smd circle
			(at -0.503936 -1.301496 270)
			(size 0.6604 0.6604)
			(layers "F.Cu" "F.Mask" "F.Paste")
			(net "L10_85OHM_10INCH_DN")
		)
		(pad "3" smd custom
			(at -0.00889 0.370078 270)
			(size 0.74295 0.74295)
			(layers "F.Cu" "F.Mask" "F.Paste")
			(net "GND")
			(options
				(clearance outline)
				(anchor circle)
			)
			(primitives
				(gr_poly
					(pts
						(xy -2.1209 1.4859) (xy 2.1209 1.4859) (xy 2.1209 -1.4859) (xy 1.08585 -1.4859) (xy 1.08585 -0.4699)
						(xy -1.08585 -0.4699) (xy -1.08585 -1.4859) (xy -2.1209 -1.4859)
					)
					(width 0)
					(fill yes)
				)
			)
		)
		(pad "4" thru_hole circle
			(at 1.266444 -3.851656 270)
			(size 1.4478 1.4478)
			(drill 1.0414)
			(layers "*.Cu" "*.Mask")
			(remove_unused_layers no)
			(net "GND")
			(clearance 0.1524)
			(thermal_gap 0.1524)
		)
		(pad "5" thru_hole circle
			(at -1.273556 -3.851656 270)
			(size 1.4478 1.4478)
			(drill 1.0414)
			(layers "*.Cu" "*.Mask")
			(remove_unused_layers no)
			(net "GND")
			(clearance 0.1524)
			(thermal_gap 0.1524)
		)
		(pad "6" thru_hole circle
			(at 1.266444 2.498344 270)
			(size 1.4478 1.4478)
			(drill 1.0414)
			(layers "*.Cu" "*.Mask")
			(remove_unused_layers no)
			(net "GND")
			(clearance 0.1524)
			(thermal_gap 0.1524)
		)
		(pad "7" thru_hole circle
			(at -1.273556 2.498344 270)
			(size 1.4478 1.4478)
			(drill 1.0414)
			(layers "*.Cu" "*.Mask")
			(remove_unused_layers no)
			(net "GND")
			(clearance 0.1524)
			(thermal_gap 0.1524)
		)
		(pad "8" thru_hole circle
			(at 1.27 -0.4572 270)
			(size 0.7112 0.7112)
			(drill 0.4064)
			(layers "*.Cu" "*.Mask")
			(remove_unused_layers no)
			(net "GND")
			(clearance 0.1016)
			(thermal_gap 0.1016)
		)
		(pad "9" thru_hole circle
			(at 1.27 0.762 270)
			(size 0.7112 0.7112)
			(drill 0.4064)
			(layers "*.Cu" "*.Mask")
			(remove_unused_layers no)
			(net "GND")
			(clearance 0.1016)
			(thermal_gap 0.1016)
		)
		(pad "10" thru_hole circle
			(at -0.0254 0.762 270)
			(size 0.7112 0.7112)
			(drill 0.4064)
			(layers "*.Cu" "*.Mask")
			(remove_unused_layers no)
			(net "GND")
			(clearance 0.1016)
			(thermal_gap 0.1016)
		)
		(pad "11" thru_hole circle
			(at -1.27 0.762 270)
			(size 0.7112 0.7112)
			(drill 0.4064)
			(layers "*.Cu" "*.Mask")
			(remove_unused_layers no)
			(net "GND")
			(clearance 0.1016)
			(thermal_gap 0.1016)
		)
		(pad "12" thru_hole circle
			(at -1.27 -0.4572 270)
			(size 0.7112 0.7112)
			(drill 0.4064)
			(layers "*.Cu" "*.Mask")
			(remove_unused_layers no)
			(net "GND")
			(clearance 0.1016)
			(thermal_gap 0.1016)
		)
	)
	(footprint ""
		(layer "F.Cu")
		(at 176.437798 -17.65681 90)
		(property "Reference" "R4F6"
			(at 0 0 90)
			(layer "F.SilkS")
			(hide yes)
			(effects
				(font
					(size 1.27 1.27)
				)
			)
		)
		(property "Value" ""
			(at 0 0 90)
			(layer "F.Fab")
			(effects
				(font
					(size 1.27 1.27)
				)
			)
		)
		(duplicate_pad_numbers_are_jumpers no)
		(fp_rect
			(start -0.2794 -0.1016)
			(end 0.2794 0.9906)
			(stroke
				(width 0)
				(type default)
			)
			(fill no)
			(layer "F.CrtYd")
		)
		(fp_line
			(start 0.2794 -0.1016)
			(end -0.2794 -0.1016)
			(stroke
				(width 0.1)
				(type default)
			)
			(layer "F.Fab")
		)
		(fp_line
			(start -0.2794 -0.1016)
			(end -0.2794 0.9906)
			(stroke
				(width 0.1)
				(type default)
			)
			(layer "F.Fab")
		)
		(fp_line
			(start 0.2794 0.9906)
			(end 0.2794 -0.1016)
			(stroke
				(width 0.1)
				(type default)
			)
			(layer "F.Fab")
		)
		(fp_line
			(start -0.2794 0.9906)
			(end 0.2794 0.9906)
			(stroke
				(width 0.1)
				(type default)
			)
			(layer "F.Fab")
		)
		(pad "1" smd rect
			(at 0 0 90)
			(size 0.508 0.508)
			(layers "F.Cu" "F.Mask" "F.Paste")
			(net "VR_PVPP_GHJ_SNUB")
		)
		(pad "2" smd rect
			(at 0 0.889 90)
			(size 0.508 0.508)
			(layers "F.Cu" "F.Mask" "F.Paste")
			(net "GND")
		)
		(zone
			(layer "F.Cu")
			(hatch none 0.5)
			(connect_pads
				(clearance 0)
			)
			(min_thickness 0.25)
			(keepout
				(tracks allowed)
				(vias not_allowed)
				(pads allowed)
				(copperpour not_allowed)
				(footprints allowed)
			)
			(placement
				(enabled no)
				(sheetname "")
			)
			(fill
				(thermal_gap 0.5)
				(thermal_bridge_width 0.5)
				(island_removal_mode 0)
			)
			(polygon
				(pts
					(xy 176.691798 -17.40281) (xy 177.072798 -17.40281) (xy 177.072798 -17.91081) (xy 176.691798 -17.91081)
				)
			)
		)
		(zone
			(layer "F.Cu")
			(hatch none 0.5)
			(connect_pads
				(clearance 0)
			)
			(min_thickness 0.25)
			(keepout
				(tracks not_allowed)
				(vias allowed)
				(pads allowed)
				(copperpour not_allowed)
				(footprints allowed)
			)
			(placement
				(enabled no)
				(sheetname "")
			)
			(fill
				(thermal_gap 0.5)
				(thermal_bridge_width 0.5)
				(island_removal_mode 0)
			)
			(polygon
				(pts
					(xy 176.691798 -17.40281) (xy 177.072798 -17.40281) (xy 177.072798 -17.91081) (xy 176.691798 -17.91081)
				)
			)
		)
	)
	(footprint ""
		(layer "F.Cu")
		(at 484.251 -43.9674 180)
		(property "Reference" "EU9E1"
			(at 7.2644 -5.49529 0)
			(unlocked yes)
			(layer "F.SilkS")
			(effects
				(font
					(size 0.7874 0.5842)
					(thickness 0.1524)
				)
				(justify left)
			)
		)
		(property "Value" ""
			(at 0 0 180)
			(layer "F.Fab")
			(effects
				(font
					(size 1.27 1.27)
				)
			)
		)
		(duplicate_pad_numbers_are_jumpers no)
		(fp_line
			(start 5.0038 5.0038)
			(end -5.0038 5.0038)
			(stroke
				(width 0.1524)
				(type default)
			)
			(layer "F.SilkS")
		)
		(fp_line
			(start 5.0038 -5.0038)
			(end 5.0038 5.0038)
			(stroke
				(width 0.1524)
				(type default)
			)
			(layer "F.SilkS")
		)
		(fp_line
			(start 4.49961 4.49961)
			(end 4.232656 4.49961)
			(stroke
				(width 0.1524)
				(type default)
			)
			(layer "F.SilkS")
		)
		(fp_line
			(start 4.49961 4.232656)
			(end 4.49961 4.49961)
			(stroke
				(width 0.1524)
				(type default)
			)
			(layer "F.SilkS")
		)
		(fp_line
			(start 4.49961 -4.49961)
			(end 4.49961 -4.232656)
			(stroke
				(width 0.1524)
				(type default)
			)
			(layer "F.SilkS")
		)
		(fp_line
			(start 4.233164 -4.49961)
			(end 4.49961 -4.49961)
			(stroke
				(width 0.1524)
				(type default)
			)
			(layer "F.SilkS")
		)
		(fp_line
			(start -4.232656 4.49961)
			(end -4.49961 4.49961)
			(stroke
				(width 0.1524)
				(type default)
			)
			(layer "F.SilkS")
		)
		(fp_line
			(start -4.49961 4.49961)
			(end -4.49961 4.232656)
			(stroke
				(width 0.1524)
				(type default)
			)
			(layer "F.SilkS")
		)
		(fp_line
			(start -4.49961 -4.232656)
			(end -4.49961 -4.49961)
			(stroke
				(width 0.1524)
				(type default)
			)
			(layer "F.SilkS")
		)
		(fp_line
			(start -4.49961 -4.49961)
			(end -4.232656 -4.49961)
			(stroke
				(width 0.1524)
				(type default)
			)
			(layer "F.SilkS")
		)
		(fp_line
			(start -5.0038 5.0038)
			(end -5.0038 -5.0038)
			(stroke
				(width 0.1524)
				(type default)
			)
			(layer "F.SilkS")
		)
		(fp_line
			(start -5.0038 -5.0038)
			(end 5.0038 -5.0038)
			(stroke
				(width 0.1524)
				(type default)
			)
			(layer "F.SilkS")
		)
		(fp_circle
			(center -5.314696 -4.096004)
			(end -5.441696 -4.096004)
			(stroke
				(width 0.254)
				(type default)
			)
			(fill no)
			(layer "F.SilkS")
		)
		(fp_poly
			(pts
				(xy -5.0038 -5.0038) (xy -5.0038 -4.1402) (xy -4.1402 -5.0038)
			)
			(stroke
				(width 0)
				(type default)
			)
			(fill yes)
			(layer "F.SilkS")
		)
		(fp_rect
			(start -1.8034 1.8034)
			(end 1.8034 -1.8034)
			(stroke
				(width 0)
				(type default)
			)
			(fill yes)
			(layer "F.Paste")
		)
		(fp_rect
			(start -4.49961 4.49961)
			(end 4.49961 -4.49961)
			(stroke
				(width 0)
				(type default)
			)
			(fill no)
			(layer "F.CrtYd")
		)
		(fp_line
			(start 4.49961 4.49961)
			(end -4.49961 4.49961)
			(stroke
				(width 0.1)
				(type default)
			)
			(layer "F.Fab")
		)
		(fp_line
			(start 4.49961 -4.49961)
			(end 4.49961 4.49961)
			(stroke
				(width 0.1)
				(type default)
			)
			(layer "F.Fab")
		)
		(fp_line
			(start -4.49961 4.49961)
			(end -4.49961 -4.49961)
			(stroke
				(width 0.1)
				(type default)
			)
			(layer "F.Fab")
		)
		(fp_line
			(start -4.49961 -4.49961)
			(end 4.49961 -4.49961)
			(stroke
				(width 0.1)
				(type default)
			)
			(layer "F.Fab")
		)
		(fp_circle
			(center -5.314696 -4.096004)
			(end -5.441696 -4.096004)
			(stroke
				(width 0.254)
				(type default)
			)
			(fill no)
			(layer "F.Fab")
		)
		(pad "1" smd custom
			(at -4.3688 -3.750056 180)
			(size 0.0762 0.0762)
			(layers "F.Cu" "F.Mask" "F.Paste")
			(net "PU_SPRV_LAN_PWR_GOOD")
			(options
				(clearance outline)
				(anchor circle)
			)
			(primitives
				(gr_poly
					(pts
						(xy -0.381 -0.1524)
						(arc
							(start 0.2286 -0.1524)
							(mid 0.381 0)
							(end 0.2286 0.1524)
						)
						(xy -0.381 0.1524)
					)
					(width 0)
					(fill yes)
				)
			)
		)
		(pad "2" smd custom
			(at -4.3688 -3.24993 180)
			(size 0.0762 0.0762)
			(layers "F.Cu" "F.Mask" "F.Paste")
			(net "CLK_50M_CKMNG_SPRVLLE")
			(options
				(clearance outline)
				(anchor circle)
			)
			(primitives
				(gr_poly
					(pts
						(xy -0.381 -0.1524)
						(arc
							(start 0.2286 -0.1524)
							(mid 0.381 0)
							(end 0.2286 0.1524)
						)
						(xy -0.381 0.1524)
					)
					(width 0)
					(fill yes)
				)
			)
		)
		(pad "3" smd custom
			(at -4.3688 -2.750058 180)
			(size 0.0762 0.0762)
			(layers "F.Cu" "F.Mask" "F.Paste")
			(net "RMII_BMC_PCH_SPRNGVLLE_CRSDV_R")
			(options
				(clearance outline)
				(anchor circle)
			)
			(primitives
				(gr_poly
					(pts
						(xy -0.381 -0.1524)
						(arc
							(start 0.2286 -0.1524)
							(mid 0.381 0)
							(end 0.2286 0.1524)
						)
						(xy -0.381 0.1524)
					)
					(width 0)
					(fill yes)
				)
			)
		)
		(pad "4" smd custom
			(at -4.3688 -2.249932 180)
			(size 0.0762 0.0762)
			(layers "F.Cu" "F.Mask" "F.Paste")
			(net "PU_JTAG_SPRV_TDO")
			(options
				(clearance outline)
				(anchor circle)
			)
			(primitives
				(gr_poly
					(pts
						(xy -0.381 -0.1524)
						(arc
							(start 0.2286 -0.1524)
							(mid 0.381 0)
							(end 0.2286 0.1524)
						)
						(xy -0.381 0.1524)
					)
					(width 0)
					(fill yes)
				)
			)
		)
		(pad "5" smd custom
			(at -4.3688 -1.75006 180)
			(size 0.0762 0.0762)
			(layers "F.Cu" "F.Mask" "F.Paste")
			(net "RMII_SPRNGVLLE_BMC_PCH_RXD1_R")
			(options
				(clearance outline)
				(anchor circle)
			)
			(primitives
				(gr_poly
					(pts
						(xy -0.381 -0.1524)
						(arc
							(start 0.2286 -0.1524)
							(mid 0.381 0)
							(end 0.2286 0.1524)
						)
						(xy -0.381 0.1524)
					)
					(width 0)
					(fill yes)
				)
			)
		)
		(pad "6" smd custom
			(at -4.3688 -1.249934 180)
			(size 0.0762 0.0762)
			(layers "F.Cu" "F.Mask" "F.Paste")
			(net "RMII_SPRNGVLLE_BMC_PCH_RXD0_R")
			(options
				(clearance outline)
				(anchor circle)
			)
			(primitives
				(gr_poly
					(pts
						(xy -0.381 -0.1524)
						(arc
							(start 0.2286 -0.1524)
							(mid 0.381 0)
							(end 0.2286 0.1524)
						)
						(xy -0.381 0.1524)
					)
					(width 0)
					(fill yes)
				)
			)
		)
		(pad "7" smd custom
			(at -4.3688 -0.750062 180)
			(size 0.0762 0.0762)
			(layers "F.Cu" "F.Mask" "F.Paste")
			(net "RMII_BMC_PCH_SPRNGVLLE_TXEN")
			(options
				(clearance outline)
				(anchor circle)
			)
			(primitives
				(gr_poly
					(pts
						(xy -0.381 -0.1524)
						(arc
							(start 0.2286 -0.1524)
							(mid 0.381 0)
							(end 0.2286 0.1524)
						)
						(xy -0.381 0.1524)
					)
					(width 0)
					(fill yes)
				)
			)
		)
		(pad "8" smd custom
			(at -4.3688 -0.249936 180)
			(size 0.0762 0.0762)
			(layers "F.Cu" "F.Mask" "F.Paste")
			(net "RMII_BMC_PCH_SPRNGVLLE_TXD1")
			(options
				(clearance outline)
				(anchor circle)
			)
			(primitives
				(gr_poly
					(pts
						(xy -0.381 -0.1524)
						(arc
							(start 0.2286 -0.1524)
							(mid 0.381 0)
							(end 0.2286 0.1524)
						)
						(xy -0.381 0.1524)
					)
					(width 0)
					(fill yes)
				)
			)
		)
		(pad "9" smd custom
			(at -4.3688 0.249936 180)
			(size 0.0762 0.0762)
			(layers "F.Cu" "F.Mask" "F.Paste")
			(net "RMII_BMC_PCH_SPRNGVLLE_TXD0")
			(options
				(clearance outline)
				(anchor circle)
			)
			(primitives
				(gr_poly
					(pts
						(xy -0.381 -0.1524)
						(arc
							(start 0.2286 -0.1524)
							(mid 0.381 0)
							(end 0.2286 0.1524)
						)
						(xy -0.381 0.1524)
					)
					(width 0)
					(fill yes)
				)
			)
		)
		(pad "10" smd custom
			(at -4.3688 0.750062 180)
			(size 0.0762 0.0762)
			(layers "F.Cu" "F.Mask" "F.Paste")
			(net "P3V3_STBY")
			(options
				(clearance outline)
				(anchor circle)
			)
			(primitives
				(gr_poly
					(pts
						(xy -0.381 -0.1524)
						(arc
							(start 0.2286 -0.1524)
							(mid 0.381 0)
							(end 0.2286 0.1524)
						)
						(xy -0.381 0.1524)
					)
					(width 0)
					(fill yes)
				)
			)
		)
		(pad "11" smd custom
			(at -4.3688 1.249934 180)
			(size 0.0762 0.0762)
			(layers "F.Cu" "F.Mask" "F.Paste")
			(net "P0V9_LAN")
			(options
				(clearance outline)
				(anchor circle)
			)
			(primitives
				(gr_poly
					(pts
						(xy -0.381 -0.1524)
						(arc
							(start 0.2286 -0.1524)
							(mid 0.381 0)
							(end 0.2286 0.1524)
						)
						(xy -0.381 0.1524)
					)
					(width 0)
					(fill yes)
				)
			)
		)
		(pad "12" smd custom
			(at -4.3688 1.75006 180)
			(size 0.0762 0.0762)
			(layers "F.Cu" "F.Mask" "F.Paste")
			(net "SPI_NIC_MOSI_R")
			(options
				(clearance outline)
				(anchor circle)
			)
			(primitives
				(gr_poly
					(pts
						(xy -0.381 -0.1524)
						(arc
							(start 0.2286 -0.1524)
							(mid 0.381 0)
							(end 0.2286 0.1524)
						)
						(xy -0.381 0.1524)
					)
					(width 0)
					(fill yes)
				)
			)
		)
		(pad "13" smd custom
			(at -4.3688 2.249932 180)
			(size 0.0762 0.0762)
			(layers "F.Cu" "F.Mask" "F.Paste")
			(net "SPI_NIC_SCLK_R")
			(options
				(clearance outline)
				(anchor circle)
			)
			(primitives
				(gr_poly
					(pts
						(xy -0.381 -0.1524)
						(arc
							(start 0.2286 -0.1524)
							(mid 0.381 0)
							(end 0.2286 0.1524)
						)
						(xy -0.381 0.1524)
					)
					(width 0)
					(fill yes)
				)
			)
		)
		(pad "14" smd custom
			(at -4.3688 2.750058 180)
			(size 0.0762 0.0762)
			(layers "F.Cu" "F.Mask" "F.Paste")
			(net "SPI_NIC_MISO")
			(options
				(clearance outline)
				(anchor circle)
			)
			(primitives
				(gr_poly
					(pts
						(xy -0.381 -0.1524)
						(arc
							(start 0.2286 -0.1524)
							(mid 0.381 0)
							(end 0.2286 0.1524)
						)
						(xy -0.381 0.1524)
					)
					(width 0)
					(fill yes)
				)
			)
		)
		(pad "15" smd custom
			(at -4.3688 3.24993 180)
			(size 0.0762 0.0762)
			(layers "F.Cu" "F.Mask" "F.Paste")
			(net "SPI_NIC_CS_R_N")
			(options
				(clearance outline)
				(anchor circle)
			)
			(primitives
				(gr_poly
					(pts
						(xy -0.381 -0.1524)
						(arc
							(start 0.2286 -0.1524)
							(mid 0.381 0)
							(end 0.2286 0.1524)
						)
						(xy -0.381 0.1524)
					)
					(width 0)
					(fill yes)
				)
			)
		)
		(pad "16" smd custom
			(at -4.3688 3.750056 180)
			(size 0.0762 0.0762)
			(layers "F.Cu" "F.Mask" "F.Paste")
			(net "FM_PE_SPRV_WAKE_N")
			(options
				(clearance outline)
				(anchor circle)
			)
			(primitives
				(gr_poly
					(pts
						(xy -0.381 -0.1524)
						(arc
							(start 0.2286 -0.1524)
							(mid 0.381 0)
							(end 0.2286 0.1524)
						)
						(xy -0.381 0.1524)
					)
					(width 0)
					(fill yes)
				)
			)
		)
		(pad "17" smd custom
			(at -3.750056 4.3688 180)
			(size 0.0762 0.0762)
			(layers "F.Cu" "F.Mask" "F.Paste")
			(net "RST_PLTRST_SPRV_R_N")
			(options
				(clearance outline)
				(anchor circle)
			)
			(primitives
				(gr_poly
					(pts
						(xy -0.1524 0.381)
						(arc
							(start -0.1524 -0.2286)
							(mid 0 -0.381)
							(end 0.1524 -0.2286)
						)
						(xy 0.1524 0.381)
					)
					(width 0)
					(fill yes)
				)
			)
		)
		(pad "18" smd custom
			(at -3.250184 4.3688 180)
			(size 0.0762 0.0762)
			(layers "F.Cu" "F.Mask" "F.Paste")
			(net "PU_JTAG_SPRV_TMS")
			(options
				(clearance outline)
				(anchor circle)
			)
			(primitives
				(gr_poly
					(pts
						(xy -0.1524 0.381)
						(arc
							(start -0.1524 -0.2286)
							(mid 0 -0.381)
							(end 0.1524 -0.2286)
						)
						(xy 0.1524 0.381)
					)
					(width 0)
					(fill yes)
				)
			)
		)
		(pad "19" smd custom
			(at -2.750058 4.3688 180)
			(size 0.0762 0.0762)
			(layers "F.Cu" "F.Mask" "F.Paste")
			(net "PU_JTAG_SPRV_TCK")
			(options
				(clearance outline)
				(anchor circle)
			)
			(primitives
				(gr_poly
					(pts
						(xy -0.1524 0.381)
						(arc
							(start -0.1524 -0.2286)
							(mid 0 -0.381)
							(end 0.1524 -0.2286)
						)
						(xy 0.1524 0.381)
					)
					(width 0)
					(fill yes)
				)
			)
		)
		(pad "20" smd custom
			(at -2.250186 4.3688 180)
			(size 0.0762 0.0762)
			(layers "F.Cu" "F.Mask" "F.Paste")
			(net "PE_PCH_SPRV_RX_DN")
			(options
				(clearance outline)
				(anchor circle)
			)
			(primitives
				(gr_poly
					(pts
						(xy -0.1524 0.381)
						(arc
							(start -0.1524 -0.2286)
							(mid 0 -0.381)
							(end 0.1524 -0.2286)
						)
						(xy 0.1524 0.381)
					)
					(width 0)
					(fill yes)
				)
			)
		)
		(pad "21" smd custom
			(at -1.75006 4.3688 180)
			(size 0.0762 0.0762)
			(layers "F.Cu" "F.Mask" "F.Paste")
			(net "PE_PCH_SPRV_RX_DP")
			(options
				(clearance outline)
				(anchor circle)
			)
			(primitives
				(gr_poly
					(pts
						(xy -0.1524 0.381)
						(arc
							(start -0.1524 -0.2286)
							(mid 0 -0.381)
							(end 0.1524 -0.2286)
						)
						(xy 0.1524 0.381)
					)
					(width 0)
					(fill yes)
				)
			)
		)
		(pad "22" smd custom
			(at -1.250188 4.3688 180)
			(size 0.0762 0.0762)
			(layers "F.Cu" "F.Mask" "F.Paste")
			(net "Net_314")
			(options
				(clearance outline)
				(anchor circle)
			)
			(primitives
				(gr_poly
					(pts
						(xy -0.1524 0.381)
						(arc
							(start -0.1524 -0.2286)
							(mid 0 -0.381)
							(end 0.1524 -0.2286)
						)
						(xy 0.1524 0.381)
					)
					(width 0)
					(fill yes)
				)
			)
		)
		(pad "23" smd custom
			(at -0.750062 4.3688 180)
			(size 0.0762 0.0762)
			(layers "F.Cu" "F.Mask" "F.Paste")
			(net "PE_PCH_SPRV_TX_C_DN")
			(options
				(clearance outline)
				(anchor circle)
			)
			(primitives
				(gr_poly
					(pts
						(xy -0.1524 0.381)
						(arc
							(start -0.1524 -0.2286)
							(mid 0 -0.381)
							(end 0.1524 -0.2286)
						)
						(xy 0.1524 0.381)
					)
					(width 0)
					(fill yes)
				)
			)
		)
		(pad "24" smd custom
			(at -0.25019 4.3688 180)
			(size 0.0762 0.0762)
			(layers "F.Cu" "F.Mask" "F.Paste")
			(net "PE_PCH_SPRV_TX_C_DP")
			(options
				(clearance outline)
				(anchor circle)
			)
			(primitives
				(gr_poly
					(pts
						(xy -0.1524 0.381)
						(arc
							(start -0.1524 -0.2286)
							(mid 0 -0.381)
							(end 0.1524 -0.2286)
						)
						(xy 0.1524 0.381)
					)
					(width 0)
					(fill yes)
				)
			)
		)
		(pad "25" smd custom
			(at 0.249936 4.3688 180)
			(size 0.0762 0.0762)
			(layers "F.Cu" "F.Mask" "F.Paste")
			(net "CLK_100M_SPRV_DN")
			(options
				(clearance outline)
				(anchor circle)
			)
			(primitives
				(gr_poly
					(pts
						(xy -0.1524 0.381)
						(arc
							(start -0.1524 -0.2286)
							(mid 0 -0.381)
							(end 0.1524 -0.2286)
						)
						(xy 0.1524 0.381)
					)
					(width 0)
					(fill yes)
				)
			)
		)
		(pad "26" smd custom
			(at 0.749808 4.3688 180)
			(size 0.0762 0.0762)
			(layers "F.Cu" "F.Mask" "F.Paste")
			(net "CLK_100M_SPRV_DP")
			(options
				(clearance outline)
				(anchor circle)
			)
			(primitives
				(gr_poly
					(pts
						(xy -0.1524 0.381)
						(arc
							(start -0.1524 -0.2286)
							(mid 0 -0.381)
							(end 0.1524 -0.2286)
						)
						(xy 0.1524 0.381)
					)
					(width 0)
					(fill yes)
				)
			)
		)
		(pad "27" smd custom
			(at 1.249934 4.3688 180)
			(size 0.0762 0.0762)
			(layers "F.Cu" "F.Mask" "F.Paste")
			(net "P3V3_STBY")
			(options
				(clearance outline)
				(anchor circle)
			)
			(primitives
				(gr_poly
					(pts
						(xy -0.1524 0.381)
						(arc
							(start -0.1524 -0.2286)
							(mid 0 -0.381)
							(end 0.1524 -0.2286)
						)
						(xy 0.1524 0.381)
					)
					(width 0)
					(fill yes)
				)
			)
		)
		(pad "28" smd custom
			(at 1.749806 4.3688 180)
			(size 0.0762 0.0762)
			(layers "F.Cu" "F.Mask" "F.Paste")
			(net "PU_DEV_OFF_N")
			(options
				(clearance outline)
				(anchor circle)
			)
			(primitives
				(gr_poly
					(pts
						(xy -0.1524 0.381)
						(arc
							(start -0.1524 -0.2286)
							(mid 0 -0.381)
							(end 0.1524 -0.2286)
						)
						(xy 0.1524 0.381)
					)
					(width 0)
					(fill yes)
				)
			)
		)
		(pad "29" smd custom
			(at 2.249932 4.3688 180)
			(size 0.0762 0.0762)
			(layers "F.Cu" "F.Mask" "F.Paste")
			(net "PU_JTAG_SPRV_TDI")
			(options
				(clearance outline)
				(anchor circle)
			)
			(primitives
				(gr_poly
					(pts
						(xy -0.1524 0.381)
						(arc
							(start -0.1524 -0.2286)
							(mid 0 -0.381)
							(end 0.1524 -0.2286)
						)
						(xy 0.1524 0.381)
					)
					(width 0)
					(fill yes)
				)
			)
		)
		(pad "30" smd custom
			(at 2.750058 4.3688 180)
			(size 0.0762 0.0762)
			(layers "F.Cu" "F.Mask" "F.Paste")
			(net "LED_LAN_1_N")
			(options
				(clearance outline)
				(anchor circle)
			)
			(primitives
				(gr_poly
					(pts
						(xy -0.1524 0.381)
						(arc
							(start -0.1524 -0.2286)
							(mid 0 -0.381)
							(end 0.1524 -0.2286)
						)
						(xy 0.1524 0.381)
					)
					(width 0)
					(fill yes)
				)
			)
		)
		(pad "31" smd custom
			(at 3.24993 4.3688 180)
			(size 0.0762 0.0762)
			(layers "F.Cu" "F.Mask" "F.Paste")
			(net "LED_LAN_0_N")
			(options
				(clearance outline)
				(anchor circle)
			)
			(primitives
				(gr_poly
					(pts
						(xy -0.1524 0.381)
						(arc
							(start -0.1524 -0.2286)
							(mid 0 -0.381)
							(end 0.1524 -0.2286)
						)
						(xy 0.1524 0.381)
					)
					(width 0)
					(fill yes)
				)
			)
		)
		(pad "32" smd custom
			(at 3.750056 4.3688 180)
			(size 0.0762 0.0762)
			(layers "F.Cu" "F.Mask" "F.Paste")
			(net "P0V9_LAN")
			(options
				(clearance outline)
				(anchor circle)
			)
			(primitives
				(gr_poly
					(pts
						(xy -0.1524 0.381)
						(arc
							(start -0.1524 -0.2286)
							(mid 0 -0.381)
							(end 0.1524 -0.2286)
						)
						(xy 0.1524 0.381)
					)
					(width 0)
					(fill yes)
				)
			)
		)
		(pad "33" smd custom
			(at 4.3688 3.750056 180)
			(size 0.0762 0.0762)
			(layers "F.Cu" "F.Mask" "F.Paste")
			(net "LED_LAN_2_N")
			(options
				(clearance outline)
				(anchor circle)
			)
			(primitives
				(gr_poly
					(pts
						(xy 0.381 0.1524)
						(arc
							(start -0.2286 0.1524)
							(mid -0.381 0)
							(end -0.2286 -0.1524)
						)
						(xy 0.381 -0.1524)
					)
					(width 0)
					(fill yes)
				)
			)
		)
		(pad "34" smd custom
			(at 4.3688 3.24993 180)
			(size 0.0762 0.0762)
			(layers "F.Cu" "F.Mask" "F.Paste")
			(net "SMB_SPRINGVILLE_STBY_LVC3_SCL")
			(options
				(clearance outline)
				(anchor circle)
			)
			(primitives
				(gr_poly
					(pts
						(xy 0.381 0.1524)
						(arc
							(start -0.2286 0.1524)
							(mid -0.381 0)
							(end -0.2286 -0.1524)
						)
						(xy 0.381 -0.1524)
					)
					(width 0)
					(fill yes)
				)
			)
		)
		(pad "35" smd custom
			(at 4.3688 2.750058 180)
			(size 0.0762 0.0762)
			(layers "F.Cu" "F.Mask" "F.Paste")
			(net "IRQ_LOM_ALERT_N")
			(options
				(clearance outline)
				(anchor circle)
			)
			(primitives
				(gr_poly
					(pts
						(xy 0.381 0.1524)
						(arc
							(start -0.2286 0.1524)
							(mid -0.381 0)
							(end -0.2286 -0.1524)
						)
						(xy 0.381 -0.1524)
					)
					(width 0)
					(fill yes)
				)
			)
		)
		(pad "36" smd custom
			(at 4.3688 2.249932 180)
			(size 0.0762 0.0762)
			(layers "F.Cu" "F.Mask" "F.Paste")
			(net "SMB_SPRINGVILLE_STBY_LVC3_SDA")
			(options
				(clearance outline)
				(anchor circle)
			)
			(primitives
				(gr_poly
					(pts
						(xy 0.381 0.1524)
						(arc
							(start -0.2286 0.1524)
							(mid -0.381 0)
							(end -0.2286 -0.1524)
						)
						(xy 0.381 -0.1524)
					)
					(width 0)
					(fill yes)
				)
			)
		)
		(pad "37" smd custom
			(at 4.3688 1.75006 180)
			(size 0.0762 0.0762)
			(layers "F.Cu" "F.Mask" "F.Paste")
			(net "A_CBOT")
			(options
				(clearance outline)
				(anchor circle)
			)
			(primitives
				(gr_poly
					(pts
						(xy 0.381 0.1524)
						(arc
							(start -0.2286 0.1524)
							(mid -0.381 0)
							(end -0.2286 -0.1524)
						)
						(xy 0.381 -0.1524)
					)
					(width 0)
					(fill yes)
				)
			)
		)
		(pad "38" smd custom
			(at 4.3688 1.249934 180)
			(size 0.0762 0.0762)
			(layers "F.Cu" "F.Mask" "F.Paste")
			(net "P0V9_LAN_I210")
			(options
				(clearance outline)
				(anchor circle)
			)
			(primitives
				(gr_poly
					(pts
						(xy 0.381 0.1524)
						(arc
							(start -0.2286 0.1524)
							(mid -0.381 0)
							(end -0.2286 -0.1524)
						)
						(xy 0.381 -0.1524)
					)
					(width 0)
					(fill yes)
				)
			)
		)
		(pad "39" smd custom
			(at 4.3688 0.750062 180)
			(size 0.0762 0.0762)
			(layers "F.Cu" "F.Mask" "F.Paste")
			(net "P1V5_LAN")
			(options
				(clearance outline)
				(anchor circle)
			)
			(primitives
				(gr_poly
					(pts
						(xy 0.381 0.1524)
						(arc
							(start -0.2286 0.1524)
							(mid -0.381 0)
							(end -0.2286 -0.1524)
						)
						(xy 0.381 -0.1524)
					)
					(width 0)
					(fill yes)
				)
			)
		)
		(pad "40" smd custom
			(at 4.3688 0.249936 180)
			(size 0.0762 0.0762)
			(layers "F.Cu" "F.Mask" "F.Paste")
			(net "A_CTOP")
			(options
				(clearance outline)
				(anchor circle)
			)
			(primitives
				(gr_poly
					(pts
						(xy 0.381 0.1524)
						(arc
							(start -0.2286 0.1524)
							(mid -0.381 0)
							(end -0.2286 -0.1524)
						)
						(xy 0.381 -0.1524)
					)
					(width 0)
					(fill yes)
				)
			)
		)
		(pad "41" smd custom
			(at 4.3688 -0.249936 180)
			(size 0.0762 0.0762)
			(layers "F.Cu" "F.Mask" "F.Paste")
			(net "P3V3_STBY")
			(options
				(clearance outline)
				(anchor circle)
			)
			(primitives
				(gr_poly
					(pts
						(xy 0.381 0.1524)
						(arc
							(start -0.2286 0.1524)
							(mid -0.381 0)
							(end -0.2286 -0.1524)
						)
						(xy 0.381 -0.1524)
					)
					(width 0)
					(fill yes)
				)
			)
		)
		(pad "42" smd custom
			(at 4.3688 -0.750062 180)
			(size 0.0762 0.0762)
			(layers "F.Cu" "F.Mask" "F.Paste")
			(net "P0V9_LAN")
			(options
				(clearance outline)
				(anchor circle)
			)
			(primitives
				(gr_poly
					(pts
						(xy 0.381 0.1524)
						(arc
							(start -0.2286 0.1524)
							(mid -0.381 0)
							(end -0.2286 -0.1524)
						)
						(xy 0.381 -0.1524)
					)
					(width 0)
					(fill yes)
				)
			)
		)
		(pad "43" smd custom
			(at 4.3688 -1.249934 180)
			(size 0.0762 0.0762)
			(layers "F.Cu" "F.Mask" "F.Paste")
			(net "RMII_PCH_SPRNGVLLE_ARB_OUT")
			(options
				(clearance outline)
				(anchor circle)
			)
			(primitives
				(gr_poly
					(pts
						(xy 0.381 0.1524)
						(arc
							(start -0.2286 0.1524)
							(mid -0.381 0)
							(end -0.2286 -0.1524)
						)
						(xy 0.381 -0.1524)
					)
					(width 0)
					(fill yes)
				)
			)
		)
		(pad "44" smd custom
			(at 4.3688 -1.75006 180)
			(size 0.0762 0.0762)
			(layers "F.Cu" "F.Mask" "F.Paste")
			(net "RMII_PCH_SPRNGVLLE_ARB_IN_R")
			(options
				(clearance outline)
				(anchor circle)
			)
			(primitives
				(gr_poly
					(pts
						(xy 0.381 0.1524)
						(arc
							(start -0.2286 0.1524)
							(mid -0.381 0)
							(end -0.2286 -0.1524)
						)
						(xy 0.381 -0.1524)
					)
					(width 0)
					(fill yes)
				)
			)
		)
		(pad "45" smd custom
			(at 4.3688 -2.249932 180)
			(size 0.0762 0.0762)
			(layers "F.Cu" "F.Mask" "F.Paste")
			(net "XTAL_25MHZ_OUT")
			(options
				(clearance outline)
				(anchor circle)
			)
			(primitives
				(gr_poly
					(pts
						(xy 0.381 0.1524)
						(arc
							(start -0.2286 0.1524)
							(mid -0.381 0)
							(end -0.2286 -0.1524)
						)
						(xy 0.381 -0.1524)
					)
					(width 0)
					(fill yes)
				)
			)
		)
		(pad "46" smd custom
			(at 4.3688 -2.750058 180)
			(size 0.0762 0.0762)
			(layers "F.Cu" "F.Mask" "F.Paste")
			(net "XTAL_25MHZ_IN_R")
			(options
				(clearance outline)
				(anchor circle)
			)
			(primitives
				(gr_poly
					(pts
						(xy 0.381 0.1524)
						(arc
							(start -0.2286 0.1524)
							(mid -0.381 0)
							(end -0.2286 -0.1524)
						)
						(xy 0.381 -0.1524)
					)
					(width 0)
					(fill yes)
				)
			)
		)
		(pad "47" smd custom
			(at 4.3688 -3.24993 180)
			(size 0.0762 0.0762)
			(layers "F.Cu" "F.Mask" "F.Paste")
			(net "P1V5_LAN")
			(options
				(clearance outline)
				(anchor circle)
			)
			(primitives
				(gr_poly
					(pts
						(xy 0.381 0.1524)
						(arc
							(start -0.2286 0.1524)
							(mid -0.381 0)
							(end -0.2286 -0.1524)
						)
						(xy 0.381 -0.1524)
					)
					(width 0)
					(fill yes)
				)
			)
		)
		(pad "48" smd custom
			(at 4.3688 -3.750056 180)
			(size 0.0762 0.0762)
			(layers "F.Cu" "F.Mask" "F.Paste")
			(net "PD_SPRV_RSET")
			(options
				(clearance outline)
				(anchor circle)
			)
			(primitives
				(gr_poly
					(pts
						(xy 0.381 0.1524)
						(arc
							(start -0.2286 0.1524)
							(mid -0.381 0)
							(end -0.2286 -0.1524)
						)
						(xy 0.381 -0.1524)
					)
					(width 0)
					(fill yes)
				)
			)
		)
		(pad "49" smd custom
			(at 3.750056 -4.3688 180)
			(size 0.0762 0.0762)
			(layers "F.Cu" "F.Mask" "F.Paste")
			(net "NIC_SER_N_MDI_3_DN")
			(options
				(clearance outline)
				(anchor circle)
			)
			(primitives
				(gr_poly
					(pts
						(xy 0.1524 -0.381)
						(arc
							(start 0.1524 0.2286)
							(mid 0 0.381)
							(end -0.1524 0.2286)
						)
						(xy -0.1524 -0.381)
					)
					(width 0)
					(fill yes)
				)
			)
		)
		(pad "50" smd custom
			(at 3.24993 -4.3688 180)
			(size 0.0762 0.0762)
			(layers "F.Cu" "F.Mask" "F.Paste")
			(net "NIC_SER_P_MDI_3_DP")
			(options
				(clearance outline)
				(anchor circle)
			)
			(primitives
				(gr_poly
					(pts
						(xy 0.1524 -0.381)
						(arc
							(start 0.1524 0.2286)
							(mid 0 0.381)
							(end -0.1524 0.2286)
						)
						(xy -0.1524 -0.381)
					)
					(width 0)
					(fill yes)
				)
			)
		)
		(pad "51" smd custom
			(at 2.750058 -4.3688 180)
			(size 0.0762 0.0762)
			(layers "F.Cu" "F.Mask" "F.Paste")
			(net "P3V3_STBY_P1V5_LAN_I210")
			(options
				(clearance outline)
				(anchor circle)
			)
			(primitives
				(gr_poly
					(pts
						(xy 0.1524 -0.381)
						(arc
							(start 0.1524 0.2286)
							(mid 0 0.381)
							(end -0.1524 0.2286)
						)
						(xy -0.1524 -0.381)
					)
					(width 0)
					(fill yes)
				)
			)
		)
		(pad "52" smd custom
			(at 2.249932 -4.3688 180)
			(size 0.0762 0.0762)
			(layers "F.Cu" "F.Mask" "F.Paste")
			(net "NIC_SET_N_MDI_2_DN")
			(options
				(clearance outline)
				(anchor circle)
			)
			(primitives
				(gr_poly
					(pts
						(xy 0.1524 -0.381)
						(arc
							(start 0.1524 0.2286)
							(mid 0 0.381)
							(end -0.1524 0.2286)
						)
						(xy -0.1524 -0.381)
					)
					(width 0)
					(fill yes)
				)
			)
		)
		(pad "53" smd custom
			(at 1.75006 -4.3688 180)
			(size 0.0762 0.0762)
			(layers "F.Cu" "F.Mask" "F.Paste")
			(net "NIC_SET_P_MDI_2_DP")
			(options
				(clearance outline)
				(anchor circle)
			)
			(primitives
				(gr_poly
					(pts
						(xy 0.1524 -0.381)
						(arc
							(start 0.1524 0.2286)
							(mid 0 0.381)
							(end -0.1524 0.2286)
						)
						(xy -0.1524 -0.381)
					)
					(width 0)
					(fill yes)
				)
			)
		)
		(pad "54" smd custom
			(at 1.249934 -4.3688 180)
			(size 0.0762 0.0762)
			(layers "F.Cu" "F.Mask" "F.Paste")
			(net "NIC_MDI_SPRV_RJ45_1_DN")
			(options
				(clearance outline)
				(anchor circle)
			)
			(primitives
				(gr_poly
					(pts
						(xy 0.1524 -0.381)
						(arc
							(start 0.1524 0.2286)
							(mid 0 0.381)
							(end -0.1524 0.2286)
						)
						(xy -0.1524 -0.381)
					)
					(width 0)
					(fill yes)
				)
			)
		)
		(pad "55" smd custom
			(at 0.750062 -4.3688 180)
			(size 0.0762 0.0762)
			(layers "F.Cu" "F.Mask" "F.Paste")
			(net "NIC_MDI_SPRV_RJ45_1_DP")
			(options
				(clearance outline)
				(anchor circle)
			)
			(primitives
				(gr_poly
					(pts
						(xy 0.1524 -0.381)
						(arc
							(start 0.1524 0.2286)
							(mid 0 0.381)
							(end -0.1524 0.2286)
						)
						(xy -0.1524 -0.381)
					)
					(width 0)
					(fill yes)
				)
			)
		)
		(pad "56" smd custom
			(at 0.249936 -4.3688 180)
			(size 0.0762 0.0762)
			(layers "F.Cu" "F.Mask" "F.Paste")
			(net "P1V5_LAN_I210")
			(options
				(clearance outline)
				(anchor circle)
			)
			(primitives
				(gr_poly
					(pts
						(xy 0.1524 -0.381)
						(arc
							(start 0.1524 0.2286)
							(mid 0 0.381)
							(end -0.1524 0.2286)
						)
						(xy -0.1524 -0.381)
					)
					(width 0)
					(fill yes)
				)
			)
		)
		(pad "57" smd custom
			(at -0.249936 -4.3688 180)
			(size 0.0762 0.0762)
			(layers "F.Cu" "F.Mask" "F.Paste")
			(net "NIC_MDI_SPRV_RJ45_0_DN")
			(options
				(clearance outline)
				(anchor circle)
			)
			(primitives
				(gr_poly
					(pts
						(xy 0.1524 -0.381)
						(arc
							(start 0.1524 0.2286)
							(mid 0 0.381)
							(end -0.1524 0.2286)
						)
						(xy -0.1524 -0.381)
					)
					(width 0)
					(fill yes)
				)
			)
		)
		(pad "58" smd custom
			(at -0.750062 -4.3688 180)
			(size 0.0762 0.0762)
			(layers "F.Cu" "F.Mask" "F.Paste")
			(net "NIC_MDI_SPRV_RJ45_0_DP")
			(options
				(clearance outline)
				(anchor circle)
			)
			(primitives
				(gr_poly
					(pts
						(xy 0.1524 -0.381)
						(arc
							(start 0.1524 0.2286)
							(mid 0 0.381)
							(end -0.1524 0.2286)
						)
						(xy -0.1524 -0.381)
					)
					(width 0)
					(fill yes)
				)
			)
		)
		(pad "59" smd custom
			(at -1.249934 -4.3688 180)
			(size 0.0762 0.0762)
			(layers "F.Cu" "F.Mask" "F.Paste")
			(net "P0V9_LAN")
			(options
				(clearance outline)
				(anchor circle)
			)
			(primitives
				(gr_poly
					(pts
						(xy 0.1524 -0.381)
						(arc
							(start 0.1524 0.2286)
							(mid 0 0.381)
							(end -0.1524 0.2286)
						)
						(xy -0.1524 -0.381)
					)
					(width 0)
					(fill yes)
				)
			)
		)
		(pad "60" smd custom
			(at -1.75006 -4.3688 180)
			(size 0.0762 0.0762)
			(layers "F.Cu" "F.Mask" "F.Paste")
			(net "TP_SPRV_SDP3")
			(options
				(clearance outline)
				(anchor circle)
			)
			(primitives
				(gr_poly
					(pts
						(xy 0.1524 -0.381)
						(arc
							(start 0.1524 0.2286)
							(mid 0 0.381)
							(end -0.1524 0.2286)
						)
						(xy -0.1524 -0.381)
					)
					(width 0)
					(fill yes)
				)
			)
		)
		(pad "61" smd custom
			(at -2.249932 -4.3688 180)
			(size 0.0762 0.0762)
			(layers "F.Cu" "F.Mask" "F.Paste")
			(net "FM_1GB_LOM_DISABLE_N")
			(options
				(clearance outline)
				(anchor circle)
			)
			(primitives
				(gr_poly
					(pts
						(xy 0.1524 -0.381)
						(arc
							(start 0.1524 0.2286)
							(mid 0 0.381)
							(end -0.1524 0.2286)
						)
						(xy -0.1524 -0.381)
					)
					(width 0)
					(fill yes)
				)
			)
		)
		(pad "62" smd custom
			(at -2.750058 -4.3688 180)
			(size 0.0762 0.0762)
			(layers "F.Cu" "F.Mask" "F.Paste")
			(net "TP_SPRV_SDP2")
			(options
				(clearance outline)
				(anchor circle)
			)
			(primitives
				(gr_poly
					(pts
						(xy 0.1524 -0.381)
						(arc
							(start 0.1524 0.2286)
							(mid 0 0.381)
							(end -0.1524 0.2286)
						)
						(xy -0.1524 -0.381)
					)
					(width 0)
					(fill yes)
				)
			)
		)
		(pad "63" smd custom
			(at -3.24993 -4.3688 180)
			(size 0.0762 0.0762)
			(layers "F.Cu" "F.Mask" "F.Paste")
			(net "TP_SPRV_SDP0")
			(options
				(clearance outline)
				(anchor circle)
			)
			(primitives
				(gr_poly
					(pts
						(xy 0.1524 -0.381)
						(arc
							(start 0.1524 0.2286)
							(mid 0 0.381)
							(end -0.1524 0.2286)
						)
						(xy -0.1524 -0.381)
					)
					(width 0)
					(fill yes)
				)
			)
		)
		(pad "64" smd custom
			(at -3.750056 -4.3688 180)
			(size 0.0762 0.0762)
			(layers "F.Cu" "F.Mask" "F.Paste")
			(net "P3V3_STBY")
			(options
				(clearance outline)
				(anchor circle)
			)
			(primitives
				(gr_poly
					(pts
						(xy 0.1524 -0.381)
						(arc
							(start 0.1524 0.2286)
							(mid 0 0.381)
							(end -0.1524 0.2286)
						)
						(xy -0.1524 -0.381)
					)
					(width 0)
					(fill yes)
				)
			)
		)
		(pad "65" smd rect
			(at 0 0 180)
			(size 3.6068 3.6068)
			(layers "F.Cu" "F.Mask" "F.Paste")
			(net "GND")
		)
	)
	(footprint ""
		(layer "F.Cu")
		(at 10.414 -68.0593 180)
		(property "Reference" "R1D47"
			(at 0 0 180)
			(layer "F.SilkS")
			(hide yes)
			(effects
				(font
					(size 1.27 1.27)
				)
			)
		)
		(property "Value" ""
			(at 0 0 180)
			(layer "F.Fab")
			(effects
				(font
					(size 1.27 1.27)
				)
			)
		)
		(duplicate_pad_numbers_are_jumpers no)
		(fp_rect
			(start -0.2794 -0.1016)
			(end 0.2794 0.9906)
			(stroke
				(width 0)
				(type default)
			)
			(fill no)
			(layer "F.CrtYd")
		)
		(fp_line
			(start 0.2794 0.9906)
			(end 0.2794 -0.1016)
			(stroke
				(width 0.1)
				(type default)
			)
			(layer "F.Fab")
		)
		(fp_line
			(start 0.2794 -0.1016)
			(end -0.2794 -0.1016)
			(stroke
				(width 0.1)
				(type default)
			)
			(layer "F.Fab")
		)
		(fp_line
			(start -0.2794 0.9906)
			(end 0.2794 0.9906)
			(stroke
				(width 0.1)
				(type default)
			)
			(layer "F.Fab")
		)
		(fp_line
			(start -0.2794 -0.1016)
			(end -0.2794 0.9906)
			(stroke
				(width 0.1)
				(type default)
			)
			(layer "F.Fab")
		)
		(pad "1" smd rect
			(at 0 0 180)
			(size 0.508 0.508)
			(layers "F.Cu" "F.Mask" "F.Paste")
			(net "P12V_HSC_SENN0")
		)
		(pad "2" smd rect
			(at 0 0.889 180)
			(size 0.508 0.508)
			(layers "F.Cu" "F.Mask" "F.Paste")
			(net "A_HSC_HSN")
		)
		(zone
			(layer "F.Cu")
			(hatch none 0.5)
			(connect_pads
				(clearance 0)
			)
			(min_thickness 0.25)
			(keepout
				(tracks not_allowed)
				(vias allowed)
				(pads allowed)
				(copperpour not_allowed)
				(footprints allowed)
			)
			(placement
				(enabled no)
				(sheetname "")
			)
			(fill
				(thermal_gap 0.5)
				(thermal_bridge_width 0.5)
				(island_removal_mode 0)
			)
			(polygon
				(pts
					(xy 10.668 -68.3133) (xy 10.668 -68.6943) (xy 10.16 -68.6943) (xy 10.16 -68.3133)
				)
			)
		)
		(zone
			(layer "F.Cu")
			(hatch none 0.5)
			(connect_pads
				(clearance 0)
			)
			(min_thickness 0.25)
			(keepout
				(tracks allowed)
				(vias not_allowed)
				(pads allowed)
				(copperpour not_allowed)
				(footprints allowed)
			)
			(placement
				(enabled no)
				(sheetname "")
			)
			(fill
				(thermal_gap 0.5)
				(thermal_bridge_width 0.5)
				(island_removal_mode 0)
			)
			(polygon
				(pts
					(xy 10.668 -68.3133) (xy 10.668 -68.6943) (xy 10.16 -68.6943) (xy 10.16 -68.3133)
				)
			)
		)
	)
	(footprint ""
		(layer "F.Cu")
		(at 162.0012 -74.9808 90)
		(property "Reference" "R3D14"
			(at 0 0 90)
			(layer "F.SilkS")
			(hide yes)
			(effects
				(font
					(size 1.27 1.27)
				)
			)
		)
		(property "Value" ""
			(at 0 0 90)
			(layer "F.Fab")
			(effects
				(font
					(size 1.27 1.27)
				)
			)
		)
		(duplicate_pad_numbers_are_jumpers no)
		(fp_poly
			(pts
				(xy -0.4953 -0.2032) (xy 0.4953 -0.2032) (xy 0.4953 1.6002) (xy -0.4953 1.6002)
			)
			(stroke
				(width 0)
				(type default)
			)
			(fill no)
			(layer "F.CrtYd")
		)
		(fp_line
			(start 0.4953 -0.2032)
			(end 0.4953 1.6002)
			(stroke
				(width 0.1)
				(type default)
			)
			(layer "F.Fab")
		)
		(fp_line
			(start -0.4953 -0.2032)
			(end 0.4953 -0.2032)
			(stroke
				(width 0.1)
				(type default)
			)
			(layer "F.Fab")
		)
		(fp_line
			(start 0.4953 1.6002)
			(end -0.4953 1.6002)
			(stroke
				(width 0.1)
				(type default)
			)
			(layer "F.Fab")
		)
		(fp_line
			(start -0.4953 1.6002)
			(end -0.4953 -0.2032)
			(stroke
				(width 0.1)
				(type default)
			)
			(layer "F.Fab")
		)
		(pad "1" smd rect
			(at 0 0 90)
			(size 0.762 0.889)
			(layers "F.Cu" "F.Mask" "F.Paste")
			(net "P3V3_DB1200")
		)
		(pad "2" smd rect
			(at 0 1.397 90)
			(size 0.762 0.889)
			(layers "F.Cu" "F.Mask" "F.Paste")
			(net "P3V3_DB1200_A")
		)
		(zone
			(layer "F.Cu")
			(hatch none 0.5)
			(connect_pads
				(clearance 0)
			)
			(min_thickness 0.25)
			(keepout
				(tracks allowed)
				(vias not_allowed)
				(pads allowed)
				(copperpour not_allowed)
				(footprints allowed)
			)
			(placement
				(enabled no)
				(sheetname "")
			)
			(fill
				(thermal_gap 0.5)
				(thermal_bridge_width 0.5)
				(island_removal_mode 0)
			)
			(polygon
				(pts
					(xy 162.9537 -75.3618) (xy 162.4457 -75.3618) (xy 162.4457 -74.5998) (xy 162.9537 -74.5998)
				)
			)
		)
		(zone
			(layer "F.Cu")
			(hatch none 0.5)
			(connect_pads
				(clearance 0)
			)
			(min_thickness 0.25)
			(keepout
				(tracks not_allowed)
				(vias allowed)
				(pads allowed)
				(copperpour not_allowed)
				(footprints allowed)
			)
			(placement
				(enabled no)
				(sheetname "")
			)
			(fill
				(thermal_gap 0.5)
				(thermal_bridge_width 0.5)
				(island_removal_mode 0)
			)
			(polygon
				(pts
					(xy 162.9537 -74.5998) (xy 162.9537 -75.3618) (xy 162.4457 -75.3618) (xy 162.4457 -74.5998)
				)
			)
		)
	)
	(footprint ""
		(layer "F.Cu")
		(at 392.165078 -86.569042)
		(property "Reference" "R3P64"
			(at 0 0 0)
			(layer "F.SilkS")
			(hide yes)
			(effects
				(font
					(size 1.27 1.27)
				)
			)
		)
		(property "Value" ""
			(at 0 0 0)
			(layer "F.Fab")
			(effects
				(font
					(size 1.27 1.27)
				)
			)
		)
		(duplicate_pad_numbers_are_jumpers no)
		(fp_poly
			(pts
				(xy -0.2794 -0.1016) (xy 0.2794 -0.1016) (xy 0.2794 0.9906) (xy -0.2794 0.9906)
			)
			(stroke
				(width 0)
				(type default)
			)
			(fill no)
			(layer "F.CrtYd")
		)
		(fp_line
			(start -0.2794 -0.1016)
			(end -0.2794 0.9906)
			(stroke
				(width 0.1)
				(type default)
			)
			(layer "F.Fab")
		)
		(fp_line
			(start -0.2794 0.9906)
			(end 0.2794 0.9906)
			(stroke
				(width 0.1)
				(type default)
			)
			(layer "F.Fab")
		)
		(fp_line
			(start 0.2794 -0.1016)
			(end -0.2794 -0.1016)
			(stroke
				(width 0.1)
				(type default)
			)
			(layer "F.Fab")
		)
		(fp_line
			(start 0.2794 0.9906)
			(end 0.2794 -0.1016)
			(stroke
				(width 0.1)
				(type default)
			)
			(layer "F.Fab")
		)
		(pad "1" smd rect
			(at 0 0)
			(size 0.508 0.508)
			(layers "F.Cu" "F.Mask" "F.Paste")
			(net "FM_FLASH_ATTACH_CFG_STRAP")
		)
		(pad "2" smd rect
			(at 0 0.889)
			(size 0.508 0.508)
			(layers "F.Cu" "F.Mask" "F.Paste")
			(net "GND")
		)
		(zone
			(layer "F.Cu")
			(hatch none 0.5)
			(connect_pads
				(clearance 0)
			)
			(min_thickness 0.25)
			(keepout
				(tracks allowed)
				(vias not_allowed)
				(pads allowed)
				(copperpour not_allowed)
				(footprints allowed)
			)
			(placement
				(enabled no)
				(sheetname "")
			)
			(fill
				(thermal_gap 0.5)
				(thermal_bridge_width 0.5)
				(island_removal_mode 0)
			)
			(polygon
				(pts
					(xy 391.911078 -86.315042) (xy 392.419078 -86.315042) (xy 392.419078 -85.934042) (xy 391.911078 -85.934042)
				)
			)
		)
		(zone
			(layer "F.Cu")
			(hatch none 0.5)
			(connect_pads
				(clearance 0)
			)
			(min_thickness 0.25)
			(keepout
				(tracks not_allowed)
				(vias allowed)
				(pads allowed)
				(copperpour not_allowed)
				(footprints allowed)
			)
			(placement
				(enabled no)
				(sheetname "")
			)
			(fill
				(thermal_gap 0.5)
				(thermal_bridge_width 0.5)
				(island_removal_mode 0)
			)
			(polygon
				(pts
					(xy 391.911078 -85.934042) (xy 392.419078 -85.934042) (xy 392.419078 -86.315042) (xy 391.911078 -86.315042)
				)
			)
		)
	)
	(footprint ""
		(layer "F.Cu")
		(at 400.489674 -33.50514)
		(property "Reference" "R8C16"
			(at 0 0 0)
			(layer "F.SilkS")
			(hide yes)
			(effects
				(font
					(size 1.27 1.27)
				)
			)
		)
		(property "Value" ""
			(at 0 0 0)
			(layer "F.Fab")
			(effects
				(font
					(size 1.27 1.27)
				)
			)
		)
		(duplicate_pad_numbers_are_jumpers no)
		(fp_poly
			(pts
				(xy -0.2794 -0.1016) (xy 0.2794 -0.1016) (xy 0.2794 0.9906) (xy -0.2794 0.9906)
			)
			(stroke
				(width 0)
				(type default)
			)
			(fill no)
			(layer "F.CrtYd")
		)
		(fp_line
			(start -0.2794 -0.1016)
			(end -0.2794 0.9906)
			(stroke
				(width 0.1)
				(type default)
			)
			(layer "F.Fab")
		)
		(fp_line
			(start -0.2794 0.9906)
			(end 0.2794 0.9906)
			(stroke
				(width 0.1)
				(type default)
			)
			(layer "F.Fab")
		)
		(fp_line
			(start 0.2794 -0.1016)
			(end -0.2794 -0.1016)
			(stroke
				(width 0.1)
				(type default)
			)
			(layer "F.Fab")
		)
		(fp_line
			(start 0.2794 0.9906)
			(end 0.2794 -0.1016)
			(stroke
				(width 0.1)
				(type default)
			)
			(layer "F.Fab")
		)
		(pad "1" smd rect
			(at 0 0)
			(size 0.508 0.508)
			(layers "F.Cu" "F.Mask" "F.Paste")
			(net "P3V3_STBY")
		)
		(pad "2" smd rect
			(at 0 0.889)
			(size 0.508 0.508)
			(layers "F.Cu" "F.Mask" "F.Paste")
			(net "SMB_HOST_STBY_LVC3_SDA_R")
		)
		(zone
			(layer "F.Cu")
			(hatch none 0.5)
			(connect_pads
				(clearance 0)
			)
			(min_thickness 0.25)
			(keepout
				(tracks allowed)
				(vias not_allowed)
				(pads allowed)
				(copperpour not_allowed)
				(footprints allowed)
			)
			(placement
				(enabled no)
				(sheetname "")
			)
			(fill
				(thermal_gap 0.5)
				(thermal_bridge_width 0.5)
				(island_removal_mode 0)
			)
			(polygon
				(pts
					(xy 400.235674 -33.25114) (xy 400.743674 -33.25114) (xy 400.743674 -32.87014) (xy 400.235674 -32.87014)
				)
			)
		)
		(zone
			(layer "F.Cu")
			(hatch none 0.5)
			(connect_pads
				(clearance 0)
			)
			(min_thickness 0.25)
			(keepout
				(tracks not_allowed)
				(vias allowed)
				(pads allowed)
				(copperpour not_allowed)
				(footprints allowed)
			)
			(placement
				(enabled no)
				(sheetname "")
			)
			(fill
				(thermal_gap 0.5)
				(thermal_bridge_width 0.5)
				(island_removal_mode 0)
			)
			(polygon
				(pts
					(xy 400.235674 -32.87014) (xy 400.743674 -32.87014) (xy 400.743674 -33.25114) (xy 400.235674 -33.25114)
				)
			)
		)
	)
	(footprint ""
		(layer "F.Cu")
		(at 103.16464 -77.636116)
		(property "Reference" "C2D27"
			(at 0 0 0)
			(layer "F.SilkS")
			(hide yes)
			(effects
				(font
					(size 1.27 1.27)
				)
			)
		)
		(property "Value" ""
			(at 0 0 0)
			(layer "F.Fab")
			(effects
				(font
					(size 1.27 1.27)
				)
			)
		)
		(duplicate_pad_numbers_are_jumpers no)
		(fp_poly
			(pts
				(xy -0.4953 -0.2032) (xy 0.4953 -0.2032) (xy 0.4953 1.6002) (xy -0.4953 1.6002)
			)
			(stroke
				(width 0)
				(type default)
			)
			(fill no)
			(layer "F.CrtYd")
		)
		(fp_line
			(start -0.4953 -0.2032)
			(end 0.4953 -0.2032)
			(stroke
				(width 0.1)
				(type default)
			)
			(layer "F.Fab")
		)
		(fp_line
			(start -0.4953 1.6002)
			(end -0.4953 -0.2032)
			(stroke
				(width 0.1)
				(type default)
			)
			(layer "F.Fab")
		)
		(fp_line
			(start 0.4953 -0.2032)
			(end 0.4953 1.6002)
			(stroke
				(width 0.1)
				(type default)
			)
			(layer "F.Fab")
		)
		(fp_line
			(start 0.4953 1.6002)
			(end -0.4953 1.6002)
			(stroke
				(width 0.1)
				(type default)
			)
			(layer "F.Fab")
		)
		(pad "1" smd rect
			(at 0 0)
			(size 0.762 0.889)
			(layers "F.Cu" "F.Mask" "F.Paste")
			(net "PVCCIN_CPU1")
		)
		(pad "2" smd rect
			(at 0 1.397)
			(size 0.762 0.889)
			(layers "F.Cu" "F.Mask" "F.Paste")
			(net "GND")
		)
		(zone
			(layer "F.Cu")
			(hatch none 0.5)
			(connect_pads
				(clearance 0)
			)
			(min_thickness 0.25)
			(keepout
				(tracks not_allowed)
				(vias allowed)
				(pads allowed)
				(copperpour not_allowed)
				(footprints allowed)
			)
			(placement
				(enabled no)
				(sheetname "")
			)
			(fill
				(thermal_gap 0.5)
				(thermal_bridge_width 0.5)
				(island_removal_mode 0)
			)
			(polygon
				(pts
					(xy 102.78364 -77.191616) (xy 103.54564 -77.191616) (xy 103.54564 -76.683616) (xy 102.78364 -76.683616)
				)
			)
		)
	)
	(footprint ""
		(layer "F.Cu")
		(at 100.903024 -68.412614 180)
		(property "Reference" "C2D43"
			(at 0 0 180)
			(layer "F.SilkS")
			(hide yes)
			(effects
				(font
					(size 1.27 1.27)
				)
			)
		)
		(property "Value" ""
			(at 0 0 180)
			(layer "F.Fab")
			(effects
				(font
					(size 1.27 1.27)
				)
			)
		)
		(duplicate_pad_numbers_are_jumpers no)
		(fp_poly
			(pts
				(xy -0.4953 -0.2032) (xy 0.4953 -0.2032) (xy 0.4953 1.6002) (xy -0.4953 1.6002)
			)
			(stroke
				(width 0)
				(type default)
			)
			(fill no)
			(layer "F.CrtYd")
		)
		(fp_line
			(start 0.4953 1.6002)
			(end -0.4953 1.6002)
			(stroke
				(width 0.1)
				(type default)
			)
			(layer "F.Fab")
		)
		(fp_line
			(start 0.4953 -0.2032)
			(end 0.4953 1.6002)
			(stroke
				(width 0.1)
				(type default)
			)
			(layer "F.Fab")
		)
		(fp_line
			(start -0.4953 1.6002)
			(end -0.4953 -0.2032)
			(stroke
				(width 0.1)
				(type default)
			)
			(layer "F.Fab")
		)
		(fp_line
			(start -0.4953 -0.2032)
			(end 0.4953 -0.2032)
			(stroke
				(width 0.1)
				(type default)
			)
			(layer "F.Fab")
		)
		(pad "1" smd rect
			(at 0 0 180)
			(size 0.762 0.889)
			(layers "F.Cu" "F.Mask" "F.Paste")
			(net "PVDDQ_GHJ")
		)
		(pad "2" smd rect
			(at 0 1.397 180)
			(size 0.762 0.889)
			(layers "F.Cu" "F.Mask" "F.Paste")
			(net "GND")
		)
		(zone
			(layer "F.Cu")
			(hatch none 0.5)
			(connect_pads
				(clearance 0)
			)
			(min_thickness 0.25)
			(keepout
				(tracks not_allowed)
				(vias allowed)
				(pads allowed)
				(copperpour not_allowed)
				(footprints allowed)
			)
			(placement
				(enabled no)
				(sheetname "")
			)
			(fill
				(thermal_gap 0.5)
				(thermal_bridge_width 0.5)
				(island_removal_mode 0)
			)
			(polygon
				(pts
					(xy 101.284024 -68.857114) (xy 100.522024 -68.857114) (xy 100.522024 -69.365114) (xy 101.284024 -69.365114)
				)
			)
		)
	)
	(footprint ""
		(layer "F.Cu")
		(at 276.978872 -73.318116)
		(property "Reference" "C6D8"
			(at 0 0 0)
			(layer "F.SilkS")
			(hide yes)
			(effects
				(font
					(size 1.27 1.27)
				)
			)
		)
		(property "Value" ""
			(at 0 0 0)
			(layer "F.Fab")
			(effects
				(font
					(size 1.27 1.27)
				)
			)
		)
		(duplicate_pad_numbers_are_jumpers no)
		(fp_poly
			(pts
				(xy -0.4953 -0.2032) (xy 0.4953 -0.2032) (xy 0.4953 1.6002) (xy -0.4953 1.6002)
			)
			(stroke
				(width 0)
				(type default)
			)
			(fill no)
			(layer "F.CrtYd")
		)
		(fp_line
			(start -0.4953 -0.2032)
			(end 0.4953 -0.2032)
			(stroke
				(width 0.1)
				(type default)
			)
			(layer "F.Fab")
		)
		(fp_line
			(start -0.4953 1.6002)
			(end -0.4953 -0.2032)
			(stroke
				(width 0.1)
				(type default)
			)
			(layer "F.Fab")
		)
		(fp_line
			(start 0.4953 -0.2032)
			(end 0.4953 1.6002)
			(stroke
				(width 0.1)
				(type default)
			)
			(layer "F.Fab")
		)
		(fp_line
			(start 0.4953 1.6002)
			(end -0.4953 1.6002)
			(stroke
				(width 0.1)
				(type default)
			)
			(layer "F.Fab")
		)
		(pad "1" smd rect
			(at 0 0)
			(size 0.762 0.889)
			(layers "F.Cu" "F.Mask" "F.Paste")
			(net "PVCCMCP_CPU0")
		)
		(pad "2" smd rect
			(at 0 1.397)
			(size 0.762 0.889)
			(layers "F.Cu" "F.Mask" "F.Paste")
			(net "GND")
		)
		(zone
			(layer "F.Cu")
			(hatch none 0.5)
			(connect_pads
				(clearance 0)
			)
			(min_thickness 0.25)
			(keepout
				(tracks not_allowed)
				(vias allowed)
				(pads allowed)
				(copperpour not_allowed)
				(footprints allowed)
			)
			(placement
				(enabled no)
				(sheetname "")
			)
			(fill
				(thermal_gap 0.5)
				(thermal_bridge_width 0.5)
				(island_removal_mode 0)
			)
			(polygon
				(pts
					(xy 276.597872 -72.873616) (xy 277.359872 -72.873616) (xy 277.359872 -72.365616) (xy 276.597872 -72.365616)
				)
			)
		)
	)
	(footprint ""
		(layer "F.Cu")
		(at 478.545144 -14.478508 -90)
		(property "Reference" "R9G19"
			(at -0.8382 -0.67818 270)
			(unlocked yes)
			(layer "F.SilkS")
			(effects
				(font
					(size 0.4064 0.254)
					(thickness 0.1524)
				)
				(justify left)
			)
		)
		(property "Value" ""
			(at 0 0 270)
			(layer "F.Fab")
			(effects
				(font
					(size 1.27 1.27)
				)
			)
		)
		(duplicate_pad_numbers_are_jumpers no)
		(fp_poly
			(pts
				(xy -0.2794 -0.1016) (xy 0.2794 -0.1016) (xy 0.2794 0.9906) (xy -0.2794 0.9906)
			)
			(stroke
				(width 0)
				(type default)
			)
			(fill no)
			(layer "F.CrtYd")
		)
		(fp_line
			(start -0.2794 0.9906)
			(end 0.2794 0.9906)
			(stroke
				(width 0.1)
				(type default)
			)
			(layer "F.Fab")
		)
		(fp_line
			(start 0.2794 0.9906)
			(end 0.2794 -0.1016)
			(stroke
				(width 0.1)
				(type default)
			)
			(layer "F.Fab")
		)
		(fp_line
			(start -0.2794 -0.1016)
			(end -0.2794 0.9906)
			(stroke
				(width 0.1)
				(type default)
			)
			(layer "F.Fab")
		)
		(fp_line
			(start 0.2794 -0.1016)
			(end -0.2794 -0.1016)
			(stroke
				(width 0.1)
				(type default)
			)
			(layer "F.Fab")
		)
		(pad "1" smd rect
			(at 0 0 270)
			(size 0.508 0.508)
			(layers "F.Cu" "F.Mask" "F.Paste")
			(net "NIC_MDI_SPRV_RJ45_1_DP")
		)
		(pad "2" smd rect
			(at 0 0.889 270)
			(size 0.508 0.508)
			(layers "F.Cu" "F.Mask" "F.Paste")
			(net "NIC_MDI_SPRV_RJ45_1_R_DP")
		)
		(zone
			(layer "F.Cu")
			(hatch none 0.5)
			(connect_pads
				(clearance 0)
			)
			(min_thickness 0.25)
			(keepout
				(tracks not_allowed)
				(vias allowed)
				(pads allowed)
				(copperpour not_allowed)
				(footprints allowed)
			)
			(placement
				(enabled no)
				(sheetname "")
			)
			(fill
				(thermal_gap 0.5)
				(thermal_bridge_width 0.5)
				(island_removal_mode 0)
			)
			(polygon
				(pts
					(xy 477.910144 -14.732508) (xy 477.910144 -14.224508) (xy 478.291144 -14.224508) (xy 478.291144 -14.732508)
				)
			)
		)
		(zone
			(layer "F.Cu")
			(hatch none 0.5)
			(connect_pads
				(clearance 0)
			)
			(min_thickness 0.25)
			(keepout
				(tracks allowed)
				(vias not_allowed)
				(pads allowed)
				(copperpour not_allowed)
				(footprints allowed)
			)
			(placement
				(enabled no)
				(sheetname "")
			)
			(fill
				(thermal_gap 0.5)
				(thermal_bridge_width 0.5)
				(island_removal_mode 0)
			)
			(polygon
				(pts
					(xy 478.291144 -14.732508) (xy 478.291144 -14.224508) (xy 477.910144 -14.224508) (xy 477.910144 -14.732508)
				)
			)
		)
	)
	(footprint ""
		(layer "F.Cu")
		(at 411.327092 -125.088904 -90)
		(property "Reference" "R8B12"
			(at 0 0 270)
			(layer "F.SilkS")
			(hide yes)
			(effects
				(font
					(size 1.27 1.27)
				)
			)
		)
		(property "Value" ""
			(at 0 0 270)
			(layer "F.Fab")
			(effects
				(font
					(size 1.27 1.27)
				)
			)
		)
		(duplicate_pad_numbers_are_jumpers no)
		(fp_poly
			(pts
				(xy -0.2794 -0.1016) (xy 0.2794 -0.1016) (xy 0.2794 0.9906) (xy -0.2794 0.9906)
			)
			(stroke
				(width 0)
				(type default)
			)
			(fill no)
			(layer "F.CrtYd")
		)
		(fp_line
			(start -0.2794 0.9906)
			(end 0.2794 0.9906)
			(stroke
				(width 0.1)
				(type default)
			)
			(layer "F.Fab")
		)
		(fp_line
			(start 0.2794 0.9906)
			(end 0.2794 -0.1016)
			(stroke
				(width 0.1)
				(type default)
			)
			(layer "F.Fab")
		)
		(fp_line
			(start -0.2794 -0.1016)
			(end -0.2794 0.9906)
			(stroke
				(width 0.1)
				(type default)
			)
			(layer "F.Fab")
		)
		(fp_line
			(start 0.2794 -0.1016)
			(end -0.2794 -0.1016)
			(stroke
				(width 0.1)
				(type default)
			)
			(layer "F.Fab")
		)
		(pad "1" smd rect
			(at 0 0 270)
			(size 0.508 0.508)
			(layers "F.Cu" "F.Mask" "F.Paste")
			(net "VSENSE_P1V05_PCH_STBY_AVSN")
		)
		(pad "2" smd rect
			(at 0 0.889 270)
			(size 0.508 0.508)
			(layers "F.Cu" "F.Mask" "F.Paste")
			(net "GND")
		)
		(zone
			(layer "F.Cu")
			(hatch none 0.5)
			(connect_pads
				(clearance 0)
			)
			(min_thickness 0.25)
			(keepout
				(tracks not_allowed)
				(vias allowed)
				(pads allowed)
				(copperpour not_allowed)
				(footprints allowed)
			)
			(placement
				(enabled no)
				(sheetname "")
			)
			(fill
				(thermal_gap 0.5)
				(thermal_bridge_width 0.5)
				(island_removal_mode 0)
			)
			(polygon
				(pts
					(xy 410.692092 -125.342904) (xy 410.692092 -124.834904) (xy 411.073092 -124.834904) (xy 411.073092 -125.342904)
				)
			)
		)
		(zone
			(layer "F.Cu")
			(hatch none 0.5)
			(connect_pads
				(clearance 0)
			)
			(min_thickness 0.25)
			(keepout
				(tracks allowed)
				(vias not_allowed)
				(pads allowed)
				(copperpour not_allowed)
				(footprints allowed)
			)
			(placement
				(enabled no)
				(sheetname "")
			)
			(fill
				(thermal_gap 0.5)
				(thermal_bridge_width 0.5)
				(island_removal_mode 0)
			)
			(polygon
				(pts
					(xy 411.073092 -125.342904) (xy 411.073092 -124.834904) (xy 410.692092 -124.834904) (xy 410.692092 -125.342904)
				)
			)
		)
	)
	(footprint ""
		(layer "F.Cu")
		(at 395.732 -0.2286)
		(property "Reference" "R8G17"
			(at 0 0 0)
			(layer "F.SilkS")
			(hide yes)
			(effects
				(font
					(size 1.27 1.27)
				)
			)
		)
		(property "Value" ""
			(at 0 0 0)
			(layer "F.Fab")
			(effects
				(font
					(size 1.27 1.27)
				)
			)
		)
		(duplicate_pad_numbers_are_jumpers no)
		(fp_poly
			(pts
				(xy -0.2794 -0.1016) (xy 0.2794 -0.1016) (xy 0.2794 0.9906) (xy -0.2794 0.9906)
			)
			(stroke
				(width 0)
				(type default)
			)
			(fill no)
			(layer "F.CrtYd")
		)
		(fp_line
			(start -0.2794 -0.1016)
			(end -0.2794 0.9906)
			(stroke
				(width 0.1)
				(type default)
			)
			(layer "F.Fab")
		)
		(fp_line
			(start -0.2794 0.9906)
			(end 0.2794 0.9906)
			(stroke
				(width 0.1)
				(type default)
			)
			(layer "F.Fab")
		)
		(fp_line
			(start 0.2794 -0.1016)
			(end -0.2794 -0.1016)
			(stroke
				(width 0.1)
				(type default)
			)
			(layer "F.Fab")
		)
		(fp_line
			(start 0.2794 0.9906)
			(end 0.2794 -0.1016)
			(stroke
				(width 0.1)
				(type default)
			)
			(layer "F.Fab")
		)
		(pad "1" smd rect
			(at 0 0)
			(size 0.508 0.508)
			(layers "F.Cu" "F.Mask" "F.Paste")
			(net "JTAG_BMC_TCK")
		)
		(pad "2" smd rect
			(at 0 0.889)
			(size 0.508 0.508)
			(layers "F.Cu" "F.Mask" "F.Paste")
			(net "JTAG_TCK")
		)
		(zone
			(layer "F.Cu")
			(hatch none 0.5)
			(connect_pads
				(clearance 0)
			)
			(min_thickness 0.25)
			(keepout
				(tracks allowed)
				(vias not_allowed)
				(pads allowed)
				(copperpour not_allowed)
				(footprints allowed)
			)
			(placement
				(enabled no)
				(sheetname "")
			)
			(fill
				(thermal_gap 0.5)
				(thermal_bridge_width 0.5)
				(island_removal_mode 0)
			)
			(polygon
				(pts
					(xy 395.478 0.0254) (xy 395.986 0.0254) (xy 395.986 0.4064) (xy 395.478 0.4064)
				)
			)
		)
		(zone
			(layer "F.Cu")
			(hatch none 0.5)
			(connect_pads
				(clearance 0)
			)
			(min_thickness 0.25)
			(keepout
				(tracks not_allowed)
				(vias allowed)
				(pads allowed)
				(copperpour not_allowed)
				(footprints allowed)
			)
			(placement
				(enabled no)
				(sheetname "")
			)
			(fill
				(thermal_gap 0.5)
				(thermal_bridge_width 0.5)
				(island_removal_mode 0)
			)
			(polygon
				(pts
					(xy 395.478 0.4064) (xy 395.986 0.4064) (xy 395.986 0.0254) (xy 395.478 0.0254)
				)
			)
		)
	)
	(footprint ""
		(layer "F.Cu")
		(at 14.097 -83.058 90)
		(property "Reference" "R1D15"
			(at 0 0 90)
			(layer "F.SilkS")
			(hide yes)
			(effects
				(font
					(size 1.27 1.27)
				)
			)
		)
		(property "Value" ""
			(at 0 0 90)
			(layer "F.Fab")
			(effects
				(font
					(size 1.27 1.27)
				)
			)
		)
		(duplicate_pad_numbers_are_jumpers no)
		(fp_poly
			(pts
				(xy -0.2794 -0.1016) (xy 0.2794 -0.1016) (xy 0.2794 0.9906) (xy -0.2794 0.9906)
			)
			(stroke
				(width 0)
				(type default)
			)
			(fill no)
			(layer "F.CrtYd")
		)
		(fp_line
			(start 0.2794 -0.1016)
			(end -0.2794 -0.1016)
			(stroke
				(width 0.1)
				(type default)
			)
			(layer "F.Fab")
		)
		(fp_line
			(start -0.2794 -0.1016)
			(end -0.2794 0.9906)
			(stroke
				(width 0.1)
				(type default)
			)
			(layer "F.Fab")
		)
		(fp_line
			(start 0.2794 0.9906)
			(end 0.2794 -0.1016)
			(stroke
				(width 0.1)
				(type default)
			)
			(layer "F.Fab")
		)
		(fp_line
			(start -0.2794 0.9906)
			(end 0.2794 0.9906)
			(stroke
				(width 0.1)
				(type default)
			)
			(layer "F.Fab")
		)
		(pad "1" smd rect
			(at 0 0 90)
			(size 0.508 0.508)
			(layers "F.Cu" "F.Mask" "F.Paste")
			(net "P12V_PSU")
		)
		(pad "2" smd rect
			(at 0 0.889 90)
			(size 0.508 0.508)
			(layers "F.Cu" "F.Mask" "F.Paste")
			(net "A_HSC_OCP_SEL")
		)
		(zone
			(layer "F.Cu")
			(hatch none 0.5)
			(connect_pads
				(clearance 0)
			)
			(min_thickness 0.25)
			(keepout
				(tracks allowed)
				(vias not_allowed)
				(pads allowed)
				(copperpour not_allowed)
				(footprints allowed)
			)
			(placement
				(enabled no)
				(sheetname "")
			)
			(fill
				(thermal_gap 0.5)
				(thermal_bridge_width 0.5)
				(island_removal_mode 0)
			)
			(polygon
				(pts
					(xy 14.351 -82.804) (xy 14.351 -83.312) (xy 14.732 -83.312) (xy 14.732 -82.804)
				)
			)
		)
		(zone
			(layer "F.Cu")
			(hatch none 0.5)
			(connect_pads
				(clearance 0)
			)
			(min_thickness 0.25)
			(keepout
				(tracks not_allowed)
				(vias allowed)
				(pads allowed)
				(copperpour not_allowed)
				(footprints allowed)
			)
			(placement
				(enabled no)
				(sheetname "")
			)
			(fill
				(thermal_gap 0.5)
				(thermal_bridge_width 0.5)
				(island_removal_mode 0)
			)
			(polygon
				(pts
					(xy 14.732 -82.804) (xy 14.732 -83.312) (xy 14.351 -83.312) (xy 14.351 -82.804)
				)
			)
		)
	)
	(footprint ""
		(layer "F.Cu")
		(at 248.8565 -3.3528 -90)
		(property "Reference" "C5G12"
			(at 1.848866 0.752348 270)
			(unlocked yes)
			(layer "F.SilkS")
			(effects
				(font
					(size 1.27 0.9652)
					(thickness 0.1524)
				)
			)
		)
		(property "Value" ""
			(at 0 0 270)
			(layer "F.Fab")
			(effects
				(font
					(size 1.27 1.27)
				)
			)
		)
		(duplicate_pad_numbers_are_jumpers no)
		(fp_rect
			(start -0.500126 1.598422)
			(end 0.500126 -0.201422)
			(stroke
				(width 0)
				(type default)
			)
			(fill no)
			(layer "F.CrtYd")
		)
		(fp_line
			(start -0.500126 1.598422)
			(end -0.500126 -0.201422)
			(stroke
				(width 0.1)
				(type default)
			)
			(layer "F.Fab")
		)
		(fp_line
			(start 0.500126 1.598422)
			(end -0.500126 1.598422)
			(stroke
				(width 0.1)
				(type default)
			)
			(layer "F.Fab")
		)
		(fp_line
			(start -0.500126 -0.201422)
			(end 0.500126 -0.201422)
			(stroke
				(width 0.1)
				(type default)
			)
			(layer "F.Fab")
		)
		(fp_line
			(start 0.500126 -0.201422)
			(end 0.500126 1.598422)
			(stroke
				(width 0.1)
				(type default)
			)
			(layer "F.Fab")
		)
		(pad "1" smd rect
			(at 0 0 180)
			(size 0.889 0.9906)
			(layers "F.Cu" "F.Mask" "F.Paste")
			(net "PVDDQ_ABC")
		)
		(pad "2" smd rect
			(at 0 1.397 180)
			(size 0.889 0.9906)
			(layers "F.Cu" "F.Mask" "F.Paste")
			(net "GND")
		)
		(zone
			(layer "F.Cu")
			(hatch none 0.5)
			(connect_pads
				(clearance 0)
			)
			(min_thickness 0.25)
			(keepout
				(tracks not_allowed)
				(vias allowed)
				(pads allowed)
				(copperpour not_allowed)
				(footprints allowed)
			)
			(placement
				(enabled no)
				(sheetname "")
			)
			(fill
				(thermal_gap 0.5)
				(thermal_bridge_width 0.5)
				(island_removal_mode 0)
			)
			(polygon
				(pts
					(xy 247.904 -3.8481) (xy 247.904 -2.8575) (xy 248.412 -2.8575) (xy 248.412 -3.8481)
				)
			)
		)
		(zone
			(layer "F.Cu")
			(hatch none 0.5)
			(connect_pads
				(clearance 0)
			)
			(min_thickness 0.25)
			(keepout
				(tracks allowed)
				(vias not_allowed)
				(pads allowed)
				(copperpour not_allowed)
				(footprints allowed)
			)
			(placement
				(enabled no)
				(sheetname "")
			)
			(fill
				(thermal_gap 0.5)
				(thermal_bridge_width 0.5)
				(island_removal_mode 0)
			)
			(polygon
				(pts
					(xy 247.904 -3.8481) (xy 247.904 -2.8575) (xy 248.412 -2.8575) (xy 248.412 -3.8481)
				)
			)
		)
	)
	(footprint ""
		(layer "F.Cu")
		(at 0.724662 -124.076968 90)
		(property "Reference" "RF22"
			(at -0.8382 -0.67818 90)
			(unlocked yes)
			(layer "F.SilkS")
			(effects
				(font
					(size 0.4064 0.254)
					(thickness 0.1524)
				)
				(justify left)
			)
		)
		(property "Value" ""
			(at 0 0 90)
			(layer "F.Fab")
			(effects
				(font
					(size 1.27 1.27)
				)
			)
		)
		(duplicate_pad_numbers_are_jumpers no)
		(fp_poly
			(pts
				(xy -0.2794 -0.1016) (xy 0.2794 -0.1016) (xy 0.2794 0.9906) (xy -0.2794 0.9906)
			)
			(stroke
				(width 0)
				(type default)
			)
			(fill no)
			(layer "F.CrtYd")
		)
		(fp_line
			(start 0.2794 -0.1016)
			(end -0.2794 -0.1016)
			(stroke
				(width 0.1)
				(type default)
			)
			(layer "F.Fab")
		)
		(fp_line
			(start -0.2794 -0.1016)
			(end -0.2794 0.9906)
			(stroke
				(width 0.1)
				(type default)
			)
			(layer "F.Fab")
		)
		(fp_line
			(start 0.2794 0.9906)
			(end 0.2794 -0.1016)
			(stroke
				(width 0.1)
				(type default)
			)
			(layer "F.Fab")
		)
		(fp_line
			(start -0.2794 0.9906)
			(end 0.2794 0.9906)
			(stroke
				(width 0.1)
				(type default)
			)
			(layer "F.Fab")
		)
		(pad "1" smd rect
			(at 0 0 90)
			(size 0.508 0.508)
			(layers "F.Cu" "F.Mask" "F.Paste")
			(net "VR_PVDDQ_KLM_AIREF2")
		)
		(pad "2" smd rect
			(at 0 0.889 90)
			(size 0.508 0.508)
			(layers "F.Cu" "F.Mask" "F.Paste")
			(net "ISENSE_PVDDQ_KLM_PH2_IMON")
		)
		(zone
			(layer "F.Cu")
			(hatch none 0.5)
			(connect_pads
				(clearance 0)
			)
			(min_thickness 0.25)
			(keepout
				(tracks allowed)
				(vias not_allowed)
				(pads allowed)
				(copperpour not_allowed)
				(footprints allowed)
			)
			(placement
				(enabled no)
				(sheetname "")
			)
			(fill
				(thermal_gap 0.5)
				(thermal_bridge_width 0.5)
				(island_removal_mode 0)
			)
			(polygon
				(pts
					(xy 0.978662 -123.822968) (xy 0.978662 -124.330968) (xy 1.359662 -124.330968) (xy 1.359662 -123.822968)
				)
			)
		)
		(zone
			(layer "F.Cu")
			(hatch none 0.5)
			(connect_pads
				(clearance 0)
			)
			(min_thickness 0.25)
			(keepout
				(tracks not_allowed)
				(vias allowed)
				(pads allowed)
				(copperpour not_allowed)
				(footprints allowed)
			)
			(placement
				(enabled no)
				(sheetname "")
			)
			(fill
				(thermal_gap 0.5)
				(thermal_bridge_width 0.5)
				(island_removal_mode 0)
			)
			(polygon
				(pts
					(xy 1.359662 -123.822968) (xy 1.359662 -124.330968) (xy 0.978662 -124.330968) (xy 0.978662 -123.822968)
				)
			)
		)
	)
	(footprint ""
		(layer "F.Cu")
		(at 376.678444 -10.916158)
		(property "Reference" "C7G17"
			(at 0 0 0)
			(layer "F.SilkS")
			(hide yes)
			(effects
				(font
					(size 1.27 1.27)
				)
			)
		)
		(property "Value" ""
			(at 0 0 0)
			(layer "F.Fab")
			(effects
				(font
					(size 1.27 1.27)
				)
			)
		)
		(duplicate_pad_numbers_are_jumpers no)
		(fp_rect
			(start -0.3048 0.9906)
			(end 0.3048 -0.1016)
			(stroke
				(width 0)
				(type default)
			)
			(fill no)
			(layer "F.CrtYd")
		)
		(fp_line
			(start -0.3048 -0.1016)
			(end -0.3048 0.9906)
			(stroke
				(width 0.1)
				(type default)
			)
			(layer "F.Fab")
		)
		(fp_line
			(start -0.3048 0.9906)
			(end 0.3048 0.9906)
			(stroke
				(width 0.1)
				(type default)
			)
			(layer "F.Fab")
		)
		(fp_line
			(start 0.3048 -0.1016)
			(end -0.3048 -0.1016)
			(stroke
				(width 0.1)
				(type default)
			)
			(layer "F.Fab")
		)
		(fp_line
			(start 0.3048 0.9906)
			(end 0.3048 -0.1016)
			(stroke
				(width 0.1)
				(type default)
			)
			(layer "F.Fab")
		)
		(pad "1" smd rect
			(at 0 0)
			(size 0.508 0.508)
			(layers "F.Cu" "F.Mask" "F.Paste")
			(net "P3E_CPU0_PE2_SS_TXP<9>")
		)
		(pad "2" smd rect
			(at 0 0.889)
			(size 0.508 0.508)
			(layers "F.Cu" "F.Mask" "F.Paste")
			(net "P3E_CPU0_PE2_SS_C_TXP<9>")
		)
		(zone
			(layer "F.Cu")
			(hatch none 0.5)
			(connect_pads
				(clearance 0)
			)
			(min_thickness 0.25)
			(keepout
				(tracks not_allowed)
				(vias allowed)
				(pads allowed)
				(copperpour not_allowed)
				(footprints allowed)
			)
			(placement
				(enabled no)
				(sheetname "")
			)
			(fill
				(thermal_gap 0.5)
				(thermal_bridge_width 0.5)
				(island_removal_mode 0)
			)
			(polygon
				(pts
					(xy 376.424444 -10.281158) (xy 376.932444 -10.281158) (xy 376.932444 -10.662158) (xy 376.424444 -10.662158)
				)
			)
		)
		(zone
			(layer "F.Cu")
			(hatch none 0.5)
			(connect_pads
				(clearance 0)
			)
			(min_thickness 0.25)
			(keepout
				(tracks allowed)
				(vias not_allowed)
				(pads allowed)
				(copperpour not_allowed)
				(footprints allowed)
			)
			(placement
				(enabled no)
				(sheetname "")
			)
			(fill
				(thermal_gap 0.5)
				(thermal_bridge_width 0.5)
				(island_removal_mode 0)
			)
			(polygon
				(pts
					(xy 376.424444 -10.281158) (xy 376.932444 -10.281158) (xy 376.932444 -10.662158) (xy 376.424444 -10.662158)
				)
			)
		)
	)
	(footprint ""
		(layer "F.Cu")
		(at 180.848 -8.255)
		(property "Reference" "R4G12"
			(at 0 0 0)
			(layer "F.SilkS")
			(hide yes)
			(effects
				(font
					(size 1.27 1.27)
				)
			)
		)
		(property "Value" ""
			(at 0 0 0)
			(layer "F.Fab")
			(effects
				(font
					(size 1.27 1.27)
				)
			)
		)
		(duplicate_pad_numbers_are_jumpers no)
		(fp_poly
			(pts
				(xy -0.2794 -0.1016) (xy 0.2794 -0.1016) (xy 0.2794 0.9906) (xy -0.2794 0.9906)
			)
			(stroke
				(width 0)
				(type default)
			)
			(fill no)
			(layer "F.CrtYd")
		)
		(fp_line
			(start -0.2794 -0.1016)
			(end -0.2794 0.9906)
			(stroke
				(width 0.1)
				(type default)
			)
			(layer "F.Fab")
		)
		(fp_line
			(start -0.2794 0.9906)
			(end 0.2794 0.9906)
			(stroke
				(width 0.1)
				(type default)
			)
			(layer "F.Fab")
		)
		(fp_line
			(start 0.2794 -0.1016)
			(end -0.2794 -0.1016)
			(stroke
				(width 0.1)
				(type default)
			)
			(layer "F.Fab")
		)
		(fp_line
			(start 0.2794 0.9906)
			(end 0.2794 -0.1016)
			(stroke
				(width 0.1)
				(type default)
			)
			(layer "F.Fab")
		)
		(pad "1" smd rect
			(at 0 0)
			(size 0.508 0.508)
			(layers "F.Cu" "F.Mask" "F.Paste")
			(net "PWRGD_PVPP_GHJ_R")
		)
		(pad "2" smd rect
			(at 0 0.889)
			(size 0.508 0.508)
			(layers "F.Cu" "F.Mask" "F.Paste")
			(net "PWRGD_PVPP_GHJ")
		)
		(zone
			(layer "F.Cu")
			(hatch none 0.5)
			(connect_pads
				(clearance 0)
			)
			(min_thickness 0.25)
			(keepout
				(tracks allowed)
				(vias not_allowed)
				(pads allowed)
				(copperpour not_allowed)
				(footprints allowed)
			)
			(placement
				(enabled no)
				(sheetname "")
			)
			(fill
				(thermal_gap 0.5)
				(thermal_bridge_width 0.5)
				(island_removal_mode 0)
			)
			(polygon
				(pts
					(xy 180.594 -8.001) (xy 181.102 -8.001) (xy 181.102 -7.62) (xy 180.594 -7.62)
				)
			)
		)
		(zone
			(layer "F.Cu")
			(hatch none 0.5)
			(connect_pads
				(clearance 0)
			)
			(min_thickness 0.25)
			(keepout
				(tracks not_allowed)
				(vias allowed)
				(pads allowed)
				(copperpour not_allowed)
				(footprints allowed)
			)
			(placement
				(enabled no)
				(sheetname "")
			)
			(fill
				(thermal_gap 0.5)
				(thermal_bridge_width 0.5)
				(island_removal_mode 0)
			)
			(polygon
				(pts
					(xy 180.594 -7.62) (xy 181.102 -7.62) (xy 181.102 -8.001) (xy 180.594 -8.001)
				)
			)
		)
	)
	(footprint ""
		(layer "F.Cu")
		(at 482.67366 -30.29712 90)
		(property "Reference" "R8F29"
			(at 0 0 90)
			(layer "F.SilkS")
			(hide yes)
			(effects
				(font
					(size 1.27 1.27)
				)
			)
		)
		(property "Value" ""
			(at 0 0 90)
			(layer "F.Fab")
			(effects
				(font
					(size 1.27 1.27)
				)
			)
		)
		(duplicate_pad_numbers_are_jumpers no)
		(fp_poly
			(pts
				(xy -0.2794 -0.1016) (xy 0.2794 -0.1016) (xy 0.2794 0.9906) (xy -0.2794 0.9906)
			)
			(stroke
				(width 0)
				(type default)
			)
			(fill no)
			(layer "F.CrtYd")
		)
		(fp_line
			(start 0.2794 -0.1016)
			(end -0.2794 -0.1016)
			(stroke
				(width 0.1)
				(type default)
			)
			(layer "F.Fab")
		)
		(fp_line
			(start -0.2794 -0.1016)
			(end -0.2794 0.9906)
			(stroke
				(width 0.1)
				(type default)
			)
			(layer "F.Fab")
		)
		(fp_line
			(start 0.2794 0.9906)
			(end 0.2794 -0.1016)
			(stroke
				(width 0.1)
				(type default)
			)
			(layer "F.Fab")
		)
		(fp_line
			(start -0.2794 0.9906)
			(end 0.2794 0.9906)
			(stroke
				(width 0.1)
				(type default)
			)
			(layer "F.Fab")
		)
		(pad "1" smd rect
			(at 0 0 90)
			(size 0.508 0.508)
			(layers "F.Cu" "F.Mask" "F.Paste")
			(net "CLK_25M_BMC_R")
		)
		(pad "2" smd rect
			(at 0 0.889 90)
			(size 0.508 0.508)
			(layers "F.Cu" "F.Mask" "F.Paste")
			(net "CLK_25M_BMC")
		)
		(zone
			(layer "F.Cu")
			(hatch none 0.5)
			(connect_pads
				(clearance 0)
			)
			(min_thickness 0.25)
			(keepout
				(tracks allowed)
				(vias not_allowed)
				(pads allowed)
				(copperpour not_allowed)
				(footprints allowed)
			)
			(placement
				(enabled no)
				(sheetname "")
			)
			(fill
				(thermal_gap 0.5)
				(thermal_bridge_width 0.5)
				(island_removal_mode 0)
			)
			(polygon
				(pts
					(xy 482.92766 -30.04312) (xy 482.92766 -30.55112) (xy 483.30866 -30.55112) (xy 483.30866 -30.04312)
				)
			)
		)
		(zone
			(layer "F.Cu")
			(hatch none 0.5)
			(connect_pads
				(clearance 0)
			)
			(min_thickness 0.25)
			(keepout
				(tracks not_allowed)
				(vias allowed)
				(pads allowed)
				(copperpour not_allowed)
				(footprints allowed)
			)
			(placement
				(enabled no)
				(sheetname "")
			)
			(fill
				(thermal_gap 0.5)
				(thermal_bridge_width 0.5)
				(island_removal_mode 0)
			)
			(polygon
				(pts
					(xy 483.30866 -30.04312) (xy 483.30866 -30.55112) (xy 482.92766 -30.55112) (xy 482.92766 -30.04312)
				)
			)
		)
	)
	(footprint ""
		(layer "F.Cu")
		(at 22.225 -75.438 90)
		(property "Reference" "R1D34"
			(at 0 0 90)
			(layer "F.SilkS")
			(hide yes)
			(effects
				(font
					(size 1.27 1.27)
				)
			)
		)
		(property "Value" ""
			(at 0 0 90)
			(layer "F.Fab")
			(effects
				(font
					(size 1.27 1.27)
				)
			)
		)
		(duplicate_pad_numbers_are_jumpers no)
		(fp_poly
			(pts
				(xy -0.2794 -0.1016) (xy 0.2794 -0.1016) (xy 0.2794 0.9906) (xy -0.2794 0.9906)
			)
			(stroke
				(width 0)
				(type default)
			)
			(fill no)
			(layer "F.CrtYd")
		)
		(fp_line
			(start 0.2794 -0.1016)
			(end -0.2794 -0.1016)
			(stroke
				(width 0.1)
				(type default)
			)
			(layer "F.Fab")
		)
		(fp_line
			(start -0.2794 -0.1016)
			(end -0.2794 0.9906)
			(stroke
				(width 0.1)
				(type default)
			)
			(layer "F.Fab")
		)
		(fp_line
			(start 0.2794 0.9906)
			(end 0.2794 -0.1016)
			(stroke
				(width 0.1)
				(type default)
			)
			(layer "F.Fab")
		)
		(fp_line
			(start -0.2794 0.9906)
			(end 0.2794 0.9906)
			(stroke
				(width 0.1)
				(type default)
			)
			(layer "F.Fab")
		)
		(pad "1" smd rect
			(at 0 0 90)
			(size 0.508 0.508)
			(layers "F.Cu" "F.Mask" "F.Paste")
			(net "A_HSC_ISTART")
		)
		(pad "2" smd rect
			(at 0 0.889 90)
			(size 0.508 0.508)
			(layers "F.Cu" "F.Mask" "F.Paste")
			(net "AGND_HSC")
		)
		(zone
			(layer "F.Cu")
			(hatch none 0.5)
			(connect_pads
				(clearance 0)
			)
			(min_thickness 0.25)
			(keepout
				(tracks allowed)
				(vias not_allowed)
				(pads allowed)
				(copperpour not_allowed)
				(footprints allowed)
			)
			(placement
				(enabled no)
				(sheetname "")
			)
			(fill
				(thermal_gap 0.5)
				(thermal_bridge_width 0.5)
				(island_removal_mode 0)
			)
			(polygon
				(pts
					(xy 22.479 -75.184) (xy 22.479 -75.692) (xy 22.86 -75.692) (xy 22.86 -75.184)
				)
			)
		)
		(zone
			(layer "F.Cu")
			(hatch none 0.5)
			(connect_pads
				(clearance 0)
			)
			(min_thickness 0.25)
			(keepout
				(tracks not_allowed)
				(vias allowed)
				(pads allowed)
				(copperpour not_allowed)
				(footprints allowed)
			)
			(placement
				(enabled no)
				(sheetname "")
			)
			(fill
				(thermal_gap 0.5)
				(thermal_bridge_width 0.5)
				(island_removal_mode 0)
			)
			(polygon
				(pts
					(xy 22.86 -75.184) (xy 22.86 -75.692) (xy 22.479 -75.692) (xy 22.479 -75.184)
				)
			)
		)
	)
	(footprint ""
		(layer "F.Cu")
		(at 13.843 -89.281 90)
		(property "Reference" "R1C28"
			(at 0 0 90)
			(layer "F.SilkS")
			(hide yes)
			(effects
				(font
					(size 1.27 1.27)
				)
			)
		)
		(property "Value" ""
			(at 0 0 90)
			(layer "F.Fab")
			(effects
				(font
					(size 1.27 1.27)
				)
			)
		)
		(duplicate_pad_numbers_are_jumpers no)
		(fp_rect
			(start -0.2794 -0.1016)
			(end 0.2794 0.9906)
			(stroke
				(width 0)
				(type default)
			)
			(fill no)
			(layer "F.CrtYd")
		)
		(fp_line
			(start 0.2794 -0.1016)
			(end -0.2794 -0.1016)
			(stroke
				(width 0.1)
				(type default)
			)
			(layer "F.Fab")
		)
		(fp_line
			(start -0.2794 -0.1016)
			(end -0.2794 0.9906)
			(stroke
				(width 0.1)
				(type default)
			)
			(layer "F.Fab")
		)
		(fp_line
			(start 0.2794 0.9906)
			(end 0.2794 -0.1016)
			(stroke
				(width 0.1)
				(type default)
			)
			(layer "F.Fab")
		)
		(fp_line
			(start -0.2794 0.9906)
			(end 0.2794 0.9906)
			(stroke
				(width 0.1)
				(type default)
			)
			(layer "F.Fab")
		)
		(pad "1" smd rect
			(at 0 0 90)
			(size 0.508 0.508)
			(layers "F.Cu" "F.Mask" "F.Paste")
			(net "P3V3_STBY")
		)
		(pad "2" smd rect
			(at 0 0.889 90)
			(size 0.508 0.508)
			(layers "F.Cu" "F.Mask" "F.Paste")
			(net "VR_VRRDY_PVCCIN_CPU1")
		)
		(zone
			(layer "F.Cu")
			(hatch none 0.5)
			(connect_pads
				(clearance 0)
			)
			(min_thickness 0.25)
			(keepout
				(tracks not_allowed)
				(vias allowed)
				(pads allowed)
				(copperpour not_allowed)
				(footprints allowed)
			)
			(placement
				(enabled no)
				(sheetname "")
			)
			(fill
				(thermal_gap 0.5)
				(thermal_bridge_width 0.5)
				(island_removal_mode 0)
			)
			(polygon
				(pts
					(xy 14.097 -89.027) (xy 14.478 -89.027) (xy 14.478 -89.535) (xy 14.097 -89.535)
				)
			)
		)
		(zone
			(layer "F.Cu")
			(hatch none 0.5)
			(connect_pads
				(clearance 0)
			)
			(min_thickness 0.25)
			(keepout
				(tracks allowed)
				(vias not_allowed)
				(pads allowed)
				(copperpour not_allowed)
				(footprints allowed)
			)
			(placement
				(enabled no)
				(sheetname "")
			)
			(fill
				(thermal_gap 0.5)
				(thermal_bridge_width 0.5)
				(island_removal_mode 0)
			)
			(polygon
				(pts
					(xy 14.097 -89.027) (xy 14.478 -89.027) (xy 14.478 -89.535) (xy 14.097 -89.535)
				)
			)
		)
	)
	(footprint ""
		(layer "F.Cu")
		(at 112.062768 -79.6036 180)
		(property "Reference" "C3D7"
			(at 0 0 180)
			(layer "F.SilkS")
			(hide yes)
			(effects
				(font
					(size 1.27 1.27)
				)
			)
		)
		(property "Value" ""
			(at 0 0 180)
			(layer "F.Fab")
			(effects
				(font
					(size 1.27 1.27)
				)
			)
		)
		(duplicate_pad_numbers_are_jumpers no)
		(fp_poly
			(pts
				(xy -0.4953 -0.2032) (xy 0.4953 -0.2032) (xy 0.4953 1.6002) (xy -0.4953 1.6002)
			)
			(stroke
				(width 0)
				(type default)
			)
			(fill no)
			(layer "F.CrtYd")
		)
		(fp_line
			(start 0.4953 1.6002)
			(end -0.4953 1.6002)
			(stroke
				(width 0.1)
				(type default)
			)
			(layer "F.Fab")
		)
		(fp_line
			(start 0.4953 -0.2032)
			(end 0.4953 1.6002)
			(stroke
				(width 0.1)
				(type default)
			)
			(layer "F.Fab")
		)
		(fp_line
			(start -0.4953 1.6002)
			(end -0.4953 -0.2032)
			(stroke
				(width 0.1)
				(type default)
			)
			(layer "F.Fab")
		)
		(fp_line
			(start -0.4953 -0.2032)
			(end 0.4953 -0.2032)
			(stroke
				(width 0.1)
				(type default)
			)
			(layer "F.Fab")
		)
		(pad "1" smd rect
			(at 0 0 180)
			(size 0.762 0.889)
			(layers "F.Cu" "F.Mask" "F.Paste")
			(net "PVCCMCP_CPU1")
		)
		(pad "2" smd rect
			(at 0 1.397 180)
			(size 0.762 0.889)
			(layers "F.Cu" "F.Mask" "F.Paste")
			(net "GND")
		)
		(zone
			(layer "F.Cu")
			(hatch none 0.5)
			(connect_pads
				(clearance 0)
			)
			(min_thickness 0.25)
			(keepout
				(tracks not_allowed)
				(vias allowed)
				(pads allowed)
				(copperpour not_allowed)
				(footprints allowed)
			)
			(placement
				(enabled no)
				(sheetname "")
			)
			(fill
				(thermal_gap 0.5)
				(thermal_bridge_width 0.5)
				(island_removal_mode 0)
			)
			(polygon
				(pts
					(xy 112.443768 -80.0481) (xy 111.681768 -80.0481) (xy 111.681768 -80.5561) (xy 112.443768 -80.5561)
				)
			)
		)
	)
	(footprint ""
		(layer "F.Cu")
		(at 261.747 -129.859024)
		(property "Reference" "C5B1"
			(at 0 0 0)
			(layer "F.SilkS")
			(hide yes)
			(effects
				(font
					(size 1.27 1.27)
				)
			)
		)
		(property "Value" ""
			(at 0 0 0)
			(layer "F.Fab")
			(effects
				(font
					(size 1.27 1.27)
				)
			)
		)
		(duplicate_pad_numbers_are_jumpers no)
		(fp_rect
			(start -0.500126 1.598422)
			(end 0.500126 -0.201422)
			(stroke
				(width 0)
				(type default)
			)
			(fill no)
			(layer "F.CrtYd")
		)
		(fp_line
			(start -0.500126 -0.201422)
			(end 0.500126 -0.201422)
			(stroke
				(width 0.1)
				(type default)
			)
			(layer "F.Fab")
		)
		(fp_line
			(start -0.500126 1.598422)
			(end -0.500126 -0.201422)
			(stroke
				(width 0.1)
				(type default)
			)
			(layer "F.Fab")
		)
		(fp_line
			(start 0.500126 -0.201422)
			(end 0.500126 1.598422)
			(stroke
				(width 0.1)
				(type default)
			)
			(layer "F.Fab")
		)
		(fp_line
			(start 0.500126 1.598422)
			(end -0.500126 1.598422)
			(stroke
				(width 0.1)
				(type default)
			)
			(layer "F.Fab")
		)
		(pad "1" smd rect
			(at 0 0 270)
			(size 0.889 0.9906)
			(layers "F.Cu" "F.Mask" "F.Paste")
			(net "PVDDQ_DEF")
		)
		(pad "2" smd rect
			(at 0 1.397 270)
			(size 0.889 0.9906)
			(layers "F.Cu" "F.Mask" "F.Paste")
			(net "GND")
		)
		(zone
			(layer "F.Cu")
			(hatch none 0.5)
			(connect_pads
				(clearance 0)
			)
			(min_thickness 0.25)
			(keepout
				(tracks allowed)
				(vias not_allowed)
				(pads allowed)
				(copperpour not_allowed)
				(footprints allowed)
			)
			(placement
				(enabled no)
				(sheetname "")
			)
			(fill
				(thermal_gap 0.5)
				(thermal_bridge_width 0.5)
				(island_removal_mode 0)
			)
			(polygon
				(pts
					(xy 261.2517 -128.906524) (xy 262.2423 -128.906524) (xy 262.2423 -129.414524) (xy 261.2517 -129.414524)
				)
			)
		)
		(zone
			(layer "F.Cu")
			(hatch none 0.5)
			(connect_pads
				(clearance 0)
			)
			(min_thickness 0.25)
			(keepout
				(tracks not_allowed)
				(vias allowed)
				(pads allowed)
				(copperpour not_allowed)
				(footprints allowed)
			)
			(placement
				(enabled no)
				(sheetname "")
			)
			(fill
				(thermal_gap 0.5)
				(thermal_bridge_width 0.5)
				(island_removal_mode 0)
			)
			(polygon
				(pts
					(xy 261.2517 -128.906524) (xy 262.2423 -128.906524) (xy 262.2423 -129.414524) (xy 261.2517 -129.414524)
				)
			)
		)
	)
	(footprint ""
		(layer "F.Cu")
		(at 399.932144 -40.404542 -90)
		(property "Reference" "C9W7"
			(at -0.8382 -0.67818 270)
			(unlocked yes)
			(layer "F.SilkS")
			(effects
				(font
					(size 0.4064 0.254)
					(thickness 0.1524)
				)
				(justify left)
			)
		)
		(property "Value" ""
			(at 0 0 270)
			(layer "F.Fab")
			(effects
				(font
					(size 1.27 1.27)
				)
			)
		)
		(duplicate_pad_numbers_are_jumpers no)
		(fp_poly
			(pts
				(xy 0.3048 -0.1016) (xy 0.3048 0.9906) (xy -0.3048 0.9906) (xy -0.3048 -0.1016)
			)
			(stroke
				(width 0)
				(type default)
			)
			(fill no)
			(layer "F.CrtYd")
		)
		(fp_line
			(start -0.3048 0.9906)
			(end 0.3048 0.9906)
			(stroke
				(width 0.1)
				(type default)
			)
			(layer "F.Fab")
		)
		(fp_line
			(start 0.3048 0.9906)
			(end 0.3048 -0.1016)
			(stroke
				(width 0.1)
				(type default)
			)
			(layer "F.Fab")
		)
		(fp_line
			(start -0.3048 -0.1016)
			(end -0.3048 0.9906)
			(stroke
				(width 0.1)
				(type default)
			)
			(layer "F.Fab")
		)
		(fp_line
			(start 0.3048 -0.1016)
			(end -0.3048 -0.1016)
			(stroke
				(width 0.1)
				(type default)
			)
			(layer "F.Fab")
		)
		(pad "1" smd rect
			(at 0 0 270)
			(size 0.508 0.508)
			(layers "F.Cu" "F.Mask" "F.Paste")
			(net "P3V3_STBY")
		)
		(pad "2" smd rect
			(at 0 0.889 270)
			(size 0.508 0.508)
			(layers "F.Cu" "F.Mask" "F.Paste")
			(net "GND")
		)
		(zone
			(layer "F.Cu")
			(hatch none 0.5)
			(connect_pads
				(clearance 0)
			)
			(min_thickness 0.25)
			(keepout
				(tracks not_allowed)
				(vias allowed)
				(pads allowed)
				(copperpour not_allowed)
				(footprints allowed)
			)
			(placement
				(enabled no)
				(sheetname "")
			)
			(fill
				(thermal_gap 0.5)
				(thermal_bridge_width 0.5)
				(island_removal_mode 0)
			)
			(polygon
				(pts
					(xy 399.297144 -40.658542) (xy 399.297144 -40.150542) (xy 399.678144 -40.150542) (xy 399.678144 -40.658542)
				)
			)
		)
		(zone
			(layer "F.Cu")
			(hatch none 0.5)
			(connect_pads
				(clearance 0)
			)
			(min_thickness 0.25)
			(keepout
				(tracks allowed)
				(vias not_allowed)
				(pads allowed)
				(copperpour not_allowed)
				(footprints allowed)
			)
			(placement
				(enabled no)
				(sheetname "")
			)
			(fill
				(thermal_gap 0.5)
				(thermal_bridge_width 0.5)
				(island_removal_mode 0)
			)
			(polygon
				(pts
					(xy 399.678144 -40.658542) (xy 399.678144 -40.150542) (xy 399.297144 -40.150542) (xy 399.297144 -40.658542)
				)
			)
		)
	)
	(footprint ""
		(layer "F.Cu")
		(at 155.194 -27.9908 180)
		(property "Reference" "R3F3"
			(at 0 0 180)
			(layer "F.SilkS")
			(hide yes)
			(effects
				(font
					(size 1.27 1.27)
				)
			)
		)
		(property "Value" ""
			(at 0 0 180)
			(layer "F.Fab")
			(effects
				(font
					(size 1.27 1.27)
				)
			)
		)
		(duplicate_pad_numbers_are_jumpers no)
		(fp_poly
			(pts
				(xy -0.2794 -0.1016) (xy 0.2794 -0.1016) (xy 0.2794 0.9906) (xy -0.2794 0.9906)
			)
			(stroke
				(width 0)
				(type default)
			)
			(fill no)
			(layer "F.CrtYd")
		)
		(fp_line
			(start 0.2794 0.9906)
			(end 0.2794 -0.1016)
			(stroke
				(width 0.1)
				(type default)
			)
			(layer "F.Fab")
		)
		(fp_line
			(start 0.2794 -0.1016)
			(end -0.2794 -0.1016)
			(stroke
				(width 0.1)
				(type default)
			)
			(layer "F.Fab")
		)
		(fp_line
			(start -0.2794 0.9906)
			(end 0.2794 0.9906)
			(stroke
				(width 0.1)
				(type default)
			)
			(layer "F.Fab")
		)
		(fp_line
			(start -0.2794 -0.1016)
			(end -0.2794 0.9906)
			(stroke
				(width 0.1)
				(type default)
			)
			(layer "F.Fab")
		)
		(pad "1" smd rect
			(at 0 0 180)
			(size 0.508 0.508)
			(layers "F.Cu" "F.Mask" "F.Paste")
			(net "CLK_322M_156M_CPU1_OSC_VRM_DP")
		)
		(pad "2" smd rect
			(at 0 0.889 180)
			(size 0.508 0.508)
			(layers "F.Cu" "F.Mask" "F.Paste")
			(net "CLK_156M_OSC_CPU1_HFI_DP")
		)
		(zone
			(layer "F.Cu")
			(hatch none 0.5)
			(connect_pads
				(clearance 0)
			)
			(min_thickness 0.25)
			(keepout
				(tracks not_allowed)
				(vias allowed)
				(pads allowed)
				(copperpour not_allowed)
				(footprints allowed)
			)
			(placement
				(enabled no)
				(sheetname "")
			)
			(fill
				(thermal_gap 0.5)
				(thermal_bridge_width 0.5)
				(island_removal_mode 0)
			)
			(polygon
				(pts
					(xy 155.448 -28.6258) (xy 154.94 -28.6258) (xy 154.94 -28.2448) (xy 155.448 -28.2448)
				)
			)
		)
		(zone
			(layer "F.Cu")
			(hatch none 0.5)
			(connect_pads
				(clearance 0)
			)
			(min_thickness 0.25)
			(keepout
				(tracks allowed)
				(vias not_allowed)
				(pads allowed)
				(copperpour not_allowed)
				(footprints allowed)
			)
			(placement
				(enabled no)
				(sheetname "")
			)
			(fill
				(thermal_gap 0.5)
				(thermal_bridge_width 0.5)
				(island_removal_mode 0)
			)
			(polygon
				(pts
					(xy 155.448 -28.2448) (xy 154.94 -28.2448) (xy 154.94 -28.6258) (xy 155.448 -28.6258)
				)
			)
		)
	)
	(footprint ""
		(layer "F.Cu")
		(at 394.5763 -147.0152 90)
		(property "Reference" "C7B19"
			(at 0 0 90)
			(layer "F.SilkS")
			(hide yes)
			(effects
				(font
					(size 1.27 1.27)
				)
			)
		)
		(property "Value" ""
			(at 0 0 90)
			(layer "F.Fab")
			(effects
				(font
					(size 1.27 1.27)
				)
			)
		)
		(duplicate_pad_numbers_are_jumpers no)
		(fp_rect
			(start -0.4953 -0.2032)
			(end 0.4953 1.6002)
			(stroke
				(width 0)
				(type default)
			)
			(fill no)
			(layer "F.CrtYd")
		)
		(fp_line
			(start 0.4953 -0.2032)
			(end 0.4953 1.6002)
			(stroke
				(width 0.1)
				(type default)
			)
			(layer "F.Fab")
		)
		(fp_line
			(start -0.4953 -0.2032)
			(end 0.4953 -0.2032)
			(stroke
				(width 0.1)
				(type default)
			)
			(layer "F.Fab")
		)
		(fp_line
			(start 0.4953 1.6002)
			(end -0.4953 1.6002)
			(stroke
				(width 0.1)
				(type default)
			)
			(layer "F.Fab")
		)
		(fp_line
			(start -0.4953 1.6002)
			(end -0.4953 -0.2032)
			(stroke
				(width 0.1)
				(type default)
			)
			(layer "F.Fab")
		)
		(pad "1" smd rect
			(at 0 0 90)
			(size 0.762 0.889)
			(layers "F.Cu" "F.Mask" "F.Paste")
			(net "P1V05_PCH_STBY")
		)
		(pad "2" smd rect
			(at 0 1.397 90)
			(size 0.762 0.889)
			(layers "F.Cu" "F.Mask" "F.Paste")
			(net "GND")
		)
		(zone
			(layer "F.Cu")
			(hatch none 0.5)
			(connect_pads
				(clearance 0)
			)
			(min_thickness 0.25)
			(keepout
				(tracks not_allowed)
				(vias allowed)
				(pads allowed)
				(copperpour not_allowed)
				(footprints allowed)
			)
			(placement
				(enabled no)
				(sheetname "")
			)
			(fill
				(thermal_gap 0.5)
				(thermal_bridge_width 0.5)
				(island_removal_mode 0)
			)
			(polygon
				(pts
					(xy 395.0208 -146.6342) (xy 395.5288 -146.6342) (xy 395.5288 -147.3962) (xy 395.0208 -147.3962)
				)
			)
		)
	)
	(footprint ""
		(layer "F.Cu")
		(at -2.28346 -131.96316 180)
		(property "Reference" "R1B4"
			(at 0 0 180)
			(layer "F.SilkS")
			(hide yes)
			(effects
				(font
					(size 1.27 1.27)
				)
			)
		)
		(property "Value" ""
			(at 0 0 180)
			(layer "F.Fab")
			(effects
				(font
					(size 1.27 1.27)
				)
			)
		)
		(duplicate_pad_numbers_are_jumpers no)
		(fp_poly
			(pts
				(xy -0.2794 -0.1016) (xy 0.2794 -0.1016) (xy 0.2794 0.9906) (xy -0.2794 0.9906)
			)
			(stroke
				(width 0)
				(type default)
			)
			(fill no)
			(layer "F.CrtYd")
		)
		(fp_line
			(start 0.2794 0.9906)
			(end 0.2794 -0.1016)
			(stroke
				(width 0.1)
				(type default)
			)
			(layer "F.Fab")
		)
		(fp_line
			(start 0.2794 -0.1016)
			(end -0.2794 -0.1016)
			(stroke
				(width 0.1)
				(type default)
			)
			(layer "F.Fab")
		)
		(fp_line
			(start -0.2794 0.9906)
			(end 0.2794 0.9906)
			(stroke
				(width 0.1)
				(type default)
			)
			(layer "F.Fab")
		)
		(fp_line
			(start -0.2794 -0.1016)
			(end -0.2794 0.9906)
			(stroke
				(width 0.1)
				(type default)
			)
			(layer "F.Fab")
		)
		(pad "1" smd rect
			(at 0 0 180)
			(size 0.508 0.508)
			(layers "F.Cu" "F.Mask" "F.Paste")
			(net "IRQ_PVDDQ_KLM_VRHOT_LVT3_R_N")
		)
		(pad "2" smd rect
			(at 0 0.889 180)
			(size 0.508 0.508)
			(layers "F.Cu" "F.Mask" "F.Paste")
			(net "IRQ_PVDDQ_KLM_VRHOT_LVT3_N")
		)
		(zone
			(layer "F.Cu")
			(hatch none 0.5)
			(connect_pads
				(clearance 0)
			)
			(min_thickness 0.25)
			(keepout
				(tracks not_allowed)
				(vias allowed)
				(pads allowed)
				(copperpour not_allowed)
				(footprints allowed)
			)
			(placement
				(enabled no)
				(sheetname "")
			)
			(fill
				(thermal_gap 0.5)
				(thermal_bridge_width 0.5)
				(island_removal_mode 0)
			)
			(polygon
				(pts
					(xy -2.02946 -132.59816) (xy -2.53746 -132.59816) (xy -2.53746 -132.21716) (xy -2.02946 -132.21716)
				)
			)
		)
		(zone
			(layer "F.Cu")
			(hatch none 0.5)
			(connect_pads
				(clearance 0)
			)
			(min_thickness 0.25)
			(keepout
				(tracks allowed)
				(vias not_allowed)
				(pads allowed)
				(copperpour not_allowed)
				(footprints allowed)
			)
			(placement
				(enabled no)
				(sheetname "")
			)
			(fill
				(thermal_gap 0.5)
				(thermal_bridge_width 0.5)
				(island_removal_mode 0)
			)
			(polygon
				(pts
					(xy -2.02946 -132.21716) (xy -2.53746 -132.21716) (xy -2.53746 -132.59816) (xy -2.02946 -132.59816)
				)
			)
		)
	)
	(footprint ""
		(layer "F.Cu")
		(at 33.127696 -69.4182 90)
		(property "Reference" "C1D16"
			(at 0 0 90)
			(layer "F.SilkS")
			(hide yes)
			(effects
				(font
					(size 1.27 1.27)
				)
			)
		)
		(property "Value" ""
			(at 0 0 90)
			(layer "F.Fab")
			(effects
				(font
					(size 1.27 1.27)
				)
			)
		)
		(duplicate_pad_numbers_are_jumpers no)
		(fp_rect
			(start 0.3048 0.9906)
			(end -0.3048 -0.1016)
			(stroke
				(width 0)
				(type default)
			)
			(fill no)
			(layer "F.CrtYd")
		)
		(fp_line
			(start 0.3048 -0.1016)
			(end -0.3048 -0.1016)
			(stroke
				(width 0.1)
				(type default)
			)
			(layer "F.Fab")
		)
		(fp_line
			(start -0.3048 -0.1016)
			(end -0.3048 0.9906)
			(stroke
				(width 0.1)
				(type default)
			)
			(layer "F.Fab")
		)
		(fp_line
			(start 0.3048 0.9906)
			(end 0.3048 -0.1016)
			(stroke
				(width 0.1)
				(type default)
			)
			(layer "F.Fab")
		)
		(fp_line
			(start -0.3048 0.9906)
			(end 0.3048 0.9906)
			(stroke
				(width 0.1)
				(type default)
			)
			(layer "F.Fab")
		)
		(pad "1" smd rect
			(at 0 0 90)
			(size 0.508 0.508)
			(layers "F.Cu" "F.Mask" "F.Paste")
			(net "P5V_STBY")
		)
		(pad "2" smd rect
			(at 0 0.889 90)
			(size 0.508 0.508)
			(layers "F.Cu" "F.Mask" "F.Paste")
			(net "GND")
		)
		(zone
			(layer "F.Cu")
			(hatch none 0.5)
			(connect_pads
				(clearance 0)
			)
			(min_thickness 0.25)
			(keepout
				(tracks allowed)
				(vias not_allowed)
				(pads allowed)
				(copperpour not_allowed)
				(footprints allowed)
			)
			(placement
				(enabled no)
				(sheetname "")
			)
			(fill
				(thermal_gap 0.5)
				(thermal_bridge_width 0.5)
				(island_removal_mode 0)
			)
			(polygon
				(pts
					(xy 33.762696 -69.6722) (xy 33.381696 -69.6722) (xy 33.381696 -69.1642) (xy 33.762696 -69.1642)
				)
			)
		)
		(zone
			(layer "F.Cu")
			(hatch none 0.5)
			(connect_pads
				(clearance 0)
			)
			(min_thickness 0.25)
			(keepout
				(tracks not_allowed)
				(vias allowed)
				(pads allowed)
				(copperpour not_allowed)
				(footprints allowed)
			)
			(placement
				(enabled no)
				(sheetname "")
			)
			(fill
				(thermal_gap 0.5)
				(thermal_bridge_width 0.5)
				(island_removal_mode 0)
			)
			(polygon
				(pts
					(xy 33.762696 -69.6722) (xy 33.381696 -69.6722) (xy 33.381696 -69.1642) (xy 33.762696 -69.1642)
				)
			)
		)
	)
	(footprint ""
		(layer "F.Cu")
		(at 245.7577 -3.3528 -90)
		(property "Reference" "C5G11"
			(at 1.848866 0.752348 270)
			(unlocked yes)
			(layer "F.SilkS")
			(effects
				(font
					(size 1.27 0.9652)
					(thickness 0.1524)
				)
			)
		)
		(property "Value" ""
			(at 0 0 270)
			(layer "F.Fab")
			(effects
				(font
					(size 1.27 1.27)
				)
			)
		)
		(duplicate_pad_numbers_are_jumpers no)
		(fp_rect
			(start -0.500126 1.598422)
			(end 0.500126 -0.201422)
			(stroke
				(width 0)
				(type default)
			)
			(fill no)
			(layer "F.CrtYd")
		)
		(fp_line
			(start -0.500126 1.598422)
			(end -0.500126 -0.201422)
			(stroke
				(width 0.1)
				(type default)
			)
			(layer "F.Fab")
		)
		(fp_line
			(start 0.500126 1.598422)
			(end -0.500126 1.598422)
			(stroke
				(width 0.1)
				(type default)
			)
			(layer "F.Fab")
		)
		(fp_line
			(start -0.500126 -0.201422)
			(end 0.500126 -0.201422)
			(stroke
				(width 0.1)
				(type default)
			)
			(layer "F.Fab")
		)
		(fp_line
			(start 0.500126 -0.201422)
			(end 0.500126 1.598422)
			(stroke
				(width 0.1)
				(type default)
			)
			(layer "F.Fab")
		)
		(pad "1" smd rect
			(at 0 0 180)
			(size 0.889 0.9906)
			(layers "F.Cu" "F.Mask" "F.Paste")
			(net "PVDDQ_ABC")
		)
		(pad "2" smd rect
			(at 0 1.397 180)
			(size 0.889 0.9906)
			(layers "F.Cu" "F.Mask" "F.Paste")
			(net "GND")
		)
		(zone
			(layer "F.Cu")
			(hatch none 0.5)
			(connect_pads
				(clearance 0)
			)
			(min_thickness 0.25)
			(keepout
				(tracks allowed)
				(vias not_allowed)
				(pads allowed)
				(copperpour not_allowed)
				(footprints allowed)
			)
			(placement
				(enabled no)
				(sheetname "")
			)
			(fill
				(thermal_gap 0.5)
				(thermal_bridge_width 0.5)
				(island_removal_mode 0)
			)
			(polygon
				(pts
					(xy 244.8052 -3.8481) (xy 244.8052 -2.8575) (xy 245.3132 -2.8575) (xy 245.3132 -3.8481)
				)
			)
		)
		(zone
			(layer "F.Cu")
			(hatch none 0.5)
			(connect_pads
				(clearance 0)
			)
			(min_thickness 0.25)
			(keepout
				(tracks not_allowed)
				(vias allowed)
				(pads allowed)
				(copperpour not_allowed)
				(footprints allowed)
			)
			(placement
				(enabled no)
				(sheetname "")
			)
			(fill
				(thermal_gap 0.5)
				(thermal_bridge_width 0.5)
				(island_removal_mode 0)
			)
			(polygon
				(pts
					(xy 244.8052 -3.8481) (xy 244.8052 -2.8575) (xy 245.3132 -2.8575) (xy 245.3132 -3.8481)
				)
			)
		)
	)
	(footprint ""
		(layer "F.Cu")
		(at 413.3215 -113.411 -90)
		(property "Reference" "R2L4"
			(at 0 0 270)
			(layer "F.SilkS")
			(hide yes)
			(effects
				(font
					(size 1.27 1.27)
				)
			)
		)
		(property "Value" ""
			(at 0 0 270)
			(layer "F.Fab")
			(effects
				(font
					(size 1.27 1.27)
				)
			)
		)
		(duplicate_pad_numbers_are_jumpers no)
		(fp_poly
			(pts
				(xy -0.2794 -0.1016) (xy 0.2794 -0.1016) (xy 0.2794 0.9906) (xy -0.2794 0.9906)
			)
			(stroke
				(width 0)
				(type default)
			)
			(fill no)
			(layer "F.CrtYd")
		)
		(fp_line
			(start -0.2794 0.9906)
			(end 0.2794 0.9906)
			(stroke
				(width 0.1)
				(type default)
			)
			(layer "F.Fab")
		)
		(fp_line
			(start 0.2794 0.9906)
			(end 0.2794 -0.1016)
			(stroke
				(width 0.1)
				(type default)
			)
			(layer "F.Fab")
		)
		(fp_line
			(start -0.2794 -0.1016)
			(end -0.2794 0.9906)
			(stroke
				(width 0.1)
				(type default)
			)
			(layer "F.Fab")
		)
		(fp_line
			(start 0.2794 -0.1016)
			(end -0.2794 -0.1016)
			(stroke
				(width 0.1)
				(type default)
			)
			(layer "F.Fab")
		)
		(pad "1" smd rect
			(at 0 0 270)
			(size 0.508 0.508)
			(layers "F.Cu" "F.Mask" "F.Paste")
			(net "P3V3_STBY")
		)
		(pad "2" smd rect
			(at 0 0.889 270)
			(size 0.508 0.508)
			(layers "F.Cu" "F.Mask" "F.Paste")
			(net "SGPIO_PCH_SSATA_DOUT0_R")
		)
		(zone
			(layer "F.Cu")
			(hatch none 0.5)
			(connect_pads
				(clearance 0)
			)
			(min_thickness 0.25)
			(keepout
				(tracks not_allowed)
				(vias allowed)
				(pads allowed)
				(copperpour not_allowed)
				(footprints allowed)
			)
			(placement
				(enabled no)
				(sheetname "")
			)
			(fill
				(thermal_gap 0.5)
				(thermal_bridge_width 0.5)
				(island_removal_mode 0)
			)
			(polygon
				(pts
					(xy 412.6865 -113.665) (xy 412.6865 -113.157) (xy 413.0675 -113.157) (xy 413.0675 -113.665)
				)
			)
		)
		(zone
			(layer "F.Cu")
			(hatch none 0.5)
			(connect_pads
				(clearance 0)
			)
			(min_thickness 0.25)
			(keepout
				(tracks allowed)
				(vias not_allowed)
				(pads allowed)
				(copperpour not_allowed)
				(footprints allowed)
			)
			(placement
				(enabled no)
				(sheetname "")
			)
			(fill
				(thermal_gap 0.5)
				(thermal_bridge_width 0.5)
				(island_removal_mode 0)
			)
			(polygon
				(pts
					(xy 413.0675 -113.665) (xy 413.0675 -113.157) (xy 412.6865 -113.157) (xy 412.6865 -113.665)
				)
			)
		)
	)
	(footprint ""
		(layer "F.Cu")
		(at 485.9274 -136.652 -90)
		(property "Reference" "DS9A6"
			(at -0.19304 3.36169 90)
			(unlocked yes)
			(layer "F.SilkS")
			(effects
				(font
					(size 0.7874 0.5842)
					(thickness 0.1524)
				)
			)
		)
		(property "Value" ""
			(at 0 0 270)
			(layer "F.Fab")
			(effects
				(font
					(size 1.27 1.27)
				)
			)
		)
		(duplicate_pad_numbers_are_jumpers no)
		(fp_line
			(start -1.78562 5.26796)
			(end -1.78562 4.144518)
			(stroke
				(width 0.1524)
				(type default)
			)
			(layer "F.SilkS")
		)
		(fp_line
			(start -2.266442 4.144518)
			(end -1.304798 4.144518)
			(stroke
				(width 0.1524)
				(type default)
			)
			(layer "F.SilkS")
		)
		(fp_line
			(start -1.78562 4.144518)
			(end -2.266442 3.311652)
			(stroke
				(width 0.1524)
				(type default)
			)
			(layer "F.SilkS")
		)
		(fp_line
			(start -2.266442 3.311652)
			(end -1.78562 3.311652)
			(stroke
				(width 0.1524)
				(type default)
			)
			(layer "F.SilkS")
		)
		(fp_line
			(start -1.78562 3.311652)
			(end -1.304798 3.311652)
			(stroke
				(width 0.1524)
				(type default)
			)
			(layer "F.SilkS")
		)
		(fp_line
			(start -1.304798 3.311652)
			(end -1.78562 4.144518)
			(stroke
				(width 0.1524)
				(type default)
			)
			(layer "F.SilkS")
		)
		(fp_line
			(start -1.78562 2.400046)
			(end -1.78562 3.311652)
			(stroke
				(width 0.1524)
				(type default)
			)
			(layer "F.SilkS")
		)
		(fp_poly
			(pts
				(xy 0.6223 2.032) (xy -0.6223 2.032) (xy -0.6223 0.0254) (xy 0.6223 0.0254)
			)
			(stroke
				(width 0)
				(type default)
			)
			(fill no)
			(layer "F.CrtYd")
		)
		(fp_line
			(start -2.266442 4.144518)
			(end -1.304798 4.144518)
			(stroke
				(width 0.1)
				(type default)
			)
			(layer "F.Fab")
		)
		(fp_line
			(start -1.78562 4.144518)
			(end -1.78562 5.26796)
			(stroke
				(width 0.1)
				(type default)
			)
			(layer "F.Fab")
		)
		(fp_line
			(start -1.78562 4.144518)
			(end -2.266442 3.311652)
			(stroke
				(width 0.1)
				(type default)
			)
			(layer "F.Fab")
		)
		(fp_line
			(start -1.782318 3.314446)
			(end -1.782318 2.40284)
			(stroke
				(width 0.1)
				(type default)
			)
			(layer "F.Fab")
		)
		(fp_line
			(start -2.266442 3.311652)
			(end -1.304798 3.311652)
			(stroke
				(width 0.1)
				(type default)
			)
			(layer "F.Fab")
		)
		(fp_line
			(start -1.304798 3.311652)
			(end -1.78562 4.144518)
			(stroke
				(width 0.1)
				(type default)
			)
			(layer "F.Fab")
		)
		(fp_line
			(start -0.6223 2.032)
			(end -0.6223 0.0254)
			(stroke
				(width 0.1)
				(type default)
			)
			(layer "F.Fab")
		)
		(fp_line
			(start 0.6223 2.032)
			(end -0.6223 2.032)
			(stroke
				(width 0.1)
				(type default)
			)
			(layer "F.Fab")
		)
		(fp_line
			(start -0.6223 0.0254)
			(end 0.6223 0.0254)
			(stroke
				(width 0.1)
				(type default)
			)
			(layer "F.Fab")
		)
		(fp_line
			(start 0.6223 0.0254)
			(end 0.6223 2.032)
			(stroke
				(width 0.1)
				(type default)
			)
			(layer "F.Fab")
		)
		(pad "1" smd rect
			(at 0 0 270)
			(size 1.27 1.27)
			(layers "F.Cu" "F.Mask" "F.Paste")
			(net "LED_P5V_STBY")
		)
		(pad "2" smd rect
			(at 0 2.032 270)
			(size 1.27 1.27)
			(layers "F.Cu" "F.Mask" "F.Paste")
			(net "GND")
		)
		(zone
			(layer "F.Cu")
			(hatch none 0.5)
			(connect_pads
				(clearance 0)
			)
			(min_thickness 0.25)
			(keepout
				(tracks not_allowed)
				(vias allowed)
				(pads allowed)
				(copperpour not_allowed)
				(footprints allowed)
			)
			(placement
				(enabled no)
				(sheetname "")
			)
			(fill
				(thermal_gap 0.5)
				(thermal_bridge_width 0.5)
				(island_removal_mode 0)
			)
			(polygon
				(pts
					(xy 484.5304 -137.287) (xy 484.5304 -136.017) (xy 485.2924 -136.017) (xy 485.2924 -137.287)
				)
			)
		)
		(zone
			(layer "F.Cu")
			(hatch none 0.5)
			(connect_pads
				(clearance 0)
			)
			(min_thickness 0.25)
			(keepout
				(tracks allowed)
				(vias not_allowed)
				(pads allowed)
				(copperpour not_allowed)
				(footprints allowed)
			)
			(placement
				(enabled no)
				(sheetname "")
			)
			(fill
				(thermal_gap 0.5)
				(thermal_bridge_width 0.5)
				(island_removal_mode 0)
			)
			(polygon
				(pts
					(xy 484.5304 -137.287) (xy 484.5304 -136.017) (xy 485.2924 -136.017) (xy 485.2924 -137.287)
				)
			)
		)
	)
	(footprint ""
		(layer "F.Cu")
		(at 397.9672 1.7272 90)
		(property "Reference" "R8G22"
			(at 0 0 90)
			(layer "F.SilkS")
			(hide yes)
			(effects
				(font
					(size 1.27 1.27)
				)
			)
		)
		(property "Value" ""
			(at 0 0 90)
			(layer "F.Fab")
			(effects
				(font
					(size 1.27 1.27)
				)
			)
		)
		(duplicate_pad_numbers_are_jumpers no)
		(fp_poly
			(pts
				(xy -0.2794 -0.1016) (xy 0.2794 -0.1016) (xy 0.2794 0.9906) (xy -0.2794 0.9906)
			)
			(stroke
				(width 0)
				(type default)
			)
			(fill no)
			(layer "F.CrtYd")
		)
		(fp_line
			(start 0.2794 -0.1016)
			(end -0.2794 -0.1016)
			(stroke
				(width 0.1)
				(type default)
			)
			(layer "F.Fab")
		)
		(fp_line
			(start -0.2794 -0.1016)
			(end -0.2794 0.9906)
			(stroke
				(width 0.1)
				(type default)
			)
			(layer "F.Fab")
		)
		(fp_line
			(start 0.2794 0.9906)
			(end 0.2794 -0.1016)
			(stroke
				(width 0.1)
				(type default)
			)
			(layer "F.Fab")
		)
		(fp_line
			(start -0.2794 0.9906)
			(end 0.2794 0.9906)
			(stroke
				(width 0.1)
				(type default)
			)
			(layer "F.Fab")
		)
		(pad "1" smd rect
			(at 0 0 90)
			(size 0.508 0.508)
			(layers "F.Cu" "F.Mask" "F.Paste")
			(net "JTAG_TCK")
		)
		(pad "2" smd rect
			(at 0 0.889 90)
			(size 0.508 0.508)
			(layers "F.Cu" "F.Mask" "F.Paste")
			(net "JTAG_TCK_R")
		)
		(zone
			(layer "F.Cu")
			(hatch none 0.5)
			(connect_pads
				(clearance 0)
			)
			(min_thickness 0.25)
			(keepout
				(tracks allowed)
				(vias not_allowed)
				(pads allowed)
				(copperpour not_allowed)
				(footprints allowed)
			)
			(placement
				(enabled no)
				(sheetname "")
			)
			(fill
				(thermal_gap 0.5)
				(thermal_bridge_width 0.5)
				(island_removal_mode 0)
			)
			(polygon
				(pts
					(xy 398.2212 1.9812) (xy 398.2212 1.4732) (xy 398.6022 1.4732) (xy 398.6022 1.9812)
				)
			)
		)
		(zone
			(layer "F.Cu")
			(hatch none 0.5)
			(connect_pads
				(clearance 0)
			)
			(min_thickness 0.25)
			(keepout
				(tracks not_allowed)
				(vias allowed)
				(pads allowed)
				(copperpour not_allowed)
				(footprints allowed)
			)
			(placement
				(enabled no)
				(sheetname "")
			)
			(fill
				(thermal_gap 0.5)
				(thermal_bridge_width 0.5)
				(island_removal_mode 0)
			)
			(polygon
				(pts
					(xy 398.6022 1.9812) (xy 398.6022 1.4732) (xy 398.2212 1.4732) (xy 398.2212 1.9812)
				)
			)
		)
	)
	(footprint ""
		(layer "F.Cu")
		(at -1.864868 -140.939012 -90)
		(property "Reference" "C1A19"
			(at 0 0 270)
			(layer "F.SilkS")
			(hide yes)
			(effects
				(font
					(size 1.27 1.27)
				)
			)
		)
		(property "Value" ""
			(at 0 0 270)
			(layer "F.Fab")
			(effects
				(font
					(size 1.27 1.27)
				)
			)
		)
		(duplicate_pad_numbers_are_jumpers no)
		(fp_poly
			(pts
				(xy 0.3048 -0.1016) (xy 0.3048 0.9906) (xy -0.3048 0.9906) (xy -0.3048 -0.1016)
			)
			(stroke
				(width 0)
				(type default)
			)
			(fill no)
			(layer "F.CrtYd")
		)
		(fp_line
			(start -0.3048 0.9906)
			(end 0.3048 0.9906)
			(stroke
				(width 0.1)
				(type default)
			)
			(layer "F.Fab")
		)
		(fp_line
			(start 0.3048 0.9906)
			(end 0.3048 -0.1016)
			(stroke
				(width 0.1)
				(type default)
			)
			(layer "F.Fab")
		)
		(fp_line
			(start -0.3048 -0.1016)
			(end -0.3048 0.9906)
			(stroke
				(width 0.1)
				(type default)
			)
			(layer "F.Fab")
		)
		(fp_line
			(start 0.3048 -0.1016)
			(end -0.3048 -0.1016)
			(stroke
				(width 0.1)
				(type default)
			)
			(layer "F.Fab")
		)
		(pad "1" smd rect
			(at 0 0 270)
			(size 0.508 0.508)
			(layers "F.Cu" "F.Mask" "F.Paste")
			(net "VR_FET_SW_P12V_STBY_PVDDQ_KLM")
		)
		(pad "2" smd rect
			(at 0 0.889 270)
			(size 0.508 0.508)
			(layers "F.Cu" "F.Mask" "F.Paste")
			(net "GND")
		)
		(zone
			(layer "F.Cu")
			(hatch none 0.5)
			(connect_pads
				(clearance 0)
			)
			(min_thickness 0.25)
			(keepout
				(tracks not_allowed)
				(vias allowed)
				(pads allowed)
				(copperpour not_allowed)
				(footprints allowed)
			)
			(placement
				(enabled no)
				(sheetname "")
			)
			(fill
				(thermal_gap 0.5)
				(thermal_bridge_width 0.5)
				(island_removal_mode 0)
			)
			(polygon
				(pts
					(xy -2.499868 -141.193012) (xy -2.499868 -140.685012) (xy -2.118868 -140.685012) (xy -2.118868 -141.193012)
				)
			)
		)
		(zone
			(layer "F.Cu")
			(hatch none 0.5)
			(connect_pads
				(clearance 0)
			)
			(min_thickness 0.25)
			(keepout
				(tracks allowed)
				(vias not_allowed)
				(pads allowed)
				(copperpour not_allowed)
				(footprints allowed)
			)
			(placement
				(enabled no)
				(sheetname "")
			)
			(fill
				(thermal_gap 0.5)
				(thermal_bridge_width 0.5)
				(island_removal_mode 0)
			)
			(polygon
				(pts
					(xy -2.118868 -141.193012) (xy -2.118868 -140.685012) (xy -2.499868 -140.685012) (xy -2.499868 -141.193012)
				)
			)
		)
	)
	(footprint ""
		(layer "F.Cu")
		(at 15.494 -80.4545)
		(property "Reference" "R1D24"
			(at 0 0 0)
			(layer "F.SilkS")
			(hide yes)
			(effects
				(font
					(size 1.27 1.27)
				)
			)
		)
		(property "Value" ""
			(at 0 0 0)
			(layer "F.Fab")
			(effects
				(font
					(size 1.27 1.27)
				)
			)
		)
		(duplicate_pad_numbers_are_jumpers no)
		(fp_rect
			(start 0.2794 0.9906)
			(end -0.2794 -0.1016)
			(stroke
				(width 0)
				(type default)
			)
			(fill no)
			(layer "F.CrtYd")
		)
		(fp_line
			(start -0.2794 -0.1016)
			(end -0.2794 0.9906)
			(stroke
				(width 0.1)
				(type default)
			)
			(layer "F.Fab")
		)
		(fp_line
			(start -0.2794 0.9906)
			(end 0.2794 0.9906)
			(stroke
				(width 0.1)
				(type default)
			)
			(layer "F.Fab")
		)
		(fp_line
			(start 0.2794 -0.1016)
			(end -0.2794 -0.1016)
			(stroke
				(width 0.1)
				(type default)
			)
			(layer "F.Fab")
		)
		(fp_line
			(start 0.2794 0.9906)
			(end 0.2794 -0.1016)
			(stroke
				(width 0.1)
				(type default)
			)
			(layer "F.Fab")
		)
		(pad "1" smd rect
			(at 0 0)
			(size 0.508 0.508)
			(layers "F.Cu" "F.Mask" "F.Paste")
			(net "SMB_BMC_PMBUS_STBY_LVC3_SCL")
		)
		(pad "2" smd rect
			(at 0 0.889)
			(size 0.508 0.508)
			(layers "F.Cu" "F.Mask" "F.Paste")
			(net "SMB_3V3SB_HSC_SCL_R")
		)
		(zone
			(layer "F.Cu")
			(hatch none 0.5)
			(connect_pads
				(clearance 0)
			)
			(min_thickness 0.25)
			(keepout
				(tracks allowed)
				(vias not_allowed)
				(pads allowed)
				(copperpour not_allowed)
				(footprints allowed)
			)
			(placement
				(enabled no)
				(sheetname "")
			)
			(fill
				(thermal_gap 0.5)
				(thermal_bridge_width 0.5)
				(island_removal_mode 0)
			)
			(polygon
				(pts
					(xy 15.748 -79.8195) (xy 15.748 -80.2005) (xy 15.24 -80.2005) (xy 15.24 -79.8195)
				)
			)
		)
		(zone
			(layer "F.Cu")
			(hatch none 0.5)
			(connect_pads
				(clearance 0)
			)
			(min_thickness 0.25)
			(keepout
				(tracks not_allowed)
				(vias allowed)
				(pads allowed)
				(copperpour not_allowed)
				(footprints allowed)
			)
			(placement
				(enabled no)
				(sheetname "")
			)
			(fill
				(thermal_gap 0.5)
				(thermal_bridge_width 0.5)
				(island_removal_mode 0)
			)
			(polygon
				(pts
					(xy 15.748 -79.8195) (xy 15.748 -80.2005) (xy 15.24 -80.2005) (xy 15.24 -79.8195)
				)
			)
		)
	)
	(footprint ""
		(layer "F.Cu")
		(at 108.16844 -73.318116)
		(property "Reference" "C3D17"
			(at 0 0 0)
			(layer "F.SilkS")
			(hide yes)
			(effects
				(font
					(size 1.27 1.27)
				)
			)
		)
		(property "Value" ""
			(at 0 0 0)
			(layer "F.Fab")
			(effects
				(font
					(size 1.27 1.27)
				)
			)
		)
		(duplicate_pad_numbers_are_jumpers no)
		(fp_poly
			(pts
				(xy -0.4953 -0.2032) (xy 0.4953 -0.2032) (xy 0.4953 1.6002) (xy -0.4953 1.6002)
			)
			(stroke
				(width 0)
				(type default)
			)
			(fill no)
			(layer "F.CrtYd")
		)
		(fp_line
			(start -0.4953 -0.2032)
			(end 0.4953 -0.2032)
			(stroke
				(width 0.1)
				(type default)
			)
			(layer "F.Fab")
		)
		(fp_line
			(start -0.4953 1.6002)
			(end -0.4953 -0.2032)
			(stroke
				(width 0.1)
				(type default)
			)
			(layer "F.Fab")
		)
		(fp_line
			(start 0.4953 -0.2032)
			(end 0.4953 1.6002)
			(stroke
				(width 0.1)
				(type default)
			)
			(layer "F.Fab")
		)
		(fp_line
			(start 0.4953 1.6002)
			(end -0.4953 1.6002)
			(stroke
				(width 0.1)
				(type default)
			)
			(layer "F.Fab")
		)
		(pad "1" smd rect
			(at 0 0)
			(size 0.762 0.889)
			(layers "F.Cu" "F.Mask" "F.Paste")
			(net "PVCCMCP_CPU1")
		)
		(pad "2" smd rect
			(at 0 1.397)
			(size 0.762 0.889)
			(layers "F.Cu" "F.Mask" "F.Paste")
			(net "GND")
		)
		(zone
			(layer "F.Cu")
			(hatch none 0.5)
			(connect_pads
				(clearance 0)
			)
			(min_thickness 0.25)
			(keepout
				(tracks not_allowed)
				(vias allowed)
				(pads allowed)
				(copperpour not_allowed)
				(footprints allowed)
			)
			(placement
				(enabled no)
				(sheetname "")
			)
			(fill
				(thermal_gap 0.5)
				(thermal_bridge_width 0.5)
				(island_removal_mode 0)
			)
			(polygon
				(pts
					(xy 107.78744 -72.873616) (xy 108.54944 -72.873616) (xy 108.54944 -72.365616) (xy 107.78744 -72.365616)
				)
			)
		)
	)
	(footprint ""
		(layer "F.Cu")
		(at 378.587 -158.1404 -90)
		(property "Reference" "RT44"
			(at 1.01473 0.656336 180)
			(unlocked yes)
			(layer "F.SilkS")
			(effects
				(font
					(size 0.4064 0.254)
					(thickness 0.1524)
				)
			)
		)
		(property "Value" ""
			(at 0 0 270)
			(layer "F.Fab")
			(effects
				(font
					(size 1.27 1.27)
				)
			)
		)
		(duplicate_pad_numbers_are_jumpers no)
		(fp_poly
			(pts
				(xy -0.4953 -0.2032) (xy 0.4953 -0.2032) (xy 0.4953 1.6002) (xy -0.4953 1.6002)
			)
			(stroke
				(width 0)
				(type default)
			)
			(fill no)
			(layer "F.CrtYd")
		)
		(fp_line
			(start -0.4953 1.6002)
			(end -0.4953 -0.2032)
			(stroke
				(width 0.1)
				(type default)
			)
			(layer "F.Fab")
		)
		(fp_line
			(start 0.4953 1.6002)
			(end -0.4953 1.6002)
			(stroke
				(width 0.1)
				(type default)
			)
			(layer "F.Fab")
		)
		(fp_line
			(start -0.4953 -0.2032)
			(end 0.4953 -0.2032)
			(stroke
				(width 0.1)
				(type default)
			)
			(layer "F.Fab")
		)
		(fp_line
			(start 0.4953 -0.2032)
			(end 0.4953 1.6002)
			(stroke
				(width 0.1)
				(type default)
			)
			(layer "F.Fab")
		)
		(pad "1" smd rect
			(at 0 0 270)
			(size 0.762 0.889)
			(layers "F.Cu" "F.Mask" "F.Paste")
			(net "VR_PVNN_PCH_PH1_BOOT")
		)
		(pad "2" smd rect
			(at 0 1.397 270)
			(size 0.762 0.889)
			(layers "F.Cu" "F.Mask" "F.Paste")
			(net "VR_PVNN_PCH_PH1_BOOT_R")
		)
		(zone
			(layer "F.Cu")
			(hatch none 0.5)
			(connect_pads
				(clearance 0)
			)
			(min_thickness 0.25)
			(keepout
				(tracks not_allowed)
				(vias allowed)
				(pads allowed)
				(copperpour not_allowed)
				(footprints allowed)
			)
			(placement
				(enabled no)
				(sheetname "")
			)
			(fill
				(thermal_gap 0.5)
				(thermal_bridge_width 0.5)
				(island_removal_mode 0)
			)
			(polygon
				(pts
					(xy 377.6345 -158.5214) (xy 377.6345 -157.7594) (xy 378.1425 -157.7594) (xy 378.1425 -158.5214)
				)
			)
		)
		(zone
			(layer "F.Cu")
			(hatch none 0.5)
			(connect_pads
				(clearance 0)
			)
			(min_thickness 0.25)
			(keepout
				(tracks allowed)
				(vias not_allowed)
				(pads allowed)
				(copperpour not_allowed)
				(footprints allowed)
			)
			(placement
				(enabled no)
				(sheetname "")
			)
			(fill
				(thermal_gap 0.5)
				(thermal_bridge_width 0.5)
				(island_removal_mode 0)
			)
			(polygon
				(pts
					(xy 377.6345 -157.7594) (xy 378.1425 -157.7594) (xy 378.1425 -158.5214) (xy 377.6345 -158.5214)
				)
			)
		)
	)
	(footprint ""
		(layer "F.Cu")
		(at 29.337 10.7315 -90)
		(property "Reference" "T1P29"
			(at 0 0 270)
			(layer "F.SilkS")
			(hide yes)
			(effects
				(font
					(size 1.27 1.27)
				)
			)
		)
		(property "Value" "*"
			(at 0 -3.44805 270)
			(unlocked yes)
			(layer "F.Fab")
			(hide yes)
			(effects
				(font
					(size 0.889 0.889)
					(thickness 0.1524)
				)
			)
		)
		(property "Device Type" "TPAD-SE-2P-GP_DISCRET-GA1-TPADA"
			(at 0 -4.97205 270)
			(unlocked yes)
			(layer "F.Fab")
			(hide yes)
			(effects
				(font
					(size 0.889 0.889)
					(thickness 0.1524)
				)
			)
		)
		(duplicate_pad_numbers_are_jumpers no)
		(fp_line
			(start -1.016 2.286)
			(end -1.016 -2.286)
			(stroke
				(width 0.1524)
				(type default)
			)
			(layer "F.SilkS")
		)
		(fp_line
			(start 1.016 2.286)
			(end -1.016 2.286)
			(stroke
				(width 0.1524)
				(type default)
			)
			(layer "F.SilkS")
		)
		(fp_line
			(start -1.016 -2.286)
			(end 1.016 -2.286)
			(stroke
				(width 0.1524)
				(type default)
			)
			(layer "F.SilkS")
		)
		(fp_line
			(start 1.016 -2.286)
			(end 1.016 2.286)
			(stroke
				(width 0.1524)
				(type default)
			)
			(layer "F.SilkS")
		)
		(fp_rect
			(start -1.27 2.54)
			(end 1.27 -2.54)
			(stroke
				(width 0)
				(type default)
			)
			(fill no)
			(layer "F.CrtYd")
		)
		(fp_rect
			(start -1.27 2.54)
			(end 1.27 -2.54)
			(stroke
				(width 0)
				(type default)
			)
			(fill no)
			(layer "F.Fab")
		)
		(pad "1" thru_hole circle
			(at 0 -1.27 270)
			(size 1.524 1.524)
			(drill 0.9144)
			(layers "*.Cu" "*.Mask")
			(remove_unused_layers no)
			(net "L12_40OHM_6INCH")
			(clearance -0.0508)
			(thermal_gap 0.127)
			(padstack
				(mode front_inner_back)
				(layer "Inner"
					(shape circle)
					(size 1.1684 1.1684)
					(clearance 0.127)
				)
				(layer "B.Cu"
					(shape circle)
					(size 1.524 1.524)
					(clearance -0.0508)
				)
			)
		)
		(pad "GND1" thru_hole rect
			(at 0 1.27 270)
			(size 1.524 1.524)
			(drill 0.9144)
			(layers "*.Cu" "*.Mask")
			(remove_unused_layers no)
			(net "GND")
			(clearance -0.0508)
			(thermal_gap 0.127)
			(padstack
				(mode front_inner_back)
				(layer "Inner"
					(shape circle)
					(size 1.1684 1.1684)
					(clearance 0.127)
				)
				(layer "B.Cu"
					(shape rect)
					(size 1.524 1.524)
					(clearance -0.0508)
				)
			)
		)
	)
	(footprint ""
		(layer "F.Cu")
		(at 111.633 -69.85)
		(property "Reference" "R3D24"
			(at 0 0 0)
			(layer "F.SilkS")
			(hide yes)
			(effects
				(font
					(size 1.27 1.27)
				)
			)
		)
		(property "Value" ""
			(at 0 0 0)
			(layer "F.Fab")
			(effects
				(font
					(size 1.27 1.27)
				)
			)
		)
		(duplicate_pad_numbers_are_jumpers no)
		(fp_poly
			(pts
				(xy -0.2794 -0.1016) (xy 0.2794 -0.1016) (xy 0.2794 0.9906) (xy -0.2794 0.9906)
			)
			(stroke
				(width 0)
				(type default)
			)
			(fill no)
			(layer "F.CrtYd")
		)
		(fp_line
			(start -0.2794 -0.1016)
			(end -0.2794 0.9906)
			(stroke
				(width 0.1)
				(type default)
			)
			(layer "F.Fab")
		)
		(fp_line
			(start -0.2794 0.9906)
			(end 0.2794 0.9906)
			(stroke
				(width 0.1)
				(type default)
			)
			(layer "F.Fab")
		)
		(fp_line
			(start 0.2794 -0.1016)
			(end -0.2794 -0.1016)
			(stroke
				(width 0.1)
				(type default)
			)
			(layer "F.Fab")
		)
		(fp_line
			(start 0.2794 0.9906)
			(end 0.2794 -0.1016)
			(stroke
				(width 0.1)
				(type default)
			)
			(layer "F.Fab")
		)
		(pad "1" smd rect
			(at 0 0)
			(size 0.508 0.508)
			(layers "F.Cu" "F.Mask" "F.Paste")
			(net "PVCCIO_CPU1")
		)
		(pad "2" smd rect
			(at 0 0.889)
			(size 0.508 0.508)
			(layers "F.Cu" "F.Mask" "F.Paste")
			(net "PU_CPU1_SOCKET_ID_0")
		)
		(zone
			(layer "F.Cu")
			(hatch none 0.5)
			(connect_pads
				(clearance 0)
			)
			(min_thickness 0.25)
			(keepout
				(tracks allowed)
				(vias not_allowed)
				(pads allowed)
				(copperpour not_allowed)
				(footprints allowed)
			)
			(placement
				(enabled no)
				(sheetname "")
			)
			(fill
				(thermal_gap 0.5)
				(thermal_bridge_width 0.5)
				(island_removal_mode 0)
			)
			(polygon
				(pts
					(xy 111.379 -69.596) (xy 111.887 -69.596) (xy 111.887 -69.215) (xy 111.379 -69.215)
				)
			)
		)
		(zone
			(layer "F.Cu")
			(hatch none 0.5)
			(connect_pads
				(clearance 0)
			)
			(min_thickness 0.25)
			(keepout
				(tracks not_allowed)
				(vias allowed)
				(pads allowed)
				(copperpour not_allowed)
				(footprints allowed)
			)
			(placement
				(enabled no)
				(sheetname "")
			)
			(fill
				(thermal_gap 0.5)
				(thermal_bridge_width 0.5)
				(island_removal_mode 0)
			)
			(polygon
				(pts
					(xy 111.379 -69.215) (xy 111.887 -69.215) (xy 111.887 -69.596) (xy 111.379 -69.596)
				)
			)
		)
	)
	(footprint ""
		(layer "F.Cu")
		(at 193.127122 -149.778212 -90)
		(property "Reference" "C4A4"
			(at 0 0 270)
			(layer "F.SilkS")
			(hide yes)
			(effects
				(font
					(size 1.27 1.27)
				)
			)
		)
		(property "Value" ""
			(at 0 0 270)
			(layer "F.Fab")
			(effects
				(font
					(size 1.27 1.27)
				)
			)
		)
		(duplicate_pad_numbers_are_jumpers no)
		(fp_rect
			(start -0.7239 1.9939)
			(end 0.7239 -0.2159)
			(stroke
				(width 0)
				(type default)
			)
			(fill no)
			(layer "F.CrtYd")
		)
		(fp_line
			(start -0.7239 1.9939)
			(end 0.7239 1.9939)
			(stroke
				(width 0.1)
				(type default)
			)
			(layer "F.Fab")
		)
		(fp_line
			(start 0.7239 1.9939)
			(end 0.7239 -0.2159)
			(stroke
				(width 0.1)
				(type default)
			)
			(layer "F.Fab")
		)
		(fp_line
			(start -0.7239 -0.2159)
			(end -0.7239 1.9939)
			(stroke
				(width 0.1)
				(type default)
			)
			(layer "F.Fab")
		)
		(fp_line
			(start 0.7239 -0.2159)
			(end -0.7239 -0.2159)
			(stroke
				(width 0.1)
				(type default)
			)
			(layer "F.Fab")
		)
		(pad "1" smd rect
			(at 0 0 270)
			(size 1.27 1.016)
			(layers "F.Cu" "F.Mask" "F.Paste")
			(net "P12V_NVDIMM_DEF")
		)
		(pad "2" smd rect
			(at 0 1.778 270)
			(size 1.27 1.016)
			(layers "F.Cu" "F.Mask" "F.Paste")
			(net "GND")
		)
		(zone
			(layer "F.Cu")
			(hatch none 0.5)
			(connect_pads
				(clearance 0)
			)
			(min_thickness 0.25)
			(keepout
				(tracks not_allowed)
				(vias allowed)
				(pads allowed)
				(copperpour not_allowed)
				(footprints allowed)
			)
			(placement
				(enabled no)
				(sheetname "")
			)
			(fill
				(thermal_gap 0.5)
				(thermal_bridge_width 0.5)
				(island_removal_mode 0)
			)
			(polygon
				(pts
					(xy 191.857122 -150.413212) (xy 191.857122 -149.143212) (xy 192.619122 -149.143212) (xy 192.619122 -150.413212)
				)
			)
		)
	)
	(footprint ""
		(layer "F.Cu")
		(at 182.118 -47.8282 -90)
		(property "Reference" "C4E24"
			(at 2.05867 9.652 0)
			(unlocked yes)
			(layer "F.SilkS")
			(effects
				(font
					(size 0.7874 0.5842)
					(thickness 0.1524)
				)
			)
		)
		(property "Value" ""
			(at 0 0 270)
			(layer "F.Fab")
			(effects
				(font
					(size 1.27 1.27)
				)
			)
		)
		(duplicate_pad_numbers_are_jumpers no)
		(fp_line
			(start -2.286 7.366)
			(end -1.60147 7.366)
			(stroke
				(width 0.1524)
				(type default)
			)
			(layer "F.SilkS")
		)
		(fp_line
			(start -2.286 7.366)
			(end -2.286 1.632712)
			(stroke
				(width 0.1524)
				(type default)
			)
			(layer "F.SilkS")
		)
		(fp_line
			(start 2.286 7.366)
			(end 1.600708 7.366)
			(stroke
				(width 0.1524)
				(type default)
			)
			(layer "F.SilkS")
		)
		(fp_line
			(start 2.286 7.366)
			(end 2.286 1.63195)
			(stroke
				(width 0.1524)
				(type default)
			)
			(layer "F.SilkS")
		)
		(fp_line
			(start -2.563114 1.633728)
			(end -1.6002 1.633728)
			(stroke
				(width 0.1524)
				(type default)
			)
			(layer "F.SilkS")
		)
		(fp_line
			(start 2.504948 1.633728)
			(end 1.6002 1.633728)
			(stroke
				(width 0.1524)
				(type default)
			)
			(layer "F.SilkS")
		)
		(fp_line
			(start -2.563114 -1.616456)
			(end -2.563114 1.633728)
			(stroke
				(width 0.1524)
				(type default)
			)
			(layer "F.SilkS")
		)
		(fp_line
			(start -1.6002 -1.616456)
			(end -2.563114 -1.616456)
			(stroke
				(width 0.1524)
				(type default)
			)
			(layer "F.SilkS")
		)
		(fp_line
			(start 1.6002 -1.616456)
			(end 2.504948 -1.616456)
			(stroke
				(width 0.1524)
				(type default)
			)
			(layer "F.SilkS")
		)
		(fp_line
			(start 2.504948 -1.616456)
			(end 2.504948 1.633728)
			(stroke
				(width 0.1524)
				(type default)
			)
			(layer "F.SilkS")
		)
		(fp_rect
			(start -2.286 7.366)
			(end 2.286 -0.254)
			(stroke
				(width 0)
				(type default)
			)
			(fill no)
			(layer "F.CrtYd")
		)
		(fp_line
			(start -2.286 7.366)
			(end -2.286 -0.254)
			(stroke
				(width 0.1)
				(type default)
			)
			(layer "F.Fab")
		)
		(fp_line
			(start 2.286 7.366)
			(end -2.286 7.366)
			(stroke
				(width 0.1)
				(type default)
			)
			(layer "F.Fab")
		)
		(fp_line
			(start -2.286 -0.254)
			(end 2.286 -0.254)
			(stroke
				(width 0.1)
				(type default)
			)
			(layer "F.Fab")
		)
		(fp_line
			(start 2.286 -0.254)
			(end 2.286 7.366)
			(stroke
				(width 0.1)
				(type default)
			)
			(layer "F.Fab")
		)
		(pad "1" smd rect
			(at 0 0 270)
			(size 2.54 3.048)
			(layers "F.Cu" "F.Mask" "F.Paste")
			(net "PVCCMCP_CPU1")
		)
		(pad "2" smd rect
			(at 0 7.112 270)
			(size 2.54 3.048)
			(layers "F.Cu" "F.Mask" "F.Paste")
			(net "GND")
		)
	)
	(footprint ""
		(layer "F.Cu")
		(at 36.425886 -85.6996 -90)
		(property "Reference" "RT10"
			(at 0 0 270)
			(layer "F.SilkS")
			(hide yes)
			(effects
				(font
					(size 1.27 1.27)
				)
			)
		)
		(property "Value" "*"
			(at -0.0254 -2.6289 270)
			(unlocked yes)
			(layer "F.Fab")
			(hide yes)
			(effects
				(font
					(size 1.27 1.016)
					(thickness 0.1524)
				)
			)
		)
		(property "Device Type" "1R3F-GP_RCL_GP-1R3F-GP,64.1R00A"
			(at -0.0254 -4.1529 270)
			(unlocked yes)
			(layer "F.Fab")
			(hide yes)
			(effects
				(font
					(size 1.27 1.016)
					(thickness 0.1524)
				)
			)
		)
		(duplicate_pad_numbers_are_jumpers no)
		(fp_line
			(start -0.4826 0)
			(end -0.2032 0)
			(stroke
				(width 0.2032)
				(type default)
			)
			(layer "F.SilkS")
		)
		(fp_line
			(start 0.2032 0)
			(end 0.4826 0)
			(stroke
				(width 0.2032)
				(type default)
			)
			(layer "F.SilkS")
		)
		(fp_rect
			(start -0.5842 1.3335)
			(end 0.5842 -1.3335)
			(stroke
				(width 0)
				(type default)
			)
			(fill no)
			(layer "F.CrtYd")
		)
		(fp_rect
			(start -0.5842 1.3335)
			(end 0.5842 -1.3335)
			(stroke
				(width 0)
				(type default)
			)
			(fill no)
			(layer "F.Fab")
		)
		(pad "1" smd custom
			(at 0 -0.762 270)
			(size 0.2159 0.2159)
			(layers "F.Cu" "F.Mask" "F.Paste")
			(net "VR_PVCCIN_CPU1_PHASE5_RC")
			(options
				(clearance outline)
				(anchor circle)
			)
			(primitives
				(gr_poly
					(pts
						(arc
							(start -0.3302 -0.4318)
							(mid -0.402042 -0.402042)
							(end -0.4318 -0.3302)
						)
						(arc
							(start -0.4318 0.3302)
							(mid -0.402042 0.402042)
							(end -0.3302 0.4318)
						)
						(arc
							(start 0.3302 0.4318)
							(mid 0.402042 0.402042)
							(end 0.4318 0.3302)
						)
						(arc
							(start 0.4318 -0.3302)
							(mid 0.402042 -0.402042)
							(end 0.3302 -0.4318)
						)
					)
					(width 0)
					(fill yes)
				)
			)
		)
		(pad "2" smd custom
			(at 0 0.762 270)
			(size 0.2159 0.2159)
			(layers "F.Cu" "F.Mask" "F.Paste")
			(net "GND")
			(options
				(clearance outline)
				(anchor circle)
			)
			(primitives
				(gr_poly
					(pts
						(arc
							(start -0.3302 -0.4318)
							(mid -0.402042 -0.402042)
							(end -0.4318 -0.3302)
						)
						(arc
							(start -0.4318 0.3302)
							(mid -0.402042 0.402042)
							(end -0.3302 0.4318)
						)
						(arc
							(start 0.3302 0.4318)
							(mid 0.402042 0.402042)
							(end 0.4318 0.3302)
						)
						(arc
							(start 0.4318 -0.3302)
							(mid 0.402042 -0.402042)
							(end 0.3302 -0.4318)
						)
					)
					(width 0)
					(fill yes)
				)
			)
		)
	)
	(footprint ""
		(layer "F.Cu")
		(at 396.367 -85.09 180)
		(property "Reference" "R2N25"
			(at 0 0 180)
			(layer "F.SilkS")
			(hide yes)
			(effects
				(font
					(size 1.27 1.27)
				)
			)
		)
		(property "Value" ""
			(at 0 0 180)
			(layer "F.Fab")
			(effects
				(font
					(size 1.27 1.27)
				)
			)
		)
		(duplicate_pad_numbers_are_jumpers no)
		(fp_poly
			(pts
				(xy -0.2794 -0.1016) (xy 0.2794 -0.1016) (xy 0.2794 0.9906) (xy -0.2794 0.9906)
			)
			(stroke
				(width 0)
				(type default)
			)
			(fill no)
			(layer "F.CrtYd")
		)
		(fp_line
			(start 0.2794 0.9906)
			(end 0.2794 -0.1016)
			(stroke
				(width 0.1)
				(type default)
			)
			(layer "F.Fab")
		)
		(fp_line
			(start 0.2794 -0.1016)
			(end -0.2794 -0.1016)
			(stroke
				(width 0.1)
				(type default)
			)
			(layer "F.Fab")
		)
		(fp_line
			(start -0.2794 0.9906)
			(end 0.2794 0.9906)
			(stroke
				(width 0.1)
				(type default)
			)
			(layer "F.Fab")
		)
		(fp_line
			(start -0.2794 -0.1016)
			(end -0.2794 0.9906)
			(stroke
				(width 0.1)
				(type default)
			)
			(layer "F.Fab")
		)
		(pad "1" smd rect
			(at 0 0 180)
			(size 0.508 0.508)
			(layers "F.Cu" "F.Mask" "F.Paste")
			(net "FM_NMI_EVENT_N")
		)
		(pad "2" smd rect
			(at 0 0.889 180)
			(size 0.508 0.508)
			(layers "F.Cu" "F.Mask" "F.Paste")
			(net "FM_BMC_NMI_N")
		)
		(zone
			(layer "F.Cu")
			(hatch none 0.5)
			(connect_pads
				(clearance 0)
			)
			(min_thickness 0.25)
			(keepout
				(tracks not_allowed)
				(vias allowed)
				(pads allowed)
				(copperpour not_allowed)
				(footprints allowed)
			)
			(placement
				(enabled no)
				(sheetname "")
			)
			(fill
				(thermal_gap 0.5)
				(thermal_bridge_width 0.5)
				(island_removal_mode 0)
			)
			(polygon
				(pts
					(xy 396.621 -85.725) (xy 396.113 -85.725) (xy 396.113 -85.344) (xy 396.621 -85.344)
				)
			)
		)
		(zone
			(layer "F.Cu")
			(hatch none 0.5)
			(connect_pads
				(clearance 0)
			)
			(min_thickness 0.25)
			(keepout
				(tracks allowed)
				(vias not_allowed)
				(pads allowed)
				(copperpour not_allowed)
				(footprints allowed)
			)
			(placement
				(enabled no)
				(sheetname "")
			)
			(fill
				(thermal_gap 0.5)
				(thermal_bridge_width 0.5)
				(island_removal_mode 0)
			)
			(polygon
				(pts
					(xy 396.621 -85.344) (xy 396.113 -85.344) (xy 396.113 -85.725) (xy 396.621 -85.725)
				)
			)
		)
	)
	(footprint ""
		(layer "F.Cu")
		(at 40.60825 -102.729284 90)
		(property "Reference" "R1C7"
			(at -0.8382 -0.67818 90)
			(unlocked yes)
			(layer "F.SilkS")
			(effects
				(font
					(size 0.4064 0.254)
					(thickness 0.1524)
				)
				(justify left)
			)
		)
		(property "Value" ""
			(at 0 0 90)
			(layer "F.Fab")
			(effects
				(font
					(size 1.27 1.27)
				)
			)
		)
		(duplicate_pad_numbers_are_jumpers no)
		(fp_poly
			(pts
				(xy -0.2794 -0.1016) (xy 0.2794 -0.1016) (xy 0.2794 0.9906) (xy -0.2794 0.9906)
			)
			(stroke
				(width 0)
				(type default)
			)
			(fill no)
			(layer "F.CrtYd")
		)
		(fp_line
			(start 0.2794 -0.1016)
			(end -0.2794 -0.1016)
			(stroke
				(width 0.1)
				(type default)
			)
			(layer "F.Fab")
		)
		(fp_line
			(start -0.2794 -0.1016)
			(end -0.2794 0.9906)
			(stroke
				(width 0.1)
				(type default)
			)
			(layer "F.Fab")
		)
		(fp_line
			(start 0.2794 0.9906)
			(end 0.2794 -0.1016)
			(stroke
				(width 0.1)
				(type default)
			)
			(layer "F.Fab")
		)
		(fp_line
			(start -0.2794 0.9906)
			(end 0.2794 0.9906)
			(stroke
				(width 0.1)
				(type default)
			)
			(layer "F.Fab")
		)
		(pad "1" smd rect
			(at 0 0 90)
			(size 0.508 0.508)
			(layers "F.Cu" "F.Mask" "F.Paste")
			(net "VSENSE_PVSA_CPU1_P")
		)
		(pad "2" smd rect
			(at 0 0.889 90)
			(size 0.508 0.508)
			(layers "F.Cu" "F.Mask" "F.Paste")
			(net "VSENSE_PVSA_CPU1_SKT_VSEN")
		)
		(zone
			(layer "F.Cu")
			(hatch none 0.5)
			(connect_pads
				(clearance 0)
			)
			(min_thickness 0.25)
			(keepout
				(tracks allowed)
				(vias not_allowed)
				(pads allowed)
				(copperpour not_allowed)
				(footprints allowed)
			)
			(placement
				(enabled no)
				(sheetname "")
			)
			(fill
				(thermal_gap 0.5)
				(thermal_bridge_width 0.5)
				(island_removal_mode 0)
			)
			(polygon
				(pts
					(xy 40.86225 -102.475284) (xy 40.86225 -102.983284) (xy 41.24325 -102.983284) (xy 41.24325 -102.475284)
				)
			)
		)
		(zone
			(layer "F.Cu")
			(hatch none 0.5)
			(connect_pads
				(clearance 0)
			)
			(min_thickness 0.25)
			(keepout
				(tracks not_allowed)
				(vias allowed)
				(pads allowed)
				(copperpour not_allowed)
				(footprints allowed)
			)
			(placement
				(enabled no)
				(sheetname "")
			)
			(fill
				(thermal_gap 0.5)
				(thermal_bridge_width 0.5)
				(island_removal_mode 0)
			)
			(polygon
				(pts
					(xy 41.24325 -102.475284) (xy 41.24325 -102.983284) (xy 40.86225 -102.983284) (xy 40.86225 -102.475284)
				)
			)
		)
	)
	(footprint ""
		(layer "F.Cu")
		(at 477.901 -36.6395 180)
		(property "Reference" "R8G24"
			(at 0 0 180)
			(layer "F.SilkS")
			(hide yes)
			(effects
				(font
					(size 1.27 1.27)
				)
			)
		)
		(property "Value" ""
			(at 0 0 180)
			(layer "F.Fab")
			(effects
				(font
					(size 1.27 1.27)
				)
			)
		)
		(duplicate_pad_numbers_are_jumpers no)
		(fp_poly
			(pts
				(xy -0.2794 -0.1016) (xy 0.2794 -0.1016) (xy 0.2794 0.9906) (xy -0.2794 0.9906)
			)
			(stroke
				(width 0)
				(type default)
			)
			(fill no)
			(layer "F.CrtYd")
		)
		(fp_line
			(start 0.2794 0.9906)
			(end 0.2794 -0.1016)
			(stroke
				(width 0.1)
				(type default)
			)
			(layer "F.Fab")
		)
		(fp_line
			(start 0.2794 -0.1016)
			(end -0.2794 -0.1016)
			(stroke
				(width 0.1)
				(type default)
			)
			(layer "F.Fab")
		)
		(fp_line
			(start -0.2794 0.9906)
			(end 0.2794 0.9906)
			(stroke
				(width 0.1)
				(type default)
			)
			(layer "F.Fab")
		)
		(fp_line
			(start -0.2794 -0.1016)
			(end -0.2794 0.9906)
			(stroke
				(width 0.1)
				(type default)
			)
			(layer "F.Fab")
		)
		(pad "1" smd rect
			(at 0 0 180)
			(size 0.508 0.508)
			(layers "F.Cu" "F.Mask" "F.Paste")
			(net "CLK_50M_CKMNG_PCH_10GBE_R")
		)
		(pad "2" smd rect
			(at 0 0.889 180)
			(size 0.508 0.508)
			(layers "F.Cu" "F.Mask" "F.Paste")
			(net "CLK_50M_CKMNG_PCH_10GBE")
		)
		(zone
			(layer "F.Cu")
			(hatch none 0.5)
			(connect_pads
				(clearance 0)
			)
			(min_thickness 0.25)
			(keepout
				(tracks not_allowed)
				(vias allowed)
				(pads allowed)
				(copperpour not_allowed)
				(footprints allowed)
			)
			(placement
				(enabled no)
				(sheetname "")
			)
			(fill
				(thermal_gap 0.5)
				(thermal_bridge_width 0.5)
				(island_removal_mode 0)
			)
			(polygon
				(pts
					(xy 478.155 -37.2745) (xy 477.647 -37.2745) (xy 477.647 -36.8935) (xy 478.155 -36.8935)
				)
			)
		)
		(zone
			(layer "F.Cu")
			(hatch none 0.5)
			(connect_pads
				(clearance 0)
			)
			(min_thickness 0.25)
			(keepout
				(tracks allowed)
				(vias not_allowed)
				(pads allowed)
				(copperpour not_allowed)
				(footprints allowed)
			)
			(placement
				(enabled no)
				(sheetname "")
			)
			(fill
				(thermal_gap 0.5)
				(thermal_bridge_width 0.5)
				(island_removal_mode 0)
			)
			(polygon
				(pts
					(xy 478.155 -36.8935) (xy 477.647 -36.8935) (xy 477.647 -37.2745) (xy 478.155 -37.2745)
				)
			)
		)
	)
	(footprint ""
		(layer "F.Cu")
		(at 384.556 -87.3125 180)
		(property "Reference" "R7D10"
			(at 0 0 180)
			(layer "F.SilkS")
			(hide yes)
			(effects
				(font
					(size 1.27 1.27)
				)
			)
		)
		(property "Value" ""
			(at 0 0 180)
			(layer "F.Fab")
			(effects
				(font
					(size 1.27 1.27)
				)
			)
		)
		(duplicate_pad_numbers_are_jumpers no)
		(fp_poly
			(pts
				(xy -0.2794 -0.1016) (xy 0.2794 -0.1016) (xy 0.2794 0.9906) (xy -0.2794 0.9906)
			)
			(stroke
				(width 0)
				(type default)
			)
			(fill no)
			(layer "F.CrtYd")
		)
		(fp_line
			(start 0.2794 0.9906)
			(end 0.2794 -0.1016)
			(stroke
				(width 0.1)
				(type default)
			)
			(layer "F.Fab")
		)
		(fp_line
			(start 0.2794 -0.1016)
			(end -0.2794 -0.1016)
			(stroke
				(width 0.1)
				(type default)
			)
			(layer "F.Fab")
		)
		(fp_line
			(start -0.2794 0.9906)
			(end 0.2794 0.9906)
			(stroke
				(width 0.1)
				(type default)
			)
			(layer "F.Fab")
		)
		(fp_line
			(start -0.2794 -0.1016)
			(end -0.2794 0.9906)
			(stroke
				(width 0.1)
				(type default)
			)
			(layer "F.Fab")
		)
		(pad "1" smd rect
			(at 0 0 180)
			(size 0.508 0.508)
			(layers "F.Cu" "F.Mask" "F.Paste")
			(net "P3V3_STBY")
		)
		(pad "2" smd rect
			(at 0 0.889 180)
			(size 0.508 0.508)
			(layers "F.Cu" "F.Mask" "F.Paste")
			(net "PU_LPC_PME_N")
		)
		(zone
			(layer "F.Cu")
			(hatch none 0.5)
			(connect_pads
				(clearance 0)
			)
			(min_thickness 0.25)
			(keepout
				(tracks not_allowed)
				(vias allowed)
				(pads allowed)
				(copperpour not_allowed)
				(footprints allowed)
			)
			(placement
				(enabled no)
				(sheetname "")
			)
			(fill
				(thermal_gap 0.5)
				(thermal_bridge_width 0.5)
				(island_removal_mode 0)
			)
			(polygon
				(pts
					(xy 384.81 -87.9475) (xy 384.302 -87.9475) (xy 384.302 -87.5665) (xy 384.81 -87.5665)
				)
			)
		)
		(zone
			(layer "F.Cu")
			(hatch none 0.5)
			(connect_pads
				(clearance 0)
			)
			(min_thickness 0.25)
			(keepout
				(tracks allowed)
				(vias not_allowed)
				(pads allowed)
				(copperpour not_allowed)
				(footprints allowed)
			)
			(placement
				(enabled no)
				(sheetname "")
			)
			(fill
				(thermal_gap 0.5)
				(thermal_bridge_width 0.5)
				(island_removal_mode 0)
			)
			(polygon
				(pts
					(xy 384.81 -87.5665) (xy 384.302 -87.5665) (xy 384.302 -87.9475) (xy 384.81 -87.9475)
				)
			)
		)
	)
	(footprint ""
		(layer "F.Cu")
		(at 408.319478 -118.239032 90)
		(property "Reference" "R1W15"
			(at -0.8382 -0.67818 90)
			(unlocked yes)
			(layer "F.SilkS")
			(effects
				(font
					(size 0.4064 0.254)
					(thickness 0.1524)
				)
				(justify left)
			)
		)
		(property "Value" ""
			(at 0 0 90)
			(layer "F.Fab")
			(effects
				(font
					(size 1.27 1.27)
				)
			)
		)
		(duplicate_pad_numbers_are_jumpers no)
		(fp_poly
			(pts
				(xy -0.2794 -0.1016) (xy 0.2794 -0.1016) (xy 0.2794 0.9906) (xy -0.2794 0.9906)
			)
			(stroke
				(width 0)
				(type default)
			)
			(fill no)
			(layer "F.CrtYd")
		)
		(fp_line
			(start 0.2794 -0.1016)
			(end -0.2794 -0.1016)
			(stroke
				(width 0.1)
				(type default)
			)
			(layer "F.Fab")
		)
		(fp_line
			(start -0.2794 -0.1016)
			(end -0.2794 0.9906)
			(stroke
				(width 0.1)
				(type default)
			)
			(layer "F.Fab")
		)
		(fp_line
			(start 0.2794 0.9906)
			(end 0.2794 -0.1016)
			(stroke
				(width 0.1)
				(type default)
			)
			(layer "F.Fab")
		)
		(fp_line
			(start -0.2794 0.9906)
			(end 0.2794 0.9906)
			(stroke
				(width 0.1)
				(type default)
			)
			(layer "F.Fab")
		)
		(pad "1" smd rect
			(at 0 0 90)
			(size 0.508 0.508)
			(layers "F.Cu" "F.Mask" "F.Paste")
			(net "USB2_PCH_BMC_P5_DN_R")
		)
		(pad "2" smd rect
			(at 0 0.889 90)
			(size 0.508 0.508)
			(layers "F.Cu" "F.Mask" "F.Paste")
			(net "USB2_PCH_BMC_P5_DN")
		)
		(zone
			(layer "F.Cu")
			(hatch none 0.5)
			(connect_pads
				(clearance 0)
			)
			(min_thickness 0.25)
			(keepout
				(tracks allowed)
				(vias not_allowed)
				(pads allowed)
				(copperpour not_allowed)
				(footprints allowed)
			)
			(placement
				(enabled no)
				(sheetname "")
			)
			(fill
				(thermal_gap 0.5)
				(thermal_bridge_width 0.5)
				(island_removal_mode 0)
			)
			(polygon
				(pts
					(xy 408.573478 -117.985032) (xy 408.573478 -118.493032) (xy 408.954478 -118.493032) (xy 408.954478 -117.985032)
				)
			)
		)
		(zone
			(layer "F.Cu")
			(hatch none 0.5)
			(connect_pads
				(clearance 0)
			)
			(min_thickness 0.25)
			(keepout
				(tracks not_allowed)
				(vias allowed)
				(pads allowed)
				(copperpour not_allowed)
				(footprints allowed)
			)
			(placement
				(enabled no)
				(sheetname "")
			)
			(fill
				(thermal_gap 0.5)
				(thermal_bridge_width 0.5)
				(island_removal_mode 0)
			)
			(polygon
				(pts
					(xy 408.954478 -117.985032) (xy 408.954478 -118.493032) (xy 408.573478 -118.493032) (xy 408.573478 -117.985032)
				)
			)
		)
	)
	(footprint ""
		(layer "F.Cu")
		(at 332.5114 -140.9446 90)
		(property "Reference" "C6A5"
			(at 2.92862 3.24612 0)
			(unlocked yes)
			(layer "F.SilkS")
			(effects
				(font
					(size 0.4064 0.254)
					(thickness 0.1524)
				)
			)
		)
		(property "Value" ""
			(at 0 0 90)
			(layer "F.Fab")
			(effects
				(font
					(size 1.27 1.27)
				)
			)
		)
		(duplicate_pad_numbers_are_jumpers no)
		(fp_line
			(start 2.504948 -1.616456)
			(end 2.504948 1.633728)
			(stroke
				(width 0.1524)
				(type default)
			)
			(layer "F.SilkS")
		)
		(fp_line
			(start 1.6002 -1.616456)
			(end 2.504948 -1.616456)
			(stroke
				(width 0.1524)
				(type default)
			)
			(layer "F.SilkS")
		)
		(fp_line
			(start -1.6002 -1.616456)
			(end -2.563114 -1.616456)
			(stroke
				(width 0.1524)
				(type default)
			)
			(layer "F.SilkS")
		)
		(fp_line
			(start -2.563114 -1.616456)
			(end -2.563114 1.633728)
			(stroke
				(width 0.1524)
				(type default)
			)
			(layer "F.SilkS")
		)
		(fp_line
			(start 2.504948 1.633728)
			(end 1.6002 1.633728)
			(stroke
				(width 0.1524)
				(type default)
			)
			(layer "F.SilkS")
		)
		(fp_line
			(start -2.563114 1.633728)
			(end -1.6002 1.633728)
			(stroke
				(width 0.1524)
				(type default)
			)
			(layer "F.SilkS")
		)
		(fp_line
			(start 2.286 7.366)
			(end 2.286 1.63195)
			(stroke
				(width 0.1524)
				(type default)
			)
			(layer "F.SilkS")
		)
		(fp_line
			(start 2.286 7.366)
			(end 1.600708 7.366)
			(stroke
				(width 0.1524)
				(type default)
			)
			(layer "F.SilkS")
		)
		(fp_line
			(start -2.286 7.366)
			(end -2.286 1.632712)
			(stroke
				(width 0.1524)
				(type default)
			)
			(layer "F.SilkS")
		)
		(fp_line
			(start -2.286 7.366)
			(end -1.60147 7.366)
			(stroke
				(width 0.1524)
				(type default)
			)
			(layer "F.SilkS")
		)
		(fp_rect
			(start -2.286 7.366)
			(end 2.286 -0.254)
			(stroke
				(width 0)
				(type default)
			)
			(fill no)
			(layer "F.CrtYd")
		)
		(fp_line
			(start 2.286 -0.254)
			(end 2.286 7.366)
			(stroke
				(width 0.1)
				(type default)
			)
			(layer "F.Fab")
		)
		(fp_line
			(start -2.286 -0.254)
			(end 2.286 -0.254)
			(stroke
				(width 0.1)
				(type default)
			)
			(layer "F.Fab")
		)
		(fp_line
			(start 2.286 7.366)
			(end -2.286 7.366)
			(stroke
				(width 0.1)
				(type default)
			)
			(layer "F.Fab")
		)
		(fp_line
			(start -2.286 7.366)
			(end -2.286 -0.254)
			(stroke
				(width 0.1)
				(type default)
			)
			(layer "F.Fab")
		)
		(pad "1" smd rect
			(at 0 0 90)
			(size 2.54 3.048)
			(layers "F.Cu" "F.Mask" "F.Paste")
			(net "PVDDQ_DEF")
		)
		(pad "2" smd rect
			(at 0 7.112 90)
			(size 2.54 3.048)
			(layers "F.Cu" "F.Mask" "F.Paste")
			(net "GND")
		)
	)
	(footprint ""
		(layer "F.Cu")
		(at 177.434494 -54.347618 -90)
		(property "Reference" "EU4E2"
			(at 3.320288 0.142494 0)
			(unlocked yes)
			(layer "F.SilkS")
			(effects
				(font
					(size 0.7874 0.5842)
					(thickness 0.1524)
				)
			)
		)
		(property "Value" ""
			(at 0 0 270)
			(layer "F.Fab")
			(effects
				(font
					(size 1.27 1.27)
				)
			)
		)
		(duplicate_pad_numbers_are_jumpers no)
		(fp_line
			(start -3.0099 3.429)
			(end -3.0099 -3.5052)
			(stroke
				(width 0.1524)
				(type default)
			)
			(layer "F.SilkS")
		)
		(fp_line
			(start 2.9718 3.429)
			(end -3.0099 3.429)
			(stroke
				(width 0.1524)
				(type default)
			)
			(layer "F.SilkS")
		)
		(fp_line
			(start -3.0099 -3.5052)
			(end 2.9718 -3.5052)
			(stroke
				(width 0.1524)
				(type default)
			)
			(layer "F.SilkS")
		)
		(fp_line
			(start 2.9718 -3.5052)
			(end 2.9718 3.429)
			(stroke
				(width 0.1524)
				(type default)
			)
			(layer "F.SilkS")
		)
		(fp_circle
			(center -3.057398 -2.678684)
			(end -3.057398 -2.805684)
			(stroke
				(width 0.254)
				(type default)
			)
			(fill no)
			(layer "F.SilkS")
		)
		(fp_poly
			(pts
				(xy -2.9972 -3.4925) (xy -2.9972 -2.6924) (xy -2.1971 -3.4925)
			)
			(stroke
				(width 0)
				(type default)
			)
			(fill yes)
			(layer "F.SilkS")
		)
		(fp_poly
			(pts
				(xy -2.549906 -3.050032) (xy -2.549906 3.050032) (xy 2.549906 3.050032) (xy 2.549906 -3.050032)
			)
			(stroke
				(width 0)
				(type default)
			)
			(fill no)
			(layer "F.CrtYd")
		)
		(fp_line
			(start -2.549906 3.050032)
			(end -2.549906 -3.050032)
			(stroke
				(width 0.1)
				(type default)
			)
			(layer "F.Fab")
		)
		(fp_line
			(start 2.549906 3.050032)
			(end -2.549906 3.050032)
			(stroke
				(width 0.1)
				(type default)
			)
			(layer "F.Fab")
		)
		(fp_line
			(start -2.549906 -3.050032)
			(end 2.549906 -3.050032)
			(stroke
				(width 0.1)
				(type default)
			)
			(layer "F.Fab")
		)
		(fp_line
			(start 2.549906 -3.050032)
			(end 2.549906 3.050032)
			(stroke
				(width 0.1)
				(type default)
			)
			(layer "F.Fab")
		)
		(fp_circle
			(center -3.057398 -2.678684)
			(end -3.057398 -2.805684)
			(stroke
				(width 0.254)
				(type default)
			)
			(fill no)
			(layer "F.Fab")
		)
		(pad "1" smd rect
			(at -2.39522 -2.279904 270)
			(size 0.7112 0.254)
			(layers "F.Cu" "F.Mask" "F.Paste")
			(net "PVCCIO_CPU1")
		)
		(pad "2" smd rect
			(at -2.39522 -1.83007 270)
			(size 0.7112 0.254)
			(layers "F.Cu" "F.Mask" "F.Paste")
			(net "GND")
		)
		(pad "3" smd rect
			(at -2.39522 -1.379982 270)
			(size 0.7112 0.254)
			(layers "F.Cu" "F.Mask" "F.Paste")
			(net "VR_PVCCIO_CPU1_PH1_VCIN")
		)
		(pad "4" smd rect
			(at -2.39522 -0.929894 270)
			(size 0.7112 0.254)
			(layers "F.Cu" "F.Mask" "F.Paste")
			(net "P5V_STBY")
		)
		(pad "5" smd rect
			(at -2.39522 -0.48006 270)
			(size 0.7112 0.254)
			(layers "F.Cu" "F.Mask" "F.Paste")
			(net "GND")
		)
		(pad "6" smd rect
			(at -2.39522 -0.029972 270)
			(size 0.7112 0.254)
			(layers "F.Cu" "F.Mask" "F.Paste")
			(net "TP_PVCCIO_CPU1_GL_0")
		)
		(pad "7" smd custom
			(at 0.016764 1.145032 270)
			(size 0.53975 0.53975)
			(layers "F.Cu" "F.Mask" "F.Paste")
			(net "GND")
			(options
				(clearance outline)
				(anchor circle)
			)
			(primitives
				(gr_poly
					(pts
						(xy -2.7051 1.0795) (xy -2.7051 -0.3683) (xy -0.9271 -0.3683) (xy -0.9271 -1.0795) (xy 2.7051 -1.0795)
						(xy 2.7051 1.0795)
					)
					(width 0)
					(fill yes)
				)
			)
		)
		(pad "10" smd rect
			(at -0.008382 2.874772 270)
			(size 4.3434 0.6096)
			(layers "F.Cu" "F.Mask" "F.Paste")
			(net "VR_PVCCIO_CPU1_PH1_SW")
		)
		(pad "25" smd rect
			(at 1.548384 -1.283208 270)
			(size 2.3368 2.0066)
			(layers "F.Cu" "F.Mask" "F.Paste")
			(net "VR_FET_SW_P12V_STBY_PVCCIN_CPU0")
		)
		(pad "30" smd rect
			(at 2.050034 -2.895092 270)
			(size 0.254 0.7112)
			(layers "F.Cu" "F.Mask" "F.Paste")
			(net "VR_FET_SW_P12V_STBY_PVCCIN_CPU0")
		)
		(pad "31" smd rect
			(at 1.599946 -2.895092 270)
			(size 0.254 0.7112)
			(layers "F.Cu" "F.Mask" "F.Paste")
			(net "Net_367")
		)
		(pad "32" smd rect
			(at 1.150112 -2.895092 270)
			(size 0.254 0.7112)
			(layers "F.Cu" "F.Mask" "F.Paste")
			(net "VR_PVCCIO_CPU1_PH1_PHASE")
		)
		(pad "33" smd rect
			(at 0.700024 -2.895092 270)
			(size 0.254 0.7112)
			(layers "F.Cu" "F.Mask" "F.Paste")
			(net "VR_PVCCIO_CPU1_PH1_BOOT_R")
		)
		(pad "34" smd rect
			(at 0.249936 -2.895092 270)
			(size 0.254 0.7112)
			(layers "F.Cu" "F.Mask" "F.Paste")
			(net "VR_PVCCIO_CPU1_PWM1")
		)
		(pad "35" smd rect
			(at -0.199898 -2.895092 270)
			(size 0.254 0.7112)
			(layers "F.Cu" "F.Mask" "F.Paste")
			(net "P5V_STBY")
		)
		(pad "36" smd rect
			(at -0.649986 -2.895092 270)
			(size 0.254 0.7112)
			(layers "F.Cu" "F.Mask" "F.Paste")
			(net "A_TSENSE_PVCCIO_CPU1")
		)
		(pad "37" smd rect
			(at -1.100074 -2.895092 270)
			(size 0.254 0.7112)
			(layers "F.Cu" "F.Mask" "F.Paste")
			(net "VR_PVCCIO_CPU1_OCSET")
		)
		(pad "38" smd rect
			(at -1.549908 -2.895092 270)
			(size 0.254 0.7112)
			(layers "F.Cu" "F.Mask" "F.Paste")
			(net "ISENSE_PVCCIO_CPU1_PH1_IMON")
		)
		(pad "39" smd rect
			(at -1.999996 -2.895092 270)
			(size 0.254 0.7112)
			(layers "F.Cu" "F.Mask" "F.Paste")
			(net "VR_PVCCIO_CPU1_AIREF1")
		)
		(pad "40" smd rect
			(at -0.871728 -1.283208 270)
			(size 1.8034 2.0066)
			(layers "F.Cu" "F.Mask" "F.Paste")
			(net "GND")
		)
		(pad "41" smd rect
			(at -1.533906 0.247904 270)
			(size 0.508 0.3556)
			(layers "F.Cu" "F.Mask" "F.Paste")
			(net "TP_PVCCIO_CPU1_GL_1")
		)
	)
	(footprint ""
		(layer "F.Cu")
		(at 29.6164 -59.617102 -90)
		(property "Reference" "C1E13"
			(at 0 0 270)
			(layer "F.SilkS")
			(hide yes)
			(effects
				(font
					(size 1.27 1.27)
				)
			)
		)
		(property "Value" ""
			(at 0 0 270)
			(layer "F.Fab")
			(effects
				(font
					(size 1.27 1.27)
				)
			)
		)
		(duplicate_pad_numbers_are_jumpers no)
		(fp_rect
			(start 0.3048 -0.1016)
			(end -0.3048 0.9906)
			(stroke
				(width 0)
				(type default)
			)
			(fill no)
			(layer "F.CrtYd")
		)
		(fp_line
			(start -0.3048 0.9906)
			(end 0.3048 0.9906)
			(stroke
				(width 0.1)
				(type default)
			)
			(layer "F.Fab")
		)
		(fp_line
			(start 0.3048 0.9906)
			(end 0.3048 -0.1016)
			(stroke
				(width 0.1)
				(type default)
			)
			(layer "F.Fab")
		)
		(fp_line
			(start -0.3048 -0.1016)
			(end -0.3048 0.9906)
			(stroke
				(width 0.1)
				(type default)
			)
			(layer "F.Fab")
		)
		(fp_line
			(start 0.3048 -0.1016)
			(end -0.3048 -0.1016)
			(stroke
				(width 0.1)
				(type default)
			)
			(layer "F.Fab")
		)
		(pad "1" smd rect
			(at 0 0 270)
			(size 0.508 0.508)
			(layers "F.Cu" "F.Mask" "F.Paste")
			(net "VR_FET_SW_P12V_STBY_PVCCIN_CPU1")
		)
		(pad "2" smd rect
			(at 0 0.889 270)
			(size 0.508 0.508)
			(layers "F.Cu" "F.Mask" "F.Paste")
			(net "GND")
		)
		(zone
			(layer "F.Cu")
			(hatch none 0.5)
			(connect_pads
				(clearance 0)
			)
			(min_thickness 0.25)
			(keepout
				(tracks not_allowed)
				(vias allowed)
				(pads allowed)
				(copperpour not_allowed)
				(footprints allowed)
			)
			(placement
				(enabled no)
				(sheetname "")
			)
			(fill
				(thermal_gap 0.5)
				(thermal_bridge_width 0.5)
				(island_removal_mode 0)
			)
			(polygon
				(pts
					(xy 29.3624 -59.363102) (xy 29.3624 -59.871102) (xy 28.9814 -59.871102) (xy 28.9814 -59.363102)
				)
			)
		)
		(zone
			(layer "F.Cu")
			(hatch none 0.5)
			(connect_pads
				(clearance 0)
			)
			(min_thickness 0.25)
			(keepout
				(tracks allowed)
				(vias not_allowed)
				(pads allowed)
				(copperpour not_allowed)
				(footprints allowed)
			)
			(placement
				(enabled no)
				(sheetname "")
			)
			(fill
				(thermal_gap 0.5)
				(thermal_bridge_width 0.5)
				(island_removal_mode 0)
			)
			(polygon
				(pts
					(xy 29.3624 -59.363102) (xy 29.3624 -59.871102) (xy 28.9814 -59.871102) (xy 28.9814 -59.363102)
				)
			)
		)
	)
	(footprint ""
		(layer "F.Cu")
		(at 341.3506 -147.461224 180)
		(property "Reference" "L7A3"
			(at 3.378708 -4.251706 180)
			(unlocked yes)
			(layer "F.SilkS")
			(effects
				(font
					(size 0.4064 0.254)
					(thickness 0.1524)
				)
			)
		)
		(property "Value" ""
			(at 0 0 180)
			(layer "F.Fab")
			(effects
				(font
					(size 1.27 1.27)
				)
			)
		)
		(duplicate_pad_numbers_are_jumpers no)
		(fp_line
			(start 8.3693 3.199892)
			(end -1.1303 3.199892)
			(stroke
				(width 0.1524)
				(type default)
			)
			(layer "F.SilkS")
		)
		(fp_line
			(start 8.3693 1.6637)
			(end 8.3693 3.199892)
			(stroke
				(width 0.1524)
				(type default)
			)
			(layer "F.SilkS")
		)
		(fp_line
			(start 8.3693 -3.199892)
			(end 8.3693 -1.6637)
			(stroke
				(width 0.1524)
				(type default)
			)
			(layer "F.SilkS")
		)
		(fp_line
			(start -1.1303 3.199892)
			(end -1.1303 1.6637)
			(stroke
				(width 0.1524)
				(type default)
			)
			(layer "F.SilkS")
		)
		(fp_line
			(start -1.1303 -1.6637)
			(end -1.1303 -3.199892)
			(stroke
				(width 0.1524)
				(type default)
			)
			(layer "F.SilkS")
		)
		(fp_line
			(start -1.1303 -3.199892)
			(end 8.3693 -3.199892)
			(stroke
				(width 0.1524)
				(type default)
			)
			(layer "F.SilkS")
		)
		(fp_rect
			(start -1.1303 3.199892)
			(end 8.3693 -3.199892)
			(stroke
				(width 0)
				(type default)
			)
			(fill no)
			(layer "F.CrtYd")
		)
		(fp_line
			(start 8.3693 3.199892)
			(end -1.1303 3.199892)
			(stroke
				(width 0.1)
				(type default)
			)
			(layer "F.Fab")
		)
		(fp_line
			(start 8.3693 -3.199892)
			(end 8.3693 3.199892)
			(stroke
				(width 0.1)
				(type default)
			)
			(layer "F.Fab")
		)
		(fp_line
			(start -1.1303 3.199892)
			(end -1.1303 -3.199892)
			(stroke
				(width 0.1)
				(type default)
			)
			(layer "F.Fab")
		)
		(fp_line
			(start -1.1303 -3.199892)
			(end 8.3693 -3.199892)
			(stroke
				(width 0.1)
				(type default)
			)
			(layer "F.Fab")
		)
		(pad "1" smd rect
			(at 0 0 180)
			(size 3.683 2.667)
			(layers "F.Cu" "F.Mask" "F.Paste")
			(net "VR_PVDDQ_DEF_PH2_SW")
		)
		(pad "2" smd rect
			(at 7.239 0 180)
			(size 3.683 2.667)
			(layers "F.Cu" "F.Mask" "F.Paste")
			(net "PVDDQ_DEF")
		)
	)
	(footprint ""
		(layer "F.Cu")
		(at 292.248082 12.01039 -90)
		(property "Reference" "T1P17"
			(at 0 0 270)
			(layer "F.SilkS")
			(hide yes)
			(effects
				(font
					(size 1.27 1.27)
				)
			)
		)
		(property "Value" "*"
			(at -3.302 1.12395 270)
			(unlocked yes)
			(layer "F.Fab")
			(hide yes)
			(effects
				(font
					(size 0.889 0.889)
					(thickness 0.1524)
				)
			)
		)
		(property "Device Type" "TPAD-DIFF-4P-GP_DISCRET-GB3-TPA"
			(at -3.302 -0.40005 270)
			(unlocked yes)
			(layer "F.Fab")
			(hide yes)
			(effects
				(font
					(size 0.889 0.889)
					(thickness 0.1524)
				)
			)
		)
		(duplicate_pad_numbers_are_jumpers no)
		(fp_line
			(start -2.286 2.286)
			(end 2.286 2.286)
			(stroke
				(width 0.1524)
				(type default)
			)
			(layer "F.SilkS")
		)
		(fp_line
			(start 2.286 2.286)
			(end 2.286 -2.286)
			(stroke
				(width 0.1524)
				(type default)
			)
			(layer "F.SilkS")
		)
		(fp_line
			(start -2.286 -2.286)
			(end -2.286 2.286)
			(stroke
				(width 0.1524)
				(type default)
			)
			(layer "F.SilkS")
		)
		(fp_line
			(start 2.286 -2.286)
			(end -2.286 -2.286)
			(stroke
				(width 0.1524)
				(type default)
			)
			(layer "F.SilkS")
		)
		(fp_line
			(start -2.413 -2.413)
			(end -2.413 -1.143)
			(stroke
				(width 0.4064)
				(type default)
			)
			(layer "F.SilkS")
		)
		(fp_line
			(start -1.143 -2.413)
			(end -2.413 -2.413)
			(stroke
				(width 0.4064)
				(type default)
			)
			(layer "F.SilkS")
		)
		(fp_rect
			(start -2.54 2.54)
			(end 2.54 -2.54)
			(stroke
				(width 0)
				(type default)
			)
			(fill no)
			(layer "F.CrtYd")
		)
		(fp_rect
			(start -2.54 2.54)
			(end 2.54 -2.54)
			(stroke
				(width 0)
				(type default)
			)
			(fill no)
			(layer "F.Fab")
		)
		(pad "1" thru_hole circle
			(at -1.27 -1.27 270)
			(size 1.524 1.524)
			(drill 0.9144)
			(layers "*.Cu" "*.Mask")
			(remove_unused_layers no)
			(net "L12_95OHM_6INCH_DP")
			(clearance -0.0508)
			(thermal_gap 0.127)
			(padstack
				(mode front_inner_back)
				(layer "Inner"
					(shape circle)
					(size 1.1684 1.1684)
					(clearance 0.127)
				)
				(layer "B.Cu"
					(shape circle)
					(size 1.524 1.524)
					(clearance -0.0508)
				)
			)
		)
		(pad "2" thru_hole circle
			(at 1.27 -1.27 270)
			(size 1.524 1.524)
			(drill 0.9144)
			(layers "*.Cu" "*.Mask")
			(remove_unused_layers no)
			(net "L12_95OHM_6INCH_DN")
			(clearance -0.0508)
			(thermal_gap 0.127)
			(padstack
				(mode front_inner_back)
				(layer "Inner"
					(shape circle)
					(size 1.1684 1.1684)
					(clearance 0.127)
				)
				(layer "B.Cu"
					(shape circle)
					(size 1.524 1.524)
					(clearance -0.0508)
				)
			)
		)
		(pad "GND1" thru_hole rect
			(at -1.27 1.27 270)
			(size 1.524 1.524)
			(drill 0.9144)
			(layers "*.Cu" "*.Mask")
			(remove_unused_layers no)
			(net "GND")
			(clearance -0.0508)
			(thermal_gap 0.127)
			(padstack
				(mode front_inner_back)
				(layer "Inner"
					(shape circle)
					(size 1.1684 1.1684)
					(clearance 0.127)
				)
				(layer "B.Cu"
					(shape rect)
					(size 1.524 1.524)
					(clearance -0.0508)
				)
			)
		)
		(pad "GND2" thru_hole rect
			(at 1.27 1.27 270)
			(size 1.524 1.524)
			(drill 0.9144)
			(layers "*.Cu" "*.Mask")
			(remove_unused_layers no)
			(net "GND")
			(clearance -0.0508)
			(thermal_gap 0.127)
			(padstack
				(mode front_inner_back)
				(layer "Inner"
					(shape circle)
					(size 1.1684 1.1684)
					(clearance 0.127)
				)
				(layer "B.Cu"
					(shape rect)
					(size 1.524 1.524)
					(clearance -0.0508)
				)
			)
		)
	)
	(footprint ""
		(layer "F.Cu")
		(at 451.85838 -34.7345 90)
		(property "Reference" "R25W35"
			(at 0 0 90)
			(layer "F.SilkS")
			(hide yes)
			(effects
				(font
					(size 1.27 1.27)
				)
			)
		)
		(property "Value" "*"
			(at 0.064008 -4.108196 90)
			(unlocked yes)
			(layer "F.Fab")
			(hide yes)
			(effects
				(font
					(size 1.27 1.016)
					(thickness 0.1524)
				)
			)
		)
		(property "Device Type" "120R2F-GP_RCL_GP-120R2F-GP,64.A"
			(at 0.064008 -5.632196 90)
			(unlocked yes)
			(layer "F.Fab")
			(hide yes)
			(effects
				(font
					(size 1.27 1.016)
					(thickness 0.1524)
				)
			)
		)
		(duplicate_pad_numbers_are_jumpers no)
		(fp_line
			(start 0.508 -0.9398)
			(end -0.508 -0.9398)
			(stroke
				(width 0.1524)
				(type default)
			)
			(layer "F.SilkS")
		)
		(fp_line
			(start -0.508 -0.9398)
			(end -0.508 0.9398)
			(stroke
				(width 0.1524)
				(type default)
			)
			(layer "F.SilkS")
		)
		(fp_rect
			(start -0.508 0.9398)
			(end 0.508 -0.9398)
			(stroke
				(width 0)
				(type default)
			)
			(fill no)
			(layer "F.CrtYd")
		)
		(fp_rect
			(start -0.508 0.9398)
			(end 0.508 -0.9398)
			(stroke
				(width 0)
				(type default)
			)
			(fill no)
			(layer "F.Fab")
		)
		(pad "1" smd custom
			(at 0 -0.4445 90)
			(size 0.1397 0.1397)
			(layers "F.Cu" "F.Mask" "F.Paste")
			(net "BMC_M_BA0")
			(options
				(clearance outline)
				(anchor circle)
			)
			(primitives
				(gr_poly
					(pts
						(arc
							(start -0.1778 -0.2794)
							(mid -0.249642 -0.249642)
							(end -0.2794 -0.1778)
						)
						(arc
							(start -0.2794 0.1778)
							(mid -0.249642 0.249642)
							(end -0.1778 0.2794)
						)
						(arc
							(start 0.1778 0.2794)
							(mid 0.249642 0.249642)
							(end 0.2794 0.1778)
						)
						(arc
							(start 0.2794 -0.1778)
							(mid 0.249642 -0.249642)
							(end 0.1778 -0.2794)
						)
					)
					(width 0)
					(fill yes)
				)
			)
		)
		(pad "2" smd custom
			(at 0 0.4445 90)
			(size 0.1397 0.1397)
			(layers "F.Cu" "F.Mask" "F.Paste")
			(net "P1V2_AUX_BMC")
			(options
				(clearance outline)
				(anchor circle)
			)
			(primitives
				(gr_poly
					(pts
						(arc
							(start -0.1778 -0.2794)
							(mid -0.249642 -0.249642)
							(end -0.2794 -0.1778)
						)
						(arc
							(start -0.2794 0.1778)
							(mid -0.249642 0.249642)
							(end -0.1778 0.2794)
						)
						(arc
							(start 0.1778 0.2794)
							(mid 0.249642 0.249642)
							(end 0.2794 0.1778)
						)
						(arc
							(start 0.2794 -0.1778)
							(mid 0.249642 -0.249642)
							(end 0.1778 -0.2794)
						)
					)
					(width 0)
					(fill yes)
				)
			)
		)
	)
	(footprint ""
		(layer "F.Cu")
		(at 431.734468 -50.482246 90)
		(property "Reference" "C9F23"
			(at 0 0 90)
			(layer "F.SilkS")
			(hide yes)
			(effects
				(font
					(size 1.27 1.27)
				)
			)
		)
		(property "Value" ""
			(at 0 0 90)
			(layer "F.Fab")
			(effects
				(font
					(size 1.27 1.27)
				)
			)
		)
		(duplicate_pad_numbers_are_jumpers no)
		(fp_poly
			(pts
				(xy 0.3048 -0.1016) (xy 0.3048 0.9906) (xy -0.3048 0.9906) (xy -0.3048 -0.1016)
			)
			(stroke
				(width 0)
				(type default)
			)
			(fill no)
			(layer "F.CrtYd")
		)
		(fp_line
			(start 0.3048 -0.1016)
			(end -0.3048 -0.1016)
			(stroke
				(width 0.1)
				(type default)
			)
			(layer "F.Fab")
		)
		(fp_line
			(start -0.3048 -0.1016)
			(end -0.3048 0.9906)
			(stroke
				(width 0.1)
				(type default)
			)
			(layer "F.Fab")
		)
		(fp_line
			(start 0.3048 0.9906)
			(end 0.3048 -0.1016)
			(stroke
				(width 0.1)
				(type default)
			)
			(layer "F.Fab")
		)
		(fp_line
			(start -0.3048 0.9906)
			(end 0.3048 0.9906)
			(stroke
				(width 0.1)
				(type default)
			)
			(layer "F.Fab")
		)
		(pad "1" smd rect
			(at 0 0 90)
			(size 0.508 0.508)
			(layers "F.Cu" "F.Mask" "F.Paste")
			(net "P3V3_STBY")
		)
		(pad "2" smd rect
			(at 0 0.889 90)
			(size 0.508 0.508)
			(layers "F.Cu" "F.Mask" "F.Paste")
			(net "GND")
		)
		(zone
			(layer "F.Cu")
			(hatch none 0.5)
			(connect_pads
				(clearance 0)
			)
			(min_thickness 0.25)
			(keepout
				(tracks allowed)
				(vias not_allowed)
				(pads allowed)
				(copperpour not_allowed)
				(footprints allowed)
			)
			(placement
				(enabled no)
				(sheetname "")
			)
			(fill
				(thermal_gap 0.5)
				(thermal_bridge_width 0.5)
				(island_removal_mode 0)
			)
			(polygon
				(pts
					(xy 431.988468 -50.228246) (xy 431.988468 -50.736246) (xy 432.369468 -50.736246) (xy 432.369468 -50.228246)
				)
			)
		)
		(zone
			(layer "F.Cu")
			(hatch none 0.5)
			(connect_pads
				(clearance 0)
			)
			(min_thickness 0.25)
			(keepout
				(tracks not_allowed)
				(vias allowed)
				(pads allowed)
				(copperpour not_allowed)
				(footprints allowed)
			)
			(placement
				(enabled no)
				(sheetname "")
			)
			(fill
				(thermal_gap 0.5)
				(thermal_bridge_width 0.5)
				(island_removal_mode 0)
			)
			(polygon
				(pts
					(xy 432.369468 -50.228246) (xy 432.369468 -50.736246) (xy 431.988468 -50.736246) (xy 431.988468 -50.228246)
				)
			)
		)
	)
	(footprint ""
		(layer "F.Cu")
		(at 409.6512 -114.3 90)
		(property "Reference" "R8B29"
			(at 0 0 90)
			(layer "F.SilkS")
			(hide yes)
			(effects
				(font
					(size 1.27 1.27)
				)
			)
		)
		(property "Value" ""
			(at 0 0 90)
			(layer "F.Fab")
			(effects
				(font
					(size 1.27 1.27)
				)
			)
		)
		(duplicate_pad_numbers_are_jumpers no)
		(fp_poly
			(pts
				(xy -0.2794 -0.1016) (xy 0.2794 -0.1016) (xy 0.2794 0.9906) (xy -0.2794 0.9906)
			)
			(stroke
				(width 0)
				(type default)
			)
			(fill no)
			(layer "F.CrtYd")
		)
		(fp_line
			(start 0.2794 -0.1016)
			(end -0.2794 -0.1016)
			(stroke
				(width 0.1)
				(type default)
			)
			(layer "F.Fab")
		)
		(fp_line
			(start -0.2794 -0.1016)
			(end -0.2794 0.9906)
			(stroke
				(width 0.1)
				(type default)
			)
			(layer "F.Fab")
		)
		(fp_line
			(start 0.2794 0.9906)
			(end 0.2794 -0.1016)
			(stroke
				(width 0.1)
				(type default)
			)
			(layer "F.Fab")
		)
		(fp_line
			(start -0.2794 0.9906)
			(end 0.2794 0.9906)
			(stroke
				(width 0.1)
				(type default)
			)
			(layer "F.Fab")
		)
		(pad "1" smd rect
			(at 0 0 90)
			(size 0.508 0.508)
			(layers "F.Cu" "F.Mask" "F.Paste")
			(net "SGPIO_PCH_SSATA_DOUT0")
		)
		(pad "2" smd rect
			(at 0 0.889 90)
			(size 0.508 0.508)
			(layers "F.Cu" "F.Mask" "F.Paste")
			(net "SGPIO_PCH_SSATA_DOUT0_R")
		)
		(zone
			(layer "F.Cu")
			(hatch none 0.5)
			(connect_pads
				(clearance 0)
			)
			(min_thickness 0.25)
			(keepout
				(tracks allowed)
				(vias not_allowed)
				(pads allowed)
				(copperpour not_allowed)
				(footprints allowed)
			)
			(placement
				(enabled no)
				(sheetname "")
			)
			(fill
				(thermal_gap 0.5)
				(thermal_bridge_width 0.5)
				(island_removal_mode 0)
			)
			(polygon
				(pts
					(xy 409.9052 -114.046) (xy 409.9052 -114.554) (xy 410.2862 -114.554) (xy 410.2862 -114.046)
				)
			)
		)
		(zone
			(layer "F.Cu")
			(hatch none 0.5)
			(connect_pads
				(clearance 0)
			)
			(min_thickness 0.25)
			(keepout
				(tracks not_allowed)
				(vias allowed)
				(pads allowed)
				(copperpour not_allowed)
				(footprints allowed)
			)
			(placement
				(enabled no)
				(sheetname "")
			)
			(fill
				(thermal_gap 0.5)
				(thermal_bridge_width 0.5)
				(island_removal_mode 0)
			)
			(polygon
				(pts
					(xy 410.2862 -114.046) (xy 410.2862 -114.554) (xy 409.9052 -114.554) (xy 409.9052 -114.046)
				)
			)
		)
	)
	(footprint ""
		(layer "F.Cu")
		(at 88.392 -149.8092 90)
		(property "Reference" "C2A4"
			(at 1.848866 0.752348 90)
			(unlocked yes)
			(layer "F.SilkS")
			(effects
				(font
					(size 1.27 0.9652)
					(thickness 0.1524)
				)
			)
		)
		(property "Value" ""
			(at 0 0 90)
			(layer "F.Fab")
			(effects
				(font
					(size 1.27 1.27)
				)
			)
		)
		(duplicate_pad_numbers_are_jumpers no)
		(fp_rect
			(start -0.500126 1.598422)
			(end 0.500126 -0.201422)
			(stroke
				(width 0)
				(type default)
			)
			(fill no)
			(layer "F.CrtYd")
		)
		(fp_line
			(start 0.500126 -0.201422)
			(end 0.500126 1.598422)
			(stroke
				(width 0.1)
				(type default)
			)
			(layer "F.Fab")
		)
		(fp_line
			(start -0.500126 -0.201422)
			(end 0.500126 -0.201422)
			(stroke
				(width 0.1)
				(type default)
			)
			(layer "F.Fab")
		)
		(fp_line
			(start 0.500126 1.598422)
			(end -0.500126 1.598422)
			(stroke
				(width 0.1)
				(type default)
			)
			(layer "F.Fab")
		)
		(fp_line
			(start -0.500126 1.598422)
			(end -0.500126 -0.201422)
			(stroke
				(width 0.1)
				(type default)
			)
			(layer "F.Fab")
		)
		(pad "1" smd rect
			(at 0 0)
			(size 0.889 0.9906)
			(layers "F.Cu" "F.Mask" "F.Paste")
			(net "PVDDQ_KLM")
		)
		(pad "2" smd rect
			(at 0 1.397)
			(size 0.889 0.9906)
			(layers "F.Cu" "F.Mask" "F.Paste")
			(net "GND")
		)
		(zone
			(layer "F.Cu")
			(hatch none 0.5)
			(connect_pads
				(clearance 0)
			)
			(min_thickness 0.25)
			(keepout
				(tracks allowed)
				(vias not_allowed)
				(pads allowed)
				(copperpour not_allowed)
				(footprints allowed)
			)
			(placement
				(enabled no)
				(sheetname "")
			)
			(fill
				(thermal_gap 0.5)
				(thermal_bridge_width 0.5)
				(island_removal_mode 0)
			)
			(polygon
				(pts
					(xy 89.3445 -149.3139) (xy 89.3445 -150.3045) (xy 88.8365 -150.3045) (xy 88.8365 -149.3139)
				)
			)
		)
		(zone
			(layer "F.Cu")
			(hatch none 0.5)
			(connect_pads
				(clearance 0)
			)
			(min_thickness 0.25)
			(keepout
				(tracks not_allowed)
				(vias allowed)
				(pads allowed)
				(copperpour not_allowed)
				(footprints allowed)
			)
			(placement
				(enabled no)
				(sheetname "")
			)
			(fill
				(thermal_gap 0.5)
				(thermal_bridge_width 0.5)
				(island_removal_mode 0)
			)
			(polygon
				(pts
					(xy 89.3445 -149.3139) (xy 89.3445 -150.3045) (xy 88.8365 -150.3045) (xy 88.8365 -149.3139)
				)
			)
		)
	)
	(footprint ""
		(layer "F.Cu")
		(at 0.635 -20.0406 -90)
		(property "Reference" "C1F27"
			(at 0 0 270)
			(layer "F.SilkS")
			(hide yes)
			(effects
				(font
					(size 1.27 1.27)
				)
			)
		)
		(property "Value" ""
			(at 0 0 270)
			(layer "F.Fab")
			(effects
				(font
					(size 1.27 1.27)
				)
			)
		)
		(duplicate_pad_numbers_are_jumpers no)
		(fp_poly
			(pts
				(xy 0.3048 -0.1016) (xy 0.3048 0.9906) (xy -0.3048 0.9906) (xy -0.3048 -0.1016)
			)
			(stroke
				(width 0)
				(type default)
			)
			(fill no)
			(layer "F.CrtYd")
		)
		(fp_line
			(start -0.3048 0.9906)
			(end 0.3048 0.9906)
			(stroke
				(width 0.1)
				(type default)
			)
			(layer "F.Fab")
		)
		(fp_line
			(start 0.3048 0.9906)
			(end 0.3048 -0.1016)
			(stroke
				(width 0.1)
				(type default)
			)
			(layer "F.Fab")
		)
		(fp_line
			(start -0.3048 -0.1016)
			(end -0.3048 0.9906)
			(stroke
				(width 0.1)
				(type default)
			)
			(layer "F.Fab")
		)
		(fp_line
			(start 0.3048 -0.1016)
			(end -0.3048 -0.1016)
			(stroke
				(width 0.1)
				(type default)
			)
			(layer "F.Fab")
		)
		(pad "1" smd rect
			(at 0 0 270)
			(size 0.508 0.508)
			(layers "F.Cu" "F.Mask" "F.Paste")
			(net "VR_FET_SW_P12V_STBY_PVDDQ_GHJ")
		)
		(pad "2" smd rect
			(at 0 0.889 270)
			(size 0.508 0.508)
			(layers "F.Cu" "F.Mask" "F.Paste")
			(net "GND")
		)
		(zone
			(layer "F.Cu")
			(hatch none 0.5)
			(connect_pads
				(clearance 0)
			)
			(min_thickness 0.25)
			(keepout
				(tracks not_allowed)
				(vias allowed)
				(pads allowed)
				(copperpour not_allowed)
				(footprints allowed)
			)
			(placement
				(enabled no)
				(sheetname "")
			)
			(fill
				(thermal_gap 0.5)
				(thermal_bridge_width 0.5)
				(island_removal_mode 0)
			)
			(polygon
				(pts
					(xy 0 -20.2946) (xy 0 -19.7866) (xy 0.381 -19.7866) (xy 0.381 -20.2946)
				)
			)
		)
		(zone
			(layer "F.Cu")
			(hatch none 0.5)
			(connect_pads
				(clearance 0)
			)
			(min_thickness 0.25)
			(keepout
				(tracks allowed)
				(vias not_allowed)
				(pads allowed)
				(copperpour not_allowed)
				(footprints allowed)
			)
			(placement
				(enabled no)
				(sheetname "")
			)
			(fill
				(thermal_gap 0.5)
				(thermal_bridge_width 0.5)
				(island_removal_mode 0)
			)
			(polygon
				(pts
					(xy 0.381 -20.2946) (xy 0.381 -19.7866) (xy 0 -19.7866) (xy 0 -20.2946)
				)
			)
		)
	)
	(footprint ""
		(layer "F.Cu")
		(at 488.6706 -123.75134)
		(property "Reference" "U9B4"
			(at 1.30302 5.01777 0)
			(unlocked yes)
			(layer "F.SilkS")
			(effects
				(font
					(size 0.7874 0.5842)
					(thickness 0.1524)
				)
			)
		)
		(property "Value" ""
			(at 0 0 0)
			(layer "F.Fab")
			(effects
				(font
					(size 1.27 1.27)
				)
			)
		)
		(duplicate_pad_numbers_are_jumpers no)
		(fp_line
			(start 1.566672 -0.52324)
			(end 0.985774 -0.52324)
			(stroke
				(width 0.1524)
				(type default)
			)
			(layer "F.SilkS")
		)
		(fp_line
			(start 1.583436 2.47396)
			(end 0.965454 2.47396)
			(stroke
				(width 0.1524)
				(type default)
			)
			(layer "F.SilkS")
		)
		(fp_circle
			(center -0.635 -0.889)
			(end -0.508 -0.889)
			(stroke
				(width 0.254)
				(type default)
			)
			(fill no)
			(layer "F.SilkS")
		)
		(fp_rect
			(start 0.3937 2.47396)
			(end 2.1463 -0.52324)
			(stroke
				(width 0)
				(type default)
			)
			(fill no)
			(layer "F.CrtYd")
		)
		(fp_line
			(start 0.3937 -0.52324)
			(end 2.1463 -0.52324)
			(stroke
				(width 0.1)
				(type default)
			)
			(layer "F.Fab")
		)
		(fp_line
			(start 0.3937 2.47396)
			(end 0.3937 -0.52324)
			(stroke
				(width 0.1)
				(type default)
			)
			(layer "F.Fab")
		)
		(fp_line
			(start 2.1463 -0.52324)
			(end 2.1463 2.47396)
			(stroke
				(width 0.1)
				(type default)
			)
			(layer "F.Fab")
		)
		(fp_line
			(start 2.1463 2.47396)
			(end 0.3937 2.47396)
			(stroke
				(width 0.1)
				(type default)
			)
			(layer "F.Fab")
		)
		(fp_circle
			(center -0.635 -0.889)
			(end -0.508 -0.889)
			(stroke
				(width 0.254)
				(type default)
			)
			(fill no)
			(layer "F.Fab")
		)
		(pad "1" smd rect
			(at 0 0)
			(size 1.27 0.381)
			(layers "F.Cu" "F.Mask" "F.Paste")
			(net "ISENSE_TMP421_1_DXP")
		)
		(pad "2" smd rect
			(at 0 0.65024)
			(size 1.27 0.381)
			(layers "F.Cu" "F.Mask" "F.Paste")
			(net "ISENSE_TMP421_1_DXN")
		)
		(pad "3" smd rect
			(at 0 1.30048)
			(size 1.27 0.381)
			(layers "F.Cu" "F.Mask" "F.Paste")
			(net "PU_TMP421_1_A1")
		)
		(pad "4" smd rect
			(at 0 1.95072)
			(size 1.27 0.381)
			(layers "F.Cu" "F.Mask" "F.Paste")
			(net "PD_TMP421_1_A0")
		)
		(pad "5" smd rect
			(at 2.54 1.95072)
			(size 1.27 0.381)
			(layers "F.Cu" "F.Mask" "F.Paste")
			(net "GND")
		)
		(pad "6" smd rect
			(at 2.54 1.30048)
			(size 1.27 0.381)
			(layers "F.Cu" "F.Mask" "F.Paste")
			(net "SMB_SENSOR_TMP421_1_SDA")
		)
		(pad "7" smd rect
			(at 2.54 0.65024)
			(size 1.27 0.381)
			(layers "F.Cu" "F.Mask" "F.Paste")
			(net "SMB_SENSOR_TMP421_1_SCL")
		)
		(pad "8" smd rect
			(at 2.54 0)
			(size 1.27 0.381)
			(layers "F.Cu" "F.Mask" "F.Paste")
			(net "P3V3_STBY")
		)
	)
	(footprint ""
		(layer "F.Cu")
		(at 406.146 -46.8249 180)
		(property "Reference" "R2T64"
			(at 0 0 180)
			(layer "F.SilkS")
			(hide yes)
			(effects
				(font
					(size 1.27 1.27)
				)
			)
		)
		(property "Value" ""
			(at 0 0 180)
			(layer "F.Fab")
			(effects
				(font
					(size 1.27 1.27)
				)
			)
		)
		(duplicate_pad_numbers_are_jumpers no)
		(fp_poly
			(pts
				(xy -0.2794 -0.1016) (xy 0.2794 -0.1016) (xy 0.2794 0.9906) (xy -0.2794 0.9906)
			)
			(stroke
				(width 0)
				(type default)
			)
			(fill no)
			(layer "F.CrtYd")
		)
		(fp_line
			(start 0.2794 0.9906)
			(end 0.2794 -0.1016)
			(stroke
				(width 0.1)
				(type default)
			)
			(layer "F.Fab")
		)
		(fp_line
			(start 0.2794 -0.1016)
			(end -0.2794 -0.1016)
			(stroke
				(width 0.1)
				(type default)
			)
			(layer "F.Fab")
		)
		(fp_line
			(start -0.2794 0.9906)
			(end 0.2794 0.9906)
			(stroke
				(width 0.1)
				(type default)
			)
			(layer "F.Fab")
		)
		(fp_line
			(start -0.2794 -0.1016)
			(end -0.2794 0.9906)
			(stroke
				(width 0.1)
				(type default)
			)
			(layer "F.Fab")
		)
		(pad "1" smd rect
			(at 0 0 180)
			(size 0.508 0.508)
			(layers "F.Cu" "F.Mask" "F.Paste")
			(net "FM_CPU_ERR1_LVT3_N")
		)
		(pad "2" smd rect
			(at 0 0.889 180)
			(size 0.508 0.508)
			(layers "F.Cu" "F.Mask" "F.Paste")
			(net "FM_CPU_ERR1_LVT3_BMC_N")
		)
		(zone
			(layer "F.Cu")
			(hatch none 0.5)
			(connect_pads
				(clearance 0)
			)
			(min_thickness 0.25)
			(keepout
				(tracks not_allowed)
				(vias allowed)
				(pads allowed)
				(copperpour not_allowed)
				(footprints allowed)
			)
			(placement
				(enabled no)
				(sheetname "")
			)
			(fill
				(thermal_gap 0.5)
				(thermal_bridge_width 0.5)
				(island_removal_mode 0)
			)
			(polygon
				(pts
					(xy 406.4 -47.4599) (xy 405.892 -47.4599) (xy 405.892 -47.0789) (xy 406.4 -47.0789)
				)
			)
		)
		(zone
			(layer "F.Cu")
			(hatch none 0.5)
			(connect_pads
				(clearance 0)
			)
			(min_thickness 0.25)
			(keepout
				(tracks allowed)
				(vias not_allowed)
				(pads allowed)
				(copperpour not_allowed)
				(footprints allowed)
			)
			(placement
				(enabled no)
				(sheetname "")
			)
			(fill
				(thermal_gap 0.5)
				(thermal_bridge_width 0.5)
				(island_removal_mode 0)
			)
			(polygon
				(pts
					(xy 406.4 -47.0789) (xy 405.892 -47.0789) (xy 405.892 -47.4599) (xy 406.4 -47.4599)
				)
			)
		)
	)
	(footprint ""
		(layer "F.Cu")
		(at 152.146 -25.908 -90)
		(property "Reference" "C3F2"
			(at 0 0 270)
			(layer "F.SilkS")
			(hide yes)
			(effects
				(font
					(size 1.27 1.27)
				)
			)
		)
		(property "Value" ""
			(at 0 0 270)
			(layer "F.Fab")
			(effects
				(font
					(size 1.27 1.27)
				)
			)
		)
		(duplicate_pad_numbers_are_jumpers no)
		(fp_poly
			(pts
				(xy 0.3048 -0.1016) (xy 0.3048 0.9906) (xy -0.3048 0.9906) (xy -0.3048 -0.1016)
			)
			(stroke
				(width 0)
				(type default)
			)
			(fill no)
			(layer "F.CrtYd")
		)
		(fp_line
			(start -0.3048 0.9906)
			(end 0.3048 0.9906)
			(stroke
				(width 0.1)
				(type default)
			)
			(layer "F.Fab")
		)
		(fp_line
			(start 0.3048 0.9906)
			(end 0.3048 -0.1016)
			(stroke
				(width 0.1)
				(type default)
			)
			(layer "F.Fab")
		)
		(fp_line
			(start -0.3048 -0.1016)
			(end -0.3048 0.9906)
			(stroke
				(width 0.1)
				(type default)
			)
			(layer "F.Fab")
		)
		(fp_line
			(start 0.3048 -0.1016)
			(end -0.3048 -0.1016)
			(stroke
				(width 0.1)
				(type default)
			)
			(layer "F.Fab")
		)
		(pad "1" smd rect
			(at 0 0 270)
			(size 0.508 0.508)
			(layers "F.Cu" "F.Mask" "F.Paste")
			(net "P3V3")
		)
		(pad "2" smd rect
			(at 0 0.889 270)
			(size 0.508 0.508)
			(layers "F.Cu" "F.Mask" "F.Paste")
			(net "GND")
		)
		(zone
			(layer "F.Cu")
			(hatch none 0.5)
			(connect_pads
				(clearance 0)
			)
			(min_thickness 0.25)
			(keepout
				(tracks not_allowed)
				(vias allowed)
				(pads allowed)
				(copperpour not_allowed)
				(footprints allowed)
			)
			(placement
				(enabled no)
				(sheetname "")
			)
			(fill
				(thermal_gap 0.5)
				(thermal_bridge_width 0.5)
				(island_removal_mode 0)
			)
			(polygon
				(pts
					(xy 151.511 -26.162) (xy 151.511 -25.654) (xy 151.892 -25.654) (xy 151.892 -26.162)
				)
			)
		)
		(zone
			(layer "F.Cu")
			(hatch none 0.5)
			(connect_pads
				(clearance 0)
			)
			(min_thickness 0.25)
			(keepout
				(tracks allowed)
				(vias not_allowed)
				(pads allowed)
				(copperpour not_allowed)
				(footprints allowed)
			)
			(placement
				(enabled no)
				(sheetname "")
			)
			(fill
				(thermal_gap 0.5)
				(thermal_bridge_width 0.5)
				(island_removal_mode 0)
			)
			(polygon
				(pts
					(xy 151.892 -26.162) (xy 151.892 -25.654) (xy 151.511 -25.654) (xy 151.511 -26.162)
				)
			)
		)
	)
	(footprint ""
		(layer "F.Cu")
		(at 458.177392 -40.877998 -90)
		(property "Reference" "C9F4"
			(at 0 0 270)
			(layer "F.SilkS")
			(hide yes)
			(effects
				(font
					(size 1.27 1.27)
				)
			)
		)
		(property "Value" ""
			(at 0 0 270)
			(layer "F.Fab")
			(effects
				(font
					(size 1.27 1.27)
				)
			)
		)
		(duplicate_pad_numbers_are_jumpers no)
		(fp_poly
			(pts
				(xy -0.7239 -0.2159) (xy 0.7239 -0.2159) (xy 0.7239 1.9939) (xy -0.7239 1.9939)
			)
			(stroke
				(width 0)
				(type default)
			)
			(fill no)
			(layer "F.CrtYd")
		)
		(fp_line
			(start -0.7239 1.9939)
			(end 0.7239 1.9939)
			(stroke
				(width 0.1)
				(type default)
			)
			(layer "F.Fab")
		)
		(fp_line
			(start 0.7239 1.9939)
			(end 0.7239 -0.2159)
			(stroke
				(width 0.1)
				(type default)
			)
			(layer "F.Fab")
		)
		(fp_line
			(start -0.7239 -0.2159)
			(end -0.7239 1.9939)
			(stroke
				(width 0.1)
				(type default)
			)
			(layer "F.Fab")
		)
		(fp_line
			(start 0.7239 -0.2159)
			(end -0.7239 -0.2159)
			(stroke
				(width 0.1)
				(type default)
			)
			(layer "F.Fab")
		)
		(pad "1" smd rect
			(at 0 0 270)
			(size 1.27 1.016)
			(layers "F.Cu" "F.Mask" "F.Paste")
			(net "P1V15_AUX_BMC")
		)
		(pad "2" smd rect
			(at 0 1.778 270)
			(size 1.27 1.016)
			(layers "F.Cu" "F.Mask" "F.Paste")
			(net "GND")
		)
		(zone
			(layer "F.Cu")
			(hatch none 0.5)
			(connect_pads
				(clearance 0)
			)
			(min_thickness 0.25)
			(keepout
				(tracks not_allowed)
				(vias allowed)
				(pads allowed)
				(copperpour not_allowed)
				(footprints allowed)
			)
			(placement
				(enabled no)
				(sheetname "")
			)
			(fill
				(thermal_gap 0.5)
				(thermal_bridge_width 0.5)
				(island_removal_mode 0)
			)
			(polygon
				(pts
					(xy 457.669392 -41.512998) (xy 457.669392 -40.242998) (xy 456.907392 -40.242998) (xy 456.907392 -41.512998)
				)
			)
		)
	)
	(footprint ""
		(layer "F.Cu")
		(at 179.959 -130.8735 180)
		(property "Reference" "R4B10"
			(at 0 0 180)
			(layer "F.SilkS")
			(hide yes)
			(effects
				(font
					(size 1.27 1.27)
				)
			)
		)
		(property "Value" ""
			(at 0 0 180)
			(layer "F.Fab")
			(effects
				(font
					(size 1.27 1.27)
				)
			)
		)
		(duplicate_pad_numbers_are_jumpers no)
		(fp_poly
			(pts
				(xy -0.2794 -0.1016) (xy 0.2794 -0.1016) (xy 0.2794 0.9906) (xy -0.2794 0.9906)
			)
			(stroke
				(width 0)
				(type default)
			)
			(fill no)
			(layer "F.CrtYd")
		)
		(fp_line
			(start 0.2794 0.9906)
			(end 0.2794 -0.1016)
			(stroke
				(width 0.1)
				(type default)
			)
			(layer "F.Fab")
		)
		(fp_line
			(start 0.2794 -0.1016)
			(end -0.2794 -0.1016)
			(stroke
				(width 0.1)
				(type default)
			)
			(layer "F.Fab")
		)
		(fp_line
			(start -0.2794 0.9906)
			(end 0.2794 0.9906)
			(stroke
				(width 0.1)
				(type default)
			)
			(layer "F.Fab")
		)
		(fp_line
			(start -0.2794 -0.1016)
			(end -0.2794 0.9906)
			(stroke
				(width 0.1)
				(type default)
			)
			(layer "F.Fab")
		)
		(pad "1" smd rect
			(at 0 0 180)
			(size 0.508 0.508)
			(layers "F.Cu" "F.Mask" "F.Paste")
			(net "P3V3_STBY")
		)
		(pad "2" smd rect
			(at 0 0.889 180)
			(size 0.508 0.508)
			(layers "F.Cu" "F.Mask" "F.Paste")
			(net "PWRGD_PVPP_KLM_R")
		)
		(zone
			(layer "F.Cu")
			(hatch none 0.5)
			(connect_pads
				(clearance 0)
			)
			(min_thickness 0.25)
			(keepout
				(tracks not_allowed)
				(vias allowed)
				(pads allowed)
				(copperpour not_allowed)
				(footprints allowed)
			)
			(placement
				(enabled no)
				(sheetname "")
			)
			(fill
				(thermal_gap 0.5)
				(thermal_bridge_width 0.5)
				(island_removal_mode 0)
			)
			(polygon
				(pts
					(xy 180.213 -131.5085) (xy 179.705 -131.5085) (xy 179.705 -131.1275) (xy 180.213 -131.1275)
				)
			)
		)
		(zone
			(layer "F.Cu")
			(hatch none 0.5)
			(connect_pads
				(clearance 0)
			)
			(min_thickness 0.25)
			(keepout
				(tracks allowed)
				(vias not_allowed)
				(pads allowed)
				(copperpour not_allowed)
				(footprints allowed)
			)
			(placement
				(enabled no)
				(sheetname "")
			)
			(fill
				(thermal_gap 0.5)
				(thermal_bridge_width 0.5)
				(island_removal_mode 0)
			)
			(polygon
				(pts
					(xy 180.213 -131.1275) (xy 179.705 -131.1275) (xy 179.705 -131.5085) (xy 180.213 -131.5085)
				)
			)
		)
	)
	(footprint ""
		(layer "F.Cu")
		(at 277.0632 -79.6036 180)
		(property "Reference" "C6D2"
			(at 0 0 180)
			(layer "F.SilkS")
			(hide yes)
			(effects
				(font
					(size 1.27 1.27)
				)
			)
		)
		(property "Value" ""
			(at 0 0 180)
			(layer "F.Fab")
			(effects
				(font
					(size 1.27 1.27)
				)
			)
		)
		(duplicate_pad_numbers_are_jumpers no)
		(fp_poly
			(pts
				(xy -0.4953 -0.2032) (xy 0.4953 -0.2032) (xy 0.4953 1.6002) (xy -0.4953 1.6002)
			)
			(stroke
				(width 0)
				(type default)
			)
			(fill no)
			(layer "F.CrtYd")
		)
		(fp_line
			(start 0.4953 1.6002)
			(end -0.4953 1.6002)
			(stroke
				(width 0.1)
				(type default)
			)
			(layer "F.Fab")
		)
		(fp_line
			(start 0.4953 -0.2032)
			(end 0.4953 1.6002)
			(stroke
				(width 0.1)
				(type default)
			)
			(layer "F.Fab")
		)
		(fp_line
			(start -0.4953 1.6002)
			(end -0.4953 -0.2032)
			(stroke
				(width 0.1)
				(type default)
			)
			(layer "F.Fab")
		)
		(fp_line
			(start -0.4953 -0.2032)
			(end 0.4953 -0.2032)
			(stroke
				(width 0.1)
				(type default)
			)
			(layer "F.Fab")
		)
		(pad "1" smd rect
			(at 0 0 180)
			(size 0.762 0.889)
			(layers "F.Cu" "F.Mask" "F.Paste")
			(net "PVCCMCP_CPU0")
		)
		(pad "2" smd rect
			(at 0 1.397 180)
			(size 0.762 0.889)
			(layers "F.Cu" "F.Mask" "F.Paste")
			(net "GND")
		)
		(zone
			(layer "F.Cu")
			(hatch none 0.5)
			(connect_pads
				(clearance 0)
			)
			(min_thickness 0.25)
			(keepout
				(tracks not_allowed)
				(vias allowed)
				(pads allowed)
				(copperpour not_allowed)
				(footprints allowed)
			)
			(placement
				(enabled no)
				(sheetname "")
			)
			(fill
				(thermal_gap 0.5)
				(thermal_bridge_width 0.5)
				(island_removal_mode 0)
			)
			(polygon
				(pts
					(xy 277.4442 -80.0481) (xy 276.6822 -80.0481) (xy 276.6822 -80.5561) (xy 277.4442 -80.5561)
				)
			)
		)
	)
	(footprint ""
		(layer "F.Cu")
		(at 281.01036 -81.96072 90)
		(property "Reference" "R6D16"
			(at 0 0 90)
			(layer "F.SilkS")
			(hide yes)
			(effects
				(font
					(size 1.27 1.27)
				)
			)
		)
		(property "Value" ""
			(at 0 0 90)
			(layer "F.Fab")
			(effects
				(font
					(size 1.27 1.27)
				)
			)
		)
		(duplicate_pad_numbers_are_jumpers no)
		(fp_poly
			(pts
				(xy -0.2794 -0.1016) (xy 0.2794 -0.1016) (xy 0.2794 0.9906) (xy -0.2794 0.9906)
			)
			(stroke
				(width 0)
				(type default)
			)
			(fill no)
			(layer "F.CrtYd")
		)
		(fp_line
			(start 0.2794 -0.1016)
			(end -0.2794 -0.1016)
			(stroke
				(width 0.1)
				(type default)
			)
			(layer "F.Fab")
		)
		(fp_line
			(start -0.2794 -0.1016)
			(end -0.2794 0.9906)
			(stroke
				(width 0.1)
				(type default)
			)
			(layer "F.Fab")
		)
		(fp_line
			(start 0.2794 0.9906)
			(end 0.2794 -0.1016)
			(stroke
				(width 0.1)
				(type default)
			)
			(layer "F.Fab")
		)
		(fp_line
			(start -0.2794 0.9906)
			(end 0.2794 0.9906)
			(stroke
				(width 0.1)
				(type default)
			)
			(layer "F.Fab")
		)
		(pad "1" smd rect
			(at 0 0 90)
			(size 0.508 0.508)
			(layers "F.Cu" "F.Mask" "F.Paste")
			(net "FM_CPU_BMC_INIT")
		)
		(pad "2" smd rect
			(at 0 0.889 90)
			(size 0.508 0.508)
			(layers "F.Cu" "F.Mask" "F.Paste")
			(net "H_CPU0_BMCINIT")
		)
		(zone
			(layer "F.Cu")
			(hatch none 0.5)
			(connect_pads
				(clearance 0)
			)
			(min_thickness 0.25)
			(keepout
				(tracks allowed)
				(vias not_allowed)
				(pads allowed)
				(copperpour not_allowed)
				(footprints allowed)
			)
			(placement
				(enabled no)
				(sheetname "")
			)
			(fill
				(thermal_gap 0.5)
				(thermal_bridge_width 0.5)
				(island_removal_mode 0)
			)
			(polygon
				(pts
					(xy 281.26436 -81.70672) (xy 281.26436 -82.21472) (xy 281.64536 -82.21472) (xy 281.64536 -81.70672)
				)
			)
		)
		(zone
			(layer "F.Cu")
			(hatch none 0.5)
			(connect_pads
				(clearance 0)
			)
			(min_thickness 0.25)
			(keepout
				(tracks not_allowed)
				(vias allowed)
				(pads allowed)
				(copperpour not_allowed)
				(footprints allowed)
			)
			(placement
				(enabled no)
				(sheetname "")
			)
			(fill
				(thermal_gap 0.5)
				(thermal_bridge_width 0.5)
				(island_removal_mode 0)
			)
			(polygon
				(pts
					(xy 281.64536 -81.70672) (xy 281.64536 -82.21472) (xy 281.26436 -82.21472) (xy 281.26436 -81.70672)
				)
			)
		)
	)
	(footprint ""
		(layer "F.Cu")
		(at 354.805234 -129.3622)
		(property "Reference" "R7B17"
			(at 0 0 0)
			(layer "F.SilkS")
			(hide yes)
			(effects
				(font
					(size 1.27 1.27)
				)
			)
		)
		(property "Value" ""
			(at 0 0 0)
			(layer "F.Fab")
			(effects
				(font
					(size 1.27 1.27)
				)
			)
		)
		(duplicate_pad_numbers_are_jumpers no)
		(fp_poly
			(pts
				(xy -0.2794 -0.1016) (xy 0.2794 -0.1016) (xy 0.2794 0.9906) (xy -0.2794 0.9906)
			)
			(stroke
				(width 0)
				(type default)
			)
			(fill no)
			(layer "F.CrtYd")
		)
		(fp_line
			(start -0.2794 -0.1016)
			(end -0.2794 0.9906)
			(stroke
				(width 0.1)
				(type default)
			)
			(layer "F.Fab")
		)
		(fp_line
			(start -0.2794 0.9906)
			(end 0.2794 0.9906)
			(stroke
				(width 0.1)
				(type default)
			)
			(layer "F.Fab")
		)
		(fp_line
			(start 0.2794 -0.1016)
			(end -0.2794 -0.1016)
			(stroke
				(width 0.1)
				(type default)
			)
			(layer "F.Fab")
		)
		(fp_line
			(start 0.2794 0.9906)
			(end 0.2794 -0.1016)
			(stroke
				(width 0.1)
				(type default)
			)
			(layer "F.Fab")
		)
		(pad "1" smd rect
			(at 0 0)
			(size 0.508 0.508)
			(layers "F.Cu" "F.Mask" "F.Paste")
			(net "P3V3_STBY")
		)
		(pad "2" smd rect
			(at 0 0.889)
			(size 0.508 0.508)
			(layers "F.Cu" "F.Mask" "F.Paste")
			(net "PWRGD_PVPP_DEF_R")
		)
		(zone
			(layer "F.Cu")
			(hatch none 0.5)
			(connect_pads
				(clearance 0)
			)
			(min_thickness 0.25)
			(keepout
				(tracks allowed)
				(vias not_allowed)
				(pads allowed)
				(copperpour not_allowed)
				(footprints allowed)
			)
			(placement
				(enabled no)
				(sheetname "")
			)
			(fill
				(thermal_gap 0.5)
				(thermal_bridge_width 0.5)
				(island_removal_mode 0)
			)
			(polygon
				(pts
					(xy 354.551234 -129.1082) (xy 355.059234 -129.1082) (xy 355.059234 -128.7272) (xy 354.551234 -128.7272)
				)
			)
		)
		(zone
			(layer "F.Cu")
			(hatch none 0.5)
			(connect_pads
				(clearance 0)
			)
			(min_thickness 0.25)
			(keepout
				(tracks not_allowed)
				(vias allowed)
				(pads allowed)
				(copperpour not_allowed)
				(footprints allowed)
			)
			(placement
				(enabled no)
				(sheetname "")
			)
			(fill
				(thermal_gap 0.5)
				(thermal_bridge_width 0.5)
				(island_removal_mode 0)
			)
			(polygon
				(pts
					(xy 354.551234 -128.7272) (xy 355.059234 -128.7272) (xy 355.059234 -129.1082) (xy 354.551234 -129.1082)
				)
			)
		)
	)
	(footprint ""
		(layer "F.Cu")
		(at 10.8204 -8.951976)
		(property "Reference" "L1G1"
			(at 3.378708 -4.251706 0)
			(unlocked yes)
			(layer "F.SilkS")
			(effects
				(font
					(size 0.4064 0.254)
					(thickness 0.1524)
				)
			)
		)
		(property "Value" ""
			(at 0 0 0)
			(layer "F.Fab")
			(effects
				(font
					(size 1.27 1.27)
				)
			)
		)
		(duplicate_pad_numbers_are_jumpers no)
		(fp_line
			(start -1.1303 -3.199892)
			(end 8.3693 -3.199892)
			(stroke
				(width 0.1524)
				(type default)
			)
			(layer "F.SilkS")
		)
		(fp_line
			(start -1.1303 -1.6637)
			(end -1.1303 -3.199892)
			(stroke
				(width 0.1524)
				(type default)
			)
			(layer "F.SilkS")
		)
		(fp_line
			(start -1.1303 3.199892)
			(end -1.1303 1.6637)
			(stroke
				(width 0.1524)
				(type default)
			)
			(layer "F.SilkS")
		)
		(fp_line
			(start 8.3693 -3.199892)
			(end 8.3693 -1.6637)
			(stroke
				(width 0.1524)
				(type default)
			)
			(layer "F.SilkS")
		)
		(fp_line
			(start 8.3693 1.6637)
			(end 8.3693 3.199892)
			(stroke
				(width 0.1524)
				(type default)
			)
			(layer "F.SilkS")
		)
		(fp_line
			(start 8.3693 3.199892)
			(end -1.1303 3.199892)
			(stroke
				(width 0.1524)
				(type default)
			)
			(layer "F.SilkS")
		)
		(fp_rect
			(start -1.1303 3.199892)
			(end 8.3693 -3.199892)
			(stroke
				(width 0)
				(type default)
			)
			(fill no)
			(layer "F.CrtYd")
		)
		(fp_line
			(start -1.1303 -3.199892)
			(end 8.3693 -3.199892)
			(stroke
				(width 0.1)
				(type default)
			)
			(layer "F.Fab")
		)
		(fp_line
			(start -1.1303 3.199892)
			(end -1.1303 -3.199892)
			(stroke
				(width 0.1)
				(type default)
			)
			(layer "F.Fab")
		)
		(fp_line
			(start 8.3693 -3.199892)
			(end 8.3693 3.199892)
			(stroke
				(width 0.1)
				(type default)
			)
			(layer "F.Fab")
		)
		(fp_line
			(start 8.3693 3.199892)
			(end -1.1303 3.199892)
			(stroke
				(width 0.1)
				(type default)
			)
			(layer "F.Fab")
		)
		(pad "1" smd rect
			(at 0 0)
			(size 3.683 2.667)
			(layers "F.Cu" "F.Mask" "F.Paste")
			(net "VR_PVDDQ_GHJ_PH1_SW")
		)
		(pad "2" smd rect
			(at 7.239 0)
			(size 3.683 2.667)
			(layers "F.Cu" "F.Mask" "F.Paste")
			(net "PVDDQ_GHJ")
		)
	)
	(footprint ""
		(layer "F.Cu")
		(at 14.7066 -126.6825 90)
		(property "Reference" "C1B10"
			(at 5.68833 3.1496 0)
			(unlocked yes)
			(layer "F.SilkS")
			(effects
				(font
					(size 0.7874 0.5842)
					(thickness 0.1524)
				)
				(justify left)
			)
		)
		(property "Value" ""
			(at 0 0 90)
			(layer "F.Fab")
			(effects
				(font
					(size 1.27 1.27)
				)
			)
		)
		(duplicate_pad_numbers_are_jumpers no)
		(fp_line
			(start 0.9017 -1.714246)
			(end 0.7239 -1.714246)
			(stroke
				(width 0.1524)
				(type default)
			)
			(layer "F.SilkS")
		)
		(fp_line
			(start -0.7239 -1.714246)
			(end -0.9017 -1.714246)
			(stroke
				(width 0.1524)
				(type default)
			)
			(layer "F.SilkS")
		)
		(fp_line
			(start -0.9017 -1.714246)
			(end -0.9017 1.587754)
			(stroke
				(width 0.1524)
				(type default)
			)
			(layer "F.SilkS")
		)
		(fp_line
			(start 2.638044 -0.733044)
			(end 0.9017 -0.733044)
			(stroke
				(width 0.1524)
				(type default)
			)
			(layer "F.SilkS")
		)
		(fp_line
			(start -0.9017 -0.733044)
			(end -2.638044 -0.733044)
			(stroke
				(width 0.1524)
				(type default)
			)
			(layer "F.SilkS")
		)
		(fp_line
			(start -2.638044 -0.733044)
			(end -3.400044 0.028956)
			(stroke
				(width 0.1524)
				(type default)
			)
			(layer "F.SilkS")
		)
		(fp_line
			(start 3.400044 0.028956)
			(end 2.638044 -0.733044)
			(stroke
				(width 0.1524)
				(type default)
			)
			(layer "F.SilkS")
		)
		(fp_line
			(start -3.400044 0.028956)
			(end -3.400044 6.067044)
			(stroke
				(width 0.1524)
				(type default)
			)
			(layer "F.SilkS")
		)
		(fp_line
			(start 0.9017 1.587754)
			(end 0.9017 -1.714246)
			(stroke
				(width 0.1524)
				(type default)
			)
			(layer "F.SilkS")
		)
		(fp_line
			(start 0.7239 1.587754)
			(end 0.9017 1.587754)
			(stroke
				(width 0.1524)
				(type default)
			)
			(layer "F.SilkS")
		)
		(fp_line
			(start -0.9017 1.587754)
			(end -0.7239 1.587754)
			(stroke
				(width 0.1524)
				(type default)
			)
			(layer "F.SilkS")
		)
		(fp_line
			(start 3.400044 6.067044)
			(end 3.400044 0.028956)
			(stroke
				(width 0.1524)
				(type default)
			)
			(layer "F.SilkS")
		)
		(fp_line
			(start 0.9017 6.067044)
			(end 3.400044 6.067044)
			(stroke
				(width 0.1524)
				(type default)
			)
			(layer "F.SilkS")
		)
		(fp_line
			(start -3.400044 6.067044)
			(end -0.9017 6.067044)
			(stroke
				(width 0.1524)
				(type default)
			)
			(layer "F.SilkS")
		)
		(fp_poly
			(pts
				(xy -3.400044 6.067044) (xy 3.400044 6.067044) (xy 3.400044 0.028956) (xy 2.638044 -0.733044) (xy -2.638044 -0.733044)
				(xy -3.400044 0.028956)
			)
			(stroke
				(width 0)
				(type default)
			)
			(fill no)
			(layer "F.CrtYd")
		)
		(fp_line
			(start 2.638044 -0.733044)
			(end -2.638044 -0.733044)
			(stroke
				(width 0.1)
				(type default)
			)
			(layer "F.Fab")
		)
		(fp_line
			(start -2.638044 -0.733044)
			(end -3.400044 0.028956)
			(stroke
				(width 0.1)
				(type default)
			)
			(layer "F.Fab")
		)
		(fp_line
			(start 3.400044 0.028956)
			(end 2.638044 -0.733044)
			(stroke
				(width 0.1)
				(type default)
			)
			(layer "F.Fab")
		)
		(fp_line
			(start -3.400044 0.028956)
			(end -3.400044 6.067044)
			(stroke
				(width 0.1)
				(type default)
			)
			(layer "F.Fab")
		)
		(fp_line
			(start 3.400044 6.067044)
			(end 3.400044 0.028956)
			(stroke
				(width 0.1)
				(type default)
			)
			(layer "F.Fab")
		)
		(fp_line
			(start -3.400044 6.067044)
			(end 3.400044 6.067044)
			(stroke
				(width 0.1)
				(type default)
			)
			(layer "F.Fab")
		)
		(fp_circle
			(center 0 2.667)
			(end 0 6.067044)
			(stroke
				(width 0.1)
				(type default)
			)
			(fill no)
			(layer "F.Fab")
		)
		(pad "1" smd rect
			(at 0 0 90)
			(size 0.7874 3.429)
			(layers "F.Cu" "F.Mask" "F.Paste")
			(net "VR_FET_SW_P12V_STBY_PVDDQ_KLM")
		)
		(pad "2" smd rect
			(at 0 5.334 90)
			(size 0.7874 3.429)
			(layers "F.Cu" "F.Mask" "F.Paste")
			(net "GND")
		)
	)
	(footprint ""
		(layer "F.Cu")
		(at 7.366 -66.3702)
		(property "Reference" "R1D49"
			(at -3.556 -2.56413 0)
			(unlocked yes)
			(layer "F.SilkS")
			(effects
				(font
					(size 0.7874 0.5842)
					(thickness 0.1524)
				)
				(justify left)
			)
		)
		(property "Value" ""
			(at 0 0 0)
			(layer "F.Fab")
			(effects
				(font
					(size 1.27 1.27)
				)
			)
		)
		(duplicate_pad_numbers_are_jumpers no)
		(fp_circle
			(center -2.07264 -0.597154)
			(end -1.94564 -0.597154)
			(stroke
				(width 0.254)
				(type default)
			)
			(fill no)
			(layer "F.SilkS")
		)
		(fp_rect
			(start -0.8001 -0.31242)
			(end 5.8039 3.11658)
			(stroke
				(width 0)
				(type default)
			)
			(fill no)
			(layer "F.CrtYd")
		)
		(fp_line
			(start -0.8001 -0.31242)
			(end 5.8039 -0.31242)
			(stroke
				(width 0.1)
				(type default)
			)
			(layer "F.Fab")
		)
		(fp_line
			(start -0.8001 3.11658)
			(end -0.8001 -0.31242)
			(stroke
				(width 0.1)
				(type default)
			)
			(layer "F.Fab")
		)
		(fp_line
			(start 5.8039 -0.31242)
			(end 5.8039 3.11658)
			(stroke
				(width 0.1)
				(type default)
			)
			(layer "F.Fab")
		)
		(fp_line
			(start 5.8039 3.11658)
			(end -0.8001 3.11658)
			(stroke
				(width 0.1)
				(type default)
			)
			(layer "F.Fab")
		)
		(fp_circle
			(center -1.740916 -1.623822)
			(end -1.613916 -1.623822)
			(stroke
				(width 0.254)
				(type default)
			)
			(fill no)
			(layer "F.Fab")
		)
		(pad "1" smd rect
			(at 0 0)
			(size 3.4036 1.1938)
			(layers "F.Cu" "F.Mask" "F.Paste")
			(net "P12V_PSU")
		)
		(pad "2" smd rect
			(at 5.0038 0)
			(size 3.4036 1.1938)
			(layers "F.Cu" "F.Mask" "F.Paste")
			(net "P12V_MB0_SW")
		)
		(pad "3" smd rect
			(at 0 1.40208)
			(size 3.4036 0.6096)
			(layers "F.Cu" "F.Mask" "F.Paste")
			(net "P12V_HSC_SENP0")
		)
		(pad "4" smd rect
			(at 5.0038 1.40208)
			(size 3.4036 0.6096)
			(layers "F.Cu" "F.Mask" "F.Paste")
			(net "P12V_HSC_SENN0")
		)
		(pad "5" smd rect
			(at 0 2.80416)
			(size 3.4036 1.1938)
			(layers "F.Cu" "F.Mask" "F.Paste")
			(net "P12V_PSU")
		)
		(pad "6" smd rect
			(at 5.0038 2.80416)
			(size 3.4036 1.1938)
			(layers "F.Cu" "F.Mask" "F.Paste")
			(net "P12V_MB0_SW")
		)
		(zone
			(layer "F.Cu")
			(hatch none 0.5)
			(connect_pads
				(clearance 0)
			)
			(min_thickness 0.25)
			(keepout
				(tracks allowed)
				(vias not_allowed)
				(pads allowed)
				(copperpour not_allowed)
				(footprints allowed)
			)
			(placement
				(enabled no)
				(sheetname "")
			)
			(fill
				(thermal_gap 0.5)
				(thermal_bridge_width 0.5)
				(island_removal_mode 0)
			)
			(polygon
				(pts
					(xy 9.0678 -66.75628) (xy 9.0678 -62.96914) (xy 10.668 -62.96914) (xy 10.668 -66.9671) (xy 9.11352 -66.9671)
					(xy 9.0678 -66.9671)
				)
			)
		)
	)
	(footprint ""
		(layer "F.Cu")
		(at 276.000464 -3.3528 90)
		(property "Reference" "C5G18"
			(at 1.848866 0.752348 90)
			(unlocked yes)
			(layer "F.SilkS")
			(effects
				(font
					(size 1.27 0.9652)
					(thickness 0.1524)
				)
			)
		)
		(property "Value" ""
			(at 0 0 90)
			(layer "F.Fab")
			(effects
				(font
					(size 1.27 1.27)
				)
			)
		)
		(duplicate_pad_numbers_are_jumpers no)
		(fp_rect
			(start -0.500126 1.598422)
			(end 0.500126 -0.201422)
			(stroke
				(width 0)
				(type default)
			)
			(fill no)
			(layer "F.CrtYd")
		)
		(fp_line
			(start 0.500126 -0.201422)
			(end 0.500126 1.598422)
			(stroke
				(width 0.1)
				(type default)
			)
			(layer "F.Fab")
		)
		(fp_line
			(start -0.500126 -0.201422)
			(end 0.500126 -0.201422)
			(stroke
				(width 0.1)
				(type default)
			)
			(layer "F.Fab")
		)
		(fp_line
			(start 0.500126 1.598422)
			(end -0.500126 1.598422)
			(stroke
				(width 0.1)
				(type default)
			)
			(layer "F.Fab")
		)
		(fp_line
			(start -0.500126 1.598422)
			(end -0.500126 -0.201422)
			(stroke
				(width 0.1)
				(type default)
			)
			(layer "F.Fab")
		)
		(pad "1" smd rect
			(at 0 0)
			(size 0.889 0.9906)
			(layers "F.Cu" "F.Mask" "F.Paste")
			(net "PVDDQ_ABC")
		)
		(pad "2" smd rect
			(at 0 1.397)
			(size 0.889 0.9906)
			(layers "F.Cu" "F.Mask" "F.Paste")
			(net "GND")
		)
		(zone
			(layer "F.Cu")
			(hatch none 0.5)
			(connect_pads
				(clearance 0)
			)
			(min_thickness 0.25)
			(keepout
				(tracks allowed)
				(vias not_allowed)
				(pads allowed)
				(copperpour not_allowed)
				(footprints allowed)
			)
			(placement
				(enabled no)
				(sheetname "")
			)
			(fill
				(thermal_gap 0.5)
				(thermal_bridge_width 0.5)
				(island_removal_mode 0)
			)
			(polygon
				(pts
					(xy 276.952964 -2.8575) (xy 276.952964 -3.8481) (xy 276.444964 -3.8481) (xy 276.444964 -2.8575)
				)
			)
		)
		(zone
			(layer "F.Cu")
			(hatch none 0.5)
			(connect_pads
				(clearance 0)
			)
			(min_thickness 0.25)
			(keepout
				(tracks not_allowed)
				(vias allowed)
				(pads allowed)
				(copperpour not_allowed)
				(footprints allowed)
			)
			(placement
				(enabled no)
				(sheetname "")
			)
			(fill
				(thermal_gap 0.5)
				(thermal_bridge_width 0.5)
				(island_removal_mode 0)
			)
			(polygon
				(pts
					(xy 276.952964 -2.8575) (xy 276.952964 -3.8481) (xy 276.444964 -3.8481) (xy 276.444964 -2.8575)
				)
			)
		)
	)
	(footprint ""
		(layer "F.Cu")
		(at 393.2936 -0.2286)
		(property "Reference" "R8G11"
			(at 0 0 0)
			(layer "F.SilkS")
			(hide yes)
			(effects
				(font
					(size 1.27 1.27)
				)
			)
		)
		(property "Value" ""
			(at 0 0 0)
			(layer "F.Fab")
			(effects
				(font
					(size 1.27 1.27)
				)
			)
		)
		(duplicate_pad_numbers_are_jumpers no)
		(fp_poly
			(pts
				(xy -0.2794 -0.1016) (xy 0.2794 -0.1016) (xy 0.2794 0.9906) (xy -0.2794 0.9906)
			)
			(stroke
				(width 0)
				(type default)
			)
			(fill no)
			(layer "F.CrtYd")
		)
		(fp_line
			(start -0.2794 -0.1016)
			(end -0.2794 0.9906)
			(stroke
				(width 0.1)
				(type default)
			)
			(layer "F.Fab")
		)
		(fp_line
			(start -0.2794 0.9906)
			(end 0.2794 0.9906)
			(stroke
				(width 0.1)
				(type default)
			)
			(layer "F.Fab")
		)
		(fp_line
			(start 0.2794 -0.1016)
			(end -0.2794 -0.1016)
			(stroke
				(width 0.1)
				(type default)
			)
			(layer "F.Fab")
		)
		(fp_line
			(start 0.2794 0.9906)
			(end 0.2794 -0.1016)
			(stroke
				(width 0.1)
				(type default)
			)
			(layer "F.Fab")
		)
		(pad "1" smd rect
			(at 0 0)
			(size 0.508 0.508)
			(layers "F.Cu" "F.Mask" "F.Paste")
			(net "JTAG_PCH_PLD_TMS")
		)
		(pad "2" smd rect
			(at 0 0.889)
			(size 0.508 0.508)
			(layers "F.Cu" "F.Mask" "F.Paste")
			(net "JTAG_TMS")
		)
		(zone
			(layer "F.Cu")
			(hatch none 0.5)
			(connect_pads
				(clearance 0)
			)
			(min_thickness 0.25)
			(keepout
				(tracks allowed)
				(vias not_allowed)
				(pads allowed)
				(copperpour not_allowed)
				(footprints allowed)
			)
			(placement
				(enabled no)
				(sheetname "")
			)
			(fill
				(thermal_gap 0.5)
				(thermal_bridge_width 0.5)
				(island_removal_mode 0)
			)
			(polygon
				(pts
					(xy 393.0396 0.0254) (xy 393.5476 0.0254) (xy 393.5476 0.4064) (xy 393.0396 0.4064)
				)
			)
		)
		(zone
			(layer "F.Cu")
			(hatch none 0.5)
			(connect_pads
				(clearance 0)
			)
			(min_thickness 0.25)
			(keepout
				(tracks not_allowed)
				(vias allowed)
				(pads allowed)
				(copperpour not_allowed)
				(footprints allowed)
			)
			(placement
				(enabled no)
				(sheetname "")
			)
			(fill
				(thermal_gap 0.5)
				(thermal_bridge_width 0.5)
				(island_removal_mode 0)
			)
			(polygon
				(pts
					(xy 393.0396 0.4064) (xy 393.5476 0.4064) (xy 393.5476 0.0254) (xy 393.0396 0.0254)
				)
			)
		)
	)
	(footprint ""
		(layer "F.Cu")
		(at 465.6074 -1.9558)
		(property "Reference" "R25W154"
			(at -0.8382 -0.67818 0)
			(unlocked yes)
			(layer "F.SilkS")
			(effects
				(font
					(size 0.4064 0.254)
					(thickness 0.1524)
				)
				(justify left)
			)
		)
		(property "Value" ""
			(at 0 0 0)
			(layer "F.Fab")
			(effects
				(font
					(size 1.27 1.27)
				)
			)
		)
		(duplicate_pad_numbers_are_jumpers no)
		(fp_poly
			(pts
				(xy -0.2794 -0.1016) (xy 0.2794 -0.1016) (xy 0.2794 0.9906) (xy -0.2794 0.9906)
			)
			(stroke
				(width 0)
				(type default)
			)
			(fill no)
			(layer "F.CrtYd")
		)
		(fp_line
			(start -0.2794 -0.1016)
			(end -0.2794 0.9906)
			(stroke
				(width 0.1)
				(type default)
			)
			(layer "F.Fab")
		)
		(fp_line
			(start -0.2794 0.9906)
			(end 0.2794 0.9906)
			(stroke
				(width 0.1)
				(type default)
			)
			(layer "F.Fab")
		)
		(fp_line
			(start 0.2794 -0.1016)
			(end -0.2794 -0.1016)
			(stroke
				(width 0.1)
				(type default)
			)
			(layer "F.Fab")
		)
		(fp_line
			(start 0.2794 0.9906)
			(end 0.2794 -0.1016)
			(stroke
				(width 0.1)
				(type default)
			)
			(layer "F.Fab")
		)
		(pad "1" smd rect
			(at 0 0)
			(size 0.508 0.508)
			(layers "F.Cu" "F.Mask" "F.Paste")
			(net "SPI_BMC_BT_WP0_N")
		)
		(pad "2" smd rect
			(at 0 0.889)
			(size 0.508 0.508)
			(layers "F.Cu" "F.Mask" "F.Paste")
			(net "TPM_SPI_BMC_WP_N")
		)
		(zone
			(layer "F.Cu")
			(hatch none 0.5)
			(connect_pads
				(clearance 0)
			)
			(min_thickness 0.25)
			(keepout
				(tracks allowed)
				(vias not_allowed)
				(pads allowed)
				(copperpour not_allowed)
				(footprints allowed)
			)
			(placement
				(enabled no)
				(sheetname "")
			)
			(fill
				(thermal_gap 0.5)
				(thermal_bridge_width 0.5)
				(island_removal_mode 0)
			)
			(polygon
				(pts
					(xy 465.3534 -1.7018) (xy 465.8614 -1.7018) (xy 465.8614 -1.3208) (xy 465.3534 -1.3208)
				)
			)
		)
		(zone
			(layer "F.Cu")
			(hatch none 0.5)
			(connect_pads
				(clearance 0)
			)
			(min_thickness 0.25)
			(keepout
				(tracks not_allowed)
				(vias allowed)
				(pads allowed)
				(copperpour not_allowed)
				(footprints allowed)
			)
			(placement
				(enabled no)
				(sheetname "")
			)
			(fill
				(thermal_gap 0.5)
				(thermal_bridge_width 0.5)
				(island_removal_mode 0)
			)
			(polygon
				(pts
					(xy 465.3534 -1.3208) (xy 465.8614 -1.3208) (xy 465.8614 -1.7018) (xy 465.3534 -1.7018)
				)
			)
		)
	)
	(footprint ""
		(layer "F.Cu")
		(at 104.751378 -84.890102)
		(property "Reference" "C2D2"
			(at 0 0 0)
			(layer "F.SilkS")
			(hide yes)
			(effects
				(font
					(size 1.27 1.27)
				)
			)
		)
		(property "Value" ""
			(at 0 0 0)
			(layer "F.Fab")
			(effects
				(font
					(size 1.27 1.27)
				)
			)
		)
		(duplicate_pad_numbers_are_jumpers no)
		(fp_poly
			(pts
				(xy -0.4953 -0.2032) (xy 0.4953 -0.2032) (xy 0.4953 1.6002) (xy -0.4953 1.6002)
			)
			(stroke
				(width 0)
				(type default)
			)
			(fill no)
			(layer "F.CrtYd")
		)
		(fp_line
			(start -0.4953 -0.2032)
			(end 0.4953 -0.2032)
			(stroke
				(width 0.1)
				(type default)
			)
			(layer "F.Fab")
		)
		(fp_line
			(start -0.4953 1.6002)
			(end -0.4953 -0.2032)
			(stroke
				(width 0.1)
				(type default)
			)
			(layer "F.Fab")
		)
		(fp_line
			(start 0.4953 -0.2032)
			(end 0.4953 1.6002)
			(stroke
				(width 0.1)
				(type default)
			)
			(layer "F.Fab")
		)
		(fp_line
			(start 0.4953 1.6002)
			(end -0.4953 1.6002)
			(stroke
				(width 0.1)
				(type default)
			)
			(layer "F.Fab")
		)
		(pad "1" smd rect
			(at 0 0)
			(size 0.762 0.889)
			(layers "F.Cu" "F.Mask" "F.Paste")
			(net "PVDDQ_KLM")
		)
		(pad "2" smd rect
			(at 0 1.397)
			(size 0.762 0.889)
			(layers "F.Cu" "F.Mask" "F.Paste")
			(net "GND")
		)
		(zone
			(layer "F.Cu")
			(hatch none 0.5)
			(connect_pads
				(clearance 0)
			)
			(min_thickness 0.25)
			(keepout
				(tracks not_allowed)
				(vias allowed)
				(pads allowed)
				(copperpour not_allowed)
				(footprints allowed)
			)
			(placement
				(enabled no)
				(sheetname "")
			)
			(fill
				(thermal_gap 0.5)
				(thermal_bridge_width 0.5)
				(island_removal_mode 0)
			)
			(polygon
				(pts
					(xy 104.370378 -84.445602) (xy 105.132378 -84.445602) (xy 105.132378 -83.937602) (xy 104.370378 -83.937602)
				)
			)
		)
	)
	(footprint ""
		(layer "F.Cu")
		(at 350.012 -17.78 180)
		(property "Reference" "C7F18"
			(at 0 0 180)
			(layer "F.SilkS")
			(hide yes)
			(effects
				(font
					(size 1.27 1.27)
				)
			)
		)
		(property "Value" ""
			(at 0 0 180)
			(layer "F.Fab")
			(effects
				(font
					(size 1.27 1.27)
				)
			)
		)
		(duplicate_pad_numbers_are_jumpers no)
		(fp_poly
			(pts
				(xy 0.3048 -0.1016) (xy 0.3048 0.9906) (xy -0.3048 0.9906) (xy -0.3048 -0.1016)
			)
			(stroke
				(width 0)
				(type default)
			)
			(fill no)
			(layer "F.CrtYd")
		)
		(fp_line
			(start 0.3048 0.9906)
			(end 0.3048 -0.1016)
			(stroke
				(width 0.1)
				(type default)
			)
			(layer "F.Fab")
		)
		(fp_line
			(start 0.3048 -0.1016)
			(end -0.3048 -0.1016)
			(stroke
				(width 0.1)
				(type default)
			)
			(layer "F.Fab")
		)
		(fp_line
			(start -0.3048 0.9906)
			(end 0.3048 0.9906)
			(stroke
				(width 0.1)
				(type default)
			)
			(layer "F.Fab")
		)
		(fp_line
			(start -0.3048 -0.1016)
			(end -0.3048 0.9906)
			(stroke
				(width 0.1)
				(type default)
			)
			(layer "F.Fab")
		)
		(pad "1" smd rect
			(at 0 0 180)
			(size 0.508 0.508)
			(layers "F.Cu" "F.Mask" "F.Paste")
			(net "VR_PVDDQ_ABC_VDD")
		)
		(pad "2" smd rect
			(at 0 0.889 180)
			(size 0.508 0.508)
			(layers "F.Cu" "F.Mask" "F.Paste")
			(net "GND")
		)
		(zone
			(layer "F.Cu")
			(hatch none 0.5)
			(connect_pads
				(clearance 0)
			)
			(min_thickness 0.25)
			(keepout
				(tracks not_allowed)
				(vias allowed)
				(pads allowed)
				(copperpour not_allowed)
				(footprints allowed)
			)
			(placement
				(enabled no)
				(sheetname "")
			)
			(fill
				(thermal_gap 0.5)
				(thermal_bridge_width 0.5)
				(island_removal_mode 0)
			)
			(polygon
				(pts
					(xy 350.266 -18.415) (xy 349.758 -18.415) (xy 349.758 -18.034) (xy 350.266 -18.034)
				)
			)
		)
		(zone
			(layer "F.Cu")
			(hatch none 0.5)
			(connect_pads
				(clearance 0)
			)
			(min_thickness 0.25)
			(keepout
				(tracks allowed)
				(vias not_allowed)
				(pads allowed)
				(copperpour not_allowed)
				(footprints allowed)
			)
			(placement
				(enabled no)
				(sheetname "")
			)
			(fill
				(thermal_gap 0.5)
				(thermal_bridge_width 0.5)
				(island_removal_mode 0)
			)
			(polygon
				(pts
					(xy 350.266 -18.034) (xy 349.758 -18.034) (xy 349.758 -18.415) (xy 350.266 -18.415)
				)
			)
		)
	)
	(footprint ""
		(layer "F.Cu")
		(at 434.5051 -43.1038)
		(property "Reference" "R9F20"
			(at 0 0 0)
			(layer "F.SilkS")
			(hide yes)
			(effects
				(font
					(size 1.27 1.27)
				)
			)
		)
		(property "Value" ""
			(at 0 0 0)
			(layer "F.Fab")
			(effects
				(font
					(size 1.27 1.27)
				)
			)
		)
		(duplicate_pad_numbers_are_jumpers no)
		(fp_poly
			(pts
				(xy -0.2794 -0.1016) (xy 0.2794 -0.1016) (xy 0.2794 0.9906) (xy -0.2794 0.9906)
			)
			(stroke
				(width 0)
				(type default)
			)
			(fill no)
			(layer "F.CrtYd")
		)
		(fp_line
			(start -0.2794 -0.1016)
			(end -0.2794 0.9906)
			(stroke
				(width 0.1)
				(type default)
			)
			(layer "F.Fab")
		)
		(fp_line
			(start -0.2794 0.9906)
			(end 0.2794 0.9906)
			(stroke
				(width 0.1)
				(type default)
			)
			(layer "F.Fab")
		)
		(fp_line
			(start 0.2794 -0.1016)
			(end -0.2794 -0.1016)
			(stroke
				(width 0.1)
				(type default)
			)
			(layer "F.Fab")
		)
		(fp_line
			(start 0.2794 0.9906)
			(end 0.2794 -0.1016)
			(stroke
				(width 0.1)
				(type default)
			)
			(layer "F.Fab")
		)
		(pad "1" smd rect
			(at 0 0)
			(size 0.508 0.508)
			(layers "F.Cu" "F.Mask" "F.Paste")
			(net "PECI_BMC")
		)
		(pad "2" smd rect
			(at 0 0.889)
			(size 0.508 0.508)
			(layers "F.Cu" "F.Mask" "F.Paste")
			(net "GND")
		)
		(zone
			(layer "F.Cu")
			(hatch none 0.5)
			(connect_pads
				(clearance 0)
			)
			(min_thickness 0.25)
			(keepout
				(tracks allowed)
				(vias not_allowed)
				(pads allowed)
				(copperpour not_allowed)
				(footprints allowed)
			)
			(placement
				(enabled no)
				(sheetname "")
			)
			(fill
				(thermal_gap 0.5)
				(thermal_bridge_width 0.5)
				(island_removal_mode 0)
			)
			(polygon
				(pts
					(xy 434.2511 -42.8498) (xy 434.7591 -42.8498) (xy 434.7591 -42.4688) (xy 434.2511 -42.4688)
				)
			)
		)
		(zone
			(layer "F.Cu")
			(hatch none 0.5)
			(connect_pads
				(clearance 0)
			)
			(min_thickness 0.25)
			(keepout
				(tracks not_allowed)
				(vias allowed)
				(pads allowed)
				(copperpour not_allowed)
				(footprints allowed)
			)
			(placement
				(enabled no)
				(sheetname "")
			)
			(fill
				(thermal_gap 0.5)
				(thermal_bridge_width 0.5)
				(island_removal_mode 0)
			)
			(polygon
				(pts
					(xy 434.2511 -42.4688) (xy 434.7591 -42.4688) (xy 434.7591 -42.8498) (xy 434.2511 -42.8498)
				)
			)
		)
	)
	(footprint ""
		(layer "F.Cu")
		(at 197.108826 -69.324474 -90)
		(property "Reference" "C4D16"
			(at 0 0 270)
			(layer "F.SilkS")
			(hide yes)
			(effects
				(font
					(size 1.27 1.27)
				)
			)
		)
		(property "Value" ""
			(at 0 0 270)
			(layer "F.Fab")
			(effects
				(font
					(size 1.27 1.27)
				)
			)
		)
		(duplicate_pad_numbers_are_jumpers no)
		(fp_poly
			(pts
				(xy 0.3048 -0.1016) (xy 0.3048 0.9906) (xy -0.3048 0.9906) (xy -0.3048 -0.1016)
			)
			(stroke
				(width 0)
				(type default)
			)
			(fill no)
			(layer "F.CrtYd")
		)
		(fp_line
			(start -0.3048 0.9906)
			(end 0.3048 0.9906)
			(stroke
				(width 0.1)
				(type default)
			)
			(layer "F.Fab")
		)
		(fp_line
			(start 0.3048 0.9906)
			(end 0.3048 -0.1016)
			(stroke
				(width 0.1)
				(type default)
			)
			(layer "F.Fab")
		)
		(fp_line
			(start -0.3048 -0.1016)
			(end -0.3048 0.9906)
			(stroke
				(width 0.1)
				(type default)
			)
			(layer "F.Fab")
		)
		(fp_line
			(start 0.3048 -0.1016)
			(end -0.3048 -0.1016)
			(stroke
				(width 0.1)
				(type default)
			)
			(layer "F.Fab")
		)
		(pad "1" smd rect
			(at 0 0 270)
			(size 0.508 0.508)
			(layers "F.Cu" "F.Mask" "F.Paste")
			(net "VR_PVCCIN_CPU0_PH3_VCIN")
		)
		(pad "2" smd rect
			(at 0 0.889 270)
			(size 0.508 0.508)
			(layers "F.Cu" "F.Mask" "F.Paste")
			(net "GND")
		)
		(zone
			(layer "F.Cu")
			(hatch none 0.5)
			(connect_pads
				(clearance 0)
			)
			(min_thickness 0.25)
			(keepout
				(tracks not_allowed)
				(vias allowed)
				(pads allowed)
				(copperpour not_allowed)
				(footprints allowed)
			)
			(placement
				(enabled no)
				(sheetname "")
			)
			(fill
				(thermal_gap 0.5)
				(thermal_bridge_width 0.5)
				(island_removal_mode 0)
			)
			(polygon
				(pts
					(xy 196.473826 -69.578474) (xy 196.473826 -69.070474) (xy 196.854826 -69.070474) (xy 196.854826 -69.578474)
				)
			)
		)
		(zone
			(layer "F.Cu")
			(hatch none 0.5)
			(connect_pads
				(clearance 0)
			)
			(min_thickness 0.25)
			(keepout
				(tracks allowed)
				(vias not_allowed)
				(pads allowed)
				(copperpour not_allowed)
				(footprints allowed)
			)
			(placement
				(enabled no)
				(sheetname "")
			)
			(fill
				(thermal_gap 0.5)
				(thermal_bridge_width 0.5)
				(island_removal_mode 0)
			)
			(polygon
				(pts
					(xy 196.854826 -69.578474) (xy 196.854826 -69.070474) (xy 196.473826 -69.070474) (xy 196.473826 -69.578474)
				)
			)
		)
	)
	(footprint ""
		(layer "F.Cu")
		(at 364.75924 -137.52957 -90)
		(property "Reference" "R7A17"
			(at 0 0 270)
			(layer "F.SilkS")
			(hide yes)
			(effects
				(font
					(size 1.27 1.27)
				)
			)
		)
		(property "Value" ""
			(at 0 0 270)
			(layer "F.Fab")
			(effects
				(font
					(size 1.27 1.27)
				)
			)
		)
		(duplicate_pad_numbers_are_jumpers no)
		(fp_rect
			(start 0.2794 0.9906)
			(end -0.2794 -0.1016)
			(stroke
				(width 0)
				(type default)
			)
			(fill no)
			(layer "F.CrtYd")
		)
		(fp_line
			(start -0.2794 0.9906)
			(end 0.2794 0.9906)
			(stroke
				(width 0.1)
				(type default)
			)
			(layer "F.Fab")
		)
		(fp_line
			(start 0.2794 0.9906)
			(end 0.2794 -0.1016)
			(stroke
				(width 0.1)
				(type default)
			)
			(layer "F.Fab")
		)
		(fp_line
			(start -0.2794 -0.1016)
			(end -0.2794 0.9906)
			(stroke
				(width 0.1)
				(type default)
			)
			(layer "F.Fab")
		)
		(fp_line
			(start 0.2794 -0.1016)
			(end -0.2794 -0.1016)
			(stroke
				(width 0.1)
				(type default)
			)
			(layer "F.Fab")
		)
		(pad "1" smd rect
			(at 0 0 270)
			(size 0.508 0.508)
			(layers "F.Cu" "F.Mask" "F.Paste")
			(net "SVID_CLK1_CPU0_R")
		)
		(pad "2" smd rect
			(at 0 0.889 270)
			(size 0.508 0.508)
			(layers "F.Cu" "F.Mask" "F.Paste")
			(net "SVID_CLK_PVDDQ_DEF")
		)
		(zone
			(layer "F.Cu")
			(hatch none 0.5)
			(connect_pads
				(clearance 0)
			)
			(min_thickness 0.25)
			(keepout
				(tracks allowed)
				(vias not_allowed)
				(pads allowed)
				(copperpour not_allowed)
				(footprints allowed)
			)
			(placement
				(enabled no)
				(sheetname "")
			)
			(fill
				(thermal_gap 0.5)
				(thermal_bridge_width 0.5)
				(island_removal_mode 0)
			)
			(polygon
				(pts
					(xy 364.12424 -137.27557) (xy 364.50524 -137.27557) (xy 364.50524 -137.78357) (xy 364.12424 -137.78357)
				)
			)
		)
		(zone
			(layer "F.Cu")
			(hatch none 0.5)
			(connect_pads
				(clearance 0)
			)
			(min_thickness 0.25)
			(keepout
				(tracks not_allowed)
				(vias allowed)
				(pads allowed)
				(copperpour not_allowed)
				(footprints allowed)
			)
			(placement
				(enabled no)
				(sheetname "")
			)
			(fill
				(thermal_gap 0.5)
				(thermal_bridge_width 0.5)
				(island_removal_mode 0)
			)
			(polygon
				(pts
					(xy 364.12424 -137.27557) (xy 364.50524 -137.27557) (xy 364.50524 -137.78357) (xy 364.12424 -137.78357)
				)
			)
		)
	)
	(footprint ""
		(layer "F.Cu")
		(at 79.551022 -125.88113 -90)
		(property "Reference" "C2B2"
			(at 0 0 270)
			(layer "F.SilkS")
			(hide yes)
			(effects
				(font
					(size 1.27 1.27)
				)
			)
		)
		(property "Value" ""
			(at 0 0 270)
			(layer "F.Fab")
			(effects
				(font
					(size 1.27 1.27)
				)
			)
		)
		(duplicate_pad_numbers_are_jumpers no)
		(fp_rect
			(start -0.500126 1.598422)
			(end 0.500126 -0.201422)
			(stroke
				(width 0)
				(type default)
			)
			(fill no)
			(layer "F.CrtYd")
		)
		(fp_line
			(start -0.500126 1.598422)
			(end -0.500126 -0.201422)
			(stroke
				(width 0.1)
				(type default)
			)
			(layer "F.Fab")
		)
		(fp_line
			(start 0.500126 1.598422)
			(end -0.500126 1.598422)
			(stroke
				(width 0.1)
				(type default)
			)
			(layer "F.Fab")
		)
		(fp_line
			(start -0.500126 -0.201422)
			(end 0.500126 -0.201422)
			(stroke
				(width 0.1)
				(type default)
			)
			(layer "F.Fab")
		)
		(fp_line
			(start 0.500126 -0.201422)
			(end 0.500126 1.598422)
			(stroke
				(width 0.1)
				(type default)
			)
			(layer "F.Fab")
		)
		(pad "1" smd rect
			(at 0 0 180)
			(size 0.889 0.9906)
			(layers "F.Cu" "F.Mask" "F.Paste")
			(net "PVDDQ_KLM")
		)
		(pad "2" smd rect
			(at 0 1.397 180)
			(size 0.889 0.9906)
			(layers "F.Cu" "F.Mask" "F.Paste")
			(net "GND")
		)
		(zone
			(layer "F.Cu")
			(hatch none 0.5)
			(connect_pads
				(clearance 0)
			)
			(min_thickness 0.25)
			(keepout
				(tracks not_allowed)
				(vias allowed)
				(pads allowed)
				(copperpour not_allowed)
				(footprints allowed)
			)
			(placement
				(enabled no)
				(sheetname "")
			)
			(fill
				(thermal_gap 0.5)
				(thermal_bridge_width 0.5)
				(island_removal_mode 0)
			)
			(polygon
				(pts
					(xy 78.598522 -126.37643) (xy 78.598522 -125.38583) (xy 79.106522 -125.38583) (xy 79.106522 -126.37643)
				)
			)
		)
		(zone
			(layer "F.Cu")
			(hatch none 0.5)
			(connect_pads
				(clearance 0)
			)
			(min_thickness 0.25)
			(keepout
				(tracks allowed)
				(vias not_allowed)
				(pads allowed)
				(copperpour not_allowed)
				(footprints allowed)
			)
			(placement
				(enabled no)
				(sheetname "")
			)
			(fill
				(thermal_gap 0.5)
				(thermal_bridge_width 0.5)
				(island_removal_mode 0)
			)
			(polygon
				(pts
					(xy 78.598522 -126.37643) (xy 78.598522 -125.38583) (xy 79.106522 -125.38583) (xy 79.106522 -126.37643)
				)
			)
		)
	)
	(footprint ""
		(layer "F.Cu")
		(at 183.007 -64.135 180)
		(property "Reference" "R4E6"
			(at 0 0 180)
			(layer "F.SilkS")
			(hide yes)
			(effects
				(font
					(size 1.27 1.27)
				)
			)
		)
		(property "Value" ""
			(at 0 0 180)
			(layer "F.Fab")
			(effects
				(font
					(size 1.27 1.27)
				)
			)
		)
		(duplicate_pad_numbers_are_jumpers no)
		(fp_rect
			(start 0.2794 -0.1016)
			(end -0.2794 0.9906)
			(stroke
				(width 0)
				(type default)
			)
			(fill no)
			(layer "F.CrtYd")
		)
		(fp_line
			(start 0.2794 0.9906)
			(end 0.2794 -0.1016)
			(stroke
				(width 0.1)
				(type default)
			)
			(layer "F.Fab")
		)
		(fp_line
			(start 0.2794 -0.1016)
			(end -0.2794 -0.1016)
			(stroke
				(width 0.1)
				(type default)
			)
			(layer "F.Fab")
		)
		(fp_line
			(start -0.2794 0.9906)
			(end 0.2794 0.9906)
			(stroke
				(width 0.1)
				(type default)
			)
			(layer "F.Fab")
		)
		(fp_line
			(start -0.2794 -0.1016)
			(end -0.2794 0.9906)
			(stroke
				(width 0.1)
				(type default)
			)
			(layer "F.Fab")
		)
		(pad "1" smd rect
			(at 0 0 180)
			(size 0.508 0.508)
			(layers "F.Cu" "F.Mask" "F.Paste")
			(net "SVID_CLK0_CPU0_R")
		)
		(pad "2" smd rect
			(at 0 0.889 180)
			(size 0.508 0.508)
			(layers "F.Cu" "F.Mask" "F.Paste")
			(net "SVID_VCLK_PVCCIN_CPU0")
		)
		(zone
			(layer "F.Cu")
			(hatch none 0.5)
			(connect_pads
				(clearance 0)
			)
			(min_thickness 0.25)
			(keepout
				(tracks not_allowed)
				(vias allowed)
				(pads allowed)
				(copperpour not_allowed)
				(footprints allowed)
			)
			(placement
				(enabled no)
				(sheetname "")
			)
			(fill
				(thermal_gap 0.5)
				(thermal_bridge_width 0.5)
				(island_removal_mode 0)
			)
			(polygon
				(pts
					(xy 182.753 -64.389) (xy 183.261 -64.389) (xy 183.261 -64.77) (xy 182.753 -64.77)
				)
			)
		)
		(zone
			(layer "F.Cu")
			(hatch none 0.5)
			(connect_pads
				(clearance 0)
			)
			(min_thickness 0.25)
			(keepout
				(tracks allowed)
				(vias not_allowed)
				(pads allowed)
				(copperpour not_allowed)
				(footprints allowed)
			)
			(placement
				(enabled no)
				(sheetname "")
			)
			(fill
				(thermal_gap 0.5)
				(thermal_bridge_width 0.5)
				(island_removal_mode 0)
			)
			(polygon
				(pts
					(xy 182.753 -64.389) (xy 183.261 -64.389) (xy 183.261 -64.77) (xy 182.753 -64.77)
				)
			)
		)
	)
	(footprint ""
		(layer "F.Cu")
		(at 403.8854 -124.841 90)
		(property "Reference" "R8B9"
			(at 0 0 90)
			(layer "F.SilkS")
			(hide yes)
			(effects
				(font
					(size 1.27 1.27)
				)
			)
		)
		(property "Value" ""
			(at 0 0 90)
			(layer "F.Fab")
			(effects
				(font
					(size 1.27 1.27)
				)
			)
		)
		(duplicate_pad_numbers_are_jumpers no)
		(fp_poly
			(pts
				(xy -0.2794 -0.1016) (xy 0.2794 -0.1016) (xy 0.2794 0.9906) (xy -0.2794 0.9906)
			)
			(stroke
				(width 0)
				(type default)
			)
			(fill no)
			(layer "F.CrtYd")
		)
		(fp_line
			(start 0.2794 -0.1016)
			(end -0.2794 -0.1016)
			(stroke
				(width 0.1)
				(type default)
			)
			(layer "F.Fab")
		)
		(fp_line
			(start -0.2794 -0.1016)
			(end -0.2794 0.9906)
			(stroke
				(width 0.1)
				(type default)
			)
			(layer "F.Fab")
		)
		(fp_line
			(start 0.2794 0.9906)
			(end 0.2794 -0.1016)
			(stroke
				(width 0.1)
				(type default)
			)
			(layer "F.Fab")
		)
		(fp_line
			(start -0.2794 0.9906)
			(end 0.2794 0.9906)
			(stroke
				(width 0.1)
				(type default)
			)
			(layer "F.Fab")
		)
		(pad "1" smd rect
			(at 0 0 90)
			(size 0.508 0.508)
			(layers "F.Cu" "F.Mask" "F.Paste")
			(net "A_USB2_COMP")
		)
		(pad "2" smd rect
			(at 0 0.889 90)
			(size 0.508 0.508)
			(layers "F.Cu" "F.Mask" "F.Paste")
			(net "GND")
		)
		(zone
			(layer "F.Cu")
			(hatch none 0.5)
			(connect_pads
				(clearance 0)
			)
			(min_thickness 0.25)
			(keepout
				(tracks allowed)
				(vias not_allowed)
				(pads allowed)
				(copperpour not_allowed)
				(footprints allowed)
			)
			(placement
				(enabled no)
				(sheetname "")
			)
			(fill
				(thermal_gap 0.5)
				(thermal_bridge_width 0.5)
				(island_removal_mode 0)
			)
			(polygon
				(pts
					(xy 404.1394 -124.587) (xy 404.1394 -125.095) (xy 404.5204 -125.095) (xy 404.5204 -124.587)
				)
			)
		)
		(zone
			(layer "F.Cu")
			(hatch none 0.5)
			(connect_pads
				(clearance 0)
			)
			(min_thickness 0.25)
			(keepout
				(tracks not_allowed)
				(vias allowed)
				(pads allowed)
				(copperpour not_allowed)
				(footprints allowed)
			)
			(placement
				(enabled no)
				(sheetname "")
			)
			(fill
				(thermal_gap 0.5)
				(thermal_bridge_width 0.5)
				(island_removal_mode 0)
			)
			(polygon
				(pts
					(xy 404.5204 -124.587) (xy 404.5204 -125.095) (xy 404.1394 -125.095) (xy 404.1394 -124.587)
				)
			)
		)
	)
	(footprint ""
		(layer "F.Cu")
		(at 173.609 -2.794 90)
		(property "Reference" "C4G21"
			(at 0 0 90)
			(layer "F.SilkS")
			(hide yes)
			(effects
				(font
					(size 1.27 1.27)
				)
			)
		)
		(property "Value" ""
			(at 0 0 90)
			(layer "F.Fab")
			(effects
				(font
					(size 1.27 1.27)
				)
			)
		)
		(duplicate_pad_numbers_are_jumpers no)
		(fp_rect
			(start 0.3048 0.9906)
			(end -0.3048 -0.1016)
			(stroke
				(width 0)
				(type default)
			)
			(fill no)
			(layer "F.CrtYd")
		)
		(fp_line
			(start 0.3048 -0.1016)
			(end -0.3048 -0.1016)
			(stroke
				(width 0.1)
				(type default)
			)
			(layer "F.Fab")
		)
		(fp_line
			(start -0.3048 -0.1016)
			(end -0.3048 0.9906)
			(stroke
				(width 0.1)
				(type default)
			)
			(layer "F.Fab")
		)
		(fp_line
			(start 0.3048 0.9906)
			(end 0.3048 -0.1016)
			(stroke
				(width 0.1)
				(type default)
			)
			(layer "F.Fab")
		)
		(fp_line
			(start -0.3048 0.9906)
			(end 0.3048 0.9906)
			(stroke
				(width 0.1)
				(type default)
			)
			(layer "F.Fab")
		)
		(pad "1" smd rect
			(at 0 0 90)
			(size 0.508 0.508)
			(layers "F.Cu" "F.Mask" "F.Paste")
			(net "VR_PVTT_GHJ_VREF")
		)
		(pad "2" smd rect
			(at 0 0.889 90)
			(size 0.508 0.508)
			(layers "F.Cu" "F.Mask" "F.Paste")
			(net "GND")
		)
		(zone
			(layer "F.Cu")
			(hatch none 0.5)
			(connect_pads
				(clearance 0)
			)
			(min_thickness 0.25)
			(keepout
				(tracks not_allowed)
				(vias allowed)
				(pads allowed)
				(copperpour not_allowed)
				(footprints allowed)
			)
			(placement
				(enabled no)
				(sheetname "")
			)
			(fill
				(thermal_gap 0.5)
				(thermal_bridge_width 0.5)
				(island_removal_mode 0)
			)
			(polygon
				(pts
					(xy 174.244 -3.048) (xy 173.863 -3.048) (xy 173.863 -2.54) (xy 174.244 -2.54)
				)
			)
		)
		(zone
			(layer "F.Cu")
			(hatch none 0.5)
			(connect_pads
				(clearance 0)
			)
			(min_thickness 0.25)
			(keepout
				(tracks allowed)
				(vias not_allowed)
				(pads allowed)
				(copperpour not_allowed)
				(footprints allowed)
			)
			(placement
				(enabled no)
				(sheetname "")
			)
			(fill
				(thermal_gap 0.5)
				(thermal_bridge_width 0.5)
				(island_removal_mode 0)
			)
			(polygon
				(pts
					(xy 174.244 -3.048) (xy 173.863 -3.048) (xy 173.863 -2.54) (xy 174.244 -2.54)
				)
			)
		)
	)
	(footprint ""
		(layer "F.Cu")
		(at 28.7528 -102.997 90)
		(property "Reference" "R1C35"
			(at 0 0 90)
			(layer "F.SilkS")
			(hide yes)
			(effects
				(font
					(size 1.27 1.27)
				)
			)
		)
		(property "Value" ""
			(at 0 0 90)
			(layer "F.Fab")
			(effects
				(font
					(size 1.27 1.27)
				)
			)
		)
		(duplicate_pad_numbers_are_jumpers no)
		(fp_poly
			(pts
				(xy -0.2794 -0.1016) (xy 0.2794 -0.1016) (xy 0.2794 0.9906) (xy -0.2794 0.9906)
			)
			(stroke
				(width 0)
				(type default)
			)
			(fill no)
			(layer "F.CrtYd")
		)
		(fp_line
			(start 0.2794 -0.1016)
			(end -0.2794 -0.1016)
			(stroke
				(width 0.1)
				(type default)
			)
			(layer "F.Fab")
		)
		(fp_line
			(start -0.2794 -0.1016)
			(end -0.2794 0.9906)
			(stroke
				(width 0.1)
				(type default)
			)
			(layer "F.Fab")
		)
		(fp_line
			(start 0.2794 0.9906)
			(end 0.2794 -0.1016)
			(stroke
				(width 0.1)
				(type default)
			)
			(layer "F.Fab")
		)
		(fp_line
			(start -0.2794 0.9906)
			(end 0.2794 0.9906)
			(stroke
				(width 0.1)
				(type default)
			)
			(layer "F.Fab")
		)
		(pad "1" smd rect
			(at 0 0 90)
			(size 0.508 0.508)
			(layers "F.Cu" "F.Mask" "F.Paste")
			(net "P3V3_STBY")
		)
		(pad "2" smd rect
			(at 0 0.889 90)
			(size 0.508 0.508)
			(layers "F.Cu" "F.Mask" "F.Paste")
			(net "FM_CPU1_SM_WP")
		)
		(zone
			(layer "F.Cu")
			(hatch none 0.5)
			(connect_pads
				(clearance 0)
			)
			(min_thickness 0.25)
			(keepout
				(tracks allowed)
				(vias not_allowed)
				(pads allowed)
				(copperpour not_allowed)
				(footprints allowed)
			)
			(placement
				(enabled no)
				(sheetname "")
			)
			(fill
				(thermal_gap 0.5)
				(thermal_bridge_width 0.5)
				(island_removal_mode 0)
			)
			(polygon
				(pts
					(xy 29.0068 -102.743) (xy 29.0068 -103.251) (xy 29.3878 -103.251) (xy 29.3878 -102.743)
				)
			)
		)
		(zone
			(layer "F.Cu")
			(hatch none 0.5)
			(connect_pads
				(clearance 0)
			)
			(min_thickness 0.25)
			(keepout
				(tracks not_allowed)
				(vias allowed)
				(pads allowed)
				(copperpour not_allowed)
				(footprints allowed)
			)
			(placement
				(enabled no)
				(sheetname "")
			)
			(fill
				(thermal_gap 0.5)
				(thermal_bridge_width 0.5)
				(island_removal_mode 0)
			)
			(polygon
				(pts
					(xy 29.3878 -102.743) (xy 29.3878 -103.251) (xy 29.0068 -103.251) (xy 29.0068 -102.743)
				)
			)
		)
	)
	(footprint ""
		(layer "F.Cu")
		(at 350.407224 -4.167378 180)
		(property "Reference" "C7G31"
			(at 0 0 180)
			(layer "F.SilkS")
			(hide yes)
			(effects
				(font
					(size 1.27 1.27)
				)
			)
		)
		(property "Value" ""
			(at 0 0 180)
			(layer "F.Fab")
			(effects
				(font
					(size 1.27 1.27)
				)
			)
		)
		(duplicate_pad_numbers_are_jumpers no)
		(fp_poly
			(pts
				(xy 0.3048 -0.1016) (xy 0.3048 0.9906) (xy -0.3048 0.9906) (xy -0.3048 -0.1016)
			)
			(stroke
				(width 0)
				(type default)
			)
			(fill no)
			(layer "F.CrtYd")
		)
		(fp_line
			(start 0.3048 0.9906)
			(end 0.3048 -0.1016)
			(stroke
				(width 0.1)
				(type default)
			)
			(layer "F.Fab")
		)
		(fp_line
			(start 0.3048 -0.1016)
			(end -0.3048 -0.1016)
			(stroke
				(width 0.1)
				(type default)
			)
			(layer "F.Fab")
		)
		(fp_line
			(start -0.3048 0.9906)
			(end 0.3048 0.9906)
			(stroke
				(width 0.1)
				(type default)
			)
			(layer "F.Fab")
		)
		(fp_line
			(start -0.3048 -0.1016)
			(end -0.3048 0.9906)
			(stroke
				(width 0.1)
				(type default)
			)
			(layer "F.Fab")
		)
		(pad "1" smd rect
			(at 0 0 180)
			(size 0.508 0.508)
			(layers "F.Cu" "F.Mask" "F.Paste")
			(net "VR_PVDDQ_ABC_PH1_BOOT")
		)
		(pad "2" smd rect
			(at 0 0.889 180)
			(size 0.508 0.508)
			(layers "F.Cu" "F.Mask" "F.Paste")
			(net "VR_PVDDQ_ABC_PH1_PHASE")
		)
		(zone
			(layer "F.Cu")
			(hatch none 0.5)
			(connect_pads
				(clearance 0)
			)
			(min_thickness 0.25)
			(keepout
				(tracks not_allowed)
				(vias allowed)
				(pads allowed)
				(copperpour not_allowed)
				(footprints allowed)
			)
			(placement
				(enabled no)
				(sheetname "")
			)
			(fill
				(thermal_gap 0.5)
				(thermal_bridge_width 0.5)
				(island_removal_mode 0)
			)
			(polygon
				(pts
					(xy 350.661224 -4.802378) (xy 350.153224 -4.802378) (xy 350.153224 -4.421378) (xy 350.661224 -4.421378)
				)
			)
		)
		(zone
			(layer "F.Cu")
			(hatch none 0.5)
			(connect_pads
				(clearance 0)
			)
			(min_thickness 0.25)
			(keepout
				(tracks allowed)
				(vias not_allowed)
				(pads allowed)
				(copperpour not_allowed)
				(footprints allowed)
			)
			(placement
				(enabled no)
				(sheetname "")
			)
			(fill
				(thermal_gap 0.5)
				(thermal_bridge_width 0.5)
				(island_removal_mode 0)
			)
			(polygon
				(pts
					(xy 350.661224 -4.421378) (xy 350.153224 -4.421378) (xy 350.153224 -4.802378) (xy 350.661224 -4.802378)
				)
			)
		)
	)
	(footprint ""
		(layer "F.Cu")
		(at 178.181 -58.166 -90)
		(property "Reference" "C4E23"
			(at 0 0 270)
			(layer "F.SilkS")
			(hide yes)
			(effects
				(font
					(size 1.27 1.27)
				)
			)
		)
		(property "Value" ""
			(at 0 0 270)
			(layer "F.Fab")
			(effects
				(font
					(size 1.27 1.27)
				)
			)
		)
		(duplicate_pad_numbers_are_jumpers no)
		(fp_poly
			(pts
				(xy 0.3048 -0.1016) (xy 0.3048 0.9906) (xy -0.3048 0.9906) (xy -0.3048 -0.1016)
			)
			(stroke
				(width 0)
				(type default)
			)
			(fill no)
			(layer "F.CrtYd")
		)
		(fp_line
			(start -0.3048 0.9906)
			(end 0.3048 0.9906)
			(stroke
				(width 0.1)
				(type default)
			)
			(layer "F.Fab")
		)
		(fp_line
			(start 0.3048 0.9906)
			(end 0.3048 -0.1016)
			(stroke
				(width 0.1)
				(type default)
			)
			(layer "F.Fab")
		)
		(fp_line
			(start -0.3048 -0.1016)
			(end -0.3048 0.9906)
			(stroke
				(width 0.1)
				(type default)
			)
			(layer "F.Fab")
		)
		(fp_line
			(start 0.3048 -0.1016)
			(end -0.3048 -0.1016)
			(stroke
				(width 0.1)
				(type default)
			)
			(layer "F.Fab")
		)
		(pad "1" smd rect
			(at 0 0 270)
			(size 0.508 0.508)
			(layers "F.Cu" "F.Mask" "F.Paste")
			(net "P5V_STBY")
		)
		(pad "2" smd rect
			(at 0 0.889 270)
			(size 0.508 0.508)
			(layers "F.Cu" "F.Mask" "F.Paste")
			(net "GND")
		)
		(zone
			(layer "F.Cu")
			(hatch none 0.5)
			(connect_pads
				(clearance 0)
			)
			(min_thickness 0.25)
			(keepout
				(tracks not_allowed)
				(vias allowed)
				(pads allowed)
				(copperpour not_allowed)
				(footprints allowed)
			)
			(placement
				(enabled no)
				(sheetname "")
			)
			(fill
				(thermal_gap 0.5)
				(thermal_bridge_width 0.5)
				(island_removal_mode 0)
			)
			(polygon
				(pts
					(xy 177.546 -58.42) (xy 177.546 -57.912) (xy 177.927 -57.912) (xy 177.927 -58.42)
				)
			)
		)
		(zone
			(layer "F.Cu")
			(hatch none 0.5)
			(connect_pads
				(clearance 0)
			)
			(min_thickness 0.25)
			(keepout
				(tracks allowed)
				(vias not_allowed)
				(pads allowed)
				(copperpour not_allowed)
				(footprints allowed)
			)
			(placement
				(enabled no)
				(sheetname "")
			)
			(fill
				(thermal_gap 0.5)
				(thermal_bridge_width 0.5)
				(island_removal_mode 0)
			)
			(polygon
				(pts
					(xy 177.927 -58.42) (xy 177.927 -57.912) (xy 177.546 -57.912) (xy 177.546 -58.42)
				)
			)
		)
	)
	(footprint ""
		(layer "F.Cu")
		(at 0 0 90)
		(property "Reference" "RM1G1"
			(at 0 0 90)
			(layer "F.SilkS")
			(hide yes)
			(effects
				(font
					(size 1.27 1.27)
				)
			)
		)
		(property "Value" "*"
			(at 7.0612 1.3462 90)
			(unlocked yes)
			(layer "F.Fab")
			(hide yes)
			(effects
				(font
					(size 1.27 1.016)
					(thickness 0.1524)
				)
			)
		)
		(property "Device Type" "STFT363B238R224H453-GP_DISCRETA"
			(at 7.0612 -0.1778 90)
			(unlocked yes)
			(layer "F.Fab")
			(hide yes)
			(effects
				(font
					(size 1.27 1.016)
					(thickness 0.1524)
				)
			)
		)
		(duplicate_pad_numbers_are_jumpers no)
		(fp_circle
			(center 0 0)
			(end 0 5.3594)
			(stroke
				(width 0.3048)
				(type default)
			)
			(fill no)
			(layer "F.SilkS")
		)
		(fp_poly
			(pts
				(arc
					(start 0 3.5306)
					(mid 0 -3.5306)
					(end 0 3.5306)
				)
			)
			(stroke
				(width 0)
				(type default)
			)
			(fill no)
			(layer "B.CrtYd")
		)
		(fp_poly
			(pts
				(arc
					(start 0 5.0038)
					(mid 0 -5.0038)
					(end 0 5.0038)
				)
			)
			(stroke
				(width 0)
				(type default)
			)
			(fill no)
			(layer "F.CrtYd")
		)
		(fp_poly
			(pts
				(arc
					(start 5.5118 0.00635)
					(mid -5.511804 0)
					(end 5.5118 -0.00635)
				)
				(arc
					(start 5.0038 -0.00635)
					(mid -5.003804 0)
					(end 5.0038 0.00635)
				)
			)
			(stroke
				(width 0)
				(type default)
			)
			(fill no)
			(layer "F.CrtYd")
		)
		(fp_poly
			(pts
				(arc
					(start 0 3.5306)
					(mid 0 -3.5306)
					(end 0 3.5306)
				)
			)
			(stroke
				(width 0)
				(type default)
			)
			(fill no)
			(layer "B.Fab")
		)
		(fp_poly
			(pts
				(arc
					(start 0 5.5118)
					(mid 0 -5.5118)
					(end 0 5.5118)
				)
			)
			(stroke
				(width 0)
				(type default)
			)
			(fill no)
			(layer "F.Fab")
		)
		(pad "1" thru_hole circle
			(at 0 0 90)
			(size 9.2202 9.2202)
			(drill 5.6896)
			(layers "*.Cu" "*.Mask")
			(remove_unused_layers no)
			(net "GND")
			(clearance -1.2573)
			(thermal_gap 0.3302)
			(padstack
				(mode front_inner_back)
				(layer "Inner"
					(shape circle)
					(size 6.0452 6.0452)
					(clearance 0.3302)
				)
				(layer "B.Cu"
					(shape circle)
					(size 6.0452 6.0452)
					(clearance 0.3302)
				)
			)
		)
	)
	(footprint ""
		(layer "F.Cu")
		(at 411.975046 -22.196552)
		(property "Reference" "C25W8"
			(at -0.8382 -0.67818 0)
			(unlocked yes)
			(layer "F.SilkS")
			(effects
				(font
					(size 0.4064 0.254)
					(thickness 0.1524)
				)
				(justify left)
			)
		)
		(property "Value" ""
			(at 0 0 0)
			(layer "F.Fab")
			(effects
				(font
					(size 1.27 1.27)
				)
			)
		)
		(duplicate_pad_numbers_are_jumpers no)
		(fp_poly
			(pts
				(xy 0.3048 -0.1016) (xy 0.3048 0.9906) (xy -0.3048 0.9906) (xy -0.3048 -0.1016)
			)
			(stroke
				(width 0)
				(type default)
			)
			(fill no)
			(layer "F.CrtYd")
		)
		(fp_line
			(start -0.3048 -0.1016)
			(end -0.3048 0.9906)
			(stroke
				(width 0.1)
				(type default)
			)
			(layer "F.Fab")
		)
		(fp_line
			(start -0.3048 0.9906)
			(end 0.3048 0.9906)
			(stroke
				(width 0.1)
				(type default)
			)
			(layer "F.Fab")
		)
		(fp_line
			(start 0.3048 -0.1016)
			(end -0.3048 -0.1016)
			(stroke
				(width 0.1)
				(type default)
			)
			(layer "F.Fab")
		)
		(fp_line
			(start 0.3048 0.9906)
			(end 0.3048 -0.1016)
			(stroke
				(width 0.1)
				(type default)
			)
			(layer "F.Fab")
		)
		(pad "1" smd rect
			(at 0 0)
			(size 0.508 0.508)
			(layers "F.Cu" "F.Mask" "F.Paste")
			(net "P3V3_STBY_BMC_ADCVREFN")
		)
		(pad "2" smd rect
			(at 0 0.889)
			(size 0.508 0.508)
			(layers "F.Cu" "F.Mask" "F.Paste")
			(net "GND")
		)
		(zone
			(layer "F.Cu")
			(hatch none 0.5)
			(connect_pads
				(clearance 0)
			)
			(min_thickness 0.25)
			(keepout
				(tracks allowed)
				(vias not_allowed)
				(pads allowed)
				(copperpour not_allowed)
				(footprints allowed)
			)
			(placement
				(enabled no)
				(sheetname "")
			)
			(fill
				(thermal_gap 0.5)
				(thermal_bridge_width 0.5)
				(island_removal_mode 0)
			)
			(polygon
				(pts
					(xy 411.721046 -21.942552) (xy 412.229046 -21.942552) (xy 412.229046 -21.561552) (xy 411.721046 -21.561552)
				)
			)
		)
		(zone
			(layer "F.Cu")
			(hatch none 0.5)
			(connect_pads
				(clearance 0)
			)
			(min_thickness 0.25)
			(keepout
				(tracks not_allowed)
				(vias allowed)
				(pads allowed)
				(copperpour not_allowed)
				(footprints allowed)
			)
			(placement
				(enabled no)
				(sheetname "")
			)
			(fill
				(thermal_gap 0.5)
				(thermal_bridge_width 0.5)
				(island_removal_mode 0)
			)
			(polygon
				(pts
					(xy 411.721046 -21.561552) (xy 412.229046 -21.561552) (xy 412.229046 -21.942552) (xy 411.721046 -21.942552)
				)
			)
		)
	)
	(footprint ""
		(layer "F.Cu")
		(at 420.7256 -86.4235)
		(property "Reference" "C8D2"
			(at 0 0 0)
			(layer "F.SilkS")
			(hide yes)
			(effects
				(font
					(size 1.27 1.27)
				)
			)
		)
		(property "Value" ""
			(at 0 0 0)
			(layer "F.Fab")
			(effects
				(font
					(size 1.27 1.27)
				)
			)
		)
		(duplicate_pad_numbers_are_jumpers no)
		(fp_poly
			(pts
				(xy 0.3048 -0.1016) (xy 0.3048 0.9906) (xy -0.3048 0.9906) (xy -0.3048 -0.1016)
			)
			(stroke
				(width 0)
				(type default)
			)
			(fill no)
			(layer "F.CrtYd")
		)
		(fp_line
			(start -0.3048 -0.1016)
			(end -0.3048 0.9906)
			(stroke
				(width 0.1)
				(type default)
			)
			(layer "F.Fab")
		)
		(fp_line
			(start -0.3048 0.9906)
			(end 0.3048 0.9906)
			(stroke
				(width 0.1)
				(type default)
			)
			(layer "F.Fab")
		)
		(fp_line
			(start 0.3048 -0.1016)
			(end -0.3048 -0.1016)
			(stroke
				(width 0.1)
				(type default)
			)
			(layer "F.Fab")
		)
		(fp_line
			(start 0.3048 0.9906)
			(end 0.3048 -0.1016)
			(stroke
				(width 0.1)
				(type default)
			)
			(layer "F.Fab")
		)
		(pad "1" smd rect
			(at 0 0)
			(size 0.508 0.508)
			(layers "F.Cu" "F.Mask" "F.Paste")
			(net "P3V3_STBY")
		)
		(pad "2" smd rect
			(at 0 0.889)
			(size 0.508 0.508)
			(layers "F.Cu" "F.Mask" "F.Paste")
			(net "GND")
		)
		(zone
			(layer "F.Cu")
			(hatch none 0.5)
			(connect_pads
				(clearance 0)
			)
			(min_thickness 0.25)
			(keepout
				(tracks allowed)
				(vias not_allowed)
				(pads allowed)
				(copperpour not_allowed)
				(footprints allowed)
			)
			(placement
				(enabled no)
				(sheetname "")
			)
			(fill
				(thermal_gap 0.5)
				(thermal_bridge_width 0.5)
				(island_removal_mode 0)
			)
			(polygon
				(pts
					(xy 420.4716 -86.1695) (xy 420.9796 -86.1695) (xy 420.9796 -85.7885) (xy 420.4716 -85.7885)
				)
			)
		)
		(zone
			(layer "F.Cu")
			(hatch none 0.5)
			(connect_pads
				(clearance 0)
			)
			(min_thickness 0.25)
			(keepout
				(tracks not_allowed)
				(vias allowed)
				(pads allowed)
				(copperpour not_allowed)
				(footprints allowed)
			)
			(placement
				(enabled no)
				(sheetname "")
			)
			(fill
				(thermal_gap 0.5)
				(thermal_bridge_width 0.5)
				(island_removal_mode 0)
			)
			(polygon
				(pts
					(xy 420.4716 -85.7885) (xy 420.9796 -85.7885) (xy 420.9796 -86.1695) (xy 420.4716 -86.1695)
				)
			)
		)
	)
	(footprint ""
		(layer "F.Cu")
		(at 170.9166 -8.6614)
		(property "Reference" "R4G5"
			(at 0 0 0)
			(layer "F.SilkS")
			(hide yes)
			(effects
				(font
					(size 1.27 1.27)
				)
			)
		)
		(property "Value" ""
			(at 0 0 0)
			(layer "F.Fab")
			(effects
				(font
					(size 1.27 1.27)
				)
			)
		)
		(duplicate_pad_numbers_are_jumpers no)
		(fp_rect
			(start -0.2794 0.9906)
			(end 0.2794 -0.1016)
			(stroke
				(width 0)
				(type default)
			)
			(fill no)
			(layer "F.CrtYd")
		)
		(fp_line
			(start -0.2794 -0.1016)
			(end -0.2794 0.9906)
			(stroke
				(width 0.1)
				(type default)
			)
			(layer "F.Fab")
		)
		(fp_line
			(start -0.2794 0.9906)
			(end 0.2794 0.9906)
			(stroke
				(width 0.1)
				(type default)
			)
			(layer "F.Fab")
		)
		(fp_line
			(start 0.2794 -0.1016)
			(end -0.2794 -0.1016)
			(stroke
				(width 0.1)
				(type default)
			)
			(layer "F.Fab")
		)
		(fp_line
			(start 0.2794 0.9906)
			(end 0.2794 -0.1016)
			(stroke
				(width 0.1)
				(type default)
			)
			(layer "F.Fab")
		)
		(pad "1" smd rect
			(at 0 0)
			(size 0.508 0.508)
			(layers "F.Cu" "F.Mask" "F.Paste")
			(net "FM_PVPP_CPU1_EN")
		)
		(pad "2" smd rect
			(at 0 0.889)
			(size 0.508 0.508)
			(layers "F.Cu" "F.Mask" "F.Paste")
			(net "GND")
		)
		(zone
			(layer "F.Cu")
			(hatch none 0.5)
			(connect_pads
				(clearance 0)
			)
			(min_thickness 0.25)
			(keepout
				(tracks not_allowed)
				(vias allowed)
				(pads allowed)
				(copperpour not_allowed)
				(footprints allowed)
			)
			(placement
				(enabled no)
				(sheetname "")
			)
			(fill
				(thermal_gap 0.5)
				(thermal_bridge_width 0.5)
				(island_removal_mode 0)
			)
			(polygon
				(pts
					(xy 170.6626 -8.0264) (xy 171.1706 -8.0264) (xy 171.1706 -8.4074) (xy 170.6626 -8.4074)
				)
			)
		)
		(zone
			(layer "F.Cu")
			(hatch none 0.5)
			(connect_pads
				(clearance 0)
			)
			(min_thickness 0.25)
			(keepout
				(tracks allowed)
				(vias not_allowed)
				(pads allowed)
				(copperpour not_allowed)
				(footprints allowed)
			)
			(placement
				(enabled no)
				(sheetname "")
			)
			(fill
				(thermal_gap 0.5)
				(thermal_bridge_width 0.5)
				(island_removal_mode 0)
			)
			(polygon
				(pts
					(xy 170.6626 -8.0264) (xy 171.1706 -8.0264) (xy 171.1706 -8.4074) (xy 170.6626 -8.4074)
				)
			)
		)
	)
	(footprint ""
		(layer "F.Cu")
		(at 29.083 -92.3798 -90)
		(property "Reference" "C1C26"
			(at 0 0 270)
			(layer "F.SilkS")
			(hide yes)
			(effects
				(font
					(size 1.27 1.27)
				)
			)
		)
		(property "Value" ""
			(at 0 0 270)
			(layer "F.Fab")
			(effects
				(font
					(size 1.27 1.27)
				)
			)
		)
		(duplicate_pad_numbers_are_jumpers no)
		(fp_rect
			(start 0.3048 -0.1016)
			(end -0.3048 0.9906)
			(stroke
				(width 0)
				(type default)
			)
			(fill no)
			(layer "F.CrtYd")
		)
		(fp_line
			(start -0.3048 0.9906)
			(end 0.3048 0.9906)
			(stroke
				(width 0.1)
				(type default)
			)
			(layer "F.Fab")
		)
		(fp_line
			(start 0.3048 0.9906)
			(end 0.3048 -0.1016)
			(stroke
				(width 0.1)
				(type default)
			)
			(layer "F.Fab")
		)
		(fp_line
			(start -0.3048 -0.1016)
			(end -0.3048 0.9906)
			(stroke
				(width 0.1)
				(type default)
			)
			(layer "F.Fab")
		)
		(fp_line
			(start 0.3048 -0.1016)
			(end -0.3048 -0.1016)
			(stroke
				(width 0.1)
				(type default)
			)
			(layer "F.Fab")
		)
		(pad "1" smd rect
			(at 0 0 270)
			(size 0.508 0.508)
			(layers "F.Cu" "F.Mask" "F.Paste")
			(net "VR_FET_SW_P12V_STBY_PVCCIN_CPU1")
		)
		(pad "2" smd rect
			(at 0 0.889 270)
			(size 0.508 0.508)
			(layers "F.Cu" "F.Mask" "F.Paste")
			(net "GND")
		)
		(zone
			(layer "F.Cu")
			(hatch none 0.5)
			(connect_pads
				(clearance 0)
			)
			(min_thickness 0.25)
			(keepout
				(tracks allowed)
				(vias not_allowed)
				(pads allowed)
				(copperpour not_allowed)
				(footprints allowed)
			)
			(placement
				(enabled no)
				(sheetname "")
			)
			(fill
				(thermal_gap 0.5)
				(thermal_bridge_width 0.5)
				(island_removal_mode 0)
			)
			(polygon
				(pts
					(xy 28.829 -92.1258) (xy 28.829 -92.6338) (xy 28.448 -92.6338) (xy 28.448 -92.1258)
				)
			)
		)
		(zone
			(layer "F.Cu")
			(hatch none 0.5)
			(connect_pads
				(clearance 0)
			)
			(min_thickness 0.25)
			(keepout
				(tracks not_allowed)
				(vias allowed)
				(pads allowed)
				(copperpour not_allowed)
				(footprints allowed)
			)
			(placement
				(enabled no)
				(sheetname "")
			)
			(fill
				(thermal_gap 0.5)
				(thermal_bridge_width 0.5)
				(island_removal_mode 0)
			)
			(polygon
				(pts
					(xy 28.829 -92.1258) (xy 28.829 -92.6338) (xy 28.448 -92.6338) (xy 28.448 -92.1258)
				)
			)
		)
	)
	(footprint ""
		(layer "F.Cu")
		(at 487.970576 -28.408376 180)
		(property "Reference" "R9F63"
			(at 0 0 180)
			(layer "F.SilkS")
			(hide yes)
			(effects
				(font
					(size 1.27 1.27)
				)
			)
		)
		(property "Value" ""
			(at 0 0 180)
			(layer "F.Fab")
			(effects
				(font
					(size 1.27 1.27)
				)
			)
		)
		(duplicate_pad_numbers_are_jumpers no)
		(fp_poly
			(pts
				(xy -0.2794 -0.1016) (xy 0.2794 -0.1016) (xy 0.2794 0.9906) (xy -0.2794 0.9906)
			)
			(stroke
				(width 0)
				(type default)
			)
			(fill no)
			(layer "F.CrtYd")
		)
		(fp_line
			(start 0.2794 0.9906)
			(end 0.2794 -0.1016)
			(stroke
				(width 0.1)
				(type default)
			)
			(layer "F.Fab")
		)
		(fp_line
			(start 0.2794 -0.1016)
			(end -0.2794 -0.1016)
			(stroke
				(width 0.1)
				(type default)
			)
			(layer "F.Fab")
		)
		(fp_line
			(start -0.2794 0.9906)
			(end 0.2794 0.9906)
			(stroke
				(width 0.1)
				(type default)
			)
			(layer "F.Fab")
		)
		(fp_line
			(start -0.2794 -0.1016)
			(end -0.2794 0.9906)
			(stroke
				(width 0.1)
				(type default)
			)
			(layer "F.Fab")
		)
		(pad "1" smd rect
			(at 0 0 180)
			(size 0.508 0.508)
			(layers "F.Cu" "F.Mask" "F.Paste")
			(net "SPA_MID_DBG_RX")
		)
		(pad "2" smd rect
			(at 0 0.889 180)
			(size 0.508 0.508)
			(layers "F.Cu" "F.Mask" "F.Paste")
			(net "SPA_MID_DBG_RX_R")
		)
		(zone
			(layer "F.Cu")
			(hatch none 0.5)
			(connect_pads
				(clearance 0)
			)
			(min_thickness 0.25)
			(keepout
				(tracks not_allowed)
				(vias allowed)
				(pads allowed)
				(copperpour not_allowed)
				(footprints allowed)
			)
			(placement
				(enabled no)
				(sheetname "")
			)
			(fill
				(thermal_gap 0.5)
				(thermal_bridge_width 0.5)
				(island_removal_mode 0)
			)
			(polygon
				(pts
					(xy 488.224576 -29.043376) (xy 487.716576 -29.043376) (xy 487.716576 -28.662376) (xy 488.224576 -28.662376)
				)
			)
		)
		(zone
			(layer "F.Cu")
			(hatch none 0.5)
			(connect_pads
				(clearance 0)
			)
			(min_thickness 0.25)
			(keepout
				(tracks allowed)
				(vias not_allowed)
				(pads allowed)
				(copperpour not_allowed)
				(footprints allowed)
			)
			(placement
				(enabled no)
				(sheetname "")
			)
			(fill
				(thermal_gap 0.5)
				(thermal_bridge_width 0.5)
				(island_removal_mode 0)
			)
			(polygon
				(pts
					(xy 488.224576 -28.662376) (xy 487.716576 -28.662376) (xy 487.716576 -29.043376) (xy 488.224576 -29.043376)
				)
			)
		)
	)
	(footprint ""
		(layer "F.Cu")
		(at 24.123142 -86.380066 180)
		(property "Reference" "CF7"
			(at 0 0 180)
			(layer "F.SilkS")
			(hide yes)
			(effects
				(font
					(size 1.27 1.27)
				)
			)
		)
		(property "Value" "*"
			(at 1.1811 -2.8194 180)
			(unlocked yes)
			(layer "F.Fab")
			(hide yes)
			(effects
				(font
					(size 1.27 1.016)
					(thickness 0.1524)
				)
			)
		)
		(property "Device Type" "SC22P50V2JN-4GP_SMD-BCG-SC22P5A"
			(at 1.1811 -4.3434 180)
			(unlocked yes)
			(layer "F.Fab")
			(hide yes)
			(effects
				(font
					(size 1.27 1.016)
					(thickness 0.1524)
				)
			)
		)
		(duplicate_pad_numbers_are_jumpers no)
		(fp_rect
			(start -0.4318 0.9525)
			(end 0.4318 -0.9525)
			(stroke
				(width 0)
				(type default)
			)
			(fill no)
			(layer "F.CrtYd")
		)
		(fp_rect
			(start -0.4318 0.9525)
			(end 0.4318 -0.9525)
			(stroke
				(width 0)
				(type default)
			)
			(fill no)
			(layer "F.Fab")
		)
		(pad "1" smd custom
			(at 0 -0.4445 180)
			(size 0.1524 0.1524)
			(layers "F.Cu" "F.Mask" "F.Paste")
			(net "VR_PVCCIN_CPU1_AIREF1")
			(options
				(clearance outline)
				(anchor circle)
			)
			(primitives
				(gr_poly
					(pts
						(arc
							(start 0.3048 -0.2032)
							(mid 0.275042 -0.275042)
							(end 0.2032 -0.3048)
						)
						(arc
							(start -0.2032 -0.3048)
							(mid -0.275042 -0.275042)
							(end -0.3048 -0.2032)
						)
						(arc
							(start -0.3048 0.2032)
							(mid -0.275042 0.275042)
							(end -0.2032 0.3048)
						)
						(arc
							(start 0.2032 0.3048)
							(mid 0.275042 0.275042)
							(end 0.3048 0.2032)
						)
					)
					(width 0)
					(fill yes)
				)
			)
		)
		(pad "2" smd custom
			(at 0 0.4445 180)
			(size 0.1524 0.1524)
			(layers "F.Cu" "F.Mask" "F.Paste")
			(net "ISENSE_PVCCIN_CPU1_PH1_IMON")
			(options
				(clearance outline)
				(anchor circle)
			)
			(primitives
				(gr_poly
					(pts
						(arc
							(start 0.3048 -0.2032)
							(mid 0.275042 -0.275042)
							(end 0.2032 -0.3048)
						)
						(arc
							(start -0.2032 -0.3048)
							(mid -0.275042 -0.275042)
							(end -0.3048 -0.2032)
						)
						(arc
							(start -0.3048 0.2032)
							(mid -0.275042 0.275042)
							(end -0.2032 0.3048)
						)
						(arc
							(start 0.2032 0.3048)
							(mid 0.275042 0.275042)
							(end 0.3048 0.2032)
						)
					)
					(width 0)
					(fill yes)
				)
			)
		)
	)
	(footprint ""
		(layer "F.Cu")
		(at 403.733 0.1524)
		(property "Reference" "U1L10"
			(at -1.743964 -3.834638 0)
			(unlocked yes)
			(layer "F.SilkS")
			(effects
				(font
					(size 3.048 1.524)
					(thickness 0.000001)
				)
				(justify left)
			)
		)
		(property "Value" ""
			(at 0 0 0)
			(layer "F.Fab")
			(effects
				(font
					(size 1.27 1.27)
				)
			)
		)
		(duplicate_pad_numbers_are_jumpers no)
		(fp_circle
			(center -1.17856 -2.466086)
			(end -1.05156 -2.466086)
			(stroke
				(width 0.254)
				(type default)
			)
			(fill no)
			(layer "F.SilkS")
		)
		(fp_rect
			(start -0.9144 0.9144)
			(end 0.9144 -0.9144)
			(stroke
				(width 0)
				(type default)
			)
			(fill yes)
			(layer "F.Paste")
		)
		(fp_rect
			(start -1.82499 1.82499)
			(end 1.82499 -1.82499)
			(stroke
				(width 0)
				(type default)
			)
			(fill no)
			(layer "F.CrtYd")
		)
		(fp_line
			(start -1.82499 -1.82499)
			(end 1.82499 -1.82499)
			(stroke
				(width 0.1)
				(type default)
			)
			(layer "F.Fab")
		)
		(fp_line
			(start -1.82499 1.82499)
			(end -1.82499 -1.82499)
			(stroke
				(width 0.1)
				(type default)
			)
			(layer "F.Fab")
		)
		(fp_line
			(start 1.82499 -1.82499)
			(end 1.82499 1.82499)
			(stroke
				(width 0.1)
				(type default)
			)
			(layer "F.Fab")
		)
		(fp_line
			(start 1.82499 1.82499)
			(end -1.82499 1.82499)
			(stroke
				(width 0.1)
				(type default)
			)
			(layer "F.Fab")
		)
		(fp_circle
			(center -1.17856 -2.466086)
			(end -1.05156 -2.466086)
			(stroke
				(width 0.254)
				(type default)
			)
			(fill no)
			(layer "F.Fab")
		)
		(pad "1" smd custom
			(at -0.750062 -1.549908)
			(size 0.0762 0.0762)
			(layers "F.Cu" "F.Mask" "F.Paste")
			(net "BMC_JTAG_SEL_N_MUX")
			(options
				(clearance outline)
				(anchor circle)
			)
			(primitives
				(gr_poly
					(pts
						(xy 0.1524 -0.381)
						(arc
							(start 0.1524 0.2286)
							(mid 0 0.381)
							(end -0.1524 0.2286)
						)
						(xy -0.1524 -0.381)
					)
					(width 0)
					(fill yes)
				)
			)
		)
		(pad "2" smd custom
			(at -1.549908 -0.999998)
			(size 0.0762 0.0762)
			(layers "F.Cu" "F.Mask" "F.Paste")
			(net "JTAG_PLD_TDO_MUX")
			(options
				(clearance outline)
				(anchor circle)
			)
			(primitives
				(gr_poly
					(pts
						(xy -0.381 -0.1524)
						(arc
							(start 0.2286 -0.1524)
							(mid 0.381 0)
							(end 0.2286 0.1524)
						)
						(xy -0.381 0.1524)
					)
					(width 0)
					(fill yes)
				)
			)
		)
		(pad "3" smd custom
			(at -1.549908 -0.500126)
			(size 0.0762 0.0762)
			(layers "F.Cu" "F.Mask" "F.Paste")
			(net "JTAG_TDO")
			(options
				(clearance outline)
				(anchor circle)
			)
			(primitives
				(gr_poly
					(pts
						(xy -0.381 -0.1524)
						(arc
							(start 0.2286 -0.1524)
							(mid 0.381 0)
							(end 0.2286 0.1524)
						)
						(xy -0.381 0.1524)
					)
					(width 0)
					(fill yes)
				)
			)
		)
		(pad "4" smd custom
			(at -1.549908 0)
			(size 0.0762 0.0762)
			(layers "F.Cu" "F.Mask" "F.Paste")
			(net "BMC_JTAG_SEL_N_MUX")
			(options
				(clearance outline)
				(anchor circle)
			)
			(primitives
				(gr_poly
					(pts
						(xy -0.381 -0.1524)
						(arc
							(start 0.2286 -0.1524)
							(mid 0.381 0)
							(end 0.2286 0.1524)
						)
						(xy -0.381 0.1524)
					)
					(width 0)
					(fill yes)
				)
			)
		)
		(pad "5" smd custom
			(at -1.549908 0.500126)
			(size 0.0762 0.0762)
			(layers "F.Cu" "F.Mask" "F.Paste")
			(net "JTAG_PLD_TCK_MUX")
			(options
				(clearance outline)
				(anchor circle)
			)
			(primitives
				(gr_poly
					(pts
						(xy -0.381 -0.1524)
						(arc
							(start 0.2286 -0.1524)
							(mid 0.381 0)
							(end 0.2286 0.1524)
						)
						(xy -0.381 0.1524)
					)
					(width 0)
					(fill yes)
				)
			)
		)
		(pad "6" smd custom
			(at -1.549908 0.999998)
			(size 0.0762 0.0762)
			(layers "F.Cu" "F.Mask" "F.Paste")
			(net "JTAG_TCK")
			(options
				(clearance outline)
				(anchor circle)
			)
			(primitives
				(gr_poly
					(pts
						(xy -0.381 -0.1524)
						(arc
							(start 0.2286 -0.1524)
							(mid 0.381 0)
							(end 0.2286 0.1524)
						)
						(xy -0.381 0.1524)
					)
					(width 0)
					(fill yes)
				)
			)
		)
		(pad "7" smd custom
			(at -0.750062 1.549908)
			(size 0.0762 0.0762)
			(layers "F.Cu" "F.Mask" "F.Paste")
			(net "GND")
			(options
				(clearance outline)
				(anchor circle)
			)
			(primitives
				(gr_poly
					(pts
						(xy -0.1524 0.381)
						(arc
							(start -0.1524 -0.2286)
							(mid 0 -0.381)
							(end 0.1524 -0.2286)
						)
						(xy 0.1524 0.381)
					)
					(width 0)
					(fill yes)
				)
			)
		)
		(pad "8" smd custom
			(at 0.769874 1.549908)
			(size 0.0762 0.0762)
			(layers "F.Cu" "F.Mask" "F.Paste")
			(net "JTAG_TMS")
			(options
				(clearance outline)
				(anchor circle)
			)
			(primitives
				(gr_poly
					(pts
						(xy -0.1524 0.381)
						(arc
							(start -0.1524 -0.2286)
							(mid 0 -0.381)
							(end 0.1524 -0.2286)
						)
						(xy 0.1524 0.381)
					)
					(width 0)
					(fill yes)
				)
			)
		)
		(pad "9" smd custom
			(at 1.549908 0.999998)
			(size 0.0762 0.0762)
			(layers "F.Cu" "F.Mask" "F.Paste")
			(net "JTAG_PLD_TMS_MUX")
			(options
				(clearance outline)
				(anchor circle)
			)
			(primitives
				(gr_poly
					(pts
						(xy 0.381 0.1524)
						(arc
							(start -0.2286 0.1524)
							(mid -0.381 0)
							(end -0.2286 -0.1524)
						)
						(xy 0.381 -0.1524)
					)
					(width 0)
					(fill yes)
				)
			)
		)
		(pad "10" smd custom
			(at 1.549908 0.500126)
			(size 0.0762 0.0762)
			(layers "F.Cu" "F.Mask" "F.Paste")
			(net "BMC_JTAG_SEL_N_MUX")
			(options
				(clearance outline)
				(anchor circle)
			)
			(primitives
				(gr_poly
					(pts
						(xy 0.381 0.1524)
						(arc
							(start -0.2286 0.1524)
							(mid -0.381 0)
							(end -0.2286 -0.1524)
						)
						(xy 0.381 -0.1524)
					)
					(width 0)
					(fill yes)
				)
			)
		)
		(pad "11" smd custom
			(at 1.549908 0)
			(size 0.0762 0.0762)
			(layers "F.Cu" "F.Mask" "F.Paste")
			(net "JTAG_TDI")
			(options
				(clearance outline)
				(anchor circle)
			)
			(primitives
				(gr_poly
					(pts
						(xy 0.381 0.1524)
						(arc
							(start -0.2286 0.1524)
							(mid -0.381 0)
							(end -0.2286 -0.1524)
						)
						(xy 0.381 -0.1524)
					)
					(width 0)
					(fill yes)
				)
			)
		)
		(pad "12" smd custom
			(at 1.549908 -0.500126)
			(size 0.0762 0.0762)
			(layers "F.Cu" "F.Mask" "F.Paste")
			(net "JTAG_PLD_TDI_MUX")
			(options
				(clearance outline)
				(anchor circle)
			)
			(primitives
				(gr_poly
					(pts
						(xy 0.381 0.1524)
						(arc
							(start -0.2286 0.1524)
							(mid -0.381 0)
							(end -0.2286 -0.1524)
						)
						(xy 0.381 -0.1524)
					)
					(width 0)
					(fill yes)
				)
			)
		)
		(pad "13" smd custom
			(at 1.549908 -0.999998)
			(size 0.0762 0.0762)
			(layers "F.Cu" "F.Mask" "F.Paste")
			(net "BMC_JTAG_SEL_N_MUX")
			(options
				(clearance outline)
				(anchor circle)
			)
			(primitives
				(gr_poly
					(pts
						(xy 0.381 0.1524)
						(arc
							(start -0.2286 0.1524)
							(mid -0.381 0)
							(end -0.2286 -0.1524)
						)
						(xy 0.381 -0.1524)
					)
					(width 0)
					(fill yes)
				)
			)
		)
		(pad "14" smd custom
			(at 0.750062 -1.549908)
			(size 0.0762 0.0762)
			(layers "F.Cu" "F.Mask" "F.Paste")
			(net "P3V3_STBY")
			(options
				(clearance outline)
				(anchor circle)
			)
			(primitives
				(gr_poly
					(pts
						(xy 0.1524 -0.381)
						(arc
							(start 0.1524 0.2286)
							(mid 0 0.381)
							(end -0.1524 0.2286)
						)
						(xy -0.1524 -0.381)
					)
					(width 0)
					(fill yes)
				)
			)
		)
		(pad "15" smd rect
			(at 0 0)
			(size 1.8288 1.8288)
			(layers "F.Cu" "F.Mask" "F.Paste")
			(net "GND")
		)
	)
	(footprint ""
		(layer "F.Cu")
		(at 393.254992 -10.917936)
		(property "Reference" "C7G21"
			(at 0 0 0)
			(layer "F.SilkS")
			(hide yes)
			(effects
				(font
					(size 1.27 1.27)
				)
			)
		)
		(property "Value" ""
			(at 0 0 0)
			(layer "F.Fab")
			(effects
				(font
					(size 1.27 1.27)
				)
			)
		)
		(duplicate_pad_numbers_are_jumpers no)
		(fp_rect
			(start -0.3048 0.9906)
			(end 0.3048 -0.1016)
			(stroke
				(width 0)
				(type default)
			)
			(fill no)
			(layer "F.CrtYd")
		)
		(fp_line
			(start -0.3048 -0.1016)
			(end -0.3048 0.9906)
			(stroke
				(width 0.1)
				(type default)
			)
			(layer "F.Fab")
		)
		(fp_line
			(start -0.3048 0.9906)
			(end 0.3048 0.9906)
			(stroke
				(width 0.1)
				(type default)
			)
			(layer "F.Fab")
		)
		(fp_line
			(start 0.3048 -0.1016)
			(end -0.3048 -0.1016)
			(stroke
				(width 0.1)
				(type default)
			)
			(layer "F.Fab")
		)
		(fp_line
			(start 0.3048 0.9906)
			(end 0.3048 -0.1016)
			(stroke
				(width 0.1)
				(type default)
			)
			(layer "F.Fab")
		)
		(pad "1" smd rect
			(at 0 0)
			(size 0.508 0.508)
			(layers "F.Cu" "F.Mask" "F.Paste")
			(net "P3E_CPU0_PE2_SS_TXP<7>")
		)
		(pad "2" smd rect
			(at 0 0.889)
			(size 0.508 0.508)
			(layers "F.Cu" "F.Mask" "F.Paste")
			(net "P3E_CPU0_PE2_SS_C_TXP<7>")
		)
		(zone
			(layer "F.Cu")
			(hatch none 0.5)
			(connect_pads
				(clearance 0)
			)
			(min_thickness 0.25)
			(keepout
				(tracks not_allowed)
				(vias allowed)
				(pads allowed)
				(copperpour not_allowed)
				(footprints allowed)
			)
			(placement
				(enabled no)
				(sheetname "")
			)
			(fill
				(thermal_gap 0.5)
				(thermal_bridge_width 0.5)
				(island_removal_mode 0)
			)
			(polygon
				(pts
					(xy 393.000992 -10.282936) (xy 393.508992 -10.282936) (xy 393.508992 -10.663936) (xy 393.000992 -10.663936)
				)
			)
		)
		(zone
			(layer "F.Cu")
			(hatch none 0.5)
			(connect_pads
				(clearance 0)
			)
			(min_thickness 0.25)
			(keepout
				(tracks allowed)
				(vias not_allowed)
				(pads allowed)
				(copperpour not_allowed)
				(footprints allowed)
			)
			(placement
				(enabled no)
				(sheetname "")
			)
			(fill
				(thermal_gap 0.5)
				(thermal_bridge_width 0.5)
				(island_removal_mode 0)
			)
			(polygon
				(pts
					(xy 393.000992 -10.282936) (xy 393.508992 -10.282936) (xy 393.508992 -10.663936) (xy 393.000992 -10.663936)
				)
			)
		)
	)
	(footprint ""
		(layer "F.Cu")
		(at 437.9468 -128.6764 180)
		(property "Reference" "C8B7"
			(at 0 0 180)
			(layer "F.SilkS")
			(hide yes)
			(effects
				(font
					(size 1.27 1.27)
				)
			)
		)
		(property "Value" ""
			(at 0 0 180)
			(layer "F.Fab")
			(effects
				(font
					(size 1.27 1.27)
				)
			)
		)
		(duplicate_pad_numbers_are_jumpers no)
		(fp_poly
			(pts
				(xy 0.3048 -0.1016) (xy 0.3048 0.9906) (xy -0.3048 0.9906) (xy -0.3048 -0.1016)
			)
			(stroke
				(width 0)
				(type default)
			)
			(fill no)
			(layer "F.CrtYd")
		)
		(fp_line
			(start 0.3048 0.9906)
			(end 0.3048 -0.1016)
			(stroke
				(width 0.1)
				(type default)
			)
			(layer "F.Fab")
		)
		(fp_line
			(start 0.3048 -0.1016)
			(end -0.3048 -0.1016)
			(stroke
				(width 0.1)
				(type default)
			)
			(layer "F.Fab")
		)
		(fp_line
			(start -0.3048 0.9906)
			(end 0.3048 0.9906)
			(stroke
				(width 0.1)
				(type default)
			)
			(layer "F.Fab")
		)
		(fp_line
			(start -0.3048 -0.1016)
			(end -0.3048 0.9906)
			(stroke
				(width 0.1)
				(type default)
			)
			(layer "F.Fab")
		)
		(pad "1" smd rect
			(at 0 0 180)
			(size 0.508 0.508)
			(layers "F.Cu" "F.Mask" "F.Paste")
			(net "P5V")
		)
		(pad "2" smd rect
			(at 0 0.889 180)
			(size 0.508 0.508)
			(layers "F.Cu" "F.Mask" "F.Paste")
			(net "GND")
		)
		(zone
			(layer "F.Cu")
			(hatch none 0.5)
			(connect_pads
				(clearance 0)
			)
			(min_thickness 0.25)
			(keepout
				(tracks not_allowed)
				(vias allowed)
				(pads allowed)
				(copperpour not_allowed)
				(footprints allowed)
			)
			(placement
				(enabled no)
				(sheetname "")
			)
			(fill
				(thermal_gap 0.5)
				(thermal_bridge_width 0.5)
				(island_removal_mode 0)
			)
			(polygon
				(pts
					(xy 438.2008 -129.3114) (xy 437.6928 -129.3114) (xy 437.6928 -128.9304) (xy 438.2008 -128.9304)
				)
			)
		)
		(zone
			(layer "F.Cu")
			(hatch none 0.5)
			(connect_pads
				(clearance 0)
			)
			(min_thickness 0.25)
			(keepout
				(tracks allowed)
				(vias not_allowed)
				(pads allowed)
				(copperpour not_allowed)
				(footprints allowed)
			)
			(placement
				(enabled no)
				(sheetname "")
			)
			(fill
				(thermal_gap 0.5)
				(thermal_bridge_width 0.5)
				(island_removal_mode 0)
			)
			(polygon
				(pts
					(xy 438.2008 -128.9304) (xy 437.6928 -128.9304) (xy 437.6928 -129.3114) (xy 438.2008 -129.3114)
				)
			)
		)
	)
	(footprint ""
		(layer "F.Cu")
		(at 375.5136 -158.2166 -90)
		(property "Reference" "CT64"
			(at 4.90347 8.7884 0)
			(unlocked yes)
			(layer "F.SilkS")
			(effects
				(font
					(size 0.7874 0.5842)
					(thickness 0.1524)
				)
				(justify left)
			)
		)
		(property "Value" ""
			(at 0 0 270)
			(layer "F.Fab")
			(effects
				(font
					(size 1.27 1.27)
				)
			)
		)
		(duplicate_pad_numbers_are_jumpers no)
		(fp_poly
			(pts
				(xy 0.3048 -0.1016) (xy 0.3048 0.9906) (xy -0.3048 0.9906) (xy -0.3048 -0.1016)
			)
			(stroke
				(width 0)
				(type default)
			)
			(fill no)
			(layer "F.CrtYd")
		)
		(fp_line
			(start -0.3048 0.9906)
			(end 0.3048 0.9906)
			(stroke
				(width 0.1)
				(type default)
			)
			(layer "F.Fab")
		)
		(fp_line
			(start 0.3048 0.9906)
			(end 0.3048 -0.1016)
			(stroke
				(width 0.1)
				(type default)
			)
			(layer "F.Fab")
		)
		(fp_line
			(start -0.3048 -0.1016)
			(end -0.3048 0.9906)
			(stroke
				(width 0.1)
				(type default)
			)
			(layer "F.Fab")
		)
		(fp_line
			(start 0.3048 -0.1016)
			(end -0.3048 -0.1016)
			(stroke
				(width 0.1)
				(type default)
			)
			(layer "F.Fab")
		)
		(pad "1" smd rect
			(at 0 0 270)
			(size 0.508 0.508)
			(layers "F.Cu" "F.Mask" "F.Paste")
			(net "A_TSENSE_PVNN_PCH_TMON")
		)
		(pad "2" smd rect
			(at 0 0.889 270)
			(size 0.508 0.508)
			(layers "F.Cu" "F.Mask" "F.Paste")
			(net "GND")
		)
		(zone
			(layer "F.Cu")
			(hatch none 0.5)
			(connect_pads
				(clearance 0)
			)
			(min_thickness 0.25)
			(keepout
				(tracks not_allowed)
				(vias allowed)
				(pads allowed)
				(copperpour not_allowed)
				(footprints allowed)
			)
			(placement
				(enabled no)
				(sheetname "")
			)
			(fill
				(thermal_gap 0.5)
				(thermal_bridge_width 0.5)
				(island_removal_mode 0)
			)
			(polygon
				(pts
					(xy 374.8786 -158.4706) (xy 374.8786 -157.9626) (xy 375.2596 -157.9626) (xy 375.2596 -158.4706)
				)
			)
		)
		(zone
			(layer "F.Cu")
			(hatch none 0.5)
			(connect_pads
				(clearance 0)
			)
			(min_thickness 0.25)
			(keepout
				(tracks allowed)
				(vias not_allowed)
				(pads allowed)
				(copperpour not_allowed)
				(footprints allowed)
			)
			(placement
				(enabled no)
				(sheetname "")
			)
			(fill
				(thermal_gap 0.5)
				(thermal_bridge_width 0.5)
				(island_removal_mode 0)
			)
			(polygon
				(pts
					(xy 375.2596 -158.4706) (xy 375.2596 -157.9626) (xy 374.8786 -157.9626) (xy 374.8786 -158.4706)
				)
			)
		)
	)
	(footprint ""
		(layer "F.Cu")
		(at 389.636 -71.0565 180)
		(property "Reference" "R7E13"
			(at 0 0 180)
			(layer "F.SilkS")
			(hide yes)
			(effects
				(font
					(size 1.27 1.27)
				)
			)
		)
		(property "Value" ""
			(at 0 0 180)
			(layer "F.Fab")
			(effects
				(font
					(size 1.27 1.27)
				)
			)
		)
		(duplicate_pad_numbers_are_jumpers no)
		(fp_poly
			(pts
				(xy -0.2794 -0.1016) (xy 0.2794 -0.1016) (xy 0.2794 0.9906) (xy -0.2794 0.9906)
			)
			(stroke
				(width 0)
				(type default)
			)
			(fill no)
			(layer "F.CrtYd")
		)
		(fp_line
			(start 0.2794 0.9906)
			(end 0.2794 -0.1016)
			(stroke
				(width 0.1)
				(type default)
			)
			(layer "F.Fab")
		)
		(fp_line
			(start 0.2794 -0.1016)
			(end -0.2794 -0.1016)
			(stroke
				(width 0.1)
				(type default)
			)
			(layer "F.Fab")
		)
		(fp_line
			(start -0.2794 0.9906)
			(end 0.2794 0.9906)
			(stroke
				(width 0.1)
				(type default)
			)
			(layer "F.Fab")
		)
		(fp_line
			(start -0.2794 -0.1016)
			(end -0.2794 0.9906)
			(stroke
				(width 0.1)
				(type default)
			)
			(layer "F.Fab")
		)
		(pad "1" smd rect
			(at 0 0 180)
			(size 0.508 0.508)
			(layers "F.Cu" "F.Mask" "F.Paste")
			(net "GND")
		)
		(pad "2" smd rect
			(at 0 0.889 180)
			(size 0.508 0.508)
			(layers "F.Cu" "F.Mask" "F.Paste")
			(net "AGND_P5V_STBY")
		)
		(zone
			(layer "F.Cu")
			(hatch none 0.5)
			(connect_pads
				(clearance 0)
			)
			(min_thickness 0.25)
			(keepout
				(tracks not_allowed)
				(vias allowed)
				(pads allowed)
				(copperpour not_allowed)
				(footprints allowed)
			)
			(placement
				(enabled no)
				(sheetname "")
			)
			(fill
				(thermal_gap 0.5)
				(thermal_bridge_width 0.5)
				(island_removal_mode 0)
			)
			(polygon
				(pts
					(xy 389.89 -71.6915) (xy 389.382 -71.6915) (xy 389.382 -71.3105) (xy 389.89 -71.3105)
				)
			)
		)
		(zone
			(layer "F.Cu")
			(hatch none 0.5)
			(connect_pads
				(clearance 0)
			)
			(min_thickness 0.25)
			(keepout
				(tracks allowed)
				(vias not_allowed)
				(pads allowed)
				(copperpour not_allowed)
				(footprints allowed)
			)
			(placement
				(enabled no)
				(sheetname "")
			)
			(fill
				(thermal_gap 0.5)
				(thermal_bridge_width 0.5)
				(island_removal_mode 0)
			)
			(polygon
				(pts
					(xy 389.89 -71.3105) (xy 389.382 -71.3105) (xy 389.382 -71.6915) (xy 389.89 -71.6915)
				)
			)
		)
	)
	(footprint ""
		(layer "F.Cu")
		(at 164.973 -67.31 -90)
		(property "Reference" "R4D56"
			(at 0 0 270)
			(layer "F.SilkS")
			(hide yes)
			(effects
				(font
					(size 1.27 1.27)
				)
			)
		)
		(property "Value" ""
			(at 0 0 270)
			(layer "F.Fab")
			(effects
				(font
					(size 1.27 1.27)
				)
			)
		)
		(duplicate_pad_numbers_are_jumpers no)
		(fp_poly
			(pts
				(xy -0.2794 -0.1016) (xy 0.2794 -0.1016) (xy 0.2794 0.9906) (xy -0.2794 0.9906)
			)
			(stroke
				(width 0)
				(type default)
			)
			(fill no)
			(layer "F.CrtYd")
		)
		(fp_line
			(start -0.2794 0.9906)
			(end 0.2794 0.9906)
			(stroke
				(width 0.1)
				(type default)
			)
			(layer "F.Fab")
		)
		(fp_line
			(start 0.2794 0.9906)
			(end 0.2794 -0.1016)
			(stroke
				(width 0.1)
				(type default)
			)
			(layer "F.Fab")
		)
		(fp_line
			(start -0.2794 -0.1016)
			(end -0.2794 0.9906)
			(stroke
				(width 0.1)
				(type default)
			)
			(layer "F.Fab")
		)
		(fp_line
			(start 0.2794 -0.1016)
			(end -0.2794 -0.1016)
			(stroke
				(width 0.1)
				(type default)
			)
			(layer "F.Fab")
		)
		(pad "1" smd rect
			(at 0 0 270)
			(size 0.508 0.508)
			(layers "F.Cu" "F.Mask" "F.Paste")
			(net "SVID_ALERT_PVCCIO_CPU1")
		)
		(pad "2" smd rect
			(at 0 0.889 270)
			(size 0.508 0.508)
			(layers "F.Cu" "F.Mask" "F.Paste")
			(net "SVID_ALERT0_CPU1_R_N")
		)
		(zone
			(layer "F.Cu")
			(hatch none 0.5)
			(connect_pads
				(clearance 0)
			)
			(min_thickness 0.25)
			(keepout
				(tracks not_allowed)
				(vias allowed)
				(pads allowed)
				(copperpour not_allowed)
				(footprints allowed)
			)
			(placement
				(enabled no)
				(sheetname "")
			)
			(fill
				(thermal_gap 0.5)
				(thermal_bridge_width 0.5)
				(island_removal_mode 0)
			)
			(polygon
				(pts
					(xy 164.338 -67.564) (xy 164.338 -67.056) (xy 164.719 -67.056) (xy 164.719 -67.564)
				)
			)
		)
		(zone
			(layer "F.Cu")
			(hatch none 0.5)
			(connect_pads
				(clearance 0)
			)
			(min_thickness 0.25)
			(keepout
				(tracks allowed)
				(vias not_allowed)
				(pads allowed)
				(copperpour not_allowed)
				(footprints allowed)
			)
			(placement
				(enabled no)
				(sheetname "")
			)
			(fill
				(thermal_gap 0.5)
				(thermal_bridge_width 0.5)
				(island_removal_mode 0)
			)
			(polygon
				(pts
					(xy 164.719 -67.564) (xy 164.719 -67.056) (xy 164.338 -67.056) (xy 164.338 -67.564)
				)
			)
		)
	)
	(footprint ""
		(layer "F.Cu")
		(at 398.093946 -47.22368 180)
		(property "Reference" "U7F1"
			(at 8.94334 -3.18643 0)
			(unlocked yes)
			(layer "F.SilkS")
			(effects
				(font
					(size 0.7874 0.5842)
					(thickness 0.1524)
				)
				(justify left)
			)
		)
		(property "Value" ""
			(at 0 0 180)
			(layer "F.Fab")
			(effects
				(font
					(size 1.27 1.27)
				)
			)
		)
		(duplicate_pad_numbers_are_jumpers no)
		(fp_line
			(start 11.645392 10.819892)
			(end -2.094738 10.819892)
			(stroke
				(width 0.1524)
				(type default)
			)
			(layer "F.SilkS")
		)
		(fp_line
			(start 11.645392 -1.929892)
			(end 11.645392 10.819892)
			(stroke
				(width 0.1524)
				(type default)
			)
			(layer "F.SilkS")
		)
		(fp_line
			(start -2.094738 10.819892)
			(end -2.094738 -1.929892)
			(stroke
				(width 0.1524)
				(type default)
			)
			(layer "F.SilkS")
		)
		(fp_line
			(start -2.094738 -1.929892)
			(end 11.645392 -1.929892)
			(stroke
				(width 0.1524)
				(type default)
			)
			(layer "F.SilkS")
		)
		(fp_circle
			(center -1.604264 -2.699512)
			(end -1.731264 -2.699512)
			(stroke
				(width 0.762)
				(type default)
			)
			(fill no)
			(layer "F.SilkS")
		)
		(fp_rect
			(start 11.645392 12.260326)
			(end 15.404846 -3.284474)
			(stroke
				(width 0)
				(type default)
			)
			(fill no)
			(layer "F.CrtYd")
		)
		(fp_rect
			(start -5.600954 12.260326)
			(end -2.094738 -3.284474)
			(stroke
				(width 0)
				(type default)
			)
			(fill no)
			(layer "F.CrtYd")
		)
		(fp_poly
			(pts
				(xy 7.569962 10.819892) (xy 6.970014 12.21994) (xy 2.629916 12.21994) (xy 2.029968 10.819892)
			)
			(stroke
				(width 0)
				(type default)
			)
			(fill no)
			(layer "F.CrtYd")
		)
		(fp_poly
			(pts
				(xy 2.029968 -1.929892) (xy 2.629916 -3.32994) (xy 6.970014 -3.32994) (xy 7.569962 -1.929892)
			)
			(stroke
				(width 0)
				(type default)
			)
			(fill no)
			(layer "F.CrtYd")
		)
		(fp_poly
			(pts
				(xy -2.094738 10.819892) (xy 11.645392 10.819892) (xy 11.645392 -1.929892) (xy -2.094738 -1.929892)
			)
			(stroke
				(width 0)
				(type default)
			)
			(fill no)
			(layer "F.CrtYd")
		)
		(fp_line
			(start 11.645392 10.819892)
			(end -2.094738 10.819892)
			(stroke
				(width 0.1)
				(type default)
			)
			(layer "F.Fab")
		)
		(fp_line
			(start 11.645392 -1.929892)
			(end 11.645392 10.819892)
			(stroke
				(width 0.1)
				(type default)
			)
			(layer "F.Fab")
		)
		(fp_line
			(start 7.569962 10.819892)
			(end 6.970014 12.21994)
			(stroke
				(width 0.1)
				(type default)
			)
			(layer "F.Fab")
		)
		(fp_line
			(start 6.970014 12.21994)
			(end 2.629916 12.21994)
			(stroke
				(width 0.1)
				(type default)
			)
			(layer "F.Fab")
		)
		(fp_line
			(start 6.970014 -3.32994)
			(end 7.569962 -1.929892)
			(stroke
				(width 0.1)
				(type default)
			)
			(layer "F.Fab")
		)
		(fp_line
			(start 2.629916 12.21994)
			(end 2.029968 10.819892)
			(stroke
				(width 0.1)
				(type default)
			)
			(layer "F.Fab")
		)
		(fp_line
			(start 2.629916 -3.32994)
			(end 6.970014 -3.32994)
			(stroke
				(width 0.1)
				(type default)
			)
			(layer "F.Fab")
		)
		(fp_line
			(start 2.029968 -1.929892)
			(end 2.629916 -3.32994)
			(stroke
				(width 0.1)
				(type default)
			)
			(layer "F.Fab")
		)
		(fp_line
			(start -2.094738 10.819892)
			(end -2.094738 -1.929892)
			(stroke
				(width 0.1)
				(type default)
			)
			(layer "F.Fab")
		)
		(fp_line
			(start -2.094738 -1.929892)
			(end 11.645392 -1.929892)
			(stroke
				(width 0.1)
				(type default)
			)
			(layer "F.Fab")
		)
		(fp_circle
			(center -2.645918 -0.940054)
			(end -2.772918 -0.940054)
			(stroke
				(width 0.254)
				(type default)
			)
			(fill no)
			(layer "F.Fab")
		)
		(fp_text user "9"
			(at 12.861798 10.70102 270)
			(unlocked yes)
			(layer "F.SilkS")
			(effects
				(font
					(size 0.7874 0.5842)
					(thickness 0.1524)
				)
				(justify left)
			)
		)
		(fp_text user "16"
			(at 11.13917 -2.15392 270)
			(unlocked yes)
			(layer "F.SilkS")
			(effects
				(font
					(size 0.7874 0.5842)
					(thickness 0.1524)
				)
				(justify left)
			)
		)
		(fp_text user "8"
			(at -1.215136 11.422634 0)
			(unlocked yes)
			(layer "F.SilkS")
			(effects
				(font
					(size 0.7874 0.5842)
					(thickness 0.1524)
				)
				(justify left)
			)
		)
		(fp_text user "9"
			(at 11.862054 9.20369 180)
			(unlocked yes)
			(layer "F.Fab")
			(effects
				(font
					(size 0.254 0.254)
					(thickness 0.000001)
				)
				(justify left)
			)
		)
		(fp_text user "16"
			(at 11.646916 0.367792 180)
			(unlocked yes)
			(layer "F.Fab")
			(effects
				(font
					(size 0.254 0.254)
					(thickness 0.000001)
				)
				(justify left)
			)
		)
		(fp_text user "8"
			(at -2.3241 8.86333 180)
			(unlocked yes)
			(layer "F.Fab")
			(effects
				(font
					(size 0.635 0.635)
					(thickness 0.1524)
				)
				(justify left)
			)
		)
		(pad "1" smd rect
			(at 0 0 180)
			(size 1.9304 0.635)
			(layers "F.Cu" "F.Mask" "F.Paste")
			(net "PU_BIOS_SPI_HOLD0_N")
		)
		(pad "2" smd rect
			(at 0 1.27 180)
			(size 1.9304 0.635)
			(layers "F.Cu" "F.Mask" "F.Paste")
			(net "P3V3_STBY")
		)
		(pad "3" smd rect
			(at 0 2.54 180)
			(size 1.9304 0.635)
			(layers "F.Cu" "F.Mask" "F.Paste")
			(net "PU_SPI0_RST")
		)
		(pad "4" smd rect
			(at 0 3.81 180)
			(size 1.9304 0.635)
			(layers "F.Cu" "F.Mask" "F.Paste")
			(net "TP_SPI_0_6")
		)
		(pad "5" smd rect
			(at 0 5.08 180)
			(size 1.9304 0.635)
			(layers "F.Cu" "F.Mask" "F.Paste")
			(net "TP_SPI_0_5")
		)
		(pad "6" smd rect
			(at 0 6.35 180)
			(size 1.9304 0.635)
			(layers "F.Cu" "F.Mask" "F.Paste")
			(net "TP_SPI_0_4")
		)
		(pad "7" smd rect
			(at 0 7.62 180)
			(size 1.9304 0.635)
			(layers "F.Cu" "F.Mask" "F.Paste")
			(net "SPI_CS0_PRIMARY_R_N")
		)
		(pad "8" smd rect
			(at 0 8.89 180)
			(size 1.9304 0.635)
			(layers "F.Cu" "F.Mask" "F.Paste")
			(net "SPI_MISO_R0")
		)
		(pad "9" smd rect
			(at 9.5504 8.89 180)
			(size 1.9304 0.635)
			(layers "F.Cu" "F.Mask" "F.Paste")
			(net "PU_BIOS_SPI_WP0_N")
		)
		(pad "10" smd rect
			(at 9.5504 7.62 180)
			(size 1.9304 0.635)
			(layers "F.Cu" "F.Mask" "F.Paste")
			(net "GND")
		)
		(pad "11" smd rect
			(at 9.5504 6.35 180)
			(size 1.9304 0.635)
			(layers "F.Cu" "F.Mask" "F.Paste")
			(net "TP_SPI_0_3")
		)
		(pad "12" smd rect
			(at 9.5504 5.08 180)
			(size 1.9304 0.635)
			(layers "F.Cu" "F.Mask" "F.Paste")
			(net "TP_SPI_0_2")
		)
		(pad "13" smd rect
			(at 9.5504 3.81 180)
			(size 1.9304 0.635)
			(layers "F.Cu" "F.Mask" "F.Paste")
			(net "TP_SPI_0_1")
		)
		(pad "14" smd rect
			(at 9.5504 2.54 180)
			(size 1.9304 0.635)
			(layers "F.Cu" "F.Mask" "F.Paste")
			(net "TP_SPI_0_0")
		)
		(pad "15" smd rect
			(at 9.5504 1.27 180)
			(size 1.9304 0.635)
			(layers "F.Cu" "F.Mask" "F.Paste")
			(net "SPI_SWITCH_MOSI_R0")
		)
		(pad "16" smd rect
			(at 9.5504 0 180)
			(size 1.9304 0.635)
			(layers "F.Cu" "F.Mask" "F.Paste")
			(net "SPI_CLK_R0")
		)
	)
	(footprint ""
		(layer "F.Cu")
		(at 253.392432 -3.3528 90)
		(property "Reference" "C5G14"
			(at 1.848866 0.752348 90)
			(unlocked yes)
			(layer "F.SilkS")
			(effects
				(font
					(size 1.27 0.9652)
					(thickness 0.1524)
				)
			)
		)
		(property "Value" ""
			(at 0 0 90)
			(layer "F.Fab")
			(effects
				(font
					(size 1.27 1.27)
				)
			)
		)
		(duplicate_pad_numbers_are_jumpers no)
		(fp_rect
			(start -0.500126 1.598422)
			(end 0.500126 -0.201422)
			(stroke
				(width 0)
				(type default)
			)
			(fill no)
			(layer "F.CrtYd")
		)
		(fp_line
			(start 0.500126 -0.201422)
			(end 0.500126 1.598422)
			(stroke
				(width 0.1)
				(type default)
			)
			(layer "F.Fab")
		)
		(fp_line
			(start -0.500126 -0.201422)
			(end 0.500126 -0.201422)
			(stroke
				(width 0.1)
				(type default)
			)
			(layer "F.Fab")
		)
		(fp_line
			(start 0.500126 1.598422)
			(end -0.500126 1.598422)
			(stroke
				(width 0.1)
				(type default)
			)
			(layer "F.Fab")
		)
		(fp_line
			(start -0.500126 1.598422)
			(end -0.500126 -0.201422)
			(stroke
				(width 0.1)
				(type default)
			)
			(layer "F.Fab")
		)
		(pad "1" smd rect
			(at 0 0)
			(size 0.889 0.9906)
			(layers "F.Cu" "F.Mask" "F.Paste")
			(net "PVDDQ_ABC")
		)
		(pad "2" smd rect
			(at 0 1.397)
			(size 0.889 0.9906)
			(layers "F.Cu" "F.Mask" "F.Paste")
			(net "GND")
		)
		(zone
			(layer "F.Cu")
			(hatch none 0.5)
			(connect_pads
				(clearance 0)
			)
			(min_thickness 0.25)
			(keepout
				(tracks not_allowed)
				(vias allowed)
				(pads allowed)
				(copperpour not_allowed)
				(footprints allowed)
			)
			(placement
				(enabled no)
				(sheetname "")
			)
			(fill
				(thermal_gap 0.5)
				(thermal_bridge_width 0.5)
				(island_removal_mode 0)
			)
			(polygon
				(pts
					(xy 254.344932 -2.8575) (xy 254.344932 -3.8481) (xy 253.836932 -3.8481) (xy 253.836932 -2.8575)
				)
			)
		)
		(zone
			(layer "F.Cu")
			(hatch none 0.5)
			(connect_pads
				(clearance 0)
			)
			(min_thickness 0.25)
			(keepout
				(tracks allowed)
				(vias not_allowed)
				(pads allowed)
				(copperpour not_allowed)
				(footprints allowed)
			)
			(placement
				(enabled no)
				(sheetname "")
			)
			(fill
				(thermal_gap 0.5)
				(thermal_bridge_width 0.5)
				(island_removal_mode 0)
			)
			(polygon
				(pts
					(xy 254.344932 -2.8575) (xy 254.344932 -3.8481) (xy 253.836932 -3.8481) (xy 253.836932 -2.8575)
				)
			)
		)
	)
	(footprint ""
		(layer "F.Cu")
		(at 169.037 -73.7108 90)
		(property "Reference" "C4D27"
			(at 0 0 90)
			(layer "F.SilkS")
			(hide yes)
			(effects
				(font
					(size 1.27 1.27)
				)
			)
		)
		(property "Value" ""
			(at 0 0 90)
			(layer "F.Fab")
			(effects
				(font
					(size 1.27 1.27)
				)
			)
		)
		(duplicate_pad_numbers_are_jumpers no)
		(fp_poly
			(pts
				(xy 0.3048 -0.1016) (xy 0.3048 0.9906) (xy -0.3048 0.9906) (xy -0.3048 -0.1016)
			)
			(stroke
				(width 0)
				(type default)
			)
			(fill no)
			(layer "F.CrtYd")
		)
		(fp_line
			(start 0.3048 -0.1016)
			(end -0.3048 -0.1016)
			(stroke
				(width 0.1)
				(type default)
			)
			(layer "F.Fab")
		)
		(fp_line
			(start -0.3048 -0.1016)
			(end -0.3048 0.9906)
			(stroke
				(width 0.1)
				(type default)
			)
			(layer "F.Fab")
		)
		(fp_line
			(start 0.3048 0.9906)
			(end 0.3048 -0.1016)
			(stroke
				(width 0.1)
				(type default)
			)
			(layer "F.Fab")
		)
		(fp_line
			(start -0.3048 0.9906)
			(end 0.3048 0.9906)
			(stroke
				(width 0.1)
				(type default)
			)
			(layer "F.Fab")
		)
		(pad "1" smd rect
			(at 0 0 90)
			(size 0.508 0.508)
			(layers "F.Cu" "F.Mask" "F.Paste")
			(net "P3V3_DB1200_R")
		)
		(pad "2" smd rect
			(at 0 0.889 90)
			(size 0.508 0.508)
			(layers "F.Cu" "F.Mask" "F.Paste")
			(net "GND")
		)
		(zone
			(layer "F.Cu")
			(hatch none 0.5)
			(connect_pads
				(clearance 0)
			)
			(min_thickness 0.25)
			(keepout
				(tracks allowed)
				(vias not_allowed)
				(pads allowed)
				(copperpour not_allowed)
				(footprints allowed)
			)
			(placement
				(enabled no)
				(sheetname "")
			)
			(fill
				(thermal_gap 0.5)
				(thermal_bridge_width 0.5)
				(island_removal_mode 0)
			)
			(polygon
				(pts
					(xy 169.291 -73.4568) (xy 169.291 -73.9648) (xy 169.672 -73.9648) (xy 169.672 -73.4568)
				)
			)
		)
		(zone
			(layer "F.Cu")
			(hatch none 0.5)
			(connect_pads
				(clearance 0)
			)
			(min_thickness 0.25)
			(keepout
				(tracks not_allowed)
				(vias allowed)
				(pads allowed)
				(copperpour not_allowed)
				(footprints allowed)
			)
			(placement
				(enabled no)
				(sheetname "")
			)
			(fill
				(thermal_gap 0.5)
				(thermal_bridge_width 0.5)
				(island_removal_mode 0)
			)
			(polygon
				(pts
					(xy 169.672 -73.4568) (xy 169.672 -73.9648) (xy 169.291 -73.9648) (xy 169.291 -73.4568)
				)
			)
		)
	)
	(footprint ""
		(layer "F.Cu")
		(at 258.064 -140.1318 -90)
		(property "Reference" "C5A15"
			(at 1.848866 0.752348 270)
			(unlocked yes)
			(layer "F.SilkS")
			(effects
				(font
					(size 1.27 0.9652)
					(thickness 0.1524)
				)
			)
		)
		(property "Value" ""
			(at 0 0 270)
			(layer "F.Fab")
			(effects
				(font
					(size 1.27 1.27)
				)
			)
		)
		(duplicate_pad_numbers_are_jumpers no)
		(fp_rect
			(start -0.500126 1.598422)
			(end 0.500126 -0.201422)
			(stroke
				(width 0)
				(type default)
			)
			(fill no)
			(layer "F.CrtYd")
		)
		(fp_line
			(start -0.500126 1.598422)
			(end -0.500126 -0.201422)
			(stroke
				(width 0.1)
				(type default)
			)
			(layer "F.Fab")
		)
		(fp_line
			(start 0.500126 1.598422)
			(end -0.500126 1.598422)
			(stroke
				(width 0.1)
				(type default)
			)
			(layer "F.Fab")
		)
		(fp_line
			(start -0.500126 -0.201422)
			(end 0.500126 -0.201422)
			(stroke
				(width 0.1)
				(type default)
			)
			(layer "F.Fab")
		)
		(fp_line
			(start 0.500126 -0.201422)
			(end 0.500126 1.598422)
			(stroke
				(width 0.1)
				(type default)
			)
			(layer "F.Fab")
		)
		(pad "1" smd rect
			(at 0 0 180)
			(size 0.889 0.9906)
			(layers "F.Cu" "F.Mask" "F.Paste")
			(net "PVDDQ_DEF")
		)
		(pad "2" smd rect
			(at 0 1.397 180)
			(size 0.889 0.9906)
			(layers "F.Cu" "F.Mask" "F.Paste")
			(net "GND")
		)
		(zone
			(layer "F.Cu")
			(hatch none 0.5)
			(connect_pads
				(clearance 0)
			)
			(min_thickness 0.25)
			(keepout
				(tracks not_allowed)
				(vias allowed)
				(pads allowed)
				(copperpour not_allowed)
				(footprints allowed)
			)
			(placement
				(enabled no)
				(sheetname "")
			)
			(fill
				(thermal_gap 0.5)
				(thermal_bridge_width 0.5)
				(island_removal_mode 0)
			)
			(polygon
				(pts
					(xy 257.1115 -140.6271) (xy 257.1115 -139.6365) (xy 257.6195 -139.6365) (xy 257.6195 -140.6271)
				)
			)
		)
		(zone
			(layer "F.Cu")
			(hatch none 0.5)
			(connect_pads
				(clearance 0)
			)
			(min_thickness 0.25)
			(keepout
				(tracks allowed)
				(vias not_allowed)
				(pads allowed)
				(copperpour not_allowed)
				(footprints allowed)
			)
			(placement
				(enabled no)
				(sheetname "")
			)
			(fill
				(thermal_gap 0.5)
				(thermal_bridge_width 0.5)
				(island_removal_mode 0)
			)
			(polygon
				(pts
					(xy 257.1115 -140.6271) (xy 257.1115 -139.6365) (xy 257.6195 -139.6365) (xy 257.6195 -140.6271)
				)
			)
		)
	)
	(footprint ""
		(layer "F.Cu")
		(at 321.16522 -119.26316 -90)
		(property "Reference" "C841"
			(at -0.8382 -0.67818 270)
			(unlocked yes)
			(layer "F.SilkS")
			(effects
				(font
					(size 0.4064 0.254)
					(thickness 0.1524)
				)
				(justify left)
			)
		)
		(property "Value" ""
			(at 0 0 270)
			(layer "F.Fab")
			(effects
				(font
					(size 1.27 1.27)
				)
			)
		)
		(duplicate_pad_numbers_are_jumpers no)
		(fp_poly
			(pts
				(xy 0.3048 -0.1016) (xy 0.3048 0.9906) (xy -0.3048 0.9906) (xy -0.3048 -0.1016)
			)
			(stroke
				(width 0)
				(type default)
			)
			(fill no)
			(layer "F.CrtYd")
		)
		(fp_line
			(start -0.3048 0.9906)
			(end 0.3048 0.9906)
			(stroke
				(width 0.1)
				(type default)
			)
			(layer "F.Fab")
		)
		(fp_line
			(start 0.3048 0.9906)
			(end 0.3048 -0.1016)
			(stroke
				(width 0.1)
				(type default)
			)
			(layer "F.Fab")
		)
		(fp_line
			(start -0.3048 -0.1016)
			(end -0.3048 0.9906)
			(stroke
				(width 0.1)
				(type default)
			)
			(layer "F.Fab")
		)
		(fp_line
			(start 0.3048 -0.1016)
			(end -0.3048 -0.1016)
			(stroke
				(width 0.1)
				(type default)
			)
			(layer "F.Fab")
		)
		(pad "1" smd rect
			(at 0 0 270)
			(size 0.508 0.508)
			(layers "F.Cu" "F.Mask" "F.Paste")
			(net "P3E_CPU0_PE1_PCH_TXP<12>")
		)
		(pad "2" smd rect
			(at 0 0.889 270)
			(size 0.508 0.508)
			(layers "F.Cu" "F.Mask" "F.Paste")
			(net "P3E_CPU0_PE1_PCH_CON_TXP<12>")
		)
		(zone
			(layer "F.Cu")
			(hatch none 0.5)
			(connect_pads
				(clearance 0)
			)
			(min_thickness 0.25)
			(keepout
				(tracks not_allowed)
				(vias allowed)
				(pads allowed)
				(copperpour not_allowed)
				(footprints allowed)
			)
			(placement
				(enabled no)
				(sheetname "")
			)
			(fill
				(thermal_gap 0.5)
				(thermal_bridge_width 0.5)
				(island_removal_mode 0)
			)
			(polygon
				(pts
					(xy 320.53022 -119.51716) (xy 320.53022 -119.00916) (xy 320.91122 -119.00916) (xy 320.91122 -119.51716)
				)
			)
		)
		(zone
			(layer "F.Cu")
			(hatch none 0.5)
			(connect_pads
				(clearance 0)
			)
			(min_thickness 0.25)
			(keepout
				(tracks allowed)
				(vias not_allowed)
				(pads allowed)
				(copperpour not_allowed)
				(footprints allowed)
			)
			(placement
				(enabled no)
				(sheetname "")
			)
			(fill
				(thermal_gap 0.5)
				(thermal_bridge_width 0.5)
				(island_removal_mode 0)
			)
			(polygon
				(pts
					(xy 320.91122 -119.51716) (xy 320.91122 -119.00916) (xy 320.53022 -119.00916) (xy 320.53022 -119.51716)
				)
			)
		)
	)
	(footprint ""
		(layer "F.Cu")
		(at 374.278144 -10.916158)
		(property "Reference" "C7G15"
			(at 0 0 0)
			(layer "F.SilkS")
			(hide yes)
			(effects
				(font
					(size 1.27 1.27)
				)
			)
		)
		(property "Value" ""
			(at 0 0 0)
			(layer "F.Fab")
			(effects
				(font
					(size 1.27 1.27)
				)
			)
		)
		(duplicate_pad_numbers_are_jumpers no)
		(fp_rect
			(start -0.3048 0.9906)
			(end 0.3048 -0.1016)
			(stroke
				(width 0)
				(type default)
			)
			(fill no)
			(layer "F.CrtYd")
		)
		(fp_line
			(start -0.3048 -0.1016)
			(end -0.3048 0.9906)
			(stroke
				(width 0.1)
				(type default)
			)
			(layer "F.Fab")
		)
		(fp_line
			(start -0.3048 0.9906)
			(end 0.3048 0.9906)
			(stroke
				(width 0.1)
				(type default)
			)
			(layer "F.Fab")
		)
		(fp_line
			(start 0.3048 -0.1016)
			(end -0.3048 -0.1016)
			(stroke
				(width 0.1)
				(type default)
			)
			(layer "F.Fab")
		)
		(fp_line
			(start 0.3048 0.9906)
			(end 0.3048 -0.1016)
			(stroke
				(width 0.1)
				(type default)
			)
			(layer "F.Fab")
		)
		(pad "1" smd rect
			(at 0 0)
			(size 0.508 0.508)
			(layers "F.Cu" "F.Mask" "F.Paste")
			(net "P3E_CPU0_PE2_SS_TXP<10>")
		)
		(pad "2" smd rect
			(at 0 0.889)
			(size 0.508 0.508)
			(layers "F.Cu" "F.Mask" "F.Paste")
			(net "P3E_CPU0_PE2_SS_C_TXP<10>")
		)
		(zone
			(layer "F.Cu")
			(hatch none 0.5)
			(connect_pads
				(clearance 0)
			)
			(min_thickness 0.25)
			(keepout
				(tracks allowed)
				(vias not_allowed)
				(pads allowed)
				(copperpour not_allowed)
				(footprints allowed)
			)
			(placement
				(enabled no)
				(sheetname "")
			)
			(fill
				(thermal_gap 0.5)
				(thermal_bridge_width 0.5)
				(island_removal_mode 0)
			)
			(polygon
				(pts
					(xy 374.024144 -10.281158) (xy 374.532144 -10.281158) (xy 374.532144 -10.662158) (xy 374.024144 -10.662158)
				)
			)
		)
		(zone
			(layer "F.Cu")
			(hatch none 0.5)
			(connect_pads
				(clearance 0)
			)
			(min_thickness 0.25)
			(keepout
				(tracks not_allowed)
				(vias allowed)
				(pads allowed)
				(copperpour not_allowed)
				(footprints allowed)
			)
			(placement
				(enabled no)
				(sheetname "")
			)
			(fill
				(thermal_gap 0.5)
				(thermal_bridge_width 0.5)
				(island_removal_mode 0)
			)
			(polygon
				(pts
					(xy 374.024144 -10.281158) (xy 374.532144 -10.281158) (xy 374.532144 -10.662158) (xy 374.024144 -10.662158)
				)
			)
		)
	)
	(footprint ""
		(layer "F.Cu")
		(at 29.965904 -94.604332)
		(property "Reference" "CT57"
			(at -3.37693 1.9304 90)
			(unlocked yes)
			(layer "F.SilkS")
			(effects
				(font
					(size 0.7874 0.5842)
					(thickness 0.1524)
				)
				(justify left)
			)
		)
		(property "Value" ""
			(at 0 0 0)
			(layer "F.Fab")
			(effects
				(font
					(size 1.27 1.27)
				)
			)
		)
		(duplicate_pad_numbers_are_jumpers no)
		(fp_poly
			(pts
				(xy 0.3048 -0.1016) (xy 0.3048 0.9906) (xy -0.3048 0.9906) (xy -0.3048 -0.1016)
			)
			(stroke
				(width 0)
				(type default)
			)
			(fill no)
			(layer "F.CrtYd")
		)
		(fp_line
			(start -0.3048 -0.1016)
			(end -0.3048 0.9906)
			(stroke
				(width 0.1)
				(type default)
			)
			(layer "F.Fab")
		)
		(fp_line
			(start -0.3048 0.9906)
			(end 0.3048 0.9906)
			(stroke
				(width 0.1)
				(type default)
			)
			(layer "F.Fab")
		)
		(fp_line
			(start 0.3048 -0.1016)
			(end -0.3048 -0.1016)
			(stroke
				(width 0.1)
				(type default)
			)
			(layer "F.Fab")
		)
		(fp_line
			(start 0.3048 0.9906)
			(end 0.3048 -0.1016)
			(stroke
				(width 0.1)
				(type default)
			)
			(layer "F.Fab")
		)
		(pad "1" smd rect
			(at 0 0)
			(size 0.508 0.508)
			(layers "F.Cu" "F.Mask" "F.Paste")
			(net "VR_PVSA_CPU1_BIREF1")
		)
		(pad "2" smd rect
			(at 0 0.889)
			(size 0.508 0.508)
			(layers "F.Cu" "F.Mask" "F.Paste")
			(net "GND")
		)
		(zone
			(layer "F.Cu")
			(hatch none 0.5)
			(connect_pads
				(clearance 0)
			)
			(min_thickness 0.25)
			(keepout
				(tracks allowed)
				(vias not_allowed)
				(pads allowed)
				(copperpour not_allowed)
				(footprints allowed)
			)
			(placement
				(enabled no)
				(sheetname "")
			)
			(fill
				(thermal_gap 0.5)
				(thermal_bridge_width 0.5)
				(island_removal_mode 0)
			)
			(polygon
				(pts
					(xy 29.711904 -94.350332) (xy 30.219904 -94.350332) (xy 30.219904 -93.969332) (xy 29.711904 -93.969332)
				)
			)
		)
		(zone
			(layer "F.Cu")
			(hatch none 0.5)
			(connect_pads
				(clearance 0)
			)
			(min_thickness 0.25)
			(keepout
				(tracks not_allowed)
				(vias allowed)
				(pads allowed)
				(copperpour not_allowed)
				(footprints allowed)
			)
			(placement
				(enabled no)
				(sheetname "")
			)
			(fill
				(thermal_gap 0.5)
				(thermal_bridge_width 0.5)
				(island_removal_mode 0)
			)
			(polygon
				(pts
					(xy 29.711904 -93.969332) (xy 30.219904 -93.969332) (xy 30.219904 -94.350332) (xy 29.711904 -94.350332)
				)
			)
		)
	)
	(footprint ""
		(layer "F.Cu")
		(at 181.356 -64.135 180)
		(property "Reference" "R4E5"
			(at 0 0 180)
			(layer "F.SilkS")
			(hide yes)
			(effects
				(font
					(size 1.27 1.27)
				)
			)
		)
		(property "Value" ""
			(at 0 0 180)
			(layer "F.Fab")
			(effects
				(font
					(size 1.27 1.27)
				)
			)
		)
		(duplicate_pad_numbers_are_jumpers no)
		(fp_rect
			(start 0.2794 -0.1016)
			(end -0.2794 0.9906)
			(stroke
				(width 0)
				(type default)
			)
			(fill no)
			(layer "F.CrtYd")
		)
		(fp_line
			(start 0.2794 0.9906)
			(end 0.2794 -0.1016)
			(stroke
				(width 0.1)
				(type default)
			)
			(layer "F.Fab")
		)
		(fp_line
			(start 0.2794 -0.1016)
			(end -0.2794 -0.1016)
			(stroke
				(width 0.1)
				(type default)
			)
			(layer "F.Fab")
		)
		(fp_line
			(start -0.2794 0.9906)
			(end 0.2794 0.9906)
			(stroke
				(width 0.1)
				(type default)
			)
			(layer "F.Fab")
		)
		(fp_line
			(start -0.2794 -0.1016)
			(end -0.2794 0.9906)
			(stroke
				(width 0.1)
				(type default)
			)
			(layer "F.Fab")
		)
		(pad "1" smd rect
			(at 0 0 180)
			(size 0.508 0.508)
			(layers "F.Cu" "F.Mask" "F.Paste")
			(net "P3V3_STBY")
		)
		(pad "2" smd rect
			(at 0 0.889 180)
			(size 0.508 0.508)
			(layers "F.Cu" "F.Mask" "F.Paste")
			(net "PWRGD_PVSA_CPU0_R")
		)
		(zone
			(layer "F.Cu")
			(hatch none 0.5)
			(connect_pads
				(clearance 0)
			)
			(min_thickness 0.25)
			(keepout
				(tracks not_allowed)
				(vias allowed)
				(pads allowed)
				(copperpour not_allowed)
				(footprints allowed)
			)
			(placement
				(enabled no)
				(sheetname "")
			)
			(fill
				(thermal_gap 0.5)
				(thermal_bridge_width 0.5)
				(island_removal_mode 0)
			)
			(polygon
				(pts
					(xy 181.102 -64.389) (xy 181.61 -64.389) (xy 181.61 -64.77) (xy 181.102 -64.77)
				)
			)
		)
		(zone
			(layer "F.Cu")
			(hatch none 0.5)
			(connect_pads
				(clearance 0)
			)
			(min_thickness 0.25)
			(keepout
				(tracks allowed)
				(vias not_allowed)
				(pads allowed)
				(copperpour not_allowed)
				(footprints allowed)
			)
			(placement
				(enabled no)
				(sheetname "")
			)
			(fill
				(thermal_gap 0.5)
				(thermal_bridge_width 0.5)
				(island_removal_mode 0)
			)
			(polygon
				(pts
					(xy 181.102 -64.389) (xy 181.61 -64.389) (xy 181.61 -64.77) (xy 181.102 -64.77)
				)
			)
		)
	)
	(footprint ""
		(layer "F.Cu")
		(at 112.2934 -83.8962)
		(property "Reference" "R3D4"
			(at 0 0 0)
			(layer "F.SilkS")
			(hide yes)
			(effects
				(font
					(size 1.27 1.27)
				)
			)
		)
		(property "Value" ""
			(at 0 0 0)
			(layer "F.Fab")
			(effects
				(font
					(size 1.27 1.27)
				)
			)
		)
		(duplicate_pad_numbers_are_jumpers no)
		(fp_poly
			(pts
				(xy -0.2794 -0.1016) (xy 0.2794 -0.1016) (xy 0.2794 0.9906) (xy -0.2794 0.9906)
			)
			(stroke
				(width 0)
				(type default)
			)
			(fill no)
			(layer "F.CrtYd")
		)
		(fp_line
			(start -0.2794 -0.1016)
			(end -0.2794 0.9906)
			(stroke
				(width 0.1)
				(type default)
			)
			(layer "F.Fab")
		)
		(fp_line
			(start -0.2794 0.9906)
			(end 0.2794 0.9906)
			(stroke
				(width 0.1)
				(type default)
			)
			(layer "F.Fab")
		)
		(fp_line
			(start 0.2794 -0.1016)
			(end -0.2794 -0.1016)
			(stroke
				(width 0.1)
				(type default)
			)
			(layer "F.Fab")
		)
		(fp_line
			(start 0.2794 0.9906)
			(end 0.2794 -0.1016)
			(stroke
				(width 0.1)
				(type default)
			)
			(layer "F.Fab")
		)
		(pad "1" smd rect
			(at 0 0)
			(size 0.508 0.508)
			(layers "F.Cu" "F.Mask" "F.Paste")
			(net "A_CPU1_MCP01_RBIAS")
		)
		(pad "2" smd rect
			(at 0 0.889)
			(size 0.508 0.508)
			(layers "F.Cu" "F.Mask" "F.Paste")
			(net "GND")
		)
		(zone
			(layer "F.Cu")
			(hatch none 0.5)
			(connect_pads
				(clearance 0)
			)
			(min_thickness 0.25)
			(keepout
				(tracks allowed)
				(vias not_allowed)
				(pads allowed)
				(copperpour not_allowed)
				(footprints allowed)
			)
			(placement
				(enabled no)
				(sheetname "")
			)
			(fill
				(thermal_gap 0.5)
				(thermal_bridge_width 0.5)
				(island_removal_mode 0)
			)
			(polygon
				(pts
					(xy 112.0394 -83.6422) (xy 112.5474 -83.6422) (xy 112.5474 -83.2612) (xy 112.0394 -83.2612)
				)
			)
		)
		(zone
			(layer "F.Cu")
			(hatch none 0.5)
			(connect_pads
				(clearance 0)
			)
			(min_thickness 0.25)
			(keepout
				(tracks not_allowed)
				(vias allowed)
				(pads allowed)
				(copperpour not_allowed)
				(footprints allowed)
			)
			(placement
				(enabled no)
				(sheetname "")
			)
			(fill
				(thermal_gap 0.5)
				(thermal_bridge_width 0.5)
				(island_removal_mode 0)
			)
			(polygon
				(pts
					(xy 112.0394 -83.2612) (xy 112.5474 -83.2612) (xy 112.5474 -83.6422) (xy 112.0394 -83.6422)
				)
			)
		)
	)
	(footprint ""
		(layer "F.Cu")
		(at 260.697472 -81.573116)
		(property "Reference" "C5D12"
			(at 0 0 0)
			(layer "F.SilkS")
			(hide yes)
			(effects
				(font
					(size 1.27 1.27)
				)
			)
		)
		(property "Value" ""
			(at 0 0 0)
			(layer "F.Fab")
			(effects
				(font
					(size 1.27 1.27)
				)
			)
		)
		(duplicate_pad_numbers_are_jumpers no)
		(fp_poly
			(pts
				(xy -0.4953 -0.2032) (xy 0.4953 -0.2032) (xy 0.4953 1.6002) (xy -0.4953 1.6002)
			)
			(stroke
				(width 0)
				(type default)
			)
			(fill no)
			(layer "F.CrtYd")
		)
		(fp_line
			(start -0.4953 -0.2032)
			(end 0.4953 -0.2032)
			(stroke
				(width 0.1)
				(type default)
			)
			(layer "F.Fab")
		)
		(fp_line
			(start -0.4953 1.6002)
			(end -0.4953 -0.2032)
			(stroke
				(width 0.1)
				(type default)
			)
			(layer "F.Fab")
		)
		(fp_line
			(start 0.4953 -0.2032)
			(end 0.4953 1.6002)
			(stroke
				(width 0.1)
				(type default)
			)
			(layer "F.Fab")
		)
		(fp_line
			(start 0.4953 1.6002)
			(end -0.4953 1.6002)
			(stroke
				(width 0.1)
				(type default)
			)
			(layer "F.Fab")
		)
		(pad "1" smd rect
			(at 0 0)
			(size 0.762 0.889)
			(layers "F.Cu" "F.Mask" "F.Paste")
			(net "PVSA_CPU0")
		)
		(pad "2" smd rect
			(at 0 1.397)
			(size 0.762 0.889)
			(layers "F.Cu" "F.Mask" "F.Paste")
			(net "GND")
		)
		(zone
			(layer "F.Cu")
			(hatch none 0.5)
			(connect_pads
				(clearance 0)
			)
			(min_thickness 0.25)
			(keepout
				(tracks not_allowed)
				(vias allowed)
				(pads allowed)
				(copperpour not_allowed)
				(footprints allowed)
			)
			(placement
				(enabled no)
				(sheetname "")
			)
			(fill
				(thermal_gap 0.5)
				(thermal_bridge_width 0.5)
				(island_removal_mode 0)
			)
			(polygon
				(pts
					(xy 260.316472 -81.128616) (xy 261.078472 -81.128616) (xy 261.078472 -80.620616) (xy 260.316472 -80.620616)
				)
			)
		)
	)
	(footprint ""
		(layer "F.Cu")
		(at 393.827 -87.3125 180)
		(property "Reference" "R8D14"
			(at 0 0 180)
			(layer "F.SilkS")
			(hide yes)
			(effects
				(font
					(size 1.27 1.27)
				)
			)
		)
		(property "Value" ""
			(at 0 0 180)
			(layer "F.Fab")
			(effects
				(font
					(size 1.27 1.27)
				)
			)
		)
		(duplicate_pad_numbers_are_jumpers no)
		(fp_poly
			(pts
				(xy -0.2794 -0.1016) (xy 0.2794 -0.1016) (xy 0.2794 0.9906) (xy -0.2794 0.9906)
			)
			(stroke
				(width 0)
				(type default)
			)
			(fill no)
			(layer "F.CrtYd")
		)
		(fp_line
			(start 0.2794 0.9906)
			(end 0.2794 -0.1016)
			(stroke
				(width 0.1)
				(type default)
			)
			(layer "F.Fab")
		)
		(fp_line
			(start 0.2794 -0.1016)
			(end -0.2794 -0.1016)
			(stroke
				(width 0.1)
				(type default)
			)
			(layer "F.Fab")
		)
		(fp_line
			(start -0.2794 0.9906)
			(end 0.2794 0.9906)
			(stroke
				(width 0.1)
				(type default)
			)
			(layer "F.Fab")
		)
		(fp_line
			(start -0.2794 -0.1016)
			(end -0.2794 0.9906)
			(stroke
				(width 0.1)
				(type default)
			)
			(layer "F.Fab")
		)
		(pad "1" smd rect
			(at 0 0 180)
			(size 0.508 0.508)
			(layers "F.Cu" "F.Mask" "F.Paste")
			(net "P3V3_STBY")
		)
		(pad "2" smd rect
			(at 0 0.889 180)
			(size 0.508 0.508)
			(layers "F.Cu" "F.Mask" "F.Paste")
			(net "FP_PWR_ID_LED_N")
		)
		(zone
			(layer "F.Cu")
			(hatch none 0.5)
			(connect_pads
				(clearance 0)
			)
			(min_thickness 0.25)
			(keepout
				(tracks not_allowed)
				(vias allowed)
				(pads allowed)
				(copperpour not_allowed)
				(footprints allowed)
			)
			(placement
				(enabled no)
				(sheetname "")
			)
			(fill
				(thermal_gap 0.5)
				(thermal_bridge_width 0.5)
				(island_removal_mode 0)
			)
			(polygon
				(pts
					(xy 394.081 -87.9475) (xy 393.573 -87.9475) (xy 393.573 -87.5665) (xy 394.081 -87.5665)
				)
			)
		)
		(zone
			(layer "F.Cu")
			(hatch none 0.5)
			(connect_pads
				(clearance 0)
			)
			(min_thickness 0.25)
			(keepout
				(tracks allowed)
				(vias not_allowed)
				(pads allowed)
				(copperpour not_allowed)
				(footprints allowed)
			)
			(placement
				(enabled no)
				(sheetname "")
			)
			(fill
				(thermal_gap 0.5)
				(thermal_bridge_width 0.5)
				(island_removal_mode 0)
			)
			(polygon
				(pts
					(xy 394.081 -87.5665) (xy 393.573 -87.5665) (xy 393.573 -87.9475) (xy 394.081 -87.9475)
				)
			)
		)
	)
	(footprint ""
		(layer "F.Cu")
		(at 388.366 -87.3125 180)
		(property "Reference" "R3P3"
			(at 0 0 180)
			(layer "F.SilkS")
			(hide yes)
			(effects
				(font
					(size 1.27 1.27)
				)
			)
		)
		(property "Value" ""
			(at 0 0 180)
			(layer "F.Fab")
			(effects
				(font
					(size 1.27 1.27)
				)
			)
		)
		(duplicate_pad_numbers_are_jumpers no)
		(fp_poly
			(pts
				(xy -0.2794 -0.1016) (xy 0.2794 -0.1016) (xy 0.2794 0.9906) (xy -0.2794 0.9906)
			)
			(stroke
				(width 0)
				(type default)
			)
			(fill no)
			(layer "F.CrtYd")
		)
		(fp_line
			(start 0.2794 0.9906)
			(end 0.2794 -0.1016)
			(stroke
				(width 0.1)
				(type default)
			)
			(layer "F.Fab")
		)
		(fp_line
			(start 0.2794 -0.1016)
			(end -0.2794 -0.1016)
			(stroke
				(width 0.1)
				(type default)
			)
			(layer "F.Fab")
		)
		(fp_line
			(start -0.2794 0.9906)
			(end 0.2794 0.9906)
			(stroke
				(width 0.1)
				(type default)
			)
			(layer "F.Fab")
		)
		(fp_line
			(start -0.2794 -0.1016)
			(end -0.2794 0.9906)
			(stroke
				(width 0.1)
				(type default)
			)
			(layer "F.Fab")
		)
		(pad "1" smd rect
			(at 0 0 180)
			(size 0.508 0.508)
			(layers "F.Cu" "F.Mask" "F.Paste")
			(net "RMII_SPRNGVLLE_BMC_PCH_RXD0")
		)
		(pad "2" smd rect
			(at 0 0.889 180)
			(size 0.508 0.508)
			(layers "F.Cu" "F.Mask" "F.Paste")
			(net "RMII_SPRNGVLLE_BMC_PCH_RXD0_R1")
		)
		(zone
			(layer "F.Cu")
			(hatch none 0.5)
			(connect_pads
				(clearance 0)
			)
			(min_thickness 0.25)
			(keepout
				(tracks not_allowed)
				(vias allowed)
				(pads allowed)
				(copperpour not_allowed)
				(footprints allowed)
			)
			(placement
				(enabled no)
				(sheetname "")
			)
			(fill
				(thermal_gap 0.5)
				(thermal_bridge_width 0.5)
				(island_removal_mode 0)
			)
			(polygon
				(pts
					(xy 388.62 -87.9475) (xy 388.112 -87.9475) (xy 388.112 -87.5665) (xy 388.62 -87.5665)
				)
			)
		)
		(zone
			(layer "F.Cu")
			(hatch none 0.5)
			(connect_pads
				(clearance 0)
			)
			(min_thickness 0.25)
			(keepout
				(tracks allowed)
				(vias not_allowed)
				(pads allowed)
				(copperpour not_allowed)
				(footprints allowed)
			)
			(placement
				(enabled no)
				(sheetname "")
			)
			(fill
				(thermal_gap 0.5)
				(thermal_bridge_width 0.5)
				(island_removal_mode 0)
			)
			(polygon
				(pts
					(xy 388.62 -87.5665) (xy 388.112 -87.5665) (xy 388.112 -87.9475) (xy 388.62 -87.9475)
				)
			)
		)
	)
	(footprint ""
		(layer "F.Cu")
		(at 401.955 -24.892)
		(property "Reference" "R25W151"
			(at -0.8382 -0.67818 0)
			(unlocked yes)
			(layer "F.SilkS")
			(effects
				(font
					(size 0.4064 0.254)
					(thickness 0.1524)
				)
				(justify left)
			)
		)
		(property "Value" ""
			(at 0 0 0)
			(layer "F.Fab")
			(effects
				(font
					(size 1.27 1.27)
				)
			)
		)
		(duplicate_pad_numbers_are_jumpers no)
		(fp_poly
			(pts
				(xy -0.2794 -0.1016) (xy 0.2794 -0.1016) (xy 0.2794 0.9906) (xy -0.2794 0.9906)
			)
			(stroke
				(width 0)
				(type default)
			)
			(fill no)
			(layer "F.CrtYd")
		)
		(fp_line
			(start -0.2794 -0.1016)
			(end -0.2794 0.9906)
			(stroke
				(width 0.1)
				(type default)
			)
			(layer "F.Fab")
		)
		(fp_line
			(start -0.2794 0.9906)
			(end 0.2794 0.9906)
			(stroke
				(width 0.1)
				(type default)
			)
			(layer "F.Fab")
		)
		(fp_line
			(start 0.2794 -0.1016)
			(end -0.2794 -0.1016)
			(stroke
				(width 0.1)
				(type default)
			)
			(layer "F.Fab")
		)
		(fp_line
			(start 0.2794 0.9906)
			(end 0.2794 -0.1016)
			(stroke
				(width 0.1)
				(type default)
			)
			(layer "F.Fab")
		)
		(pad "1" smd rect
			(at 0 0)
			(size 0.508 0.508)
			(layers "F.Cu" "F.Mask" "F.Paste")
			(net "GND")
		)
		(pad "2" smd rect
			(at 0 0.889)
			(size 0.508 0.508)
			(layers "F.Cu" "F.Mask" "F.Paste")
			(net "RMII_BMC_PCH_SPRNGVLLE_TXD1_R")
		)
		(zone
			(layer "F.Cu")
			(hatch none 0.5)
			(connect_pads
				(clearance 0)
			)
			(min_thickness 0.25)
			(keepout
				(tracks allowed)
				(vias not_allowed)
				(pads allowed)
				(copperpour not_allowed)
				(footprints allowed)
			)
			(placement
				(enabled no)
				(sheetname "")
			)
			(fill
				(thermal_gap 0.5)
				(thermal_bridge_width 0.5)
				(island_removal_mode 0)
			)
			(polygon
				(pts
					(xy 401.701 -24.638) (xy 402.209 -24.638) (xy 402.209 -24.257) (xy 401.701 -24.257)
				)
			)
		)
		(zone
			(layer "F.Cu")
			(hatch none 0.5)
			(connect_pads
				(clearance 0)
			)
			(min_thickness 0.25)
			(keepout
				(tracks not_allowed)
				(vias allowed)
				(pads allowed)
				(copperpour not_allowed)
				(footprints allowed)
			)
			(placement
				(enabled no)
				(sheetname "")
			)
			(fill
				(thermal_gap 0.5)
				(thermal_bridge_width 0.5)
				(island_removal_mode 0)
			)
			(polygon
				(pts
					(xy 401.701 -24.257) (xy 402.209 -24.257) (xy 402.209 -24.638) (xy 401.701 -24.638)
				)
			)
		)
	)
	(footprint ""
		(layer "F.Cu")
		(at 33.243012 -60.376308 90)
		(property "Reference" "C1E14"
			(at 0 0 90)
			(layer "F.SilkS")
			(hide yes)
			(effects
				(font
					(size 1.27 1.27)
				)
			)
		)
		(property "Value" ""
			(at 0 0 90)
			(layer "F.Fab")
			(effects
				(font
					(size 1.27 1.27)
				)
			)
		)
		(duplicate_pad_numbers_are_jumpers no)
		(fp_rect
			(start 0.3048 0.9906)
			(end -0.3048 -0.1016)
			(stroke
				(width 0)
				(type default)
			)
			(fill no)
			(layer "F.CrtYd")
		)
		(fp_line
			(start 0.3048 -0.1016)
			(end -0.3048 -0.1016)
			(stroke
				(width 0.1)
				(type default)
			)
			(layer "F.Fab")
		)
		(fp_line
			(start -0.3048 -0.1016)
			(end -0.3048 0.9906)
			(stroke
				(width 0.1)
				(type default)
			)
			(layer "F.Fab")
		)
		(fp_line
			(start 0.3048 0.9906)
			(end 0.3048 -0.1016)
			(stroke
				(width 0.1)
				(type default)
			)
			(layer "F.Fab")
		)
		(fp_line
			(start -0.3048 0.9906)
			(end 0.3048 0.9906)
			(stroke
				(width 0.1)
				(type default)
			)
			(layer "F.Fab")
		)
		(pad "1" smd rect
			(at 0 0 90)
			(size 0.508 0.508)
			(layers "F.Cu" "F.Mask" "F.Paste")
			(net "VR_FET_SW_P12V_STBY_PVCCIN_CPU1")
		)
		(pad "2" smd rect
			(at 0 0.889 90)
			(size 0.508 0.508)
			(layers "F.Cu" "F.Mask" "F.Paste")
			(net "GND")
		)
		(zone
			(layer "F.Cu")
			(hatch none 0.5)
			(connect_pads
				(clearance 0)
			)
			(min_thickness 0.25)
			(keepout
				(tracks not_allowed)
				(vias allowed)
				(pads allowed)
				(copperpour not_allowed)
				(footprints allowed)
			)
			(placement
				(enabled no)
				(sheetname "")
			)
			(fill
				(thermal_gap 0.5)
				(thermal_bridge_width 0.5)
				(island_removal_mode 0)
			)
			(polygon
				(pts
					(xy 33.878012 -60.630308) (xy 33.497012 -60.630308) (xy 33.497012 -60.122308) (xy 33.878012 -60.122308)
				)
			)
		)
		(zone
			(layer "F.Cu")
			(hatch none 0.5)
			(connect_pads
				(clearance 0)
			)
			(min_thickness 0.25)
			(keepout
				(tracks allowed)
				(vias not_allowed)
				(pads allowed)
				(copperpour not_allowed)
				(footprints allowed)
			)
			(placement
				(enabled no)
				(sheetname "")
			)
			(fill
				(thermal_gap 0.5)
				(thermal_bridge_width 0.5)
				(island_removal_mode 0)
			)
			(polygon
				(pts
					(xy 33.878012 -60.630308) (xy 33.497012 -60.630308) (xy 33.497012 -60.122308) (xy 33.878012 -60.122308)
				)
			)
		)
	)
	(footprint ""
		(layer "F.Cu")
		(at 447.548 -20.2565)
		(property "Reference" "R1W9"
			(at -0.8382 -0.67818 0)
			(unlocked yes)
			(layer "F.SilkS")
			(effects
				(font
					(size 0.4064 0.254)
					(thickness 0.1524)
				)
				(justify left)
			)
		)
		(property "Value" ""
			(at 0 0 0)
			(layer "F.Fab")
			(effects
				(font
					(size 1.27 1.27)
				)
			)
		)
		(duplicate_pad_numbers_are_jumpers no)
		(fp_poly
			(pts
				(xy -0.2794 -0.1016) (xy 0.2794 -0.1016) (xy 0.2794 0.9906) (xy -0.2794 0.9906)
			)
			(stroke
				(width 0)
				(type default)
			)
			(fill no)
			(layer "F.CrtYd")
		)
		(fp_line
			(start -0.2794 -0.1016)
			(end -0.2794 0.9906)
			(stroke
				(width 0.1)
				(type default)
			)
			(layer "F.Fab")
		)
		(fp_line
			(start -0.2794 0.9906)
			(end 0.2794 0.9906)
			(stroke
				(width 0.1)
				(type default)
			)
			(layer "F.Fab")
		)
		(fp_line
			(start 0.2794 -0.1016)
			(end -0.2794 -0.1016)
			(stroke
				(width 0.1)
				(type default)
			)
			(layer "F.Fab")
		)
		(fp_line
			(start 0.2794 0.9906)
			(end 0.2794 -0.1016)
			(stroke
				(width 0.1)
				(type default)
			)
			(layer "F.Fab")
		)
		(pad "1" smd rect
			(at 0 0)
			(size 0.508 0.508)
			(layers "F.Cu" "F.Mask" "F.Paste")
			(net "PWRGD_P2V5_BMC_STBY_R")
		)
		(pad "2" smd rect
			(at 0 0.889)
			(size 0.508 0.508)
			(layers "F.Cu" "F.Mask" "F.Paste")
			(net "PWRGD_P2V5_BMC_STBY")
		)
		(zone
			(layer "F.Cu")
			(hatch none 0.5)
			(connect_pads
				(clearance 0)
			)
			(min_thickness 0.25)
			(keepout
				(tracks allowed)
				(vias not_allowed)
				(pads allowed)
				(copperpour not_allowed)
				(footprints allowed)
			)
			(placement
				(enabled no)
				(sheetname "")
			)
			(fill
				(thermal_gap 0.5)
				(thermal_bridge_width 0.5)
				(island_removal_mode 0)
			)
			(polygon
				(pts
					(xy 447.294 -20.0025) (xy 447.802 -20.0025) (xy 447.802 -19.6215) (xy 447.294 -19.6215)
				)
			)
		)
		(zone
			(layer "F.Cu")
			(hatch none 0.5)
			(connect_pads
				(clearance 0)
			)
			(min_thickness 0.25)
			(keepout
				(tracks not_allowed)
				(vias allowed)
				(pads allowed)
				(copperpour not_allowed)
				(footprints allowed)
			)
			(placement
				(enabled no)
				(sheetname "")
			)
			(fill
				(thermal_gap 0.5)
				(thermal_bridge_width 0.5)
				(island_removal_mode 0)
			)
			(polygon
				(pts
					(xy 447.294 -19.6215) (xy 447.802 -19.6215) (xy 447.802 -20.0025) (xy 447.294 -20.0025)
				)
			)
		)
	)
	(footprint ""
		(layer "F.Cu")
		(at 7.33298 -128.36779)
		(property "Reference" "R12W20"
			(at 0 0 0)
			(layer "F.SilkS")
			(hide yes)
			(effects
				(font
					(size 1.27 1.27)
				)
			)
		)
		(property "Value" "*"
			(at 0.064008 -4.108196 0)
			(unlocked yes)
			(layer "F.Fab")
			(hide yes)
			(effects
				(font
					(size 1.27 1.016)
					(thickness 0.1524)
				)
			)
		)
		(property "Device Type" "665KR2B-GP_SMD-RG2-665KR2B-GP,A"
			(at 0.064008 -5.632196 0)
			(unlocked yes)
			(layer "F.Fab")
			(hide yes)
			(effects
				(font
					(size 1.27 1.016)
					(thickness 0.1524)
				)
			)
		)
		(duplicate_pad_numbers_are_jumpers no)
		(fp_line
			(start -0.508 -0.9398)
			(end -0.508 0.9398)
			(stroke
				(width 0.1524)
				(type default)
			)
			(layer "F.SilkS")
		)
		(fp_line
			(start 0.508 -0.9398)
			(end -0.508 -0.9398)
			(stroke
				(width 0.1524)
				(type default)
			)
			(layer "F.SilkS")
		)
		(fp_rect
			(start -0.508 0.9398)
			(end 0.508 -0.9398)
			(stroke
				(width 0)
				(type default)
			)
			(fill no)
			(layer "F.CrtYd")
		)
		(fp_rect
			(start -0.508 0.9398)
			(end 0.508 -0.9398)
			(stroke
				(width 0)
				(type default)
			)
			(fill no)
			(layer "F.Fab")
		)
		(pad "1" smd custom
			(at 0 -0.4445)
			(size 0.1397 0.1397)
			(layers "F.Cu" "F.Mask" "F.Paste")
			(net "VR_PVDDQ_KLM_AIINSEN")
			(options
				(clearance outline)
				(anchor circle)
			)
			(primitives
				(gr_poly
					(pts
						(arc
							(start -0.1778 -0.2794)
							(mid -0.249642 -0.249642)
							(end -0.2794 -0.1778)
						)
						(arc
							(start -0.2794 0.1778)
							(mid -0.249642 0.249642)
							(end -0.1778 0.2794)
						)
						(arc
							(start 0.1778 0.2794)
							(mid 0.249642 0.249642)
							(end 0.2794 0.1778)
						)
						(arc
							(start 0.2794 -0.1778)
							(mid 0.249642 -0.249642)
							(end 0.1778 -0.2794)
						)
					)
					(width 0)
					(fill yes)
				)
			)
		)
		(pad "2" smd custom
			(at 0 0.4445)
			(size 0.1397 0.1397)
			(layers "F.Cu" "F.Mask" "F.Paste")
			(net "VR_PVDDQ_KLM_VINSEN")
			(options
				(clearance outline)
				(anchor circle)
			)
			(primitives
				(gr_poly
					(pts
						(arc
							(start -0.1778 -0.2794)
							(mid -0.249642 -0.249642)
							(end -0.2794 -0.1778)
						)
						(arc
							(start -0.2794 0.1778)
							(mid -0.249642 0.249642)
							(end -0.1778 0.2794)
						)
						(arc
							(start 0.1778 0.2794)
							(mid 0.249642 0.249642)
							(end 0.2794 0.1778)
						)
						(arc
							(start 0.2794 -0.1778)
							(mid 0.249642 -0.249642)
							(end 0.1778 -0.2794)
						)
					)
					(width 0)
					(fill yes)
				)
			)
		)
	)
	(footprint ""
		(layer "F.Cu")
		(at 411.115256 -56.50484 -90)
		(property "Reference" "R8D24"
			(at 0 0 270)
			(layer "F.SilkS")
			(hide yes)
			(effects
				(font
					(size 1.27 1.27)
				)
			)
		)
		(property "Value" ""
			(at 0 0 270)
			(layer "F.Fab")
			(effects
				(font
					(size 1.27 1.27)
				)
			)
		)
		(duplicate_pad_numbers_are_jumpers no)
		(fp_poly
			(pts
				(xy -0.2794 -0.1016) (xy 0.2794 -0.1016) (xy 0.2794 0.9906) (xy -0.2794 0.9906)
			)
			(stroke
				(width 0)
				(type default)
			)
			(fill no)
			(layer "F.CrtYd")
		)
		(fp_line
			(start -0.2794 0.9906)
			(end 0.2794 0.9906)
			(stroke
				(width 0.1)
				(type default)
			)
			(layer "F.Fab")
		)
		(fp_line
			(start 0.2794 0.9906)
			(end 0.2794 -0.1016)
			(stroke
				(width 0.1)
				(type default)
			)
			(layer "F.Fab")
		)
		(fp_line
			(start -0.2794 -0.1016)
			(end -0.2794 0.9906)
			(stroke
				(width 0.1)
				(type default)
			)
			(layer "F.Fab")
		)
		(fp_line
			(start 0.2794 -0.1016)
			(end -0.2794 -0.1016)
			(stroke
				(width 0.1)
				(type default)
			)
			(layer "F.Fab")
		)
		(pad "1" smd rect
			(at 0 0 270)
			(size 0.508 0.508)
			(layers "F.Cu" "F.Mask" "F.Paste")
			(net "SMB_SENSOR_STBY_LVC3_SCL")
		)
		(pad "2" smd rect
			(at 0 0.889 270)
			(size 0.508 0.508)
			(layers "F.Cu" "F.Mask" "F.Paste")
			(net "SMB_SENSOR_STBY_LVC3_SCL_R2")
		)
		(zone
			(layer "F.Cu")
			(hatch none 0.5)
			(connect_pads
				(clearance 0)
			)
			(min_thickness 0.25)
			(keepout
				(tracks not_allowed)
				(vias allowed)
				(pads allowed)
				(copperpour not_allowed)
				(footprints allowed)
			)
			(placement
				(enabled no)
				(sheetname "")
			)
			(fill
				(thermal_gap 0.5)
				(thermal_bridge_width 0.5)
				(island_removal_mode 0)
			)
			(polygon
				(pts
					(xy 410.480256 -56.75884) (xy 410.480256 -56.25084) (xy 410.861256 -56.25084) (xy 410.861256 -56.75884)
				)
			)
		)
		(zone
			(layer "F.Cu")
			(hatch none 0.5)
			(connect_pads
				(clearance 0)
			)
			(min_thickness 0.25)
			(keepout
				(tracks allowed)
				(vias not_allowed)
				(pads allowed)
				(copperpour not_allowed)
				(footprints allowed)
			)
			(placement
				(enabled no)
				(sheetname "")
			)
			(fill
				(thermal_gap 0.5)
				(thermal_bridge_width 0.5)
				(island_removal_mode 0)
			)
			(polygon
				(pts
					(xy 410.861256 -56.75884) (xy 410.861256 -56.25084) (xy 410.480256 -56.25084) (xy 410.480256 -56.75884)
				)
			)
		)
	)
	(footprint ""
		(layer "F.Cu")
		(at 467.257892 -26.665936)
		(property "Reference" "R8E31"
			(at 0 0 0)
			(layer "F.SilkS")
			(hide yes)
			(effects
				(font
					(size 1.27 1.27)
				)
			)
		)
		(property "Value" ""
			(at 0 0 0)
			(layer "F.Fab")
			(effects
				(font
					(size 1.27 1.27)
				)
			)
		)
		(duplicate_pad_numbers_are_jumpers no)
		(fp_rect
			(start -0.2794 0.9906)
			(end 0.2794 -0.1016)
			(stroke
				(width 0)
				(type default)
			)
			(fill no)
			(layer "F.CrtYd")
		)
		(fp_line
			(start -0.2794 -0.1016)
			(end -0.2794 0.9906)
			(stroke
				(width 0.1)
				(type default)
			)
			(layer "F.Fab")
		)
		(fp_line
			(start -0.2794 0.9906)
			(end 0.2794 0.9906)
			(stroke
				(width 0.1)
				(type default)
			)
			(layer "F.Fab")
		)
		(fp_line
			(start 0.2794 -0.1016)
			(end -0.2794 -0.1016)
			(stroke
				(width 0.1)
				(type default)
			)
			(layer "F.Fab")
		)
		(fp_line
			(start 0.2794 0.9906)
			(end 0.2794 -0.1016)
			(stroke
				(width 0.1)
				(type default)
			)
			(layer "F.Fab")
		)
		(pad "1" smd rect
			(at 0 0)
			(size 0.508 0.508)
			(layers "F.Cu" "F.Mask" "F.Paste")
			(net "VSENSE_P3V3_STBY")
		)
		(pad "2" smd rect
			(at 0 0.889)
			(size 0.508 0.508)
			(layers "F.Cu" "F.Mask" "F.Paste")
			(net "VSENSE_VOUT_P3V3_STBY")
		)
		(zone
			(layer "F.Cu")
			(hatch none 0.5)
			(connect_pads
				(clearance 0)
			)
			(min_thickness 0.25)
			(keepout
				(tracks allowed)
				(vias not_allowed)
				(pads allowed)
				(copperpour not_allowed)
				(footprints allowed)
			)
			(placement
				(enabled no)
				(sheetname "")
			)
			(fill
				(thermal_gap 0.5)
				(thermal_bridge_width 0.5)
				(island_removal_mode 0)
			)
			(polygon
				(pts
					(xy 467.003892 -26.030936) (xy 467.511892 -26.030936) (xy 467.511892 -26.411936) (xy 467.003892 -26.411936)
				)
			)
		)
		(zone
			(layer "F.Cu")
			(hatch none 0.5)
			(connect_pads
				(clearance 0)
			)
			(min_thickness 0.25)
			(keepout
				(tracks not_allowed)
				(vias allowed)
				(pads allowed)
				(copperpour not_allowed)
				(footprints allowed)
			)
			(placement
				(enabled no)
				(sheetname "")
			)
			(fill
				(thermal_gap 0.5)
				(thermal_bridge_width 0.5)
				(island_removal_mode 0)
			)
			(polygon
				(pts
					(xy 467.003892 -26.030936) (xy 467.511892 -26.030936) (xy 467.511892 -26.411936) (xy 467.003892 -26.411936)
				)
			)
		)
	)
	(footprint ""
		(layer "F.Cu")
		(at 323.0245 -118.415816 90)
		(property "Reference" "C6B13"
			(at -0.8382 -0.67818 90)
			(unlocked yes)
			(layer "F.SilkS")
			(effects
				(font
					(size 0.4064 0.254)
					(thickness 0.1524)
				)
				(justify left)
			)
		)
		(property "Value" ""
			(at 0 0 90)
			(layer "F.Fab")
			(effects
				(font
					(size 1.27 1.27)
				)
			)
		)
		(duplicate_pad_numbers_are_jumpers no)
		(fp_poly
			(pts
				(xy 0.3048 -0.1016) (xy 0.3048 0.9906) (xy -0.3048 0.9906) (xy -0.3048 -0.1016)
			)
			(stroke
				(width 0)
				(type default)
			)
			(fill no)
			(layer "F.CrtYd")
		)
		(fp_line
			(start 0.3048 -0.1016)
			(end -0.3048 -0.1016)
			(stroke
				(width 0.1)
				(type default)
			)
			(layer "F.Fab")
		)
		(fp_line
			(start -0.3048 -0.1016)
			(end -0.3048 0.9906)
			(stroke
				(width 0.1)
				(type default)
			)
			(layer "F.Fab")
		)
		(fp_line
			(start 0.3048 0.9906)
			(end 0.3048 -0.1016)
			(stroke
				(width 0.1)
				(type default)
			)
			(layer "F.Fab")
		)
		(fp_line
			(start -0.3048 0.9906)
			(end 0.3048 0.9906)
			(stroke
				(width 0.1)
				(type default)
			)
			(layer "F.Fab")
		)
		(pad "1" smd rect
			(at 0 0 90)
			(size 0.508 0.508)
			(layers "F.Cu" "F.Mask" "F.Paste")
			(net "P3E_CPU0_PE1_PCH_TXP<11>")
		)
		(pad "2" smd rect
			(at 0 0.889 90)
			(size 0.508 0.508)
			(layers "F.Cu" "F.Mask" "F.Paste")
			(net "P3E_CPU0_PE1_PCH_C_TXP<11>")
		)
		(zone
			(layer "F.Cu")
			(hatch none 0.5)
			(connect_pads
				(clearance 0)
			)
			(min_thickness 0.25)
			(keepout
				(tracks allowed)
				(vias not_allowed)
				(pads allowed)
				(copperpour not_allowed)
				(footprints allowed)
			)
			(placement
				(enabled no)
				(sheetname "")
			)
			(fill
				(thermal_gap 0.5)
				(thermal_bridge_width 0.5)
				(island_removal_mode 0)
			)
			(polygon
				(pts
					(xy 323.2785 -118.161816) (xy 323.2785 -118.669816) (xy 323.6595 -118.669816) (xy 323.6595 -118.161816)
				)
			)
		)
		(zone
			(layer "F.Cu")
			(hatch none 0.5)
			(connect_pads
				(clearance 0)
			)
			(min_thickness 0.25)
			(keepout
				(tracks not_allowed)
				(vias allowed)
				(pads allowed)
				(copperpour not_allowed)
				(footprints allowed)
			)
			(placement
				(enabled no)
				(sheetname "")
			)
			(fill
				(thermal_gap 0.5)
				(thermal_bridge_width 0.5)
				(island_removal_mode 0)
			)
			(polygon
				(pts
					(xy 323.6595 -118.161816) (xy 323.6595 -118.669816) (xy 323.2785 -118.669816) (xy 323.2785 -118.161816)
				)
			)
		)
	)
	(footprint ""
		(layer "F.Cu")
		(at 416.511994 -47.828962 180)
		(property "Reference" "R25W64"
			(at -0.8382 -0.67818 180)
			(unlocked yes)
			(layer "F.SilkS")
			(effects
				(font
					(size 0.4064 0.254)
					(thickness 0.1524)
				)
				(justify left)
			)
		)
		(property "Value" ""
			(at 0 0 180)
			(layer "F.Fab")
			(effects
				(font
					(size 1.27 1.27)
				)
			)
		)
		(duplicate_pad_numbers_are_jumpers no)
		(fp_poly
			(pts
				(xy -0.2794 -0.1016) (xy 0.2794 -0.1016) (xy 0.2794 0.9906) (xy -0.2794 0.9906)
			)
			(stroke
				(width 0)
				(type default)
			)
			(fill no)
			(layer "F.CrtYd")
		)
		(fp_line
			(start 0.2794 0.9906)
			(end 0.2794 -0.1016)
			(stroke
				(width 0.1)
				(type default)
			)
			(layer "F.Fab")
		)
		(fp_line
			(start 0.2794 -0.1016)
			(end -0.2794 -0.1016)
			(stroke
				(width 0.1)
				(type default)
			)
			(layer "F.Fab")
		)
		(fp_line
			(start -0.2794 0.9906)
			(end 0.2794 0.9906)
			(stroke
				(width 0.1)
				(type default)
			)
			(layer "F.Fab")
		)
		(fp_line
			(start -0.2794 -0.1016)
			(end -0.2794 0.9906)
			(stroke
				(width 0.1)
				(type default)
			)
			(layer "F.Fab")
		)
		(pad "1" smd rect
			(at 0 0 180)
			(size 0.508 0.508)
			(layers "F.Cu" "F.Mask" "F.Paste")
			(net "P2E_SSB_BMC_TX_C_DP")
		)
		(pad "2" smd rect
			(at 0 0.889 180)
			(size 0.508 0.508)
			(layers "F.Cu" "F.Mask" "F.Paste")
			(net "GND")
		)
		(zone
			(layer "F.Cu")
			(hatch none 0.5)
			(connect_pads
				(clearance 0)
			)
			(min_thickness 0.25)
			(keepout
				(tracks not_allowed)
				(vias allowed)
				(pads allowed)
				(copperpour not_allowed)
				(footprints allowed)
			)
			(placement
				(enabled no)
				(sheetname "")
			)
			(fill
				(thermal_gap 0.5)
				(thermal_bridge_width 0.5)
				(island_removal_mode 0)
			)
			(polygon
				(pts
					(xy 416.765994 -48.463962) (xy 416.257994 -48.463962) (xy 416.257994 -48.082962) (xy 416.765994 -48.082962)
				)
			)
		)
		(zone
			(layer "F.Cu")
			(hatch none 0.5)
			(connect_pads
				(clearance 0)
			)
			(min_thickness 0.25)
			(keepout
				(tracks allowed)
				(vias not_allowed)
				(pads allowed)
				(copperpour not_allowed)
				(footprints allowed)
			)
			(placement
				(enabled no)
				(sheetname "")
			)
			(fill
				(thermal_gap 0.5)
				(thermal_bridge_width 0.5)
				(island_removal_mode 0)
			)
			(polygon
				(pts
					(xy 416.765994 -48.082962) (xy 416.257994 -48.082962) (xy 416.257994 -48.463962) (xy 416.765994 -48.463962)
				)
			)
		)
	)
	(footprint ""
		(layer "F.Cu")
		(at 320.6115 -124.587 -90)
		(property "Reference" "C830"
			(at -0.8382 -0.67818 270)
			(unlocked yes)
			(layer "F.SilkS")
			(effects
				(font
					(size 0.4064 0.254)
					(thickness 0.1524)
				)
				(justify left)
			)
		)
		(property "Value" ""
			(at 0 0 270)
			(layer "F.Fab")
			(effects
				(font
					(size 1.27 1.27)
				)
			)
		)
		(duplicate_pad_numbers_are_jumpers no)
		(fp_poly
			(pts
				(xy 0.3048 -0.1016) (xy 0.3048 0.9906) (xy -0.3048 0.9906) (xy -0.3048 -0.1016)
			)
			(stroke
				(width 0)
				(type default)
			)
			(fill no)
			(layer "F.CrtYd")
		)
		(fp_line
			(start -0.3048 0.9906)
			(end 0.3048 0.9906)
			(stroke
				(width 0.1)
				(type default)
			)
			(layer "F.Fab")
		)
		(fp_line
			(start 0.3048 0.9906)
			(end 0.3048 -0.1016)
			(stroke
				(width 0.1)
				(type default)
			)
			(layer "F.Fab")
		)
		(fp_line
			(start -0.3048 -0.1016)
			(end -0.3048 0.9906)
			(stroke
				(width 0.1)
				(type default)
			)
			(layer "F.Fab")
		)
		(fp_line
			(start 0.3048 -0.1016)
			(end -0.3048 -0.1016)
			(stroke
				(width 0.1)
				(type default)
			)
			(layer "F.Fab")
		)
		(pad "1" smd rect
			(at 0 0 270)
			(size 0.508 0.508)
			(layers "F.Cu" "F.Mask" "F.Paste")
			(net "P3E_CPU0_PE1_PCH_TXN<15>")
		)
		(pad "2" smd rect
			(at 0 0.889 270)
			(size 0.508 0.508)
			(layers "F.Cu" "F.Mask" "F.Paste")
			(net "P3E_CPU0_PE1_PCH_CON_TXN<15>")
		)
		(zone
			(layer "F.Cu")
			(hatch none 0.5)
			(connect_pads
				(clearance 0)
			)
			(min_thickness 0.25)
			(keepout
				(tracks not_allowed)
				(vias allowed)
				(pads allowed)
				(copperpour not_allowed)
				(footprints allowed)
			)
			(placement
				(enabled no)
				(sheetname "")
			)
			(fill
				(thermal_gap 0.5)
				(thermal_bridge_width 0.5)
				(island_removal_mode 0)
			)
			(polygon
				(pts
					(xy 319.9765 -124.841) (xy 319.9765 -124.333) (xy 320.3575 -124.333) (xy 320.3575 -124.841)
				)
			)
		)
		(zone
			(layer "F.Cu")
			(hatch none 0.5)
			(connect_pads
				(clearance 0)
			)
			(min_thickness 0.25)
			(keepout
				(tracks allowed)
				(vias not_allowed)
				(pads allowed)
				(copperpour not_allowed)
				(footprints allowed)
			)
			(placement
				(enabled no)
				(sheetname "")
			)
			(fill
				(thermal_gap 0.5)
				(thermal_bridge_width 0.5)
				(island_removal_mode 0)
			)
			(polygon
				(pts
					(xy 320.3575 -124.841) (xy 320.3575 -124.333) (xy 319.9765 -124.333) (xy 319.9765 -124.841)
				)
			)
		)
	)
	(footprint ""
		(layer "F.Cu")
		(at 155.532836 -119.267986 90)
		(property "Reference" "R3B3"
			(at 0 0 90)
			(layer "F.SilkS")
			(hide yes)
			(effects
				(font
					(size 1.27 1.27)
				)
			)
		)
		(property "Value" ""
			(at 0 0 90)
			(layer "F.Fab")
			(effects
				(font
					(size 1.27 1.27)
				)
			)
		)
		(duplicate_pad_numbers_are_jumpers no)
		(fp_poly
			(pts
				(xy -0.2794 -0.1016) (xy 0.2794 -0.1016) (xy 0.2794 0.9906) (xy -0.2794 0.9906)
			)
			(stroke
				(width 0)
				(type default)
			)
			(fill no)
			(layer "F.CrtYd")
		)
		(fp_line
			(start 0.2794 -0.1016)
			(end -0.2794 -0.1016)
			(stroke
				(width 0.1)
				(type default)
			)
			(layer "F.Fab")
		)
		(fp_line
			(start -0.2794 -0.1016)
			(end -0.2794 0.9906)
			(stroke
				(width 0.1)
				(type default)
			)
			(layer "F.Fab")
		)
		(fp_line
			(start 0.2794 0.9906)
			(end 0.2794 -0.1016)
			(stroke
				(width 0.1)
				(type default)
			)
			(layer "F.Fab")
		)
		(fp_line
			(start -0.2794 0.9906)
			(end 0.2794 0.9906)
			(stroke
				(width 0.1)
				(type default)
			)
			(layer "F.Fab")
		)
		(pad "1" smd rect
			(at 0 0 90)
			(size 0.508 0.508)
			(layers "F.Cu" "F.Mask" "F.Paste")
			(net "SVID_DIO0_CPU1")
		)
		(pad "2" smd rect
			(at 0 0.889 90)
			(size 0.508 0.508)
			(layers "F.Cu" "F.Mask" "F.Paste")
			(net "SVID_DIO0_CPU1_R")
		)
		(zone
			(layer "F.Cu")
			(hatch none 0.5)
			(connect_pads
				(clearance 0)
			)
			(min_thickness 0.25)
			(keepout
				(tracks allowed)
				(vias not_allowed)
				(pads allowed)
				(copperpour not_allowed)
				(footprints allowed)
			)
			(placement
				(enabled no)
				(sheetname "")
			)
			(fill
				(thermal_gap 0.5)
				(thermal_bridge_width 0.5)
				(island_removal_mode 0)
			)
			(polygon
				(pts
					(xy 155.786836 -119.013986) (xy 155.786836 -119.521986) (xy 156.167836 -119.521986) (xy 156.167836 -119.013986)
				)
			)
		)
		(zone
			(layer "F.Cu")
			(hatch none 0.5)
			(connect_pads
				(clearance 0)
			)
			(min_thickness 0.25)
			(keepout
				(tracks not_allowed)
				(vias allowed)
				(pads allowed)
				(copperpour not_allowed)
				(footprints allowed)
			)
			(placement
				(enabled no)
				(sheetname "")
			)
			(fill
				(thermal_gap 0.5)
				(thermal_bridge_width 0.5)
				(island_removal_mode 0)
			)
			(polygon
				(pts
					(xy 156.167836 -119.013986) (xy 156.167836 -119.521986) (xy 155.786836 -119.521986) (xy 155.786836 -119.013986)
				)
			)
		)
	)
	(footprint ""
		(layer "F.Cu")
		(at 26.543 -29.972 -90)
		(property "Reference" "R1F2"
			(at 0 0 270)
			(layer "F.SilkS")
			(hide yes)
			(effects
				(font
					(size 1.27 1.27)
				)
			)
		)
		(property "Value" ""
			(at 0 0 270)
			(layer "F.Fab")
			(effects
				(font
					(size 1.27 1.27)
				)
			)
		)
		(duplicate_pad_numbers_are_jumpers no)
		(fp_rect
			(start -0.2794 -0.1016)
			(end 0.2794 0.9906)
			(stroke
				(width 0)
				(type default)
			)
			(fill no)
			(layer "F.CrtYd")
		)
		(fp_line
			(start -0.2794 0.9906)
			(end 0.2794 0.9906)
			(stroke
				(width 0.1)
				(type default)
			)
			(layer "F.Fab")
		)
		(fp_line
			(start 0.2794 0.9906)
			(end 0.2794 -0.1016)
			(stroke
				(width 0.1)
				(type default)
			)
			(layer "F.Fab")
		)
		(fp_line
			(start -0.2794 -0.1016)
			(end -0.2794 0.9906)
			(stroke
				(width 0.1)
				(type default)
			)
			(layer "F.Fab")
		)
		(fp_line
			(start 0.2794 -0.1016)
			(end -0.2794 -0.1016)
			(stroke
				(width 0.1)
				(type default)
			)
			(layer "F.Fab")
		)
		(pad "1" smd rect
			(at 0 0 270)
			(size 0.508 0.508)
			(layers "F.Cu" "F.Mask" "F.Paste")
			(net "FAN_TACH0")
		)
		(pad "2" smd rect
			(at 0 0.889 270)
			(size 0.508 0.508)
			(layers "F.Cu" "F.Mask" "F.Paste")
			(net "FAN_TACH0_CPU0_D2")
		)
		(zone
			(layer "F.Cu")
			(hatch none 0.5)
			(connect_pads
				(clearance 0)
			)
			(min_thickness 0.25)
			(keepout
				(tracks not_allowed)
				(vias allowed)
				(pads allowed)
				(copperpour not_allowed)
				(footprints allowed)
			)
			(placement
				(enabled no)
				(sheetname "")
			)
			(fill
				(thermal_gap 0.5)
				(thermal_bridge_width 0.5)
				(island_removal_mode 0)
			)
			(polygon
				(pts
					(xy 26.289 -30.226) (xy 25.908 -30.226) (xy 25.908 -29.718) (xy 26.289 -29.718)
				)
			)
		)
		(zone
			(layer "F.Cu")
			(hatch none 0.5)
			(connect_pads
				(clearance 0)
			)
			(min_thickness 0.25)
			(keepout
				(tracks allowed)
				(vias not_allowed)
				(pads allowed)
				(copperpour not_allowed)
				(footprints allowed)
			)
			(placement
				(enabled no)
				(sheetname "")
			)
			(fill
				(thermal_gap 0.5)
				(thermal_bridge_width 0.5)
				(island_removal_mode 0)
			)
			(polygon
				(pts
					(xy 26.289 -30.226) (xy 25.908 -30.226) (xy 25.908 -29.718) (xy 26.289 -29.718)
				)
			)
		)
	)
	(footprint ""
		(layer "F.Cu")
		(at 476.4786 -41.2369)
		(property "Reference" "C9E9"
			(at 0 0 0)
			(layer "F.SilkS")
			(hide yes)
			(effects
				(font
					(size 1.27 1.27)
				)
			)
		)
		(property "Value" ""
			(at 0 0 0)
			(layer "F.Fab")
			(effects
				(font
					(size 1.27 1.27)
				)
			)
		)
		(duplicate_pad_numbers_are_jumpers no)
		(fp_poly
			(pts
				(xy 0.3048 -0.1016) (xy 0.3048 0.9906) (xy -0.3048 0.9906) (xy -0.3048 -0.1016)
			)
			(stroke
				(width 0)
				(type default)
			)
			(fill no)
			(layer "F.CrtYd")
		)
		(fp_line
			(start -0.3048 -0.1016)
			(end -0.3048 0.9906)
			(stroke
				(width 0.1)
				(type default)
			)
			(layer "F.Fab")
		)
		(fp_line
			(start -0.3048 0.9906)
			(end 0.3048 0.9906)
			(stroke
				(width 0.1)
				(type default)
			)
			(layer "F.Fab")
		)
		(fp_line
			(start 0.3048 -0.1016)
			(end -0.3048 -0.1016)
			(stroke
				(width 0.1)
				(type default)
			)
			(layer "F.Fab")
		)
		(fp_line
			(start 0.3048 0.9906)
			(end 0.3048 -0.1016)
			(stroke
				(width 0.1)
				(type default)
			)
			(layer "F.Fab")
		)
		(pad "1" smd rect
			(at 0 0)
			(size 0.508 0.508)
			(layers "F.Cu" "F.Mask" "F.Paste")
			(net "XTAL_25MHZ_IN")
		)
		(pad "2" smd rect
			(at 0 0.889)
			(size 0.508 0.508)
			(layers "F.Cu" "F.Mask" "F.Paste")
			(net "GND")
		)
		(zone
			(layer "F.Cu")
			(hatch none 0.5)
			(connect_pads
				(clearance 0)
			)
			(min_thickness 0.25)
			(keepout
				(tracks allowed)
				(vias not_allowed)
				(pads allowed)
				(copperpour not_allowed)
				(footprints allowed)
			)
			(placement
				(enabled no)
				(sheetname "")
			)
			(fill
				(thermal_gap 0.5)
				(thermal_bridge_width 0.5)
				(island_removal_mode 0)
			)
			(polygon
				(pts
					(xy 476.2246 -40.9829) (xy 476.7326 -40.9829) (xy 476.7326 -40.6019) (xy 476.2246 -40.6019)
				)
			)
		)
		(zone
			(layer "F.Cu")
			(hatch none 0.5)
			(connect_pads
				(clearance 0)
			)
			(min_thickness 0.25)
			(keepout
				(tracks not_allowed)
				(vias allowed)
				(pads allowed)
				(copperpour not_allowed)
				(footprints allowed)
			)
			(placement
				(enabled no)
				(sheetname "")
			)
			(fill
				(thermal_gap 0.5)
				(thermal_bridge_width 0.5)
				(island_removal_mode 0)
			)
			(polygon
				(pts
					(xy 476.2246 -40.6019) (xy 476.7326 -40.6019) (xy 476.7326 -40.9829) (xy 476.2246 -40.9829)
				)
			)
		)
	)
	(footprint ""
		(layer "F.Cu")
		(at 391.4902 -80.0354 180)
		(property "Reference" "R7D33"
			(at 0 0 180)
			(layer "F.SilkS")
			(hide yes)
			(effects
				(font
					(size 1.27 1.27)
				)
			)
		)
		(property "Value" "*"
			(at 0.064008 -4.108196 180)
			(unlocked yes)
			(layer "F.Fab")
			(hide yes)
			(effects
				(font
					(size 1.27 1.016)
					(thickness 0.1524)
				)
			)
		)
		(property "Device Type" "374R2F-1-GP_SMD-RG-374R2F-1-GPA"
			(at 0.064008 -5.632196 180)
			(unlocked yes)
			(layer "F.Fab")
			(hide yes)
			(effects
				(font
					(size 1.27 1.016)
					(thickness 0.1524)
				)
			)
		)
		(duplicate_pad_numbers_are_jumpers no)
		(fp_line
			(start 0.508 -0.9398)
			(end -0.508 -0.9398)
			(stroke
				(width 0.1524)
				(type default)
			)
			(layer "F.SilkS")
		)
		(fp_line
			(start -0.508 -0.9398)
			(end -0.508 0.9398)
			(stroke
				(width 0.1524)
				(type default)
			)
			(layer "F.SilkS")
		)
		(fp_rect
			(start -0.508 0.9398)
			(end 0.508 -0.9398)
			(stroke
				(width 0)
				(type default)
			)
			(fill no)
			(layer "F.CrtYd")
		)
		(fp_rect
			(start -0.508 0.9398)
			(end 0.508 -0.9398)
			(stroke
				(width 0)
				(type default)
			)
			(fill no)
			(layer "F.Fab")
		)
		(pad "1" smd custom
			(at 0 -0.4445 180)
			(size 0.1397 0.1397)
			(layers "F.Cu" "F.Mask" "F.Paste")
			(net "P3V3")
			(options
				(clearance outline)
				(anchor circle)
			)
			(primitives
				(gr_poly
					(pts
						(arc
							(start -0.1778 -0.2794)
							(mid -0.249642 -0.249642)
							(end -0.2794 -0.1778)
						)
						(arc
							(start -0.2794 0.1778)
							(mid -0.249642 0.249642)
							(end -0.1778 0.2794)
						)
						(arc
							(start 0.1778 0.2794)
							(mid 0.249642 0.249642)
							(end 0.2794 0.1778)
						)
						(arc
							(start 0.2794 -0.1778)
							(mid 0.249642 -0.249642)
							(end 0.1778 -0.2794)
						)
					)
					(width 0)
					(fill yes)
				)
			)
		)
		(pad "2" smd custom
			(at 0 0.4445 180)
			(size 0.1397 0.1397)
			(layers "F.Cu" "F.Mask" "F.Paste")
			(net "P0V7_GTL2104_VREF_0")
			(options
				(clearance outline)
				(anchor circle)
			)
			(primitives
				(gr_poly
					(pts
						(arc
							(start -0.1778 -0.2794)
							(mid -0.249642 -0.249642)
							(end -0.2794 -0.1778)
						)
						(arc
							(start -0.2794 0.1778)
							(mid -0.249642 0.249642)
							(end -0.1778 0.2794)
						)
						(arc
							(start 0.1778 0.2794)
							(mid 0.249642 0.249642)
							(end 0.2794 0.1778)
						)
						(arc
							(start 0.2794 -0.1778)
							(mid 0.249642 -0.249642)
							(end 0.1778 -0.2794)
						)
					)
					(width 0)
					(fill yes)
				)
			)
		)
	)
	(footprint ""
		(layer "F.Cu")
		(at 398.919192 -10.917936)
		(property "Reference" "C7G26"
			(at 0 0 0)
			(layer "F.SilkS")
			(hide yes)
			(effects
				(font
					(size 1.27 1.27)
				)
			)
		)
		(property "Value" ""
			(at 0 0 0)
			(layer "F.Fab")
			(effects
				(font
					(size 1.27 1.27)
				)
			)
		)
		(duplicate_pad_numbers_are_jumpers no)
		(fp_rect
			(start -0.3048 0.9906)
			(end 0.3048 -0.1016)
			(stroke
				(width 0)
				(type default)
			)
			(fill no)
			(layer "F.CrtYd")
		)
		(fp_line
			(start -0.3048 -0.1016)
			(end -0.3048 0.9906)
			(stroke
				(width 0.1)
				(type default)
			)
			(layer "F.Fab")
		)
		(fp_line
			(start -0.3048 0.9906)
			(end 0.3048 0.9906)
			(stroke
				(width 0.1)
				(type default)
			)
			(layer "F.Fab")
		)
		(fp_line
			(start 0.3048 -0.1016)
			(end -0.3048 -0.1016)
			(stroke
				(width 0.1)
				(type default)
			)
			(layer "F.Fab")
		)
		(fp_line
			(start 0.3048 0.9906)
			(end 0.3048 -0.1016)
			(stroke
				(width 0.1)
				(type default)
			)
			(layer "F.Fab")
		)
		(pad "1" smd rect
			(at 0 0)
			(size 0.508 0.508)
			(layers "F.Cu" "F.Mask" "F.Paste")
			(net "P3E_CPU0_PE2_SS_TXN<5>")
		)
		(pad "2" smd rect
			(at 0 0.889)
			(size 0.508 0.508)
			(layers "F.Cu" "F.Mask" "F.Paste")
			(net "P3E_CPU0_PE2_SS_C_TXN<5>")
		)
		(zone
			(layer "F.Cu")
			(hatch none 0.5)
			(connect_pads
				(clearance 0)
			)
			(min_thickness 0.25)
			(keepout
				(tracks allowed)
				(vias not_allowed)
				(pads allowed)
				(copperpour not_allowed)
				(footprints allowed)
			)
			(placement
				(enabled no)
				(sheetname "")
			)
			(fill
				(thermal_gap 0.5)
				(thermal_bridge_width 0.5)
				(island_removal_mode 0)
			)
			(polygon
				(pts
					(xy 398.665192 -10.282936) (xy 399.173192 -10.282936) (xy 399.173192 -10.663936) (xy 398.665192 -10.663936)
				)
			)
		)
		(zone
			(layer "F.Cu")
			(hatch none 0.5)
			(connect_pads
				(clearance 0)
			)
			(min_thickness 0.25)
			(keepout
				(tracks not_allowed)
				(vias allowed)
				(pads allowed)
				(copperpour not_allowed)
				(footprints allowed)
			)
			(placement
				(enabled no)
				(sheetname "")
			)
			(fill
				(thermal_gap 0.5)
				(thermal_bridge_width 0.5)
				(island_removal_mode 0)
			)
			(polygon
				(pts
					(xy 398.665192 -10.282936) (xy 399.173192 -10.282936) (xy 399.173192 -10.663936) (xy 398.665192 -10.663936)
				)
			)
		)
	)
	(footprint ""
		(layer "F.Cu")
		(at 19.6342 -97.310956 180)
		(property "Reference" "C1C10"
			(at 0 0 180)
			(layer "F.SilkS")
			(hide yes)
			(effects
				(font
					(size 1.27 1.27)
				)
			)
		)
		(property "Value" ""
			(at 0 0 180)
			(layer "F.Fab")
			(effects
				(font
					(size 1.27 1.27)
				)
			)
		)
		(duplicate_pad_numbers_are_jumpers no)
		(fp_rect
			(start 0.3048 -0.1016)
			(end -0.3048 0.9906)
			(stroke
				(width 0)
				(type default)
			)
			(fill no)
			(layer "F.CrtYd")
		)
		(fp_line
			(start 0.3048 0.9906)
			(end 0.3048 -0.1016)
			(stroke
				(width 0.1)
				(type default)
			)
			(layer "F.Fab")
		)
		(fp_line
			(start 0.3048 -0.1016)
			(end -0.3048 -0.1016)
			(stroke
				(width 0.1)
				(type default)
			)
			(layer "F.Fab")
		)
		(fp_line
			(start -0.3048 0.9906)
			(end 0.3048 0.9906)
			(stroke
				(width 0.1)
				(type default)
			)
			(layer "F.Fab")
		)
		(fp_line
			(start -0.3048 -0.1016)
			(end -0.3048 0.9906)
			(stroke
				(width 0.1)
				(type default)
			)
			(layer "F.Fab")
		)
		(pad "1" smd rect
			(at 0 0 180)
			(size 0.508 0.508)
			(layers "F.Cu" "F.Mask" "F.Paste")
			(net "A_TSENSE_PVCCIN_CPU1")
		)
		(pad "2" smd rect
			(at 0 0.889 180)
			(size 0.508 0.508)
			(layers "F.Cu" "F.Mask" "F.Paste")
			(net "GND")
		)
		(zone
			(layer "F.Cu")
			(hatch none 0.5)
			(connect_pads
				(clearance 0)
			)
			(min_thickness 0.25)
			(keepout
				(tracks not_allowed)
				(vias allowed)
				(pads allowed)
				(copperpour not_allowed)
				(footprints allowed)
			)
			(placement
				(enabled no)
				(sheetname "")
			)
			(fill
				(thermal_gap 0.5)
				(thermal_bridge_width 0.5)
				(island_removal_mode 0)
			)
			(polygon
				(pts
					(xy 19.3802 -97.564956) (xy 19.8882 -97.564956) (xy 19.8882 -97.945956) (xy 19.3802 -97.945956)
				)
			)
		)
		(zone
			(layer "F.Cu")
			(hatch none 0.5)
			(connect_pads
				(clearance 0)
			)
			(min_thickness 0.25)
			(keepout
				(tracks allowed)
				(vias not_allowed)
				(pads allowed)
				(copperpour not_allowed)
				(footprints allowed)
			)
			(placement
				(enabled no)
				(sheetname "")
			)
			(fill
				(thermal_gap 0.5)
				(thermal_bridge_width 0.5)
				(island_removal_mode 0)
			)
			(polygon
				(pts
					(xy 19.3802 -97.564956) (xy 19.8882 -97.564956) (xy 19.8882 -97.945956) (xy 19.3802 -97.945956)
				)
			)
		)
	)
	(footprint ""
		(layer "F.Cu")
		(at 466.54212 -144.907 -90)
		(property "Reference" "R9A15"
			(at 0 0 270)
			(layer "F.SilkS")
			(hide yes)
			(effects
				(font
					(size 1.27 1.27)
				)
			)
		)
		(property "Value" ""
			(at 0 0 270)
			(layer "F.Fab")
			(effects
				(font
					(size 1.27 1.27)
				)
			)
		)
		(duplicate_pad_numbers_are_jumpers no)
		(fp_poly
			(pts
				(xy -0.2794 -0.1016) (xy 0.2794 -0.1016) (xy 0.2794 0.9906) (xy -0.2794 0.9906)
			)
			(stroke
				(width 0)
				(type default)
			)
			(fill no)
			(layer "F.CrtYd")
		)
		(fp_line
			(start -0.2794 0.9906)
			(end 0.2794 0.9906)
			(stroke
				(width 0.1)
				(type default)
			)
			(layer "F.Fab")
		)
		(fp_line
			(start 0.2794 0.9906)
			(end 0.2794 -0.1016)
			(stroke
				(width 0.1)
				(type default)
			)
			(layer "F.Fab")
		)
		(fp_line
			(start -0.2794 -0.1016)
			(end -0.2794 0.9906)
			(stroke
				(width 0.1)
				(type default)
			)
			(layer "F.Fab")
		)
		(fp_line
			(start 0.2794 -0.1016)
			(end -0.2794 -0.1016)
			(stroke
				(width 0.1)
				(type default)
			)
			(layer "F.Fab")
		)
		(pad "1" smd rect
			(at 0 0 270)
			(size 0.508 0.508)
			(layers "F.Cu" "F.Mask" "F.Paste")
			(net "RST_RSMRST_N")
		)
		(pad "2" smd rect
			(at 0 0.889 270)
			(size 0.508 0.508)
			(layers "F.Cu" "F.Mask" "F.Paste")
			(net "XDP_RSMRST_N")
		)
		(zone
			(layer "F.Cu")
			(hatch none 0.5)
			(connect_pads
				(clearance 0)
			)
			(min_thickness 0.25)
			(keepout
				(tracks not_allowed)
				(vias allowed)
				(pads allowed)
				(copperpour not_allowed)
				(footprints allowed)
			)
			(placement
				(enabled no)
				(sheetname "")
			)
			(fill
				(thermal_gap 0.5)
				(thermal_bridge_width 0.5)
				(island_removal_mode 0)
			)
			(polygon
				(pts
					(xy 465.90712 -145.161) (xy 465.90712 -144.653) (xy 466.28812 -144.653) (xy 466.28812 -145.161)
				)
			)
		)
		(zone
			(layer "F.Cu")
			(hatch none 0.5)
			(connect_pads
				(clearance 0)
			)
			(min_thickness 0.25)
			(keepout
				(tracks allowed)
				(vias not_allowed)
				(pads allowed)
				(copperpour not_allowed)
				(footprints allowed)
			)
			(placement
				(enabled no)
				(sheetname "")
			)
			(fill
				(thermal_gap 0.5)
				(thermal_bridge_width 0.5)
				(island_removal_mode 0)
			)
			(polygon
				(pts
					(xy 466.28812 -145.161) (xy 466.28812 -144.653) (xy 465.90712 -144.653) (xy 465.90712 -145.161)
				)
			)
		)
	)
	(footprint ""
		(layer "F.Cu")
		(at 385.8768 -65.3034)
		(property "Reference" "C7E12"
			(at 0 0 0)
			(layer "F.SilkS")
			(hide yes)
			(effects
				(font
					(size 1.27 1.27)
				)
			)
		)
		(property "Value" "*"
			(at -0.0762 -6.2357 0)
			(unlocked yes)
			(layer "F.Fab")
			(hide yes)
			(effects
				(font
					(size 1.27 1.016)
					(thickness 0.1524)
				)
			)
		)
		(property "Device Type" "SC22U16V5MX-4-GP_SMD-BCG5-SC22A"
			(at -0.0762 -8.2677 0)
			(unlocked yes)
			(layer "F.Fab")
			(hide yes)
			(effects
				(font
					(size 1.27 1.016)
					(thickness 0.1524)
				)
			)
		)
		(duplicate_pad_numbers_are_jumpers no)
		(fp_line
			(start 0.635 0)
			(end -0.635 0)
			(stroke
				(width 0.508)
				(type default)
			)
			(layer "F.SilkS")
		)
		(fp_rect
			(start -0.9652 1.778)
			(end 0.9652 -1.778)
			(stroke
				(width 0)
				(type default)
			)
			(fill no)
			(layer "F.CrtYd")
		)
		(fp_poly
			(pts
				(xy -0.9652 -1.778) (xy 0.9652 -1.778) (xy 0.9652 1.778) (xy -0.9652 1.778)
			)
			(stroke
				(width 0)
				(type default)
			)
			(fill no)
			(layer "F.Fab")
		)
		(pad "1" smd rect
			(at 0 -0.9652)
			(size 1.397 1.143)
			(layers "F.Cu" "F.Mask" "F.Paste")
			(net "VR_FET_SW_P5V_STBY_PVIN")
		)
		(pad "2" smd rect
			(at 0 0.9652)
			(size 1.397 1.143)
			(layers "F.Cu" "F.Mask" "F.Paste")
			(net "GND")
		)
	)
	(footprint ""
		(layer "F.Cu")
		(at 439.626756 -146.477228)
		(property "Reference" "U25W19"
			(at -0.14986 2.621788 0)
			(unlocked yes)
			(layer "F.SilkS")
			(effects
				(font
					(size 1.27 0.964946)
					(thickness 0.000001)
				)
				(justify left)
			)
		)
		(property "Value" ""
			(at 0 0 0)
			(layer "F.Fab")
			(effects
				(font
					(size 1.27 1.27)
				)
			)
		)
		(duplicate_pad_numbers_are_jumpers no)
		(fp_circle
			(center -0.4699 -0.8382)
			(end -0.3429 -0.8382)
			(stroke
				(width 0.254)
				(type default)
			)
			(fill no)
			(layer "F.SilkS")
		)
		(fp_poly
			(pts
				(xy 0.21463 -0.450088) (xy 1.56337 -0.450088) (xy 1.56337 1.75006) (xy 0.21463 1.75006)
			)
			(stroke
				(width 0)
				(type default)
			)
			(fill no)
			(layer "F.CrtYd")
		)
		(fp_line
			(start 0.21463 -0.450088)
			(end 1.56337 -0.450088)
			(stroke
				(width 0.1)
				(type default)
			)
			(layer "F.Fab")
		)
		(fp_line
			(start 0.21463 1.75006)
			(end 0.21463 -0.450088)
			(stroke
				(width 0.1)
				(type default)
			)
			(layer "F.Fab")
		)
		(fp_line
			(start 1.56337 -0.450088)
			(end 1.56337 1.75006)
			(stroke
				(width 0.1)
				(type default)
			)
			(layer "F.Fab")
		)
		(fp_line
			(start 1.56337 1.75006)
			(end 0.21463 1.75006)
			(stroke
				(width 0.1)
				(type default)
			)
			(layer "F.Fab")
		)
		(fp_circle
			(center -0.4699 -0.8382)
			(end -0.3429 -0.8382)
			(stroke
				(width 0.254)
				(type default)
			)
			(fill no)
			(layer "F.Fab")
		)
		(pad "1" smd rect
			(at 0 0)
			(size 1.016 0.381)
			(layers "F.Cu" "F.Mask" "F.Paste")
			(net "BMC_JTAG_SEL_BUF")
		)
		(pad "2" smd rect
			(at 0 0.649986)
			(size 1.016 0.381)
			(layers "F.Cu" "F.Mask" "F.Paste")
			(net "JTAG_BMC_TCK")
		)
		(pad "3" smd rect
			(at 0 1.299972)
			(size 1.016 0.381)
			(layers "F.Cu" "F.Mask" "F.Paste")
			(net "GND")
		)
		(pad "4" smd rect
			(at 1.778 1.299972)
			(size 1.016 0.381)
			(layers "F.Cu" "F.Mask" "F.Paste")
			(net "JTAG_BMC_TCK_BUF")
		)
		(pad "5" smd rect
			(at 1.778 0)
			(size 1.016 0.381)
			(layers "F.Cu" "F.Mask" "F.Paste")
			(net "P3V3_STBY")
		)
	)
	(footprint ""
		(layer "F.Cu")
		(at 16.764 -86.741 180)
		(property "Reference" "R1D8"
			(at 0 0 180)
			(layer "F.SilkS")
			(hide yes)
			(effects
				(font
					(size 1.27 1.27)
				)
			)
		)
		(property "Value" ""
			(at 0 0 180)
			(layer "F.Fab")
			(effects
				(font
					(size 1.27 1.27)
				)
			)
		)
		(duplicate_pad_numbers_are_jumpers no)
		(fp_rect
			(start 0.2794 -0.1016)
			(end -0.2794 0.9906)
			(stroke
				(width 0)
				(type default)
			)
			(fill no)
			(layer "F.CrtYd")
		)
		(fp_line
			(start 0.2794 0.9906)
			(end 0.2794 -0.1016)
			(stroke
				(width 0.1)
				(type default)
			)
			(layer "F.Fab")
		)
		(fp_line
			(start 0.2794 -0.1016)
			(end -0.2794 -0.1016)
			(stroke
				(width 0.1)
				(type default)
			)
			(layer "F.Fab")
		)
		(fp_line
			(start -0.2794 0.9906)
			(end 0.2794 0.9906)
			(stroke
				(width 0.1)
				(type default)
			)
			(layer "F.Fab")
		)
		(fp_line
			(start -0.2794 -0.1016)
			(end -0.2794 0.9906)
			(stroke
				(width 0.1)
				(type default)
			)
			(layer "F.Fab")
		)
		(pad "1" smd rect
			(at 0 0 180)
			(size 0.508 0.508)
			(layers "F.Cu" "F.Mask" "F.Paste")
			(net "P3V3_STBY")
		)
		(pad "2" smd rect
			(at 0 0.889 180)
			(size 0.508 0.508)
			(layers "F.Cu" "F.Mask" "F.Paste")
			(net "PWRGD_PVSA_CPU1_R")
		)
		(zone
			(layer "F.Cu")
			(hatch none 0.5)
			(connect_pads
				(clearance 0)
			)
			(min_thickness 0.25)
			(keepout
				(tracks allowed)
				(vias not_allowed)
				(pads allowed)
				(copperpour not_allowed)
				(footprints allowed)
			)
			(placement
				(enabled no)
				(sheetname "")
			)
			(fill
				(thermal_gap 0.5)
				(thermal_bridge_width 0.5)
				(island_removal_mode 0)
			)
			(polygon
				(pts
					(xy 16.51 -86.995) (xy 17.018 -86.995) (xy 17.018 -87.376) (xy 16.51 -87.376)
				)
			)
		)
		(zone
			(layer "F.Cu")
			(hatch none 0.5)
			(connect_pads
				(clearance 0)
			)
			(min_thickness 0.25)
			(keepout
				(tracks not_allowed)
				(vias allowed)
				(pads allowed)
				(copperpour not_allowed)
				(footprints allowed)
			)
			(placement
				(enabled no)
				(sheetname "")
			)
			(fill
				(thermal_gap 0.5)
				(thermal_bridge_width 0.5)
				(island_removal_mode 0)
			)
			(polygon
				(pts
					(xy 16.51 -86.995) (xy 17.018 -86.995) (xy 17.018 -87.376) (xy 16.51 -87.376)
				)
			)
		)
	)
	(footprint ""
		(layer "F.Cu")
		(at 466.5345 -20.6502 90)
		(property "Reference" "R8F9"
			(at 0 0 90)
			(layer "F.SilkS")
			(hide yes)
			(effects
				(font
					(size 1.27 1.27)
				)
			)
		)
		(property "Value" ""
			(at 0 0 90)
			(layer "F.Fab")
			(effects
				(font
					(size 1.27 1.27)
				)
			)
		)
		(duplicate_pad_numbers_are_jumpers no)
		(fp_rect
			(start -0.2794 -0.1016)
			(end 0.2794 0.9906)
			(stroke
				(width 0)
				(type default)
			)
			(fill no)
			(layer "F.CrtYd")
		)
		(fp_line
			(start 0.2794 -0.1016)
			(end -0.2794 -0.1016)
			(stroke
				(width 0.1)
				(type default)
			)
			(layer "F.Fab")
		)
		(fp_line
			(start -0.2794 -0.1016)
			(end -0.2794 0.9906)
			(stroke
				(width 0.1)
				(type default)
			)
			(layer "F.Fab")
		)
		(fp_line
			(start 0.2794 0.9906)
			(end 0.2794 -0.1016)
			(stroke
				(width 0.1)
				(type default)
			)
			(layer "F.Fab")
		)
		(fp_line
			(start -0.2794 0.9906)
			(end 0.2794 0.9906)
			(stroke
				(width 0.1)
				(type default)
			)
			(layer "F.Fab")
		)
		(pad "1" smd rect
			(at 0 0 90)
			(size 0.508 0.508)
			(layers "F.Cu" "F.Mask" "F.Paste")
			(net "VR_P3V3_STBY_OCSELECT")
		)
		(pad "2" smd rect
			(at 0 0.889 90)
			(size 0.508 0.508)
			(layers "F.Cu" "F.Mask" "F.Paste")
			(net "AGND_P3V3_STBY")
		)
		(zone
			(layer "F.Cu")
			(hatch none 0.5)
			(connect_pads
				(clearance 0)
			)
			(min_thickness 0.25)
			(keepout
				(tracks allowed)
				(vias not_allowed)
				(pads allowed)
				(copperpour not_allowed)
				(footprints allowed)
			)
			(placement
				(enabled no)
				(sheetname "")
			)
			(fill
				(thermal_gap 0.5)
				(thermal_bridge_width 0.5)
				(island_removal_mode 0)
			)
			(polygon
				(pts
					(xy 466.7885 -20.3962) (xy 467.1695 -20.3962) (xy 467.1695 -20.9042) (xy 466.7885 -20.9042)
				)
			)
		)
		(zone
			(layer "F.Cu")
			(hatch none 0.5)
			(connect_pads
				(clearance 0)
			)
			(min_thickness 0.25)
			(keepout
				(tracks not_allowed)
				(vias allowed)
				(pads allowed)
				(copperpour not_allowed)
				(footprints allowed)
			)
			(placement
				(enabled no)
				(sheetname "")
			)
			(fill
				(thermal_gap 0.5)
				(thermal_bridge_width 0.5)
				(island_removal_mode 0)
			)
			(polygon
				(pts
					(xy 466.7885 -20.3962) (xy 467.1695 -20.3962) (xy 467.1695 -20.9042) (xy 466.7885 -20.9042)
				)
			)
		)
	)
	(footprint ""
		(layer "F.Cu")
		(at 53.80228 -165.01618 90)
		(property "Reference" "T1D2"
			(at 0 0 90)
			(layer "F.SilkS")
			(hide yes)
			(effects
				(font
					(size 1.27 1.27)
				)
			)
		)
		(property "Value" "*"
			(at -3.4036 -4.46405 90)
			(unlocked yes)
			(layer "F.Fab")
			(hide yes)
			(effects
				(font
					(size 0.889 0.889)
					(thickness 0.1524)
				)
			)
		)
		(property "Device Type" "TEST-PAD-12P-1-GP-U_DISCRET-GBA"
			(at -3.4036 -5.98805 90)
			(unlocked yes)
			(layer "F.Fab")
			(hide yes)
			(effects
				(font
					(size 0.889 0.889)
					(thickness 0.1524)
				)
			)
		)
		(duplicate_pad_numbers_are_jumpers no)
		(fp_line
			(start 2.3622 -4.826)
			(end 2.3622 3.4798)
			(stroke
				(width 0.1524)
				(type default)
			)
			(layer "F.SilkS")
		)
		(fp_line
			(start -2.3876 -4.826)
			(end 2.3622 -4.826)
			(stroke
				(width 0.1524)
				(type default)
			)
			(layer "F.SilkS")
		)
		(fp_line
			(start 2.3622 3.4798)
			(end -2.3876 3.4798)
			(stroke
				(width 0.1524)
				(type default)
			)
			(layer "F.SilkS")
		)
		(fp_line
			(start -2.3876 3.4798)
			(end -2.3876 -4.826)
			(stroke
				(width 0.1524)
				(type default)
			)
			(layer "F.SilkS")
		)
		(fp_rect
			(start -2.6416 3.7338)
			(end 2.6162 -5.08)
			(stroke
				(width 0)
				(type default)
			)
			(fill no)
			(layer "F.CrtYd")
		)
		(fp_rect
			(start -2.6416 3.7338)
			(end 2.6162 -5.08)
			(stroke
				(width 0)
				(type default)
			)
			(fill no)
			(layer "F.Fab")
		)
		(pad "1" smd circle
			(at 0.496824 -1.301496 90)
			(size 0.6604 0.6604)
			(layers "F.Cu" "F.Mask" "F.Paste")
			(net "L1_85OHM_5INCH_DN")
		)
		(pad "2" smd circle
			(at -0.503936 -1.301496 90)
			(size 0.6604 0.6604)
			(layers "F.Cu" "F.Mask" "F.Paste")
			(net "L1_85OHM_5INCH_DP")
		)
		(pad "3" smd custom
			(at -0.00889 0.370078 90)
			(size 0.74295 0.74295)
			(layers "F.Cu" "F.Mask" "F.Paste")
			(net "GND")
			(options
				(clearance outline)
				(anchor circle)
			)
			(primitives
				(gr_poly
					(pts
						(xy -2.1209 1.4859) (xy 2.1209 1.4859) (xy 2.1209 -1.4859) (xy 1.08585 -1.4859) (xy 1.08585 -0.4699)
						(xy -1.08585 -0.4699) (xy -1.08585 -1.4859) (xy -2.1209 -1.4859)
					)
					(width 0)
					(fill yes)
				)
			)
		)
		(pad "4" thru_hole circle
			(at 1.266444 -3.851656 90)
			(size 1.4478 1.4478)
			(drill 1.0414)
			(layers "*.Cu" "*.Mask")
			(remove_unused_layers no)
			(net "GND")
			(clearance 0.1524)
			(thermal_gap 0.1524)
		)
		(pad "5" thru_hole circle
			(at -1.273556 -3.851656 90)
			(size 1.4478 1.4478)
			(drill 1.0414)
			(layers "*.Cu" "*.Mask")
			(remove_unused_layers no)
			(net "GND")
			(clearance 0.1524)
			(thermal_gap 0.1524)
		)
		(pad "6" thru_hole circle
			(at 1.266444 2.498344 90)
			(size 1.4478 1.4478)
			(drill 1.0414)
			(layers "*.Cu" "*.Mask")
			(remove_unused_layers no)
			(net "GND")
			(clearance 0.1524)
			(thermal_gap 0.1524)
		)
		(pad "7" thru_hole circle
			(at -1.273556 2.498344 90)
			(size 1.4478 1.4478)
			(drill 1.0414)
			(layers "*.Cu" "*.Mask")
			(remove_unused_layers no)
			(net "GND")
			(clearance 0.1524)
			(thermal_gap 0.1524)
		)
		(pad "8" thru_hole circle
			(at 1.27 -0.4572 90)
			(size 0.7112 0.7112)
			(drill 0.4064)
			(layers "*.Cu" "*.Mask")
			(remove_unused_layers no)
			(net "GND")
			(clearance 0.1016)
			(thermal_gap 0.1016)
		)
		(pad "9" thru_hole circle
			(at 1.27 0.762 90)
			(size 0.7112 0.7112)
			(drill 0.4064)
			(layers "*.Cu" "*.Mask")
			(remove_unused_layers no)
			(net "GND")
			(clearance 0.1016)
			(thermal_gap 0.1016)
		)
		(pad "10" thru_hole circle
			(at -0.0254 0.762 90)
			(size 0.7112 0.7112)
			(drill 0.4064)
			(layers "*.Cu" "*.Mask")
			(remove_unused_layers no)
			(net "GND")
			(clearance 0.1016)
			(thermal_gap 0.1016)
		)
		(pad "11" thru_hole circle
			(at -1.27 0.762 90)
			(size 0.7112 0.7112)
			(drill 0.4064)
			(layers "*.Cu" "*.Mask")
			(remove_unused_layers no)
			(net "GND")
			(clearance 0.1016)
			(thermal_gap 0.1016)
		)
		(pad "12" thru_hole circle
			(at -1.27 -0.4572 90)
			(size 0.7112 0.7112)
			(drill 0.4064)
			(layers "*.Cu" "*.Mask")
			(remove_unused_layers no)
			(net "GND")
			(clearance 0.1016)
			(thermal_gap 0.1016)
		)
	)
	(footprint ""
		(layer "F.Cu")
		(at 39.0906 -52.9082 -90)
		(property "Reference" "CT23"
			(at -0.8382 -0.67818 270)
			(unlocked yes)
			(layer "F.SilkS")
			(effects
				(font
					(size 0.4064 0.254)
					(thickness 0.1524)
				)
				(justify left)
			)
		)
		(property "Value" ""
			(at 0 0 270)
			(layer "F.Fab")
			(effects
				(font
					(size 1.27 1.27)
				)
			)
		)
		(duplicate_pad_numbers_are_jumpers no)
		(fp_poly
			(pts
				(xy 0.3048 -0.1016) (xy 0.3048 0.9906) (xy -0.3048 0.9906) (xy -0.3048 -0.1016)
			)
			(stroke
				(width 0)
				(type default)
			)
			(fill no)
			(layer "F.CrtYd")
		)
		(fp_line
			(start -0.3048 0.9906)
			(end 0.3048 0.9906)
			(stroke
				(width 0.1)
				(type default)
			)
			(layer "F.Fab")
		)
		(fp_line
			(start 0.3048 0.9906)
			(end 0.3048 -0.1016)
			(stroke
				(width 0.1)
				(type default)
			)
			(layer "F.Fab")
		)
		(fp_line
			(start -0.3048 -0.1016)
			(end -0.3048 0.9906)
			(stroke
				(width 0.1)
				(type default)
			)
			(layer "F.Fab")
		)
		(fp_line
			(start 0.3048 -0.1016)
			(end -0.3048 -0.1016)
			(stroke
				(width 0.1)
				(type default)
			)
			(layer "F.Fab")
		)
		(pad "1" smd rect
			(at 0 0 270)
			(size 0.508 0.508)
			(layers "F.Cu" "F.Mask" "F.Paste")
			(net "VR_PVCCIN_CPU1_PHASE1")
		)
		(pad "2" smd rect
			(at 0 0.889 270)
			(size 0.508 0.508)
			(layers "F.Cu" "F.Mask" "F.Paste")
			(net "VR_PVCCIN_CPU1_PHASE1_RC")
		)
		(zone
			(layer "F.Cu")
			(hatch none 0.5)
			(connect_pads
				(clearance 0)
			)
			(min_thickness 0.25)
			(keepout
				(tracks not_allowed)
				(vias allowed)
				(pads allowed)
				(copperpour not_allowed)
				(footprints allowed)
			)
			(placement
				(enabled no)
				(sheetname "")
			)
			(fill
				(thermal_gap 0.5)
				(thermal_bridge_width 0.5)
				(island_removal_mode 0)
			)
			(polygon
				(pts
					(xy 38.4556 -53.1622) (xy 38.4556 -52.6542) (xy 38.8366 -52.6542) (xy 38.8366 -53.1622)
				)
			)
		)
		(zone
			(layer "F.Cu")
			(hatch none 0.5)
			(connect_pads
				(clearance 0)
			)
			(min_thickness 0.25)
			(keepout
				(tracks allowed)
				(vias not_allowed)
				(pads allowed)
				(copperpour not_allowed)
				(footprints allowed)
			)
			(placement
				(enabled no)
				(sheetname "")
			)
			(fill
				(thermal_gap 0.5)
				(thermal_bridge_width 0.5)
				(island_removal_mode 0)
			)
			(polygon
				(pts
					(xy 38.8366 -53.1622) (xy 38.8366 -52.6542) (xy 38.4556 -52.6542) (xy 38.4556 -53.1622)
				)
			)
		)
	)
	(footprint ""
		(layer "F.Cu")
		(at 465.5947 -24.8539 -90)
		(property "Reference" "R8E38"
			(at 0 0 270)
			(layer "F.SilkS")
			(hide yes)
			(effects
				(font
					(size 1.27 1.27)
				)
			)
		)
		(property "Value" ""
			(at 0 0 270)
			(layer "F.Fab")
			(effects
				(font
					(size 1.27 1.27)
				)
			)
		)
		(duplicate_pad_numbers_are_jumpers no)
		(fp_rect
			(start 0.2794 0.9906)
			(end -0.2794 -0.1016)
			(stroke
				(width 0)
				(type default)
			)
			(fill no)
			(layer "F.CrtYd")
		)
		(fp_line
			(start -0.2794 0.9906)
			(end 0.2794 0.9906)
			(stroke
				(width 0.1)
				(type default)
			)
			(layer "F.Fab")
		)
		(fp_line
			(start 0.2794 0.9906)
			(end 0.2794 -0.1016)
			(stroke
				(width 0.1)
				(type default)
			)
			(layer "F.Fab")
		)
		(fp_line
			(start -0.2794 -0.1016)
			(end -0.2794 0.9906)
			(stroke
				(width 0.1)
				(type default)
			)
			(layer "F.Fab")
		)
		(fp_line
			(start 0.2794 -0.1016)
			(end -0.2794 -0.1016)
			(stroke
				(width 0.1)
				(type default)
			)
			(layer "F.Fab")
		)
		(pad "1" smd rect
			(at 0 0 270)
			(size 0.508 0.508)
			(layers "F.Cu" "F.Mask" "F.Paste")
			(net "VSENSE_RGND_P3V3_STBY")
		)
		(pad "2" smd rect
			(at 0 0.889 270)
			(size 0.508 0.508)
			(layers "F.Cu" "F.Mask" "F.Paste")
			(net "AGND_P3V3_STBY")
		)
		(zone
			(layer "F.Cu")
			(hatch none 0.5)
			(connect_pads
				(clearance 0)
			)
			(min_thickness 0.25)
			(keepout
				(tracks not_allowed)
				(vias allowed)
				(pads allowed)
				(copperpour not_allowed)
				(footprints allowed)
			)
			(placement
				(enabled no)
				(sheetname "")
			)
			(fill
				(thermal_gap 0.5)
				(thermal_bridge_width 0.5)
				(island_removal_mode 0)
			)
			(polygon
				(pts
					(xy 464.9597 -24.5999) (xy 465.3407 -24.5999) (xy 465.3407 -25.1079) (xy 464.9597 -25.1079)
				)
			)
		)
		(zone
			(layer "F.Cu")
			(hatch none 0.5)
			(connect_pads
				(clearance 0)
			)
			(min_thickness 0.25)
			(keepout
				(tracks allowed)
				(vias not_allowed)
				(pads allowed)
				(copperpour not_allowed)
				(footprints allowed)
			)
			(placement
				(enabled no)
				(sheetname "")
			)
			(fill
				(thermal_gap 0.5)
				(thermal_bridge_width 0.5)
				(island_removal_mode 0)
			)
			(polygon
				(pts
					(xy 464.9597 -24.5999) (xy 465.3407 -24.5999) (xy 465.3407 -25.1079) (xy 464.9597 -25.1079)
				)
			)
		)
	)
	(footprint ""
		(layer "F.Cu")
		(at 387.754876 -158.152084 -90)
		(property "Reference" "RT46"
			(at 1.01473 0.656336 180)
			(unlocked yes)
			(layer "F.SilkS")
			(effects
				(font
					(size 0.4064 0.254)
					(thickness 0.1524)
				)
			)
		)
		(property "Value" ""
			(at 0 0 270)
			(layer "F.Fab")
			(effects
				(font
					(size 1.27 1.27)
				)
			)
		)
		(duplicate_pad_numbers_are_jumpers no)
		(fp_poly
			(pts
				(xy -0.4953 -0.2032) (xy 0.4953 -0.2032) (xy 0.4953 1.6002) (xy -0.4953 1.6002)
			)
			(stroke
				(width 0)
				(type default)
			)
			(fill no)
			(layer "F.CrtYd")
		)
		(fp_line
			(start -0.4953 1.6002)
			(end -0.4953 -0.2032)
			(stroke
				(width 0.1)
				(type default)
			)
			(layer "F.Fab")
		)
		(fp_line
			(start 0.4953 1.6002)
			(end -0.4953 1.6002)
			(stroke
				(width 0.1)
				(type default)
			)
			(layer "F.Fab")
		)
		(fp_line
			(start -0.4953 -0.2032)
			(end 0.4953 -0.2032)
			(stroke
				(width 0.1)
				(type default)
			)
			(layer "F.Fab")
		)
		(fp_line
			(start 0.4953 -0.2032)
			(end 0.4953 1.6002)
			(stroke
				(width 0.1)
				(type default)
			)
			(layer "F.Fab")
		)
		(pad "1" smd rect
			(at 0 0 270)
			(size 0.762 0.889)
			(layers "F.Cu" "F.Mask" "F.Paste")
			(net "VR_P1V05_PCH_STBY_PH1_BOOT")
		)
		(pad "2" smd rect
			(at 0 1.397 270)
			(size 0.762 0.889)
			(layers "F.Cu" "F.Mask" "F.Paste")
			(net "VR_P1V05_PCH_STBY_PH1_BOOT_R")
		)
		(zone
			(layer "F.Cu")
			(hatch none 0.5)
			(connect_pads
				(clearance 0)
			)
			(min_thickness 0.25)
			(keepout
				(tracks not_allowed)
				(vias allowed)
				(pads allowed)
				(copperpour not_allowed)
				(footprints allowed)
			)
			(placement
				(enabled no)
				(sheetname "")
			)
			(fill
				(thermal_gap 0.5)
				(thermal_bridge_width 0.5)
				(island_removal_mode 0)
			)
			(polygon
				(pts
					(xy 386.802376 -158.533084) (xy 386.802376 -157.771084) (xy 387.310376 -157.771084) (xy 387.310376 -158.533084)
				)
			)
		)
		(zone
			(layer "F.Cu")
			(hatch none 0.5)
			(connect_pads
				(clearance 0)
			)
			(min_thickness 0.25)
			(keepout
				(tracks allowed)
				(vias not_allowed)
				(pads allowed)
				(copperpour not_allowed)
				(footprints allowed)
			)
			(placement
				(enabled no)
				(sheetname "")
			)
			(fill
				(thermal_gap 0.5)
				(thermal_bridge_width 0.5)
				(island_removal_mode 0)
			)
			(polygon
				(pts
					(xy 386.802376 -157.771084) (xy 387.310376 -157.771084) (xy 387.310376 -158.533084) (xy 386.802376 -158.533084)
				)
			)
		)
	)
	(footprint ""
		(layer "F.Cu")
		(at 173.5836 -4.5466 90)
		(property "Reference" "C4G13"
			(at 0 0 90)
			(layer "F.SilkS")
			(hide yes)
			(effects
				(font
					(size 1.27 1.27)
				)
			)
		)
		(property "Value" ""
			(at 0 0 90)
			(layer "F.Fab")
			(effects
				(font
					(size 1.27 1.27)
				)
			)
		)
		(duplicate_pad_numbers_are_jumpers no)
		(fp_rect
			(start 0.3048 0.9906)
			(end -0.3048 -0.1016)
			(stroke
				(width 0)
				(type default)
			)
			(fill no)
			(layer "F.CrtYd")
		)
		(fp_line
			(start 0.3048 -0.1016)
			(end -0.3048 -0.1016)
			(stroke
				(width 0.1)
				(type default)
			)
			(layer "F.Fab")
		)
		(fp_line
			(start -0.3048 -0.1016)
			(end -0.3048 0.9906)
			(stroke
				(width 0.1)
				(type default)
			)
			(layer "F.Fab")
		)
		(fp_line
			(start 0.3048 0.9906)
			(end 0.3048 -0.1016)
			(stroke
				(width 0.1)
				(type default)
			)
			(layer "F.Fab")
		)
		(fp_line
			(start -0.3048 0.9906)
			(end 0.3048 0.9906)
			(stroke
				(width 0.1)
				(type default)
			)
			(layer "F.Fab")
		)
		(pad "1" smd rect
			(at 0 0 90)
			(size 0.508 0.508)
			(layers "F.Cu" "F.Mask" "F.Paste")
			(net "PWRGD_PVTT_GHJ_CPU1_R")
		)
		(pad "2" smd rect
			(at 0 0.889 90)
			(size 0.508 0.508)
			(layers "F.Cu" "F.Mask" "F.Paste")
			(net "GND")
		)
		(zone
			(layer "F.Cu")
			(hatch none 0.5)
			(connect_pads
				(clearance 0)
			)
			(min_thickness 0.25)
			(keepout
				(tracks allowed)
				(vias not_allowed)
				(pads allowed)
				(copperpour not_allowed)
				(footprints allowed)
			)
			(placement
				(enabled no)
				(sheetname "")
			)
			(fill
				(thermal_gap 0.5)
				(thermal_bridge_width 0.5)
				(island_removal_mode 0)
			)
			(polygon
				(pts
					(xy 174.2186 -4.8006) (xy 173.8376 -4.8006) (xy 173.8376 -4.2926) (xy 174.2186 -4.2926)
				)
			)
		)
		(zone
			(layer "F.Cu")
			(hatch none 0.5)
			(connect_pads
				(clearance 0)
			)
			(min_thickness 0.25)
			(keepout
				(tracks not_allowed)
				(vias allowed)
				(pads allowed)
				(copperpour not_allowed)
				(footprints allowed)
			)
			(placement
				(enabled no)
				(sheetname "")
			)
			(fill
				(thermal_gap 0.5)
				(thermal_bridge_width 0.5)
				(island_removal_mode 0)
			)
			(polygon
				(pts
					(xy 174.2186 -4.8006) (xy 173.8376 -4.8006) (xy 173.8376 -4.2926) (xy 174.2186 -4.2926)
				)
			)
		)
	)
	(footprint ""
		(layer "F.Cu")
		(at 405.1935 -118.237 90)
		(property "Reference" "C8B14"
			(at 0 0 90)
			(layer "F.SilkS")
			(hide yes)
			(effects
				(font
					(size 1.27 1.27)
				)
			)
		)
		(property "Value" ""
			(at 0 0 90)
			(layer "F.Fab")
			(effects
				(font
					(size 1.27 1.27)
				)
			)
		)
		(duplicate_pad_numbers_are_jumpers no)
		(fp_poly
			(pts
				(xy -0.4953 -0.2032) (xy 0.4953 -0.2032) (xy 0.4953 1.6002) (xy -0.4953 1.6002)
			)
			(stroke
				(width 0)
				(type default)
			)
			(fill no)
			(layer "F.CrtYd")
		)
		(fp_line
			(start 0.4953 -0.2032)
			(end 0.4953 1.6002)
			(stroke
				(width 0.1)
				(type default)
			)
			(layer "F.Fab")
		)
		(fp_line
			(start -0.4953 -0.2032)
			(end 0.4953 -0.2032)
			(stroke
				(width 0.1)
				(type default)
			)
			(layer "F.Fab")
		)
		(fp_line
			(start 0.4953 1.6002)
			(end -0.4953 1.6002)
			(stroke
				(width 0.1)
				(type default)
			)
			(layer "F.Fab")
		)
		(fp_line
			(start -0.4953 1.6002)
			(end -0.4953 -0.2032)
			(stroke
				(width 0.1)
				(type default)
			)
			(layer "F.Fab")
		)
		(pad "1" smd rect
			(at 0 0 90)
			(size 0.762 0.889)
			(layers "F.Cu" "F.Mask" "F.Paste")
			(net "P1V05_PCH_STBY")
		)
		(pad "2" smd rect
			(at 0 1.397 90)
			(size 0.762 0.889)
			(layers "F.Cu" "F.Mask" "F.Paste")
			(net "GND")
		)
		(zone
			(layer "F.Cu")
			(hatch none 0.5)
			(connect_pads
				(clearance 0)
			)
			(min_thickness 0.25)
			(keepout
				(tracks not_allowed)
				(vias allowed)
				(pads allowed)
				(copperpour not_allowed)
				(footprints allowed)
			)
			(placement
				(enabled no)
				(sheetname "")
			)
			(fill
				(thermal_gap 0.5)
				(thermal_bridge_width 0.5)
				(island_removal_mode 0)
			)
			(polygon
				(pts
					(xy 405.638 -117.856) (xy 405.638 -118.618) (xy 406.146 -118.618) (xy 406.146 -117.856)
				)
			)
		)
	)
	(footprint ""
		(layer "F.Cu")
		(at 390.271 1.651 -90)
		(property "Reference" "R8G19"
			(at 0 0 270)
			(layer "F.SilkS")
			(hide yes)
			(effects
				(font
					(size 1.27 1.27)
				)
			)
		)
		(property "Value" ""
			(at 0 0 270)
			(layer "F.Fab")
			(effects
				(font
					(size 1.27 1.27)
				)
			)
		)
		(duplicate_pad_numbers_are_jumpers no)
		(fp_poly
			(pts
				(xy -0.2794 -0.1016) (xy 0.2794 -0.1016) (xy 0.2794 0.9906) (xy -0.2794 0.9906)
			)
			(stroke
				(width 0)
				(type default)
			)
			(fill no)
			(layer "F.CrtYd")
		)
		(fp_line
			(start -0.2794 0.9906)
			(end 0.2794 0.9906)
			(stroke
				(width 0.1)
				(type default)
			)
			(layer "F.Fab")
		)
		(fp_line
			(start 0.2794 0.9906)
			(end 0.2794 -0.1016)
			(stroke
				(width 0.1)
				(type default)
			)
			(layer "F.Fab")
		)
		(fp_line
			(start -0.2794 -0.1016)
			(end -0.2794 0.9906)
			(stroke
				(width 0.1)
				(type default)
			)
			(layer "F.Fab")
		)
		(fp_line
			(start 0.2794 -0.1016)
			(end -0.2794 -0.1016)
			(stroke
				(width 0.1)
				(type default)
			)
			(layer "F.Fab")
		)
		(pad "1" smd rect
			(at 0 0 270)
			(size 0.508 0.508)
			(layers "F.Cu" "F.Mask" "F.Paste")
			(net "JTAG_TDI")
		)
		(pad "2" smd rect
			(at 0 0.889 270)
			(size 0.508 0.508)
			(layers "F.Cu" "F.Mask" "F.Paste")
			(net "JTAG_TDI_R")
		)
		(zone
			(layer "F.Cu")
			(hatch none 0.5)
			(connect_pads
				(clearance 0)
			)
			(min_thickness 0.25)
			(keepout
				(tracks not_allowed)
				(vias allowed)
				(pads allowed)
				(copperpour not_allowed)
				(footprints allowed)
			)
			(placement
				(enabled no)
				(sheetname "")
			)
			(fill
				(thermal_gap 0.5)
				(thermal_bridge_width 0.5)
				(island_removal_mode 0)
			)
			(polygon
				(pts
					(xy 389.636 1.397) (xy 389.636 1.905) (xy 390.017 1.905) (xy 390.017 1.397)
				)
			)
		)
		(zone
			(layer "F.Cu")
			(hatch none 0.5)
			(connect_pads
				(clearance 0)
			)
			(min_thickness 0.25)
			(keepout
				(tracks allowed)
				(vias not_allowed)
				(pads allowed)
				(copperpour not_allowed)
				(footprints allowed)
			)
			(placement
				(enabled no)
				(sheetname "")
			)
			(fill
				(thermal_gap 0.5)
				(thermal_bridge_width 0.5)
				(island_removal_mode 0)
			)
			(polygon
				(pts
					(xy 390.017 1.397) (xy 390.017 1.905) (xy 389.636 1.905) (xy 389.636 1.397)
				)
			)
		)
	)
	(footprint ""
		(layer "F.Cu")
		(at 252.1585 -3.3528 -90)
		(property "Reference" "C5G13"
			(at 1.848866 0.752348 270)
			(unlocked yes)
			(layer "F.SilkS")
			(effects
				(font
					(size 1.27 0.9652)
					(thickness 0.1524)
				)
			)
		)
		(property "Value" ""
			(at 0 0 270)
			(layer "F.Fab")
			(effects
				(font
					(size 1.27 1.27)
				)
			)
		)
		(duplicate_pad_numbers_are_jumpers no)
		(fp_rect
			(start -0.500126 1.598422)
			(end 0.500126 -0.201422)
			(stroke
				(width 0)
				(type default)
			)
			(fill no)
			(layer "F.CrtYd")
		)
		(fp_line
			(start -0.500126 1.598422)
			(end -0.500126 -0.201422)
			(stroke
				(width 0.1)
				(type default)
			)
			(layer "F.Fab")
		)
		(fp_line
			(start 0.500126 1.598422)
			(end -0.500126 1.598422)
			(stroke
				(width 0.1)
				(type default)
			)
			(layer "F.Fab")
		)
		(fp_line
			(start -0.500126 -0.201422)
			(end 0.500126 -0.201422)
			(stroke
				(width 0.1)
				(type default)
			)
			(layer "F.Fab")
		)
		(fp_line
			(start 0.500126 -0.201422)
			(end 0.500126 1.598422)
			(stroke
				(width 0.1)
				(type default)
			)
			(layer "F.Fab")
		)
		(pad "1" smd rect
			(at 0 0 180)
			(size 0.889 0.9906)
			(layers "F.Cu" "F.Mask" "F.Paste")
			(net "PVDDQ_ABC")
		)
		(pad "2" smd rect
			(at 0 1.397 180)
			(size 0.889 0.9906)
			(layers "F.Cu" "F.Mask" "F.Paste")
			(net "GND")
		)
		(zone
			(layer "F.Cu")
			(hatch none 0.5)
			(connect_pads
				(clearance 0)
			)
			(min_thickness 0.25)
			(keepout
				(tracks allowed)
				(vias not_allowed)
				(pads allowed)
				(copperpour not_allowed)
				(footprints allowed)
			)
			(placement
				(enabled no)
				(sheetname "")
			)
			(fill
				(thermal_gap 0.5)
				(thermal_bridge_width 0.5)
				(island_removal_mode 0)
			)
			(polygon
				(pts
					(xy 251.206 -3.8481) (xy 251.206 -2.8575) (xy 251.714 -2.8575) (xy 251.714 -3.8481)
				)
			)
		)
		(zone
			(layer "F.Cu")
			(hatch none 0.5)
			(connect_pads
				(clearance 0)
			)
			(min_thickness 0.25)
			(keepout
				(tracks not_allowed)
				(vias allowed)
				(pads allowed)
				(copperpour not_allowed)
				(footprints allowed)
			)
			(placement
				(enabled no)
				(sheetname "")
			)
			(fill
				(thermal_gap 0.5)
				(thermal_bridge_width 0.5)
				(island_removal_mode 0)
			)
			(polygon
				(pts
					(xy 251.206 -3.8481) (xy 251.206 -2.8575) (xy 251.714 -2.8575) (xy 251.714 -3.8481)
				)
			)
		)
	)
	(footprint ""
		(layer "F.Cu")
		(at 414.126172 -48.083978 180)
		(property "Reference" "C25W21"
			(at -0.8382 -0.67818 180)
			(unlocked yes)
			(layer "F.SilkS")
			(effects
				(font
					(size 0.4064 0.254)
					(thickness 0.1524)
				)
				(justify left)
			)
		)
		(property "Value" ""
			(at 0 0 180)
			(layer "F.Fab")
			(effects
				(font
					(size 1.27 1.27)
				)
			)
		)
		(duplicate_pad_numbers_are_jumpers no)
		(fp_poly
			(pts
				(xy 0.3048 -0.1016) (xy 0.3048 0.9906) (xy -0.3048 0.9906) (xy -0.3048 -0.1016)
			)
			(stroke
				(width 0)
				(type default)
			)
			(fill no)
			(layer "F.CrtYd")
		)
		(fp_line
			(start 0.3048 0.9906)
			(end 0.3048 -0.1016)
			(stroke
				(width 0.1)
				(type default)
			)
			(layer "F.Fab")
		)
		(fp_line
			(start 0.3048 -0.1016)
			(end -0.3048 -0.1016)
			(stroke
				(width 0.1)
				(type default)
			)
			(layer "F.Fab")
		)
		(fp_line
			(start -0.3048 0.9906)
			(end 0.3048 0.9906)
			(stroke
				(width 0.1)
				(type default)
			)
			(layer "F.Fab")
		)
		(fp_line
			(start -0.3048 -0.1016)
			(end -0.3048 0.9906)
			(stroke
				(width 0.1)
				(type default)
			)
			(layer "F.Fab")
		)
		(pad "1" smd rect
			(at 0 0 180)
			(size 0.508 0.508)
			(layers "F.Cu" "F.Mask" "F.Paste")
			(net "P2E_SSB_BMC_RX_DN")
		)
		(pad "2" smd rect
			(at 0 0.889 180)
			(size 0.508 0.508)
			(layers "F.Cu" "F.Mask" "F.Paste")
			(net "P2E_SSB_BMC_RX_C_DN")
		)
		(zone
			(layer "F.Cu")
			(hatch none 0.5)
			(connect_pads
				(clearance 0)
			)
			(min_thickness 0.25)
			(keepout
				(tracks not_allowed)
				(vias allowed)
				(pads allowed)
				(copperpour not_allowed)
				(footprints allowed)
			)
			(placement
				(enabled no)
				(sheetname "")
			)
			(fill
				(thermal_gap 0.5)
				(thermal_bridge_width 0.5)
				(island_removal_mode 0)
			)
			(polygon
				(pts
					(xy 414.380172 -48.718978) (xy 413.872172 -48.718978) (xy 413.872172 -48.337978) (xy 414.380172 -48.337978)
				)
			)
		)
		(zone
			(layer "F.Cu")
			(hatch none 0.5)
			(connect_pads
				(clearance 0)
			)
			(min_thickness 0.25)
			(keepout
				(tracks allowed)
				(vias not_allowed)
				(pads allowed)
				(copperpour not_allowed)
				(footprints allowed)
			)
			(placement
				(enabled no)
				(sheetname "")
			)
			(fill
				(thermal_gap 0.5)
				(thermal_bridge_width 0.5)
				(island_removal_mode 0)
			)
			(polygon
				(pts
					(xy 414.380172 -48.337978) (xy 413.872172 -48.337978) (xy 413.872172 -48.718978) (xy 414.380172 -48.718978)
				)
			)
		)
	)
	(footprint ""
		(layer "F.Cu")
		(at 169.926 -86.868 180)
		(property "Reference" "R4D5"
			(at 0 0 180)
			(layer "F.SilkS")
			(hide yes)
			(effects
				(font
					(size 1.27 1.27)
				)
			)
		)
		(property "Value" ""
			(at 0 0 180)
			(layer "F.Fab")
			(effects
				(font
					(size 1.27 1.27)
				)
			)
		)
		(duplicate_pad_numbers_are_jumpers no)
		(fp_poly
			(pts
				(xy -0.2794 -0.1016) (xy 0.2794 -0.1016) (xy 0.2794 0.9906) (xy -0.2794 0.9906)
			)
			(stroke
				(width 0)
				(type default)
			)
			(fill no)
			(layer "F.CrtYd")
		)
		(fp_line
			(start 0.2794 0.9906)
			(end 0.2794 -0.1016)
			(stroke
				(width 0.1)
				(type default)
			)
			(layer "F.Fab")
		)
		(fp_line
			(start 0.2794 -0.1016)
			(end -0.2794 -0.1016)
			(stroke
				(width 0.1)
				(type default)
			)
			(layer "F.Fab")
		)
		(fp_line
			(start -0.2794 0.9906)
			(end 0.2794 0.9906)
			(stroke
				(width 0.1)
				(type default)
			)
			(layer "F.Fab")
		)
		(fp_line
			(start -0.2794 -0.1016)
			(end -0.2794 0.9906)
			(stroke
				(width 0.1)
				(type default)
			)
			(layer "F.Fab")
		)
		(pad "1" smd rect
			(at 0 0 180)
			(size 0.508 0.508)
			(layers "F.Cu" "F.Mask" "F.Paste")
			(net "CLK_100M_CPU0_RC_REFCLK1_R_DN")
		)
		(pad "2" smd rect
			(at 0 0.889 180)
			(size 0.508 0.508)
			(layers "F.Cu" "F.Mask" "F.Paste")
			(net "CLK_100M_CPU0_RC_REFCLK1_DN")
		)
		(zone
			(layer "F.Cu")
			(hatch none 0.5)
			(connect_pads
				(clearance 0)
			)
			(min_thickness 0.25)
			(keepout
				(tracks not_allowed)
				(vias allowed)
				(pads allowed)
				(copperpour not_allowed)
				(footprints allowed)
			)
			(placement
				(enabled no)
				(sheetname "")
			)
			(fill
				(thermal_gap 0.5)
				(thermal_bridge_width 0.5)
				(island_removal_mode 0)
			)
			(polygon
				(pts
					(xy 170.18 -87.503) (xy 169.672 -87.503) (xy 169.672 -87.122) (xy 170.18 -87.122)
				)
			)
		)
		(zone
			(layer "F.Cu")
			(hatch none 0.5)
			(connect_pads
				(clearance 0)
			)
			(min_thickness 0.25)
			(keepout
				(tracks allowed)
				(vias not_allowed)
				(pads allowed)
				(copperpour not_allowed)
				(footprints allowed)
			)
			(placement
				(enabled no)
				(sheetname "")
			)
			(fill
				(thermal_gap 0.5)
				(thermal_bridge_width 0.5)
				(island_removal_mode 0)
			)
			(polygon
				(pts
					(xy 170.18 -87.122) (xy 169.672 -87.122) (xy 169.672 -87.503) (xy 170.18 -87.503)
				)
			)
		)
	)
	(footprint ""
		(layer "F.Cu")
		(at 456.2475 -25.8572 -90)
		(property "Reference" "C9W5"
			(at -0.8382 -0.67818 270)
			(unlocked yes)
			(layer "F.SilkS")
			(effects
				(font
					(size 0.4064 0.254)
					(thickness 0.1524)
				)
				(justify left)
			)
		)
		(property "Value" ""
			(at 0 0 270)
			(layer "F.Fab")
			(effects
				(font
					(size 1.27 1.27)
				)
			)
		)
		(duplicate_pad_numbers_are_jumpers no)
		(fp_poly
			(pts
				(xy 0.3048 -0.1016) (xy 0.3048 0.9906) (xy -0.3048 0.9906) (xy -0.3048 -0.1016)
			)
			(stroke
				(width 0)
				(type default)
			)
			(fill no)
			(layer "F.CrtYd")
		)
		(fp_line
			(start -0.3048 0.9906)
			(end 0.3048 0.9906)
			(stroke
				(width 0.1)
				(type default)
			)
			(layer "F.Fab")
		)
		(fp_line
			(start 0.3048 0.9906)
			(end 0.3048 -0.1016)
			(stroke
				(width 0.1)
				(type default)
			)
			(layer "F.Fab")
		)
		(fp_line
			(start -0.3048 -0.1016)
			(end -0.3048 0.9906)
			(stroke
				(width 0.1)
				(type default)
			)
			(layer "F.Fab")
		)
		(fp_line
			(start 0.3048 -0.1016)
			(end -0.3048 -0.1016)
			(stroke
				(width 0.1)
				(type default)
			)
			(layer "F.Fab")
		)
		(pad "1" smd rect
			(at 0 0 270)
			(size 0.508 0.508)
			(layers "F.Cu" "F.Mask" "F.Paste")
			(net "P3V3_STBY")
		)
		(pad "2" smd rect
			(at 0 0.889 270)
			(size 0.508 0.508)
			(layers "F.Cu" "F.Mask" "F.Paste")
			(net "GND")
		)
		(zone
			(layer "F.Cu")
			(hatch none 0.5)
			(connect_pads
				(clearance 0)
			)
			(min_thickness 0.25)
			(keepout
				(tracks not_allowed)
				(vias allowed)
				(pads allowed)
				(copperpour not_allowed)
				(footprints allowed)
			)
			(placement
				(enabled no)
				(sheetname "")
			)
			(fill
				(thermal_gap 0.5)
				(thermal_bridge_width 0.5)
				(island_removal_mode 0)
			)
			(polygon
				(pts
					(xy 455.6125 -26.1112) (xy 455.6125 -25.6032) (xy 455.9935 -25.6032) (xy 455.9935 -26.1112)
				)
			)
		)
		(zone
			(layer "F.Cu")
			(hatch none 0.5)
			(connect_pads
				(clearance 0)
			)
			(min_thickness 0.25)
			(keepout
				(tracks allowed)
				(vias not_allowed)
				(pads allowed)
				(copperpour not_allowed)
				(footprints allowed)
			)
			(placement
				(enabled no)
				(sheetname "")
			)
			(fill
				(thermal_gap 0.5)
				(thermal_bridge_width 0.5)
				(island_removal_mode 0)
			)
			(polygon
				(pts
					(xy 455.9935 -26.1112) (xy 455.9935 -25.6032) (xy 455.6125 -25.6032) (xy 455.6125 -26.1112)
				)
			)
		)
	)
	(footprint ""
		(layer "F.Cu")
		(at 109.43844 -73.318116)
		(property "Reference" "C3D18"
			(at 0 0 0)
			(layer "F.SilkS")
			(hide yes)
			(effects
				(font
					(size 1.27 1.27)
				)
			)
		)
		(property "Value" ""
			(at 0 0 0)
			(layer "F.Fab")
			(effects
				(font
					(size 1.27 1.27)
				)
			)
		)
		(duplicate_pad_numbers_are_jumpers no)
		(fp_poly
			(pts
				(xy -0.4953 -0.2032) (xy 0.4953 -0.2032) (xy 0.4953 1.6002) (xy -0.4953 1.6002)
			)
			(stroke
				(width 0)
				(type default)
			)
			(fill no)
			(layer "F.CrtYd")
		)
		(fp_line
			(start -0.4953 -0.2032)
			(end 0.4953 -0.2032)
			(stroke
				(width 0.1)
				(type default)
			)
			(layer "F.Fab")
		)
		(fp_line
			(start -0.4953 1.6002)
			(end -0.4953 -0.2032)
			(stroke
				(width 0.1)
				(type default)
			)
			(layer "F.Fab")
		)
		(fp_line
			(start 0.4953 -0.2032)
			(end 0.4953 1.6002)
			(stroke
				(width 0.1)
				(type default)
			)
			(layer "F.Fab")
		)
		(fp_line
			(start 0.4953 1.6002)
			(end -0.4953 1.6002)
			(stroke
				(width 0.1)
				(type default)
			)
			(layer "F.Fab")
		)
		(pad "1" smd rect
			(at 0 0)
			(size 0.762 0.889)
			(layers "F.Cu" "F.Mask" "F.Paste")
			(net "PVCCMCP_CPU1")
		)
		(pad "2" smd rect
			(at 0 1.397)
			(size 0.762 0.889)
			(layers "F.Cu" "F.Mask" "F.Paste")
			(net "GND")
		)
		(zone
			(layer "F.Cu")
			(hatch none 0.5)
			(connect_pads
				(clearance 0)
			)
			(min_thickness 0.25)
			(keepout
				(tracks not_allowed)
				(vias allowed)
				(pads allowed)
				(copperpour not_allowed)
				(footprints allowed)
			)
			(placement
				(enabled no)
				(sheetname "")
			)
			(fill
				(thermal_gap 0.5)
				(thermal_bridge_width 0.5)
				(island_removal_mode 0)
			)
			(polygon
				(pts
					(xy 109.05744 -72.873616) (xy 109.81944 -72.873616) (xy 109.81944 -72.365616) (xy 109.05744 -72.365616)
				)
			)
		)
	)
	(footprint ""
		(layer "F.Cu")
		(at 0.55118 -12.97432 90)
		(property "Reference" "C1G11"
			(at 0 0 90)
			(layer "F.SilkS")
			(hide yes)
			(effects
				(font
					(size 1.27 1.27)
				)
			)
		)
		(property "Value" ""
			(at 0 0 90)
			(layer "F.Fab")
			(effects
				(font
					(size 1.27 1.27)
				)
			)
		)
		(duplicate_pad_numbers_are_jumpers no)
		(fp_rect
			(start -0.3048 -0.1016)
			(end 0.3048 0.9906)
			(stroke
				(width 0)
				(type default)
			)
			(fill no)
			(layer "F.CrtYd")
		)
		(fp_line
			(start 0.3048 -0.1016)
			(end -0.3048 -0.1016)
			(stroke
				(width 0.1)
				(type default)
			)
			(layer "F.Fab")
		)
		(fp_line
			(start -0.3048 -0.1016)
			(end -0.3048 0.9906)
			(stroke
				(width 0.1)
				(type default)
			)
			(layer "F.Fab")
		)
		(fp_line
			(start 0.3048 0.9906)
			(end 0.3048 -0.1016)
			(stroke
				(width 0.1)
				(type default)
			)
			(layer "F.Fab")
		)
		(fp_line
			(start -0.3048 0.9906)
			(end 0.3048 0.9906)
			(stroke
				(width 0.1)
				(type default)
			)
			(layer "F.Fab")
		)
		(pad "1" smd rect
			(at 0 0 90)
			(size 0.508 0.508)
			(layers "F.Cu" "F.Mask" "F.Paste")
			(net "VR_PVDDQ_GHJ_PH1_BOOT")
		)
		(pad "2" smd rect
			(at 0 0.889 90)
			(size 0.508 0.508)
			(layers "F.Cu" "F.Mask" "F.Paste")
			(net "VR_PVDDQ_GHJ_PH1_PHASE")
		)
		(zone
			(layer "F.Cu")
			(hatch none 0.5)
			(connect_pads
				(clearance 0)
			)
			(min_thickness 0.25)
			(keepout
				(tracks not_allowed)
				(vias allowed)
				(pads allowed)
				(copperpour not_allowed)
				(footprints allowed)
			)
			(placement
				(enabled no)
				(sheetname "")
			)
			(fill
				(thermal_gap 0.5)
				(thermal_bridge_width 0.5)
				(island_removal_mode 0)
			)
			(polygon
				(pts
					(xy 0.80518 -12.72032) (xy 1.18618 -12.72032) (xy 1.18618 -13.22832) (xy 0.80518 -13.22832)
				)
			)
		)
		(zone
			(layer "F.Cu")
			(hatch none 0.5)
			(connect_pads
				(clearance 0)
			)
			(min_thickness 0.25)
			(keepout
				(tracks allowed)
				(vias not_allowed)
				(pads allowed)
				(copperpour not_allowed)
				(footprints allowed)
			)
			(placement
				(enabled no)
				(sheetname "")
			)
			(fill
				(thermal_gap 0.5)
				(thermal_bridge_width 0.5)
				(island_removal_mode 0)
			)
			(polygon
				(pts
					(xy 0.80518 -12.72032) (xy 1.18618 -12.72032) (xy 1.18618 -13.22832) (xy 0.80518 -13.22832)
				)
			)
		)
	)
	(footprint ""
		(layer "F.Cu")
		(at 182.118 -65.024)
		(property "Reference" "R4D65"
			(at 0 0 0)
			(layer "F.SilkS")
			(hide yes)
			(effects
				(font
					(size 1.27 1.27)
				)
			)
		)
		(property "Value" ""
			(at 0 0 0)
			(layer "F.Fab")
			(effects
				(font
					(size 1.27 1.27)
				)
			)
		)
		(duplicate_pad_numbers_are_jumpers no)
		(fp_poly
			(pts
				(xy -0.2794 -0.1016) (xy 0.2794 -0.1016) (xy 0.2794 0.9906) (xy -0.2794 0.9906)
			)
			(stroke
				(width 0)
				(type default)
			)
			(fill no)
			(layer "F.CrtYd")
		)
		(fp_line
			(start -0.2794 -0.1016)
			(end -0.2794 0.9906)
			(stroke
				(width 0.1)
				(type default)
			)
			(layer "F.Fab")
		)
		(fp_line
			(start -0.2794 0.9906)
			(end 0.2794 0.9906)
			(stroke
				(width 0.1)
				(type default)
			)
			(layer "F.Fab")
		)
		(fp_line
			(start 0.2794 -0.1016)
			(end -0.2794 -0.1016)
			(stroke
				(width 0.1)
				(type default)
			)
			(layer "F.Fab")
		)
		(fp_line
			(start 0.2794 0.9906)
			(end 0.2794 -0.1016)
			(stroke
				(width 0.1)
				(type default)
			)
			(layer "F.Fab")
		)
		(pad "1" smd rect
			(at 0 0)
			(size 0.508 0.508)
			(layers "F.Cu" "F.Mask" "F.Paste")
			(net "PWRGD_PVSA_CPU0_R")
		)
		(pad "2" smd rect
			(at 0 0.889)
			(size 0.508 0.508)
			(layers "F.Cu" "F.Mask" "F.Paste")
			(net "PWRGD_PVSA_CPU0")
		)
		(zone
			(layer "F.Cu")
			(hatch none 0.5)
			(connect_pads
				(clearance 0)
			)
			(min_thickness 0.25)
			(keepout
				(tracks allowed)
				(vias not_allowed)
				(pads allowed)
				(copperpour not_allowed)
				(footprints allowed)
			)
			(placement
				(enabled no)
				(sheetname "")
			)
			(fill
				(thermal_gap 0.5)
				(thermal_bridge_width 0.5)
				(island_removal_mode 0)
			)
			(polygon
				(pts
					(xy 181.864 -64.77) (xy 182.372 -64.77) (xy 182.372 -64.389) (xy 181.864 -64.389)
				)
			)
		)
		(zone
			(layer "F.Cu")
			(hatch none 0.5)
			(connect_pads
				(clearance 0)
			)
			(min_thickness 0.25)
			(keepout
				(tracks not_allowed)
				(vias allowed)
				(pads allowed)
				(copperpour not_allowed)
				(footprints allowed)
			)
			(placement
				(enabled no)
				(sheetname "")
			)
			(fill
				(thermal_gap 0.5)
				(thermal_bridge_width 0.5)
				(island_removal_mode 0)
			)
			(polygon
				(pts
					(xy 181.864 -64.389) (xy 182.372 -64.389) (xy 182.372 -64.77) (xy 181.864 -64.77)
				)
			)
		)
	)
	(footprint ""
		(layer "F.Cu")
		(at 3.384042 -13.599414 -90)
		(property "Reference" "C1G28"
			(at 0 0 270)
			(layer "F.SilkS")
			(hide yes)
			(effects
				(font
					(size 1.27 1.27)
				)
			)
		)
		(property "Value" ""
			(at 0 0 270)
			(layer "F.Fab")
			(effects
				(font
					(size 1.27 1.27)
				)
			)
		)
		(duplicate_pad_numbers_are_jumpers no)
		(fp_poly
			(pts
				(xy 0.3048 -0.1016) (xy 0.3048 0.9906) (xy -0.3048 0.9906) (xy -0.3048 -0.1016)
			)
			(stroke
				(width 0)
				(type default)
			)
			(fill no)
			(layer "F.CrtYd")
		)
		(fp_line
			(start -0.3048 0.9906)
			(end 0.3048 0.9906)
			(stroke
				(width 0.1)
				(type default)
			)
			(layer "F.Fab")
		)
		(fp_line
			(start 0.3048 0.9906)
			(end 0.3048 -0.1016)
			(stroke
				(width 0.1)
				(type default)
			)
			(layer "F.Fab")
		)
		(fp_line
			(start -0.3048 -0.1016)
			(end -0.3048 0.9906)
			(stroke
				(width 0.1)
				(type default)
			)
			(layer "F.Fab")
		)
		(fp_line
			(start 0.3048 -0.1016)
			(end -0.3048 -0.1016)
			(stroke
				(width 0.1)
				(type default)
			)
			(layer "F.Fab")
		)
		(pad "1" smd rect
			(at 0 0 270)
			(size 0.508 0.508)
			(layers "F.Cu" "F.Mask" "F.Paste")
			(net "VR_PVDDQ_GHJ_PH2_VCIN")
		)
		(pad "2" smd rect
			(at 0 0.889 270)
			(size 0.508 0.508)
			(layers "F.Cu" "F.Mask" "F.Paste")
			(net "GND")
		)
		(zone
			(layer "F.Cu")
			(hatch none 0.5)
			(connect_pads
				(clearance 0)
			)
			(min_thickness 0.25)
			(keepout
				(tracks not_allowed)
				(vias allowed)
				(pads allowed)
				(copperpour not_allowed)
				(footprints allowed)
			)
			(placement
				(enabled no)
				(sheetname "")
			)
			(fill
				(thermal_gap 0.5)
				(thermal_bridge_width 0.5)
				(island_removal_mode 0)
			)
			(polygon
				(pts
					(xy 2.749042 -13.853414) (xy 2.749042 -13.345414) (xy 3.130042 -13.345414) (xy 3.130042 -13.853414)
				)
			)
		)
		(zone
			(layer "F.Cu")
			(hatch none 0.5)
			(connect_pads
				(clearance 0)
			)
			(min_thickness 0.25)
			(keepout
				(tracks allowed)
				(vias not_allowed)
				(pads allowed)
				(copperpour not_allowed)
				(footprints allowed)
			)
			(placement
				(enabled no)
				(sheetname "")
			)
			(fill
				(thermal_gap 0.5)
				(thermal_bridge_width 0.5)
				(island_removal_mode 0)
			)
			(polygon
				(pts
					(xy 3.130042 -13.853414) (xy 3.130042 -13.345414) (xy 2.749042 -13.345414) (xy 2.749042 -13.853414)
				)
			)
		)
	)
	(footprint ""
		(layer "F.Cu")
		(at 406.120092 -10.917936)
		(property "Reference" "C8G6"
			(at 0 0 0)
			(layer "F.SilkS")
			(hide yes)
			(effects
				(font
					(size 1.27 1.27)
				)
			)
		)
		(property "Value" ""
			(at 0 0 0)
			(layer "F.Fab")
			(effects
				(font
					(size 1.27 1.27)
				)
			)
		)
		(duplicate_pad_numbers_are_jumpers no)
		(fp_rect
			(start -0.3048 0.9906)
			(end 0.3048 -0.1016)
			(stroke
				(width 0)
				(type default)
			)
			(fill no)
			(layer "F.CrtYd")
		)
		(fp_line
			(start -0.3048 -0.1016)
			(end -0.3048 0.9906)
			(stroke
				(width 0.1)
				(type default)
			)
			(layer "F.Fab")
		)
		(fp_line
			(start -0.3048 0.9906)
			(end 0.3048 0.9906)
			(stroke
				(width 0.1)
				(type default)
			)
			(layer "F.Fab")
		)
		(fp_line
			(start 0.3048 -0.1016)
			(end -0.3048 -0.1016)
			(stroke
				(width 0.1)
				(type default)
			)
			(layer "F.Fab")
		)
		(fp_line
			(start 0.3048 0.9906)
			(end 0.3048 -0.1016)
			(stroke
				(width 0.1)
				(type default)
			)
			(layer "F.Fab")
		)
		(pad "1" smd rect
			(at 0 0)
			(size 0.508 0.508)
			(layers "F.Cu" "F.Mask" "F.Paste")
			(net "P3E_CPU0_PE2_SS_TXN<2>")
		)
		(pad "2" smd rect
			(at 0 0.889)
			(size 0.508 0.508)
			(layers "F.Cu" "F.Mask" "F.Paste")
			(net "P3E_CPU0_PE2_SS_C_TXN<2>")
		)
		(zone
			(layer "F.Cu")
			(hatch none 0.5)
			(connect_pads
				(clearance 0)
			)
			(min_thickness 0.25)
			(keepout
				(tracks allowed)
				(vias not_allowed)
				(pads allowed)
				(copperpour not_allowed)
				(footprints allowed)
			)
			(placement
				(enabled no)
				(sheetname "")
			)
			(fill
				(thermal_gap 0.5)
				(thermal_bridge_width 0.5)
				(island_removal_mode 0)
			)
			(polygon
				(pts
					(xy 405.866092 -10.282936) (xy 406.374092 -10.282936) (xy 406.374092 -10.663936) (xy 405.866092 -10.663936)
				)
			)
		)
		(zone
			(layer "F.Cu")
			(hatch none 0.5)
			(connect_pads
				(clearance 0)
			)
			(min_thickness 0.25)
			(keepout
				(tracks not_allowed)
				(vias allowed)
				(pads allowed)
				(copperpour not_allowed)
				(footprints allowed)
			)
			(placement
				(enabled no)
				(sheetname "")
			)
			(fill
				(thermal_gap 0.5)
				(thermal_bridge_width 0.5)
				(island_removal_mode 0)
			)
			(polygon
				(pts
					(xy 405.866092 -10.282936) (xy 406.374092 -10.282936) (xy 406.374092 -10.663936) (xy 405.866092 -10.663936)
				)
			)
		)
	)
	(footprint ""
		(layer "F.Cu")
		(at 7.05231 -134.383526 -90)
		(property "Reference" "CT9"
			(at -0.8382 -0.67818 270)
			(unlocked yes)
			(layer "F.SilkS")
			(effects
				(font
					(size 0.4064 0.254)
					(thickness 0.1524)
				)
				(justify left)
			)
		)
		(property "Value" ""
			(at 0 0 270)
			(layer "F.Fab")
			(effects
				(font
					(size 1.27 1.27)
				)
			)
		)
		(duplicate_pad_numbers_are_jumpers no)
		(fp_poly
			(pts
				(xy 0.3048 -0.1016) (xy 0.3048 0.9906) (xy -0.3048 0.9906) (xy -0.3048 -0.1016)
			)
			(stroke
				(width 0)
				(type default)
			)
			(fill no)
			(layer "F.CrtYd")
		)
		(fp_line
			(start -0.3048 0.9906)
			(end 0.3048 0.9906)
			(stroke
				(width 0.1)
				(type default)
			)
			(layer "F.Fab")
		)
		(fp_line
			(start 0.3048 0.9906)
			(end 0.3048 -0.1016)
			(stroke
				(width 0.1)
				(type default)
			)
			(layer "F.Fab")
		)
		(fp_line
			(start -0.3048 -0.1016)
			(end -0.3048 0.9906)
			(stroke
				(width 0.1)
				(type default)
			)
			(layer "F.Fab")
		)
		(fp_line
			(start 0.3048 -0.1016)
			(end -0.3048 -0.1016)
			(stroke
				(width 0.1)
				(type default)
			)
			(layer "F.Fab")
		)
		(pad "1" smd rect
			(at 0 0 270)
			(size 0.508 0.508)
			(layers "F.Cu" "F.Mask" "F.Paste")
			(net "VR_PVDDQ_KLM_PH1_SW")
		)
		(pad "2" smd rect
			(at 0 0.889 270)
			(size 0.508 0.508)
			(layers "F.Cu" "F.Mask" "F.Paste")
			(net "VR_PVDDQ_KLM_PH1_RC")
		)
		(zone
			(layer "F.Cu")
			(hatch none 0.5)
			(connect_pads
				(clearance 0)
			)
			(min_thickness 0.25)
			(keepout
				(tracks not_allowed)
				(vias allowed)
				(pads allowed)
				(copperpour not_allowed)
				(footprints allowed)
			)
			(placement
				(enabled no)
				(sheetname "")
			)
			(fill
				(thermal_gap 0.5)
				(thermal_bridge_width 0.5)
				(island_removal_mode 0)
			)
			(polygon
				(pts
					(xy 6.41731 -134.637526) (xy 6.41731 -134.129526) (xy 6.79831 -134.129526) (xy 6.79831 -134.637526)
				)
			)
		)
		(zone
			(layer "F.Cu")
			(hatch none 0.5)
			(connect_pads
				(clearance 0)
			)
			(min_thickness 0.25)
			(keepout
				(tracks allowed)
				(vias not_allowed)
				(pads allowed)
				(copperpour not_allowed)
				(footprints allowed)
			)
			(placement
				(enabled no)
				(sheetname "")
			)
			(fill
				(thermal_gap 0.5)
				(thermal_bridge_width 0.5)
				(island_removal_mode 0)
			)
			(polygon
				(pts
					(xy 6.79831 -134.637526) (xy 6.79831 -134.129526) (xy 6.41731 -134.129526) (xy 6.41731 -134.637526)
				)
			)
		)
	)
	(footprint ""
		(layer "F.Cu")
		(at 467.36 -134.366 180)
		(property "Reference" "R9B11"
			(at 0 0 180)
			(layer "F.SilkS")
			(hide yes)
			(effects
				(font
					(size 1.27 1.27)
				)
			)
		)
		(property "Value" ""
			(at 0 0 180)
			(layer "F.Fab")
			(effects
				(font
					(size 1.27 1.27)
				)
			)
		)
		(duplicate_pad_numbers_are_jumpers no)
		(fp_poly
			(pts
				(xy -0.2794 -0.1016) (xy 0.2794 -0.1016) (xy 0.2794 0.9906) (xy -0.2794 0.9906)
			)
			(stroke
				(width 0)
				(type default)
			)
			(fill no)
			(layer "F.CrtYd")
		)
		(fp_line
			(start 0.2794 0.9906)
			(end 0.2794 -0.1016)
			(stroke
				(width 0.1)
				(type default)
			)
			(layer "F.Fab")
		)
		(fp_line
			(start 0.2794 -0.1016)
			(end -0.2794 -0.1016)
			(stroke
				(width 0.1)
				(type default)
			)
			(layer "F.Fab")
		)
		(fp_line
			(start -0.2794 0.9906)
			(end 0.2794 0.9906)
			(stroke
				(width 0.1)
				(type default)
			)
			(layer "F.Fab")
		)
		(fp_line
			(start -0.2794 -0.1016)
			(end -0.2794 0.9906)
			(stroke
				(width 0.1)
				(type default)
			)
			(layer "F.Fab")
		)
		(pad "1" smd rect
			(at 0 0 180)
			(size 0.508 0.508)
			(layers "F.Cu" "F.Mask" "F.Paste")
			(net "JTAG_MCP_TCK")
		)
		(pad "2" smd rect
			(at 0 0.889 180)
			(size 0.508 0.508)
			(layers "F.Cu" "F.Mask" "F.Paste")
			(net "JTAG_MCP_TCK_R")
		)
		(zone
			(layer "F.Cu")
			(hatch none 0.5)
			(connect_pads
				(clearance 0)
			)
			(min_thickness 0.25)
			(keepout
				(tracks not_allowed)
				(vias allowed)
				(pads allowed)
				(copperpour not_allowed)
				(footprints allowed)
			)
			(placement
				(enabled no)
				(sheetname "")
			)
			(fill
				(thermal_gap 0.5)
				(thermal_bridge_width 0.5)
				(island_removal_mode 0)
			)
			(polygon
				(pts
					(xy 467.614 -135.001) (xy 467.106 -135.001) (xy 467.106 -134.62) (xy 467.614 -134.62)
				)
			)
		)
		(zone
			(layer "F.Cu")
			(hatch none 0.5)
			(connect_pads
				(clearance 0)
			)
			(min_thickness 0.25)
			(keepout
				(tracks allowed)
				(vias not_allowed)
				(pads allowed)
				(copperpour not_allowed)
				(footprints allowed)
			)
			(placement
				(enabled no)
				(sheetname "")
			)
			(fill
				(thermal_gap 0.5)
				(thermal_bridge_width 0.5)
				(island_removal_mode 0)
			)
			(polygon
				(pts
					(xy 467.614 -134.62) (xy 467.106 -134.62) (xy 467.106 -135.001) (xy 467.614 -135.001)
				)
			)
		)
	)
	(footprint ""
		(layer "F.Cu")
		(at 405.9555 -102.108 -90)
		(property "Reference" "R2N12"
			(at 0 0 270)
			(layer "F.SilkS")
			(hide yes)
			(effects
				(font
					(size 1.27 1.27)
				)
			)
		)
		(property "Value" ""
			(at 0 0 270)
			(layer "F.Fab")
			(effects
				(font
					(size 1.27 1.27)
				)
			)
		)
		(duplicate_pad_numbers_are_jumpers no)
		(fp_poly
			(pts
				(xy -0.2794 -0.1016) (xy 0.2794 -0.1016) (xy 0.2794 0.9906) (xy -0.2794 0.9906)
			)
			(stroke
				(width 0)
				(type default)
			)
			(fill no)
			(layer "F.CrtYd")
		)
		(fp_line
			(start -0.2794 0.9906)
			(end 0.2794 0.9906)
			(stroke
				(width 0.1)
				(type default)
			)
			(layer "F.Fab")
		)
		(fp_line
			(start 0.2794 0.9906)
			(end 0.2794 -0.1016)
			(stroke
				(width 0.1)
				(type default)
			)
			(layer "F.Fab")
		)
		(fp_line
			(start -0.2794 -0.1016)
			(end -0.2794 0.9906)
			(stroke
				(width 0.1)
				(type default)
			)
			(layer "F.Fab")
		)
		(fp_line
			(start 0.2794 -0.1016)
			(end -0.2794 -0.1016)
			(stroke
				(width 0.1)
				(type default)
			)
			(layer "F.Fab")
		)
		(pad "1" smd rect
			(at 0 0 270)
			(size 0.508 0.508)
			(layers "F.Cu" "F.Mask" "F.Paste")
			(net "GND")
		)
		(pad "2" smd rect
			(at 0 0.889 270)
			(size 0.508 0.508)
			(layers "F.Cu" "F.Mask" "F.Paste")
			(net "PWRGD_SYS_PWROK")
		)
		(zone
			(layer "F.Cu")
			(hatch none 0.5)
			(connect_pads
				(clearance 0)
			)
			(min_thickness 0.25)
			(keepout
				(tracks not_allowed)
				(vias allowed)
				(pads allowed)
				(copperpour not_allowed)
				(footprints allowed)
			)
			(placement
				(enabled no)
				(sheetname "")
			)
			(fill
				(thermal_gap 0.5)
				(thermal_bridge_width 0.5)
				(island_removal_mode 0)
			)
			(polygon
				(pts
					(xy 405.3205 -102.362) (xy 405.3205 -101.854) (xy 405.7015 -101.854) (xy 405.7015 -102.362)
				)
			)
		)
		(zone
			(layer "F.Cu")
			(hatch none 0.5)
			(connect_pads
				(clearance 0)
			)
			(min_thickness 0.25)
			(keepout
				(tracks allowed)
				(vias not_allowed)
				(pads allowed)
				(copperpour not_allowed)
				(footprints allowed)
			)
			(placement
				(enabled no)
				(sheetname "")
			)
			(fill
				(thermal_gap 0.5)
				(thermal_bridge_width 0.5)
				(island_removal_mode 0)
			)
			(polygon
				(pts
					(xy 405.7015 -102.362) (xy 405.7015 -101.854) (xy 405.3205 -101.854) (xy 405.3205 -102.362)
				)
			)
		)
	)
	(footprint ""
		(layer "F.Cu")
		(at 276.27072 -83.88604)
		(property "Reference" "R5D2"
			(at 0 0 0)
			(layer "F.SilkS")
			(hide yes)
			(effects
				(font
					(size 1.27 1.27)
				)
			)
		)
		(property "Value" ""
			(at 0 0 0)
			(layer "F.Fab")
			(effects
				(font
					(size 1.27 1.27)
				)
			)
		)
		(duplicate_pad_numbers_are_jumpers no)
		(fp_poly
			(pts
				(xy -0.2794 -0.1016) (xy 0.2794 -0.1016) (xy 0.2794 0.9906) (xy -0.2794 0.9906)
			)
			(stroke
				(width 0)
				(type default)
			)
			(fill no)
			(layer "F.CrtYd")
		)
		(fp_line
			(start -0.2794 -0.1016)
			(end -0.2794 0.9906)
			(stroke
				(width 0.1)
				(type default)
			)
			(layer "F.Fab")
		)
		(fp_line
			(start -0.2794 0.9906)
			(end 0.2794 0.9906)
			(stroke
				(width 0.1)
				(type default)
			)
			(layer "F.Fab")
		)
		(fp_line
			(start 0.2794 -0.1016)
			(end -0.2794 -0.1016)
			(stroke
				(width 0.1)
				(type default)
			)
			(layer "F.Fab")
		)
		(fp_line
			(start 0.2794 0.9906)
			(end 0.2794 -0.1016)
			(stroke
				(width 0.1)
				(type default)
			)
			(layer "F.Fab")
		)
		(pad "1" smd rect
			(at 0 0)
			(size 0.508 0.508)
			(layers "F.Cu" "F.Mask" "F.Paste")
			(net "A_CPU0_DEF_RCOMP1")
		)
		(pad "2" smd rect
			(at 0 0.889)
			(size 0.508 0.508)
			(layers "F.Cu" "F.Mask" "F.Paste")
			(net "GND")
		)
		(zone
			(layer "F.Cu")
			(hatch none 0.5)
			(connect_pads
				(clearance 0)
			)
			(min_thickness 0.25)
			(keepout
				(tracks allowed)
				(vias not_allowed)
				(pads allowed)
				(copperpour not_allowed)
				(footprints allowed)
			)
			(placement
				(enabled no)
				(sheetname "")
			)
			(fill
				(thermal_gap 0.5)
				(thermal_bridge_width 0.5)
				(island_removal_mode 0)
			)
			(polygon
				(pts
					(xy 276.01672 -83.63204) (xy 276.52472 -83.63204) (xy 276.52472 -83.25104) (xy 276.01672 -83.25104)
				)
			)
		)
		(zone
			(layer "F.Cu")
			(hatch none 0.5)
			(connect_pads
				(clearance 0)
			)
			(min_thickness 0.25)
			(keepout
				(tracks not_allowed)
				(vias allowed)
				(pads allowed)
				(copperpour not_allowed)
				(footprints allowed)
			)
			(placement
				(enabled no)
				(sheetname "")
			)
			(fill
				(thermal_gap 0.5)
				(thermal_bridge_width 0.5)
				(island_removal_mode 0)
			)
			(polygon
				(pts
					(xy 276.01672 -83.25104) (xy 276.52472 -83.25104) (xy 276.52472 -83.63204) (xy 276.01672 -83.63204)
				)
			)
		)
	)
	(footprint ""
		(layer "F.Cu")
		(at 269.559532 -3.3528 90)
		(property "Reference" "C5G16"
			(at 1.848866 0.752348 90)
			(unlocked yes)
			(layer "F.SilkS")
			(effects
				(font
					(size 1.27 0.9652)
					(thickness 0.1524)
				)
			)
		)
		(property "Value" ""
			(at 0 0 90)
			(layer "F.Fab")
			(effects
				(font
					(size 1.27 1.27)
				)
			)
		)
		(duplicate_pad_numbers_are_jumpers no)
		(fp_rect
			(start -0.500126 1.598422)
			(end 0.500126 -0.201422)
			(stroke
				(width 0)
				(type default)
			)
			(fill no)
			(layer "F.CrtYd")
		)
		(fp_line
			(start 0.500126 -0.201422)
			(end 0.500126 1.598422)
			(stroke
				(width 0.1)
				(type default)
			)
			(layer "F.Fab")
		)
		(fp_line
			(start -0.500126 -0.201422)
			(end 0.500126 -0.201422)
			(stroke
				(width 0.1)
				(type default)
			)
			(layer "F.Fab")
		)
		(fp_line
			(start 0.500126 1.598422)
			(end -0.500126 1.598422)
			(stroke
				(width 0.1)
				(type default)
			)
			(layer "F.Fab")
		)
		(fp_line
			(start -0.500126 1.598422)
			(end -0.500126 -0.201422)
			(stroke
				(width 0.1)
				(type default)
			)
			(layer "F.Fab")
		)
		(pad "1" smd rect
			(at 0 0)
			(size 0.889 0.9906)
			(layers "F.Cu" "F.Mask" "F.Paste")
			(net "PVDDQ_ABC")
		)
		(pad "2" smd rect
			(at 0 1.397)
			(size 0.889 0.9906)
			(layers "F.Cu" "F.Mask" "F.Paste")
			(net "GND")
		)
		(zone
			(layer "F.Cu")
			(hatch none 0.5)
			(connect_pads
				(clearance 0)
			)
			(min_thickness 0.25)
			(keepout
				(tracks allowed)
				(vias not_allowed)
				(pads allowed)
				(copperpour not_allowed)
				(footprints allowed)
			)
			(placement
				(enabled no)
				(sheetname "")
			)
			(fill
				(thermal_gap 0.5)
				(thermal_bridge_width 0.5)
				(island_removal_mode 0)
			)
			(polygon
				(pts
					(xy 270.512032 -2.8575) (xy 270.512032 -3.8481) (xy 270.004032 -3.8481) (xy 270.004032 -2.8575)
				)
			)
		)
		(zone
			(layer "F.Cu")
			(hatch none 0.5)
			(connect_pads
				(clearance 0)
			)
			(min_thickness 0.25)
			(keepout
				(tracks not_allowed)
				(vias allowed)
				(pads allowed)
				(copperpour not_allowed)
				(footprints allowed)
			)
			(placement
				(enabled no)
				(sheetname "")
			)
			(fill
				(thermal_gap 0.5)
				(thermal_bridge_width 0.5)
				(island_removal_mode 0)
			)
			(polygon
				(pts
					(xy 270.512032 -2.8575) (xy 270.512032 -3.8481) (xy 270.004032 -3.8481) (xy 270.004032 -2.8575)
				)
			)
		)
	)
	(footprint ""
		(layer "F.Cu")
		(at 341.996776 -11.798046 90)
		(property "Reference" "RF15"
			(at -0.8382 -0.67818 90)
			(unlocked yes)
			(layer "F.SilkS")
			(effects
				(font
					(size 0.4064 0.254)
					(thickness 0.1524)
				)
				(justify left)
			)
		)
		(property "Value" ""
			(at 0 0 90)
			(layer "F.Fab")
			(effects
				(font
					(size 1.27 1.27)
				)
			)
		)
		(duplicate_pad_numbers_are_jumpers no)
		(fp_poly
			(pts
				(xy -0.2794 -0.1016) (xy 0.2794 -0.1016) (xy 0.2794 0.9906) (xy -0.2794 0.9906)
			)
			(stroke
				(width 0)
				(type default)
			)
			(fill no)
			(layer "F.CrtYd")
		)
		(fp_line
			(start 0.2794 -0.1016)
			(end -0.2794 -0.1016)
			(stroke
				(width 0.1)
				(type default)
			)
			(layer "F.Fab")
		)
		(fp_line
			(start -0.2794 -0.1016)
			(end -0.2794 0.9906)
			(stroke
				(width 0.1)
				(type default)
			)
			(layer "F.Fab")
		)
		(fp_line
			(start 0.2794 0.9906)
			(end 0.2794 -0.1016)
			(stroke
				(width 0.1)
				(type default)
			)
			(layer "F.Fab")
		)
		(fp_line
			(start -0.2794 0.9906)
			(end 0.2794 0.9906)
			(stroke
				(width 0.1)
				(type default)
			)
			(layer "F.Fab")
		)
		(pad "1" smd rect
			(at 0 0 90)
			(size 0.508 0.508)
			(layers "F.Cu" "F.Mask" "F.Paste")
			(net "VR_PVDDQ_ABC_AIREF1")
		)
		(pad "2" smd rect
			(at 0 0.889 90)
			(size 0.508 0.508)
			(layers "F.Cu" "F.Mask" "F.Paste")
			(net "ISENSE_PVDDQ_ABC_PH1_IMON")
		)
		(zone
			(layer "F.Cu")
			(hatch none 0.5)
			(connect_pads
				(clearance 0)
			)
			(min_thickness 0.25)
			(keepout
				(tracks allowed)
				(vias not_allowed)
				(pads allowed)
				(copperpour not_allowed)
				(footprints allowed)
			)
			(placement
				(enabled no)
				(sheetname "")
			)
			(fill
				(thermal_gap 0.5)
				(thermal_bridge_width 0.5)
				(island_removal_mode 0)
			)
			(polygon
				(pts
					(xy 342.250776 -11.544046) (xy 342.250776 -12.052046) (xy 342.631776 -12.052046) (xy 342.631776 -11.544046)
				)
			)
		)
		(zone
			(layer "F.Cu")
			(hatch none 0.5)
			(connect_pads
				(clearance 0)
			)
			(min_thickness 0.25)
			(keepout
				(tracks not_allowed)
				(vias allowed)
				(pads allowed)
				(copperpour not_allowed)
				(footprints allowed)
			)
			(placement
				(enabled no)
				(sheetname "")
			)
			(fill
				(thermal_gap 0.5)
				(thermal_bridge_width 0.5)
				(island_removal_mode 0)
			)
			(polygon
				(pts
					(xy 342.631776 -11.544046) (xy 342.631776 -12.052046) (xy 342.250776 -12.052046) (xy 342.250776 -11.544046)
				)
			)
		)
	)
	(footprint ""
		(layer "F.Cu")
		(at 480.335844 -150.39467 180)
		(property "Reference" "J8C1"
			(at 5.66801 2.02184 90)
			(unlocked yes)
			(layer "F.SilkS")
			(effects
				(font
					(size 0.7874 0.5842)
					(thickness 0.1524)
				)
			)
		)
		(property "Value" ""
			(at 0 0 180)
			(layer "F.Fab")
			(effects
				(font
					(size 1.27 1.27)
				)
			)
		)
		(duplicate_pad_numbers_are_jumpers no)
		(fp_line
			(start 1.27 6.54939)
			(end -1.27 6.54939)
			(stroke
				(width 0.1524)
				(type default)
			)
			(layer "F.SilkS")
		)
		(fp_line
			(start 1.27 -1.46939)
			(end 1.27 6.54939)
			(stroke
				(width 0.1524)
				(type default)
			)
			(layer "F.SilkS")
		)
		(fp_line
			(start -1.27 6.54939)
			(end -1.27 -1.46939)
			(stroke
				(width 0.1524)
				(type default)
			)
			(layer "F.SilkS")
		)
		(fp_line
			(start -1.27 -1.46939)
			(end 1.27 -1.46939)
			(stroke
				(width 0.1524)
				(type default)
			)
			(layer "F.SilkS")
		)
		(fp_poly
			(pts
				(xy 2.662682 0.546862) (xy 2.662682 1.562862) (xy 1.392682 1.054862)
			)
			(stroke
				(width 0)
				(type default)
			)
			(fill yes)
			(layer "F.SilkS")
		)
		(fp_poly
			(pts
				(xy 2.148078 -0.52197) (xy 2.148078 0.49403) (xy 0.878078 -0.01397)
			)
			(stroke
				(width 0)
				(type default)
			)
			(fill yes)
			(layer "B.SilkS")
		)
		(fp_poly
			(pts
				(xy 1.27 6.54939) (xy 1.27 -1.46939) (xy -1.27 -1.46939) (xy -1.27 6.54939)
			)
			(stroke
				(width 0)
				(type default)
			)
			(fill no)
			(layer "F.CrtYd")
		)
		(fp_poly
			(pts
				(xy -3.17246 0.38862) (xy -3.17246 -0.62738) (xy -1.90246 -0.11938)
			)
			(stroke
				(width 0)
				(type default)
			)
			(fill yes)
			(layer "B.Fab")
		)
		(fp_line
			(start 1.27 6.54939)
			(end -1.27 6.54939)
			(stroke
				(width 0.1)
				(type default)
			)
			(layer "F.Fab")
		)
		(fp_line
			(start 1.27 -1.46939)
			(end 1.27 6.54939)
			(stroke
				(width 0.1)
				(type default)
			)
			(layer "F.Fab")
		)
		(fp_line
			(start -1.27 6.54939)
			(end -1.27 -1.46939)
			(stroke
				(width 0.1)
				(type default)
			)
			(layer "F.Fab")
		)
		(fp_line
			(start -1.27 -1.46939)
			(end 1.27 -1.46939)
			(stroke
				(width 0.1)
				(type default)
			)
			(layer "F.Fab")
		)
		(fp_poly
			(pts
				(xy -3.17246 0.38862) (xy -3.17246 -0.62738) (xy -1.90246 -0.11938)
			)
			(stroke
				(width 0)
				(type default)
			)
			(fill yes)
			(layer "F.Fab")
		)
		(fp_text user "3"
			(at 2.036064 6.67004 0)
			(unlocked yes)
			(layer "F.SilkS")
			(effects
				(font
					(size 0.7874 0.5842)
					(thickness 0.1524)
				)
				(justify left)
			)
		)
		(fp_text user "3"
			(at 0.258064 6.604 180)
			(unlocked yes)
			(layer "B.SilkS")
			(effects
				(font
					(size 0.7874 0.5842)
					(thickness 0.1524)
				)
				(justify left mirror)
			)
		)
		(fp_text user "3"
			(at 0.247904 6.604 180)
			(unlocked yes)
			(layer "B.Fab")
			(effects
				(font
					(size 0.7874 0.5842)
					(thickness 0.1524)
				)
				(justify left mirror)
			)
		)
		(fp_text user "3"
			(at 1.964944 2.986024 0)
			(unlocked yes)
			(layer "F.Fab")
			(effects
				(font
					(size 0.7874 0.5842)
					(thickness 0.1524)
				)
				(justify left)
			)
		)
		(pad "1" thru_hole rect
			(at 0 0 180)
			(size 1.524 1.524)
			(drill 1.143)
			(layers "*.Cu" "*.Mask")
			(remove_unused_layers no)
			(net "SMB_HOST_STBY_LVC3_SDA")
			(clearance 0.127)
			(thermal_gap 0.127)
			(padstack
				(mode front_inner_back)
				(layer "Inner"
					(shape circle)
					(size 1.524 1.524)
					(clearance 0.127)
				)
				(layer "B.Cu"
					(shape rect)
					(size 1.524 1.524)
					(clearance 0.127)
				)
			)
		)
		(pad "2" thru_hole circle
			(at 0 2.54 180)
			(size 1.524 1.524)
			(drill 1.143)
			(layers "*.Cu" "*.Mask")
			(remove_unused_layers no)
			(net "GND")
			(clearance 0.127)
			(thermal_gap 0.127)
		)
		(pad "3" thru_hole circle
			(at 0 5.08 180)
			(size 1.524 1.524)
			(drill 1.143)
			(layers "*.Cu" "*.Mask")
			(remove_unused_layers no)
			(net "SMB_HOST_STBY_LVC3_SCL")
			(clearance 0.127)
			(thermal_gap 0.127)
		)
	)
	(footprint ""
		(layer "F.Cu")
		(at 221.991936 11.952478 -90)
		(property "Reference" "T1P5"
			(at 0 0 270)
			(layer "F.SilkS")
			(hide yes)
			(effects
				(font
					(size 1.27 1.27)
				)
			)
		)
		(property "Value" "*"
			(at -3.302 1.12395 270)
			(unlocked yes)
			(layer "F.Fab")
			(hide yes)
			(effects
				(font
					(size 0.889 0.889)
					(thickness 0.1524)
				)
			)
		)
		(property "Device Type" "TPAD-DIFF-4P-GP_DISCRET-GB3-TPA"
			(at -3.302 -0.40005 270)
			(unlocked yes)
			(layer "F.Fab")
			(hide yes)
			(effects
				(font
					(size 0.889 0.889)
					(thickness 0.1524)
				)
			)
		)
		(duplicate_pad_numbers_are_jumpers no)
		(fp_line
			(start -2.286 2.286)
			(end 2.286 2.286)
			(stroke
				(width 0.1524)
				(type default)
			)
			(layer "F.SilkS")
		)
		(fp_line
			(start 2.286 2.286)
			(end 2.286 -2.286)
			(stroke
				(width 0.1524)
				(type default)
			)
			(layer "F.SilkS")
		)
		(fp_line
			(start -2.286 -2.286)
			(end -2.286 2.286)
			(stroke
				(width 0.1524)
				(type default)
			)
			(layer "F.SilkS")
		)
		(fp_line
			(start 2.286 -2.286)
			(end -2.286 -2.286)
			(stroke
				(width 0.1524)
				(type default)
			)
			(layer "F.SilkS")
		)
		(fp_line
			(start -2.413 -2.413)
			(end -2.413 -1.143)
			(stroke
				(width 0.4064)
				(type default)
			)
			(layer "F.SilkS")
		)
		(fp_line
			(start -1.143 -2.413)
			(end -2.413 -2.413)
			(stroke
				(width 0.4064)
				(type default)
			)
			(layer "F.SilkS")
		)
		(fp_rect
			(start -2.54 2.54)
			(end 2.54 -2.54)
			(stroke
				(width 0)
				(type default)
			)
			(fill no)
			(layer "F.CrtYd")
		)
		(fp_rect
			(start -2.54 2.54)
			(end 2.54 -2.54)
			(stroke
				(width 0)
				(type default)
			)
			(fill no)
			(layer "F.Fab")
		)
		(pad "1" thru_hole circle
			(at -1.27 -1.27 270)
			(size 1.524 1.524)
			(drill 0.9144)
			(layers "*.Cu" "*.Mask")
			(remove_unused_layers no)
			(net "L12_85OHM_6INCH_DP")
			(clearance -0.0508)
			(thermal_gap 0.127)
			(padstack
				(mode front_inner_back)
				(layer "Inner"
					(shape circle)
					(size 1.1684 1.1684)
					(clearance 0.127)
				)
				(layer "B.Cu"
					(shape circle)
					(size 1.524 1.524)
					(clearance -0.0508)
				)
			)
		)
		(pad "2" thru_hole circle
			(at 1.27 -1.27 270)
			(size 1.524 1.524)
			(drill 0.9144)
			(layers "*.Cu" "*.Mask")
			(remove_unused_layers no)
			(net "L12_85OHM_6INCH_DN")
			(clearance -0.0508)
			(thermal_gap 0.127)
			(padstack
				(mode front_inner_back)
				(layer "Inner"
					(shape circle)
					(size 1.1684 1.1684)
					(clearance 0.127)
				)
				(layer "B.Cu"
					(shape circle)
					(size 1.524 1.524)
					(clearance -0.0508)
				)
			)
		)
		(pad "GND1" thru_hole rect
			(at -1.27 1.27 270)
			(size 1.524 1.524)
			(drill 0.9144)
			(layers "*.Cu" "*.Mask")
			(remove_unused_layers no)
			(net "GND")
			(clearance -0.0508)
			(thermal_gap 0.127)
			(padstack
				(mode front_inner_back)
				(layer "Inner"
					(shape circle)
					(size 1.1684 1.1684)
					(clearance 0.127)
				)
				(layer "B.Cu"
					(shape rect)
					(size 1.524 1.524)
					(clearance -0.0508)
				)
			)
		)
		(pad "GND2" thru_hole rect
			(at 1.27 1.27 270)
			(size 1.524 1.524)
			(drill 0.9144)
			(layers "*.Cu" "*.Mask")
			(remove_unused_layers no)
			(net "GND")
			(clearance -0.0508)
			(thermal_gap 0.127)
			(padstack
				(mode front_inner_back)
				(layer "Inner"
					(shape circle)
					(size 1.1684 1.1684)
					(clearance 0.127)
				)
				(layer "B.Cu"
					(shape rect)
					(size 1.524 1.524)
					(clearance -0.0508)
				)
			)
		)
	)
	(footprint ""
		(layer "F.Cu")
		(at 7.333234 -113.840514 90)
		(property "Reference" "R10W5"
			(at 1.47828 0.78994 0)
			(unlocked yes)
			(layer "F.SilkS")
			(effects
				(font
					(size 0.4064 0.254)
					(thickness 0.1524)
				)
			)
		)
		(property "Value" ""
			(at 0 0 90)
			(layer "F.Fab")
			(effects
				(font
					(size 1.27 1.27)
				)
			)
		)
		(duplicate_pad_numbers_are_jumpers no)
		(fp_poly
			(pts
				(xy -0.7239 -0.2159) (xy 0.7239 -0.2159) (xy 0.7239 1.9939) (xy -0.7239 1.9939)
			)
			(stroke
				(width 0)
				(type default)
			)
			(fill no)
			(layer "F.CrtYd")
		)
		(fp_line
			(start 0.7239 -0.2159)
			(end -0.7239 -0.2159)
			(stroke
				(width 0.1)
				(type default)
			)
			(layer "F.Fab")
		)
		(fp_line
			(start -0.7239 -0.2159)
			(end -0.7239 1.9939)
			(stroke
				(width 0.1)
				(type default)
			)
			(layer "F.Fab")
		)
		(fp_line
			(start 0.7239 1.9939)
			(end 0.7239 -0.2159)
			(stroke
				(width 0.1)
				(type default)
			)
			(layer "F.Fab")
		)
		(fp_line
			(start -0.7239 1.9939)
			(end 0.7239 1.9939)
			(stroke
				(width 0.1)
				(type default)
			)
			(layer "F.Fab")
		)
		(pad "1" smd rect
			(at 0 0 90)
			(size 1.27 1.016)
			(layers "F.Cu" "F.Mask" "F.Paste")
			(net "P12V_FAN")
		)
		(pad "2" smd rect
			(at 0 1.778 90)
			(size 1.27 1.016)
			(layers "F.Cu" "F.Mask" "F.Paste")
			(net "P12V_PUMP")
		)
		(zone
			(layer "F.Cu")
			(hatch none 0.5)
			(connect_pads
				(clearance 0)
			)
			(min_thickness 0.25)
			(keepout
				(tracks not_allowed)
				(vias allowed)
				(pads allowed)
				(copperpour not_allowed)
				(footprints allowed)
			)
			(placement
				(enabled no)
				(sheetname "")
			)
			(fill
				(thermal_gap 0.5)
				(thermal_bridge_width 0.5)
				(island_removal_mode 0)
			)
			(polygon
				(pts
					(xy 7.841234 -114.475514) (xy 8.603234 -114.475514) (xy 8.603234 -114.386614) (xy 8.603234 -113.205514)
					(xy 7.841234 -113.205514)
				)
			)
		)
	)
	(footprint ""
		(layer "F.Cu")
		(at 313.299602 -34.652458)
		(property "Reference" "Q1W6"
			(at -0.229362 -1.59512 0)
			(unlocked yes)
			(layer "F.SilkS")
			(effects
				(font
					(size 1.27 0.9652)
					(thickness 0.1524)
				)
				(justify left)
			)
		)
		(property "Value" ""
			(at 0 0 0)
			(layer "F.Fab")
			(effects
				(font
					(size 1.27 1.27)
				)
			)
		)
		(duplicate_pad_numbers_are_jumpers no)
		(fp_line
			(start 0.381 0.635)
			(end 0.381 1.27)
			(stroke
				(width 0.1524)
				(type default)
			)
			(layer "F.SilkS")
		)
		(fp_line
			(start 0.9525 -0.5715)
			(end 1.778 -0.5715)
			(stroke
				(width 0.1524)
				(type default)
			)
			(layer "F.SilkS")
		)
		(fp_line
			(start 0.9525 2.4765)
			(end 1.778 2.4765)
			(stroke
				(width 0.1524)
				(type default)
			)
			(layer "F.SilkS")
		)
		(fp_line
			(start 1.778 -0.5715)
			(end 1.778 0.3175)
			(stroke
				(width 0.1524)
				(type default)
			)
			(layer "F.SilkS")
		)
		(fp_line
			(start 1.778 2.4765)
			(end 1.778 1.5875)
			(stroke
				(width 0.1524)
				(type default)
			)
			(layer "F.SilkS")
		)
		(fp_circle
			(center -0.37846 -0.885952)
			(end -0.25146 -0.885952)
			(stroke
				(width 0.254)
				(type default)
			)
			(fill no)
			(layer "F.SilkS")
		)
		(fp_poly
			(pts
				(xy 1.778 2.4765) (xy 0.381 2.4765) (xy 0.381 -0.5715) (xy 1.778 -0.5715)
			)
			(stroke
				(width 0)
				(type default)
			)
			(fill no)
			(layer "F.CrtYd")
		)
		(fp_line
			(start 0.381 -0.5715)
			(end 0.381 2.4765)
			(stroke
				(width 0.1)
				(type default)
			)
			(layer "F.Fab")
		)
		(fp_line
			(start 0.381 2.4765)
			(end 1.778 2.4765)
			(stroke
				(width 0.1)
				(type default)
			)
			(layer "F.Fab")
		)
		(fp_line
			(start 1.778 -0.5715)
			(end 0.381 -0.5715)
			(stroke
				(width 0.1)
				(type default)
			)
			(layer "F.Fab")
		)
		(fp_line
			(start 1.778 2.4765)
			(end 1.778 -0.5715)
			(stroke
				(width 0.1)
				(type default)
			)
			(layer "F.Fab")
		)
		(fp_circle
			(center -0.37846 -0.885952)
			(end -0.25146 -0.885952)
			(stroke
				(width 0.254)
				(type default)
			)
			(fill no)
			(layer "F.Fab")
		)
		(pad "1" smd rect
			(at 0 0)
			(size 1.143 0.508)
			(layers "F.Cu" "F.Mask" "F.Paste")
			(net "FM_ADR_COMPLETE_CPU1_R")
		)
		(pad "2" smd rect
			(at 0 1.905)
			(size 1.143 0.508)
			(layers "F.Cu" "F.Mask" "F.Paste")
			(net "GND")
		)
		(pad "3" smd rect
			(at 2.159 0.9525)
			(size 1.143 0.508)
			(layers "F.Cu" "F.Mask" "F.Paste")
			(net "FM_ADR_COMPLETE_CPU1_N")
		)
	)
	(footprint ""
		(layer "F.Cu")
		(at 451.612 -25.4254 90)
		(property "Reference" "C9W13"
			(at 1.47828 0.78994 0)
			(unlocked yes)
			(layer "F.SilkS")
			(effects
				(font
					(size 0.4064 0.254)
					(thickness 0.1524)
				)
			)
		)
		(property "Value" ""
			(at 0 0 90)
			(layer "F.Fab")
			(effects
				(font
					(size 1.27 1.27)
				)
			)
		)
		(duplicate_pad_numbers_are_jumpers no)
		(fp_poly
			(pts
				(xy -0.7239 -0.2159) (xy 0.7239 -0.2159) (xy 0.7239 1.9939) (xy -0.7239 1.9939)
			)
			(stroke
				(width 0)
				(type default)
			)
			(fill no)
			(layer "F.CrtYd")
		)
		(fp_line
			(start 0.7239 -0.2159)
			(end -0.7239 -0.2159)
			(stroke
				(width 0.1)
				(type default)
			)
			(layer "F.Fab")
		)
		(fp_line
			(start -0.7239 -0.2159)
			(end -0.7239 1.9939)
			(stroke
				(width 0.1)
				(type default)
			)
			(layer "F.Fab")
		)
		(fp_line
			(start 0.7239 1.9939)
			(end 0.7239 -0.2159)
			(stroke
				(width 0.1)
				(type default)
			)
			(layer "F.Fab")
		)
		(fp_line
			(start -0.7239 1.9939)
			(end 0.7239 1.9939)
			(stroke
				(width 0.1)
				(type default)
			)
			(layer "F.Fab")
		)
		(pad "1" smd rect
			(at 0 0 90)
			(size 1.27 1.016)
			(layers "F.Cu" "F.Mask" "F.Paste")
			(net "P2V5_AUX_BMC")
		)
		(pad "2" smd rect
			(at 0 1.778 90)
			(size 1.27 1.016)
			(layers "F.Cu" "F.Mask" "F.Paste")
			(net "GND")
		)
		(zone
			(layer "F.Cu")
			(hatch none 0.5)
			(connect_pads
				(clearance 0)
			)
			(min_thickness 0.25)
			(keepout
				(tracks not_allowed)
				(vias allowed)
				(pads allowed)
				(copperpour not_allowed)
				(footprints allowed)
			)
			(placement
				(enabled no)
				(sheetname "")
			)
			(fill
				(thermal_gap 0.5)
				(thermal_bridge_width 0.5)
				(island_removal_mode 0)
			)
			(polygon
				(pts
					(xy 452.12 -24.7904) (xy 452.12 -26.0604) (xy 452.882 -26.0604) (xy 452.882 -24.7904)
				)
			)
		)
	)
	(footprint ""
		(layer "F.Cu")
		(at 455.40549 -34.744406 90)
		(property "Reference" "Q9E1"
			(at 3.81 -0.98933 90)
			(unlocked yes)
			(layer "F.SilkS")
			(effects
				(font
					(size 0.7874 0.5842)
					(thickness 0.1524)
				)
				(justify left)
			)
		)
		(property "Value" ""
			(at 0 0 90)
			(layer "F.Fab")
			(effects
				(font
					(size 1.27 1.27)
				)
			)
		)
		(duplicate_pad_numbers_are_jumpers no)
		(fp_circle
			(center -0.844804 -0.416052)
			(end -0.844804 -0.289052)
			(stroke
				(width 0.254)
				(type default)
			)
			(fill no)
			(layer "F.SilkS")
		)
		(fp_poly
			(pts
				(xy 0.2159 1.7526) (xy 1.5621 1.7526) (xy 1.5621 -0.4572) (xy 0.2159 -0.4572)
			)
			(stroke
				(width 0)
				(type default)
			)
			(fill no)
			(layer "F.CrtYd")
		)
		(fp_line
			(start 1.5621 -0.45466)
			(end 0.2159 -0.45466)
			(stroke
				(width 0.1)
				(type default)
			)
			(layer "F.Fab")
		)
		(fp_line
			(start 0.2159 -0.45466)
			(end 0.2159 1.75514)
			(stroke
				(width 0.1)
				(type default)
			)
			(layer "F.Fab")
		)
		(fp_line
			(start 1.5621 1.75514)
			(end 1.5621 -0.45466)
			(stroke
				(width 0.1)
				(type default)
			)
			(layer "F.Fab")
		)
		(fp_line
			(start 0.2159 1.75514)
			(end 1.5621 1.75514)
			(stroke
				(width 0.1)
				(type default)
			)
			(layer "F.Fab")
		)
		(fp_circle
			(center -0.508 -0.7874)
			(end -0.508 -0.6604)
			(stroke
				(width 0.254)
				(type default)
			)
			(fill no)
			(layer "F.Fab")
		)
		(pad "1" smd rect
			(at 0 0 90)
			(size 1.016 0.381)
			(layers "F.Cu" "F.Mask" "F.Paste")
			(net "GND")
		)
		(pad "2" smd rect
			(at 0 0.65024 90)
			(size 1.016 0.381)
			(layers "F.Cu" "F.Mask" "F.Paste")
			(net "FM_BMC_HEARTBEAT_N")
		)
		(pad "3" smd rect
			(at 0 1.30048 90)
			(size 1.016 0.381)
			(layers "F.Cu" "F.Mask" "F.Paste")
			(net "FM_HEARTBEAT_LED_K")
		)
		(pad "4" smd rect
			(at 1.778 1.30048 90)
			(size 1.016 0.381)
			(layers "F.Cu" "F.Mask" "F.Paste")
			(net "GND")
		)
		(pad "5" smd rect
			(at 1.778 0.65024 90)
			(size 1.016 0.381)
			(layers "F.Cu" "F.Mask" "F.Paste")
			(net "FM_HEARTBEAT_LED")
		)
		(pad "6" smd rect
			(at 1.778 0 90)
			(size 1.016 0.381)
			(layers "F.Cu" "F.Mask" "F.Paste")
			(net "FM_HEARTBEAT_LED")
		)
		(zone
			(layer "F.Cu")
			(hatch none 0.5)
			(connect_pads
				(clearance 0)
			)
			(min_thickness 0.25)
			(keepout
				(tracks allowed)
				(vias not_allowed)
				(pads allowed)
				(copperpour not_allowed)
				(footprints allowed)
			)
			(placement
				(enabled no)
				(sheetname "")
			)
			(fill
				(thermal_gap 0.5)
				(thermal_bridge_width 0.5)
				(island_removal_mode 0)
			)
			(polygon
				(pts
					(xy 455.21499 -36.014406) (xy 455.21499 -37.030406) (xy 456.90409 -37.030406) (xy 456.90409 -36.014406)
				)
			)
		)
		(zone
			(layer "F.Cu")
			(hatch none 0.5)
			(connect_pads
				(clearance 0)
			)
			(min_thickness 0.25)
			(keepout
				(tracks allowed)
				(vias not_allowed)
				(pads allowed)
				(copperpour not_allowed)
				(footprints allowed)
			)
			(placement
				(enabled no)
				(sheetname "")
			)
			(fill
				(thermal_gap 0.5)
				(thermal_bridge_width 0.5)
				(island_removal_mode 0)
			)
			(polygon
				(pts
					(xy 455.21499 -34.236406) (xy 455.21499 -35.252406) (xy 456.90409 -35.252406) (xy 456.90409 -34.236406)
				)
			)
		)
	)
	(footprint ""
		(layer "F.Cu")
		(at 479.19386 -18.48739)
		(property "Reference" "C9G5"
			(at 0 0 0)
			(layer "F.SilkS")
			(hide yes)
			(effects
				(font
					(size 1.27 1.27)
				)
			)
		)
		(property "Value" ""
			(at 0 0 0)
			(layer "F.Fab")
			(effects
				(font
					(size 1.27 1.27)
				)
			)
		)
		(duplicate_pad_numbers_are_jumpers no)
		(fp_poly
			(pts
				(xy 0.3048 -0.1016) (xy 0.3048 0.9906) (xy -0.3048 0.9906) (xy -0.3048 -0.1016)
			)
			(stroke
				(width 0)
				(type default)
			)
			(fill no)
			(layer "F.CrtYd")
		)
		(fp_line
			(start -0.3048 -0.1016)
			(end -0.3048 0.9906)
			(stroke
				(width 0.1)
				(type default)
			)
			(layer "F.Fab")
		)
		(fp_line
			(start -0.3048 0.9906)
			(end 0.3048 0.9906)
			(stroke
				(width 0.1)
				(type default)
			)
			(layer "F.Fab")
		)
		(fp_line
			(start 0.3048 -0.1016)
			(end -0.3048 -0.1016)
			(stroke
				(width 0.1)
				(type default)
			)
			(layer "F.Fab")
		)
		(fp_line
			(start 0.3048 0.9906)
			(end 0.3048 -0.1016)
			(stroke
				(width 0.1)
				(type default)
			)
			(layer "F.Fab")
		)
		(pad "1" smd rect
			(at 0 0)
			(size 0.508 0.508)
			(layers "F.Cu" "F.Mask" "F.Paste")
			(net "GND_LAN_TRCT1234_C")
		)
		(pad "2" smd rect
			(at 0 0.889)
			(size 0.508 0.508)
			(layers "F.Cu" "F.Mask" "F.Paste")
			(net "GND")
		)
		(zone
			(layer "F.Cu")
			(hatch none 0.5)
			(connect_pads
				(clearance 0)
			)
			(min_thickness 0.25)
			(keepout
				(tracks allowed)
				(vias not_allowed)
				(pads allowed)
				(copperpour not_allowed)
				(footprints allowed)
			)
			(placement
				(enabled no)
				(sheetname "")
			)
			(fill
				(thermal_gap 0.5)
				(thermal_bridge_width 0.5)
				(island_removal_mode 0)
			)
			(polygon
				(pts
					(xy 478.93986 -18.23339) (xy 479.44786 -18.23339) (xy 479.44786 -17.85239) (xy 478.93986 -17.85239)
				)
			)
		)
		(zone
			(layer "F.Cu")
			(hatch none 0.5)
			(connect_pads
				(clearance 0)
			)
			(min_thickness 0.25)
			(keepout
				(tracks not_allowed)
				(vias allowed)
				(pads allowed)
				(copperpour not_allowed)
				(footprints allowed)
			)
			(placement
				(enabled no)
				(sheetname "")
			)
			(fill
				(thermal_gap 0.5)
				(thermal_bridge_width 0.5)
				(island_removal_mode 0)
			)
			(polygon
				(pts
					(xy 478.93986 -17.85239) (xy 479.44786 -17.85239) (xy 479.44786 -18.23339) (xy 478.93986 -18.23339)
				)
			)
		)
	)
	(footprint ""
		(layer "F.Cu")
		(at 1.651 -143.256 90)
		(property "Reference" "C1A13"
			(at 0 0 90)
			(layer "F.SilkS")
			(hide yes)
			(effects
				(font
					(size 1.27 1.27)
				)
			)
		)
		(property "Value" ""
			(at 0 0 90)
			(layer "F.Fab")
			(effects
				(font
					(size 1.27 1.27)
				)
			)
		)
		(duplicate_pad_numbers_are_jumpers no)
		(fp_rect
			(start 0.3048 0.9906)
			(end -0.3048 -0.1016)
			(stroke
				(width 0)
				(type default)
			)
			(fill no)
			(layer "F.CrtYd")
		)
		(fp_line
			(start 0.3048 -0.1016)
			(end -0.3048 -0.1016)
			(stroke
				(width 0.1)
				(type default)
			)
			(layer "F.Fab")
		)
		(fp_line
			(start -0.3048 -0.1016)
			(end -0.3048 0.9906)
			(stroke
				(width 0.1)
				(type default)
			)
			(layer "F.Fab")
		)
		(fp_line
			(start 0.3048 0.9906)
			(end 0.3048 -0.1016)
			(stroke
				(width 0.1)
				(type default)
			)
			(layer "F.Fab")
		)
		(fp_line
			(start -0.3048 0.9906)
			(end 0.3048 0.9906)
			(stroke
				(width 0.1)
				(type default)
			)
			(layer "F.Fab")
		)
		(pad "1" smd rect
			(at 0 0 90)
			(size 0.508 0.508)
			(layers "F.Cu" "F.Mask" "F.Paste")
			(net "P5V_STBY")
		)
		(pad "2" smd rect
			(at 0 0.889 90)
			(size 0.508 0.508)
			(layers "F.Cu" "F.Mask" "F.Paste")
			(net "GND")
		)
		(zone
			(layer "F.Cu")
			(hatch none 0.5)
			(connect_pads
				(clearance 0)
			)
			(min_thickness 0.25)
			(keepout
				(tracks not_allowed)
				(vias allowed)
				(pads allowed)
				(copperpour not_allowed)
				(footprints allowed)
			)
			(placement
				(enabled no)
				(sheetname "")
			)
			(fill
				(thermal_gap 0.5)
				(thermal_bridge_width 0.5)
				(island_removal_mode 0)
			)
			(polygon
				(pts
					(xy 2.286 -143.51) (xy 1.905 -143.51) (xy 1.905 -143.002) (xy 2.286 -143.002)
				)
			)
		)
		(zone
			(layer "F.Cu")
			(hatch none 0.5)
			(connect_pads
				(clearance 0)
			)
			(min_thickness 0.25)
			(keepout
				(tracks allowed)
				(vias not_allowed)
				(pads allowed)
				(copperpour not_allowed)
				(footprints allowed)
			)
			(placement
				(enabled no)
				(sheetname "")
			)
			(fill
				(thermal_gap 0.5)
				(thermal_bridge_width 0.5)
				(island_removal_mode 0)
			)
			(polygon
				(pts
					(xy 2.286 -143.51) (xy 1.905 -143.51) (xy 1.905 -143.002) (xy 2.286 -143.002)
				)
			)
		)
	)
	(footprint ""
		(layer "F.Cu")
		(at 347.850206 -2.254504 90)
		(property "Reference" "C7G40"
			(at 0 0 90)
			(layer "F.SilkS")
			(hide yes)
			(effects
				(font
					(size 1.27 1.27)
				)
			)
		)
		(property "Value" ""
			(at 0 0 90)
			(layer "F.Fab")
			(effects
				(font
					(size 1.27 1.27)
				)
			)
		)
		(duplicate_pad_numbers_are_jumpers no)
		(fp_poly
			(pts
				(xy 0.3048 -0.1016) (xy 0.3048 0.9906) (xy -0.3048 0.9906) (xy -0.3048 -0.1016)
			)
			(stroke
				(width 0)
				(type default)
			)
			(fill no)
			(layer "F.CrtYd")
		)
		(fp_line
			(start 0.3048 -0.1016)
			(end -0.3048 -0.1016)
			(stroke
				(width 0.1)
				(type default)
			)
			(layer "F.Fab")
		)
		(fp_line
			(start -0.3048 -0.1016)
			(end -0.3048 0.9906)
			(stroke
				(width 0.1)
				(type default)
			)
			(layer "F.Fab")
		)
		(fp_line
			(start 0.3048 0.9906)
			(end 0.3048 -0.1016)
			(stroke
				(width 0.1)
				(type default)
			)
			(layer "F.Fab")
		)
		(fp_line
			(start -0.3048 0.9906)
			(end 0.3048 0.9906)
			(stroke
				(width 0.1)
				(type default)
			)
			(layer "F.Fab")
		)
		(pad "1" smd rect
			(at 0 0 90)
			(size 0.508 0.508)
			(layers "F.Cu" "F.Mask" "F.Paste")
			(net "VR_PVDDQ_ABC_PH2_VCIN")
		)
		(pad "2" smd rect
			(at 0 0.889 90)
			(size 0.508 0.508)
			(layers "F.Cu" "F.Mask" "F.Paste")
			(net "GND")
		)
		(zone
			(layer "F.Cu")
			(hatch none 0.5)
			(connect_pads
				(clearance 0)
			)
			(min_thickness 0.25)
			(keepout
				(tracks allowed)
				(vias not_allowed)
				(pads allowed)
				(copperpour not_allowed)
				(footprints allowed)
			)
			(placement
				(enabled no)
				(sheetname "")
			)
			(fill
				(thermal_gap 0.5)
				(thermal_bridge_width 0.5)
				(island_removal_mode 0)
			)
			(polygon
				(pts
					(xy 348.104206 -2.000504) (xy 348.104206 -2.508504) (xy 348.485206 -2.508504) (xy 348.485206 -2.000504)
				)
			)
		)
		(zone
			(layer "F.Cu")
			(hatch none 0.5)
			(connect_pads
				(clearance 0)
			)
			(min_thickness 0.25)
			(keepout
				(tracks not_allowed)
				(vias allowed)
				(pads allowed)
				(copperpour not_allowed)
				(footprints allowed)
			)
			(placement
				(enabled no)
				(sheetname "")
			)
			(fill
				(thermal_gap 0.5)
				(thermal_bridge_width 0.5)
				(island_removal_mode 0)
			)
			(polygon
				(pts
					(xy 348.485206 -2.000504) (xy 348.485206 -2.508504) (xy 348.104206 -2.508504) (xy 348.104206 -2.000504)
				)
			)
		)
	)
	(footprint ""
		(layer "F.Cu")
		(at 195.165218 -86.502748)
		(property "Reference" "CT36"
			(at -4.29387 -6.096 270)
			(unlocked yes)
			(layer "F.SilkS")
			(effects
				(font
					(size 0.7874 0.5842)
					(thickness 0.1524)
				)
				(justify left)
			)
		)
		(property "Value" ""
			(at 0 0 0)
			(layer "F.Fab")
			(effects
				(font
					(size 1.27 1.27)
				)
			)
		)
		(duplicate_pad_numbers_are_jumpers no)
		(fp_poly
			(pts
				(xy 0.3048 -0.1016) (xy 0.3048 0.9906) (xy -0.3048 0.9906) (xy -0.3048 -0.1016)
			)
			(stroke
				(width 0)
				(type default)
			)
			(fill no)
			(layer "F.CrtYd")
		)
		(fp_line
			(start -0.3048 -0.1016)
			(end -0.3048 0.9906)
			(stroke
				(width 0.1)
				(type default)
			)
			(layer "F.Fab")
		)
		(fp_line
			(start -0.3048 0.9906)
			(end 0.3048 0.9906)
			(stroke
				(width 0.1)
				(type default)
			)
			(layer "F.Fab")
		)
		(fp_line
			(start 0.3048 -0.1016)
			(end -0.3048 -0.1016)
			(stroke
				(width 0.1)
				(type default)
			)
			(layer "F.Fab")
		)
		(fp_line
			(start 0.3048 0.9906)
			(end 0.3048 -0.1016)
			(stroke
				(width 0.1)
				(type default)
			)
			(layer "F.Fab")
		)
		(pad "1" smd rect
			(at 0 0)
			(size 0.508 0.508)
			(layers "F.Cu" "F.Mask" "F.Paste")
			(net "VR_PVCCIN_CPU0_AIREF5")
		)
		(pad "2" smd rect
			(at 0 0.889)
			(size 0.508 0.508)
			(layers "F.Cu" "F.Mask" "F.Paste")
			(net "GND")
		)
		(zone
			(layer "F.Cu")
			(hatch none 0.5)
			(connect_pads
				(clearance 0)
			)
			(min_thickness 0.25)
			(keepout
				(tracks allowed)
				(vias not_allowed)
				(pads allowed)
				(copperpour not_allowed)
				(footprints allowed)
			)
			(placement
				(enabled no)
				(sheetname "")
			)
			(fill
				(thermal_gap 0.5)
				(thermal_bridge_width 0.5)
				(island_removal_mode 0)
			)
			(polygon
				(pts
					(xy 194.911218 -86.248748) (xy 195.419218 -86.248748) (xy 195.419218 -85.867748) (xy 194.911218 -85.867748)
				)
			)
		)
		(zone
			(layer "F.Cu")
			(hatch none 0.5)
			(connect_pads
				(clearance 0)
			)
			(min_thickness 0.25)
			(keepout
				(tracks not_allowed)
				(vias allowed)
				(pads allowed)
				(copperpour not_allowed)
				(footprints allowed)
			)
			(placement
				(enabled no)
				(sheetname "")
			)
			(fill
				(thermal_gap 0.5)
				(thermal_bridge_width 0.5)
				(island_removal_mode 0)
			)
			(polygon
				(pts
					(xy 194.911218 -85.867748) (xy 195.419218 -85.867748) (xy 195.419218 -86.248748) (xy 194.911218 -86.248748)
				)
			)
		)
	)
	(footprint ""
		(layer "F.Cu")
		(at 178.054 -77.978)
		(property "Reference" "R4D24"
			(at 0 0 0)
			(layer "F.SilkS")
			(hide yes)
			(effects
				(font
					(size 1.27 1.27)
				)
			)
		)
		(property "Value" ""
			(at 0 0 0)
			(layer "F.Fab")
			(effects
				(font
					(size 1.27 1.27)
				)
			)
		)
		(duplicate_pad_numbers_are_jumpers no)
		(fp_poly
			(pts
				(xy -0.2794 -0.1016) (xy 0.2794 -0.1016) (xy 0.2794 0.9906) (xy -0.2794 0.9906)
			)
			(stroke
				(width 0)
				(type default)
			)
			(fill no)
			(layer "F.CrtYd")
		)
		(fp_line
			(start -0.2794 -0.1016)
			(end -0.2794 0.9906)
			(stroke
				(width 0.1)
				(type default)
			)
			(layer "F.Fab")
		)
		(fp_line
			(start -0.2794 0.9906)
			(end 0.2794 0.9906)
			(stroke
				(width 0.1)
				(type default)
			)
			(layer "F.Fab")
		)
		(fp_line
			(start 0.2794 -0.1016)
			(end -0.2794 -0.1016)
			(stroke
				(width 0.1)
				(type default)
			)
			(layer "F.Fab")
		)
		(fp_line
			(start 0.2794 0.9906)
			(end 0.2794 -0.1016)
			(stroke
				(width 0.1)
				(type default)
			)
			(layer "F.Fab")
		)
		(pad "1" smd rect
			(at 0 0)
			(size 0.508 0.508)
			(layers "F.Cu" "F.Mask" "F.Paste")
			(net "CLK_100M_CPU0_BCLK1_DP")
		)
		(pad "2" smd rect
			(at 0 0.889)
			(size 0.508 0.508)
			(layers "F.Cu" "F.Mask" "F.Paste")
			(net "GND")
		)
		(zone
			(layer "F.Cu")
			(hatch none 0.5)
			(connect_pads
				(clearance 0)
			)
			(min_thickness 0.25)
			(keepout
				(tracks allowed)
				(vias not_allowed)
				(pads allowed)
				(copperpour not_allowed)
				(footprints allowed)
			)
			(placement
				(enabled no)
				(sheetname "")
			)
			(fill
				(thermal_gap 0.5)
				(thermal_bridge_width 0.5)
				(island_removal_mode 0)
			)
			(polygon
				(pts
					(xy 177.8 -77.724) (xy 178.308 -77.724) (xy 178.308 -77.343) (xy 177.8 -77.343)
				)
			)
		)
		(zone
			(layer "F.Cu")
			(hatch none 0.5)
			(connect_pads
				(clearance 0)
			)
			(min_thickness 0.25)
			(keepout
				(tracks not_allowed)
				(vias allowed)
				(pads allowed)
				(copperpour not_allowed)
				(footprints allowed)
			)
			(placement
				(enabled no)
				(sheetname "")
			)
			(fill
				(thermal_gap 0.5)
				(thermal_bridge_width 0.5)
				(island_removal_mode 0)
			)
			(polygon
				(pts
					(xy 177.8 -77.343) (xy 178.308 -77.343) (xy 178.308 -77.724) (xy 177.8 -77.724)
				)
			)
		)
	)
	(footprint ""
		(layer "F.Cu")
		(at 318.2239 -127.0508 -90)
		(property "Reference" "C6B7"
			(at 3.07467 4.8006 0)
			(unlocked yes)
			(layer "F.SilkS")
			(effects
				(font
					(size 0.7874 0.5842)
					(thickness 0.1524)
				)
				(justify left)
			)
		)
		(property "Value" ""
			(at 0 0 270)
			(layer "F.Fab")
			(effects
				(font
					(size 1.27 1.27)
				)
			)
		)
		(duplicate_pad_numbers_are_jumpers no)
		(fp_line
			(start -2.2987 7.3533)
			(end -1.7272 7.3533)
			(stroke
				(width 0.1524)
				(type default)
			)
			(layer "F.SilkS")
		)
		(fp_line
			(start 1.7272 7.3533)
			(end 2.2987 7.3533)
			(stroke
				(width 0.1524)
				(type default)
			)
			(layer "F.SilkS")
		)
		(fp_line
			(start 2.2987 7.3533)
			(end 2.2987 -0.2413)
			(stroke
				(width 0.1524)
				(type default)
			)
			(layer "F.SilkS")
		)
		(fp_line
			(start -2.032 1.524)
			(end -1.7272 1.524)
			(stroke
				(width 0.1524)
				(type default)
			)
			(layer "F.SilkS")
		)
		(fp_line
			(start 2.032 1.524)
			(end 1.7272 1.524)
			(stroke
				(width 0.1524)
				(type default)
			)
			(layer "F.SilkS")
		)
		(fp_line
			(start -2.2987 -0.2413)
			(end -2.2987 7.3533)
			(stroke
				(width 0.1524)
				(type default)
			)
			(layer "F.SilkS")
		)
		(fp_line
			(start -2.032 -0.2413)
			(end -2.2987 -0.2413)
			(stroke
				(width 0.1524)
				(type default)
			)
			(layer "F.SilkS")
		)
		(fp_line
			(start 2.2987 -0.2413)
			(end 2.032 -0.2413)
			(stroke
				(width 0.1524)
				(type default)
			)
			(layer "F.SilkS")
		)
		(fp_line
			(start -2.032 -1.524)
			(end -2.032 1.524)
			(stroke
				(width 0.1524)
				(type default)
			)
			(layer "F.SilkS")
		)
		(fp_line
			(start -1.7272 -1.524)
			(end -2.032 -1.524)
			(stroke
				(width 0.1524)
				(type default)
			)
			(layer "F.SilkS")
		)
		(fp_line
			(start 1.7272 -1.524)
			(end 2.032 -1.524)
			(stroke
				(width 0.1524)
				(type default)
			)
			(layer "F.SilkS")
		)
		(fp_line
			(start 2.032 -1.524)
			(end 2.032 1.524)
			(stroke
				(width 0.1524)
				(type default)
			)
			(layer "F.SilkS")
		)
		(fp_poly
			(pts
				(xy -2.2987 -0.2413) (xy 2.2987 -0.2413) (xy 2.2987 7.3533) (xy -2.2987 7.3533)
			)
			(stroke
				(width 0)
				(type default)
			)
			(fill no)
			(layer "F.CrtYd")
		)
		(fp_line
			(start -2.2987 7.3533)
			(end -2.2987 -0.2413)
			(stroke
				(width 0.1)
				(type default)
			)
			(layer "F.Fab")
		)
		(fp_line
			(start 2.2987 7.3533)
			(end -2.2987 7.3533)
			(stroke
				(width 0.1)
				(type default)
			)
			(layer "F.Fab")
		)
		(fp_line
			(start -2.2987 -0.2413)
			(end 2.2987 -0.2413)
			(stroke
				(width 0.1)
				(type default)
			)
			(layer "F.Fab")
		)
		(fp_line
			(start 2.2987 -0.2413)
			(end 2.2987 7.3533)
			(stroke
				(width 0.1)
				(type default)
			)
			(layer "F.Fab")
		)
		(pad "1" smd rect
			(at 0 0 270)
			(size 2.54 3.048)
			(layers "F.Cu" "F.Mask" "F.Paste")
			(net "PVPP_DEF")
		)
		(pad "2" smd rect
			(at 0 7.112 270)
			(size 2.54 3.048)
			(layers "F.Cu" "F.Mask" "F.Paste")
			(net "GND")
		)
	)
	(footprint ""
		(layer "F.Cu")
		(at 28.1305 -90.551 90)
		(property "Reference" "RT9"
			(at 1.01473 0.656336 0)
			(unlocked yes)
			(layer "F.SilkS")
			(effects
				(font
					(size 0.4064 0.254)
					(thickness 0.1524)
				)
			)
		)
		(property "Value" ""
			(at 0 0 90)
			(layer "F.Fab")
			(effects
				(font
					(size 1.27 1.27)
				)
			)
		)
		(duplicate_pad_numbers_are_jumpers no)
		(fp_poly
			(pts
				(xy -0.4953 -0.2032) (xy 0.4953 -0.2032) (xy 0.4953 1.6002) (xy -0.4953 1.6002)
			)
			(stroke
				(width 0)
				(type default)
			)
			(fill no)
			(layer "F.CrtYd")
		)
		(fp_line
			(start 0.4953 -0.2032)
			(end 0.4953 1.6002)
			(stroke
				(width 0.1)
				(type default)
			)
			(layer "F.Fab")
		)
		(fp_line
			(start -0.4953 -0.2032)
			(end 0.4953 -0.2032)
			(stroke
				(width 0.1)
				(type default)
			)
			(layer "F.Fab")
		)
		(fp_line
			(start 0.4953 1.6002)
			(end -0.4953 1.6002)
			(stroke
				(width 0.1)
				(type default)
			)
			(layer "F.Fab")
		)
		(fp_line
			(start -0.4953 1.6002)
			(end -0.4953 -0.2032)
			(stroke
				(width 0.1)
				(type default)
			)
			(layer "F.Fab")
		)
		(pad "1" smd rect
			(at 0 0 90)
			(size 0.762 0.889)
			(layers "F.Cu" "F.Mask" "F.Paste")
			(net "VR_PVCCIN_CPU1_PH5_BOOT")
		)
		(pad "2" smd rect
			(at 0 1.397 90)
			(size 0.762 0.889)
			(layers "F.Cu" "F.Mask" "F.Paste")
			(net "VR_PVCCIN_CPU1_PH5_BOOT_R")
		)
		(zone
			(layer "F.Cu")
			(hatch none 0.5)
			(connect_pads
				(clearance 0)
			)
			(min_thickness 0.25)
			(keepout
				(tracks allowed)
				(vias not_allowed)
				(pads allowed)
				(copperpour not_allowed)
				(footprints allowed)
			)
			(placement
				(enabled no)
				(sheetname "")
			)
			(fill
				(thermal_gap 0.5)
				(thermal_bridge_width 0.5)
				(island_removal_mode 0)
			)
			(polygon
				(pts
					(xy 29.083 -90.932) (xy 28.575 -90.932) (xy 28.575 -90.17) (xy 29.083 -90.17)
				)
			)
		)
		(zone
			(layer "F.Cu")
			(hatch none 0.5)
			(connect_pads
				(clearance 0)
			)
			(min_thickness 0.25)
			(keepout
				(tracks not_allowed)
				(vias allowed)
				(pads allowed)
				(copperpour not_allowed)
				(footprints allowed)
			)
			(placement
				(enabled no)
				(sheetname "")
			)
			(fill
				(thermal_gap 0.5)
				(thermal_bridge_width 0.5)
				(island_removal_mode 0)
			)
			(polygon
				(pts
					(xy 29.083 -90.17) (xy 29.083 -90.932) (xy 28.575 -90.932) (xy 28.575 -90.17)
				)
			)
		)
	)
	(footprint ""
		(layer "F.Cu")
		(at 439.293 -12.954 180)
		(property "Reference" "R2U41"
			(at 0 0 180)
			(layer "F.SilkS")
			(hide yes)
			(effects
				(font
					(size 1.27 1.27)
				)
			)
		)
		(property "Value" ""
			(at 0 0 180)
			(layer "F.Fab")
			(effects
				(font
					(size 1.27 1.27)
				)
			)
		)
		(duplicate_pad_numbers_are_jumpers no)
		(fp_poly
			(pts
				(xy -0.2794 -0.1016) (xy 0.2794 -0.1016) (xy 0.2794 0.9906) (xy -0.2794 0.9906)
			)
			(stroke
				(width 0)
				(type default)
			)
			(fill no)
			(layer "F.CrtYd")
		)
		(fp_line
			(start 0.2794 0.9906)
			(end 0.2794 -0.1016)
			(stroke
				(width 0.1)
				(type default)
			)
			(layer "F.Fab")
		)
		(fp_line
			(start 0.2794 -0.1016)
			(end -0.2794 -0.1016)
			(stroke
				(width 0.1)
				(type default)
			)
			(layer "F.Fab")
		)
		(fp_line
			(start -0.2794 0.9906)
			(end 0.2794 0.9906)
			(stroke
				(width 0.1)
				(type default)
			)
			(layer "F.Fab")
		)
		(fp_line
			(start -0.2794 -0.1016)
			(end -0.2794 0.9906)
			(stroke
				(width 0.1)
				(type default)
			)
			(layer "F.Fab")
		)
		(pad "1" smd rect
			(at 0 0 180)
			(size 0.508 0.508)
			(layers "F.Cu" "F.Mask" "F.Paste")
			(net "PVCCIO_CPU0")
		)
		(pad "2" smd rect
			(at 0 0.889 180)
			(size 0.508 0.508)
			(layers "F.Cu" "F.Mask" "F.Paste")
			(net "H_CPU0_MEMDEF_MEMHOT_G_N")
		)
		(zone
			(layer "F.Cu")
			(hatch none 0.5)
			(connect_pads
				(clearance 0)
			)
			(min_thickness 0.25)
			(keepout
				(tracks not_allowed)
				(vias allowed)
				(pads allowed)
				(copperpour not_allowed)
				(footprints allowed)
			)
			(placement
				(enabled no)
				(sheetname "")
			)
			(fill
				(thermal_gap 0.5)
				(thermal_bridge_width 0.5)
				(island_removal_mode 0)
			)
			(polygon
				(pts
					(xy 439.547 -13.589) (xy 439.039 -13.589) (xy 439.039 -13.208) (xy 439.547 -13.208)
				)
			)
		)
		(zone
			(layer "F.Cu")
			(hatch none 0.5)
			(connect_pads
				(clearance 0)
			)
			(min_thickness 0.25)
			(keepout
				(tracks allowed)
				(vias not_allowed)
				(pads allowed)
				(copperpour not_allowed)
				(footprints allowed)
			)
			(placement
				(enabled no)
				(sheetname "")
			)
			(fill
				(thermal_gap 0.5)
				(thermal_bridge_width 0.5)
				(island_removal_mode 0)
			)
			(polygon
				(pts
					(xy 439.547 -13.208) (xy 439.039 -13.208) (xy 439.039 -13.589) (xy 439.547 -13.589)
				)
			)
		)
	)
	(footprint ""
		(layer "F.Cu")
		(at 410.6926 -103.3526)
		(property "Reference" "R7W11"
			(at -0.8382 -0.67818 0)
			(unlocked yes)
			(layer "F.SilkS")
			(effects
				(font
					(size 0.4064 0.254)
					(thickness 0.1524)
				)
				(justify left)
			)
		)
		(property "Value" ""
			(at 0 0 0)
			(layer "F.Fab")
			(effects
				(font
					(size 1.27 1.27)
				)
			)
		)
		(duplicate_pad_numbers_are_jumpers no)
		(fp_poly
			(pts
				(xy -0.2794 -0.1016) (xy 0.2794 -0.1016) (xy 0.2794 0.9906) (xy -0.2794 0.9906)
			)
			(stroke
				(width 0)
				(type default)
			)
			(fill no)
			(layer "F.CrtYd")
		)
		(fp_line
			(start -0.2794 -0.1016)
			(end -0.2794 0.9906)
			(stroke
				(width 0.1)
				(type default)
			)
			(layer "F.Fab")
		)
		(fp_line
			(start -0.2794 0.9906)
			(end 0.2794 0.9906)
			(stroke
				(width 0.1)
				(type default)
			)
			(layer "F.Fab")
		)
		(fp_line
			(start 0.2794 -0.1016)
			(end -0.2794 -0.1016)
			(stroke
				(width 0.1)
				(type default)
			)
			(layer "F.Fab")
		)
		(fp_line
			(start 0.2794 0.9906)
			(end 0.2794 -0.1016)
			(stroke
				(width 0.1)
				(type default)
			)
			(layer "F.Fab")
		)
		(pad "1" smd rect
			(at 0 0)
			(size 0.508 0.508)
			(layers "F.Cu" "F.Mask" "F.Paste")
			(net "FM_CPU1_RC_ERROR_R_N")
		)
		(pad "2" smd rect
			(at 0 0.889)
			(size 0.508 0.508)
			(layers "F.Cu" "F.Mask" "F.Paste")
			(net "FM_CPU1_RC_ERROR_N")
		)
		(zone
			(layer "F.Cu")
			(hatch none 0.5)
			(connect_pads
				(clearance 0)
			)
			(min_thickness 0.25)
			(keepout
				(tracks allowed)
				(vias not_allowed)
				(pads allowed)
				(copperpour not_allowed)
				(footprints allowed)
			)
			(placement
				(enabled no)
				(sheetname "")
			)
			(fill
				(thermal_gap 0.5)
				(thermal_bridge_width 0.5)
				(island_removal_mode 0)
			)
			(polygon
				(pts
					(xy 410.4386 -103.0986) (xy 410.9466 -103.0986) (xy 410.9466 -102.7176) (xy 410.4386 -102.7176)
				)
			)
		)
		(zone
			(layer "F.Cu")
			(hatch none 0.5)
			(connect_pads
				(clearance 0)
			)
			(min_thickness 0.25)
			(keepout
				(tracks not_allowed)
				(vias allowed)
				(pads allowed)
				(copperpour not_allowed)
				(footprints allowed)
			)
			(placement
				(enabled no)
				(sheetname "")
			)
			(fill
				(thermal_gap 0.5)
				(thermal_bridge_width 0.5)
				(island_removal_mode 0)
			)
			(polygon
				(pts
					(xy 410.4386 -102.7176) (xy 410.9466 -102.7176) (xy 410.9466 -103.0986) (xy 410.4386 -103.0986)
				)
			)
		)
	)
	(footprint ""
		(layer "F.Cu")
		(at 479.9076 -22.4282)
		(property "Reference" "C8E10"
			(at -0.381 -1.21793 0)
			(unlocked yes)
			(layer "F.SilkS")
			(effects
				(font
					(size 0.7874 0.5842)
					(thickness 0.1524)
				)
			)
		)
		(property "Value" ""
			(at 0 0 0)
			(layer "F.Fab")
			(effects
				(font
					(size 1.27 1.27)
				)
			)
		)
		(duplicate_pad_numbers_are_jumpers no)
		(fp_line
			(start -0.9017 1.953006)
			(end -0.9017 0.823976)
			(stroke
				(width 0.1524)
				(type default)
			)
			(layer "F.SilkS")
		)
		(fp_line
			(start 0.9017 1.953768)
			(end 0.9017 0.824484)
			(stroke
				(width 0.1524)
				(type default)
			)
			(layer "F.SilkS")
		)
		(fp_poly
			(pts
				(xy -0.9017 -0.3048) (xy 0.9017 -0.3048) (xy 0.9017 3.0988) (xy -0.9017 3.0988)
			)
			(stroke
				(width 0)
				(type default)
			)
			(fill no)
			(layer "F.CrtYd")
		)
		(fp_line
			(start -0.9017 -0.3048)
			(end -0.9017 3.0988)
			(stroke
				(width 0.1)
				(type default)
			)
			(layer "F.Fab")
		)
		(fp_line
			(start -0.9017 3.0988)
			(end 0.9017 3.0988)
			(stroke
				(width 0.1)
				(type default)
			)
			(layer "F.Fab")
		)
		(fp_line
			(start 0.9017 -0.3048)
			(end -0.9017 -0.3048)
			(stroke
				(width 0.1)
				(type default)
			)
			(layer "F.Fab")
		)
		(fp_line
			(start 0.9017 3.0988)
			(end 0.9017 -0.3048)
			(stroke
				(width 0.1)
				(type default)
			)
			(layer "F.Fab")
		)
		(pad "1" smd rect
			(at 0 0)
			(size 1.524 1.016)
			(layers "F.Cu" "F.Mask" "F.Paste")
			(net "VR_FET_SW_P12V_STBY_P3V3_STBY")
		)
		(pad "2" smd rect
			(at 0 2.794)
			(size 1.524 1.016)
			(layers "F.Cu" "F.Mask" "F.Paste")
			(net "GND")
		)
		(zone
			(layer "F.Cu")
			(hatch none 0.5)
			(connect_pads
				(clearance 0)
			)
			(min_thickness 0.25)
			(keepout
				(tracks allowed)
				(vias not_allowed)
				(pads allowed)
				(copperpour not_allowed)
				(footprints allowed)
			)
			(placement
				(enabled no)
				(sheetname "")
			)
			(fill
				(thermal_gap 0.5)
				(thermal_bridge_width 0.5)
				(island_removal_mode 0)
			)
			(polygon
				(pts
					(xy 480.6696 -21.9202) (xy 480.6696 -20.1422) (xy 479.1456 -20.1422) (xy 479.1456 -21.9202)
				)
			)
		)
	)
	(footprint ""
		(layer "F.Cu")
		(at 433.07 -15.113)
		(property "Reference" "R6W45"
			(at -0.8382 -0.67818 0)
			(unlocked yes)
			(layer "F.SilkS")
			(effects
				(font
					(size 0.4064 0.254)
					(thickness 0.1524)
				)
				(justify left)
			)
		)
		(property "Value" ""
			(at 0 0 0)
			(layer "F.Fab")
			(effects
				(font
					(size 1.27 1.27)
				)
			)
		)
		(duplicate_pad_numbers_are_jumpers no)
		(fp_poly
			(pts
				(xy -0.2794 -0.1016) (xy 0.2794 -0.1016) (xy 0.2794 0.9906) (xy -0.2794 0.9906)
			)
			(stroke
				(width 0)
				(type default)
			)
			(fill no)
			(layer "F.CrtYd")
		)
		(fp_line
			(start -0.2794 -0.1016)
			(end -0.2794 0.9906)
			(stroke
				(width 0.1)
				(type default)
			)
			(layer "F.Fab")
		)
		(fp_line
			(start -0.2794 0.9906)
			(end 0.2794 0.9906)
			(stroke
				(width 0.1)
				(type default)
			)
			(layer "F.Fab")
		)
		(fp_line
			(start 0.2794 -0.1016)
			(end -0.2794 -0.1016)
			(stroke
				(width 0.1)
				(type default)
			)
			(layer "F.Fab")
		)
		(fp_line
			(start 0.2794 0.9906)
			(end 0.2794 -0.1016)
			(stroke
				(width 0.1)
				(type default)
			)
			(layer "F.Fab")
		)
		(pad "1" smd rect
			(at 0 0)
			(size 0.508 0.508)
			(layers "F.Cu" "F.Mask" "F.Paste")
			(net "PCA9554_A2")
		)
		(pad "2" smd rect
			(at 0 0.889)
			(size 0.508 0.508)
			(layers "F.Cu" "F.Mask" "F.Paste")
			(net "GND")
		)
		(zone
			(layer "F.Cu")
			(hatch none 0.5)
			(connect_pads
				(clearance 0)
			)
			(min_thickness 0.25)
			(keepout
				(tracks allowed)
				(vias not_allowed)
				(pads allowed)
				(copperpour not_allowed)
				(footprints allowed)
			)
			(placement
				(enabled no)
				(sheetname "")
			)
			(fill
				(thermal_gap 0.5)
				(thermal_bridge_width 0.5)
				(island_removal_mode 0)
			)
			(polygon
				(pts
					(xy 432.816 -14.859) (xy 433.324 -14.859) (xy 433.324 -14.478) (xy 432.816 -14.478)
				)
			)
		)
		(zone
			(layer "F.Cu")
			(hatch none 0.5)
			(connect_pads
				(clearance 0)
			)
			(min_thickness 0.25)
			(keepout
				(tracks not_allowed)
				(vias allowed)
				(pads allowed)
				(copperpour not_allowed)
				(footprints allowed)
			)
			(placement
				(enabled no)
				(sheetname "")
			)
			(fill
				(thermal_gap 0.5)
				(thermal_bridge_width 0.5)
				(island_removal_mode 0)
			)
			(polygon
				(pts
					(xy 432.816 -14.478) (xy 433.324 -14.478) (xy 433.324 -14.859) (xy 432.816 -14.859)
				)
			)
		)
	)
	(footprint ""
		(layer "F.Cu")
		(at 386.842 -87.3125 180)
		(property "Reference" "R7C14"
			(at 0 0 180)
			(layer "F.SilkS")
			(hide yes)
			(effects
				(font
					(size 1.27 1.27)
				)
			)
		)
		(property "Value" ""
			(at 0 0 180)
			(layer "F.Fab")
			(effects
				(font
					(size 1.27 1.27)
				)
			)
		)
		(duplicate_pad_numbers_are_jumpers no)
		(fp_poly
			(pts
				(xy -0.2794 -0.1016) (xy 0.2794 -0.1016) (xy 0.2794 0.9906) (xy -0.2794 0.9906)
			)
			(stroke
				(width 0)
				(type default)
			)
			(fill no)
			(layer "F.CrtYd")
		)
		(fp_line
			(start 0.2794 0.9906)
			(end 0.2794 -0.1016)
			(stroke
				(width 0.1)
				(type default)
			)
			(layer "F.Fab")
		)
		(fp_line
			(start 0.2794 -0.1016)
			(end -0.2794 -0.1016)
			(stroke
				(width 0.1)
				(type default)
			)
			(layer "F.Fab")
		)
		(fp_line
			(start -0.2794 0.9906)
			(end 0.2794 0.9906)
			(stroke
				(width 0.1)
				(type default)
			)
			(layer "F.Fab")
		)
		(fp_line
			(start -0.2794 -0.1016)
			(end -0.2794 0.9906)
			(stroke
				(width 0.1)
				(type default)
			)
			(layer "F.Fab")
		)
		(pad "1" smd rect
			(at 0 0 180)
			(size 0.508 0.508)
			(layers "F.Cu" "F.Mask" "F.Paste")
			(net "RMII_BMC_PCH_SPRNGVLLE_RXER")
		)
		(pad "2" smd rect
			(at 0 0.889 180)
			(size 0.508 0.508)
			(layers "F.Cu" "F.Mask" "F.Paste")
			(net "RMII_BMC_PCH_SPRNGVLLE_RXER_R")
		)
		(zone
			(layer "F.Cu")
			(hatch none 0.5)
			(connect_pads
				(clearance 0)
			)
			(min_thickness 0.25)
			(keepout
				(tracks not_allowed)
				(vias allowed)
				(pads allowed)
				(copperpour not_allowed)
				(footprints allowed)
			)
			(placement
				(enabled no)
				(sheetname "")
			)
			(fill
				(thermal_gap 0.5)
				(thermal_bridge_width 0.5)
				(island_removal_mode 0)
			)
			(polygon
				(pts
					(xy 387.096 -87.9475) (xy 386.588 -87.9475) (xy 386.588 -87.5665) (xy 387.096 -87.5665)
				)
			)
		)
		(zone
			(layer "F.Cu")
			(hatch none 0.5)
			(connect_pads
				(clearance 0)
			)
			(min_thickness 0.25)
			(keepout
				(tracks allowed)
				(vias not_allowed)
				(pads allowed)
				(copperpour not_allowed)
				(footprints allowed)
			)
			(placement
				(enabled no)
				(sheetname "")
			)
			(fill
				(thermal_gap 0.5)
				(thermal_bridge_width 0.5)
				(island_removal_mode 0)
			)
			(polygon
				(pts
					(xy 387.096 -87.5665) (xy 386.588 -87.5665) (xy 386.588 -87.9475) (xy 387.096 -87.9475)
				)
			)
		)
	)
	(footprint ""
		(layer "F.Cu")
		(at 166.624 -150.241 90)
		(property "Reference" "R4A3"
			(at 0 0 90)
			(layer "F.SilkS")
			(hide yes)
			(effects
				(font
					(size 1.27 1.27)
				)
			)
		)
		(property "Value" ""
			(at 0 0 90)
			(layer "F.Fab")
			(effects
				(font
					(size 1.27 1.27)
				)
			)
		)
		(duplicate_pad_numbers_are_jumpers no)
		(fp_poly
			(pts
				(xy -0.2794 -0.1016) (xy 0.2794 -0.1016) (xy 0.2794 0.9906) (xy -0.2794 0.9906)
			)
			(stroke
				(width 0)
				(type default)
			)
			(fill no)
			(layer "F.CrtYd")
		)
		(fp_line
			(start 0.2794 -0.1016)
			(end -0.2794 -0.1016)
			(stroke
				(width 0.1)
				(type default)
			)
			(layer "F.Fab")
		)
		(fp_line
			(start -0.2794 -0.1016)
			(end -0.2794 0.9906)
			(stroke
				(width 0.1)
				(type default)
			)
			(layer "F.Fab")
		)
		(fp_line
			(start 0.2794 0.9906)
			(end 0.2794 -0.1016)
			(stroke
				(width 0.1)
				(type default)
			)
			(layer "F.Fab")
		)
		(fp_line
			(start -0.2794 0.9906)
			(end 0.2794 0.9906)
			(stroke
				(width 0.1)
				(type default)
			)
			(layer "F.Fab")
		)
		(pad "1" smd rect
			(at 0 0 90)
			(size 0.508 0.508)
			(layers "F.Cu" "F.Mask" "F.Paste")
			(net "PWRGD_PVDDQ_KLM_R")
		)
		(pad "2" smd rect
			(at 0 0.889 90)
			(size 0.508 0.508)
			(layers "F.Cu" "F.Mask" "F.Paste")
			(net "FM_PVTT_KLM_EN_R")
		)
		(zone
			(layer "F.Cu")
			(hatch none 0.5)
			(connect_pads
				(clearance 0)
			)
			(min_thickness 0.25)
			(keepout
				(tracks allowed)
				(vias not_allowed)
				(pads allowed)
				(copperpour not_allowed)
				(footprints allowed)
			)
			(placement
				(enabled no)
				(sheetname "")
			)
			(fill
				(thermal_gap 0.5)
				(thermal_bridge_width 0.5)
				(island_removal_mode 0)
			)
			(polygon
				(pts
					(xy 166.878 -149.987) (xy 166.878 -150.495) (xy 167.259 -150.495) (xy 167.259 -149.987)
				)
			)
		)
		(zone
			(layer "F.Cu")
			(hatch none 0.5)
			(connect_pads
				(clearance 0)
			)
			(min_thickness 0.25)
			(keepout
				(tracks not_allowed)
				(vias allowed)
				(pads allowed)
				(copperpour not_allowed)
				(footprints allowed)
			)
			(placement
				(enabled no)
				(sheetname "")
			)
			(fill
				(thermal_gap 0.5)
				(thermal_bridge_width 0.5)
				(island_removal_mode 0)
			)
			(polygon
				(pts
					(xy 167.259 -149.987) (xy 167.259 -150.495) (xy 166.878 -150.495) (xy 166.878 -149.987)
				)
			)
		)
	)
	(footprint ""
		(layer "F.Cu")
		(at 406.172416 -149.452584 -90)
		(property "Reference" "R8A10"
			(at 0 0 270)
			(layer "F.SilkS")
			(hide yes)
			(effects
				(font
					(size 1.27 1.27)
				)
			)
		)
		(property "Value" ""
			(at 0 0 270)
			(layer "F.Fab")
			(effects
				(font
					(size 1.27 1.27)
				)
			)
		)
		(duplicate_pad_numbers_are_jumpers no)
		(fp_poly
			(pts
				(xy -0.2794 -0.1016) (xy 0.2794 -0.1016) (xy 0.2794 0.9906) (xy -0.2794 0.9906)
			)
			(stroke
				(width 0)
				(type default)
			)
			(fill no)
			(layer "F.CrtYd")
		)
		(fp_line
			(start -0.2794 0.9906)
			(end 0.2794 0.9906)
			(stroke
				(width 0.1)
				(type default)
			)
			(layer "F.Fab")
		)
		(fp_line
			(start 0.2794 0.9906)
			(end 0.2794 -0.1016)
			(stroke
				(width 0.1)
				(type default)
			)
			(layer "F.Fab")
		)
		(fp_line
			(start -0.2794 -0.1016)
			(end -0.2794 0.9906)
			(stroke
				(width 0.1)
				(type default)
			)
			(layer "F.Fab")
		)
		(fp_line
			(start 0.2794 -0.1016)
			(end -0.2794 -0.1016)
			(stroke
				(width 0.1)
				(type default)
			)
			(layer "F.Fab")
		)
		(pad "1" smd rect
			(at 0 0 270)
			(size 0.508 0.508)
			(layers "F.Cu" "F.Mask" "F.Paste")
			(net "P3V3_STBY")
		)
		(pad "2" smd rect
			(at 0 0.889 270)
			(size 0.508 0.508)
			(layers "F.Cu" "F.Mask" "F.Paste")
			(net "PWRGD_P1V8_PCH_STBY_R")
		)
		(zone
			(layer "F.Cu")
			(hatch none 0.5)
			(connect_pads
				(clearance 0)
			)
			(min_thickness 0.25)
			(keepout
				(tracks not_allowed)
				(vias allowed)
				(pads allowed)
				(copperpour not_allowed)
				(footprints allowed)
			)
			(placement
				(enabled no)
				(sheetname "")
			)
			(fill
				(thermal_gap 0.5)
				(thermal_bridge_width 0.5)
				(island_removal_mode 0)
			)
			(polygon
				(pts
					(xy 405.537416 -149.706584) (xy 405.537416 -149.198584) (xy 405.918416 -149.198584) (xy 405.918416 -149.706584)
				)
			)
		)
		(zone
			(layer "F.Cu")
			(hatch none 0.5)
			(connect_pads
				(clearance 0)
			)
			(min_thickness 0.25)
			(keepout
				(tracks allowed)
				(vias not_allowed)
				(pads allowed)
				(copperpour not_allowed)
				(footprints allowed)
			)
			(placement
				(enabled no)
				(sheetname "")
			)
			(fill
				(thermal_gap 0.5)
				(thermal_bridge_width 0.5)
				(island_removal_mode 0)
			)
			(polygon
				(pts
					(xy 405.918416 -149.706584) (xy 405.918416 -149.198584) (xy 405.537416 -149.198584) (xy 405.537416 -149.706584)
				)
			)
		)
	)
	(footprint ""
		(layer "F.Cu")
		(at 197.226428 -93.734382 -90)
		(property "Reference" "C4C6"
			(at 0 0 270)
			(layer "F.SilkS")
			(hide yes)
			(effects
				(font
					(size 1.27 1.27)
				)
			)
		)
		(property "Value" ""
			(at 0 0 270)
			(layer "F.Fab")
			(effects
				(font
					(size 1.27 1.27)
				)
			)
		)
		(duplicate_pad_numbers_are_jumpers no)
		(fp_poly
			(pts
				(xy 0.3048 -0.1016) (xy 0.3048 0.9906) (xy -0.3048 0.9906) (xy -0.3048 -0.1016)
			)
			(stroke
				(width 0)
				(type default)
			)
			(fill no)
			(layer "F.CrtYd")
		)
		(fp_line
			(start -0.3048 0.9906)
			(end 0.3048 0.9906)
			(stroke
				(width 0.1)
				(type default)
			)
			(layer "F.Fab")
		)
		(fp_line
			(start 0.3048 0.9906)
			(end 0.3048 -0.1016)
			(stroke
				(width 0.1)
				(type default)
			)
			(layer "F.Fab")
		)
		(fp_line
			(start -0.3048 -0.1016)
			(end -0.3048 0.9906)
			(stroke
				(width 0.1)
				(type default)
			)
			(layer "F.Fab")
		)
		(fp_line
			(start 0.3048 -0.1016)
			(end -0.3048 -0.1016)
			(stroke
				(width 0.1)
				(type default)
			)
			(layer "F.Fab")
		)
		(pad "1" smd rect
			(at 0 0 270)
			(size 0.508 0.508)
			(layers "F.Cu" "F.Mask" "F.Paste")
			(net "VR_PVSA_CPU0_VCIN")
		)
		(pad "2" smd rect
			(at 0 0.889 270)
			(size 0.508 0.508)
			(layers "F.Cu" "F.Mask" "F.Paste")
			(net "GND")
		)
		(zone
			(layer "F.Cu")
			(hatch none 0.5)
			(connect_pads
				(clearance 0)
			)
			(min_thickness 0.25)
			(keepout
				(tracks not_allowed)
				(vias allowed)
				(pads allowed)
				(copperpour not_allowed)
				(footprints allowed)
			)
			(placement
				(enabled no)
				(sheetname "")
			)
			(fill
				(thermal_gap 0.5)
				(thermal_bridge_width 0.5)
				(island_removal_mode 0)
			)
			(polygon
				(pts
					(xy 196.591428 -93.988382) (xy 196.591428 -93.480382) (xy 196.972428 -93.480382) (xy 196.972428 -93.988382)
				)
			)
		)
		(zone
			(layer "F.Cu")
			(hatch none 0.5)
			(connect_pads
				(clearance 0)
			)
			(min_thickness 0.25)
			(keepout
				(tracks allowed)
				(vias not_allowed)
				(pads allowed)
				(copperpour not_allowed)
				(footprints allowed)
			)
			(placement
				(enabled no)
				(sheetname "")
			)
			(fill
				(thermal_gap 0.5)
				(thermal_bridge_width 0.5)
				(island_removal_mode 0)
			)
			(polygon
				(pts
					(xy 196.972428 -93.988382) (xy 196.972428 -93.480382) (xy 196.591428 -93.480382) (xy 196.591428 -93.988382)
				)
			)
		)
	)
	(footprint ""
		(layer "F.Cu")
		(at 368.808 -137.3124)
		(property "Reference" "R7A13"
			(at 0 0 0)
			(layer "F.SilkS")
			(hide yes)
			(effects
				(font
					(size 1.27 1.27)
				)
			)
		)
		(property "Value" ""
			(at 0 0 0)
			(layer "F.Fab")
			(effects
				(font
					(size 1.27 1.27)
				)
			)
		)
		(duplicate_pad_numbers_are_jumpers no)
		(fp_poly
			(pts
				(xy -0.2794 -0.1016) (xy 0.2794 -0.1016) (xy 0.2794 0.9906) (xy -0.2794 0.9906)
			)
			(stroke
				(width 0)
				(type default)
			)
			(fill no)
			(layer "F.CrtYd")
		)
		(fp_line
			(start -0.2794 -0.1016)
			(end -0.2794 0.9906)
			(stroke
				(width 0.1)
				(type default)
			)
			(layer "F.Fab")
		)
		(fp_line
			(start -0.2794 0.9906)
			(end 0.2794 0.9906)
			(stroke
				(width 0.1)
				(type default)
			)
			(layer "F.Fab")
		)
		(fp_line
			(start 0.2794 -0.1016)
			(end -0.2794 -0.1016)
			(stroke
				(width 0.1)
				(type default)
			)
			(layer "F.Fab")
		)
		(fp_line
			(start 0.2794 0.9906)
			(end 0.2794 -0.1016)
			(stroke
				(width 0.1)
				(type default)
			)
			(layer "F.Fab")
		)
		(pad "1" smd rect
			(at 0 0)
			(size 0.508 0.508)
			(layers "F.Cu" "F.Mask" "F.Paste")
			(net "VSENSE_PVNN_PCH_STBY_AVSP")
		)
		(pad "2" smd rect
			(at 0 0.889)
			(size 0.508 0.508)
			(layers "F.Cu" "F.Mask" "F.Paste")
			(net "PVNN_PCH_STBY")
		)
		(zone
			(layer "F.Cu")
			(hatch none 0.5)
			(connect_pads
				(clearance 0)
			)
			(min_thickness 0.25)
			(keepout
				(tracks allowed)
				(vias not_allowed)
				(pads allowed)
				(copperpour not_allowed)
				(footprints allowed)
			)
			(placement
				(enabled no)
				(sheetname "")
			)
			(fill
				(thermal_gap 0.5)
				(thermal_bridge_width 0.5)
				(island_removal_mode 0)
			)
			(polygon
				(pts
					(xy 368.554 -137.0584) (xy 369.062 -137.0584) (xy 369.062 -136.6774) (xy 368.554 -136.6774)
				)
			)
		)
		(zone
			(layer "F.Cu")
			(hatch none 0.5)
			(connect_pads
				(clearance 0)
			)
			(min_thickness 0.25)
			(keepout
				(tracks not_allowed)
				(vias allowed)
				(pads allowed)
				(copperpour not_allowed)
				(footprints allowed)
			)
			(placement
				(enabled no)
				(sheetname "")
			)
			(fill
				(thermal_gap 0.5)
				(thermal_bridge_width 0.5)
				(island_removal_mode 0)
			)
			(polygon
				(pts
					(xy 368.554 -136.6774) (xy 369.062 -136.6774) (xy 369.062 -137.0584) (xy 368.554 -137.0584)
				)
			)
		)
	)
	(footprint ""
		(layer "F.Cu")
		(at 0 -155.10002 90)
		(property "Reference" "TH1A1"
			(at 2.45491 8.6868 0)
			(unlocked yes)
			(layer "F.SilkS")
			(effects
				(font
					(size 0.7874 0.5842)
					(thickness 0.1524)
				)
				(justify left)
			)
		)
		(property "Value" ""
			(at 0 0 90)
			(layer "F.Fab")
			(effects
				(font
					(size 1.27 1.27)
				)
			)
		)
		(duplicate_pad_numbers_are_jumpers no)
		(fp_poly
			(pts
				(arc
					(start 3.0226 0.68834)
					(mid 3.042235 0.827855)
					(end 3.099562 0.956564)
				)
				(arc
					(start 3.099562 0.956564)
					(mid 4.012804 3.550073)
					(end 3.042158 6.12267)
				)
				(arc
					(start 3.042158 6.12267)
					(mid 0 7.518589)
					(end -3.042158 6.12267)
				)
				(arc
					(start -3.042158 6.12267)
					(mid -4.012854 3.55061)
					(end -3.100324 0.957326)
				)
				(arc
					(start -3.100324 0.957326)
					(mid -3.042498 0.827518)
					(end -3.0226 0.686816)
				)
				(arc
					(start -3.0226 -0.000254)
					(mid -2.137121 -2.137227)
					(end 0 -3.022346)
				)
				(arc
					(start 0 -3.022346)
					(mid 2.137227 -2.136973)
					(end 3.0226 0.000254)
				)
			)
			(stroke
				(width 0)
				(type default)
			)
			(fill no)
			(layer "F.CrtYd")
		)
		(pad "1" thru_hole custom
			(at 0 0 90)
			(size 2.00667 2.00667)
			(drill 0.3048)
			(layers "*.Cu" "*.Mask")
			(remove_unused_layers no)
			(net "GND")
			(clearance -0.889)
			(options
				(clearance outline)
				(anchor circle)
			)
			(primitives
				(gr_poly
					(pts
						(arc
							(start 3.042158 3.874516)
							(mid 0 5.270435)
							(end -3.042158 3.874516)
						)
						(arc
							(start -3.042158 3.874516)
							(mid -4.012854 1.302456)
							(end -3.100324 -1.290828)
						)
						(arc
							(start -3.100324 -1.290828)
							(mid -3.042498 -1.420636)
							(end -3.0226 -1.561338)
						)
						(arc
							(start -3.0226 -2.248408)
							(mid -2.137121 -4.385381)
							(end 0 -5.2705)
						)
						(arc
							(start 0 -5.2705)
							(mid 2.137227 -4.385127)
							(end 3.0226 -2.2479)
						)
						(arc
							(start 3.0226 -1.55956)
							(mid 3.04227 -1.420177)
							(end 3.099562 -1.29159)
						)
						(arc
							(start 3.099562 -1.29159)
							(mid 4.012804 1.301919)
							(end 3.042158 3.874516)
						)
					)
					(width 0)
					(fill yes)
				)
			)
		)
	)
	(footprint ""
		(layer "F.Cu")
		(at 39.6748 -49.6824 90)
		(property "Reference" "R1E7"
			(at 0 0 90)
			(layer "F.SilkS")
			(hide yes)
			(effects
				(font
					(size 1.27 1.27)
				)
			)
		)
		(property "Value" ""
			(at 0 0 90)
			(layer "F.Fab")
			(effects
				(font
					(size 1.27 1.27)
				)
			)
		)
		(duplicate_pad_numbers_are_jumpers no)
		(fp_poly
			(pts
				(xy -0.2794 -0.1016) (xy 0.2794 -0.1016) (xy 0.2794 0.9906) (xy -0.2794 0.9906)
			)
			(stroke
				(width 0)
				(type default)
			)
			(fill no)
			(layer "F.CrtYd")
		)
		(fp_line
			(start 0.2794 -0.1016)
			(end -0.2794 -0.1016)
			(stroke
				(width 0.1)
				(type default)
			)
			(layer "F.Fab")
		)
		(fp_line
			(start -0.2794 -0.1016)
			(end -0.2794 0.9906)
			(stroke
				(width 0.1)
				(type default)
			)
			(layer "F.Fab")
		)
		(fp_line
			(start 0.2794 0.9906)
			(end 0.2794 -0.1016)
			(stroke
				(width 0.1)
				(type default)
			)
			(layer "F.Fab")
		)
		(fp_line
			(start -0.2794 0.9906)
			(end 0.2794 0.9906)
			(stroke
				(width 0.1)
				(type default)
			)
			(layer "F.Fab")
		)
		(pad "1" smd rect
			(at 0 0 90)
			(size 0.508 0.508)
			(layers "F.Cu" "F.Mask" "F.Paste")
			(net "VSENSE_PVCCIN_CPU1_N")
		)
		(pad "2" smd rect
			(at 0 0.889 90)
			(size 0.508 0.508)
			(layers "F.Cu" "F.Mask" "F.Paste")
			(net "VSENSE_PVCCIN_CPU1_SKT_VRTN")
		)
		(zone
			(layer "F.Cu")
			(hatch none 0.5)
			(connect_pads
				(clearance 0)
			)
			(min_thickness 0.25)
			(keepout
				(tracks allowed)
				(vias not_allowed)
				(pads allowed)
				(copperpour not_allowed)
				(footprints allowed)
			)
			(placement
				(enabled no)
				(sheetname "")
			)
			(fill
				(thermal_gap 0.5)
				(thermal_bridge_width 0.5)
				(island_removal_mode 0)
			)
			(polygon
				(pts
					(xy 39.9288 -49.4284) (xy 39.9288 -49.9364) (xy 40.3098 -49.9364) (xy 40.3098 -49.4284)
				)
			)
		)
		(zone
			(layer "F.Cu")
			(hatch none 0.5)
			(connect_pads
				(clearance 0)
			)
			(min_thickness 0.25)
			(keepout
				(tracks not_allowed)
				(vias allowed)
				(pads allowed)
				(copperpour not_allowed)
				(footprints allowed)
			)
			(placement
				(enabled no)
				(sheetname "")
			)
			(fill
				(thermal_gap 0.5)
				(thermal_bridge_width 0.5)
				(island_removal_mode 0)
			)
			(polygon
				(pts
					(xy 40.3098 -49.4284) (xy 40.3098 -49.9364) (xy 39.9288 -49.9364) (xy 39.9288 -49.4284)
				)
			)
		)
	)
	(footprint ""
		(layer "F.Cu")
		(at 14.224 -69.977 90)
		(property "Reference" "R1D44"
			(at 0 0 90)
			(layer "F.SilkS")
			(hide yes)
			(effects
				(font
					(size 1.27 1.27)
				)
			)
		)
		(property "Value" ""
			(at 0 0 90)
			(layer "F.Fab")
			(effects
				(font
					(size 1.27 1.27)
				)
			)
		)
		(duplicate_pad_numbers_are_jumpers no)
		(fp_rect
			(start -0.2794 0.9906)
			(end 0.2794 -0.1016)
			(stroke
				(width 0)
				(type default)
			)
			(fill no)
			(layer "F.CrtYd")
		)
		(fp_line
			(start 0.2794 -0.1016)
			(end -0.2794 -0.1016)
			(stroke
				(width 0.1)
				(type default)
			)
			(layer "F.Fab")
		)
		(fp_line
			(start -0.2794 -0.1016)
			(end -0.2794 0.9906)
			(stroke
				(width 0.1)
				(type default)
			)
			(layer "F.Fab")
		)
		(fp_line
			(start 0.2794 0.9906)
			(end 0.2794 -0.1016)
			(stroke
				(width 0.1)
				(type default)
			)
			(layer "F.Fab")
		)
		(fp_line
			(start -0.2794 0.9906)
			(end 0.2794 0.9906)
			(stroke
				(width 0.1)
				(type default)
			)
			(layer "F.Fab")
		)
		(pad "1" smd rect
			(at 0 0 90)
			(size 0.508 0.508)
			(layers "F.Cu" "F.Mask" "F.Paste")
			(net "A_HSC_MOP")
		)
		(pad "2" smd rect
			(at 0 0.889 90)
			(size 0.508 0.508)
			(layers "F.Cu" "F.Mask" "F.Paste")
			(net "A_HSC_HSP")
		)
		(zone
			(layer "F.Cu")
			(hatch none 0.5)
			(connect_pads
				(clearance 0)
			)
			(min_thickness 0.25)
			(keepout
				(tracks not_allowed)
				(vias allowed)
				(pads allowed)
				(copperpour not_allowed)
				(footprints allowed)
			)
			(placement
				(enabled no)
				(sheetname "")
			)
			(fill
				(thermal_gap 0.5)
				(thermal_bridge_width 0.5)
				(island_removal_mode 0)
			)
			(polygon
				(pts
					(xy 14.859 -69.723) (xy 14.859 -70.231) (xy 14.478 -70.231) (xy 14.478 -69.723)
				)
			)
		)
		(zone
			(layer "F.Cu")
			(hatch none 0.5)
			(connect_pads
				(clearance 0)
			)
			(min_thickness 0.25)
			(keepout
				(tracks allowed)
				(vias not_allowed)
				(pads allowed)
				(copperpour not_allowed)
				(footprints allowed)
			)
			(placement
				(enabled no)
				(sheetname "")
			)
			(fill
				(thermal_gap 0.5)
				(thermal_bridge_width 0.5)
				(island_removal_mode 0)
			)
			(polygon
				(pts
					(xy 14.859 -69.723) (xy 14.859 -70.231) (xy 14.478 -70.231) (xy 14.478 -69.723)
				)
			)
		)
	)
	(footprint ""
		(layer "F.Cu")
		(at 177.927 -131.7625)
		(property "Reference" "R4B6"
			(at 0 0 0)
			(layer "F.SilkS")
			(hide yes)
			(effects
				(font
					(size 1.27 1.27)
				)
			)
		)
		(property "Value" ""
			(at 0 0 0)
			(layer "F.Fab")
			(effects
				(font
					(size 1.27 1.27)
				)
			)
		)
		(duplicate_pad_numbers_are_jumpers no)
		(fp_poly
			(pts
				(xy -0.2794 -0.1016) (xy 0.2794 -0.1016) (xy 0.2794 0.9906) (xy -0.2794 0.9906)
			)
			(stroke
				(width 0)
				(type default)
			)
			(fill no)
			(layer "F.CrtYd")
		)
		(fp_line
			(start -0.2794 -0.1016)
			(end -0.2794 0.9906)
			(stroke
				(width 0.1)
				(type default)
			)
			(layer "F.Fab")
		)
		(fp_line
			(start -0.2794 0.9906)
			(end 0.2794 0.9906)
			(stroke
				(width 0.1)
				(type default)
			)
			(layer "F.Fab")
		)
		(fp_line
			(start 0.2794 -0.1016)
			(end -0.2794 -0.1016)
			(stroke
				(width 0.1)
				(type default)
			)
			(layer "F.Fab")
		)
		(fp_line
			(start 0.2794 0.9906)
			(end 0.2794 -0.1016)
			(stroke
				(width 0.1)
				(type default)
			)
			(layer "F.Fab")
		)
		(pad "1" smd rect
			(at 0 0)
			(size 0.508 0.508)
			(layers "F.Cu" "F.Mask" "F.Paste")
			(net "VR_PVPP_KLM_ISET")
		)
		(pad "2" smd rect
			(at 0 0.889)
			(size 0.508 0.508)
			(layers "F.Cu" "F.Mask" "F.Paste")
			(net "AGND_PVPP_KLM")
		)
		(zone
			(layer "F.Cu")
			(hatch none 0.5)
			(connect_pads
				(clearance 0)
			)
			(min_thickness 0.25)
			(keepout
				(tracks allowed)
				(vias not_allowed)
				(pads allowed)
				(copperpour not_allowed)
				(footprints allowed)
			)
			(placement
				(enabled no)
				(sheetname "")
			)
			(fill
				(thermal_gap 0.5)
				(thermal_bridge_width 0.5)
				(island_removal_mode 0)
			)
			(polygon
				(pts
					(xy 177.673 -131.5085) (xy 178.181 -131.5085) (xy 178.181 -131.1275) (xy 177.673 -131.1275)
				)
			)
		)
		(zone
			(layer "F.Cu")
			(hatch none 0.5)
			(connect_pads
				(clearance 0)
			)
			(min_thickness 0.25)
			(keepout
				(tracks not_allowed)
				(vias allowed)
				(pads allowed)
				(copperpour not_allowed)
				(footprints allowed)
			)
			(placement
				(enabled no)
				(sheetname "")
			)
			(fill
				(thermal_gap 0.5)
				(thermal_bridge_width 0.5)
				(island_removal_mode 0)
			)
			(polygon
				(pts
					(xy 177.673 -131.1275) (xy 178.181 -131.1275) (xy 178.181 -131.5085) (xy 177.673 -131.5085)
				)
			)
		)
	)
	(footprint ""
		(layer "F.Cu")
		(at 471.000074 -155.10002 90)
		(property "Reference" "TH9A1"
			(at 3.36931 -4.656074 0)
			(unlocked yes)
			(layer "F.SilkS")
			(effects
				(font
					(size 0.7874 0.5842)
					(thickness 0.1524)
				)
				(justify left)
			)
		)
		(property "Value" ""
			(at 0 0 90)
			(layer "F.Fab")
			(effects
				(font
					(size 1.27 1.27)
				)
			)
		)
		(duplicate_pad_numbers_are_jumpers no)
		(fp_poly
			(pts
				(arc
					(start 3.0226 0.68834)
					(mid 3.042235 0.827855)
					(end 3.099562 0.956564)
				)
				(arc
					(start 3.099562 0.956564)
					(mid 4.012804 3.550073)
					(end 3.042158 6.12267)
				)
				(arc
					(start 3.042158 6.12267)
					(mid 0 7.518589)
					(end -3.042158 6.12267)
				)
				(arc
					(start -3.042158 6.12267)
					(mid -4.012854 3.55061)
					(end -3.100324 0.957326)
				)
				(arc
					(start -3.100324 0.957326)
					(mid -3.042498 0.827518)
					(end -3.0226 0.686816)
				)
				(arc
					(start -3.0226 -0.000254)
					(mid -2.137121 -2.137227)
					(end 0 -3.022346)
				)
				(arc
					(start 0 -3.022346)
					(mid 2.137227 -2.136973)
					(end 3.0226 0.000254)
				)
			)
			(stroke
				(width 0)
				(type default)
			)
			(fill no)
			(layer "F.CrtYd")
		)
		(pad "1" thru_hole custom
			(at 0 0 90)
			(size 2.00667 2.00667)
			(drill 0.3048)
			(layers "*.Cu" "*.Mask")
			(remove_unused_layers no)
			(net "GND")
			(clearance -0.889)
			(options
				(clearance outline)
				(anchor circle)
			)
			(primitives
				(gr_poly
					(pts
						(arc
							(start 3.042158 3.874516)
							(mid 0 5.270435)
							(end -3.042158 3.874516)
						)
						(arc
							(start -3.042158 3.874516)
							(mid -4.012854 1.302456)
							(end -3.100324 -1.290828)
						)
						(arc
							(start -3.100324 -1.290828)
							(mid -3.042498 -1.420636)
							(end -3.0226 -1.561338)
						)
						(arc
							(start -3.0226 -2.248408)
							(mid -2.137121 -4.385381)
							(end 0 -5.2705)
						)
						(arc
							(start 0 -5.2705)
							(mid 2.137227 -4.385127)
							(end 3.0226 -2.2479)
						)
						(arc
							(start 3.0226 -1.55956)
							(mid 3.04227 -1.420177)
							(end 3.099562 -1.29159)
						)
						(arc
							(start 3.099562 -1.29159)
							(mid 4.012804 1.301919)
							(end 3.042158 3.874516)
						)
					)
					(width 0)
					(fill yes)
				)
			)
		)
	)
	(footprint ""
		(layer "F.Cu")
		(at 6.448552 -129.026158)
		(property "Reference" "C12W4"
			(at -0.8382 -0.67818 0)
			(unlocked yes)
			(layer "F.SilkS")
			(effects
				(font
					(size 0.4064 0.254)
					(thickness 0.1524)
				)
				(justify left)
			)
		)
		(property "Value" ""
			(at 0 0 0)
			(layer "F.Fab")
			(effects
				(font
					(size 1.27 1.27)
				)
			)
		)
		(duplicate_pad_numbers_are_jumpers no)
		(fp_poly
			(pts
				(xy 0.3048 -0.1016) (xy 0.3048 0.9906) (xy -0.3048 0.9906) (xy -0.3048 -0.1016)
			)
			(stroke
				(width 0)
				(type default)
			)
			(fill no)
			(layer "F.CrtYd")
		)
		(fp_line
			(start -0.3048 -0.1016)
			(end -0.3048 0.9906)
			(stroke
				(width 0.1)
				(type default)
			)
			(layer "F.Fab")
		)
		(fp_line
			(start -0.3048 0.9906)
			(end 0.3048 0.9906)
			(stroke
				(width 0.1)
				(type default)
			)
			(layer "F.Fab")
		)
		(fp_line
			(start 0.3048 -0.1016)
			(end -0.3048 -0.1016)
			(stroke
				(width 0.1)
				(type default)
			)
			(layer "F.Fab")
		)
		(fp_line
			(start 0.3048 0.9906)
			(end 0.3048 -0.1016)
			(stroke
				(width 0.1)
				(type default)
			)
			(layer "F.Fab")
		)
		(pad "1" smd rect
			(at 0 0)
			(size 0.508 0.508)
			(layers "F.Cu" "F.Mask" "F.Paste")
			(net "VR_PVDDQ_KLM_AIINSEN")
		)
		(pad "2" smd rect
			(at 0 0.889)
			(size 0.508 0.508)
			(layers "F.Cu" "F.Mask" "F.Paste")
			(net "VR_PVDDQ_KLM_VINSEN")
		)
		(zone
			(layer "F.Cu")
			(hatch none 0.5)
			(connect_pads
				(clearance 0)
			)
			(min_thickness 0.25)
			(keepout
				(tracks allowed)
				(vias not_allowed)
				(pads allowed)
				(copperpour not_allowed)
				(footprints allowed)
			)
			(placement
				(enabled no)
				(sheetname "")
			)
			(fill
				(thermal_gap 0.5)
				(thermal_bridge_width 0.5)
				(island_removal_mode 0)
			)
			(polygon
				(pts
					(xy 6.194552 -128.772158) (xy 6.702552 -128.772158) (xy 6.702552 -128.391158) (xy 6.194552 -128.391158)
				)
			)
		)
		(zone
			(layer "F.Cu")
			(hatch none 0.5)
			(connect_pads
				(clearance 0)
			)
			(min_thickness 0.25)
			(keepout
				(tracks not_allowed)
				(vias allowed)
				(pads allowed)
				(copperpour not_allowed)
				(footprints allowed)
			)
			(placement
				(enabled no)
				(sheetname "")
			)
			(fill
				(thermal_gap 0.5)
				(thermal_bridge_width 0.5)
				(island_removal_mode 0)
			)
			(polygon
				(pts
					(xy 6.194552 -128.391158) (xy 6.702552 -128.391158) (xy 6.702552 -128.772158) (xy 6.194552 -128.772158)
				)
			)
		)
	)
	(footprint ""
		(layer "F.Cu")
		(at 105.889806 -68.365116 180)
		(property "Reference" "C2D47"
			(at 0 0 180)
			(layer "F.SilkS")
			(hide yes)
			(effects
				(font
					(size 1.27 1.27)
				)
			)
		)
		(property "Value" ""
			(at 0 0 180)
			(layer "F.Fab")
			(effects
				(font
					(size 1.27 1.27)
				)
			)
		)
		(duplicate_pad_numbers_are_jumpers no)
		(fp_poly
			(pts
				(xy -0.4953 -0.2032) (xy 0.4953 -0.2032) (xy 0.4953 1.6002) (xy -0.4953 1.6002)
			)
			(stroke
				(width 0)
				(type default)
			)
			(fill no)
			(layer "F.CrtYd")
		)
		(fp_line
			(start 0.4953 1.6002)
			(end -0.4953 1.6002)
			(stroke
				(width 0.1)
				(type default)
			)
			(layer "F.Fab")
		)
		(fp_line
			(start 0.4953 -0.2032)
			(end 0.4953 1.6002)
			(stroke
				(width 0.1)
				(type default)
			)
			(layer "F.Fab")
		)
		(fp_line
			(start -0.4953 1.6002)
			(end -0.4953 -0.2032)
			(stroke
				(width 0.1)
				(type default)
			)
			(layer "F.Fab")
		)
		(fp_line
			(start -0.4953 -0.2032)
			(end 0.4953 -0.2032)
			(stroke
				(width 0.1)
				(type default)
			)
			(layer "F.Fab")
		)
		(pad "1" smd rect
			(at 0 0 180)
			(size 0.762 0.889)
			(layers "F.Cu" "F.Mask" "F.Paste")
			(net "PVDDQ_GHJ")
		)
		(pad "2" smd rect
			(at 0 1.397 180)
			(size 0.762 0.889)
			(layers "F.Cu" "F.Mask" "F.Paste")
			(net "GND")
		)
		(zone
			(layer "F.Cu")
			(hatch none 0.5)
			(connect_pads
				(clearance 0)
			)
			(min_thickness 0.25)
			(keepout
				(tracks not_allowed)
				(vias allowed)
				(pads allowed)
				(copperpour not_allowed)
				(footprints allowed)
			)
			(placement
				(enabled no)
				(sheetname "")
			)
			(fill
				(thermal_gap 0.5)
				(thermal_bridge_width 0.5)
				(island_removal_mode 0)
			)
			(polygon
				(pts
					(xy 106.270806 -68.809616) (xy 105.508806 -68.809616) (xy 105.508806 -69.317616) (xy 106.270806 -69.317616)
				)
			)
		)
	)
	(footprint ""
		(layer "F.Cu")
		(at 277.241 -69.977)
		(property "Reference" "R6D15"
			(at 0 0 0)
			(layer "F.SilkS")
			(hide yes)
			(effects
				(font
					(size 1.27 1.27)
				)
			)
		)
		(property "Value" ""
			(at 0 0 0)
			(layer "F.Fab")
			(effects
				(font
					(size 1.27 1.27)
				)
			)
		)
		(duplicate_pad_numbers_are_jumpers no)
		(fp_poly
			(pts
				(xy -0.2794 -0.1016) (xy 0.2794 -0.1016) (xy 0.2794 0.9906) (xy -0.2794 0.9906)
			)
			(stroke
				(width 0)
				(type default)
			)
			(fill no)
			(layer "F.CrtYd")
		)
		(fp_line
			(start -0.2794 -0.1016)
			(end -0.2794 0.9906)
			(stroke
				(width 0.1)
				(type default)
			)
			(layer "F.Fab")
		)
		(fp_line
			(start -0.2794 0.9906)
			(end 0.2794 0.9906)
			(stroke
				(width 0.1)
				(type default)
			)
			(layer "F.Fab")
		)
		(fp_line
			(start 0.2794 -0.1016)
			(end -0.2794 -0.1016)
			(stroke
				(width 0.1)
				(type default)
			)
			(layer "F.Fab")
		)
		(fp_line
			(start 0.2794 0.9906)
			(end 0.2794 -0.1016)
			(stroke
				(width 0.1)
				(type default)
			)
			(layer "F.Fab")
		)
		(pad "1" smd rect
			(at 0 0)
			(size 0.508 0.508)
			(layers "F.Cu" "F.Mask" "F.Paste")
			(net "PVCCIO_CPU0")
		)
		(pad "2" smd rect
			(at 0 0.889)
			(size 0.508 0.508)
			(layers "F.Cu" "F.Mask" "F.Paste")
			(net "PU_CPU0_SOCKET_ID_0")
		)
		(zone
			(layer "F.Cu")
			(hatch none 0.5)
			(connect_pads
				(clearance 0)
			)
			(min_thickness 0.25)
			(keepout
				(tracks allowed)
				(vias not_allowed)
				(pads allowed)
				(copperpour not_allowed)
				(footprints allowed)
			)
			(placement
				(enabled no)
				(sheetname "")
			)
			(fill
				(thermal_gap 0.5)
				(thermal_bridge_width 0.5)
				(island_removal_mode 0)
			)
			(polygon
				(pts
					(xy 276.987 -69.723) (xy 277.495 -69.723) (xy 277.495 -69.342) (xy 276.987 -69.342)
				)
			)
		)
		(zone
			(layer "F.Cu")
			(hatch none 0.5)
			(connect_pads
				(clearance 0)
			)
			(min_thickness 0.25)
			(keepout
				(tracks not_allowed)
				(vias allowed)
				(pads allowed)
				(copperpour not_allowed)
				(footprints allowed)
			)
			(placement
				(enabled no)
				(sheetname "")
			)
			(fill
				(thermal_gap 0.5)
				(thermal_bridge_width 0.5)
				(island_removal_mode 0)
			)
			(polygon
				(pts
					(xy 276.987 -69.342) (xy 277.495 -69.342) (xy 277.495 -69.723) (xy 276.987 -69.723)
				)
			)
		)
	)
	(footprint ""
		(layer "F.Cu")
		(at 411.099 -127.5588 90)
		(property "Reference" "C8B11"
			(at 0 0 90)
			(layer "F.SilkS")
			(hide yes)
			(effects
				(font
					(size 1.27 1.27)
				)
			)
		)
		(property "Value" ""
			(at 0 0 90)
			(layer "F.Fab")
			(effects
				(font
					(size 1.27 1.27)
				)
			)
		)
		(duplicate_pad_numbers_are_jumpers no)
		(fp_poly
			(pts
				(xy -0.4953 -0.2032) (xy 0.4953 -0.2032) (xy 0.4953 1.6002) (xy -0.4953 1.6002)
			)
			(stroke
				(width 0)
				(type default)
			)
			(fill no)
			(layer "F.CrtYd")
		)
		(fp_line
			(start 0.4953 -0.2032)
			(end 0.4953 1.6002)
			(stroke
				(width 0.1)
				(type default)
			)
			(layer "F.Fab")
		)
		(fp_line
			(start -0.4953 -0.2032)
			(end 0.4953 -0.2032)
			(stroke
				(width 0.1)
				(type default)
			)
			(layer "F.Fab")
		)
		(fp_line
			(start 0.4953 1.6002)
			(end -0.4953 1.6002)
			(stroke
				(width 0.1)
				(type default)
			)
			(layer "F.Fab")
		)
		(fp_line
			(start -0.4953 1.6002)
			(end -0.4953 -0.2032)
			(stroke
				(width 0.1)
				(type default)
			)
			(layer "F.Fab")
		)
		(pad "1" smd rect
			(at 0 0 90)
			(size 0.762 0.889)
			(layers "F.Cu" "F.Mask" "F.Paste")
			(net "P1V05_PCH_STBY")
		)
		(pad "2" smd rect
			(at 0 1.397 90)
			(size 0.762 0.889)
			(layers "F.Cu" "F.Mask" "F.Paste")
			(net "GND")
		)
		(zone
			(layer "F.Cu")
			(hatch none 0.5)
			(connect_pads
				(clearance 0)
			)
			(min_thickness 0.25)
			(keepout
				(tracks not_allowed)
				(vias allowed)
				(pads allowed)
				(copperpour not_allowed)
				(footprints allowed)
			)
			(placement
				(enabled no)
				(sheetname "")
			)
			(fill
				(thermal_gap 0.5)
				(thermal_bridge_width 0.5)
				(island_removal_mode 0)
			)
			(polygon
				(pts
					(xy 411.5435 -127.1778) (xy 411.5435 -127.9398) (xy 412.0515 -127.9398) (xy 412.0515 -127.1778)
				)
			)
		)
	)
	(footprint ""
		(layer "F.Cu")
		(at 477.139 -36.6395 180)
		(property "Reference" "R8G25"
			(at 0 0 180)
			(layer "F.SilkS")
			(hide yes)
			(effects
				(font
					(size 1.27 1.27)
				)
			)
		)
		(property "Value" ""
			(at 0 0 180)
			(layer "F.Fab")
			(effects
				(font
					(size 1.27 1.27)
				)
			)
		)
		(duplicate_pad_numbers_are_jumpers no)
		(fp_poly
			(pts
				(xy -0.2794 -0.1016) (xy 0.2794 -0.1016) (xy 0.2794 0.9906) (xy -0.2794 0.9906)
			)
			(stroke
				(width 0)
				(type default)
			)
			(fill no)
			(layer "F.CrtYd")
		)
		(fp_line
			(start 0.2794 0.9906)
			(end 0.2794 -0.1016)
			(stroke
				(width 0.1)
				(type default)
			)
			(layer "F.Fab")
		)
		(fp_line
			(start 0.2794 -0.1016)
			(end -0.2794 -0.1016)
			(stroke
				(width 0.1)
				(type default)
			)
			(layer "F.Fab")
		)
		(fp_line
			(start -0.2794 0.9906)
			(end 0.2794 0.9906)
			(stroke
				(width 0.1)
				(type default)
			)
			(layer "F.Fab")
		)
		(fp_line
			(start -0.2794 -0.1016)
			(end -0.2794 0.9906)
			(stroke
				(width 0.1)
				(type default)
			)
			(layer "F.Fab")
		)
		(pad "1" smd rect
			(at 0 0 180)
			(size 0.508 0.508)
			(layers "F.Cu" "F.Mask" "F.Paste")
			(net "CLK_50M_CKMNG_SPRVLLE_R")
		)
		(pad "2" smd rect
			(at 0 0.889 180)
			(size 0.508 0.508)
			(layers "F.Cu" "F.Mask" "F.Paste")
			(net "CLK_50M_CKMNG_SPRVLLE")
		)
		(zone
			(layer "F.Cu")
			(hatch none 0.5)
			(connect_pads
				(clearance 0)
			)
			(min_thickness 0.25)
			(keepout
				(tracks not_allowed)
				(vias allowed)
				(pads allowed)
				(copperpour not_allowed)
				(footprints allowed)
			)
			(placement
				(enabled no)
				(sheetname "")
			)
			(fill
				(thermal_gap 0.5)
				(thermal_bridge_width 0.5)
				(island_removal_mode 0)
			)
			(polygon
				(pts
					(xy 477.393 -37.2745) (xy 476.885 -37.2745) (xy 476.885 -36.8935) (xy 477.393 -36.8935)
				)
			)
		)
		(zone
			(layer "F.Cu")
			(hatch none 0.5)
			(connect_pads
				(clearance 0)
			)
			(min_thickness 0.25)
			(keepout
				(tracks allowed)
				(vias not_allowed)
				(pads allowed)
				(copperpour not_allowed)
				(footprints allowed)
			)
			(placement
				(enabled no)
				(sheetname "")
			)
			(fill
				(thermal_gap 0.5)
				(thermal_bridge_width 0.5)
				(island_removal_mode 0)
			)
			(polygon
				(pts
					(xy 477.393 -36.8935) (xy 476.885 -36.8935) (xy 476.885 -37.2745) (xy 477.393 -37.2745)
				)
			)
		)
	)
	(footprint ""
		(layer "F.Cu")
		(at 350.376236 4.434332 90)
		(property "Reference" "C7G37"
			(at 0 0 90)
			(layer "F.SilkS")
			(hide yes)
			(effects
				(font
					(size 1.27 1.27)
				)
			)
		)
		(property "Value" ""
			(at 0 0 90)
			(layer "F.Fab")
			(effects
				(font
					(size 1.27 1.27)
				)
			)
		)
		(duplicate_pad_numbers_are_jumpers no)
		(fp_poly
			(pts
				(xy 0.3048 -0.1016) (xy 0.3048 0.9906) (xy -0.3048 0.9906) (xy -0.3048 -0.1016)
			)
			(stroke
				(width 0)
				(type default)
			)
			(fill no)
			(layer "F.CrtYd")
		)
		(fp_line
			(start 0.3048 -0.1016)
			(end -0.3048 -0.1016)
			(stroke
				(width 0.1)
				(type default)
			)
			(layer "F.Fab")
		)
		(fp_line
			(start -0.3048 -0.1016)
			(end -0.3048 0.9906)
			(stroke
				(width 0.1)
				(type default)
			)
			(layer "F.Fab")
		)
		(fp_line
			(start 0.3048 0.9906)
			(end 0.3048 -0.1016)
			(stroke
				(width 0.1)
				(type default)
			)
			(layer "F.Fab")
		)
		(fp_line
			(start -0.3048 0.9906)
			(end 0.3048 0.9906)
			(stroke
				(width 0.1)
				(type default)
			)
			(layer "F.Fab")
		)
		(pad "1" smd rect
			(at 0 0 90)
			(size 0.508 0.508)
			(layers "F.Cu" "F.Mask" "F.Paste")
			(net "VR_FET_SW_P12V_STBY_PVDDQ_ABC")
		)
		(pad "2" smd rect
			(at 0 0.889 90)
			(size 0.508 0.508)
			(layers "F.Cu" "F.Mask" "F.Paste")
			(net "GND")
		)
		(zone
			(layer "F.Cu")
			(hatch none 0.5)
			(connect_pads
				(clearance 0)
			)
			(min_thickness 0.25)
			(keepout
				(tracks allowed)
				(vias not_allowed)
				(pads allowed)
				(copperpour not_allowed)
				(footprints allowed)
			)
			(placement
				(enabled no)
				(sheetname "")
			)
			(fill
				(thermal_gap 0.5)
				(thermal_bridge_width 0.5)
				(island_removal_mode 0)
			)
			(polygon
				(pts
					(xy 350.630236 4.688332) (xy 350.630236 4.180332) (xy 351.011236 4.180332) (xy 351.011236 4.688332)
				)
			)
		)
		(zone
			(layer "F.Cu")
			(hatch none 0.5)
			(connect_pads
				(clearance 0)
			)
			(min_thickness 0.25)
			(keepout
				(tracks not_allowed)
				(vias allowed)
				(pads allowed)
				(copperpour not_allowed)
				(footprints allowed)
			)
			(placement
				(enabled no)
				(sheetname "")
			)
			(fill
				(thermal_gap 0.5)
				(thermal_bridge_width 0.5)
				(island_removal_mode 0)
			)
			(polygon
				(pts
					(xy 351.011236 4.688332) (xy 351.011236 4.180332) (xy 350.630236 4.180332) (xy 350.630236 4.688332)
				)
			)
		)
	)
	(footprint ""
		(layer "F.Cu")
		(at 347.462094 -145.293842 -90)
		(property "Reference" "EU7A4"
			(at 5.874512 -1.483106 0)
			(unlocked yes)
			(layer "F.SilkS")
			(effects
				(font
					(size 0.7874 0.5842)
					(thickness 0.1524)
				)
			)
		)
		(property "Value" ""
			(at 0 0 270)
			(layer "F.Fab")
			(effects
				(font
					(size 1.27 1.27)
				)
			)
		)
		(duplicate_pad_numbers_are_jumpers no)
		(fp_line
			(start -3.0099 3.429)
			(end -3.0099 -3.5052)
			(stroke
				(width 0.1524)
				(type default)
			)
			(layer "F.SilkS")
		)
		(fp_line
			(start 2.9718 3.429)
			(end -3.0099 3.429)
			(stroke
				(width 0.1524)
				(type default)
			)
			(layer "F.SilkS")
		)
		(fp_line
			(start -3.0099 -3.5052)
			(end 2.9718 -3.5052)
			(stroke
				(width 0.1524)
				(type default)
			)
			(layer "F.SilkS")
		)
		(fp_line
			(start 2.9718 -3.5052)
			(end 2.9718 3.429)
			(stroke
				(width 0.1524)
				(type default)
			)
			(layer "F.SilkS")
		)
		(fp_circle
			(center -3.736848 -3.271266)
			(end -3.736848 -3.398266)
			(stroke
				(width 0.254)
				(type default)
			)
			(fill no)
			(layer "F.SilkS")
		)
		(fp_poly
			(pts
				(xy -2.9972 -3.4925) (xy -2.9972 -2.6924) (xy -2.1971 -3.4925)
			)
			(stroke
				(width 0)
				(type default)
			)
			(fill yes)
			(layer "F.SilkS")
		)
		(fp_poly
			(pts
				(xy -2.549906 -3.050032) (xy -2.549906 3.050032) (xy 2.549906 3.050032) (xy 2.549906 -3.050032)
			)
			(stroke
				(width 0)
				(type default)
			)
			(fill no)
			(layer "F.CrtYd")
		)
		(fp_line
			(start -2.549906 3.050032)
			(end -2.549906 -3.050032)
			(stroke
				(width 0.1)
				(type default)
			)
			(layer "F.Fab")
		)
		(fp_line
			(start 2.549906 3.050032)
			(end -2.549906 3.050032)
			(stroke
				(width 0.1)
				(type default)
			)
			(layer "F.Fab")
		)
		(fp_line
			(start -2.549906 -3.050032)
			(end 2.549906 -3.050032)
			(stroke
				(width 0.1)
				(type default)
			)
			(layer "F.Fab")
		)
		(fp_line
			(start 2.549906 -3.050032)
			(end 2.549906 3.050032)
			(stroke
				(width 0.1)
				(type default)
			)
			(layer "F.Fab")
		)
		(fp_circle
			(center -3.057398 -2.678684)
			(end -3.057398 -2.805684)
			(stroke
				(width 0.254)
				(type default)
			)
			(fill no)
			(layer "F.Fab")
		)
		(pad "1" smd rect
			(at -2.39522 -2.279904 270)
			(size 0.7112 0.254)
			(layers "F.Cu" "F.Mask" "F.Paste")
			(net "PVDDQ_DEF")
		)
		(pad "2" smd rect
			(at -2.39522 -1.83007 270)
			(size 0.7112 0.254)
			(layers "F.Cu" "F.Mask" "F.Paste")
			(net "GND")
		)
		(pad "3" smd rect
			(at -2.39522 -1.379982 270)
			(size 0.7112 0.254)
			(layers "F.Cu" "F.Mask" "F.Paste")
			(net "VR_PVDDQ_DEF_PH2_VCIN")
		)
		(pad "4" smd rect
			(at -2.39522 -0.929894 270)
			(size 0.7112 0.254)
			(layers "F.Cu" "F.Mask" "F.Paste")
			(net "P5V_STBY")
		)
		(pad "5" smd rect
			(at -2.39522 -0.48006 270)
			(size 0.7112 0.254)
			(layers "F.Cu" "F.Mask" "F.Paste")
			(net "GND")
		)
		(pad "6" smd rect
			(at -2.39522 -0.029972 270)
			(size 0.7112 0.254)
			(layers "F.Cu" "F.Mask" "F.Paste")
			(net "TP_PVDDQ_DEF_PH2_GL_0")
		)
		(pad "7" smd custom
			(at 0.016764 1.145032 270)
			(size 0.53975 0.53975)
			(layers "F.Cu" "F.Mask" "F.Paste")
			(net "GND")
			(options
				(clearance outline)
				(anchor circle)
			)
			(primitives
				(gr_poly
					(pts
						(xy -2.7051 1.0795) (xy -2.7051 -0.3683) (xy -0.9271 -0.3683) (xy -0.9271 -1.0795) (xy 2.7051 -1.0795)
						(xy 2.7051 1.0795)
					)
					(width 0)
					(fill yes)
				)
			)
		)
		(pad "10" smd rect
			(at -0.008382 2.874772 270)
			(size 4.3434 0.6096)
			(layers "F.Cu" "F.Mask" "F.Paste")
			(net "VR_PVDDQ_DEF_PH2_SW")
		)
		(pad "25" smd rect
			(at 1.548384 -1.283208 270)
			(size 2.3368 2.0066)
			(layers "F.Cu" "F.Mask" "F.Paste")
			(net "VR_FET_SW_P12V_STBY_PVDDQ_DEF")
		)
		(pad "30" smd rect
			(at 2.050034 -2.895092 270)
			(size 0.254 0.7112)
			(layers "F.Cu" "F.Mask" "F.Paste")
			(net "VR_FET_SW_P12V_STBY_PVDDQ_DEF")
		)
		(pad "31" smd rect
			(at 1.599946 -2.895092 270)
			(size 0.254 0.7112)
			(layers "F.Cu" "F.Mask" "F.Paste")
			(net "Net_371")
		)
		(pad "32" smd rect
			(at 1.150112 -2.895092 270)
			(size 0.254 0.7112)
			(layers "F.Cu" "F.Mask" "F.Paste")
			(net "VR_PVDDQ_DEF_PH2_PHASE")
		)
		(pad "33" smd rect
			(at 0.700024 -2.895092 270)
			(size 0.254 0.7112)
			(layers "F.Cu" "F.Mask" "F.Paste")
			(net "VR_PVDDQ_DEF_PH2_BOOT_R")
		)
		(pad "34" smd rect
			(at 0.249936 -2.895092 270)
			(size 0.254 0.7112)
			(layers "F.Cu" "F.Mask" "F.Paste")
			(net "VR_PVDDQ_DEF_PWM2")
		)
		(pad "35" smd rect
			(at -0.199898 -2.895092 270)
			(size 0.254 0.7112)
			(layers "F.Cu" "F.Mask" "F.Paste")
			(net "P5V_STBY")
		)
		(pad "36" smd rect
			(at -0.649986 -2.895092 270)
			(size 0.254 0.7112)
			(layers "F.Cu" "F.Mask" "F.Paste")
			(net "A_TSENSE_PVDDQ_DEF")
		)
		(pad "37" smd rect
			(at -1.100074 -2.895092 270)
			(size 0.254 0.7112)
			(layers "F.Cu" "F.Mask" "F.Paste")
			(net "VR_PVDDQ_DEF_PH2_OCSET")
		)
		(pad "38" smd rect
			(at -1.549908 -2.895092 270)
			(size 0.254 0.7112)
			(layers "F.Cu" "F.Mask" "F.Paste")
			(net "ISENSE_PVDDQ_DEF_PH2_IMON")
		)
		(pad "39" smd rect
			(at -1.999996 -2.895092 270)
			(size 0.254 0.7112)
			(layers "F.Cu" "F.Mask" "F.Paste")
			(net "VR_PVDDQ_DEF_AIREF2")
		)
		(pad "40" smd rect
			(at -0.871728 -1.283208 270)
			(size 1.8034 2.0066)
			(layers "F.Cu" "F.Mask" "F.Paste")
			(net "GND")
		)
		(pad "41" smd rect
			(at -1.533906 0.247904 270)
			(size 0.508 0.3556)
			(layers "F.Cu" "F.Mask" "F.Paste")
			(net "TP_PVDDQ_DEF_PH2_GL_1")
		)
	)
	(footprint ""
		(layer "F.Cu")
		(at 405.283416 -148.436584 90)
		(property "Reference" "C8A11"
			(at 0 0 90)
			(layer "F.SilkS")
			(hide yes)
			(effects
				(font
					(size 1.27 1.27)
				)
			)
		)
		(property "Value" ""
			(at 0 0 90)
			(layer "F.Fab")
			(effects
				(font
					(size 1.27 1.27)
				)
			)
		)
		(duplicate_pad_numbers_are_jumpers no)
		(fp_poly
			(pts
				(xy 0.3048 -0.1016) (xy 0.3048 0.9906) (xy -0.3048 0.9906) (xy -0.3048 -0.1016)
			)
			(stroke
				(width 0)
				(type default)
			)
			(fill no)
			(layer "F.CrtYd")
		)
		(fp_line
			(start 0.3048 -0.1016)
			(end -0.3048 -0.1016)
			(stroke
				(width 0.1)
				(type default)
			)
			(layer "F.Fab")
		)
		(fp_line
			(start -0.3048 -0.1016)
			(end -0.3048 0.9906)
			(stroke
				(width 0.1)
				(type default)
			)
			(layer "F.Fab")
		)
		(fp_line
			(start 0.3048 0.9906)
			(end 0.3048 -0.1016)
			(stroke
				(width 0.1)
				(type default)
			)
			(layer "F.Fab")
		)
		(fp_line
			(start -0.3048 0.9906)
			(end 0.3048 0.9906)
			(stroke
				(width 0.1)
				(type default)
			)
			(layer "F.Fab")
		)
		(pad "1" smd rect
			(at 0 0 90)
			(size 0.508 0.508)
			(layers "F.Cu" "F.Mask" "F.Paste")
			(net "PWRGD_P1V8_PCH_STBY_R")
		)
		(pad "2" smd rect
			(at 0 0.889 90)
			(size 0.508 0.508)
			(layers "F.Cu" "F.Mask" "F.Paste")
			(net "GND")
		)
		(zone
			(layer "F.Cu")
			(hatch none 0.5)
			(connect_pads
				(clearance 0)
			)
			(min_thickness 0.25)
			(keepout
				(tracks allowed)
				(vias not_allowed)
				(pads allowed)
				(copperpour not_allowed)
				(footprints allowed)
			)
			(placement
				(enabled no)
				(sheetname "")
			)
			(fill
				(thermal_gap 0.5)
				(thermal_bridge_width 0.5)
				(island_removal_mode 0)
			)
			(polygon
				(pts
					(xy 405.537416 -148.182584) (xy 405.537416 -148.690584) (xy 405.918416 -148.690584) (xy 405.918416 -148.182584)
				)
			)
		)
		(zone
			(layer "F.Cu")
			(hatch none 0.5)
			(connect_pads
				(clearance 0)
			)
			(min_thickness 0.25)
			(keepout
				(tracks not_allowed)
				(vias allowed)
				(pads allowed)
				(copperpour not_allowed)
				(footprints allowed)
			)
			(placement
				(enabled no)
				(sheetname "")
			)
			(fill
				(thermal_gap 0.5)
				(thermal_bridge_width 0.5)
				(island_removal_mode 0)
			)
			(polygon
				(pts
					(xy 405.918416 -148.182584) (xy 405.918416 -148.690584) (xy 405.537416 -148.690584) (xy 405.537416 -148.182584)
				)
			)
		)
	)
	(footprint ""
		(layer "F.Cu")
		(at 429.220122 -45.054774 90)
		(property "Reference" "R9F60"
			(at 0 0 90)
			(layer "F.SilkS")
			(hide yes)
			(effects
				(font
					(size 1.27 1.27)
				)
			)
		)
		(property "Value" ""
			(at 0 0 90)
			(layer "F.Fab")
			(effects
				(font
					(size 1.27 1.27)
				)
			)
		)
		(duplicate_pad_numbers_are_jumpers no)
		(fp_poly
			(pts
				(xy -0.2794 -0.1016) (xy 0.2794 -0.1016) (xy 0.2794 0.9906) (xy -0.2794 0.9906)
			)
			(stroke
				(width 0)
				(type default)
			)
			(fill no)
			(layer "F.CrtYd")
		)
		(fp_line
			(start 0.2794 -0.1016)
			(end -0.2794 -0.1016)
			(stroke
				(width 0.1)
				(type default)
			)
			(layer "F.Fab")
		)
		(fp_line
			(start -0.2794 -0.1016)
			(end -0.2794 0.9906)
			(stroke
				(width 0.1)
				(type default)
			)
			(layer "F.Fab")
		)
		(fp_line
			(start 0.2794 0.9906)
			(end 0.2794 -0.1016)
			(stroke
				(width 0.1)
				(type default)
			)
			(layer "F.Fab")
		)
		(fp_line
			(start -0.2794 0.9906)
			(end 0.2794 0.9906)
			(stroke
				(width 0.1)
				(type default)
			)
			(layer "F.Fab")
		)
		(pad "1" smd rect
			(at 0 0 90)
			(size 0.508 0.508)
			(layers "F.Cu" "F.Mask" "F.Paste")
			(net "CLK_25M_BMC")
		)
		(pad "2" smd rect
			(at 0 0.889 90)
			(size 0.508 0.508)
			(layers "F.Cu" "F.Mask" "F.Paste")
			(net "CLK_24M_25M_BMC_CLKIN")
		)
		(zone
			(layer "F.Cu")
			(hatch none 0.5)
			(connect_pads
				(clearance 0)
			)
			(min_thickness 0.25)
			(keepout
				(tracks allowed)
				(vias not_allowed)
				(pads allowed)
				(copperpour not_allowed)
				(footprints allowed)
			)
			(placement
				(enabled no)
				(sheetname "")
			)
			(fill
				(thermal_gap 0.5)
				(thermal_bridge_width 0.5)
				(island_removal_mode 0)
			)
			(polygon
				(pts
					(xy 429.474122 -44.800774) (xy 429.474122 -45.308774) (xy 429.855122 -45.308774) (xy 429.855122 -44.800774)
				)
			)
		)
		(zone
			(layer "F.Cu")
			(hatch none 0.5)
			(connect_pads
				(clearance 0)
			)
			(min_thickness 0.25)
			(keepout
				(tracks not_allowed)
				(vias allowed)
				(pads allowed)
				(copperpour not_allowed)
				(footprints allowed)
			)
			(placement
				(enabled no)
				(sheetname "")
			)
			(fill
				(thermal_gap 0.5)
				(thermal_bridge_width 0.5)
				(island_removal_mode 0)
			)
			(polygon
				(pts
					(xy 429.855122 -44.800774) (xy 429.855122 -45.308774) (xy 429.474122 -45.308774) (xy 429.474122 -44.800774)
				)
			)
		)
	)
	(footprint ""
		(layer "F.Cu")
		(at 475.7801 -141.6177 180)
		(property "Reference" "C1L17"
			(at 0 0 180)
			(layer "F.SilkS")
			(hide yes)
			(effects
				(font
					(size 1.27 1.27)
				)
			)
		)
		(property "Value" ""
			(at 0 0 180)
			(layer "F.Fab")
			(effects
				(font
					(size 1.27 1.27)
				)
			)
		)
		(duplicate_pad_numbers_are_jumpers no)
		(fp_poly
			(pts
				(xy 0.3048 -0.1016) (xy 0.3048 0.9906) (xy -0.3048 0.9906) (xy -0.3048 -0.1016)
			)
			(stroke
				(width 0)
				(type default)
			)
			(fill no)
			(layer "F.CrtYd")
		)
		(fp_line
			(start 0.3048 0.9906)
			(end 0.3048 -0.1016)
			(stroke
				(width 0.1)
				(type default)
			)
			(layer "F.Fab")
		)
		(fp_line
			(start 0.3048 -0.1016)
			(end -0.3048 -0.1016)
			(stroke
				(width 0.1)
				(type default)
			)
			(layer "F.Fab")
		)
		(fp_line
			(start -0.3048 0.9906)
			(end 0.3048 0.9906)
			(stroke
				(width 0.1)
				(type default)
			)
			(layer "F.Fab")
		)
		(fp_line
			(start -0.3048 -0.1016)
			(end -0.3048 0.9906)
			(stroke
				(width 0.1)
				(type default)
			)
			(layer "F.Fab")
		)
		(pad "1" smd rect
			(at 0 0 180)
			(size 0.508 0.508)
			(layers "F.Cu" "F.Mask" "F.Paste")
			(net "P3V3_STBY")
		)
		(pad "2" smd rect
			(at 0 0.889 180)
			(size 0.508 0.508)
			(layers "F.Cu" "F.Mask" "F.Paste")
			(net "GND")
		)
		(zone
			(layer "F.Cu")
			(hatch none 0.5)
			(connect_pads
				(clearance 0)
			)
			(min_thickness 0.25)
			(keepout
				(tracks not_allowed)
				(vias allowed)
				(pads allowed)
				(copperpour not_allowed)
				(footprints allowed)
			)
			(placement
				(enabled no)
				(sheetname "")
			)
			(fill
				(thermal_gap 0.5)
				(thermal_bridge_width 0.5)
				(island_removal_mode 0)
			)
			(polygon
				(pts
					(xy 476.0341 -142.2527) (xy 475.5261 -142.2527) (xy 475.5261 -141.8717) (xy 476.0341 -141.8717)
				)
			)
		)
		(zone
			(layer "F.Cu")
			(hatch none 0.5)
			(connect_pads
				(clearance 0)
			)
			(min_thickness 0.25)
			(keepout
				(tracks allowed)
				(vias not_allowed)
				(pads allowed)
				(copperpour not_allowed)
				(footprints allowed)
			)
			(placement
				(enabled no)
				(sheetname "")
			)
			(fill
				(thermal_gap 0.5)
				(thermal_bridge_width 0.5)
				(island_removal_mode 0)
			)
			(polygon
				(pts
					(xy 476.0341 -141.8717) (xy 475.5261 -141.8717) (xy 475.5261 -142.2527) (xy 476.0341 -142.2527)
				)
			)
		)
	)
	(footprint ""
		(layer "F.Cu")
		(at 351.663 -135.001)
		(property "Reference" "FB7B1"
			(at 0 0 0)
			(layer "F.SilkS")
			(hide yes)
			(effects
				(font
					(size 1.27 1.27)
				)
			)
		)
		(property "Value" ""
			(at 0 0 0)
			(layer "F.Fab")
			(effects
				(font
					(size 1.27 1.27)
				)
			)
		)
		(duplicate_pad_numbers_are_jumpers no)
		(fp_poly
			(pts
				(xy -0.7239 -0.26035) (xy 0.7239 -0.26035) (xy 0.7239 2.03835) (xy -0.7239 2.03835)
			)
			(stroke
				(width 0)
				(type default)
			)
			(fill no)
			(layer "F.CrtYd")
		)
		(fp_line
			(start -0.7239 -0.26035)
			(end 0.7239 -0.26035)
			(stroke
				(width 0.1)
				(type default)
			)
			(layer "F.Fab")
		)
		(fp_line
			(start -0.7239 2.03835)
			(end -0.7239 -0.26035)
			(stroke
				(width 0.1)
				(type default)
			)
			(layer "F.Fab")
		)
		(fp_line
			(start 0.7239 -0.26035)
			(end 0.7239 2.03835)
			(stroke
				(width 0.1)
				(type default)
			)
			(layer "F.Fab")
		)
		(fp_line
			(start 0.7239 2.03835)
			(end -0.7239 2.03835)
			(stroke
				(width 0.1)
				(type default)
			)
			(layer "F.Fab")
		)
		(pad "1" smd rect
			(at 0 0)
			(size 1.27 1.016)
			(layers "F.Cu" "F.Mask" "F.Paste")
			(net "P12V_STBY")
		)
		(pad "2" smd rect
			(at 0 1.778)
			(size 1.27 1.016)
			(layers "F.Cu" "F.Mask" "F.Paste")
			(net "VR_FET_SW_P12V_STBY_PVPP_DEF")
		)
		(zone
			(layer "F.Cu")
			(hatch none 0.5)
			(connect_pads
				(clearance 0)
			)
			(min_thickness 0.25)
			(keepout
				(tracks not_allowed)
				(vias allowed)
				(pads allowed)
				(copperpour not_allowed)
				(footprints allowed)
			)
			(placement
				(enabled no)
				(sheetname "")
			)
			(fill
				(thermal_gap 0.5)
				(thermal_bridge_width 0.5)
				(island_removal_mode 0)
			)
			(polygon
				(pts
					(xy 352.298 -134.493) (xy 352.298 -133.731) (xy 352.2091 -133.731) (xy 351.028 -133.731) (xy 351.028 -134.493)
				)
			)
		)
	)
	(footprint ""
		(layer "F.Cu")
		(at 432.6509 -45.1739)
		(property "Reference" "R25W95"
			(at -0.8382 -0.67818 0)
			(unlocked yes)
			(layer "F.SilkS")
			(effects
				(font
					(size 0.4064 0.254)
					(thickness 0.1524)
				)
				(justify left)
			)
		)
		(property "Value" ""
			(at 0 0 0)
			(layer "F.Fab")
			(effects
				(font
					(size 1.27 1.27)
				)
			)
		)
		(duplicate_pad_numbers_are_jumpers no)
		(fp_poly
			(pts
				(xy -0.2794 -0.1016) (xy 0.2794 -0.1016) (xy 0.2794 0.9906) (xy -0.2794 0.9906)
			)
			(stroke
				(width 0)
				(type default)
			)
			(fill no)
			(layer "F.CrtYd")
		)
		(fp_line
			(start -0.2794 -0.1016)
			(end -0.2794 0.9906)
			(stroke
				(width 0.1)
				(type default)
			)
			(layer "F.Fab")
		)
		(fp_line
			(start -0.2794 0.9906)
			(end 0.2794 0.9906)
			(stroke
				(width 0.1)
				(type default)
			)
			(layer "F.Fab")
		)
		(fp_line
			(start 0.2794 -0.1016)
			(end -0.2794 -0.1016)
			(stroke
				(width 0.1)
				(type default)
			)
			(layer "F.Fab")
		)
		(fp_line
			(start 0.2794 0.9906)
			(end 0.2794 -0.1016)
			(stroke
				(width 0.1)
				(type default)
			)
			(layer "F.Fab")
		)
		(pad "1" smd rect
			(at 0 0)
			(size 0.508 0.508)
			(layers "F.Cu" "F.Mask" "F.Paste")
			(net "P3V3_STBY")
		)
		(pad "2" smd rect
			(at 0 0.889)
			(size 0.508 0.508)
			(layers "F.Cu" "F.Mask" "F.Paste")
			(net "SPI_BMC_BT_CLK")
		)
		(zone
			(layer "F.Cu")
			(hatch none 0.5)
			(connect_pads
				(clearance 0)
			)
			(min_thickness 0.25)
			(keepout
				(tracks allowed)
				(vias not_allowed)
				(pads allowed)
				(copperpour not_allowed)
				(footprints allowed)
			)
			(placement
				(enabled no)
				(sheetname "")
			)
			(fill
				(thermal_gap 0.5)
				(thermal_bridge_width 0.5)
				(island_removal_mode 0)
			)
			(polygon
				(pts
					(xy 432.3969 -44.9199) (xy 432.9049 -44.9199) (xy 432.9049 -44.5389) (xy 432.3969 -44.5389)
				)
			)
		)
		(zone
			(layer "F.Cu")
			(hatch none 0.5)
			(connect_pads
				(clearance 0)
			)
			(min_thickness 0.25)
			(keepout
				(tracks not_allowed)
				(vias allowed)
				(pads allowed)
				(copperpour not_allowed)
				(footprints allowed)
			)
			(placement
				(enabled no)
				(sheetname "")
			)
			(fill
				(thermal_gap 0.5)
				(thermal_bridge_width 0.5)
				(island_removal_mode 0)
			)
			(polygon
				(pts
					(xy 432.3969 -44.5389) (xy 432.9049 -44.5389) (xy 432.9049 -44.9199) (xy 432.3969 -44.9199)
				)
			)
		)
	)
	(footprint ""
		(layer "F.Cu")
		(at 337.404202 -121.282968 90)
		(property "Reference" "C6B15"
			(at -0.8382 -0.67818 90)
			(unlocked yes)
			(layer "F.SilkS")
			(effects
				(font
					(size 0.4064 0.254)
					(thickness 0.1524)
				)
				(justify left)
			)
		)
		(property "Value" ""
			(at 0 0 90)
			(layer "F.Fab")
			(effects
				(font
					(size 1.27 1.27)
				)
			)
		)
		(duplicate_pad_numbers_are_jumpers no)
		(fp_poly
			(pts
				(xy 0.3048 -0.1016) (xy 0.3048 0.9906) (xy -0.3048 0.9906) (xy -0.3048 -0.1016)
			)
			(stroke
				(width 0)
				(type default)
			)
			(fill no)
			(layer "F.CrtYd")
		)
		(fp_line
			(start 0.3048 -0.1016)
			(end -0.3048 -0.1016)
			(stroke
				(width 0.1)
				(type default)
			)
			(layer "F.Fab")
		)
		(fp_line
			(start -0.3048 -0.1016)
			(end -0.3048 0.9906)
			(stroke
				(width 0.1)
				(type default)
			)
			(layer "F.Fab")
		)
		(fp_line
			(start 0.3048 0.9906)
			(end 0.3048 -0.1016)
			(stroke
				(width 0.1)
				(type default)
			)
			(layer "F.Fab")
		)
		(fp_line
			(start -0.3048 0.9906)
			(end 0.3048 0.9906)
			(stroke
				(width 0.1)
				(type default)
			)
			(layer "F.Fab")
		)
		(pad "1" smd rect
			(at 0 0 90)
			(size 0.508 0.508)
			(layers "F.Cu" "F.Mask" "F.Paste")
			(net "P3E_CPU0_PE1_PCH_TXN<10>")
		)
		(pad "2" smd rect
			(at 0 0.889 90)
			(size 0.508 0.508)
			(layers "F.Cu" "F.Mask" "F.Paste")
			(net "P3E_CPU0_PE1_PCH_C_TXN<10>")
		)
		(zone
			(layer "F.Cu")
			(hatch none 0.5)
			(connect_pads
				(clearance 0)
			)
			(min_thickness 0.25)
			(keepout
				(tracks allowed)
				(vias not_allowed)
				(pads allowed)
				(copperpour not_allowed)
				(footprints allowed)
			)
			(placement
				(enabled no)
				(sheetname "")
			)
			(fill
				(thermal_gap 0.5)
				(thermal_bridge_width 0.5)
				(island_removal_mode 0)
			)
			(polygon
				(pts
					(xy 337.658202 -121.028968) (xy 337.658202 -121.536968) (xy 338.039202 -121.536968) (xy 338.039202 -121.028968)
				)
			)
		)
		(zone
			(layer "F.Cu")
			(hatch none 0.5)
			(connect_pads
				(clearance 0)
			)
			(min_thickness 0.25)
			(keepout
				(tracks not_allowed)
				(vias allowed)
				(pads allowed)
				(copperpour not_allowed)
				(footprints allowed)
			)
			(placement
				(enabled no)
				(sheetname "")
			)
			(fill
				(thermal_gap 0.5)
				(thermal_bridge_width 0.5)
				(island_removal_mode 0)
			)
			(polygon
				(pts
					(xy 338.039202 -121.028968) (xy 338.039202 -121.536968) (xy 337.658202 -121.536968) (xy 337.658202 -121.028968)
				)
			)
		)
	)
	(footprint ""
		(layer "F.Cu")
		(at 179.705 -64.135 180)
		(property "Reference" "R4E3"
			(at 0 0 180)
			(layer "F.SilkS")
			(hide yes)
			(effects
				(font
					(size 1.27 1.27)
				)
			)
		)
		(property "Value" ""
			(at 0 0 180)
			(layer "F.Fab")
			(effects
				(font
					(size 1.27 1.27)
				)
			)
		)
		(duplicate_pad_numbers_are_jumpers no)
		(fp_rect
			(start 0.2794 -0.1016)
			(end -0.2794 0.9906)
			(stroke
				(width 0)
				(type default)
			)
			(fill no)
			(layer "F.CrtYd")
		)
		(fp_line
			(start 0.2794 0.9906)
			(end 0.2794 -0.1016)
			(stroke
				(width 0.1)
				(type default)
			)
			(layer "F.Fab")
		)
		(fp_line
			(start 0.2794 -0.1016)
			(end -0.2794 -0.1016)
			(stroke
				(width 0.1)
				(type default)
			)
			(layer "F.Fab")
		)
		(fp_line
			(start -0.2794 0.9906)
			(end 0.2794 0.9906)
			(stroke
				(width 0.1)
				(type default)
			)
			(layer "F.Fab")
		)
		(fp_line
			(start -0.2794 -0.1016)
			(end -0.2794 0.9906)
			(stroke
				(width 0.1)
				(type default)
			)
			(layer "F.Fab")
		)
		(pad "1" smd rect
			(at 0 0 180)
			(size 0.508 0.508)
			(layers "F.Cu" "F.Mask" "F.Paste")
			(net "P3V3_STBY")
		)
		(pad "2" smd rect
			(at 0 0.889 180)
			(size 0.508 0.508)
			(layers "F.Cu" "F.Mask" "F.Paste")
			(net "IRQ_PVCCIN_CPU0_VRHOT_LVC3_R_N")
		)
		(zone
			(layer "F.Cu")
			(hatch none 0.5)
			(connect_pads
				(clearance 0)
			)
			(min_thickness 0.25)
			(keepout
				(tracks allowed)
				(vias not_allowed)
				(pads allowed)
				(copperpour not_allowed)
				(footprints allowed)
			)
			(placement
				(enabled no)
				(sheetname "")
			)
			(fill
				(thermal_gap 0.5)
				(thermal_bridge_width 0.5)
				(island_removal_mode 0)
			)
			(polygon
				(pts
					(xy 179.451 -64.389) (xy 179.959 -64.389) (xy 179.959 -64.77) (xy 179.451 -64.77)
				)
			)
		)
		(zone
			(layer "F.Cu")
			(hatch none 0.5)
			(connect_pads
				(clearance 0)
			)
			(min_thickness 0.25)
			(keepout
				(tracks not_allowed)
				(vias allowed)
				(pads allowed)
				(copperpour not_allowed)
				(footprints allowed)
			)
			(placement
				(enabled no)
				(sheetname "")
			)
			(fill
				(thermal_gap 0.5)
				(thermal_bridge_width 0.5)
				(island_removal_mode 0)
			)
			(polygon
				(pts
					(xy 179.451 -64.389) (xy 179.959 -64.389) (xy 179.959 -64.77) (xy 179.451 -64.77)
				)
			)
		)
	)
	(footprint ""
		(layer "F.Cu")
		(at 442.364876 -14.123924 90)
		(property "Reference" "R2U40"
			(at 0 0 90)
			(layer "F.SilkS")
			(hide yes)
			(effects
				(font
					(size 1.27 1.27)
				)
			)
		)
		(property "Value" ""
			(at 0 0 90)
			(layer "F.Fab")
			(effects
				(font
					(size 1.27 1.27)
				)
			)
		)
		(duplicate_pad_numbers_are_jumpers no)
		(fp_poly
			(pts
				(xy -0.2794 -0.1016) (xy 0.2794 -0.1016) (xy 0.2794 0.9906) (xy -0.2794 0.9906)
			)
			(stroke
				(width 0)
				(type default)
			)
			(fill no)
			(layer "F.CrtYd")
		)
		(fp_line
			(start 0.2794 -0.1016)
			(end -0.2794 -0.1016)
			(stroke
				(width 0.1)
				(type default)
			)
			(layer "F.Fab")
		)
		(fp_line
			(start -0.2794 -0.1016)
			(end -0.2794 0.9906)
			(stroke
				(width 0.1)
				(type default)
			)
			(layer "F.Fab")
		)
		(fp_line
			(start 0.2794 0.9906)
			(end 0.2794 -0.1016)
			(stroke
				(width 0.1)
				(type default)
			)
			(layer "F.Fab")
		)
		(fp_line
			(start -0.2794 0.9906)
			(end 0.2794 0.9906)
			(stroke
				(width 0.1)
				(type default)
			)
			(layer "F.Fab")
		)
		(pad "1" smd rect
			(at 0 0 90)
			(size 0.508 0.508)
			(layers "F.Cu" "F.Mask" "F.Paste")
			(net "PVCCIO_CPU0")
		)
		(pad "2" smd rect
			(at 0 0.889 90)
			(size 0.508 0.508)
			(layers "F.Cu" "F.Mask" "F.Paste")
			(net "H_CPU0_MEMABC_MEMHOT_G_N")
		)
		(zone
			(layer "F.Cu")
			(hatch none 0.5)
			(connect_pads
				(clearance 0)
			)
			(min_thickness 0.25)
			(keepout
				(tracks allowed)
				(vias not_allowed)
				(pads allowed)
				(copperpour not_allowed)
				(footprints allowed)
			)
			(placement
				(enabled no)
				(sheetname "")
			)
			(fill
				(thermal_gap 0.5)
				(thermal_bridge_width 0.5)
				(island_removal_mode 0)
			)
			(polygon
				(pts
					(xy 442.618876 -13.869924) (xy 442.618876 -14.377924) (xy 442.999876 -14.377924) (xy 442.999876 -13.869924)
				)
			)
		)
		(zone
			(layer "F.Cu")
			(hatch none 0.5)
			(connect_pads
				(clearance 0)
			)
			(min_thickness 0.25)
			(keepout
				(tracks not_allowed)
				(vias allowed)
				(pads allowed)
				(copperpour not_allowed)
				(footprints allowed)
			)
			(placement
				(enabled no)
				(sheetname "")
			)
			(fill
				(thermal_gap 0.5)
				(thermal_bridge_width 0.5)
				(island_removal_mode 0)
			)
			(polygon
				(pts
					(xy 442.999876 -13.869924) (xy 442.999876 -14.377924) (xy 442.618876 -14.377924) (xy 442.618876 -13.869924)
				)
			)
		)
	)
	(footprint ""
		(layer "F.Cu")
		(at 49.4284 -63.080392)
		(property "Reference" "C1E3"
			(at 0 0 0)
			(layer "F.SilkS")
			(hide yes)
			(effects
				(font
					(size 1.27 1.27)
				)
			)
		)
		(property "Value" ""
			(at 0 0 0)
			(layer "F.Fab")
			(effects
				(font
					(size 1.27 1.27)
				)
			)
		)
		(duplicate_pad_numbers_are_jumpers no)
		(fp_poly
			(pts
				(xy -0.4953 -0.2032) (xy 0.4953 -0.2032) (xy 0.4953 1.6002) (xy -0.4953 1.6002)
			)
			(stroke
				(width 0)
				(type default)
			)
			(fill no)
			(layer "F.CrtYd")
		)
		(fp_line
			(start -0.4953 -0.2032)
			(end 0.4953 -0.2032)
			(stroke
				(width 0.1)
				(type default)
			)
			(layer "F.Fab")
		)
		(fp_line
			(start -0.4953 1.6002)
			(end -0.4953 -0.2032)
			(stroke
				(width 0.1)
				(type default)
			)
			(layer "F.Fab")
		)
		(fp_line
			(start 0.4953 -0.2032)
			(end 0.4953 1.6002)
			(stroke
				(width 0.1)
				(type default)
			)
			(layer "F.Fab")
		)
		(fp_line
			(start 0.4953 1.6002)
			(end -0.4953 1.6002)
			(stroke
				(width 0.1)
				(type default)
			)
			(layer "F.Fab")
		)
		(pad "1" smd rect
			(at 0 0)
			(size 0.762 0.889)
			(layers "F.Cu" "F.Mask" "F.Paste")
			(net "PVCCIN_CPU1")
		)
		(pad "2" smd rect
			(at 0 1.397)
			(size 0.762 0.889)
			(layers "F.Cu" "F.Mask" "F.Paste")
			(net "GND")
		)
		(zone
			(layer "F.Cu")
			(hatch none 0.5)
			(connect_pads
				(clearance 0)
			)
			(min_thickness 0.25)
			(keepout
				(tracks not_allowed)
				(vias allowed)
				(pads allowed)
				(copperpour not_allowed)
				(footprints allowed)
			)
			(placement
				(enabled no)
				(sheetname "")
			)
			(fill
				(thermal_gap 0.5)
				(thermal_bridge_width 0.5)
				(island_removal_mode 0)
			)
			(polygon
				(pts
					(xy 49.0474 -62.635892) (xy 49.8094 -62.635892) (xy 49.8094 -62.127892) (xy 49.0474 -62.127892)
				)
			)
		)
	)
	(footprint ""
		(layer "F.Cu")
		(at 181.339998 1.536192)
		(property "Reference" "C4G23"
			(at 0 0 0)
			(layer "F.SilkS")
			(hide yes)
			(effects
				(font
					(size 1.27 1.27)
				)
			)
		)
		(property "Value" ""
			(at 0 0 0)
			(layer "F.Fab")
			(effects
				(font
					(size 1.27 1.27)
				)
			)
		)
		(duplicate_pad_numbers_are_jumpers no)
		(fp_rect
			(start -0.3048 0.9906)
			(end 0.3048 -0.1016)
			(stroke
				(width 0)
				(type default)
			)
			(fill no)
			(layer "F.CrtYd")
		)
		(fp_line
			(start -0.3048 -0.1016)
			(end -0.3048 0.9906)
			(stroke
				(width 0.1)
				(type default)
			)
			(layer "F.Fab")
		)
		(fp_line
			(start -0.3048 0.9906)
			(end 0.3048 0.9906)
			(stroke
				(width 0.1)
				(type default)
			)
			(layer "F.Fab")
		)
		(fp_line
			(start 0.3048 -0.1016)
			(end -0.3048 -0.1016)
			(stroke
				(width 0.1)
				(type default)
			)
			(layer "F.Fab")
		)
		(fp_line
			(start 0.3048 0.9906)
			(end 0.3048 -0.1016)
			(stroke
				(width 0.1)
				(type default)
			)
			(layer "F.Fab")
		)
		(pad "1" smd rect
			(at 0 0)
			(size 0.508 0.508)
			(layers "F.Cu" "F.Mask" "F.Paste")
			(net "FM_PVTT_ABC_EN_R")
		)
		(pad "2" smd rect
			(at 0 0.889)
			(size 0.508 0.508)
			(layers "F.Cu" "F.Mask" "F.Paste")
			(net "GND")
		)
		(zone
			(layer "F.Cu")
			(hatch none 0.5)
			(connect_pads
				(clearance 0)
			)
			(min_thickness 0.25)
			(keepout
				(tracks allowed)
				(vias not_allowed)
				(pads allowed)
				(copperpour not_allowed)
				(footprints allowed)
			)
			(placement
				(enabled no)
				(sheetname "")
			)
			(fill
				(thermal_gap 0.5)
				(thermal_bridge_width 0.5)
				(island_removal_mode 0)
			)
			(polygon
				(pts
					(xy 181.085998 2.171192) (xy 181.593998 2.171192) (xy 181.593998 1.790192) (xy 181.085998 1.790192)
				)
			)
		)
		(zone
			(layer "F.Cu")
			(hatch none 0.5)
			(connect_pads
				(clearance 0)
			)
			(min_thickness 0.25)
			(keepout
				(tracks not_allowed)
				(vias allowed)
				(pads allowed)
				(copperpour not_allowed)
				(footprints allowed)
			)
			(placement
				(enabled no)
				(sheetname "")
			)
			(fill
				(thermal_gap 0.5)
				(thermal_bridge_width 0.5)
				(island_removal_mode 0)
			)
			(polygon
				(pts
					(xy 181.085998 2.171192) (xy 181.593998 2.171192) (xy 181.593998 1.790192) (xy 181.085998 1.790192)
				)
			)
		)
	)
	(footprint ""
		(layer "F.Cu")
		(at 411.0355 -109.855 -90)
		(property "Reference" "R8C7"
			(at 0 0 270)
			(layer "F.SilkS")
			(hide yes)
			(effects
				(font
					(size 1.27 1.27)
				)
			)
		)
		(property "Value" ""
			(at 0 0 270)
			(layer "F.Fab")
			(effects
				(font
					(size 1.27 1.27)
				)
			)
		)
		(duplicate_pad_numbers_are_jumpers no)
		(fp_poly
			(pts
				(xy -0.2794 -0.1016) (xy 0.2794 -0.1016) (xy 0.2794 0.9906) (xy -0.2794 0.9906)
			)
			(stroke
				(width 0)
				(type default)
			)
			(fill no)
			(layer "F.CrtYd")
		)
		(fp_line
			(start -0.2794 0.9906)
			(end 0.2794 0.9906)
			(stroke
				(width 0.1)
				(type default)
			)
			(layer "F.Fab")
		)
		(fp_line
			(start 0.2794 0.9906)
			(end 0.2794 -0.1016)
			(stroke
				(width 0.1)
				(type default)
			)
			(layer "F.Fab")
		)
		(fp_line
			(start -0.2794 -0.1016)
			(end -0.2794 0.9906)
			(stroke
				(width 0.1)
				(type default)
			)
			(layer "F.Fab")
		)
		(fp_line
			(start 0.2794 -0.1016)
			(end -0.2794 -0.1016)
			(stroke
				(width 0.1)
				(type default)
			)
			(layer "F.Fab")
		)
		(pad "1" smd rect
			(at 0 0 270)
			(size 0.508 0.508)
			(layers "F.Cu" "F.Mask" "F.Paste")
			(net "P3V3_STBY")
		)
		(pad "2" smd rect
			(at 0 0.889 270)
			(size 0.508 0.508)
			(layers "F.Cu" "F.Mask" "F.Paste")
			(net "FM_SLT_CFG0")
		)
		(zone
			(layer "F.Cu")
			(hatch none 0.5)
			(connect_pads
				(clearance 0)
			)
			(min_thickness 0.25)
			(keepout
				(tracks not_allowed)
				(vias allowed)
				(pads allowed)
				(copperpour not_allowed)
				(footprints allowed)
			)
			(placement
				(enabled no)
				(sheetname "")
			)
			(fill
				(thermal_gap 0.5)
				(thermal_bridge_width 0.5)
				(island_removal_mode 0)
			)
			(polygon
				(pts
					(xy 410.4005 -110.109) (xy 410.4005 -109.601) (xy 410.7815 -109.601) (xy 410.7815 -110.109)
				)
			)
		)
		(zone
			(layer "F.Cu")
			(hatch none 0.5)
			(connect_pads
				(clearance 0)
			)
			(min_thickness 0.25)
			(keepout
				(tracks allowed)
				(vias not_allowed)
				(pads allowed)
				(copperpour not_allowed)
				(footprints allowed)
			)
			(placement
				(enabled no)
				(sheetname "")
			)
			(fill
				(thermal_gap 0.5)
				(thermal_bridge_width 0.5)
				(island_removal_mode 0)
			)
			(polygon
				(pts
					(xy 410.7815 -110.109) (xy 410.7815 -109.601) (xy 410.4005 -109.601) (xy 410.4005 -110.109)
				)
			)
		)
	)
	(footprint ""
		(layer "F.Cu")
		(at 173.736 -64.63538 90)
		(property "Reference" "C4W2"
			(at -0.8382 -0.67818 90)
			(unlocked yes)
			(layer "F.SilkS")
			(effects
				(font
					(size 0.4064 0.254)
					(thickness 0.1524)
				)
				(justify left)
			)
		)
		(property "Value" ""
			(at 0 0 90)
			(layer "F.Fab")
			(effects
				(font
					(size 1.27 1.27)
				)
			)
		)
		(duplicate_pad_numbers_are_jumpers no)
		(fp_poly
			(pts
				(xy 0.3048 -0.1016) (xy 0.3048 0.9906) (xy -0.3048 0.9906) (xy -0.3048 -0.1016)
			)
			(stroke
				(width 0)
				(type default)
			)
			(fill no)
			(layer "F.CrtYd")
		)
		(fp_line
			(start 0.3048 -0.1016)
			(end -0.3048 -0.1016)
			(stroke
				(width 0.1)
				(type default)
			)
			(layer "F.Fab")
		)
		(fp_line
			(start -0.3048 -0.1016)
			(end -0.3048 0.9906)
			(stroke
				(width 0.1)
				(type default)
			)
			(layer "F.Fab")
		)
		(fp_line
			(start 0.3048 0.9906)
			(end 0.3048 -0.1016)
			(stroke
				(width 0.1)
				(type default)
			)
			(layer "F.Fab")
		)
		(fp_line
			(start -0.3048 0.9906)
			(end 0.3048 0.9906)
			(stroke
				(width 0.1)
				(type default)
			)
			(layer "F.Fab")
		)
		(pad "1" smd rect
			(at 0 0 90)
			(size 0.508 0.508)
			(layers "F.Cu" "F.Mask" "F.Paste")
			(net "A_TSENSE_PVCCIO_CPU1")
		)
		(pad "2" smd rect
			(at 0 0.889 90)
			(size 0.508 0.508)
			(layers "F.Cu" "F.Mask" "F.Paste")
			(net "GND")
		)
		(zone
			(layer "F.Cu")
			(hatch none 0.5)
			(connect_pads
				(clearance 0)
			)
			(min_thickness 0.25)
			(keepout
				(tracks allowed)
				(vias not_allowed)
				(pads allowed)
				(copperpour not_allowed)
				(footprints allowed)
			)
			(placement
				(enabled no)
				(sheetname "")
			)
			(fill
				(thermal_gap 0.5)
				(thermal_bridge_width 0.5)
				(island_removal_mode 0)
			)
			(polygon
				(pts
					(xy 173.99 -64.38138) (xy 173.99 -64.88938) (xy 174.371 -64.88938) (xy 174.371 -64.38138)
				)
			)
		)
		(zone
			(layer "F.Cu")
			(hatch none 0.5)
			(connect_pads
				(clearance 0)
			)
			(min_thickness 0.25)
			(keepout
				(tracks not_allowed)
				(vias allowed)
				(pads allowed)
				(copperpour not_allowed)
				(footprints allowed)
			)
			(placement
				(enabled no)
				(sheetname "")
			)
			(fill
				(thermal_gap 0.5)
				(thermal_bridge_width 0.5)
				(island_removal_mode 0)
			)
			(polygon
				(pts
					(xy 174.371 -64.38138) (xy 174.371 -64.88938) (xy 173.99 -64.88938) (xy 173.99 -64.38138)
				)
			)
		)
	)
	(footprint ""
		(layer "F.Cu")
		(at 24.230584 -95.827596)
		(property "Reference" "R1C21"
			(at 0 0 0)
			(layer "F.SilkS")
			(hide yes)
			(effects
				(font
					(size 1.27 1.27)
				)
			)
		)
		(property "Value" ""
			(at 0 0 0)
			(layer "F.Fab")
			(effects
				(font
					(size 1.27 1.27)
				)
			)
		)
		(duplicate_pad_numbers_are_jumpers no)
		(fp_rect
			(start -0.2794 0.9906)
			(end 0.2794 -0.1016)
			(stroke
				(width 0)
				(type default)
			)
			(fill no)
			(layer "F.CrtYd")
		)
		(fp_line
			(start -0.2794 -0.1016)
			(end -0.2794 0.9906)
			(stroke
				(width 0.1)
				(type default)
			)
			(layer "F.Fab")
		)
		(fp_line
			(start -0.2794 0.9906)
			(end 0.2794 0.9906)
			(stroke
				(width 0.1)
				(type default)
			)
			(layer "F.Fab")
		)
		(fp_line
			(start 0.2794 -0.1016)
			(end -0.2794 -0.1016)
			(stroke
				(width 0.1)
				(type default)
			)
			(layer "F.Fab")
		)
		(fp_line
			(start 0.2794 0.9906)
			(end 0.2794 -0.1016)
			(stroke
				(width 0.1)
				(type default)
			)
			(layer "F.Fab")
		)
		(pad "1" smd rect
			(at 0 0)
			(size 0.508 0.508)
			(layers "F.Cu" "F.Mask" "F.Paste")
			(net "VSENSE_PVSA_CPU1_P")
		)
		(pad "2" smd rect
			(at 0 0.889)
			(size 0.508 0.508)
			(layers "F.Cu" "F.Mask" "F.Paste")
			(net "VSENSE_PVSA_CPU1_BVSP")
		)
		(zone
			(layer "F.Cu")
			(hatch none 0.5)
			(connect_pads
				(clearance 0)
			)
			(min_thickness 0.25)
			(keepout
				(tracks allowed)
				(vias not_allowed)
				(pads allowed)
				(copperpour not_allowed)
				(footprints allowed)
			)
			(placement
				(enabled no)
				(sheetname "")
			)
			(fill
				(thermal_gap 0.5)
				(thermal_bridge_width 0.5)
				(island_removal_mode 0)
			)
			(polygon
				(pts
					(xy 23.976584 -95.192596) (xy 24.484584 -95.192596) (xy 24.484584 -95.573596) (xy 23.976584 -95.573596)
				)
			)
		)
		(zone
			(layer "F.Cu")
			(hatch none 0.5)
			(connect_pads
				(clearance 0)
			)
			(min_thickness 0.25)
			(keepout
				(tracks not_allowed)
				(vias allowed)
				(pads allowed)
				(copperpour not_allowed)
				(footprints allowed)
			)
			(placement
				(enabled no)
				(sheetname "")
			)
			(fill
				(thermal_gap 0.5)
				(thermal_bridge_width 0.5)
				(island_removal_mode 0)
			)
			(polygon
				(pts
					(xy 23.976584 -95.192596) (xy 24.484584 -95.192596) (xy 24.484584 -95.573596) (xy 23.976584 -95.573596)
				)
			)
		)
	)
	(footprint ""
		(layer "F.Cu")
		(at 28.194 -91.567 90)
		(property "Reference" "C1C24"
			(at 0 0 90)
			(layer "F.SilkS")
			(hide yes)
			(effects
				(font
					(size 1.27 1.27)
				)
			)
		)
		(property "Value" ""
			(at 0 0 90)
			(layer "F.Fab")
			(effects
				(font
					(size 1.27 1.27)
				)
			)
		)
		(duplicate_pad_numbers_are_jumpers no)
		(fp_rect
			(start -0.3048 0.9906)
			(end 0.3048 -0.1016)
			(stroke
				(width 0)
				(type default)
			)
			(fill no)
			(layer "F.CrtYd")
		)
		(fp_line
			(start 0.3048 -0.1016)
			(end -0.3048 -0.1016)
			(stroke
				(width 0.1)
				(type default)
			)
			(layer "F.Fab")
		)
		(fp_line
			(start -0.3048 -0.1016)
			(end -0.3048 0.9906)
			(stroke
				(width 0.1)
				(type default)
			)
			(layer "F.Fab")
		)
		(fp_line
			(start 0.3048 0.9906)
			(end 0.3048 -0.1016)
			(stroke
				(width 0.1)
				(type default)
			)
			(layer "F.Fab")
		)
		(fp_line
			(start -0.3048 0.9906)
			(end 0.3048 0.9906)
			(stroke
				(width 0.1)
				(type default)
			)
			(layer "F.Fab")
		)
		(pad "1" smd rect
			(at 0 0 90)
			(size 0.508 0.508)
			(layers "F.Cu" "F.Mask" "F.Paste")
			(net "VR_PVCCIN_CPU1_PH5_BOOT")
		)
		(pad "2" smd rect
			(at 0 0.889 90)
			(size 0.508 0.508)
			(layers "F.Cu" "F.Mask" "F.Paste")
			(net "VR_PVCCIN_CPU1_PH5_PHASE")
		)
		(zone
			(layer "F.Cu")
			(hatch none 0.5)
			(connect_pads
				(clearance 0)
			)
			(min_thickness 0.25)
			(keepout
				(tracks not_allowed)
				(vias allowed)
				(pads allowed)
				(copperpour not_allowed)
				(footprints allowed)
			)
			(placement
				(enabled no)
				(sheetname "")
			)
			(fill
				(thermal_gap 0.5)
				(thermal_bridge_width 0.5)
				(island_removal_mode 0)
			)
			(polygon
				(pts
					(xy 28.829 -91.313) (xy 28.829 -91.821) (xy 28.448 -91.821) (xy 28.448 -91.313)
				)
			)
		)
		(zone
			(layer "F.Cu")
			(hatch none 0.5)
			(connect_pads
				(clearance 0)
			)
			(min_thickness 0.25)
			(keepout
				(tracks allowed)
				(vias not_allowed)
				(pads allowed)
				(copperpour not_allowed)
				(footprints allowed)
			)
			(placement
				(enabled no)
				(sheetname "")
			)
			(fill
				(thermal_gap 0.5)
				(thermal_bridge_width 0.5)
				(island_removal_mode 0)
			)
			(polygon
				(pts
					(xy 28.829 -91.313) (xy 28.829 -91.821) (xy 28.448 -91.821) (xy 28.448 -91.313)
				)
			)
		)
	)
	(footprint ""
		(layer "F.Cu")
		(at 33.2105 -84.836 90)
		(property "Reference" "C1D13"
			(at 0 0 90)
			(layer "F.SilkS")
			(hide yes)
			(effects
				(font
					(size 1.27 1.27)
				)
			)
		)
		(property "Value" ""
			(at 0 0 90)
			(layer "F.Fab")
			(effects
				(font
					(size 1.27 1.27)
				)
			)
		)
		(duplicate_pad_numbers_are_jumpers no)
		(fp_rect
			(start 0.3048 0.9906)
			(end -0.3048 -0.1016)
			(stroke
				(width 0)
				(type default)
			)
			(fill no)
			(layer "F.CrtYd")
		)
		(fp_line
			(start 0.3048 -0.1016)
			(end -0.3048 -0.1016)
			(stroke
				(width 0.1)
				(type default)
			)
			(layer "F.Fab")
		)
		(fp_line
			(start -0.3048 -0.1016)
			(end -0.3048 0.9906)
			(stroke
				(width 0.1)
				(type default)
			)
			(layer "F.Fab")
		)
		(fp_line
			(start 0.3048 0.9906)
			(end 0.3048 -0.1016)
			(stroke
				(width 0.1)
				(type default)
			)
			(layer "F.Fab")
		)
		(fp_line
			(start -0.3048 0.9906)
			(end 0.3048 0.9906)
			(stroke
				(width 0.1)
				(type default)
			)
			(layer "F.Fab")
		)
		(pad "1" smd rect
			(at 0 0 90)
			(size 0.508 0.508)
			(layers "F.Cu" "F.Mask" "F.Paste")
			(net "VR_FET_SW_P12V_STBY_PVCCIN_CPU1")
		)
		(pad "2" smd rect
			(at 0 0.889 90)
			(size 0.508 0.508)
			(layers "F.Cu" "F.Mask" "F.Paste")
			(net "GND")
		)
		(zone
			(layer "F.Cu")
			(hatch none 0.5)
			(connect_pads
				(clearance 0)
			)
			(min_thickness 0.25)
			(keepout
				(tracks allowed)
				(vias not_allowed)
				(pads allowed)
				(copperpour not_allowed)
				(footprints allowed)
			)
			(placement
				(enabled no)
				(sheetname "")
			)
			(fill
				(thermal_gap 0.5)
				(thermal_bridge_width 0.5)
				(island_removal_mode 0)
			)
			(polygon
				(pts
					(xy 33.8455 -85.09) (xy 33.4645 -85.09) (xy 33.4645 -84.582) (xy 33.8455 -84.582)
				)
			)
		)
		(zone
			(layer "F.Cu")
			(hatch none 0.5)
			(connect_pads
				(clearance 0)
			)
			(min_thickness 0.25)
			(keepout
				(tracks not_allowed)
				(vias allowed)
				(pads allowed)
				(copperpour not_allowed)
				(footprints allowed)
			)
			(placement
				(enabled no)
				(sheetname "")
			)
			(fill
				(thermal_gap 0.5)
				(thermal_bridge_width 0.5)
				(island_removal_mode 0)
			)
			(polygon
				(pts
					(xy 33.8455 -85.09) (xy 33.4645 -85.09) (xy 33.4645 -84.582) (xy 33.8455 -84.582)
				)
			)
		)
	)
	(footprint ""
		(layer "F.Cu")
		(at 404.990554 -100.337112 180)
		(property "Reference" "C8C1"
			(at 0 0 180)
			(layer "F.SilkS")
			(hide yes)
			(effects
				(font
					(size 1.27 1.27)
				)
			)
		)
		(property "Value" ""
			(at 0 0 180)
			(layer "F.Fab")
			(effects
				(font
					(size 1.27 1.27)
				)
			)
		)
		(duplicate_pad_numbers_are_jumpers no)
		(fp_poly
			(pts
				(xy 0.3048 -0.1016) (xy 0.3048 0.9906) (xy -0.3048 0.9906) (xy -0.3048 -0.1016)
			)
			(stroke
				(width 0)
				(type default)
			)
			(fill no)
			(layer "F.CrtYd")
		)
		(fp_line
			(start 0.3048 0.9906)
			(end 0.3048 -0.1016)
			(stroke
				(width 0.1)
				(type default)
			)
			(layer "F.Fab")
		)
		(fp_line
			(start 0.3048 -0.1016)
			(end -0.3048 -0.1016)
			(stroke
				(width 0.1)
				(type default)
			)
			(layer "F.Fab")
		)
		(fp_line
			(start -0.3048 0.9906)
			(end 0.3048 0.9906)
			(stroke
				(width 0.1)
				(type default)
			)
			(layer "F.Fab")
		)
		(fp_line
			(start -0.3048 -0.1016)
			(end -0.3048 0.9906)
			(stroke
				(width 0.1)
				(type default)
			)
			(layer "F.Fab")
		)
		(pad "1" smd rect
			(at 0 0 180)
			(size 0.508 0.508)
			(layers "F.Cu" "F.Mask" "F.Paste")
			(net "XTAL_KR_25M_IN")
		)
		(pad "2" smd rect
			(at 0 0.889 180)
			(size 0.508 0.508)
			(layers "F.Cu" "F.Mask" "F.Paste")
			(net "GND")
		)
		(zone
			(layer "F.Cu")
			(hatch none 0.5)
			(connect_pads
				(clearance 0)
			)
			(min_thickness 0.25)
			(keepout
				(tracks not_allowed)
				(vias allowed)
				(pads allowed)
				(copperpour not_allowed)
				(footprints allowed)
			)
			(placement
				(enabled no)
				(sheetname "")
			)
			(fill
				(thermal_gap 0.5)
				(thermal_bridge_width 0.5)
				(island_removal_mode 0)
			)
			(polygon
				(pts
					(xy 405.244554 -100.972112) (xy 404.736554 -100.972112) (xy 404.736554 -100.591112) (xy 405.244554 -100.591112)
				)
			)
		)
		(zone
			(layer "F.Cu")
			(hatch none 0.5)
			(connect_pads
				(clearance 0)
			)
			(min_thickness 0.25)
			(keepout
				(tracks allowed)
				(vias not_allowed)
				(pads allowed)
				(copperpour not_allowed)
				(footprints allowed)
			)
			(placement
				(enabled no)
				(sheetname "")
			)
			(fill
				(thermal_gap 0.5)
				(thermal_bridge_width 0.5)
				(island_removal_mode 0)
			)
			(polygon
				(pts
					(xy 405.244554 -100.591112) (xy 404.736554 -100.591112) (xy 404.736554 -100.972112) (xy 405.244554 -100.972112)
				)
			)
		)
	)
	(footprint ""
		(layer "F.Cu")
		(at 334.137 -24.13 90)
		(property "Reference" "R7F12"
			(at 0 0 90)
			(layer "F.SilkS")
			(hide yes)
			(effects
				(font
					(size 1.27 1.27)
				)
			)
		)
		(property "Value" ""
			(at 0 0 90)
			(layer "F.Fab")
			(effects
				(font
					(size 1.27 1.27)
				)
			)
		)
		(duplicate_pad_numbers_are_jumpers no)
		(fp_rect
			(start 0.2794 0.9906)
			(end -0.2794 -0.1016)
			(stroke
				(width 0)
				(type default)
			)
			(fill no)
			(layer "F.CrtYd")
		)
		(fp_line
			(start 0.2794 -0.1016)
			(end -0.2794 -0.1016)
			(stroke
				(width 0.1)
				(type default)
			)
			(layer "F.Fab")
		)
		(fp_line
			(start -0.2794 -0.1016)
			(end -0.2794 0.9906)
			(stroke
				(width 0.1)
				(type default)
			)
			(layer "F.Fab")
		)
		(fp_line
			(start 0.2794 0.9906)
			(end 0.2794 -0.1016)
			(stroke
				(width 0.1)
				(type default)
			)
			(layer "F.Fab")
		)
		(fp_line
			(start -0.2794 0.9906)
			(end 0.2794 0.9906)
			(stroke
				(width 0.1)
				(type default)
			)
			(layer "F.Fab")
		)
		(pad "1" smd rect
			(at 0 0 90)
			(size 0.508 0.508)
			(layers "F.Cu" "F.Mask" "F.Paste")
			(net "PVPP_ABC")
		)
		(pad "2" smd rect
			(at 0 0.889 90)
			(size 0.508 0.508)
			(layers "F.Cu" "F.Mask" "F.Paste")
			(net "VSENSE_PVPP_ABC")
		)
		(zone
			(layer "F.Cu")
			(hatch none 0.5)
			(connect_pads
				(clearance 0)
			)
			(min_thickness 0.25)
			(keepout
				(tracks not_allowed)
				(vias allowed)
				(pads allowed)
				(copperpour not_allowed)
				(footprints allowed)
			)
			(placement
				(enabled no)
				(sheetname "")
			)
			(fill
				(thermal_gap 0.5)
				(thermal_bridge_width 0.5)
				(island_removal_mode 0)
			)
			(polygon
				(pts
					(xy 334.772 -24.384) (xy 334.391 -24.384) (xy 334.391 -23.876) (xy 334.772 -23.876)
				)
			)
		)
		(zone
			(layer "F.Cu")
			(hatch none 0.5)
			(connect_pads
				(clearance 0)
			)
			(min_thickness 0.25)
			(keepout
				(tracks allowed)
				(vias not_allowed)
				(pads allowed)
				(copperpour not_allowed)
				(footprints allowed)
			)
			(placement
				(enabled no)
				(sheetname "")
			)
			(fill
				(thermal_gap 0.5)
				(thermal_bridge_width 0.5)
				(island_removal_mode 0)
			)
			(polygon
				(pts
					(xy 334.772 -24.384) (xy 334.391 -24.384) (xy 334.391 -23.876) (xy 334.772 -23.876)
				)
			)
		)
	)
	(footprint ""
		(layer "F.Cu")
		(at 29.464 -12.4841 180)
		(property "Reference" "R1G3"
			(at 0 0 180)
			(layer "F.SilkS")
			(hide yes)
			(effects
				(font
					(size 1.27 1.27)
				)
			)
		)
		(property "Value" ""
			(at 0 0 180)
			(layer "F.Fab")
			(effects
				(font
					(size 1.27 1.27)
				)
			)
		)
		(duplicate_pad_numbers_are_jumpers no)
		(fp_poly
			(pts
				(xy -0.2794 -0.1016) (xy 0.2794 -0.1016) (xy 0.2794 0.9906) (xy -0.2794 0.9906)
			)
			(stroke
				(width 0)
				(type default)
			)
			(fill no)
			(layer "F.CrtYd")
		)
		(fp_line
			(start 0.2794 0.9906)
			(end 0.2794 -0.1016)
			(stroke
				(width 0.1)
				(type default)
			)
			(layer "F.Fab")
		)
		(fp_line
			(start 0.2794 -0.1016)
			(end -0.2794 -0.1016)
			(stroke
				(width 0.1)
				(type default)
			)
			(layer "F.Fab")
		)
		(fp_line
			(start -0.2794 0.9906)
			(end 0.2794 0.9906)
			(stroke
				(width 0.1)
				(type default)
			)
			(layer "F.Fab")
		)
		(fp_line
			(start -0.2794 -0.1016)
			(end -0.2794 0.9906)
			(stroke
				(width 0.1)
				(type default)
			)
			(layer "F.Fab")
		)
		(pad "1" smd rect
			(at 0 0 180)
			(size 0.508 0.508)
			(layers "F.Cu" "F.Mask" "F.Paste")
			(net "M_H_VREF")
		)
		(pad "2" smd rect
			(at 0 0.889 180)
			(size 0.508 0.508)
			(layers "F.Cu" "F.Mask" "F.Paste")
			(net "GND")
		)
		(zone
			(layer "F.Cu")
			(hatch none 0.5)
			(connect_pads
				(clearance 0)
			)
			(min_thickness 0.25)
			(keepout
				(tracks not_allowed)
				(vias allowed)
				(pads allowed)
				(copperpour not_allowed)
				(footprints allowed)
			)
			(placement
				(enabled no)
				(sheetname "")
			)
			(fill
				(thermal_gap 0.5)
				(thermal_bridge_width 0.5)
				(island_removal_mode 0)
			)
			(polygon
				(pts
					(xy 29.718 -13.1191) (xy 29.21 -13.1191) (xy 29.21 -12.7381) (xy 29.718 -12.7381)
				)
			)
		)
		(zone
			(layer "F.Cu")
			(hatch none 0.5)
			(connect_pads
				(clearance 0)
			)
			(min_thickness 0.25)
			(keepout
				(tracks allowed)
				(vias not_allowed)
				(pads allowed)
				(copperpour not_allowed)
				(footprints allowed)
			)
			(placement
				(enabled no)
				(sheetname "")
			)
			(fill
				(thermal_gap 0.5)
				(thermal_bridge_width 0.5)
				(island_removal_mode 0)
			)
			(polygon
				(pts
					(xy 29.718 -12.7381) (xy 29.21 -12.7381) (xy 29.21 -13.1191) (xy 29.718 -13.1191)
				)
			)
		)
	)
	(footprint ""
		(layer "F.Cu")
		(at 177.673 -13.335 90)
		(property "Reference" "EU4G1"
			(at 5.18033 -0.889 0)
			(unlocked yes)
			(layer "F.SilkS")
			(effects
				(font
					(size 0.7874 0.5842)
					(thickness 0.1524)
				)
				(justify left)
			)
		)
		(property "Value" ""
			(at 0 0 90)
			(layer "F.Fab")
			(effects
				(font
					(size 1.27 1.27)
				)
			)
		)
		(duplicate_pad_numbers_are_jumpers no)
		(fp_line
			(start 3.4671 -3.4671)
			(end 3.4671 3.4671)
			(stroke
				(width 0.1524)
				(type default)
			)
			(layer "F.SilkS")
		)
		(fp_line
			(start -3.4671 -3.4671)
			(end 3.4671 -3.4671)
			(stroke
				(width 0.1524)
				(type default)
			)
			(layer "F.SilkS")
		)
		(fp_line
			(start 3.10007 -3.10007)
			(end 3.10007 -2.900934)
			(stroke
				(width 0.1524)
				(type default)
			)
			(layer "F.SilkS")
		)
		(fp_line
			(start 2.897886 -3.10007)
			(end 3.10007 -3.10007)
			(stroke
				(width 0.1524)
				(type default)
			)
			(layer "F.SilkS")
		)
		(fp_line
			(start -3.10007 -3.10007)
			(end -2.897886 -3.10007)
			(stroke
				(width 0.1524)
				(type default)
			)
			(layer "F.SilkS")
		)
		(fp_line
			(start -3.10007 -2.900934)
			(end -3.10007 -3.10007)
			(stroke
				(width 0.1524)
				(type default)
			)
			(layer "F.SilkS")
		)
		(fp_line
			(start 3.10007 2.897378)
			(end 3.10007 3.10007)
			(stroke
				(width 0.1524)
				(type default)
			)
			(layer "F.SilkS")
		)
		(fp_line
			(start 3.10007 3.10007)
			(end 2.897886 3.10007)
			(stroke
				(width 0.1524)
				(type default)
			)
			(layer "F.SilkS")
		)
		(fp_line
			(start -2.897886 3.10007)
			(end -3.10007 3.10007)
			(stroke
				(width 0.1524)
				(type default)
			)
			(layer "F.SilkS")
		)
		(fp_line
			(start -3.10007 3.10007)
			(end -3.10007 2.897378)
			(stroke
				(width 0.1524)
				(type default)
			)
			(layer "F.SilkS")
		)
		(fp_line
			(start 3.4671 3.4671)
			(end -3.4671 3.4671)
			(stroke
				(width 0.1524)
				(type default)
			)
			(layer "F.SilkS")
		)
		(fp_line
			(start -3.4671 3.4671)
			(end -3.4671 -3.4671)
			(stroke
				(width 0.1524)
				(type default)
			)
			(layer "F.SilkS")
		)
		(fp_circle
			(center -3.917696 -3.100578)
			(end -3.917696 -2.973578)
			(stroke
				(width 0.254)
				(type default)
			)
			(fill no)
			(layer "F.SilkS")
		)
		(fp_poly
			(pts
				(xy -3.4671 -3.4671) (xy -3.4671 -2.5146) (xy -2.5146 -3.4671)
			)
			(stroke
				(width 0)
				(type default)
			)
			(fill yes)
			(layer "F.SilkS")
		)
		(fp_rect
			(start -2.1971 -0.1905)
			(end -0.6985 -2.1971)
			(stroke
				(width 0)
				(type default)
			)
			(fill yes)
			(layer "F.Paste")
		)
		(fp_rect
			(start -0.1905 2.1971)
			(end 2.1971 -2.1971)
			(stroke
				(width 0)
				(type default)
			)
			(fill yes)
			(layer "F.Paste")
		)
		(fp_rect
			(start -2.1971 2.1971)
			(end -0.6985 0.1905)
			(stroke
				(width 0)
				(type default)
			)
			(fill yes)
			(layer "F.Paste")
		)
		(fp_poly
			(pts
				(xy -3.10007 -3.10007) (xy -3.10007 3.10007) (xy 3.10007 3.10007) (xy 3.10007 -3.10007)
			)
			(stroke
				(width 0)
				(type default)
			)
			(fill no)
			(layer "F.CrtYd")
		)
		(fp_line
			(start 3.10007 -3.10007)
			(end 3.10007 3.10007)
			(stroke
				(width 0.1)
				(type default)
			)
			(layer "F.Fab")
		)
		(fp_line
			(start -3.10007 -3.10007)
			(end 3.10007 -3.10007)
			(stroke
				(width 0.1)
				(type default)
			)
			(layer "F.Fab")
		)
		(fp_line
			(start 3.10007 3.10007)
			(end -3.10007 3.10007)
			(stroke
				(width 0.1)
				(type default)
			)
			(layer "F.Fab")
		)
		(fp_line
			(start -3.10007 3.10007)
			(end -3.10007 -3.10007)
			(stroke
				(width 0.1)
				(type default)
			)
			(layer "F.Fab")
		)
		(fp_circle
			(center -3.917696 -3.100578)
			(end -3.917696 -2.973578)
			(stroke
				(width 0.254)
				(type default)
			)
			(fill no)
			(layer "F.Fab")
		)
		(pad "1" smd custom
			(at -2.8321 -2.249932 90)
			(size 0.06985 0.06985)
			(layers "F.Cu" "F.Mask" "F.Paste")
			(net "VR_PVPP_GHJ_SS")
			(options
				(clearance outline)
				(anchor circle)
			)
			(primitives
				(gr_poly
					(pts
						(arc
							(start 0.2413 -0.1397)
							(mid 0.381 0)
							(end 0.2413 0.1397)
						)
						(xy -0.381 0.1397) (xy -0.381 -0.1397)
					)
					(width 0)
					(fill yes)
				)
			)
		)
		(pad "2" smd custom
			(at -2.8321 -1.75006 90)
			(size 0.06985 0.06985)
			(layers "F.Cu" "F.Mask" "F.Paste")
			(net "VR_FB_PVPP_GHJ")
			(options
				(clearance outline)
				(anchor circle)
			)
			(primitives
				(gr_poly
					(pts
						(arc
							(start 0.2413 -0.1397)
							(mid 0.381 0)
							(end 0.2413 0.1397)
						)
						(xy -0.381 0.1397) (xy -0.381 -0.1397)
					)
					(width 0)
					(fill yes)
				)
			)
		)
		(pad "3" smd custom
			(at -2.8321 -1.249934 90)
			(size 0.06985 0.06985)
			(layers "F.Cu" "F.Mask" "F.Paste")
			(net "VR_COMP_PVPP_GHJ_3")
			(options
				(clearance outline)
				(anchor circle)
			)
			(primitives
				(gr_poly
					(pts
						(arc
							(start 0.2413 -0.1397)
							(mid 0.381 0)
							(end 0.2413 0.1397)
						)
						(xy -0.381 0.1397) (xy -0.381 -0.1397)
					)
					(width 0)
					(fill yes)
				)
			)
		)
		(pad "4" smd custom
			(at -2.8321 -0.750062 90)
			(size 0.06985 0.06985)
			(layers "F.Cu" "F.Mask" "F.Paste")
			(net "VR_PVPP_GHJ_ISET")
			(options
				(clearance outline)
				(anchor circle)
			)
			(primitives
				(gr_poly
					(pts
						(arc
							(start 0.2413 -0.1397)
							(mid 0.381 0)
							(end 0.2413 0.1397)
						)
						(xy -0.381 0.1397) (xy -0.381 -0.1397)
					)
					(width 0)
					(fill yes)
				)
			)
		)
		(pad "5" smd custom
			(at -2.8321 -0.249936 90)
			(size 0.06985 0.06985)
			(layers "F.Cu" "F.Mask" "F.Paste")
			(net "AGND_PVPP_GHJ")
			(options
				(clearance outline)
				(anchor circle)
			)
			(primitives
				(gr_poly
					(pts
						(arc
							(start 0.2413 -0.1397)
							(mid 0.381 0)
							(end 0.2413 0.1397)
						)
						(xy -0.381 0.1397) (xy -0.381 -0.1397)
					)
					(width 0)
					(fill yes)
				)
			)
		)
		(pad "6" smd custom
			(at -2.8321 0.249936 90)
			(size 0.06985 0.06985)
			(layers "F.Cu" "F.Mask" "F.Paste")
			(net "AGND_PVPP_GHJ")
			(options
				(clearance outline)
				(anchor circle)
			)
			(primitives
				(gr_poly
					(pts
						(arc
							(start 0.2413 -0.1397)
							(mid 0.381 0)
							(end 0.2413 0.1397)
						)
						(xy -0.381 0.1397) (xy -0.381 -0.1397)
					)
					(width 0)
					(fill yes)
				)
			)
		)
		(pad "7" smd custom
			(at -2.8321 0.750062 90)
			(size 0.06985 0.06985)
			(layers "F.Cu" "F.Mask" "F.Paste")
			(net "PWRGD_PVPP_GHJ_R")
			(options
				(clearance outline)
				(anchor circle)
			)
			(primitives
				(gr_poly
					(pts
						(arc
							(start 0.2413 -0.1397)
							(mid 0.381 0)
							(end 0.2413 0.1397)
						)
						(xy -0.381 0.1397) (xy -0.381 -0.1397)
					)
					(width 0)
					(fill yes)
				)
			)
		)
		(pad "8" smd custom
			(at -2.8321 1.249934 90)
			(size 0.06985 0.06985)
			(layers "F.Cu" "F.Mask" "F.Paste")
			(net "VR_FET_SW_P12V_STBY_PVPP_GHJ")
			(options
				(clearance outline)
				(anchor circle)
			)
			(primitives
				(gr_poly
					(pts
						(arc
							(start 0.2413 -0.1397)
							(mid 0.381 0)
							(end 0.2413 0.1397)
						)
						(xy -0.381 0.1397) (xy -0.381 -0.1397)
					)
					(width 0)
					(fill yes)
				)
			)
		)
		(pad "9" smd custom
			(at -2.8321 1.75006 90)
			(size 0.06985 0.06985)
			(layers "F.Cu" "F.Mask" "F.Paste")
			(net "VR_FET_SW_P12V_STBY_PVPP_GHJ")
			(options
				(clearance outline)
				(anchor circle)
			)
			(primitives
				(gr_poly
					(pts
						(arc
							(start 0.2413 -0.1397)
							(mid 0.381 0)
							(end 0.2413 0.1397)
						)
						(xy -0.381 0.1397) (xy -0.381 -0.1397)
					)
					(width 0)
					(fill yes)
				)
			)
		)
		(pad "10" smd custom
			(at -2.8321 2.249932 90)
			(size 0.06985 0.06985)
			(layers "F.Cu" "F.Mask" "F.Paste")
			(net "VR_FET_SW_P12V_STBY_PVPP_GHJ")
			(options
				(clearance outline)
				(anchor circle)
			)
			(primitives
				(gr_poly
					(pts
						(arc
							(start 0.2413 -0.1397)
							(mid 0.381 0)
							(end 0.2413 0.1397)
						)
						(xy -0.381 0.1397) (xy -0.381 -0.1397)
					)
					(width 0)
					(fill yes)
				)
			)
		)
		(pad "11" smd custom
			(at -2.249932 2.8321 90)
			(size 0.06985 0.06985)
			(layers "F.Cu" "F.Mask" "F.Paste")
			(net "VR_FET_SW_P12V_STBY_PVPP_GHJ")
			(options
				(clearance outline)
				(anchor circle)
			)
			(primitives
				(gr_poly
					(pts
						(arc
							(start -0.1397 -0.2413)
							(mid 0 -0.381)
							(end 0.1397 -0.2413)
						)
						(xy 0.1397 0.381) (xy -0.1397 0.381)
					)
					(width 0)
					(fill yes)
				)
			)
		)
		(pad "12" smd custom
			(at -1.75006 2.8321 90)
			(size 0.06985 0.06985)
			(layers "F.Cu" "F.Mask" "F.Paste")
			(net "VR_FET_SW_P12V_STBY_PVPP_GHJ")
			(options
				(clearance outline)
				(anchor circle)
			)
			(primitives
				(gr_poly
					(pts
						(arc
							(start -0.1397 -0.2413)
							(mid 0 -0.381)
							(end 0.1397 -0.2413)
						)
						(xy 0.1397 0.381) (xy -0.1397 0.381)
					)
					(width 0)
					(fill yes)
				)
			)
		)
		(pad "13" smd custom
			(at -1.249934 2.8321 90)
			(size 0.06985 0.06985)
			(layers "F.Cu" "F.Mask" "F.Paste")
			(net "VR_FET_SW_P12V_STBY_PVPP_GHJ")
			(options
				(clearance outline)
				(anchor circle)
			)
			(primitives
				(gr_poly
					(pts
						(arc
							(start -0.1397 -0.2413)
							(mid 0 -0.381)
							(end 0.1397 -0.2413)
						)
						(xy 0.1397 0.381) (xy -0.1397 0.381)
					)
					(width 0)
					(fill yes)
				)
			)
		)
		(pad "14" smd custom
			(at -0.750062 2.8321 90)
			(size 0.06985 0.06985)
			(layers "F.Cu" "F.Mask" "F.Paste")
			(net "VR_FET_SW_P12V_STBY_PVPP_GHJ")
			(options
				(clearance outline)
				(anchor circle)
			)
			(primitives
				(gr_poly
					(pts
						(arc
							(start -0.1397 -0.2413)
							(mid 0 -0.381)
							(end 0.1397 -0.2413)
						)
						(xy 0.1397 0.381) (xy -0.1397 0.381)
					)
					(width 0)
					(fill yes)
				)
			)
		)
		(pad "15" smd custom
			(at -0.249936 2.8321 90)
			(size 0.06985 0.06985)
			(layers "F.Cu" "F.Mask" "F.Paste")
			(net "VR_PVPP_GHJ_PHASE")
			(options
				(clearance outline)
				(anchor circle)
			)
			(primitives
				(gr_poly
					(pts
						(arc
							(start -0.1397 -0.2413)
							(mid 0 -0.381)
							(end 0.1397 -0.2413)
						)
						(xy 0.1397 0.381) (xy -0.1397 0.381)
					)
					(width 0)
					(fill yes)
				)
			)
		)
		(pad "16" smd custom
			(at 0.249936 2.8321 90)
			(size 0.06985 0.06985)
			(layers "F.Cu" "F.Mask" "F.Paste")
			(net "GND")
			(options
				(clearance outline)
				(anchor circle)
			)
			(primitives
				(gr_poly
					(pts
						(arc
							(start -0.1397 -0.2413)
							(mid 0 -0.381)
							(end 0.1397 -0.2413)
						)
						(xy 0.1397 0.381) (xy -0.1397 0.381)
					)
					(width 0)
					(fill yes)
				)
			)
		)
		(pad "17" smd custom
			(at 0.750062 2.8321 90)
			(size 0.06985 0.06985)
			(layers "F.Cu" "F.Mask" "F.Paste")
			(net "GND")
			(options
				(clearance outline)
				(anchor circle)
			)
			(primitives
				(gr_poly
					(pts
						(arc
							(start -0.1397 -0.2413)
							(mid 0 -0.381)
							(end 0.1397 -0.2413)
						)
						(xy 0.1397 0.381) (xy -0.1397 0.381)
					)
					(width 0)
					(fill yes)
				)
			)
		)
		(pad "18" smd custom
			(at 1.249934 2.8321 90)
			(size 0.06985 0.06985)
			(layers "F.Cu" "F.Mask" "F.Paste")
			(net "GND")
			(options
				(clearance outline)
				(anchor circle)
			)
			(primitives
				(gr_poly
					(pts
						(arc
							(start -0.1397 -0.2413)
							(mid 0 -0.381)
							(end 0.1397 -0.2413)
						)
						(xy 0.1397 0.381) (xy -0.1397 0.381)
					)
					(width 0)
					(fill yes)
				)
			)
		)
		(pad "19" smd custom
			(at 1.75006 2.8321 90)
			(size 0.06985 0.06985)
			(layers "F.Cu" "F.Mask" "F.Paste")
			(net "GND")
			(options
				(clearance outline)
				(anchor circle)
			)
			(primitives
				(gr_poly
					(pts
						(arc
							(start -0.1397 -0.2413)
							(mid 0 -0.381)
							(end 0.1397 -0.2413)
						)
						(xy 0.1397 0.381) (xy -0.1397 0.381)
					)
					(width 0)
					(fill yes)
				)
			)
		)
		(pad "20" smd custom
			(at 2.249932 2.8321 90)
			(size 0.06985 0.06985)
			(layers "F.Cu" "F.Mask" "F.Paste")
			(net "GND")
			(options
				(clearance outline)
				(anchor circle)
			)
			(primitives
				(gr_poly
					(pts
						(arc
							(start -0.1397 -0.2413)
							(mid 0 -0.381)
							(end 0.1397 -0.2413)
						)
						(xy 0.1397 0.381) (xy -0.1397 0.381)
					)
					(width 0)
					(fill yes)
				)
			)
		)
		(pad "21" smd custom
			(at 2.8321 2.249932 90)
			(size 0.06985 0.06985)
			(layers "F.Cu" "F.Mask" "F.Paste")
			(net "GND")
			(options
				(clearance outline)
				(anchor circle)
			)
			(primitives
				(gr_poly
					(pts
						(arc
							(start -0.2413 0.1397)
							(mid -0.381 0)
							(end -0.2413 -0.1397)
						)
						(xy 0.381 -0.1397) (xy 0.381 0.1397)
					)
					(width 0)
					(fill yes)
				)
			)
		)
		(pad "22" smd custom
			(at 2.8321 1.75006 90)
			(size 0.06985 0.06985)
			(layers "F.Cu" "F.Mask" "F.Paste")
			(net "GND")
			(options
				(clearance outline)
				(anchor circle)
			)
			(primitives
				(gr_poly
					(pts
						(arc
							(start -0.2413 0.1397)
							(mid -0.381 0)
							(end -0.2413 -0.1397)
						)
						(xy 0.381 -0.1397) (xy 0.381 0.1397)
					)
					(width 0)
					(fill yes)
				)
			)
		)
		(pad "23" smd custom
			(at 2.8321 1.249934 90)
			(size 0.06985 0.06985)
			(layers "F.Cu" "F.Mask" "F.Paste")
			(net "GND")
			(options
				(clearance outline)
				(anchor circle)
			)
			(primitives
				(gr_poly
					(pts
						(arc
							(start -0.2413 0.1397)
							(mid -0.381 0)
							(end -0.2413 -0.1397)
						)
						(xy 0.381 -0.1397) (xy 0.381 0.1397)
					)
					(width 0)
					(fill yes)
				)
			)
		)
		(pad "24" smd custom
			(at 2.8321 0.750062 90)
			(size 0.06985 0.06985)
			(layers "F.Cu" "F.Mask" "F.Paste")
			(net "GND")
			(options
				(clearance outline)
				(anchor circle)
			)
			(primitives
				(gr_poly
					(pts
						(arc
							(start -0.2413 0.1397)
							(mid -0.381 0)
							(end -0.2413 -0.1397)
						)
						(xy 0.381 -0.1397) (xy 0.381 0.1397)
					)
					(width 0)
					(fill yes)
				)
			)
		)
		(pad "25" smd custom
			(at 2.8321 0.249936 90)
			(size 0.06985 0.06985)
			(layers "F.Cu" "F.Mask" "F.Paste")
			(net "GND")
			(options
				(clearance outline)
				(anchor circle)
			)
			(primitives
				(gr_poly
					(pts
						(arc
							(start -0.2413 0.1397)
							(mid -0.381 0)
							(end -0.2413 -0.1397)
						)
						(xy 0.381 -0.1397) (xy 0.381 0.1397)
					)
					(width 0)
					(fill yes)
				)
			)
		)
		(pad "26" smd custom
			(at 2.8321 -0.249936 90)
			(size 0.06985 0.06985)
			(layers "F.Cu" "F.Mask" "F.Paste")
			(net "GND")
			(options
				(clearance outline)
				(anchor circle)
			)
			(primitives
				(gr_poly
					(pts
						(arc
							(start -0.2413 0.1397)
							(mid -0.381 0)
							(end -0.2413 -0.1397)
						)
						(xy 0.381 -0.1397) (xy 0.381 0.1397)
					)
					(width 0)
					(fill yes)
				)
			)
		)
		(pad "27" smd custom
			(at 2.8321 -0.750062 90)
			(size 0.06985 0.06985)
			(layers "F.Cu" "F.Mask" "F.Paste")
			(net "GND")
			(options
				(clearance outline)
				(anchor circle)
			)
			(primitives
				(gr_poly
					(pts
						(arc
							(start -0.2413 0.1397)
							(mid -0.381 0)
							(end -0.2413 -0.1397)
						)
						(xy 0.381 -0.1397) (xy 0.381 0.1397)
					)
					(width 0)
					(fill yes)
				)
			)
		)
		(pad "28" smd custom
			(at 2.8321 -1.249934 90)
			(size 0.06985 0.06985)
			(layers "F.Cu" "F.Mask" "F.Paste")
			(net "GND")
			(options
				(clearance outline)
				(anchor circle)
			)
			(primitives
				(gr_poly
					(pts
						(arc
							(start -0.2413 0.1397)
							(mid -0.381 0)
							(end -0.2413 -0.1397)
						)
						(xy 0.381 -0.1397) (xy 0.381 0.1397)
					)
					(width 0)
					(fill yes)
				)
			)
		)
		(pad "29" smd custom
			(at 2.8321 -1.75006 90)
			(size 0.06985 0.06985)
			(layers "F.Cu" "F.Mask" "F.Paste")
			(net "VR_PVPP_GHJ_PHASE")
			(options
				(clearance outline)
				(anchor circle)
			)
			(primitives
				(gr_poly
					(pts
						(arc
							(start -0.2413 0.1397)
							(mid -0.381 0)
							(end -0.2413 -0.1397)
						)
						(xy 0.381 -0.1397) (xy 0.381 0.1397)
					)
					(width 0)
					(fill yes)
				)
			)
		)
		(pad "30" smd custom
			(at 2.8321 -2.249932 90)
			(size 0.06985 0.06985)
			(layers "F.Cu" "F.Mask" "F.Paste")
			(net "VR_PVPP_GHJ_PHASE")
			(options
				(clearance outline)
				(anchor circle)
			)
			(primitives
				(gr_poly
					(pts
						(arc
							(start -0.2413 0.1397)
							(mid -0.381 0)
							(end -0.2413 -0.1397)
						)
						(xy 0.381 -0.1397) (xy 0.381 0.1397)
					)
					(width 0)
					(fill yes)
				)
			)
		)
		(pad "31" smd custom
			(at 2.249932 -2.8321 90)
			(size 0.06985 0.06985)
			(layers "F.Cu" "F.Mask" "F.Paste")
			(net "VR_PVPP_GHJ_PHASE")
			(options
				(clearance outline)
				(anchor circle)
			)
			(primitives
				(gr_poly
					(pts
						(arc
							(start 0.1397 0.2413)
							(mid 0 0.381)
							(end -0.1397 0.2413)
						)
						(xy -0.1397 -0.381) (xy 0.1397 -0.381)
					)
					(width 0)
					(fill yes)
				)
			)
		)
		(pad "32" smd custom
			(at 1.75006 -2.8321 90)
			(size 0.06985 0.06985)
			(layers "F.Cu" "F.Mask" "F.Paste")
			(net "VR_PVPP_GHJ_PHASE")
			(options
				(clearance outline)
				(anchor circle)
			)
			(primitives
				(gr_poly
					(pts
						(arc
							(start 0.1397 0.2413)
							(mid 0 0.381)
							(end -0.1397 0.2413)
						)
						(xy -0.1397 -0.381) (xy 0.1397 -0.381)
					)
					(width 0)
					(fill yes)
				)
			)
		)
		(pad "33" smd custom
			(at 1.249934 -2.8321 90)
			(size 0.06985 0.06985)
			(layers "F.Cu" "F.Mask" "F.Paste")
			(net "VR_PVPP_GHJ_PHASE")
			(options
				(clearance outline)
				(anchor circle)
			)
			(primitives
				(gr_poly
					(pts
						(arc
							(start 0.1397 0.2413)
							(mid 0 0.381)
							(end -0.1397 0.2413)
						)
						(xy -0.1397 -0.381) (xy 0.1397 -0.381)
					)
					(width 0)
					(fill yes)
				)
			)
		)
		(pad "34" smd custom
			(at 0.750062 -2.8321 90)
			(size 0.06985 0.06985)
			(layers "F.Cu" "F.Mask" "F.Paste")
			(net "VR_PVPP_GHJ_PHASE")
			(options
				(clearance outline)
				(anchor circle)
			)
			(primitives
				(gr_poly
					(pts
						(arc
							(start 0.1397 0.2413)
							(mid 0 0.381)
							(end -0.1397 0.2413)
						)
						(xy -0.1397 -0.381) (xy 0.1397 -0.381)
					)
					(width 0)
					(fill yes)
				)
			)
		)
		(pad "35" smd custom
			(at 0.249936 -2.8321 90)
			(size 0.06985 0.06985)
			(layers "F.Cu" "F.Mask" "F.Paste")
			(net "VR_PVPP_GHJ_PHASE")
			(options
				(clearance outline)
				(anchor circle)
			)
			(primitives
				(gr_poly
					(pts
						(arc
							(start 0.1397 0.2413)
							(mid 0 0.381)
							(end -0.1397 0.2413)
						)
						(xy -0.1397 -0.381) (xy 0.1397 -0.381)
					)
					(width 0)
					(fill yes)
				)
			)
		)
		(pad "36" smd custom
			(at -0.249936 -2.8321 90)
			(size 0.06985 0.06985)
			(layers "F.Cu" "F.Mask" "F.Paste")
			(net "VR_PVPP_GHJ_BOOT")
			(options
				(clearance outline)
				(anchor circle)
			)
			(primitives
				(gr_poly
					(pts
						(arc
							(start 0.1397 0.2413)
							(mid 0 0.381)
							(end -0.1397 0.2413)
						)
						(xy -0.1397 -0.381) (xy 0.1397 -0.381)
					)
					(width 0)
					(fill yes)
				)
			)
		)
		(pad "37" smd custom
			(at -0.750062 -2.8321 90)
			(size 0.06985 0.06985)
			(layers "F.Cu" "F.Mask" "F.Paste")
			(net "GND")
			(options
				(clearance outline)
				(anchor circle)
			)
			(primitives
				(gr_poly
					(pts
						(arc
							(start 0.1397 0.2413)
							(mid 0 0.381)
							(end -0.1397 0.2413)
						)
						(xy -0.1397 -0.381) (xy 0.1397 -0.381)
					)
					(width 0)
					(fill yes)
				)
			)
		)
		(pad "38" smd custom
			(at -1.249934 -2.8321 90)
			(size 0.06985 0.06985)
			(layers "F.Cu" "F.Mask" "F.Paste")
			(net "VR_VB_PVPP_GHJ")
			(options
				(clearance outline)
				(anchor circle)
			)
			(primitives
				(gr_poly
					(pts
						(arc
							(start 0.1397 0.2413)
							(mid 0 0.381)
							(end -0.1397 0.2413)
						)
						(xy -0.1397 -0.381) (xy 0.1397 -0.381)
					)
					(width 0)
					(fill yes)
				)
			)
		)
		(pad "39" smd custom
			(at -1.75006 -2.8321 90)
			(size 0.06985 0.06985)
			(layers "F.Cu" "F.Mask" "F.Paste")
			(net "VR_FET_SW_P12V_STBY_PVPP_GHJ")
			(options
				(clearance outline)
				(anchor circle)
			)
			(primitives
				(gr_poly
					(pts
						(arc
							(start 0.1397 0.2413)
							(mid 0 0.381)
							(end -0.1397 0.2413)
						)
						(xy -0.1397 -0.381) (xy 0.1397 -0.381)
					)
					(width 0)
					(fill yes)
				)
			)
		)
		(pad "40" smd custom
			(at -2.249932 -2.8321 90)
			(size 0.06985 0.06985)
			(layers "F.Cu" "F.Mask" "F.Paste")
			(net "FM_PVPP_PVDDQ_CPU1_EN_GHJ")
			(options
				(clearance outline)
				(anchor circle)
			)
			(primitives
				(gr_poly
					(pts
						(arc
							(start 0.1397 0.2413)
							(mid 0 0.381)
							(end -0.1397 0.2413)
						)
						(xy -0.1397 -0.381) (xy 0.1397 -0.381)
					)
					(width 0)
					(fill yes)
				)
			)
		)
		(pad "41" smd rect
			(at -1.4478 -1.1938 90)
			(size 1.4986 2.0066)
			(layers "F.Cu" "F.Mask" "F.Paste")
			(net "GND")
		)
		(pad "42" smd rect
			(at -1.4478 1.1938 90)
			(size 1.4986 2.0066)
			(layers "F.Cu" "F.Mask" "F.Paste")
			(net "VR_FET_SW_P12V_STBY_PVPP_GHJ")
		)
		(pad "43" smd rect
			(at 1.0033 0 90)
			(size 2.3876 4.3942)
			(layers "F.Cu" "F.Mask" "F.Paste")
			(net "VR_PVPP_GHJ_PHASE")
		)
	)
	(footprint ""
		(layer "F.Cu")
		(at 488.3912 -50.6857)
		(property "Reference" "R9E3"
			(at 0 0 0)
			(layer "F.SilkS")
			(hide yes)
			(effects
				(font
					(size 1.27 1.27)
				)
			)
		)
		(property "Value" ""
			(at 0 0 0)
			(layer "F.Fab")
			(effects
				(font
					(size 1.27 1.27)
				)
			)
		)
		(duplicate_pad_numbers_are_jumpers no)
		(fp_poly
			(pts
				(xy -0.2794 -0.1016) (xy 0.2794 -0.1016) (xy 0.2794 0.9906) (xy -0.2794 0.9906)
			)
			(stroke
				(width 0)
				(type default)
			)
			(fill no)
			(layer "F.CrtYd")
		)
		(fp_line
			(start -0.2794 -0.1016)
			(end -0.2794 0.9906)
			(stroke
				(width 0.1)
				(type default)
			)
			(layer "F.Fab")
		)
		(fp_line
			(start -0.2794 0.9906)
			(end 0.2794 0.9906)
			(stroke
				(width 0.1)
				(type default)
			)
			(layer "F.Fab")
		)
		(fp_line
			(start 0.2794 -0.1016)
			(end -0.2794 -0.1016)
			(stroke
				(width 0.1)
				(type default)
			)
			(layer "F.Fab")
		)
		(fp_line
			(start 0.2794 0.9906)
			(end 0.2794 -0.1016)
			(stroke
				(width 0.1)
				(type default)
			)
			(layer "F.Fab")
		)
		(pad "1" smd rect
			(at 0 0)
			(size 0.508 0.508)
			(layers "F.Cu" "F.Mask" "F.Paste")
			(net "P3V3_STBY")
		)
		(pad "2" smd rect
			(at 0 0.889)
			(size 0.508 0.508)
			(layers "F.Cu" "F.Mask" "F.Paste")
			(net "PU_JTAG_SPRV_TMS")
		)
		(zone
			(layer "F.Cu")
			(hatch none 0.5)
			(connect_pads
				(clearance 0)
			)
			(min_thickness 0.25)
			(keepout
				(tracks allowed)
				(vias not_allowed)
				(pads allowed)
				(copperpour not_allowed)
				(footprints allowed)
			)
			(placement
				(enabled no)
				(sheetname "")
			)
			(fill
				(thermal_gap 0.5)
				(thermal_bridge_width 0.5)
				(island_removal_mode 0)
			)
			(polygon
				(pts
					(xy 488.1372 -50.4317) (xy 488.6452 -50.4317) (xy 488.6452 -50.0507) (xy 488.1372 -50.0507)
				)
			)
		)
		(zone
			(layer "F.Cu")
			(hatch none 0.5)
			(connect_pads
				(clearance 0)
			)
			(min_thickness 0.25)
			(keepout
				(tracks not_allowed)
				(vias allowed)
				(pads allowed)
				(copperpour not_allowed)
				(footprints allowed)
			)
			(placement
				(enabled no)
				(sheetname "")
			)
			(fill
				(thermal_gap 0.5)
				(thermal_bridge_width 0.5)
				(island_removal_mode 0)
			)
			(polygon
				(pts
					(xy 488.1372 -50.0507) (xy 488.6452 -50.0507) (xy 488.6452 -50.4317) (xy 488.1372 -50.4317)
				)
			)
		)
	)
	(footprint ""
		(layer "F.Cu")
		(at 417.83 -86.4235)
		(property "Reference" "C8E1"
			(at 0 0 0)
			(layer "F.SilkS")
			(hide yes)
			(effects
				(font
					(size 1.27 1.27)
				)
			)
		)
		(property "Value" ""
			(at 0 0 0)
			(layer "F.Fab")
			(effects
				(font
					(size 1.27 1.27)
				)
			)
		)
		(duplicate_pad_numbers_are_jumpers no)
		(fp_poly
			(pts
				(xy 0.3048 -0.1016) (xy 0.3048 0.9906) (xy -0.3048 0.9906) (xy -0.3048 -0.1016)
			)
			(stroke
				(width 0)
				(type default)
			)
			(fill no)
			(layer "F.CrtYd")
		)
		(fp_line
			(start -0.3048 -0.1016)
			(end -0.3048 0.9906)
			(stroke
				(width 0.1)
				(type default)
			)
			(layer "F.Fab")
		)
		(fp_line
			(start -0.3048 0.9906)
			(end 0.3048 0.9906)
			(stroke
				(width 0.1)
				(type default)
			)
			(layer "F.Fab")
		)
		(fp_line
			(start 0.3048 -0.1016)
			(end -0.3048 -0.1016)
			(stroke
				(width 0.1)
				(type default)
			)
			(layer "F.Fab")
		)
		(fp_line
			(start 0.3048 0.9906)
			(end 0.3048 -0.1016)
			(stroke
				(width 0.1)
				(type default)
			)
			(layer "F.Fab")
		)
		(pad "1" smd rect
			(at 0 0)
			(size 0.508 0.508)
			(layers "F.Cu" "F.Mask" "F.Paste")
			(net "P3V3_STBY")
		)
		(pad "2" smd rect
			(at 0 0.889)
			(size 0.508 0.508)
			(layers "F.Cu" "F.Mask" "F.Paste")
			(net "GND")
		)
		(zone
			(layer "F.Cu")
			(hatch none 0.5)
			(connect_pads
				(clearance 0)
			)
			(min_thickness 0.25)
			(keepout
				(tracks allowed)
				(vias not_allowed)
				(pads allowed)
				(copperpour not_allowed)
				(footprints allowed)
			)
			(placement
				(enabled no)
				(sheetname "")
			)
			(fill
				(thermal_gap 0.5)
				(thermal_bridge_width 0.5)
				(island_removal_mode 0)
			)
			(polygon
				(pts
					(xy 417.576 -86.1695) (xy 418.084 -86.1695) (xy 418.084 -85.7885) (xy 417.576 -85.7885)
				)
			)
		)
		(zone
			(layer "F.Cu")
			(hatch none 0.5)
			(connect_pads
				(clearance 0)
			)
			(min_thickness 0.25)
			(keepout
				(tracks not_allowed)
				(vias allowed)
				(pads allowed)
				(copperpour not_allowed)
				(footprints allowed)
			)
			(placement
				(enabled no)
				(sheetname "")
			)
			(fill
				(thermal_gap 0.5)
				(thermal_bridge_width 0.5)
				(island_removal_mode 0)
			)
			(polygon
				(pts
					(xy 417.576 -85.7885) (xy 418.084 -85.7885) (xy 418.084 -86.1695) (xy 417.576 -86.1695)
				)
			)
		)
	)
	(footprint ""
		(layer "F.Cu")
		(at 40.036496 -65.159382)
		(property "Reference" "L1D3"
			(at 3.378708 -4.251706 0)
			(unlocked yes)
			(layer "F.SilkS")
			(effects
				(font
					(size 0.4064 0.254)
					(thickness 0.1524)
				)
			)
		)
		(property "Value" ""
			(at 0 0 0)
			(layer "F.Fab")
			(effects
				(font
					(size 1.27 1.27)
				)
			)
		)
		(duplicate_pad_numbers_are_jumpers no)
		(fp_line
			(start -1.1303 -3.199892)
			(end 8.3693 -3.199892)
			(stroke
				(width 0.1524)
				(type default)
			)
			(layer "F.SilkS")
		)
		(fp_line
			(start -1.1303 -1.6637)
			(end -1.1303 -3.199892)
			(stroke
				(width 0.1524)
				(type default)
			)
			(layer "F.SilkS")
		)
		(fp_line
			(start -1.1303 3.199892)
			(end -1.1303 1.6637)
			(stroke
				(width 0.1524)
				(type default)
			)
			(layer "F.SilkS")
		)
		(fp_line
			(start 8.3693 -3.199892)
			(end 8.3693 -1.6637)
			(stroke
				(width 0.1524)
				(type default)
			)
			(layer "F.SilkS")
		)
		(fp_line
			(start 8.3693 1.6637)
			(end 8.3693 3.199892)
			(stroke
				(width 0.1524)
				(type default)
			)
			(layer "F.SilkS")
		)
		(fp_line
			(start 8.3693 3.199892)
			(end -1.1303 3.199892)
			(stroke
				(width 0.1524)
				(type default)
			)
			(layer "F.SilkS")
		)
		(fp_rect
			(start -1.1303 3.199892)
			(end 8.3693 -3.199892)
			(stroke
				(width 0)
				(type default)
			)
			(fill no)
			(layer "F.CrtYd")
		)
		(fp_line
			(start -1.1303 -3.199892)
			(end 8.3693 -3.199892)
			(stroke
				(width 0.1)
				(type default)
			)
			(layer "F.Fab")
		)
		(fp_line
			(start -1.1303 3.199892)
			(end -1.1303 -3.199892)
			(stroke
				(width 0.1)
				(type default)
			)
			(layer "F.Fab")
		)
		(fp_line
			(start 8.3693 -3.199892)
			(end 8.3693 3.199892)
			(stroke
				(width 0.1)
				(type default)
			)
			(layer "F.Fab")
		)
		(fp_line
			(start 8.3693 3.199892)
			(end -1.1303 3.199892)
			(stroke
				(width 0.1)
				(type default)
			)
			(layer "F.Fab")
		)
		(pad "1" smd rect
			(at 0 0)
			(size 3.683 2.667)
			(layers "F.Cu" "F.Mask" "F.Paste")
			(net "VR_PVCCIN_CPU1_PHASE2")
		)
		(pad "2" smd rect
			(at 7.239 0)
			(size 3.683 2.667)
			(layers "F.Cu" "F.Mask" "F.Paste")
			(net "PVCCIN_CPU1")
		)
	)
	(footprint ""
		(layer "F.Cu")
		(at 455.422 -38.735)
		(property "Reference" "R9E21"
			(at 0 0 0)
			(layer "F.SilkS")
			(hide yes)
			(effects
				(font
					(size 1.27 1.27)
				)
			)
		)
		(property "Value" ""
			(at 0 0 0)
			(layer "F.Fab")
			(effects
				(font
					(size 1.27 1.27)
				)
			)
		)
		(duplicate_pad_numbers_are_jumpers no)
		(fp_poly
			(pts
				(xy -0.2794 -0.1016) (xy 0.2794 -0.1016) (xy 0.2794 0.9906) (xy -0.2794 0.9906)
			)
			(stroke
				(width 0)
				(type default)
			)
			(fill no)
			(layer "F.CrtYd")
		)
		(fp_line
			(start -0.2794 -0.1016)
			(end -0.2794 0.9906)
			(stroke
				(width 0.1)
				(type default)
			)
			(layer "F.Fab")
		)
		(fp_line
			(start -0.2794 0.9906)
			(end 0.2794 0.9906)
			(stroke
				(width 0.1)
				(type default)
			)
			(layer "F.Fab")
		)
		(fp_line
			(start 0.2794 -0.1016)
			(end -0.2794 -0.1016)
			(stroke
				(width 0.1)
				(type default)
			)
			(layer "F.Fab")
		)
		(fp_line
			(start 0.2794 0.9906)
			(end 0.2794 -0.1016)
			(stroke
				(width 0.1)
				(type default)
			)
			(layer "F.Fab")
		)
		(pad "1" smd rect
			(at 0 0)
			(size 0.508 0.508)
			(layers "F.Cu" "F.Mask" "F.Paste")
			(net "P3V3_STBY")
		)
		(pad "2" smd rect
			(at 0 0.889)
			(size 0.508 0.508)
			(layers "F.Cu" "F.Mask" "F.Paste")
			(net "FM_HEARTBEAT_LED")
		)
		(zone
			(layer "F.Cu")
			(hatch none 0.5)
			(connect_pads
				(clearance 0)
			)
			(min_thickness 0.25)
			(keepout
				(tracks allowed)
				(vias not_allowed)
				(pads allowed)
				(copperpour not_allowed)
				(footprints allowed)
			)
			(placement
				(enabled no)
				(sheetname "")
			)
			(fill
				(thermal_gap 0.5)
				(thermal_bridge_width 0.5)
				(island_removal_mode 0)
			)
			(polygon
				(pts
					(xy 455.168 -38.481) (xy 455.676 -38.481) (xy 455.676 -38.1) (xy 455.168 -38.1)
				)
			)
		)
		(zone
			(layer "F.Cu")
			(hatch none 0.5)
			(connect_pads
				(clearance 0)
			)
			(min_thickness 0.25)
			(keepout
				(tracks not_allowed)
				(vias allowed)
				(pads allowed)
				(copperpour not_allowed)
				(footprints allowed)
			)
			(placement
				(enabled no)
				(sheetname "")
			)
			(fill
				(thermal_gap 0.5)
				(thermal_bridge_width 0.5)
				(island_removal_mode 0)
			)
			(polygon
				(pts
					(xy 455.168 -38.1) (xy 455.676 -38.1) (xy 455.676 -38.481) (xy 455.168 -38.481)
				)
			)
		)
	)
	(footprint ""
		(layer "F.Cu")
		(at 404.43658 -141.783816 -90)
		(property "Reference" "C8A14"
			(at 0 0 270)
			(layer "F.SilkS")
			(hide yes)
			(effects
				(font
					(size 1.27 1.27)
				)
			)
		)
		(property "Value" ""
			(at 0 0 270)
			(layer "F.Fab")
			(effects
				(font
					(size 1.27 1.27)
				)
			)
		)
		(duplicate_pad_numbers_are_jumpers no)
		(fp_poly
			(pts
				(xy -0.7239 -0.2159) (xy 0.7239 -0.2159) (xy 0.7239 1.9939) (xy -0.7239 1.9939)
			)
			(stroke
				(width 0)
				(type default)
			)
			(fill no)
			(layer "F.CrtYd")
		)
		(fp_line
			(start -0.7239 1.9939)
			(end 0.7239 1.9939)
			(stroke
				(width 0.1)
				(type default)
			)
			(layer "F.Fab")
		)
		(fp_line
			(start 0.7239 1.9939)
			(end 0.7239 -0.2159)
			(stroke
				(width 0.1)
				(type default)
			)
			(layer "F.Fab")
		)
		(fp_line
			(start -0.7239 -0.2159)
			(end -0.7239 1.9939)
			(stroke
				(width 0.1)
				(type default)
			)
			(layer "F.Fab")
		)
		(fp_line
			(start 0.7239 -0.2159)
			(end -0.7239 -0.2159)
			(stroke
				(width 0.1)
				(type default)
			)
			(layer "F.Fab")
		)
		(pad "1" smd rect
			(at 0 0 270)
			(size 1.27 1.016)
			(layers "F.Cu" "F.Mask" "F.Paste")
			(net "P1V8_PCH_STBY")
		)
		(pad "2" smd rect
			(at 0 1.778 270)
			(size 1.27 1.016)
			(layers "F.Cu" "F.Mask" "F.Paste")
			(net "GND")
		)
		(zone
			(layer "F.Cu")
			(hatch none 0.5)
			(connect_pads
				(clearance 0)
			)
			(min_thickness 0.25)
			(keepout
				(tracks not_allowed)
				(vias allowed)
				(pads allowed)
				(copperpour not_allowed)
				(footprints allowed)
			)
			(placement
				(enabled no)
				(sheetname "")
			)
			(fill
				(thermal_gap 0.5)
				(thermal_bridge_width 0.5)
				(island_removal_mode 0)
			)
			(polygon
				(pts
					(xy 403.92858 -142.418816) (xy 403.92858 -141.148816) (xy 403.16658 -141.148816) (xy 403.16658 -142.418816)
				)
			)
		)
	)
	(footprint ""
		(layer "F.Cu")
		(at 369.333526 -104.309164 90)
		(property "Reference" "R7C4"
			(at 0 0 90)
			(layer "F.SilkS")
			(hide yes)
			(effects
				(font
					(size 1.27 1.27)
				)
			)
		)
		(property "Value" ""
			(at 0 0 90)
			(layer "F.Fab")
			(effects
				(font
					(size 1.27 1.27)
				)
			)
		)
		(duplicate_pad_numbers_are_jumpers no)
		(fp_poly
			(pts
				(xy -0.2794 -0.1016) (xy 0.2794 -0.1016) (xy 0.2794 0.9906) (xy -0.2794 0.9906)
			)
			(stroke
				(width 0)
				(type default)
			)
			(fill no)
			(layer "F.CrtYd")
		)
		(fp_line
			(start 0.2794 -0.1016)
			(end -0.2794 -0.1016)
			(stroke
				(width 0.1)
				(type default)
			)
			(layer "F.Fab")
		)
		(fp_line
			(start -0.2794 -0.1016)
			(end -0.2794 0.9906)
			(stroke
				(width 0.1)
				(type default)
			)
			(layer "F.Fab")
		)
		(fp_line
			(start 0.2794 0.9906)
			(end 0.2794 -0.1016)
			(stroke
				(width 0.1)
				(type default)
			)
			(layer "F.Fab")
		)
		(fp_line
			(start -0.2794 0.9906)
			(end 0.2794 0.9906)
			(stroke
				(width 0.1)
				(type default)
			)
			(layer "F.Fab")
		)
		(pad "1" smd rect
			(at 0 0 90)
			(size 0.508 0.508)
			(layers "F.Cu" "F.Mask" "F.Paste")
			(net "CLK_100M_BMC_PE_R_DP")
		)
		(pad "2" smd rect
			(at 0 0.889 90)
			(size 0.508 0.508)
			(layers "F.Cu" "F.Mask" "F.Paste")
			(net "CLK_100M_BMC_PE_DP")
		)
		(zone
			(layer "F.Cu")
			(hatch none 0.5)
			(connect_pads
				(clearance 0)
			)
			(min_thickness 0.25)
			(keepout
				(tracks allowed)
				(vias not_allowed)
				(pads allowed)
				(copperpour not_allowed)
				(footprints allowed)
			)
			(placement
				(enabled no)
				(sheetname "")
			)
			(fill
				(thermal_gap 0.5)
				(thermal_bridge_width 0.5)
				(island_removal_mode 0)
			)
			(polygon
				(pts
					(xy 369.587526 -104.055164) (xy 369.587526 -104.563164) (xy 369.968526 -104.563164) (xy 369.968526 -104.055164)
				)
			)
		)
		(zone
			(layer "F.Cu")
			(hatch none 0.5)
			(connect_pads
				(clearance 0)
			)
			(min_thickness 0.25)
			(keepout
				(tracks not_allowed)
				(vias allowed)
				(pads allowed)
				(copperpour not_allowed)
				(footprints allowed)
			)
			(placement
				(enabled no)
				(sheetname "")
			)
			(fill
				(thermal_gap 0.5)
				(thermal_bridge_width 0.5)
				(island_removal_mode 0)
			)
			(polygon
				(pts
					(xy 369.968526 -104.055164) (xy 369.968526 -104.563164) (xy 369.587526 -104.563164) (xy 369.587526 -104.055164)
				)
			)
		)
	)
	(footprint ""
		(layer "F.Cu")
		(at 183.795416 -59.238896 180)
		(property "Reference" "C4E14"
			(at 0 0 180)
			(layer "F.SilkS")
			(hide yes)
			(effects
				(font
					(size 1.27 1.27)
				)
			)
		)
		(property "Value" "*"
			(at -0.0762 -6.2357 180)
			(unlocked yes)
			(layer "F.Fab")
			(hide yes)
			(effects
				(font
					(size 1.27 1.016)
					(thickness 0.1524)
				)
			)
		)
		(property "Device Type" "SC22U16V5MX-4-GP_SMD-BCG5-SC22A"
			(at -0.0762 -8.2677 180)
			(unlocked yes)
			(layer "F.Fab")
			(hide yes)
			(effects
				(font
					(size 1.27 1.016)
					(thickness 0.1524)
				)
			)
		)
		(duplicate_pad_numbers_are_jumpers no)
		(fp_line
			(start 0.635 0)
			(end -0.635 0)
			(stroke
				(width 0.508)
				(type default)
			)
			(layer "F.SilkS")
		)
		(fp_rect
			(start -0.9652 1.778)
			(end 0.9652 -1.778)
			(stroke
				(width 0)
				(type default)
			)
			(fill no)
			(layer "F.CrtYd")
		)
		(fp_poly
			(pts
				(xy -0.9652 -1.778) (xy 0.9652 -1.778) (xy 0.9652 1.778) (xy -0.9652 1.778)
			)
			(stroke
				(width 0)
				(type default)
			)
			(fill no)
			(layer "F.Fab")
		)
		(pad "1" smd rect
			(at 0 -0.9652 180)
			(size 1.397 1.143)
			(layers "F.Cu" "F.Mask" "F.Paste")
			(net "VR_FET_SW_P12V_STBY_PVCCIN_CPU0")
		)
		(pad "2" smd rect
			(at 0 0.9652 180)
			(size 1.397 1.143)
			(layers "F.Cu" "F.Mask" "F.Paste")
			(net "GND")
		)
	)
	(footprint ""
		(layer "F.Cu")
		(at 29.036518 -72.03313 -90)
		(property "Reference" "R1D55"
			(at 0 0 270)
			(layer "F.SilkS")
			(hide yes)
			(effects
				(font
					(size 1.27 1.27)
				)
			)
		)
		(property "Value" ""
			(at 0 0 270)
			(layer "F.Fab")
			(effects
				(font
					(size 1.27 1.27)
				)
			)
		)
		(duplicate_pad_numbers_are_jumpers no)
		(fp_poly
			(pts
				(xy -0.2794 -0.1016) (xy 0.2794 -0.1016) (xy 0.2794 0.9906) (xy -0.2794 0.9906)
			)
			(stroke
				(width 0)
				(type default)
			)
			(fill no)
			(layer "F.CrtYd")
		)
		(fp_line
			(start -0.2794 0.9906)
			(end 0.2794 0.9906)
			(stroke
				(width 0.1)
				(type default)
			)
			(layer "F.Fab")
		)
		(fp_line
			(start 0.2794 0.9906)
			(end 0.2794 -0.1016)
			(stroke
				(width 0.1)
				(type default)
			)
			(layer "F.Fab")
		)
		(fp_line
			(start -0.2794 -0.1016)
			(end -0.2794 0.9906)
			(stroke
				(width 0.1)
				(type default)
			)
			(layer "F.Fab")
		)
		(fp_line
			(start 0.2794 -0.1016)
			(end -0.2794 -0.1016)
			(stroke
				(width 0.1)
				(type default)
			)
			(layer "F.Fab")
		)
		(pad "1" smd rect
			(at 0 0 270)
			(size 0.508 0.508)
			(layers "F.Cu" "F.Mask" "F.Paste")
			(net "VR_PVCCIN_CPU1_PH3_OCSET")
		)
		(pad "2" smd rect
			(at 0 0.889 270)
			(size 0.508 0.508)
			(layers "F.Cu" "F.Mask" "F.Paste")
			(net "GND")
		)
		(zone
			(layer "F.Cu")
			(hatch none 0.5)
			(connect_pads
				(clearance 0)
			)
			(min_thickness 0.25)
			(keepout
				(tracks not_allowed)
				(vias allowed)
				(pads allowed)
				(copperpour not_allowed)
				(footprints allowed)
			)
			(placement
				(enabled no)
				(sheetname "")
			)
			(fill
				(thermal_gap 0.5)
				(thermal_bridge_width 0.5)
				(island_removal_mode 0)
			)
			(polygon
				(pts
					(xy 28.401518 -72.28713) (xy 28.401518 -71.77913) (xy 28.782518 -71.77913) (xy 28.782518 -72.28713)
				)
			)
		)
		(zone
			(layer "F.Cu")
			(hatch none 0.5)
			(connect_pads
				(clearance 0)
			)
			(min_thickness 0.25)
			(keepout
				(tracks allowed)
				(vias not_allowed)
				(pads allowed)
				(copperpour not_allowed)
				(footprints allowed)
			)
			(placement
				(enabled no)
				(sheetname "")
			)
			(fill
				(thermal_gap 0.5)
				(thermal_bridge_width 0.5)
				(island_removal_mode 0)
			)
			(polygon
				(pts
					(xy 28.782518 -72.28713) (xy 28.782518 -71.77913) (xy 28.401518 -71.77913) (xy 28.401518 -72.28713)
				)
			)
		)
	)
	(footprint ""
		(layer "F.Cu")
		(at 451.3326 -22.4282)
		(property "Reference" "R9W31"
			(at 0 0 0)
			(layer "F.SilkS")
			(hide yes)
			(effects
				(font
					(size 1.27 1.27)
				)
			)
		)
		(property "Value" "*"
			(at 0.064008 -4.108196 0)
			(unlocked yes)
			(layer "F.Fab")
			(hide yes)
			(effects
				(font
					(size 1.27 1.016)
					(thickness 0.1524)
				)
			)
		)
		(property "Device Type" "21K5R2F-GP_RCL_GP-21K5R2F-GP,6A"
			(at 0.064008 -5.632196 0)
			(unlocked yes)
			(layer "F.Fab")
			(hide yes)
			(effects
				(font
					(size 1.27 1.016)
					(thickness 0.1524)
				)
			)
		)
		(duplicate_pad_numbers_are_jumpers no)
		(fp_line
			(start -0.508 -0.9398)
			(end -0.508 0.9398)
			(stroke
				(width 0.1524)
				(type default)
			)
			(layer "F.SilkS")
		)
		(fp_line
			(start 0.508 -0.9398)
			(end -0.508 -0.9398)
			(stroke
				(width 0.1524)
				(type default)
			)
			(layer "F.SilkS")
		)
		(fp_rect
			(start -0.508 0.9398)
			(end 0.508 -0.9398)
			(stroke
				(width 0)
				(type default)
			)
			(fill no)
			(layer "F.CrtYd")
		)
		(fp_rect
			(start -0.508 0.9398)
			(end 0.508 -0.9398)
			(stroke
				(width 0)
				(type default)
			)
			(fill no)
			(layer "F.Fab")
		)
		(pad "1" smd custom
			(at 0 -0.4445)
			(size 0.1397 0.1397)
			(layers "F.Cu" "F.Mask" "F.Paste")
			(net "P2V5_AUX_BMC")
			(options
				(clearance outline)
				(anchor circle)
			)
			(primitives
				(gr_poly
					(pts
						(arc
							(start -0.1778 -0.2794)
							(mid -0.249642 -0.249642)
							(end -0.2794 -0.1778)
						)
						(arc
							(start -0.2794 0.1778)
							(mid -0.249642 0.249642)
							(end -0.1778 0.2794)
						)
						(arc
							(start 0.1778 0.2794)
							(mid 0.249642 0.249642)
							(end 0.2794 0.1778)
						)
						(arc
							(start 0.2794 -0.1778)
							(mid 0.249642 -0.249642)
							(end 0.1778 -0.2794)
						)
					)
					(width 0)
					(fill yes)
				)
			)
		)
		(pad "2" smd custom
			(at 0 0.4445)
			(size 0.1397 0.1397)
			(layers "F.Cu" "F.Mask" "F.Paste")
			(net "VR_P2V5_BMC_STBY_FB")
			(options
				(clearance outline)
				(anchor circle)
			)
			(primitives
				(gr_poly
					(pts
						(arc
							(start -0.1778 -0.2794)
							(mid -0.249642 -0.249642)
							(end -0.2794 -0.1778)
						)
						(arc
							(start -0.2794 0.1778)
							(mid -0.249642 0.249642)
							(end -0.1778 0.2794)
						)
						(arc
							(start 0.1778 0.2794)
							(mid 0.249642 0.249642)
							(end 0.2794 0.1778)
						)
						(arc
							(start 0.2794 -0.1778)
							(mid 0.249642 -0.249642)
							(end 0.1778 -0.2794)
						)
					)
					(width 0)
					(fill yes)
				)
			)
		)
	)
	(footprint ""
		(layer "F.Cu")
		(at 363.165644 -10.916158)
		(property "Reference" "C7G6"
			(at 0 0 0)
			(layer "F.SilkS")
			(hide yes)
			(effects
				(font
					(size 1.27 1.27)
				)
			)
		)
		(property "Value" ""
			(at 0 0 0)
			(layer "F.Fab")
			(effects
				(font
					(size 1.27 1.27)
				)
			)
		)
		(duplicate_pad_numbers_are_jumpers no)
		(fp_rect
			(start -0.3048 0.9906)
			(end 0.3048 -0.1016)
			(stroke
				(width 0)
				(type default)
			)
			(fill no)
			(layer "F.CrtYd")
		)
		(fp_line
			(start -0.3048 -0.1016)
			(end -0.3048 0.9906)
			(stroke
				(width 0.1)
				(type default)
			)
			(layer "F.Fab")
		)
		(fp_line
			(start -0.3048 0.9906)
			(end 0.3048 0.9906)
			(stroke
				(width 0.1)
				(type default)
			)
			(layer "F.Fab")
		)
		(fp_line
			(start 0.3048 -0.1016)
			(end -0.3048 -0.1016)
			(stroke
				(width 0.1)
				(type default)
			)
			(layer "F.Fab")
		)
		(fp_line
			(start 0.3048 0.9906)
			(end 0.3048 -0.1016)
			(stroke
				(width 0.1)
				(type default)
			)
			(layer "F.Fab")
		)
		(pad "1" smd rect
			(at 0 0)
			(size 0.508 0.508)
			(layers "F.Cu" "F.Mask" "F.Paste")
			(net "P3E_CPU0_PE2_SS_TXN<15>")
		)
		(pad "2" smd rect
			(at 0 0.889)
			(size 0.508 0.508)
			(layers "F.Cu" "F.Mask" "F.Paste")
			(net "P3E_CPU0_PE2_SS_C_TXN<15>")
		)
		(zone
			(layer "F.Cu")
			(hatch none 0.5)
			(connect_pads
				(clearance 0)
			)
			(min_thickness 0.25)
			(keepout
				(tracks not_allowed)
				(vias allowed)
				(pads allowed)
				(copperpour not_allowed)
				(footprints allowed)
			)
			(placement
				(enabled no)
				(sheetname "")
			)
			(fill
				(thermal_gap 0.5)
				(thermal_bridge_width 0.5)
				(island_removal_mode 0)
			)
			(polygon
				(pts
					(xy 362.911644 -10.281158) (xy 363.419644 -10.281158) (xy 363.419644 -10.662158) (xy 362.911644 -10.662158)
				)
			)
		)
		(zone
			(layer "F.Cu")
			(hatch none 0.5)
			(connect_pads
				(clearance 0)
			)
			(min_thickness 0.25)
			(keepout
				(tracks allowed)
				(vias not_allowed)
				(pads allowed)
				(copperpour not_allowed)
				(footprints allowed)
			)
			(placement
				(enabled no)
				(sheetname "")
			)
			(fill
				(thermal_gap 0.5)
				(thermal_bridge_width 0.5)
				(island_removal_mode 0)
			)
			(polygon
				(pts
					(xy 362.911644 -10.281158) (xy 363.419644 -10.281158) (xy 363.419644 -10.662158) (xy 362.911644 -10.662158)
				)
			)
		)
	)
	(footprint ""
		(layer "F.Cu")
		(at 407.8605 -114.554 90)
		(property "Reference" "R2M7"
			(at 0 0 90)
			(layer "F.SilkS")
			(hide yes)
			(effects
				(font
					(size 1.27 1.27)
				)
			)
		)
		(property "Value" ""
			(at 0 0 90)
			(layer "F.Fab")
			(effects
				(font
					(size 1.27 1.27)
				)
			)
		)
		(duplicate_pad_numbers_are_jumpers no)
		(fp_poly
			(pts
				(xy -0.2794 -0.1016) (xy 0.2794 -0.1016) (xy 0.2794 0.9906) (xy -0.2794 0.9906)
			)
			(stroke
				(width 0)
				(type default)
			)
			(fill no)
			(layer "F.CrtYd")
		)
		(fp_line
			(start 0.2794 -0.1016)
			(end -0.2794 -0.1016)
			(stroke
				(width 0.1)
				(type default)
			)
			(layer "F.Fab")
		)
		(fp_line
			(start -0.2794 -0.1016)
			(end -0.2794 0.9906)
			(stroke
				(width 0.1)
				(type default)
			)
			(layer "F.Fab")
		)
		(fp_line
			(start 0.2794 0.9906)
			(end 0.2794 -0.1016)
			(stroke
				(width 0.1)
				(type default)
			)
			(layer "F.Fab")
		)
		(fp_line
			(start -0.2794 0.9906)
			(end 0.2794 0.9906)
			(stroke
				(width 0.1)
				(type default)
			)
			(layer "F.Fab")
		)
		(pad "1" smd rect
			(at 0 0 90)
			(size 0.508 0.508)
			(layers "F.Cu" "F.Mask" "F.Paste")
			(net "FM_ADR_MODE_SEL_R")
		)
		(pad "2" smd rect
			(at 0 0.889 90)
			(size 0.508 0.508)
			(layers "F.Cu" "F.Mask" "F.Paste")
			(net "FM_ADR_MODE_SEL")
		)
		(zone
			(layer "F.Cu")
			(hatch none 0.5)
			(connect_pads
				(clearance 0)
			)
			(min_thickness 0.25)
			(keepout
				(tracks allowed)
				(vias not_allowed)
				(pads allowed)
				(copperpour not_allowed)
				(footprints allowed)
			)
			(placement
				(enabled no)
				(sheetname "")
			)
			(fill
				(thermal_gap 0.5)
				(thermal_bridge_width 0.5)
				(island_removal_mode 0)
			)
			(polygon
				(pts
					(xy 408.1145 -114.3) (xy 408.1145 -114.808) (xy 408.4955 -114.808) (xy 408.4955 -114.3)
				)
			)
		)
		(zone
			(layer "F.Cu")
			(hatch none 0.5)
			(connect_pads
				(clearance 0)
			)
			(min_thickness 0.25)
			(keepout
				(tracks not_allowed)
				(vias allowed)
				(pads allowed)
				(copperpour not_allowed)
				(footprints allowed)
			)
			(placement
				(enabled no)
				(sheetname "")
			)
			(fill
				(thermal_gap 0.5)
				(thermal_bridge_width 0.5)
				(island_removal_mode 0)
			)
			(polygon
				(pts
					(xy 408.4955 -114.3) (xy 408.4955 -114.808) (xy 408.1145 -114.808) (xy 408.1145 -114.3)
				)
			)
		)
	)
	(footprint ""
		(layer "F.Cu")
		(at 111.5314 -83.8962)
		(property "Reference" "R3D3"
			(at 0 0 0)
			(layer "F.SilkS")
			(hide yes)
			(effects
				(font
					(size 1.27 1.27)
				)
			)
		)
		(property "Value" ""
			(at 0 0 0)
			(layer "F.Fab")
			(effects
				(font
					(size 1.27 1.27)
				)
			)
		)
		(duplicate_pad_numbers_are_jumpers no)
		(fp_poly
			(pts
				(xy -0.2794 -0.1016) (xy 0.2794 -0.1016) (xy 0.2794 0.9906) (xy -0.2794 0.9906)
			)
			(stroke
				(width 0)
				(type default)
			)
			(fill no)
			(layer "F.CrtYd")
		)
		(fp_line
			(start -0.2794 -0.1016)
			(end -0.2794 0.9906)
			(stroke
				(width 0.1)
				(type default)
			)
			(layer "F.Fab")
		)
		(fp_line
			(start -0.2794 0.9906)
			(end 0.2794 0.9906)
			(stroke
				(width 0.1)
				(type default)
			)
			(layer "F.Fab")
		)
		(fp_line
			(start 0.2794 -0.1016)
			(end -0.2794 -0.1016)
			(stroke
				(width 0.1)
				(type default)
			)
			(layer "F.Fab")
		)
		(fp_line
			(start 0.2794 0.9906)
			(end 0.2794 -0.1016)
			(stroke
				(width 0.1)
				(type default)
			)
			(layer "F.Fab")
		)
		(pad "1" smd rect
			(at 0 0)
			(size 0.508 0.508)
			(layers "F.Cu" "F.Mask" "F.Paste")
			(net "A_CPU1_KLM_RCOMP2")
		)
		(pad "2" smd rect
			(at 0 0.889)
			(size 0.508 0.508)
			(layers "F.Cu" "F.Mask" "F.Paste")
			(net "GND")
		)
		(zone
			(layer "F.Cu")
			(hatch none 0.5)
			(connect_pads
				(clearance 0)
			)
			(min_thickness 0.25)
			(keepout
				(tracks allowed)
				(vias not_allowed)
				(pads allowed)
				(copperpour not_allowed)
				(footprints allowed)
			)
			(placement
				(enabled no)
				(sheetname "")
			)
			(fill
				(thermal_gap 0.5)
				(thermal_bridge_width 0.5)
				(island_removal_mode 0)
			)
			(polygon
				(pts
					(xy 111.2774 -83.6422) (xy 111.7854 -83.6422) (xy 111.7854 -83.2612) (xy 111.2774 -83.2612)
				)
			)
		)
		(zone
			(layer "F.Cu")
			(hatch none 0.5)
			(connect_pads
				(clearance 0)
			)
			(min_thickness 0.25)
			(keepout
				(tracks not_allowed)
				(vias allowed)
				(pads allowed)
				(copperpour not_allowed)
				(footprints allowed)
			)
			(placement
				(enabled no)
				(sheetname "")
			)
			(fill
				(thermal_gap 0.5)
				(thermal_bridge_width 0.5)
				(island_removal_mode 0)
			)
			(polygon
				(pts
					(xy 111.2774 -83.2612) (xy 111.7854 -83.2612) (xy 111.7854 -83.6422) (xy 111.2774 -83.6422)
				)
			)
		)
	)
	(footprint ""
		(layer "F.Cu")
		(at 420.624 -109.07014)
		(property "Reference" "U1W2"
			(at 0 0 0)
			(layer "F.SilkS")
			(hide yes)
			(effects
				(font
					(size 1.27 1.27)
				)
			)
		)
		(property "Value" "*"
			(at -0.1143 -9.3091 0)
			(unlocked yes)
			(layer "F.Fab")
			(hide yes)
			(effects
				(font
					(size 1.27 1.016)
					(thickness 0.1524)
				)
			)
		)
		(property "Device Type" "TCA9517DGKR-GP_DISCRET-G8-TCA9A"
			(at -0.1143 -10.9093 0)
			(unlocked yes)
			(layer "F.Fab")
			(hide yes)
			(effects
				(font
					(size 1.27 1.016)
					(thickness 0.1524)
				)
			)
		)
		(duplicate_pad_numbers_are_jumpers no)
		(fp_line
			(start -1.9558 -1.016)
			(end -1.9558 1.016)
			(stroke
				(width 0.1524)
				(type default)
			)
			(layer "F.SilkS")
		)
		(fp_line
			(start -1.9558 -0.5461)
			(end -1.4478 -0.0381)
			(stroke
				(width 0.1524)
				(type default)
			)
			(layer "F.SilkS")
		)
		(fp_line
			(start -1.9558 1.016)
			(end 1.0795 1.016)
			(stroke
				(width 0.1524)
				(type default)
			)
			(layer "F.SilkS")
		)
		(fp_line
			(start -1.778 1.0922)
			(end -1.778 3.048)
			(stroke
				(width 0.508)
				(type default)
			)
			(layer "F.SilkS")
		)
		(fp_line
			(start -1.4478 -0.0381)
			(end -1.9558 0.4699)
			(stroke
				(width 0.1524)
				(type default)
			)
			(layer "F.SilkS")
		)
		(fp_line
			(start 1.0795 -1.016)
			(end -1.9558 -1.016)
			(stroke
				(width 0.1524)
				(type default)
			)
			(layer "F.SilkS")
		)
		(fp_line
			(start 1.0795 1.016)
			(end 1.0795 -1.016)
			(stroke
				(width 0.1524)
				(type default)
			)
			(layer "F.SilkS")
		)
		(fp_poly
			(pts
				(xy -1.1557 -1.016) (xy -1.1557 1.016) (xy 1.1557 1.016) (xy 1.1557 -1.016)
			)
			(stroke
				(width 0)
				(type default)
			)
			(fill yes)
			(layer "F.SilkS")
		)
		(fp_rect
			(start -1.4986 2.4511)
			(end 1.4986 -2.4511)
			(stroke
				(width 0)
				(type default)
			)
			(fill no)
			(layer "F.CrtYd")
		)
		(fp_poly
			(pts
				(xy -2.032 3.302) (xy -2.032 -3.302) (xy 2.032 -3.302) (xy 2.032 -2.1209) (xy 1.4986 -2.1209) (xy 1.4986 -2.4511)
				(xy -1.4986 -2.4511) (xy -1.4986 2.4511) (xy 1.4986 2.4511) (xy 1.4986 -2.1082) (xy 2.032 -2.1082)
				(xy 2.032 3.302)
			)
			(stroke
				(width 0)
				(type default)
			)
			(fill no)
			(layer "F.CrtYd")
		)
		(fp_rect
			(start -2.032 3.302)
			(end 2.032 -3.302)
			(stroke
				(width 0)
				(type default)
			)
			(fill no)
			(layer "F.Fab")
		)
		(pad "1" smd rect
			(at -0.97536 2.05486)
			(size 0.3556 1.524)
			(layers "F.Cu" "F.Mask" "F.Paste")
			(net "PVCCIO_CPU0")
		)
		(pad "2" smd rect
			(at -0.32512 2.05486)
			(size 0.3556 1.524)
			(layers "F.Cu" "F.Mask" "F.Paste")
			(net "SMB_CPU0_PE_HP_GTL_R_SCL")
		)
		(pad "3" smd rect
			(at 0.32512 2.05486)
			(size 0.3556 1.524)
			(layers "F.Cu" "F.Mask" "F.Paste")
			(net "SMB_CPU0_PE_HP_GTL_R_SDA")
		)
		(pad "4" smd rect
			(at 0.97536 2.05486)
			(size 0.3556 1.524)
			(layers "F.Cu" "F.Mask" "F.Paste")
			(net "GND")
		)
		(pad "5" smd rect
			(at 0.97536 -2.05486)
			(size 0.3556 1.524)
			(layers "F.Cu" "F.Mask" "F.Paste")
			(net "TP_SMB_PEHPCPU0_EN")
		)
		(pad "6" smd rect
			(at 0.32512 -2.05486)
			(size 0.3556 1.524)
			(layers "F.Cu" "F.Mask" "F.Paste")
			(net "SMB_PEHPCPU0_STBY_LVC3_R_SDA")
		)
		(pad "7" smd rect
			(at -0.32512 -2.05486)
			(size 0.3556 1.524)
			(layers "F.Cu" "F.Mask" "F.Paste")
			(net "SMB_PEHPCPU0_STBY_LVC3_R_SCL")
		)
		(pad "8" smd rect
			(at -0.97536 -2.05486)
			(size 0.3556 1.524)
			(layers "F.Cu" "F.Mask" "F.Paste")
			(net "P3V3_STBY")
		)
	)
	(footprint ""
		(layer "F.Cu")
		(at 274.43303 -84.796122)
		(property "Reference" "C5D5"
			(at 0 0 0)
			(layer "F.SilkS")
			(hide yes)
			(effects
				(font
					(size 1.27 1.27)
				)
			)
		)
		(property "Value" ""
			(at 0 0 0)
			(layer "F.Fab")
			(effects
				(font
					(size 1.27 1.27)
				)
			)
		)
		(duplicate_pad_numbers_are_jumpers no)
		(fp_poly
			(pts
				(xy -0.4953 -0.2032) (xy 0.4953 -0.2032) (xy 0.4953 1.6002) (xy -0.4953 1.6002)
			)
			(stroke
				(width 0)
				(type default)
			)
			(fill no)
			(layer "F.CrtYd")
		)
		(fp_line
			(start -0.4953 -0.2032)
			(end 0.4953 -0.2032)
			(stroke
				(width 0.1)
				(type default)
			)
			(layer "F.Fab")
		)
		(fp_line
			(start -0.4953 1.6002)
			(end -0.4953 -0.2032)
			(stroke
				(width 0.1)
				(type default)
			)
			(layer "F.Fab")
		)
		(fp_line
			(start 0.4953 -0.2032)
			(end 0.4953 1.6002)
			(stroke
				(width 0.1)
				(type default)
			)
			(layer "F.Fab")
		)
		(fp_line
			(start 0.4953 1.6002)
			(end -0.4953 1.6002)
			(stroke
				(width 0.1)
				(type default)
			)
			(layer "F.Fab")
		)
		(pad "1" smd rect
			(at 0 0)
			(size 0.762 0.889)
			(layers "F.Cu" "F.Mask" "F.Paste")
			(net "PVCCIN_CPU0")
		)
		(pad "2" smd rect
			(at 0 1.397)
			(size 0.762 0.889)
			(layers "F.Cu" "F.Mask" "F.Paste")
			(net "GND")
		)
		(zone
			(layer "F.Cu")
			(hatch none 0.5)
			(connect_pads
				(clearance 0)
			)
			(min_thickness 0.25)
			(keepout
				(tracks not_allowed)
				(vias allowed)
				(pads allowed)
				(copperpour not_allowed)
				(footprints allowed)
			)
			(placement
				(enabled no)
				(sheetname "")
			)
			(fill
				(thermal_gap 0.5)
				(thermal_bridge_width 0.5)
				(island_removal_mode 0)
			)
			(polygon
				(pts
					(xy 274.05203 -84.351622) (xy 274.81403 -84.351622) (xy 274.81403 -83.843622) (xy 274.05203 -83.843622)
				)
			)
		)
	)
	(footprint ""
		(layer "F.Cu")
		(at 170.0276 -131.8768)
		(property "Reference" "R4B3"
			(at 0 0 0)
			(layer "F.SilkS")
			(hide yes)
			(effects
				(font
					(size 1.27 1.27)
				)
			)
		)
		(property "Value" ""
			(at 0 0 0)
			(layer "F.Fab")
			(effects
				(font
					(size 1.27 1.27)
				)
			)
		)
		(duplicate_pad_numbers_are_jumpers no)
		(fp_poly
			(pts
				(xy -0.2794 -0.1016) (xy 0.2794 -0.1016) (xy 0.2794 0.9906) (xy -0.2794 0.9906)
			)
			(stroke
				(width 0)
				(type default)
			)
			(fill no)
			(layer "F.CrtYd")
		)
		(fp_line
			(start -0.2794 -0.1016)
			(end -0.2794 0.9906)
			(stroke
				(width 0.1)
				(type default)
			)
			(layer "F.Fab")
		)
		(fp_line
			(start -0.2794 0.9906)
			(end 0.2794 0.9906)
			(stroke
				(width 0.1)
				(type default)
			)
			(layer "F.Fab")
		)
		(fp_line
			(start 0.2794 -0.1016)
			(end -0.2794 -0.1016)
			(stroke
				(width 0.1)
				(type default)
			)
			(layer "F.Fab")
		)
		(fp_line
			(start 0.2794 0.9906)
			(end 0.2794 -0.1016)
			(stroke
				(width 0.1)
				(type default)
			)
			(layer "F.Fab")
		)
		(pad "1" smd rect
			(at 0 0)
			(size 0.508 0.508)
			(layers "F.Cu" "F.Mask" "F.Paste")
			(net "PVPP_KLM")
		)
		(pad "2" smd rect
			(at 0 0.889)
			(size 0.508 0.508)
			(layers "F.Cu" "F.Mask" "F.Paste")
			(net "VSENSE_PVPP_KLM")
		)
		(zone
			(layer "F.Cu")
			(hatch none 0.5)
			(connect_pads
				(clearance 0)
			)
			(min_thickness 0.25)
			(keepout
				(tracks allowed)
				(vias not_allowed)
				(pads allowed)
				(copperpour not_allowed)
				(footprints allowed)
			)
			(placement
				(enabled no)
				(sheetname "")
			)
			(fill
				(thermal_gap 0.5)
				(thermal_bridge_width 0.5)
				(island_removal_mode 0)
			)
			(polygon
				(pts
					(xy 169.7736 -131.6228) (xy 170.2816 -131.6228) (xy 170.2816 -131.2418) (xy 169.7736 -131.2418)
				)
			)
		)
		(zone
			(layer "F.Cu")
			(hatch none 0.5)
			(connect_pads
				(clearance 0)
			)
			(min_thickness 0.25)
			(keepout
				(tracks not_allowed)
				(vias allowed)
				(pads allowed)
				(copperpour not_allowed)
				(footprints allowed)
			)
			(placement
				(enabled no)
				(sheetname "")
			)
			(fill
				(thermal_gap 0.5)
				(thermal_bridge_width 0.5)
				(island_removal_mode 0)
			)
			(polygon
				(pts
					(xy 169.7736 -131.2418) (xy 170.2816 -131.2418) (xy 170.2816 -131.6228) (xy 169.7736 -131.6228)
				)
			)
		)
	)
	(footprint ""
		(layer "F.Cu")
		(at 275.708872 -73.318116)
		(property "Reference" "C5D50"
			(at 0 0 0)
			(layer "F.SilkS")
			(hide yes)
			(effects
				(font
					(size 1.27 1.27)
				)
			)
		)
		(property "Value" ""
			(at 0 0 0)
			(layer "F.Fab")
			(effects
				(font
					(size 1.27 1.27)
				)
			)
		)
		(duplicate_pad_numbers_are_jumpers no)
		(fp_poly
			(pts
				(xy -0.4953 -0.2032) (xy 0.4953 -0.2032) (xy 0.4953 1.6002) (xy -0.4953 1.6002)
			)
			(stroke
				(width 0)
				(type default)
			)
			(fill no)
			(layer "F.CrtYd")
		)
		(fp_line
			(start -0.4953 -0.2032)
			(end 0.4953 -0.2032)
			(stroke
				(width 0.1)
				(type default)
			)
			(layer "F.Fab")
		)
		(fp_line
			(start -0.4953 1.6002)
			(end -0.4953 -0.2032)
			(stroke
				(width 0.1)
				(type default)
			)
			(layer "F.Fab")
		)
		(fp_line
			(start 0.4953 -0.2032)
			(end 0.4953 1.6002)
			(stroke
				(width 0.1)
				(type default)
			)
			(layer "F.Fab")
		)
		(fp_line
			(start 0.4953 1.6002)
			(end -0.4953 1.6002)
			(stroke
				(width 0.1)
				(type default)
			)
			(layer "F.Fab")
		)
		(pad "1" smd rect
			(at 0 0)
			(size 0.762 0.889)
			(layers "F.Cu" "F.Mask" "F.Paste")
			(net "PVCCMCP_CPU0")
		)
		(pad "2" smd rect
			(at 0 1.397)
			(size 0.762 0.889)
			(layers "F.Cu" "F.Mask" "F.Paste")
			(net "GND")
		)
		(zone
			(layer "F.Cu")
			(hatch none 0.5)
			(connect_pads
				(clearance 0)
			)
			(min_thickness 0.25)
			(keepout
				(tracks not_allowed)
				(vias allowed)
				(pads allowed)
				(copperpour not_allowed)
				(footprints allowed)
			)
			(placement
				(enabled no)
				(sheetname "")
			)
			(fill
				(thermal_gap 0.5)
				(thermal_bridge_width 0.5)
				(island_removal_mode 0)
			)
			(polygon
				(pts
					(xy 275.327872 -72.873616) (xy 276.089872 -72.873616) (xy 276.089872 -72.365616) (xy 275.327872 -72.365616)
				)
			)
		)
	)
	(footprint ""
		(layer "F.Cu")
		(at 167.3098 -6.5024 180)
		(property "Reference" "C4G12"
			(at 0 0 180)
			(layer "F.SilkS")
			(hide yes)
			(effects
				(font
					(size 1.27 1.27)
				)
			)
		)
		(property "Value" ""
			(at 0 0 180)
			(layer "F.Fab")
			(effects
				(font
					(size 1.27 1.27)
				)
			)
		)
		(duplicate_pad_numbers_are_jumpers no)
		(fp_rect
			(start -0.3048 -0.1016)
			(end 0.3048 0.9906)
			(stroke
				(width 0)
				(type default)
			)
			(fill no)
			(layer "F.CrtYd")
		)
		(fp_line
			(start 0.3048 0.9906)
			(end 0.3048 -0.1016)
			(stroke
				(width 0.1)
				(type default)
			)
			(layer "F.Fab")
		)
		(fp_line
			(start 0.3048 -0.1016)
			(end -0.3048 -0.1016)
			(stroke
				(width 0.1)
				(type default)
			)
			(layer "F.Fab")
		)
		(fp_line
			(start -0.3048 0.9906)
			(end 0.3048 0.9906)
			(stroke
				(width 0.1)
				(type default)
			)
			(layer "F.Fab")
		)
		(fp_line
			(start -0.3048 -0.1016)
			(end -0.3048 0.9906)
			(stroke
				(width 0.1)
				(type default)
			)
			(layer "F.Fab")
		)
		(pad "1" smd rect
			(at 0 0 180)
			(size 0.508 0.508)
			(layers "F.Cu" "F.Mask" "F.Paste")
			(net "FM_PVTT_GHJ_EN_R")
		)
		(pad "2" smd rect
			(at 0 0.889 180)
			(size 0.508 0.508)
			(layers "F.Cu" "F.Mask" "F.Paste")
			(net "GND")
		)
		(zone
			(layer "F.Cu")
			(hatch none 0.5)
			(connect_pads
				(clearance 0)
			)
			(min_thickness 0.25)
			(keepout
				(tracks not_allowed)
				(vias allowed)
				(pads allowed)
				(copperpour not_allowed)
				(footprints allowed)
			)
			(placement
				(enabled no)
				(sheetname "")
			)
			(fill
				(thermal_gap 0.5)
				(thermal_bridge_width 0.5)
				(island_removal_mode 0)
			)
			(polygon
				(pts
					(xy 167.5638 -6.7564) (xy 167.5638 -7.1374) (xy 167.0558 -7.1374) (xy 167.0558 -6.7564)
				)
			)
		)
		(zone
			(layer "F.Cu")
			(hatch none 0.5)
			(connect_pads
				(clearance 0)
			)
			(min_thickness 0.25)
			(keepout
				(tracks allowed)
				(vias not_allowed)
				(pads allowed)
				(copperpour not_allowed)
				(footprints allowed)
			)
			(placement
				(enabled no)
				(sheetname "")
			)
			(fill
				(thermal_gap 0.5)
				(thermal_bridge_width 0.5)
				(island_removal_mode 0)
			)
			(polygon
				(pts
					(xy 167.5638 -6.7564) (xy 167.5638 -7.1374) (xy 167.0558 -7.1374) (xy 167.0558 -6.7564)
				)
			)
		)
	)
	(footprint ""
		(layer "F.Cu")
		(at 13.941806 2.692654 90)
		(property "Reference" "C1G22"
			(at 0 0 90)
			(layer "F.SilkS")
			(hide yes)
			(effects
				(font
					(size 1.27 1.27)
				)
			)
		)
		(property "Value" ""
			(at 0 0 90)
			(layer "F.Fab")
			(effects
				(font
					(size 1.27 1.27)
				)
			)
		)
		(duplicate_pad_numbers_are_jumpers no)
		(fp_rect
			(start 0.3048 -0.1016)
			(end -0.3048 0.9906)
			(stroke
				(width 0)
				(type default)
			)
			(fill no)
			(layer "F.CrtYd")
		)
		(fp_line
			(start 0.3048 -0.1016)
			(end -0.3048 -0.1016)
			(stroke
				(width 0.1)
				(type default)
			)
			(layer "F.Fab")
		)
		(fp_line
			(start -0.3048 -0.1016)
			(end -0.3048 0.9906)
			(stroke
				(width 0.1)
				(type default)
			)
			(layer "F.Fab")
		)
		(fp_line
			(start 0.3048 0.9906)
			(end 0.3048 -0.1016)
			(stroke
				(width 0.1)
				(type default)
			)
			(layer "F.Fab")
		)
		(fp_line
			(start -0.3048 0.9906)
			(end 0.3048 0.9906)
			(stroke
				(width 0.1)
				(type default)
			)
			(layer "F.Fab")
		)
		(pad "1" smd rect
			(at 0 0 90)
			(size 0.508 0.508)
			(layers "F.Cu" "F.Mask" "F.Paste")
			(net "VR_PVDDQ_GHJ_VD12")
		)
		(pad "2" smd rect
			(at 0 0.889 90)
			(size 0.508 0.508)
			(layers "F.Cu" "F.Mask" "F.Paste")
			(net "GND")
		)
		(zone
			(layer "F.Cu")
			(hatch none 0.5)
			(connect_pads
				(clearance 0)
			)
			(min_thickness 0.25)
			(keepout
				(tracks not_allowed)
				(vias allowed)
				(pads allowed)
				(copperpour not_allowed)
				(footprints allowed)
			)
			(placement
				(enabled no)
				(sheetname "")
			)
			(fill
				(thermal_gap 0.5)
				(thermal_bridge_width 0.5)
				(island_removal_mode 0)
			)
			(polygon
				(pts
					(xy 14.195806 2.438654) (xy 14.195806 2.946654) (xy 14.576806 2.946654) (xy 14.576806 2.438654)
				)
			)
		)
		(zone
			(layer "F.Cu")
			(hatch none 0.5)
			(connect_pads
				(clearance 0)
			)
			(min_thickness 0.25)
			(keepout
				(tracks allowed)
				(vias not_allowed)
				(pads allowed)
				(copperpour not_allowed)
				(footprints allowed)
			)
			(placement
				(enabled no)
				(sheetname "")
			)
			(fill
				(thermal_gap 0.5)
				(thermal_bridge_width 0.5)
				(island_removal_mode 0)
			)
			(polygon
				(pts
					(xy 14.195806 2.438654) (xy 14.195806 2.946654) (xy 14.576806 2.946654) (xy 14.576806 2.438654)
				)
			)
		)
	)
	(footprint ""
		(layer "F.Cu")
		(at 430.276 -154.94 -90)
		(property "Reference" "J8A1"
			(at 15.64767 10.287 0)
			(unlocked yes)
			(layer "B.SilkS")
			(effects
				(font
					(size 0.7874 0.5842)
					(thickness 0.1524)
				)
				(justify left mirror)
			)
		)
		(property "Value" ""
			(at 0 0 270)
			(layer "F.Fab")
			(effects
				(font
					(size 1.27 1.27)
				)
			)
		)
		(duplicate_pad_numbers_are_jumpers no)
		(fp_line
			(start -3.065018 22.645116)
			(end -3.065018 -4.644898)
			(stroke
				(width 0.1524)
				(type default)
			)
			(layer "F.SilkS")
		)
		(fp_line
			(start 13.765022 22.645116)
			(end -3.065018 22.645116)
			(stroke
				(width 0.1524)
				(type default)
			)
			(layer "F.SilkS")
		)
		(fp_line
			(start -3.065018 -4.644898)
			(end 13.765022 -4.644898)
			(stroke
				(width 0.1524)
				(type default)
			)
			(layer "F.SilkS")
		)
		(fp_line
			(start 13.765022 -4.644898)
			(end 13.765022 22.645116)
			(stroke
				(width 0.1524)
				(type default)
			)
			(layer "F.SilkS")
		)
		(fp_poly
			(pts
				(xy -4.604512 -0.604012) (xy -4.604512 0.411988) (xy -3.334512 -0.096012)
			)
			(stroke
				(width 0)
				(type default)
			)
			(fill yes)
			(layer "F.SilkS")
		)
		(fp_poly
			(pts
				(xy -4.604512 -0.604012) (xy -4.604512 0.411988) (xy -3.334512 -0.096012)
			)
			(stroke
				(width 0)
				(type default)
			)
			(fill yes)
			(layer "B.SilkS")
		)
		(fp_rect
			(start -3.065018 22.645116)
			(end 13.765022 -4.644898)
			(stroke
				(width 0)
				(type default)
			)
			(fill no)
			(layer "F.CrtYd")
		)
		(fp_poly
			(pts
				(xy -4.604512 -0.604012) (xy -4.604512 0.411988) (xy -3.334512 -0.096012)
			)
			(stroke
				(width 0)
				(type default)
			)
			(fill yes)
			(layer "B.Fab")
		)
		(fp_line
			(start -3.065018 22.645116)
			(end -3.065018 -4.644898)
			(stroke
				(width 0.1)
				(type default)
			)
			(layer "F.Fab")
		)
		(fp_line
			(start 13.765022 22.645116)
			(end -3.065018 22.645116)
			(stroke
				(width 0.1)
				(type default)
			)
			(layer "F.Fab")
		)
		(fp_line
			(start -3.065018 -4.644898)
			(end 13.765022 -4.644898)
			(stroke
				(width 0.1)
				(type default)
			)
			(layer "F.Fab")
		)
		(fp_line
			(start 13.765022 -4.644898)
			(end 13.765022 22.645116)
			(stroke
				(width 0.1)
				(type default)
			)
			(layer "F.Fab")
		)
		(fp_poly
			(pts
				(xy -4.604512 -0.604012) (xy -4.604512 0.411988) (xy -3.334512 -0.096012)
			)
			(stroke
				(width 0)
				(type default)
			)
			(fill yes)
			(layer "F.Fab")
		)
		(fp_text user "2A9"
			(at -3.34137 24.90978 0)
			(unlocked yes)
			(layer "F.SilkS")
			(effects
				(font
					(size 0.7874 0.5842)
					(thickness 0.1524)
				)
				(justify left)
			)
		)
		(fp_text user "2D9"
			(at 14.819122 19.393408 0)
			(unlocked yes)
			(layer "F.SilkS")
			(effects
				(font
					(size 0.7874 0.5842)
					(thickness 0.1524)
				)
				(justify left)
			)
		)
		(fp_text user "1D1"
			(at 14.42847 6.1722 0)
			(unlocked yes)
			(layer "F.SilkS")
			(effects
				(font
					(size 0.7874 0.5842)
					(thickness 0.1524)
				)
				(justify left)
			)
		)
		(fp_text user "2A9"
			(at -1.524 18.69567 270)
			(unlocked yes)
			(layer "B.SilkS")
			(effects
				(font
					(size 0.7874 0.5842)
					(thickness 0.1524)
				)
				(justify left mirror)
			)
		)
		(fp_text user "2D9"
			(at 13.5636 18.16989 270)
			(unlocked yes)
			(layer "B.SilkS")
			(effects
				(font
					(size 0.7874 0.5842)
					(thickness 0.1524)
				)
				(justify left mirror)
			)
		)
		(fp_text user "1D1"
			(at 14.3383 -2.63525 270)
			(unlocked yes)
			(layer "B.SilkS")
			(effects
				(font
					(size 0.7874 0.5842)
					(thickness 0.1524)
				)
				(justify left mirror)
			)
		)
		(fp_text user "2A9"
			(at -1.5367 17.74571 270)
			(unlocked yes)
			(layer "B.Fab")
			(effects
				(font
					(size 0.7874 0.5842)
					(thickness 0.1524)
				)
				(justify left mirror)
			)
		)
		(fp_text user "2D9"
			(at -3.04927 1.75768 0)
			(unlocked yes)
			(layer "B.Fab")
			(effects
				(font
					(size 0.7874 0.5842)
					(thickness 0.1524)
				)
				(justify left mirror)
			)
		)
		(fp_text user "1D1"
			(at 16.320262 -0.217424 270)
			(unlocked yes)
			(layer "B.Fab")
			(effects
				(font
					(size 0.7874 0.5842)
					(thickness 0.1524)
				)
				(justify left mirror)
			)
		)
		(fp_text user "2A9"
			(at -3.343656 24.909526 0)
			(unlocked yes)
			(layer "F.Fab")
			(effects
				(font
					(size 0.7874 0.5842)
					(thickness 0.1524)
				)
				(justify left)
			)
		)
		(pad "" np_thru_hole circle
			(at -1.329944 -2.990088 270)
			(size 0.254 0.254)
			(drill 2.2098)
			(layers "*.Cu" "*.Mask")
			(clearance 1.2954)
			(thermal_gap 1.2954)
		)
		(pad "" np_thru_hole circle
			(at -1.329944 21.010118 270)
			(size 0.254 0.254)
			(drill 2.2098)
			(layers "*.Cu" "*.Mask")
			(clearance 1.2954)
			(thermal_gap 1.2954)
		)
		(pad "" np_thru_hole circle
			(at 10.700004 -2.990088 270)
			(size 0.254 0.254)
			(drill 2.2098)
			(layers "*.Cu" "*.Mask")
			(clearance 1.2954)
			(thermal_gap 1.2954)
		)
		(pad "" np_thru_hole circle
			(at 10.700004 9.009888 270)
			(size 0.254 0.254)
			(drill 2.2098)
			(layers "*.Cu" "*.Mask")
			(clearance 1.2954)
			(thermal_gap 1.2954)
		)
		(pad "" np_thru_hole circle
			(at 10.700004 21.010118 270)
			(size 0.254 0.254)
			(drill 2.2098)
			(layers "*.Cu" "*.Mask")
			(clearance 1.2954)
			(thermal_gap 1.2954)
		)
		(pad "1A1" thru_hole rect
			(at 0 0 270)
			(size 0.7874 0.7874)
			(drill 0.381)
			(layers "*.Cu" "*.Mask")
			(remove_unused_layers no)
			(net "TP_FM_QAT_CBL_PRSNT0_R_N")
			(clearance 0.1143)
			(thermal_gap 0.1143)
			(padstack
				(mode front_inner_back)
				(layer "Inner"
					(shape circle)
					(size 0.7874 0.7874)
					(clearance 0.1143)
				)
				(layer "B.Cu"
					(shape rect)
					(size 0.7874 0.7874)
					(clearance 0.1143)
				)
			)
		)
		(pad "1A2" thru_hole circle
			(at -1.400048 0.750062 270)
			(size 0.7874 0.7874)
			(drill 0.381)
			(layers "*.Cu" "*.Mask")
			(remove_unused_layers no)
			(net "SGPIO_PCH_SATA_CLOCK_R")
			(clearance 0.1143)
			(thermal_gap 0.1143)
		)
		(pad "1A3" thru_hole circle
			(at -0.700024 1.500124 270)
			(size 0.7874 0.7874)
			(drill 0.381)
			(layers "*.Cu" "*.Mask")
			(remove_unused_layers no)
			(net "GND")
			(clearance 0.1143)
			(thermal_gap 0.1143)
		)
		(pad "1A4" thru_hole circle
			(at 0 2.249932 270)
			(size 0.7874 0.7874)
			(drill 0.381)
			(layers "*.Cu" "*.Mask")
			(remove_unused_layers no)
			(net "SATA6G_P1_RX_C_DP")
			(clearance 0.1143)
			(thermal_gap 0.1143)
		)
		(pad "1A5" thru_hole circle
			(at -1.400048 2.999994 270)
			(size 0.7874 0.7874)
			(drill 0.381)
			(layers "*.Cu" "*.Mask")
			(remove_unused_layers no)
			(net "SATA6G_P1_RX_C_DN")
			(clearance 0.1143)
			(thermal_gap 0.1143)
		)
		(pad "1A6" thru_hole circle
			(at -0.700024 3.750056 270)
			(size 0.7874 0.7874)
			(drill 0.381)
			(layers "*.Cu" "*.Mask")
			(remove_unused_layers no)
			(net "GND")
			(clearance 0.1143)
			(thermal_gap 0.1143)
		)
		(pad "1A7" thru_hole circle
			(at 0 4.500118 270)
			(size 0.7874 0.7874)
			(drill 0.381)
			(layers "*.Cu" "*.Mask")
			(remove_unused_layers no)
			(net "SATA6G_P3_RX_C_DP")
			(clearance 0.1143)
			(thermal_gap 0.1143)
		)
		(pad "1A8" thru_hole circle
			(at -1.400048 5.249926 270)
			(size 0.7874 0.7874)
			(drill 0.381)
			(layers "*.Cu" "*.Mask")
			(remove_unused_layers no)
			(net "SATA6G_P3_RX_C_DN")
			(clearance 0.1143)
			(thermal_gap 0.1143)
		)
		(pad "1A9" thru_hole circle
			(at -0.700024 5.999988 270)
			(size 0.7874 0.7874)
			(drill 0.381)
			(layers "*.Cu" "*.Mask")
			(remove_unused_layers no)
			(net "GND")
			(clearance 0.1143)
			(thermal_gap 0.1143)
		)
		(pad "1B1" thru_hole circle
			(at 3.800094 0 270)
			(size 0.7874 0.7874)
			(drill 0.381)
			(layers "*.Cu" "*.Mask")
			(remove_unused_layers no)
			(net "GND")
			(clearance 0.1143)
			(thermal_gap 0.1143)
		)
		(pad "1B2" thru_hole circle
			(at 2.400046 0.750062 270)
			(size 0.7874 0.7874)
			(drill 0.381)
			(layers "*.Cu" "*.Mask")
			(remove_unused_layers no)
			(net "SGPIO_PCH_SATA_LOAD_R")
			(clearance 0.1143)
			(thermal_gap 0.1143)
		)
		(pad "1B3" thru_hole circle
			(at 3.10007 1.500124 270)
			(size 0.7874 0.7874)
			(drill 0.381)
			(layers "*.Cu" "*.Mask")
			(remove_unused_layers no)
			(net "GND")
			(clearance 0.1143)
			(thermal_gap 0.1143)
		)
		(pad "1B4" thru_hole circle
			(at 3.800094 2.249932 270)
			(size 0.7874 0.7874)
			(drill 0.381)
			(layers "*.Cu" "*.Mask")
			(remove_unused_layers no)
			(net "SATA6G_P0_RX_C_DP")
			(clearance 0.1143)
			(thermal_gap 0.1143)
		)
		(pad "1B5" thru_hole circle
			(at 2.400046 2.999994 270)
			(size 0.7874 0.7874)
			(drill 0.381)
			(layers "*.Cu" "*.Mask")
			(remove_unused_layers no)
			(net "SATA6G_P0_RX_C_DN")
			(clearance 0.1143)
			(thermal_gap 0.1143)
		)
		(pad "1B6" thru_hole circle
			(at 3.10007 3.750056 270)
			(size 0.7874 0.7874)
			(drill 0.381)
			(layers "*.Cu" "*.Mask")
			(remove_unused_layers no)
			(net "GND")
			(clearance 0.1143)
			(thermal_gap 0.1143)
		)
		(pad "1B7" thru_hole circle
			(at 3.800094 4.500118 270)
			(size 0.7874 0.7874)
			(drill 0.381)
			(layers "*.Cu" "*.Mask")
			(remove_unused_layers no)
			(net "SATA6G_P2_RX_C_DP")
			(clearance 0.1143)
			(thermal_gap 0.1143)
		)
		(pad "1B8" thru_hole circle
			(at 2.400046 5.249926 270)
			(size 0.7874 0.7874)
			(drill 0.381)
			(layers "*.Cu" "*.Mask")
			(remove_unused_layers no)
			(net "SATA6G_P2_RX_C_DN")
			(clearance 0.1143)
			(thermal_gap 0.1143)
		)
		(pad "1B9" thru_hole circle
			(at 3.10007 5.999988 270)
			(size 0.7874 0.7874)
			(drill 0.381)
			(layers "*.Cu" "*.Mask")
			(remove_unused_layers no)
			(net "GND")
			(clearance 0.1143)
			(thermal_gap 0.1143)
		)
		(pad "1C1" thru_hole circle
			(at 7.599934 0 270)
			(size 0.7874 0.7874)
			(drill 0.381)
			(layers "*.Cu" "*.Mask")
			(remove_unused_layers no)
			(net "SGPIO_PCH_SATA_DOUT0_R")
			(clearance 0.1143)
			(thermal_gap 0.1143)
		)
		(pad "1C2" thru_hole circle
			(at 6.199886 0.750062 270)
			(size 0.7874 0.7874)
			(drill 0.381)
			(layers "*.Cu" "*.Mask")
			(remove_unused_layers no)
			(net "GND")
			(clearance 0.1143)
			(thermal_gap 0.1143)
		)
		(pad "1C3" thru_hole circle
			(at 6.89991 1.500124 270)
			(size 0.7874 0.7874)
			(drill 0.381)
			(layers "*.Cu" "*.Mask")
			(remove_unused_layers no)
			(net "GND")
			(clearance 0.1143)
			(thermal_gap 0.1143)
		)
		(pad "1C4" thru_hole circle
			(at 7.599934 2.249932 270)
			(size 0.7874 0.7874)
			(drill 0.381)
			(layers "*.Cu" "*.Mask")
			(remove_unused_layers no)
			(net "SATA6G_P1_TX_C_DP")
			(clearance 0.1143)
			(thermal_gap 0.1143)
		)
		(pad "1C5" thru_hole circle
			(at 6.199886 2.999994 270)
			(size 0.7874 0.7874)
			(drill 0.381)
			(layers "*.Cu" "*.Mask")
			(remove_unused_layers no)
			(net "SATA6G_P1_TX_C_DN")
			(clearance 0.1143)
			(thermal_gap 0.1143)
		)
		(pad "1C6" thru_hole circle
			(at 6.89991 3.750056 270)
			(size 0.7874 0.7874)
			(drill 0.381)
			(layers "*.Cu" "*.Mask")
			(remove_unused_layers no)
			(net "GND")
			(clearance 0.1143)
			(thermal_gap 0.1143)
		)
		(pad "1C7" thru_hole circle
			(at 7.599934 4.500118 270)
			(size 0.7874 0.7874)
			(drill 0.381)
			(layers "*.Cu" "*.Mask")
			(remove_unused_layers no)
			(net "SATA6G_P3_TX_C_DP")
			(clearance 0.1143)
			(thermal_gap 0.1143)
		)
		(pad "1C8" thru_hole circle
			(at 6.199886 5.249926 270)
			(size 0.7874 0.7874)
			(drill 0.381)
			(layers "*.Cu" "*.Mask")
			(remove_unused_layers no)
			(net "SATA6G_P3_TX_C_DN")
			(clearance 0.1143)
			(thermal_gap 0.1143)
		)
		(pad "1C9" thru_hole circle
			(at 6.89991 5.999988 270)
			(size 0.7874 0.7874)
			(drill 0.381)
			(layers "*.Cu" "*.Mask")
			(remove_unused_layers no)
			(net "GND")
			(clearance 0.1143)
			(thermal_gap 0.1143)
		)
		(pad "1D1" thru_hole circle
			(at 11.400028 0 270)
			(size 0.7874 0.7874)
			(drill 0.381)
			(layers "*.Cu" "*.Mask")
			(remove_unused_layers no)
			(net "PU_DATAIN1_SATA_0_R")
			(clearance 0.1143)
			(thermal_gap 0.1143)
		)
		(pad "1D2" thru_hole circle
			(at 9.99998 0.750062 270)
			(size 0.7874 0.7874)
			(drill 0.381)
			(layers "*.Cu" "*.Mask")
			(remove_unused_layers no)
			(net "PD_SATA0_CONTROLLER_TYPE_R")
			(clearance 0.1143)
			(thermal_gap 0.1143)
		)
		(pad "1D3" thru_hole circle
			(at 10.700004 1.500124 270)
			(size 0.7874 0.7874)
			(drill 0.381)
			(layers "*.Cu" "*.Mask")
			(remove_unused_layers no)
			(net "GND")
			(clearance 0.1143)
			(thermal_gap 0.1143)
		)
		(pad "1D4" thru_hole circle
			(at 11.400028 2.249932 270)
			(size 0.7874 0.7874)
			(drill 0.381)
			(layers "*.Cu" "*.Mask")
			(remove_unused_layers no)
			(net "SATA6G_P0_TX_C_DP")
			(clearance 0.1143)
			(thermal_gap 0.1143)
		)
		(pad "1D5" thru_hole circle
			(at 9.99998 2.999994 270)
			(size 0.7874 0.7874)
			(drill 0.381)
			(layers "*.Cu" "*.Mask")
			(remove_unused_layers no)
			(net "SATA6G_P0_TX_C_DN")
			(clearance 0.1143)
			(thermal_gap 0.1143)
		)
		(pad "1D6" thru_hole circle
			(at 10.700004 3.750056 270)
			(size 0.7874 0.7874)
			(drill 0.381)
			(layers "*.Cu" "*.Mask")
			(remove_unused_layers no)
			(net "GND")
			(clearance 0.1143)
			(thermal_gap 0.1143)
		)
		(pad "1D7" thru_hole circle
			(at 11.400028 4.500118 270)
			(size 0.7874 0.7874)
			(drill 0.381)
			(layers "*.Cu" "*.Mask")
			(remove_unused_layers no)
			(net "SATA6G_P2_TX_C_DP")
			(clearance 0.1143)
			(thermal_gap 0.1143)
		)
		(pad "1D8" thru_hole circle
			(at 9.99998 5.249926 270)
			(size 0.7874 0.7874)
			(drill 0.381)
			(layers "*.Cu" "*.Mask")
			(remove_unused_layers no)
			(net "SATA6G_P2_TX_C_DN")
			(clearance 0.1143)
			(thermal_gap 0.1143)
		)
		(pad "1D9" thru_hole circle
			(at 10.700004 5.999988 270)
			(size 0.7874 0.7874)
			(drill 0.381)
			(layers "*.Cu" "*.Mask")
			(remove_unused_layers no)
			(net "GND")
			(clearance 0.1143)
			(thermal_gap 0.1143)
		)
		(pad "2A1" thru_hole circle
			(at 0 11.999976 270)
			(size 0.7874 0.7874)
			(drill 0.381)
			(layers "*.Cu" "*.Mask")
			(remove_unused_layers no)
			(net "TP_FM_QAT_CBL_PRSNT1_N_R")
			(clearance 0.1143)
			(thermal_gap 0.1143)
		)
		(pad "2A2" thru_hole circle
			(at -1.400048 12.750038 270)
			(size 0.7874 0.7874)
			(drill 0.381)
			(layers "*.Cu" "*.Mask")
			(remove_unused_layers no)
			(net "TP_SGPIO_SATA_CLOCK1_R")
			(clearance 0.1143)
			(thermal_gap 0.1143)
		)
		(pad "2A3" thru_hole circle
			(at -0.700024 13.5001 270)
			(size 0.7874 0.7874)
			(drill 0.381)
			(layers "*.Cu" "*.Mask")
			(remove_unused_layers no)
			(net "GND")
			(clearance 0.1143)
			(thermal_gap 0.1143)
		)
		(pad "2A4" thru_hole circle
			(at 0 14.249908 270)
			(size 0.7874 0.7874)
			(drill 0.381)
			(layers "*.Cu" "*.Mask")
			(remove_unused_layers no)
			(net "SATA6G_P5_RX_C_DP")
			(clearance 0.1143)
			(thermal_gap 0.1143)
		)
		(pad "2A5" thru_hole circle
			(at -1.400048 14.99997 270)
			(size 0.7874 0.7874)
			(drill 0.381)
			(layers "*.Cu" "*.Mask")
			(remove_unused_layers no)
			(net "SATA6G_P5_RX_C_DN")
			(clearance 0.1143)
			(thermal_gap 0.1143)
		)
		(pad "2A6" thru_hole circle
			(at -0.700024 15.750032 270)
			(size 0.7874 0.7874)
			(drill 0.381)
			(layers "*.Cu" "*.Mask")
			(remove_unused_layers no)
			(net "GND")
			(clearance 0.1143)
			(thermal_gap 0.1143)
		)
		(pad "2A7" thru_hole circle
			(at 0 16.500094 270)
			(size 0.7874 0.7874)
			(drill 0.381)
			(layers "*.Cu" "*.Mask")
			(remove_unused_layers no)
			(net "SATA6G_P7_RX_C_DP")
			(clearance 0.1143)
			(thermal_gap 0.1143)
		)
		(pad "2A8" thru_hole circle
			(at -1.400048 17.249902 270)
			(size 0.7874 0.7874)
			(drill 0.381)
			(layers "*.Cu" "*.Mask")
			(remove_unused_layers no)
			(net "SATA6G_P7_RX_C_DN")
			(clearance 0.1143)
			(thermal_gap 0.1143)
		)
		(pad "2A9" thru_hole circle
			(at -0.700024 17.999964 270)
			(size 0.7874 0.7874)
			(drill 0.381)
			(layers "*.Cu" "*.Mask")
			(remove_unused_layers no)
			(net "GND")
			(clearance 0.1143)
			(thermal_gap 0.1143)
		)
		(pad "2B1" thru_hole circle
			(at 3.800094 11.999976 270)
			(size 0.7874 0.7874)
			(drill 0.381)
			(layers "*.Cu" "*.Mask")
			(remove_unused_layers no)
			(net "GND")
			(clearance 0.1143)
			(thermal_gap 0.1143)
		)
		(pad "2B2" thru_hole circle
			(at 2.400046 12.750038 270)
			(size 0.7874 0.7874)
			(drill 0.381)
			(layers "*.Cu" "*.Mask")
			(remove_unused_layers no)
			(net "TP_SGPIO_SATA_LOAD1_R")
			(clearance 0.1143)
			(thermal_gap 0.1143)
		)
		(pad "2B3" thru_hole circle
			(at 3.10007 13.5001 270)
			(size 0.7874 0.7874)
			(drill 0.381)
			(layers "*.Cu" "*.Mask")
			(remove_unused_layers no)
			(net "GND")
			(clearance 0.1143)
			(thermal_gap 0.1143)
		)
		(pad "2B4" thru_hole circle
			(at 3.800094 14.249908 270)
			(size 0.7874 0.7874)
			(drill 0.381)
			(layers "*.Cu" "*.Mask")
			(remove_unused_layers no)
			(net "SATA6G_P4_RX_C_DP")
			(clearance 0.1143)
			(thermal_gap 0.1143)
		)
		(pad "2B5" thru_hole circle
			(at 2.400046 14.99997 270)
			(size 0.7874 0.7874)
			(drill 0.381)
			(layers "*.Cu" "*.Mask")
			(remove_unused_layers no)
			(net "SATA6G_P4_RX_C_DN")
			(clearance 0.1143)
			(thermal_gap 0.1143)
		)
		(pad "2B6" thru_hole circle
			(at 3.10007 15.750032 270)
			(size 0.7874 0.7874)
			(drill 0.381)
			(layers "*.Cu" "*.Mask")
			(remove_unused_layers no)
			(net "GND")
			(clearance 0.1143)
			(thermal_gap 0.1143)
		)
		(pad "2B7" thru_hole circle
			(at 3.800094 16.500094 270)
			(size 0.7874 0.7874)
			(drill 0.381)
			(layers "*.Cu" "*.Mask")
			(remove_unused_layers no)
			(net "SATA6G_P6_RX_C_DP")
			(clearance 0.1143)
			(thermal_gap 0.1143)
		)
		(pad "2B8" thru_hole circle
			(at 2.400046 17.249902 270)
			(size 0.7874 0.7874)
			(drill 0.381)
			(layers "*.Cu" "*.Mask")
			(remove_unused_layers no)
			(net "SATA6G_P6_RX_C_DN")
			(clearance 0.1143)
			(thermal_gap 0.1143)
		)
		(pad "2B9" thru_hole circle
			(at 3.10007 17.999964 270)
			(size 0.7874 0.7874)
			(drill 0.381)
			(layers "*.Cu" "*.Mask")
			(remove_unused_layers no)
			(net "GND")
			(clearance 0.1143)
			(thermal_gap 0.1143)
		)
		(pad "2C1" thru_hole circle
			(at 7.599934 11.999976 270)
			(size 0.7874 0.7874)
			(drill 0.381)
			(layers "*.Cu" "*.Mask")
			(remove_unused_layers no)
			(net "TP_SGPIO_SATA_DATA1_R")
			(clearance 0.1143)
			(thermal_gap 0.1143)
		)
		(pad "2C2" thru_hole circle
			(at 6.199886 12.750038 270)
			(size 0.7874 0.7874)
			(drill 0.381)
			(layers "*.Cu" "*.Mask")
			(remove_unused_layers no)
			(net "GND")
			(clearance 0.1143)
			(thermal_gap 0.1143)
		)
		(pad "2C3" thru_hole circle
			(at 6.89991 13.5001 270)
			(size 0.7874 0.7874)
			(drill 0.381)
			(layers "*.Cu" "*.Mask")
			(remove_unused_layers no)
			(net "GND")
			(clearance 0.1143)
			(thermal_gap 0.1143)
		)
		(pad "2C4" thru_hole circle
			(at 7.599934 14.249908 270)
			(size 0.7874 0.7874)
			(drill 0.381)
			(layers "*.Cu" "*.Mask")
			(remove_unused_layers no)
			(net "SATA6G_P5_TX_C_DP")
			(clearance 0.1143)
			(thermal_gap 0.1143)
		)
		(pad "2C5" thru_hole circle
			(at 6.199886 14.99997 270)
			(size 0.7874 0.7874)
			(drill 0.381)
			(layers "*.Cu" "*.Mask")
			(remove_unused_layers no)
			(net "SATA6G_P5_TX_C_DN")
			(clearance 0.1143)
			(thermal_gap 0.1143)
		)
		(pad "2C6" thru_hole circle
			(at 6.89991 15.750032 270)
			(size 0.7874 0.7874)
			(drill 0.381)
			(layers "*.Cu" "*.Mask")
			(remove_unused_layers no)
			(net "GND")
			(clearance 0.1143)
			(thermal_gap 0.1143)
		)
		(pad "2C7" thru_hole circle
			(at 7.599934 16.500094 270)
			(size 0.7874 0.7874)
			(drill 0.381)
			(layers "*.Cu" "*.Mask")
			(remove_unused_layers no)
			(net "SATA6G_P7_TX_C_DP")
			(clearance 0.1143)
			(thermal_gap 0.1143)
		)
		(pad "2C8" thru_hole circle
			(at 6.199886 17.249902 270)
			(size 0.7874 0.7874)
			(drill 0.381)
			(layers "*.Cu" "*.Mask")
			(remove_unused_layers no)
			(net "SATA6G_P7_TX_C_DN")
			(clearance 0.1143)
			(thermal_gap 0.1143)
		)
		(pad "2C9" thru_hole circle
			(at 6.89991 17.999964 270)
			(size 0.7874 0.7874)
			(drill 0.381)
			(layers "*.Cu" "*.Mask")
			(remove_unused_layers no)
			(net "GND")
			(clearance 0.1143)
			(thermal_gap 0.1143)
		)
		(pad "2D1" thru_hole circle
			(at 11.400028 11.999976 270)
			(size 0.7874 0.7874)
			(drill 0.381)
			(layers "*.Cu" "*.Mask")
			(remove_unused_layers no)
			(net "PU_DATAIN1_SATA_1_R")
			(clearance 0.1143)
			(thermal_gap 0.1143)
		)
		(pad "2D2" thru_hole circle
			(at 9.99998 12.750038 270)
			(size 0.7874 0.7874)
			(drill 0.381)
			(layers "*.Cu" "*.Mask")
			(remove_unused_layers no)
			(net "PD_SATA1_CONTROLLER_TYPE_R")
			(clearance 0.1143)
			(thermal_gap 0.1143)
		)
		(pad "2D3" thru_hole circle
			(at 10.700004 13.5001 270)
			(size 0.7874 0.7874)
			(drill 0.381)
			(layers "*.Cu" "*.Mask")
			(remove_unused_layers no)
			(net "GND")
			(clearance 0.1143)
			(thermal_gap 0.1143)
		)
		(pad "2D4" thru_hole circle
			(at 11.400028 14.249908 270)
			(size 0.7874 0.7874)
			(drill 0.381)
			(layers "*.Cu" "*.Mask")
			(remove_unused_layers no)
			(net "SATA6G_P4_TX_C_DP")
			(clearance 0.1143)
			(thermal_gap 0.1143)
		)
		(pad "2D5" thru_hole circle
			(at 9.99998 14.99997 270)
			(size 0.7874 0.7874)
			(drill 0.381)
			(layers "*.Cu" "*.Mask")
			(remove_unused_layers no)
			(net "SATA6G_P4_TX_C_DN")
			(clearance 0.1143)
			(thermal_gap 0.1143)
		)
		(pad "2D6" thru_hole circle
			(at 10.700004 15.750032 270)
			(size 0.7874 0.7874)
			(drill 0.381)
			(layers "*.Cu" "*.Mask")
			(remove_unused_layers no)
			(net "GND")
			(clearance 0.1143)
			(thermal_gap 0.1143)
		)
		(pad "2D7" thru_hole circle
			(at 11.400028 16.500094 270)
			(size 0.7874 0.7874)
			(drill 0.381)
			(layers "*.Cu" "*.Mask")
			(remove_unused_layers no)
			(net "SATA6G_P6_TX_C_DP")
			(clearance 0.1143)
			(thermal_gap 0.1143)
		)
		(pad "2D8" thru_hole circle
			(at 9.99998 17.249902 270)
			(size 0.7874 0.7874)
			(drill 0.381)
			(layers "*.Cu" "*.Mask")
			(remove_unused_layers no)
			(net "SATA6G_P6_TX_C_DN")
			(clearance 0.1143)
			(thermal_gap 0.1143)
		)
		(pad "2D9" thru_hole circle
			(at 10.700004 17.999964 270)
			(size 0.7874 0.7874)
			(drill 0.381)
			(layers "*.Cu" "*.Mask")
			(remove_unused_layers no)
			(net "GND")
			(clearance 0.1143)
			(thermal_gap 0.1143)
		)
		(zone
			(layers "F.Cu" "B.Cu" "In1.Cu" "In2.Cu" "In3.Cu" "In4.Cu" "In5.Cu" "In6.Cu"
				"In7.Cu" "In8.Cu" "In9.Cu" "In10.Cu" "In11.Cu" "In12.Cu"
			)
			(hatch none 0.5)
			(connect_pads
				(clearance 0)
			)
			(min_thickness 0.25)
			(keepout
				(tracks not_allowed)
				(vias allowed)
				(pads allowed)
				(copperpour not_allowed)
				(footprints allowed)
			)
			(placement
				(enabled no)
				(sheetname "")
			)
			(fill
				(thermal_gap 0.5)
				(thermal_bridge_width 0.5)
				(island_removal_mode 0)
			)
			(polygon
				(pts
					(arc
						(start 410.68879 -156.269944)
						(mid 407.842974 -156.269944)
						(end 410.68879 -156.269944)
					)
				)
			)
		)
		(zone
			(layers "F.Cu" "B.Cu" "In1.Cu" "In2.Cu" "In3.Cu" "In4.Cu" "In5.Cu" "In6.Cu"
				"In7.Cu" "In8.Cu" "In9.Cu" "In10.Cu" "In11.Cu" "In12.Cu"
			)
			(hatch none 0.5)
			(connect_pads
				(clearance 0)
			)
			(min_thickness 0.25)
			(keepout
				(tracks not_allowed)
				(vias allowed)
				(pads allowed)
				(copperpour not_allowed)
				(footprints allowed)
			)
			(placement
				(enabled no)
				(sheetname "")
			)
			(fill
				(thermal_gap 0.5)
				(thermal_bridge_width 0.5)
				(island_removal_mode 0)
			)
			(polygon
				(pts
					(arc
						(start 410.68879 -144.239996)
						(mid 407.842974 -144.239996)
						(end 410.68879 -144.239996)
					)
				)
			)
		)
		(zone
			(layers "F.Cu" "B.Cu" "In1.Cu" "In2.Cu" "In3.Cu" "In4.Cu" "In5.Cu" "In6.Cu"
				"In7.Cu" "In8.Cu" "In9.Cu" "In10.Cu" "In11.Cu" "In12.Cu"
			)
			(hatch none 0.5)
			(connect_pads
				(clearance 0)
			)
			(min_thickness 0.25)
			(keepout
				(tracks not_allowed)
				(vias allowed)
				(pads allowed)
				(copperpour not_allowed)
				(footprints allowed)
			)
			(placement
				(enabled no)
				(sheetname "")
			)
			(fill
				(thermal_gap 0.5)
				(thermal_bridge_width 0.5)
				(island_removal_mode 0)
			)
			(polygon
				(pts
					(arc
						(start 422.68902 -144.239996)
						(mid 419.843204 -144.239996)
						(end 422.68902 -144.239996)
					)
				)
			)
		)
		(zone
			(layers "F.Cu" "B.Cu" "In1.Cu" "In2.Cu" "In3.Cu" "In4.Cu" "In5.Cu" "In6.Cu"
				"In7.Cu" "In8.Cu" "In9.Cu" "In10.Cu" "In11.Cu" "In12.Cu"
			)
			(hatch none 0.5)
			(connect_pads
				(clearance 0)
			)
			(min_thickness 0.25)
			(keepout
				(tracks not_allowed)
				(vias allowed)
				(pads allowed)
				(copperpour not_allowed)
				(footprints allowed)
			)
			(placement
				(enabled no)
				(sheetname "")
			)
			(fill
				(thermal_gap 0.5)
				(thermal_bridge_width 0.5)
				(island_removal_mode 0)
			)
			(polygon
				(pts
					(arc
						(start 434.688996 -156.269944)
						(mid 431.84318 -156.269944)
						(end 434.688996 -156.269944)
					)
				)
			)
		)
		(zone
			(layers "F.Cu" "B.Cu" "In1.Cu" "In2.Cu" "In3.Cu" "In4.Cu" "In5.Cu" "In6.Cu"
				"In7.Cu" "In8.Cu" "In9.Cu" "In10.Cu" "In11.Cu" "In12.Cu"
			)
			(hatch none 0.5)
			(connect_pads
				(clearance 0)
			)
			(min_thickness 0.25)
			(keepout
				(tracks not_allowed)
				(vias allowed)
				(pads allowed)
				(copperpour not_allowed)
				(footprints allowed)
			)
			(placement
				(enabled no)
				(sheetname "")
			)
			(fill
				(thermal_gap 0.5)
				(thermal_bridge_width 0.5)
				(island_removal_mode 0)
			)
			(polygon
				(pts
					(arc
						(start 434.688996 -144.239996)
						(mid 431.84318 -144.239996)
						(end 434.688996 -144.239996)
					)
				)
			)
		)
	)
	(footprint ""
		(layer "F.Cu")
		(at 279.6032 -79.6036 180)
		(property "Reference" "C6D4"
			(at 0 0 180)
			(layer "F.SilkS")
			(hide yes)
			(effects
				(font
					(size 1.27 1.27)
				)
			)
		)
		(property "Value" ""
			(at 0 0 180)
			(layer "F.Fab")
			(effects
				(font
					(size 1.27 1.27)
				)
			)
		)
		(duplicate_pad_numbers_are_jumpers no)
		(fp_poly
			(pts
				(xy -0.4953 -0.2032) (xy 0.4953 -0.2032) (xy 0.4953 1.6002) (xy -0.4953 1.6002)
			)
			(stroke
				(width 0)
				(type default)
			)
			(fill no)
			(layer "F.CrtYd")
		)
		(fp_line
			(start 0.4953 1.6002)
			(end -0.4953 1.6002)
			(stroke
				(width 0.1)
				(type default)
			)
			(layer "F.Fab")
		)
		(fp_line
			(start 0.4953 -0.2032)
			(end 0.4953 1.6002)
			(stroke
				(width 0.1)
				(type default)
			)
			(layer "F.Fab")
		)
		(fp_line
			(start -0.4953 1.6002)
			(end -0.4953 -0.2032)
			(stroke
				(width 0.1)
				(type default)
			)
			(layer "F.Fab")
		)
		(fp_line
			(start -0.4953 -0.2032)
			(end 0.4953 -0.2032)
			(stroke
				(width 0.1)
				(type default)
			)
			(layer "F.Fab")
		)
		(pad "1" smd rect
			(at 0 0 180)
			(size 0.762 0.889)
			(layers "F.Cu" "F.Mask" "F.Paste")
			(net "PVCCIO_CPU0")
		)
		(pad "2" smd rect
			(at 0 1.397 180)
			(size 0.762 0.889)
			(layers "F.Cu" "F.Mask" "F.Paste")
			(net "GND")
		)
		(zone
			(layer "F.Cu")
			(hatch none 0.5)
			(connect_pads
				(clearance 0)
			)
			(min_thickness 0.25)
			(keepout
				(tracks not_allowed)
				(vias allowed)
				(pads allowed)
				(copperpour not_allowed)
				(footprints allowed)
			)
			(placement
				(enabled no)
				(sheetname "")
			)
			(fill
				(thermal_gap 0.5)
				(thermal_bridge_width 0.5)
				(island_removal_mode 0)
			)
			(polygon
				(pts
					(xy 279.9842 -80.0481) (xy 279.2222 -80.0481) (xy 279.2222 -80.5561) (xy 279.9842 -80.5561)
				)
			)
		)
	)
	(footprint ""
		(layer "F.Cu")
		(at 359.29824 -138.16457 90)
		(property "Reference" "EU7A5"
			(at -1.51257 -3.29057 90)
			(unlocked yes)
			(layer "F.SilkS")
			(effects
				(font
					(size 0.7874 0.5842)
					(thickness 0.1524)
				)
				(justify left)
			)
		)
		(property "Value" ""
			(at 0 0 90)
			(layer "F.Fab")
			(effects
				(font
					(size 1.27 1.27)
				)
			)
		)
		(duplicate_pad_numbers_are_jumpers no)
		(fp_line
			(start 3.0607 -3.0607)
			(end 3.0607 3.0607)
			(stroke
				(width 0.1524)
				(type default)
			)
			(layer "F.SilkS")
		)
		(fp_line
			(start -3.0607 -3.0607)
			(end 3.0607 -3.0607)
			(stroke
				(width 0.1524)
				(type default)
			)
			(layer "F.SilkS")
		)
		(fp_line
			(start 2.549906 -2.549906)
			(end 2.549906 -2.258314)
			(stroke
				(width 0.1524)
				(type default)
			)
			(layer "F.SilkS")
		)
		(fp_line
			(start 2.245614 -2.549906)
			(end 2.549906 -2.549906)
			(stroke
				(width 0.1524)
				(type default)
			)
			(layer "F.SilkS")
		)
		(fp_line
			(start -2.549906 -2.549906)
			(end -2.249678 -2.549906)
			(stroke
				(width 0.1524)
				(type default)
			)
			(layer "F.SilkS")
		)
		(fp_line
			(start -2.549906 -2.29362)
			(end -2.549906 -2.549906)
			(stroke
				(width 0.1524)
				(type default)
			)
			(layer "F.SilkS")
		)
		(fp_line
			(start 2.549906 2.233422)
			(end 2.549906 2.549906)
			(stroke
				(width 0.1524)
				(type default)
			)
			(layer "F.SilkS")
		)
		(fp_line
			(start 2.549906 2.549906)
			(end 2.249678 2.549906)
			(stroke
				(width 0.1524)
				(type default)
			)
			(layer "F.SilkS")
		)
		(fp_line
			(start -2.277618 2.549906)
			(end -2.549906 2.549906)
			(stroke
				(width 0.1524)
				(type default)
			)
			(layer "F.SilkS")
		)
		(fp_line
			(start -2.549906 2.549906)
			(end -2.549906 2.267204)
			(stroke
				(width 0.1524)
				(type default)
			)
			(layer "F.SilkS")
		)
		(fp_line
			(start 3.0607 3.0607)
			(end -3.0607 3.0607)
			(stroke
				(width 0.1524)
				(type default)
			)
			(layer "F.SilkS")
		)
		(fp_line
			(start -3.0607 3.0607)
			(end -3.0607 -3.0607)
			(stroke
				(width 0.1524)
				(type default)
			)
			(layer "F.SilkS")
		)
		(fp_circle
			(center -3.237738 -2.256536)
			(end -3.237738 -2.129536)
			(stroke
				(width 0.254)
				(type default)
			)
			(fill no)
			(layer "F.SilkS")
		)
		(fp_poly
			(pts
				(xy -3.0607 -3.0607) (xy -3.0607 -2.0193) (xy -2.0193 -3.0607)
			)
			(stroke
				(width 0)
				(type default)
			)
			(fill yes)
			(layer "F.SilkS")
		)
		(fp_rect
			(start -1.8415 1.8415)
			(end 1.8415 -1.8415)
			(stroke
				(width 0)
				(type default)
			)
			(fill yes)
			(layer "F.Paste")
		)
		(fp_rect
			(start -2.549906 2.549906)
			(end 2.549906 -2.549906)
			(stroke
				(width 0)
				(type default)
			)
			(fill no)
			(layer "F.CrtYd")
		)
		(fp_line
			(start 2.549906 -2.549906)
			(end 2.549906 2.549906)
			(stroke
				(width 0.1)
				(type default)
			)
			(layer "F.Fab")
		)
		(fp_line
			(start -2.549906 -2.549906)
			(end 2.549906 -2.549906)
			(stroke
				(width 0.1)
				(type default)
			)
			(layer "F.Fab")
		)
		(fp_line
			(start 2.549906 2.549906)
			(end -2.549906 2.549906)
			(stroke
				(width 0.1)
				(type default)
			)
			(layer "F.Fab")
		)
		(fp_line
			(start -2.549906 2.549906)
			(end -2.549906 -2.549906)
			(stroke
				(width 0.1)
				(type default)
			)
			(layer "F.Fab")
		)
		(fp_circle
			(center -3.237738 -2.256536)
			(end -3.237738 -2.129536)
			(stroke
				(width 0.254)
				(type default)
			)
			(fill no)
			(layer "F.Fab")
		)
		(pad "1" smd custom
			(at -2.4511 -1.800098 90)
			(size 0.0508 0.0508)
			(layers "F.Cu" "F.Mask" "F.Paste")
			(net "Net_283")
			(options
				(clearance outline)
				(anchor circle)
			)
			(primitives
				(gr_poly
					(pts
						(arc
							(start 0.254 -0.1016)
							(mid 0.3556 0)
							(end 0.254 0.1016)
						)
						(xy -0.3556 0.1016) (xy -0.3556 -0.1016)
					)
					(width 0)
					(fill yes)
				)
			)
		)
		(pad "2" smd custom
			(at -2.4511 -1.400048 90)
			(size 0.0508 0.0508)
			(layers "F.Cu" "F.Mask" "F.Paste")
			(net "Net_347")
			(options
				(clearance outline)
				(anchor circle)
			)
			(primitives
				(gr_poly
					(pts
						(arc
							(start 0.254 -0.1016)
							(mid 0.3556 0)
							(end 0.254 0.1016)
						)
						(xy -0.3556 0.1016) (xy -0.3556 -0.1016)
					)
					(width 0)
					(fill yes)
				)
			)
		)
		(pad "3" smd custom
			(at -2.4511 -0.999998 90)
			(size 0.0508 0.0508)
			(layers "F.Cu" "F.Mask" "F.Paste")
			(net "Net_245")
			(options
				(clearance outline)
				(anchor circle)
			)
			(primitives
				(gr_poly
					(pts
						(arc
							(start 0.254 -0.1016)
							(mid 0.3556 0)
							(end 0.254 0.1016)
						)
						(xy -0.3556 0.1016) (xy -0.3556 -0.1016)
					)
					(width 0)
					(fill yes)
				)
			)
		)
		(pad "4" smd custom
			(at -2.4511 -0.599948 90)
			(size 0.0508 0.0508)
			(layers "F.Cu" "F.Mask" "F.Paste")
			(net "VR_PVDDQ_DEF_PWM2")
			(options
				(clearance outline)
				(anchor circle)
			)
			(primitives
				(gr_poly
					(pts
						(arc
							(start 0.254 -0.1016)
							(mid 0.3556 0)
							(end 0.254 0.1016)
						)
						(xy -0.3556 0.1016) (xy -0.3556 -0.1016)
					)
					(width 0)
					(fill yes)
				)
			)
		)
		(pad "5" smd custom
			(at -2.4511 -0.199898 90)
			(size 0.0508 0.0508)
			(layers "F.Cu" "F.Mask" "F.Paste")
			(net "VR_PVDDQ_DEF_PWM1")
			(options
				(clearance outline)
				(anchor circle)
			)
			(primitives
				(gr_poly
					(pts
						(arc
							(start 0.254 -0.1016)
							(mid 0.3556 0)
							(end 0.254 0.1016)
						)
						(xy -0.3556 0.1016) (xy -0.3556 -0.1016)
					)
					(width 0)
					(fill yes)
				)
			)
		)
		(pad "6" smd custom
			(at -2.4511 0.199898 90)
			(size 0.0508 0.0508)
			(layers "F.Cu" "F.Mask" "F.Paste")
			(net "SMB_VR_STBY_LVC3_SDA")
			(options
				(clearance outline)
				(anchor circle)
			)
			(primitives
				(gr_poly
					(pts
						(arc
							(start 0.254 -0.1016)
							(mid 0.3556 0)
							(end 0.254 0.1016)
						)
						(xy -0.3556 0.1016) (xy -0.3556 -0.1016)
					)
					(width 0)
					(fill yes)
				)
			)
		)
		(pad "7" smd custom
			(at -2.4511 0.599948 90)
			(size 0.0508 0.0508)
			(layers "F.Cu" "F.Mask" "F.Paste")
			(net "SMB_VR_STBY_LVC3_SCL")
			(options
				(clearance outline)
				(anchor circle)
			)
			(primitives
				(gr_poly
					(pts
						(arc
							(start 0.254 -0.1016)
							(mid 0.3556 0)
							(end 0.254 0.1016)
						)
						(xy -0.3556 0.1016) (xy -0.3556 -0.1016)
					)
					(width 0)
					(fill yes)
				)
			)
		)
		(pad "8" smd custom
			(at -2.4511 0.999998 90)
			(size 0.0508 0.0508)
			(layers "F.Cu" "F.Mask" "F.Paste")
			(net "Net_284")
			(options
				(clearance outline)
				(anchor circle)
			)
			(primitives
				(gr_poly
					(pts
						(arc
							(start 0.254 -0.1016)
							(mid 0.3556 0)
							(end 0.254 0.1016)
						)
						(xy -0.3556 0.1016) (xy -0.3556 -0.1016)
					)
					(width 0)
					(fill yes)
				)
			)
		)
		(pad "9" smd custom
			(at -2.4511 1.400048 90)
			(size 0.0508 0.0508)
			(layers "F.Cu" "F.Mask" "F.Paste")
			(net "PWRGD_PVDDQ_DEF_R")
			(options
				(clearance outline)
				(anchor circle)
			)
			(primitives
				(gr_poly
					(pts
						(arc
							(start 0.254 -0.1016)
							(mid 0.3556 0)
							(end 0.254 0.1016)
						)
						(xy -0.3556 0.1016) (xy -0.3556 -0.1016)
					)
					(width 0)
					(fill yes)
				)
			)
		)
		(pad "10" smd custom
			(at -2.4511 1.800098 90)
			(size 0.0508 0.0508)
			(layers "F.Cu" "F.Mask" "F.Paste")
			(net "VR_PVDDQ_DEF_VREN")
			(options
				(clearance outline)
				(anchor circle)
			)
			(primitives
				(gr_poly
					(pts
						(arc
							(start 0.254 -0.1016)
							(mid 0.3556 0)
							(end 0.254 0.1016)
						)
						(xy -0.3556 0.1016) (xy -0.3556 -0.1016)
					)
					(width 0)
					(fill yes)
				)
			)
		)
		(pad "11" smd custom
			(at -1.800098 2.4511 90)
			(size 0.0508 0.0508)
			(layers "F.Cu" "F.Mask" "F.Paste")
			(net "IRQ_PVDDQ_DEF_VRHOT_LVT3_R_N")
			(options
				(clearance outline)
				(anchor circle)
			)
			(primitives
				(gr_poly
					(pts
						(arc
							(start -0.1016 -0.254)
							(mid 0 -0.3556)
							(end 0.1016 -0.254)
						)
						(xy 0.1016 0.3556) (xy -0.1016 0.3556)
					)
					(width 0)
					(fill yes)
				)
			)
		)
		(pad "12" smd custom
			(at -1.400048 2.4511 90)
			(size 0.0508 0.0508)
			(layers "F.Cu" "F.Mask" "F.Paste")
			(net "Net_230")
			(options
				(clearance outline)
				(anchor circle)
			)
			(primitives
				(gr_poly
					(pts
						(arc
							(start -0.1016 -0.254)
							(mid 0 -0.3556)
							(end 0.1016 -0.254)
						)
						(xy 0.1016 0.3556) (xy -0.1016 0.3556)
					)
					(width 0)
					(fill yes)
				)
			)
		)
		(pad "13" smd custom
			(at -0.999998 2.4511 90)
			(size 0.0508 0.0508)
			(layers "F.Cu" "F.Mask" "F.Paste")
			(net "PU_VR_PVDDQ_DEF_FAULT1")
			(options
				(clearance outline)
				(anchor circle)
			)
			(primitives
				(gr_poly
					(pts
						(arc
							(start -0.1016 -0.254)
							(mid 0 -0.3556)
							(end 0.1016 -0.254)
						)
						(xy 0.1016 0.3556) (xy -0.1016 0.3556)
					)
					(width 0)
					(fill yes)
				)
			)
		)
		(pad "14" smd custom
			(at -0.599948 2.4511 90)
			(size 0.0508 0.0508)
			(layers "F.Cu" "F.Mask" "F.Paste")
			(net "TP_PVDDQ_DEF_MP1")
			(options
				(clearance outline)
				(anchor circle)
			)
			(primitives
				(gr_poly
					(pts
						(arc
							(start -0.1016 -0.254)
							(mid 0 -0.3556)
							(end 0.1016 -0.254)
						)
						(xy 0.1016 0.3556) (xy -0.1016 0.3556)
					)
					(width 0)
					(fill yes)
				)
			)
		)
		(pad "15" smd custom
			(at -0.199898 2.4511 90)
			(size 0.0508 0.0508)
			(layers "F.Cu" "F.Mask" "F.Paste")
			(net "SVID_CLK_PVDDQ_DEF")
			(options
				(clearance outline)
				(anchor circle)
			)
			(primitives
				(gr_poly
					(pts
						(arc
							(start -0.1016 -0.254)
							(mid 0 -0.3556)
							(end 0.1016 -0.254)
						)
						(xy 0.1016 0.3556) (xy -0.1016 0.3556)
					)
					(width 0)
					(fill yes)
				)
			)
		)
		(pad "16" smd custom
			(at 0.199898 2.4511 90)
			(size 0.0508 0.0508)
			(layers "F.Cu" "F.Mask" "F.Paste")
			(net "SVID_VDIO_PVDDQ_DEF")
			(options
				(clearance outline)
				(anchor circle)
			)
			(primitives
				(gr_poly
					(pts
						(arc
							(start -0.1016 -0.254)
							(mid 0 -0.3556)
							(end 0.1016 -0.254)
						)
						(xy 0.1016 0.3556) (xy -0.1016 0.3556)
					)
					(width 0)
					(fill yes)
				)
			)
		)
		(pad "17" smd custom
			(at 0.599948 2.4511 90)
			(size 0.0508 0.0508)
			(layers "F.Cu" "F.Mask" "F.Paste")
			(net "SVID_ALERT_PVDDQ_DEF")
			(options
				(clearance outline)
				(anchor circle)
			)
			(primitives
				(gr_poly
					(pts
						(arc
							(start -0.1016 -0.254)
							(mid 0 -0.3556)
							(end 0.1016 -0.254)
						)
						(xy 0.1016 0.3556) (xy -0.1016 0.3556)
					)
					(width 0)
					(fill yes)
				)
			)
		)
		(pad "18" smd custom
			(at 0.999998 2.4511 90)
			(size 0.0508 0.0508)
			(layers "F.Cu" "F.Mask" "F.Paste")
			(net "TP_PVDDQ_DEF_MP2")
			(options
				(clearance outline)
				(anchor circle)
			)
			(primitives
				(gr_poly
					(pts
						(arc
							(start -0.1016 -0.254)
							(mid 0 -0.3556)
							(end 0.1016 -0.254)
						)
						(xy 0.1016 0.3556) (xy -0.1016 0.3556)
					)
					(width 0)
					(fill yes)
				)
			)
		)
		(pad "19" smd custom
			(at 1.400048 2.4511 90)
			(size 0.0508 0.0508)
			(layers "F.Cu" "F.Mask" "F.Paste")
			(net "VR_PVDDQ_DEF_AVSP")
			(options
				(clearance outline)
				(anchor circle)
			)
			(primitives
				(gr_poly
					(pts
						(arc
							(start -0.1016 -0.254)
							(mid 0 -0.3556)
							(end 0.1016 -0.254)
						)
						(xy 0.1016 0.3556) (xy -0.1016 0.3556)
					)
					(width 0)
					(fill yes)
				)
			)
		)
		(pad "20" smd custom
			(at 1.800098 2.4511 90)
			(size 0.0508 0.0508)
			(layers "F.Cu" "F.Mask" "F.Paste")
			(net "VSENSE_PVDDQ_DEF_N")
			(options
				(clearance outline)
				(anchor circle)
			)
			(primitives
				(gr_poly
					(pts
						(arc
							(start -0.1016 -0.254)
							(mid 0 -0.3556)
							(end 0.1016 -0.254)
						)
						(xy 0.1016 0.3556) (xy -0.1016 0.3556)
					)
					(width 0)
					(fill yes)
				)
			)
		)
		(pad "21" smd custom
			(at 2.4511 1.800098 90)
			(size 0.0508 0.0508)
			(layers "F.Cu" "F.Mask" "F.Paste")
			(net "VR_PVDDQ_DEF_AIREF1")
			(options
				(clearance outline)
				(anchor circle)
			)
			(primitives
				(gr_poly
					(pts
						(arc
							(start -0.254 0.1016)
							(mid -0.3556 0)
							(end -0.254 -0.1016)
						)
						(xy 0.3556 -0.1016) (xy 0.3556 0.1016)
					)
					(width 0)
					(fill yes)
				)
			)
		)
		(pad "22" smd custom
			(at 2.4511 1.400048 90)
			(size 0.0508 0.0508)
			(layers "F.Cu" "F.Mask" "F.Paste")
			(net "ISENSE_PVDDQ_DEF_PH1_IMON")
			(options
				(clearance outline)
				(anchor circle)
			)
			(primitives
				(gr_poly
					(pts
						(arc
							(start -0.254 0.1016)
							(mid -0.3556 0)
							(end -0.254 -0.1016)
						)
						(xy 0.3556 -0.1016) (xy 0.3556 0.1016)
					)
					(width 0)
					(fill yes)
				)
			)
		)
		(pad "23" smd custom
			(at 2.4511 0.999998 90)
			(size 0.0508 0.0508)
			(layers "F.Cu" "F.Mask" "F.Paste")
			(net "VR_PVDDQ_DEF_AIREF2")
			(options
				(clearance outline)
				(anchor circle)
			)
			(primitives
				(gr_poly
					(pts
						(arc
							(start -0.254 0.1016)
							(mid -0.3556 0)
							(end -0.254 -0.1016)
						)
						(xy 0.3556 -0.1016) (xy 0.3556 0.1016)
					)
					(width 0)
					(fill yes)
				)
			)
		)
		(pad "24" smd custom
			(at 2.4511 0.599948 90)
			(size 0.0508 0.0508)
			(layers "F.Cu" "F.Mask" "F.Paste")
			(net "ISENSE_PVDDQ_DEF_PH2_IMON")
			(options
				(clearance outline)
				(anchor circle)
			)
			(primitives
				(gr_poly
					(pts
						(arc
							(start -0.254 0.1016)
							(mid -0.3556 0)
							(end -0.254 -0.1016)
						)
						(xy 0.3556 -0.1016) (xy 0.3556 0.1016)
					)
					(width 0)
					(fill yes)
				)
			)
		)
		(pad "25" smd custom
			(at 2.4511 0.199898 90)
			(size 0.0508 0.0508)
			(layers "F.Cu" "F.Mask" "F.Paste")
			(net "Net_244")
			(options
				(clearance outline)
				(anchor circle)
			)
			(primitives
				(gr_poly
					(pts
						(arc
							(start -0.254 0.1016)
							(mid -0.3556 0)
							(end -0.254 -0.1016)
						)
						(xy 0.3556 -0.1016) (xy 0.3556 0.1016)
					)
					(width 0)
					(fill yes)
				)
			)
		)
		(pad "26" smd custom
			(at 2.4511 -0.199898 90)
			(size 0.0508 0.0508)
			(layers "F.Cu" "F.Mask" "F.Paste")
			(net "Net_243")
			(options
				(clearance outline)
				(anchor circle)
			)
			(primitives
				(gr_poly
					(pts
						(arc
							(start -0.254 0.1016)
							(mid -0.3556 0)
							(end -0.254 -0.1016)
						)
						(xy 0.3556 -0.1016) (xy 0.3556 0.1016)
					)
					(width 0)
					(fill yes)
				)
			)
		)
		(pad "27" smd custom
			(at 2.4511 -0.599948 90)
			(size 0.0508 0.0508)
			(layers "F.Cu" "F.Mask" "F.Paste")
			(net "GND")
			(options
				(clearance outline)
				(anchor circle)
			)
			(primitives
				(gr_poly
					(pts
						(arc
							(start -0.254 0.1016)
							(mid -0.3556 0)
							(end -0.254 -0.1016)
						)
						(xy 0.3556 -0.1016) (xy 0.3556 0.1016)
					)
					(width 0)
					(fill yes)
				)
			)
		)
		(pad "28" smd custom
			(at 2.4511 -0.999998 90)
			(size 0.0508 0.0508)
			(layers "F.Cu" "F.Mask" "F.Paste")
			(net "Net_348")
			(options
				(clearance outline)
				(anchor circle)
			)
			(primitives
				(gr_poly
					(pts
						(arc
							(start -0.254 0.1016)
							(mid -0.3556 0)
							(end -0.254 -0.1016)
						)
						(xy 0.3556 -0.1016) (xy 0.3556 0.1016)
					)
					(width 0)
					(fill yes)
				)
			)
		)
		(pad "29" smd custom
			(at 2.4511 -1.400048 90)
			(size 0.0508 0.0508)
			(layers "F.Cu" "F.Mask" "F.Paste")
			(net "Net_229")
			(options
				(clearance outline)
				(anchor circle)
			)
			(primitives
				(gr_poly
					(pts
						(arc
							(start -0.254 0.1016)
							(mid -0.3556 0)
							(end -0.254 -0.1016)
						)
						(xy 0.3556 -0.1016) (xy 0.3556 0.1016)
					)
					(width 0)
					(fill yes)
				)
			)
		)
		(pad "30" smd custom
			(at 2.4511 -1.800098 90)
			(size 0.0508 0.0508)
			(layers "F.Cu" "F.Mask" "F.Paste")
			(net "Net_228")
			(options
				(clearance outline)
				(anchor circle)
			)
			(primitives
				(gr_poly
					(pts
						(arc
							(start -0.254 0.1016)
							(mid -0.3556 0)
							(end -0.254 -0.1016)
						)
						(xy 0.3556 -0.1016) (xy 0.3556 0.1016)
					)
					(width 0)
					(fill yes)
				)
			)
		)
		(pad "31" smd custom
			(at 1.800098 -2.4511 90)
			(size 0.0508 0.0508)
			(layers "F.Cu" "F.Mask" "F.Paste")
			(net "Net_226")
			(options
				(clearance outline)
				(anchor circle)
			)
			(primitives
				(gr_poly
					(pts
						(arc
							(start 0.1016 0.254)
							(mid 0 0.3556)
							(end -0.1016 0.254)
						)
						(xy -0.1016 -0.3556) (xy 0.1016 -0.3556)
					)
					(width 0)
					(fill yes)
				)
			)
		)
		(pad "32" smd custom
			(at 1.400048 -2.4511 90)
			(size 0.0508 0.0508)
			(layers "F.Cu" "F.Mask" "F.Paste")
			(net "GND")
			(options
				(clearance outline)
				(anchor circle)
			)
			(primitives
				(gr_poly
					(pts
						(arc
							(start 0.1016 0.254)
							(mid 0 0.3556)
							(end -0.1016 0.254)
						)
						(xy -0.1016 -0.3556) (xy 0.1016 -0.3556)
					)
					(width 0)
					(fill yes)
				)
			)
		)
		(pad "33" smd custom
			(at 0.999998 -2.4511 90)
			(size 0.0508 0.0508)
			(layers "F.Cu" "F.Mask" "F.Paste")
			(net "VR_PVDDQ_DEF_XADDR2")
			(options
				(clearance outline)
				(anchor circle)
			)
			(primitives
				(gr_poly
					(pts
						(arc
							(start 0.1016 0.254)
							(mid 0 0.3556)
							(end -0.1016 0.254)
						)
						(xy -0.1016 -0.3556) (xy 0.1016 -0.3556)
					)
					(width 0)
					(fill yes)
				)
			)
		)
		(pad "34" smd custom
			(at 0.599948 -2.4511 90)
			(size 0.0508 0.0508)
			(layers "F.Cu" "F.Mask" "F.Paste")
			(net "Net_227")
			(options
				(clearance outline)
				(anchor circle)
			)
			(primitives
				(gr_poly
					(pts
						(arc
							(start 0.1016 0.254)
							(mid 0 0.3556)
							(end -0.1016 0.254)
						)
						(xy -0.1016 -0.3556) (xy 0.1016 -0.3556)
					)
					(width 0)
					(fill yes)
				)
			)
		)
		(pad "35" smd custom
			(at 0.199898 -2.4511 90)
			(size 0.0508 0.0508)
			(layers "F.Cu" "F.Mask" "F.Paste")
			(net "A_TSENSE_PVDDQ_DEF")
			(options
				(clearance outline)
				(anchor circle)
			)
			(primitives
				(gr_poly
					(pts
						(arc
							(start 0.1016 0.254)
							(mid 0 0.3556)
							(end -0.1016 0.254)
						)
						(xy -0.1016 -0.3556) (xy 0.1016 -0.3556)
					)
					(width 0)
					(fill yes)
				)
			)
		)
		(pad "36" smd custom
			(at -0.199898 -2.4511 90)
			(size 0.0508 0.0508)
			(layers "F.Cu" "F.Mask" "F.Paste")
			(net "VR_PVDDQ_DEF_XADDR1")
			(options
				(clearance outline)
				(anchor circle)
			)
			(primitives
				(gr_poly
					(pts
						(arc
							(start 0.1016 0.254)
							(mid 0 0.3556)
							(end -0.1016 0.254)
						)
						(xy -0.1016 -0.3556) (xy 0.1016 -0.3556)
					)
					(width 0)
					(fill yes)
				)
			)
		)
		(pad "37" smd custom
			(at -0.599948 -2.4511 90)
			(size 0.0508 0.0508)
			(layers "F.Cu" "F.Mask" "F.Paste")
			(net "VR_PVDDQ_DEF_VINSEN")
			(options
				(clearance outline)
				(anchor circle)
			)
			(primitives
				(gr_poly
					(pts
						(arc
							(start 0.1016 0.254)
							(mid 0 0.3556)
							(end -0.1016 0.254)
						)
						(xy -0.1016 -0.3556) (xy 0.1016 -0.3556)
					)
					(width 0)
					(fill yes)
				)
			)
		)
		(pad "38" smd custom
			(at -0.999998 -2.4511 90)
			(size 0.0508 0.0508)
			(layers "F.Cu" "F.Mask" "F.Paste")
			(net "VR_PVDDQ_DEF_AIINSEN")
			(options
				(clearance outline)
				(anchor circle)
			)
			(primitives
				(gr_poly
					(pts
						(arc
							(start 0.1016 0.254)
							(mid 0 0.3556)
							(end -0.1016 0.254)
						)
						(xy -0.1016 -0.3556) (xy 0.1016 -0.3556)
					)
					(width 0)
					(fill yes)
				)
			)
		)
		(pad "39" smd custom
			(at -1.400048 -2.4511 90)
			(size 0.0508 0.0508)
			(layers "F.Cu" "F.Mask" "F.Paste")
			(net "VR_PVDDQ_DEF_VDD")
			(options
				(clearance outline)
				(anchor circle)
			)
			(primitives
				(gr_poly
					(pts
						(arc
							(start 0.1016 0.254)
							(mid 0 0.3556)
							(end -0.1016 0.254)
						)
						(xy -0.1016 -0.3556) (xy 0.1016 -0.3556)
					)
					(width 0)
					(fill yes)
				)
			)
		)
		(pad "40" smd custom
			(at -1.800098 -2.4511 90)
			(size 0.0508 0.0508)
			(layers "F.Cu" "F.Mask" "F.Paste")
			(net "VR_PVDDQ_DEF_VD12")
			(options
				(clearance outline)
				(anchor circle)
			)
			(primitives
				(gr_poly
					(pts
						(arc
							(start 0.1016 0.254)
							(mid 0 0.3556)
							(end -0.1016 0.254)
						)
						(xy -0.1016 -0.3556) (xy 0.1016 -0.3556)
					)
					(width 0)
					(fill yes)
				)
			)
		)
		(pad "41" smd rect
			(at 0 0 90)
			(size 3.683 3.683)
			(layers "F.Cu" "F.Mask" "F.Paste")
			(net "GND")
		)
		(zone
			(layer "F.Cu")
			(hatch none 0.5)
			(connect_pads
				(clearance 0)
			)
			(min_thickness 0.25)
			(keepout
				(tracks allowed)
				(vias not_allowed)
				(pads allowed)
				(copperpour not_allowed)
				(footprints allowed)
			)
			(placement
				(enabled no)
				(sheetname "")
			)
			(fill
				(thermal_gap 0.5)
				(thermal_bridge_width 0.5)
				(island_removal_mode 0)
			)
			(polygon
				(pts
					(xy 361.39374 -136.06907) (xy 360.93273 -136.06907) (xy 360.93273 -136.32307) (xy 361.13974 -136.32307)
					(xy 361.13974 -140.00607) (xy 357.45674 -140.00607) (xy 357.45674 -136.32307) (xy 360.930698 -136.32307)
					(xy 360.930698 -136.06907) (xy 357.20274 -136.06907) (xy 357.20274 -140.26007) (xy 361.39374 -140.26007)
				)
			)
		)
		(zone
			(layer "F.Cu")
			(hatch none 0.5)
			(connect_pads
				(clearance 0)
			)
			(min_thickness 0.25)
			(keepout
				(tracks not_allowed)
				(vias allowed)
				(pads allowed)
				(copperpour not_allowed)
				(footprints allowed)
			)
			(placement
				(enabled no)
				(sheetname "")
			)
			(fill
				(thermal_gap 0.5)
				(thermal_bridge_width 0.5)
				(island_removal_mode 0)
			)
			(polygon
				(pts
					(xy 361.39374 -136.06907) (xy 360.93273 -136.06907) (xy 360.93273 -136.32307) (xy 361.13974 -136.32307)
					(xy 361.13974 -140.00607) (xy 357.45674 -140.00607) (xy 357.45674 -136.32307) (xy 360.930698 -136.32307)
					(xy 360.930698 -136.06907) (xy 357.20274 -136.06907) (xy 357.20274 -140.26007) (xy 361.39374 -140.26007)
				)
			)
		)
	)
	(footprint ""
		(layer "F.Cu")
		(at 25.908 -75.819 -90)
		(property "Reference" "R1D35"
			(at 0 0 270)
			(layer "F.SilkS")
			(hide yes)
			(effects
				(font
					(size 1.27 1.27)
				)
			)
		)
		(property "Value" ""
			(at 0 0 270)
			(layer "F.Fab")
			(effects
				(font
					(size 1.27 1.27)
				)
			)
		)
		(duplicate_pad_numbers_are_jumpers no)
		(fp_poly
			(pts
				(xy -0.2794 -0.1016) (xy 0.2794 -0.1016) (xy 0.2794 0.9906) (xy -0.2794 0.9906)
			)
			(stroke
				(width 0)
				(type default)
			)
			(fill no)
			(layer "F.CrtYd")
		)
		(fp_line
			(start -0.2794 0.9906)
			(end 0.2794 0.9906)
			(stroke
				(width 0.1)
				(type default)
			)
			(layer "F.Fab")
		)
		(fp_line
			(start 0.2794 0.9906)
			(end 0.2794 -0.1016)
			(stroke
				(width 0.1)
				(type default)
			)
			(layer "F.Fab")
		)
		(fp_line
			(start -0.2794 -0.1016)
			(end -0.2794 0.9906)
			(stroke
				(width 0.1)
				(type default)
			)
			(layer "F.Fab")
		)
		(fp_line
			(start 0.2794 -0.1016)
			(end -0.2794 -0.1016)
			(stroke
				(width 0.1)
				(type default)
			)
			(layer "F.Fab")
		)
		(pad "1" smd rect
			(at 0 0 270)
			(size 0.508 0.508)
			(layers "F.Cu" "F.Mask" "F.Paste")
			(net "P3V3_STBY")
		)
		(pad "2" smd rect
			(at 0 0.889 270)
			(size 0.508 0.508)
			(layers "F.Cu" "F.Mask" "F.Paste")
			(net "FM_OC_DETECT_EN_N")
		)
		(zone
			(layer "F.Cu")
			(hatch none 0.5)
			(connect_pads
				(clearance 0)
			)
			(min_thickness 0.25)
			(keepout
				(tracks not_allowed)
				(vias allowed)
				(pads allowed)
				(copperpour not_allowed)
				(footprints allowed)
			)
			(placement
				(enabled no)
				(sheetname "")
			)
			(fill
				(thermal_gap 0.5)
				(thermal_bridge_width 0.5)
				(island_removal_mode 0)
			)
			(polygon
				(pts
					(xy 25.273 -76.073) (xy 25.273 -75.565) (xy 25.654 -75.565) (xy 25.654 -76.073)
				)
			)
		)
		(zone
			(layer "F.Cu")
			(hatch none 0.5)
			(connect_pads
				(clearance 0)
			)
			(min_thickness 0.25)
			(keepout
				(tracks allowed)
				(vias not_allowed)
				(pads allowed)
				(copperpour not_allowed)
				(footprints allowed)
			)
			(placement
				(enabled no)
				(sheetname "")
			)
			(fill
				(thermal_gap 0.5)
				(thermal_bridge_width 0.5)
				(island_removal_mode 0)
			)
			(polygon
				(pts
					(xy 25.654 -76.073) (xy 25.654 -75.565) (xy 25.273 -75.565) (xy 25.273 -76.073)
				)
			)
		)
	)
	(footprint ""
		(layer "F.Cu")
		(at 14.478 -86.741 180)
		(property "Reference" "R1D6"
			(at 0 0 180)
			(layer "F.SilkS")
			(hide yes)
			(effects
				(font
					(size 1.27 1.27)
				)
			)
		)
		(property "Value" ""
			(at 0 0 180)
			(layer "F.Fab")
			(effects
				(font
					(size 1.27 1.27)
				)
			)
		)
		(duplicate_pad_numbers_are_jumpers no)
		(fp_rect
			(start 0.2794 -0.1016)
			(end -0.2794 0.9906)
			(stroke
				(width 0)
				(type default)
			)
			(fill no)
			(layer "F.CrtYd")
		)
		(fp_line
			(start 0.2794 0.9906)
			(end 0.2794 -0.1016)
			(stroke
				(width 0.1)
				(type default)
			)
			(layer "F.Fab")
		)
		(fp_line
			(start 0.2794 -0.1016)
			(end -0.2794 -0.1016)
			(stroke
				(width 0.1)
				(type default)
			)
			(layer "F.Fab")
		)
		(fp_line
			(start -0.2794 0.9906)
			(end 0.2794 0.9906)
			(stroke
				(width 0.1)
				(type default)
			)
			(layer "F.Fab")
		)
		(fp_line
			(start -0.2794 -0.1016)
			(end -0.2794 0.9906)
			(stroke
				(width 0.1)
				(type default)
			)
			(layer "F.Fab")
		)
		(pad "1" smd rect
			(at 0 0 180)
			(size 0.508 0.508)
			(layers "F.Cu" "F.Mask" "F.Paste")
			(net "P3V3_STBY")
		)
		(pad "2" smd rect
			(at 0 0.889 180)
			(size 0.508 0.508)
			(layers "F.Cu" "F.Mask" "F.Paste")
			(net "IRQ_PVCCIN_CPU1_VRHOT_LVC3_R_N")
		)
		(zone
			(layer "F.Cu")
			(hatch none 0.5)
			(connect_pads
				(clearance 0)
			)
			(min_thickness 0.25)
			(keepout
				(tracks allowed)
				(vias not_allowed)
				(pads allowed)
				(copperpour not_allowed)
				(footprints allowed)
			)
			(placement
				(enabled no)
				(sheetname "")
			)
			(fill
				(thermal_gap 0.5)
				(thermal_bridge_width 0.5)
				(island_removal_mode 0)
			)
			(polygon
				(pts
					(xy 14.224 -86.995) (xy 14.732 -86.995) (xy 14.732 -87.376) (xy 14.224 -87.376)
				)
			)
		)
		(zone
			(layer "F.Cu")
			(hatch none 0.5)
			(connect_pads
				(clearance 0)
			)
			(min_thickness 0.25)
			(keepout
				(tracks not_allowed)
				(vias allowed)
				(pads allowed)
				(copperpour not_allowed)
				(footprints allowed)
			)
			(placement
				(enabled no)
				(sheetname "")
			)
			(fill
				(thermal_gap 0.5)
				(thermal_bridge_width 0.5)
				(island_removal_mode 0)
			)
			(polygon
				(pts
					(xy 14.224 -86.995) (xy 14.732 -86.995) (xy 14.732 -87.376) (xy 14.224 -87.376)
				)
			)
		)
	)
	(footprint ""
		(layer "F.Cu")
		(at 478.540572 -12.462256)
		(property "Reference" "R9G24"
			(at -0.8382 -0.67818 0)
			(unlocked yes)
			(layer "F.SilkS")
			(effects
				(font
					(size 0.4064 0.254)
					(thickness 0.1524)
				)
				(justify left)
			)
		)
		(property "Value" ""
			(at 0 0 0)
			(layer "F.Fab")
			(effects
				(font
					(size 1.27 1.27)
				)
			)
		)
		(duplicate_pad_numbers_are_jumpers no)
		(fp_poly
			(pts
				(xy -0.2794 -0.1016) (xy 0.2794 -0.1016) (xy 0.2794 0.9906) (xy -0.2794 0.9906)
			)
			(stroke
				(width 0)
				(type default)
			)
			(fill no)
			(layer "F.CrtYd")
		)
		(fp_line
			(start -0.2794 -0.1016)
			(end -0.2794 0.9906)
			(stroke
				(width 0.1)
				(type default)
			)
			(layer "F.Fab")
		)
		(fp_line
			(start -0.2794 0.9906)
			(end 0.2794 0.9906)
			(stroke
				(width 0.1)
				(type default)
			)
			(layer "F.Fab")
		)
		(fp_line
			(start 0.2794 -0.1016)
			(end -0.2794 -0.1016)
			(stroke
				(width 0.1)
				(type default)
			)
			(layer "F.Fab")
		)
		(fp_line
			(start 0.2794 0.9906)
			(end 0.2794 -0.1016)
			(stroke
				(width 0.1)
				(type default)
			)
			(layer "F.Fab")
		)
		(pad "1" smd rect
			(at 0 0)
			(size 0.508 0.508)
			(layers "F.Cu" "F.Mask" "F.Paste")
			(net "NIC_MDI_SPRV_RJ45_0_DP")
		)
		(pad "2" smd rect
			(at 0 0.889)
			(size 0.508 0.508)
			(layers "F.Cu" "F.Mask" "F.Paste")
			(net "NIC_MDI_SPRV_RJ45_0_R_DP")
		)
		(zone
			(layer "F.Cu")
			(hatch none 0.5)
			(connect_pads
				(clearance 0)
			)
			(min_thickness 0.25)
			(keepout
				(tracks allowed)
				(vias not_allowed)
				(pads allowed)
				(copperpour not_allowed)
				(footprints allowed)
			)
			(placement
				(enabled no)
				(sheetname "")
			)
			(fill
				(thermal_gap 0.5)
				(thermal_bridge_width 0.5)
				(island_removal_mode 0)
			)
			(polygon
				(pts
					(xy 478.286572 -12.208256) (xy 478.794572 -12.208256) (xy 478.794572 -11.827256) (xy 478.286572 -11.827256)
				)
			)
		)
		(zone
			(layer "F.Cu")
			(hatch none 0.5)
			(connect_pads
				(clearance 0)
			)
			(min_thickness 0.25)
			(keepout
				(tracks not_allowed)
				(vias allowed)
				(pads allowed)
				(copperpour not_allowed)
				(footprints allowed)
			)
			(placement
				(enabled no)
				(sheetname "")
			)
			(fill
				(thermal_gap 0.5)
				(thermal_bridge_width 0.5)
				(island_removal_mode 0)
			)
			(polygon
				(pts
					(xy 478.286572 -11.827256) (xy 478.794572 -11.827256) (xy 478.794572 -12.208256) (xy 478.286572 -12.208256)
				)
			)
		)
	)
	(footprint ""
		(layer "F.Cu")
		(at 420.751 -22.733)
		(property "Reference" "R1U14"
			(at 0 0 0)
			(layer "F.SilkS")
			(hide yes)
			(effects
				(font
					(size 1.27 1.27)
				)
			)
		)
		(property "Value" ""
			(at 0 0 0)
			(layer "F.Fab")
			(effects
				(font
					(size 1.27 1.27)
				)
			)
		)
		(duplicate_pad_numbers_are_jumpers no)
		(fp_poly
			(pts
				(xy -0.2794 -0.1016) (xy 0.2794 -0.1016) (xy 0.2794 0.9906) (xy -0.2794 0.9906)
			)
			(stroke
				(width 0)
				(type default)
			)
			(fill no)
			(layer "F.CrtYd")
		)
		(fp_line
			(start -0.2794 -0.1016)
			(end -0.2794 0.9906)
			(stroke
				(width 0.1)
				(type default)
			)
			(layer "F.Fab")
		)
		(fp_line
			(start -0.2794 0.9906)
			(end 0.2794 0.9906)
			(stroke
				(width 0.1)
				(type default)
			)
			(layer "F.Fab")
		)
		(fp_line
			(start 0.2794 -0.1016)
			(end -0.2794 -0.1016)
			(stroke
				(width 0.1)
				(type default)
			)
			(layer "F.Fab")
		)
		(fp_line
			(start 0.2794 0.9906)
			(end 0.2794 -0.1016)
			(stroke
				(width 0.1)
				(type default)
			)
			(layer "F.Fab")
		)
		(pad "1" smd rect
			(at 0 0)
			(size 0.508 0.508)
			(layers "F.Cu" "F.Mask" "F.Paste")
			(net "SGPIO_BMC_CLK_R")
		)
		(pad "2" smd rect
			(at 0 0.889)
			(size 0.508 0.508)
			(layers "F.Cu" "F.Mask" "F.Paste")
			(net "SGPIO_BMC_CLK")
		)
		(zone
			(layer "F.Cu")
			(hatch none 0.5)
			(connect_pads
				(clearance 0)
			)
			(min_thickness 0.25)
			(keepout
				(tracks allowed)
				(vias not_allowed)
				(pads allowed)
				(copperpour not_allowed)
				(footprints allowed)
			)
			(placement
				(enabled no)
				(sheetname "")
			)
			(fill
				(thermal_gap 0.5)
				(thermal_bridge_width 0.5)
				(island_removal_mode 0)
			)
			(polygon
				(pts
					(xy 420.497 -22.479) (xy 421.005 -22.479) (xy 421.005 -22.098) (xy 420.497 -22.098)
				)
			)
		)
		(zone
			(layer "F.Cu")
			(hatch none 0.5)
			(connect_pads
				(clearance 0)
			)
			(min_thickness 0.25)
			(keepout
				(tracks not_allowed)
				(vias allowed)
				(pads allowed)
				(copperpour not_allowed)
				(footprints allowed)
			)
			(placement
				(enabled no)
				(sheetname "")
			)
			(fill
				(thermal_gap 0.5)
				(thermal_bridge_width 0.5)
				(island_removal_mode 0)
			)
			(polygon
				(pts
					(xy 420.497 -22.098) (xy 421.005 -22.098) (xy 421.005 -22.479) (xy 420.497 -22.479)
				)
			)
		)
	)
	(footprint ""
		(layer "F.Cu")
		(at 20.447 -80.90408 180)
		(property "Reference" "R1D23"
			(at 0 0 180)
			(layer "F.SilkS")
			(hide yes)
			(effects
				(font
					(size 1.27 1.27)
				)
			)
		)
		(property "Value" ""
			(at 0 0 180)
			(layer "F.Fab")
			(effects
				(font
					(size 1.27 1.27)
				)
			)
		)
		(duplicate_pad_numbers_are_jumpers no)
		(fp_poly
			(pts
				(xy -0.2794 -0.1016) (xy 0.2794 -0.1016) (xy 0.2794 0.9906) (xy -0.2794 0.9906)
			)
			(stroke
				(width 0)
				(type default)
			)
			(fill no)
			(layer "F.CrtYd")
		)
		(fp_line
			(start 0.2794 0.9906)
			(end 0.2794 -0.1016)
			(stroke
				(width 0.1)
				(type default)
			)
			(layer "F.Fab")
		)
		(fp_line
			(start 0.2794 -0.1016)
			(end -0.2794 -0.1016)
			(stroke
				(width 0.1)
				(type default)
			)
			(layer "F.Fab")
		)
		(fp_line
			(start -0.2794 0.9906)
			(end 0.2794 0.9906)
			(stroke
				(width 0.1)
				(type default)
			)
			(layer "F.Fab")
		)
		(fp_line
			(start -0.2794 -0.1016)
			(end -0.2794 0.9906)
			(stroke
				(width 0.1)
				(type default)
			)
			(layer "F.Fab")
		)
		(pad "1" smd rect
			(at 0 0 180)
			(size 0.508 0.508)
			(layers "F.Cu" "F.Mask" "F.Paste")
			(net "P3V3_STBY")
		)
		(pad "2" smd rect
			(at 0 0.889 180)
			(size 0.508 0.508)
			(layers "F.Cu" "F.Mask" "F.Paste")
			(net "IRQ_OC_DETECT_N")
		)
		(zone
			(layer "F.Cu")
			(hatch none 0.5)
			(connect_pads
				(clearance 0)
			)
			(min_thickness 0.25)
			(keepout
				(tracks not_allowed)
				(vias allowed)
				(pads allowed)
				(copperpour not_allowed)
				(footprints allowed)
			)
			(placement
				(enabled no)
				(sheetname "")
			)
			(fill
				(thermal_gap 0.5)
				(thermal_bridge_width 0.5)
				(island_removal_mode 0)
			)
			(polygon
				(pts
					(xy 20.701 -81.53908) (xy 20.193 -81.53908) (xy 20.193 -81.15808) (xy 20.701 -81.15808)
				)
			)
		)
		(zone
			(layer "F.Cu")
			(hatch none 0.5)
			(connect_pads
				(clearance 0)
			)
			(min_thickness 0.25)
			(keepout
				(tracks allowed)
				(vias not_allowed)
				(pads allowed)
				(copperpour not_allowed)
				(footprints allowed)
			)
			(placement
				(enabled no)
				(sheetname "")
			)
			(fill
				(thermal_gap 0.5)
				(thermal_bridge_width 0.5)
				(island_removal_mode 0)
			)
			(polygon
				(pts
					(xy 20.701 -81.15808) (xy 20.193 -81.15808) (xy 20.193 -81.53908) (xy 20.701 -81.53908)
				)
			)
		)
	)
	(footprint ""
		(layer "F.Cu")
		(at 403.112986 -81.548986 -90)
		(property "Reference" "C2P9"
			(at 0 0 270)
			(layer "F.SilkS")
			(hide yes)
			(effects
				(font
					(size 1.27 1.27)
				)
			)
		)
		(property "Value" ""
			(at 0 0 270)
			(layer "F.Fab")
			(effects
				(font
					(size 1.27 1.27)
				)
			)
		)
		(duplicate_pad_numbers_are_jumpers no)
		(fp_poly
			(pts
				(xy 0.3048 -0.1016) (xy 0.3048 0.9906) (xy -0.3048 0.9906) (xy -0.3048 -0.1016)
			)
			(stroke
				(width 0)
				(type default)
			)
			(fill no)
			(layer "F.CrtYd")
		)
		(fp_line
			(start -0.3048 0.9906)
			(end 0.3048 0.9906)
			(stroke
				(width 0.1)
				(type default)
			)
			(layer "F.Fab")
		)
		(fp_line
			(start 0.3048 0.9906)
			(end 0.3048 -0.1016)
			(stroke
				(width 0.1)
				(type default)
			)
			(layer "F.Fab")
		)
		(fp_line
			(start -0.3048 -0.1016)
			(end -0.3048 0.9906)
			(stroke
				(width 0.1)
				(type default)
			)
			(layer "F.Fab")
		)
		(fp_line
			(start 0.3048 -0.1016)
			(end -0.3048 -0.1016)
			(stroke
				(width 0.1)
				(type default)
			)
			(layer "F.Fab")
		)
		(pad "1" smd rect
			(at 0 0 270)
			(size 0.508 0.508)
			(layers "F.Cu" "F.Mask" "F.Paste")
			(net "P3V3_STBY")
		)
		(pad "2" smd rect
			(at 0 0.889 270)
			(size 0.508 0.508)
			(layers "F.Cu" "F.Mask" "F.Paste")
			(net "GND")
		)
		(zone
			(layer "F.Cu")
			(hatch none 0.5)
			(connect_pads
				(clearance 0)
			)
			(min_thickness 0.25)
			(keepout
				(tracks not_allowed)
				(vias allowed)
				(pads allowed)
				(copperpour not_allowed)
				(footprints allowed)
			)
			(placement
				(enabled no)
				(sheetname "")
			)
			(fill
				(thermal_gap 0.5)
				(thermal_bridge_width 0.5)
				(island_removal_mode 0)
			)
			(polygon
				(pts
					(xy 402.477986 -81.802986) (xy 402.477986 -81.294986) (xy 402.858986 -81.294986) (xy 402.858986 -81.802986)
				)
			)
		)
		(zone
			(layer "F.Cu")
			(hatch none 0.5)
			(connect_pads
				(clearance 0)
			)
			(min_thickness 0.25)
			(keepout
				(tracks allowed)
				(vias not_allowed)
				(pads allowed)
				(copperpour not_allowed)
				(footprints allowed)
			)
			(placement
				(enabled no)
				(sheetname "")
			)
			(fill
				(thermal_gap 0.5)
				(thermal_bridge_width 0.5)
				(island_removal_mode 0)
			)
			(polygon
				(pts
					(xy 402.858986 -81.802986) (xy 402.858986 -81.294986) (xy 402.477986 -81.294986) (xy 402.477986 -81.802986)
				)
			)
		)
	)
	(footprint ""
		(layer "F.Cu")
		(at 181.1147 -75.68565 -90)
		(property "Reference" "C4D19"
			(at 0 0 270)
			(layer "F.SilkS")
			(hide yes)
			(effects
				(font
					(size 1.27 1.27)
				)
			)
		)
		(property "Value" ""
			(at 0 0 270)
			(layer "F.Fab")
			(effects
				(font
					(size 1.27 1.27)
				)
			)
		)
		(duplicate_pad_numbers_are_jumpers no)
		(fp_rect
			(start 0.3048 0.9906)
			(end -0.3048 -0.1016)
			(stroke
				(width 0)
				(type default)
			)
			(fill no)
			(layer "F.CrtYd")
		)
		(fp_line
			(start -0.3048 0.9906)
			(end 0.3048 0.9906)
			(stroke
				(width 0.1)
				(type default)
			)
			(layer "F.Fab")
		)
		(fp_line
			(start 0.3048 0.9906)
			(end 0.3048 -0.1016)
			(stroke
				(width 0.1)
				(type default)
			)
			(layer "F.Fab")
		)
		(fp_line
			(start -0.3048 -0.1016)
			(end -0.3048 0.9906)
			(stroke
				(width 0.1)
				(type default)
			)
			(layer "F.Fab")
		)
		(fp_line
			(start 0.3048 -0.1016)
			(end -0.3048 -0.1016)
			(stroke
				(width 0.1)
				(type default)
			)
			(layer "F.Fab")
		)
		(pad "1" smd rect
			(at 0 0 270)
			(size 0.508 0.508)
			(layers "F.Cu" "F.Mask" "F.Paste")
			(net "VR_PVCCIN_CPU0_VDD")
		)
		(pad "2" smd rect
			(at 0 0.889 270)
			(size 0.508 0.508)
			(layers "F.Cu" "F.Mask" "F.Paste")
			(net "GND")
		)
		(zone
			(layer "F.Cu")
			(hatch none 0.5)
			(connect_pads
				(clearance 0)
			)
			(min_thickness 0.25)
			(keepout
				(tracks allowed)
				(vias not_allowed)
				(pads allowed)
				(copperpour not_allowed)
				(footprints allowed)
			)
			(placement
				(enabled no)
				(sheetname "")
			)
			(fill
				(thermal_gap 0.5)
				(thermal_bridge_width 0.5)
				(island_removal_mode 0)
			)
			(polygon
				(pts
					(xy 180.4797 -75.43165) (xy 180.8607 -75.43165) (xy 180.8607 -75.93965) (xy 180.4797 -75.93965)
				)
			)
		)
		(zone
			(layer "F.Cu")
			(hatch none 0.5)
			(connect_pads
				(clearance 0)
			)
			(min_thickness 0.25)
			(keepout
				(tracks not_allowed)
				(vias allowed)
				(pads allowed)
				(copperpour not_allowed)
				(footprints allowed)
			)
			(placement
				(enabled no)
				(sheetname "")
			)
			(fill
				(thermal_gap 0.5)
				(thermal_bridge_width 0.5)
				(island_removal_mode 0)
			)
			(polygon
				(pts
					(xy 180.4797 -75.43165) (xy 180.8607 -75.43165) (xy 180.8607 -75.93965) (xy 180.4797 -75.93965)
				)
			)
		)
	)
	(footprint ""
		(layer "F.Cu")
		(at 163.592764 -70.694296 -90)
		(property "Reference" "R3D21"
			(at 0 0 270)
			(layer "F.SilkS")
			(hide yes)
			(effects
				(font
					(size 1.27 1.27)
				)
			)
		)
		(property "Value" ""
			(at 0 0 270)
			(layer "F.Fab")
			(effects
				(font
					(size 1.27 1.27)
				)
			)
		)
		(duplicate_pad_numbers_are_jumpers no)
		(fp_poly
			(pts
				(xy -0.2794 -0.1016) (xy 0.2794 -0.1016) (xy 0.2794 0.9906) (xy -0.2794 0.9906)
			)
			(stroke
				(width 0)
				(type default)
			)
			(fill no)
			(layer "F.CrtYd")
		)
		(fp_line
			(start -0.2794 0.9906)
			(end 0.2794 0.9906)
			(stroke
				(width 0.1)
				(type default)
			)
			(layer "F.Fab")
		)
		(fp_line
			(start 0.2794 0.9906)
			(end 0.2794 -0.1016)
			(stroke
				(width 0.1)
				(type default)
			)
			(layer "F.Fab")
		)
		(fp_line
			(start -0.2794 -0.1016)
			(end -0.2794 0.9906)
			(stroke
				(width 0.1)
				(type default)
			)
			(layer "F.Fab")
		)
		(fp_line
			(start 0.2794 -0.1016)
			(end -0.2794 -0.1016)
			(stroke
				(width 0.1)
				(type default)
			)
			(layer "F.Fab")
		)
		(pad "1" smd rect
			(at 0 0 270)
			(size 0.508 0.508)
			(layers "F.Cu" "F.Mask" "F.Paste")
			(net "PVDDQ_GHJ")
		)
		(pad "2" smd rect
			(at 0 0.889 270)
			(size 0.508 0.508)
			(layers "F.Cu" "F.Mask" "F.Paste")
			(net "PWRGD_CPU1_DRAMPWROK_GHJ_G")
		)
		(zone
			(layer "F.Cu")
			(hatch none 0.5)
			(connect_pads
				(clearance 0)
			)
			(min_thickness 0.25)
			(keepout
				(tracks not_allowed)
				(vias allowed)
				(pads allowed)
				(copperpour not_allowed)
				(footprints allowed)
			)
			(placement
				(enabled no)
				(sheetname "")
			)
			(fill
				(thermal_gap 0.5)
				(thermal_bridge_width 0.5)
				(island_removal_mode 0)
			)
			(polygon
				(pts
					(xy 162.957764 -70.948296) (xy 162.957764 -70.440296) (xy 163.338764 -70.440296) (xy 163.338764 -70.948296)
				)
			)
		)
		(zone
			(layer "F.Cu")
			(hatch none 0.5)
			(connect_pads
				(clearance 0)
			)
			(min_thickness 0.25)
			(keepout
				(tracks allowed)
				(vias not_allowed)
				(pads allowed)
				(copperpour not_allowed)
				(footprints allowed)
			)
			(placement
				(enabled no)
				(sheetname "")
			)
			(fill
				(thermal_gap 0.5)
				(thermal_bridge_width 0.5)
				(island_removal_mode 0)
			)
			(polygon
				(pts
					(xy 163.338764 -70.948296) (xy 163.338764 -70.440296) (xy 162.957764 -70.440296) (xy 162.957764 -70.948296)
				)
			)
		)
	)
	(footprint ""
		(layer "F.Cu")
		(at 398.768316 -157.664658 -90)
		(property "Reference" "RF23"
			(at -0.8382 -0.67818 270)
			(unlocked yes)
			(layer "F.SilkS")
			(effects
				(font
					(size 0.4064 0.254)
					(thickness 0.1524)
				)
				(justify left)
			)
		)
		(property "Value" ""
			(at 0 0 270)
			(layer "F.Fab")
			(effects
				(font
					(size 1.27 1.27)
				)
			)
		)
		(duplicate_pad_numbers_are_jumpers no)
		(fp_poly
			(pts
				(xy -0.2794 -0.1016) (xy 0.2794 -0.1016) (xy 0.2794 0.9906) (xy -0.2794 0.9906)
			)
			(stroke
				(width 0)
				(type default)
			)
			(fill no)
			(layer "F.CrtYd")
		)
		(fp_line
			(start -0.2794 0.9906)
			(end 0.2794 0.9906)
			(stroke
				(width 0.1)
				(type default)
			)
			(layer "F.Fab")
		)
		(fp_line
			(start 0.2794 0.9906)
			(end 0.2794 -0.1016)
			(stroke
				(width 0.1)
				(type default)
			)
			(layer "F.Fab")
		)
		(fp_line
			(start -0.2794 -0.1016)
			(end -0.2794 0.9906)
			(stroke
				(width 0.1)
				(type default)
			)
			(layer "F.Fab")
		)
		(fp_line
			(start 0.2794 -0.1016)
			(end -0.2794 -0.1016)
			(stroke
				(width 0.1)
				(type default)
			)
			(layer "F.Fab")
		)
		(pad "1" smd rect
			(at 0 0 270)
			(size 0.508 0.508)
			(layers "F.Cu" "F.Mask" "F.Paste")
			(net "VR_PVNN_PCH_AIREF1")
		)
		(pad "2" smd rect
			(at 0 0.889 270)
			(size 0.508 0.508)
			(layers "F.Cu" "F.Mask" "F.Paste")
			(net "ISENSE_PVNN_PCH_PH1_IMON")
		)
		(zone
			(layer "F.Cu")
			(hatch none 0.5)
			(connect_pads
				(clearance 0)
			)
			(min_thickness 0.25)
			(keepout
				(tracks not_allowed)
				(vias allowed)
				(pads allowed)
				(copperpour not_allowed)
				(footprints allowed)
			)
			(placement
				(enabled no)
				(sheetname "")
			)
			(fill
				(thermal_gap 0.5)
				(thermal_bridge_width 0.5)
				(island_removal_mode 0)
			)
			(polygon
				(pts
					(xy 398.133316 -157.918658) (xy 398.133316 -157.410658) (xy 398.514316 -157.410658) (xy 398.514316 -157.918658)
				)
			)
		)
		(zone
			(layer "F.Cu")
			(hatch none 0.5)
			(connect_pads
				(clearance 0)
			)
			(min_thickness 0.25)
			(keepout
				(tracks allowed)
				(vias not_allowed)
				(pads allowed)
				(copperpour not_allowed)
				(footprints allowed)
			)
			(placement
				(enabled no)
				(sheetname "")
			)
			(fill
				(thermal_gap 0.5)
				(thermal_bridge_width 0.5)
				(island_removal_mode 0)
			)
			(polygon
				(pts
					(xy 398.514316 -157.918658) (xy 398.514316 -157.410658) (xy 398.133316 -157.410658) (xy 398.133316 -157.918658)
				)
			)
		)
	)
	(footprint ""
		(layer "F.Cu")
		(at 210.312 -106.045)
		(property "Reference" ""
			(at 0 0 0)
			(layer "F.SilkS")
			(hide yes)
			(effects
				(font
					(size 1.27 1.27)
				)
			)
		)
		(property "Value" ""
			(at 0 0 0)
			(layer "F.Fab")
			(effects
				(font
					(size 1.27 1.27)
				)
			)
		)
		(duplicate_pad_numbers_are_jumpers no)
		(fp_poly
			(pts
				(arc
					(start 2.032 0)
					(mid -2.032 0)
					(end 2.032 0)
				)
			)
			(stroke
				(width 0)
				(type default)
			)
			(fill no)
			(layer "F.CrtYd")
		)
		(pad "1" smd circle
			(at 0 0)
			(size 1.016 1.016)
			(layers "F.Cu" "F.Mask" "F.Paste")
			(net "Net_394")
		)
		(zone
			(layer "F.Cu")
			(hatch none 0.5)
			(connect_pads
				(clearance 0)
			)
			(min_thickness 0.25)
			(keepout
				(tracks not_allowed)
				(vias allowed)
				(pads allowed)
				(copperpour not_allowed)
				(footprints allowed)
			)
			(placement
				(enabled no)
				(sheetname "")
			)
			(fill
				(thermal_gap 0.5)
				(thermal_bridge_width 0.5)
				(island_removal_mode 0)
			)
			(polygon
				(pts
					(arc
						(start 211.836 -106.045)
						(mid 208.788 -106.045)
						(end 211.836 -106.045)
					)
				)
			)
		)
		(zone
			(layers "F.Cu" "B.Cu" "In1.Cu" "In2.Cu" "In3.Cu" "In4.Cu" "In5.Cu" "In6.Cu"
				"In7.Cu" "In8.Cu" "In9.Cu" "In10.Cu" "In11.Cu" "In12.Cu"
			)
			(hatch none 0.5)
			(connect_pads
				(clearance 0)
			)
			(min_thickness 0.25)
			(keepout
				(tracks allowed)
				(vias not_allowed)
				(pads allowed)
				(copperpour not_allowed)
				(footprints allowed)
			)
			(placement
				(enabled no)
				(sheetname "")
			)
			(fill
				(thermal_gap 0.5)
				(thermal_bridge_width 0.5)
				(island_removal_mode 0)
			)
			(polygon
				(pts
					(arc
						(start 211.836 -106.045)
						(mid 208.788 -106.045)
						(end 211.836 -106.045)
					)
				)
			)
		)
	)
	(footprint ""
		(layer "F.Cu")
		(at 39.1414 -77.7494 -90)
		(property "Reference" "CT20"
			(at -0.8382 -0.67818 270)
			(unlocked yes)
			(layer "F.SilkS")
			(effects
				(font
					(size 0.4064 0.254)
					(thickness 0.1524)
				)
				(justify left)
			)
		)
		(property "Value" ""
			(at 0 0 270)
			(layer "F.Fab")
			(effects
				(font
					(size 1.27 1.27)
				)
			)
		)
		(duplicate_pad_numbers_are_jumpers no)
		(fp_poly
			(pts
				(xy 0.3048 -0.1016) (xy 0.3048 0.9906) (xy -0.3048 0.9906) (xy -0.3048 -0.1016)
			)
			(stroke
				(width 0)
				(type default)
			)
			(fill no)
			(layer "F.CrtYd")
		)
		(fp_line
			(start -0.3048 0.9906)
			(end 0.3048 0.9906)
			(stroke
				(width 0.1)
				(type default)
			)
			(layer "F.Fab")
		)
		(fp_line
			(start 0.3048 0.9906)
			(end 0.3048 -0.1016)
			(stroke
				(width 0.1)
				(type default)
			)
			(layer "F.Fab")
		)
		(fp_line
			(start -0.3048 -0.1016)
			(end -0.3048 0.9906)
			(stroke
				(width 0.1)
				(type default)
			)
			(layer "F.Fab")
		)
		(fp_line
			(start 0.3048 -0.1016)
			(end -0.3048 -0.1016)
			(stroke
				(width 0.1)
				(type default)
			)
			(layer "F.Fab")
		)
		(pad "1" smd rect
			(at 0 0 270)
			(size 0.508 0.508)
			(layers "F.Cu" "F.Mask" "F.Paste")
			(net "VR_PVCCIN_CPU1_PHASE4")
		)
		(pad "2" smd rect
			(at 0 0.889 270)
			(size 0.508 0.508)
			(layers "F.Cu" "F.Mask" "F.Paste")
			(net "VR_PVCCIN_CPU1_PHASE4_RC")
		)
		(zone
			(layer "F.Cu")
			(hatch none 0.5)
			(connect_pads
				(clearance 0)
			)
			(min_thickness 0.25)
			(keepout
				(tracks not_allowed)
				(vias allowed)
				(pads allowed)
				(copperpour not_allowed)
				(footprints allowed)
			)
			(placement
				(enabled no)
				(sheetname "")
			)
			(fill
				(thermal_gap 0.5)
				(thermal_bridge_width 0.5)
				(island_removal_mode 0)
			)
			(polygon
				(pts
					(xy 38.5064 -78.0034) (xy 38.5064 -77.4954) (xy 38.8874 -77.4954) (xy 38.8874 -78.0034)
				)
			)
		)
		(zone
			(layer "F.Cu")
			(hatch none 0.5)
			(connect_pads
				(clearance 0)
			)
			(min_thickness 0.25)
			(keepout
				(tracks allowed)
				(vias not_allowed)
				(pads allowed)
				(copperpour not_allowed)
				(footprints allowed)
			)
			(placement
				(enabled no)
				(sheetname "")
			)
			(fill
				(thermal_gap 0.5)
				(thermal_bridge_width 0.5)
				(island_removal_mode 0)
			)
			(polygon
				(pts
					(xy 38.8874 -78.0034) (xy 38.8874 -77.4954) (xy 38.5064 -77.4954) (xy 38.5064 -78.0034)
				)
			)
		)
	)
	(footprint ""
		(layer "F.Cu")
		(at 21.082 -62.9158 180)
		(property "Reference" "EU1E1"
			(at 2.921 5.25653 0)
			(unlocked yes)
			(layer "F.SilkS")
			(effects
				(font
					(size 0.7874 0.5842)
					(thickness 0.1524)
				)
			)
		)
		(property "Value" ""
			(at 0 0 180)
			(layer "F.Fab")
			(effects
				(font
					(size 1.27 1.27)
				)
			)
		)
		(duplicate_pad_numbers_are_jumpers no)
		(fp_line
			(start 4.8006 4.5593)
			(end 4.8006 4.445254)
			(stroke
				(width 0.1524)
				(type default)
			)
			(layer "F.SilkS")
		)
		(fp_line
			(start 4.8006 -0.7493)
			(end 4.8006 -0.635254)
			(stroke
				(width 0.1524)
				(type default)
			)
			(layer "F.SilkS")
		)
		(fp_line
			(start 0.4064 4.5593)
			(end 4.8006 4.5593)
			(stroke
				(width 0.1524)
				(type default)
			)
			(layer "F.SilkS")
		)
		(fp_line
			(start 0.4064 4.445254)
			(end 0.4064 4.5593)
			(stroke
				(width 0.1524)
				(type default)
			)
			(layer "F.SilkS")
		)
		(fp_line
			(start 0.4064 -0.635254)
			(end 0.4064 -0.7493)
			(stroke
				(width 0.1524)
				(type default)
			)
			(layer "F.SilkS")
		)
		(fp_line
			(start 0.4064 -0.7493)
			(end 4.8006 -0.7493)
			(stroke
				(width 0.1524)
				(type default)
			)
			(layer "F.SilkS")
		)
		(fp_circle
			(center -0.682244 -0.831342)
			(end -0.809244 -0.831342)
			(stroke
				(width 0.254)
				(type default)
			)
			(fill no)
			(layer "F.SilkS")
		)
		(fp_rect
			(start 4.8006 4.5593)
			(end 0.4064 -0.7493)
			(stroke
				(width 0)
				(type default)
			)
			(fill no)
			(layer "F.CrtYd")
		)
		(fp_line
			(start 4.8006 4.5593)
			(end 0.4064 4.5593)
			(stroke
				(width 0.1)
				(type default)
			)
			(layer "F.Fab")
		)
		(fp_line
			(start 4.8006 -0.7493)
			(end 4.8006 4.5593)
			(stroke
				(width 0.1)
				(type default)
			)
			(layer "F.Fab")
		)
		(fp_line
			(start 0.4064 4.5593)
			(end 0.4064 -0.7493)
			(stroke
				(width 0.1)
				(type default)
			)
			(layer "F.Fab")
		)
		(fp_line
			(start 0.4064 -0.7493)
			(end 4.8006 -0.7493)
			(stroke
				(width 0.1)
				(type default)
			)
			(layer "F.Fab")
		)
		(fp_circle
			(center -1.076706 -0.704342)
			(end -1.203706 -0.704342)
			(stroke
				(width 0.635)
				(type default)
			)
			(fill no)
			(layer "F.Fab")
		)
		(pad "1" smd rect
			(at 0 0 180)
			(size 1.651 0.508)
			(layers "F.Cu" "F.Mask" "F.Paste")
			(net "P12V_STBY")
		)
		(pad "2" smd rect
			(at 0 1.27 180)
			(size 1.651 0.508)
			(layers "F.Cu" "F.Mask" "F.Paste")
			(net "P12V_STBY")
		)
		(pad "3" smd rect
			(at 0 2.54 180)
			(size 1.651 0.508)
			(layers "F.Cu" "F.Mask" "F.Paste")
			(net "P12V_STBY")
		)
		(pad "4" smd rect
			(at 0 3.81 180)
			(size 1.651 0.508)
			(layers "F.Cu" "F.Mask" "F.Paste")
			(net "A_HSC_GATE3_R")
		)
		(pad "5" smd custom
			(at 3.937 1.905 180)
			(size 1.04775 1.04775)
			(layers "F.Cu" "F.Mask" "F.Paste")
			(net "P12V_MB0_SW")
			(options
				(clearance outline)
				(anchor circle)
			)
			(primitives
				(gr_poly
					(pts
						(xy -2.0955 -1.651) (xy -2.0955 1.651) (xy 0.4445 1.651) (xy 0.4445 2.2098) (xy 2.0955 2.2098)
						(xy 2.0955 -2.2098) (xy 0.4445 -2.2098) (xy 0.4445 -1.651)
					)
					(width 0)
					(fill yes)
				)
			)
		)
	)
	(footprint ""
		(layer "F.Cu")
		(at 159.87522 -125.1077 90)
		(property "Reference" "C3B5"
			(at 0 0 90)
			(layer "F.SilkS")
			(hide yes)
			(effects
				(font
					(size 1.27 1.27)
				)
			)
		)
		(property "Value" ""
			(at 0 0 90)
			(layer "F.Fab")
			(effects
				(font
					(size 1.27 1.27)
				)
			)
		)
		(duplicate_pad_numbers_are_jumpers no)
		(fp_poly
			(pts
				(xy 0.3048 -0.1016) (xy 0.3048 0.9906) (xy -0.3048 0.9906) (xy -0.3048 -0.1016)
			)
			(stroke
				(width 0)
				(type default)
			)
			(fill no)
			(layer "F.CrtYd")
		)
		(fp_line
			(start 0.3048 -0.1016)
			(end -0.3048 -0.1016)
			(stroke
				(width 0.1)
				(type default)
			)
			(layer "F.Fab")
		)
		(fp_line
			(start -0.3048 -0.1016)
			(end -0.3048 0.9906)
			(stroke
				(width 0.1)
				(type default)
			)
			(layer "F.Fab")
		)
		(fp_line
			(start 0.3048 0.9906)
			(end 0.3048 -0.1016)
			(stroke
				(width 0.1)
				(type default)
			)
			(layer "F.Fab")
		)
		(fp_line
			(start -0.3048 0.9906)
			(end 0.3048 0.9906)
			(stroke
				(width 0.1)
				(type default)
			)
			(layer "F.Fab")
		)
		(pad "1" smd rect
			(at 0 0 90)
			(size 0.508 0.508)
			(layers "F.Cu" "F.Mask" "F.Paste")
			(net "PVPP_KLM")
		)
		(pad "2" smd rect
			(at 0 0.889 90)
			(size 0.508 0.508)
			(layers "F.Cu" "F.Mask" "F.Paste")
			(net "GND")
		)
		(zone
			(layer "F.Cu")
			(hatch none 0.5)
			(connect_pads
				(clearance 0)
			)
			(min_thickness 0.25)
			(keepout
				(tracks allowed)
				(vias not_allowed)
				(pads allowed)
				(copperpour not_allowed)
				(footprints allowed)
			)
			(placement
				(enabled no)
				(sheetname "")
			)
			(fill
				(thermal_gap 0.5)
				(thermal_bridge_width 0.5)
				(island_removal_mode 0)
			)
			(polygon
				(pts
					(xy 160.12922 -124.8537) (xy 160.12922 -125.3617) (xy 160.51022 -125.3617) (xy 160.51022 -124.8537)
				)
			)
		)
		(zone
			(layer "F.Cu")
			(hatch none 0.5)
			(connect_pads
				(clearance 0)
			)
			(min_thickness 0.25)
			(keepout
				(tracks not_allowed)
				(vias allowed)
				(pads allowed)
				(copperpour not_allowed)
				(footprints allowed)
			)
			(placement
				(enabled no)
				(sheetname "")
			)
			(fill
				(thermal_gap 0.5)
				(thermal_bridge_width 0.5)
				(island_removal_mode 0)
			)
			(polygon
				(pts
					(xy 160.51022 -124.8537) (xy 160.51022 -125.3617) (xy 160.12922 -125.3617) (xy 160.12922 -124.8537)
				)
			)
		)
	)
	(footprint ""
		(layer "F.Cu")
		(at 149.7711 -31.1658)
		(property "Reference" "Y3F1"
			(at -0.0381 -2.08153 0)
			(unlocked yes)
			(layer "F.SilkS")
			(effects
				(font
					(size 0.7874 0.5842)
					(thickness 0.1524)
				)
				(justify left)
			)
		)
		(property "Value" ""
			(at 0 0 0)
			(layer "F.Fab")
			(effects
				(font
					(size 1.27 1.27)
				)
			)
		)
		(duplicate_pad_numbers_are_jumpers no)
		(fp_line
			(start -0.366522 -1.329944)
			(end 3.033522 -1.329944)
			(stroke
				(width 0.1524)
				(type default)
			)
			(layer "F.SilkS")
		)
		(fp_line
			(start -0.366522 -0.80391)
			(end -0.366522 -1.329944)
			(stroke
				(width 0.1524)
				(type default)
			)
			(layer "F.SilkS")
		)
		(fp_line
			(start -0.366522 3.869944)
			(end -0.366522 3.363468)
			(stroke
				(width 0.1524)
				(type default)
			)
			(layer "F.SilkS")
		)
		(fp_line
			(start 3.033522 -1.329944)
			(end 3.033522 -0.790956)
			(stroke
				(width 0.1524)
				(type default)
			)
			(layer "F.SilkS")
		)
		(fp_line
			(start 3.033522 3.370072)
			(end 3.033522 3.869944)
			(stroke
				(width 0.1524)
				(type default)
			)
			(layer "F.SilkS")
		)
		(fp_line
			(start 3.033522 3.869944)
			(end -0.366522 3.869944)
			(stroke
				(width 0.1524)
				(type default)
			)
			(layer "F.SilkS")
		)
		(fp_circle
			(center -1.914906 -0.701802)
			(end -1.787906 -0.701802)
			(stroke
				(width 0.254)
				(type default)
			)
			(fill no)
			(layer "F.SilkS")
		)
		(fp_rect
			(start -0.366522 3.869944)
			(end 3.033522 -1.329944)
			(stroke
				(width 0)
				(type default)
			)
			(fill no)
			(layer "F.CrtYd")
		)
		(fp_line
			(start -0.366522 -1.329944)
			(end 3.033522 -1.329944)
			(stroke
				(width 0.1)
				(type default)
			)
			(layer "F.Fab")
		)
		(fp_line
			(start -0.366522 3.869944)
			(end -0.366522 -1.329944)
			(stroke
				(width 0.1)
				(type default)
			)
			(layer "F.Fab")
		)
		(fp_line
			(start 3.033522 -1.329944)
			(end 3.033522 3.869944)
			(stroke
				(width 0.1)
				(type default)
			)
			(layer "F.Fab")
		)
		(fp_line
			(start 3.033522 3.869944)
			(end -0.366522 3.869944)
			(stroke
				(width 0.1)
				(type default)
			)
			(layer "F.Fab")
		)
		(fp_circle
			(center -1.913636 -0.708152)
			(end -1.786636 -0.708152)
			(stroke
				(width 0.254)
				(type default)
			)
			(fill no)
			(layer "F.Fab")
		)
		(pad "1" smd rect
			(at 0 0)
			(size 1.651 0.8382)
			(layers "F.Cu" "F.Mask" "F.Paste")
			(net "FM_CPU1_STL_BRD_OSC_EN")
		)
		(pad "2" smd rect
			(at 0 1.27)
			(size 1.651 0.8382)
			(layers "F.Cu" "F.Mask" "F.Paste")
			(net "NC_CLK_156M_CPU1_OSC")
		)
		(pad "3" smd rect
			(at 0 2.54)
			(size 1.651 0.8382)
			(layers "F.Cu" "F.Mask" "F.Paste")
			(net "GND")
		)
		(pad "4" smd rect
			(at 2.667 2.54)
			(size 1.651 0.8382)
			(layers "F.Cu" "F.Mask" "F.Paste")
			(net "CLK_156M_OSC_BRD_CPU1_DP")
		)
		(pad "5" smd rect
			(at 2.667 1.27)
			(size 1.651 0.8382)
			(layers "F.Cu" "F.Mask" "F.Paste")
			(net "CLK_156M_OSC_BRD_CPU1_DN")
		)
		(pad "6" smd rect
			(at 2.667 0)
			(size 1.651 0.8382)
			(layers "F.Cu" "F.Mask" "F.Paste")
			(net "P3V3")
		)
	)
	(footprint ""
		(layer "F.Cu")
		(at 414.655762 -87.159084 -90)
		(property "Reference" "U8E1"
			(at -3.99669 -0.20828 0)
			(unlocked yes)
			(layer "F.SilkS")
			(effects
				(font
					(size 0.7874 0.5842)
					(thickness 0.1524)
				)
				(justify left)
			)
		)
		(property "Value" ""
			(at 0 0 270)
			(layer "F.Fab")
			(effects
				(font
					(size 1.27 1.27)
				)
			)
		)
		(duplicate_pad_numbers_are_jumpers no)
		(fp_line
			(start -1.82499 1.82499)
			(end -1.82499 1.660144)
			(stroke
				(width 0.1524)
				(type default)
			)
			(layer "F.SilkS")
		)
		(fp_line
			(start -1.411732 1.82499)
			(end -1.82499 1.82499)
			(stroke
				(width 0.1524)
				(type default)
			)
			(layer "F.SilkS")
		)
		(fp_line
			(start 0.088392 1.82499)
			(end -0.089408 1.82499)
			(stroke
				(width 0.1524)
				(type default)
			)
			(layer "F.SilkS")
		)
		(fp_line
			(start 1.82499 1.82499)
			(end 1.410208 1.82499)
			(stroke
				(width 0.1524)
				(type default)
			)
			(layer "F.SilkS")
		)
		(fp_line
			(start 1.82499 1.660144)
			(end 1.82499 1.82499)
			(stroke
				(width 0.1524)
				(type default)
			)
			(layer "F.SilkS")
		)
		(fp_line
			(start -1.82499 -1.660906)
			(end -1.82499 -1.82499)
			(stroke
				(width 0.1524)
				(type default)
			)
			(layer "F.SilkS")
		)
		(fp_line
			(start -1.82499 -1.82499)
			(end -1.411732 -1.82499)
			(stroke
				(width 0.1524)
				(type default)
			)
			(layer "F.SilkS")
		)
		(fp_line
			(start -0.089408 -1.82499)
			(end 0.088392 -1.82499)
			(stroke
				(width 0.1524)
				(type default)
			)
			(layer "F.SilkS")
		)
		(fp_line
			(start 1.410208 -1.82499)
			(end 1.82499 -1.82499)
			(stroke
				(width 0.1524)
				(type default)
			)
			(layer "F.SilkS")
		)
		(fp_line
			(start 1.82499 -1.82499)
			(end 1.82499 -1.660906)
			(stroke
				(width 0.1524)
				(type default)
			)
			(layer "F.SilkS")
		)
		(fp_circle
			(center -1.17856 -2.466086)
			(end -1.17856 -2.593086)
			(stroke
				(width 0.254)
				(type default)
			)
			(fill no)
			(layer "F.SilkS")
		)
		(fp_poly
			(pts
				(xy -1.0287 1.0287) (xy -1.0287 -1.0287) (xy 1.0287 -1.0287) (xy 1.0287 1.0287)
			)
			(stroke
				(width 0)
				(type default)
			)
			(fill yes)
			(layer "F.Paste")
		)
		(fp_rect
			(start -1.82499 1.82499)
			(end 1.82499 -1.82499)
			(stroke
				(width 0)
				(type default)
			)
			(fill no)
			(layer "F.CrtYd")
		)
		(fp_line
			(start -1.82499 1.82499)
			(end -1.82499 -1.82499)
			(stroke
				(width 0.1)
				(type default)
			)
			(layer "F.Fab")
		)
		(fp_line
			(start 1.82499 1.82499)
			(end -1.82499 1.82499)
			(stroke
				(width 0.1)
				(type default)
			)
			(layer "F.Fab")
		)
		(fp_line
			(start -1.82499 -1.82499)
			(end 1.82499 -1.82499)
			(stroke
				(width 0.1)
				(type default)
			)
			(layer "F.Fab")
		)
		(fp_line
			(start 1.82499 -1.82499)
			(end 1.82499 1.82499)
			(stroke
				(width 0.1)
				(type default)
			)
			(layer "F.Fab")
		)
		(fp_circle
			(center -1.17856 -2.466086)
			(end -1.17856 -2.593086)
			(stroke
				(width 0.254)
				(type default)
			)
			(fill no)
			(layer "F.Fab")
		)
		(pad "1" smd rect
			(at -0.750062 -1.664208 270)
			(size 0.3048 0.762)
			(layers "F.Cu" "F.Mask" "F.Paste")
			(net "IRQ_FORCE_NM_THROTTLE_N")
		)
		(pad "2" smd rect
			(at -1.664208 -0.999998 270)
			(size 0.762 0.3048)
			(layers "F.Cu" "F.Mask" "F.Paste")
			(net "FM_OC_DETECT_N")
		)
		(pad "3" smd rect
			(at -1.664208 -0.500126 270)
			(size 0.762 0.3048)
			(layers "F.Cu" "F.Mask" "F.Paste")
			(net "FM_FAST_PROCHOT_AND_OUT_0_N")
		)
		(pad "4" smd rect
			(at -1.664208 0 270)
			(size 0.762 0.3048)
			(layers "F.Cu" "F.Mask" "F.Paste")
			(net "IRQ_UV_DETECT_N")
		)
		(pad "5" smd rect
			(at -1.664208 0.500126 270)
			(size 0.762 0.3048)
			(layers "F.Cu" "F.Mask" "F.Paste")
			(net "FM_HSC_TIMER_EXP_N")
		)
		(pad "6" smd rect
			(at -1.664208 0.999998 270)
			(size 0.762 0.3048)
			(layers "F.Cu" "F.Mask" "F.Paste")
			(net "FM_FAST_PROCHOT_AND_OUT_1_N")
		)
		(pad "7" smd rect
			(at -0.750062 1.664208 270)
			(size 0.3048 0.762)
			(layers "F.Cu" "F.Mask" "F.Paste")
			(net "GND")
		)
		(pad "8" smd rect
			(at 0.750062 1.664208 270)
			(size 0.3048 0.762)
			(layers "F.Cu" "F.Mask" "F.Paste")
			(net "FM_CTNR_PS_ON_R")
		)
		(pad "9" smd rect
			(at 1.664208 0.999998 270)
			(size 0.762 0.3048)
			(layers "F.Cu" "F.Mask" "F.Paste")
			(net "FM_PS_EN")
		)
		(pad "10" smd rect
			(at 1.664208 0.500126 270)
			(size 0.762 0.3048)
			(layers "F.Cu" "F.Mask" "F.Paste")
			(net "PWRGD_P12V_HSC_DLY")
		)
		(pad "11" smd rect
			(at 1.664208 0 270)
			(size 0.762 0.3048)
			(layers "F.Cu" "F.Mask" "F.Paste")
			(net "FM_FAST_PROCHOT_THROTTLE_IN_N")
		)
		(pad "12" smd rect
			(at 1.664208 -0.500126 270)
			(size 0.762 0.3048)
			(layers "F.Cu" "F.Mask" "F.Paste")
			(net "FM_FAST_PROCHOT_AND_OUT_0_N")
		)
		(pad "13" smd rect
			(at 1.664208 -0.999998 270)
			(size 0.762 0.3048)
			(layers "F.Cu" "F.Mask" "F.Paste")
			(net "FM_FAST_PROCHOT_AND_OUT_1_N")
		)
		(pad "14" smd rect
			(at 0.750062 -1.664208 270)
			(size 0.3048 0.762)
			(layers "F.Cu" "F.Mask" "F.Paste")
			(net "P3V3_STBY")
		)
		(pad "15" smd rect
			(at 0 0 270)
			(size 2.0574 2.0574)
			(layers "F.Cu" "F.Mask" "F.Paste")
			(net "GND")
		)
	)
	(footprint ""
		(layer "F.Cu")
		(at 333.726536 -20.801584 90)
		(property "Reference" "R7F33"
			(at 0 0 90)
			(layer "F.SilkS")
			(hide yes)
			(effects
				(font
					(size 1.27 1.27)
				)
			)
		)
		(property "Value" ""
			(at 0 0 90)
			(layer "F.Fab")
			(effects
				(font
					(size 1.27 1.27)
				)
			)
		)
		(duplicate_pad_numbers_are_jumpers no)
		(fp_rect
			(start 0.2794 0.9906)
			(end -0.2794 -0.1016)
			(stroke
				(width 0)
				(type default)
			)
			(fill no)
			(layer "F.CrtYd")
		)
		(fp_line
			(start 0.2794 -0.1016)
			(end -0.2794 -0.1016)
			(stroke
				(width 0.1)
				(type default)
			)
			(layer "F.Fab")
		)
		(fp_line
			(start -0.2794 -0.1016)
			(end -0.2794 0.9906)
			(stroke
				(width 0.1)
				(type default)
			)
			(layer "F.Fab")
		)
		(fp_line
			(start 0.2794 0.9906)
			(end 0.2794 -0.1016)
			(stroke
				(width 0.1)
				(type default)
			)
			(layer "F.Fab")
		)
		(fp_line
			(start -0.2794 0.9906)
			(end 0.2794 0.9906)
			(stroke
				(width 0.1)
				(type default)
			)
			(layer "F.Fab")
		)
		(pad "1" smd rect
			(at 0 0 90)
			(size 0.508 0.508)
			(layers "F.Cu" "F.Mask" "F.Paste")
			(net "P5V_STBY")
		)
		(pad "2" smd rect
			(at 0 0.889 90)
			(size 0.508 0.508)
			(layers "F.Cu" "F.Mask" "F.Paste")
			(net "FAN_PWM_OUT_SYS1_R")
		)
		(zone
			(layer "F.Cu")
			(hatch none 0.5)
			(connect_pads
				(clearance 0)
			)
			(min_thickness 0.25)
			(keepout
				(tracks allowed)
				(vias not_allowed)
				(pads allowed)
				(copperpour not_allowed)
				(footprints allowed)
			)
			(placement
				(enabled no)
				(sheetname "")
			)
			(fill
				(thermal_gap 0.5)
				(thermal_bridge_width 0.5)
				(island_removal_mode 0)
			)
			(polygon
				(pts
					(xy 334.361536 -21.055584) (xy 333.980536 -21.055584) (xy 333.980536 -20.547584) (xy 334.361536 -20.547584)
				)
			)
		)
		(zone
			(layer "F.Cu")
			(hatch none 0.5)
			(connect_pads
				(clearance 0)
			)
			(min_thickness 0.25)
			(keepout
				(tracks not_allowed)
				(vias allowed)
				(pads allowed)
				(copperpour not_allowed)
				(footprints allowed)
			)
			(placement
				(enabled no)
				(sheetname "")
			)
			(fill
				(thermal_gap 0.5)
				(thermal_bridge_width 0.5)
				(island_removal_mode 0)
			)
			(polygon
				(pts
					(xy 334.361536 -21.055584) (xy 333.980536 -21.055584) (xy 333.980536 -20.547584) (xy 334.361536 -20.547584)
				)
			)
		)
	)
	(footprint ""
		(layer "F.Cu")
		(at 419.1635 -57.1881)
		(property "Reference" "Q8E1"
			(at 2.1463 0.18669 0)
			(unlocked yes)
			(layer "F.SilkS")
			(effects
				(font
					(size 0.7874 0.5842)
					(thickness 0.1524)
				)
				(justify left)
			)
		)
		(property "Value" ""
			(at 0 0 0)
			(layer "F.Fab")
			(effects
				(font
					(size 1.27 1.27)
				)
			)
		)
		(duplicate_pad_numbers_are_jumpers no)
		(fp_line
			(start 0.381 0.635)
			(end 0.381 1.27)
			(stroke
				(width 0.1524)
				(type default)
			)
			(layer "F.SilkS")
		)
		(fp_line
			(start 0.9525 -0.5715)
			(end 1.778 -0.5715)
			(stroke
				(width 0.1524)
				(type default)
			)
			(layer "F.SilkS")
		)
		(fp_line
			(start 0.9525 2.4765)
			(end 1.778 2.4765)
			(stroke
				(width 0.1524)
				(type default)
			)
			(layer "F.SilkS")
		)
		(fp_line
			(start 1.778 -0.5715)
			(end 1.778 0.3175)
			(stroke
				(width 0.1524)
				(type default)
			)
			(layer "F.SilkS")
		)
		(fp_line
			(start 1.778 2.4765)
			(end 1.778 1.5875)
			(stroke
				(width 0.1524)
				(type default)
			)
			(layer "F.SilkS")
		)
		(fp_circle
			(center -0.636524 -0.804672)
			(end -0.509524 -0.804672)
			(stroke
				(width 0.254)
				(type default)
			)
			(fill no)
			(layer "F.SilkS")
		)
		(fp_poly
			(pts
				(xy 1.778 2.4765) (xy 0.381 2.4765) (xy 0.381 -0.5715) (xy 1.778 -0.5715)
			)
			(stroke
				(width 0)
				(type default)
			)
			(fill no)
			(layer "F.CrtYd")
		)
		(fp_line
			(start 0.381 -0.5715)
			(end 0.381 2.4765)
			(stroke
				(width 0.1)
				(type default)
			)
			(layer "F.Fab")
		)
		(fp_line
			(start 0.381 2.4765)
			(end 1.778 2.4765)
			(stroke
				(width 0.1)
				(type default)
			)
			(layer "F.Fab")
		)
		(fp_line
			(start 1.778 -0.5715)
			(end 0.381 -0.5715)
			(stroke
				(width 0.1)
				(type default)
			)
			(layer "F.Fab")
		)
		(fp_line
			(start 1.778 2.4765)
			(end 1.778 -0.5715)
			(stroke
				(width 0.1)
				(type default)
			)
			(layer "F.Fab")
		)
		(fp_circle
			(center -0.9525 -0.9271)
			(end -0.8255 -0.9271)
			(stroke
				(width 0.254)
				(type default)
			)
			(fill no)
			(layer "F.Fab")
		)
		(pad "1" smd rect
			(at 0 0)
			(size 1.143 0.508)
			(layers "F.Cu" "F.Mask" "F.Paste")
			(net "RST_PLTRST_N")
		)
		(pad "2" smd rect
			(at 0 1.905)
			(size 1.143 0.508)
			(layers "F.Cu" "F.Mask" "F.Paste")
			(net "GND")
		)
		(pad "3" smd rect
			(at 2.159 0.9525)
			(size 1.143 0.508)
			(layers "F.Cu" "F.Mask" "F.Paste")
			(net "RST_PLTRST_TOP_SWAP")
		)
	)
	(footprint ""
		(layer "F.Cu")
		(at 419.862 -21.6535)
		(property "Reference" "R2T49"
			(at 0 0 0)
			(layer "F.SilkS")
			(hide yes)
			(effects
				(font
					(size 1.27 1.27)
				)
			)
		)
		(property "Value" ""
			(at 0 0 0)
			(layer "F.Fab")
			(effects
				(font
					(size 1.27 1.27)
				)
			)
		)
		(duplicate_pad_numbers_are_jumpers no)
		(fp_poly
			(pts
				(xy -0.2794 -0.1016) (xy 0.2794 -0.1016) (xy 0.2794 0.9906) (xy -0.2794 0.9906)
			)
			(stroke
				(width 0)
				(type default)
			)
			(fill no)
			(layer "F.CrtYd")
		)
		(fp_line
			(start -0.2794 -0.1016)
			(end -0.2794 0.9906)
			(stroke
				(width 0.1)
				(type default)
			)
			(layer "F.Fab")
		)
		(fp_line
			(start -0.2794 0.9906)
			(end 0.2794 0.9906)
			(stroke
				(width 0.1)
				(type default)
			)
			(layer "F.Fab")
		)
		(fp_line
			(start 0.2794 -0.1016)
			(end -0.2794 -0.1016)
			(stroke
				(width 0.1)
				(type default)
			)
			(layer "F.Fab")
		)
		(fp_line
			(start 0.2794 0.9906)
			(end 0.2794 -0.1016)
			(stroke
				(width 0.1)
				(type default)
			)
			(layer "F.Fab")
		)
		(pad "1" smd rect
			(at 0 0)
			(size 0.508 0.508)
			(layers "F.Cu" "F.Mask" "F.Paste")
			(net "SMB_BMC_PMBUS_STBY_LVC3_SDA_R")
		)
		(pad "2" smd rect
			(at 0 0.889)
			(size 0.508 0.508)
			(layers "F.Cu" "F.Mask" "F.Paste")
			(net "SMB_BMC_PMBUS_STBY_LVC3_SDA")
		)
		(zone
			(layer "F.Cu")
			(hatch none 0.5)
			(connect_pads
				(clearance 0)
			)
			(min_thickness 0.25)
			(keepout
				(tracks allowed)
				(vias not_allowed)
				(pads allowed)
				(copperpour not_allowed)
				(footprints allowed)
			)
			(placement
				(enabled no)
				(sheetname "")
			)
			(fill
				(thermal_gap 0.5)
				(thermal_bridge_width 0.5)
				(island_removal_mode 0)
			)
			(polygon
				(pts
					(xy 419.608 -21.3995) (xy 420.116 -21.3995) (xy 420.116 -21.0185) (xy 419.608 -21.0185)
				)
			)
		)
		(zone
			(layer "F.Cu")
			(hatch none 0.5)
			(connect_pads
				(clearance 0)
			)
			(min_thickness 0.25)
			(keepout
				(tracks not_allowed)
				(vias allowed)
				(pads allowed)
				(copperpour not_allowed)
				(footprints allowed)
			)
			(placement
				(enabled no)
				(sheetname "")
			)
			(fill
				(thermal_gap 0.5)
				(thermal_bridge_width 0.5)
				(island_removal_mode 0)
			)
			(polygon
				(pts
					(xy 419.608 -21.0185) (xy 420.116 -21.0185) (xy 420.116 -21.3995) (xy 419.608 -21.3995)
				)
			)
		)
	)
	(footprint ""
		(layer "F.Cu")
		(at 98.18624 -73.318116)
		(property "Reference" "C2D34"
			(at 0 0 0)
			(layer "F.SilkS")
			(hide yes)
			(effects
				(font
					(size 1.27 1.27)
				)
			)
		)
		(property "Value" ""
			(at 0 0 0)
			(layer "F.Fab")
			(effects
				(font
					(size 1.27 1.27)
				)
			)
		)
		(duplicate_pad_numbers_are_jumpers no)
		(fp_poly
			(pts
				(xy -0.4953 -0.2032) (xy 0.4953 -0.2032) (xy 0.4953 1.6002) (xy -0.4953 1.6002)
			)
			(stroke
				(width 0)
				(type default)
			)
			(fill no)
			(layer "F.CrtYd")
		)
		(fp_line
			(start -0.4953 -0.2032)
			(end 0.4953 -0.2032)
			(stroke
				(width 0.1)
				(type default)
			)
			(layer "F.Fab")
		)
		(fp_line
			(start -0.4953 1.6002)
			(end -0.4953 -0.2032)
			(stroke
				(width 0.1)
				(type default)
			)
			(layer "F.Fab")
		)
		(fp_line
			(start 0.4953 -0.2032)
			(end 0.4953 1.6002)
			(stroke
				(width 0.1)
				(type default)
			)
			(layer "F.Fab")
		)
		(fp_line
			(start 0.4953 1.6002)
			(end -0.4953 1.6002)
			(stroke
				(width 0.1)
				(type default)
			)
			(layer "F.Fab")
		)
		(pad "1" smd rect
			(at 0 0)
			(size 0.762 0.889)
			(layers "F.Cu" "F.Mask" "F.Paste")
			(net "PVCCIN_CPU1")
		)
		(pad "2" smd rect
			(at 0 1.397)
			(size 0.762 0.889)
			(layers "F.Cu" "F.Mask" "F.Paste")
			(net "GND")
		)
		(zone
			(layer "F.Cu")
			(hatch none 0.5)
			(connect_pads
				(clearance 0)
			)
			(min_thickness 0.25)
			(keepout
				(tracks not_allowed)
				(vias allowed)
				(pads allowed)
				(copperpour not_allowed)
				(footprints allowed)
			)
			(placement
				(enabled no)
				(sheetname "")
			)
			(fill
				(thermal_gap 0.5)
				(thermal_bridge_width 0.5)
				(island_removal_mode 0)
			)
			(polygon
				(pts
					(xy 97.80524 -72.873616) (xy 98.56724 -72.873616) (xy 98.56724 -72.365616) (xy 97.80524 -72.365616)
				)
			)
		)
	)
	(footprint ""
		(layer "F.Cu")
		(at 21.6408 -87.3506 -90)
		(property "Reference" "R1D4"
			(at 0 0 270)
			(layer "F.SilkS")
			(hide yes)
			(effects
				(font
					(size 1.27 1.27)
				)
			)
		)
		(property "Value" ""
			(at 0 0 270)
			(layer "F.Fab")
			(effects
				(font
					(size 1.27 1.27)
				)
			)
		)
		(duplicate_pad_numbers_are_jumpers no)
		(fp_rect
			(start 0.2794 0.9906)
			(end -0.2794 -0.1016)
			(stroke
				(width 0)
				(type default)
			)
			(fill no)
			(layer "F.CrtYd")
		)
		(fp_line
			(start -0.2794 0.9906)
			(end 0.2794 0.9906)
			(stroke
				(width 0.1)
				(type default)
			)
			(layer "F.Fab")
		)
		(fp_line
			(start 0.2794 0.9906)
			(end 0.2794 -0.1016)
			(stroke
				(width 0.1)
				(type default)
			)
			(layer "F.Fab")
		)
		(fp_line
			(start -0.2794 -0.1016)
			(end -0.2794 0.9906)
			(stroke
				(width 0.1)
				(type default)
			)
			(layer "F.Fab")
		)
		(fp_line
			(start 0.2794 -0.1016)
			(end -0.2794 -0.1016)
			(stroke
				(width 0.1)
				(type default)
			)
			(layer "F.Fab")
		)
		(pad "1" smd rect
			(at 0 0 270)
			(size 0.508 0.508)
			(layers "F.Cu" "F.Mask" "F.Paste")
			(net "VSENSE_PVCCIN_CPU1_P")
		)
		(pad "2" smd rect
			(at 0 0.889 270)
			(size 0.508 0.508)
			(layers "F.Cu" "F.Mask" "F.Paste")
			(net "VSENSE_PVCCIN_CPU1_AVSP")
		)
		(zone
			(layer "F.Cu")
			(hatch none 0.5)
			(connect_pads
				(clearance 0)
			)
			(min_thickness 0.25)
			(keepout
				(tracks not_allowed)
				(vias allowed)
				(pads allowed)
				(copperpour not_allowed)
				(footprints allowed)
			)
			(placement
				(enabled no)
				(sheetname "")
			)
			(fill
				(thermal_gap 0.5)
				(thermal_bridge_width 0.5)
				(island_removal_mode 0)
			)
			(polygon
				(pts
					(xy 21.0058 -87.0966) (xy 21.3868 -87.0966) (xy 21.3868 -87.6046) (xy 21.0058 -87.6046)
				)
			)
		)
		(zone
			(layer "F.Cu")
			(hatch none 0.5)
			(connect_pads
				(clearance 0)
			)
			(min_thickness 0.25)
			(keepout
				(tracks allowed)
				(vias not_allowed)
				(pads allowed)
				(copperpour not_allowed)
				(footprints allowed)
			)
			(placement
				(enabled no)
				(sheetname "")
			)
			(fill
				(thermal_gap 0.5)
				(thermal_bridge_width 0.5)
				(island_removal_mode 0)
			)
			(polygon
				(pts
					(xy 21.0058 -87.0966) (xy 21.3868 -87.0966) (xy 21.3868 -87.6046) (xy 21.0058 -87.6046)
				)
			)
		)
	)
	(footprint ""
		(layer "F.Cu")
		(at 403.112986 -84.582 -90)
		(property "Reference" "U2P1"
			(at 2.1463 3.50901 90)
			(unlocked yes)
			(layer "F.SilkS")
			(effects
				(font
					(size 0.7874 0.5842)
					(thickness 0.1524)
				)
				(justify left)
			)
		)
		(property "Value" ""
			(at 0 0 270)
			(layer "F.Fab")
			(effects
				(font
					(size 1.27 1.27)
				)
			)
		)
		(duplicate_pad_numbers_are_jumpers no)
		(fp_circle
			(center -0.4699 -0.8382)
			(end -0.4699 -0.9652)
			(stroke
				(width 0.254)
				(type default)
			)
			(fill no)
			(layer "F.SilkS")
		)
		(fp_poly
			(pts
				(xy 0.21463 -0.450088) (xy 1.56337 -0.450088) (xy 1.56337 1.75006) (xy 0.21463 1.75006)
			)
			(stroke
				(width 0)
				(type default)
			)
			(fill no)
			(layer "F.CrtYd")
		)
		(fp_line
			(start 0.21463 1.75006)
			(end 0.21463 -0.450088)
			(stroke
				(width 0.1)
				(type default)
			)
			(layer "F.Fab")
		)
		(fp_line
			(start 1.56337 1.75006)
			(end 0.21463 1.75006)
			(stroke
				(width 0.1)
				(type default)
			)
			(layer "F.Fab")
		)
		(fp_line
			(start 0.21463 -0.450088)
			(end 1.56337 -0.450088)
			(stroke
				(width 0.1)
				(type default)
			)
			(layer "F.Fab")
		)
		(fp_line
			(start 1.56337 -0.450088)
			(end 1.56337 1.75006)
			(stroke
				(width 0.1)
				(type default)
			)
			(layer "F.Fab")
		)
		(fp_circle
			(center -0.4699 -0.8382)
			(end -0.4699 -0.9652)
			(stroke
				(width 0.254)
				(type default)
			)
			(fill no)
			(layer "F.Fab")
		)
		(pad "1" smd rect
			(at 0 0 270)
			(size 1.016 0.381)
			(layers "F.Cu" "F.Mask" "F.Paste")
			(net "Net_6470")
		)
		(pad "2" smd rect
			(at 0 0.649986 270)
			(size 1.016 0.381)
			(layers "F.Cu" "F.Mask" "F.Paste")
			(net "FM_M2_SSD_PEDET")
		)
		(pad "3" smd rect
			(at 0 1.299972 270)
			(size 1.016 0.381)
			(layers "F.Cu" "F.Mask" "F.Paste")
			(net "GND")
		)
		(pad "4" smd rect
			(at 1.778 1.299972 270)
			(size 1.016 0.381)
			(layers "F.Cu" "F.Mask" "F.Paste")
			(net "FM_M2_DET_LVC3")
		)
		(pad "5" smd rect
			(at 1.778 0 270)
			(size 1.016 0.381)
			(layers "F.Cu" "F.Mask" "F.Paste")
			(net "P3V3_STBY")
		)
	)
	(footprint ""
		(layer "F.Cu")
		(at 426.5295 -126.5047 -90)
		(property "Reference" "R8B11"
			(at 0 0 270)
			(layer "F.SilkS")
			(hide yes)
			(effects
				(font
					(size 1.27 1.27)
				)
			)
		)
		(property "Value" ""
			(at 0 0 270)
			(layer "F.Fab")
			(effects
				(font
					(size 1.27 1.27)
				)
			)
		)
		(duplicate_pad_numbers_are_jumpers no)
		(fp_poly
			(pts
				(xy -0.2794 -0.1016) (xy 0.2794 -0.1016) (xy 0.2794 0.9906) (xy -0.2794 0.9906)
			)
			(stroke
				(width 0)
				(type default)
			)
			(fill no)
			(layer "F.CrtYd")
		)
		(fp_line
			(start -0.2794 0.9906)
			(end 0.2794 0.9906)
			(stroke
				(width 0.1)
				(type default)
			)
			(layer "F.Fab")
		)
		(fp_line
			(start 0.2794 0.9906)
			(end 0.2794 -0.1016)
			(stroke
				(width 0.1)
				(type default)
			)
			(layer "F.Fab")
		)
		(fp_line
			(start -0.2794 -0.1016)
			(end -0.2794 0.9906)
			(stroke
				(width 0.1)
				(type default)
			)
			(layer "F.Fab")
		)
		(fp_line
			(start 0.2794 -0.1016)
			(end -0.2794 -0.1016)
			(stroke
				(width 0.1)
				(type default)
			)
			(layer "F.Fab")
		)
		(pad "1" smd rect
			(at 0 0 270)
			(size 0.508 0.508)
			(layers "F.Cu" "F.Mask" "F.Paste")
			(net "PVPP_ABC")
		)
		(pad "2" smd rect
			(at 0 0.889 270)
			(size 0.508 0.508)
			(layers "F.Cu" "F.Mask" "F.Paste")
			(net "SMB_HFI1_CPU0_LVC2_SCL")
		)
		(zone
			(layer "F.Cu")
			(hatch none 0.5)
			(connect_pads
				(clearance 0)
			)
			(min_thickness 0.25)
			(keepout
				(tracks not_allowed)
				(vias allowed)
				(pads allowed)
				(copperpour not_allowed)
				(footprints allowed)
			)
			(placement
				(enabled no)
				(sheetname "")
			)
			(fill
				(thermal_gap 0.5)
				(thermal_bridge_width 0.5)
				(island_removal_mode 0)
			)
			(polygon
				(pts
					(xy 425.8945 -126.7587) (xy 425.8945 -126.2507) (xy 426.2755 -126.2507) (xy 426.2755 -126.7587)
				)
			)
		)
		(zone
			(layer "F.Cu")
			(hatch none 0.5)
			(connect_pads
				(clearance 0)
			)
			(min_thickness 0.25)
			(keepout
				(tracks allowed)
				(vias not_allowed)
				(pads allowed)
				(copperpour not_allowed)
				(footprints allowed)
			)
			(placement
				(enabled no)
				(sheetname "")
			)
			(fill
				(thermal_gap 0.5)
				(thermal_bridge_width 0.5)
				(island_removal_mode 0)
			)
			(polygon
				(pts
					(xy 426.2755 -126.7587) (xy 426.2755 -126.2507) (xy 425.8945 -126.2507) (xy 425.8945 -126.7587)
				)
			)
		)
	)
	(footprint ""
		(layer "F.Cu")
		(at 32.416496 -69.223382 -90)
		(property "Reference" "C1D17"
			(at 0 0 270)
			(layer "F.SilkS")
			(hide yes)
			(effects
				(font
					(size 1.27 1.27)
				)
			)
		)
		(property "Value" ""
			(at 0 0 270)
			(layer "F.Fab")
			(effects
				(font
					(size 1.27 1.27)
				)
			)
		)
		(duplicate_pad_numbers_are_jumpers no)
		(fp_rect
			(start 0.3048 0.9906)
			(end -0.3048 -0.1016)
			(stroke
				(width 0)
				(type default)
			)
			(fill no)
			(layer "F.CrtYd")
		)
		(fp_line
			(start -0.3048 0.9906)
			(end 0.3048 0.9906)
			(stroke
				(width 0.1)
				(type default)
			)
			(layer "F.Fab")
		)
		(fp_line
			(start 0.3048 0.9906)
			(end 0.3048 -0.1016)
			(stroke
				(width 0.1)
				(type default)
			)
			(layer "F.Fab")
		)
		(fp_line
			(start -0.3048 -0.1016)
			(end -0.3048 0.9906)
			(stroke
				(width 0.1)
				(type default)
			)
			(layer "F.Fab")
		)
		(fp_line
			(start 0.3048 -0.1016)
			(end -0.3048 -0.1016)
			(stroke
				(width 0.1)
				(type default)
			)
			(layer "F.Fab")
		)
		(pad "1" smd rect
			(at 0 0 270)
			(size 0.508 0.508)
			(layers "F.Cu" "F.Mask" "F.Paste")
			(net "VR_PVCCIN_CPU1_PH3_VCIN")
		)
		(pad "2" smd rect
			(at 0 0.889 270)
			(size 0.508 0.508)
			(layers "F.Cu" "F.Mask" "F.Paste")
			(net "GND")
		)
		(zone
			(layer "F.Cu")
			(hatch none 0.5)
			(connect_pads
				(clearance 0)
			)
			(min_thickness 0.25)
			(keepout
				(tracks allowed)
				(vias not_allowed)
				(pads allowed)
				(copperpour not_allowed)
				(footprints allowed)
			)
			(placement
				(enabled no)
				(sheetname "")
			)
			(fill
				(thermal_gap 0.5)
				(thermal_bridge_width 0.5)
				(island_removal_mode 0)
			)
			(polygon
				(pts
					(xy 31.781496 -68.969382) (xy 32.162496 -68.969382) (xy 32.162496 -69.477382) (xy 31.781496 -69.477382)
				)
			)
		)
		(zone
			(layer "F.Cu")
			(hatch none 0.5)
			(connect_pads
				(clearance 0)
			)
			(min_thickness 0.25)
			(keepout
				(tracks not_allowed)
				(vias allowed)
				(pads allowed)
				(copperpour not_allowed)
				(footprints allowed)
			)
			(placement
				(enabled no)
				(sheetname "")
			)
			(fill
				(thermal_gap 0.5)
				(thermal_bridge_width 0.5)
				(island_removal_mode 0)
			)
			(polygon
				(pts
					(xy 31.781496 -68.969382) (xy 32.162496 -68.969382) (xy 32.162496 -69.477382) (xy 31.781496 -69.477382)
				)
			)
		)
	)
	(footprint ""
		(layer "F.Cu")
		(at 21.222462 -57.0992 180)
		(property "Reference" "EU1E3"
			(at 2.299462 -1.49987 0)
			(unlocked yes)
			(layer "F.SilkS")
			(effects
				(font
					(size 0.7874 0.5842)
					(thickness 0.1524)
				)
			)
		)
		(property "Value" ""
			(at 0 0 180)
			(layer "F.Fab")
			(effects
				(font
					(size 1.27 1.27)
				)
			)
		)
		(duplicate_pad_numbers_are_jumpers no)
		(fp_line
			(start 4.8006 4.5593)
			(end 4.8006 4.445254)
			(stroke
				(width 0.1524)
				(type default)
			)
			(layer "F.SilkS")
		)
		(fp_line
			(start 4.8006 -0.7493)
			(end 4.8006 -0.635254)
			(stroke
				(width 0.1524)
				(type default)
			)
			(layer "F.SilkS")
		)
		(fp_line
			(start 0.4064 4.5593)
			(end 4.8006 4.5593)
			(stroke
				(width 0.1524)
				(type default)
			)
			(layer "F.SilkS")
		)
		(fp_line
			(start 0.4064 4.445254)
			(end 0.4064 4.5593)
			(stroke
				(width 0.1524)
				(type default)
			)
			(layer "F.SilkS")
		)
		(fp_line
			(start 0.4064 -0.635254)
			(end 0.4064 -0.7493)
			(stroke
				(width 0.1524)
				(type default)
			)
			(layer "F.SilkS")
		)
		(fp_line
			(start 0.4064 -0.7493)
			(end 4.8006 -0.7493)
			(stroke
				(width 0.1524)
				(type default)
			)
			(layer "F.SilkS")
		)
		(fp_circle
			(center -1.279906 -0.230378)
			(end -1.406906 -0.230378)
			(stroke
				(width 0.254)
				(type default)
			)
			(fill no)
			(layer "F.SilkS")
		)
		(fp_rect
			(start 4.8006 -0.7493)
			(end 0.4064 4.5593)
			(stroke
				(width 0)
				(type default)
			)
			(fill no)
			(layer "F.CrtYd")
		)
		(fp_line
			(start 4.8006 4.5593)
			(end 0.4064 4.5593)
			(stroke
				(width 0.1)
				(type default)
			)
			(layer "F.Fab")
		)
		(fp_line
			(start 4.8006 -0.7493)
			(end 4.8006 4.5593)
			(stroke
				(width 0.1)
				(type default)
			)
			(layer "F.Fab")
		)
		(fp_line
			(start 0.4064 4.5593)
			(end 0.4064 -0.7493)
			(stroke
				(width 0.1)
				(type default)
			)
			(layer "F.Fab")
		)
		(fp_line
			(start 0.4064 -0.7493)
			(end 4.8006 -0.7493)
			(stroke
				(width 0.1)
				(type default)
			)
			(layer "F.Fab")
		)
		(fp_circle
			(center -1.076706 -0.704342)
			(end -1.203706 -0.704342)
			(stroke
				(width 0.635)
				(type default)
			)
			(fill no)
			(layer "F.Fab")
		)
		(pad "1" smd rect
			(at 0 0 180)
			(size 1.651 0.508)
			(layers "F.Cu" "F.Mask" "F.Paste")
			(net "P12V_STBY")
		)
		(pad "2" smd rect
			(at 0 1.27 180)
			(size 1.651 0.508)
			(layers "F.Cu" "F.Mask" "F.Paste")
			(net "P12V_STBY")
		)
		(pad "3" smd rect
			(at 0 2.54 180)
			(size 1.651 0.508)
			(layers "F.Cu" "F.Mask" "F.Paste")
			(net "P12V_STBY")
		)
		(pad "4" smd rect
			(at 0 3.81 180)
			(size 1.651 0.508)
			(layers "F.Cu" "F.Mask" "F.Paste")
			(net "A_HSC_GATE1_R")
		)
		(pad "5" smd custom
			(at 3.937 1.905 180)
			(size 1.04775 1.04775)
			(layers "F.Cu" "F.Mask" "F.Paste")
			(net "P12V_MB0_SW")
			(options
				(clearance outline)
				(anchor circle)
			)
			(primitives
				(gr_poly
					(pts
						(xy -2.0955 -1.651) (xy -2.0955 1.651) (xy 0.4445 1.651) (xy 0.4445 2.2098) (xy 2.0955 2.2098)
						(xy 2.0955 -2.2098) (xy 0.4445 -2.2098) (xy 0.4445 -1.651)
					)
					(width 0)
					(fill yes)
				)
			)
		)
	)
	(footprint ""
		(layer "F.Cu")
		(at 416.402012 -52.738782)
		(property "Reference" "Q1W4"
			(at 0 -0.81788 0)
			(unlocked yes)
			(layer "F.SilkS")
			(effects
				(font
					(size 0.4064 0.254)
					(thickness 0.1524)
				)
				(justify left)
			)
		)
		(property "Value" ""
			(at 0 0 0)
			(layer "F.Fab")
			(effects
				(font
					(size 1.27 1.27)
				)
			)
		)
		(duplicate_pad_numbers_are_jumpers no)
		(fp_circle
			(center -0.848614 -0.6477)
			(end -0.721614 -0.6477)
			(stroke
				(width 0.254)
				(type default)
			)
			(fill no)
			(layer "F.SilkS")
		)
		(fp_poly
			(pts
				(xy 0.21463 -0.450088) (xy 1.56337 -0.450088) (xy 1.56337 1.75006) (xy 0.21463 1.75006)
			)
			(stroke
				(width 0)
				(type default)
			)
			(fill no)
			(layer "F.CrtYd")
		)
		(fp_line
			(start 0.21463 -0.450088)
			(end 1.56337 -0.450088)
			(stroke
				(width 0.1)
				(type default)
			)
			(layer "F.Fab")
		)
		(fp_line
			(start 0.21463 1.75006)
			(end 0.21463 -0.450088)
			(stroke
				(width 0.1)
				(type default)
			)
			(layer "F.Fab")
		)
		(fp_line
			(start 1.56337 -0.450088)
			(end 1.56337 1.75006)
			(stroke
				(width 0.1)
				(type default)
			)
			(layer "F.Fab")
		)
		(fp_line
			(start 1.56337 1.75006)
			(end 0.21463 1.75006)
			(stroke
				(width 0.1)
				(type default)
			)
			(layer "F.Fab")
		)
		(fp_circle
			(center -0.848614 -0.6477)
			(end -0.721614 -0.6477)
			(stroke
				(width 0.254)
				(type default)
			)
			(fill no)
			(layer "F.Fab")
		)
		(pad "1" smd rect
			(at 0 0)
			(size 1.016 0.381)
			(layers "F.Cu" "F.Mask" "F.Paste")
			(net "GND")
		)
		(pad "2" smd rect
			(at 0 0.649986)
			(size 1.016 0.381)
			(layers "F.Cu" "F.Mask" "F.Paste")
			(net "FM_OCP_MEZZC_PRES_N")
		)
		(pad "3" smd rect
			(at 0 1.299972)
			(size 1.016 0.381)
			(layers "F.Cu" "F.Mask" "F.Paste")
			(net "FM_OCP_MEZZC_PRES_1V05_PCH_N")
		)
		(pad "4" smd rect
			(at 1.778 1.299972)
			(size 1.016 0.381)
			(layers "F.Cu" "F.Mask" "F.Paste")
			(net "GND")
		)
		(pad "5" smd rect
			(at 1.778 0.649986)
			(size 1.016 0.381)
			(layers "F.Cu" "F.Mask" "F.Paste")
			(net "FM_OCP_MEZZC_PRES_LVT3_BMC")
		)
		(pad "6" smd rect
			(at 1.778 0)
			(size 1.016 0.381)
			(layers "F.Cu" "F.Mask" "F.Paste")
			(net "FM_OCP_MEZZC_PRES_LVT3_BMC")
		)
	)
	(footprint ""
		(layer "F.Cu")
		(at 236.715808 -164.90188 -90)
		(property "Reference" "T1D21"
			(at 0 0 270)
			(layer "F.SilkS")
			(hide yes)
			(effects
				(font
					(size 1.27 1.27)
				)
			)
		)
		(property "Value" "*"
			(at -3.4036 -4.46405 270)
			(unlocked yes)
			(layer "F.Fab")
			(hide yes)
			(effects
				(font
					(size 0.889 0.889)
					(thickness 0.1524)
				)
			)
		)
		(property "Device Type" "TEST-PAD-12P-1-GP-U_DISCRET-GBA"
			(at -3.4036 -5.98805 270)
			(unlocked yes)
			(layer "F.Fab")
			(hide yes)
			(effects
				(font
					(size 0.889 0.889)
					(thickness 0.1524)
				)
			)
		)
		(duplicate_pad_numbers_are_jumpers no)
		(fp_line
			(start -2.3876 3.4798)
			(end -2.3876 -4.826)
			(stroke
				(width 0.1524)
				(type default)
			)
			(layer "F.SilkS")
		)
		(fp_line
			(start 2.3622 3.4798)
			(end -2.3876 3.4798)
			(stroke
				(width 0.1524)
				(type default)
			)
			(layer "F.SilkS")
		)
		(fp_line
			(start -2.3876 -4.826)
			(end 2.3622 -4.826)
			(stroke
				(width 0.1524)
				(type default)
			)
			(layer "F.SilkS")
		)
		(fp_line
			(start 2.3622 -4.826)
			(end 2.3622 3.4798)
			(stroke
				(width 0.1524)
				(type default)
			)
			(layer "F.SilkS")
		)
		(fp_rect
			(start -2.6416 3.7338)
			(end 2.6162 -5.08)
			(stroke
				(width 0)
				(type default)
			)
			(fill no)
			(layer "F.CrtYd")
		)
		(fp_rect
			(start -2.6416 3.7338)
			(end 2.6162 -5.08)
			(stroke
				(width 0)
				(type default)
			)
			(fill no)
			(layer "F.Fab")
		)
		(pad "1" smd circle
			(at 0.496824 -1.301496 270)
			(size 0.6604 0.6604)
			(layers "F.Cu" "F.Mask" "F.Paste")
			(net "L12_85OHM_10INCH_DP")
		)
		(pad "2" smd circle
			(at -0.503936 -1.301496 270)
			(size 0.6604 0.6604)
			(layers "F.Cu" "F.Mask" "F.Paste")
			(net "L12_85OHM_10INCH_DN")
		)
		(pad "3" smd custom
			(at -0.00889 0.370078 270)
			(size 0.74295 0.74295)
			(layers "F.Cu" "F.Mask" "F.Paste")
			(net "GND")
			(options
				(clearance outline)
				(anchor circle)
			)
			(primitives
				(gr_poly
					(pts
						(xy -2.1209 1.4859) (xy 2.1209 1.4859) (xy 2.1209 -1.4859) (xy 1.08585 -1.4859) (xy 1.08585 -0.4699)
						(xy -1.08585 -0.4699) (xy -1.08585 -1.4859) (xy -2.1209 -1.4859)
					)
					(width 0)
					(fill yes)
				)
			)
		)
		(pad "4" thru_hole circle
			(at 1.266444 -3.851656 270)
			(size 1.4478 1.4478)
			(drill 1.0414)
			(layers "*.Cu" "*.Mask")
			(remove_unused_layers no)
			(net "GND")
			(clearance 0.1524)
			(thermal_gap 0.1524)
		)
		(pad "5" thru_hole circle
			(at -1.273556 -3.851656 270)
			(size 1.4478 1.4478)
			(drill 1.0414)
			(layers "*.Cu" "*.Mask")
			(remove_unused_layers no)
			(net "GND")
			(clearance 0.1524)
			(thermal_gap 0.1524)
		)
		(pad "6" thru_hole circle
			(at 1.266444 2.498344 270)
			(size 1.4478 1.4478)
			(drill 1.0414)
			(layers "*.Cu" "*.Mask")
			(remove_unused_layers no)
			(net "GND")
			(clearance 0.1524)
			(thermal_gap 0.1524)
		)
		(pad "7" thru_hole circle
			(at -1.273556 2.498344 270)
			(size 1.4478 1.4478)
			(drill 1.0414)
			(layers "*.Cu" "*.Mask")
			(remove_unused_layers no)
			(net "GND")
			(clearance 0.1524)
			(thermal_gap 0.1524)
		)
		(pad "8" thru_hole circle
			(at 1.27 -0.4572 270)
			(size 0.7112 0.7112)
			(drill 0.4064)
			(layers "*.Cu" "*.Mask")
			(remove_unused_layers no)
			(net "GND")
			(clearance 0.1016)
			(thermal_gap 0.1016)
		)
		(pad "9" thru_hole circle
			(at 1.27 0.762 270)
			(size 0.7112 0.7112)
			(drill 0.4064)
			(layers "*.Cu" "*.Mask")
			(remove_unused_layers no)
			(net "GND")
			(clearance 0.1016)
			(thermal_gap 0.1016)
		)
		(pad "10" thru_hole circle
			(at -0.0254 0.762 270)
			(size 0.7112 0.7112)
			(drill 0.4064)
			(layers "*.Cu" "*.Mask")
			(remove_unused_layers no)
			(net "GND")
			(clearance 0.1016)
			(thermal_gap 0.1016)
		)
		(pad "11" thru_hole circle
			(at -1.27 0.762 270)
			(size 0.7112 0.7112)
			(drill 0.4064)
			(layers "*.Cu" "*.Mask")
			(remove_unused_layers no)
			(net "GND")
			(clearance 0.1016)
			(thermal_gap 0.1016)
		)
		(pad "12" thru_hole circle
			(at -1.27 -0.4572 270)
			(size 0.7112 0.7112)
			(drill 0.4064)
			(layers "*.Cu" "*.Mask")
			(remove_unused_layers no)
			(net "GND")
			(clearance 0.1016)
			(thermal_gap 0.1016)
		)
	)
	(footprint ""
		(layer "F.Cu")
		(at 110.744 -69.85)
		(property "Reference" "R3D23"
			(at 0 0 0)
			(layer "F.SilkS")
			(hide yes)
			(effects
				(font
					(size 1.27 1.27)
				)
			)
		)
		(property "Value" ""
			(at 0 0 0)
			(layer "F.Fab")
			(effects
				(font
					(size 1.27 1.27)
				)
			)
		)
		(duplicate_pad_numbers_are_jumpers no)
		(fp_poly
			(pts
				(xy -0.2794 -0.1016) (xy 0.2794 -0.1016) (xy 0.2794 0.9906) (xy -0.2794 0.9906)
			)
			(stroke
				(width 0)
				(type default)
			)
			(fill no)
			(layer "F.CrtYd")
		)
		(fp_line
			(start -0.2794 -0.1016)
			(end -0.2794 0.9906)
			(stroke
				(width 0.1)
				(type default)
			)
			(layer "F.Fab")
		)
		(fp_line
			(start -0.2794 0.9906)
			(end 0.2794 0.9906)
			(stroke
				(width 0.1)
				(type default)
			)
			(layer "F.Fab")
		)
		(fp_line
			(start 0.2794 -0.1016)
			(end -0.2794 -0.1016)
			(stroke
				(width 0.1)
				(type default)
			)
			(layer "F.Fab")
		)
		(fp_line
			(start 0.2794 0.9906)
			(end 0.2794 -0.1016)
			(stroke
				(width 0.1)
				(type default)
			)
			(layer "F.Fab")
		)
		(pad "1" smd rect
			(at 0 0)
			(size 0.508 0.508)
			(layers "F.Cu" "F.Mask" "F.Paste")
			(net "PVCCIO_CPU1")
		)
		(pad "2" smd rect
			(at 0 0.889)
			(size 0.508 0.508)
			(layers "F.Cu" "F.Mask" "F.Paste")
			(net "PU_CPU1_TXT_AGENT")
		)
		(zone
			(layer "F.Cu")
			(hatch none 0.5)
			(connect_pads
				(clearance 0)
			)
			(min_thickness 0.25)
			(keepout
				(tracks allowed)
				(vias not_allowed)
				(pads allowed)
				(copperpour not_allowed)
				(footprints allowed)
			)
			(placement
				(enabled no)
				(sheetname "")
			)
			(fill
				(thermal_gap 0.5)
				(thermal_bridge_width 0.5)
				(island_removal_mode 0)
			)
			(polygon
				(pts
					(xy 110.49 -69.596) (xy 110.998 -69.596) (xy 110.998 -69.215) (xy 110.49 -69.215)
				)
			)
		)
		(zone
			(layer "F.Cu")
			(hatch none 0.5)
			(connect_pads
				(clearance 0)
			)
			(min_thickness 0.25)
			(keepout
				(tracks not_allowed)
				(vias allowed)
				(pads allowed)
				(copperpour not_allowed)
				(footprints allowed)
			)
			(placement
				(enabled no)
				(sheetname "")
			)
			(fill
				(thermal_gap 0.5)
				(thermal_bridge_width 0.5)
				(island_removal_mode 0)
			)
			(polygon
				(pts
					(xy 110.49 -69.215) (xy 110.998 -69.215) (xy 110.998 -69.596) (xy 110.49 -69.596)
				)
			)
		)
	)
	(footprint ""
		(layer "F.Cu")
		(at 486.3846 -50.2539 180)
		(property "Reference" "C9E5"
			(at 0 0 180)
			(layer "F.SilkS")
			(hide yes)
			(effects
				(font
					(size 1.27 1.27)
				)
			)
		)
		(property "Value" ""
			(at 0 0 180)
			(layer "F.Fab")
			(effects
				(font
					(size 1.27 1.27)
				)
			)
		)
		(duplicate_pad_numbers_are_jumpers no)
		(fp_poly
			(pts
				(xy 0.3048 -0.1016) (xy 0.3048 0.9906) (xy -0.3048 0.9906) (xy -0.3048 -0.1016)
			)
			(stroke
				(width 0)
				(type default)
			)
			(fill no)
			(layer "F.CrtYd")
		)
		(fp_line
			(start 0.3048 0.9906)
			(end 0.3048 -0.1016)
			(stroke
				(width 0.1)
				(type default)
			)
			(layer "F.Fab")
		)
		(fp_line
			(start 0.3048 -0.1016)
			(end -0.3048 -0.1016)
			(stroke
				(width 0.1)
				(type default)
			)
			(layer "F.Fab")
		)
		(fp_line
			(start -0.3048 0.9906)
			(end 0.3048 0.9906)
			(stroke
				(width 0.1)
				(type default)
			)
			(layer "F.Fab")
		)
		(fp_line
			(start -0.3048 -0.1016)
			(end -0.3048 0.9906)
			(stroke
				(width 0.1)
				(type default)
			)
			(layer "F.Fab")
		)
		(pad "1" smd rect
			(at 0 0 180)
			(size 0.508 0.508)
			(layers "F.Cu" "F.Mask" "F.Paste")
			(net "PE_PCH_SPRV_RX_DN")
		)
		(pad "2" smd rect
			(at 0 0.889 180)
			(size 0.508 0.508)
			(layers "F.Cu" "F.Mask" "F.Paste")
			(net "PE_PCH_SPRV_RX_C_DN")
		)
		(zone
			(layer "F.Cu")
			(hatch none 0.5)
			(connect_pads
				(clearance 0)
			)
			(min_thickness 0.25)
			(keepout
				(tracks not_allowed)
				(vias allowed)
				(pads allowed)
				(copperpour not_allowed)
				(footprints allowed)
			)
			(placement
				(enabled no)
				(sheetname "")
			)
			(fill
				(thermal_gap 0.5)
				(thermal_bridge_width 0.5)
				(island_removal_mode 0)
			)
			(polygon
				(pts
					(xy 486.6386 -50.8889) (xy 486.1306 -50.8889) (xy 486.1306 -50.5079) (xy 486.6386 -50.5079)
				)
			)
		)
		(zone
			(layer "F.Cu")
			(hatch none 0.5)
			(connect_pads
				(clearance 0)
			)
			(min_thickness 0.25)
			(keepout
				(tracks allowed)
				(vias not_allowed)
				(pads allowed)
				(copperpour not_allowed)
				(footprints allowed)
			)
			(placement
				(enabled no)
				(sheetname "")
			)
			(fill
				(thermal_gap 0.5)
				(thermal_bridge_width 0.5)
				(island_removal_mode 0)
			)
			(polygon
				(pts
					(xy 486.6386 -50.5079) (xy 486.1306 -50.5079) (xy 486.1306 -50.8889) (xy 486.6386 -50.8889)
				)
			)
		)
	)
	(footprint ""
		(layer "F.Cu")
		(at 1.7018 -134.3152 90)
		(property "Reference" "C1B21"
			(at 0 0 90)
			(layer "F.SilkS")
			(hide yes)
			(effects
				(font
					(size 1.27 1.27)
				)
			)
		)
		(property "Value" ""
			(at 0 0 90)
			(layer "F.Fab")
			(effects
				(font
					(size 1.27 1.27)
				)
			)
		)
		(duplicate_pad_numbers_are_jumpers no)
		(fp_rect
			(start 0.3048 0.9906)
			(end -0.3048 -0.1016)
			(stroke
				(width 0)
				(type default)
			)
			(fill no)
			(layer "F.CrtYd")
		)
		(fp_line
			(start 0.3048 -0.1016)
			(end -0.3048 -0.1016)
			(stroke
				(width 0.1)
				(type default)
			)
			(layer "F.Fab")
		)
		(fp_line
			(start -0.3048 -0.1016)
			(end -0.3048 0.9906)
			(stroke
				(width 0.1)
				(type default)
			)
			(layer "F.Fab")
		)
		(fp_line
			(start 0.3048 0.9906)
			(end 0.3048 -0.1016)
			(stroke
				(width 0.1)
				(type default)
			)
			(layer "F.Fab")
		)
		(fp_line
			(start -0.3048 0.9906)
			(end 0.3048 0.9906)
			(stroke
				(width 0.1)
				(type default)
			)
			(layer "F.Fab")
		)
		(pad "1" smd rect
			(at 0 0 90)
			(size 0.508 0.508)
			(layers "F.Cu" "F.Mask" "F.Paste")
			(net "P5V_STBY")
		)
		(pad "2" smd rect
			(at 0 0.889 90)
			(size 0.508 0.508)
			(layers "F.Cu" "F.Mask" "F.Paste")
			(net "GND")
		)
		(zone
			(layer "F.Cu")
			(hatch none 0.5)
			(connect_pads
				(clearance 0)
			)
			(min_thickness 0.25)
			(keepout
				(tracks not_allowed)
				(vias allowed)
				(pads allowed)
				(copperpour not_allowed)
				(footprints allowed)
			)
			(placement
				(enabled no)
				(sheetname "")
			)
			(fill
				(thermal_gap 0.5)
				(thermal_bridge_width 0.5)
				(island_removal_mode 0)
			)
			(polygon
				(pts
					(xy 2.3368 -134.5692) (xy 1.9558 -134.5692) (xy 1.9558 -134.0612) (xy 2.3368 -134.0612)
				)
			)
		)
		(zone
			(layer "F.Cu")
			(hatch none 0.5)
			(connect_pads
				(clearance 0)
			)
			(min_thickness 0.25)
			(keepout
				(tracks allowed)
				(vias not_allowed)
				(pads allowed)
				(copperpour not_allowed)
				(footprints allowed)
			)
			(placement
				(enabled no)
				(sheetname "")
			)
			(fill
				(thermal_gap 0.5)
				(thermal_bridge_width 0.5)
				(island_removal_mode 0)
			)
			(polygon
				(pts
					(xy 2.3368 -134.5692) (xy 1.9558 -134.5692) (xy 1.9558 -134.0612) (xy 2.3368 -134.0612)
				)
			)
		)
	)
	(footprint ""
		(layer "F.Cu")
		(at 318.543432 -22.740112 -90)
		(property "Reference" "C6F5"
			(at 0 0 270)
			(layer "F.SilkS")
			(hide yes)
			(effects
				(font
					(size 1.27 1.27)
				)
			)
		)
		(property "Value" ""
			(at 0 0 270)
			(layer "F.Fab")
			(effects
				(font
					(size 1.27 1.27)
				)
			)
		)
		(duplicate_pad_numbers_are_jumpers no)
		(fp_poly
			(pts
				(xy -0.4953 -0.2032) (xy 0.4953 -0.2032) (xy 0.4953 1.6002) (xy -0.4953 1.6002)
			)
			(stroke
				(width 0)
				(type default)
			)
			(fill no)
			(layer "F.CrtYd")
		)
		(fp_line
			(start -0.4953 1.6002)
			(end -0.4953 -0.2032)
			(stroke
				(width 0.1)
				(type default)
			)
			(layer "F.Fab")
		)
		(fp_line
			(start 0.4953 1.6002)
			(end -0.4953 1.6002)
			(stroke
				(width 0.1)
				(type default)
			)
			(layer "F.Fab")
		)
		(fp_line
			(start -0.4953 -0.2032)
			(end 0.4953 -0.2032)
			(stroke
				(width 0.1)
				(type default)
			)
			(layer "F.Fab")
		)
		(fp_line
			(start 0.4953 -0.2032)
			(end 0.4953 1.6002)
			(stroke
				(width 0.1)
				(type default)
			)
			(layer "F.Fab")
		)
		(pad "1" smd rect
			(at 0 0 270)
			(size 0.762 0.889)
			(layers "F.Cu" "F.Mask" "F.Paste")
			(net "PVPP_ABC")
		)
		(pad "2" smd rect
			(at 0 1.397 270)
			(size 0.762 0.889)
			(layers "F.Cu" "F.Mask" "F.Paste")
			(net "GND")
		)
		(zone
			(layer "F.Cu")
			(hatch none 0.5)
			(connect_pads
				(clearance 0)
			)
			(min_thickness 0.25)
			(keepout
				(tracks not_allowed)
				(vias allowed)
				(pads allowed)
				(copperpour not_allowed)
				(footprints allowed)
			)
			(placement
				(enabled no)
				(sheetname "")
			)
			(fill
				(thermal_gap 0.5)
				(thermal_bridge_width 0.5)
				(island_removal_mode 0)
			)
			(polygon
				(pts
					(xy 318.098932 -23.121112) (xy 318.098932 -22.359112) (xy 317.590932 -22.359112) (xy 317.590932 -23.121112)
				)
			)
		)
	)
	(footprint ""
		(layer "F.Cu")
		(at 178.981862 -144.998948 90)
		(property "Reference" "R4A8"
			(at 0 0 90)
			(layer "F.SilkS")
			(hide yes)
			(effects
				(font
					(size 1.27 1.27)
				)
			)
		)
		(property "Value" ""
			(at 0 0 90)
			(layer "F.Fab")
			(effects
				(font
					(size 1.27 1.27)
				)
			)
		)
		(duplicate_pad_numbers_are_jumpers no)
		(fp_poly
			(pts
				(xy -0.2794 -0.1016) (xy 0.2794 -0.1016) (xy 0.2794 0.9906) (xy -0.2794 0.9906)
			)
			(stroke
				(width 0)
				(type default)
			)
			(fill no)
			(layer "F.CrtYd")
		)
		(fp_line
			(start 0.2794 -0.1016)
			(end -0.2794 -0.1016)
			(stroke
				(width 0.1)
				(type default)
			)
			(layer "F.Fab")
		)
		(fp_line
			(start -0.2794 -0.1016)
			(end -0.2794 0.9906)
			(stroke
				(width 0.1)
				(type default)
			)
			(layer "F.Fab")
		)
		(fp_line
			(start 0.2794 0.9906)
			(end 0.2794 -0.1016)
			(stroke
				(width 0.1)
				(type default)
			)
			(layer "F.Fab")
		)
		(fp_line
			(start -0.2794 0.9906)
			(end 0.2794 0.9906)
			(stroke
				(width 0.1)
				(type default)
			)
			(layer "F.Fab")
		)
		(pad "1" smd rect
			(at 0 0 90)
			(size 0.508 0.508)
			(layers "F.Cu" "F.Mask" "F.Paste")
			(net "SMB_LAN_STBY_LVC3_SDA")
		)
		(pad "2" smd rect
			(at 0 0.889 90)
			(size 0.508 0.508)
			(layers "F.Cu" "F.Mask" "F.Paste")
			(net "SMB_PIROM_CPU0_SDA")
		)
		(zone
			(layer "F.Cu")
			(hatch none 0.5)
			(connect_pads
				(clearance 0)
			)
			(min_thickness 0.25)
			(keepout
				(tracks allowed)
				(vias not_allowed)
				(pads allowed)
				(copperpour not_allowed)
				(footprints allowed)
			)
			(placement
				(enabled no)
				(sheetname "")
			)
			(fill
				(thermal_gap 0.5)
				(thermal_bridge_width 0.5)
				(island_removal_mode 0)
			)
			(polygon
				(pts
					(xy 179.235862 -144.744948) (xy 179.235862 -145.252948) (xy 179.616862 -145.252948) (xy 179.616862 -144.744948)
				)
			)
		)
		(zone
			(layer "F.Cu")
			(hatch none 0.5)
			(connect_pads
				(clearance 0)
			)
			(min_thickness 0.25)
			(keepout
				(tracks not_allowed)
				(vias allowed)
				(pads allowed)
				(copperpour not_allowed)
				(footprints allowed)
			)
			(placement
				(enabled no)
				(sheetname "")
			)
			(fill
				(thermal_gap 0.5)
				(thermal_bridge_width 0.5)
				(island_removal_mode 0)
			)
			(polygon
				(pts
					(xy 179.616862 -144.744948) (xy 179.616862 -145.252948) (xy 179.235862 -145.252948) (xy 179.235862 -144.744948)
				)
			)
		)
	)
	(footprint ""
		(layer "F.Cu")
		(at 416.56 -56.896 -90)
		(property "Reference" "U8E3"
			(at 0.1778 -2.13487 90)
			(unlocked yes)
			(layer "F.SilkS")
			(effects
				(font
					(size 0.7874 0.5842)
					(thickness 0.1524)
				)
				(justify left)
			)
		)
		(property "Value" ""
			(at 0 0 270)
			(layer "F.Fab")
			(effects
				(font
					(size 1.27 1.27)
				)
			)
		)
		(duplicate_pad_numbers_are_jumpers no)
		(fp_circle
			(center -0.71882 -0.53848)
			(end -0.71882 -0.66548)
			(stroke
				(width 0.254)
				(type default)
			)
			(fill no)
			(layer "F.SilkS")
		)
		(fp_poly
			(pts
				(xy 0.21463 -0.450088) (xy 1.56337 -0.450088) (xy 1.56337 1.75006) (xy 0.21463 1.75006)
			)
			(stroke
				(width 0)
				(type default)
			)
			(fill no)
			(layer "F.CrtYd")
		)
		(fp_line
			(start 0.21463 1.75006)
			(end 0.21463 -0.450088)
			(stroke
				(width 0.1)
				(type default)
			)
			(layer "F.Fab")
		)
		(fp_line
			(start 1.56337 1.75006)
			(end 0.21463 1.75006)
			(stroke
				(width 0.1)
				(type default)
			)
			(layer "F.Fab")
		)
		(fp_line
			(start 0.21463 -0.450088)
			(end 1.56337 -0.450088)
			(stroke
				(width 0.1)
				(type default)
			)
			(layer "F.Fab")
		)
		(fp_line
			(start 1.56337 -0.450088)
			(end 1.56337 1.75006)
			(stroke
				(width 0.1)
				(type default)
			)
			(layer "F.Fab")
		)
		(fp_circle
			(center -0.4699 -0.8382)
			(end -0.4699 -0.9652)
			(stroke
				(width 0.254)
				(type default)
			)
			(fill no)
			(layer "F.Fab")
		)
		(pad "1" smd rect
			(at 0 0 270)
			(size 1.016 0.381)
			(layers "F.Cu" "F.Mask" "F.Paste")
			(net "RST_PLTRST_TOP_SWAP")
		)
		(pad "2" smd rect
			(at 0 0.649986 270)
			(size 1.016 0.381)
			(layers "F.Cu" "F.Mask" "F.Paste")
			(net "FM_BIOS_TOP_SWAP")
		)
		(pad "3" smd rect
			(at 0 1.299972 270)
			(size 1.016 0.381)
			(layers "F.Cu" "F.Mask" "F.Paste")
			(net "GND")
		)
		(pad "4" smd rect
			(at 1.778 1.299972 270)
			(size 1.016 0.381)
			(layers "F.Cu" "F.Mask" "F.Paste")
			(net "FM_BIOS_TOP_SWAP_SPKR_R")
		)
		(pad "5" smd rect
			(at 1.778 0 270)
			(size 1.016 0.381)
			(layers "F.Cu" "F.Mask" "F.Paste")
			(net "P3V3_STBY")
		)
	)
	(footprint ""
		(layer "F.Cu")
		(at 377.5202 -30.629352 90)
		(property "Reference" "C8F15"
			(at -0.8382 -0.67818 90)
			(unlocked yes)
			(layer "F.SilkS")
			(effects
				(font
					(size 0.4064 0.254)
					(thickness 0.1524)
				)
				(justify left)
			)
		)
		(property "Value" ""
			(at 0 0 90)
			(layer "F.Fab")
			(effects
				(font
					(size 1.27 1.27)
				)
			)
		)
		(duplicate_pad_numbers_are_jumpers no)
		(fp_poly
			(pts
				(xy 0.3048 -0.1016) (xy 0.3048 0.9906) (xy -0.3048 0.9906) (xy -0.3048 -0.1016)
			)
			(stroke
				(width 0)
				(type default)
			)
			(fill no)
			(layer "F.CrtYd")
		)
		(fp_line
			(start 0.3048 -0.1016)
			(end -0.3048 -0.1016)
			(stroke
				(width 0.1)
				(type default)
			)
			(layer "F.Fab")
		)
		(fp_line
			(start -0.3048 -0.1016)
			(end -0.3048 0.9906)
			(stroke
				(width 0.1)
				(type default)
			)
			(layer "F.Fab")
		)
		(fp_line
			(start 0.3048 0.9906)
			(end 0.3048 -0.1016)
			(stroke
				(width 0.1)
				(type default)
			)
			(layer "F.Fab")
		)
		(fp_line
			(start -0.3048 0.9906)
			(end 0.3048 0.9906)
			(stroke
				(width 0.1)
				(type default)
			)
			(layer "F.Fab")
		)
		(pad "1" smd rect
			(at 0 0 90)
			(size 0.508 0.508)
			(layers "F.Cu" "F.Mask" "F.Paste")
			(net "SATA6G_S0_RX_DN")
		)
		(pad "2" smd rect
			(at 0 0.889 90)
			(size 0.508 0.508)
			(layers "F.Cu" "F.Mask" "F.Paste")
			(net "P3E_PCH_M2_SATA6G_RX_R_DN")
		)
		(zone
			(layer "F.Cu")
			(hatch none 0.5)
			(connect_pads
				(clearance 0)
			)
			(min_thickness 0.25)
			(keepout
				(tracks allowed)
				(vias not_allowed)
				(pads allowed)
				(copperpour not_allowed)
				(footprints allowed)
			)
			(placement
				(enabled no)
				(sheetname "")
			)
			(fill
				(thermal_gap 0.5)
				(thermal_bridge_width 0.5)
				(island_removal_mode 0)
			)
			(polygon
				(pts
					(xy 377.7742 -30.375352) (xy 377.7742 -30.883352) (xy 378.1552 -30.883352) (xy 378.1552 -30.375352)
				)
			)
		)
		(zone
			(layer "F.Cu")
			(hatch none 0.5)
			(connect_pads
				(clearance 0)
			)
			(min_thickness 0.25)
			(keepout
				(tracks not_allowed)
				(vias allowed)
				(pads allowed)
				(copperpour not_allowed)
				(footprints allowed)
			)
			(placement
				(enabled no)
				(sheetname "")
			)
			(fill
				(thermal_gap 0.5)
				(thermal_bridge_width 0.5)
				(island_removal_mode 0)
			)
			(polygon
				(pts
					(xy 378.1552 -30.375352) (xy 378.1552 -30.883352) (xy 377.7742 -30.883352) (xy 377.7742 -30.375352)
				)
			)
		)
	)
	(footprint ""
		(layer "F.Cu")
		(at 192.62725 -90.3859 90)
		(property "Reference" "RT23"
			(at 1.01473 0.656336 0)
			(unlocked yes)
			(layer "F.SilkS")
			(effects
				(font
					(size 0.4064 0.254)
					(thickness 0.1524)
				)
			)
		)
		(property "Value" ""
			(at 0 0 90)
			(layer "F.Fab")
			(effects
				(font
					(size 1.27 1.27)
				)
			)
		)
		(duplicate_pad_numbers_are_jumpers no)
		(fp_poly
			(pts
				(xy -0.4953 -0.2032) (xy 0.4953 -0.2032) (xy 0.4953 1.6002) (xy -0.4953 1.6002)
			)
			(stroke
				(width 0)
				(type default)
			)
			(fill no)
			(layer "F.CrtYd")
		)
		(fp_line
			(start 0.4953 -0.2032)
			(end 0.4953 1.6002)
			(stroke
				(width 0.1)
				(type default)
			)
			(layer "F.Fab")
		)
		(fp_line
			(start -0.4953 -0.2032)
			(end 0.4953 -0.2032)
			(stroke
				(width 0.1)
				(type default)
			)
			(layer "F.Fab")
		)
		(fp_line
			(start 0.4953 1.6002)
			(end -0.4953 1.6002)
			(stroke
				(width 0.1)
				(type default)
			)
			(layer "F.Fab")
		)
		(fp_line
			(start -0.4953 1.6002)
			(end -0.4953 -0.2032)
			(stroke
				(width 0.1)
				(type default)
			)
			(layer "F.Fab")
		)
		(pad "1" smd rect
			(at 0 0 90)
			(size 0.762 0.889)
			(layers "F.Cu" "F.Mask" "F.Paste")
			(net "VR_PVCCIN_CPU0_PH5_BOOT")
		)
		(pad "2" smd rect
			(at 0 1.397 90)
			(size 0.762 0.889)
			(layers "F.Cu" "F.Mask" "F.Paste")
			(net "VR_PVCCIN_CPU0_PH5_BOOT_R")
		)
		(zone
			(layer "F.Cu")
			(hatch none 0.5)
			(connect_pads
				(clearance 0)
			)
			(min_thickness 0.25)
			(keepout
				(tracks allowed)
				(vias not_allowed)
				(pads allowed)
				(copperpour not_allowed)
				(footprints allowed)
			)
			(placement
				(enabled no)
				(sheetname "")
			)
			(fill
				(thermal_gap 0.5)
				(thermal_bridge_width 0.5)
				(island_removal_mode 0)
			)
			(polygon
				(pts
					(xy 193.57975 -90.7669) (xy 193.07175 -90.7669) (xy 193.07175 -90.0049) (xy 193.57975 -90.0049)
				)
			)
		)
		(zone
			(layer "F.Cu")
			(hatch none 0.5)
			(connect_pads
				(clearance 0)
			)
			(min_thickness 0.25)
			(keepout
				(tracks not_allowed)
				(vias allowed)
				(pads allowed)
				(copperpour not_allowed)
				(footprints allowed)
			)
			(placement
				(enabled no)
				(sheetname "")
			)
			(fill
				(thermal_gap 0.5)
				(thermal_bridge_width 0.5)
				(island_removal_mode 0)
			)
			(polygon
				(pts
					(xy 193.57975 -90.0049) (xy 193.57975 -90.7669) (xy 193.07175 -90.7669) (xy 193.07175 -90.0049)
				)
			)
		)
	)
	(footprint ""
		(layer "F.Cu")
		(at 399.758916 -35.041586 -90)
		(property "Reference" "R8G5"
			(at 0 0 270)
			(layer "F.SilkS")
			(hide yes)
			(effects
				(font
					(size 1.27 1.27)
				)
			)
		)
		(property "Value" ""
			(at 0 0 270)
			(layer "F.Fab")
			(effects
				(font
					(size 1.27 1.27)
				)
			)
		)
		(duplicate_pad_numbers_are_jumpers no)
		(fp_poly
			(pts
				(xy -0.2794 -0.1016) (xy 0.2794 -0.1016) (xy 0.2794 0.9906) (xy -0.2794 0.9906)
			)
			(stroke
				(width 0)
				(type default)
			)
			(fill no)
			(layer "F.CrtYd")
		)
		(fp_line
			(start -0.2794 0.9906)
			(end 0.2794 0.9906)
			(stroke
				(width 0.1)
				(type default)
			)
			(layer "F.Fab")
		)
		(fp_line
			(start 0.2794 0.9906)
			(end 0.2794 -0.1016)
			(stroke
				(width 0.1)
				(type default)
			)
			(layer "F.Fab")
		)
		(fp_line
			(start -0.2794 -0.1016)
			(end -0.2794 0.9906)
			(stroke
				(width 0.1)
				(type default)
			)
			(layer "F.Fab")
		)
		(fp_line
			(start 0.2794 -0.1016)
			(end -0.2794 -0.1016)
			(stroke
				(width 0.1)
				(type default)
			)
			(layer "F.Fab")
		)
		(pad "1" smd rect
			(at 0 0 270)
			(size 0.508 0.508)
			(layers "F.Cu" "F.Mask" "F.Paste")
			(net "SMB_OCP_LAN_STBY_LVC3_SDA_R")
		)
		(pad "2" smd rect
			(at 0 0.889 270)
			(size 0.508 0.508)
			(layers "F.Cu" "F.Mask" "F.Paste")
			(net "SMB_OCP_LAN_STBY_LVC3_SDA")
		)
		(zone
			(layer "F.Cu")
			(hatch none 0.5)
			(connect_pads
				(clearance 0)
			)
			(min_thickness 0.25)
			(keepout
				(tracks not_allowed)
				(vias allowed)
				(pads allowed)
				(copperpour not_allowed)
				(footprints allowed)
			)
			(placement
				(enabled no)
				(sheetname "")
			)
			(fill
				(thermal_gap 0.5)
				(thermal_bridge_width 0.5)
				(island_removal_mode 0)
			)
			(polygon
				(pts
					(xy 399.123916 -35.295586) (xy 399.123916 -34.787586) (xy 399.504916 -34.787586) (xy 399.504916 -35.295586)
				)
			)
		)
		(zone
			(layer "F.Cu")
			(hatch none 0.5)
			(connect_pads
				(clearance 0)
			)
			(min_thickness 0.25)
			(keepout
				(tracks allowed)
				(vias not_allowed)
				(pads allowed)
				(copperpour not_allowed)
				(footprints allowed)
			)
			(placement
				(enabled no)
				(sheetname "")
			)
			(fill
				(thermal_gap 0.5)
				(thermal_bridge_width 0.5)
				(island_removal_mode 0)
			)
			(polygon
				(pts
					(xy 399.504916 -35.295586) (xy 399.504916 -34.787586) (xy 399.123916 -34.787586) (xy 399.123916 -35.295586)
				)
			)
		)
	)
	(footprint ""
		(layer "F.Cu")
		(at 36.7538 -69.3166 -90)
		(property "Reference" "RT12"
			(at 0 0 270)
			(layer "F.SilkS")
			(hide yes)
			(effects
				(font
					(size 1.27 1.27)
				)
			)
		)
		(property "Value" "*"
			(at -0.0254 -2.6289 270)
			(unlocked yes)
			(layer "F.Fab")
			(hide yes)
			(effects
				(font
					(size 1.27 1.016)
					(thickness 0.1524)
				)
			)
		)
		(property "Device Type" "1R3F-GP_RCL_GP-1R3F-GP,64.1R00A"
			(at -0.0254 -4.1529 270)
			(unlocked yes)
			(layer "F.Fab")
			(hide yes)
			(effects
				(font
					(size 1.27 1.016)
					(thickness 0.1524)
				)
			)
		)
		(duplicate_pad_numbers_are_jumpers no)
		(fp_line
			(start -0.4826 0)
			(end -0.2032 0)
			(stroke
				(width 0.2032)
				(type default)
			)
			(layer "F.SilkS")
		)
		(fp_line
			(start 0.2032 0)
			(end 0.4826 0)
			(stroke
				(width 0.2032)
				(type default)
			)
			(layer "F.SilkS")
		)
		(fp_rect
			(start -0.5842 1.3335)
			(end 0.5842 -1.3335)
			(stroke
				(width 0)
				(type default)
			)
			(fill no)
			(layer "F.CrtYd")
		)
		(fp_rect
			(start -0.5842 1.3335)
			(end 0.5842 -1.3335)
			(stroke
				(width 0)
				(type default)
			)
			(fill no)
			(layer "F.Fab")
		)
		(pad "1" smd custom
			(at 0 -0.762 270)
			(size 0.2159 0.2159)
			(layers "F.Cu" "F.Mask" "F.Paste")
			(net "VR_PVCCIN_CPU1_PHASE3_RC")
			(options
				(clearance outline)
				(anchor circle)
			)
			(primitives
				(gr_poly
					(pts
						(arc
							(start -0.3302 -0.4318)
							(mid -0.402042 -0.402042)
							(end -0.4318 -0.3302)
						)
						(arc
							(start -0.4318 0.3302)
							(mid -0.402042 0.402042)
							(end -0.3302 0.4318)
						)
						(arc
							(start 0.3302 0.4318)
							(mid 0.402042 0.402042)
							(end 0.4318 0.3302)
						)
						(arc
							(start 0.4318 -0.3302)
							(mid 0.402042 -0.402042)
							(end 0.3302 -0.4318)
						)
					)
					(width 0)
					(fill yes)
				)
			)
		)
		(pad "2" smd custom
			(at 0 0.762 270)
			(size 0.2159 0.2159)
			(layers "F.Cu" "F.Mask" "F.Paste")
			(net "GND")
			(options
				(clearance outline)
				(anchor circle)
			)
			(primitives
				(gr_poly
					(pts
						(arc
							(start -0.3302 -0.4318)
							(mid -0.402042 -0.402042)
							(end -0.4318 -0.3302)
						)
						(arc
							(start -0.4318 0.3302)
							(mid -0.402042 0.402042)
							(end -0.3302 0.4318)
						)
						(arc
							(start 0.3302 0.4318)
							(mid 0.402042 0.402042)
							(end 0.4318 0.3302)
						)
						(arc
							(start 0.4318 -0.3302)
							(mid 0.402042 -0.402042)
							(end 0.3302 -0.4318)
						)
					)
					(width 0)
					(fill yes)
				)
			)
		)
	)
	(footprint ""
		(layer "F.Cu")
		(at 340.7664 -128.3335)
		(property "Reference" "R7B13"
			(at 0 0 0)
			(layer "F.SilkS")
			(hide yes)
			(effects
				(font
					(size 1.27 1.27)
				)
			)
		)
		(property "Value" ""
			(at 0 0 0)
			(layer "F.Fab")
			(effects
				(font
					(size 1.27 1.27)
				)
			)
		)
		(duplicate_pad_numbers_are_jumpers no)
		(fp_poly
			(pts
				(xy -0.2794 -0.1016) (xy 0.2794 -0.1016) (xy 0.2794 0.9906) (xy -0.2794 0.9906)
			)
			(stroke
				(width 0)
				(type default)
			)
			(fill no)
			(layer "F.CrtYd")
		)
		(fp_line
			(start -0.2794 -0.1016)
			(end -0.2794 0.9906)
			(stroke
				(width 0.1)
				(type default)
			)
			(layer "F.Fab")
		)
		(fp_line
			(start -0.2794 0.9906)
			(end 0.2794 0.9906)
			(stroke
				(width 0.1)
				(type default)
			)
			(layer "F.Fab")
		)
		(fp_line
			(start 0.2794 -0.1016)
			(end -0.2794 -0.1016)
			(stroke
				(width 0.1)
				(type default)
			)
			(layer "F.Fab")
		)
		(fp_line
			(start 0.2794 0.9906)
			(end 0.2794 -0.1016)
			(stroke
				(width 0.1)
				(type default)
			)
			(layer "F.Fab")
		)
		(pad "1" smd rect
			(at 0 0)
			(size 0.508 0.508)
			(layers "F.Cu" "F.Mask" "F.Paste")
			(net "VR_FB_PVPP_DEF")
		)
		(pad "2" smd rect
			(at 0 0.889)
			(size 0.508 0.508)
			(layers "F.Cu" "F.Mask" "F.Paste")
			(net "AGND_PVPP_DEF")
		)
		(zone
			(layer "F.Cu")
			(hatch none 0.5)
			(connect_pads
				(clearance 0)
			)
			(min_thickness 0.25)
			(keepout
				(tracks allowed)
				(vias not_allowed)
				(pads allowed)
				(copperpour not_allowed)
				(footprints allowed)
			)
			(placement
				(enabled no)
				(sheetname "")
			)
			(fill
				(thermal_gap 0.5)
				(thermal_bridge_width 0.5)
				(island_removal_mode 0)
			)
			(polygon
				(pts
					(xy 340.5124 -128.0795) (xy 341.0204 -128.0795) (xy 341.0204 -127.6985) (xy 340.5124 -127.6985)
				)
			)
		)
		(zone
			(layer "F.Cu")
			(hatch none 0.5)
			(connect_pads
				(clearance 0)
			)
			(min_thickness 0.25)
			(keepout
				(tracks not_allowed)
				(vias allowed)
				(pads allowed)
				(copperpour not_allowed)
				(footprints allowed)
			)
			(placement
				(enabled no)
				(sheetname "")
			)
			(fill
				(thermal_gap 0.5)
				(thermal_bridge_width 0.5)
				(island_removal_mode 0)
			)
			(polygon
				(pts
					(xy 340.5124 -127.6985) (xy 341.0204 -127.6985) (xy 341.0204 -128.0795) (xy 340.5124 -128.0795)
				)
			)
		)
	)
	(footprint ""
		(layer "F.Cu")
		(at 318.8716 -28.045918 180)
		(property "Reference" "R6F8"
			(at 0 0 180)
			(layer "F.SilkS")
			(hide yes)
			(effects
				(font
					(size 1.27 1.27)
				)
			)
		)
		(property "Value" ""
			(at 0 0 180)
			(layer "F.Fab")
			(effects
				(font
					(size 1.27 1.27)
				)
			)
		)
		(duplicate_pad_numbers_are_jumpers no)
		(fp_poly
			(pts
				(xy -0.2794 -0.1016) (xy 0.2794 -0.1016) (xy 0.2794 0.9906) (xy -0.2794 0.9906)
			)
			(stroke
				(width 0)
				(type default)
			)
			(fill no)
			(layer "F.CrtYd")
		)
		(fp_line
			(start 0.2794 0.9906)
			(end 0.2794 -0.1016)
			(stroke
				(width 0.1)
				(type default)
			)
			(layer "F.Fab")
		)
		(fp_line
			(start 0.2794 -0.1016)
			(end -0.2794 -0.1016)
			(stroke
				(width 0.1)
				(type default)
			)
			(layer "F.Fab")
		)
		(fp_line
			(start -0.2794 0.9906)
			(end 0.2794 0.9906)
			(stroke
				(width 0.1)
				(type default)
			)
			(layer "F.Fab")
		)
		(fp_line
			(start -0.2794 -0.1016)
			(end -0.2794 0.9906)
			(stroke
				(width 0.1)
				(type default)
			)
			(layer "F.Fab")
		)
		(pad "1" smd rect
			(at 0 0 180)
			(size 0.508 0.508)
			(layers "F.Cu" "F.Mask" "F.Paste")
			(net "CLK_322M_156M_CPU0_OSC_VRM_DP")
		)
		(pad "2" smd rect
			(at 0 0.889 180)
			(size 0.508 0.508)
			(layers "F.Cu" "F.Mask" "F.Paste")
			(net "CLK_156M_OSC_CPU0_HFI_DP")
		)
		(zone
			(layer "F.Cu")
			(hatch none 0.5)
			(connect_pads
				(clearance 0)
			)
			(min_thickness 0.25)
			(keepout
				(tracks not_allowed)
				(vias allowed)
				(pads allowed)
				(copperpour not_allowed)
				(footprints allowed)
			)
			(placement
				(enabled no)
				(sheetname "")
			)
			(fill
				(thermal_gap 0.5)
				(thermal_bridge_width 0.5)
				(island_removal_mode 0)
			)
			(polygon
				(pts
					(xy 319.1256 -28.680918) (xy 318.6176 -28.680918) (xy 318.6176 -28.299918) (xy 319.1256 -28.299918)
				)
			)
		)
		(zone
			(layer "F.Cu")
			(hatch none 0.5)
			(connect_pads
				(clearance 0)
			)
			(min_thickness 0.25)
			(keepout
				(tracks allowed)
				(vias not_allowed)
				(pads allowed)
				(copperpour not_allowed)
				(footprints allowed)
			)
			(placement
				(enabled no)
				(sheetname "")
			)
			(fill
				(thermal_gap 0.5)
				(thermal_bridge_width 0.5)
				(island_removal_mode 0)
			)
			(polygon
				(pts
					(xy 319.1256 -28.299918) (xy 318.6176 -28.299918) (xy 318.6176 -28.680918) (xy 319.1256 -28.680918)
				)
			)
		)
	)
	(footprint ""
		(layer "F.Cu")
		(at 467.9315 -23.0505 180)
		(property "Reference" "EU8F1"
			(at -2.56667 -0.254 90)
			(unlocked yes)
			(layer "F.SilkS")
			(effects
				(font
					(size 0.7874 0.5842)
					(thickness 0.1524)
				)
			)
		)
		(property "Value" ""
			(at 0 0 180)
			(layer "F.Fab")
			(effects
				(font
					(size 1.27 1.27)
				)
			)
		)
		(duplicate_pad_numbers_are_jumpers no)
		(fp_line
			(start 1.050036 0.834898)
			(end 1.050036 1.050036)
			(stroke
				(width 0.1524)
				(type default)
			)
			(layer "F.SilkS")
		)
		(fp_line
			(start 1.050036 -0.834898)
			(end 1.050036 -1.050036)
			(stroke
				(width 0.1524)
				(type default)
			)
			(layer "F.SilkS")
		)
		(fp_line
			(start 0.834898 1.050036)
			(end 1.050036 1.050036)
			(stroke
				(width 0.1524)
				(type default)
			)
			(layer "F.SilkS")
		)
		(fp_line
			(start 0.834898 -1.050036)
			(end 1.050036 -1.050036)
			(stroke
				(width 0.1524)
				(type default)
			)
			(layer "F.SilkS")
		)
		(fp_line
			(start -0.834898 1.050036)
			(end -1.050036 1.050036)
			(stroke
				(width 0.1524)
				(type default)
			)
			(layer "F.SilkS")
		)
		(fp_line
			(start -0.834898 -1.050036)
			(end -1.050036 -1.050036)
			(stroke
				(width 0.1524)
				(type default)
			)
			(layer "F.SilkS")
		)
		(fp_line
			(start -1.050036 0.834898)
			(end -1.050036 1.050036)
			(stroke
				(width 0.1524)
				(type default)
			)
			(layer "F.SilkS")
		)
		(fp_line
			(start -1.050036 -0.834898)
			(end -1.050036 -1.050036)
			(stroke
				(width 0.1524)
				(type default)
			)
			(layer "F.SilkS")
		)
		(fp_circle
			(center -1.675892 -0.964438)
			(end -1.802638 -0.964438)
			(stroke
				(width 0.254)
				(type default)
			)
			(fill no)
			(layer "F.SilkS")
		)
		(fp_rect
			(start 0.4445 -0.4445)
			(end -0.4445 0.4445)
			(stroke
				(width 0)
				(type default)
			)
			(fill yes)
			(layer "F.Paste")
		)
		(fp_rect
			(start 1.050036 -1.050036)
			(end -1.050036 1.050036)
			(stroke
				(width 0)
				(type default)
			)
			(fill no)
			(layer "F.CrtYd")
		)
		(fp_line
			(start 1.050036 1.050036)
			(end -1.050036 1.050036)
			(stroke
				(width 0.1)
				(type default)
			)
			(layer "F.Fab")
		)
		(fp_line
			(start 1.050036 -1.050036)
			(end 1.050036 1.050036)
			(stroke
				(width 0.1)
				(type default)
			)
			(layer "F.Fab")
		)
		(fp_line
			(start -1.050036 1.050036)
			(end -1.050036 -1.050036)
			(stroke
				(width 0.1)
				(type default)
			)
			(layer "F.Fab")
		)
		(fp_line
			(start -1.050036 -1.050036)
			(end 1.050036 -1.050036)
			(stroke
				(width 0.1)
				(type default)
			)
			(layer "F.Fab")
		)
		(fp_circle
			(center -1.675892 -0.964438)
			(end -1.802638 -0.964438)
			(stroke
				(width 0.254)
				(type default)
			)
			(fill no)
			(layer "F.Fab")
		)
		(pad "1" smd custom
			(at -0.9779 -0.40005 180)
			(size 0.0508 0.0508)
			(layers "F.Cu" "F.Mask" "F.Paste")
			(net "VR_P3V3_STBY_LGATE")
			(options
				(clearance outline)
				(anchor circle)
			)
			(primitives
				(gr_poly
					(pts
						(xy -0.3302 0.1016) (xy -0.3302 -0.1016)
						(arc
							(start 0.2286 -0.1016)
							(mid 0.3302 0)
							(end 0.2286 0.1016)
						)
					)
					(width 0)
					(fill yes)
				)
			)
		)
		(pad "2" smd custom
			(at -0.9779 0 180)
			(size 0.0508 0.0508)
			(layers "F.Cu" "F.Mask" "F.Paste")
			(net "VR_P3V3_STBY_PHASE")
			(options
				(clearance outline)
				(anchor circle)
			)
			(primitives
				(gr_poly
					(pts
						(xy -0.3302 0.1016) (xy -0.3302 -0.1016)
						(arc
							(start 0.2286 -0.1016)
							(mid 0.3302 0)
							(end 0.2286 0.1016)
						)
					)
					(width 0)
					(fill yes)
				)
			)
		)
		(pad "3" smd custom
			(at -0.9779 0.40005 180)
			(size 0.0508 0.0508)
			(layers "F.Cu" "F.Mask" "F.Paste")
			(net "VR_P3V3_STBY_UGATE")
			(options
				(clearance outline)
				(anchor circle)
			)
			(primitives
				(gr_poly
					(pts
						(xy -0.3302 0.1016) (xy -0.3302 -0.1016)
						(arc
							(start 0.2286 -0.1016)
							(mid 0.3302 0)
							(end 0.2286 0.1016)
						)
					)
					(width 0)
					(fill yes)
				)
			)
		)
		(pad "4" smd custom
			(at -0.40005 0.9779 180)
			(size 0.0508 0.0508)
			(layers "F.Cu" "F.Mask" "F.Paste")
			(net "VR_P3V3_STBY_BOOT")
			(options
				(clearance outline)
				(anchor circle)
			)
			(primitives
				(gr_poly
					(pts
						(xy 0.1016 0.3302) (xy -0.1016 0.3302)
						(arc
							(start -0.1016 -0.2286)
							(mid 0 -0.3302)
							(end 0.1016 -0.2286)
						)
					)
					(width 0)
					(fill yes)
				)
			)
		)
		(pad "5" smd custom
			(at 0 0.9779 180)
			(size 0.0508 0.0508)
			(layers "F.Cu" "F.Mask" "F.Paste")
			(net "P5V_STBY")
			(options
				(clearance outline)
				(anchor circle)
			)
			(primitives
				(gr_poly
					(pts
						(xy 0.1016 0.3302) (xy -0.1016 0.3302)
						(arc
							(start -0.1016 -0.2286)
							(mid 0 -0.3302)
							(end 0.1016 -0.2286)
						)
					)
					(width 0)
					(fill yes)
				)
			)
		)
		(pad "6" smd custom
			(at 0.40005 0.9779 180)
			(size 0.0508 0.0508)
			(layers "F.Cu" "F.Mask" "F.Paste")
			(net "VSENSE_VOUT_P3V3_STBY")
			(options
				(clearance outline)
				(anchor circle)
			)
			(primitives
				(gr_poly
					(pts
						(xy 0.1016 0.3302) (xy -0.1016 0.3302)
						(arc
							(start -0.1016 -0.2286)
							(mid 0 -0.3302)
							(end 0.1016 -0.2286)
						)
					)
					(width 0)
					(fill yes)
				)
			)
		)
		(pad "7" smd custom
			(at 0.9779 0.40005 180)
			(size 0.0508 0.0508)
			(layers "F.Cu" "F.Mask" "F.Paste")
			(net "VSENSE_RGND_P3V3_STBY")
			(options
				(clearance outline)
				(anchor circle)
			)
			(primitives
				(gr_poly
					(pts
						(xy 0.3302 -0.1016) (xy 0.3302 0.1016)
						(arc
							(start -0.2286 0.1016)
							(mid -0.3302 0)
							(end -0.2286 -0.1016)
						)
					)
					(width 0)
					(fill yes)
				)
			)
		)
		(pad "8" smd custom
			(at 0.9779 0 180)
			(size 0.0508 0.0508)
			(layers "F.Cu" "F.Mask" "F.Paste")
			(net "VR_P3V3_STBY_EN")
			(options
				(clearance outline)
				(anchor circle)
			)
			(primitives
				(gr_poly
					(pts
						(xy 0.3302 -0.1016) (xy 0.3302 0.1016)
						(arc
							(start -0.2286 0.1016)
							(mid -0.3302 0)
							(end -0.2286 -0.1016)
						)
					)
					(width 0)
					(fill yes)
				)
			)
		)
		(pad "9" smd custom
			(at 0.9779 -0.40005 180)
			(size 0.0508 0.0508)
			(layers "F.Cu" "F.Mask" "F.Paste")
			(net "PWRGD_P3V3_STBY_R")
			(options
				(clearance outline)
				(anchor circle)
			)
			(primitives
				(gr_poly
					(pts
						(xy 0.3302 -0.1016) (xy 0.3302 0.1016)
						(arc
							(start -0.2286 0.1016)
							(mid -0.3302 0)
							(end -0.2286 -0.1016)
						)
					)
					(width 0)
					(fill yes)
				)
			)
		)
		(pad "10" smd custom
			(at 0.40005 -0.9779 180)
			(size 0.0508 0.0508)
			(layers "F.Cu" "F.Mask" "F.Paste")
			(net "VR_P3V3_STBY_OCSELECT")
			(options
				(clearance outline)
				(anchor circle)
			)
			(primitives
				(gr_poly
					(pts
						(xy -0.1016 -0.3302) (xy 0.1016 -0.3302)
						(arc
							(start 0.1016 0.2286)
							(mid 0 0.3302)
							(end -0.1016 0.2286)
						)
					)
					(width 0)
					(fill yes)
				)
			)
		)
		(pad "11" smd custom
			(at 0 -0.9779 180)
			(size 0.0508 0.0508)
			(layers "F.Cu" "F.Mask" "F.Paste")
			(net "AGND_P3V3_STBY")
			(options
				(clearance outline)
				(anchor circle)
			)
			(primitives
				(gr_poly
					(pts
						(xy -0.1016 -0.3302) (xy 0.1016 -0.3302)
						(arc
							(start 0.1016 0.2286)
							(mid 0 0.3302)
							(end -0.1016 0.2286)
						)
					)
					(width 0)
					(fill yes)
				)
			)
		)
		(pad "12" smd custom
			(at -0.40005 -0.9779 180)
			(size 0.0508 0.0508)
			(layers "F.Cu" "F.Mask" "F.Paste")
			(net "AGND_P3V3_STBY")
			(options
				(clearance outline)
				(anchor circle)
			)
			(primitives
				(gr_poly
					(pts
						(xy -0.1016 -0.3302) (xy 0.1016 -0.3302)
						(arc
							(start 0.1016 0.2286)
							(mid 0 0.3302)
							(end -0.1016 0.2286)
						)
					)
					(width 0)
					(fill yes)
				)
			)
		)
		(pad "13" smd rect
			(at 0 0 180)
			(size 0.889 0.889)
			(layers "F.Cu" "F.Mask" "F.Paste")
			(net "AGND_P3V3_STBY")
		)
	)
	(footprint ""
		(layer "F.Cu")
		(at 111.000032 -149.8092 90)
		(property "Reference" "C3A2"
			(at 1.848866 0.752348 90)
			(unlocked yes)
			(layer "F.SilkS")
			(effects
				(font
					(size 1.27 0.9652)
					(thickness 0.1524)
				)
			)
		)
		(property "Value" ""
			(at 0 0 90)
			(layer "F.Fab")
			(effects
				(font
					(size 1.27 1.27)
				)
			)
		)
		(duplicate_pad_numbers_are_jumpers no)
		(fp_rect
			(start -0.500126 1.598422)
			(end 0.500126 -0.201422)
			(stroke
				(width 0)
				(type default)
			)
			(fill no)
			(layer "F.CrtYd")
		)
		(fp_line
			(start 0.500126 -0.201422)
			(end 0.500126 1.598422)
			(stroke
				(width 0.1)
				(type default)
			)
			(layer "F.Fab")
		)
		(fp_line
			(start -0.500126 -0.201422)
			(end 0.500126 -0.201422)
			(stroke
				(width 0.1)
				(type default)
			)
			(layer "F.Fab")
		)
		(fp_line
			(start 0.500126 1.598422)
			(end -0.500126 1.598422)
			(stroke
				(width 0.1)
				(type default)
			)
			(layer "F.Fab")
		)
		(fp_line
			(start -0.500126 1.598422)
			(end -0.500126 -0.201422)
			(stroke
				(width 0.1)
				(type default)
			)
			(layer "F.Fab")
		)
		(pad "1" smd rect
			(at 0 0)
			(size 0.889 0.9906)
			(layers "F.Cu" "F.Mask" "F.Paste")
			(net "PVDDQ_KLM")
		)
		(pad "2" smd rect
			(at 0 1.397)
			(size 0.889 0.9906)
			(layers "F.Cu" "F.Mask" "F.Paste")
			(net "GND")
		)
		(zone
			(layer "F.Cu")
			(hatch none 0.5)
			(connect_pads
				(clearance 0)
			)
			(min_thickness 0.25)
			(keepout
				(tracks allowed)
				(vias not_allowed)
				(pads allowed)
				(copperpour not_allowed)
				(footprints allowed)
			)
			(placement
				(enabled no)
				(sheetname "")
			)
			(fill
				(thermal_gap 0.5)
				(thermal_bridge_width 0.5)
				(island_removal_mode 0)
			)
			(polygon
				(pts
					(xy 111.952532 -149.3139) (xy 111.952532 -150.3045) (xy 111.444532 -150.3045) (xy 111.444532 -149.3139)
				)
			)
		)
		(zone
			(layer "F.Cu")
			(hatch none 0.5)
			(connect_pads
				(clearance 0)
			)
			(min_thickness 0.25)
			(keepout
				(tracks not_allowed)
				(vias allowed)
				(pads allowed)
				(copperpour not_allowed)
				(footprints allowed)
			)
			(placement
				(enabled no)
				(sheetname "")
			)
			(fill
				(thermal_gap 0.5)
				(thermal_bridge_width 0.5)
				(island_removal_mode 0)
			)
			(polygon
				(pts
					(xy 111.952532 -149.3139) (xy 111.952532 -150.3045) (xy 111.444532 -150.3045) (xy 111.444532 -149.3139)
				)
			)
		)
	)
	(footprint ""
		(layer "F.Cu")
		(at 163.576 -83.058 -90)
		(property "Reference" "R4D13"
			(at 0 0 270)
			(layer "F.SilkS")
			(hide yes)
			(effects
				(font
					(size 1.27 1.27)
				)
			)
		)
		(property "Value" ""
			(at 0 0 270)
			(layer "F.Fab")
			(effects
				(font
					(size 1.27 1.27)
				)
			)
		)
		(duplicate_pad_numbers_are_jumpers no)
		(fp_poly
			(pts
				(xy -0.2794 -0.1016) (xy 0.2794 -0.1016) (xy 0.2794 0.9906) (xy -0.2794 0.9906)
			)
			(stroke
				(width 0)
				(type default)
			)
			(fill no)
			(layer "F.CrtYd")
		)
		(fp_line
			(start -0.2794 0.9906)
			(end 0.2794 0.9906)
			(stroke
				(width 0.1)
				(type default)
			)
			(layer "F.Fab")
		)
		(fp_line
			(start 0.2794 0.9906)
			(end 0.2794 -0.1016)
			(stroke
				(width 0.1)
				(type default)
			)
			(layer "F.Fab")
		)
		(fp_line
			(start -0.2794 -0.1016)
			(end -0.2794 0.9906)
			(stroke
				(width 0.1)
				(type default)
			)
			(layer "F.Fab")
		)
		(fp_line
			(start 0.2794 -0.1016)
			(end -0.2794 -0.1016)
			(stroke
				(width 0.1)
				(type default)
			)
			(layer "F.Fab")
		)
		(pad "1" smd rect
			(at 0 0 270)
			(size 0.508 0.508)
			(layers "F.Cu" "F.Mask" "F.Paste")
			(net "CLK_100M_CPU1_PE_REFCLK_R_DP")
		)
		(pad "2" smd rect
			(at 0 0.889 270)
			(size 0.508 0.508)
			(layers "F.Cu" "F.Mask" "F.Paste")
			(net "CLK_100M_CPU1_PE_REFCLK_DP")
		)
		(zone
			(layer "F.Cu")
			(hatch none 0.5)
			(connect_pads
				(clearance 0)
			)
			(min_thickness 0.25)
			(keepout
				(tracks not_allowed)
				(vias allowed)
				(pads allowed)
				(copperpour not_allowed)
				(footprints allowed)
			)
			(placement
				(enabled no)
				(sheetname "")
			)
			(fill
				(thermal_gap 0.5)
				(thermal_bridge_width 0.5)
				(island_removal_mode 0)
			)
			(polygon
				(pts
					(xy 162.941 -83.312) (xy 162.941 -82.804) (xy 163.322 -82.804) (xy 163.322 -83.312)
				)
			)
		)
		(zone
			(layer "F.Cu")
			(hatch none 0.5)
			(connect_pads
				(clearance 0)
			)
			(min_thickness 0.25)
			(keepout
				(tracks allowed)
				(vias not_allowed)
				(pads allowed)
				(copperpour not_allowed)
				(footprints allowed)
			)
			(placement
				(enabled no)
				(sheetname "")
			)
			(fill
				(thermal_gap 0.5)
				(thermal_bridge_width 0.5)
				(island_removal_mode 0)
			)
			(polygon
				(pts
					(xy 163.322 -83.312) (xy 163.322 -82.804) (xy 162.941 -82.804) (xy 162.941 -83.312)
				)
			)
		)
	)
	(footprint ""
		(layer "F.Cu")
		(at 188.137038 -65.27546 180)
		(property "Reference" "RF1"
			(at -0.8382 -0.67818 180)
			(unlocked yes)
			(layer "F.SilkS")
			(effects
				(font
					(size 0.4064 0.254)
					(thickness 0.1524)
				)
				(justify left)
			)
		)
		(property "Value" ""
			(at 0 0 180)
			(layer "F.Fab")
			(effects
				(font
					(size 1.27 1.27)
				)
			)
		)
		(duplicate_pad_numbers_are_jumpers no)
		(fp_poly
			(pts
				(xy -0.2794 -0.1016) (xy 0.2794 -0.1016) (xy 0.2794 0.9906) (xy -0.2794 0.9906)
			)
			(stroke
				(width 0)
				(type default)
			)
			(fill no)
			(layer "F.CrtYd")
		)
		(fp_line
			(start 0.2794 0.9906)
			(end 0.2794 -0.1016)
			(stroke
				(width 0.1)
				(type default)
			)
			(layer "F.Fab")
		)
		(fp_line
			(start 0.2794 -0.1016)
			(end -0.2794 -0.1016)
			(stroke
				(width 0.1)
				(type default)
			)
			(layer "F.Fab")
		)
		(fp_line
			(start -0.2794 0.9906)
			(end 0.2794 0.9906)
			(stroke
				(width 0.1)
				(type default)
			)
			(layer "F.Fab")
		)
		(fp_line
			(start -0.2794 -0.1016)
			(end -0.2794 0.9906)
			(stroke
				(width 0.1)
				(type default)
			)
			(layer "F.Fab")
		)
		(pad "1" smd rect
			(at 0 0 180)
			(size 0.508 0.508)
			(layers "F.Cu" "F.Mask" "F.Paste")
			(net "VR_PVCCIN_CPU0_AIREF1")
		)
		(pad "2" smd rect
			(at 0 0.889 180)
			(size 0.508 0.508)
			(layers "F.Cu" "F.Mask" "F.Paste")
			(net "ISENSE_PVCCIN_CPU0_PH1_IMON")
		)
		(zone
			(layer "F.Cu")
			(hatch none 0.5)
			(connect_pads
				(clearance 0)
			)
			(min_thickness 0.25)
			(keepout
				(tracks not_allowed)
				(vias allowed)
				(pads allowed)
				(copperpour not_allowed)
				(footprints allowed)
			)
			(placement
				(enabled no)
				(sheetname "")
			)
			(fill
				(thermal_gap 0.5)
				(thermal_bridge_width 0.5)
				(island_removal_mode 0)
			)
			(polygon
				(pts
					(xy 188.391038 -65.91046) (xy 187.883038 -65.91046) (xy 187.883038 -65.52946) (xy 188.391038 -65.52946)
				)
			)
		)
		(zone
			(layer "F.Cu")
			(hatch none 0.5)
			(connect_pads
				(clearance 0)
			)
			(min_thickness 0.25)
			(keepout
				(tracks allowed)
				(vias not_allowed)
				(pads allowed)
				(copperpour not_allowed)
				(footprints allowed)
			)
			(placement
				(enabled no)
				(sheetname "")
			)
			(fill
				(thermal_gap 0.5)
				(thermal_bridge_width 0.5)
				(island_removal_mode 0)
			)
			(polygon
				(pts
					(xy 188.391038 -65.52946) (xy 187.883038 -65.52946) (xy 187.883038 -65.91046) (xy 188.391038 -65.91046)
				)
			)
		)
	)
	(footprint ""
		(layer "F.Cu")
		(at 30.477968 -140.0556 90)
		(property "Reference" "C1A17"
			(at 0 0 90)
			(layer "F.SilkS")
			(hide yes)
			(effects
				(font
					(size 1.27 1.27)
				)
			)
		)
		(property "Value" ""
			(at 0 0 90)
			(layer "F.Fab")
			(effects
				(font
					(size 1.27 1.27)
				)
			)
		)
		(duplicate_pad_numbers_are_jumpers no)
		(fp_poly
			(pts
				(xy 0.3048 -0.1016) (xy 0.3048 0.9906) (xy -0.3048 0.9906) (xy -0.3048 -0.1016)
			)
			(stroke
				(width 0)
				(type default)
			)
			(fill no)
			(layer "F.CrtYd")
		)
		(fp_line
			(start 0.3048 -0.1016)
			(end -0.3048 -0.1016)
			(stroke
				(width 0.1)
				(type default)
			)
			(layer "F.Fab")
		)
		(fp_line
			(start -0.3048 -0.1016)
			(end -0.3048 0.9906)
			(stroke
				(width 0.1)
				(type default)
			)
			(layer "F.Fab")
		)
		(fp_line
			(start 0.3048 0.9906)
			(end 0.3048 -0.1016)
			(stroke
				(width 0.1)
				(type default)
			)
			(layer "F.Fab")
		)
		(fp_line
			(start -0.3048 0.9906)
			(end 0.3048 0.9906)
			(stroke
				(width 0.1)
				(type default)
			)
			(layer "F.Fab")
		)
		(pad "1" smd rect
			(at 0 0 90)
			(size 0.508 0.508)
			(layers "F.Cu" "F.Mask" "F.Paste")
			(net "M_L_VREF")
		)
		(pad "2" smd rect
			(at 0 0.889 90)
			(size 0.508 0.508)
			(layers "F.Cu" "F.Mask" "F.Paste")
			(net "GND")
		)
		(zone
			(layer "F.Cu")
			(hatch none 0.5)
			(connect_pads
				(clearance 0)
			)
			(min_thickness 0.25)
			(keepout
				(tracks allowed)
				(vias not_allowed)
				(pads allowed)
				(copperpour not_allowed)
				(footprints allowed)
			)
			(placement
				(enabled no)
				(sheetname "")
			)
			(fill
				(thermal_gap 0.5)
				(thermal_bridge_width 0.5)
				(island_removal_mode 0)
			)
			(polygon
				(pts
					(xy 30.731968 -139.8016) (xy 30.731968 -140.3096) (xy 31.112968 -140.3096) (xy 31.112968 -139.8016)
				)
			)
		)
		(zone
			(layer "F.Cu")
			(hatch none 0.5)
			(connect_pads
				(clearance 0)
			)
			(min_thickness 0.25)
			(keepout
				(tracks not_allowed)
				(vias allowed)
				(pads allowed)
				(copperpour not_allowed)
				(footprints allowed)
			)
			(placement
				(enabled no)
				(sheetname "")
			)
			(fill
				(thermal_gap 0.5)
				(thermal_bridge_width 0.5)
				(island_removal_mode 0)
			)
			(polygon
				(pts
					(xy 31.112968 -139.8016) (xy 31.112968 -140.3096) (xy 30.731968 -140.3096) (xy 30.731968 -139.8016)
				)
			)
		)
	)
	(footprint ""
		(layer "F.Cu")
		(at 485.87406 -122.91314 90)
		(property "Reference" "R9B5"
			(at 0 0 90)
			(layer "F.SilkS")
			(hide yes)
			(effects
				(font
					(size 1.27 1.27)
				)
			)
		)
		(property "Value" ""
			(at 0 0 90)
			(layer "F.Fab")
			(effects
				(font
					(size 1.27 1.27)
				)
			)
		)
		(duplicate_pad_numbers_are_jumpers no)
		(fp_rect
			(start 0.2794 0.9906)
			(end -0.2794 -0.1016)
			(stroke
				(width 0)
				(type default)
			)
			(fill no)
			(layer "F.CrtYd")
		)
		(fp_line
			(start 0.2794 -0.1016)
			(end -0.2794 -0.1016)
			(stroke
				(width 0.1)
				(type default)
			)
			(layer "F.Fab")
		)
		(fp_line
			(start -0.2794 -0.1016)
			(end -0.2794 0.9906)
			(stroke
				(width 0.1)
				(type default)
			)
			(layer "F.Fab")
		)
		(fp_line
			(start 0.2794 0.9906)
			(end 0.2794 -0.1016)
			(stroke
				(width 0.1)
				(type default)
			)
			(layer "F.Fab")
		)
		(fp_line
			(start -0.2794 0.9906)
			(end 0.2794 0.9906)
			(stroke
				(width 0.1)
				(type default)
			)
			(layer "F.Fab")
		)
		(pad "1" smd rect
			(at 0 0 90)
			(size 0.508 0.508)
			(layers "F.Cu" "F.Mask" "F.Paste")
			(net "ISENSE_TMP421_1_BC")
		)
		(pad "2" smd rect
			(at 0 0.889 90)
			(size 0.508 0.508)
			(layers "F.Cu" "F.Mask" "F.Paste")
			(net "ISENSE_TMP421_1_DXN")
		)
		(zone
			(layer "F.Cu")
			(hatch none 0.5)
			(connect_pads
				(clearance 0)
			)
			(min_thickness 0.25)
			(keepout
				(tracks allowed)
				(vias not_allowed)
				(pads allowed)
				(copperpour not_allowed)
				(footprints allowed)
			)
			(placement
				(enabled no)
				(sheetname "")
			)
			(fill
				(thermal_gap 0.5)
				(thermal_bridge_width 0.5)
				(island_removal_mode 0)
			)
			(polygon
				(pts
					(xy 486.50906 -123.16714) (xy 486.12806 -123.16714) (xy 486.12806 -122.65914) (xy 486.50906 -122.65914)
				)
			)
		)
	)
	(footprint ""
		(layer "F.Cu")
		(at -1.8542 -134.3152 90)
		(property "Reference" "CT7"
			(at -2.79273 1.3716 180)
			(unlocked yes)
			(layer "F.SilkS")
			(effects
				(font
					(size 0.7874 0.5842)
					(thickness 0.1524)
				)
				(justify left)
			)
		)
		(property "Value" ""
			(at 0 0 90)
			(layer "F.Fab")
			(effects
				(font
					(size 1.27 1.27)
				)
			)
		)
		(duplicate_pad_numbers_are_jumpers no)
		(fp_poly
			(pts
				(xy 0.3048 -0.1016) (xy 0.3048 0.9906) (xy -0.3048 0.9906) (xy -0.3048 -0.1016)
			)
			(stroke
				(width 0)
				(type default)
			)
			(fill no)
			(layer "F.CrtYd")
		)
		(fp_line
			(start 0.3048 -0.1016)
			(end -0.3048 -0.1016)
			(stroke
				(width 0.1)
				(type default)
			)
			(layer "F.Fab")
		)
		(fp_line
			(start -0.3048 -0.1016)
			(end -0.3048 0.9906)
			(stroke
				(width 0.1)
				(type default)
			)
			(layer "F.Fab")
		)
		(fp_line
			(start 0.3048 0.9906)
			(end 0.3048 -0.1016)
			(stroke
				(width 0.1)
				(type default)
			)
			(layer "F.Fab")
		)
		(fp_line
			(start -0.3048 0.9906)
			(end 0.3048 0.9906)
			(stroke
				(width 0.1)
				(type default)
			)
			(layer "F.Fab")
		)
		(pad "1" smd rect
			(at 0 0 90)
			(size 0.508 0.508)
			(layers "F.Cu" "F.Mask" "F.Paste")
			(net "VR_PVDDQ_KLM_AIREF1")
		)
		(pad "2" smd rect
			(at 0 0.889 90)
			(size 0.508 0.508)
			(layers "F.Cu" "F.Mask" "F.Paste")
			(net "GND")
		)
		(zone
			(layer "F.Cu")
			(hatch none 0.5)
			(connect_pads
				(clearance 0)
			)
			(min_thickness 0.25)
			(keepout
				(tracks allowed)
				(vias not_allowed)
				(pads allowed)
				(copperpour not_allowed)
				(footprints allowed)
			)
			(placement
				(enabled no)
				(sheetname "")
			)
			(fill
				(thermal_gap 0.5)
				(thermal_bridge_width 0.5)
				(island_removal_mode 0)
			)
			(polygon
				(pts
					(xy -1.6002 -134.0612) (xy -1.6002 -134.5692) (xy -1.2192 -134.5692) (xy -1.2192 -134.0612)
				)
			)
		)
		(zone
			(layer "F.Cu")
			(hatch none 0.5)
			(connect_pads
				(clearance 0)
			)
			(min_thickness 0.25)
			(keepout
				(tracks not_allowed)
				(vias allowed)
				(pads allowed)
				(copperpour not_allowed)
				(footprints allowed)
			)
			(placement
				(enabled no)
				(sheetname "")
			)
			(fill
				(thermal_gap 0.5)
				(thermal_bridge_width 0.5)
				(island_removal_mode 0)
			)
			(polygon
				(pts
					(xy -1.2192 -134.0612) (xy -1.2192 -134.5692) (xy -1.6002 -134.5692) (xy -1.6002 -134.0612)
				)
			)
		)
	)
	(footprint ""
		(layer "F.Cu")
		(at 368.554 -94.742 90)
		(property "Reference" "R7C8"
			(at 0 0 90)
			(layer "F.SilkS")
			(hide yes)
			(effects
				(font
					(size 1.27 1.27)
				)
			)
		)
		(property "Value" ""
			(at 0 0 90)
			(layer "F.Fab")
			(effects
				(font
					(size 1.27 1.27)
				)
			)
		)
		(duplicate_pad_numbers_are_jumpers no)
		(fp_poly
			(pts
				(xy -0.2794 -0.1016) (xy 0.2794 -0.1016) (xy 0.2794 0.9906) (xy -0.2794 0.9906)
			)
			(stroke
				(width 0)
				(type default)
			)
			(fill no)
			(layer "F.CrtYd")
		)
		(fp_line
			(start 0.2794 -0.1016)
			(end -0.2794 -0.1016)
			(stroke
				(width 0.1)
				(type default)
			)
			(layer "F.Fab")
		)
		(fp_line
			(start -0.2794 -0.1016)
			(end -0.2794 0.9906)
			(stroke
				(width 0.1)
				(type default)
			)
			(layer "F.Fab")
		)
		(fp_line
			(start 0.2794 0.9906)
			(end 0.2794 -0.1016)
			(stroke
				(width 0.1)
				(type default)
			)
			(layer "F.Fab")
		)
		(fp_line
			(start -0.2794 0.9906)
			(end 0.2794 0.9906)
			(stroke
				(width 0.1)
				(type default)
			)
			(layer "F.Fab")
		)
		(pad "1" smd rect
			(at 0 0 90)
			(size 0.508 0.508)
			(layers "F.Cu" "F.Mask" "F.Paste")
			(net "P3V3_STBY")
		)
		(pad "2" smd rect
			(at 0 0.889 90)
			(size 0.508 0.508)
			(layers "F.Cu" "F.Mask" "F.Paste")
			(net "FM_WBG_PRSNT_N")
		)
		(zone
			(layer "F.Cu")
			(hatch none 0.5)
			(connect_pads
				(clearance 0)
			)
			(min_thickness 0.25)
			(keepout
				(tracks allowed)
				(vias not_allowed)
				(pads allowed)
				(copperpour not_allowed)
				(footprints allowed)
			)
			(placement
				(enabled no)
				(sheetname "")
			)
			(fill
				(thermal_gap 0.5)
				(thermal_bridge_width 0.5)
				(island_removal_mode 0)
			)
			(polygon
				(pts
					(xy 368.808 -94.488) (xy 368.808 -94.996) (xy 369.189 -94.996) (xy 369.189 -94.488)
				)
			)
		)
		(zone
			(layer "F.Cu")
			(hatch none 0.5)
			(connect_pads
				(clearance 0)
			)
			(min_thickness 0.25)
			(keepout
				(tracks not_allowed)
				(vias allowed)
				(pads allowed)
				(copperpour not_allowed)
				(footprints allowed)
			)
			(placement
				(enabled no)
				(sheetname "")
			)
			(fill
				(thermal_gap 0.5)
				(thermal_bridge_width 0.5)
				(island_removal_mode 0)
			)
			(polygon
				(pts
					(xy 369.189 -94.488) (xy 369.189 -94.996) (xy 368.808 -94.996) (xy 368.808 -94.488)
				)
			)
		)
	)
	(footprint ""
		(layer "F.Cu")
		(at 341.3252 -154.801824 180)
		(property "Reference" "L7A1"
			(at 3.378708 -4.251706 180)
			(unlocked yes)
			(layer "F.SilkS")
			(effects
				(font
					(size 0.4064 0.254)
					(thickness 0.1524)
				)
			)
		)
		(property "Value" ""
			(at 0 0 180)
			(layer "F.Fab")
			(effects
				(font
					(size 1.27 1.27)
				)
			)
		)
		(duplicate_pad_numbers_are_jumpers no)
		(fp_line
			(start 8.3693 3.199892)
			(end -1.1303 3.199892)
			(stroke
				(width 0.1524)
				(type default)
			)
			(layer "F.SilkS")
		)
		(fp_line
			(start 8.3693 1.6637)
			(end 8.3693 3.199892)
			(stroke
				(width 0.1524)
				(type default)
			)
			(layer "F.SilkS")
		)
		(fp_line
			(start 8.3693 -3.199892)
			(end 8.3693 -1.6637)
			(stroke
				(width 0.1524)
				(type default)
			)
			(layer "F.SilkS")
		)
		(fp_line
			(start -1.1303 3.199892)
			(end -1.1303 1.6637)
			(stroke
				(width 0.1524)
				(type default)
			)
			(layer "F.SilkS")
		)
		(fp_line
			(start -1.1303 -1.6637)
			(end -1.1303 -3.199892)
			(stroke
				(width 0.1524)
				(type default)
			)
			(layer "F.SilkS")
		)
		(fp_line
			(start -1.1303 -3.199892)
			(end 8.3693 -3.199892)
			(stroke
				(width 0.1524)
				(type default)
			)
			(layer "F.SilkS")
		)
		(fp_rect
			(start -1.1303 3.199892)
			(end 8.3693 -3.199892)
			(stroke
				(width 0)
				(type default)
			)
			(fill no)
			(layer "F.CrtYd")
		)
		(fp_line
			(start 8.3693 3.199892)
			(end -1.1303 3.199892)
			(stroke
				(width 0.1)
				(type default)
			)
			(layer "F.Fab")
		)
		(fp_line
			(start 8.3693 -3.199892)
			(end 8.3693 3.199892)
			(stroke
				(width 0.1)
				(type default)
			)
			(layer "F.Fab")
		)
		(fp_line
			(start -1.1303 3.199892)
			(end -1.1303 -3.199892)
			(stroke
				(width 0.1)
				(type default)
			)
			(layer "F.Fab")
		)
		(fp_line
			(start -1.1303 -3.199892)
			(end 8.3693 -3.199892)
			(stroke
				(width 0.1)
				(type default)
			)
			(layer "F.Fab")
		)
		(pad "1" smd rect
			(at 0 0 180)
			(size 3.683 2.667)
			(layers "F.Cu" "F.Mask" "F.Paste")
			(net "VR_PVDDQ_DEF_PH1_SW")
		)
		(pad "2" smd rect
			(at 7.239 0 180)
			(size 3.683 2.667)
			(layers "F.Cu" "F.Mask" "F.Paste")
			(net "PVDDQ_DEF")
		)
	)
	(footprint ""
		(layer "F.Cu")
		(at 476.4786 -41.9989 180)
		(property "Reference" "C9E8"
			(at 0 0 180)
			(layer "F.SilkS")
			(hide yes)
			(effects
				(font
					(size 1.27 1.27)
				)
			)
		)
		(property "Value" ""
			(at 0 0 180)
			(layer "F.Fab")
			(effects
				(font
					(size 1.27 1.27)
				)
			)
		)
		(duplicate_pad_numbers_are_jumpers no)
		(fp_poly
			(pts
				(xy 0.3048 -0.1016) (xy 0.3048 0.9906) (xy -0.3048 0.9906) (xy -0.3048 -0.1016)
			)
			(stroke
				(width 0)
				(type default)
			)
			(fill no)
			(layer "F.CrtYd")
		)
		(fp_line
			(start 0.3048 0.9906)
			(end 0.3048 -0.1016)
			(stroke
				(width 0.1)
				(type default)
			)
			(layer "F.Fab")
		)
		(fp_line
			(start 0.3048 -0.1016)
			(end -0.3048 -0.1016)
			(stroke
				(width 0.1)
				(type default)
			)
			(layer "F.Fab")
		)
		(fp_line
			(start -0.3048 0.9906)
			(end 0.3048 0.9906)
			(stroke
				(width 0.1)
				(type default)
			)
			(layer "F.Fab")
		)
		(fp_line
			(start -0.3048 -0.1016)
			(end -0.3048 0.9906)
			(stroke
				(width 0.1)
				(type default)
			)
			(layer "F.Fab")
		)
		(pad "1" smd rect
			(at 0 0 180)
			(size 0.508 0.508)
			(layers "F.Cu" "F.Mask" "F.Paste")
			(net "XTAL_25MHZ_OUT_R")
		)
		(pad "2" smd rect
			(at 0 0.889 180)
			(size 0.508 0.508)
			(layers "F.Cu" "F.Mask" "F.Paste")
			(net "GND")
		)
		(zone
			(layer "F.Cu")
			(hatch none 0.5)
			(connect_pads
				(clearance 0)
			)
			(min_thickness 0.25)
			(keepout
				(tracks not_allowed)
				(vias allowed)
				(pads allowed)
				(copperpour not_allowed)
				(footprints allowed)
			)
			(placement
				(enabled no)
				(sheetname "")
			)
			(fill
				(thermal_gap 0.5)
				(thermal_bridge_width 0.5)
				(island_removal_mode 0)
			)
			(polygon
				(pts
					(xy 476.7326 -42.6339) (xy 476.2246 -42.6339) (xy 476.2246 -42.2529) (xy 476.7326 -42.2529)
				)
			)
		)
		(zone
			(layer "F.Cu")
			(hatch none 0.5)
			(connect_pads
				(clearance 0)
			)
			(min_thickness 0.25)
			(keepout
				(tracks allowed)
				(vias not_allowed)
				(pads allowed)
				(copperpour not_allowed)
				(footprints allowed)
			)
			(placement
				(enabled no)
				(sheetname "")
			)
			(fill
				(thermal_gap 0.5)
				(thermal_bridge_width 0.5)
				(island_removal_mode 0)
			)
			(polygon
				(pts
					(xy 476.7326 -42.2529) (xy 476.2246 -42.2529) (xy 476.2246 -42.6339) (xy 476.7326 -42.6339)
				)
			)
		)
	)
	(footprint ""
		(layer "F.Cu")
		(at -3.180588 -119.4435)
		(property "Reference" "U1B2"
			(at 0 0 0)
			(layer "F.SilkS")
			(hide yes)
			(effects
				(font
					(size 1.27 1.27)
				)
			)
		)
		(property "Value" "*"
			(at -0.1143 -9.3091 0)
			(unlocked yes)
			(layer "F.Fab")
			(hide yes)
			(effects
				(font
					(size 1.27 1.016)
					(thickness 0.1524)
				)
			)
		)
		(property "Device Type" "TCA9517DGKR-GP_DISCRET-G8-TCA9A"
			(at -0.1143 -10.9093 0)
			(unlocked yes)
			(layer "F.Fab")
			(hide yes)
			(effects
				(font
					(size 1.27 1.016)
					(thickness 0.1524)
				)
			)
		)
		(duplicate_pad_numbers_are_jumpers no)
		(fp_line
			(start -1.9558 -1.016)
			(end -1.9558 1.016)
			(stroke
				(width 0.1524)
				(type default)
			)
			(layer "F.SilkS")
		)
		(fp_line
			(start -1.9558 -0.5461)
			(end -1.4478 -0.0381)
			(stroke
				(width 0.1524)
				(type default)
			)
			(layer "F.SilkS")
		)
		(fp_line
			(start -1.9558 1.016)
			(end 1.0795 1.016)
			(stroke
				(width 0.1524)
				(type default)
			)
			(layer "F.SilkS")
		)
		(fp_line
			(start -1.778 1.0922)
			(end -1.778 3.048)
			(stroke
				(width 0.508)
				(type default)
			)
			(layer "F.SilkS")
		)
		(fp_line
			(start -1.4478 -0.0381)
			(end -1.9558 0.4699)
			(stroke
				(width 0.1524)
				(type default)
			)
			(layer "F.SilkS")
		)
		(fp_line
			(start 1.0795 -1.016)
			(end -1.9558 -1.016)
			(stroke
				(width 0.1524)
				(type default)
			)
			(layer "F.SilkS")
		)
		(fp_line
			(start 1.0795 1.016)
			(end 1.0795 -1.016)
			(stroke
				(width 0.1524)
				(type default)
			)
			(layer "F.SilkS")
		)
		(fp_poly
			(pts
				(xy -1.1557 -1.016) (xy -1.1557 1.016) (xy 1.1557 1.016) (xy 1.1557 -1.016)
			)
			(stroke
				(width 0)
				(type default)
			)
			(fill yes)
			(layer "F.SilkS")
		)
		(fp_rect
			(start -1.4986 2.4511)
			(end 1.4986 -2.4511)
			(stroke
				(width 0)
				(type default)
			)
			(fill no)
			(layer "F.CrtYd")
		)
		(fp_poly
			(pts
				(xy -2.032 3.302) (xy -2.032 -3.302) (xy 2.032 -3.302) (xy 2.032 -2.1209) (xy 1.4986 -2.1209) (xy 1.4986 -2.4511)
				(xy -1.4986 -2.4511) (xy -1.4986 2.4511) (xy 1.4986 2.4511) (xy 1.4986 -2.1082) (xy 2.032 -2.1082)
				(xy 2.032 3.302)
			)
			(stroke
				(width 0)
				(type default)
			)
			(fill no)
			(layer "F.CrtYd")
		)
		(fp_rect
			(start -2.032 3.302)
			(end 2.032 -3.302)
			(stroke
				(width 0)
				(type default)
			)
			(fill no)
			(layer "F.Fab")
		)
		(pad "1" smd rect
			(at -0.97536 2.05486)
			(size 0.3556 1.524)
			(layers "F.Cu" "F.Mask" "F.Paste")
			(net "PVCCIO_CPU1")
		)
		(pad "2" smd rect
			(at -0.32512 2.05486)
			(size 0.3556 1.524)
			(layers "F.Cu" "F.Mask" "F.Paste")
			(net "SMB_CPU1_PE_HP_GTL_R_SCL")
		)
		(pad "3" smd rect
			(at 0.32512 2.05486)
			(size 0.3556 1.524)
			(layers "F.Cu" "F.Mask" "F.Paste")
			(net "SMB_CPU1_PE_HP_GTL_R_SDA")
		)
		(pad "4" smd rect
			(at 0.97536 2.05486)
			(size 0.3556 1.524)
			(layers "F.Cu" "F.Mask" "F.Paste")
			(net "GND")
		)
		(pad "5" smd rect
			(at 0.97536 -2.05486)
			(size 0.3556 1.524)
			(layers "F.Cu" "F.Mask" "F.Paste")
			(net "TP_SMB_PEHPCPU1_EN")
		)
		(pad "6" smd rect
			(at 0.32512 -2.05486)
			(size 0.3556 1.524)
			(layers "F.Cu" "F.Mask" "F.Paste")
			(net "SMB_PEHPCPU1_STBY_LVC3_R_SDA")
		)
		(pad "7" smd rect
			(at -0.32512 -2.05486)
			(size 0.3556 1.524)
			(layers "F.Cu" "F.Mask" "F.Paste")
			(net "SMB_PEHPCPU1_STBY_LVC3_R_SCL")
		)
		(pad "8" smd rect
			(at -0.97536 -2.05486)
			(size 0.3556 1.524)
			(layers "F.Cu" "F.Mask" "F.Paste")
			(net "P3V3_STBY")
		)
	)
	(footprint ""
		(layer "F.Cu")
		(at 337.429602 -120.038368 -90)
		(property "Reference" "C835"
			(at -0.8382 -0.67818 270)
			(unlocked yes)
			(layer "F.SilkS")
			(effects
				(font
					(size 0.4064 0.254)
					(thickness 0.1524)
				)
				(justify left)
			)
		)
		(property "Value" ""
			(at 0 0 270)
			(layer "F.Fab")
			(effects
				(font
					(size 1.27 1.27)
				)
			)
		)
		(duplicate_pad_numbers_are_jumpers no)
		(fp_poly
			(pts
				(xy 0.3048 -0.1016) (xy 0.3048 0.9906) (xy -0.3048 0.9906) (xy -0.3048 -0.1016)
			)
			(stroke
				(width 0)
				(type default)
			)
			(fill no)
			(layer "F.CrtYd")
		)
		(fp_line
			(start -0.3048 0.9906)
			(end 0.3048 0.9906)
			(stroke
				(width 0.1)
				(type default)
			)
			(layer "F.Fab")
		)
		(fp_line
			(start 0.3048 0.9906)
			(end 0.3048 -0.1016)
			(stroke
				(width 0.1)
				(type default)
			)
			(layer "F.Fab")
		)
		(fp_line
			(start -0.3048 -0.1016)
			(end -0.3048 0.9906)
			(stroke
				(width 0.1)
				(type default)
			)
			(layer "F.Fab")
		)
		(fp_line
			(start 0.3048 -0.1016)
			(end -0.3048 -0.1016)
			(stroke
				(width 0.1)
				(type default)
			)
			(layer "F.Fab")
		)
		(pad "1" smd rect
			(at 0 0 270)
			(size 0.508 0.508)
			(layers "F.Cu" "F.Mask" "F.Paste")
			(net "P3E_CPU0_PE1_PCH_TXP<10>")
		)
		(pad "2" smd rect
			(at 0 0.889 270)
			(size 0.508 0.508)
			(layers "F.Cu" "F.Mask" "F.Paste")
			(net "P3E_CPU0_PE1_PCH_CON_TXP<10>")
		)
		(zone
			(layer "F.Cu")
			(hatch none 0.5)
			(connect_pads
				(clearance 0)
			)
			(min_thickness 0.25)
			(keepout
				(tracks not_allowed)
				(vias allowed)
				(pads allowed)
				(copperpour not_allowed)
				(footprints allowed)
			)
			(placement
				(enabled no)
				(sheetname "")
			)
			(fill
				(thermal_gap 0.5)
				(thermal_bridge_width 0.5)
				(island_removal_mode 0)
			)
			(polygon
				(pts
					(xy 336.794602 -120.292368) (xy 336.794602 -119.784368) (xy 337.175602 -119.784368) (xy 337.175602 -120.292368)
				)
			)
		)
		(zone
			(layer "F.Cu")
			(hatch none 0.5)
			(connect_pads
				(clearance 0)
			)
			(min_thickness 0.25)
			(keepout
				(tracks allowed)
				(vias not_allowed)
				(pads allowed)
				(copperpour not_allowed)
				(footprints allowed)
			)
			(placement
				(enabled no)
				(sheetname "")
			)
			(fill
				(thermal_gap 0.5)
				(thermal_bridge_width 0.5)
				(island_removal_mode 0)
			)
			(polygon
				(pts
					(xy 337.175602 -120.292368) (xy 337.175602 -119.784368) (xy 336.794602 -119.784368) (xy 336.794602 -120.292368)
				)
			)
		)
	)
	(footprint ""
		(layer "F.Cu")
		(at 173.355 -8.6995)
		(property "Reference" "C4G8"
			(at 0 0 0)
			(layer "F.SilkS")
			(hide yes)
			(effects
				(font
					(size 1.27 1.27)
				)
			)
		)
		(property "Value" ""
			(at 0 0 0)
			(layer "F.Fab")
			(effects
				(font
					(size 1.27 1.27)
				)
			)
		)
		(duplicate_pad_numbers_are_jumpers no)
		(fp_rect
			(start -0.3048 0.9906)
			(end 0.3048 -0.1016)
			(stroke
				(width 0)
				(type default)
			)
			(fill no)
			(layer "F.CrtYd")
		)
		(fp_line
			(start -0.3048 -0.1016)
			(end -0.3048 0.9906)
			(stroke
				(width 0.1)
				(type default)
			)
			(layer "F.Fab")
		)
		(fp_line
			(start -0.3048 0.9906)
			(end 0.3048 0.9906)
			(stroke
				(width 0.1)
				(type default)
			)
			(layer "F.Fab")
		)
		(fp_line
			(start 0.3048 -0.1016)
			(end -0.3048 -0.1016)
			(stroke
				(width 0.1)
				(type default)
			)
			(layer "F.Fab")
		)
		(fp_line
			(start 0.3048 0.9906)
			(end 0.3048 -0.1016)
			(stroke
				(width 0.1)
				(type default)
			)
			(layer "F.Fab")
		)
		(pad "1" smd rect
			(at 0 0)
			(size 0.508 0.508)
			(layers "F.Cu" "F.Mask" "F.Paste")
			(net "VR_PVPP_GHJ_SS")
		)
		(pad "2" smd rect
			(at 0 0.889)
			(size 0.508 0.508)
			(layers "F.Cu" "F.Mask" "F.Paste")
			(net "AGND_PVPP_GHJ")
		)
		(zone
			(layer "F.Cu")
			(hatch none 0.5)
			(connect_pads
				(clearance 0)
			)
			(min_thickness 0.25)
			(keepout
				(tracks allowed)
				(vias not_allowed)
				(pads allowed)
				(copperpour not_allowed)
				(footprints allowed)
			)
			(placement
				(enabled no)
				(sheetname "")
			)
			(fill
				(thermal_gap 0.5)
				(thermal_bridge_width 0.5)
				(island_removal_mode 0)
			)
			(polygon
				(pts
					(xy 173.101 -8.0645) (xy 173.609 -8.0645) (xy 173.609 -8.4455) (xy 173.101 -8.4455)
				)
			)
		)
		(zone
			(layer "F.Cu")
			(hatch none 0.5)
			(connect_pads
				(clearance 0)
			)
			(min_thickness 0.25)
			(keepout
				(tracks not_allowed)
				(vias allowed)
				(pads allowed)
				(copperpour not_allowed)
				(footprints allowed)
			)
			(placement
				(enabled no)
				(sheetname "")
			)
			(fill
				(thermal_gap 0.5)
				(thermal_bridge_width 0.5)
				(island_removal_mode 0)
			)
			(polygon
				(pts
					(xy 173.101 -8.0645) (xy 173.609 -8.0645) (xy 173.609 -8.4455) (xy 173.101 -8.4455)
				)
			)
		)
	)
	(footprint ""
		(layer "F.Cu")
		(at 166.3446 -26.1747 90)
		(property "Reference" "C4F7"
			(at 2.88163 1.9304 0)
			(unlocked yes)
			(layer "F.SilkS")
			(effects
				(font
					(size 0.7874 0.5842)
					(thickness 0.1524)
				)
				(justify left)
			)
		)
		(property "Value" ""
			(at 0 0 90)
			(layer "F.Fab")
			(effects
				(font
					(size 1.27 1.27)
				)
			)
		)
		(duplicate_pad_numbers_are_jumpers no)
		(fp_line
			(start 2.032 -1.524)
			(end 2.032 1.524)
			(stroke
				(width 0.1524)
				(type default)
			)
			(layer "F.SilkS")
		)
		(fp_line
			(start 1.7272 -1.524)
			(end 2.032 -1.524)
			(stroke
				(width 0.1524)
				(type default)
			)
			(layer "F.SilkS")
		)
		(fp_line
			(start -1.7272 -1.524)
			(end -2.032 -1.524)
			(stroke
				(width 0.1524)
				(type default)
			)
			(layer "F.SilkS")
		)
		(fp_line
			(start -2.032 -1.524)
			(end -2.032 1.524)
			(stroke
				(width 0.1524)
				(type default)
			)
			(layer "F.SilkS")
		)
		(fp_line
			(start 2.2987 -0.2413)
			(end 2.032 -0.2413)
			(stroke
				(width 0.1524)
				(type default)
			)
			(layer "F.SilkS")
		)
		(fp_line
			(start -2.032 -0.2413)
			(end -2.2987 -0.2413)
			(stroke
				(width 0.1524)
				(type default)
			)
			(layer "F.SilkS")
		)
		(fp_line
			(start -2.2987 -0.2413)
			(end -2.2987 7.3533)
			(stroke
				(width 0.1524)
				(type default)
			)
			(layer "F.SilkS")
		)
		(fp_line
			(start 2.032 1.524)
			(end 1.7272 1.524)
			(stroke
				(width 0.1524)
				(type default)
			)
			(layer "F.SilkS")
		)
		(fp_line
			(start -2.032 1.524)
			(end -1.7272 1.524)
			(stroke
				(width 0.1524)
				(type default)
			)
			(layer "F.SilkS")
		)
		(fp_line
			(start 2.2987 7.3533)
			(end 2.2987 -0.2413)
			(stroke
				(width 0.1524)
				(type default)
			)
			(layer "F.SilkS")
		)
		(fp_line
			(start 1.7272 7.3533)
			(end 2.2987 7.3533)
			(stroke
				(width 0.1524)
				(type default)
			)
			(layer "F.SilkS")
		)
		(fp_line
			(start -2.2987 7.3533)
			(end -1.7272 7.3533)
			(stroke
				(width 0.1524)
				(type default)
			)
			(layer "F.SilkS")
		)
		(fp_rect
			(start 2.2987 -0.2413)
			(end -2.2987 7.3533)
			(stroke
				(width 0)
				(type default)
			)
			(fill no)
			(layer "F.CrtYd")
		)
		(fp_line
			(start 2.2987 -0.2413)
			(end 2.2987 7.3533)
			(stroke
				(width 0.1)
				(type default)
			)
			(layer "F.Fab")
		)
		(fp_line
			(start -2.2987 -0.2413)
			(end 2.2987 -0.2413)
			(stroke
				(width 0.1)
				(type default)
			)
			(layer "F.Fab")
		)
		(fp_line
			(start 2.2987 7.3533)
			(end -2.2987 7.3533)
			(stroke
				(width 0.1)
				(type default)
			)
			(layer "F.Fab")
		)
		(fp_line
			(start -2.2987 7.3533)
			(end -2.2987 -0.2413)
			(stroke
				(width 0.1)
				(type default)
			)
			(layer "F.Fab")
		)
		(pad "1" smd rect
			(at 0 0 90)
			(size 2.54 3.048)
			(layers "F.Cu" "F.Mask" "F.Paste")
			(net "PVPP_GHJ")
		)
		(pad "2" smd rect
			(at 0 7.112 90)
			(size 2.54 3.048)
			(layers "F.Cu" "F.Mask" "F.Paste")
			(net "GND")
		)
	)
	(footprint ""
		(layer "F.Cu")
		(at 342.138 -23.749)
		(property "Reference" "C7F10"
			(at 0 0 0)
			(layer "F.SilkS")
			(hide yes)
			(effects
				(font
					(size 1.27 1.27)
				)
			)
		)
		(property "Value" ""
			(at 0 0 0)
			(layer "F.Fab")
			(effects
				(font
					(size 1.27 1.27)
				)
			)
		)
		(duplicate_pad_numbers_are_jumpers no)
		(fp_rect
			(start -0.3048 0.9906)
			(end 0.3048 -0.1016)
			(stroke
				(width 0)
				(type default)
			)
			(fill no)
			(layer "F.CrtYd")
		)
		(fp_line
			(start -0.3048 -0.1016)
			(end -0.3048 0.9906)
			(stroke
				(width 0.1)
				(type default)
			)
			(layer "F.Fab")
		)
		(fp_line
			(start -0.3048 0.9906)
			(end 0.3048 0.9906)
			(stroke
				(width 0.1)
				(type default)
			)
			(layer "F.Fab")
		)
		(fp_line
			(start 0.3048 -0.1016)
			(end -0.3048 -0.1016)
			(stroke
				(width 0.1)
				(type default)
			)
			(layer "F.Fab")
		)
		(fp_line
			(start 0.3048 0.9906)
			(end 0.3048 -0.1016)
			(stroke
				(width 0.1)
				(type default)
			)
			(layer "F.Fab")
		)
		(pad "1" smd rect
			(at 0 0)
			(size 0.508 0.508)
			(layers "F.Cu" "F.Mask" "F.Paste")
			(net "VR_PVPP_ABC_SS")
		)
		(pad "2" smd rect
			(at 0 0.889)
			(size 0.508 0.508)
			(layers "F.Cu" "F.Mask" "F.Paste")
			(net "AGND_PVPP_ABC")
		)
		(zone
			(layer "F.Cu")
			(hatch none 0.5)
			(connect_pads
				(clearance 0)
			)
			(min_thickness 0.25)
			(keepout
				(tracks not_allowed)
				(vias allowed)
				(pads allowed)
				(copperpour not_allowed)
				(footprints allowed)
			)
			(placement
				(enabled no)
				(sheetname "")
			)
			(fill
				(thermal_gap 0.5)
				(thermal_bridge_width 0.5)
				(island_removal_mode 0)
			)
			(polygon
				(pts
					(xy 341.884 -23.114) (xy 342.392 -23.114) (xy 342.392 -23.495) (xy 341.884 -23.495)
				)
			)
		)
		(zone
			(layer "F.Cu")
			(hatch none 0.5)
			(connect_pads
				(clearance 0)
			)
			(min_thickness 0.25)
			(keepout
				(tracks allowed)
				(vias not_allowed)
				(pads allowed)
				(copperpour not_allowed)
				(footprints allowed)
			)
			(placement
				(enabled no)
				(sheetname "")
			)
			(fill
				(thermal_gap 0.5)
				(thermal_bridge_width 0.5)
				(island_removal_mode 0)
			)
			(polygon
				(pts
					(xy 341.884 -23.114) (xy 342.392 -23.114) (xy 342.392 -23.495) (xy 341.884 -23.495)
				)
			)
		)
	)
	(footprint ""
		(layer "F.Cu")
		(at 420.1414 -18.7452)
		(property "Reference" "R9G15"
			(at 0 0 0)
			(layer "F.SilkS")
			(hide yes)
			(effects
				(font
					(size 1.27 1.27)
				)
			)
		)
		(property "Value" ""
			(at 0 0 0)
			(layer "F.Fab")
			(effects
				(font
					(size 1.27 1.27)
				)
			)
		)
		(duplicate_pad_numbers_are_jumpers no)
		(fp_poly
			(pts
				(xy -0.2794 -0.1016) (xy 0.2794 -0.1016) (xy 0.2794 0.9906) (xy -0.2794 0.9906)
			)
			(stroke
				(width 0)
				(type default)
			)
			(fill no)
			(layer "F.CrtYd")
		)
		(fp_line
			(start -0.2794 -0.1016)
			(end -0.2794 0.9906)
			(stroke
				(width 0.1)
				(type default)
			)
			(layer "F.Fab")
		)
		(fp_line
			(start -0.2794 0.9906)
			(end 0.2794 0.9906)
			(stroke
				(width 0.1)
				(type default)
			)
			(layer "F.Fab")
		)
		(fp_line
			(start 0.2794 -0.1016)
			(end -0.2794 -0.1016)
			(stroke
				(width 0.1)
				(type default)
			)
			(layer "F.Fab")
		)
		(fp_line
			(start 0.2794 0.9906)
			(end 0.2794 -0.1016)
			(stroke
				(width 0.1)
				(type default)
			)
			(layer "F.Fab")
		)
		(pad "1" smd rect
			(at 0 0)
			(size 0.508 0.508)
			(layers "F.Cu" "F.Mask" "F.Paste")
			(net "SMB_SENSOR_BMC_STBY_LVC3_SDA")
		)
		(pad "2" smd rect
			(at 0 0.889)
			(size 0.508 0.508)
			(layers "F.Cu" "F.Mask" "F.Paste")
			(net "SMB_SENSOR_STBY_LVC3_SDA")
		)
		(zone
			(layer "F.Cu")
			(hatch none 0.5)
			(connect_pads
				(clearance 0)
			)
			(min_thickness 0.25)
			(keepout
				(tracks allowed)
				(vias not_allowed)
				(pads allowed)
				(copperpour not_allowed)
				(footprints allowed)
			)
			(placement
				(enabled no)
				(sheetname "")
			)
			(fill
				(thermal_gap 0.5)
				(thermal_bridge_width 0.5)
				(island_removal_mode 0)
			)
			(polygon
				(pts
					(xy 419.8874 -18.4912) (xy 420.3954 -18.4912) (xy 420.3954 -18.1102) (xy 419.8874 -18.1102)
				)
			)
		)
		(zone
			(layer "F.Cu")
			(hatch none 0.5)
			(connect_pads
				(clearance 0)
			)
			(min_thickness 0.25)
			(keepout
				(tracks not_allowed)
				(vias allowed)
				(pads allowed)
				(copperpour not_allowed)
				(footprints allowed)
			)
			(placement
				(enabled no)
				(sheetname "")
			)
			(fill
				(thermal_gap 0.5)
				(thermal_bridge_width 0.5)
				(island_removal_mode 0)
			)
			(polygon
				(pts
					(xy 419.8874 -18.1102) (xy 420.3954 -18.1102) (xy 420.3954 -18.4912) (xy 419.8874 -18.4912)
				)
			)
		)
	)
	(footprint ""
		(layer "F.Cu")
		(at 440.817 -143.002 90)
		(property "Reference" "R25W160"
			(at -0.8382 -0.67818 90)
			(unlocked yes)
			(layer "F.SilkS")
			(effects
				(font
					(size 0.4064 0.254)
					(thickness 0.1524)
				)
				(justify left)
			)
		)
		(property "Value" ""
			(at 0 0 90)
			(layer "F.Fab")
			(effects
				(font
					(size 1.27 1.27)
				)
			)
		)
		(duplicate_pad_numbers_are_jumpers no)
		(fp_poly
			(pts
				(xy -0.2794 -0.1016) (xy 0.2794 -0.1016) (xy 0.2794 0.9906) (xy -0.2794 0.9906)
			)
			(stroke
				(width 0)
				(type default)
			)
			(fill no)
			(layer "F.CrtYd")
		)
		(fp_line
			(start 0.2794 -0.1016)
			(end -0.2794 -0.1016)
			(stroke
				(width 0.1)
				(type default)
			)
			(layer "F.Fab")
		)
		(fp_line
			(start -0.2794 -0.1016)
			(end -0.2794 0.9906)
			(stroke
				(width 0.1)
				(type default)
			)
			(layer "F.Fab")
		)
		(fp_line
			(start 0.2794 0.9906)
			(end 0.2794 -0.1016)
			(stroke
				(width 0.1)
				(type default)
			)
			(layer "F.Fab")
		)
		(fp_line
			(start -0.2794 0.9906)
			(end 0.2794 0.9906)
			(stroke
				(width 0.1)
				(type default)
			)
			(layer "F.Fab")
		)
		(pad "1" smd rect
			(at 0 0 90)
			(size 0.508 0.508)
			(layers "F.Cu" "F.Mask" "F.Paste")
			(net "P3V3_STBY")
		)
		(pad "2" smd rect
			(at 0 0.889 90)
			(size 0.508 0.508)
			(layers "F.Cu" "F.Mask" "F.Paste")
			(net "JTAG_BMC_BUF_TDI")
		)
		(zone
			(layer "F.Cu")
			(hatch none 0.5)
			(connect_pads
				(clearance 0)
			)
			(min_thickness 0.25)
			(keepout
				(tracks allowed)
				(vias not_allowed)
				(pads allowed)
				(copperpour not_allowed)
				(footprints allowed)
			)
			(placement
				(enabled no)
				(sheetname "")
			)
			(fill
				(thermal_gap 0.5)
				(thermal_bridge_width 0.5)
				(island_removal_mode 0)
			)
			(polygon
				(pts
					(xy 441.071 -142.748) (xy 441.071 -143.256) (xy 441.452 -143.256) (xy 441.452 -142.748)
				)
			)
		)
		(zone
			(layer "F.Cu")
			(hatch none 0.5)
			(connect_pads
				(clearance 0)
			)
			(min_thickness 0.25)
			(keepout
				(tracks not_allowed)
				(vias allowed)
				(pads allowed)
				(copperpour not_allowed)
				(footprints allowed)
			)
			(placement
				(enabled no)
				(sheetname "")
			)
			(fill
				(thermal_gap 0.5)
				(thermal_bridge_width 0.5)
				(island_removal_mode 0)
			)
			(polygon
				(pts
					(xy 441.452 -142.748) (xy 441.452 -143.256) (xy 441.071 -143.256) (xy 441.071 -142.748)
				)
			)
		)
	)
	(footprint ""
		(layer "F.Cu")
		(at 269.409672 -77.636116)
		(property "Reference" "C5D33"
			(at 0 0 0)
			(layer "F.SilkS")
			(hide yes)
			(effects
				(font
					(size 1.27 1.27)
				)
			)
		)
		(property "Value" ""
			(at 0 0 0)
			(layer "F.Fab")
			(effects
				(font
					(size 1.27 1.27)
				)
			)
		)
		(duplicate_pad_numbers_are_jumpers no)
		(fp_poly
			(pts
				(xy -0.4953 -0.2032) (xy 0.4953 -0.2032) (xy 0.4953 1.6002) (xy -0.4953 1.6002)
			)
			(stroke
				(width 0)
				(type default)
			)
			(fill no)
			(layer "F.CrtYd")
		)
		(fp_line
			(start -0.4953 -0.2032)
			(end 0.4953 -0.2032)
			(stroke
				(width 0.1)
				(type default)
			)
			(layer "F.Fab")
		)
		(fp_line
			(start -0.4953 1.6002)
			(end -0.4953 -0.2032)
			(stroke
				(width 0.1)
				(type default)
			)
			(layer "F.Fab")
		)
		(fp_line
			(start 0.4953 -0.2032)
			(end 0.4953 1.6002)
			(stroke
				(width 0.1)
				(type default)
			)
			(layer "F.Fab")
		)
		(fp_line
			(start 0.4953 1.6002)
			(end -0.4953 1.6002)
			(stroke
				(width 0.1)
				(type default)
			)
			(layer "F.Fab")
		)
		(pad "1" smd rect
			(at 0 0)
			(size 0.762 0.889)
			(layers "F.Cu" "F.Mask" "F.Paste")
			(net "PVCCMCP_CPU0")
		)
		(pad "2" smd rect
			(at 0 1.397)
			(size 0.762 0.889)
			(layers "F.Cu" "F.Mask" "F.Paste")
			(net "GND")
		)
		(zone
			(layer "F.Cu")
			(hatch none 0.5)
			(connect_pads
				(clearance 0)
			)
			(min_thickness 0.25)
			(keepout
				(tracks not_allowed)
				(vias allowed)
				(pads allowed)
				(copperpour not_allowed)
				(footprints allowed)
			)
			(placement
				(enabled no)
				(sheetname "")
			)
			(fill
				(thermal_gap 0.5)
				(thermal_bridge_width 0.5)
				(island_removal_mode 0)
			)
			(polygon
				(pts
					(xy 269.028672 -77.191616) (xy 269.790672 -77.191616) (xy 269.790672 -76.683616) (xy 269.028672 -76.683616)
				)
			)
		)
	)
	(footprint ""
		(layer "F.Cu")
		(at 177.927 -8.255)
		(property "Reference" "R4G11"
			(at 0 0 0)
			(layer "F.SilkS")
			(hide yes)
			(effects
				(font
					(size 1.27 1.27)
				)
			)
		)
		(property "Value" ""
			(at 0 0 0)
			(layer "F.Fab")
			(effects
				(font
					(size 1.27 1.27)
				)
			)
		)
		(duplicate_pad_numbers_are_jumpers no)
		(fp_rect
			(start -0.2794 0.9906)
			(end 0.2794 -0.1016)
			(stroke
				(width 0)
				(type default)
			)
			(fill no)
			(layer "F.CrtYd")
		)
		(fp_line
			(start -0.2794 -0.1016)
			(end -0.2794 0.9906)
			(stroke
				(width 0.1)
				(type default)
			)
			(layer "F.Fab")
		)
		(fp_line
			(start -0.2794 0.9906)
			(end 0.2794 0.9906)
			(stroke
				(width 0.1)
				(type default)
			)
			(layer "F.Fab")
		)
		(fp_line
			(start 0.2794 -0.1016)
			(end -0.2794 -0.1016)
			(stroke
				(width 0.1)
				(type default)
			)
			(layer "F.Fab")
		)
		(fp_line
			(start 0.2794 0.9906)
			(end 0.2794 -0.1016)
			(stroke
				(width 0.1)
				(type default)
			)
			(layer "F.Fab")
		)
		(pad "1" smd rect
			(at 0 0)
			(size 0.508 0.508)
			(layers "F.Cu" "F.Mask" "F.Paste")
			(net "VR_PVPP_GHJ_ISET")
		)
		(pad "2" smd rect
			(at 0 0.889)
			(size 0.508 0.508)
			(layers "F.Cu" "F.Mask" "F.Paste")
			(net "AGND_PVPP_GHJ")
		)
		(zone
			(layer "F.Cu")
			(hatch none 0.5)
			(connect_pads
				(clearance 0)
			)
			(min_thickness 0.25)
			(keepout
				(tracks allowed)
				(vias not_allowed)
				(pads allowed)
				(copperpour not_allowed)
				(footprints allowed)
			)
			(placement
				(enabled no)
				(sheetname "")
			)
			(fill
				(thermal_gap 0.5)
				(thermal_bridge_width 0.5)
				(island_removal_mode 0)
			)
			(polygon
				(pts
					(xy 177.673 -7.62) (xy 178.181 -7.62) (xy 178.181 -8.001) (xy 177.673 -8.001)
				)
			)
		)
		(zone
			(layer "F.Cu")
			(hatch none 0.5)
			(connect_pads
				(clearance 0)
			)
			(min_thickness 0.25)
			(keepout
				(tracks not_allowed)
				(vias allowed)
				(pads allowed)
				(copperpour not_allowed)
				(footprints allowed)
			)
			(placement
				(enabled no)
				(sheetname "")
			)
			(fill
				(thermal_gap 0.5)
				(thermal_bridge_width 0.5)
				(island_removal_mode 0)
			)
			(polygon
				(pts
					(xy 177.673 -7.62) (xy 178.181 -7.62) (xy 178.181 -8.001) (xy 177.673 -8.001)
				)
			)
		)
	)
	(footprint ""
		(layer "F.Cu")
		(at 33.925002 -81.423764 90)
		(property "Reference" "EU1D1"
			(at 3.334766 -1.565402 0)
			(unlocked yes)
			(layer "F.SilkS")
			(effects
				(font
					(size 0.7874 0.5842)
					(thickness 0.1524)
				)
			)
		)
		(property "Value" ""
			(at 0 0 90)
			(layer "F.Fab")
			(effects
				(font
					(size 1.27 1.27)
				)
			)
		)
		(duplicate_pad_numbers_are_jumpers no)
		(fp_line
			(start 2.9718 -3.5052)
			(end 2.9718 3.429)
			(stroke
				(width 0.1524)
				(type default)
			)
			(layer "F.SilkS")
		)
		(fp_line
			(start -3.0099 -3.5052)
			(end 2.9718 -3.5052)
			(stroke
				(width 0.1524)
				(type default)
			)
			(layer "F.SilkS")
		)
		(fp_line
			(start 2.9718 3.429)
			(end -3.0099 3.429)
			(stroke
				(width 0.1524)
				(type default)
			)
			(layer "F.SilkS")
		)
		(fp_line
			(start -3.0099 3.429)
			(end -3.0099 -3.5052)
			(stroke
				(width 0.1524)
				(type default)
			)
			(layer "F.SilkS")
		)
		(fp_circle
			(center -3.057398 -2.678684)
			(end -3.057398 -2.551684)
			(stroke
				(width 0.254)
				(type default)
			)
			(fill no)
			(layer "F.SilkS")
		)
		(fp_poly
			(pts
				(xy -2.9972 -3.4925) (xy -2.9972 -2.6924) (xy -2.1971 -3.4925)
			)
			(stroke
				(width 0)
				(type default)
			)
			(fill yes)
			(layer "F.SilkS")
		)
		(fp_poly
			(pts
				(xy -2.549906 -3.050032) (xy -2.549906 3.050032) (xy 2.549906 3.050032) (xy 2.549906 -3.050032)
			)
			(stroke
				(width 0)
				(type default)
			)
			(fill no)
			(layer "F.CrtYd")
		)
		(fp_line
			(start 2.549906 -3.050032)
			(end 2.549906 3.050032)
			(stroke
				(width 0.1)
				(type default)
			)
			(layer "F.Fab")
		)
		(fp_line
			(start -2.549906 -3.050032)
			(end 2.549906 -3.050032)
			(stroke
				(width 0.1)
				(type default)
			)
			(layer "F.Fab")
		)
		(fp_line
			(start 2.549906 3.050032)
			(end -2.549906 3.050032)
			(stroke
				(width 0.1)
				(type default)
			)
			(layer "F.Fab")
		)
		(fp_line
			(start -2.549906 3.050032)
			(end -2.549906 -3.050032)
			(stroke
				(width 0.1)
				(type default)
			)
			(layer "F.Fab")
		)
		(fp_circle
			(center -3.057398 -2.678684)
			(end -3.057398 -2.551684)
			(stroke
				(width 0.254)
				(type default)
			)
			(fill no)
			(layer "F.Fab")
		)
		(pad "1" smd rect
			(at -2.39522 -2.279904 90)
			(size 0.7112 0.254)
			(layers "F.Cu" "F.Mask" "F.Paste")
			(net "PVCCIN_CPU1")
		)
		(pad "2" smd rect
			(at -2.39522 -1.83007 90)
			(size 0.7112 0.254)
			(layers "F.Cu" "F.Mask" "F.Paste")
			(net "GND")
		)
		(pad "3" smd rect
			(at -2.39522 -1.379982 90)
			(size 0.7112 0.254)
			(layers "F.Cu" "F.Mask" "F.Paste")
			(net "VR_PVCCIN_CPU1_PH4_VCIN")
		)
		(pad "4" smd rect
			(at -2.39522 -0.929894 90)
			(size 0.7112 0.254)
			(layers "F.Cu" "F.Mask" "F.Paste")
			(net "P5V_STBY")
		)
		(pad "5" smd rect
			(at -2.39522 -0.48006 90)
			(size 0.7112 0.254)
			(layers "F.Cu" "F.Mask" "F.Paste")
			(net "GND")
		)
		(pad "6" smd rect
			(at -2.39522 -0.029972 90)
			(size 0.7112 0.254)
			(layers "F.Cu" "F.Mask" "F.Paste")
			(net "TP_PVCCIN_CPU1_PH4_GL_0")
		)
		(pad "7" smd custom
			(at 0.016764 1.145032 90)
			(size 0.53975 0.53975)
			(layers "F.Cu" "F.Mask" "F.Paste")
			(net "GND")
			(options
				(clearance outline)
				(anchor circle)
			)
			(primitives
				(gr_poly
					(pts
						(xy -2.7051 1.0795) (xy -2.7051 -0.3683) (xy -0.9271 -0.3683) (xy -0.9271 -1.0795) (xy 2.7051 -1.0795)
						(xy 2.7051 1.0795)
					)
					(width 0)
					(fill yes)
				)
			)
		)
		(pad "10" smd rect
			(at -0.008382 2.874772 90)
			(size 4.3434 0.6096)
			(layers "F.Cu" "F.Mask" "F.Paste")
			(net "VR_PVCCIN_CPU1_PHASE4")
		)
		(pad "25" smd rect
			(at 1.548384 -1.283208 90)
			(size 2.3368 2.0066)
			(layers "F.Cu" "F.Mask" "F.Paste")
			(net "VR_FET_SW_P12V_STBY_PVCCIN_CPU1")
		)
		(pad "30" smd rect
			(at 2.050034 -2.895092 90)
			(size 0.254 0.7112)
			(layers "F.Cu" "F.Mask" "F.Paste")
			(net "VR_FET_SW_P12V_STBY_PVCCIN_CPU1")
		)
		(pad "31" smd rect
			(at 1.599946 -2.895092 90)
			(size 0.254 0.7112)
			(layers "F.Cu" "F.Mask" "F.Paste")
			(net "Net_358")
		)
		(pad "32" smd rect
			(at 1.150112 -2.895092 90)
			(size 0.254 0.7112)
			(layers "F.Cu" "F.Mask" "F.Paste")
			(net "VR_PVCCIN_CPU1_PH4_PHASE")
		)
		(pad "33" smd rect
			(at 0.700024 -2.895092 90)
			(size 0.254 0.7112)
			(layers "F.Cu" "F.Mask" "F.Paste")
			(net "VR_PVCCIN_CPU1_PH4_BOOT_R")
		)
		(pad "34" smd rect
			(at 0.249936 -2.895092 90)
			(size 0.254 0.7112)
			(layers "F.Cu" "F.Mask" "F.Paste")
			(net "VR_PVCCIN_CPU1_PWM4")
		)
		(pad "35" smd rect
			(at -0.199898 -2.895092 90)
			(size 0.254 0.7112)
			(layers "F.Cu" "F.Mask" "F.Paste")
			(net "P5V_STBY")
		)
		(pad "36" smd rect
			(at -0.649986 -2.895092 90)
			(size 0.254 0.7112)
			(layers "F.Cu" "F.Mask" "F.Paste")
			(net "A_TSENSE_PVCCIN_CPU1")
		)
		(pad "37" smd rect
			(at -1.100074 -2.895092 90)
			(size 0.254 0.7112)
			(layers "F.Cu" "F.Mask" "F.Paste")
			(net "VR_PVCCIN_CPU1_PH4_OCSET")
		)
		(pad "38" smd rect
			(at -1.549908 -2.895092 90)
			(size 0.254 0.7112)
			(layers "F.Cu" "F.Mask" "F.Paste")
			(net "ISENSE_PVCCIN_CPU1_PH4_IMON")
		)
		(pad "39" smd rect
			(at -1.999996 -2.895092 90)
			(size 0.254 0.7112)
			(layers "F.Cu" "F.Mask" "F.Paste")
			(net "VR_PVCCIN_CPU1_AIREF4")
		)
		(pad "40" smd rect
			(at -0.871728 -1.283208 90)
			(size 1.8034 2.0066)
			(layers "F.Cu" "F.Mask" "F.Paste")
			(net "GND")
		)
		(pad "41" smd rect
			(at -1.533906 0.247904 90)
			(size 0.508 0.3556)
			(layers "F.Cu" "F.Mask" "F.Paste")
			(net "TP_PVCCIN_CPU1_PH4_GL_1")
		)
	)
	(footprint ""
		(layer "F.Cu")
		(at 13.438124 -4.426204)
		(property "Reference" "R1G11"
			(at 0 0 0)
			(layer "F.SilkS")
			(hide yes)
			(effects
				(font
					(size 1.27 1.27)
				)
			)
		)
		(property "Value" ""
			(at 0 0 0)
			(layer "F.Fab")
			(effects
				(font
					(size 1.27 1.27)
				)
			)
		)
		(duplicate_pad_numbers_are_jumpers no)
		(fp_poly
			(pts
				(xy -0.2794 -0.1016) (xy 0.2794 -0.1016) (xy 0.2794 0.9906) (xy -0.2794 0.9906)
			)
			(stroke
				(width 0)
				(type default)
			)
			(fill no)
			(layer "F.CrtYd")
		)
		(fp_line
			(start -0.2794 -0.1016)
			(end -0.2794 0.9906)
			(stroke
				(width 0.1)
				(type default)
			)
			(layer "F.Fab")
		)
		(fp_line
			(start -0.2794 0.9906)
			(end 0.2794 0.9906)
			(stroke
				(width 0.1)
				(type default)
			)
			(layer "F.Fab")
		)
		(fp_line
			(start 0.2794 -0.1016)
			(end -0.2794 -0.1016)
			(stroke
				(width 0.1)
				(type default)
			)
			(layer "F.Fab")
		)
		(fp_line
			(start 0.2794 0.9906)
			(end 0.2794 -0.1016)
			(stroke
				(width 0.1)
				(type default)
			)
			(layer "F.Fab")
		)
		(pad "1" smd rect
			(at 0 0)
			(size 0.508 0.508)
			(layers "F.Cu" "F.Mask" "F.Paste")
			(net "P3V3_STBY")
		)
		(pad "2" smd rect
			(at 0 0.889)
			(size 0.508 0.508)
			(layers "F.Cu" "F.Mask" "F.Paste")
			(net "IRQ_PVDDQ_GHJ_VRHOT_LVT3_R_N")
		)
		(zone
			(layer "F.Cu")
			(hatch none 0.5)
			(connect_pads
				(clearance 0)
			)
			(min_thickness 0.25)
			(keepout
				(tracks allowed)
				(vias not_allowed)
				(pads allowed)
				(copperpour not_allowed)
				(footprints allowed)
			)
			(placement
				(enabled no)
				(sheetname "")
			)
			(fill
				(thermal_gap 0.5)
				(thermal_bridge_width 0.5)
				(island_removal_mode 0)
			)
			(polygon
				(pts
					(xy 13.184124 -4.172204) (xy 13.692124 -4.172204) (xy 13.692124 -3.791204) (xy 13.184124 -3.791204)
				)
			)
		)
		(zone
			(layer "F.Cu")
			(hatch none 0.5)
			(connect_pads
				(clearance 0)
			)
			(min_thickness 0.25)
			(keepout
				(tracks not_allowed)
				(vias allowed)
				(pads allowed)
				(copperpour not_allowed)
				(footprints allowed)
			)
			(placement
				(enabled no)
				(sheetname "")
			)
			(fill
				(thermal_gap 0.5)
				(thermal_bridge_width 0.5)
				(island_removal_mode 0)
			)
			(polygon
				(pts
					(xy 13.184124 -3.791204) (xy 13.692124 -3.791204) (xy 13.692124 -4.172204) (xy 13.184124 -4.172204)
				)
			)
		)
	)
	(footprint ""
		(layer "F.Cu")
		(at 346.202 -127.127 90)
		(property "Reference" "C7B12"
			(at 0 0 90)
			(layer "F.SilkS")
			(hide yes)
			(effects
				(font
					(size 1.27 1.27)
				)
			)
		)
		(property "Value" ""
			(at 0 0 90)
			(layer "F.Fab")
			(effects
				(font
					(size 1.27 1.27)
				)
			)
		)
		(duplicate_pad_numbers_are_jumpers no)
		(fp_poly
			(pts
				(xy 0.3048 -0.1016) (xy 0.3048 0.9906) (xy -0.3048 0.9906) (xy -0.3048 -0.1016)
			)
			(stroke
				(width 0)
				(type default)
			)
			(fill no)
			(layer "F.CrtYd")
		)
		(fp_line
			(start 0.3048 -0.1016)
			(end -0.3048 -0.1016)
			(stroke
				(width 0.1)
				(type default)
			)
			(layer "F.Fab")
		)
		(fp_line
			(start -0.3048 -0.1016)
			(end -0.3048 0.9906)
			(stroke
				(width 0.1)
				(type default)
			)
			(layer "F.Fab")
		)
		(fp_line
			(start 0.3048 0.9906)
			(end 0.3048 -0.1016)
			(stroke
				(width 0.1)
				(type default)
			)
			(layer "F.Fab")
		)
		(fp_line
			(start -0.3048 0.9906)
			(end 0.3048 0.9906)
			(stroke
				(width 0.1)
				(type default)
			)
			(layer "F.Fab")
		)
		(pad "1" smd rect
			(at 0 0 90)
			(size 0.508 0.508)
			(layers "F.Cu" "F.Mask" "F.Paste")
			(net "PWRGD_PVPP_DEF_R")
		)
		(pad "2" smd rect
			(at 0 0.889 90)
			(size 0.508 0.508)
			(layers "F.Cu" "F.Mask" "F.Paste")
			(net "GND")
		)
		(zone
			(layer "F.Cu")
			(hatch none 0.5)
			(connect_pads
				(clearance 0)
			)
			(min_thickness 0.25)
			(keepout
				(tracks allowed)
				(vias not_allowed)
				(pads allowed)
				(copperpour not_allowed)
				(footprints allowed)
			)
			(placement
				(enabled no)
				(sheetname "")
			)
			(fill
				(thermal_gap 0.5)
				(thermal_bridge_width 0.5)
				(island_removal_mode 0)
			)
			(polygon
				(pts
					(xy 346.456 -126.873) (xy 346.456 -127.381) (xy 346.837 -127.381) (xy 346.837 -126.873)
				)
			)
		)
		(zone
			(layer "F.Cu")
			(hatch none 0.5)
			(connect_pads
				(clearance 0)
			)
			(min_thickness 0.25)
			(keepout
				(tracks not_allowed)
				(vias allowed)
				(pads allowed)
				(copperpour not_allowed)
				(footprints allowed)
			)
			(placement
				(enabled no)
				(sheetname "")
			)
			(fill
				(thermal_gap 0.5)
				(thermal_bridge_width 0.5)
				(island_removal_mode 0)
			)
			(polygon
				(pts
					(xy 346.837 -126.873) (xy 346.837 -127.381) (xy 346.456 -127.381) (xy 346.456 -126.873)
				)
			)
		)
	)
	(footprint ""
		(layer "F.Cu")
		(at 478.5995 -142.875 -90)
		(property "Reference" "R1L26"
			(at 0 0 270)
			(layer "F.SilkS")
			(hide yes)
			(effects
				(font
					(size 1.27 1.27)
				)
			)
		)
		(property "Value" ""
			(at 0 0 270)
			(layer "F.Fab")
			(effects
				(font
					(size 1.27 1.27)
				)
			)
		)
		(duplicate_pad_numbers_are_jumpers no)
		(fp_poly
			(pts
				(xy -0.2794 -0.1016) (xy 0.2794 -0.1016) (xy 0.2794 0.9906) (xy -0.2794 0.9906)
			)
			(stroke
				(width 0)
				(type default)
			)
			(fill no)
			(layer "F.CrtYd")
		)
		(fp_line
			(start -0.2794 0.9906)
			(end 0.2794 0.9906)
			(stroke
				(width 0.1)
				(type default)
			)
			(layer "F.Fab")
		)
		(fp_line
			(start 0.2794 0.9906)
			(end 0.2794 -0.1016)
			(stroke
				(width 0.1)
				(type default)
			)
			(layer "F.Fab")
		)
		(fp_line
			(start -0.2794 -0.1016)
			(end -0.2794 0.9906)
			(stroke
				(width 0.1)
				(type default)
			)
			(layer "F.Fab")
		)
		(fp_line
			(start 0.2794 -0.1016)
			(end -0.2794 -0.1016)
			(stroke
				(width 0.1)
				(type default)
			)
			(layer "F.Fab")
		)
		(pad "1" smd rect
			(at 0 0 270)
			(size 0.508 0.508)
			(layers "F.Cu" "F.Mask" "F.Paste")
			(net "FM_PWR_BTN_R_N")
		)
		(pad "2" smd rect
			(at 0 0.889 270)
			(size 0.508 0.508)
			(layers "F.Cu" "F.Mask" "F.Paste")
			(net "FM_PWR_BTN_N")
		)
		(zone
			(layer "F.Cu")
			(hatch none 0.5)
			(connect_pads
				(clearance 0)
			)
			(min_thickness 0.25)
			(keepout
				(tracks not_allowed)
				(vias allowed)
				(pads allowed)
				(copperpour not_allowed)
				(footprints allowed)
			)
			(placement
				(enabled no)
				(sheetname "")
			)
			(fill
				(thermal_gap 0.5)
				(thermal_bridge_width 0.5)
				(island_removal_mode 0)
			)
			(polygon
				(pts
					(xy 477.9645 -143.129) (xy 477.9645 -142.621) (xy 478.3455 -142.621) (xy 478.3455 -143.129)
				)
			)
		)
		(zone
			(layer "F.Cu")
			(hatch none 0.5)
			(connect_pads
				(clearance 0)
			)
			(min_thickness 0.25)
			(keepout
				(tracks allowed)
				(vias not_allowed)
				(pads allowed)
				(copperpour not_allowed)
				(footprints allowed)
			)
			(placement
				(enabled no)
				(sheetname "")
			)
			(fill
				(thermal_gap 0.5)
				(thermal_bridge_width 0.5)
				(island_removal_mode 0)
			)
			(polygon
				(pts
					(xy 478.3455 -143.129) (xy 478.3455 -142.621) (xy 477.9645 -142.621) (xy 477.9645 -143.129)
				)
			)
		)
	)
	(footprint ""
		(layer "F.Cu")
		(at 490.3724 -59.944 180)
		(property "Reference" "C30W7"
			(at 0 0 180)
			(layer "F.SilkS")
			(hide yes)
			(effects
				(font
					(size 1.27 1.27)
				)
			)
		)
		(property "Value" "*"
			(at -0.0762 -6.2357 180)
			(unlocked yes)
			(layer "F.Fab")
			(hide yes)
			(effects
				(font
					(size 1.27 1.016)
					(thickness 0.1524)
				)
			)
		)
		(property "Device Type" "SC22U16V5MX-4-GP_SMD-BCG5-SC22A"
			(at -0.0762 -8.2677 180)
			(unlocked yes)
			(layer "F.Fab")
			(hide yes)
			(effects
				(font
					(size 1.27 1.016)
					(thickness 0.1524)
				)
			)
		)
		(duplicate_pad_numbers_are_jumpers no)
		(fp_line
			(start 0.635 0)
			(end -0.635 0)
			(stroke
				(width 0.508)
				(type default)
			)
			(layer "F.SilkS")
		)
		(fp_rect
			(start -0.9652 1.778)
			(end 0.9652 -1.778)
			(stroke
				(width 0)
				(type default)
			)
			(fill no)
			(layer "F.CrtYd")
		)
		(fp_poly
			(pts
				(xy -0.9652 -1.778) (xy 0.9652 -1.778) (xy 0.9652 1.778) (xy -0.9652 1.778)
			)
			(stroke
				(width 0)
				(type default)
			)
			(fill no)
			(layer "F.Fab")
		)
		(pad "1" smd rect
			(at 0 -0.9652 180)
			(size 1.397 1.143)
			(layers "F.Cu" "F.Mask" "F.Paste")
			(net "P5V_STBY_USBC")
		)
		(pad "2" smd rect
			(at 0 0.9652 180)
			(size 1.397 1.143)
			(layers "F.Cu" "F.Mask" "F.Paste")
			(net "GND")
		)
	)
	(footprint ""
		(layer "F.Cu")
		(at 344.043 -127.4572 90)
		(property "Reference" "R7B14"
			(at 0 0 90)
			(layer "F.SilkS")
			(hide yes)
			(effects
				(font
					(size 1.27 1.27)
				)
			)
		)
		(property "Value" ""
			(at 0 0 90)
			(layer "F.Fab")
			(effects
				(font
					(size 1.27 1.27)
				)
			)
		)
		(duplicate_pad_numbers_are_jumpers no)
		(fp_poly
			(pts
				(xy -0.2794 -0.1016) (xy 0.2794 -0.1016) (xy 0.2794 0.9906) (xy -0.2794 0.9906)
			)
			(stroke
				(width 0)
				(type default)
			)
			(fill no)
			(layer "F.CrtYd")
		)
		(fp_line
			(start 0.2794 -0.1016)
			(end -0.2794 -0.1016)
			(stroke
				(width 0.1)
				(type default)
			)
			(layer "F.Fab")
		)
		(fp_line
			(start -0.2794 -0.1016)
			(end -0.2794 0.9906)
			(stroke
				(width 0.1)
				(type default)
			)
			(layer "F.Fab")
		)
		(fp_line
			(start 0.2794 0.9906)
			(end 0.2794 -0.1016)
			(stroke
				(width 0.1)
				(type default)
			)
			(layer "F.Fab")
		)
		(fp_line
			(start -0.2794 0.9906)
			(end 0.2794 0.9906)
			(stroke
				(width 0.1)
				(type default)
			)
			(layer "F.Fab")
		)
		(pad "1" smd rect
			(at 0 0 90)
			(size 0.508 0.508)
			(layers "F.Cu" "F.Mask" "F.Paste")
			(net "VR_PVPP_DEF_ISET")
		)
		(pad "2" smd rect
			(at 0 0.889 90)
			(size 0.508 0.508)
			(layers "F.Cu" "F.Mask" "F.Paste")
			(net "AGND_PVPP_DEF")
		)
		(zone
			(layer "F.Cu")
			(hatch none 0.5)
			(connect_pads
				(clearance 0)
			)
			(min_thickness 0.25)
			(keepout
				(tracks allowed)
				(vias not_allowed)
				(pads allowed)
				(copperpour not_allowed)
				(footprints allowed)
			)
			(placement
				(enabled no)
				(sheetname "")
			)
			(fill
				(thermal_gap 0.5)
				(thermal_bridge_width 0.5)
				(island_removal_mode 0)
			)
			(polygon
				(pts
					(xy 344.297 -127.2032) (xy 344.297 -127.7112) (xy 344.678 -127.7112) (xy 344.678 -127.2032)
				)
			)
		)
		(zone
			(layer "F.Cu")
			(hatch none 0.5)
			(connect_pads
				(clearance 0)
			)
			(min_thickness 0.25)
			(keepout
				(tracks not_allowed)
				(vias allowed)
				(pads allowed)
				(copperpour not_allowed)
				(footprints allowed)
			)
			(placement
				(enabled no)
				(sheetname "")
			)
			(fill
				(thermal_gap 0.5)
				(thermal_bridge_width 0.5)
				(island_removal_mode 0)
			)
			(polygon
				(pts
					(xy 344.678 -127.2032) (xy 344.678 -127.7112) (xy 344.297 -127.7112) (xy 344.297 -127.2032)
				)
			)
		)
	)
	(footprint ""
		(layer "F.Cu")
		(at 115.137692 -71.714614 180)
		(property "Reference" "C3D24"
			(at 0 0 180)
			(layer "F.SilkS")
			(hide yes)
			(effects
				(font
					(size 1.27 1.27)
				)
			)
		)
		(property "Value" ""
			(at 0 0 180)
			(layer "F.Fab")
			(effects
				(font
					(size 1.27 1.27)
				)
			)
		)
		(duplicate_pad_numbers_are_jumpers no)
		(fp_poly
			(pts
				(xy -0.4953 -0.2032) (xy 0.4953 -0.2032) (xy 0.4953 1.6002) (xy -0.4953 1.6002)
			)
			(stroke
				(width 0)
				(type default)
			)
			(fill no)
			(layer "F.CrtYd")
		)
		(fp_line
			(start 0.4953 1.6002)
			(end -0.4953 1.6002)
			(stroke
				(width 0.1)
				(type default)
			)
			(layer "F.Fab")
		)
		(fp_line
			(start 0.4953 -0.2032)
			(end 0.4953 1.6002)
			(stroke
				(width 0.1)
				(type default)
			)
			(layer "F.Fab")
		)
		(fp_line
			(start -0.4953 1.6002)
			(end -0.4953 -0.2032)
			(stroke
				(width 0.1)
				(type default)
			)
			(layer "F.Fab")
		)
		(fp_line
			(start -0.4953 -0.2032)
			(end 0.4953 -0.2032)
			(stroke
				(width 0.1)
				(type default)
			)
			(layer "F.Fab")
		)
		(pad "1" smd rect
			(at 0 0 180)
			(size 0.762 0.889)
			(layers "F.Cu" "F.Mask" "F.Paste")
			(net "PVCCIO_CPU1")
		)
		(pad "2" smd rect
			(at 0 1.397 180)
			(size 0.762 0.889)
			(layers "F.Cu" "F.Mask" "F.Paste")
			(net "GND")
		)
		(zone
			(layer "F.Cu")
			(hatch none 0.5)
			(connect_pads
				(clearance 0)
			)
			(min_thickness 0.25)
			(keepout
				(tracks not_allowed)
				(vias allowed)
				(pads allowed)
				(copperpour not_allowed)
				(footprints allowed)
			)
			(placement
				(enabled no)
				(sheetname "")
			)
			(fill
				(thermal_gap 0.5)
				(thermal_bridge_width 0.5)
				(island_removal_mode 0)
			)
			(polygon
				(pts
					(xy 115.518692 -72.159114) (xy 114.756692 -72.159114) (xy 114.756692 -72.667114) (xy 115.518692 -72.667114)
				)
			)
		)
	)
	(footprint ""
		(layer "F.Cu")
		(at 181.63413 -61.03112 180)
		(property "Reference" "C22W16"
			(at 0 0 180)
			(layer "F.SilkS")
			(hide yes)
			(effects
				(font
					(size 1.27 1.27)
				)
			)
		)
		(property "Value" "*"
			(at -0.0762 -6.2357 180)
			(unlocked yes)
			(layer "F.Fab")
			(hide yes)
			(effects
				(font
					(size 1.27 1.016)
					(thickness 0.1524)
				)
			)
		)
		(property "Device Type" "SC22U16V5MX-4-GP_SMD-BCG5-SC22A"
			(at -0.0762 -8.2677 180)
			(unlocked yes)
			(layer "F.Fab")
			(hide yes)
			(effects
				(font
					(size 1.27 1.016)
					(thickness 0.1524)
				)
			)
		)
		(duplicate_pad_numbers_are_jumpers no)
		(fp_line
			(start 0.635 0)
			(end -0.635 0)
			(stroke
				(width 0.508)
				(type default)
			)
			(layer "F.SilkS")
		)
		(fp_rect
			(start -0.9652 1.778)
			(end 0.9652 -1.778)
			(stroke
				(width 0)
				(type default)
			)
			(fill no)
			(layer "F.CrtYd")
		)
		(fp_poly
			(pts
				(xy -0.9652 -1.778) (xy 0.9652 -1.778) (xy 0.9652 1.778) (xy -0.9652 1.778)
			)
			(stroke
				(width 0)
				(type default)
			)
			(fill no)
			(layer "F.Fab")
		)
		(pad "1" smd rect
			(at 0 -0.9652 180)
			(size 1.397 1.143)
			(layers "F.Cu" "F.Mask" "F.Paste")
			(net "VR_FET_SW_P12V_STBY_PVCCIN_CPU0")
		)
		(pad "2" smd rect
			(at 0 0.9652 180)
			(size 1.397 1.143)
			(layers "F.Cu" "F.Mask" "F.Paste")
			(net "GND")
		)
	)
	(footprint ""
		(layer "F.Cu")
		(at 370.4463 -91.9353 180)
		(property "Reference" "R7C23"
			(at 0 0 180)
			(layer "F.SilkS")
			(hide yes)
			(effects
				(font
					(size 1.27 1.27)
				)
			)
		)
		(property "Value" ""
			(at 0 0 180)
			(layer "F.Fab")
			(effects
				(font
					(size 1.27 1.27)
				)
			)
		)
		(duplicate_pad_numbers_are_jumpers no)
		(fp_poly
			(pts
				(xy -0.2794 -0.1016) (xy 0.2794 -0.1016) (xy 0.2794 0.9906) (xy -0.2794 0.9906)
			)
			(stroke
				(width 0)
				(type default)
			)
			(fill no)
			(layer "F.CrtYd")
		)
		(fp_line
			(start 0.2794 0.9906)
			(end 0.2794 -0.1016)
			(stroke
				(width 0.1)
				(type default)
			)
			(layer "F.Fab")
		)
		(fp_line
			(start 0.2794 -0.1016)
			(end -0.2794 -0.1016)
			(stroke
				(width 0.1)
				(type default)
			)
			(layer "F.Fab")
		)
		(fp_line
			(start -0.2794 0.9906)
			(end 0.2794 0.9906)
			(stroke
				(width 0.1)
				(type default)
			)
			(layer "F.Fab")
		)
		(fp_line
			(start -0.2794 -0.1016)
			(end -0.2794 0.9906)
			(stroke
				(width 0.1)
				(type default)
			)
			(layer "F.Fab")
		)
		(pad "1" smd rect
			(at 0 0 180)
			(size 0.508 0.508)
			(layers "F.Cu" "F.Mask" "F.Paste")
			(net "P3V3_STBY")
		)
		(pad "2" smd rect
			(at 0 0.889 180)
			(size 0.508 0.508)
			(layers "F.Cu" "F.Mask" "F.Paste")
			(net "XDP_PCH_PWR_DEBUG_N")
		)
		(zone
			(layer "F.Cu")
			(hatch none 0.5)
			(connect_pads
				(clearance 0)
			)
			(min_thickness 0.25)
			(keepout
				(tracks not_allowed)
				(vias allowed)
				(pads allowed)
				(copperpour not_allowed)
				(footprints allowed)
			)
			(placement
				(enabled no)
				(sheetname "")
			)
			(fill
				(thermal_gap 0.5)
				(thermal_bridge_width 0.5)
				(island_removal_mode 0)
			)
			(polygon
				(pts
					(xy 370.7003 -92.5703) (xy 370.1923 -92.5703) (xy 370.1923 -92.1893) (xy 370.7003 -92.1893)
				)
			)
		)
		(zone
			(layer "F.Cu")
			(hatch none 0.5)
			(connect_pads
				(clearance 0)
			)
			(min_thickness 0.25)
			(keepout
				(tracks allowed)
				(vias not_allowed)
				(pads allowed)
				(copperpour not_allowed)
				(footprints allowed)
			)
			(placement
				(enabled no)
				(sheetname "")
			)
			(fill
				(thermal_gap 0.5)
				(thermal_bridge_width 0.5)
				(island_removal_mode 0)
			)
			(polygon
				(pts
					(xy 370.7003 -92.1893) (xy 370.1923 -92.1893) (xy 370.1923 -92.5703) (xy 370.7003 -92.5703)
				)
			)
		)
	)
	(footprint ""
		(layer "F.Cu")
		(at 431.622708 -127.587502 -90)
		(property "Reference" "C8B8"
			(at 0 0 270)
			(layer "F.SilkS")
			(hide yes)
			(effects
				(font
					(size 1.27 1.27)
				)
			)
		)
		(property "Value" ""
			(at 0 0 270)
			(layer "F.Fab")
			(effects
				(font
					(size 1.27 1.27)
				)
			)
		)
		(duplicate_pad_numbers_are_jumpers no)
		(fp_rect
			(start -0.3048 0.9906)
			(end 0.3048 -0.1016)
			(stroke
				(width 0)
				(type default)
			)
			(fill no)
			(layer "F.CrtYd")
		)
		(fp_line
			(start -0.3048 0.9906)
			(end 0.3048 0.9906)
			(stroke
				(width 0.1)
				(type default)
			)
			(layer "F.Fab")
		)
		(fp_line
			(start 0.3048 0.9906)
			(end 0.3048 -0.1016)
			(stroke
				(width 0.1)
				(type default)
			)
			(layer "F.Fab")
		)
		(fp_line
			(start -0.3048 -0.1016)
			(end -0.3048 0.9906)
			(stroke
				(width 0.1)
				(type default)
			)
			(layer "F.Fab")
		)
		(fp_line
			(start 0.3048 -0.1016)
			(end -0.3048 -0.1016)
			(stroke
				(width 0.1)
				(type default)
			)
			(layer "F.Fab")
		)
		(pad "1" smd rect
			(at 0 0 270)
			(size 0.508 0.508)
			(layers "F.Cu" "F.Mask" "F.Paste")
			(net "P5V_STBY")
		)
		(pad "2" smd rect
			(at 0 0.889 270)
			(size 0.508 0.508)
			(layers "F.Cu" "F.Mask" "F.Paste")
			(net "GND")
		)
		(zone
			(layer "F.Cu")
			(hatch none 0.5)
			(connect_pads
				(clearance 0)
			)
			(min_thickness 0.25)
			(keepout
				(tracks not_allowed)
				(vias allowed)
				(pads allowed)
				(copperpour not_allowed)
				(footprints allowed)
			)
			(placement
				(enabled no)
				(sheetname "")
			)
			(fill
				(thermal_gap 0.5)
				(thermal_bridge_width 0.5)
				(island_removal_mode 0)
			)
			(polygon
				(pts
					(xy 430.987708 -127.841502) (xy 430.987708 -127.333502) (xy 431.368708 -127.333502) (xy 431.368708 -127.841502)
				)
			)
		)
		(zone
			(layer "F.Cu")
			(hatch none 0.5)
			(connect_pads
				(clearance 0)
			)
			(min_thickness 0.25)
			(keepout
				(tracks allowed)
				(vias not_allowed)
				(pads allowed)
				(copperpour not_allowed)
				(footprints allowed)
			)
			(placement
				(enabled no)
				(sheetname "")
			)
			(fill
				(thermal_gap 0.5)
				(thermal_bridge_width 0.5)
				(island_removal_mode 0)
			)
			(polygon
				(pts
					(xy 430.987708 -127.841502) (xy 430.987708 -127.333502) (xy 431.368708 -127.333502) (xy 431.368708 -127.841502)
				)
			)
		)
	)
	(footprint ""
		(layer "F.Cu")
		(at 23.057612 -68.796408 90)
		(property "Reference" "R1W20"
			(at -0.8382 -0.67818 90)
			(unlocked yes)
			(layer "F.SilkS")
			(effects
				(font
					(size 0.4064 0.254)
					(thickness 0.1524)
				)
				(justify left)
			)
		)
		(property "Value" ""
			(at 0 0 90)
			(layer "F.Fab")
			(effects
				(font
					(size 1.27 1.27)
				)
			)
		)
		(duplicate_pad_numbers_are_jumpers no)
		(fp_poly
			(pts
				(xy -0.2794 -0.1016) (xy 0.2794 -0.1016) (xy 0.2794 0.9906) (xy -0.2794 0.9906)
			)
			(stroke
				(width 0)
				(type default)
			)
			(fill no)
			(layer "F.CrtYd")
		)
		(fp_line
			(start 0.2794 -0.1016)
			(end -0.2794 -0.1016)
			(stroke
				(width 0.1)
				(type default)
			)
			(layer "F.Fab")
		)
		(fp_line
			(start -0.2794 -0.1016)
			(end -0.2794 0.9906)
			(stroke
				(width 0.1)
				(type default)
			)
			(layer "F.Fab")
		)
		(fp_line
			(start 0.2794 0.9906)
			(end 0.2794 -0.1016)
			(stroke
				(width 0.1)
				(type default)
			)
			(layer "F.Fab")
		)
		(fp_line
			(start -0.2794 0.9906)
			(end 0.2794 0.9906)
			(stroke
				(width 0.1)
				(type default)
			)
			(layer "F.Fab")
		)
		(pad "1" smd rect
			(at 0 0 90)
			(size 0.508 0.508)
			(layers "F.Cu" "F.Mask" "F.Paste")
			(net "A_HSC_TEMP")
		)
		(pad "2" smd rect
			(at 0 0.889 90)
			(size 0.508 0.508)
			(layers "F.Cu" "F.Mask" "F.Paste")
			(net "TEMP_SENSOR_B")
		)
		(zone
			(layer "F.Cu")
			(hatch none 0.5)
			(connect_pads
				(clearance 0)
			)
			(min_thickness 0.25)
			(keepout
				(tracks allowed)
				(vias not_allowed)
				(pads allowed)
				(copperpour not_allowed)
				(footprints allowed)
			)
			(placement
				(enabled no)
				(sheetname "")
			)
			(fill
				(thermal_gap 0.5)
				(thermal_bridge_width 0.5)
				(island_removal_mode 0)
			)
			(polygon
				(pts
					(xy 23.311612 -68.542408) (xy 23.311612 -69.050408) (xy 23.692612 -69.050408) (xy 23.692612 -68.542408)
				)
			)
		)
		(zone
			(layer "F.Cu")
			(hatch none 0.5)
			(connect_pads
				(clearance 0)
			)
			(min_thickness 0.25)
			(keepout
				(tracks not_allowed)
				(vias allowed)
				(pads allowed)
				(copperpour not_allowed)
				(footprints allowed)
			)
			(placement
				(enabled no)
				(sheetname "")
			)
			(fill
				(thermal_gap 0.5)
				(thermal_bridge_width 0.5)
				(island_removal_mode 0)
			)
			(polygon
				(pts
					(xy 23.692612 -68.542408) (xy 23.692612 -69.050408) (xy 23.311612 -69.050408) (xy 23.311612 -68.542408)
				)
			)
		)
	)
	(footprint ""
		(layer "F.Cu")
		(at 183.3626 -136.4234 180)
		(property "Reference" "C4A19"
			(at 0 0 180)
			(layer "F.SilkS")
			(hide yes)
			(effects
				(font
					(size 1.27 1.27)
				)
			)
		)
		(property "Value" ""
			(at 0 0 180)
			(layer "F.Fab")
			(effects
				(font
					(size 1.27 1.27)
				)
			)
		)
		(duplicate_pad_numbers_are_jumpers no)
		(fp_poly
			(pts
				(xy -0.7239 -0.2159) (xy 0.7239 -0.2159) (xy 0.7239 1.9939) (xy -0.7239 1.9939)
			)
			(stroke
				(width 0)
				(type default)
			)
			(fill no)
			(layer "F.CrtYd")
		)
		(fp_line
			(start 0.7239 1.9939)
			(end 0.7239 -0.2159)
			(stroke
				(width 0.1)
				(type default)
			)
			(layer "F.Fab")
		)
		(fp_line
			(start 0.7239 -0.2159)
			(end -0.7239 -0.2159)
			(stroke
				(width 0.1)
				(type default)
			)
			(layer "F.Fab")
		)
		(fp_line
			(start -0.7239 1.9939)
			(end 0.7239 1.9939)
			(stroke
				(width 0.1)
				(type default)
			)
			(layer "F.Fab")
		)
		(fp_line
			(start -0.7239 -0.2159)
			(end -0.7239 1.9939)
			(stroke
				(width 0.1)
				(type default)
			)
			(layer "F.Fab")
		)
		(pad "1" smd rect
			(at 0 0 180)
			(size 1.27 1.016)
			(layers "F.Cu" "F.Mask" "F.Paste")
			(net "VR_FET_SW_P12V_STBY_PVPP_KLM")
		)
		(pad "2" smd rect
			(at 0 1.778 180)
			(size 1.27 1.016)
			(layers "F.Cu" "F.Mask" "F.Paste")
			(net "GND")
		)
		(zone
			(layer "F.Cu")
			(hatch none 0.5)
			(connect_pads
				(clearance 0)
			)
			(min_thickness 0.25)
			(keepout
				(tracks not_allowed)
				(vias allowed)
				(pads allowed)
				(copperpour not_allowed)
				(footprints allowed)
			)
			(placement
				(enabled no)
				(sheetname "")
			)
			(fill
				(thermal_gap 0.5)
				(thermal_bridge_width 0.5)
				(island_removal_mode 0)
			)
			(polygon
				(pts
					(xy 183.9976 -136.9314) (xy 182.7276 -136.9314) (xy 182.7276 -137.6934) (xy 183.9976 -137.6934)
				)
			)
		)
	)
	(footprint ""
		(layer "F.Cu")
		(at 430.972468 -50.482246 -90)
		(property "Reference" "R9F61"
			(at 0 0 270)
			(layer "F.SilkS")
			(hide yes)
			(effects
				(font
					(size 1.27 1.27)
				)
			)
		)
		(property "Value" ""
			(at 0 0 270)
			(layer "F.Fab")
			(effects
				(font
					(size 1.27 1.27)
				)
			)
		)
		(duplicate_pad_numbers_are_jumpers no)
		(fp_poly
			(pts
				(xy -0.2794 -0.1016) (xy 0.2794 -0.1016) (xy 0.2794 0.9906) (xy -0.2794 0.9906)
			)
			(stroke
				(width 0)
				(type default)
			)
			(fill no)
			(layer "F.CrtYd")
		)
		(fp_line
			(start -0.2794 0.9906)
			(end 0.2794 0.9906)
			(stroke
				(width 0.1)
				(type default)
			)
			(layer "F.Fab")
		)
		(fp_line
			(start 0.2794 0.9906)
			(end 0.2794 -0.1016)
			(stroke
				(width 0.1)
				(type default)
			)
			(layer "F.Fab")
		)
		(fp_line
			(start -0.2794 -0.1016)
			(end -0.2794 0.9906)
			(stroke
				(width 0.1)
				(type default)
			)
			(layer "F.Fab")
		)
		(fp_line
			(start 0.2794 -0.1016)
			(end -0.2794 -0.1016)
			(stroke
				(width 0.1)
				(type default)
			)
			(layer "F.Fab")
		)
		(pad "1" smd rect
			(at 0 0 270)
			(size 0.508 0.508)
			(layers "F.Cu" "F.Mask" "F.Paste")
			(net "P3V3_STBY")
		)
		(pad "2" smd rect
			(at 0 0.889 270)
			(size 0.508 0.508)
			(layers "F.Cu" "F.Mask" "F.Paste")
			(net "PU_24M_OSC_OE")
		)
		(zone
			(layer "F.Cu")
			(hatch none 0.5)
			(connect_pads
				(clearance 0)
			)
			(min_thickness 0.25)
			(keepout
				(tracks not_allowed)
				(vias allowed)
				(pads allowed)
				(copperpour not_allowed)
				(footprints allowed)
			)
			(placement
				(enabled no)
				(sheetname "")
			)
			(fill
				(thermal_gap 0.5)
				(thermal_bridge_width 0.5)
				(island_removal_mode 0)
			)
			(polygon
				(pts
					(xy 430.337468 -50.736246) (xy 430.337468 -50.228246) (xy 430.718468 -50.228246) (xy 430.718468 -50.736246)
				)
			)
		)
		(zone
			(layer "F.Cu")
			(hatch none 0.5)
			(connect_pads
				(clearance 0)
			)
			(min_thickness 0.25)
			(keepout
				(tracks allowed)
				(vias not_allowed)
				(pads allowed)
				(copperpour not_allowed)
				(footprints allowed)
			)
			(placement
				(enabled no)
				(sheetname "")
			)
			(fill
				(thermal_gap 0.5)
				(thermal_bridge_width 0.5)
				(island_removal_mode 0)
			)
			(polygon
				(pts
					(xy 430.718468 -50.736246) (xy 430.718468 -50.228246) (xy 430.337468 -50.228246) (xy 430.337468 -50.736246)
				)
			)
		)
	)
	(footprint ""
		(layer "F.Cu")
		(at 287.168082 12.01039 -90)
		(property "Reference" "T1P14"
			(at 0 0 270)
			(layer "F.SilkS")
			(hide yes)
			(effects
				(font
					(size 1.27 1.27)
				)
			)
		)
		(property "Value" "*"
			(at -3.302 1.12395 270)
			(unlocked yes)
			(layer "F.Fab")
			(hide yes)
			(effects
				(font
					(size 0.889 0.889)
					(thickness 0.1524)
				)
			)
		)
		(property "Device Type" "TPAD-DIFF-4P-GP_DISCRET-GB3-TPA"
			(at -3.302 -0.40005 270)
			(unlocked yes)
			(layer "F.Fab")
			(hide yes)
			(effects
				(font
					(size 0.889 0.889)
					(thickness 0.1524)
				)
			)
		)
		(duplicate_pad_numbers_are_jumpers no)
		(fp_line
			(start -2.286 2.286)
			(end 2.286 2.286)
			(stroke
				(width 0.1524)
				(type default)
			)
			(layer "F.SilkS")
		)
		(fp_line
			(start 2.286 2.286)
			(end 2.286 -2.286)
			(stroke
				(width 0.1524)
				(type default)
			)
			(layer "F.SilkS")
		)
		(fp_line
			(start -2.286 -2.286)
			(end -2.286 2.286)
			(stroke
				(width 0.1524)
				(type default)
			)
			(layer "F.SilkS")
		)
		(fp_line
			(start 2.286 -2.286)
			(end -2.286 -2.286)
			(stroke
				(width 0.1524)
				(type default)
			)
			(layer "F.SilkS")
		)
		(fp_line
			(start -2.413 -2.413)
			(end -2.413 -1.143)
			(stroke
				(width 0.4064)
				(type default)
			)
			(layer "F.SilkS")
		)
		(fp_line
			(start -1.143 -2.413)
			(end -2.413 -2.413)
			(stroke
				(width 0.4064)
				(type default)
			)
			(layer "F.SilkS")
		)
		(fp_rect
			(start -2.54 2.54)
			(end 2.54 -2.54)
			(stroke
				(width 0)
				(type default)
			)
			(fill no)
			(layer "F.CrtYd")
		)
		(fp_rect
			(start -2.54 2.54)
			(end 2.54 -2.54)
			(stroke
				(width 0)
				(type default)
			)
			(fill no)
			(layer "F.Fab")
		)
		(pad "1" thru_hole circle
			(at -1.27 -1.27 270)
			(size 1.524 1.524)
			(drill 0.9144)
			(layers "*.Cu" "*.Mask")
			(remove_unused_layers no)
			(net "L1_95OHM_6INCH_DP")
			(clearance -0.0508)
			(thermal_gap 0.127)
			(padstack
				(mode front_inner_back)
				(layer "Inner"
					(shape circle)
					(size 1.1684 1.1684)
					(clearance 0.127)
				)
				(layer "B.Cu"
					(shape circle)
					(size 1.524 1.524)
					(clearance -0.0508)
				)
			)
		)
		(pad "2" thru_hole circle
			(at 1.27 -1.27 270)
			(size 1.524 1.524)
			(drill 0.9144)
			(layers "*.Cu" "*.Mask")
			(remove_unused_layers no)
			(net "L1_95OHM_6INCH_DN")
			(clearance -0.0508)
			(thermal_gap 0.127)
			(padstack
				(mode front_inner_back)
				(layer "Inner"
					(shape circle)
					(size 1.1684 1.1684)
					(clearance 0.127)
				)
				(layer "B.Cu"
					(shape circle)
					(size 1.524 1.524)
					(clearance -0.0508)
				)
			)
		)
		(pad "GND1" thru_hole rect
			(at -1.27 1.27 270)
			(size 1.524 1.524)
			(drill 0.9144)
			(layers "*.Cu" "*.Mask")
			(remove_unused_layers no)
			(net "GND")
			(clearance -0.0508)
			(thermal_gap 0.127)
			(padstack
				(mode front_inner_back)
				(layer "Inner"
					(shape circle)
					(size 1.1684 1.1684)
					(clearance 0.127)
				)
				(layer "B.Cu"
					(shape rect)
					(size 1.524 1.524)
					(clearance -0.0508)
				)
			)
		)
		(pad "GND2" thru_hole rect
			(at 1.27 1.27 270)
			(size 1.524 1.524)
			(drill 0.9144)
			(layers "*.Cu" "*.Mask")
			(remove_unused_layers no)
			(net "GND")
			(clearance -0.0508)
			(thermal_gap 0.127)
			(padstack
				(mode front_inner_back)
				(layer "Inner"
					(shape circle)
					(size 1.1684 1.1684)
					(clearance 0.127)
				)
				(layer "B.Cu"
					(shape rect)
					(size 1.524 1.524)
					(clearance -0.0508)
				)
			)
		)
	)
	(footprint ""
		(layer "F.Cu")
		(at 8.616188 -142.883128 -90)
		(property "Reference" "CT11"
			(at -0.8382 -0.67818 270)
			(unlocked yes)
			(layer "F.SilkS")
			(effects
				(font
					(size 0.4064 0.254)
					(thickness 0.1524)
				)
				(justify left)
			)
		)
		(property "Value" ""
			(at 0 0 270)
			(layer "F.Fab")
			(effects
				(font
					(size 1.27 1.27)
				)
			)
		)
		(duplicate_pad_numbers_are_jumpers no)
		(fp_poly
			(pts
				(xy 0.3048 -0.1016) (xy 0.3048 0.9906) (xy -0.3048 0.9906) (xy -0.3048 -0.1016)
			)
			(stroke
				(width 0)
				(type default)
			)
			(fill no)
			(layer "F.CrtYd")
		)
		(fp_line
			(start -0.3048 0.9906)
			(end 0.3048 0.9906)
			(stroke
				(width 0.1)
				(type default)
			)
			(layer "F.Fab")
		)
		(fp_line
			(start 0.3048 0.9906)
			(end 0.3048 -0.1016)
			(stroke
				(width 0.1)
				(type default)
			)
			(layer "F.Fab")
		)
		(fp_line
			(start -0.3048 -0.1016)
			(end -0.3048 0.9906)
			(stroke
				(width 0.1)
				(type default)
			)
			(layer "F.Fab")
		)
		(fp_line
			(start 0.3048 -0.1016)
			(end -0.3048 -0.1016)
			(stroke
				(width 0.1)
				(type default)
			)
			(layer "F.Fab")
		)
		(pad "1" smd rect
			(at 0 0 270)
			(size 0.508 0.508)
			(layers "F.Cu" "F.Mask" "F.Paste")
			(net "VR_PVDDQ_KLM_PH2_SW")
		)
		(pad "2" smd rect
			(at 0 0.889 270)
			(size 0.508 0.508)
			(layers "F.Cu" "F.Mask" "F.Paste")
			(net "VR_PVDDQ_KLM_PH2_RC")
		)
		(zone
			(layer "F.Cu")
			(hatch none 0.5)
			(connect_pads
				(clearance 0)
			)
			(min_thickness 0.25)
			(keepout
				(tracks not_allowed)
				(vias allowed)
				(pads allowed)
				(copperpour not_allowed)
				(footprints allowed)
			)
			(placement
				(enabled no)
				(sheetname "")
			)
			(fill
				(thermal_gap 0.5)
				(thermal_bridge_width 0.5)
				(island_removal_mode 0)
			)
			(polygon
				(pts
					(xy 7.981188 -143.137128) (xy 7.981188 -142.629128) (xy 8.362188 -142.629128) (xy 8.362188 -143.137128)
				)
			)
		)
		(zone
			(layer "F.Cu")
			(hatch none 0.5)
			(connect_pads
				(clearance 0)
			)
			(min_thickness 0.25)
			(keepout
				(tracks allowed)
				(vias not_allowed)
				(pads allowed)
				(copperpour not_allowed)
				(footprints allowed)
			)
			(placement
				(enabled no)
				(sheetname "")
			)
			(fill
				(thermal_gap 0.5)
				(thermal_bridge_width 0.5)
				(island_removal_mode 0)
			)
			(polygon
				(pts
					(xy 8.362188 -143.137128) (xy 8.362188 -142.629128) (xy 7.981188 -142.629128) (xy 7.981188 -143.137128)
				)
			)
		)
	)
	(footprint ""
		(layer "F.Cu")
		(at 408.923236 -47.825914 180)
		(property "Reference" "R1T10"
			(at 0 0 180)
			(layer "F.SilkS")
			(hide yes)
			(effects
				(font
					(size 1.27 1.27)
				)
			)
		)
		(property "Value" ""
			(at 0 0 180)
			(layer "F.Fab")
			(effects
				(font
					(size 1.27 1.27)
				)
			)
		)
		(duplicate_pad_numbers_are_jumpers no)
		(fp_poly
			(pts
				(xy -0.2794 -0.1016) (xy 0.2794 -0.1016) (xy 0.2794 0.9906) (xy -0.2794 0.9906)
			)
			(stroke
				(width 0)
				(type default)
			)
			(fill no)
			(layer "F.CrtYd")
		)
		(fp_line
			(start 0.2794 0.9906)
			(end 0.2794 -0.1016)
			(stroke
				(width 0.1)
				(type default)
			)
			(layer "F.Fab")
		)
		(fp_line
			(start 0.2794 -0.1016)
			(end -0.2794 -0.1016)
			(stroke
				(width 0.1)
				(type default)
			)
			(layer "F.Fab")
		)
		(fp_line
			(start -0.2794 0.9906)
			(end 0.2794 0.9906)
			(stroke
				(width 0.1)
				(type default)
			)
			(layer "F.Fab")
		)
		(fp_line
			(start -0.2794 -0.1016)
			(end -0.2794 0.9906)
			(stroke
				(width 0.1)
				(type default)
			)
			(layer "F.Fab")
		)
		(pad "1" smd rect
			(at 0 0 180)
			(size 0.508 0.508)
			(layers "F.Cu" "F.Mask" "F.Paste")
			(net "FM_BOARD_REV_ID0")
		)
		(pad "2" smd rect
			(at 0 0.889 180)
			(size 0.508 0.508)
			(layers "F.Cu" "F.Mask" "F.Paste")
			(net "GND")
		)
	)
	(footprint ""
		(layer "F.Cu")
		(at 39.8018 -69.3166 -90)
		(property "Reference" "CT18"
			(at -0.8382 -0.67818 270)
			(unlocked yes)
			(layer "F.SilkS")
			(effects
				(font
					(size 0.4064 0.254)
					(thickness 0.1524)
				)
				(justify left)
			)
		)
		(property "Value" ""
			(at 0 0 270)
			(layer "F.Fab")
			(effects
				(font
					(size 1.27 1.27)
				)
			)
		)
		(duplicate_pad_numbers_are_jumpers no)
		(fp_poly
			(pts
				(xy 0.3048 -0.1016) (xy 0.3048 0.9906) (xy -0.3048 0.9906) (xy -0.3048 -0.1016)
			)
			(stroke
				(width 0)
				(type default)
			)
			(fill no)
			(layer "F.CrtYd")
		)
		(fp_line
			(start -0.3048 0.9906)
			(end 0.3048 0.9906)
			(stroke
				(width 0.1)
				(type default)
			)
			(layer "F.Fab")
		)
		(fp_line
			(start 0.3048 0.9906)
			(end 0.3048 -0.1016)
			(stroke
				(width 0.1)
				(type default)
			)
			(layer "F.Fab")
		)
		(fp_line
			(start -0.3048 -0.1016)
			(end -0.3048 0.9906)
			(stroke
				(width 0.1)
				(type default)
			)
			(layer "F.Fab")
		)
		(fp_line
			(start 0.3048 -0.1016)
			(end -0.3048 -0.1016)
			(stroke
				(width 0.1)
				(type default)
			)
			(layer "F.Fab")
		)
		(pad "1" smd rect
			(at 0 0 270)
			(size 0.508 0.508)
			(layers "F.Cu" "F.Mask" "F.Paste")
			(net "VR_PVCCIN_CPU1_PHASE3")
		)
		(pad "2" smd rect
			(at 0 0.889 270)
			(size 0.508 0.508)
			(layers "F.Cu" "F.Mask" "F.Paste")
			(net "VR_PVCCIN_CPU1_PHASE3_RC")
		)
		(zone
			(layer "F.Cu")
			(hatch none 0.5)
			(connect_pads
				(clearance 0)
			)
			(min_thickness 0.25)
			(keepout
				(tracks not_allowed)
				(vias allowed)
				(pads allowed)
				(copperpour not_allowed)
				(footprints allowed)
			)
			(placement
				(enabled no)
				(sheetname "")
			)
			(fill
				(thermal_gap 0.5)
				(thermal_bridge_width 0.5)
				(island_removal_mode 0)
			)
			(polygon
				(pts
					(xy 39.1668 -69.5706) (xy 39.1668 -69.0626) (xy 39.5478 -69.0626) (xy 39.5478 -69.5706)
				)
			)
		)
		(zone
			(layer "F.Cu")
			(hatch none 0.5)
			(connect_pads
				(clearance 0)
			)
			(min_thickness 0.25)
			(keepout
				(tracks allowed)
				(vias not_allowed)
				(pads allowed)
				(copperpour not_allowed)
				(footprints allowed)
			)
			(placement
				(enabled no)
				(sheetname "")
			)
			(fill
				(thermal_gap 0.5)
				(thermal_bridge_width 0.5)
				(island_removal_mode 0)
			)
			(polygon
				(pts
					(xy 39.5478 -69.5706) (xy 39.5478 -69.0626) (xy 39.1668 -69.0626) (xy 39.1668 -69.5706)
				)
			)
		)
	)
	(footprint ""
		(layer "F.Cu")
		(at 165.354 -74.803)
		(property "Reference" "C4D24"
			(at 0 0 0)
			(layer "F.SilkS")
			(hide yes)
			(effects
				(font
					(size 1.27 1.27)
				)
			)
		)
		(property "Value" ""
			(at 0 0 0)
			(layer "F.Fab")
			(effects
				(font
					(size 1.27 1.27)
				)
			)
		)
		(duplicate_pad_numbers_are_jumpers no)
		(fp_poly
			(pts
				(xy 0.3048 -0.1016) (xy 0.3048 0.9906) (xy -0.3048 0.9906) (xy -0.3048 -0.1016)
			)
			(stroke
				(width 0)
				(type default)
			)
			(fill no)
			(layer "F.CrtYd")
		)
		(fp_line
			(start -0.3048 -0.1016)
			(end -0.3048 0.9906)
			(stroke
				(width 0.1)
				(type default)
			)
			(layer "F.Fab")
		)
		(fp_line
			(start -0.3048 0.9906)
			(end 0.3048 0.9906)
			(stroke
				(width 0.1)
				(type default)
			)
			(layer "F.Fab")
		)
		(fp_line
			(start 0.3048 -0.1016)
			(end -0.3048 -0.1016)
			(stroke
				(width 0.1)
				(type default)
			)
			(layer "F.Fab")
		)
		(fp_line
			(start 0.3048 0.9906)
			(end 0.3048 -0.1016)
			(stroke
				(width 0.1)
				(type default)
			)
			(layer "F.Fab")
		)
		(pad "1" smd rect
			(at 0 0)
			(size 0.508 0.508)
			(layers "F.Cu" "F.Mask" "F.Paste")
			(net "P3V3_DB1200_A")
		)
		(pad "2" smd rect
			(at 0 0.889)
			(size 0.508 0.508)
			(layers "F.Cu" "F.Mask" "F.Paste")
			(net "GND")
		)
		(zone
			(layer "F.Cu")
			(hatch none 0.5)
			(connect_pads
				(clearance 0)
			)
			(min_thickness 0.25)
			(keepout
				(tracks allowed)
				(vias not_allowed)
				(pads allowed)
				(copperpour not_allowed)
				(footprints allowed)
			)
			(placement
				(enabled no)
				(sheetname "")
			)
			(fill
				(thermal_gap 0.5)
				(thermal_bridge_width 0.5)
				(island_removal_mode 0)
			)
			(polygon
				(pts
					(xy 165.1 -74.549) (xy 165.608 -74.549) (xy 165.608 -74.168) (xy 165.1 -74.168)
				)
			)
		)
		(zone
			(layer "F.Cu")
			(hatch none 0.5)
			(connect_pads
				(clearance 0)
			)
			(min_thickness 0.25)
			(keepout
				(tracks not_allowed)
				(vias allowed)
				(pads allowed)
				(copperpour not_allowed)
				(footprints allowed)
			)
			(placement
				(enabled no)
				(sheetname "")
			)
			(fill
				(thermal_gap 0.5)
				(thermal_bridge_width 0.5)
				(island_removal_mode 0)
			)
			(polygon
				(pts
					(xy 165.1 -74.168) (xy 165.608 -74.168) (xy 165.608 -74.549) (xy 165.1 -74.549)
				)
			)
		)
	)
	(footprint ""
		(layer "F.Cu")
		(at 42.31513 -109.512862)
		(property "Reference" ""
			(at 0 0 0)
			(layer "F.SilkS")
			(hide yes)
			(effects
				(font
					(size 1.27 1.27)
				)
			)
		)
		(property "Value" ""
			(at 0 0 0)
			(layer "F.Fab")
			(effects
				(font
					(size 1.27 1.27)
				)
			)
		)
		(duplicate_pad_numbers_are_jumpers no)
		(fp_poly
			(pts
				(arc
					(start 2.032 0)
					(mid -2.032 0)
					(end 2.032 0)
				)
			)
			(stroke
				(width 0)
				(type default)
			)
			(fill no)
			(layer "F.CrtYd")
		)
		(pad "1" smd circle
			(at 0 0)
			(size 1.016 1.016)
			(layers "F.Cu" "F.Mask" "F.Paste")
			(net "Net_385")
		)
		(zone
			(layer "F.Cu")
			(hatch none 0.5)
			(connect_pads
				(clearance 0)
			)
			(min_thickness 0.25)
			(keepout
				(tracks not_allowed)
				(vias allowed)
				(pads allowed)
				(copperpour not_allowed)
				(footprints allowed)
			)
			(placement
				(enabled no)
				(sheetname "")
			)
			(fill
				(thermal_gap 0.5)
				(thermal_bridge_width 0.5)
				(island_removal_mode 0)
			)
			(polygon
				(pts
					(arc
						(start 43.83913 -109.512862)
						(mid 40.79113 -109.512862)
						(end 43.83913 -109.512862)
					)
				)
			)
		)
		(zone
			(layers "F.Cu" "B.Cu" "In1.Cu" "In2.Cu" "In3.Cu" "In4.Cu" "In5.Cu" "In6.Cu"
				"In7.Cu" "In8.Cu" "In9.Cu" "In10.Cu" "In11.Cu" "In12.Cu"
			)
			(hatch none 0.5)
			(connect_pads
				(clearance 0)
			)
			(min_thickness 0.25)
			(keepout
				(tracks allowed)
				(vias not_allowed)
				(pads allowed)
				(copperpour not_allowed)
				(footprints allowed)
			)
			(placement
				(enabled no)
				(sheetname "")
			)
			(fill
				(thermal_gap 0.5)
				(thermal_bridge_width 0.5)
				(island_removal_mode 0)
			)
			(polygon
				(pts
					(arc
						(start 43.83913 -109.512862)
						(mid 40.79113 -109.512862)
						(end 43.83913 -109.512862)
					)
				)
			)
		)
	)
	(footprint ""
		(layer "F.Cu")
		(at 186.015376 -59.243722 180)
		(property "Reference" "C22W13"
			(at 0 0 180)
			(layer "F.SilkS")
			(hide yes)
			(effects
				(font
					(size 1.27 1.27)
				)
			)
		)
		(property "Value" "*"
			(at -0.0762 -6.2357 180)
			(unlocked yes)
			(layer "F.Fab")
			(hide yes)
			(effects
				(font
					(size 1.27 1.016)
					(thickness 0.1524)
				)
			)
		)
		(property "Device Type" "SC22U16V5MX-4-GP_SMD-BCG5-SC22A"
			(at -0.0762 -8.2677 180)
			(unlocked yes)
			(layer "F.Fab")
			(hide yes)
			(effects
				(font
					(size 1.27 1.016)
					(thickness 0.1524)
				)
			)
		)
		(duplicate_pad_numbers_are_jumpers no)
		(fp_line
			(start 0.635 0)
			(end -0.635 0)
			(stroke
				(width 0.508)
				(type default)
			)
			(layer "F.SilkS")
		)
		(fp_rect
			(start -0.9652 1.778)
			(end 0.9652 -1.778)
			(stroke
				(width 0)
				(type default)
			)
			(fill no)
			(layer "F.CrtYd")
		)
		(fp_poly
			(pts
				(xy -0.9652 -1.778) (xy 0.9652 -1.778) (xy 0.9652 1.778) (xy -0.9652 1.778)
			)
			(stroke
				(width 0)
				(type default)
			)
			(fill no)
			(layer "F.Fab")
		)
		(pad "1" smd rect
			(at 0 -0.9652 180)
			(size 1.397 1.143)
			(layers "F.Cu" "F.Mask" "F.Paste")
			(net "VR_FET_SW_P12V_STBY_PVCCIN_CPU0")
		)
		(pad "2" smd rect
			(at 0 0.9652 180)
			(size 1.397 1.143)
			(layers "F.Cu" "F.Mask" "F.Paste")
			(net "GND")
		)
	)
	(footprint ""
		(layer "F.Cu")
		(at 324.5485 -121.666 -90)
		(property "Reference" "C828"
			(at -0.8382 -0.67818 270)
			(unlocked yes)
			(layer "F.SilkS")
			(effects
				(font
					(size 0.4064 0.254)
					(thickness 0.1524)
				)
				(justify left)
			)
		)
		(property "Value" ""
			(at 0 0 270)
			(layer "F.Fab")
			(effects
				(font
					(size 1.27 1.27)
				)
			)
		)
		(duplicate_pad_numbers_are_jumpers no)
		(fp_poly
			(pts
				(xy 0.3048 -0.1016) (xy 0.3048 0.9906) (xy -0.3048 0.9906) (xy -0.3048 -0.1016)
			)
			(stroke
				(width 0)
				(type default)
			)
			(fill no)
			(layer "F.CrtYd")
		)
		(fp_line
			(start -0.3048 0.9906)
			(end 0.3048 0.9906)
			(stroke
				(width 0.1)
				(type default)
			)
			(layer "F.Fab")
		)
		(fp_line
			(start 0.3048 0.9906)
			(end 0.3048 -0.1016)
			(stroke
				(width 0.1)
				(type default)
			)
			(layer "F.Fab")
		)
		(fp_line
			(start -0.3048 -0.1016)
			(end -0.3048 0.9906)
			(stroke
				(width 0.1)
				(type default)
			)
			(layer "F.Fab")
		)
		(fp_line
			(start 0.3048 -0.1016)
			(end -0.3048 -0.1016)
			(stroke
				(width 0.1)
				(type default)
			)
			(layer "F.Fab")
		)
		(pad "1" smd rect
			(at 0 0 270)
			(size 0.508 0.508)
			(layers "F.Cu" "F.Mask" "F.Paste")
			(net "P3E_CPU0_PE1_PCH_TXN<13>")
		)
		(pad "2" smd rect
			(at 0 0.889 270)
			(size 0.508 0.508)
			(layers "F.Cu" "F.Mask" "F.Paste")
			(net "P3E_CPU0_PE1_PCH_CON_TXN<13>")
		)
		(zone
			(layer "F.Cu")
			(hatch none 0.5)
			(connect_pads
				(clearance 0)
			)
			(min_thickness 0.25)
			(keepout
				(tracks allowed)
				(vias not_allowed)
				(pads allowed)
				(copperpour not_allowed)
				(footprints allowed)
			)
			(placement
				(enabled no)
				(sheetname "")
			)
			(fill
				(thermal_gap 0.5)
				(thermal_bridge_width 0.5)
				(island_removal_mode 0)
			)
			(polygon
				(pts
					(xy 324.2945 -121.92) (xy 324.2945 -121.412) (xy 323.9135 -121.412) (xy 323.9135 -121.92)
				)
			)
		)
	)
	(footprint ""
		(layer "F.Cu")
		(at 346.456 -104.267 180)
		(property "Reference" "C7C7"
			(at 0 0 180)
			(layer "F.SilkS")
			(hide yes)
			(effects
				(font
					(size 1.27 1.27)
				)
			)
		)
		(property "Value" "*"
			(at -0.0762 -6.2357 180)
			(unlocked yes)
			(layer "F.Fab")
			(hide yes)
			(effects
				(font
					(size 1.27 1.016)
					(thickness 0.1524)
				)
			)
		)
		(property "Device Type" "SC22U16V5MX-4-GP_SMD-BCG5-SC22A"
			(at -0.0762 -8.2677 180)
			(unlocked yes)
			(layer "F.Fab")
			(hide yes)
			(effects
				(font
					(size 1.27 1.016)
					(thickness 0.1524)
				)
			)
		)
		(duplicate_pad_numbers_are_jumpers no)
		(fp_line
			(start 0.635 0)
			(end -0.635 0)
			(stroke
				(width 0.508)
				(type default)
			)
			(layer "F.SilkS")
		)
		(fp_rect
			(start -0.9652 1.778)
			(end 0.9652 -1.778)
			(stroke
				(width 0)
				(type default)
			)
			(fill no)
			(layer "F.CrtYd")
		)
		(fp_poly
			(pts
				(xy -0.9652 -1.778) (xy 0.9652 -1.778) (xy 0.9652 1.778) (xy -0.9652 1.778)
			)
			(stroke
				(width 0)
				(type default)
			)
			(fill no)
			(layer "F.Fab")
		)
		(pad "1" smd rect
			(at 0 -0.9652 180)
			(size 1.397 1.143)
			(layers "F.Cu" "F.Mask" "F.Paste")
			(net "VR_FET_SW_P12V_STBY_PVCCIO_CPU0")
		)
		(pad "2" smd rect
			(at 0 0.9652 180)
			(size 1.397 1.143)
			(layers "F.Cu" "F.Mask" "F.Paste")
			(net "GND")
		)
	)
	(footprint ""
		(layer "F.Cu")
		(at 349.123 -17.78 180)
		(property "Reference" "C7F17"
			(at 0 0 180)
			(layer "F.SilkS")
			(hide yes)
			(effects
				(font
					(size 1.27 1.27)
				)
			)
		)
		(property "Value" ""
			(at 0 0 180)
			(layer "F.Fab")
			(effects
				(font
					(size 1.27 1.27)
				)
			)
		)
		(duplicate_pad_numbers_are_jumpers no)
		(fp_rect
			(start 0.3048 -0.1016)
			(end -0.3048 0.9906)
			(stroke
				(width 0)
				(type default)
			)
			(fill no)
			(layer "F.CrtYd")
		)
		(fp_line
			(start 0.3048 0.9906)
			(end 0.3048 -0.1016)
			(stroke
				(width 0.1)
				(type default)
			)
			(layer "F.Fab")
		)
		(fp_line
			(start 0.3048 -0.1016)
			(end -0.3048 -0.1016)
			(stroke
				(width 0.1)
				(type default)
			)
			(layer "F.Fab")
		)
		(fp_line
			(start -0.3048 0.9906)
			(end 0.3048 0.9906)
			(stroke
				(width 0.1)
				(type default)
			)
			(layer "F.Fab")
		)
		(fp_line
			(start -0.3048 -0.1016)
			(end -0.3048 0.9906)
			(stroke
				(width 0.1)
				(type default)
			)
			(layer "F.Fab")
		)
		(pad "1" smd rect
			(at 0 0 180)
			(size 0.508 0.508)
			(layers "F.Cu" "F.Mask" "F.Paste")
			(net "VR_PVDDQ_ABC_VDD")
		)
		(pad "2" smd rect
			(at 0 0.889 180)
			(size 0.508 0.508)
			(layers "F.Cu" "F.Mask" "F.Paste")
			(net "GND")
		)
		(zone
			(layer "F.Cu")
			(hatch none 0.5)
			(connect_pads
				(clearance 0)
			)
			(min_thickness 0.25)
			(keepout
				(tracks not_allowed)
				(vias allowed)
				(pads allowed)
				(copperpour not_allowed)
				(footprints allowed)
			)
			(placement
				(enabled no)
				(sheetname "")
			)
			(fill
				(thermal_gap 0.5)
				(thermal_bridge_width 0.5)
				(island_removal_mode 0)
			)
			(polygon
				(pts
					(xy 348.869 -18.034) (xy 349.377 -18.034) (xy 349.377 -18.415) (xy 348.869 -18.415)
				)
			)
		)
		(zone
			(layer "F.Cu")
			(hatch none 0.5)
			(connect_pads
				(clearance 0)
			)
			(min_thickness 0.25)
			(keepout
				(tracks allowed)
				(vias not_allowed)
				(pads allowed)
				(copperpour not_allowed)
				(footprints allowed)
			)
			(placement
				(enabled no)
				(sheetname "")
			)
			(fill
				(thermal_gap 0.5)
				(thermal_bridge_width 0.5)
				(island_removal_mode 0)
			)
			(polygon
				(pts
					(xy 348.869 -18.034) (xy 349.377 -18.034) (xy 349.377 -18.415) (xy 348.869 -18.415)
				)
			)
		)
	)
	(footprint ""
		(layer "F.Cu")
		(at 369.333526 -105.198164 90)
		(property "Reference" "R7C2"
			(at 0 0 90)
			(layer "F.SilkS")
			(hide yes)
			(effects
				(font
					(size 1.27 1.27)
				)
			)
		)
		(property "Value" ""
			(at 0 0 90)
			(layer "F.Fab")
			(effects
				(font
					(size 1.27 1.27)
				)
			)
		)
		(duplicate_pad_numbers_are_jumpers no)
		(fp_poly
			(pts
				(xy -0.2794 -0.1016) (xy 0.2794 -0.1016) (xy 0.2794 0.9906) (xy -0.2794 0.9906)
			)
			(stroke
				(width 0)
				(type default)
			)
			(fill no)
			(layer "F.CrtYd")
		)
		(fp_line
			(start 0.2794 -0.1016)
			(end -0.2794 -0.1016)
			(stroke
				(width 0.1)
				(type default)
			)
			(layer "F.Fab")
		)
		(fp_line
			(start -0.2794 -0.1016)
			(end -0.2794 0.9906)
			(stroke
				(width 0.1)
				(type default)
			)
			(layer "F.Fab")
		)
		(fp_line
			(start 0.2794 0.9906)
			(end 0.2794 -0.1016)
			(stroke
				(width 0.1)
				(type default)
			)
			(layer "F.Fab")
		)
		(fp_line
			(start -0.2794 0.9906)
			(end 0.2794 0.9906)
			(stroke
				(width 0.1)
				(type default)
			)
			(layer "F.Fab")
		)
		(pad "1" smd rect
			(at 0 0 90)
			(size 0.508 0.508)
			(layers "F.Cu" "F.Mask" "F.Paste")
			(net "CLK_100M_BMC_PE_R_DN")
		)
		(pad "2" smd rect
			(at 0 0.889 90)
			(size 0.508 0.508)
			(layers "F.Cu" "F.Mask" "F.Paste")
			(net "CLK_100M_BMC_PE_DN")
		)
		(zone
			(layer "F.Cu")
			(hatch none 0.5)
			(connect_pads
				(clearance 0)
			)
			(min_thickness 0.25)
			(keepout
				(tracks allowed)
				(vias not_allowed)
				(pads allowed)
				(copperpour not_allowed)
				(footprints allowed)
			)
			(placement
				(enabled no)
				(sheetname "")
			)
			(fill
				(thermal_gap 0.5)
				(thermal_bridge_width 0.5)
				(island_removal_mode 0)
			)
			(polygon
				(pts
					(xy 369.587526 -104.944164) (xy 369.587526 -105.452164) (xy 369.968526 -105.452164) (xy 369.968526 -104.944164)
				)
			)
		)
		(zone
			(layer "F.Cu")
			(hatch none 0.5)
			(connect_pads
				(clearance 0)
			)
			(min_thickness 0.25)
			(keepout
				(tracks not_allowed)
				(vias allowed)
				(pads allowed)
				(copperpour not_allowed)
				(footprints allowed)
			)
			(placement
				(enabled no)
				(sheetname "")
			)
			(fill
				(thermal_gap 0.5)
				(thermal_bridge_width 0.5)
				(island_removal_mode 0)
			)
			(polygon
				(pts
					(xy 369.968526 -104.944164) (xy 369.968526 -105.452164) (xy 369.587526 -105.452164) (xy 369.587526 -104.944164)
				)
			)
		)
	)
	(footprint ""
		(layer "F.Cu")
		(at 324.5485 -120.396 -90)
		(property "Reference" "C829"
			(at -0.8382 -0.67818 270)
			(unlocked yes)
			(layer "F.SilkS")
			(effects
				(font
					(size 0.4064 0.254)
					(thickness 0.1524)
				)
				(justify left)
			)
		)
		(property "Value" ""
			(at 0 0 270)
			(layer "F.Fab")
			(effects
				(font
					(size 1.27 1.27)
				)
			)
		)
		(duplicate_pad_numbers_are_jumpers no)
		(fp_poly
			(pts
				(xy 0.3048 -0.1016) (xy 0.3048 0.9906) (xy -0.3048 0.9906) (xy -0.3048 -0.1016)
			)
			(stroke
				(width 0)
				(type default)
			)
			(fill no)
			(layer "F.CrtYd")
		)
		(fp_line
			(start -0.3048 0.9906)
			(end 0.3048 0.9906)
			(stroke
				(width 0.1)
				(type default)
			)
			(layer "F.Fab")
		)
		(fp_line
			(start 0.3048 0.9906)
			(end 0.3048 -0.1016)
			(stroke
				(width 0.1)
				(type default)
			)
			(layer "F.Fab")
		)
		(fp_line
			(start -0.3048 -0.1016)
			(end -0.3048 0.9906)
			(stroke
				(width 0.1)
				(type default)
			)
			(layer "F.Fab")
		)
		(fp_line
			(start 0.3048 -0.1016)
			(end -0.3048 -0.1016)
			(stroke
				(width 0.1)
				(type default)
			)
			(layer "F.Fab")
		)
		(pad "1" smd rect
			(at 0 0 270)
			(size 0.508 0.508)
			(layers "F.Cu" "F.Mask" "F.Paste")
			(net "P3E_CPU0_PE1_PCH_TXP<13>")
		)
		(pad "2" smd rect
			(at 0 0.889 270)
			(size 0.508 0.508)
			(layers "F.Cu" "F.Mask" "F.Paste")
			(net "P3E_CPU0_PE1_PCH_CON_TXP<13>")
		)
		(zone
			(layer "F.Cu")
			(hatch none 0.5)
			(connect_pads
				(clearance 0)
			)
			(min_thickness 0.25)
			(keepout
				(tracks allowed)
				(vias not_allowed)
				(pads allowed)
				(copperpour not_allowed)
				(footprints allowed)
			)
			(placement
				(enabled no)
				(sheetname "")
			)
			(fill
				(thermal_gap 0.5)
				(thermal_bridge_width 0.5)
				(island_removal_mode 0)
			)
			(polygon
				(pts
					(xy 324.2945 -120.65) (xy 324.2945 -120.142) (xy 323.9135 -120.142) (xy 323.9135 -120.65)
				)
			)
		)
	)
	(footprint ""
		(layer "F.Cu")
		(at 49.4284 -70.993)
		(property "Reference" "C1D24"
			(at 0 0 0)
			(layer "F.SilkS")
			(hide yes)
			(effects
				(font
					(size 1.27 1.27)
				)
			)
		)
		(property "Value" ""
			(at 0 0 0)
			(layer "F.Fab")
			(effects
				(font
					(size 1.27 1.27)
				)
			)
		)
		(duplicate_pad_numbers_are_jumpers no)
		(fp_poly
			(pts
				(xy -0.4953 -0.2032) (xy 0.4953 -0.2032) (xy 0.4953 1.6002) (xy -0.4953 1.6002)
			)
			(stroke
				(width 0)
				(type default)
			)
			(fill no)
			(layer "F.CrtYd")
		)
		(fp_line
			(start -0.4953 -0.2032)
			(end 0.4953 -0.2032)
			(stroke
				(width 0.1)
				(type default)
			)
			(layer "F.Fab")
		)
		(fp_line
			(start -0.4953 1.6002)
			(end -0.4953 -0.2032)
			(stroke
				(width 0.1)
				(type default)
			)
			(layer "F.Fab")
		)
		(fp_line
			(start 0.4953 -0.2032)
			(end 0.4953 1.6002)
			(stroke
				(width 0.1)
				(type default)
			)
			(layer "F.Fab")
		)
		(fp_line
			(start 0.4953 1.6002)
			(end -0.4953 1.6002)
			(stroke
				(width 0.1)
				(type default)
			)
			(layer "F.Fab")
		)
		(pad "1" smd rect
			(at 0 0)
			(size 0.762 0.889)
			(layers "F.Cu" "F.Mask" "F.Paste")
			(net "PVCCIN_CPU1")
		)
		(pad "2" smd rect
			(at 0 1.397)
			(size 0.762 0.889)
			(layers "F.Cu" "F.Mask" "F.Paste")
			(net "GND")
		)
		(zone
			(layer "F.Cu")
			(hatch none 0.5)
			(connect_pads
				(clearance 0)
			)
			(min_thickness 0.25)
			(keepout
				(tracks not_allowed)
				(vias allowed)
				(pads allowed)
				(copperpour not_allowed)
				(footprints allowed)
			)
			(placement
				(enabled no)
				(sheetname "")
			)
			(fill
				(thermal_gap 0.5)
				(thermal_bridge_width 0.5)
				(island_removal_mode 0)
			)
			(polygon
				(pts
					(xy 49.0474 -70.5485) (xy 49.8094 -70.5485) (xy 49.8094 -70.0405) (xy 49.0474 -70.0405)
				)
			)
		)
	)
	(footprint ""
		(layer "F.Cu")
		(at 488.3912 -22.1996 180)
		(property "Reference" "R25W156"
			(at -0.8382 -0.67818 180)
			(unlocked yes)
			(layer "F.SilkS")
			(effects
				(font
					(size 0.4064 0.254)
					(thickness 0.1524)
				)
				(justify left)
			)
		)
		(property "Value" ""
			(at 0 0 180)
			(layer "F.Fab")
			(effects
				(font
					(size 1.27 1.27)
				)
			)
		)
		(duplicate_pad_numbers_are_jumpers no)
		(fp_poly
			(pts
				(xy -0.2794 -0.1016) (xy 0.2794 -0.1016) (xy 0.2794 0.9906) (xy -0.2794 0.9906)
			)
			(stroke
				(width 0)
				(type default)
			)
			(fill no)
			(layer "F.CrtYd")
		)
		(fp_line
			(start 0.2794 0.9906)
			(end 0.2794 -0.1016)
			(stroke
				(width 0.1)
				(type default)
			)
			(layer "F.Fab")
		)
		(fp_line
			(start 0.2794 -0.1016)
			(end -0.2794 -0.1016)
			(stroke
				(width 0.1)
				(type default)
			)
			(layer "F.Fab")
		)
		(fp_line
			(start -0.2794 0.9906)
			(end 0.2794 0.9906)
			(stroke
				(width 0.1)
				(type default)
			)
			(layer "F.Fab")
		)
		(fp_line
			(start -0.2794 -0.1016)
			(end -0.2794 0.9906)
			(stroke
				(width 0.1)
				(type default)
			)
			(layer "F.Fab")
		)
		(pad "1" smd rect
			(at 0 0 180)
			(size 0.508 0.508)
			(layers "F.Cu" "F.Mask" "F.Paste")
			(net "P3V3_STBY")
		)
		(pad "2" smd rect
			(at 0 0.889 180)
			(size 0.508 0.508)
			(layers "F.Cu" "F.Mask" "F.Paste")
			(net "UART_BMC_TXD5")
		)
		(zone
			(layer "F.Cu")
			(hatch none 0.5)
			(connect_pads
				(clearance 0)
			)
			(min_thickness 0.25)
			(keepout
				(tracks not_allowed)
				(vias allowed)
				(pads allowed)
				(copperpour not_allowed)
				(footprints allowed)
			)
			(placement
				(enabled no)
				(sheetname "")
			)
			(fill
				(thermal_gap 0.5)
				(thermal_bridge_width 0.5)
				(island_removal_mode 0)
			)
			(polygon
				(pts
					(xy 488.6452 -22.8346) (xy 488.1372 -22.8346) (xy 488.1372 -22.4536) (xy 488.6452 -22.4536)
				)
			)
		)
		(zone
			(layer "F.Cu")
			(hatch none 0.5)
			(connect_pads
				(clearance 0)
			)
			(min_thickness 0.25)
			(keepout
				(tracks allowed)
				(vias not_allowed)
				(pads allowed)
				(copperpour not_allowed)
				(footprints allowed)
			)
			(placement
				(enabled no)
				(sheetname "")
			)
			(fill
				(thermal_gap 0.5)
				(thermal_bridge_width 0.5)
				(island_removal_mode 0)
			)
			(polygon
				(pts
					(xy 488.6452 -22.4536) (xy 488.1372 -22.4536) (xy 488.1372 -22.8346) (xy 488.6452 -22.8346)
				)
			)
		)
	)
	(footprint ""
		(layer "F.Cu")
		(at 4.533138 -20.77339 90)
		(property "Reference" "C1F28"
			(at 0 0 90)
			(layer "F.SilkS")
			(hide yes)
			(effects
				(font
					(size 1.27 1.27)
				)
			)
		)
		(property "Value" ""
			(at 0 0 90)
			(layer "F.Fab")
			(effects
				(font
					(size 1.27 1.27)
				)
			)
		)
		(duplicate_pad_numbers_are_jumpers no)
		(fp_rect
			(start 0.3048 -0.1016)
			(end -0.3048 0.9906)
			(stroke
				(width 0)
				(type default)
			)
			(fill no)
			(layer "F.CrtYd")
		)
		(fp_line
			(start 0.3048 -0.1016)
			(end -0.3048 -0.1016)
			(stroke
				(width 0.1)
				(type default)
			)
			(layer "F.Fab")
		)
		(fp_line
			(start -0.3048 -0.1016)
			(end -0.3048 0.9906)
			(stroke
				(width 0.1)
				(type default)
			)
			(layer "F.Fab")
		)
		(fp_line
			(start 0.3048 0.9906)
			(end 0.3048 -0.1016)
			(stroke
				(width 0.1)
				(type default)
			)
			(layer "F.Fab")
		)
		(fp_line
			(start -0.3048 0.9906)
			(end 0.3048 0.9906)
			(stroke
				(width 0.1)
				(type default)
			)
			(layer "F.Fab")
		)
		(pad "1" smd rect
			(at 0 0 90)
			(size 0.508 0.508)
			(layers "F.Cu" "F.Mask" "F.Paste")
			(net "VR_FET_SW_P12V_STBY_PVDDQ_GHJ")
		)
		(pad "2" smd rect
			(at 0 0.889 90)
			(size 0.508 0.508)
			(layers "F.Cu" "F.Mask" "F.Paste")
			(net "GND")
		)
		(zone
			(layer "F.Cu")
			(hatch none 0.5)
			(connect_pads
				(clearance 0)
			)
			(min_thickness 0.25)
			(keepout
				(tracks allowed)
				(vias not_allowed)
				(pads allowed)
				(copperpour not_allowed)
				(footprints allowed)
			)
			(placement
				(enabled no)
				(sheetname "")
			)
			(fill
				(thermal_gap 0.5)
				(thermal_bridge_width 0.5)
				(island_removal_mode 0)
			)
			(polygon
				(pts
					(xy 4.787138 -21.02739) (xy 4.787138 -20.51939) (xy 5.168138 -20.51939) (xy 5.168138 -21.02739)
				)
			)
		)
		(zone
			(layer "F.Cu")
			(hatch none 0.5)
			(connect_pads
				(clearance 0)
			)
			(min_thickness 0.25)
			(keepout
				(tracks not_allowed)
				(vias allowed)
				(pads allowed)
				(copperpour not_allowed)
				(footprints allowed)
			)
			(placement
				(enabled no)
				(sheetname "")
			)
			(fill
				(thermal_gap 0.5)
				(thermal_bridge_width 0.5)
				(island_removal_mode 0)
			)
			(polygon
				(pts
					(xy 4.787138 -21.02739) (xy 4.787138 -20.51939) (xy 5.168138 -20.51939) (xy 5.168138 -21.02739)
				)
			)
		)
	)
	(footprint ""
		(layer "F.Cu")
		(at 480.08286 -18.48739)
		(property "Reference" "C9G6"
			(at 0 0 0)
			(layer "F.SilkS")
			(hide yes)
			(effects
				(font
					(size 1.27 1.27)
				)
			)
		)
		(property "Value" ""
			(at 0 0 0)
			(layer "F.Fab")
			(effects
				(font
					(size 1.27 1.27)
				)
			)
		)
		(duplicate_pad_numbers_are_jumpers no)
		(fp_poly
			(pts
				(xy 0.3048 -0.1016) (xy 0.3048 0.9906) (xy -0.3048 0.9906) (xy -0.3048 -0.1016)
			)
			(stroke
				(width 0)
				(type default)
			)
			(fill no)
			(layer "F.CrtYd")
		)
		(fp_line
			(start -0.3048 -0.1016)
			(end -0.3048 0.9906)
			(stroke
				(width 0.1)
				(type default)
			)
			(layer "F.Fab")
		)
		(fp_line
			(start -0.3048 0.9906)
			(end 0.3048 0.9906)
			(stroke
				(width 0.1)
				(type default)
			)
			(layer "F.Fab")
		)
		(fp_line
			(start 0.3048 -0.1016)
			(end -0.3048 -0.1016)
			(stroke
				(width 0.1)
				(type default)
			)
			(layer "F.Fab")
		)
		(fp_line
			(start 0.3048 0.9906)
			(end 0.3048 -0.1016)
			(stroke
				(width 0.1)
				(type default)
			)
			(layer "F.Fab")
		)
		(pad "1" smd rect
			(at 0 0)
			(size 0.508 0.508)
			(layers "F.Cu" "F.Mask" "F.Paste")
			(net "GND_LAN_TRCT1234_C")
		)
		(pad "2" smd rect
			(at 0 0.889)
			(size 0.508 0.508)
			(layers "F.Cu" "F.Mask" "F.Paste")
			(net "GND")
		)
		(zone
			(layer "F.Cu")
			(hatch none 0.5)
			(connect_pads
				(clearance 0)
			)
			(min_thickness 0.25)
			(keepout
				(tracks allowed)
				(vias not_allowed)
				(pads allowed)
				(copperpour not_allowed)
				(footprints allowed)
			)
			(placement
				(enabled no)
				(sheetname "")
			)
			(fill
				(thermal_gap 0.5)
				(thermal_bridge_width 0.5)
				(island_removal_mode 0)
			)
			(polygon
				(pts
					(xy 479.82886 -18.23339) (xy 480.33686 -18.23339) (xy 480.33686 -17.85239) (xy 479.82886 -17.85239)
				)
			)
		)
		(zone
			(layer "F.Cu")
			(hatch none 0.5)
			(connect_pads
				(clearance 0)
			)
			(min_thickness 0.25)
			(keepout
				(tracks not_allowed)
				(vias allowed)
				(pads allowed)
				(copperpour not_allowed)
				(footprints allowed)
			)
			(placement
				(enabled no)
				(sheetname "")
			)
			(fill
				(thermal_gap 0.5)
				(thermal_bridge_width 0.5)
				(island_removal_mode 0)
			)
			(polygon
				(pts
					(xy 479.82886 -17.85239) (xy 480.33686 -17.85239) (xy 480.33686 -18.23339) (xy 479.82886 -18.23339)
				)
			)
		)
	)
	(footprint ""
		(layer "F.Cu")
		(at 415.7345 -114.173 -90)
		(property "Reference" "R8E11"
			(at 0 0 270)
			(layer "F.SilkS")
			(hide yes)
			(effects
				(font
					(size 1.27 1.27)
				)
			)
		)
		(property "Value" ""
			(at 0 0 270)
			(layer "F.Fab")
			(effects
				(font
					(size 1.27 1.27)
				)
			)
		)
		(duplicate_pad_numbers_are_jumpers no)
		(fp_poly
			(pts
				(xy -0.2794 -0.1016) (xy 0.2794 -0.1016) (xy 0.2794 0.9906) (xy -0.2794 0.9906)
			)
			(stroke
				(width 0)
				(type default)
			)
			(fill no)
			(layer "F.CrtYd")
		)
		(fp_line
			(start -0.2794 0.9906)
			(end 0.2794 0.9906)
			(stroke
				(width 0.1)
				(type default)
			)
			(layer "F.Fab")
		)
		(fp_line
			(start 0.2794 0.9906)
			(end 0.2794 -0.1016)
			(stroke
				(width 0.1)
				(type default)
			)
			(layer "F.Fab")
		)
		(fp_line
			(start -0.2794 -0.1016)
			(end -0.2794 0.9906)
			(stroke
				(width 0.1)
				(type default)
			)
			(layer "F.Fab")
		)
		(fp_line
			(start 0.2794 -0.1016)
			(end -0.2794 -0.1016)
			(stroke
				(width 0.1)
				(type default)
			)
			(layer "F.Fab")
		)
		(pad "1" smd rect
			(at 0 0 270)
			(size 0.508 0.508)
			(layers "F.Cu" "F.Mask" "F.Paste")
			(net "FM_MEM_THERM_EVENT_LVT3_N")
		)
		(pad "2" smd rect
			(at 0 0.889 270)
			(size 0.508 0.508)
			(layers "F.Cu" "F.Mask" "F.Paste")
			(net "FM_ADR_SMI_GPIO_N")
		)
		(zone
			(layer "F.Cu")
			(hatch none 0.5)
			(connect_pads
				(clearance 0)
			)
			(min_thickness 0.25)
			(keepout
				(tracks not_allowed)
				(vias allowed)
				(pads allowed)
				(copperpour not_allowed)
				(footprints allowed)
			)
			(placement
				(enabled no)
				(sheetname "")
			)
			(fill
				(thermal_gap 0.5)
				(thermal_bridge_width 0.5)
				(island_removal_mode 0)
			)
			(polygon
				(pts
					(xy 415.0995 -114.427) (xy 415.0995 -113.919) (xy 415.4805 -113.919) (xy 415.4805 -114.427)
				)
			)
		)
		(zone
			(layer "F.Cu")
			(hatch none 0.5)
			(connect_pads
				(clearance 0)
			)
			(min_thickness 0.25)
			(keepout
				(tracks allowed)
				(vias not_allowed)
				(pads allowed)
				(copperpour not_allowed)
				(footprints allowed)
			)
			(placement
				(enabled no)
				(sheetname "")
			)
			(fill
				(thermal_gap 0.5)
				(thermal_bridge_width 0.5)
				(island_removal_mode 0)
			)
			(polygon
				(pts
					(xy 415.4805 -114.427) (xy 415.4805 -113.919) (xy 415.0995 -113.919) (xy 415.0995 -114.427)
				)
			)
		)
	)
	(footprint ""
		(layer "F.Cu")
		(at 122.490484 12.014454 -90)
		(property "Reference" "T1P8"
			(at 0 0 270)
			(layer "F.SilkS")
			(hide yes)
			(effects
				(font
					(size 1.27 1.27)
				)
			)
		)
		(property "Value" "*"
			(at -3.302 1.12395 270)
			(unlocked yes)
			(layer "F.Fab")
			(hide yes)
			(effects
				(font
					(size 0.889 0.889)
					(thickness 0.1524)
				)
			)
		)
		(property "Device Type" "TPAD-DIFF-4P-GP_DISCRET-GB3-TPA"
			(at -3.302 -0.40005 270)
			(unlocked yes)
			(layer "F.Fab")
			(hide yes)
			(effects
				(font
					(size 0.889 0.889)
					(thickness 0.1524)
				)
			)
		)
		(duplicate_pad_numbers_are_jumpers no)
		(fp_line
			(start -2.286 2.286)
			(end 2.286 2.286)
			(stroke
				(width 0.1524)
				(type default)
			)
			(layer "F.SilkS")
		)
		(fp_line
			(start 2.286 2.286)
			(end 2.286 -2.286)
			(stroke
				(width 0.1524)
				(type default)
			)
			(layer "F.SilkS")
		)
		(fp_line
			(start -2.286 -2.286)
			(end -2.286 2.286)
			(stroke
				(width 0.1524)
				(type default)
			)
			(layer "F.SilkS")
		)
		(fp_line
			(start 2.286 -2.286)
			(end -2.286 -2.286)
			(stroke
				(width 0.1524)
				(type default)
			)
			(layer "F.SilkS")
		)
		(fp_line
			(start -2.413 -2.413)
			(end -2.413 -1.143)
			(stroke
				(width 0.4064)
				(type default)
			)
			(layer "F.SilkS")
		)
		(fp_line
			(start -1.143 -2.413)
			(end -2.413 -2.413)
			(stroke
				(width 0.4064)
				(type default)
			)
			(layer "F.SilkS")
		)
		(fp_rect
			(start -2.54 2.54)
			(end 2.54 -2.54)
			(stroke
				(width 0)
				(type default)
			)
			(fill no)
			(layer "F.CrtYd")
		)
		(fp_rect
			(start -2.54 2.54)
			(end 2.54 -2.54)
			(stroke
				(width 0)
				(type default)
			)
			(fill no)
			(layer "F.Fab")
		)
		(pad "1" thru_hole circle
			(at -1.27 -1.27 270)
			(size 1.524 1.524)
			(drill 0.9144)
			(layers "*.Cu" "*.Mask")
			(remove_unused_layers no)
			(net "L3_73OHM_6INCH_DP")
			(clearance -0.0508)
			(thermal_gap 0.127)
			(padstack
				(mode front_inner_back)
				(layer "Inner"
					(shape circle)
					(size 1.1684 1.1684)
					(clearance 0.127)
				)
				(layer "B.Cu"
					(shape circle)
					(size 1.524 1.524)
					(clearance -0.0508)
				)
			)
		)
		(pad "2" thru_hole circle
			(at 1.27 -1.27 270)
			(size 1.524 1.524)
			(drill 0.9144)
			(layers "*.Cu" "*.Mask")
			(remove_unused_layers no)
			(net "L3_73OHM_6INCH_DN")
			(clearance -0.0508)
			(thermal_gap 0.127)
			(padstack
				(mode front_inner_back)
				(layer "Inner"
					(shape circle)
					(size 1.1684 1.1684)
					(clearance 0.127)
				)
				(layer "B.Cu"
					(shape circle)
					(size 1.524 1.524)
					(clearance -0.0508)
				)
			)
		)
		(pad "GND1" thru_hole rect
			(at -1.27 1.27 270)
			(size 1.524 1.524)
			(drill 0.9144)
			(layers "*.Cu" "*.Mask")
			(remove_unused_layers no)
			(net "GND")
			(clearance -0.0508)
			(thermal_gap 0.127)
			(padstack
				(mode front_inner_back)
				(layer "Inner"
					(shape circle)
					(size 1.1684 1.1684)
					(clearance 0.127)
				)
				(layer "B.Cu"
					(shape rect)
					(size 1.524 1.524)
					(clearance -0.0508)
				)
			)
		)
		(pad "GND2" thru_hole rect
			(at 1.27 1.27 270)
			(size 1.524 1.524)
			(drill 0.9144)
			(layers "*.Cu" "*.Mask")
			(remove_unused_layers no)
			(net "GND")
			(clearance -0.0508)
			(thermal_gap 0.127)
			(padstack
				(mode front_inner_back)
				(layer "Inner"
					(shape circle)
					(size 1.1684 1.1684)
					(clearance 0.127)
				)
				(layer "B.Cu"
					(shape rect)
					(size 1.524 1.524)
					(clearance -0.0508)
				)
			)
		)
	)
	(footprint ""
		(layer "F.Cu")
		(at 13.8938 -23.241 90)
		(property "Reference" "C1F20"
			(at 0 0 90)
			(layer "F.SilkS")
			(hide yes)
			(effects
				(font
					(size 1.27 1.27)
				)
			)
		)
		(property "Value" ""
			(at 0 0 90)
			(layer "F.Fab")
			(effects
				(font
					(size 1.27 1.27)
				)
			)
		)
		(duplicate_pad_numbers_are_jumpers no)
		(fp_rect
			(start -0.3048 -0.1016)
			(end 0.3048 0.9906)
			(stroke
				(width 0)
				(type default)
			)
			(fill no)
			(layer "F.CrtYd")
		)
		(fp_line
			(start 0.3048 -0.1016)
			(end -0.3048 -0.1016)
			(stroke
				(width 0.1)
				(type default)
			)
			(layer "F.Fab")
		)
		(fp_line
			(start -0.3048 -0.1016)
			(end -0.3048 0.9906)
			(stroke
				(width 0.1)
				(type default)
			)
			(layer "F.Fab")
		)
		(fp_line
			(start 0.3048 0.9906)
			(end 0.3048 -0.1016)
			(stroke
				(width 0.1)
				(type default)
			)
			(layer "F.Fab")
		)
		(fp_line
			(start -0.3048 0.9906)
			(end 0.3048 0.9906)
			(stroke
				(width 0.1)
				(type default)
			)
			(layer "F.Fab")
		)
		(pad "1" smd rect
			(at 0 0 90)
			(size 0.508 0.508)
			(layers "F.Cu" "F.Mask" "F.Paste")
			(net "P3E_CPU1_PE3_MP_C_TXN<0>")
		)
		(pad "2" smd rect
			(at 0 0.889 90)
			(size 0.508 0.508)
			(layers "F.Cu" "F.Mask" "F.Paste")
			(net "P3E_CPU1_PE3_MP_TXN<0>")
		)
		(zone
			(layer "F.Cu")
			(hatch none 0.5)
			(connect_pads
				(clearance 0)
			)
			(min_thickness 0.25)
			(keepout
				(tracks allowed)
				(vias not_allowed)
				(pads allowed)
				(copperpour not_allowed)
				(footprints allowed)
			)
			(placement
				(enabled no)
				(sheetname "")
			)
			(fill
				(thermal_gap 0.5)
				(thermal_bridge_width 0.5)
				(island_removal_mode 0)
			)
			(polygon
				(pts
					(xy 14.1478 -22.987) (xy 14.5288 -22.987) (xy 14.5288 -23.495) (xy 14.1478 -23.495)
				)
			)
		)
		(zone
			(layer "F.Cu")
			(hatch none 0.5)
			(connect_pads
				(clearance 0)
			)
			(min_thickness 0.25)
			(keepout
				(tracks not_allowed)
				(vias allowed)
				(pads allowed)
				(copperpour not_allowed)
				(footprints allowed)
			)
			(placement
				(enabled no)
				(sheetname "")
			)
			(fill
				(thermal_gap 0.5)
				(thermal_bridge_width 0.5)
				(island_removal_mode 0)
			)
			(polygon
				(pts
					(xy 14.1478 -22.987) (xy 14.5288 -22.987) (xy 14.5288 -23.495) (xy 14.1478 -23.495)
				)
			)
		)
	)
	(footprint ""
		(layer "F.Cu")
		(at 366.268 3.81 90)
		(property "Reference" "J7G3"
			(at 5.63245 2.22758 0)
			(unlocked yes)
			(layer "F.SilkS")
			(effects
				(font
					(size 0.7874 0.5842)
					(thickness 0.1524)
				)
			)
		)
		(property "Value" ""
			(at 0 0 90)
			(layer "F.Fab")
			(effects
				(font
					(size 1.27 1.27)
				)
			)
		)
		(duplicate_pad_numbers_are_jumpers no)
		(fp_line
			(start 3.8227 -1.27)
			(end 3.8227 13.97)
			(stroke
				(width 0.1524)
				(type default)
			)
			(layer "F.SilkS")
		)
		(fp_line
			(start -1.2827 -1.27)
			(end 3.8227 -1.27)
			(stroke
				(width 0.1524)
				(type default)
			)
			(layer "F.SilkS")
		)
		(fp_line
			(start 3.7592 -1.143)
			(end 3.758184 -1.143)
			(stroke
				(width 0.1)
				(type default)
			)
			(layer "F.SilkS")
		)
		(fp_line
			(start -1.2192 -1.143)
			(end -1.218946 -1.143)
			(stroke
				(width 0.1)
				(type default)
			)
			(layer "F.SilkS")
		)
		(fp_line
			(start 3.7592 13.843)
			(end 3.758946 13.843)
			(stroke
				(width 0.1524)
				(type default)
			)
			(layer "F.SilkS")
		)
		(fp_line
			(start -1.2192 13.843)
			(end -1.218946 13.843)
			(stroke
				(width 0.1524)
				(type default)
			)
			(layer "F.SilkS")
		)
		(fp_line
			(start 3.8227 13.97)
			(end -1.2827 13.97)
			(stroke
				(width 0.1524)
				(type default)
			)
			(layer "F.SilkS")
		)
		(fp_line
			(start -1.2827 13.97)
			(end -1.2827 -1.27)
			(stroke
				(width 0.1524)
				(type default)
			)
			(layer "F.SilkS")
		)
		(fp_poly
			(pts
				(xy -1.7145 -0.005588) (xy -2.9845 0.502412) (xy -2.9845 -0.513588)
			)
			(stroke
				(width 0)
				(type default)
			)
			(fill yes)
			(layer "F.SilkS")
		)
		(fp_poly
			(pts
				(xy -1.7145 -0.005588) (xy -2.9845 0.502412) (xy -2.9845 -0.513588)
			)
			(stroke
				(width 0)
				(type default)
			)
			(fill yes)
			(layer "B.SilkS")
		)
		(fp_poly
			(pts
				(xy -1.2827 -1.27) (xy -1.2827 13.97) (xy 3.8227 13.97) (xy 3.8227 -1.27)
			)
			(stroke
				(width 0)
				(type default)
			)
			(fill no)
			(layer "F.CrtYd")
		)
		(fp_poly
			(pts
				(xy -1.7145 -0.005588) (xy -2.9845 0.502412) (xy -2.9845 -0.513588)
			)
			(stroke
				(width 0)
				(type default)
			)
			(fill yes)
			(layer "B.Fab")
		)
		(fp_line
			(start 3.8227 -1.27)
			(end -1.2827 -1.27)
			(stroke
				(width 0.1)
				(type default)
			)
			(layer "F.Fab")
		)
		(fp_line
			(start -1.2827 -1.27)
			(end -1.2827 13.97)
			(stroke
				(width 0.1)
				(type default)
			)
			(layer "F.Fab")
		)
		(fp_line
			(start 3.8227 13.97)
			(end 3.8227 -1.27)
			(stroke
				(width 0.1)
				(type default)
			)
			(layer "F.Fab")
		)
		(fp_line
			(start -1.2827 13.97)
			(end 3.8227 13.97)
			(stroke
				(width 0.1)
				(type default)
			)
			(layer "F.Fab")
		)
		(fp_poly
			(pts
				(xy -1.7145 -0.005588) (xy -2.9845 0.502412) (xy -2.9845 -0.513588)
			)
			(stroke
				(width 0)
				(type default)
			)
			(fill yes)
			(layer "F.Fab")
		)
		(fp_text user "2"
			(at 4.41706 -0.0381 0)
			(unlocked yes)
			(layer "F.SilkS")
			(effects
				(font
					(size 0.7874 0.5842)
					(thickness 0.1524)
				)
			)
		)
		(fp_text user "12"
			(at 4.41325 13.23086 0)
			(unlocked yes)
			(layer "F.SilkS")
			(effects
				(font
					(size 0.7874 0.5842)
					(thickness 0.1524)
				)
			)
		)
		(fp_text user "11"
			(at 2.97561 14.7066 0)
			(unlocked yes)
			(layer "F.SilkS")
			(effects
				(font
					(size 0.7874 0.5842)
					(thickness 0.1524)
				)
			)
		)
		(fp_text user "12"
			(at -0.508 -1.47193 90)
			(unlocked yes)
			(layer "B.SilkS")
			(effects
				(font
					(size 0.7874 0.5842)
					(thickness 0.1524)
				)
				(justify mirror)
			)
		)
		(fp_text user "2"
			(at 4.01701 -0.93218 0)
			(unlocked yes)
			(layer "B.SilkS")
			(effects
				(font
					(size 0.7874 0.5842)
					(thickness 0.1524)
				)
				(justify mirror)
			)
		)
		(fp_text user "11"
			(at -1.40843 12.55268 0)
			(unlocked yes)
			(layer "B.SilkS")
			(effects
				(font
					(size 0.7874 0.5842)
					(thickness 0.1524)
				)
				(justify mirror)
			)
		)
		(fp_text user "2"
			(at 4.5466 0.02667 90)
			(unlocked yes)
			(layer "B.Fab")
			(effects
				(font
					(size 0.7874 0.5842)
					(thickness 0.1524)
				)
				(justify mirror)
			)
		)
		(fp_text user "12"
			(at 4.9403 12.72667 90)
			(unlocked yes)
			(layer "B.Fab")
			(effects
				(font
					(size 0.7874 0.5842)
					(thickness 0.1524)
				)
				(justify mirror)
			)
		)
		(fp_text user "11"
			(at -2.2606 12.72667 90)
			(unlocked yes)
			(layer "B.Fab")
			(effects
				(font
					(size 0.7874 0.5842)
					(thickness 0.1524)
				)
				(justify mirror)
			)
		)
		(fp_text user "2"
			(at 4.445 -0.980694 90)
			(unlocked yes)
			(layer "F.Fab")
			(effects
				(font
					(size 0.7874 0.5842)
					(thickness 0.1524)
				)
			)
		)
		(fp_text user "12"
			(at 4.826 10.703306 90)
			(unlocked yes)
			(layer "F.Fab")
			(effects
				(font
					(size 0.7874 0.5842)
					(thickness 0.1524)
				)
			)
		)
		(fp_text user "11"
			(at -1.4478 13.43787 90)
			(unlocked yes)
			(layer "F.Fab")
			(effects
				(font
					(size 0.7874 0.5842)
					(thickness 0.1524)
				)
			)
		)
		(pad "1" thru_hole rect
			(at 0 0 90)
			(size 1.6256 1.6256)
			(drill 1.2446)
			(layers "*.Cu" "*.Mask")
			(remove_unused_layers no)
			(net "TP_ME_RCVR_BOOT")
			(clearance 0.127)
			(thermal_gap 0.127)
			(padstack
				(mode front_inner_back)
				(layer "Inner"
					(shape circle)
					(size 1.6256 1.6256)
					(clearance 0.127)
				)
				(layer "B.Cu"
					(shape rect)
					(size 1.6256 1.6256)
					(clearance 0.127)
				)
			)
		)
		(pad "2" thru_hole circle
			(at 2.54 0 90)
			(size 1.6256 1.6256)
			(drill 1.2446)
			(layers "*.Cu" "*.Mask")
			(remove_unused_layers no)
			(net "TP_BIOS_USB_RECOVERY")
			(clearance 0.127)
			(thermal_gap 0.127)
		)
		(pad "3" thru_hole circle
			(at 0 2.54 90)
			(size 1.6256 1.6256)
			(drill 1.2446)
			(layers "*.Cu" "*.Mask")
			(remove_unused_layers no)
			(net "FM_ME_RECOVER_N")
			(clearance 0.127)
			(thermal_gap 0.127)
		)
		(pad "4" thru_hole circle
			(at 2.54 2.54 90)
			(size 1.6256 1.6256)
			(drill 1.2446)
			(layers "*.Cu" "*.Mask")
			(remove_unused_layers no)
			(net "FM_BIOS_USB_RECOVERY")
			(clearance 0.127)
			(thermal_gap 0.127)
		)
		(pad "5" thru_hole circle
			(at 0 5.08 90)
			(size 1.6256 1.6256)
			(drill 1.2446)
			(layers "*.Cu" "*.Mask")
			(remove_unused_layers no)
			(net "PD_ME_RCVR_N")
			(clearance 0.127)
			(thermal_gap 0.127)
		)
		(pad "6" thru_hole circle
			(at 2.54 5.08 90)
			(size 1.6256 1.6256)
			(drill 1.2446)
			(layers "*.Cu" "*.Mask")
			(remove_unused_layers no)
			(net "PU_BIOS_USB_RECOVERY")
			(clearance 0.127)
			(thermal_gap 0.127)
		)
		(pad "7" thru_hole circle
			(at 0 7.62 90)
			(size 1.6256 1.6256)
			(drill 1.2446)
			(layers "*.Cu" "*.Mask")
			(remove_unused_layers no)
			(net "TP_PASSWORD_CLEAR")
			(clearance 0.127)
			(thermal_gap 0.127)
		)
		(pad "8" thru_hole circle
			(at 2.54 7.62 90)
			(size 1.6256 1.6256)
			(drill 1.2446)
			(layers "*.Cu" "*.Mask")
			(remove_unused_layers no)
			(net "TP_BIOS_RECOVER_BOOT")
			(clearance 0.127)
			(thermal_gap 0.127)
		)
		(pad "9" thru_hole circle
			(at 0 10.16 90)
			(size 1.6256 1.6256)
			(drill 1.2446)
			(layers "*.Cu" "*.Mask")
			(remove_unused_layers no)
			(net "FM_PASSWORD_CLEAR_N")
			(clearance 0.127)
			(thermal_gap 0.127)
		)
		(pad "10" thru_hole circle
			(at 2.54 10.16 90)
			(size 1.6256 1.6256)
			(drill 1.2446)
			(layers "*.Cu" "*.Mask")
			(remove_unused_layers no)
			(net "FM_BIOS_TOP_SWAP")
			(clearance 0.127)
			(thermal_gap 0.127)
		)
		(pad "11" thru_hole circle
			(at 0 12.7 90)
			(size 1.6256 1.6256)
			(drill 1.2446)
			(layers "*.Cu" "*.Mask")
			(remove_unused_layers no)
			(net "PD_PASSWORD_CLEAR")
			(clearance 0.127)
			(thermal_gap 0.127)
		)
		(pad "12" thru_hole circle
			(at 2.54 12.7 90)
			(size 1.6256 1.6256)
			(drill 1.2446)
			(layers "*.Cu" "*.Mask")
			(remove_unused_layers no)
			(net "PU_BIOS_RECOVER_BOOT")
			(clearance 0.127)
			(thermal_gap 0.127)
		)
	)
	(footprint ""
		(layer "F.Cu")
		(at 338.836 -18.923 -90)
		(property "Reference" "R12W25"
			(at -0.8382 -0.67818 270)
			(unlocked yes)
			(layer "F.SilkS")
			(effects
				(font
					(size 0.4064 0.254)
					(thickness 0.1524)
				)
				(justify left)
			)
		)
		(property "Value" ""
			(at 0 0 270)
			(layer "F.Fab")
			(effects
				(font
					(size 1.27 1.27)
				)
			)
		)
		(duplicate_pad_numbers_are_jumpers no)
		(fp_poly
			(pts
				(xy -0.2794 -0.1016) (xy 0.2794 -0.1016) (xy 0.2794 0.9906) (xy -0.2794 0.9906)
			)
			(stroke
				(width 0)
				(type default)
			)
			(fill no)
			(layer "F.CrtYd")
		)
		(fp_line
			(start -0.2794 0.9906)
			(end 0.2794 0.9906)
			(stroke
				(width 0.1)
				(type default)
			)
			(layer "F.Fab")
		)
		(fp_line
			(start 0.2794 0.9906)
			(end 0.2794 -0.1016)
			(stroke
				(width 0.1)
				(type default)
			)
			(layer "F.Fab")
		)
		(fp_line
			(start -0.2794 -0.1016)
			(end -0.2794 0.9906)
			(stroke
				(width 0.1)
				(type default)
			)
			(layer "F.Fab")
		)
		(fp_line
			(start 0.2794 -0.1016)
			(end -0.2794 -0.1016)
			(stroke
				(width 0.1)
				(type default)
			)
			(layer "F.Fab")
		)
		(pad "1" smd rect
			(at 0 0 270)
			(size 0.508 0.508)
			(layers "F.Cu" "F.Mask" "F.Paste")
			(net "PU_VR_PVDDQ_ABC_FAULT1")
		)
		(pad "2" smd rect
			(at 0 0.889 270)
			(size 0.508 0.508)
			(layers "F.Cu" "F.Mask" "F.Paste")
			(net "PWRGD_PVDDQ_ABC")
		)
		(zone
			(layer "F.Cu")
			(hatch none 0.5)
			(connect_pads
				(clearance 0)
			)
			(min_thickness 0.25)
			(keepout
				(tracks not_allowed)
				(vias allowed)
				(pads allowed)
				(copperpour not_allowed)
				(footprints allowed)
			)
			(placement
				(enabled no)
				(sheetname "")
			)
			(fill
				(thermal_gap 0.5)
				(thermal_bridge_width 0.5)
				(island_removal_mode 0)
			)
			(polygon
				(pts
					(xy 338.201 -19.177) (xy 338.201 -18.669) (xy 338.582 -18.669) (xy 338.582 -19.177)
				)
			)
		)
		(zone
			(layer "F.Cu")
			(hatch none 0.5)
			(connect_pads
				(clearance 0)
			)
			(min_thickness 0.25)
			(keepout
				(tracks allowed)
				(vias not_allowed)
				(pads allowed)
				(copperpour not_allowed)
				(footprints allowed)
			)
			(placement
				(enabled no)
				(sheetname "")
			)
			(fill
				(thermal_gap 0.5)
				(thermal_bridge_width 0.5)
				(island_removal_mode 0)
			)
			(polygon
				(pts
					(xy 338.582 -19.177) (xy 338.582 -18.669) (xy 338.201 -18.669) (xy 338.201 -19.177)
				)
			)
		)
	)
	(footprint ""
		(layer "F.Cu")
		(at 344.932 -93.5228 90)
		(property "Reference" "RT48"
			(at 0 0 90)
			(layer "F.SilkS")
			(hide yes)
			(effects
				(font
					(size 1.27 1.27)
				)
			)
		)
		(property "Value" "*"
			(at -0.0254 -2.6289 90)
			(unlocked yes)
			(layer "F.Fab")
			(hide yes)
			(effects
				(font
					(size 1.27 1.016)
					(thickness 0.1524)
				)
			)
		)
		(property "Device Type" "1R3F-GP_RCL_GP-1R3F-GP,64.1R00A"
			(at -0.0254 -4.1529 90)
			(unlocked yes)
			(layer "F.Fab")
			(hide yes)
			(effects
				(font
					(size 1.27 1.016)
					(thickness 0.1524)
				)
			)
		)
		(duplicate_pad_numbers_are_jumpers no)
		(fp_line
			(start 0.2032 0)
			(end 0.4826 0)
			(stroke
				(width 0.2032)
				(type default)
			)
			(layer "F.SilkS")
		)
		(fp_line
			(start -0.4826 0)
			(end -0.2032 0)
			(stroke
				(width 0.2032)
				(type default)
			)
			(layer "F.SilkS")
		)
		(fp_rect
			(start -0.5842 1.3335)
			(end 0.5842 -1.3335)
			(stroke
				(width 0)
				(type default)
			)
			(fill no)
			(layer "F.CrtYd")
		)
		(fp_rect
			(start -0.5842 1.3335)
			(end 0.5842 -1.3335)
			(stroke
				(width 0)
				(type default)
			)
			(fill no)
			(layer "F.Fab")
		)
		(pad "1" smd custom
			(at 0 -0.762 90)
			(size 0.2159 0.2159)
			(layers "F.Cu" "F.Mask" "F.Paste")
			(net "VR_PVCCIO_CPU0_PH1_SW_RC")
			(options
				(clearance outline)
				(anchor circle)
			)
			(primitives
				(gr_poly
					(pts
						(arc
							(start -0.3302 -0.4318)
							(mid -0.402042 -0.402042)
							(end -0.4318 -0.3302)
						)
						(arc
							(start -0.4318 0.3302)
							(mid -0.402042 0.402042)
							(end -0.3302 0.4318)
						)
						(arc
							(start 0.3302 0.4318)
							(mid 0.402042 0.402042)
							(end 0.4318 0.3302)
						)
						(arc
							(start 0.4318 -0.3302)
							(mid 0.402042 -0.402042)
							(end 0.3302 -0.4318)
						)
					)
					(width 0)
					(fill yes)
				)
			)
		)
		(pad "2" smd custom
			(at 0 0.762 90)
			(size 0.2159 0.2159)
			(layers "F.Cu" "F.Mask" "F.Paste")
			(net "GND")
			(options
				(clearance outline)
				(anchor circle)
			)
			(primitives
				(gr_poly
					(pts
						(arc
							(start -0.3302 -0.4318)
							(mid -0.402042 -0.402042)
							(end -0.4318 -0.3302)
						)
						(arc
							(start -0.4318 0.3302)
							(mid -0.402042 0.402042)
							(end -0.3302 0.4318)
						)
						(arc
							(start 0.3302 0.4318)
							(mid 0.402042 0.402042)
							(end 0.4318 0.3302)
						)
						(arc
							(start 0.4318 -0.3302)
							(mid 0.402042 -0.402042)
							(end 0.3302 -0.4318)
						)
					)
					(width 0)
					(fill yes)
				)
			)
		)
	)
	(footprint ""
		(layer "F.Cu")
		(at 245.7323 -140.208 -90)
		(property "Reference" "C5A11"
			(at 1.848866 0.752348 270)
			(unlocked yes)
			(layer "F.SilkS")
			(effects
				(font
					(size 1.27 0.9652)
					(thickness 0.1524)
				)
			)
		)
		(property "Value" ""
			(at 0 0 270)
			(layer "F.Fab")
			(effects
				(font
					(size 1.27 1.27)
				)
			)
		)
		(duplicate_pad_numbers_are_jumpers no)
		(fp_rect
			(start -0.500126 1.598422)
			(end 0.500126 -0.201422)
			(stroke
				(width 0)
				(type default)
			)
			(fill no)
			(layer "F.CrtYd")
		)
		(fp_line
			(start -0.500126 1.598422)
			(end -0.500126 -0.201422)
			(stroke
				(width 0.1)
				(type default)
			)
			(layer "F.Fab")
		)
		(fp_line
			(start 0.500126 1.598422)
			(end -0.500126 1.598422)
			(stroke
				(width 0.1)
				(type default)
			)
			(layer "F.Fab")
		)
		(fp_line
			(start -0.500126 -0.201422)
			(end 0.500126 -0.201422)
			(stroke
				(width 0.1)
				(type default)
			)
			(layer "F.Fab")
		)
		(fp_line
			(start 0.500126 -0.201422)
			(end 0.500126 1.598422)
			(stroke
				(width 0.1)
				(type default)
			)
			(layer "F.Fab")
		)
		(pad "1" smd rect
			(at 0 0 180)
			(size 0.889 0.9906)
			(layers "F.Cu" "F.Mask" "F.Paste")
			(net "PVDDQ_DEF")
		)
		(pad "2" smd rect
			(at 0 1.397 180)
			(size 0.889 0.9906)
			(layers "F.Cu" "F.Mask" "F.Paste")
			(net "GND")
		)
		(zone
			(layer "F.Cu")
			(hatch none 0.5)
			(connect_pads
				(clearance 0)
			)
			(min_thickness 0.25)
			(keepout
				(tracks not_allowed)
				(vias allowed)
				(pads allowed)
				(copperpour not_allowed)
				(footprints allowed)
			)
			(placement
				(enabled no)
				(sheetname "")
			)
			(fill
				(thermal_gap 0.5)
				(thermal_bridge_width 0.5)
				(island_removal_mode 0)
			)
			(polygon
				(pts
					(xy 244.7798 -140.7033) (xy 244.7798 -139.7127) (xy 245.2878 -139.7127) (xy 245.2878 -140.7033)
				)
			)
		)
		(zone
			(layer "F.Cu")
			(hatch none 0.5)
			(connect_pads
				(clearance 0)
			)
			(min_thickness 0.25)
			(keepout
				(tracks allowed)
				(vias not_allowed)
				(pads allowed)
				(copperpour not_allowed)
				(footprints allowed)
			)
			(placement
				(enabled no)
				(sheetname "")
			)
			(fill
				(thermal_gap 0.5)
				(thermal_bridge_width 0.5)
				(island_removal_mode 0)
			)
			(polygon
				(pts
					(xy 244.7798 -140.7033) (xy 244.7798 -139.7127) (xy 245.2878 -139.7127) (xy 245.2878 -140.7033)
				)
			)
		)
	)
	(footprint ""
		(layer "F.Cu")
		(at 164.084 -69.9262 90)
		(property "Reference" "R4D49"
			(at 0 0 90)
			(layer "F.SilkS")
			(hide yes)
			(effects
				(font
					(size 1.27 1.27)
				)
			)
		)
		(property "Value" ""
			(at 0 0 90)
			(layer "F.Fab")
			(effects
				(font
					(size 1.27 1.27)
				)
			)
		)
		(duplicate_pad_numbers_are_jumpers no)
		(fp_poly
			(pts
				(xy -0.2794 -0.1016) (xy 0.2794 -0.1016) (xy 0.2794 0.9906) (xy -0.2794 0.9906)
			)
			(stroke
				(width 0)
				(type default)
			)
			(fill no)
			(layer "F.CrtYd")
		)
		(fp_line
			(start 0.2794 -0.1016)
			(end -0.2794 -0.1016)
			(stroke
				(width 0.1)
				(type default)
			)
			(layer "F.Fab")
		)
		(fp_line
			(start -0.2794 -0.1016)
			(end -0.2794 0.9906)
			(stroke
				(width 0.1)
				(type default)
			)
			(layer "F.Fab")
		)
		(fp_line
			(start 0.2794 0.9906)
			(end 0.2794 -0.1016)
			(stroke
				(width 0.1)
				(type default)
			)
			(layer "F.Fab")
		)
		(fp_line
			(start -0.2794 0.9906)
			(end 0.2794 0.9906)
			(stroke
				(width 0.1)
				(type default)
			)
			(layer "F.Fab")
		)
		(pad "1" smd rect
			(at 0 0 90)
			(size 0.508 0.508)
			(layers "F.Cu" "F.Mask" "F.Paste")
			(net "P3V3_STBY")
		)
		(pad "2" smd rect
			(at 0 0.889 90)
			(size 0.508 0.508)
			(layers "F.Cu" "F.Mask" "F.Paste")
			(net "IRQ_PVCCIO_CPU1_VRHOT_N")
		)
		(zone
			(layer "F.Cu")
			(hatch none 0.5)
			(connect_pads
				(clearance 0)
			)
			(min_thickness 0.25)
			(keepout
				(tracks allowed)
				(vias not_allowed)
				(pads allowed)
				(copperpour not_allowed)
				(footprints allowed)
			)
			(placement
				(enabled no)
				(sheetname "")
			)
			(fill
				(thermal_gap 0.5)
				(thermal_bridge_width 0.5)
				(island_removal_mode 0)
			)
			(polygon
				(pts
					(xy 164.338 -69.6722) (xy 164.338 -70.1802) (xy 164.719 -70.1802) (xy 164.719 -69.6722)
				)
			)
		)
		(zone
			(layer "F.Cu")
			(hatch none 0.5)
			(connect_pads
				(clearance 0)
			)
			(min_thickness 0.25)
			(keepout
				(tracks not_allowed)
				(vias allowed)
				(pads allowed)
				(copperpour not_allowed)
				(footprints allowed)
			)
			(placement
				(enabled no)
				(sheetname "")
			)
			(fill
				(thermal_gap 0.5)
				(thermal_bridge_width 0.5)
				(island_removal_mode 0)
			)
			(polygon
				(pts
					(xy 164.719 -69.6722) (xy 164.719 -70.1802) (xy 164.338 -70.1802) (xy 164.338 -69.6722)
				)
			)
		)
	)
	(footprint ""
		(layer "F.Cu")
		(at 20.7518 -88.138 90)
		(property "Reference" "C1D1"
			(at 0 0 90)
			(layer "F.SilkS")
			(hide yes)
			(effects
				(font
					(size 1.27 1.27)
				)
			)
		)
		(property "Value" ""
			(at 0 0 90)
			(layer "F.Fab")
			(effects
				(font
					(size 1.27 1.27)
				)
			)
		)
		(duplicate_pad_numbers_are_jumpers no)
		(fp_rect
			(start -0.3048 -0.1016)
			(end 0.3048 0.9906)
			(stroke
				(width 0)
				(type default)
			)
			(fill no)
			(layer "F.CrtYd")
		)
		(fp_line
			(start 0.3048 -0.1016)
			(end -0.3048 -0.1016)
			(stroke
				(width 0.1)
				(type default)
			)
			(layer "F.Fab")
		)
		(fp_line
			(start -0.3048 -0.1016)
			(end -0.3048 0.9906)
			(stroke
				(width 0.1)
				(type default)
			)
			(layer "F.Fab")
		)
		(fp_line
			(start 0.3048 0.9906)
			(end 0.3048 -0.1016)
			(stroke
				(width 0.1)
				(type default)
			)
			(layer "F.Fab")
		)
		(fp_line
			(start -0.3048 0.9906)
			(end 0.3048 0.9906)
			(stroke
				(width 0.1)
				(type default)
			)
			(layer "F.Fab")
		)
		(pad "1" smd rect
			(at 0 0 90)
			(size 0.508 0.508)
			(layers "F.Cu" "F.Mask" "F.Paste")
			(net "VSENSE_PVCCIN_CPU1_AVSP")
		)
		(pad "2" smd rect
			(at 0 0.889 90)
			(size 0.508 0.508)
			(layers "F.Cu" "F.Mask" "F.Paste")
			(net "VSENSE_PVCCIN_CPU1_N")
		)
		(zone
			(layer "F.Cu")
			(hatch none 0.5)
			(connect_pads
				(clearance 0)
			)
			(min_thickness 0.25)
			(keepout
				(tracks allowed)
				(vias not_allowed)
				(pads allowed)
				(copperpour not_allowed)
				(footprints allowed)
			)
			(placement
				(enabled no)
				(sheetname "")
			)
			(fill
				(thermal_gap 0.5)
				(thermal_bridge_width 0.5)
				(island_removal_mode 0)
			)
			(polygon
				(pts
					(xy 21.0058 -87.884) (xy 21.3868 -87.884) (xy 21.3868 -88.392) (xy 21.0058 -88.392)
				)
			)
		)
		(zone
			(layer "F.Cu")
			(hatch none 0.5)
			(connect_pads
				(clearance 0)
			)
			(min_thickness 0.25)
			(keepout
				(tracks not_allowed)
				(vias allowed)
				(pads allowed)
				(copperpour not_allowed)
				(footprints allowed)
			)
			(placement
				(enabled no)
				(sheetname "")
			)
			(fill
				(thermal_gap 0.5)
				(thermal_bridge_width 0.5)
				(island_removal_mode 0)
			)
			(polygon
				(pts
					(xy 21.0058 -87.884) (xy 21.3868 -87.884) (xy 21.3868 -88.392) (xy 21.0058 -88.392)
				)
			)
		)
	)
	(footprint ""
		(layer "F.Cu")
		(at 24.7904 -42.6212 -90)
		(property "Reference" "CR1E1"
			(at 1.24587 0.2794 0)
			(unlocked yes)
			(layer "F.SilkS")
			(effects
				(font
					(size 0.7874 0.5842)
					(thickness 0.1524)
				)
				(justify left)
			)
		)
		(property "Value" ""
			(at 0 0 270)
			(layer "F.Fab")
			(effects
				(font
					(size 1.27 1.27)
				)
			)
		)
		(duplicate_pad_numbers_are_jumpers no)
		(fp_line
			(start -0.980186 2.623312)
			(end -0.980186 1.711706)
			(stroke
				(width 0.1524)
				(type default)
			)
			(layer "F.SilkS")
		)
		(fp_line
			(start -1.461008 1.711706)
			(end -0.980186 0.87884)
			(stroke
				(width 0.1524)
				(type default)
			)
			(layer "F.SilkS")
		)
		(fp_line
			(start -0.980186 1.711706)
			(end -1.461008 1.711706)
			(stroke
				(width 0.1524)
				(type default)
			)
			(layer "F.SilkS")
		)
		(fp_line
			(start -0.499364 1.711706)
			(end -0.980186 1.711706)
			(stroke
				(width 0.1524)
				(type default)
			)
			(layer "F.SilkS")
		)
		(fp_line
			(start -0.980186 0.87884)
			(end -0.499364 1.711706)
			(stroke
				(width 0.1524)
				(type default)
			)
			(layer "F.SilkS")
		)
		(fp_line
			(start -0.499364 0.87884)
			(end -1.461008 0.87884)
			(stroke
				(width 0.1524)
				(type default)
			)
			(layer "F.SilkS")
		)
		(fp_line
			(start -0.980186 -0.244602)
			(end -0.980186 0.87884)
			(stroke
				(width 0.1524)
				(type default)
			)
			(layer "F.SilkS")
		)
		(fp_rect
			(start 0.67437 2.04216)
			(end -0.67437 0.24384)
			(stroke
				(width 0)
				(type default)
			)
			(fill no)
			(layer "F.CrtYd")
		)
		(fp_line
			(start -0.67437 2.04216)
			(end 0.67437 2.04216)
			(stroke
				(width 0.1)
				(type default)
			)
			(layer "F.Fab")
		)
		(fp_line
			(start 0.67437 2.04216)
			(end 0.67437 0.24384)
			(stroke
				(width 0.1)
				(type default)
			)
			(layer "F.Fab")
		)
		(fp_line
			(start -1.461008 1.711706)
			(end -0.980186 0.87884)
			(stroke
				(width 0.1)
				(type default)
			)
			(layer "F.Fab")
		)
		(fp_line
			(start -0.980186 1.711706)
			(end -0.980186 2.623312)
			(stroke
				(width 0.1)
				(type default)
			)
			(layer "F.Fab")
		)
		(fp_line
			(start -0.499364 1.711706)
			(end -1.461008 1.711706)
			(stroke
				(width 0.1)
				(type default)
			)
			(layer "F.Fab")
		)
		(fp_line
			(start -0.980186 0.87884)
			(end -0.499364 1.711706)
			(stroke
				(width 0.1)
				(type default)
			)
			(layer "F.Fab")
		)
		(fp_line
			(start -0.980186 0.87884)
			(end -0.980186 -0.244602)
			(stroke
				(width 0.1)
				(type default)
			)
			(layer "F.Fab")
		)
		(fp_line
			(start -0.499364 0.87884)
			(end -1.461008 0.87884)
			(stroke
				(width 0.1)
				(type default)
			)
			(layer "F.Fab")
		)
		(fp_line
			(start -0.67437 0.24384)
			(end -0.67437 2.04216)
			(stroke
				(width 0.1)
				(type default)
			)
			(layer "F.Fab")
		)
		(fp_line
			(start 0.67437 0.24384)
			(end -0.67437 0.24384)
			(stroke
				(width 0.1)
				(type default)
			)
			(layer "F.Fab")
		)
		(pad "1" smd rect
			(at 0 0 270)
			(size 0.4064 1.016)
			(layers "F.Cu" "F.Mask" "F.Paste")
			(net "P5V_STBY")
		)
		(pad "2" smd rect
			(at 0 2.286 270)
			(size 0.4064 1.016)
			(layers "F.Cu" "F.Mask" "F.Paste")
			(net "FAN_PWM_OUT_SYS0_R")
		)
	)
	(footprint ""
		(layer "F.Cu")
		(at 29.635958 -61.716158 90)
		(property "Reference" "CT25"
			(at -0.78613 0.7874 180)
			(unlocked yes)
			(layer "F.SilkS")
			(effects
				(font
					(size 0.7874 0.5842)
					(thickness 0.1524)
				)
				(justify left)
			)
		)
		(property "Value" ""
			(at 0 0 90)
			(layer "F.Fab")
			(effects
				(font
					(size 1.27 1.27)
				)
			)
		)
		(duplicate_pad_numbers_are_jumpers no)
		(fp_poly
			(pts
				(xy 0.3048 -0.1016) (xy 0.3048 0.9906) (xy -0.3048 0.9906) (xy -0.3048 -0.1016)
			)
			(stroke
				(width 0)
				(type default)
			)
			(fill no)
			(layer "F.CrtYd")
		)
		(fp_line
			(start 0.3048 -0.1016)
			(end -0.3048 -0.1016)
			(stroke
				(width 0.1)
				(type default)
			)
			(layer "F.Fab")
		)
		(fp_line
			(start -0.3048 -0.1016)
			(end -0.3048 0.9906)
			(stroke
				(width 0.1)
				(type default)
			)
			(layer "F.Fab")
		)
		(fp_line
			(start 0.3048 0.9906)
			(end 0.3048 -0.1016)
			(stroke
				(width 0.1)
				(type default)
			)
			(layer "F.Fab")
		)
		(fp_line
			(start -0.3048 0.9906)
			(end 0.3048 0.9906)
			(stroke
				(width 0.1)
				(type default)
			)
			(layer "F.Fab")
		)
		(pad "1" smd rect
			(at 0 0 90)
			(size 0.508 0.508)
			(layers "F.Cu" "F.Mask" "F.Paste")
			(net "VR_PVCCIN_CPU1_AIREF2")
		)
		(pad "2" smd rect
			(at 0 0.889 90)
			(size 0.508 0.508)
			(layers "F.Cu" "F.Mask" "F.Paste")
			(net "GND")
		)
		(zone
			(layer "F.Cu")
			(hatch none 0.5)
			(connect_pads
				(clearance 0)
			)
			(min_thickness 0.25)
			(keepout
				(tracks allowed)
				(vias not_allowed)
				(pads allowed)
				(copperpour not_allowed)
				(footprints allowed)
			)
			(placement
				(enabled no)
				(sheetname "")
			)
			(fill
				(thermal_gap 0.5)
				(thermal_bridge_width 0.5)
				(island_removal_mode 0)
			)
			(polygon
				(pts
					(xy 29.889958 -61.462158) (xy 29.889958 -61.970158) (xy 30.270958 -61.970158) (xy 30.270958 -61.462158)
				)
			)
		)
		(zone
			(layer "F.Cu")
			(hatch none 0.5)
			(connect_pads
				(clearance 0)
			)
			(min_thickness 0.25)
			(keepout
				(tracks not_allowed)
				(vias allowed)
				(pads allowed)
				(copperpour not_allowed)
				(footprints allowed)
			)
			(placement
				(enabled no)
				(sheetname "")
			)
			(fill
				(thermal_gap 0.5)
				(thermal_bridge_width 0.5)
				(island_removal_mode 0)
			)
			(polygon
				(pts
					(xy 30.270958 -61.462158) (xy 30.270958 -61.970158) (xy 29.889958 -61.970158) (xy 29.889958 -61.462158)
				)
			)
		)
	)
	(footprint ""
		(layer "F.Cu")
		(at 381.4445 -138.9761 90)
		(property "Reference" "C7B4"
			(at 0 0 90)
			(layer "F.SilkS")
			(hide yes)
			(effects
				(font
					(size 1.27 1.27)
				)
			)
		)
		(property "Value" ""
			(at 0 0 90)
			(layer "F.Fab")
			(effects
				(font
					(size 1.27 1.27)
				)
			)
		)
		(duplicate_pad_numbers_are_jumpers no)
		(fp_rect
			(start -0.7239 -0.2159)
			(end 0.7239 1.9939)
			(stroke
				(width 0)
				(type default)
			)
			(fill no)
			(layer "F.CrtYd")
		)
		(fp_line
			(start 0.7239 -0.2159)
			(end -0.7239 -0.2159)
			(stroke
				(width 0.1)
				(type default)
			)
			(layer "F.Fab")
		)
		(fp_line
			(start -0.7239 -0.2159)
			(end -0.7239 1.9939)
			(stroke
				(width 0.1)
				(type default)
			)
			(layer "F.Fab")
		)
		(fp_line
			(start 0.7239 1.9939)
			(end 0.7239 -0.2159)
			(stroke
				(width 0.1)
				(type default)
			)
			(layer "F.Fab")
		)
		(fp_line
			(start -0.7239 1.9939)
			(end 0.7239 1.9939)
			(stroke
				(width 0.1)
				(type default)
			)
			(layer "F.Fab")
		)
		(pad "1" smd rect
			(at 0 0 90)
			(size 1.27 1.016)
			(layers "F.Cu" "F.Mask" "F.Paste")
			(net "PVNN_PCH_STBY")
		)
		(pad "2" smd rect
			(at 0 1.778 90)
			(size 1.27 1.016)
			(layers "F.Cu" "F.Mask" "F.Paste")
			(net "GND")
		)
		(zone
			(layer "F.Cu")
			(hatch none 0.5)
			(connect_pads
				(clearance 0)
			)
			(min_thickness 0.25)
			(keepout
				(tracks not_allowed)
				(vias allowed)
				(pads allowed)
				(copperpour not_allowed)
				(footprints allowed)
			)
			(placement
				(enabled no)
				(sheetname "")
			)
			(fill
				(thermal_gap 0.5)
				(thermal_bridge_width 0.5)
				(island_removal_mode 0)
			)
			(polygon
				(pts
					(xy 381.9525 -138.3411) (xy 382.7145 -138.3411) (xy 382.7145 -139.6111) (xy 381.9525 -139.6111)
				)
			)
		)
	)
	(footprint ""
		(layer "F.Cu")
		(at 391.2616 -140.2588 90)
		(property "Reference" "C8A15"
			(at 2.92862 3.24612 0)
			(unlocked yes)
			(layer "F.SilkS")
			(effects
				(font
					(size 0.4064 0.254)
					(thickness 0.1524)
				)
			)
		)
		(property "Value" ""
			(at 0 0 90)
			(layer "F.Fab")
			(effects
				(font
					(size 1.27 1.27)
				)
			)
		)
		(duplicate_pad_numbers_are_jumpers no)
		(fp_line
			(start 2.504948 -1.616456)
			(end 2.504948 1.633728)
			(stroke
				(width 0.1524)
				(type default)
			)
			(layer "F.SilkS")
		)
		(fp_line
			(start 1.6002 -1.616456)
			(end 2.504948 -1.616456)
			(stroke
				(width 0.1524)
				(type default)
			)
			(layer "F.SilkS")
		)
		(fp_line
			(start -1.6002 -1.616456)
			(end -2.563114 -1.616456)
			(stroke
				(width 0.1524)
				(type default)
			)
			(layer "F.SilkS")
		)
		(fp_line
			(start -2.563114 -1.616456)
			(end -2.563114 1.633728)
			(stroke
				(width 0.1524)
				(type default)
			)
			(layer "F.SilkS")
		)
		(fp_line
			(start 2.504948 1.633728)
			(end 1.6002 1.633728)
			(stroke
				(width 0.1524)
				(type default)
			)
			(layer "F.SilkS")
		)
		(fp_line
			(start -2.563114 1.633728)
			(end -1.6002 1.633728)
			(stroke
				(width 0.1524)
				(type default)
			)
			(layer "F.SilkS")
		)
		(fp_line
			(start 2.286 7.366)
			(end 2.286 1.63195)
			(stroke
				(width 0.1524)
				(type default)
			)
			(layer "F.SilkS")
		)
		(fp_line
			(start 2.286 7.366)
			(end 1.600708 7.366)
			(stroke
				(width 0.1524)
				(type default)
			)
			(layer "F.SilkS")
		)
		(fp_line
			(start -2.286 7.366)
			(end -2.286 1.632712)
			(stroke
				(width 0.1524)
				(type default)
			)
			(layer "F.SilkS")
		)
		(fp_line
			(start -2.286 7.366)
			(end -1.60147 7.366)
			(stroke
				(width 0.1524)
				(type default)
			)
			(layer "F.SilkS")
		)
		(fp_rect
			(start -2.286 7.366)
			(end 2.286 -0.254)
			(stroke
				(width 0)
				(type default)
			)
			(fill no)
			(layer "F.CrtYd")
		)
		(fp_line
			(start 2.286 -0.254)
			(end 2.286 7.366)
			(stroke
				(width 0.1)
				(type default)
			)
			(layer "F.Fab")
		)
		(fp_line
			(start -2.286 -0.254)
			(end 2.286 -0.254)
			(stroke
				(width 0.1)
				(type default)
			)
			(layer "F.Fab")
		)
		(fp_line
			(start 2.286 7.366)
			(end -2.286 7.366)
			(stroke
				(width 0.1)
				(type default)
			)
			(layer "F.Fab")
		)
		(fp_line
			(start -2.286 7.366)
			(end -2.286 -0.254)
			(stroke
				(width 0.1)
				(type default)
			)
			(layer "F.Fab")
		)
		(pad "1" smd rect
			(at 0 0 90)
			(size 2.54 3.048)
			(layers "F.Cu" "F.Mask" "F.Paste")
			(net "P1V05_PCH_STBY")
		)
		(pad "2" smd rect
			(at 0 7.112 90)
			(size 2.54 3.048)
			(layers "F.Cu" "F.Mask" "F.Paste")
			(net "GND")
		)
	)
	(footprint ""
		(layer "F.Cu")
		(at 11.502644 5.004562 -90)
		(property "Reference" "R12W15"
			(at 0 0 270)
			(layer "F.SilkS")
			(hide yes)
			(effects
				(font
					(size 1.27 1.27)
				)
			)
		)
		(property "Value" "*"
			(at 0.064008 -4.108196 270)
			(unlocked yes)
			(layer "F.Fab")
			(hide yes)
			(effects
				(font
					(size 1.27 1.016)
					(thickness 0.1524)
				)
			)
		)
		(property "Device Type" "665KR2B-GP_SMD-RG2-665KR2B-GP,A"
			(at 0.064008 -5.632196 270)
			(unlocked yes)
			(layer "F.Fab")
			(hide yes)
			(effects
				(font
					(size 1.27 1.016)
					(thickness 0.1524)
				)
			)
		)
		(duplicate_pad_numbers_are_jumpers no)
		(fp_line
			(start -0.508 -0.9398)
			(end -0.508 0.9398)
			(stroke
				(width 0.1524)
				(type default)
			)
			(layer "F.SilkS")
		)
		(fp_line
			(start 0.508 -0.9398)
			(end -0.508 -0.9398)
			(stroke
				(width 0.1524)
				(type default)
			)
			(layer "F.SilkS")
		)
		(fp_rect
			(start -0.508 0.9398)
			(end 0.508 -0.9398)
			(stroke
				(width 0)
				(type default)
			)
			(fill no)
			(layer "F.CrtYd")
		)
		(fp_rect
			(start -0.508 0.9398)
			(end 0.508 -0.9398)
			(stroke
				(width 0)
				(type default)
			)
			(fill no)
			(layer "F.Fab")
		)
		(pad "1" smd custom
			(at 0 -0.4445 270)
			(size 0.1397 0.1397)
			(layers "F.Cu" "F.Mask" "F.Paste")
			(net "VR_PVDDQ_GHJ_AIINSEN")
			(options
				(clearance outline)
				(anchor circle)
			)
			(primitives
				(gr_poly
					(pts
						(arc
							(start -0.1778 -0.2794)
							(mid -0.249642 -0.249642)
							(end -0.2794 -0.1778)
						)
						(arc
							(start -0.2794 0.1778)
							(mid -0.249642 0.249642)
							(end -0.1778 0.2794)
						)
						(arc
							(start 0.1778 0.2794)
							(mid 0.249642 0.249642)
							(end 0.2794 0.1778)
						)
						(arc
							(start 0.2794 -0.1778)
							(mid 0.249642 -0.249642)
							(end 0.1778 -0.2794)
						)
					)
					(width 0)
					(fill yes)
				)
			)
		)
		(pad "2" smd custom
			(at 0 0.4445 270)
			(size 0.1397 0.1397)
			(layers "F.Cu" "F.Mask" "F.Paste")
			(net "VR_PVDDQ_GHJ_VINSEN")
			(options
				(clearance outline)
				(anchor circle)
			)
			(primitives
				(gr_poly
					(pts
						(arc
							(start -0.1778 -0.2794)
							(mid -0.249642 -0.249642)
							(end -0.2794 -0.1778)
						)
						(arc
							(start -0.2794 0.1778)
							(mid -0.249642 0.249642)
							(end -0.1778 0.2794)
						)
						(arc
							(start 0.1778 0.2794)
							(mid 0.249642 0.249642)
							(end 0.2794 0.1778)
						)
						(arc
							(start 0.2794 -0.1778)
							(mid 0.249642 -0.249642)
							(end 0.1778 -0.2794)
						)
					)
					(width 0)
					(fill yes)
				)
			)
		)
	)
	(footprint ""
		(layer "F.Cu")
		(at 1.133094 -123.20905 90)
		(property "Reference" "CF22"
			(at 0 0 90)
			(layer "F.SilkS")
			(hide yes)
			(effects
				(font
					(size 1.27 1.27)
				)
			)
		)
		(property "Value" "*"
			(at 1.1811 -2.8194 90)
			(unlocked yes)
			(layer "F.Fab")
			(hide yes)
			(effects
				(font
					(size 1.27 1.016)
					(thickness 0.1524)
				)
			)
		)
		(property "Device Type" "SC22P50V2JN-4GP_SMD-BCG-SC22P5A"
			(at 1.1811 -4.3434 90)
			(unlocked yes)
			(layer "F.Fab")
			(hide yes)
			(effects
				(font
					(size 1.27 1.016)
					(thickness 0.1524)
				)
			)
		)
		(duplicate_pad_numbers_are_jumpers no)
		(fp_rect
			(start -0.4318 0.9525)
			(end 0.4318 -0.9525)
			(stroke
				(width 0)
				(type default)
			)
			(fill no)
			(layer "F.CrtYd")
		)
		(fp_rect
			(start -0.4318 0.9525)
			(end 0.4318 -0.9525)
			(stroke
				(width 0)
				(type default)
			)
			(fill no)
			(layer "F.Fab")
		)
		(pad "1" smd custom
			(at 0 -0.4445 90)
			(size 0.1524 0.1524)
			(layers "F.Cu" "F.Mask" "F.Paste")
			(net "VR_PVDDQ_KLM_AIREF2")
			(options
				(clearance outline)
				(anchor circle)
			)
			(primitives
				(gr_poly
					(pts
						(arc
							(start 0.3048 -0.2032)
							(mid 0.275042 -0.275042)
							(end 0.2032 -0.3048)
						)
						(arc
							(start -0.2032 -0.3048)
							(mid -0.275042 -0.275042)
							(end -0.3048 -0.2032)
						)
						(arc
							(start -0.3048 0.2032)
							(mid -0.275042 0.275042)
							(end -0.2032 0.3048)
						)
						(arc
							(start 0.2032 0.3048)
							(mid 0.275042 0.275042)
							(end 0.3048 0.2032)
						)
					)
					(width 0)
					(fill yes)
				)
			)
		)
		(pad "2" smd custom
			(at 0 0.4445 90)
			(size 0.1524 0.1524)
			(layers "F.Cu" "F.Mask" "F.Paste")
			(net "ISENSE_PVDDQ_KLM_PH2_IMON")
			(options
				(clearance outline)
				(anchor circle)
			)
			(primitives
				(gr_poly
					(pts
						(arc
							(start 0.3048 -0.2032)
							(mid 0.275042 -0.275042)
							(end 0.2032 -0.3048)
						)
						(arc
							(start -0.2032 -0.3048)
							(mid -0.275042 -0.275042)
							(end -0.3048 -0.2032)
						)
						(arc
							(start -0.3048 0.2032)
							(mid -0.275042 0.275042)
							(end -0.2032 0.3048)
						)
						(arc
							(start 0.2032 0.3048)
							(mid 0.275042 0.275042)
							(end 0.3048 0.2032)
						)
					)
					(width 0)
					(fill yes)
				)
			)
		)
	)
	(footprint ""
		(layer "F.Cu")
		(at 386.1054 -0.254)
		(property "Reference" "R7G17"
			(at 0 0 0)
			(layer "F.SilkS")
			(hide yes)
			(effects
				(font
					(size 1.27 1.27)
				)
			)
		)
		(property "Value" ""
			(at 0 0 0)
			(layer "F.Fab")
			(effects
				(font
					(size 1.27 1.27)
				)
			)
		)
		(duplicate_pad_numbers_are_jumpers no)
		(fp_poly
			(pts
				(xy -0.2794 -0.1016) (xy 0.2794 -0.1016) (xy 0.2794 0.9906) (xy -0.2794 0.9906)
			)
			(stroke
				(width 0)
				(type default)
			)
			(fill no)
			(layer "F.CrtYd")
		)
		(fp_line
			(start -0.2794 -0.1016)
			(end -0.2794 0.9906)
			(stroke
				(width 0.1)
				(type default)
			)
			(layer "F.Fab")
		)
		(fp_line
			(start -0.2794 0.9906)
			(end 0.2794 0.9906)
			(stroke
				(width 0.1)
				(type default)
			)
			(layer "F.Fab")
		)
		(fp_line
			(start 0.2794 -0.1016)
			(end -0.2794 -0.1016)
			(stroke
				(width 0.1)
				(type default)
			)
			(layer "F.Fab")
		)
		(fp_line
			(start 0.2794 0.9906)
			(end 0.2794 -0.1016)
			(stroke
				(width 0.1)
				(type default)
			)
			(layer "F.Fab")
		)
		(pad "1" smd rect
			(at 0 0)
			(size 0.508 0.508)
			(layers "F.Cu" "F.Mask" "F.Paste")
			(net "JTAG_BMC_TDO")
		)
		(pad "2" smd rect
			(at 0 0.889)
			(size 0.508 0.508)
			(layers "F.Cu" "F.Mask" "F.Paste")
			(net "JTAG_TDO")
		)
		(zone
			(layer "F.Cu")
			(hatch none 0.5)
			(connect_pads
				(clearance 0)
			)
			(min_thickness 0.25)
			(keepout
				(tracks allowed)
				(vias not_allowed)
				(pads allowed)
				(copperpour not_allowed)
				(footprints allowed)
			)
			(placement
				(enabled no)
				(sheetname "")
			)
			(fill
				(thermal_gap 0.5)
				(thermal_bridge_width 0.5)
				(island_removal_mode 0)
			)
			(polygon
				(pts
					(xy 385.8514 0) (xy 386.3594 0) (xy 386.3594 0.381) (xy 385.8514 0.381)
				)
			)
		)
		(zone
			(layer "F.Cu")
			(hatch none 0.5)
			(connect_pads
				(clearance 0)
			)
			(min_thickness 0.25)
			(keepout
				(tracks not_allowed)
				(vias allowed)
				(pads allowed)
				(copperpour not_allowed)
				(footprints allowed)
			)
			(placement
				(enabled no)
				(sheetname "")
			)
			(fill
				(thermal_gap 0.5)
				(thermal_bridge_width 0.5)
				(island_removal_mode 0)
			)
			(polygon
				(pts
					(xy 385.8514 0.381) (xy 386.3594 0.381) (xy 386.3594 0) (xy 385.8514 0)
				)
			)
		)
	)
	(footprint ""
		(layer "F.Cu")
		(at 411.130242 -47.682404 180)
		(property "Reference" "R25W61"
			(at -0.8382 -0.67818 180)
			(unlocked yes)
			(layer "F.SilkS")
			(effects
				(font
					(size 0.4064 0.254)
					(thickness 0.1524)
				)
				(justify left)
			)
		)
		(property "Value" ""
			(at 0 0 180)
			(layer "F.Fab")
			(effects
				(font
					(size 1.27 1.27)
				)
			)
		)
		(duplicate_pad_numbers_are_jumpers no)
		(fp_poly
			(pts
				(xy -0.2794 -0.1016) (xy 0.2794 -0.1016) (xy 0.2794 0.9906) (xy -0.2794 0.9906)
			)
			(stroke
				(width 0)
				(type default)
			)
			(fill no)
			(layer "F.CrtYd")
		)
		(fp_line
			(start 0.2794 0.9906)
			(end 0.2794 -0.1016)
			(stroke
				(width 0.1)
				(type default)
			)
			(layer "F.Fab")
		)
		(fp_line
			(start 0.2794 -0.1016)
			(end -0.2794 -0.1016)
			(stroke
				(width 0.1)
				(type default)
			)
			(layer "F.Fab")
		)
		(fp_line
			(start -0.2794 0.9906)
			(end 0.2794 0.9906)
			(stroke
				(width 0.1)
				(type default)
			)
			(layer "F.Fab")
		)
		(fp_line
			(start -0.2794 -0.1016)
			(end -0.2794 0.9906)
			(stroke
				(width 0.1)
				(type default)
			)
			(layer "F.Fab")
		)
		(pad "1" smd rect
			(at 0 0 180)
			(size 0.508 0.508)
			(layers "F.Cu" "F.Mask" "F.Paste")
			(net "CLK_100M_BMC_PE_R_DP")
		)
		(pad "2" smd rect
			(at 0 0.889 180)
			(size 0.508 0.508)
			(layers "F.Cu" "F.Mask" "F.Paste")
			(net "GND")
		)
		(zone
			(layer "F.Cu")
			(hatch none 0.5)
			(connect_pads
				(clearance 0)
			)
			(min_thickness 0.25)
			(keepout
				(tracks not_allowed)
				(vias allowed)
				(pads allowed)
				(copperpour not_allowed)
				(footprints allowed)
			)
			(placement
				(enabled no)
				(sheetname "")
			)
			(fill
				(thermal_gap 0.5)
				(thermal_bridge_width 0.5)
				(island_removal_mode 0)
			)
			(polygon
				(pts
					(xy 411.384242 -48.317404) (xy 410.876242 -48.317404) (xy 410.876242 -47.936404) (xy 411.384242 -47.936404)
				)
			)
		)
		(zone
			(layer "F.Cu")
			(hatch none 0.5)
			(connect_pads
				(clearance 0)
			)
			(min_thickness 0.25)
			(keepout
				(tracks allowed)
				(vias not_allowed)
				(pads allowed)
				(copperpour not_allowed)
				(footprints allowed)
			)
			(placement
				(enabled no)
				(sheetname "")
			)
			(fill
				(thermal_gap 0.5)
				(thermal_bridge_width 0.5)
				(island_removal_mode 0)
			)
			(polygon
				(pts
					(xy 411.384242 -47.936404) (xy 410.876242 -47.936404) (xy 410.876242 -48.317404) (xy 411.384242 -48.317404)
				)
			)
		)
	)
	(footprint ""
		(layer "F.Cu")
		(at 2.29997 -97.769934 -90)
		(property "Reference" "J1C1"
			(at 0 0 270)
			(layer "F.SilkS")
			(hide yes)
			(effects
				(font
					(size 1.27 1.27)
				)
			)
		)
		(property "Value" "*"
			(at -20.8026 -3.4036 270)
			(unlocked yes)
			(layer "F.Fab")
			(hide yes)
			(effects
				(font
					(size 1.27 1.016)
					(thickness 0.1524)
				)
			)
		)
		(property "Device Type" "DM-FCI-CONN76-8R-GP-U-01_CONN-A"
			(at -20.8026 -4.9276 270)
			(unlocked yes)
			(layer "F.Fab")
			(hide yes)
			(effects
				(font
					(size 1.27 1.016)
					(thickness 0.1524)
				)
			)
		)
		(duplicate_pad_numbers_are_jumpers no)
		(fp_line
			(start -9.1948 8.299958)
			(end -9.1948 -9.271)
			(stroke
				(width 0.1524)
				(type default)
			)
			(layer "F.SilkS")
		)
		(fp_line
			(start 9.1948 8.299958)
			(end -9.1948 8.299958)
			(stroke
				(width 0.1524)
				(type default)
			)
			(layer "F.SilkS")
		)
		(fp_line
			(start -9.1948 -9.271)
			(end 9.1948 -9.271)
			(stroke
				(width 0.1524)
				(type default)
			)
			(layer "F.SilkS")
		)
		(fp_line
			(start 9.1948 -9.271)
			(end 9.1948 8.299958)
			(stroke
				(width 0.1524)
				(type default)
			)
			(layer "F.SilkS")
		)
		(fp_poly
			(pts
				(xy -9.1948 8.299958) (xy -9.1948 -9.271) (xy 9.1948 -9.271) (xy 9.1948 8.299958)
			)
			(stroke
				(width 0)
				(type default)
			)
			(fill yes)
			(layer "F.SilkS")
		)
		(fp_poly
			(pts
				(arc
					(start -8.0518 6.183884)
					(mid -8.3058 6.437884)
					(end -8.5598 6.183884)
				)
				(arc
					(start -8.5598 4.913884)
					(mid -8.3058 4.659884)
					(end -8.0518 4.913884)
				)
			)
			(stroke
				(width 0)
				(type default)
			)
			(fill yes)
			(layer "F.SilkS")
		)
		(fp_poly
			(pts
				(arc
					(start -8.0518 3.383788)
					(mid -8.3058 3.637788)
					(end -8.5598 3.383788)
				)
				(arc
					(start -8.5598 2.113788)
					(mid -8.3058 1.859788)
					(end -8.0518 2.113788)
				)
			)
			(stroke
				(width 0)
				(type default)
			)
			(fill yes)
			(layer "F.SilkS")
		)
		(fp_poly
			(pts
				(arc
					(start -8.0518 0.583692)
					(mid -8.3058 0.837692)
					(end -8.5598 0.583692)
				)
				(arc
					(start -8.5598 -0.686308)
					(mid -8.3058 -0.940308)
					(end -8.0518 -0.686308)
				)
			)
			(stroke
				(width 0)
				(type default)
			)
			(fill yes)
			(layer "F.SilkS")
		)
		(fp_poly
			(pts
				(arc
					(start -8.0518 -2.216404)
					(mid -8.3058 -1.962404)
					(end -8.5598 -2.216404)
				)
				(arc
					(start -8.5598 -3.486404)
					(mid -8.3058 -3.740404)
					(end -8.0518 -3.486404)
				)
			)
			(stroke
				(width 0)
				(type default)
			)
			(fill yes)
			(layer "F.SilkS")
		)
		(fp_poly
			(pts
				(arc
					(start -8.0518 -5.0165)
					(mid -8.3058 -4.7625)
					(end -8.5598 -5.0165)
				)
				(arc
					(start -8.5598 -6.2865)
					(mid -8.3058 -6.5405)
					(end -8.0518 -6.2865)
				)
			)
			(stroke
				(width 0)
				(type default)
			)
			(fill yes)
			(layer "F.SilkS")
		)
		(fp_rect
			(start -12.4333 11.7348)
			(end 12.4333 -11.7348)
			(stroke
				(width 0)
				(type default)
			)
			(fill no)
			(layer "B.CrtYd")
		)
		(fp_rect
			(start -8.9408 20.4978)
			(end 8.9408 -9.017)
			(stroke
				(width 0)
				(type default)
			)
			(fill no)
			(layer "F.CrtYd")
		)
		(fp_poly
			(pts
				(xy -13.9446 25.5016) (xy -13.9446 -14.0208) (xy 13.9446 -14.0208) (xy 13.9446 -0.3048) (xy 9.4488 -0.3048)
				(xy 9.4488 -9.525) (xy -9.4488 -9.525) (xy -9.4488 21.0058) (xy 9.4488 21.0058) (xy 9.4488 -0.2921)
				(xy 13.9446 -0.2921) (xy 13.9446 25.5016)
			)
			(stroke
				(width 0)
				(type default)
			)
			(fill no)
			(layer "F.CrtYd")
		)
		(fp_poly
			(pts
				(xy -9.4488 21.0058) (xy -9.4488 -9.525) (xy 9.4488 -9.525) (xy 9.4488 -0.3048) (xy 8.9408 -0.3048)
				(xy 8.9408 -9.017) (xy -8.9408 -9.017) (xy -8.9408 20.4978) (xy 8.9408 20.4978) (xy 8.9408 -0.2921)
				(xy 9.4488 -0.2921) (xy 9.4488 21.0058)
			)
			(stroke
				(width 0)
				(type default)
			)
			(fill no)
			(layer "F.CrtYd")
		)
		(fp_rect
			(start -17.4371 16.7386)
			(end 17.4371 -16.7386)
			(stroke
				(width 0)
				(type default)
			)
			(fill no)
			(layer "B.Fab")
		)
		(fp_rect
			(start -12.4333 11.7348)
			(end 12.4333 -11.7348)
			(stroke
				(width 0)
				(type default)
			)
			(fill no)
			(layer "B.Fab")
		)
		(fp_rect
			(start -18.9484 30.5054)
			(end 18.9484 -19.0246)
			(stroke
				(width 0)
				(type default)
			)
			(fill no)
			(layer "F.Fab")
		)
		(fp_rect
			(start -13.9446 25.5016)
			(end 13.9446 -14.0208)
			(stroke
				(width 0)
				(type default)
			)
			(fill no)
			(layer "F.Fab")
		)
		(fp_rect
			(start -9.4488 21.0058)
			(end 9.4488 -9.525)
			(stroke
				(width 0)
				(type default)
			)
			(fill no)
			(layer "F.Fab")
		)
		(fp_text user "Slit"
			(at -1.577086 11.09345 270)
			(unlocked yes)
			(layer "F.SilkS")
			(effects
				(font
					(size 1.27 1.016)
					(thickness 0.1524)
				)
				(justify left)
			)
		)
		(fp_text user "Press Fit"
			(at -5.207 -8.0645 270)
			(unlocked yes)
			(layer "F.SilkS")
			(effects
				(font
					(size 1.27 1.016)
					(thickness 0.1524)
				)
				(justify left)
			)
		)
		(fp_text user "Can not place BGA,CSP,Wave Solder Component"
			(at -25.6286 13.9827 270)
			(unlocked yes)
			(layer "B.Fab")
			(effects
				(font
					(size 1.27 1.016)
					(thickness 0.1524)
				)
				(justify left)
			)
		)
		(fp_text user "Can not place BGA,CSP,Wave Solder Component"
			(at -24.892 27.3685 270)
			(unlocked yes)
			(layer "F.Fab")
			(effects
				(font
					(size 1.27 1.016)
					(thickness 0.1524)
				)
				(justify left)
			)
		)
		(fp_text user "High Limit 2mm"
			(at -8.4328 23.0759 270)
			(unlocked yes)
			(layer "F.Fab")
			(effects
				(font
					(size 1.27 1.016)
					(thickness 0.1524)
				)
				(justify left)
			)
		)
		(pad "A1" thru_hole circle
			(at -6.999986 6.199886 270)
			(size 0.8128 0.8128)
			(drill 0.399796)
			(layers "*.Cu" "*.Mask")
			(remove_unused_layers no)
			(net "P3E_CPU1_PE3_MP_RXN<8>")
			(clearance 0.2921)
			(thermal_gap 0.2921)
		)
		(pad "A2" thru_hole circle
			(at -4.99999 6.299962 270)
			(size 0.8636 0.8636)
			(drill 0.499872)
			(layers "*.Cu" "*.Mask")
			(remove_unused_layers no)
			(net "GND")
			(clearance 0.1778)
			(thermal_gap 0.1778)
		)
		(pad "A3" thru_hole circle
			(at -2.999994 6.199886 270)
			(size 0.8128 0.8128)
			(drill 0.399796)
			(layers "*.Cu" "*.Mask")
			(remove_unused_layers no)
			(net "P3E_CPU1_PE3_MP_RXP<14>")
			(clearance 0.2921)
			(thermal_gap 0.2921)
		)
		(pad "A4" thru_hole circle
			(at -0.999998 6.299962 270)
			(size 0.8636 0.8636)
			(drill 0.499872)
			(layers "*.Cu" "*.Mask")
			(remove_unused_layers no)
			(net "GND")
			(clearance 0.1778)
			(thermal_gap 0.1778)
		)
		(pad "A5" thru_hole circle
			(at 0.999998 6.199886 270)
			(size 0.8128 0.8128)
			(drill 0.399796)
			(layers "*.Cu" "*.Mask")
			(remove_unused_layers no)
			(net "TP_IOA5")
			(clearance 0.2921)
			(thermal_gap 0.2921)
		)
		(pad "A6" thru_hole circle
			(at 2.999994 6.299962 270)
			(size 0.8636 0.8636)
			(drill 0.499872)
			(layers "*.Cu" "*.Mask")
			(remove_unused_layers no)
			(net "GND")
			(clearance 0.1778)
			(thermal_gap 0.1778)
		)
		(pad "A7" thru_hole circle
			(at 4.99999 6.199886 270)
			(size 0.8128 0.8128)
			(drill 0.399796)
			(layers "*.Cu" "*.Mask")
			(remove_unused_layers no)
			(net "P3E_CPU1_PE3_MP_C_TXN<11>")
			(clearance 0.2921)
			(thermal_gap 0.2921)
		)
		(pad "A8" thru_hole circle
			(at 6.999986 6.299962 270)
			(size 0.8636 0.8636)
			(drill 0.499872)
			(layers "*.Cu" "*.Mask")
			(remove_unused_layers no)
			(net "GND")
			(clearance 0.1778)
			(thermal_gap 0.1778)
		)
		(pad "B1" thru_hole circle
			(at -6.999986 4.800092 270)
			(size 0.8128 0.8128)
			(drill 0.399796)
			(layers "*.Cu" "*.Mask")
			(remove_unused_layers no)
			(net "P3E_CPU1_PE3_MP_RXP<8>")
			(clearance 0.2921)
			(thermal_gap 0.2921)
		)
		(pad "B2" thru_hole circle
			(at -4.99999 4.899914 270)
			(size 0.8128 0.8128)
			(drill 0.399796)
			(layers "*.Cu" "*.Mask")
			(remove_unused_layers no)
			(net "P3E_CPU1_PE3_MP_RXN<11>")
			(clearance 0.2921)
			(thermal_gap 0.2921)
		)
		(pad "B3" thru_hole circle
			(at -2.999994 4.800092 270)
			(size 0.8128 0.8128)
			(drill 0.399796)
			(layers "*.Cu" "*.Mask")
			(remove_unused_layers no)
			(net "P3E_CPU1_PE3_MP_RXN<14>")
			(clearance 0.2921)
			(thermal_gap 0.2921)
		)
		(pad "B4" thru_hole circle
			(at -0.999998 4.899914 270)
			(size 0.8128 0.8128)
			(drill 0.399796)
			(layers "*.Cu" "*.Mask")
			(remove_unused_layers no)
			(net "TP_FM_WAKE_N")
			(clearance 0.1524)
			(thermal_gap 0.1524)
		)
		(pad "B5" thru_hole circle
			(at 0.999998 4.800092 270)
			(size 0.8128 0.8128)
			(drill 0.399796)
			(layers "*.Cu" "*.Mask")
			(remove_unused_layers no)
			(net "IRQ_BOARD_BMC_ALERT_N")
			(clearance 0.2921)
			(thermal_gap 0.2921)
		)
		(pad "B6" thru_hole circle
			(at 2.999994 4.899914 270)
			(size 0.8128 0.8128)
			(drill 0.399796)
			(layers "*.Cu" "*.Mask")
			(remove_unused_layers no)
			(net "SMB_PEHPCPU1_STBY_LVC3_SDA")
			(clearance 0.1524)
			(thermal_gap 0.1524)
		)
		(pad "B7" thru_hole circle
			(at 4.99999 4.800092 270)
			(size 0.8128 0.8128)
			(drill 0.399796)
			(layers "*.Cu" "*.Mask")
			(remove_unused_layers no)
			(net "P3E_CPU1_PE3_MP_C_TXP<11>")
			(clearance 0.2921)
			(thermal_gap 0.2921)
		)
		(pad "B8" thru_hole circle
			(at 6.999986 4.899914 270)
			(size 0.8128 0.8128)
			(drill 0.399796)
			(layers "*.Cu" "*.Mask")
			(remove_unused_layers no)
			(net "P3E_CPU1_PE3_MP_C_TXN<8>")
			(clearance 0.2921)
			(thermal_gap 0.2921)
		)
		(pad "C1" thru_hole circle
			(at -6.999986 3.400044 270)
			(size 0.8636 0.8636)
			(drill 0.499872)
			(layers "*.Cu" "*.Mask")
			(remove_unused_layers no)
			(net "GND")
			(clearance 0.1778)
			(thermal_gap 0.1778)
		)
		(pad "C2" thru_hole circle
			(at -4.99999 3.50012 270)
			(size 0.8128 0.8128)
			(drill 0.399796)
			(layers "*.Cu" "*.Mask")
			(remove_unused_layers no)
			(net "P3E_CPU1_PE3_MP_RXP<11>")
			(clearance 0.2921)
			(thermal_gap 0.2921)
		)
		(pad "C3" thru_hole circle
			(at -2.999994 3.400044 270)
			(size 0.8636 0.8636)
			(drill 0.499872)
			(layers "*.Cu" "*.Mask")
			(remove_unused_layers no)
			(net "GND")
			(clearance 0.1778)
			(thermal_gap 0.1778)
		)
		(pad "C4" thru_hole circle
			(at -0.999998 3.50012 270)
			(size 0.8128 0.8128)
			(drill 0.399796)
			(layers "*.Cu" "*.Mask")
			(remove_unused_layers no)
			(net "FM_BB_BMC_MP_GPIO")
			(clearance 0.1524)
			(thermal_gap 0.1524)
		)
		(pad "C5" thru_hole circle
			(at 0.999998 3.400044 270)
			(size 0.8636 0.8636)
			(drill 0.499872)
			(layers "*.Cu" "*.Mask")
			(remove_unused_layers no)
			(net "GND")
			(clearance 0.1778)
			(thermal_gap 0.1778)
		)
		(pad "C6" thru_hole circle
			(at 2.999994 3.50012 270)
			(size 0.8128 0.8128)
			(drill 0.399796)
			(layers "*.Cu" "*.Mask")
			(remove_unused_layers no)
			(net "SMB_PEHPCPU1_STBY_LVC3_SCL")
			(clearance 0.1524)
			(thermal_gap 0.1524)
		)
		(pad "C7" thru_hole circle
			(at 4.99999 3.400044 270)
			(size 0.8636 0.8636)
			(drill 0.499872)
			(layers "*.Cu" "*.Mask")
			(remove_unused_layers no)
			(net "GND")
			(clearance 0.1778)
			(thermal_gap 0.1778)
		)
		(pad "C8" thru_hole circle
			(at 6.999986 3.50012 270)
			(size 0.8128 0.8128)
			(drill 0.399796)
			(layers "*.Cu" "*.Mask")
			(remove_unused_layers no)
			(net "P3E_CPU1_PE3_MP_C_TXP<8>")
			(clearance 0.2921)
			(thermal_gap 0.2921)
		)
		(pad "D1" thru_hole circle
			(at -6.999986 1.999996 270)
			(size 0.8128 0.8128)
			(drill 0.399796)
			(layers "*.Cu" "*.Mask")
			(remove_unused_layers no)
			(net "P3E_CPU1_PE3_MP_RXN<9>")
			(clearance 0.2921)
			(thermal_gap 0.2921)
		)
		(pad "D2" thru_hole circle
			(at -4.99999 2.100072 270)
			(size 0.8636 0.8636)
			(drill 0.499872)
			(layers "*.Cu" "*.Mask")
			(remove_unused_layers no)
			(net "GND")
			(clearance 0.1778)
			(thermal_gap 0.1778)
		)
		(pad "D3" thru_hole circle
			(at -2.999994 1.999996 270)
			(size 0.8128 0.8128)
			(drill 0.399796)
			(layers "*.Cu" "*.Mask")
			(remove_unused_layers no)
			(net "P3E_CPU1_PE3_MP_RXN<15>")
			(clearance 0.2921)
			(thermal_gap 0.2921)
		)
		(pad "D4" thru_hole circle
			(at -0.999998 2.100072 270)
			(size 0.8636 0.8636)
			(drill 0.499872)
			(layers "*.Cu" "*.Mask")
			(remove_unused_layers no)
			(net "GND")
			(clearance 0.1778)
			(thermal_gap 0.1778)
		)
		(pad "D5" thru_hole circle
			(at 0.999998 1.999996 270)
			(size 0.8128 0.8128)
			(drill 0.399796)
			(layers "*.Cu" "*.Mask")
			(remove_unused_layers no)
			(net "SMB_LAN_STBY_LVC3_SDA")
			(clearance 0.2921)
			(thermal_gap 0.2921)
		)
		(pad "D6" thru_hole circle
			(at 2.999994 2.100072 270)
			(size 0.8636 0.8636)
			(drill 0.499872)
			(layers "*.Cu" "*.Mask")
			(remove_unused_layers no)
			(net "GND")
			(clearance 0.1778)
			(thermal_gap 0.1778)
		)
		(pad "D7" thru_hole circle
			(at 4.99999 1.999996 270)
			(size 0.8128 0.8128)
			(drill 0.399796)
			(layers "*.Cu" "*.Mask")
			(remove_unused_layers no)
			(net "P3E_CPU1_PE3_MP_C_TXN<12>")
			(clearance 0.2921)
			(thermal_gap 0.2921)
		)
		(pad "D8" thru_hole circle
			(at 6.999986 2.100072 270)
			(size 0.8636 0.8636)
			(drill 0.499872)
			(layers "*.Cu" "*.Mask")
			(remove_unused_layers no)
			(net "GND")
			(clearance 0.1778)
			(thermal_gap 0.1778)
		)
		(pad "E1" thru_hole circle
			(at -6.999986 0.599948 270)
			(size 0.8128 0.8128)
			(drill 0.399796)
			(layers "*.Cu" "*.Mask")
			(remove_unused_layers no)
			(net "P3E_CPU1_PE3_MP_RXP<9>")
			(clearance 0.2921)
			(thermal_gap 0.2921)
		)
		(pad "E2" thru_hole circle
			(at -4.99999 0.700024 270)
			(size 0.8128 0.8128)
			(drill 0.399796)
			(layers "*.Cu" "*.Mask")
			(remove_unused_layers no)
			(net "P3E_CPU1_PE3_MP_RXN<12>")
			(clearance 0.2921)
			(thermal_gap 0.2921)
		)
		(pad "E3" thru_hole circle
			(at -2.999994 0.599948 270)
			(size 0.8128 0.8128)
			(drill 0.399796)
			(layers "*.Cu" "*.Mask")
			(remove_unused_layers no)
			(net "P3E_CPU1_PE3_MP_RXP<15>")
			(clearance 0.2921)
			(thermal_gap 0.2921)
		)
		(pad "E4" thru_hole circle
			(at -0.999998 0.700024 270)
			(size 0.8128 0.8128)
			(drill 0.399796)
			(layers "*.Cu" "*.Mask")
			(remove_unused_layers no)
			(net "TP_IOE4")
			(clearance 0.1524)
			(thermal_gap 0.1524)
		)
		(pad "E5" thru_hole circle
			(at 0.999998 0.599948 270)
			(size 0.8128 0.8128)
			(drill 0.399796)
			(layers "*.Cu" "*.Mask")
			(remove_unused_layers no)
			(net "SMB_LAN_STBY_LVC3_SCL")
			(clearance 0.2921)
			(thermal_gap 0.2921)
		)
		(pad "E6" thru_hole circle
			(at 2.999994 0.700024 270)
			(size 0.8128 0.8128)
			(drill 0.399796)
			(layers "*.Cu" "*.Mask")
			(remove_unused_layers no)
			(net "P3E_CPU1_PE3_MP_C_TXN<14>")
			(clearance 0.2921)
			(thermal_gap 0.2921)
		)
		(pad "E7" thru_hole circle
			(at 4.99999 0.599948 270)
			(size 0.8128 0.8128)
			(drill 0.399796)
			(layers "*.Cu" "*.Mask")
			(remove_unused_layers no)
			(net "P3E_CPU1_PE3_MP_C_TXP<12>")
			(clearance 0.2921)
			(thermal_gap 0.2921)
		)
		(pad "E8" thru_hole circle
			(at 6.999986 0.700024 270)
			(size 0.8128 0.8128)
			(drill 0.399796)
			(layers "*.Cu" "*.Mask")
			(remove_unused_layers no)
			(net "P3E_CPU1_PE3_MP_C_TXN<9>")
			(clearance 0.2921)
			(thermal_gap 0.2921)
		)
		(pad "F1" thru_hole circle
			(at -6.999986 -0.8001 270)
			(size 0.8636 0.8636)
			(drill 0.499872)
			(layers "*.Cu" "*.Mask")
			(remove_unused_layers no)
			(net "GND")
			(clearance 0.1778)
			(thermal_gap 0.1778)
		)
		(pad "F2" thru_hole circle
			(at -4.99999 -0.700024 270)
			(size 0.8128 0.8128)
			(drill 0.399796)
			(layers "*.Cu" "*.Mask")
			(remove_unused_layers no)
			(net "P3E_CPU1_PE3_MP_RXP<12>")
			(clearance 0.2921)
			(thermal_gap 0.2921)
		)
		(pad "F3" thru_hole circle
			(at -2.999994 -0.8001 270)
			(size 0.8636 0.8636)
			(drill 0.499872)
			(layers "*.Cu" "*.Mask")
			(remove_unused_layers no)
			(net "GND")
			(clearance 0.1778)
			(thermal_gap 0.1778)
		)
		(pad "F4" thru_hole circle
			(at -0.999998 -0.700024 270)
			(size 0.8128 0.8128)
			(drill 0.399796)
			(layers "*.Cu" "*.Mask")
			(remove_unused_layers no)
			(net "TP_IOF4")
			(clearance 0.1524)
			(thermal_gap 0.1524)
		)
		(pad "F5" thru_hole circle
			(at 0.999998 -0.8001 270)
			(size 0.8636 0.8636)
			(drill 0.499872)
			(layers "*.Cu" "*.Mask")
			(remove_unused_layers no)
			(net "GND")
			(clearance 0.1778)
			(thermal_gap 0.1778)
		)
		(pad "F6" thru_hole circle
			(at 2.999994 -0.700024 270)
			(size 0.8128 0.8128)
			(drill 0.399796)
			(layers "*.Cu" "*.Mask")
			(remove_unused_layers no)
			(net "P3E_CPU1_PE3_MP_C_TXP<14>")
			(clearance 0.2921)
			(thermal_gap 0.2921)
		)
		(pad "F7" thru_hole circle
			(at 4.99999 -0.8001 270)
			(size 0.8636 0.8636)
			(drill 0.499872)
			(layers "*.Cu" "*.Mask")
			(remove_unused_layers no)
			(net "GND")
			(clearance 0.1778)
			(thermal_gap 0.1778)
		)
		(pad "F8" thru_hole circle
			(at 6.999986 -0.700024 270)
			(size 0.8128 0.8128)
			(drill 0.399796)
			(layers "*.Cu" "*.Mask")
			(remove_unused_layers no)
			(net "P3E_CPU1_PE3_MP_C_TXP<9>")
			(clearance 0.2921)
			(thermal_gap 0.2921)
		)
		(pad "G1" thru_hole circle
			(at -6.999986 -2.199894 270)
			(size 0.8128 0.8128)
			(drill 0.399796)
			(layers "*.Cu" "*.Mask")
			(remove_unused_layers no)
			(net "P3E_CPU1_PE3_MP_RXP<10>")
			(clearance 0.2921)
			(thermal_gap 0.2921)
		)
		(pad "G2" thru_hole circle
			(at -4.99999 -2.100072 270)
			(size 0.8636 0.8636)
			(drill 0.499872)
			(layers "*.Cu" "*.Mask")
			(remove_unused_layers no)
			(net "GND")
			(clearance 0.1778)
			(thermal_gap 0.1778)
		)
		(pad "G3" thru_hole circle
			(at -2.999994 -2.199894 270)
			(size 0.8128 0.8128)
			(drill 0.399796)
			(layers "*.Cu" "*.Mask")
			(remove_unused_layers no)
			(net "TP_IOG3")
			(clearance 0.1524)
			(thermal_gap 0.1524)
		)
		(pad "G4" thru_hole circle
			(at -0.999998 -2.100072 270)
			(size 0.8636 0.8636)
			(drill 0.499872)
			(layers "*.Cu" "*.Mask")
			(remove_unused_layers no)
			(net "GND")
			(clearance 0.1778)
			(thermal_gap 0.1778)
		)
		(pad "G5" thru_hole circle
			(at 0.999998 -2.199894 270)
			(size 0.8128 0.8128)
			(drill 0.399796)
			(layers "*.Cu" "*.Mask")
			(remove_unused_layers no)
			(net "FM_XRC_PRESENT_N")
			(clearance 0.1524)
			(thermal_gap 0.1524)
		)
		(pad "G6" thru_hole circle
			(at 2.999994 -2.100072 270)
			(size 0.8636 0.8636)
			(drill 0.499872)
			(layers "*.Cu" "*.Mask")
			(remove_unused_layers no)
			(net "GND")
			(clearance 0.1778)
			(thermal_gap 0.1778)
		)
		(pad "G7" thru_hole circle
			(at 4.99999 -2.199894 270)
			(size 0.8128 0.8128)
			(drill 0.399796)
			(layers "*.Cu" "*.Mask")
			(remove_unused_layers no)
			(net "P3E_CPU1_PE3_MP_C_TXN<13>")
			(clearance 0.2921)
			(thermal_gap 0.2921)
		)
		(pad "G8" thru_hole circle
			(at 6.999986 -2.100072 270)
			(size 0.8636 0.8636)
			(drill 0.499872)
			(layers "*.Cu" "*.Mask")
			(remove_unused_layers no)
			(net "GND")
			(clearance 0.1778)
			(thermal_gap 0.1778)
		)
		(pad "H1" thru_hole circle
			(at -6.999986 -3.599942 270)
			(size 0.8128 0.8128)
			(drill 0.399796)
			(layers "*.Cu" "*.Mask")
			(remove_unused_layers no)
			(net "P3E_CPU1_PE3_MP_RXN<10>")
			(clearance 0.2921)
			(thermal_gap 0.2921)
		)
		(pad "H2" thru_hole circle
			(at -4.99999 -3.50012 270)
			(size 0.8128 0.8128)
			(drill 0.399796)
			(layers "*.Cu" "*.Mask")
			(remove_unused_layers no)
			(net "P3E_CPU1_PE3_MP_RXP<13>")
			(clearance 0.2921)
			(thermal_gap 0.2921)
		)
		(pad "H3" thru_hole circle
			(at -2.999994 -3.599942 270)
			(size 0.8128 0.8128)
			(drill 0.399796)
			(layers "*.Cu" "*.Mask")
			(remove_unused_layers no)
			(net "TP_IOH3")
			(clearance 0.1524)
			(thermal_gap 0.1524)
		)
		(pad "H4" thru_hole circle
			(at -0.999998 -3.50012 270)
			(size 0.8128 0.8128)
			(drill 0.399796)
			(layers "*.Cu" "*.Mask")
			(remove_unused_layers no)
			(net "TP_IOH4")
			(clearance 0.2921)
			(thermal_gap 0.2921)
		)
		(pad "H5" thru_hole circle
			(at 0.999998 -3.599942 270)
			(size 0.8128 0.8128)
			(drill 0.399796)
			(layers "*.Cu" "*.Mask")
			(remove_unused_layers no)
			(net "FM_XRC_READY_N")
			(clearance 0.1524)
			(thermal_gap 0.1524)
		)
		(pad "H6" thru_hole circle
			(at 2.999994 -3.50012 270)
			(size 0.8128 0.8128)
			(drill 0.399796)
			(layers "*.Cu" "*.Mask")
			(remove_unused_layers no)
			(net "P3E_CPU1_PE3_MP_C_TXN<15>")
			(clearance 0.2921)
			(thermal_gap 0.2921)
		)
		(pad "H7" thru_hole circle
			(at 4.99999 -3.599942 270)
			(size 0.8128 0.8128)
			(drill 0.399796)
			(layers "*.Cu" "*.Mask")
			(remove_unused_layers no)
			(net "P3E_CPU1_PE3_MP_C_TXP<13>")
			(clearance 0.2921)
			(thermal_gap 0.2921)
		)
		(pad "H8" thru_hole circle
			(at 6.999986 -3.50012 270)
			(size 0.8128 0.8128)
			(drill 0.399796)
			(layers "*.Cu" "*.Mask")
			(remove_unused_layers no)
			(net "P3E_CPU1_PE3_MP_C_TXP<10>")
			(clearance 0.2921)
			(thermal_gap 0.2921)
		)
		(pad "I1" thru_hole circle
			(at -6.999986 -4.99999 270)
			(size 0.8636 0.8636)
			(drill 0.499872)
			(layers "*.Cu" "*.Mask")
			(remove_unused_layers no)
			(net "GND")
			(clearance 0.1778)
			(thermal_gap 0.1778)
		)
		(pad "I2" thru_hole circle
			(at -4.99999 -4.899914 270)
			(size 0.8128 0.8128)
			(drill 0.399796)
			(layers "*.Cu" "*.Mask")
			(remove_unused_layers no)
			(net "P3E_CPU1_PE3_MP_RXN<13>")
			(clearance 0.2921)
			(thermal_gap 0.2921)
		)
		(pad "I3" thru_hole circle
			(at -2.999994 -4.99999 270)
			(size 0.8636 0.8636)
			(drill 0.499872)
			(layers "*.Cu" "*.Mask")
			(remove_unused_layers no)
			(net "GND")
			(clearance 0.1778)
			(thermal_gap 0.1778)
		)
		(pad "I4" thru_hole circle
			(at -0.999998 -4.899914 270)
			(size 0.8128 0.8128)
			(drill 0.399796)
			(layers "*.Cu" "*.Mask")
			(remove_unused_layers no)
			(net "TP_IOI4")
			(clearance 0.2921)
			(thermal_gap 0.2921)
		)
		(pad "I5" thru_hole circle
			(at 0.999998 -4.99999 270)
			(size 0.8636 0.8636)
			(drill 0.499872)
			(layers "*.Cu" "*.Mask")
			(remove_unused_layers no)
			(net "GND")
			(clearance 0.1778)
			(thermal_gap 0.1778)
		)
		(pad "I6" thru_hole circle
			(at 2.999994 -4.899914 270)
			(size 0.8128 0.8128)
			(drill 0.399796)
			(layers "*.Cu" "*.Mask")
			(remove_unused_layers no)
			(net "P3E_CPU1_PE3_MP_C_TXP<15>")
			(clearance 0.2921)
			(thermal_gap 0.2921)
		)
		(pad "I7" thru_hole circle
			(at 4.99999 -4.99999 270)
			(size 0.8636 0.8636)
			(drill 0.499872)
			(layers "*.Cu" "*.Mask")
			(remove_unused_layers no)
			(net "GND")
			(clearance 0.1778)
			(thermal_gap 0.1778)
		)
		(pad "I8" thru_hole circle
			(at 6.999986 -4.899914 270)
			(size 0.8128 0.8128)
			(drill 0.399796)
			(layers "*.Cu" "*.Mask")
			(remove_unused_layers no)
			(net "P3E_CPU1_PE3_MP_C_TXN<10>")
			(clearance 0.2921)
			(thermal_gap 0.2921)
		)
		(pad "J2" thru_hole circle
			(at -4.99999 -6.299962 270)
			(size 0.8636 0.8636)
			(drill 0.499872)
			(layers "*.Cu" "*.Mask")
			(remove_unused_layers no)
			(net "GND")
			(clearance 0.1778)
			(thermal_gap 0.1778)
		)
		(pad "J4" thru_hole circle
			(at -0.999998 -6.299962 270)
			(size 0.8636 0.8636)
			(drill 0.499872)
			(layers "*.Cu" "*.Mask")
			(remove_unused_layers no)
			(net "GND")
			(clearance 0.1778)
			(thermal_gap 0.1778)
		)
		(pad "J6" thru_hole circle
			(at 2.999994 -6.299962 270)
			(size 0.8636 0.8636)
			(drill 0.499872)
			(layers "*.Cu" "*.Mask")
			(remove_unused_layers no)
			(net "GND")
			(clearance 0.1778)
			(thermal_gap 0.1778)
		)
		(pad "J8" thru_hole circle
			(at 6.999986 -6.299962 270)
			(size 0.8636 0.8636)
			(drill 0.499872)
			(layers "*.Cu" "*.Mask")
			(remove_unused_layers no)
			(net "GND")
			(clearance 0.1778)
			(thermal_gap 0.1778)
		)
	)
	(footprint ""
		(layer "F.Cu")
		(at 378.254768 -32.3215 90)
		(property "Reference" "C8F11"
			(at -0.8382 -0.67818 90)
			(unlocked yes)
			(layer "F.SilkS")
			(effects
				(font
					(size 0.4064 0.254)
					(thickness 0.1524)
				)
				(justify left)
			)
		)
		(property "Value" ""
			(at 0 0 90)
			(layer "F.Fab")
			(effects
				(font
					(size 1.27 1.27)
				)
			)
		)
		(duplicate_pad_numbers_are_jumpers no)
		(fp_poly
			(pts
				(xy 0.3048 -0.1016) (xy 0.3048 0.9906) (xy -0.3048 0.9906) (xy -0.3048 -0.1016)
			)
			(stroke
				(width 0)
				(type default)
			)
			(fill no)
			(layer "F.CrtYd")
		)
		(fp_line
			(start 0.3048 -0.1016)
			(end -0.3048 -0.1016)
			(stroke
				(width 0.1)
				(type default)
			)
			(layer "F.Fab")
		)
		(fp_line
			(start -0.3048 -0.1016)
			(end -0.3048 0.9906)
			(stroke
				(width 0.1)
				(type default)
			)
			(layer "F.Fab")
		)
		(fp_line
			(start 0.3048 0.9906)
			(end 0.3048 -0.1016)
			(stroke
				(width 0.1)
				(type default)
			)
			(layer "F.Fab")
		)
		(fp_line
			(start -0.3048 0.9906)
			(end 0.3048 0.9906)
			(stroke
				(width 0.1)
				(type default)
			)
			(layer "F.Fab")
		)
		(pad "1" smd rect
			(at 0 0 90)
			(size 0.508 0.508)
			(layers "F.Cu" "F.Mask" "F.Paste")
			(net "SATA6G_S0_TX_DN")
		)
		(pad "2" smd rect
			(at 0 0.889 90)
			(size 0.508 0.508)
			(layers "F.Cu" "F.Mask" "F.Paste")
			(net "P3E_PCH_M2_SATA6G_TX_R_DN")
		)
		(zone
			(layer "F.Cu")
			(hatch none 0.5)
			(connect_pads
				(clearance 0)
			)
			(min_thickness 0.25)
			(keepout
				(tracks allowed)
				(vias not_allowed)
				(pads allowed)
				(copperpour not_allowed)
				(footprints allowed)
			)
			(placement
				(enabled no)
				(sheetname "")
			)
			(fill
				(thermal_gap 0.5)
				(thermal_bridge_width 0.5)
				(island_removal_mode 0)
			)
			(polygon
				(pts
					(xy 378.508768 -32.0675) (xy 378.508768 -32.5755) (xy 378.889768 -32.5755) (xy 378.889768 -32.0675)
				)
			)
		)
		(zone
			(layer "F.Cu")
			(hatch none 0.5)
			(connect_pads
				(clearance 0)
			)
			(min_thickness 0.25)
			(keepout
				(tracks not_allowed)
				(vias allowed)
				(pads allowed)
				(copperpour not_allowed)
				(footprints allowed)
			)
			(placement
				(enabled no)
				(sheetname "")
			)
			(fill
				(thermal_gap 0.5)
				(thermal_bridge_width 0.5)
				(island_removal_mode 0)
			)
			(polygon
				(pts
					(xy 378.889768 -32.0675) (xy 378.889768 -32.5755) (xy 378.508768 -32.5755) (xy 378.508768 -32.0675)
				)
			)
		)
	)
	(footprint ""
		(layer "F.Cu")
		(at 17.91335 -118.145052 180)
		(property "Reference" "C1B15"
			(at 0 0 180)
			(layer "F.SilkS")
			(hide yes)
			(effects
				(font
					(size 1.27 1.27)
				)
			)
		)
		(property "Value" ""
			(at 0 0 180)
			(layer "F.Fab")
			(effects
				(font
					(size 1.27 1.27)
				)
			)
		)
		(duplicate_pad_numbers_are_jumpers no)
		(fp_rect
			(start 0.3048 -0.1016)
			(end -0.3048 0.9906)
			(stroke
				(width 0)
				(type default)
			)
			(fill no)
			(layer "F.CrtYd")
		)
		(fp_line
			(start 0.3048 0.9906)
			(end 0.3048 -0.1016)
			(stroke
				(width 0.1)
				(type default)
			)
			(layer "F.Fab")
		)
		(fp_line
			(start 0.3048 -0.1016)
			(end -0.3048 -0.1016)
			(stroke
				(width 0.1)
				(type default)
			)
			(layer "F.Fab")
		)
		(fp_line
			(start -0.3048 0.9906)
			(end 0.3048 0.9906)
			(stroke
				(width 0.1)
				(type default)
			)
			(layer "F.Fab")
		)
		(fp_line
			(start -0.3048 -0.1016)
			(end -0.3048 0.9906)
			(stroke
				(width 0.1)
				(type default)
			)
			(layer "F.Fab")
		)
		(pad "1" smd rect
			(at 0 0 180)
			(size 0.508 0.508)
			(layers "F.Cu" "F.Mask" "F.Paste")
			(net "FAN_TACH2")
		)
		(pad "2" smd rect
			(at 0 0.889 180)
			(size 0.508 0.508)
			(layers "F.Cu" "F.Mask" "F.Paste")
			(net "GND")
		)
		(zone
			(layer "F.Cu")
			(hatch none 0.5)
			(connect_pads
				(clearance 0)
			)
			(min_thickness 0.25)
			(keepout
				(tracks allowed)
				(vias not_allowed)
				(pads allowed)
				(copperpour not_allowed)
				(footprints allowed)
			)
			(placement
				(enabled no)
				(sheetname "")
			)
			(fill
				(thermal_gap 0.5)
				(thermal_bridge_width 0.5)
				(island_removal_mode 0)
			)
			(polygon
				(pts
					(xy 17.65935 -118.399052) (xy 18.16735 -118.399052) (xy 18.16735 -118.780052) (xy 17.65935 -118.780052)
				)
			)
		)
		(zone
			(layer "F.Cu")
			(hatch none 0.5)
			(connect_pads
				(clearance 0)
			)
			(min_thickness 0.25)
			(keepout
				(tracks not_allowed)
				(vias allowed)
				(pads allowed)
				(copperpour not_allowed)
				(footprints allowed)
			)
			(placement
				(enabled no)
				(sheetname "")
			)
			(fill
				(thermal_gap 0.5)
				(thermal_bridge_width 0.5)
				(island_removal_mode 0)
			)
			(polygon
				(pts
					(xy 17.65935 -118.399052) (xy 18.16735 -118.399052) (xy 18.16735 -118.780052) (xy 17.65935 -118.780052)
				)
			)
		)
	)
	(footprint ""
		(layer "F.Cu")
		(at 417.5506 -18.7452)
		(property "Reference" "R1U11"
			(at 0 0 0)
			(layer "F.SilkS")
			(hide yes)
			(effects
				(font
					(size 1.27 1.27)
				)
			)
		)
		(property "Value" ""
			(at 0 0 0)
			(layer "F.Fab")
			(effects
				(font
					(size 1.27 1.27)
				)
			)
		)
		(duplicate_pad_numbers_are_jumpers no)
		(fp_poly
			(pts
				(xy -0.2794 -0.1016) (xy 0.2794 -0.1016) (xy 0.2794 0.9906) (xy -0.2794 0.9906)
			)
			(stroke
				(width 0)
				(type default)
			)
			(fill no)
			(layer "F.CrtYd")
		)
		(fp_line
			(start -0.2794 -0.1016)
			(end -0.2794 0.9906)
			(stroke
				(width 0.1)
				(type default)
			)
			(layer "F.Fab")
		)
		(fp_line
			(start -0.2794 0.9906)
			(end 0.2794 0.9906)
			(stroke
				(width 0.1)
				(type default)
			)
			(layer "F.Fab")
		)
		(fp_line
			(start 0.2794 -0.1016)
			(end -0.2794 -0.1016)
			(stroke
				(width 0.1)
				(type default)
			)
			(layer "F.Fab")
		)
		(fp_line
			(start 0.2794 0.9906)
			(end 0.2794 -0.1016)
			(stroke
				(width 0.1)
				(type default)
			)
			(layer "F.Fab")
		)
		(pad "1" smd rect
			(at 0 0)
			(size 0.508 0.508)
			(layers "F.Cu" "F.Mask" "F.Paste")
			(net "SMB_VR_STBY_LVC3_SCL_R")
		)
		(pad "2" smd rect
			(at 0 0.889)
			(size 0.508 0.508)
			(layers "F.Cu" "F.Mask" "F.Paste")
			(net "SMB_VR_STBY_LVC3_SCL")
		)
		(zone
			(layer "F.Cu")
			(hatch none 0.5)
			(connect_pads
				(clearance 0)
			)
			(min_thickness 0.25)
			(keepout
				(tracks allowed)
				(vias not_allowed)
				(pads allowed)
				(copperpour not_allowed)
				(footprints allowed)
			)
			(placement
				(enabled no)
				(sheetname "")
			)
			(fill
				(thermal_gap 0.5)
				(thermal_bridge_width 0.5)
				(island_removal_mode 0)
			)
			(polygon
				(pts
					(xy 417.2966 -18.4912) (xy 417.8046 -18.4912) (xy 417.8046 -18.1102) (xy 417.2966 -18.1102)
				)
			)
		)
		(zone
			(layer "F.Cu")
			(hatch none 0.5)
			(connect_pads
				(clearance 0)
			)
			(min_thickness 0.25)
			(keepout
				(tracks not_allowed)
				(vias allowed)
				(pads allowed)
				(copperpour not_allowed)
				(footprints allowed)
			)
			(placement
				(enabled no)
				(sheetname "")
			)
			(fill
				(thermal_gap 0.5)
				(thermal_bridge_width 0.5)
				(island_removal_mode 0)
			)
			(polygon
				(pts
					(xy 417.2966 -18.1102) (xy 417.8046 -18.1102) (xy 417.8046 -18.4912) (xy 417.2966 -18.4912)
				)
			)
		)
	)
	(footprint ""
		(layer "F.Cu")
		(at 389.128 -88.2015)
		(property "Reference" "R8C26"
			(at 0 0 0)
			(layer "F.SilkS")
			(hide yes)
			(effects
				(font
					(size 1.27 1.27)
				)
			)
		)
		(property "Value" ""
			(at 0 0 0)
			(layer "F.Fab")
			(effects
				(font
					(size 1.27 1.27)
				)
			)
		)
		(duplicate_pad_numbers_are_jumpers no)
		(fp_poly
			(pts
				(xy -0.2794 -0.1016) (xy 0.2794 -0.1016) (xy 0.2794 0.9906) (xy -0.2794 0.9906)
			)
			(stroke
				(width 0)
				(type default)
			)
			(fill no)
			(layer "F.CrtYd")
		)
		(fp_line
			(start -0.2794 -0.1016)
			(end -0.2794 0.9906)
			(stroke
				(width 0.1)
				(type default)
			)
			(layer "F.Fab")
		)
		(fp_line
			(start -0.2794 0.9906)
			(end 0.2794 0.9906)
			(stroke
				(width 0.1)
				(type default)
			)
			(layer "F.Fab")
		)
		(fp_line
			(start 0.2794 -0.1016)
			(end -0.2794 -0.1016)
			(stroke
				(width 0.1)
				(type default)
			)
			(layer "F.Fab")
		)
		(fp_line
			(start 0.2794 0.9906)
			(end 0.2794 -0.1016)
			(stroke
				(width 0.1)
				(type default)
			)
			(layer "F.Fab")
		)
		(pad "1" smd rect
			(at 0 0)
			(size 0.508 0.508)
			(layers "F.Cu" "F.Mask" "F.Paste")
			(net "A_1P8_3P3_RCOMP")
		)
		(pad "2" smd rect
			(at 0 0.889)
			(size 0.508 0.508)
			(layers "F.Cu" "F.Mask" "F.Paste")
			(net "GND")
		)
		(zone
			(layer "F.Cu")
			(hatch none 0.5)
			(connect_pads
				(clearance 0)
			)
			(min_thickness 0.25)
			(keepout
				(tracks allowed)
				(vias not_allowed)
				(pads allowed)
				(copperpour not_allowed)
				(footprints allowed)
			)
			(placement
				(enabled no)
				(sheetname "")
			)
			(fill
				(thermal_gap 0.5)
				(thermal_bridge_width 0.5)
				(island_removal_mode 0)
			)
			(polygon
				(pts
					(xy 388.874 -87.9475) (xy 389.382 -87.9475) (xy 389.382 -87.5665) (xy 388.874 -87.5665)
				)
			)
		)
		(zone
			(layer "F.Cu")
			(hatch none 0.5)
			(connect_pads
				(clearance 0)
			)
			(min_thickness 0.25)
			(keepout
				(tracks not_allowed)
				(vias allowed)
				(pads allowed)
				(copperpour not_allowed)
				(footprints allowed)
			)
			(placement
				(enabled no)
				(sheetname "")
			)
			(fill
				(thermal_gap 0.5)
				(thermal_bridge_width 0.5)
				(island_removal_mode 0)
			)
			(polygon
				(pts
					(xy 388.874 -87.5665) (xy 389.382 -87.5665) (xy 389.382 -87.9475) (xy 388.874 -87.9475)
				)
			)
		)
	)
	(footprint ""
		(layer "F.Cu")
		(at 337.439 -24.1554 90)
		(property "Reference" "R7F11"
			(at 0 0 90)
			(layer "F.SilkS")
			(hide yes)
			(effects
				(font
					(size 1.27 1.27)
				)
			)
		)
		(property "Value" ""
			(at 0 0 90)
			(layer "F.Fab")
			(effects
				(font
					(size 1.27 1.27)
				)
			)
		)
		(duplicate_pad_numbers_are_jumpers no)
		(fp_rect
			(start -0.2794 0.9906)
			(end 0.2794 -0.1016)
			(stroke
				(width 0)
				(type default)
			)
			(fill no)
			(layer "F.CrtYd")
		)
		(fp_line
			(start 0.2794 -0.1016)
			(end -0.2794 -0.1016)
			(stroke
				(width 0.1)
				(type default)
			)
			(layer "F.Fab")
		)
		(fp_line
			(start -0.2794 -0.1016)
			(end -0.2794 0.9906)
			(stroke
				(width 0.1)
				(type default)
			)
			(layer "F.Fab")
		)
		(fp_line
			(start 0.2794 0.9906)
			(end 0.2794 -0.1016)
			(stroke
				(width 0.1)
				(type default)
			)
			(layer "F.Fab")
		)
		(fp_line
			(start -0.2794 0.9906)
			(end 0.2794 0.9906)
			(stroke
				(width 0.1)
				(type default)
			)
			(layer "F.Fab")
		)
		(pad "1" smd rect
			(at 0 0 90)
			(size 0.508 0.508)
			(layers "F.Cu" "F.Mask" "F.Paste")
			(net "VR_FB_PVPP_ABC")
		)
		(pad "2" smd rect
			(at 0 0.889 90)
			(size 0.508 0.508)
			(layers "F.Cu" "F.Mask" "F.Paste")
			(net "AGND_PVPP_ABC")
		)
		(zone
			(layer "F.Cu")
			(hatch none 0.5)
			(connect_pads
				(clearance 0)
			)
			(min_thickness 0.25)
			(keepout
				(tracks not_allowed)
				(vias allowed)
				(pads allowed)
				(copperpour not_allowed)
				(footprints allowed)
			)
			(placement
				(enabled no)
				(sheetname "")
			)
			(fill
				(thermal_gap 0.5)
				(thermal_bridge_width 0.5)
				(island_removal_mode 0)
			)
			(polygon
				(pts
					(xy 338.074 -23.9014) (xy 338.074 -24.4094) (xy 337.693 -24.4094) (xy 337.693 -23.9014)
				)
			)
		)
		(zone
			(layer "F.Cu")
			(hatch none 0.5)
			(connect_pads
				(clearance 0)
			)
			(min_thickness 0.25)
			(keepout
				(tracks allowed)
				(vias not_allowed)
				(pads allowed)
				(copperpour not_allowed)
				(footprints allowed)
			)
			(placement
				(enabled no)
				(sheetname "")
			)
			(fill
				(thermal_gap 0.5)
				(thermal_bridge_width 0.5)
				(island_removal_mode 0)
			)
			(polygon
				(pts
					(xy 338.074 -23.9014) (xy 338.074 -24.4094) (xy 337.693 -24.4094) (xy 337.693 -23.9014)
				)
			)
		)
	)
	(footprint ""
		(layer "F.Cu")
		(at 18.288 -87.7062)
		(property "Reference" "R1D2"
			(at 0 0 0)
			(layer "F.SilkS")
			(hide yes)
			(effects
				(font
					(size 1.27 1.27)
				)
			)
		)
		(property "Value" ""
			(at 0 0 0)
			(layer "F.Fab")
			(effects
				(font
					(size 1.27 1.27)
				)
			)
		)
		(duplicate_pad_numbers_are_jumpers no)
		(fp_rect
			(start -0.2794 0.9906)
			(end 0.2794 -0.1016)
			(stroke
				(width 0)
				(type default)
			)
			(fill no)
			(layer "F.CrtYd")
		)
		(fp_line
			(start -0.2794 -0.1016)
			(end -0.2794 0.9906)
			(stroke
				(width 0.1)
				(type default)
			)
			(layer "F.Fab")
		)
		(fp_line
			(start -0.2794 0.9906)
			(end 0.2794 0.9906)
			(stroke
				(width 0.1)
				(type default)
			)
			(layer "F.Fab")
		)
		(fp_line
			(start 0.2794 -0.1016)
			(end -0.2794 -0.1016)
			(stroke
				(width 0.1)
				(type default)
			)
			(layer "F.Fab")
		)
		(fp_line
			(start 0.2794 0.9906)
			(end 0.2794 -0.1016)
			(stroke
				(width 0.1)
				(type default)
			)
			(layer "F.Fab")
		)
		(pad "1" smd rect
			(at 0 0)
			(size 0.508 0.508)
			(layers "F.Cu" "F.Mask" "F.Paste")
			(net "SVID_VDIO_PVCCIN_CPU1")
		)
		(pad "2" smd rect
			(at 0 0.889)
			(size 0.508 0.508)
			(layers "F.Cu" "F.Mask" "F.Paste")
			(net "SVID_DIO0_CPU1_R")
		)
		(zone
			(layer "F.Cu")
			(hatch none 0.5)
			(connect_pads
				(clearance 0)
			)
			(min_thickness 0.25)
			(keepout
				(tracks not_allowed)
				(vias allowed)
				(pads allowed)
				(copperpour not_allowed)
				(footprints allowed)
			)
			(placement
				(enabled no)
				(sheetname "")
			)
			(fill
				(thermal_gap 0.5)
				(thermal_bridge_width 0.5)
				(island_removal_mode 0)
			)
			(polygon
				(pts
					(xy 18.034 -87.0712) (xy 18.542 -87.0712) (xy 18.542 -87.4522) (xy 18.034 -87.4522)
				)
			)
		)
		(zone
			(layer "F.Cu")
			(hatch none 0.5)
			(connect_pads
				(clearance 0)
			)
			(min_thickness 0.25)
			(keepout
				(tracks allowed)
				(vias not_allowed)
				(pads allowed)
				(copperpour not_allowed)
				(footprints allowed)
			)
			(placement
				(enabled no)
				(sheetname "")
			)
			(fill
				(thermal_gap 0.5)
				(thermal_bridge_width 0.5)
				(island_removal_mode 0)
			)
			(polygon
				(pts
					(xy 18.034 -87.0712) (xy 18.542 -87.0712) (xy 18.542 -87.4522) (xy 18.034 -87.4522)
				)
			)
		)
	)
	(footprint ""
		(layer "F.Cu")
		(at 348.2086 -149.112224 -90)
		(property "Reference" "C7A25"
			(at 0 0 270)
			(layer "F.SilkS")
			(hide yes)
			(effects
				(font
					(size 1.27 1.27)
				)
			)
		)
		(property "Value" ""
			(at 0 0 270)
			(layer "F.Fab")
			(effects
				(font
					(size 1.27 1.27)
				)
			)
		)
		(duplicate_pad_numbers_are_jumpers no)
		(fp_poly
			(pts
				(xy 0.3048 -0.1016) (xy 0.3048 0.9906) (xy -0.3048 0.9906) (xy -0.3048 -0.1016)
			)
			(stroke
				(width 0)
				(type default)
			)
			(fill no)
			(layer "F.CrtYd")
		)
		(fp_line
			(start -0.3048 0.9906)
			(end 0.3048 0.9906)
			(stroke
				(width 0.1)
				(type default)
			)
			(layer "F.Fab")
		)
		(fp_line
			(start 0.3048 0.9906)
			(end 0.3048 -0.1016)
			(stroke
				(width 0.1)
				(type default)
			)
			(layer "F.Fab")
		)
		(fp_line
			(start -0.3048 -0.1016)
			(end -0.3048 0.9906)
			(stroke
				(width 0.1)
				(type default)
			)
			(layer "F.Fab")
		)
		(fp_line
			(start 0.3048 -0.1016)
			(end -0.3048 -0.1016)
			(stroke
				(width 0.1)
				(type default)
			)
			(layer "F.Fab")
		)
		(pad "1" smd rect
			(at 0 0 270)
			(size 0.508 0.508)
			(layers "F.Cu" "F.Mask" "F.Paste")
			(net "P5V_STBY")
		)
		(pad "2" smd rect
			(at 0 0.889 270)
			(size 0.508 0.508)
			(layers "F.Cu" "F.Mask" "F.Paste")
			(net "GND")
		)
		(zone
			(layer "F.Cu")
			(hatch none 0.5)
			(connect_pads
				(clearance 0)
			)
			(min_thickness 0.25)
			(keepout
				(tracks not_allowed)
				(vias allowed)
				(pads allowed)
				(copperpour not_allowed)
				(footprints allowed)
			)
			(placement
				(enabled no)
				(sheetname "")
			)
			(fill
				(thermal_gap 0.5)
				(thermal_bridge_width 0.5)
				(island_removal_mode 0)
			)
			(polygon
				(pts
					(xy 347.5736 -149.366224) (xy 347.5736 -148.858224) (xy 347.9546 -148.858224) (xy 347.9546 -149.366224)
				)
			)
		)
		(zone
			(layer "F.Cu")
			(hatch none 0.5)
			(connect_pads
				(clearance 0)
			)
			(min_thickness 0.25)
			(keepout
				(tracks allowed)
				(vias not_allowed)
				(pads allowed)
				(copperpour not_allowed)
				(footprints allowed)
			)
			(placement
				(enabled no)
				(sheetname "")
			)
			(fill
				(thermal_gap 0.5)
				(thermal_bridge_width 0.5)
				(island_removal_mode 0)
			)
			(polygon
				(pts
					(xy 347.9546 -149.366224) (xy 347.9546 -148.858224) (xy 347.5736 -148.858224) (xy 347.5736 -149.366224)
				)
			)
		)
	)
	(footprint ""
		(layer "F.Cu")
		(at 389.6106 -64.5795)
		(property "Reference" "C7E14"
			(at 0 0 0)
			(layer "F.SilkS")
			(hide yes)
			(effects
				(font
					(size 1.27 1.27)
				)
			)
		)
		(property "Value" ""
			(at 0 0 0)
			(layer "F.Fab")
			(effects
				(font
					(size 1.27 1.27)
				)
			)
		)
		(duplicate_pad_numbers_are_jumpers no)
		(fp_poly
			(pts
				(xy 0.3048 -0.1016) (xy 0.3048 0.9906) (xy -0.3048 0.9906) (xy -0.3048 -0.1016)
			)
			(stroke
				(width 0)
				(type default)
			)
			(fill no)
			(layer "F.CrtYd")
		)
		(fp_line
			(start -0.3048 -0.1016)
			(end -0.3048 0.9906)
			(stroke
				(width 0.1)
				(type default)
			)
			(layer "F.Fab")
		)
		(fp_line
			(start -0.3048 0.9906)
			(end 0.3048 0.9906)
			(stroke
				(width 0.1)
				(type default)
			)
			(layer "F.Fab")
		)
		(fp_line
			(start 0.3048 -0.1016)
			(end -0.3048 -0.1016)
			(stroke
				(width 0.1)
				(type default)
			)
			(layer "F.Fab")
		)
		(fp_line
			(start 0.3048 0.9906)
			(end 0.3048 -0.1016)
			(stroke
				(width 0.1)
				(type default)
			)
			(layer "F.Fab")
		)
		(pad "1" smd rect
			(at 0 0)
			(size 0.508 0.508)
			(layers "F.Cu" "F.Mask" "F.Paste")
			(net "VR_P5V_STBY_VIN")
		)
		(pad "2" smd rect
			(at 0 0.889)
			(size 0.508 0.508)
			(layers "F.Cu" "F.Mask" "F.Paste")
			(net "GND")
		)
		(zone
			(layer "F.Cu")
			(hatch none 0.5)
			(connect_pads
				(clearance 0)
			)
			(min_thickness 0.25)
			(keepout
				(tracks allowed)
				(vias not_allowed)
				(pads allowed)
				(copperpour not_allowed)
				(footprints allowed)
			)
			(placement
				(enabled no)
				(sheetname "")
			)
			(fill
				(thermal_gap 0.5)
				(thermal_bridge_width 0.5)
				(island_removal_mode 0)
			)
			(polygon
				(pts
					(xy 389.3566 -64.3255) (xy 389.8646 -64.3255) (xy 389.8646 -63.9445) (xy 389.3566 -63.9445)
				)
			)
		)
		(zone
			(layer "F.Cu")
			(hatch none 0.5)
			(connect_pads
				(clearance 0)
			)
			(min_thickness 0.25)
			(keepout
				(tracks not_allowed)
				(vias allowed)
				(pads allowed)
				(copperpour not_allowed)
				(footprints allowed)
			)
			(placement
				(enabled no)
				(sheetname "")
			)
			(fill
				(thermal_gap 0.5)
				(thermal_bridge_width 0.5)
				(island_removal_mode 0)
			)
			(polygon
				(pts
					(xy 389.3566 -63.9445) (xy 389.8646 -63.9445) (xy 389.8646 -64.3255) (xy 389.3566 -64.3255)
				)
			)
		)
	)
	(footprint ""
		(layer "F.Cu")
		(at 329.594972 -115.55095 90)
		(property "Reference" "J6B1"
			(at -3.59283 -5.018024 90)
			(unlocked yes)
			(layer "F.SilkS")
			(effects
				(font
					(size 0.7874 0.5842)
					(thickness 0.1524)
				)
			)
		)
		(property "Value" ""
			(at 0 0 90)
			(layer "F.Fab")
			(effects
				(font
					(size 1.27 1.27)
				)
			)
		)
		(duplicate_pad_numbers_are_jumpers no)
		(fp_line
			(start -0.381 -3.81)
			(end -5.969 -3.81)
			(stroke
				(width 0.1524)
				(type default)
			)
			(layer "F.SilkS")
		)
		(fp_line
			(start -5.969 -3.81)
			(end -5.969 -3.048)
			(stroke
				(width 0.1524)
				(type default)
			)
			(layer "F.SilkS")
		)
		(fp_line
			(start -5.969 -3.048)
			(end -7.2771 -3.048)
			(stroke
				(width 0.1524)
				(type default)
			)
			(layer "F.SilkS")
		)
		(fp_line
			(start -7.2771 -3.048)
			(end -7.2771 28.194)
			(stroke
				(width 0.1524)
				(type default)
			)
			(layer "F.SilkS")
		)
		(fp_line
			(start 0.9271 28.194)
			(end 0.9271 -1.703832)
			(stroke
				(width 0.1524)
				(type default)
			)
			(layer "F.SilkS")
		)
		(fp_line
			(start -7.2771 28.194)
			(end 0.9271 28.194)
			(stroke
				(width 0.1524)
				(type default)
			)
			(layer "F.SilkS")
		)
		(fp_poly
			(pts
				(xy 1.661668 0.048006) (xy 2.931668 0.556006) (xy 2.931668 -0.459994)
			)
			(stroke
				(width 0)
				(type default)
			)
			(fill yes)
			(layer "F.SilkS")
		)
		(fp_poly
			(pts
				(xy -7.2771 28.194) (xy -7.2771 -3.048) (xy -5.969 -3.048) (xy -5.969 -3.81) (xy -0.381 -3.81) (xy -0.381 -3.048)
				(xy 0.9271 -3.048) (xy 0.9271 28.194)
			)
			(stroke
				(width 0)
				(type default)
			)
			(fill no)
			(layer "F.CrtYd")
		)
		(fp_line
			(start -0.381 -3.81)
			(end -0.381 -3.048)
			(stroke
				(width 0.1)
				(type default)
			)
			(layer "F.Fab")
		)
		(fp_line
			(start -5.969 -3.81)
			(end -0.381 -3.81)
			(stroke
				(width 0.1)
				(type default)
			)
			(layer "F.Fab")
		)
		(fp_line
			(start 0.9271 -3.048)
			(end 0.9271 28.194)
			(stroke
				(width 0.1)
				(type default)
			)
			(layer "F.Fab")
		)
		(fp_line
			(start -0.381 -3.048)
			(end 0.9271 -3.048)
			(stroke
				(width 0.1)
				(type default)
			)
			(layer "F.Fab")
		)
		(fp_line
			(start -5.969 -3.048)
			(end -5.969 -3.81)
			(stroke
				(width 0.1)
				(type default)
			)
			(layer "F.Fab")
		)
		(fp_line
			(start -7.2771 -3.048)
			(end -5.969 -3.048)
			(stroke
				(width 0.1)
				(type default)
			)
			(layer "F.Fab")
		)
		(fp_line
			(start -7.2771 28.1686)
			(end -7.2771 -3.048)
			(stroke
				(width 0.1)
				(type default)
			)
			(layer "F.Fab")
		)
		(fp_line
			(start 0.9271 28.194)
			(end -7.2771 28.194)
			(stroke
				(width 0.1)
				(type default)
			)
			(layer "F.Fab")
		)
		(fp_line
			(start -7.2771 28.194)
			(end -7.2771 28.1686)
			(stroke
				(width 0.1)
				(type default)
			)
			(layer "F.Fab")
		)
		(fp_poly
			(pts
				(xy 1.661668 0.048006) (xy 2.931668 -0.459994) (xy 2.931668 0.556006)
			)
			(stroke
				(width 0)
				(type default)
			)
			(fill yes)
			(layer "F.Fab")
		)
		(fp_text user "F1"
			(at -6.416802 -6.532372 0)
			(unlocked yes)
			(layer "F.Fab")
			(effects
				(font
					(size 0.7874 0.5842)
					(thickness 0.1524)
				)
				(justify left)
			)
		)
		(fp_text user "A20"
			(at 1.44653 24.4602 0)
			(unlocked yes)
			(layer "F.Fab")
			(effects
				(font
					(size 0.7874 0.5842)
					(thickness 0.1524)
				)
				(justify left)
			)
		)
		(fp_text user "F20"
			(at -8.144002 26.449528 0)
			(unlocked yes)
			(layer "F.Fab")
			(effects
				(font
					(size 0.7874 0.5842)
					(thickness 0.1524)
				)
				(justify left)
			)
		)
		(pad "" np_thru_hole circle
			(at -3.175 26.5557 90)
			(size 0.254 0.254)
			(drill 1.27)
			(layers "*.Cu" "*.Mask")
			(clearance 0.8255)
			(thermal_gap 0.8255)
		)
		(pad "" np_thru_hole circle
			(at -0.127 -2.4257 90)
			(size 0.254 0.254)
			(drill 1.27)
			(layers "*.Cu" "*.Mask")
			(clearance 0.8255)
			(thermal_gap 0.8255)
		)
		(pad "A1" smd circle
			(at 0 0 90)
			(size 0.635 0.635)
			(layers "F.Cu" "F.Mask" "F.Paste")
			(net "P12V_STBY")
		)
		(pad "A2" smd circle
			(at 0 1.27 90)
			(size 0.635 0.635)
			(layers "F.Cu" "F.Mask" "F.Paste")
			(net "P12V_STBY")
		)
		(pad "A3" smd circle
			(at 0 2.54 90)
			(size 0.635 0.635)
			(layers "F.Cu" "F.Mask" "F.Paste")
			(net "P12V_STBY")
		)
		(pad "A4" smd circle
			(at 0 3.81 90)
			(size 0.635 0.635)
			(layers "F.Cu" "F.Mask" "F.Paste")
			(net "P12V_STBY")
		)
		(pad "A5" smd circle
			(at 0 5.08 90)
			(size 0.635 0.635)
			(layers "F.Cu" "F.Mask" "F.Paste")
			(net "P12V_STBY")
		)
		(pad "A6" smd circle
			(at 0 6.35 90)
			(size 0.635 0.635)
			(layers "F.Cu" "F.Mask" "F.Paste")
			(net "P12V_STBY")
		)
		(pad "A7" smd circle
			(at 0 7.62 90)
			(size 0.635 0.635)
			(layers "F.Cu" "F.Mask" "F.Paste")
			(net "P12V_STBY")
		)
		(pad "A8" smd circle
			(at 0 8.89 90)
			(size 0.635 0.635)
			(layers "F.Cu" "F.Mask" "F.Paste")
			(net "P12V_STBY")
		)
		(pad "A9" smd circle
			(at 0 10.16 90)
			(size 0.635 0.635)
			(layers "F.Cu" "F.Mask" "F.Paste")
			(net "GND")
		)
		(pad "A10" smd circle
			(at 0 11.43 90)
			(size 0.635 0.635)
			(layers "F.Cu" "F.Mask" "F.Paste")
			(net "GND")
		)
		(pad "A11" smd circle
			(at 0 12.7 90)
			(size 0.635 0.635)
			(layers "F.Cu" "F.Mask" "F.Paste")
			(net "P3V3_STBY")
		)
		(pad "A12" smd circle
			(at 0 13.97 90)
			(size 0.635 0.635)
			(layers "F.Cu" "F.Mask" "F.Paste")
			(net "GND")
		)
		(pad "A13" smd circle
			(at 0 15.24 90)
			(size 0.635 0.635)
			(layers "F.Cu" "F.Mask" "F.Paste")
			(net "P5V_STBY")
		)
		(pad "A14" smd circle
			(at 0 16.51 90)
			(size 0.635 0.635)
			(layers "F.Cu" "F.Mask" "F.Paste")
			(net "GND")
		)
		(pad "A15" smd circle
			(at 0 17.78 90)
			(size 0.635 0.635)
			(layers "F.Cu" "F.Mask" "F.Paste")
			(net "FM_P1V8MCP_CPU0_EN")
		)
		(pad "A16" smd circle
			(at 0 19.05 90)
			(size 0.635 0.635)
			(layers "F.Cu" "F.Mask" "F.Paste")
			(net "FM_PVCCIOMCP_CPU0_EN")
		)
		(pad "A17" smd circle
			(at 0 20.32 90)
			(size 0.635 0.635)
			(layers "F.Cu" "F.Mask" "F.Paste")
			(net "GND")
		)
		(pad "A18" smd circle
			(at 0 21.59 90)
			(size 0.635 0.635)
			(layers "F.Cu" "F.Mask" "F.Paste")
			(net "SMB_VR_STBY_LVC3_SCL")
		)
		(pad "A19" smd circle
			(at 0 22.86 90)
			(size 0.635 0.635)
			(layers "F.Cu" "F.Mask" "F.Paste")
			(net "SVID_ALERT0_CPU0_R_N")
		)
		(pad "A20" smd circle
			(at 0 24.13 90)
			(size 0.635 0.635)
			(layers "F.Cu" "F.Mask" "F.Paste")
			(net "SVID_CLK0_CPU0_R")
		)
		(pad "B1" smd circle
			(at -1.27 0 90)
			(size 0.635 0.635)
			(layers "F.Cu" "F.Mask" "F.Paste")
			(net "P12V_STBY")
		)
		(pad "B2" smd circle
			(at -1.27 1.27 90)
			(size 0.635 0.635)
			(layers "F.Cu" "F.Mask" "F.Paste")
			(net "P12V_STBY")
		)
		(pad "B3" smd circle
			(at -1.27 2.54 90)
			(size 0.635 0.635)
			(layers "F.Cu" "F.Mask" "F.Paste")
			(net "P12V_STBY")
		)
		(pad "B4" smd circle
			(at -1.27 3.81 90)
			(size 0.635 0.635)
			(layers "F.Cu" "F.Mask" "F.Paste")
			(net "P12V_STBY")
		)
		(pad "B5" smd circle
			(at -1.27 5.08 90)
			(size 0.635 0.635)
			(layers "F.Cu" "F.Mask" "F.Paste")
			(net "P12V_STBY")
		)
		(pad "B6" smd circle
			(at -1.27 6.35 90)
			(size 0.635 0.635)
			(layers "F.Cu" "F.Mask" "F.Paste")
			(net "P12V_STBY")
		)
		(pad "B7" smd circle
			(at -1.27 7.62 90)
			(size 0.635 0.635)
			(layers "F.Cu" "F.Mask" "F.Paste")
			(net "P12V_STBY")
		)
		(pad "B8" smd circle
			(at -1.27 8.89 90)
			(size 0.635 0.635)
			(layers "F.Cu" "F.Mask" "F.Paste")
			(net "P12V_STBY")
		)
		(pad "B9" smd circle
			(at -1.27 10.16 90)
			(size 0.635 0.635)
			(layers "F.Cu" "F.Mask" "F.Paste")
			(net "GND")
		)
		(pad "B10" smd circle
			(at -1.27 11.43 90)
			(size 0.635 0.635)
			(layers "F.Cu" "F.Mask" "F.Paste")
			(net "GND")
		)
		(pad "B11" smd circle
			(at -1.27 12.7 90)
			(size 0.635 0.635)
			(layers "F.Cu" "F.Mask" "F.Paste")
			(net "P3V3_STBY")
		)
		(pad "B12" smd circle
			(at -1.27 13.97 90)
			(size 0.635 0.635)
			(layers "F.Cu" "F.Mask" "F.Paste")
			(net "GND")
		)
		(pad "B13" smd circle
			(at -1.27 15.24 90)
			(size 0.635 0.635)
			(layers "F.Cu" "F.Mask" "F.Paste")
			(net "P5V_STBY")
		)
		(pad "B14" smd circle
			(at -1.27 16.51 90)
			(size 0.635 0.635)
			(layers "F.Cu" "F.Mask" "F.Paste")
			(net "GND")
		)
		(pad "B15" smd circle
			(at -1.27 17.78 90)
			(size 0.635 0.635)
			(layers "F.Cu" "F.Mask" "F.Paste")
			(net "PWRGD_P1V8MCP_CPU0")
		)
		(pad "B16" smd circle
			(at -1.27 19.05 90)
			(size 0.635 0.635)
			(layers "F.Cu" "F.Mask" "F.Paste")
			(net "PWRGD_PVCCIOMCP_CPU0")
		)
		(pad "B17" smd circle
			(at -1.27 20.32 90)
			(size 0.635 0.635)
			(layers "F.Cu" "F.Mask" "F.Paste")
			(net "GND")
		)
		(pad "B18" smd circle
			(at -1.27 21.59 90)
			(size 0.635 0.635)
			(layers "F.Cu" "F.Mask" "F.Paste")
			(net "SMB_VR_STBY_LVC3_SDA")
		)
		(pad "B19" smd circle
			(at -1.27 22.86 90)
			(size 0.635 0.635)
			(layers "F.Cu" "F.Mask" "F.Paste")
			(net "SVID_ALERT1_CPU0_R_N")
		)
		(pad "B20" smd circle
			(at -1.27 24.13 90)
			(size 0.635 0.635)
			(layers "F.Cu" "F.Mask" "F.Paste")
			(net "SVID_DIO0_CPU0_R")
		)
		(pad "C1" smd circle
			(at -2.54 0 90)
			(size 0.635 0.635)
			(layers "F.Cu" "F.Mask" "F.Paste")
			(net "GND")
		)
		(pad "C2" smd circle
			(at -2.54 1.27 90)
			(size 0.635 0.635)
			(layers "F.Cu" "F.Mask" "F.Paste")
			(net "GND")
		)
		(pad "C3" smd circle
			(at -2.54 2.54 90)
			(size 0.635 0.635)
			(layers "F.Cu" "F.Mask" "F.Paste")
			(net "GND")
		)
		(pad "C4" smd circle
			(at -2.54 3.81 90)
			(size 0.635 0.635)
			(layers "F.Cu" "F.Mask" "F.Paste")
			(net "GND")
		)
		(pad "C5" smd circle
			(at -2.54 5.08 90)
			(size 0.635 0.635)
			(layers "F.Cu" "F.Mask" "F.Paste")
			(net "GND")
		)
		(pad "C6" smd circle
			(at -2.54 6.35 90)
			(size 0.635 0.635)
			(layers "F.Cu" "F.Mask" "F.Paste")
			(net "GND")
		)
		(pad "C7" smd circle
			(at -2.54 7.62 90)
			(size 0.635 0.635)
			(layers "F.Cu" "F.Mask" "F.Paste")
			(net "GND")
		)
		(pad "C8" smd circle
			(at -2.54 8.89 90)
			(size 0.635 0.635)
			(layers "F.Cu" "F.Mask" "F.Paste")
			(net "GND")
		)
		(pad "C9" smd circle
			(at -2.54 10.16 90)
			(size 0.635 0.635)
			(layers "F.Cu" "F.Mask" "F.Paste")
			(net "GND")
		)
		(pad "C10" smd circle
			(at -2.54 11.43 90)
			(size 0.635 0.635)
			(layers "F.Cu" "F.Mask" "F.Paste")
			(net "GND")
		)
		(pad "C11" smd circle
			(at -2.54 12.7 90)
			(size 0.635 0.635)
			(layers "F.Cu" "F.Mask" "F.Paste")
			(net "P3V3_STBY")
		)
		(pad "C12" smd circle
			(at -2.54 13.97 90)
			(size 0.635 0.635)
			(layers "F.Cu" "F.Mask" "F.Paste")
			(net "GND")
		)
		(pad "C13" smd circle
			(at -2.54 15.24 90)
			(size 0.635 0.635)
			(layers "F.Cu" "F.Mask" "F.Paste")
			(net "P5V_STBY")
		)
		(pad "C14" smd circle
			(at -2.54 16.51 90)
			(size 0.635 0.635)
			(layers "F.Cu" "F.Mask" "F.Paste")
			(net "GND")
		)
		(pad "C15" smd circle
			(at -2.54 17.78 90)
			(size 0.635 0.635)
			(layers "F.Cu" "F.Mask" "F.Paste")
			(net "GND")
		)
		(pad "C16" smd circle
			(at -2.54 19.05 90)
			(size 0.635 0.635)
			(layers "F.Cu" "F.Mask" "F.Paste")
			(net "GND")
		)
		(pad "C17" smd circle
			(at -2.54 20.32 90)
			(size 0.635 0.635)
			(layers "F.Cu" "F.Mask" "F.Paste")
			(net "PVCCIOMCP_CPU0")
		)
		(pad "C18" smd circle
			(at -2.54 21.59 90)
			(size 0.635 0.635)
			(layers "F.Cu" "F.Mask" "F.Paste")
			(net "PVCCIOMCP_CPU0")
		)
		(pad "C19" smd circle
			(at -2.54 22.86 90)
			(size 0.635 0.635)
			(layers "F.Cu" "F.Mask" "F.Paste")
			(net "PVCCIOMCP_CPU0")
		)
		(pad "C20" smd circle
			(at -2.54 24.13 90)
			(size 0.635 0.635)
			(layers "F.Cu" "F.Mask" "F.Paste")
			(net "FM_PVCCMCP_CPU0_EN")
		)
		(pad "D1" smd circle
			(at -3.81 0 90)
			(size 0.635 0.635)
			(layers "F.Cu" "F.Mask" "F.Paste")
			(net "P3V3")
		)
		(pad "D2" smd circle
			(at -3.81 1.27 90)
			(size 0.635 0.635)
			(layers "F.Cu" "F.Mask" "F.Paste")
			(net "GND")
		)
		(pad "D3" smd circle
			(at -3.81 2.54 90)
			(size 0.635 0.635)
			(layers "F.Cu" "F.Mask" "F.Paste")
			(net "GND")
		)
		(pad "D4" smd circle
			(at -3.81 3.81 90)
			(size 0.635 0.635)
			(layers "F.Cu" "F.Mask" "F.Paste")
			(net "GND")
		)
		(pad "D5" smd circle
			(at -3.81 5.08 90)
			(size 0.635 0.635)
			(layers "F.Cu" "F.Mask" "F.Paste")
			(net "GND")
		)
		(pad "D6" smd circle
			(at -3.81 6.35 90)
			(size 0.635 0.635)
			(layers "F.Cu" "F.Mask" "F.Paste")
			(net "GND")
		)
		(pad "D7" smd circle
			(at -3.81 7.62 90)
			(size 0.635 0.635)
			(layers "F.Cu" "F.Mask" "F.Paste")
			(net "GND")
		)
		(pad "D8" smd circle
			(at -3.81 8.89 90)
			(size 0.635 0.635)
			(layers "F.Cu" "F.Mask" "F.Paste")
			(net "GND")
		)
		(pad "D9" smd circle
			(at -3.81 10.16 90)
			(size 0.635 0.635)
			(layers "F.Cu" "F.Mask" "F.Paste")
			(net "GND")
		)
		(pad "D10" smd circle
			(at -3.81 11.43 90)
			(size 0.635 0.635)
			(layers "F.Cu" "F.Mask" "F.Paste")
			(net "GND")
		)
		(pad "D11" smd circle
			(at -3.81 12.7 90)
			(size 0.635 0.635)
			(layers "F.Cu" "F.Mask" "F.Paste")
			(net "GND")
		)
		(pad "D12" smd circle
			(at -3.81 13.97 90)
			(size 0.635 0.635)
			(layers "F.Cu" "F.Mask" "F.Paste")
			(net "GND")
		)
		(pad "D13" smd circle
			(at -3.81 15.24 90)
			(size 0.635 0.635)
			(layers "F.Cu" "F.Mask" "F.Paste")
			(net "GND")
		)
		(pad "D14" smd circle
			(at -3.81 16.51 90)
			(size 0.635 0.635)
			(layers "F.Cu" "F.Mask" "F.Paste")
			(net "GND")
		)
		(pad "D15" smd circle
			(at -3.81 17.78 90)
			(size 0.635 0.635)
			(layers "F.Cu" "F.Mask" "F.Paste")
			(net "GND")
		)
		(pad "D16" smd circle
			(at -3.81 19.05 90)
			(size 0.635 0.635)
			(layers "F.Cu" "F.Mask" "F.Paste")
			(net "GND")
		)
		(pad "D17" smd circle
			(at -3.81 20.32 90)
			(size 0.635 0.635)
			(layers "F.Cu" "F.Mask" "F.Paste")
			(net "PVCCIOMCP_CPU0")
		)
		(pad "D18" smd circle
			(at -3.81 21.59 90)
			(size 0.635 0.635)
			(layers "F.Cu" "F.Mask" "F.Paste")
			(net "PVCCIOMCP_CPU0")
		)
		(pad "D19" smd circle
			(at -3.81 22.86 90)
			(size 0.635 0.635)
			(layers "F.Cu" "F.Mask" "F.Paste")
			(net "PVCCIOMCP_CPU0")
		)
		(pad "D20" smd circle
			(at -3.81 24.13 90)
			(size 0.635 0.635)
			(layers "F.Cu" "F.Mask" "F.Paste")
			(net "PWRGD_PVCCMCP_CPU0")
		)
		(pad "E1" smd circle
			(at -5.08 0 90)
			(size 0.635 0.635)
			(layers "F.Cu" "F.Mask" "F.Paste")
			(net "FM_CPU0_VRM_322M_156M_OSC_EN")
		)
		(pad "E2" smd circle
			(at -5.08 1.27 90)
			(size 0.635 0.635)
			(layers "F.Cu" "F.Mask" "F.Paste")
			(net "GND")
		)
		(pad "E3" smd circle
			(at -5.08 2.54 90)
			(size 0.635 0.635)
			(layers "F.Cu" "F.Mask" "F.Paste")
			(net "GND")
		)
		(pad "E4" smd circle
			(at -5.08 3.81 90)
			(size 0.635 0.635)
			(layers "F.Cu" "F.Mask" "F.Paste")
			(net "GND")
		)
		(pad "E5" smd circle
			(at -5.08 5.08 90)
			(size 0.635 0.635)
			(layers "F.Cu" "F.Mask" "F.Paste")
			(net "GND")
		)
		(pad "E6" smd circle
			(at -5.08 6.35 90)
			(size 0.635 0.635)
			(layers "F.Cu" "F.Mask" "F.Paste")
			(net "GND")
		)
		(pad "E7" smd circle
			(at -5.08 7.62 90)
			(size 0.635 0.635)
			(layers "F.Cu" "F.Mask" "F.Paste")
			(net "GND")
		)
		(pad "E8" smd circle
			(at -5.08 8.89 90)
			(size 0.635 0.635)
			(layers "F.Cu" "F.Mask" "F.Paste")
			(net "VSENSE_PVCCIOMCP_CPU0_SKT_VSEN")
		)
		(pad "E9" smd circle
			(at -5.08 10.16 90)
			(size 0.635 0.635)
			(layers "F.Cu" "F.Mask" "F.Paste")
			(net "GND")
		)
		(pad "E10" smd circle
			(at -5.08 11.43 90)
			(size 0.635 0.635)
			(layers "F.Cu" "F.Mask" "F.Paste")
			(net "VR_PVCCIOMCP_CPU0_XADDR1")
		)
		(pad "E11" smd circle
			(at -5.08 12.7 90)
			(size 0.635 0.635)
			(layers "F.Cu" "F.Mask" "F.Paste")
			(net "GND")
		)
		(pad "E12" smd circle
			(at -5.08 13.97 90)
			(size 0.635 0.635)
			(layers "F.Cu" "F.Mask" "F.Paste")
			(net "GND")
		)
		(pad "E13" smd circle
			(at -5.08 15.24 90)
			(size 0.635 0.635)
			(layers "F.Cu" "F.Mask" "F.Paste")
			(net "GND")
		)
		(pad "E14" smd circle
			(at -5.08 16.51 90)
			(size 0.635 0.635)
			(layers "F.Cu" "F.Mask" "F.Paste")
			(net "GND")
		)
		(pad "E15" smd circle
			(at -5.08 17.78 90)
			(size 0.635 0.635)
			(layers "F.Cu" "F.Mask" "F.Paste")
			(net "PVCCIOMCP_CPU0")
		)
		(pad "E16" smd circle
			(at -5.08 19.05 90)
			(size 0.635 0.635)
			(layers "F.Cu" "F.Mask" "F.Paste")
			(net "PVCCIOMCP_CPU0")
		)
		(pad "E17" smd circle
			(at -5.08 20.32 90)
			(size 0.635 0.635)
			(layers "F.Cu" "F.Mask" "F.Paste")
			(net "PVCCIOMCP_CPU0")
		)
		(pad "E18" smd circle
			(at -5.08 21.59 90)
			(size 0.635 0.635)
			(layers "F.Cu" "F.Mask" "F.Paste")
			(net "PVCCIOMCP_CPU0")
		)
		(pad "E19" smd circle
			(at -5.08 22.86 90)
			(size 0.635 0.635)
			(layers "F.Cu" "F.Mask" "F.Paste")
			(net "PVCCIOMCP_CPU0")
		)
		(pad "E20" smd circle
			(at -5.08 24.13 90)
			(size 0.635 0.635)
			(layers "F.Cu" "F.Mask" "F.Paste")
			(net "SVID_CLK1_CPU0_R")
		)
		(pad "F1" smd circle
			(at -6.35 0 90)
			(size 0.635 0.635)
			(layers "F.Cu" "F.Mask" "F.Paste")
			(net "PVCCIO_CPU0")
		)
		(pad "F2" smd circle
			(at -6.35 1.27 90)
			(size 0.635 0.635)
			(layers "F.Cu" "F.Mask" "F.Paste")
			(net "GND")
		)
		(pad "F3" smd circle
			(at -6.35 2.54 90)
			(size 0.635 0.635)
			(layers "F.Cu" "F.Mask" "F.Paste")
			(net "GND")
		)
		(pad "F4" smd circle
			(at -6.35 3.81 90)
			(size 0.635 0.635)
			(layers "F.Cu" "F.Mask" "F.Paste")
			(net "GND")
		)
		(pad "F5" smd circle
			(at -6.35 5.08 90)
			(size 0.635 0.635)
			(layers "F.Cu" "F.Mask" "F.Paste")
			(net "GND")
		)
		(pad "F6" smd circle
			(at -6.35 6.35 90)
			(size 0.635 0.635)
			(layers "F.Cu" "F.Mask" "F.Paste")
			(net "GND")
		)
		(pad "F7" smd circle
			(at -6.35 7.62 90)
			(size 0.635 0.635)
			(layers "F.Cu" "F.Mask" "F.Paste")
			(net "GND")
		)
		(pad "F8" smd circle
			(at -6.35 8.89 90)
			(size 0.635 0.635)
			(layers "F.Cu" "F.Mask" "F.Paste")
			(net "VSENSE_PVCCIOMCP_CPU0_SKT_VRTN")
		)
		(pad "F9" smd circle
			(at -6.35 10.16 90)
			(size 0.635 0.635)
			(layers "F.Cu" "F.Mask" "F.Paste")
			(net "GND")
		)
		(pad "F10" smd circle
			(at -6.35 11.43 90)
			(size 0.635 0.635)
			(layers "F.Cu" "F.Mask" "F.Paste")
			(net "VR_PVCCMCP_CPU0_XADDR2")
		)
		(pad "F11" smd circle
			(at -6.35 12.7 90)
			(size 0.635 0.635)
			(layers "F.Cu" "F.Mask" "F.Paste")
			(net "GND")
		)
		(pad "F12" smd circle
			(at -6.35 13.97 90)
			(size 0.635 0.635)
			(layers "F.Cu" "F.Mask" "F.Paste")
			(net "GND")
		)
		(pad "F13" smd circle
			(at -6.35 15.24 90)
			(size 0.635 0.635)
			(layers "F.Cu" "F.Mask" "F.Paste")
			(net "GND")
		)
		(pad "F14" smd circle
			(at -6.35 16.51 90)
			(size 0.635 0.635)
			(layers "F.Cu" "F.Mask" "F.Paste")
			(net "GND")
		)
		(pad "F15" smd circle
			(at -6.35 17.78 90)
			(size 0.635 0.635)
			(layers "F.Cu" "F.Mask" "F.Paste")
			(net "PVCCIOMCP_CPU0")
		)
		(pad "F16" smd circle
			(at -6.35 19.05 90)
			(size 0.635 0.635)
			(layers "F.Cu" "F.Mask" "F.Paste")
			(net "PVCCIOMCP_CPU0")
		)
		(pad "F17" smd circle
			(at -6.35 20.32 90)
			(size 0.635 0.635)
			(layers "F.Cu" "F.Mask" "F.Paste")
			(net "PVCCIOMCP_CPU0")
		)
		(pad "F18" smd circle
			(at -6.35 21.59 90)
			(size 0.635 0.635)
			(layers "F.Cu" "F.Mask" "F.Paste")
			(net "PVCCIOMCP_CPU0")
		)
		(pad "F19" smd circle
			(at -6.35 22.86 90)
			(size 0.635 0.635)
			(layers "F.Cu" "F.Mask" "F.Paste")
			(net "PVCCIOMCP_CPU0")
		)
		(pad "F20" smd circle
			(at -6.35 24.13 90)
			(size 0.635 0.635)
			(layers "F.Cu" "F.Mask" "F.Paste")
			(net "SVID_DIO1_CPU0_R")
		)
		(zone
			(layers "F.Cu" "B.Cu" "In1.Cu" "In2.Cu" "In3.Cu" "In4.Cu" "In5.Cu" "In6.Cu"
				"In7.Cu" "In8.Cu" "In9.Cu" "In10.Cu" "In11.Cu" "In12.Cu"
			)
			(hatch none 0.5)
			(connect_pads
				(clearance 0)
			)
			(min_thickness 0.25)
			(keepout
				(tracks not_allowed)
				(vias allowed)
				(pads allowed)
				(copperpour not_allowed)
				(footprints allowed)
			)
			(placement
				(enabled no)
				(sheetname "")
			)
			(fill
				(thermal_gap 0.5)
				(thermal_bridge_width 0.5)
				(island_removal_mode 0)
			)
			(polygon
				(pts
					(arc
						(start 328.121772 -115.42395)
						(mid 326.216772 -115.42395)
						(end 328.121772 -115.42395)
					)
				)
			)
		)
		(zone
			(layers "F.Cu" "B.Cu" "In1.Cu" "In2.Cu" "In3.Cu" "In4.Cu" "In5.Cu" "In6.Cu"
				"In7.Cu" "In8.Cu" "In9.Cu" "In10.Cu" "In11.Cu" "In12.Cu"
			)
			(hatch none 0.5)
			(connect_pads
				(clearance 0)
			)
			(min_thickness 0.25)
			(keepout
				(tracks not_allowed)
				(vias allowed)
				(pads allowed)
				(copperpour not_allowed)
				(footprints allowed)
			)
			(placement
				(enabled no)
				(sheetname "")
			)
			(fill
				(thermal_gap 0.5)
				(thermal_bridge_width 0.5)
				(island_removal_mode 0)
			)
			(polygon
				(pts
					(arc
						(start 357.103172 -112.37595)
						(mid 355.198172 -112.37595)
						(end 357.103172 -112.37595)
					)
				)
			)
		)
	)
	(footprint ""
		(layer "F.Cu")
		(at 386.0165 -85.979 90)
		(property "Reference" "R7D13"
			(at 0 0 90)
			(layer "F.SilkS")
			(hide yes)
			(effects
				(font
					(size 1.27 1.27)
				)
			)
		)
		(property "Value" ""
			(at 0 0 90)
			(layer "F.Fab")
			(effects
				(font
					(size 1.27 1.27)
				)
			)
		)
		(duplicate_pad_numbers_are_jumpers no)
		(fp_poly
			(pts
				(xy -0.2794 -0.1016) (xy 0.2794 -0.1016) (xy 0.2794 0.9906) (xy -0.2794 0.9906)
			)
			(stroke
				(width 0)
				(type default)
			)
			(fill no)
			(layer "F.CrtYd")
		)
		(fp_line
			(start 0.2794 -0.1016)
			(end -0.2794 -0.1016)
			(stroke
				(width 0.1)
				(type default)
			)
			(layer "F.Fab")
		)
		(fp_line
			(start -0.2794 -0.1016)
			(end -0.2794 0.9906)
			(stroke
				(width 0.1)
				(type default)
			)
			(layer "F.Fab")
		)
		(fp_line
			(start 0.2794 0.9906)
			(end 0.2794 -0.1016)
			(stroke
				(width 0.1)
				(type default)
			)
			(layer "F.Fab")
		)
		(fp_line
			(start -0.2794 0.9906)
			(end 0.2794 0.9906)
			(stroke
				(width 0.1)
				(type default)
			)
			(layer "F.Fab")
		)
		(pad "1" smd rect
			(at 0 0 90)
			(size 0.508 0.508)
			(layers "F.Cu" "F.Mask" "F.Paste")
			(net "P3V3_STBY")
		)
		(pad "2" smd rect
			(at 0 0.889 90)
			(size 0.508 0.508)
			(layers "F.Cu" "F.Mask" "F.Paste")
			(net "RMII_BMC_PCH_SPRNGVLLE_RXER")
		)
		(zone
			(layer "F.Cu")
			(hatch none 0.5)
			(connect_pads
				(clearance 0)
			)
			(min_thickness 0.25)
			(keepout
				(tracks allowed)
				(vias not_allowed)
				(pads allowed)
				(copperpour not_allowed)
				(footprints allowed)
			)
			(placement
				(enabled no)
				(sheetname "")
			)
			(fill
				(thermal_gap 0.5)
				(thermal_bridge_width 0.5)
				(island_removal_mode 0)
			)
			(polygon
				(pts
					(xy 386.2705 -85.725) (xy 386.2705 -86.233) (xy 386.6515 -86.233) (xy 386.6515 -85.725)
				)
			)
		)
		(zone
			(layer "F.Cu")
			(hatch none 0.5)
			(connect_pads
				(clearance 0)
			)
			(min_thickness 0.25)
			(keepout
				(tracks not_allowed)
				(vias allowed)
				(pads allowed)
				(copperpour not_allowed)
				(footprints allowed)
			)
			(placement
				(enabled no)
				(sheetname "")
			)
			(fill
				(thermal_gap 0.5)
				(thermal_bridge_width 0.5)
				(island_removal_mode 0)
			)
			(polygon
				(pts
					(xy 386.6515 -85.725) (xy 386.6515 -86.233) (xy 386.2705 -86.233) (xy 386.2705 -85.725)
				)
			)
		)
	)
	(footprint ""
		(layer "F.Cu")
		(at 415.7345 -114.935 -90)
		(property "Reference" "R2M1"
			(at 0 0 270)
			(layer "F.SilkS")
			(hide yes)
			(effects
				(font
					(size 1.27 1.27)
				)
			)
		)
		(property "Value" ""
			(at 0 0 270)
			(layer "F.Fab")
			(effects
				(font
					(size 1.27 1.27)
				)
			)
		)
		(duplicate_pad_numbers_are_jumpers no)
		(fp_poly
			(pts
				(xy -0.2794 -0.1016) (xy 0.2794 -0.1016) (xy 0.2794 0.9906) (xy -0.2794 0.9906)
			)
			(stroke
				(width 0)
				(type default)
			)
			(fill no)
			(layer "F.CrtYd")
		)
		(fp_line
			(start -0.2794 0.9906)
			(end 0.2794 0.9906)
			(stroke
				(width 0.1)
				(type default)
			)
			(layer "F.Fab")
		)
		(fp_line
			(start 0.2794 0.9906)
			(end 0.2794 -0.1016)
			(stroke
				(width 0.1)
				(type default)
			)
			(layer "F.Fab")
		)
		(fp_line
			(start -0.2794 -0.1016)
			(end -0.2794 0.9906)
			(stroke
				(width 0.1)
				(type default)
			)
			(layer "F.Fab")
		)
		(fp_line
			(start 0.2794 -0.1016)
			(end -0.2794 -0.1016)
			(stroke
				(width 0.1)
				(type default)
			)
			(layer "F.Fab")
		)
		(pad "1" smd rect
			(at 0 0 270)
			(size 0.508 0.508)
			(layers "F.Cu" "F.Mask" "F.Paste")
			(net "FM_CPLD_ADR_TRIGGER_N")
		)
		(pad "2" smd rect
			(at 0 0.889 270)
			(size 0.508 0.508)
			(layers "F.Cu" "F.Mask" "F.Paste")
			(net "FM_CPLD_ADR_TRIGGER_R_N")
		)
		(zone
			(layer "F.Cu")
			(hatch none 0.5)
			(connect_pads
				(clearance 0)
			)
			(min_thickness 0.25)
			(keepout
				(tracks not_allowed)
				(vias allowed)
				(pads allowed)
				(copperpour not_allowed)
				(footprints allowed)
			)
			(placement
				(enabled no)
				(sheetname "")
			)
			(fill
				(thermal_gap 0.5)
				(thermal_bridge_width 0.5)
				(island_removal_mode 0)
			)
			(polygon
				(pts
					(xy 415.0995 -115.189) (xy 415.0995 -114.681) (xy 415.4805 -114.681) (xy 415.4805 -115.189)
				)
			)
		)
		(zone
			(layer "F.Cu")
			(hatch none 0.5)
			(connect_pads
				(clearance 0)
			)
			(min_thickness 0.25)
			(keepout
				(tracks allowed)
				(vias not_allowed)
				(pads allowed)
				(copperpour not_allowed)
				(footprints allowed)
			)
			(placement
				(enabled no)
				(sheetname "")
			)
			(fill
				(thermal_gap 0.5)
				(thermal_bridge_width 0.5)
				(island_removal_mode 0)
			)
			(polygon
				(pts
					(xy 415.4805 -115.189) (xy 415.4805 -114.681) (xy 415.0995 -114.681) (xy 415.0995 -115.189)
				)
			)
		)
	)
	(footprint ""
		(layer "F.Cu")
		(at 461.137 -1.524 90)
		(property "Reference" "R8B24"
			(at -0.8382 -0.67818 90)
			(unlocked yes)
			(layer "F.SilkS")
			(effects
				(font
					(size 0.4064 0.254)
					(thickness 0.1524)
				)
				(justify left)
			)
		)
		(property "Value" ""
			(at 0 0 90)
			(layer "F.Fab")
			(effects
				(font
					(size 1.27 1.27)
				)
			)
		)
		(duplicate_pad_numbers_are_jumpers no)
		(fp_poly
			(pts
				(xy -0.2794 -0.1016) (xy 0.2794 -0.1016) (xy 0.2794 0.9906) (xy -0.2794 0.9906)
			)
			(stroke
				(width 0)
				(type default)
			)
			(fill no)
			(layer "F.CrtYd")
		)
		(fp_line
			(start 0.2794 -0.1016)
			(end -0.2794 -0.1016)
			(stroke
				(width 0.1)
				(type default)
			)
			(layer "F.Fab")
		)
		(fp_line
			(start -0.2794 -0.1016)
			(end -0.2794 0.9906)
			(stroke
				(width 0.1)
				(type default)
			)
			(layer "F.Fab")
		)
		(fp_line
			(start 0.2794 0.9906)
			(end 0.2794 -0.1016)
			(stroke
				(width 0.1)
				(type default)
			)
			(layer "F.Fab")
		)
		(fp_line
			(start -0.2794 0.9906)
			(end 0.2794 0.9906)
			(stroke
				(width 0.1)
				(type default)
			)
			(layer "F.Fab")
		)
		(pad "1" smd rect
			(at 0 0 90)
			(size 0.508 0.508)
			(layers "F.Cu" "F.Mask" "F.Paste")
			(net "P3V3_STBY")
		)
		(pad "2" smd rect
			(at 0 0.889 90)
			(size 0.508 0.508)
			(layers "F.Cu" "F.Mask" "F.Paste")
			(net "SMB_HOST_STBY_LVC3_SDA_R5")
		)
		(zone
			(layer "F.Cu")
			(hatch none 0.5)
			(connect_pads
				(clearance 0)
			)
			(min_thickness 0.25)
			(keepout
				(tracks allowed)
				(vias not_allowed)
				(pads allowed)
				(copperpour not_allowed)
				(footprints allowed)
			)
			(placement
				(enabled no)
				(sheetname "")
			)
			(fill
				(thermal_gap 0.5)
				(thermal_bridge_width 0.5)
				(island_removal_mode 0)
			)
			(polygon
				(pts
					(xy 461.391 -1.27) (xy 461.391 -1.778) (xy 461.772 -1.778) (xy 461.772 -1.27)
				)
			)
		)
		(zone
			(layer "F.Cu")
			(hatch none 0.5)
			(connect_pads
				(clearance 0)
			)
			(min_thickness 0.25)
			(keepout
				(tracks not_allowed)
				(vias allowed)
				(pads allowed)
				(copperpour not_allowed)
				(footprints allowed)
			)
			(placement
				(enabled no)
				(sheetname "")
			)
			(fill
				(thermal_gap 0.5)
				(thermal_bridge_width 0.5)
				(island_removal_mode 0)
			)
			(polygon
				(pts
					(xy 461.772 -1.27) (xy 461.772 -1.778) (xy 461.391 -1.778) (xy 461.391 -1.27)
				)
			)
		)
	)
	(footprint ""
		(layer "F.Cu")
		(at 412.4325 -109.728 90)
		(property "Reference" "R8E22"
			(at 0 0 90)
			(layer "F.SilkS")
			(hide yes)
			(effects
				(font
					(size 1.27 1.27)
				)
			)
		)
		(property "Value" ""
			(at 0 0 90)
			(layer "F.Fab")
			(effects
				(font
					(size 1.27 1.27)
				)
			)
		)
		(duplicate_pad_numbers_are_jumpers no)
		(fp_poly
			(pts
				(xy -0.2794 -0.1016) (xy 0.2794 -0.1016) (xy 0.2794 0.9906) (xy -0.2794 0.9906)
			)
			(stroke
				(width 0)
				(type default)
			)
			(fill no)
			(layer "F.CrtYd")
		)
		(fp_line
			(start 0.2794 -0.1016)
			(end -0.2794 -0.1016)
			(stroke
				(width 0.1)
				(type default)
			)
			(layer "F.Fab")
		)
		(fp_line
			(start -0.2794 -0.1016)
			(end -0.2794 0.9906)
			(stroke
				(width 0.1)
				(type default)
			)
			(layer "F.Fab")
		)
		(fp_line
			(start 0.2794 0.9906)
			(end 0.2794 -0.1016)
			(stroke
				(width 0.1)
				(type default)
			)
			(layer "F.Fab")
		)
		(fp_line
			(start -0.2794 0.9906)
			(end 0.2794 0.9906)
			(stroke
				(width 0.1)
				(type default)
			)
			(layer "F.Fab")
		)
		(pad "1" smd rect
			(at 0 0 90)
			(size 0.508 0.508)
			(layers "F.Cu" "F.Mask" "F.Paste")
			(net "P3V3_STBY")
		)
		(pad "2" smd rect
			(at 0 0.889 90)
			(size 0.508 0.508)
			(layers "F.Cu" "F.Mask" "F.Paste")
			(net "IRQ_BMC_PCH_NMI_STBY_N")
		)
		(zone
			(layer "F.Cu")
			(hatch none 0.5)
			(connect_pads
				(clearance 0)
			)
			(min_thickness 0.25)
			(keepout
				(tracks allowed)
				(vias not_allowed)
				(pads allowed)
				(copperpour not_allowed)
				(footprints allowed)
			)
			(placement
				(enabled no)
				(sheetname "")
			)
			(fill
				(thermal_gap 0.5)
				(thermal_bridge_width 0.5)
				(island_removal_mode 0)
			)
			(polygon
				(pts
					(xy 412.6865 -109.474) (xy 412.6865 -109.982) (xy 413.0675 -109.982) (xy 413.0675 -109.474)
				)
			)
		)
		(zone
			(layer "F.Cu")
			(hatch none 0.5)
			(connect_pads
				(clearance 0)
			)
			(min_thickness 0.25)
			(keepout
				(tracks not_allowed)
				(vias allowed)
				(pads allowed)
				(copperpour not_allowed)
				(footprints allowed)
			)
			(placement
				(enabled no)
				(sheetname "")
			)
			(fill
				(thermal_gap 0.5)
				(thermal_bridge_width 0.5)
				(island_removal_mode 0)
			)
			(polygon
				(pts
					(xy 413.0675 -109.474) (xy 413.0675 -109.982) (xy 412.6865 -109.982) (xy 412.6865 -109.474)
				)
			)
		)
	)
	(footprint ""
		(layer "F.Cu")
		(at 269.358872 -73.279)
		(property "Reference" "C5D51"
			(at 0 0 0)
			(layer "F.SilkS")
			(hide yes)
			(effects
				(font
					(size 1.27 1.27)
				)
			)
		)
		(property "Value" ""
			(at 0 0 0)
			(layer "F.Fab")
			(effects
				(font
					(size 1.27 1.27)
				)
			)
		)
		(duplicate_pad_numbers_are_jumpers no)
		(fp_poly
			(pts
				(xy -0.4953 -0.2032) (xy 0.4953 -0.2032) (xy 0.4953 1.6002) (xy -0.4953 1.6002)
			)
			(stroke
				(width 0)
				(type default)
			)
			(fill no)
			(layer "F.CrtYd")
		)
		(fp_line
			(start -0.4953 -0.2032)
			(end 0.4953 -0.2032)
			(stroke
				(width 0.1)
				(type default)
			)
			(layer "F.Fab")
		)
		(fp_line
			(start -0.4953 1.6002)
			(end -0.4953 -0.2032)
			(stroke
				(width 0.1)
				(type default)
			)
			(layer "F.Fab")
		)
		(fp_line
			(start 0.4953 -0.2032)
			(end 0.4953 1.6002)
			(stroke
				(width 0.1)
				(type default)
			)
			(layer "F.Fab")
		)
		(fp_line
			(start 0.4953 1.6002)
			(end -0.4953 1.6002)
			(stroke
				(width 0.1)
				(type default)
			)
			(layer "F.Fab")
		)
		(pad "1" smd rect
			(at 0 0)
			(size 0.762 0.889)
			(layers "F.Cu" "F.Mask" "F.Paste")
			(net "PVCCMCP_CPU0")
		)
		(pad "2" smd rect
			(at 0 1.397)
			(size 0.762 0.889)
			(layers "F.Cu" "F.Mask" "F.Paste")
			(net "GND")
		)
		(zone
			(layer "F.Cu")
			(hatch none 0.5)
			(connect_pads
				(clearance 0)
			)
			(min_thickness 0.25)
			(keepout
				(tracks not_allowed)
				(vias allowed)
				(pads allowed)
				(copperpour not_allowed)
				(footprints allowed)
			)
			(placement
				(enabled no)
				(sheetname "")
			)
			(fill
				(thermal_gap 0.5)
				(thermal_bridge_width 0.5)
				(island_removal_mode 0)
			)
			(polygon
				(pts
					(xy 268.977872 -72.8345) (xy 269.739872 -72.8345) (xy 269.739872 -72.3265) (xy 268.977872 -72.3265)
				)
			)
		)
	)
	(footprint ""
		(layer "F.Cu")
		(at 401.066 -45.4025 180)
		(property "Reference" "R7F3"
			(at 0 0 180)
			(layer "F.SilkS")
			(hide yes)
			(effects
				(font
					(size 1.27 1.27)
				)
			)
		)
		(property "Value" ""
			(at 0 0 180)
			(layer "F.Fab")
			(effects
				(font
					(size 1.27 1.27)
				)
			)
		)
		(duplicate_pad_numbers_are_jumpers no)
		(fp_poly
			(pts
				(xy -0.2794 -0.1016) (xy 0.2794 -0.1016) (xy 0.2794 0.9906) (xy -0.2794 0.9906)
			)
			(stroke
				(width 0)
				(type default)
			)
			(fill no)
			(layer "F.CrtYd")
		)
		(fp_line
			(start 0.2794 0.9906)
			(end 0.2794 -0.1016)
			(stroke
				(width 0.1)
				(type default)
			)
			(layer "F.Fab")
		)
		(fp_line
			(start 0.2794 -0.1016)
			(end -0.2794 -0.1016)
			(stroke
				(width 0.1)
				(type default)
			)
			(layer "F.Fab")
		)
		(fp_line
			(start -0.2794 0.9906)
			(end 0.2794 0.9906)
			(stroke
				(width 0.1)
				(type default)
			)
			(layer "F.Fab")
		)
		(fp_line
			(start -0.2794 -0.1016)
			(end -0.2794 0.9906)
			(stroke
				(width 0.1)
				(type default)
			)
			(layer "F.Fab")
		)
		(pad "1" smd rect
			(at 0 0 180)
			(size 0.508 0.508)
			(layers "F.Cu" "F.Mask" "F.Paste")
			(net "SPI_BIOS_SOCKET_IO3")
		)
		(pad "2" smd rect
			(at 0 0.889 180)
			(size 0.508 0.508)
			(layers "F.Cu" "F.Mask" "F.Paste")
			(net "PU_BIOS_SPI_HOLD0_N")
		)
		(zone
			(layer "F.Cu")
			(hatch none 0.5)
			(connect_pads
				(clearance 0)
			)
			(min_thickness 0.25)
			(keepout
				(tracks not_allowed)
				(vias allowed)
				(pads allowed)
				(copperpour not_allowed)
				(footprints allowed)
			)
			(placement
				(enabled no)
				(sheetname "")
			)
			(fill
				(thermal_gap 0.5)
				(thermal_bridge_width 0.5)
				(island_removal_mode 0)
			)
			(polygon
				(pts
					(xy 401.32 -46.0375) (xy 400.812 -46.0375) (xy 400.812 -45.6565) (xy 401.32 -45.6565)
				)
			)
		)
		(zone
			(layer "F.Cu")
			(hatch none 0.5)
			(connect_pads
				(clearance 0)
			)
			(min_thickness 0.25)
			(keepout
				(tracks allowed)
				(vias not_allowed)
				(pads allowed)
				(copperpour not_allowed)
				(footprints allowed)
			)
			(placement
				(enabled no)
				(sheetname "")
			)
			(fill
				(thermal_gap 0.5)
				(thermal_bridge_width 0.5)
				(island_removal_mode 0)
			)
			(polygon
				(pts
					(xy 401.32 -45.6565) (xy 400.812 -45.6565) (xy 400.812 -46.0375) (xy 401.32 -46.0375)
				)
			)
		)
	)
	(footprint ""
		(layer "F.Cu")
		(at 346.6338 -23.4823)
		(property "Reference" "C7F11"
			(at 0 0 0)
			(layer "F.SilkS")
			(hide yes)
			(effects
				(font
					(size 1.27 1.27)
				)
			)
		)
		(property "Value" ""
			(at 0 0 0)
			(layer "F.Fab")
			(effects
				(font
					(size 1.27 1.27)
				)
			)
		)
		(duplicate_pad_numbers_are_jumpers no)
		(fp_rect
			(start -0.3048 0.9906)
			(end 0.3048 -0.1016)
			(stroke
				(width 0)
				(type default)
			)
			(fill no)
			(layer "F.CrtYd")
		)
		(fp_line
			(start -0.3048 -0.1016)
			(end -0.3048 0.9906)
			(stroke
				(width 0.1)
				(type default)
			)
			(layer "F.Fab")
		)
		(fp_line
			(start -0.3048 0.9906)
			(end 0.3048 0.9906)
			(stroke
				(width 0.1)
				(type default)
			)
			(layer "F.Fab")
		)
		(fp_line
			(start 0.3048 -0.1016)
			(end -0.3048 -0.1016)
			(stroke
				(width 0.1)
				(type default)
			)
			(layer "F.Fab")
		)
		(fp_line
			(start 0.3048 0.9906)
			(end 0.3048 -0.1016)
			(stroke
				(width 0.1)
				(type default)
			)
			(layer "F.Fab")
		)
		(pad "1" smd rect
			(at 0 0)
			(size 0.508 0.508)
			(layers "F.Cu" "F.Mask" "F.Paste")
			(net "PWRGD_PVPP_ABC_R")
		)
		(pad "2" smd rect
			(at 0 0.889)
			(size 0.508 0.508)
			(layers "F.Cu" "F.Mask" "F.Paste")
			(net "GND")
		)
		(zone
			(layer "F.Cu")
			(hatch none 0.5)
			(connect_pads
				(clearance 0)
			)
			(min_thickness 0.25)
			(keepout
				(tracks allowed)
				(vias not_allowed)
				(pads allowed)
				(copperpour not_allowed)
				(footprints allowed)
			)
			(placement
				(enabled no)
				(sheetname "")
			)
			(fill
				(thermal_gap 0.5)
				(thermal_bridge_width 0.5)
				(island_removal_mode 0)
			)
			(polygon
				(pts
					(xy 346.3798 -22.8473) (xy 346.8878 -22.8473) (xy 346.8878 -23.2283) (xy 346.3798 -23.2283)
				)
			)
		)
		(zone
			(layer "F.Cu")
			(hatch none 0.5)
			(connect_pads
				(clearance 0)
			)
			(min_thickness 0.25)
			(keepout
				(tracks not_allowed)
				(vias allowed)
				(pads allowed)
				(copperpour not_allowed)
				(footprints allowed)
			)
			(placement
				(enabled no)
				(sheetname "")
			)
			(fill
				(thermal_gap 0.5)
				(thermal_bridge_width 0.5)
				(island_removal_mode 0)
			)
			(polygon
				(pts
					(xy 346.3798 -22.8473) (xy 346.8878 -22.8473) (xy 346.8878 -23.2283) (xy 346.3798 -23.2283)
				)
			)
		)
	)
	(footprint ""
		(layer "F.Cu")
		(at 112.182402 -77.382116)
		(property "Reference" "C3D14"
			(at 0 0 0)
			(layer "F.SilkS")
			(hide yes)
			(effects
				(font
					(size 1.27 1.27)
				)
			)
		)
		(property "Value" ""
			(at 0 0 0)
			(layer "F.Fab")
			(effects
				(font
					(size 1.27 1.27)
				)
			)
		)
		(duplicate_pad_numbers_are_jumpers no)
		(fp_poly
			(pts
				(xy -0.4953 -0.2032) (xy 0.4953 -0.2032) (xy 0.4953 1.6002) (xy -0.4953 1.6002)
			)
			(stroke
				(width 0)
				(type default)
			)
			(fill no)
			(layer "F.CrtYd")
		)
		(fp_line
			(start -0.4953 -0.2032)
			(end 0.4953 -0.2032)
			(stroke
				(width 0.1)
				(type default)
			)
			(layer "F.Fab")
		)
		(fp_line
			(start -0.4953 1.6002)
			(end -0.4953 -0.2032)
			(stroke
				(width 0.1)
				(type default)
			)
			(layer "F.Fab")
		)
		(fp_line
			(start 0.4953 -0.2032)
			(end 0.4953 1.6002)
			(stroke
				(width 0.1)
				(type default)
			)
			(layer "F.Fab")
		)
		(fp_line
			(start 0.4953 1.6002)
			(end -0.4953 1.6002)
			(stroke
				(width 0.1)
				(type default)
			)
			(layer "F.Fab")
		)
		(pad "1" smd rect
			(at 0 0)
			(size 0.762 0.889)
			(layers "F.Cu" "F.Mask" "F.Paste")
			(net "PVCCMCP_CPU1")
		)
		(pad "2" smd rect
			(at 0 1.397)
			(size 0.762 0.889)
			(layers "F.Cu" "F.Mask" "F.Paste")
			(net "GND")
		)
		(zone
			(layer "F.Cu")
			(hatch none 0.5)
			(connect_pads
				(clearance 0)
			)
			(min_thickness 0.25)
			(keepout
				(tracks not_allowed)
				(vias allowed)
				(pads allowed)
				(copperpour not_allowed)
				(footprints allowed)
			)
			(placement
				(enabled no)
				(sheetname "")
			)
			(fill
				(thermal_gap 0.5)
				(thermal_bridge_width 0.5)
				(island_removal_mode 0)
			)
			(polygon
				(pts
					(xy 111.801402 -76.937616) (xy 112.563402 -76.937616) (xy 112.563402 -76.429616) (xy 111.801402 -76.429616)
				)
			)
		)
	)
	(footprint ""
		(layer "F.Cu")
		(at 13.8938 -36.576 90)
		(property "Reference" "C1F2"
			(at 0 0 90)
			(layer "F.SilkS")
			(hide yes)
			(effects
				(font
					(size 1.27 1.27)
				)
			)
		)
		(property "Value" ""
			(at 0 0 90)
			(layer "F.Fab")
			(effects
				(font
					(size 1.27 1.27)
				)
			)
		)
		(duplicate_pad_numbers_are_jumpers no)
		(fp_rect
			(start -0.3048 -0.1016)
			(end 0.3048 0.9906)
			(stroke
				(width 0)
				(type default)
			)
			(fill no)
			(layer "F.CrtYd")
		)
		(fp_line
			(start 0.3048 -0.1016)
			(end -0.3048 -0.1016)
			(stroke
				(width 0.1)
				(type default)
			)
			(layer "F.Fab")
		)
		(fp_line
			(start -0.3048 -0.1016)
			(end -0.3048 0.9906)
			(stroke
				(width 0.1)
				(type default)
			)
			(layer "F.Fab")
		)
		(fp_line
			(start 0.3048 0.9906)
			(end 0.3048 -0.1016)
			(stroke
				(width 0.1)
				(type default)
			)
			(layer "F.Fab")
		)
		(fp_line
			(start -0.3048 0.9906)
			(end 0.3048 0.9906)
			(stroke
				(width 0.1)
				(type default)
			)
			(layer "F.Fab")
		)
		(pad "1" smd rect
			(at 0 0 90)
			(size 0.508 0.508)
			(layers "F.Cu" "F.Mask" "F.Paste")
			(net "P3E_CPU1_PE3_MP_C_TXP<7>")
		)
		(pad "2" smd rect
			(at 0 0.889 90)
			(size 0.508 0.508)
			(layers "F.Cu" "F.Mask" "F.Paste")
			(net "P3E_CPU1_PE3_MP_TXP<7>")
		)
		(zone
			(layer "F.Cu")
			(hatch none 0.5)
			(connect_pads
				(clearance 0)
			)
			(min_thickness 0.25)
			(keepout
				(tracks allowed)
				(vias not_allowed)
				(pads allowed)
				(copperpour not_allowed)
				(footprints allowed)
			)
			(placement
				(enabled no)
				(sheetname "")
			)
			(fill
				(thermal_gap 0.5)
				(thermal_bridge_width 0.5)
				(island_removal_mode 0)
			)
			(polygon
				(pts
					(xy 14.1478 -36.322) (xy 14.5288 -36.322) (xy 14.5288 -36.83) (xy 14.1478 -36.83)
				)
			)
		)
		(zone
			(layer "F.Cu")
			(hatch none 0.5)
			(connect_pads
				(clearance 0)
			)
			(min_thickness 0.25)
			(keepout
				(tracks not_allowed)
				(vias allowed)
				(pads allowed)
				(copperpour not_allowed)
				(footprints allowed)
			)
			(placement
				(enabled no)
				(sheetname "")
			)
			(fill
				(thermal_gap 0.5)
				(thermal_bridge_width 0.5)
				(island_removal_mode 0)
			)
			(polygon
				(pts
					(xy 14.1478 -36.322) (xy 14.5288 -36.322) (xy 14.5288 -36.83) (xy 14.1478 -36.83)
				)
			)
		)
	)
	(footprint ""
		(layer "F.Cu")
		(at 28.575 -13.3731)
		(property "Reference" "R1G2"
			(at 0 0 0)
			(layer "F.SilkS")
			(hide yes)
			(effects
				(font
					(size 1.27 1.27)
				)
			)
		)
		(property "Value" ""
			(at 0 0 0)
			(layer "F.Fab")
			(effects
				(font
					(size 1.27 1.27)
				)
			)
		)
		(duplicate_pad_numbers_are_jumpers no)
		(fp_poly
			(pts
				(xy -0.2794 -0.1016) (xy 0.2794 -0.1016) (xy 0.2794 0.9906) (xy -0.2794 0.9906)
			)
			(stroke
				(width 0)
				(type default)
			)
			(fill no)
			(layer "F.CrtYd")
		)
		(fp_line
			(start -0.2794 -0.1016)
			(end -0.2794 0.9906)
			(stroke
				(width 0.1)
				(type default)
			)
			(layer "F.Fab")
		)
		(fp_line
			(start -0.2794 0.9906)
			(end 0.2794 0.9906)
			(stroke
				(width 0.1)
				(type default)
			)
			(layer "F.Fab")
		)
		(fp_line
			(start 0.2794 -0.1016)
			(end -0.2794 -0.1016)
			(stroke
				(width 0.1)
				(type default)
			)
			(layer "F.Fab")
		)
		(fp_line
			(start 0.2794 0.9906)
			(end 0.2794 -0.1016)
			(stroke
				(width 0.1)
				(type default)
			)
			(layer "F.Fab")
		)
		(pad "1" smd rect
			(at 0 0)
			(size 0.508 0.508)
			(layers "F.Cu" "F.Mask" "F.Paste")
			(net "PVDDQ_GHJ")
		)
		(pad "2" smd rect
			(at 0 0.889)
			(size 0.508 0.508)
			(layers "F.Cu" "F.Mask" "F.Paste")
			(net "M_H_VREF")
		)
		(zone
			(layer "F.Cu")
			(hatch none 0.5)
			(connect_pads
				(clearance 0)
			)
			(min_thickness 0.25)
			(keepout
				(tracks allowed)
				(vias not_allowed)
				(pads allowed)
				(copperpour not_allowed)
				(footprints allowed)
			)
			(placement
				(enabled no)
				(sheetname "")
			)
			(fill
				(thermal_gap 0.5)
				(thermal_bridge_width 0.5)
				(island_removal_mode 0)
			)
			(polygon
				(pts
					(xy 28.321 -13.1191) (xy 28.829 -13.1191) (xy 28.829 -12.7381) (xy 28.321 -12.7381)
				)
			)
		)
		(zone
			(layer "F.Cu")
			(hatch none 0.5)
			(connect_pads
				(clearance 0)
			)
			(min_thickness 0.25)
			(keepout
				(tracks not_allowed)
				(vias allowed)
				(pads allowed)
				(copperpour not_allowed)
				(footprints allowed)
			)
			(placement
				(enabled no)
				(sheetname "")
			)
			(fill
				(thermal_gap 0.5)
				(thermal_bridge_width 0.5)
				(island_removal_mode 0)
			)
			(polygon
				(pts
					(xy 28.321 -12.7381) (xy 28.829 -12.7381) (xy 28.829 -13.1191) (xy 28.321 -13.1191)
				)
			)
		)
	)
	(footprint ""
		(layer "F.Cu")
		(at 29.6418 -102.235 -90)
		(property "Reference" "R1C36"
			(at 0 0 270)
			(layer "F.SilkS")
			(hide yes)
			(effects
				(font
					(size 1.27 1.27)
				)
			)
		)
		(property "Value" ""
			(at 0 0 270)
			(layer "F.Fab")
			(effects
				(font
					(size 1.27 1.27)
				)
			)
		)
		(duplicate_pad_numbers_are_jumpers no)
		(fp_poly
			(pts
				(xy -0.2794 -0.1016) (xy 0.2794 -0.1016) (xy 0.2794 0.9906) (xy -0.2794 0.9906)
			)
			(stroke
				(width 0)
				(type default)
			)
			(fill no)
			(layer "F.CrtYd")
		)
		(fp_line
			(start -0.2794 0.9906)
			(end 0.2794 0.9906)
			(stroke
				(width 0.1)
				(type default)
			)
			(layer "F.Fab")
		)
		(fp_line
			(start 0.2794 0.9906)
			(end 0.2794 -0.1016)
			(stroke
				(width 0.1)
				(type default)
			)
			(layer "F.Fab")
		)
		(fp_line
			(start -0.2794 -0.1016)
			(end -0.2794 0.9906)
			(stroke
				(width 0.1)
				(type default)
			)
			(layer "F.Fab")
		)
		(fp_line
			(start 0.2794 -0.1016)
			(end -0.2794 -0.1016)
			(stroke
				(width 0.1)
				(type default)
			)
			(layer "F.Fab")
		)
		(pad "1" smd rect
			(at 0 0 270)
			(size 0.508 0.508)
			(layers "F.Cu" "F.Mask" "F.Paste")
			(net "FM_CPU1_SM_WP")
		)
		(pad "2" smd rect
			(at 0 0.889 270)
			(size 0.508 0.508)
			(layers "F.Cu" "F.Mask" "F.Paste")
			(net "GND")
		)
		(zone
			(layer "F.Cu")
			(hatch none 0.5)
			(connect_pads
				(clearance 0)
			)
			(min_thickness 0.25)
			(keepout
				(tracks not_allowed)
				(vias allowed)
				(pads allowed)
				(copperpour not_allowed)
				(footprints allowed)
			)
			(placement
				(enabled no)
				(sheetname "")
			)
			(fill
				(thermal_gap 0.5)
				(thermal_bridge_width 0.5)
				(island_removal_mode 0)
			)
			(polygon
				(pts
					(xy 29.0068 -102.489) (xy 29.0068 -101.981) (xy 29.3878 -101.981) (xy 29.3878 -102.489)
				)
			)
		)
		(zone
			(layer "F.Cu")
			(hatch none 0.5)
			(connect_pads
				(clearance 0)
			)
			(min_thickness 0.25)
			(keepout
				(tracks allowed)
				(vias not_allowed)
				(pads allowed)
				(copperpour not_allowed)
				(footprints allowed)
			)
			(placement
				(enabled no)
				(sheetname "")
			)
			(fill
				(thermal_gap 0.5)
				(thermal_bridge_width 0.5)
				(island_removal_mode 0)
			)
			(polygon
				(pts
					(xy 29.3878 -102.489) (xy 29.3878 -101.981) (xy 29.0068 -101.981) (xy 29.0068 -102.489)
				)
			)
		)
	)
	(footprint ""
		(layer "F.Cu")
		(at 26.210514 -117.35435)
		(property "Reference" "L1B2"
			(at 0 0 0)
			(layer "F.SilkS")
			(hide yes)
			(effects
				(font
					(size 1.27 1.27)
				)
			)
		)
		(property "Value" "*"
			(at 4.9784 -0.6477 0)
			(unlocked yes)
			(layer "F.Fab")
			(hide yes)
			(effects
				(font
					(size 1.27 1.016)
					(thickness 0.1524)
				)
			)
		)
		(property "Device Type" "IND-80NH-1-GP_DISCRET-GC2-IND-A"
			(at 4.9784 -2.1717 0)
			(unlocked yes)
			(layer "F.Fab")
			(hide yes)
			(effects
				(font
					(size 1.27 1.016)
					(thickness 0.1524)
				)
			)
		)
		(duplicate_pad_numbers_are_jumpers no)
		(fp_line
			(start -2.8575 -3.4544)
			(end 2.8575 -3.4544)
			(stroke
				(width 0.1524)
				(type default)
			)
			(layer "F.SilkS")
		)
		(fp_line
			(start -2.8575 3.4544)
			(end -2.8575 -3.4544)
			(stroke
				(width 0.1524)
				(type default)
			)
			(layer "F.SilkS")
		)
		(fp_line
			(start 2.8575 -3.4544)
			(end 2.8575 3.4544)
			(stroke
				(width 0.1524)
				(type default)
			)
			(layer "F.SilkS")
		)
		(fp_line
			(start 2.8575 3.4544)
			(end -2.8575 3.4544)
			(stroke
				(width 0.1524)
				(type default)
			)
			(layer "F.SilkS")
		)
		(fp_rect
			(start -2.6035 2.6035)
			(end 2.6035 -2.6035)
			(stroke
				(width 0)
				(type default)
			)
			(fill no)
			(layer "F.CrtYd")
		)
		(fp_poly
			(pts
				(xy -3.1115 3.5306) (xy -3.1115 2.6035) (xy 2.6035 2.6035) (xy 2.6035 -2.6035) (xy -2.6035 -2.6035)
				(xy -2.6035 2.5908) (xy -3.1115 2.5908) (xy -3.1115 -3.5306) (xy 3.1115 -3.5306) (xy 3.1115 3.5306)
			)
			(stroke
				(width 0)
				(type default)
			)
			(fill no)
			(layer "F.CrtYd")
		)
		(fp_rect
			(start -3.1115 3.5306)
			(end 3.1115 -3.5306)
			(stroke
				(width 0)
				(type default)
			)
			(fill no)
			(layer "F.Fab")
		)
		(pad "1" smd rect
			(at 0 -2.395982)
			(size 2.2606 1.6002)
			(layers "F.Cu" "F.Mask" "F.Paste")
			(net "P12V_STBY")
		)
		(pad "2" smd rect
			(at 0 2.395982)
			(size 2.2606 1.6002)
			(layers "F.Cu" "F.Mask" "F.Paste")
			(net "VR_FET_SW_P12V_STBY_PVCCIN_CPU1")
		)
	)
	(footprint ""
		(layer "F.Cu")
		(at 382.490726 -80.941926 90)
		(property "Reference" "U14E2"
			(at -0.14986 2.621788 90)
			(unlocked yes)
			(layer "F.SilkS")
			(effects
				(font
					(size 1.27 0.964946)
					(thickness 0.000001)
				)
				(justify left)
			)
		)
		(property "Value" ""
			(at 0 0 90)
			(layer "F.Fab")
			(effects
				(font
					(size 1.27 1.27)
				)
			)
		)
		(duplicate_pad_numbers_are_jumpers no)
		(fp_circle
			(center -0.4699 -0.8382)
			(end -0.4699 -0.7112)
			(stroke
				(width 0.254)
				(type default)
			)
			(fill no)
			(layer "F.SilkS")
		)
		(fp_poly
			(pts
				(xy 0.21463 -0.450088) (xy 1.56337 -0.450088) (xy 1.56337 1.75006) (xy 0.21463 1.75006)
			)
			(stroke
				(width 0)
				(type default)
			)
			(fill no)
			(layer "F.CrtYd")
		)
		(fp_line
			(start 1.56337 -0.450088)
			(end 1.56337 1.75006)
			(stroke
				(width 0.1)
				(type default)
			)
			(layer "F.Fab")
		)
		(fp_line
			(start 0.21463 -0.450088)
			(end 1.56337 -0.450088)
			(stroke
				(width 0.1)
				(type default)
			)
			(layer "F.Fab")
		)
		(fp_line
			(start 1.56337 1.75006)
			(end 0.21463 1.75006)
			(stroke
				(width 0.1)
				(type default)
			)
			(layer "F.Fab")
		)
		(fp_line
			(start 0.21463 1.75006)
			(end 0.21463 -0.450088)
			(stroke
				(width 0.1)
				(type default)
			)
			(layer "F.Fab")
		)
		(fp_circle
			(center -0.4699 -0.8382)
			(end -0.4699 -0.7112)
			(stroke
				(width 0.254)
				(type default)
			)
			(fill no)
			(layer "F.Fab")
		)
		(pad "1" smd rect
			(at 0 0 90)
			(size 1.016 0.381)
			(layers "F.Cu" "F.Mask" "F.Paste")
			(net "RST_PCIE_M2_DEV_N")
		)
		(pad "2" smd rect
			(at 0 0.649986 90)
			(size 1.016 0.381)
			(layers "F.Cu" "F.Mask" "F.Paste")
			(net "RST_PCIE_M2_DEV_AND")
		)
		(pad "3" smd rect
			(at 0 1.299972 90)
			(size 1.016 0.381)
			(layers "F.Cu" "F.Mask" "F.Paste")
			(net "GND")
		)
		(pad "4" smd rect
			(at 1.778 1.299972 90)
			(size 1.016 0.381)
			(layers "F.Cu" "F.Mask" "F.Paste")
			(net "RST_PCIE_M2_DEV_IC_N")
		)
		(pad "5" smd rect
			(at 1.778 0 90)
			(size 1.016 0.381)
			(layers "F.Cu" "F.Mask" "F.Paste")
			(net "P3V3")
		)
	)
	(footprint ""
		(layer "F.Cu")
		(at 367.603532 12.003278 -90)
		(property "Reference" "T1P24"
			(at 0 0 270)
			(layer "F.SilkS")
			(hide yes)
			(effects
				(font
					(size 1.27 1.27)
				)
			)
		)
		(property "Value" "*"
			(at -3.302 1.12395 270)
			(unlocked yes)
			(layer "F.Fab")
			(hide yes)
			(effects
				(font
					(size 0.889 0.889)
					(thickness 0.1524)
				)
			)
		)
		(property "Device Type" "TPAD-DIFF-4P-GP_DISCRET-GB3-TPA"
			(at -3.302 -0.40005 270)
			(unlocked yes)
			(layer "F.Fab")
			(hide yes)
			(effects
				(font
					(size 0.889 0.889)
					(thickness 0.1524)
				)
			)
		)
		(duplicate_pad_numbers_are_jumpers no)
		(fp_line
			(start -2.286 2.286)
			(end 2.286 2.286)
			(stroke
				(width 0.1524)
				(type default)
			)
			(layer "F.SilkS")
		)
		(fp_line
			(start 2.286 2.286)
			(end 2.286 -2.286)
			(stroke
				(width 0.1524)
				(type default)
			)
			(layer "F.SilkS")
		)
		(fp_line
			(start -2.286 -2.286)
			(end -2.286 2.286)
			(stroke
				(width 0.1524)
				(type default)
			)
			(layer "F.SilkS")
		)
		(fp_line
			(start 2.286 -2.286)
			(end -2.286 -2.286)
			(stroke
				(width 0.1524)
				(type default)
			)
			(layer "F.SilkS")
		)
		(fp_line
			(start -2.413 -2.413)
			(end -2.413 -1.143)
			(stroke
				(width 0.4064)
				(type default)
			)
			(layer "F.SilkS")
		)
		(fp_line
			(start -1.143 -2.413)
			(end -2.413 -2.413)
			(stroke
				(width 0.4064)
				(type default)
			)
			(layer "F.SilkS")
		)
		(fp_rect
			(start -2.54 2.54)
			(end 2.54 -2.54)
			(stroke
				(width 0)
				(type default)
			)
			(fill no)
			(layer "F.CrtYd")
		)
		(fp_rect
			(start -2.54 2.54)
			(end 2.54 -2.54)
			(stroke
				(width 0)
				(type default)
			)
			(fill no)
			(layer "F.Fab")
		)
		(pad "1" thru_hole circle
			(at -1.27 -1.27 270)
			(size 1.524 1.524)
			(drill 0.9144)
			(layers "*.Cu" "*.Mask")
			(remove_unused_layers no)
			(net "L14_100OHM_6INCH_DP")
			(clearance -0.0508)
			(thermal_gap 0.127)
			(padstack
				(mode front_inner_back)
				(layer "Inner"
					(shape circle)
					(size 1.1684 1.1684)
					(clearance 0.127)
				)
				(layer "B.Cu"
					(shape circle)
					(size 1.524 1.524)
					(clearance -0.0508)
				)
			)
		)
		(pad "2" thru_hole circle
			(at 1.27 -1.27 270)
			(size 1.524 1.524)
			(drill 0.9144)
			(layers "*.Cu" "*.Mask")
			(remove_unused_layers no)
			(net "L14_100OHM_6INCH_DN")
			(clearance -0.0508)
			(thermal_gap 0.127)
			(padstack
				(mode front_inner_back)
				(layer "Inner"
					(shape circle)
					(size 1.1684 1.1684)
					(clearance 0.127)
				)
				(layer "B.Cu"
					(shape circle)
					(size 1.524 1.524)
					(clearance -0.0508)
				)
			)
		)
		(pad "GND1" thru_hole rect
			(at -1.27 1.27 270)
			(size 1.524 1.524)
			(drill 0.9144)
			(layers "*.Cu" "*.Mask")
			(remove_unused_layers no)
			(net "GND")
			(clearance -0.0508)
			(thermal_gap 0.127)
			(padstack
				(mode front_inner_back)
				(layer "Inner"
					(shape circle)
					(size 1.1684 1.1684)
					(clearance 0.127)
				)
				(layer "B.Cu"
					(shape rect)
					(size 1.524 1.524)
					(clearance -0.0508)
				)
			)
		)
		(pad "GND2" thru_hole rect
			(at 1.27 1.27 270)
			(size 1.524 1.524)
			(drill 0.9144)
			(layers "*.Cu" "*.Mask")
			(remove_unused_layers no)
			(net "GND")
			(clearance -0.0508)
			(thermal_gap 0.127)
			(padstack
				(mode front_inner_back)
				(layer "Inner"
					(shape circle)
					(size 1.1684 1.1684)
					(clearance 0.127)
				)
				(layer "B.Cu"
					(shape rect)
					(size 1.524 1.524)
					(clearance -0.0508)
				)
			)
		)
	)
	(footprint ""
		(layer "F.Cu")
		(at 25.04186 -93.8911 180)
		(property "Reference" "CF11"
			(at 0 0 180)
			(layer "F.SilkS")
			(hide yes)
			(effects
				(font
					(size 1.27 1.27)
				)
			)
		)
		(property "Value" "*"
			(at 1.1811 -2.8194 180)
			(unlocked yes)
			(layer "F.Fab")
			(hide yes)
			(effects
				(font
					(size 1.27 1.016)
					(thickness 0.1524)
				)
			)
		)
		(property "Device Type" "SC22P50V2JN-4GP_SMD-BCG-SC22P5A"
			(at 1.1811 -4.3434 180)
			(unlocked yes)
			(layer "F.Fab")
			(hide yes)
			(effects
				(font
					(size 1.27 1.016)
					(thickness 0.1524)
				)
			)
		)
		(duplicate_pad_numbers_are_jumpers no)
		(fp_rect
			(start -0.4318 0.9525)
			(end 0.4318 -0.9525)
			(stroke
				(width 0)
				(type default)
			)
			(fill no)
			(layer "F.CrtYd")
		)
		(fp_rect
			(start -0.4318 0.9525)
			(end 0.4318 -0.9525)
			(stroke
				(width 0)
				(type default)
			)
			(fill no)
			(layer "F.Fab")
		)
		(pad "1" smd custom
			(at 0 -0.4445 180)
			(size 0.1524 0.1524)
			(layers "F.Cu" "F.Mask" "F.Paste")
			(net "VR_PVCCIN_CPU1_AIREF5")
			(options
				(clearance outline)
				(anchor circle)
			)
			(primitives
				(gr_poly
					(pts
						(arc
							(start 0.3048 -0.2032)
							(mid 0.275042 -0.275042)
							(end 0.2032 -0.3048)
						)
						(arc
							(start -0.2032 -0.3048)
							(mid -0.275042 -0.275042)
							(end -0.3048 -0.2032)
						)
						(arc
							(start -0.3048 0.2032)
							(mid -0.275042 0.275042)
							(end -0.2032 0.3048)
						)
						(arc
							(start 0.2032 0.3048)
							(mid 0.275042 0.275042)
							(end 0.3048 0.2032)
						)
					)
					(width 0)
					(fill yes)
				)
			)
		)
		(pad "2" smd custom
			(at 0 0.4445 180)
			(size 0.1524 0.1524)
			(layers "F.Cu" "F.Mask" "F.Paste")
			(net "ISENSE_PVCCIN_CPU1_PH5_IMON")
			(options
				(clearance outline)
				(anchor circle)
			)
			(primitives
				(gr_poly
					(pts
						(arc
							(start 0.3048 -0.2032)
							(mid 0.275042 -0.275042)
							(end 0.2032 -0.3048)
						)
						(arc
							(start -0.2032 -0.3048)
							(mid -0.275042 -0.275042)
							(end -0.3048 -0.2032)
						)
						(arc
							(start -0.3048 0.2032)
							(mid -0.275042 0.275042)
							(end -0.2032 0.3048)
						)
						(arc
							(start 0.2032 0.3048)
							(mid 0.275042 0.275042)
							(end 0.3048 0.2032)
						)
					)
					(width 0)
					(fill yes)
				)
			)
		)
	)
	(footprint ""
		(layer "F.Cu")
		(at 438.833006 -43.568874 180)
		(property "Reference" "R25W47"
			(at 0 0 180)
			(layer "F.SilkS")
			(hide yes)
			(effects
				(font
					(size 1.27 1.27)
				)
			)
		)
		(property "Value" "*"
			(at 0.064008 -4.108196 180)
			(unlocked yes)
			(layer "F.Fab")
			(hide yes)
			(effects
				(font
					(size 1.27 1.016)
					(thickness 0.1524)
				)
			)
		)
		(property "Device Type" "120R2F-GP_RCL_GP-120R2F-GP,64.A"
			(at 0.064008 -5.632196 180)
			(unlocked yes)
			(layer "F.Fab")
			(hide yes)
			(effects
				(font
					(size 1.27 1.016)
					(thickness 0.1524)
				)
			)
		)
		(duplicate_pad_numbers_are_jumpers no)
		(fp_line
			(start 0.508 -0.9398)
			(end -0.508 -0.9398)
			(stroke
				(width 0.1524)
				(type default)
			)
			(layer "F.SilkS")
		)
		(fp_line
			(start -0.508 -0.9398)
			(end -0.508 0.9398)
			(stroke
				(width 0.1524)
				(type default)
			)
			(layer "F.SilkS")
		)
		(fp_rect
			(start -0.508 0.9398)
			(end 0.508 -0.9398)
			(stroke
				(width 0)
				(type default)
			)
			(fill no)
			(layer "F.CrtYd")
		)
		(fp_rect
			(start -0.508 0.9398)
			(end 0.508 -0.9398)
			(stroke
				(width 0)
				(type default)
			)
			(fill no)
			(layer "F.Fab")
		)
		(pad "1" smd custom
			(at 0 -0.4445 180)
			(size 0.1397 0.1397)
			(layers "F.Cu" "F.Mask" "F.Paste")
			(net "BMC_M_A9")
			(options
				(clearance outline)
				(anchor circle)
			)
			(primitives
				(gr_poly
					(pts
						(arc
							(start -0.1778 -0.2794)
							(mid -0.249642 -0.249642)
							(end -0.2794 -0.1778)
						)
						(arc
							(start -0.2794 0.1778)
							(mid -0.249642 0.249642)
							(end -0.1778 0.2794)
						)
						(arc
							(start 0.1778 0.2794)
							(mid 0.249642 0.249642)
							(end 0.2794 0.1778)
						)
						(arc
							(start 0.2794 -0.1778)
							(mid 0.249642 -0.249642)
							(end 0.1778 -0.2794)
						)
					)
					(width 0)
					(fill yes)
				)
			)
		)
		(pad "2" smd custom
			(at 0 0.4445 180)
			(size 0.1397 0.1397)
			(layers "F.Cu" "F.Mask" "F.Paste")
			(net "P1V2_AUX_BMC")
			(options
				(clearance outline)
				(anchor circle)
			)
			(primitives
				(gr_poly
					(pts
						(arc
							(start -0.1778 -0.2794)
							(mid -0.249642 -0.249642)
							(end -0.2794 -0.1778)
						)
						(arc
							(start -0.2794 0.1778)
							(mid -0.249642 0.249642)
							(end -0.1778 0.2794)
						)
						(arc
							(start 0.1778 0.2794)
							(mid 0.249642 0.249642)
							(end 0.2794 0.1778)
						)
						(arc
							(start 0.2794 -0.1778)
							(mid 0.249642 -0.249642)
							(end 0.1778 -0.2794)
						)
					)
					(width 0)
					(fill yes)
				)
			)
		)
	)
	(footprint ""
		(layer "F.Cu")
		(at 198.370444 -102.053136 90)
		(property "Reference" "C4C10"
			(at 0 0 90)
			(layer "F.SilkS")
			(hide yes)
			(effects
				(font
					(size 1.27 1.27)
				)
			)
		)
		(property "Value" ""
			(at 0 0 90)
			(layer "F.Fab")
			(effects
				(font
					(size 1.27 1.27)
				)
			)
		)
		(duplicate_pad_numbers_are_jumpers no)
		(fp_rect
			(start 0.3048 0.9906)
			(end -0.3048 -0.1016)
			(stroke
				(width 0)
				(type default)
			)
			(fill no)
			(layer "F.CrtYd")
		)
		(fp_line
			(start 0.3048 -0.1016)
			(end -0.3048 -0.1016)
			(stroke
				(width 0.1)
				(type default)
			)
			(layer "F.Fab")
		)
		(fp_line
			(start -0.3048 -0.1016)
			(end -0.3048 0.9906)
			(stroke
				(width 0.1)
				(type default)
			)
			(layer "F.Fab")
		)
		(fp_line
			(start 0.3048 0.9906)
			(end 0.3048 -0.1016)
			(stroke
				(width 0.1)
				(type default)
			)
			(layer "F.Fab")
		)
		(fp_line
			(start -0.3048 0.9906)
			(end 0.3048 0.9906)
			(stroke
				(width 0.1)
				(type default)
			)
			(layer "F.Fab")
		)
		(pad "1" smd rect
			(at 0 0 90)
			(size 0.508 0.508)
			(layers "F.Cu" "F.Mask" "F.Paste")
			(net "VR_FET_SW_P12V_STBY_PVCCIN_CPU0")
		)
		(pad "2" smd rect
			(at 0 0.889 90)
			(size 0.508 0.508)
			(layers "F.Cu" "F.Mask" "F.Paste")
			(net "GND")
		)
		(zone
			(layer "F.Cu")
			(hatch none 0.5)
			(connect_pads
				(clearance 0)
			)
			(min_thickness 0.25)
			(keepout
				(tracks allowed)
				(vias not_allowed)
				(pads allowed)
				(copperpour not_allowed)
				(footprints allowed)
			)
			(placement
				(enabled no)
				(sheetname "")
			)
			(fill
				(thermal_gap 0.5)
				(thermal_bridge_width 0.5)
				(island_removal_mode 0)
			)
			(polygon
				(pts
					(xy 199.005444 -102.307136) (xy 198.624444 -102.307136) (xy 198.624444 -101.799136) (xy 199.005444 -101.799136)
				)
			)
		)
		(zone
			(layer "F.Cu")
			(hatch none 0.5)
			(connect_pads
				(clearance 0)
			)
			(min_thickness 0.25)
			(keepout
				(tracks not_allowed)
				(vias allowed)
				(pads allowed)
				(copperpour not_allowed)
				(footprints allowed)
			)
			(placement
				(enabled no)
				(sheetname "")
			)
			(fill
				(thermal_gap 0.5)
				(thermal_bridge_width 0.5)
				(island_removal_mode 0)
			)
			(polygon
				(pts
					(xy 199.005444 -102.307136) (xy 198.624444 -102.307136) (xy 198.624444 -101.799136) (xy 199.005444 -101.799136)
				)
			)
		)
	)
	(footprint ""
		(layer "F.Cu")
		(at 6.388608 -2.16281 -90)
		(property "Reference" "RF19"
			(at -0.8382 -0.67818 270)
			(unlocked yes)
			(layer "F.SilkS")
			(effects
				(font
					(size 0.4064 0.254)
					(thickness 0.1524)
				)
				(justify left)
			)
		)
		(property "Value" ""
			(at 0 0 270)
			(layer "F.Fab")
			(effects
				(font
					(size 1.27 1.27)
				)
			)
		)
		(duplicate_pad_numbers_are_jumpers no)
		(fp_poly
			(pts
				(xy -0.2794 -0.1016) (xy 0.2794 -0.1016) (xy 0.2794 0.9906) (xy -0.2794 0.9906)
			)
			(stroke
				(width 0)
				(type default)
			)
			(fill no)
			(layer "F.CrtYd")
		)
		(fp_line
			(start -0.2794 0.9906)
			(end 0.2794 0.9906)
			(stroke
				(width 0.1)
				(type default)
			)
			(layer "F.Fab")
		)
		(fp_line
			(start 0.2794 0.9906)
			(end 0.2794 -0.1016)
			(stroke
				(width 0.1)
				(type default)
			)
			(layer "F.Fab")
		)
		(fp_line
			(start -0.2794 -0.1016)
			(end -0.2794 0.9906)
			(stroke
				(width 0.1)
				(type default)
			)
			(layer "F.Fab")
		)
		(fp_line
			(start 0.2794 -0.1016)
			(end -0.2794 -0.1016)
			(stroke
				(width 0.1)
				(type default)
			)
			(layer "F.Fab")
		)
		(pad "1" smd rect
			(at 0 0 270)
			(size 0.508 0.508)
			(layers "F.Cu" "F.Mask" "F.Paste")
			(net "VR_PVDDQ_GHJ_AIREF1")
		)
		(pad "2" smd rect
			(at 0 0.889 270)
			(size 0.508 0.508)
			(layers "F.Cu" "F.Mask" "F.Paste")
			(net "ISENSE_PVDDQ_GHJ_PH1_IMON")
		)
		(zone
			(layer "F.Cu")
			(hatch none 0.5)
			(connect_pads
				(clearance 0)
			)
			(min_thickness 0.25)
			(keepout
				(tracks not_allowed)
				(vias allowed)
				(pads allowed)
				(copperpour not_allowed)
				(footprints allowed)
			)
			(placement
				(enabled no)
				(sheetname "")
			)
			(fill
				(thermal_gap 0.5)
				(thermal_bridge_width 0.5)
				(island_removal_mode 0)
			)
			(polygon
				(pts
					(xy 5.753608 -2.41681) (xy 5.753608 -1.90881) (xy 6.134608 -1.90881) (xy 6.134608 -2.41681)
				)
			)
		)
		(zone
			(layer "F.Cu")
			(hatch none 0.5)
			(connect_pads
				(clearance 0)
			)
			(min_thickness 0.25)
			(keepout
				(tracks allowed)
				(vias not_allowed)
				(pads allowed)
				(copperpour not_allowed)
				(footprints allowed)
			)
			(placement
				(enabled no)
				(sheetname "")
			)
			(fill
				(thermal_gap 0.5)
				(thermal_bridge_width 0.5)
				(island_removal_mode 0)
			)
			(polygon
				(pts
					(xy 6.134608 -2.41681) (xy 6.134608 -1.90881) (xy 5.753608 -1.90881) (xy 5.753608 -2.41681)
				)
			)
		)
	)
	(footprint ""
		(layer "F.Cu")
		(at 345.6178 -23.4823)
		(property "Reference" "R7F15"
			(at 0 0 0)
			(layer "F.SilkS")
			(hide yes)
			(effects
				(font
					(size 1.27 1.27)
				)
			)
		)
		(property "Value" ""
			(at 0 0 0)
			(layer "F.Fab")
			(effects
				(font
					(size 1.27 1.27)
				)
			)
		)
		(duplicate_pad_numbers_are_jumpers no)
		(fp_rect
			(start -0.2794 0.9906)
			(end 0.2794 -0.1016)
			(stroke
				(width 0)
				(type default)
			)
			(fill no)
			(layer "F.CrtYd")
		)
		(fp_line
			(start -0.2794 -0.1016)
			(end -0.2794 0.9906)
			(stroke
				(width 0.1)
				(type default)
			)
			(layer "F.Fab")
		)
		(fp_line
			(start -0.2794 0.9906)
			(end 0.2794 0.9906)
			(stroke
				(width 0.1)
				(type default)
			)
			(layer "F.Fab")
		)
		(fp_line
			(start 0.2794 -0.1016)
			(end -0.2794 -0.1016)
			(stroke
				(width 0.1)
				(type default)
			)
			(layer "F.Fab")
		)
		(fp_line
			(start 0.2794 0.9906)
			(end 0.2794 -0.1016)
			(stroke
				(width 0.1)
				(type default)
			)
			(layer "F.Fab")
		)
		(pad "1" smd rect
			(at 0 0)
			(size 0.508 0.508)
			(layers "F.Cu" "F.Mask" "F.Paste")
			(net "VR_PVPP_ABC_ISET")
		)
		(pad "2" smd rect
			(at 0 0.889)
			(size 0.508 0.508)
			(layers "F.Cu" "F.Mask" "F.Paste")
			(net "AGND_PVPP_ABC")
		)
		(zone
			(layer "F.Cu")
			(hatch none 0.5)
			(connect_pads
				(clearance 0)
			)
			(min_thickness 0.25)
			(keepout
				(tracks allowed)
				(vias not_allowed)
				(pads allowed)
				(copperpour not_allowed)
				(footprints allowed)
			)
			(placement
				(enabled no)
				(sheetname "")
			)
			(fill
				(thermal_gap 0.5)
				(thermal_bridge_width 0.5)
				(island_removal_mode 0)
			)
			(polygon
				(pts
					(xy 345.3638 -22.8473) (xy 345.8718 -22.8473) (xy 345.8718 -23.2283) (xy 345.3638 -23.2283)
				)
			)
		)
		(zone
			(layer "F.Cu")
			(hatch none 0.5)
			(connect_pads
				(clearance 0)
			)
			(min_thickness 0.25)
			(keepout
				(tracks not_allowed)
				(vias allowed)
				(pads allowed)
				(copperpour not_allowed)
				(footprints allowed)
			)
			(placement
				(enabled no)
				(sheetname "")
			)
			(fill
				(thermal_gap 0.5)
				(thermal_bridge_width 0.5)
				(island_removal_mode 0)
			)
			(polygon
				(pts
					(xy 345.3638 -22.8473) (xy 345.8718 -22.8473) (xy 345.8718 -23.2283) (xy 345.3638 -23.2283)
				)
			)
		)
	)
	(footprint ""
		(layer "F.Cu")
		(at 476.6691 -141.6177 180)
		(property "Reference" "C9A3"
			(at 0 0 180)
			(layer "F.SilkS")
			(hide yes)
			(effects
				(font
					(size 1.27 1.27)
				)
			)
		)
		(property "Value" ""
			(at 0 0 180)
			(layer "F.Fab")
			(effects
				(font
					(size 1.27 1.27)
				)
			)
		)
		(duplicate_pad_numbers_are_jumpers no)
		(fp_poly
			(pts
				(xy 0.3048 -0.1016) (xy 0.3048 0.9906) (xy -0.3048 0.9906) (xy -0.3048 -0.1016)
			)
			(stroke
				(width 0)
				(type default)
			)
			(fill no)
			(layer "F.CrtYd")
		)
		(fp_line
			(start 0.3048 0.9906)
			(end 0.3048 -0.1016)
			(stroke
				(width 0.1)
				(type default)
			)
			(layer "F.Fab")
		)
		(fp_line
			(start 0.3048 -0.1016)
			(end -0.3048 -0.1016)
			(stroke
				(width 0.1)
				(type default)
			)
			(layer "F.Fab")
		)
		(fp_line
			(start -0.3048 0.9906)
			(end 0.3048 0.9906)
			(stroke
				(width 0.1)
				(type default)
			)
			(layer "F.Fab")
		)
		(fp_line
			(start -0.3048 -0.1016)
			(end -0.3048 0.9906)
			(stroke
				(width 0.1)
				(type default)
			)
			(layer "F.Fab")
		)
		(pad "1" smd rect
			(at 0 0 180)
			(size 0.508 0.508)
			(layers "F.Cu" "F.Mask" "F.Paste")
			(net "P3V3_STBY")
		)
		(pad "2" smd rect
			(at 0 0.889 180)
			(size 0.508 0.508)
			(layers "F.Cu" "F.Mask" "F.Paste")
			(net "GND")
		)
		(zone
			(layer "F.Cu")
			(hatch none 0.5)
			(connect_pads
				(clearance 0)
			)
			(min_thickness 0.25)
			(keepout
				(tracks not_allowed)
				(vias allowed)
				(pads allowed)
				(copperpour not_allowed)
				(footprints allowed)
			)
			(placement
				(enabled no)
				(sheetname "")
			)
			(fill
				(thermal_gap 0.5)
				(thermal_bridge_width 0.5)
				(island_removal_mode 0)
			)
			(polygon
				(pts
					(xy 476.9231 -142.2527) (xy 476.4151 -142.2527) (xy 476.4151 -141.8717) (xy 476.9231 -141.8717)
				)
			)
		)
		(zone
			(layer "F.Cu")
			(hatch none 0.5)
			(connect_pads
				(clearance 0)
			)
			(min_thickness 0.25)
			(keepout
				(tracks allowed)
				(vias not_allowed)
				(pads allowed)
				(copperpour not_allowed)
				(footprints allowed)
			)
			(placement
				(enabled no)
				(sheetname "")
			)
			(fill
				(thermal_gap 0.5)
				(thermal_bridge_width 0.5)
				(island_removal_mode 0)
			)
			(polygon
				(pts
					(xy 476.9231 -141.8717) (xy 476.4151 -141.8717) (xy 476.4151 -142.2527) (xy 476.9231 -142.2527)
				)
			)
		)
	)
	(footprint ""
		(layer "F.Cu")
		(at 177.165 -80.137 90)
		(property "Reference" "R4D20"
			(at 0 0 90)
			(layer "F.SilkS")
			(hide yes)
			(effects
				(font
					(size 1.27 1.27)
				)
			)
		)
		(property "Value" ""
			(at 0 0 90)
			(layer "F.Fab")
			(effects
				(font
					(size 1.27 1.27)
				)
			)
		)
		(duplicate_pad_numbers_are_jumpers no)
		(fp_poly
			(pts
				(xy -0.2794 -0.1016) (xy 0.2794 -0.1016) (xy 0.2794 0.9906) (xy -0.2794 0.9906)
			)
			(stroke
				(width 0)
				(type default)
			)
			(fill no)
			(layer "F.CrtYd")
		)
		(fp_line
			(start 0.2794 -0.1016)
			(end -0.2794 -0.1016)
			(stroke
				(width 0.1)
				(type default)
			)
			(layer "F.Fab")
		)
		(fp_line
			(start -0.2794 -0.1016)
			(end -0.2794 0.9906)
			(stroke
				(width 0.1)
				(type default)
			)
			(layer "F.Fab")
		)
		(fp_line
			(start 0.2794 0.9906)
			(end 0.2794 -0.1016)
			(stroke
				(width 0.1)
				(type default)
			)
			(layer "F.Fab")
		)
		(fp_line
			(start -0.2794 0.9906)
			(end 0.2794 0.9906)
			(stroke
				(width 0.1)
				(type default)
			)
			(layer "F.Fab")
		)
		(pad "1" smd rect
			(at 0 0 90)
			(size 0.508 0.508)
			(layers "F.Cu" "F.Mask" "F.Paste")
			(net "CLK_100M_CPU0_BCLK1_R_DN")
		)
		(pad "2" smd rect
			(at 0 0.889 90)
			(size 0.508 0.508)
			(layers "F.Cu" "F.Mask" "F.Paste")
			(net "CLK_100M_CPU0_BCLK1_DN")
		)
		(zone
			(layer "F.Cu")
			(hatch none 0.5)
			(connect_pads
				(clearance 0)
			)
			(min_thickness 0.25)
			(keepout
				(tracks allowed)
				(vias not_allowed)
				(pads allowed)
				(copperpour not_allowed)
				(footprints allowed)
			)
			(placement
				(enabled no)
				(sheetname "")
			)
			(fill
				(thermal_gap 0.5)
				(thermal_bridge_width 0.5)
				(island_removal_mode 0)
			)
			(polygon
				(pts
					(xy 177.419 -79.883) (xy 177.419 -80.391) (xy 177.8 -80.391) (xy 177.8 -79.883)
				)
			)
		)
		(zone
			(layer "F.Cu")
			(hatch none 0.5)
			(connect_pads
				(clearance 0)
			)
			(min_thickness 0.25)
			(keepout
				(tracks not_allowed)
				(vias allowed)
				(pads allowed)
				(copperpour not_allowed)
				(footprints allowed)
			)
			(placement
				(enabled no)
				(sheetname "")
			)
			(fill
				(thermal_gap 0.5)
				(thermal_bridge_width 0.5)
				(island_removal_mode 0)
			)
			(polygon
				(pts
					(xy 177.8 -79.883) (xy 177.8 -80.391) (xy 177.419 -80.391) (xy 177.419 -79.883)
				)
			)
		)
	)
	(footprint ""
		(layer "F.Cu")
		(at 481.6983 -137.033 90)
		(property "Reference" "R9A20"
			(at 0 0 90)
			(layer "F.SilkS")
			(hide yes)
			(effects
				(font
					(size 1.27 1.27)
				)
			)
		)
		(property "Value" ""
			(at 0 0 90)
			(layer "F.Fab")
			(effects
				(font
					(size 1.27 1.27)
				)
			)
		)
		(duplicate_pad_numbers_are_jumpers no)
		(fp_poly
			(pts
				(xy -0.2794 -0.1016) (xy 0.2794 -0.1016) (xy 0.2794 0.9906) (xy -0.2794 0.9906)
			)
			(stroke
				(width 0)
				(type default)
			)
			(fill no)
			(layer "F.CrtYd")
		)
		(fp_line
			(start 0.2794 -0.1016)
			(end -0.2794 -0.1016)
			(stroke
				(width 0.1)
				(type default)
			)
			(layer "F.Fab")
		)
		(fp_line
			(start -0.2794 -0.1016)
			(end -0.2794 0.9906)
			(stroke
				(width 0.1)
				(type default)
			)
			(layer "F.Fab")
		)
		(fp_line
			(start 0.2794 0.9906)
			(end 0.2794 -0.1016)
			(stroke
				(width 0.1)
				(type default)
			)
			(layer "F.Fab")
		)
		(fp_line
			(start -0.2794 0.9906)
			(end 0.2794 0.9906)
			(stroke
				(width 0.1)
				(type default)
			)
			(layer "F.Fab")
		)
		(pad "1" smd rect
			(at 0 0 90)
			(size 0.508 0.508)
			(layers "F.Cu" "F.Mask" "F.Paste")
			(net "FM_PWR_LED_A")
		)
		(pad "2" smd rect
			(at 0 0.889 90)
			(size 0.508 0.508)
			(layers "F.Cu" "F.Mask" "F.Paste")
			(net "P3V3_STBY")
		)
		(zone
			(layer "F.Cu")
			(hatch none 0.5)
			(connect_pads
				(clearance 0)
			)
			(min_thickness 0.25)
			(keepout
				(tracks allowed)
				(vias not_allowed)
				(pads allowed)
				(copperpour not_allowed)
				(footprints allowed)
			)
			(placement
				(enabled no)
				(sheetname "")
			)
			(fill
				(thermal_gap 0.5)
				(thermal_bridge_width 0.5)
				(island_removal_mode 0)
			)
			(polygon
				(pts
					(xy 481.9523 -136.779) (xy 481.9523 -137.287) (xy 482.3333 -137.287) (xy 482.3333 -136.779)
				)
			)
		)
		(zone
			(layer "F.Cu")
			(hatch none 0.5)
			(connect_pads
				(clearance 0)
			)
			(min_thickness 0.25)
			(keepout
				(tracks not_allowed)
				(vias allowed)
				(pads allowed)
				(copperpour not_allowed)
				(footprints allowed)
			)
			(placement
				(enabled no)
				(sheetname "")
			)
			(fill
				(thermal_gap 0.5)
				(thermal_bridge_width 0.5)
				(island_removal_mode 0)
			)
			(polygon
				(pts
					(xy 482.3333 -136.779) (xy 482.3333 -137.287) (xy 481.9523 -137.287) (xy 481.9523 -136.779)
				)
			)
		)
	)
	(footprint ""
		(layer "F.Cu")
		(at 16.002 -87.63)
		(property "Reference" "R1D1"
			(at 0 0 0)
			(layer "F.SilkS")
			(hide yes)
			(effects
				(font
					(size 1.27 1.27)
				)
			)
		)
		(property "Value" ""
			(at 0 0 0)
			(layer "F.Fab")
			(effects
				(font
					(size 1.27 1.27)
				)
			)
		)
		(duplicate_pad_numbers_are_jumpers no)
		(fp_rect
			(start -0.2794 0.9906)
			(end 0.2794 -0.1016)
			(stroke
				(width 0)
				(type default)
			)
			(fill no)
			(layer "F.CrtYd")
		)
		(fp_line
			(start -0.2794 -0.1016)
			(end -0.2794 0.9906)
			(stroke
				(width 0.1)
				(type default)
			)
			(layer "F.Fab")
		)
		(fp_line
			(start -0.2794 0.9906)
			(end 0.2794 0.9906)
			(stroke
				(width 0.1)
				(type default)
			)
			(layer "F.Fab")
		)
		(fp_line
			(start 0.2794 -0.1016)
			(end -0.2794 -0.1016)
			(stroke
				(width 0.1)
				(type default)
			)
			(layer "F.Fab")
		)
		(fp_line
			(start 0.2794 0.9906)
			(end 0.2794 -0.1016)
			(stroke
				(width 0.1)
				(type default)
			)
			(layer "F.Fab")
		)
		(pad "1" smd rect
			(at 0 0)
			(size 0.508 0.508)
			(layers "F.Cu" "F.Mask" "F.Paste")
			(net "PWRGD_PVSA_CPU1_R")
		)
		(pad "2" smd rect
			(at 0 0.889)
			(size 0.508 0.508)
			(layers "F.Cu" "F.Mask" "F.Paste")
			(net "PWRGD_PVSA_CPU1")
		)
		(zone
			(layer "F.Cu")
			(hatch none 0.5)
			(connect_pads
				(clearance 0)
			)
			(min_thickness 0.25)
			(keepout
				(tracks not_allowed)
				(vias allowed)
				(pads allowed)
				(copperpour not_allowed)
				(footprints allowed)
			)
			(placement
				(enabled no)
				(sheetname "")
			)
			(fill
				(thermal_gap 0.5)
				(thermal_bridge_width 0.5)
				(island_removal_mode 0)
			)
			(polygon
				(pts
					(xy 15.748 -86.995) (xy 16.256 -86.995) (xy 16.256 -87.376) (xy 15.748 -87.376)
				)
			)
		)
		(zone
			(layer "F.Cu")
			(hatch none 0.5)
			(connect_pads
				(clearance 0)
			)
			(min_thickness 0.25)
			(keepout
				(tracks allowed)
				(vias not_allowed)
				(pads allowed)
				(copperpour not_allowed)
				(footprints allowed)
			)
			(placement
				(enabled no)
				(sheetname "")
			)
			(fill
				(thermal_gap 0.5)
				(thermal_bridge_width 0.5)
				(island_removal_mode 0)
			)
			(polygon
				(pts
					(xy 15.748 -86.995) (xy 16.256 -86.995) (xy 16.256 -87.376) (xy 15.748 -87.376)
				)
			)
		)
	)
	(footprint ""
		(layer "F.Cu")
		(at 80.757268 -3.3528 -90)
		(property "Reference" "C2G9"
			(at 1.848866 0.752348 270)
			(unlocked yes)
			(layer "F.SilkS")
			(effects
				(font
					(size 1.27 0.9652)
					(thickness 0.1524)
				)
			)
		)
		(property "Value" ""
			(at 0 0 270)
			(layer "F.Fab")
			(effects
				(font
					(size 1.27 1.27)
				)
			)
		)
		(duplicate_pad_numbers_are_jumpers no)
		(fp_rect
			(start -0.500126 1.598422)
			(end 0.500126 -0.201422)
			(stroke
				(width 0)
				(type default)
			)
			(fill no)
			(layer "F.CrtYd")
		)
		(fp_line
			(start -0.500126 1.598422)
			(end -0.500126 -0.201422)
			(stroke
				(width 0.1)
				(type default)
			)
			(layer "F.Fab")
		)
		(fp_line
			(start 0.500126 1.598422)
			(end -0.500126 1.598422)
			(stroke
				(width 0.1)
				(type default)
			)
			(layer "F.Fab")
		)
		(fp_line
			(start -0.500126 -0.201422)
			(end 0.500126 -0.201422)
			(stroke
				(width 0.1)
				(type default)
			)
			(layer "F.Fab")
		)
		(fp_line
			(start 0.500126 -0.201422)
			(end 0.500126 1.598422)
			(stroke
				(width 0.1)
				(type default)
			)
			(layer "F.Fab")
		)
		(pad "1" smd rect
			(at 0 0 180)
			(size 0.889 0.9906)
			(layers "F.Cu" "F.Mask" "F.Paste")
			(net "PVDDQ_GHJ")
		)
		(pad "2" smd rect
			(at 0 1.397 180)
			(size 0.889 0.9906)
			(layers "F.Cu" "F.Mask" "F.Paste")
			(net "GND")
		)
		(zone
			(layer "F.Cu")
			(hatch none 0.5)
			(connect_pads
				(clearance 0)
			)
			(min_thickness 0.25)
			(keepout
				(tracks not_allowed)
				(vias allowed)
				(pads allowed)
				(copperpour not_allowed)
				(footprints allowed)
			)
			(placement
				(enabled no)
				(sheetname "")
			)
			(fill
				(thermal_gap 0.5)
				(thermal_bridge_width 0.5)
				(island_removal_mode 0)
			)
			(polygon
				(pts
					(xy 79.804768 -3.8481) (xy 79.804768 -2.8575) (xy 80.312768 -2.8575) (xy 80.312768 -3.8481)
				)
			)
		)
		(zone
			(layer "F.Cu")
			(hatch none 0.5)
			(connect_pads
				(clearance 0)
			)
			(min_thickness 0.25)
			(keepout
				(tracks allowed)
				(vias not_allowed)
				(pads allowed)
				(copperpour not_allowed)
				(footprints allowed)
			)
			(placement
				(enabled no)
				(sheetname "")
			)
			(fill
				(thermal_gap 0.5)
				(thermal_bridge_width 0.5)
				(island_removal_mode 0)
			)
			(polygon
				(pts
					(xy 79.804768 -3.8481) (xy 79.804768 -2.8575) (xy 80.312768 -2.8575) (xy 80.312768 -3.8481)
				)
			)
		)
	)
	(footprint ""
		(layer "F.Cu")
		(at 13.640816 -1.197864 90)
		(property "Reference" "C1G21"
			(at 0 0 90)
			(layer "F.SilkS")
			(hide yes)
			(effects
				(font
					(size 1.27 1.27)
				)
			)
		)
		(property "Value" ""
			(at 0 0 90)
			(layer "F.Fab")
			(effects
				(font
					(size 1.27 1.27)
				)
			)
		)
		(duplicate_pad_numbers_are_jumpers no)
		(fp_poly
			(pts
				(xy 0.3048 -0.1016) (xy 0.3048 0.9906) (xy -0.3048 0.9906) (xy -0.3048 -0.1016)
			)
			(stroke
				(width 0)
				(type default)
			)
			(fill no)
			(layer "F.CrtYd")
		)
		(fp_line
			(start 0.3048 -0.1016)
			(end -0.3048 -0.1016)
			(stroke
				(width 0.1)
				(type default)
			)
			(layer "F.Fab")
		)
		(fp_line
			(start -0.3048 -0.1016)
			(end -0.3048 0.9906)
			(stroke
				(width 0.1)
				(type default)
			)
			(layer "F.Fab")
		)
		(fp_line
			(start 0.3048 0.9906)
			(end 0.3048 -0.1016)
			(stroke
				(width 0.1)
				(type default)
			)
			(layer "F.Fab")
		)
		(fp_line
			(start -0.3048 0.9906)
			(end 0.3048 0.9906)
			(stroke
				(width 0.1)
				(type default)
			)
			(layer "F.Fab")
		)
		(pad "1" smd rect
			(at 0 0 90)
			(size 0.508 0.508)
			(layers "F.Cu" "F.Mask" "F.Paste")
			(net "PWRGD_PVDDQ_GHJ_R")
		)
		(pad "2" smd rect
			(at 0 0.889 90)
			(size 0.508 0.508)
			(layers "F.Cu" "F.Mask" "F.Paste")
			(net "GND")
		)
		(zone
			(layer "F.Cu")
			(hatch none 0.5)
			(connect_pads
				(clearance 0)
			)
			(min_thickness 0.25)
			(keepout
				(tracks allowed)
				(vias not_allowed)
				(pads allowed)
				(copperpour not_allowed)
				(footprints allowed)
			)
			(placement
				(enabled no)
				(sheetname "")
			)
			(fill
				(thermal_gap 0.5)
				(thermal_bridge_width 0.5)
				(island_removal_mode 0)
			)
			(polygon
				(pts
					(xy 13.894816 -0.943864) (xy 13.894816 -1.451864) (xy 14.275816 -1.451864) (xy 14.275816 -0.943864)
				)
			)
		)
		(zone
			(layer "F.Cu")
			(hatch none 0.5)
			(connect_pads
				(clearance 0)
			)
			(min_thickness 0.25)
			(keepout
				(tracks not_allowed)
				(vias allowed)
				(pads allowed)
				(copperpour not_allowed)
				(footprints allowed)
			)
			(placement
				(enabled no)
				(sheetname "")
			)
			(fill
				(thermal_gap 0.5)
				(thermal_bridge_width 0.5)
				(island_removal_mode 0)
			)
			(polygon
				(pts
					(xy 14.275816 -0.943864) (xy 14.275816 -1.451864) (xy 13.894816 -1.451864) (xy 13.894816 -0.943864)
				)
			)
		)
	)
	(footprint ""
		(layer "F.Cu")
		(at 433.832 -14.224 180)
		(property "Reference" "R6W42"
			(at -0.8382 -0.67818 180)
			(unlocked yes)
			(layer "F.SilkS")
			(effects
				(font
					(size 0.4064 0.254)
					(thickness 0.1524)
				)
				(justify left)
			)
		)
		(property "Value" ""
			(at 0 0 180)
			(layer "F.Fab")
			(effects
				(font
					(size 1.27 1.27)
				)
			)
		)
		(duplicate_pad_numbers_are_jumpers no)
		(fp_poly
			(pts
				(xy -0.2794 -0.1016) (xy 0.2794 -0.1016) (xy 0.2794 0.9906) (xy -0.2794 0.9906)
			)
			(stroke
				(width 0)
				(type default)
			)
			(fill no)
			(layer "F.CrtYd")
		)
		(fp_line
			(start 0.2794 0.9906)
			(end 0.2794 -0.1016)
			(stroke
				(width 0.1)
				(type default)
			)
			(layer "F.Fab")
		)
		(fp_line
			(start 0.2794 -0.1016)
			(end -0.2794 -0.1016)
			(stroke
				(width 0.1)
				(type default)
			)
			(layer "F.Fab")
		)
		(fp_line
			(start -0.2794 0.9906)
			(end 0.2794 0.9906)
			(stroke
				(width 0.1)
				(type default)
			)
			(layer "F.Fab")
		)
		(fp_line
			(start -0.2794 -0.1016)
			(end -0.2794 0.9906)
			(stroke
				(width 0.1)
				(type default)
			)
			(layer "F.Fab")
		)
		(pad "1" smd rect
			(at 0 0 180)
			(size 0.508 0.508)
			(layers "F.Cu" "F.Mask" "F.Paste")
			(net "P3V3_STBY")
		)
		(pad "2" smd rect
			(at 0 0.889 180)
			(size 0.508 0.508)
			(layers "F.Cu" "F.Mask" "F.Paste")
			(net "PCA9554_A2")
		)
		(zone
			(layer "F.Cu")
			(hatch none 0.5)
			(connect_pads
				(clearance 0)
			)
			(min_thickness 0.25)
			(keepout
				(tracks not_allowed)
				(vias allowed)
				(pads allowed)
				(copperpour not_allowed)
				(footprints allowed)
			)
			(placement
				(enabled no)
				(sheetname "")
			)
			(fill
				(thermal_gap 0.5)
				(thermal_bridge_width 0.5)
				(island_removal_mode 0)
			)
			(polygon
				(pts
					(xy 434.086 -14.859) (xy 433.578 -14.859) (xy 433.578 -14.478) (xy 434.086 -14.478)
				)
			)
		)
		(zone
			(layer "F.Cu")
			(hatch none 0.5)
			(connect_pads
				(clearance 0)
			)
			(min_thickness 0.25)
			(keepout
				(tracks allowed)
				(vias not_allowed)
				(pads allowed)
				(copperpour not_allowed)
				(footprints allowed)
			)
			(placement
				(enabled no)
				(sheetname "")
			)
			(fill
				(thermal_gap 0.5)
				(thermal_bridge_width 0.5)
				(island_removal_mode 0)
			)
			(polygon
				(pts
					(xy 434.086 -14.478) (xy 433.578 -14.478) (xy 433.578 -14.859) (xy 434.086 -14.859)
				)
			)
		)
	)
	(footprint ""
		(layer "F.Cu")
		(at 346.3671 1.741678 -90)
		(property "Reference" "EU7G3"
			(at 3.675888 2.504694 0)
			(unlocked yes)
			(layer "F.SilkS")
			(effects
				(font
					(size 0.7874 0.5842)
					(thickness 0.1524)
				)
			)
		)
		(property "Value" ""
			(at 0 0 270)
			(layer "F.Fab")
			(effects
				(font
					(size 1.27 1.27)
				)
			)
		)
		(duplicate_pad_numbers_are_jumpers no)
		(fp_line
			(start -3.0099 3.429)
			(end -3.0099 -3.5052)
			(stroke
				(width 0.1524)
				(type default)
			)
			(layer "F.SilkS")
		)
		(fp_line
			(start 2.9718 3.429)
			(end -3.0099 3.429)
			(stroke
				(width 0.1524)
				(type default)
			)
			(layer "F.SilkS")
		)
		(fp_line
			(start -3.0099 -3.5052)
			(end 2.9718 -3.5052)
			(stroke
				(width 0.1524)
				(type default)
			)
			(layer "F.SilkS")
		)
		(fp_line
			(start 2.9718 -3.5052)
			(end 2.9718 3.429)
			(stroke
				(width 0.1524)
				(type default)
			)
			(layer "F.SilkS")
		)
		(fp_circle
			(center -3.057398 -2.678684)
			(end -3.057398 -2.805684)
			(stroke
				(width 0.254)
				(type default)
			)
			(fill no)
			(layer "F.SilkS")
		)
		(fp_poly
			(pts
				(xy -2.9972 -3.4925) (xy -2.9972 -2.6924) (xy -2.1971 -3.4925)
			)
			(stroke
				(width 0)
				(type default)
			)
			(fill yes)
			(layer "F.SilkS")
		)
		(fp_poly
			(pts
				(xy -2.549906 -3.050032) (xy -2.549906 3.050032) (xy 2.549906 3.050032) (xy 2.549906 -3.050032)
			)
			(stroke
				(width 0)
				(type default)
			)
			(fill no)
			(layer "F.CrtYd")
		)
		(fp_line
			(start -2.549906 3.050032)
			(end -2.549906 -3.050032)
			(stroke
				(width 0.1)
				(type default)
			)
			(layer "F.Fab")
		)
		(fp_line
			(start 2.549906 3.050032)
			(end -2.549906 3.050032)
			(stroke
				(width 0.1)
				(type default)
			)
			(layer "F.Fab")
		)
		(fp_line
			(start -2.549906 -3.050032)
			(end 2.549906 -3.050032)
			(stroke
				(width 0.1)
				(type default)
			)
			(layer "F.Fab")
		)
		(fp_line
			(start 2.549906 -3.050032)
			(end 2.549906 3.050032)
			(stroke
				(width 0.1)
				(type default)
			)
			(layer "F.Fab")
		)
		(fp_circle
			(center -3.057398 -2.678684)
			(end -3.057398 -2.805684)
			(stroke
				(width 0.254)
				(type default)
			)
			(fill no)
			(layer "F.Fab")
		)
		(pad "1" smd rect
			(at -2.39522 -2.279904 270)
			(size 0.7112 0.254)
			(layers "F.Cu" "F.Mask" "F.Paste")
			(net "PVDDQ_ABC")
		)
		(pad "2" smd rect
			(at -2.39522 -1.83007 270)
			(size 0.7112 0.254)
			(layers "F.Cu" "F.Mask" "F.Paste")
			(net "GND")
		)
		(pad "3" smd rect
			(at -2.39522 -1.379982 270)
			(size 0.7112 0.254)
			(layers "F.Cu" "F.Mask" "F.Paste")
			(net "VR_PVDDQ_ABC_PH2_VCIN")
		)
		(pad "4" smd rect
			(at -2.39522 -0.929894 270)
			(size 0.7112 0.254)
			(layers "F.Cu" "F.Mask" "F.Paste")
			(net "P5V_STBY")
		)
		(pad "5" smd rect
			(at -2.39522 -0.48006 270)
			(size 0.7112 0.254)
			(layers "F.Cu" "F.Mask" "F.Paste")
			(net "GND")
		)
		(pad "6" smd rect
			(at -2.39522 -0.029972 270)
			(size 0.7112 0.254)
			(layers "F.Cu" "F.Mask" "F.Paste")
			(net "TP_PVDDQ_ABC_PH2_GL_0")
		)
		(pad "7" smd custom
			(at 0.016764 1.145032 270)
			(size 0.53975 0.53975)
			(layers "F.Cu" "F.Mask" "F.Paste")
			(net "GND")
			(options
				(clearance outline)
				(anchor circle)
			)
			(primitives
				(gr_poly
					(pts
						(xy -2.7051 1.0795) (xy -2.7051 -0.3683) (xy -0.9271 -0.3683) (xy -0.9271 -1.0795) (xy 2.7051 -1.0795)
						(xy 2.7051 1.0795)
					)
					(width 0)
					(fill yes)
				)
			)
		)
		(pad "10" smd rect
			(at -0.008382 2.874772 270)
			(size 4.3434 0.6096)
			(layers "F.Cu" "F.Mask" "F.Paste")
			(net "VR_PVDDQ_ABC_PH2_SW")
		)
		(pad "25" smd rect
			(at 1.548384 -1.283208 270)
			(size 2.3368 2.0066)
			(layers "F.Cu" "F.Mask" "F.Paste")
			(net "VR_FET_SW_P12V_STBY_PVDDQ_ABC")
		)
		(pad "30" smd rect
			(at 2.050034 -2.895092 270)
			(size 0.254 0.7112)
			(layers "F.Cu" "F.Mask" "F.Paste")
			(net "VR_FET_SW_P12V_STBY_PVDDQ_ABC")
		)
		(pad "31" smd rect
			(at 1.599946 -2.895092 270)
			(size 0.254 0.7112)
			(layers "F.Cu" "F.Mask" "F.Paste")
			(net "Net_369")
		)
		(pad "32" smd rect
			(at 1.150112 -2.895092 270)
			(size 0.254 0.7112)
			(layers "F.Cu" "F.Mask" "F.Paste")
			(net "VR_PVDDQ_ABC_PH2_PHASE")
		)
		(pad "33" smd rect
			(at 0.700024 -2.895092 270)
			(size 0.254 0.7112)
			(layers "F.Cu" "F.Mask" "F.Paste")
			(net "VR_PVDDQ_ABC_PH2_BOOT_R")
		)
		(pad "34" smd rect
			(at 0.249936 -2.895092 270)
			(size 0.254 0.7112)
			(layers "F.Cu" "F.Mask" "F.Paste")
			(net "VR_PVDDQ_ABC_PWM2")
		)
		(pad "35" smd rect
			(at -0.199898 -2.895092 270)
			(size 0.254 0.7112)
			(layers "F.Cu" "F.Mask" "F.Paste")
			(net "P5V_STBY")
		)
		(pad "36" smd rect
			(at -0.649986 -2.895092 270)
			(size 0.254 0.7112)
			(layers "F.Cu" "F.Mask" "F.Paste")
			(net "A_TSENSE_PVDDQ_ABC")
		)
		(pad "37" smd rect
			(at -1.100074 -2.895092 270)
			(size 0.254 0.7112)
			(layers "F.Cu" "F.Mask" "F.Paste")
			(net "VR_PVDDQ_ABC_PH2_OCSET")
		)
		(pad "38" smd rect
			(at -1.549908 -2.895092 270)
			(size 0.254 0.7112)
			(layers "F.Cu" "F.Mask" "F.Paste")
			(net "ISENSE_PVDDQ_ABC_PH2_IMON")
		)
		(pad "39" smd rect
			(at -1.999996 -2.895092 270)
			(size 0.254 0.7112)
			(layers "F.Cu" "F.Mask" "F.Paste")
			(net "VR_PVDDQ_ABC_AIREF2")
		)
		(pad "40" smd rect
			(at -0.871728 -1.283208 270)
			(size 1.8034 2.0066)
			(layers "F.Cu" "F.Mask" "F.Paste")
			(net "GND")
		)
		(pad "41" smd rect
			(at -1.533906 0.247904 270)
			(size 0.508 0.3556)
			(layers "F.Cu" "F.Mask" "F.Paste")
			(net "TP_PVDDQ_ABC_PH2_GL_1")
		)
	)
	(footprint ""
		(layer "F.Cu")
		(at 10.166096 -124.854208 -90)
		(property "Reference" "R12W17"
			(at 0 0 270)
			(layer "F.SilkS")
			(hide yes)
			(effects
				(font
					(size 1.27 1.27)
				)
			)
		)
		(property "Value" "*"
			(at 0 -8.9535 270)
			(unlocked yes)
			(layer "F.Fab")
			(hide yes)
			(effects
				(font
					(size 1.27 1.016)
					(thickness 0.1524)
				)
			)
		)
		(property "Device Type" "665KR5B-1-GP_SMD-RG3-665KR5B-1A"
			(at 0 -10.6299 270)
			(unlocked yes)
			(layer "F.Fab")
			(hide yes)
			(effects
				(font
					(size 1.27 1.016)
					(thickness 0.1524)
				)
			)
		)
		(duplicate_pad_numbers_are_jumpers no)
		(fp_line
			(start -0.889 1.7018)
			(end 0.889 1.7018)
			(stroke
				(width 0.1524)
				(type default)
			)
			(layer "F.SilkS")
		)
		(fp_line
			(start 0.889 1.7018)
			(end 0.889 -0.508)
			(stroke
				(width 0.1524)
				(type default)
			)
			(layer "F.SilkS")
		)
		(fp_line
			(start -0.889 0.0762)
			(end -0.889 1.7018)
			(stroke
				(width 0.1524)
				(type default)
			)
			(layer "F.SilkS")
		)
		(fp_line
			(start -0.889 -1.7018)
			(end -0.889 0.2794)
			(stroke
				(width 0.1524)
				(type default)
			)
			(layer "F.SilkS")
		)
		(fp_line
			(start 0.889 -1.7018)
			(end 0.889 -0.381)
			(stroke
				(width 0.1524)
				(type default)
			)
			(layer "F.SilkS")
		)
		(fp_line
			(start 0.889 -1.7018)
			(end -0.889 -1.7018)
			(stroke
				(width 0.1524)
				(type default)
			)
			(layer "F.SilkS")
		)
		(fp_poly
			(pts
				(xy 0.9652 -1.778) (xy 0.9652 1.778) (xy -0.9652 1.778) (xy -0.9652 -1.778)
			)
			(stroke
				(width 0)
				(type default)
			)
			(fill no)
			(layer "F.CrtYd")
		)
		(fp_rect
			(start -0.9652 1.778)
			(end 0.9652 -1.778)
			(stroke
				(width 0)
				(type default)
			)
			(fill no)
			(layer "F.Fab")
		)
		(pad "1" smd rect
			(at 0 -0.9652 270)
			(size 1.397 1.143)
			(layers "F.Cu" "F.Mask" "F.Paste")
			(net "P12V_NVDIMM_KLM_D")
		)
		(pad "2" smd rect
			(at 0 0.9652 270)
			(size 1.397 1.143)
			(layers "F.Cu" "F.Mask" "F.Paste")
			(net "VR_PVDDQ_KLM_VINSEN")
		)
	)
	(footprint ""
		(layer "F.Cu")
		(at 480.845876 3.820668 -90)
		(property "Reference" "R9G17"
			(at 0 0 270)
			(layer "F.SilkS")
			(hide yes)
			(effects
				(font
					(size 1.27 1.27)
				)
			)
		)
		(property "Value" ""
			(at 0 0 270)
			(layer "F.Fab")
			(effects
				(font
					(size 1.27 1.27)
				)
			)
		)
		(duplicate_pad_numbers_are_jumpers no)
		(fp_poly
			(pts
				(xy -0.2794 -0.1016) (xy 0.2794 -0.1016) (xy 0.2794 0.9906) (xy -0.2794 0.9906)
			)
			(stroke
				(width 0)
				(type default)
			)
			(fill no)
			(layer "F.CrtYd")
		)
		(fp_line
			(start -0.2794 0.9906)
			(end 0.2794 0.9906)
			(stroke
				(width 0.1)
				(type default)
			)
			(layer "F.Fab")
		)
		(fp_line
			(start 0.2794 0.9906)
			(end 0.2794 -0.1016)
			(stroke
				(width 0.1)
				(type default)
			)
			(layer "F.Fab")
		)
		(fp_line
			(start -0.2794 -0.1016)
			(end -0.2794 0.9906)
			(stroke
				(width 0.1)
				(type default)
			)
			(layer "F.Fab")
		)
		(fp_line
			(start 0.2794 -0.1016)
			(end -0.2794 -0.1016)
			(stroke
				(width 0.1)
				(type default)
			)
			(layer "F.Fab")
		)
		(pad "1" smd rect
			(at 0 0 270)
			(size 0.508 0.508)
			(layers "F.Cu" "F.Mask" "F.Paste")
			(net "NIC_SET_N_MDI_2_DN")
		)
		(pad "2" smd rect
			(at 0 0.889 270)
			(size 0.508 0.508)
			(layers "F.Cu" "F.Mask" "F.Paste")
			(net "NIC_MDI_SPRV_RJ45_2_R_DN")
		)
		(zone
			(layer "F.Cu")
			(hatch none 0.5)
			(connect_pads
				(clearance 0)
			)
			(min_thickness 0.25)
			(keepout
				(tracks not_allowed)
				(vias allowed)
				(pads allowed)
				(copperpour not_allowed)
				(footprints allowed)
			)
			(placement
				(enabled no)
				(sheetname "")
			)
			(fill
				(thermal_gap 0.5)
				(thermal_bridge_width 0.5)
				(island_removal_mode 0)
			)
			(polygon
				(pts
					(xy 480.210876 3.566668) (xy 480.210876 4.074668) (xy 480.591876 4.074668) (xy 480.591876 3.566668)
				)
			)
		)
		(zone
			(layer "F.Cu")
			(hatch none 0.5)
			(connect_pads
				(clearance 0)
			)
			(min_thickness 0.25)
			(keepout
				(tracks allowed)
				(vias not_allowed)
				(pads allowed)
				(copperpour not_allowed)
				(footprints allowed)
			)
			(placement
				(enabled no)
				(sheetname "")
			)
			(fill
				(thermal_gap 0.5)
				(thermal_bridge_width 0.5)
				(island_removal_mode 0)
			)
			(polygon
				(pts
					(xy 480.591876 3.566668) (xy 480.591876 4.074668) (xy 480.210876 4.074668) (xy 480.210876 3.566668)
				)
			)
		)
	)
	(footprint ""
		(layer "F.Cu")
		(at 175.26 -149.3012 -90)
		(property "Reference" "R4A5"
			(at 0 0 270)
			(layer "F.SilkS")
			(hide yes)
			(effects
				(font
					(size 1.27 1.27)
				)
			)
		)
		(property "Value" ""
			(at 0 0 270)
			(layer "F.Fab")
			(effects
				(font
					(size 1.27 1.27)
				)
			)
		)
		(duplicate_pad_numbers_are_jumpers no)
		(fp_rect
			(start 0.2794 -0.1016)
			(end -0.2794 0.9906)
			(stroke
				(width 0)
				(type default)
			)
			(fill no)
			(layer "F.CrtYd")
		)
		(fp_line
			(start -0.2794 0.9906)
			(end 0.2794 0.9906)
			(stroke
				(width 0.1)
				(type default)
			)
			(layer "F.Fab")
		)
		(fp_line
			(start 0.2794 0.9906)
			(end 0.2794 -0.1016)
			(stroke
				(width 0.1)
				(type default)
			)
			(layer "F.Fab")
		)
		(fp_line
			(start -0.2794 -0.1016)
			(end -0.2794 0.9906)
			(stroke
				(width 0.1)
				(type default)
			)
			(layer "F.Fab")
		)
		(fp_line
			(start 0.2794 -0.1016)
			(end -0.2794 -0.1016)
			(stroke
				(width 0.1)
				(type default)
			)
			(layer "F.Fab")
		)
		(pad "1" smd rect
			(at 0 0 270)
			(size 0.508 0.508)
			(layers "F.Cu" "F.Mask" "F.Paste")
			(net "P3V3")
		)
		(pad "2" smd rect
			(at 0 0.889 270)
			(size 0.508 0.508)
			(layers "F.Cu" "F.Mask" "F.Paste")
			(net "PWRGD_PVTT_KLM_CPU1_R")
		)
		(zone
			(layer "F.Cu")
			(hatch none 0.5)
			(connect_pads
				(clearance 0)
			)
			(min_thickness 0.25)
			(keepout
				(tracks not_allowed)
				(vias allowed)
				(pads allowed)
				(copperpour not_allowed)
				(footprints allowed)
			)
			(placement
				(enabled no)
				(sheetname "")
			)
			(fill
				(thermal_gap 0.5)
				(thermal_bridge_width 0.5)
				(island_removal_mode 0)
			)
			(polygon
				(pts
					(xy 175.006 -149.0472) (xy 175.006 -149.5552) (xy 174.625 -149.5552) (xy 174.625 -149.0472)
				)
			)
		)
		(zone
			(layer "F.Cu")
			(hatch none 0.5)
			(connect_pads
				(clearance 0)
			)
			(min_thickness 0.25)
			(keepout
				(tracks allowed)
				(vias not_allowed)
				(pads allowed)
				(copperpour not_allowed)
				(footprints allowed)
			)
			(placement
				(enabled no)
				(sheetname "")
			)
			(fill
				(thermal_gap 0.5)
				(thermal_bridge_width 0.5)
				(island_removal_mode 0)
			)
			(polygon
				(pts
					(xy 175.006 -149.0472) (xy 175.006 -149.5552) (xy 174.625 -149.5552) (xy 174.625 -149.0472)
				)
			)
		)
	)
	(footprint ""
		(layer "F.Cu")
		(at 93.30944 -81.573116)
		(property "Reference" "C2D9"
			(at 0 0 0)
			(layer "F.SilkS")
			(hide yes)
			(effects
				(font
					(size 1.27 1.27)
				)
			)
		)
		(property "Value" ""
			(at 0 0 0)
			(layer "F.Fab")
			(effects
				(font
					(size 1.27 1.27)
				)
			)
		)
		(duplicate_pad_numbers_are_jumpers no)
		(fp_poly
			(pts
				(xy -0.4953 -0.2032) (xy 0.4953 -0.2032) (xy 0.4953 1.6002) (xy -0.4953 1.6002)
			)
			(stroke
				(width 0)
				(type default)
			)
			(fill no)
			(layer "F.CrtYd")
		)
		(fp_line
			(start -0.4953 -0.2032)
			(end 0.4953 -0.2032)
			(stroke
				(width 0.1)
				(type default)
			)
			(layer "F.Fab")
		)
		(fp_line
			(start -0.4953 1.6002)
			(end -0.4953 -0.2032)
			(stroke
				(width 0.1)
				(type default)
			)
			(layer "F.Fab")
		)
		(fp_line
			(start 0.4953 -0.2032)
			(end 0.4953 1.6002)
			(stroke
				(width 0.1)
				(type default)
			)
			(layer "F.Fab")
		)
		(fp_line
			(start 0.4953 1.6002)
			(end -0.4953 1.6002)
			(stroke
				(width 0.1)
				(type default)
			)
			(layer "F.Fab")
		)
		(pad "1" smd rect
			(at 0 0)
			(size 0.762 0.889)
			(layers "F.Cu" "F.Mask" "F.Paste")
			(net "PVSA_CPU1")
		)
		(pad "2" smd rect
			(at 0 1.397)
			(size 0.762 0.889)
			(layers "F.Cu" "F.Mask" "F.Paste")
			(net "GND")
		)
		(zone
			(layer "F.Cu")
			(hatch none 0.5)
			(connect_pads
				(clearance 0)
			)
			(min_thickness 0.25)
			(keepout
				(tracks not_allowed)
				(vias allowed)
				(pads allowed)
				(copperpour not_allowed)
				(footprints allowed)
			)
			(placement
				(enabled no)
				(sheetname "")
			)
			(fill
				(thermal_gap 0.5)
				(thermal_bridge_width 0.5)
				(island_removal_mode 0)
			)
			(polygon
				(pts
					(xy 92.92844 -81.128616) (xy 93.69044 -81.128616) (xy 93.69044 -80.620616) (xy 92.92844 -80.620616)
				)
			)
		)
	)
	(footprint ""
		(layer "F.Cu")
		(at 171.958 -14.5796 -90)
		(property "Reference" "L4G1"
			(at 4.953 6.95833 90)
			(unlocked yes)
			(layer "F.SilkS")
			(effects
				(font
					(size 0.7874 0.5842)
					(thickness 0.1524)
				)
				(justify left)
			)
		)
		(property "Value" ""
			(at 0 0 270)
			(layer "F.Fab")
			(effects
				(font
					(size 1.27 1.27)
				)
			)
		)
		(duplicate_pad_numbers_are_jumpers no)
		(fp_line
			(start -3.4036 6.1341)
			(end -3.4036 -0.6731)
			(stroke
				(width 0.1524)
				(type default)
			)
			(layer "F.SilkS")
		)
		(fp_line
			(start -2.5654 6.1341)
			(end -3.4036 6.1341)
			(stroke
				(width 0.1524)
				(type default)
			)
			(layer "F.SilkS")
		)
		(fp_line
			(start 3.4036 6.1341)
			(end 2.5654 6.1341)
			(stroke
				(width 0.1524)
				(type default)
			)
			(layer "F.SilkS")
		)
		(fp_line
			(start -3.4036 -0.6731)
			(end -2.5654 -0.6731)
			(stroke
				(width 0.1524)
				(type default)
			)
			(layer "F.SilkS")
		)
		(fp_line
			(start 2.5654 -0.6731)
			(end 3.4036 -0.6731)
			(stroke
				(width 0.1524)
				(type default)
			)
			(layer "F.SilkS")
		)
		(fp_line
			(start 3.4036 -0.6731)
			(end 3.4036 6.1341)
			(stroke
				(width 0.1524)
				(type default)
			)
			(layer "F.SilkS")
		)
		(fp_rect
			(start 3.4036 6.1341)
			(end -3.4036 -0.6731)
			(stroke
				(width 0)
				(type default)
			)
			(fill no)
			(layer "F.CrtYd")
		)
		(fp_line
			(start -3.4036 6.1341)
			(end -3.4036 -0.6731)
			(stroke
				(width 0.1)
				(type default)
			)
			(layer "F.Fab")
		)
		(fp_line
			(start 3.4036 6.1341)
			(end -3.4036 6.1341)
			(stroke
				(width 0.1)
				(type default)
			)
			(layer "F.Fab")
		)
		(fp_line
			(start -3.4036 -0.6731)
			(end 3.4036 -0.6731)
			(stroke
				(width 0.1)
				(type default)
			)
			(layer "F.Fab")
		)
		(fp_line
			(start 3.4036 -0.6731)
			(end 3.4036 6.1341)
			(stroke
				(width 0.1)
				(type default)
			)
			(layer "F.Fab")
		)
		(pad "1" smd rect
			(at 0 0 270)
			(size 3.556 3.175)
			(layers "F.Cu" "F.Mask" "F.Paste")
			(net "VR_PVPP_GHJ_PHASE")
		)
		(pad "2" smd rect
			(at 0 5.461 270)
			(size 3.556 3.175)
			(layers "F.Cu" "F.Mask" "F.Paste")
			(net "PVPP_GHJ")
		)
	)
	(footprint ""
		(layer "F.Cu")
		(at 176.276 -141.1605 90)
		(property "Reference" "R4A7"
			(at 0 0 90)
			(layer "F.SilkS")
			(hide yes)
			(effects
				(font
					(size 1.27 1.27)
				)
			)
		)
		(property "Value" ""
			(at 0 0 90)
			(layer "F.Fab")
			(effects
				(font
					(size 1.27 1.27)
				)
			)
		)
		(duplicate_pad_numbers_are_jumpers no)
		(fp_poly
			(pts
				(xy -0.2794 -0.1016) (xy 0.2794 -0.1016) (xy 0.2794 0.9906) (xy -0.2794 0.9906)
			)
			(stroke
				(width 0)
				(type default)
			)
			(fill no)
			(layer "F.CrtYd")
		)
		(fp_line
			(start 0.2794 -0.1016)
			(end -0.2794 -0.1016)
			(stroke
				(width 0.1)
				(type default)
			)
			(layer "F.Fab")
		)
		(fp_line
			(start -0.2794 -0.1016)
			(end -0.2794 0.9906)
			(stroke
				(width 0.1)
				(type default)
			)
			(layer "F.Fab")
		)
		(fp_line
			(start 0.2794 0.9906)
			(end 0.2794 -0.1016)
			(stroke
				(width 0.1)
				(type default)
			)
			(layer "F.Fab")
		)
		(fp_line
			(start -0.2794 0.9906)
			(end 0.2794 0.9906)
			(stroke
				(width 0.1)
				(type default)
			)
			(layer "F.Fab")
		)
		(pad "1" smd rect
			(at 0 0 90)
			(size 0.508 0.508)
			(layers "F.Cu" "F.Mask" "F.Paste")
			(net "VR_PVPP_KLM_SNUB")
		)
		(pad "2" smd rect
			(at 0 0.889 90)
			(size 0.508 0.508)
			(layers "F.Cu" "F.Mask" "F.Paste")
			(net "GND")
		)
		(zone
			(layer "F.Cu")
			(hatch none 0.5)
			(connect_pads
				(clearance 0)
			)
			(min_thickness 0.25)
			(keepout
				(tracks allowed)
				(vias not_allowed)
				(pads allowed)
				(copperpour not_allowed)
				(footprints allowed)
			)
			(placement
				(enabled no)
				(sheetname "")
			)
			(fill
				(thermal_gap 0.5)
				(thermal_bridge_width 0.5)
				(island_removal_mode 0)
			)
			(polygon
				(pts
					(xy 176.53 -140.9065) (xy 176.53 -141.4145) (xy 176.911 -141.4145) (xy 176.911 -140.9065)
				)
			)
		)
		(zone
			(layer "F.Cu")
			(hatch none 0.5)
			(connect_pads
				(clearance 0)
			)
			(min_thickness 0.25)
			(keepout
				(tracks not_allowed)
				(vias allowed)
				(pads allowed)
				(copperpour not_allowed)
				(footprints allowed)
			)
			(placement
				(enabled no)
				(sheetname "")
			)
			(fill
				(thermal_gap 0.5)
				(thermal_bridge_width 0.5)
				(island_removal_mode 0)
			)
			(polygon
				(pts
					(xy 176.911 -140.9065) (xy 176.911 -141.4145) (xy 176.53 -141.4145) (xy 176.53 -140.9065)
				)
			)
		)
	)
	(footprint ""
		(layer "F.Cu")
		(at 426.5295 -129.794 -90)
		(property "Reference" "R8B7"
			(at 0 0 270)
			(layer "F.SilkS")
			(hide yes)
			(effects
				(font
					(size 1.27 1.27)
				)
			)
		)
		(property "Value" ""
			(at 0 0 270)
			(layer "F.Fab")
			(effects
				(font
					(size 1.27 1.27)
				)
			)
		)
		(duplicate_pad_numbers_are_jumpers no)
		(fp_poly
			(pts
				(xy -0.2794 -0.1016) (xy 0.2794 -0.1016) (xy 0.2794 0.9906) (xy -0.2794 0.9906)
			)
			(stroke
				(width 0)
				(type default)
			)
			(fill no)
			(layer "F.CrtYd")
		)
		(fp_line
			(start -0.2794 0.9906)
			(end 0.2794 0.9906)
			(stroke
				(width 0.1)
				(type default)
			)
			(layer "F.Fab")
		)
		(fp_line
			(start 0.2794 0.9906)
			(end 0.2794 -0.1016)
			(stroke
				(width 0.1)
				(type default)
			)
			(layer "F.Fab")
		)
		(fp_line
			(start -0.2794 -0.1016)
			(end -0.2794 0.9906)
			(stroke
				(width 0.1)
				(type default)
			)
			(layer "F.Fab")
		)
		(fp_line
			(start 0.2794 -0.1016)
			(end -0.2794 -0.1016)
			(stroke
				(width 0.1)
				(type default)
			)
			(layer "F.Fab")
		)
		(pad "1" smd rect
			(at 0 0 270)
			(size 0.508 0.508)
			(layers "F.Cu" "F.Mask" "F.Paste")
			(net "PVPP_ABC")
		)
		(pad "2" smd rect
			(at 0 0.889 270)
			(size 0.508 0.508)
			(layers "F.Cu" "F.Mask" "F.Paste")
			(net "SMB_HFI0_CPU0_LVC2_SDA")
		)
		(zone
			(layer "F.Cu")
			(hatch none 0.5)
			(connect_pads
				(clearance 0)
			)
			(min_thickness 0.25)
			(keepout
				(tracks not_allowed)
				(vias allowed)
				(pads allowed)
				(copperpour not_allowed)
				(footprints allowed)
			)
			(placement
				(enabled no)
				(sheetname "")
			)
			(fill
				(thermal_gap 0.5)
				(thermal_bridge_width 0.5)
				(island_removal_mode 0)
			)
			(polygon
				(pts
					(xy 425.8945 -130.048) (xy 425.8945 -129.54) (xy 426.2755 -129.54) (xy 426.2755 -130.048)
				)
			)
		)
		(zone
			(layer "F.Cu")
			(hatch none 0.5)
			(connect_pads
				(clearance 0)
			)
			(min_thickness 0.25)
			(keepout
				(tracks allowed)
				(vias not_allowed)
				(pads allowed)
				(copperpour not_allowed)
				(footprints allowed)
			)
			(placement
				(enabled no)
				(sheetname "")
			)
			(fill
				(thermal_gap 0.5)
				(thermal_bridge_width 0.5)
				(island_removal_mode 0)
			)
			(polygon
				(pts
					(xy 426.2755 -130.048) (xy 426.2755 -129.54) (xy 425.8945 -129.54) (xy 425.8945 -130.048)
				)
			)
		)
	)
	(footprint ""
		(layer "F.Cu")
		(at 433.1335 -11.4046 180)
		(property "Reference" "C6W14"
			(at -0.8382 -0.67818 180)
			(unlocked yes)
			(layer "F.SilkS")
			(effects
				(font
					(size 0.4064 0.254)
					(thickness 0.1524)
				)
				(justify left)
			)
		)
		(property "Value" ""
			(at 0 0 180)
			(layer "F.Fab")
			(effects
				(font
					(size 1.27 1.27)
				)
			)
		)
		(duplicate_pad_numbers_are_jumpers no)
		(fp_poly
			(pts
				(xy 0.3048 -0.1016) (xy 0.3048 0.9906) (xy -0.3048 0.9906) (xy -0.3048 -0.1016)
			)
			(stroke
				(width 0)
				(type default)
			)
			(fill no)
			(layer "F.CrtYd")
		)
		(fp_line
			(start 0.3048 0.9906)
			(end 0.3048 -0.1016)
			(stroke
				(width 0.1)
				(type default)
			)
			(layer "F.Fab")
		)
		(fp_line
			(start 0.3048 -0.1016)
			(end -0.3048 -0.1016)
			(stroke
				(width 0.1)
				(type default)
			)
			(layer "F.Fab")
		)
		(fp_line
			(start -0.3048 0.9906)
			(end 0.3048 0.9906)
			(stroke
				(width 0.1)
				(type default)
			)
			(layer "F.Fab")
		)
		(fp_line
			(start -0.3048 -0.1016)
			(end -0.3048 0.9906)
			(stroke
				(width 0.1)
				(type default)
			)
			(layer "F.Fab")
		)
		(pad "1" smd rect
			(at 0 0 180)
			(size 0.508 0.508)
			(layers "F.Cu" "F.Mask" "F.Paste")
			(net "P3V3_STBY")
		)
		(pad "2" smd rect
			(at 0 0.889 180)
			(size 0.508 0.508)
			(layers "F.Cu" "F.Mask" "F.Paste")
			(net "GND")
		)
		(zone
			(layer "F.Cu")
			(hatch none 0.5)
			(connect_pads
				(clearance 0)
			)
			(min_thickness 0.25)
			(keepout
				(tracks not_allowed)
				(vias allowed)
				(pads allowed)
				(copperpour not_allowed)
				(footprints allowed)
			)
			(placement
				(enabled no)
				(sheetname "")
			)
			(fill
				(thermal_gap 0.5)
				(thermal_bridge_width 0.5)
				(island_removal_mode 0)
			)
			(polygon
				(pts
					(xy 433.3875 -12.0396) (xy 432.8795 -12.0396) (xy 432.8795 -11.6586) (xy 433.3875 -11.6586)
				)
			)
		)
		(zone
			(layer "F.Cu")
			(hatch none 0.5)
			(connect_pads
				(clearance 0)
			)
			(min_thickness 0.25)
			(keepout
				(tracks allowed)
				(vias not_allowed)
				(pads allowed)
				(copperpour not_allowed)
				(footprints allowed)
			)
			(placement
				(enabled no)
				(sheetname "")
			)
			(fill
				(thermal_gap 0.5)
				(thermal_bridge_width 0.5)
				(island_removal_mode 0)
			)
			(polygon
				(pts
					(xy 433.3875 -11.6586) (xy 432.8795 -11.6586) (xy 432.8795 -12.0396) (xy 433.3875 -12.0396)
				)
			)
		)
	)
	(footprint ""
		(layer "F.Cu")
		(at 336.509868 -130.455162 90)
		(property "Reference" "C7B30"
			(at 0 0 90)
			(layer "F.SilkS")
			(hide yes)
			(effects
				(font
					(size 1.27 1.27)
				)
			)
		)
		(property "Value" ""
			(at 0 0 90)
			(layer "F.Fab")
			(effects
				(font
					(size 1.27 1.27)
				)
			)
		)
		(duplicate_pad_numbers_are_jumpers no)
		(fp_poly
			(pts
				(xy -0.4953 -0.2032) (xy 0.4953 -0.2032) (xy 0.4953 1.6002) (xy -0.4953 1.6002)
			)
			(stroke
				(width 0)
				(type default)
			)
			(fill no)
			(layer "F.CrtYd")
		)
		(fp_line
			(start 0.4953 -0.2032)
			(end 0.4953 1.6002)
			(stroke
				(width 0.1)
				(type default)
			)
			(layer "F.Fab")
		)
		(fp_line
			(start -0.4953 -0.2032)
			(end 0.4953 -0.2032)
			(stroke
				(width 0.1)
				(type default)
			)
			(layer "F.Fab")
		)
		(fp_line
			(start 0.4953 1.6002)
			(end -0.4953 1.6002)
			(stroke
				(width 0.1)
				(type default)
			)
			(layer "F.Fab")
		)
		(fp_line
			(start -0.4953 1.6002)
			(end -0.4953 -0.2032)
			(stroke
				(width 0.1)
				(type default)
			)
			(layer "F.Fab")
		)
		(pad "1" smd rect
			(at 0 0 90)
			(size 0.762 0.889)
			(layers "F.Cu" "F.Mask" "F.Paste")
			(net "VR_PVPP_DEF_PHASE")
		)
		(pad "2" smd rect
			(at 0 1.397 90)
			(size 0.762 0.889)
			(layers "F.Cu" "F.Mask" "F.Paste")
			(net "VR_PVPP_DEF_BOOT_R")
		)
		(zone
			(layer "F.Cu")
			(hatch none 0.5)
			(connect_pads
				(clearance 0)
			)
			(min_thickness 0.25)
			(keepout
				(tracks not_allowed)
				(vias allowed)
				(pads allowed)
				(copperpour not_allowed)
				(footprints allowed)
			)
			(placement
				(enabled no)
				(sheetname "")
			)
			(fill
				(thermal_gap 0.5)
				(thermal_bridge_width 0.5)
				(island_removal_mode 0)
			)
			(polygon
				(pts
					(xy 336.954368 -130.074162) (xy 336.954368 -130.836162) (xy 337.462368 -130.836162) (xy 337.462368 -130.074162)
				)
			)
		)
	)
	(footprint ""
		(layer "F.Cu")
		(at 437.34101 -47.481998 90)
		(property "Reference" "J8E3"
			(at 6.402832 -4.049014 0)
			(unlocked yes)
			(layer "F.SilkS")
			(effects
				(font
					(size 0.7874 0.5842)
					(thickness 0.1524)
				)
				(justify left)
			)
		)
		(property "Value" ""
			(at 0 0 90)
			(layer "F.Fab")
			(effects
				(font
					(size 1.27 1.27)
				)
			)
		)
		(duplicate_pad_numbers_are_jumpers no)
		(fp_line
			(start 5.25907 -3.374898)
			(end 5.25907 -0.90805)
			(stroke
				(width 0.151892)
				(type default)
			)
			(layer "F.SilkS")
		)
		(fp_line
			(start 3.116072 -3.374898)
			(end 5.25907 -3.374898)
			(stroke
				(width 0.151892)
				(type default)
			)
			(layer "F.SilkS")
		)
		(fp_line
			(start -0.878078 -3.374898)
			(end 1.32588 -3.374898)
			(stroke
				(width 0.151892)
				(type default)
			)
			(layer "F.SilkS")
		)
		(fp_line
			(start -0.878078 -0.932942)
			(end -0.878078 -3.374898)
			(stroke
				(width 0.151892)
				(type default)
			)
			(layer "F.SilkS")
		)
		(fp_line
			(start 5.272024 32.109918)
			(end 5.272024 34.574988)
			(stroke
				(width 0.151892)
				(type default)
			)
			(layer "F.SilkS")
		)
		(fp_line
			(start 5.272024 34.574988)
			(end 3.228086 34.574988)
			(stroke
				(width 0.151892)
				(type default)
			)
			(layer "F.SilkS")
		)
		(fp_line
			(start 1.178052 34.574988)
			(end -0.877824 34.574988)
			(stroke
				(width 0.151892)
				(type default)
			)
			(layer "F.SilkS")
		)
		(fp_line
			(start -0.877824 34.574988)
			(end -0.877824 32.175958)
			(stroke
				(width 0.151892)
				(type default)
			)
			(layer "F.SilkS")
		)
		(fp_poly
			(pts
				(xy -2.36347 0.692404) (xy -2.36347 -0.323596) (xy -1.09347 0.184404)
			)
			(stroke
				(width 0)
				(type default)
			)
			(fill yes)
			(layer "F.SilkS")
		)
		(fp_rect
			(start -0.878078 34.574988)
			(end 5.272024 -3.374898)
			(stroke
				(width 0)
				(type default)
			)
			(fill no)
			(layer "F.CrtYd")
		)
		(fp_line
			(start 5.272024 -3.374898)
			(end 5.272024 34.574988)
			(stroke
				(width 0.1)
				(type default)
			)
			(layer "F.Fab")
		)
		(fp_line
			(start -0.878078 -3.374898)
			(end 5.272024 -3.374898)
			(stroke
				(width 0.1)
				(type default)
			)
			(layer "F.Fab")
		)
		(fp_line
			(start 5.272024 34.574988)
			(end -0.878078 34.574988)
			(stroke
				(width 0.1)
				(type default)
			)
			(layer "F.Fab")
		)
		(fp_line
			(start -0.878078 34.574988)
			(end -0.878078 -3.374898)
			(stroke
				(width 0.1)
				(type default)
			)
			(layer "F.Fab")
		)
		(fp_text user "2"
			(at 6.2357 -0.108712 0)
			(unlocked yes)
			(layer "F.SilkS")
			(effects
				(font
					(size 0.7874 0.5842)
					(thickness 0.1524)
				)
				(justify left)
			)
		)
		(fp_text user " 79"
			(at -4.289552 31.10357 90)
			(unlocked yes)
			(layer "F.SilkS")
			(effects
				(font
					(size 0.7874 0.5842)
					(thickness 0.1524)
				)
				(justify left)
			)
		)
		(fp_text user "80"
			(at 6.085332 32.052006 0)
			(unlocked yes)
			(layer "F.SilkS")
			(effects
				(font
					(size 0.7874 0.5842)
					(thickness 0.1524)
				)
				(justify left)
			)
		)
		(fp_text user "2"
			(at 6.496812 -1.275715 90)
			(unlocked yes)
			(layer "F.Fab")
			(effects
				(font
					(size 0.8001 0.598932)
					(thickness 0.000001)
				)
				(justify left)
			)
		)
		(fp_text user "80"
			(at 6.04901 31.270067 90)
			(unlocked yes)
			(layer "F.Fab")
			(effects
				(font
					(size 0.8001 0.598932)
					(thickness 0.000001)
				)
				(justify left)
			)
		)
		(fp_text user " 79"
			(at -2.219198 32.530161 90)
			(unlocked yes)
			(layer "F.Fab")
			(effects
				(font
					(size 0.8001 0.598932)
					(thickness 0.000001)
				)
				(justify left)
			)
		)
		(pad "" np_thru_hole circle
			(at 2.1971 -2.489962 90)
			(size 0.254 0.254)
			(drill 1.3716)
			(layers "*.Cu" "*.Mask")
			(clearance 0.8763)
			(thermal_gap 0.8763)
		)
		(pad "" np_thru_hole circle
			(at 2.1971 33.702244 90)
			(size 0.254 0.254)
			(drill 1.016)
			(layers "*.Cu" "*.Mask")
			(clearance 0.6985)
			(thermal_gap 0.6985)
		)
		(pad "1" smd rect
			(at 0 0 90)
			(size 2.0066 0.508)
			(layers "F.Cu" "F.Mask" "F.Paste")
			(net "FM_MEZZB_PRSNT1_N")
		)
		(pad "2" smd rect
			(at 4.393946 0 90)
			(size 2.0066 0.508)
			(layers "F.Cu" "F.Mask" "F.Paste")
			(net "P12V_STBY")
		)
		(pad "3" smd rect
			(at 0 0.8001 90)
			(size 2.0066 0.508)
			(layers "F.Cu" "F.Mask" "F.Paste")
			(net "GND")
		)
		(pad "4" smd rect
			(at 4.393946 0.8001 90)
			(size 2.0066 0.508)
			(layers "F.Cu" "F.Mask" "F.Paste")
			(net "P12V_STBY")
		)
		(pad "5" smd rect
			(at 0 1.599946 90)
			(size 2.0066 0.508)
			(layers "F.Cu" "F.Mask" "F.Paste")
			(net "P3E_CPU0_PE3_OCP_RXP<7>")
		)
		(pad "6" smd rect
			(at 4.393946 1.599946 90)
			(size 2.0066 0.508)
			(layers "F.Cu" "F.Mask" "F.Paste")
			(net "TP_RSVD_B1")
		)
		(pad "7" smd rect
			(at 0 2.400046 90)
			(size 2.0066 0.508)
			(layers "F.Cu" "F.Mask" "F.Paste")
			(net "P3E_CPU0_PE3_OCP_RXN<7>")
		)
		(pad "8" smd rect
			(at 4.393946 2.400046 90)
			(size 2.0066 0.508)
			(layers "F.Cu" "F.Mask" "F.Paste")
			(net "GND")
		)
		(pad "9" smd rect
			(at 0 3.199892 90)
			(size 2.0066 0.508)
			(layers "F.Cu" "F.Mask" "F.Paste")
			(net "GND")
		)
		(pad "10" smd rect
			(at 4.393946 3.199892 90)
			(size 2.0066 0.508)
			(layers "F.Cu" "F.Mask" "F.Paste")
			(net "P3E_OCP_CPU0_PE3_C_TXP<7>")
		)
		(pad "11" smd rect
			(at 0 3.999992 90)
			(size 2.0066 0.508)
			(layers "F.Cu" "F.Mask" "F.Paste")
			(net "GND")
		)
		(pad "12" smd rect
			(at 4.393946 3.999992 90)
			(size 2.0066 0.508)
			(layers "F.Cu" "F.Mask" "F.Paste")
			(net "P3E_OCP_CPU0_PE3_C_TXN<7>")
		)
		(pad "13" smd rect
			(at 0 4.800092 90)
			(size 2.0066 0.508)
			(layers "F.Cu" "F.Mask" "F.Paste")
			(net "P3E_CPU0_PE3_OCP_RXN<6>")
		)
		(pad "14" smd rect
			(at 4.393946 4.800092 90)
			(size 2.0066 0.508)
			(layers "F.Cu" "F.Mask" "F.Paste")
			(net "GND")
		)
		(pad "15" smd rect
			(at 0 5.599938 90)
			(size 2.0066 0.508)
			(layers "F.Cu" "F.Mask" "F.Paste")
			(net "P3E_CPU0_PE3_OCP_RXP<6>")
		)
		(pad "16" smd rect
			(at 4.393946 5.599938 90)
			(size 2.0066 0.508)
			(layers "F.Cu" "F.Mask" "F.Paste")
			(net "GND")
		)
		(pad "17" smd rect
			(at 0 6.400038 90)
			(size 2.0066 0.508)
			(layers "F.Cu" "F.Mask" "F.Paste")
			(net "GND")
		)
		(pad "18" smd rect
			(at 4.393946 6.400038 90)
			(size 2.0066 0.508)
			(layers "F.Cu" "F.Mask" "F.Paste")
			(net "P3E_OCP_CPU0_PE3_C_TXP<6>")
		)
		(pad "19" smd rect
			(at 0 7.199884 90)
			(size 2.0066 0.508)
			(layers "F.Cu" "F.Mask" "F.Paste")
			(net "GND")
		)
		(pad "20" smd rect
			(at 4.393946 7.199884 90)
			(size 2.0066 0.508)
			(layers "F.Cu" "F.Mask" "F.Paste")
			(net "P3E_OCP_CPU0_PE3_C_TXN<6>")
		)
		(pad "21" smd rect
			(at 0 7.999984 90)
			(size 2.0066 0.508)
			(layers "F.Cu" "F.Mask" "F.Paste")
			(net "P3E_CPU0_PE3_OCP_RXN<5>")
		)
		(pad "22" smd rect
			(at 4.393946 7.999984 90)
			(size 2.0066 0.508)
			(layers "F.Cu" "F.Mask" "F.Paste")
			(net "GND")
		)
		(pad "23" smd rect
			(at 0 8.800084 90)
			(size 2.0066 0.508)
			(layers "F.Cu" "F.Mask" "F.Paste")
			(net "P3E_CPU0_PE3_OCP_RXP<5>")
		)
		(pad "24" smd rect
			(at 4.393946 8.800084 90)
			(size 2.0066 0.508)
			(layers "F.Cu" "F.Mask" "F.Paste")
			(net "GND")
		)
		(pad "25" smd rect
			(at 0 9.59993 90)
			(size 2.0066 0.508)
			(layers "F.Cu" "F.Mask" "F.Paste")
			(net "GND")
		)
		(pad "26" smd rect
			(at 4.393946 9.59993 90)
			(size 2.0066 0.508)
			(layers "F.Cu" "F.Mask" "F.Paste")
			(net "P3E_OCP_CPU0_PE3_C_TXP<5>")
		)
		(pad "27" smd rect
			(at 0 10.40003 90)
			(size 2.0066 0.508)
			(layers "F.Cu" "F.Mask" "F.Paste")
			(net "GND")
		)
		(pad "28" smd rect
			(at 4.393946 10.40003 90)
			(size 2.0066 0.508)
			(layers "F.Cu" "F.Mask" "F.Paste")
			(net "P3E_OCP_CPU0_PE3_C_TXN<5>")
		)
		(pad "29" smd rect
			(at 0 11.199876 90)
			(size 2.0066 0.508)
			(layers "F.Cu" "F.Mask" "F.Paste")
			(net "P3E_CPU0_PE3_OCP_RXN<4>")
		)
		(pad "30" smd rect
			(at 4.393946 11.199876 90)
			(size 2.0066 0.508)
			(layers "F.Cu" "F.Mask" "F.Paste")
			(net "GND")
		)
		(pad "31" smd rect
			(at 0 11.999976 90)
			(size 2.0066 0.508)
			(layers "F.Cu" "F.Mask" "F.Paste")
			(net "P3E_CPU0_PE3_OCP_RXP<4>")
		)
		(pad "32" smd rect
			(at 4.393946 11.999976 90)
			(size 2.0066 0.508)
			(layers "F.Cu" "F.Mask" "F.Paste")
			(net "GND")
		)
		(pad "33" smd rect
			(at 0 12.800076 90)
			(size 2.0066 0.508)
			(layers "F.Cu" "F.Mask" "F.Paste")
			(net "GND")
		)
		(pad "34" smd rect
			(at 4.393946 12.800076 90)
			(size 2.0066 0.508)
			(layers "F.Cu" "F.Mask" "F.Paste")
			(net "P3E_OCP_CPU0_PE3_C_TXP<4>")
		)
		(pad "35" smd rect
			(at 0 13.599922 90)
			(size 2.0066 0.508)
			(layers "F.Cu" "F.Mask" "F.Paste")
			(net "GND")
		)
		(pad "36" smd rect
			(at 4.393946 13.599922 90)
			(size 2.0066 0.508)
			(layers "F.Cu" "F.Mask" "F.Paste")
			(net "P3E_OCP_CPU0_PE3_C_TXN<4>")
		)
		(pad "37" smd rect
			(at 0 14.400022 90)
			(size 2.0066 0.508)
			(layers "F.Cu" "F.Mask" "F.Paste")
			(net "P3E_CPU0_PE3_OCP_RXP<3>")
		)
		(pad "38" smd rect
			(at 4.393946 14.400022 90)
			(size 2.0066 0.508)
			(layers "F.Cu" "F.Mask" "F.Paste")
			(net "GND")
		)
		(pad "39" smd rect
			(at 0 15.200122 90)
			(size 2.0066 0.508)
			(layers "F.Cu" "F.Mask" "F.Paste")
			(net "P3E_CPU0_PE3_OCP_RXN<3>")
		)
		(pad "40" smd rect
			(at 4.393946 15.200122 90)
			(size 2.0066 0.508)
			(layers "F.Cu" "F.Mask" "F.Paste")
			(net "GND")
		)
		(pad "41" smd rect
			(at 0 15.999968 90)
			(size 2.0066 0.508)
			(layers "F.Cu" "F.Mask" "F.Paste")
			(net "GND")
		)
		(pad "42" smd rect
			(at 4.393946 15.999968 90)
			(size 2.0066 0.508)
			(layers "F.Cu" "F.Mask" "F.Paste")
			(net "P3E_OCP_CPU0_PE3_C_TXP<3>")
		)
		(pad "43" smd rect
			(at 0 16.800068 90)
			(size 2.0066 0.508)
			(layers "F.Cu" "F.Mask" "F.Paste")
			(net "GND")
		)
		(pad "44" smd rect
			(at 4.393946 16.800068 90)
			(size 2.0066 0.508)
			(layers "F.Cu" "F.Mask" "F.Paste")
			(net "P3E_OCP_CPU0_PE3_C_TXN<3>")
		)
		(pad "45" smd rect
			(at 0 17.599914 90)
			(size 2.0066 0.508)
			(layers "F.Cu" "F.Mask" "F.Paste")
			(net "P3E_CPU0_PE3_OCP_RXP<2>")
		)
		(pad "46" smd rect
			(at 4.393946 17.599914 90)
			(size 2.0066 0.508)
			(layers "F.Cu" "F.Mask" "F.Paste")
			(net "GND")
		)
		(pad "47" smd rect
			(at 0 18.400014 90)
			(size 2.0066 0.508)
			(layers "F.Cu" "F.Mask" "F.Paste")
			(net "P3E_CPU0_PE3_OCP_RXN<2>")
		)
		(pad "48" smd rect
			(at 4.393946 18.400014 90)
			(size 2.0066 0.508)
			(layers "F.Cu" "F.Mask" "F.Paste")
			(net "GND")
		)
		(pad "49" smd rect
			(at 0 19.200114 90)
			(size 2.0066 0.508)
			(layers "F.Cu" "F.Mask" "F.Paste")
			(net "GND")
		)
		(pad "50" smd rect
			(at 4.393946 19.200114 90)
			(size 2.0066 0.508)
			(layers "F.Cu" "F.Mask" "F.Paste")
			(net "P3E_OCP_CPU0_PE3_C_TXP<2>")
		)
		(pad "51" smd rect
			(at 0 19.99996 90)
			(size 2.0066 0.508)
			(layers "F.Cu" "F.Mask" "F.Paste")
			(net "GND")
		)
		(pad "52" smd rect
			(at 4.393946 19.99996 90)
			(size 2.0066 0.508)
			(layers "F.Cu" "F.Mask" "F.Paste")
			(net "P3E_OCP_CPU0_PE3_C_TXN<2>")
		)
		(pad "53" smd rect
			(at 0 20.80006 90)
			(size 2.0066 0.508)
			(layers "F.Cu" "F.Mask" "F.Paste")
			(net "P3E_CPU0_PE3_OCP_RXP<1>")
		)
		(pad "54" smd rect
			(at 4.393946 20.80006 90)
			(size 2.0066 0.508)
			(layers "F.Cu" "F.Mask" "F.Paste")
			(net "GND")
		)
		(pad "55" smd rect
			(at 0 21.599906 90)
			(size 2.0066 0.508)
			(layers "F.Cu" "F.Mask" "F.Paste")
			(net "P3E_CPU0_PE3_OCP_RXN<1>")
		)
		(pad "56" smd rect
			(at 4.393946 21.599906 90)
			(size 2.0066 0.508)
			(layers "F.Cu" "F.Mask" "F.Paste")
			(net "GND")
		)
		(pad "57" smd rect
			(at 0 22.400006 90)
			(size 2.0066 0.508)
			(layers "F.Cu" "F.Mask" "F.Paste")
			(net "GND")
		)
		(pad "58" smd rect
			(at 4.393946 22.400006 90)
			(size 2.0066 0.508)
			(layers "F.Cu" "F.Mask" "F.Paste")
			(net "P3E_OCP_CPU0_PE3_C_TXP<1>")
		)
		(pad "59" smd rect
			(at 0 23.200106 90)
			(size 2.0066 0.508)
			(layers "F.Cu" "F.Mask" "F.Paste")
			(net "GND")
		)
		(pad "60" smd rect
			(at 4.393946 23.200106 90)
			(size 2.0066 0.508)
			(layers "F.Cu" "F.Mask" "F.Paste")
			(net "P3E_OCP_CPU0_PE3_C_TXN<1>")
		)
		(pad "61" smd rect
			(at 0 23.999952 90)
			(size 2.0066 0.508)
			(layers "F.Cu" "F.Mask" "F.Paste")
			(net "P3E_CPU0_PE3_OCP_RXP<0>")
		)
		(pad "62" smd rect
			(at 4.393946 23.999952 90)
			(size 2.0066 0.508)
			(layers "F.Cu" "F.Mask" "F.Paste")
			(net "GND")
		)
		(pad "63" smd rect
			(at 0 24.800052 90)
			(size 2.0066 0.508)
			(layers "F.Cu" "F.Mask" "F.Paste")
			(net "P3E_CPU0_PE3_OCP_RXN<0>")
		)
		(pad "64" smd rect
			(at 4.393946 24.800052 90)
			(size 2.0066 0.508)
			(layers "F.Cu" "F.Mask" "F.Paste")
			(net "GND")
		)
		(pad "65" smd rect
			(at 0 25.599898 90)
			(size 2.0066 0.508)
			(layers "F.Cu" "F.Mask" "F.Paste")
			(net "GND")
		)
		(pad "66" smd rect
			(at 4.393946 25.599898 90)
			(size 2.0066 0.508)
			(layers "F.Cu" "F.Mask" "F.Paste")
			(net "P3E_OCP_CPU0_PE3_C_TXP<0>")
		)
		(pad "67" smd rect
			(at 0 26.399998 90)
			(size 2.0066 0.508)
			(layers "F.Cu" "F.Mask" "F.Paste")
			(net "GND")
		)
		(pad "68" smd rect
			(at 4.393946 26.399998 90)
			(size 2.0066 0.508)
			(layers "F.Cu" "F.Mask" "F.Paste")
			(net "P3E_OCP_CPU0_PE3_C_TXN<0>")
		)
		(pad "69" smd rect
			(at 0 27.200098 90)
			(size 2.0066 0.508)
			(layers "F.Cu" "F.Mask" "F.Paste")
			(net "CLK_100M_MEZZ3_DP")
		)
		(pad "70" smd rect
			(at 4.393946 27.200098 90)
			(size 2.0066 0.508)
			(layers "F.Cu" "F.Mask" "F.Paste")
			(net "GND")
		)
		(pad "71" smd rect
			(at 0 27.999944 90)
			(size 2.0066 0.508)
			(layers "F.Cu" "F.Mask" "F.Paste")
			(net "CLK_100M_MEZZ3_DN")
		)
		(pad "72" smd rect
			(at 4.393946 27.999944 90)
			(size 2.0066 0.508)
			(layers "F.Cu" "F.Mask" "F.Paste")
			(net "GND")
		)
		(pad "73" smd rect
			(at 0 28.800044 90)
			(size 2.0066 0.508)
			(layers "F.Cu" "F.Mask" "F.Paste")
			(net "GND")
		)
		(pad "74" smd rect
			(at 4.393946 28.800044 90)
			(size 2.0066 0.508)
			(layers "F.Cu" "F.Mask" "F.Paste")
			(net "CLK_100M_MEZZ4_DP")
		)
		(pad "75" smd rect
			(at 0 29.59989 90)
			(size 2.0066 0.508)
			(layers "F.Cu" "F.Mask" "F.Paste")
			(net "RST_PCIE_CPU_DEV1_R_N")
		)
		(pad "76" smd rect
			(at 4.393946 29.59989 90)
			(size 2.0066 0.508)
			(layers "F.Cu" "F.Mask" "F.Paste")
			(net "CLK_100M_MEZZ4_DN")
		)
		(pad "77" smd rect
			(at 0 30.39999 90)
			(size 2.0066 0.508)
			(layers "F.Cu" "F.Mask" "F.Paste")
			(net "RST_PCIE_CPU_DEV2_R_N")
		)
		(pad "78" smd rect
			(at 4.393946 30.39999 90)
			(size 2.0066 0.508)
			(layers "F.Cu" "F.Mask" "F.Paste")
			(net "GND")
		)
		(pad "79" smd rect
			(at 0 31.20009 90)
			(size 2.0066 0.508)
			(layers "F.Cu" "F.Mask" "F.Paste")
			(net "RST_PCIE_CPU_DEV3_R_N")
		)
		(pad "80" smd rect
			(at 4.393946 31.20009 90)
			(size 2.0066 0.508)
			(layers "F.Cu" "F.Mask" "F.Paste")
			(net "FM_OCP_MEZZB_PRES_N")
		)
		(zone
			(layers "F.Cu" "B.Cu" "In1.Cu" "In2.Cu" "In3.Cu" "In4.Cu" "In5.Cu" "In6.Cu"
				"In7.Cu" "In8.Cu" "In9.Cu" "In10.Cu" "In11.Cu" "In12.Cu"
			)
			(hatch none 0.5)
			(connect_pads
				(clearance 0)
			)
			(min_thickness 0.25)
			(keepout
				(tracks not_allowed)
				(vias allowed)
				(pads allowed)
				(copperpour not_allowed)
				(footprints allowed)
			)
			(placement
				(enabled no)
				(sheetname "")
			)
			(fill
				(thermal_gap 0.5)
				(thermal_bridge_width 0.5)
				(island_removal_mode 0)
			)
			(polygon
				(pts
					(arc
						(start 471.868754 -49.679098)
						(mid 470.217754 -49.679098)
						(end 471.868754 -49.679098)
					)
				)
			)
		)
		(zone
			(layers "F.Cu" "B.Cu" "In1.Cu" "In2.Cu" "In3.Cu" "In4.Cu" "In5.Cu" "In6.Cu"
				"In7.Cu" "In8.Cu" "In9.Cu" "In10.Cu" "In11.Cu" "In12.Cu"
			)
			(hatch none 0.5)
			(connect_pads
				(clearance 0)
			)
			(min_thickness 0.25)
			(keepout
				(tracks not_allowed)
				(vias allowed)
				(pads allowed)
				(copperpour not_allowed)
				(footprints allowed)
			)
			(placement
				(enabled no)
				(sheetname "")
			)
			(fill
				(thermal_gap 0.5)
				(thermal_bridge_width 0.5)
				(island_removal_mode 0)
			)
			(polygon
				(pts
					(arc
						(start 435.854348 -49.679098)
						(mid 433.847748 -49.679098)
						(end 435.854348 -49.679098)
					)
				)
			)
		)
	)
	(footprint ""
		(layer "F.Cu")
		(at 110.792768 -79.6036 180)
		(property "Reference" "C3D6"
			(at 0 0 180)
			(layer "F.SilkS")
			(hide yes)
			(effects
				(font
					(size 1.27 1.27)
				)
			)
		)
		(property "Value" ""
			(at 0 0 180)
			(layer "F.Fab")
			(effects
				(font
					(size 1.27 1.27)
				)
			)
		)
		(duplicate_pad_numbers_are_jumpers no)
		(fp_poly
			(pts
				(xy -0.4953 -0.2032) (xy 0.4953 -0.2032) (xy 0.4953 1.6002) (xy -0.4953 1.6002)
			)
			(stroke
				(width 0)
				(type default)
			)
			(fill no)
			(layer "F.CrtYd")
		)
		(fp_line
			(start 0.4953 1.6002)
			(end -0.4953 1.6002)
			(stroke
				(width 0.1)
				(type default)
			)
			(layer "F.Fab")
		)
		(fp_line
			(start 0.4953 -0.2032)
			(end 0.4953 1.6002)
			(stroke
				(width 0.1)
				(type default)
			)
			(layer "F.Fab")
		)
		(fp_line
			(start -0.4953 1.6002)
			(end -0.4953 -0.2032)
			(stroke
				(width 0.1)
				(type default)
			)
			(layer "F.Fab")
		)
		(fp_line
			(start -0.4953 -0.2032)
			(end 0.4953 -0.2032)
			(stroke
				(width 0.1)
				(type default)
			)
			(layer "F.Fab")
		)
		(pad "1" smd rect
			(at 0 0 180)
			(size 0.762 0.889)
			(layers "F.Cu" "F.Mask" "F.Paste")
			(net "PVCCMCP_CPU1")
		)
		(pad "2" smd rect
			(at 0 1.397 180)
			(size 0.762 0.889)
			(layers "F.Cu" "F.Mask" "F.Paste")
			(net "GND")
		)
		(zone
			(layer "F.Cu")
			(hatch none 0.5)
			(connect_pads
				(clearance 0)
			)
			(min_thickness 0.25)
			(keepout
				(tracks not_allowed)
				(vias allowed)
				(pads allowed)
				(copperpour not_allowed)
				(footprints allowed)
			)
			(placement
				(enabled no)
				(sheetname "")
			)
			(fill
				(thermal_gap 0.5)
				(thermal_bridge_width 0.5)
				(island_removal_mode 0)
			)
			(polygon
				(pts
					(xy 111.173768 -80.0481) (xy 110.411768 -80.0481) (xy 110.411768 -80.5561) (xy 111.173768 -80.5561)
				)
			)
		)
	)
	(footprint ""
		(layer "F.Cu")
		(at 485.4956 -50.2539 180)
		(property "Reference" "C9E4"
			(at 0 0 180)
			(layer "F.SilkS")
			(hide yes)
			(effects
				(font
					(size 1.27 1.27)
				)
			)
		)
		(property "Value" ""
			(at 0 0 180)
			(layer "F.Fab")
			(effects
				(font
					(size 1.27 1.27)
				)
			)
		)
		(duplicate_pad_numbers_are_jumpers no)
		(fp_poly
			(pts
				(xy 0.3048 -0.1016) (xy 0.3048 0.9906) (xy -0.3048 0.9906) (xy -0.3048 -0.1016)
			)
			(stroke
				(width 0)
				(type default)
			)
			(fill no)
			(layer "F.CrtYd")
		)
		(fp_line
			(start 0.3048 0.9906)
			(end 0.3048 -0.1016)
			(stroke
				(width 0.1)
				(type default)
			)
			(layer "F.Fab")
		)
		(fp_line
			(start 0.3048 -0.1016)
			(end -0.3048 -0.1016)
			(stroke
				(width 0.1)
				(type default)
			)
			(layer "F.Fab")
		)
		(fp_line
			(start -0.3048 0.9906)
			(end 0.3048 0.9906)
			(stroke
				(width 0.1)
				(type default)
			)
			(layer "F.Fab")
		)
		(fp_line
			(start -0.3048 -0.1016)
			(end -0.3048 0.9906)
			(stroke
				(width 0.1)
				(type default)
			)
			(layer "F.Fab")
		)
		(pad "1" smd rect
			(at 0 0 180)
			(size 0.508 0.508)
			(layers "F.Cu" "F.Mask" "F.Paste")
			(net "PE_PCH_SPRV_RX_DP")
		)
		(pad "2" smd rect
			(at 0 0.889 180)
			(size 0.508 0.508)
			(layers "F.Cu" "F.Mask" "F.Paste")
			(net "PE_PCH_SPRV_RX_C_DP")
		)
		(zone
			(layer "F.Cu")
			(hatch none 0.5)
			(connect_pads
				(clearance 0)
			)
			(min_thickness 0.25)
			(keepout
				(tracks not_allowed)
				(vias allowed)
				(pads allowed)
				(copperpour not_allowed)
				(footprints allowed)
			)
			(placement
				(enabled no)
				(sheetname "")
			)
			(fill
				(thermal_gap 0.5)
				(thermal_bridge_width 0.5)
				(island_removal_mode 0)
			)
			(polygon
				(pts
					(xy 485.7496 -50.8889) (xy 485.2416 -50.8889) (xy 485.2416 -50.5079) (xy 485.7496 -50.5079)
				)
			)
		)
		(zone
			(layer "F.Cu")
			(hatch none 0.5)
			(connect_pads
				(clearance 0)
			)
			(min_thickness 0.25)
			(keepout
				(tracks allowed)
				(vias not_allowed)
				(pads allowed)
				(copperpour not_allowed)
				(footprints allowed)
			)
			(placement
				(enabled no)
				(sheetname "")
			)
			(fill
				(thermal_gap 0.5)
				(thermal_bridge_width 0.5)
				(island_removal_mode 0)
			)
			(polygon
				(pts
					(xy 485.7496 -50.5079) (xy 485.2416 -50.5079) (xy 485.2416 -50.8889) (xy 485.7496 -50.8889)
				)
			)
		)
	)
	(footprint ""
		(layer "F.Cu")
		(at 431.7746 -44.2849 -90)
		(property "Reference" "R25W81"
			(at -0.8382 -0.67818 270)
			(unlocked yes)
			(layer "F.SilkS")
			(effects
				(font
					(size 0.4064 0.254)
					(thickness 0.1524)
				)
				(justify left)
			)
		)
		(property "Value" ""
			(at 0 0 270)
			(layer "F.Fab")
			(effects
				(font
					(size 1.27 1.27)
				)
			)
		)
		(duplicate_pad_numbers_are_jumpers no)
		(fp_poly
			(pts
				(xy -0.2794 -0.1016) (xy 0.2794 -0.1016) (xy 0.2794 0.9906) (xy -0.2794 0.9906)
			)
			(stroke
				(width 0)
				(type default)
			)
			(fill no)
			(layer "F.CrtYd")
		)
		(fp_line
			(start -0.2794 0.9906)
			(end 0.2794 0.9906)
			(stroke
				(width 0.1)
				(type default)
			)
			(layer "F.Fab")
		)
		(fp_line
			(start 0.2794 0.9906)
			(end 0.2794 -0.1016)
			(stroke
				(width 0.1)
				(type default)
			)
			(layer "F.Fab")
		)
		(fp_line
			(start -0.2794 -0.1016)
			(end -0.2794 0.9906)
			(stroke
				(width 0.1)
				(type default)
			)
			(layer "F.Fab")
		)
		(fp_line
			(start 0.2794 -0.1016)
			(end -0.2794 -0.1016)
			(stroke
				(width 0.1)
				(type default)
			)
			(layer "F.Fab")
		)
		(pad "1" smd rect
			(at 0 0 270)
			(size 0.508 0.508)
			(layers "F.Cu" "F.Mask" "F.Paste")
			(net "SPI_BMC_BT_CLK")
		)
		(pad "2" smd rect
			(at 0 0.889 270)
			(size 0.508 0.508)
			(layers "F.Cu" "F.Mask" "F.Paste")
			(net "SPI_BMC_BT_CLK_R")
		)
		(zone
			(layer "F.Cu")
			(hatch none 0.5)
			(connect_pads
				(clearance 0)
			)
			(min_thickness 0.25)
			(keepout
				(tracks not_allowed)
				(vias allowed)
				(pads allowed)
				(copperpour not_allowed)
				(footprints allowed)
			)
			(placement
				(enabled no)
				(sheetname "")
			)
			(fill
				(thermal_gap 0.5)
				(thermal_bridge_width 0.5)
				(island_removal_mode 0)
			)
			(polygon
				(pts
					(xy 431.1396 -44.5389) (xy 431.1396 -44.0309) (xy 431.5206 -44.0309) (xy 431.5206 -44.5389)
				)
			)
		)
		(zone
			(layer "F.Cu")
			(hatch none 0.5)
			(connect_pads
				(clearance 0)
			)
			(min_thickness 0.25)
			(keepout
				(tracks allowed)
				(vias not_allowed)
				(pads allowed)
				(copperpour not_allowed)
				(footprints allowed)
			)
			(placement
				(enabled no)
				(sheetname "")
			)
			(fill
				(thermal_gap 0.5)
				(thermal_bridge_width 0.5)
				(island_removal_mode 0)
			)
			(polygon
				(pts
					(xy 431.5206 -44.5389) (xy 431.5206 -44.0309) (xy 431.1396 -44.0309) (xy 431.1396 -44.5389)
				)
			)
		)
	)
	(footprint ""
		(layer "F.Cu")
		(at 171.196 -86.868 180)
		(property "Reference" "R4D6"
			(at 0 0 180)
			(layer "F.SilkS")
			(hide yes)
			(effects
				(font
					(size 1.27 1.27)
				)
			)
		)
		(property "Value" ""
			(at 0 0 180)
			(layer "F.Fab")
			(effects
				(font
					(size 1.27 1.27)
				)
			)
		)
		(duplicate_pad_numbers_are_jumpers no)
		(fp_poly
			(pts
				(xy -0.2794 -0.1016) (xy 0.2794 -0.1016) (xy 0.2794 0.9906) (xy -0.2794 0.9906)
			)
			(stroke
				(width 0)
				(type default)
			)
			(fill no)
			(layer "F.CrtYd")
		)
		(fp_line
			(start 0.2794 0.9906)
			(end 0.2794 -0.1016)
			(stroke
				(width 0.1)
				(type default)
			)
			(layer "F.Fab")
		)
		(fp_line
			(start 0.2794 -0.1016)
			(end -0.2794 -0.1016)
			(stroke
				(width 0.1)
				(type default)
			)
			(layer "F.Fab")
		)
		(fp_line
			(start -0.2794 0.9906)
			(end 0.2794 0.9906)
			(stroke
				(width 0.1)
				(type default)
			)
			(layer "F.Fab")
		)
		(fp_line
			(start -0.2794 -0.1016)
			(end -0.2794 0.9906)
			(stroke
				(width 0.1)
				(type default)
			)
			(layer "F.Fab")
		)
		(pad "1" smd rect
			(at 0 0 180)
			(size 0.508 0.508)
			(layers "F.Cu" "F.Mask" "F.Paste")
			(net "CLK_100M_CPU0_RC_REFCLK1_R_DP")
		)
		(pad "2" smd rect
			(at 0 0.889 180)
			(size 0.508 0.508)
			(layers "F.Cu" "F.Mask" "F.Paste")
			(net "CLK_100M_CPU0_RC_REFCLK1_DP")
		)
		(zone
			(layer "F.Cu")
			(hatch none 0.5)
			(connect_pads
				(clearance 0)
			)
			(min_thickness 0.25)
			(keepout
				(tracks not_allowed)
				(vias allowed)
				(pads allowed)
				(copperpour not_allowed)
				(footprints allowed)
			)
			(placement
				(enabled no)
				(sheetname "")
			)
			(fill
				(thermal_gap 0.5)
				(thermal_bridge_width 0.5)
				(island_removal_mode 0)
			)
			(polygon
				(pts
					(xy 171.45 -87.503) (xy 170.942 -87.503) (xy 170.942 -87.122) (xy 171.45 -87.122)
				)
			)
		)
		(zone
			(layer "F.Cu")
			(hatch none 0.5)
			(connect_pads
				(clearance 0)
			)
			(min_thickness 0.25)
			(keepout
				(tracks allowed)
				(vias not_allowed)
				(pads allowed)
				(copperpour not_allowed)
				(footprints allowed)
			)
			(placement
				(enabled no)
				(sheetname "")
			)
			(fill
				(thermal_gap 0.5)
				(thermal_bridge_width 0.5)
				(island_removal_mode 0)
			)
			(polygon
				(pts
					(xy 171.45 -87.122) (xy 170.942 -87.122) (xy 170.942 -87.503) (xy 171.45 -87.503)
				)
			)
		)
	)
	(footprint ""
		(layer "F.Cu")
		(at 418.7952 -92.6719 -90)
		(property "Reference" "C8C14"
			(at 0 0 270)
			(layer "F.SilkS")
			(hide yes)
			(effects
				(font
					(size 1.27 1.27)
				)
			)
		)
		(property "Value" ""
			(at 0 0 270)
			(layer "F.Fab")
			(effects
				(font
					(size 1.27 1.27)
				)
			)
		)
		(duplicate_pad_numbers_are_jumpers no)
		(fp_poly
			(pts
				(xy 0.3048 -0.1016) (xy 0.3048 0.9906) (xy -0.3048 0.9906) (xy -0.3048 -0.1016)
			)
			(stroke
				(width 0)
				(type default)
			)
			(fill no)
			(layer "F.CrtYd")
		)
		(fp_line
			(start -0.3048 0.9906)
			(end 0.3048 0.9906)
			(stroke
				(width 0.1)
				(type default)
			)
			(layer "F.Fab")
		)
		(fp_line
			(start 0.3048 0.9906)
			(end 0.3048 -0.1016)
			(stroke
				(width 0.1)
				(type default)
			)
			(layer "F.Fab")
		)
		(fp_line
			(start -0.3048 -0.1016)
			(end -0.3048 0.9906)
			(stroke
				(width 0.1)
				(type default)
			)
			(layer "F.Fab")
		)
		(fp_line
			(start 0.3048 -0.1016)
			(end -0.3048 -0.1016)
			(stroke
				(width 0.1)
				(type default)
			)
			(layer "F.Fab")
		)
		(pad "1" smd rect
			(at 0 0 270)
			(size 0.508 0.508)
			(layers "F.Cu" "F.Mask" "F.Paste")
			(net "KR_P0_OCP_RX_DN")
		)
		(pad "2" smd rect
			(at 0 0.889 270)
			(size 0.508 0.508)
			(layers "F.Cu" "F.Mask" "F.Paste")
			(net "KR_P0_OCP_RX_C_DN")
		)
		(zone
			(layer "F.Cu")
			(hatch none 0.5)
			(connect_pads
				(clearance 0)
			)
			(min_thickness 0.25)
			(keepout
				(tracks not_allowed)
				(vias allowed)
				(pads allowed)
				(copperpour not_allowed)
				(footprints allowed)
			)
			(placement
				(enabled no)
				(sheetname "")
			)
			(fill
				(thermal_gap 0.5)
				(thermal_bridge_width 0.5)
				(island_removal_mode 0)
			)
			(polygon
				(pts
					(xy 418.1602 -92.9259) (xy 418.1602 -92.4179) (xy 418.5412 -92.4179) (xy 418.5412 -92.9259)
				)
			)
		)
		(zone
			(layer "F.Cu")
			(hatch none 0.5)
			(connect_pads
				(clearance 0)
			)
			(min_thickness 0.25)
			(keepout
				(tracks allowed)
				(vias not_allowed)
				(pads allowed)
				(copperpour not_allowed)
				(footprints allowed)
			)
			(placement
				(enabled no)
				(sheetname "")
			)
			(fill
				(thermal_gap 0.5)
				(thermal_bridge_width 0.5)
				(island_removal_mode 0)
			)
			(polygon
				(pts
					(xy 418.5412 -92.9259) (xy 418.5412 -92.4179) (xy 418.1602 -92.4179) (xy 418.1602 -92.9259)
				)
			)
		)
	)
	(footprint ""
		(layer "F.Cu")
		(at 170.6245 -130.175 90)
		(property "Reference" "R4B9"
			(at 0 0 90)
			(layer "F.SilkS")
			(hide yes)
			(effects
				(font
					(size 1.27 1.27)
				)
			)
		)
		(property "Value" ""
			(at 0 0 90)
			(layer "F.Fab")
			(effects
				(font
					(size 1.27 1.27)
				)
			)
		)
		(duplicate_pad_numbers_are_jumpers no)
		(fp_poly
			(pts
				(xy -0.2794 -0.1016) (xy 0.2794 -0.1016) (xy 0.2794 0.9906) (xy -0.2794 0.9906)
			)
			(stroke
				(width 0)
				(type default)
			)
			(fill no)
			(layer "F.CrtYd")
		)
		(fp_line
			(start 0.2794 -0.1016)
			(end -0.2794 -0.1016)
			(stroke
				(width 0.1)
				(type default)
			)
			(layer "F.Fab")
		)
		(fp_line
			(start -0.2794 -0.1016)
			(end -0.2794 0.9906)
			(stroke
				(width 0.1)
				(type default)
			)
			(layer "F.Fab")
		)
		(fp_line
			(start 0.2794 0.9906)
			(end 0.2794 -0.1016)
			(stroke
				(width 0.1)
				(type default)
			)
			(layer "F.Fab")
		)
		(fp_line
			(start -0.2794 0.9906)
			(end 0.2794 0.9906)
			(stroke
				(width 0.1)
				(type default)
			)
			(layer "F.Fab")
		)
		(pad "1" smd rect
			(at 0 0 90)
			(size 0.508 0.508)
			(layers "F.Cu" "F.Mask" "F.Paste")
			(net "VSENSE_PVPP_KLM")
		)
		(pad "2" smd rect
			(at 0 0.889 90)
			(size 0.508 0.508)
			(layers "F.Cu" "F.Mask" "F.Paste")
			(net "VR_COMP_PVPP_KLM")
		)
		(zone
			(layer "F.Cu")
			(hatch none 0.5)
			(connect_pads
				(clearance 0)
			)
			(min_thickness 0.25)
			(keepout
				(tracks allowed)
				(vias not_allowed)
				(pads allowed)
				(copperpour not_allowed)
				(footprints allowed)
			)
			(placement
				(enabled no)
				(sheetname "")
			)
			(fill
				(thermal_gap 0.5)
				(thermal_bridge_width 0.5)
				(island_removal_mode 0)
			)
			(polygon
				(pts
					(xy 170.8785 -129.921) (xy 170.8785 -130.429) (xy 171.2595 -130.429) (xy 171.2595 -129.921)
				)
			)
		)
		(zone
			(layer "F.Cu")
			(hatch none 0.5)
			(connect_pads
				(clearance 0)
			)
			(min_thickness 0.25)
			(keepout
				(tracks not_allowed)
				(vias allowed)
				(pads allowed)
				(copperpour not_allowed)
				(footprints allowed)
			)
			(placement
				(enabled no)
				(sheetname "")
			)
			(fill
				(thermal_gap 0.5)
				(thermal_bridge_width 0.5)
				(island_removal_mode 0)
			)
			(polygon
				(pts
					(xy 171.2595 -129.921) (xy 171.2595 -130.429) (xy 170.8785 -130.429) (xy 170.8785 -129.921)
				)
			)
		)
	)
	(footprint ""
		(layer "F.Cu")
		(at 12.9286 -75.8952)
		(property "Reference" "R1D33"
			(at 0 0 0)
			(layer "F.SilkS")
			(hide yes)
			(effects
				(font
					(size 1.27 1.27)
				)
			)
		)
		(property "Value" ""
			(at 0 0 0)
			(layer "F.Fab")
			(effects
				(font
					(size 1.27 1.27)
				)
			)
		)
		(duplicate_pad_numbers_are_jumpers no)
		(fp_poly
			(pts
				(xy -0.2794 -0.1016) (xy 0.2794 -0.1016) (xy 0.2794 0.9906) (xy -0.2794 0.9906)
			)
			(stroke
				(width 0)
				(type default)
			)
			(fill no)
			(layer "F.CrtYd")
		)
		(fp_line
			(start -0.2794 -0.1016)
			(end -0.2794 0.9906)
			(stroke
				(width 0.1)
				(type default)
			)
			(layer "F.Fab")
		)
		(fp_line
			(start -0.2794 0.9906)
			(end 0.2794 0.9906)
			(stroke
				(width 0.1)
				(type default)
			)
			(layer "F.Fab")
		)
		(fp_line
			(start 0.2794 -0.1016)
			(end -0.2794 -0.1016)
			(stroke
				(width 0.1)
				(type default)
			)
			(layer "F.Fab")
		)
		(fp_line
			(start 0.2794 0.9906)
			(end 0.2794 -0.1016)
			(stroke
				(width 0.1)
				(type default)
			)
			(layer "F.Fab")
		)
		(pad "1" smd rect
			(at 0 0)
			(size 0.508 0.508)
			(layers "F.Cu" "F.Mask" "F.Paste")
			(net "PWRGD_P12V_R")
		)
		(pad "2" smd rect
			(at 0 0.889)
			(size 0.508 0.508)
			(layers "F.Cu" "F.Mask" "F.Paste")
			(net "PWRGD_P12V_HSC")
		)
		(zone
			(layer "F.Cu")
			(hatch none 0.5)
			(connect_pads
				(clearance 0)
			)
			(min_thickness 0.25)
			(keepout
				(tracks allowed)
				(vias not_allowed)
				(pads allowed)
				(copperpour not_allowed)
				(footprints allowed)
			)
			(placement
				(enabled no)
				(sheetname "")
			)
			(fill
				(thermal_gap 0.5)
				(thermal_bridge_width 0.5)
				(island_removal_mode 0)
			)
			(polygon
				(pts
					(xy 12.6746 -75.6412) (xy 13.1826 -75.6412) (xy 13.1826 -75.2602) (xy 12.6746 -75.2602)
				)
			)
		)
		(zone
			(layer "F.Cu")
			(hatch none 0.5)
			(connect_pads
				(clearance 0)
			)
			(min_thickness 0.25)
			(keepout
				(tracks not_allowed)
				(vias allowed)
				(pads allowed)
				(copperpour not_allowed)
				(footprints allowed)
			)
			(placement
				(enabled no)
				(sheetname "")
			)
			(fill
				(thermal_gap 0.5)
				(thermal_bridge_width 0.5)
				(island_removal_mode 0)
			)
			(polygon
				(pts
					(xy 12.6746 -75.2602) (xy 13.1826 -75.2602) (xy 13.1826 -75.6412) (xy 12.6746 -75.6412)
				)
			)
		)
	)
	(footprint ""
		(layer "F.Cu")
		(at 27.990292 -55.771288 -90)
		(property "Reference" "R1E14"
			(at 0 0 270)
			(layer "F.SilkS")
			(hide yes)
			(effects
				(font
					(size 1.27 1.27)
				)
			)
		)
		(property "Value" ""
			(at 0 0 270)
			(layer "F.Fab")
			(effects
				(font
					(size 1.27 1.27)
				)
			)
		)
		(duplicate_pad_numbers_are_jumpers no)
		(fp_poly
			(pts
				(xy -0.2794 -0.1016) (xy 0.2794 -0.1016) (xy 0.2794 0.9906) (xy -0.2794 0.9906)
			)
			(stroke
				(width 0)
				(type default)
			)
			(fill no)
			(layer "F.CrtYd")
		)
		(fp_line
			(start -0.2794 0.9906)
			(end 0.2794 0.9906)
			(stroke
				(width 0.1)
				(type default)
			)
			(layer "F.Fab")
		)
		(fp_line
			(start 0.2794 0.9906)
			(end 0.2794 -0.1016)
			(stroke
				(width 0.1)
				(type default)
			)
			(layer "F.Fab")
		)
		(fp_line
			(start -0.2794 -0.1016)
			(end -0.2794 0.9906)
			(stroke
				(width 0.1)
				(type default)
			)
			(layer "F.Fab")
		)
		(fp_line
			(start 0.2794 -0.1016)
			(end -0.2794 -0.1016)
			(stroke
				(width 0.1)
				(type default)
			)
			(layer "F.Fab")
		)
		(pad "1" smd rect
			(at 0 0 270)
			(size 0.508 0.508)
			(layers "F.Cu" "F.Mask" "F.Paste")
			(net "VR_PVCCIN_CPU1_PH1_OCSET")
		)
		(pad "2" smd rect
			(at 0 0.889 270)
			(size 0.508 0.508)
			(layers "F.Cu" "F.Mask" "F.Paste")
			(net "GND")
		)
		(zone
			(layer "F.Cu")
			(hatch none 0.5)
			(connect_pads
				(clearance 0)
			)
			(min_thickness 0.25)
			(keepout
				(tracks not_allowed)
				(vias allowed)
				(pads allowed)
				(copperpour not_allowed)
				(footprints allowed)
			)
			(placement
				(enabled no)
				(sheetname "")
			)
			(fill
				(thermal_gap 0.5)
				(thermal_bridge_width 0.5)
				(island_removal_mode 0)
			)
			(polygon
				(pts
					(xy 27.355292 -56.025288) (xy 27.355292 -55.517288) (xy 27.736292 -55.517288) (xy 27.736292 -56.025288)
				)
			)
		)
		(zone
			(layer "F.Cu")
			(hatch none 0.5)
			(connect_pads
				(clearance 0)
			)
			(min_thickness 0.25)
			(keepout
				(tracks allowed)
				(vias not_allowed)
				(pads allowed)
				(copperpour not_allowed)
				(footprints allowed)
			)
			(placement
				(enabled no)
				(sheetname "")
			)
			(fill
				(thermal_gap 0.5)
				(thermal_bridge_width 0.5)
				(island_removal_mode 0)
			)
			(polygon
				(pts
					(xy 27.736292 -56.025288) (xy 27.736292 -55.517288) (xy 27.355292 -55.517288) (xy 27.355292 -56.025288)
				)
			)
		)
	)
	(footprint ""
		(layer "F.Cu")
		(at 379.7173 -90.551)
		(property "Reference" "R25W72"
			(at -0.8382 -0.67818 0)
			(unlocked yes)
			(layer "F.SilkS")
			(effects
				(font
					(size 0.4064 0.254)
					(thickness 0.1524)
				)
				(justify left)
			)
		)
		(property "Value" ""
			(at 0 0 0)
			(layer "F.Fab")
			(effects
				(font
					(size 1.27 1.27)
				)
			)
		)
		(duplicate_pad_numbers_are_jumpers no)
		(fp_poly
			(pts
				(xy -0.2794 -0.1016) (xy 0.2794 -0.1016) (xy 0.2794 0.9906) (xy -0.2794 0.9906)
			)
			(stroke
				(width 0)
				(type default)
			)
			(fill no)
			(layer "F.CrtYd")
		)
		(fp_line
			(start -0.2794 -0.1016)
			(end -0.2794 0.9906)
			(stroke
				(width 0.1)
				(type default)
			)
			(layer "F.Fab")
		)
		(fp_line
			(start -0.2794 0.9906)
			(end 0.2794 0.9906)
			(stroke
				(width 0.1)
				(type default)
			)
			(layer "F.Fab")
		)
		(fp_line
			(start 0.2794 -0.1016)
			(end -0.2794 -0.1016)
			(stroke
				(width 0.1)
				(type default)
			)
			(layer "F.Fab")
		)
		(fp_line
			(start 0.2794 0.9906)
			(end 0.2794 -0.1016)
			(stroke
				(width 0.1)
				(type default)
			)
			(layer "F.Fab")
		)
		(pad "1" smd rect
			(at 0 0)
			(size 0.508 0.508)
			(layers "F.Cu" "F.Mask" "F.Paste")
			(net "LPC_LFRAME_N_CS0_N")
		)
		(pad "2" smd rect
			(at 0 0.889)
			(size 0.508 0.508)
			(layers "F.Cu" "F.Mask" "F.Paste")
			(net "LPC_LFRAME_N_CS0_R_N")
		)
		(zone
			(layer "F.Cu")
			(hatch none 0.5)
			(connect_pads
				(clearance 0)
			)
			(min_thickness 0.25)
			(keepout
				(tracks allowed)
				(vias not_allowed)
				(pads allowed)
				(copperpour not_allowed)
				(footprints allowed)
			)
			(placement
				(enabled no)
				(sheetname "")
			)
			(fill
				(thermal_gap 0.5)
				(thermal_bridge_width 0.5)
				(island_removal_mode 0)
			)
			(polygon
				(pts
					(xy 379.4633 -90.297) (xy 379.9713 -90.297) (xy 379.9713 -89.916) (xy 379.4633 -89.916)
				)
			)
		)
		(zone
			(layer "F.Cu")
			(hatch none 0.5)
			(connect_pads
				(clearance 0)
			)
			(min_thickness 0.25)
			(keepout
				(tracks not_allowed)
				(vias allowed)
				(pads allowed)
				(copperpour not_allowed)
				(footprints allowed)
			)
			(placement
				(enabled no)
				(sheetname "")
			)
			(fill
				(thermal_gap 0.5)
				(thermal_bridge_width 0.5)
				(island_removal_mode 0)
			)
			(polygon
				(pts
					(xy 379.4633 -89.916) (xy 379.9713 -89.916) (xy 379.9713 -90.297) (xy 379.4633 -90.297)
				)
			)
		)
	)
	(footprint ""
		(layer "F.Cu")
		(at 394.589 -88.2015)
		(property "Reference" "R2U9"
			(at 0 0 0)
			(layer "F.SilkS")
			(hide yes)
			(effects
				(font
					(size 1.27 1.27)
				)
			)
		)
		(property "Value" ""
			(at 0 0 0)
			(layer "F.Fab")
			(effects
				(font
					(size 1.27 1.27)
				)
			)
		)
		(duplicate_pad_numbers_are_jumpers no)
		(fp_poly
			(pts
				(xy -0.2794 -0.1016) (xy 0.2794 -0.1016) (xy 0.2794 0.9906) (xy -0.2794 0.9906)
			)
			(stroke
				(width 0)
				(type default)
			)
			(fill no)
			(layer "F.CrtYd")
		)
		(fp_line
			(start -0.2794 -0.1016)
			(end -0.2794 0.9906)
			(stroke
				(width 0.1)
				(type default)
			)
			(layer "F.Fab")
		)
		(fp_line
			(start -0.2794 0.9906)
			(end 0.2794 0.9906)
			(stroke
				(width 0.1)
				(type default)
			)
			(layer "F.Fab")
		)
		(fp_line
			(start 0.2794 -0.1016)
			(end -0.2794 -0.1016)
			(stroke
				(width 0.1)
				(type default)
			)
			(layer "F.Fab")
		)
		(fp_line
			(start 0.2794 0.9906)
			(end 0.2794 -0.1016)
			(stroke
				(width 0.1)
				(type default)
			)
			(layer "F.Fab")
		)
		(pad "1" smd rect
			(at 0 0)
			(size 0.508 0.508)
			(layers "F.Cu" "F.Mask" "F.Paste")
			(net "SMB_LAN_STBY_LVC3_SDA_R1")
		)
		(pad "2" smd rect
			(at 0 0.889)
			(size 0.508 0.508)
			(layers "F.Cu" "F.Mask" "F.Paste")
			(net "SMB_LAN_STBY_LVC3_SDA")
		)
		(zone
			(layer "F.Cu")
			(hatch none 0.5)
			(connect_pads
				(clearance 0)
			)
			(min_thickness 0.25)
			(keepout
				(tracks allowed)
				(vias not_allowed)
				(pads allowed)
				(copperpour not_allowed)
				(footprints allowed)
			)
			(placement
				(enabled no)
				(sheetname "")
			)
			(fill
				(thermal_gap 0.5)
				(thermal_bridge_width 0.5)
				(island_removal_mode 0)
			)
			(polygon
				(pts
					(xy 394.335 -87.9475) (xy 394.843 -87.9475) (xy 394.843 -87.5665) (xy 394.335 -87.5665)
				)
			)
		)
		(zone
			(layer "F.Cu")
			(hatch none 0.5)
			(connect_pads
				(clearance 0)
			)
			(min_thickness 0.25)
			(keepout
				(tracks not_allowed)
				(vias allowed)
				(pads allowed)
				(copperpour not_allowed)
				(footprints allowed)
			)
			(placement
				(enabled no)
				(sheetname "")
			)
			(fill
				(thermal_gap 0.5)
				(thermal_bridge_width 0.5)
				(island_removal_mode 0)
			)
			(polygon
				(pts
					(xy 394.335 -87.5665) (xy 394.843 -87.5665) (xy 394.843 -87.9475) (xy 394.335 -87.9475)
				)
			)
		)
	)
	(footprint ""
		(layer "F.Cu")
		(at 173.968664 -17.65681 90)
		(property "Reference" "C4F12"
			(at 0 0 90)
			(layer "F.SilkS")
			(hide yes)
			(effects
				(font
					(size 1.27 1.27)
				)
			)
		)
		(property "Value" ""
			(at 0 0 90)
			(layer "F.Fab")
			(effects
				(font
					(size 1.27 1.27)
				)
			)
		)
		(duplicate_pad_numbers_are_jumpers no)
		(fp_rect
			(start -0.3048 -0.1016)
			(end 0.3048 0.9906)
			(stroke
				(width 0)
				(type default)
			)
			(fill no)
			(layer "F.CrtYd")
		)
		(fp_line
			(start 0.3048 -0.1016)
			(end -0.3048 -0.1016)
			(stroke
				(width 0.1)
				(type default)
			)
			(layer "F.Fab")
		)
		(fp_line
			(start -0.3048 -0.1016)
			(end -0.3048 0.9906)
			(stroke
				(width 0.1)
				(type default)
			)
			(layer "F.Fab")
		)
		(fp_line
			(start 0.3048 0.9906)
			(end 0.3048 -0.1016)
			(stroke
				(width 0.1)
				(type default)
			)
			(layer "F.Fab")
		)
		(fp_line
			(start -0.3048 0.9906)
			(end 0.3048 0.9906)
			(stroke
				(width 0.1)
				(type default)
			)
			(layer "F.Fab")
		)
		(pad "1" smd rect
			(at 0 0 90)
			(size 0.508 0.508)
			(layers "F.Cu" "F.Mask" "F.Paste")
			(net "VR_PVPP_GHJ_PHASE")
		)
		(pad "2" smd rect
			(at 0 0.889 90)
			(size 0.508 0.508)
			(layers "F.Cu" "F.Mask" "F.Paste")
			(net "VR_PVPP_GHJ_SNUB")
		)
		(zone
			(layer "F.Cu")
			(hatch none 0.5)
			(connect_pads
				(clearance 0)
			)
			(min_thickness 0.25)
			(keepout
				(tracks not_allowed)
				(vias allowed)
				(pads allowed)
				(copperpour not_allowed)
				(footprints allowed)
			)
			(placement
				(enabled no)
				(sheetname "")
			)
			(fill
				(thermal_gap 0.5)
				(thermal_bridge_width 0.5)
				(island_removal_mode 0)
			)
			(polygon
				(pts
					(xy 174.222664 -17.40281) (xy 174.603664 -17.40281) (xy 174.603664 -17.91081) (xy 174.222664 -17.91081)
				)
			)
		)
		(zone
			(layer "F.Cu")
			(hatch none 0.5)
			(connect_pads
				(clearance 0)
			)
			(min_thickness 0.25)
			(keepout
				(tracks allowed)
				(vias not_allowed)
				(pads allowed)
				(copperpour not_allowed)
				(footprints allowed)
			)
			(placement
				(enabled no)
				(sheetname "")
			)
			(fill
				(thermal_gap 0.5)
				(thermal_bridge_width 0.5)
				(island_removal_mode 0)
			)
			(polygon
				(pts
					(xy 174.222664 -17.40281) (xy 174.603664 -17.40281) (xy 174.603664 -17.91081) (xy 174.222664 -17.91081)
				)
			)
		)
	)
	(footprint ""
		(layer "F.Cu")
		(at 412.4452 -111.633 90)
		(property "Reference" "R8B31"
			(at 0 0 90)
			(layer "F.SilkS")
			(hide yes)
			(effects
				(font
					(size 1.27 1.27)
				)
			)
		)
		(property "Value" ""
			(at 0 0 90)
			(layer "F.Fab")
			(effects
				(font
					(size 1.27 1.27)
				)
			)
		)
		(duplicate_pad_numbers_are_jumpers no)
		(fp_poly
			(pts
				(xy -0.2794 -0.1016) (xy 0.2794 -0.1016) (xy 0.2794 0.9906) (xy -0.2794 0.9906)
			)
			(stroke
				(width 0)
				(type default)
			)
			(fill no)
			(layer "F.CrtYd")
		)
		(fp_line
			(start 0.2794 -0.1016)
			(end -0.2794 -0.1016)
			(stroke
				(width 0.1)
				(type default)
			)
			(layer "F.Fab")
		)
		(fp_line
			(start -0.2794 -0.1016)
			(end -0.2794 0.9906)
			(stroke
				(width 0.1)
				(type default)
			)
			(layer "F.Fab")
		)
		(fp_line
			(start 0.2794 0.9906)
			(end 0.2794 -0.1016)
			(stroke
				(width 0.1)
				(type default)
			)
			(layer "F.Fab")
		)
		(fp_line
			(start -0.2794 0.9906)
			(end 0.2794 0.9906)
			(stroke
				(width 0.1)
				(type default)
			)
			(layer "F.Fab")
		)
		(pad "1" smd rect
			(at 0 0 90)
			(size 0.508 0.508)
			(layers "F.Cu" "F.Mask" "F.Paste")
			(net "P3V3_STBY")
		)
		(pad "2" smd rect
			(at 0 0.889 90)
			(size 0.508 0.508)
			(layers "F.Cu" "F.Mask" "F.Paste")
			(net "FM_THROTTLE_N")
		)
		(zone
			(layer "F.Cu")
			(hatch none 0.5)
			(connect_pads
				(clearance 0)
			)
			(min_thickness 0.25)
			(keepout
				(tracks allowed)
				(vias not_allowed)
				(pads allowed)
				(copperpour not_allowed)
				(footprints allowed)
			)
			(placement
				(enabled no)
				(sheetname "")
			)
			(fill
				(thermal_gap 0.5)
				(thermal_bridge_width 0.5)
				(island_removal_mode 0)
			)
			(polygon
				(pts
					(xy 412.6992 -111.379) (xy 412.6992 -111.887) (xy 413.0802 -111.887) (xy 413.0802 -111.379)
				)
			)
		)
		(zone
			(layer "F.Cu")
			(hatch none 0.5)
			(connect_pads
				(clearance 0)
			)
			(min_thickness 0.25)
			(keepout
				(tracks not_allowed)
				(vias allowed)
				(pads allowed)
				(copperpour not_allowed)
				(footprints allowed)
			)
			(placement
				(enabled no)
				(sheetname "")
			)
			(fill
				(thermal_gap 0.5)
				(thermal_bridge_width 0.5)
				(island_removal_mode 0)
			)
			(polygon
				(pts
					(xy 413.0802 -111.379) (xy 413.0802 -111.887) (xy 412.6992 -111.887) (xy 412.6992 -111.379)
				)
			)
		)
	)
	(footprint ""
		(layer "F.Cu")
		(at 270.628872 -73.279)
		(property "Reference" "C5D52"
			(at 0 0 0)
			(layer "F.SilkS")
			(hide yes)
			(effects
				(font
					(size 1.27 1.27)
				)
			)
		)
		(property "Value" ""
			(at 0 0 0)
			(layer "F.Fab")
			(effects
				(font
					(size 1.27 1.27)
				)
			)
		)
		(duplicate_pad_numbers_are_jumpers no)
		(fp_poly
			(pts
				(xy -0.4953 -0.2032) (xy 0.4953 -0.2032) (xy 0.4953 1.6002) (xy -0.4953 1.6002)
			)
			(stroke
				(width 0)
				(type default)
			)
			(fill no)
			(layer "F.CrtYd")
		)
		(fp_line
			(start -0.4953 -0.2032)
			(end 0.4953 -0.2032)
			(stroke
				(width 0.1)
				(type default)
			)
			(layer "F.Fab")
		)
		(fp_line
			(start -0.4953 1.6002)
			(end -0.4953 -0.2032)
			(stroke
				(width 0.1)
				(type default)
			)
			(layer "F.Fab")
		)
		(fp_line
			(start 0.4953 -0.2032)
			(end 0.4953 1.6002)
			(stroke
				(width 0.1)
				(type default)
			)
			(layer "F.Fab")
		)
		(fp_line
			(start 0.4953 1.6002)
			(end -0.4953 1.6002)
			(stroke
				(width 0.1)
				(type default)
			)
			(layer "F.Fab")
		)
		(pad "1" smd rect
			(at 0 0)
			(size 0.762 0.889)
			(layers "F.Cu" "F.Mask" "F.Paste")
			(net "PVCCMCP_CPU0")
		)
		(pad "2" smd rect
			(at 0 1.397)
			(size 0.762 0.889)
			(layers "F.Cu" "F.Mask" "F.Paste")
			(net "GND")
		)
		(zone
			(layer "F.Cu")
			(hatch none 0.5)
			(connect_pads
				(clearance 0)
			)
			(min_thickness 0.25)
			(keepout
				(tracks not_allowed)
				(vias allowed)
				(pads allowed)
				(copperpour not_allowed)
				(footprints allowed)
			)
			(placement
				(enabled no)
				(sheetname "")
			)
			(fill
				(thermal_gap 0.5)
				(thermal_bridge_width 0.5)
				(island_removal_mode 0)
			)
			(polygon
				(pts
					(xy 270.247872 -72.8345) (xy 271.009872 -72.8345) (xy 271.009872 -72.3265) (xy 270.247872 -72.3265)
				)
			)
		)
	)
	(footprint ""
		(layer "F.Cu")
		(at 444.1825 -1.143 -90)
		(property "Reference" "R2P19"
			(at 0 0 270)
			(layer "F.SilkS")
			(hide yes)
			(effects
				(font
					(size 1.27 1.27)
				)
			)
		)
		(property "Value" ""
			(at 0 0 270)
			(layer "F.Fab")
			(effects
				(font
					(size 1.27 1.27)
				)
			)
		)
		(duplicate_pad_numbers_are_jumpers no)
		(fp_poly
			(pts
				(xy -0.2794 -0.1016) (xy 0.2794 -0.1016) (xy 0.2794 0.9906) (xy -0.2794 0.9906)
			)
			(stroke
				(width 0)
				(type default)
			)
			(fill no)
			(layer "F.CrtYd")
		)
		(fp_line
			(start -0.2794 0.9906)
			(end 0.2794 0.9906)
			(stroke
				(width 0.1)
				(type default)
			)
			(layer "F.Fab")
		)
		(fp_line
			(start 0.2794 0.9906)
			(end 0.2794 -0.1016)
			(stroke
				(width 0.1)
				(type default)
			)
			(layer "F.Fab")
		)
		(fp_line
			(start -0.2794 -0.1016)
			(end -0.2794 0.9906)
			(stroke
				(width 0.1)
				(type default)
			)
			(layer "F.Fab")
		)
		(fp_line
			(start 0.2794 -0.1016)
			(end -0.2794 -0.1016)
			(stroke
				(width 0.1)
				(type default)
			)
			(layer "F.Fab")
		)
		(pad "1" smd rect
			(at 0 0 270)
			(size 0.508 0.508)
			(layers "F.Cu" "F.Mask" "F.Paste")
			(net "P3V3_STBY")
		)
		(pad "2" smd rect
			(at 0 0.889 270)
			(size 0.508 0.508)
			(layers "F.Cu" "F.Mask" "F.Paste")
			(net "FM_DIS_ADR_DLY")
		)
		(zone
			(layer "F.Cu")
			(hatch none 0.5)
			(connect_pads
				(clearance 0)
			)
			(min_thickness 0.25)
			(keepout
				(tracks not_allowed)
				(vias allowed)
				(pads allowed)
				(copperpour not_allowed)
				(footprints allowed)
			)
			(placement
				(enabled no)
				(sheetname "")
			)
			(fill
				(thermal_gap 0.5)
				(thermal_bridge_width 0.5)
				(island_removal_mode 0)
			)
			(polygon
				(pts
					(xy 443.5475 -1.397) (xy 443.5475 -0.889) (xy 443.9285 -0.889) (xy 443.9285 -1.397)
				)
			)
		)
		(zone
			(layer "F.Cu")
			(hatch none 0.5)
			(connect_pads
				(clearance 0)
			)
			(min_thickness 0.25)
			(keepout
				(tracks allowed)
				(vias not_allowed)
				(pads allowed)
				(copperpour not_allowed)
				(footprints allowed)
			)
			(placement
				(enabled no)
				(sheetname "")
			)
			(fill
				(thermal_gap 0.5)
				(thermal_bridge_width 0.5)
				(island_removal_mode 0)
			)
			(polygon
				(pts
					(xy 443.9285 -1.397) (xy 443.9285 -0.889) (xy 443.5475 -0.889) (xy 443.5475 -1.397)
				)
			)
		)
	)
	(footprint ""
		(layer "F.Cu")
		(at 437.6293 -21.9964 -90)
		(property "Reference" "R1U1"
			(at 0 0 270)
			(layer "F.SilkS")
			(hide yes)
			(effects
				(font
					(size 1.27 1.27)
				)
			)
		)
		(property "Value" ""
			(at 0 0 270)
			(layer "F.Fab")
			(effects
				(font
					(size 1.27 1.27)
				)
			)
		)
		(duplicate_pad_numbers_are_jumpers no)
		(fp_poly
			(pts
				(xy -0.2794 -0.1016) (xy 0.2794 -0.1016) (xy 0.2794 0.9906) (xy -0.2794 0.9906)
			)
			(stroke
				(width 0)
				(type default)
			)
			(fill no)
			(layer "F.CrtYd")
		)
		(fp_line
			(start -0.2794 0.9906)
			(end 0.2794 0.9906)
			(stroke
				(width 0.1)
				(type default)
			)
			(layer "F.Fab")
		)
		(fp_line
			(start 0.2794 0.9906)
			(end 0.2794 -0.1016)
			(stroke
				(width 0.1)
				(type default)
			)
			(layer "F.Fab")
		)
		(fp_line
			(start -0.2794 -0.1016)
			(end -0.2794 0.9906)
			(stroke
				(width 0.1)
				(type default)
			)
			(layer "F.Fab")
		)
		(fp_line
			(start 0.2794 -0.1016)
			(end -0.2794 -0.1016)
			(stroke
				(width 0.1)
				(type default)
			)
			(layer "F.Fab")
		)
		(pad "1" smd rect
			(at 0 0 270)
			(size 0.508 0.508)
			(layers "F.Cu" "F.Mask" "F.Paste")
			(net "FAN_TACH3")
		)
		(pad "2" smd rect
			(at 0 0.889 270)
			(size 0.508 0.508)
			(layers "F.Cu" "F.Mask" "F.Paste")
			(net "GND")
		)
		(zone
			(layer "F.Cu")
			(hatch none 0.5)
			(connect_pads
				(clearance 0)
			)
			(min_thickness 0.25)
			(keepout
				(tracks not_allowed)
				(vias allowed)
				(pads allowed)
				(copperpour not_allowed)
				(footprints allowed)
			)
			(placement
				(enabled no)
				(sheetname "")
			)
			(fill
				(thermal_gap 0.5)
				(thermal_bridge_width 0.5)
				(island_removal_mode 0)
			)
			(polygon
				(pts
					(xy 436.9943 -22.2504) (xy 436.9943 -21.7424) (xy 437.3753 -21.7424) (xy 437.3753 -22.2504)
				)
			)
		)
		(zone
			(layer "F.Cu")
			(hatch none 0.5)
			(connect_pads
				(clearance 0)
			)
			(min_thickness 0.25)
			(keepout
				(tracks allowed)
				(vias not_allowed)
				(pads allowed)
				(copperpour not_allowed)
				(footprints allowed)
			)
			(placement
				(enabled no)
				(sheetname "")
			)
			(fill
				(thermal_gap 0.5)
				(thermal_bridge_width 0.5)
				(island_removal_mode 0)
			)
			(polygon
				(pts
					(xy 437.3753 -22.2504) (xy 437.3753 -21.7424) (xy 436.9943 -21.7424) (xy 436.9943 -22.2504)
				)
			)
		)
	)
	(footprint ""
		(layer "F.Cu")
		(at 180.8734 -131.7625)
		(property "Reference" "R4B7"
			(at 0 0 0)
			(layer "F.SilkS")
			(hide yes)
			(effects
				(font
					(size 1.27 1.27)
				)
			)
		)
		(property "Value" ""
			(at 0 0 0)
			(layer "F.Fab")
			(effects
				(font
					(size 1.27 1.27)
				)
			)
		)
		(duplicate_pad_numbers_are_jumpers no)
		(fp_poly
			(pts
				(xy -0.2794 -0.1016) (xy 0.2794 -0.1016) (xy 0.2794 0.9906) (xy -0.2794 0.9906)
			)
			(stroke
				(width 0)
				(type default)
			)
			(fill no)
			(layer "F.CrtYd")
		)
		(fp_line
			(start -0.2794 -0.1016)
			(end -0.2794 0.9906)
			(stroke
				(width 0.1)
				(type default)
			)
			(layer "F.Fab")
		)
		(fp_line
			(start -0.2794 0.9906)
			(end 0.2794 0.9906)
			(stroke
				(width 0.1)
				(type default)
			)
			(layer "F.Fab")
		)
		(fp_line
			(start 0.2794 -0.1016)
			(end -0.2794 -0.1016)
			(stroke
				(width 0.1)
				(type default)
			)
			(layer "F.Fab")
		)
		(fp_line
			(start 0.2794 0.9906)
			(end 0.2794 -0.1016)
			(stroke
				(width 0.1)
				(type default)
			)
			(layer "F.Fab")
		)
		(pad "1" smd rect
			(at 0 0)
			(size 0.508 0.508)
			(layers "F.Cu" "F.Mask" "F.Paste")
			(net "PWRGD_PVPP_KLM_R")
		)
		(pad "2" smd rect
			(at 0 0.889)
			(size 0.508 0.508)
			(layers "F.Cu" "F.Mask" "F.Paste")
			(net "PWRGD_PVPP_KLM")
		)
		(zone
			(layer "F.Cu")
			(hatch none 0.5)
			(connect_pads
				(clearance 0)
			)
			(min_thickness 0.25)
			(keepout
				(tracks allowed)
				(vias not_allowed)
				(pads allowed)
				(copperpour not_allowed)
				(footprints allowed)
			)
			(placement
				(enabled no)
				(sheetname "")
			)
			(fill
				(thermal_gap 0.5)
				(thermal_bridge_width 0.5)
				(island_removal_mode 0)
			)
			(polygon
				(pts
					(xy 180.6194 -131.5085) (xy 181.1274 -131.5085) (xy 181.1274 -131.1275) (xy 180.6194 -131.1275)
				)
			)
		)
		(zone
			(layer "F.Cu")
			(hatch none 0.5)
			(connect_pads
				(clearance 0)
			)
			(min_thickness 0.25)
			(keepout
				(tracks not_allowed)
				(vias allowed)
				(pads allowed)
				(copperpour not_allowed)
				(footprints allowed)
			)
			(placement
				(enabled no)
				(sheetname "")
			)
			(fill
				(thermal_gap 0.5)
				(thermal_bridge_width 0.5)
				(island_removal_mode 0)
			)
			(polygon
				(pts
					(xy 180.6194 -131.1275) (xy 181.1274 -131.1275) (xy 181.1274 -131.5085) (xy 180.6194 -131.5085)
				)
			)
		)
	)
	(footprint ""
		(layer "F.Cu")
		(at 408.051 -103.8225)
		(property "Reference" "R2N6"
			(at 0 0 0)
			(layer "F.SilkS")
			(hide yes)
			(effects
				(font
					(size 1.27 1.27)
				)
			)
		)
		(property "Value" ""
			(at 0 0 0)
			(layer "F.Fab")
			(effects
				(font
					(size 1.27 1.27)
				)
			)
		)
		(duplicate_pad_numbers_are_jumpers no)
		(fp_poly
			(pts
				(xy -0.2794 -0.1016) (xy 0.2794 -0.1016) (xy 0.2794 0.9906) (xy -0.2794 0.9906)
			)
			(stroke
				(width 0)
				(type default)
			)
			(fill no)
			(layer "F.CrtYd")
		)
		(fp_line
			(start -0.2794 -0.1016)
			(end -0.2794 0.9906)
			(stroke
				(width 0.1)
				(type default)
			)
			(layer "F.Fab")
		)
		(fp_line
			(start -0.2794 0.9906)
			(end 0.2794 0.9906)
			(stroke
				(width 0.1)
				(type default)
			)
			(layer "F.Fab")
		)
		(fp_line
			(start 0.2794 -0.1016)
			(end -0.2794 -0.1016)
			(stroke
				(width 0.1)
				(type default)
			)
			(layer "F.Fab")
		)
		(fp_line
			(start 0.2794 0.9906)
			(end 0.2794 -0.1016)
			(stroke
				(width 0.1)
				(type default)
			)
			(layer "F.Fab")
		)
		(pad "1" smd rect
			(at 0 0)
			(size 0.508 0.508)
			(layers "F.Cu" "F.Mask" "F.Paste")
			(net "P3V3_STBY")
		)
		(pad "2" smd rect
			(at 0 0.889)
			(size 0.508 0.508)
			(layers "F.Cu" "F.Mask" "F.Paste")
			(net "FM_GBE_LOM_DISABLE_N")
		)
		(zone
			(layer "F.Cu")
			(hatch none 0.5)
			(connect_pads
				(clearance 0)
			)
			(min_thickness 0.25)
			(keepout
				(tracks allowed)
				(vias not_allowed)
				(pads allowed)
				(copperpour not_allowed)
				(footprints allowed)
			)
			(placement
				(enabled no)
				(sheetname "")
			)
			(fill
				(thermal_gap 0.5)
				(thermal_bridge_width 0.5)
				(island_removal_mode 0)
			)
			(polygon
				(pts
					(xy 407.797 -103.5685) (xy 408.305 -103.5685) (xy 408.305 -103.1875) (xy 407.797 -103.1875)
				)
			)
		)
		(zone
			(layer "F.Cu")
			(hatch none 0.5)
			(connect_pads
				(clearance 0)
			)
			(min_thickness 0.25)
			(keepout
				(tracks not_allowed)
				(vias allowed)
				(pads allowed)
				(copperpour not_allowed)
				(footprints allowed)
			)
			(placement
				(enabled no)
				(sheetname "")
			)
			(fill
				(thermal_gap 0.5)
				(thermal_bridge_width 0.5)
				(island_removal_mode 0)
			)
			(polygon
				(pts
					(xy 407.797 -103.1875) (xy 408.305 -103.1875) (xy 408.305 -103.5685) (xy 407.797 -103.5685)
				)
			)
		)
	)
	(footprint ""
		(layer "F.Cu")
		(at 394.8176 -64.8462 180)
		(property "Reference" "C8E13"
			(at 0 0 180)
			(layer "F.SilkS")
			(hide yes)
			(effects
				(font
					(size 1.27 1.27)
				)
			)
		)
		(property "Value" ""
			(at 0 0 180)
			(layer "F.Fab")
			(effects
				(font
					(size 1.27 1.27)
				)
			)
		)
		(duplicate_pad_numbers_are_jumpers no)
		(fp_poly
			(pts
				(xy 0.3048 -0.1016) (xy 0.3048 0.9906) (xy -0.3048 0.9906) (xy -0.3048 -0.1016)
			)
			(stroke
				(width 0)
				(type default)
			)
			(fill no)
			(layer "F.CrtYd")
		)
		(fp_line
			(start 0.3048 0.9906)
			(end 0.3048 -0.1016)
			(stroke
				(width 0.1)
				(type default)
			)
			(layer "F.Fab")
		)
		(fp_line
			(start 0.3048 -0.1016)
			(end -0.3048 -0.1016)
			(stroke
				(width 0.1)
				(type default)
			)
			(layer "F.Fab")
		)
		(fp_line
			(start -0.3048 0.9906)
			(end 0.3048 0.9906)
			(stroke
				(width 0.1)
				(type default)
			)
			(layer "F.Fab")
		)
		(fp_line
			(start -0.3048 -0.1016)
			(end -0.3048 0.9906)
			(stroke
				(width 0.1)
				(type default)
			)
			(layer "F.Fab")
		)
		(pad "1" smd rect
			(at 0 0 180)
			(size 0.508 0.508)
			(layers "F.Cu" "F.Mask" "F.Paste")
			(net "PWRGD_P12V_HSC_DLY")
		)
		(pad "2" smd rect
			(at 0 0.889 180)
			(size 0.508 0.508)
			(layers "F.Cu" "F.Mask" "F.Paste")
			(net "AGND_P5V_STBY")
		)
		(zone
			(layer "F.Cu")
			(hatch none 0.5)
			(connect_pads
				(clearance 0)
			)
			(min_thickness 0.25)
			(keepout
				(tracks not_allowed)
				(vias allowed)
				(pads allowed)
				(copperpour not_allowed)
				(footprints allowed)
			)
			(placement
				(enabled no)
				(sheetname "")
			)
			(fill
				(thermal_gap 0.5)
				(thermal_bridge_width 0.5)
				(island_removal_mode 0)
			)
			(polygon
				(pts
					(xy 395.0716 -65.4812) (xy 394.5636 -65.4812) (xy 394.5636 -65.1002) (xy 395.0716 -65.1002)
				)
			)
		)
		(zone
			(layer "F.Cu")
			(hatch none 0.5)
			(connect_pads
				(clearance 0)
			)
			(min_thickness 0.25)
			(keepout
				(tracks allowed)
				(vias not_allowed)
				(pads allowed)
				(copperpour not_allowed)
				(footprints allowed)
			)
			(placement
				(enabled no)
				(sheetname "")
			)
			(fill
				(thermal_gap 0.5)
				(thermal_bridge_width 0.5)
				(island_removal_mode 0)
			)
			(polygon
				(pts
					(xy 395.0716 -65.1002) (xy 394.5636 -65.1002) (xy 394.5636 -65.4812) (xy 395.0716 -65.4812)
				)
			)
		)
	)
	(footprint ""
		(layer "F.Cu")
		(at 341.376 -19.558 180)
		(property "Reference" "C7F14"
			(at 0 0 180)
			(layer "F.SilkS")
			(hide yes)
			(effects
				(font
					(size 1.27 1.27)
				)
			)
		)
		(property "Value" ""
			(at 0 0 180)
			(layer "F.Fab")
			(effects
				(font
					(size 1.27 1.27)
				)
			)
		)
		(duplicate_pad_numbers_are_jumpers no)
		(fp_poly
			(pts
				(xy 0.3048 -0.1016) (xy 0.3048 0.9906) (xy -0.3048 0.9906) (xy -0.3048 -0.1016)
			)
			(stroke
				(width 0)
				(type default)
			)
			(fill no)
			(layer "F.CrtYd")
		)
		(fp_line
			(start 0.3048 0.9906)
			(end 0.3048 -0.1016)
			(stroke
				(width 0.1)
				(type default)
			)
			(layer "F.Fab")
		)
		(fp_line
			(start 0.3048 -0.1016)
			(end -0.3048 -0.1016)
			(stroke
				(width 0.1)
				(type default)
			)
			(layer "F.Fab")
		)
		(fp_line
			(start -0.3048 0.9906)
			(end 0.3048 0.9906)
			(stroke
				(width 0.1)
				(type default)
			)
			(layer "F.Fab")
		)
		(fp_line
			(start -0.3048 -0.1016)
			(end -0.3048 0.9906)
			(stroke
				(width 0.1)
				(type default)
			)
			(layer "F.Fab")
		)
		(pad "1" smd rect
			(at 0 0 180)
			(size 0.508 0.508)
			(layers "F.Cu" "F.Mask" "F.Paste")
			(net "PWRGD_PVDDQ_ABC_R")
		)
		(pad "2" smd rect
			(at 0 0.889 180)
			(size 0.508 0.508)
			(layers "F.Cu" "F.Mask" "F.Paste")
			(net "GND")
		)
		(zone
			(layer "F.Cu")
			(hatch none 0.5)
			(connect_pads
				(clearance 0)
			)
			(min_thickness 0.25)
			(keepout
				(tracks not_allowed)
				(vias allowed)
				(pads allowed)
				(copperpour not_allowed)
				(footprints allowed)
			)
			(placement
				(enabled no)
				(sheetname "")
			)
			(fill
				(thermal_gap 0.5)
				(thermal_bridge_width 0.5)
				(island_removal_mode 0)
			)
			(polygon
				(pts
					(xy 341.63 -20.193) (xy 341.122 -20.193) (xy 341.122 -19.812) (xy 341.63 -19.812)
				)
			)
		)
		(zone
			(layer "F.Cu")
			(hatch none 0.5)
			(connect_pads
				(clearance 0)
			)
			(min_thickness 0.25)
			(keepout
				(tracks allowed)
				(vias not_allowed)
				(pads allowed)
				(copperpour not_allowed)
				(footprints allowed)
			)
			(placement
				(enabled no)
				(sheetname "")
			)
			(fill
				(thermal_gap 0.5)
				(thermal_bridge_width 0.5)
				(island_removal_mode 0)
			)
			(polygon
				(pts
					(xy 341.63 -19.812) (xy 341.122 -19.812) (xy 341.122 -20.193) (xy 341.63 -20.193)
				)
			)
		)
	)
	(footprint ""
		(layer "F.Cu")
		(at 101.3968 -12.954 90)
		(property "Reference" "C2G5"
			(at 1.848866 0.752348 90)
			(unlocked yes)
			(layer "F.SilkS")
			(effects
				(font
					(size 1.27 0.9652)
					(thickness 0.1524)
				)
			)
		)
		(property "Value" ""
			(at 0 0 90)
			(layer "F.Fab")
			(effects
				(font
					(size 1.27 1.27)
				)
			)
		)
		(duplicate_pad_numbers_are_jumpers no)
		(fp_rect
			(start -0.500126 1.598422)
			(end 0.500126 -0.201422)
			(stroke
				(width 0)
				(type default)
			)
			(fill no)
			(layer "F.CrtYd")
		)
		(fp_line
			(start 0.500126 -0.201422)
			(end 0.500126 1.598422)
			(stroke
				(width 0.1)
				(type default)
			)
			(layer "F.Fab")
		)
		(fp_line
			(start -0.500126 -0.201422)
			(end 0.500126 -0.201422)
			(stroke
				(width 0.1)
				(type default)
			)
			(layer "F.Fab")
		)
		(fp_line
			(start 0.500126 1.598422)
			(end -0.500126 1.598422)
			(stroke
				(width 0.1)
				(type default)
			)
			(layer "F.Fab")
		)
		(fp_line
			(start -0.500126 1.598422)
			(end -0.500126 -0.201422)
			(stroke
				(width 0.1)
				(type default)
			)
			(layer "F.Fab")
		)
		(pad "1" smd rect
			(at 0 0)
			(size 0.889 0.9906)
			(layers "F.Cu" "F.Mask" "F.Paste")
			(net "PVDDQ_GHJ")
		)
		(pad "2" smd rect
			(at 0 1.397)
			(size 0.889 0.9906)
			(layers "F.Cu" "F.Mask" "F.Paste")
			(net "GND")
		)
		(zone
			(layer "F.Cu")
			(hatch none 0.5)
			(connect_pads
				(clearance 0)
			)
			(min_thickness 0.25)
			(keepout
				(tracks allowed)
				(vias not_allowed)
				(pads allowed)
				(copperpour not_allowed)
				(footprints allowed)
			)
			(placement
				(enabled no)
				(sheetname "")
			)
			(fill
				(thermal_gap 0.5)
				(thermal_bridge_width 0.5)
				(island_removal_mode 0)
			)
			(polygon
				(pts
					(xy 102.3493 -12.4587) (xy 102.3493 -13.4493) (xy 101.8413 -13.4493) (xy 101.8413 -12.4587)
				)
			)
		)
		(zone
			(layer "F.Cu")
			(hatch none 0.5)
			(connect_pads
				(clearance 0)
			)
			(min_thickness 0.25)
			(keepout
				(tracks not_allowed)
				(vias allowed)
				(pads allowed)
				(copperpour not_allowed)
				(footprints allowed)
			)
			(placement
				(enabled no)
				(sheetname "")
			)
			(fill
				(thermal_gap 0.5)
				(thermal_bridge_width 0.5)
				(island_removal_mode 0)
			)
			(polygon
				(pts
					(xy 102.3493 -12.4587) (xy 102.3493 -13.4493) (xy 101.8413 -13.4493) (xy 101.8413 -12.4587)
				)
			)
		)
	)
	(footprint ""
		(layer "F.Cu")
		(at 395.579092 -10.968736)
		(property "Reference" "C7G23"
			(at 0 0 0)
			(layer "F.SilkS")
			(hide yes)
			(effects
				(font
					(size 1.27 1.27)
				)
			)
		)
		(property "Value" ""
			(at 0 0 0)
			(layer "F.Fab")
			(effects
				(font
					(size 1.27 1.27)
				)
			)
		)
		(duplicate_pad_numbers_are_jumpers no)
		(fp_rect
			(start -0.3048 0.9906)
			(end 0.3048 -0.1016)
			(stroke
				(width 0)
				(type default)
			)
			(fill no)
			(layer "F.CrtYd")
		)
		(fp_line
			(start -0.3048 -0.1016)
			(end -0.3048 0.9906)
			(stroke
				(width 0.1)
				(type default)
			)
			(layer "F.Fab")
		)
		(fp_line
			(start -0.3048 0.9906)
			(end 0.3048 0.9906)
			(stroke
				(width 0.1)
				(type default)
			)
			(layer "F.Fab")
		)
		(fp_line
			(start 0.3048 -0.1016)
			(end -0.3048 -0.1016)
			(stroke
				(width 0.1)
				(type default)
			)
			(layer "F.Fab")
		)
		(fp_line
			(start 0.3048 0.9906)
			(end 0.3048 -0.1016)
			(stroke
				(width 0.1)
				(type default)
			)
			(layer "F.Fab")
		)
		(pad "1" smd rect
			(at 0 0)
			(size 0.508 0.508)
			(layers "F.Cu" "F.Mask" "F.Paste")
			(net "P3E_CPU0_PE2_SS_TXP<6>")
		)
		(pad "2" smd rect
			(at 0 0.889)
			(size 0.508 0.508)
			(layers "F.Cu" "F.Mask" "F.Paste")
			(net "P3E_CPU0_PE2_SS_C_TXP<6>")
		)
		(zone
			(layer "F.Cu")
			(hatch none 0.5)
			(connect_pads
				(clearance 0)
			)
			(min_thickness 0.25)
			(keepout
				(tracks allowed)
				(vias not_allowed)
				(pads allowed)
				(copperpour not_allowed)
				(footprints allowed)
			)
			(placement
				(enabled no)
				(sheetname "")
			)
			(fill
				(thermal_gap 0.5)
				(thermal_bridge_width 0.5)
				(island_removal_mode 0)
			)
			(polygon
				(pts
					(xy 395.325092 -10.333736) (xy 395.833092 -10.333736) (xy 395.833092 -10.714736) (xy 395.325092 -10.714736)
				)
			)
		)
		(zone
			(layer "F.Cu")
			(hatch none 0.5)
			(connect_pads
				(clearance 0)
			)
			(min_thickness 0.25)
			(keepout
				(tracks not_allowed)
				(vias allowed)
				(pads allowed)
				(copperpour not_allowed)
				(footprints allowed)
			)
			(placement
				(enabled no)
				(sheetname "")
			)
			(fill
				(thermal_gap 0.5)
				(thermal_bridge_width 0.5)
				(island_removal_mode 0)
			)
			(polygon
				(pts
					(xy 395.325092 -10.333736) (xy 395.833092 -10.333736) (xy 395.833092 -10.714736) (xy 395.325092 -10.714736)
				)
			)
		)
	)
	(footprint ""
		(layer "F.Cu")
		(at 482.00056 -34.6964 180)
		(property "Reference" "C8F19"
			(at -0.8382 -0.67818 180)
			(unlocked yes)
			(layer "F.SilkS")
			(effects
				(font
					(size 0.4064 0.254)
					(thickness 0.1524)
				)
				(justify left)
			)
		)
		(property "Value" ""
			(at 0 0 180)
			(layer "F.Fab")
			(effects
				(font
					(size 1.27 1.27)
				)
			)
		)
		(duplicate_pad_numbers_are_jumpers no)
		(fp_poly
			(pts
				(xy 0.3048 -0.1016) (xy 0.3048 0.9906) (xy -0.3048 0.9906) (xy -0.3048 -0.1016)
			)
			(stroke
				(width 0)
				(type default)
			)
			(fill no)
			(layer "F.CrtYd")
		)
		(fp_line
			(start 0.3048 0.9906)
			(end 0.3048 -0.1016)
			(stroke
				(width 0.1)
				(type default)
			)
			(layer "F.Fab")
		)
		(fp_line
			(start 0.3048 -0.1016)
			(end -0.3048 -0.1016)
			(stroke
				(width 0.1)
				(type default)
			)
			(layer "F.Fab")
		)
		(fp_line
			(start -0.3048 0.9906)
			(end 0.3048 0.9906)
			(stroke
				(width 0.1)
				(type default)
			)
			(layer "F.Fab")
		)
		(fp_line
			(start -0.3048 -0.1016)
			(end -0.3048 0.9906)
			(stroke
				(width 0.1)
				(type default)
			)
			(layer "F.Fab")
		)
		(pad "1" smd rect
			(at 0 0 180)
			(size 0.508 0.508)
			(layers "F.Cu" "F.Mask" "F.Paste")
			(net "XTAL_CK_MNG_OUT")
		)
		(pad "2" smd rect
			(at 0 0.889 180)
			(size 0.508 0.508)
			(layers "F.Cu" "F.Mask" "F.Paste")
			(net "GND")
		)
		(zone
			(layer "F.Cu")
			(hatch none 0.5)
			(connect_pads
				(clearance 0)
			)
			(min_thickness 0.25)
			(keepout
				(tracks not_allowed)
				(vias allowed)
				(pads allowed)
				(copperpour not_allowed)
				(footprints allowed)
			)
			(placement
				(enabled no)
				(sheetname "")
			)
			(fill
				(thermal_gap 0.5)
				(thermal_bridge_width 0.5)
				(island_removal_mode 0)
			)
			(polygon
				(pts
					(xy 482.25456 -35.3314) (xy 481.74656 -35.3314) (xy 481.74656 -34.9504) (xy 482.25456 -34.9504)
				)
			)
		)
		(zone
			(layer "F.Cu")
			(hatch none 0.5)
			(connect_pads
				(clearance 0)
			)
			(min_thickness 0.25)
			(keepout
				(tracks allowed)
				(vias not_allowed)
				(pads allowed)
				(copperpour not_allowed)
				(footprints allowed)
			)
			(placement
				(enabled no)
				(sheetname "")
			)
			(fill
				(thermal_gap 0.5)
				(thermal_bridge_width 0.5)
				(island_removal_mode 0)
			)
			(polygon
				(pts
					(xy 482.25456 -34.9504) (xy 481.74656 -34.9504) (xy 481.74656 -35.3314) (xy 482.25456 -35.3314)
				)
			)
		)
	)
	(footprint ""
		(layer "F.Cu")
		(at 340.775036 -26.973276)
		(property "Reference" "R7F8"
			(at 1.01473 0.656336 270)
			(unlocked yes)
			(layer "F.SilkS")
			(effects
				(font
					(size 0.4064 0.254)
					(thickness 0.1524)
				)
			)
		)
		(property "Value" ""
			(at 0 0 0)
			(layer "F.Fab")
			(effects
				(font
					(size 1.27 1.27)
				)
			)
		)
		(duplicate_pad_numbers_are_jumpers no)
		(fp_poly
			(pts
				(xy -0.4953 -0.2032) (xy 0.4953 -0.2032) (xy 0.4953 1.6002) (xy -0.4953 1.6002)
			)
			(stroke
				(width 0)
				(type default)
			)
			(fill no)
			(layer "F.CrtYd")
		)
		(fp_line
			(start -0.4953 -0.2032)
			(end 0.4953 -0.2032)
			(stroke
				(width 0.1)
				(type default)
			)
			(layer "F.Fab")
		)
		(fp_line
			(start -0.4953 1.6002)
			(end -0.4953 -0.2032)
			(stroke
				(width 0.1)
				(type default)
			)
			(layer "F.Fab")
		)
		(fp_line
			(start 0.4953 -0.2032)
			(end 0.4953 1.6002)
			(stroke
				(width 0.1)
				(type default)
			)
			(layer "F.Fab")
		)
		(fp_line
			(start 0.4953 1.6002)
			(end -0.4953 1.6002)
			(stroke
				(width 0.1)
				(type default)
			)
			(layer "F.Fab")
		)
		(pad "1" smd rect
			(at 0 0)
			(size 0.762 0.889)
			(layers "F.Cu" "F.Mask" "F.Paste")
			(net "VR_PVPP_ABC_BOOT")
		)
		(pad "2" smd rect
			(at 0 1.397)
			(size 0.762 0.889)
			(layers "F.Cu" "F.Mask" "F.Paste")
			(net "VR_PVPP_ABC_BOOT_R")
		)
		(zone
			(layer "F.Cu")
			(hatch none 0.5)
			(connect_pads
				(clearance 0)
			)
			(min_thickness 0.25)
			(keepout
				(tracks not_allowed)
				(vias allowed)
				(pads allowed)
				(copperpour not_allowed)
				(footprints allowed)
			)
			(placement
				(enabled no)
				(sheetname "")
			)
			(fill
				(thermal_gap 0.5)
				(thermal_bridge_width 0.5)
				(island_removal_mode 0)
			)
			(polygon
				(pts
					(xy 340.394036 -26.020776) (xy 341.156036 -26.020776) (xy 341.156036 -26.528776) (xy 340.394036 -26.528776)
				)
			)
		)
		(zone
			(layer "F.Cu")
			(hatch none 0.5)
			(connect_pads
				(clearance 0)
			)
			(min_thickness 0.25)
			(keepout
				(tracks allowed)
				(vias not_allowed)
				(pads allowed)
				(copperpour not_allowed)
				(footprints allowed)
			)
			(placement
				(enabled no)
				(sheetname "")
			)
			(fill
				(thermal_gap 0.5)
				(thermal_bridge_width 0.5)
				(island_removal_mode 0)
			)
			(polygon
				(pts
					(xy 341.156036 -26.020776) (xy 341.156036 -26.528776) (xy 340.394036 -26.528776) (xy 340.394036 -26.020776)
				)
			)
		)
	)
	(footprint ""
		(layer "F.Cu")
		(at -0.27432 -15.3924)
		(property "Reference" "R1G25"
			(at -0.8382 -0.67818 0)
			(unlocked yes)
			(layer "F.SilkS")
			(effects
				(font
					(size 0.4064 0.254)
					(thickness 0.1524)
				)
				(justify left)
			)
		)
		(property "Value" ""
			(at 0 0 0)
			(layer "F.Fab")
			(effects
				(font
					(size 1.27 1.27)
				)
			)
		)
		(duplicate_pad_numbers_are_jumpers no)
		(fp_rect
			(start -0.2794 0.9906)
			(end 0.2794 -0.1016)
			(stroke
				(width 0)
				(type default)
			)
			(fill no)
			(layer "F.CrtYd")
		)
		(fp_line
			(start -0.2794 -0.1016)
			(end -0.2794 0.9906)
			(stroke
				(width 0.1)
				(type default)
			)
			(layer "F.Fab")
		)
		(fp_line
			(start -0.2794 0.9906)
			(end 0.2794 0.9906)
			(stroke
				(width 0.1)
				(type default)
			)
			(layer "F.Fab")
		)
		(fp_line
			(start 0.2794 -0.1016)
			(end -0.2794 -0.1016)
			(stroke
				(width 0.1)
				(type default)
			)
			(layer "F.Fab")
		)
		(fp_line
			(start 0.2794 0.9906)
			(end 0.2794 -0.1016)
			(stroke
				(width 0.1)
				(type default)
			)
			(layer "F.Fab")
		)
		(pad "1" smd rect
			(at 0 0)
			(size 0.508 0.508)
			(layers "F.Cu" "F.Mask" "F.Paste")
			(net "VR_PVDDQ_GHJ_PH2_OCSET")
		)
		(pad "2" smd rect
			(at 0 0.889)
			(size 0.508 0.508)
			(layers "F.Cu" "F.Mask" "F.Paste")
			(net "GND")
		)
		(zone
			(layer "F.Cu")
			(hatch none 0.5)
			(connect_pads
				(clearance 0)
			)
			(min_thickness 0.25)
			(keepout
				(tracks not_allowed)
				(vias allowed)
				(pads allowed)
				(copperpour not_allowed)
				(footprints allowed)
			)
			(placement
				(enabled no)
				(sheetname "")
			)
			(fill
				(thermal_gap 0.5)
				(thermal_bridge_width 0.5)
				(island_removal_mode 0)
			)
			(polygon
				(pts
					(xy -0.52832 -14.7574) (xy -0.02032 -14.7574) (xy -0.02032 -15.1384) (xy -0.52832 -15.1384)
				)
			)
		)
		(zone
			(layer "F.Cu")
			(hatch none 0.5)
			(connect_pads
				(clearance 0)
			)
			(min_thickness 0.25)
			(keepout
				(tracks allowed)
				(vias not_allowed)
				(pads allowed)
				(copperpour not_allowed)
				(footprints allowed)
			)
			(placement
				(enabled no)
				(sheetname "")
			)
			(fill
				(thermal_gap 0.5)
				(thermal_bridge_width 0.5)
				(island_removal_mode 0)
			)
			(polygon
				(pts
					(xy -0.52832 -14.7574) (xy -0.02032 -14.7574) (xy -0.02032 -15.1384) (xy -0.52832 -15.1384)
				)
			)
		)
	)
	(footprint ""
		(layer "F.Cu")
		(at 8.993378 4.911598 -90)
		(property "Reference" "R1G23"
			(at 0 0 270)
			(layer "F.SilkS")
			(hide yes)
			(effects
				(font
					(size 1.27 1.27)
				)
			)
		)
		(property "Value" ""
			(at 0 0 270)
			(layer "F.Fab")
			(effects
				(font
					(size 1.27 1.27)
				)
			)
		)
		(duplicate_pad_numbers_are_jumpers no)
		(fp_poly
			(pts
				(xy -0.2794 -0.1016) (xy 0.2794 -0.1016) (xy 0.2794 0.9906) (xy -0.2794 0.9906)
			)
			(stroke
				(width 0)
				(type default)
			)
			(fill no)
			(layer "F.CrtYd")
		)
		(fp_line
			(start -0.2794 0.9906)
			(end 0.2794 0.9906)
			(stroke
				(width 0.1)
				(type default)
			)
			(layer "F.Fab")
		)
		(fp_line
			(start 0.2794 0.9906)
			(end 0.2794 -0.1016)
			(stroke
				(width 0.1)
				(type default)
			)
			(layer "F.Fab")
		)
		(fp_line
			(start -0.2794 -0.1016)
			(end -0.2794 0.9906)
			(stroke
				(width 0.1)
				(type default)
			)
			(layer "F.Fab")
		)
		(fp_line
			(start 0.2794 -0.1016)
			(end -0.2794 -0.1016)
			(stroke
				(width 0.1)
				(type default)
			)
			(layer "F.Fab")
		)
		(pad "1" smd rect
			(at 0 0 270)
			(size 0.508 0.508)
			(layers "F.Cu" "F.Mask" "F.Paste")
			(net "VR_PVDDQ_GHJ_XADDR1")
		)
		(pad "2" smd rect
			(at 0 0.889 270)
			(size 0.508 0.508)
			(layers "F.Cu" "F.Mask" "F.Paste")
			(net "GND")
		)
		(zone
			(layer "F.Cu")
			(hatch none 0.5)
			(connect_pads
				(clearance 0)
			)
			(min_thickness 0.25)
			(keepout
				(tracks not_allowed)
				(vias allowed)
				(pads allowed)
				(copperpour not_allowed)
				(footprints allowed)
			)
			(placement
				(enabled no)
				(sheetname "")
			)
			(fill
				(thermal_gap 0.5)
				(thermal_bridge_width 0.5)
				(island_removal_mode 0)
			)
			(polygon
				(pts
					(xy 8.358378 4.657598) (xy 8.358378 5.165598) (xy 8.739378 5.165598) (xy 8.739378 4.657598)
				)
			)
		)
		(zone
			(layer "F.Cu")
			(hatch none 0.5)
			(connect_pads
				(clearance 0)
			)
			(min_thickness 0.25)
			(keepout
				(tracks allowed)
				(vias not_allowed)
				(pads allowed)
				(copperpour not_allowed)
				(footprints allowed)
			)
			(placement
				(enabled no)
				(sheetname "")
			)
			(fill
				(thermal_gap 0.5)
				(thermal_bridge_width 0.5)
				(island_removal_mode 0)
			)
			(polygon
				(pts
					(xy 8.739378 4.657598) (xy 8.739378 5.165598) (xy 8.358378 5.165598) (xy 8.358378 4.657598)
				)
			)
		)
	)
	(footprint ""
		(layer "F.Cu")
		(at 435.5719 -19.755612)
		(property "Reference" "R25W142"
			(at -0.8382 -0.67818 0)
			(unlocked yes)
			(layer "F.SilkS")
			(effects
				(font
					(size 0.4064 0.254)
					(thickness 0.1524)
				)
				(justify left)
			)
		)
		(property "Value" ""
			(at 0 0 0)
			(layer "F.Fab")
			(effects
				(font
					(size 1.27 1.27)
				)
			)
		)
		(duplicate_pad_numbers_are_jumpers no)
		(fp_poly
			(pts
				(xy -0.2794 -0.1016) (xy 0.2794 -0.1016) (xy 0.2794 0.9906) (xy -0.2794 0.9906)
			)
			(stroke
				(width 0)
				(type default)
			)
			(fill no)
			(layer "F.CrtYd")
		)
		(fp_line
			(start -0.2794 -0.1016)
			(end -0.2794 0.9906)
			(stroke
				(width 0.1)
				(type default)
			)
			(layer "F.Fab")
		)
		(fp_line
			(start -0.2794 0.9906)
			(end 0.2794 0.9906)
			(stroke
				(width 0.1)
				(type default)
			)
			(layer "F.Fab")
		)
		(fp_line
			(start 0.2794 -0.1016)
			(end -0.2794 -0.1016)
			(stroke
				(width 0.1)
				(type default)
			)
			(layer "F.Fab")
		)
		(fp_line
			(start 0.2794 0.9906)
			(end 0.2794 -0.1016)
			(stroke
				(width 0.1)
				(type default)
			)
			(layer "F.Fab")
		)
		(pad "1" smd rect
			(at 0 0)
			(size 0.508 0.508)
			(layers "F.Cu" "F.Mask" "F.Paste")
			(net "PUMP_TACH1")
		)
		(pad "2" smd rect
			(at 0 0.889)
			(size 0.508 0.508)
			(layers "F.Cu" "F.Mask" "F.Paste")
			(net "GND")
		)
		(zone
			(layer "F.Cu")
			(hatch none 0.5)
			(connect_pads
				(clearance 0)
			)
			(min_thickness 0.25)
			(keepout
				(tracks allowed)
				(vias not_allowed)
				(pads allowed)
				(copperpour not_allowed)
				(footprints allowed)
			)
			(placement
				(enabled no)
				(sheetname "")
			)
			(fill
				(thermal_gap 0.5)
				(thermal_bridge_width 0.5)
				(island_removal_mode 0)
			)
			(polygon
				(pts
					(xy 435.3179 -19.501612) (xy 435.8259 -19.501612) (xy 435.8259 -19.120612) (xy 435.3179 -19.120612)
				)
			)
		)
		(zone
			(layer "F.Cu")
			(hatch none 0.5)
			(connect_pads
				(clearance 0)
			)
			(min_thickness 0.25)
			(keepout
				(tracks not_allowed)
				(vias allowed)
				(pads allowed)
				(copperpour not_allowed)
				(footprints allowed)
			)
			(placement
				(enabled no)
				(sheetname "")
			)
			(fill
				(thermal_gap 0.5)
				(thermal_bridge_width 0.5)
				(island_removal_mode 0)
			)
			(polygon
				(pts
					(xy 435.3179 -19.120612) (xy 435.8259 -19.120612) (xy 435.8259 -19.501612) (xy 435.3179 -19.501612)
				)
			)
		)
	)
	(footprint ""
		(layer "F.Cu")
		(at 407.749502 -122.823986 90)
		(property "Reference" "R1W17"
			(at -0.8382 -0.67818 90)
			(unlocked yes)
			(layer "F.SilkS")
			(effects
				(font
					(size 0.4064 0.254)
					(thickness 0.1524)
				)
				(justify left)
			)
		)
		(property "Value" ""
			(at 0 0 90)
			(layer "F.Fab")
			(effects
				(font
					(size 1.27 1.27)
				)
			)
		)
		(duplicate_pad_numbers_are_jumpers no)
		(fp_poly
			(pts
				(xy -0.2794 -0.1016) (xy 0.2794 -0.1016) (xy 0.2794 0.9906) (xy -0.2794 0.9906)
			)
			(stroke
				(width 0)
				(type default)
			)
			(fill no)
			(layer "F.CrtYd")
		)
		(fp_line
			(start 0.2794 -0.1016)
			(end -0.2794 -0.1016)
			(stroke
				(width 0.1)
				(type default)
			)
			(layer "F.Fab")
		)
		(fp_line
			(start -0.2794 -0.1016)
			(end -0.2794 0.9906)
			(stroke
				(width 0.1)
				(type default)
			)
			(layer "F.Fab")
		)
		(fp_line
			(start 0.2794 0.9906)
			(end 0.2794 -0.1016)
			(stroke
				(width 0.1)
				(type default)
			)
			(layer "F.Fab")
		)
		(fp_line
			(start -0.2794 0.9906)
			(end 0.2794 0.9906)
			(stroke
				(width 0.1)
				(type default)
			)
			(layer "F.Fab")
		)
		(pad "1" smd rect
			(at 0 0 90)
			(size 0.508 0.508)
			(layers "F.Cu" "F.Mask" "F.Paste")
			(net "USB_PCH_BMC_P4_DN_R")
		)
		(pad "2" smd rect
			(at 0 0.889 90)
			(size 0.508 0.508)
			(layers "F.Cu" "F.Mask" "F.Paste")
			(net "USB_PCH_BMC_P4_DN")
		)
		(zone
			(layer "F.Cu")
			(hatch none 0.5)
			(connect_pads
				(clearance 0)
			)
			(min_thickness 0.25)
			(keepout
				(tracks allowed)
				(vias not_allowed)
				(pads allowed)
				(copperpour not_allowed)
				(footprints allowed)
			)
			(placement
				(enabled no)
				(sheetname "")
			)
			(fill
				(thermal_gap 0.5)
				(thermal_bridge_width 0.5)
				(island_removal_mode 0)
			)
			(polygon
				(pts
					(xy 408.003502 -122.569986) (xy 408.003502 -123.077986) (xy 408.384502 -123.077986) (xy 408.384502 -122.569986)
				)
			)
		)
		(zone
			(layer "F.Cu")
			(hatch none 0.5)
			(connect_pads
				(clearance 0)
			)
			(min_thickness 0.25)
			(keepout
				(tracks not_allowed)
				(vias allowed)
				(pads allowed)
				(copperpour not_allowed)
				(footprints allowed)
			)
			(placement
				(enabled no)
				(sheetname "")
			)
			(fill
				(thermal_gap 0.5)
				(thermal_bridge_width 0.5)
				(island_removal_mode 0)
			)
			(polygon
				(pts
					(xy 408.384502 -122.569986) (xy 408.384502 -123.077986) (xy 408.003502 -123.077986) (xy 408.003502 -122.569986)
				)
			)
		)
	)
	(footprint ""
		(layer "F.Cu")
		(at 492.376714 -55.865268)
		(property "Reference" "C30W6"
			(at 0 0 0)
			(layer "F.SilkS")
			(hide yes)
			(effects
				(font
					(size 1.27 1.27)
				)
			)
		)
		(property "Value" "*"
			(at -0.0762 -6.2357 0)
			(unlocked yes)
			(layer "F.Fab")
			(hide yes)
			(effects
				(font
					(size 1.27 1.016)
					(thickness 0.1524)
				)
			)
		)
		(property "Device Type" "SC22U16V5MX-4-GP_SMD-BCG5-SC22A"
			(at -0.0762 -8.2677 0)
			(unlocked yes)
			(layer "F.Fab")
			(hide yes)
			(effects
				(font
					(size 1.27 1.016)
					(thickness 0.1524)
				)
			)
		)
		(duplicate_pad_numbers_are_jumpers no)
		(fp_line
			(start 0.635 0)
			(end -0.635 0)
			(stroke
				(width 0.508)
				(type default)
			)
			(layer "F.SilkS")
		)
		(fp_rect
			(start -0.9652 1.778)
			(end 0.9652 -1.778)
			(stroke
				(width 0)
				(type default)
			)
			(fill no)
			(layer "F.CrtYd")
		)
		(fp_poly
			(pts
				(xy -0.9652 -1.778) (xy 0.9652 -1.778) (xy 0.9652 1.778) (xy -0.9652 1.778)
			)
			(stroke
				(width 0)
				(type default)
			)
			(fill no)
			(layer "F.Fab")
		)
		(pad "1" smd rect
			(at 0 -0.9652)
			(size 1.397 1.143)
			(layers "F.Cu" "F.Mask" "F.Paste")
			(net "P5V_STBY_USBC")
		)
		(pad "2" smd rect
			(at 0 0.9652)
			(size 1.397 1.143)
			(layers "F.Cu" "F.Mask" "F.Paste")
			(net "GND")
		)
	)
	(footprint ""
		(layer "F.Cu")
		(at 399.669 -155.829 180)
		(property "Reference" "C8A2"
			(at 0 0 180)
			(layer "F.SilkS")
			(hide yes)
			(effects
				(font
					(size 1.27 1.27)
				)
			)
		)
		(property "Value" ""
			(at 0 0 180)
			(layer "F.Fab")
			(effects
				(font
					(size 1.27 1.27)
				)
			)
		)
		(duplicate_pad_numbers_are_jumpers no)
		(fp_poly
			(pts
				(xy 0.3048 -0.1016) (xy 0.3048 0.9906) (xy -0.3048 0.9906) (xy -0.3048 -0.1016)
			)
			(stroke
				(width 0)
				(type default)
			)
			(fill no)
			(layer "F.CrtYd")
		)
		(fp_line
			(start 0.3048 0.9906)
			(end 0.3048 -0.1016)
			(stroke
				(width 0.1)
				(type default)
			)
			(layer "F.Fab")
		)
		(fp_line
			(start 0.3048 -0.1016)
			(end -0.3048 -0.1016)
			(stroke
				(width 0.1)
				(type default)
			)
			(layer "F.Fab")
		)
		(fp_line
			(start -0.3048 0.9906)
			(end 0.3048 0.9906)
			(stroke
				(width 0.1)
				(type default)
			)
			(layer "F.Fab")
		)
		(fp_line
			(start -0.3048 -0.1016)
			(end -0.3048 0.9906)
			(stroke
				(width 0.1)
				(type default)
			)
			(layer "F.Fab")
		)
		(pad "1" smd rect
			(at 0 0 180)
			(size 0.508 0.508)
			(layers "F.Cu" "F.Mask" "F.Paste")
			(net "VR_PVNN_PCH_AVSP")
		)
		(pad "2" smd rect
			(at 0 0.889 180)
			(size 0.508 0.508)
			(layers "F.Cu" "F.Mask" "F.Paste")
			(net "VSENSE_PVNN_PCH_STBY_AVSN")
		)
		(zone
			(layer "F.Cu")
			(hatch none 0.5)
			(connect_pads
				(clearance 0)
			)
			(min_thickness 0.25)
			(keepout
				(tracks not_allowed)
				(vias allowed)
				(pads allowed)
				(copperpour not_allowed)
				(footprints allowed)
			)
			(placement
				(enabled no)
				(sheetname "")
			)
			(fill
				(thermal_gap 0.5)
				(thermal_bridge_width 0.5)
				(island_removal_mode 0)
			)
			(polygon
				(pts
					(xy 399.923 -156.464) (xy 399.415 -156.464) (xy 399.415 -156.083) (xy 399.923 -156.083)
				)
			)
		)
		(zone
			(layer "F.Cu")
			(hatch none 0.5)
			(connect_pads
				(clearance 0)
			)
			(min_thickness 0.25)
			(keepout
				(tracks allowed)
				(vias not_allowed)
				(pads allowed)
				(copperpour not_allowed)
				(footprints allowed)
			)
			(placement
				(enabled no)
				(sheetname "")
			)
			(fill
				(thermal_gap 0.5)
				(thermal_bridge_width 0.5)
				(island_removal_mode 0)
			)
			(polygon
				(pts
					(xy 399.923 -156.083) (xy 399.415 -156.083) (xy 399.415 -156.464) (xy 399.923 -156.464)
				)
			)
		)
	)
	(footprint ""
		(layer "F.Cu")
		(at 408.7495 -110.617 -90)
		(property "Reference" "R8C4"
			(at 0 0 270)
			(layer "F.SilkS")
			(hide yes)
			(effects
				(font
					(size 1.27 1.27)
				)
			)
		)
		(property "Value" ""
			(at 0 0 270)
			(layer "F.Fab")
			(effects
				(font
					(size 1.27 1.27)
				)
			)
		)
		(duplicate_pad_numbers_are_jumpers no)
		(fp_poly
			(pts
				(xy -0.2794 -0.1016) (xy 0.2794 -0.1016) (xy 0.2794 0.9906) (xy -0.2794 0.9906)
			)
			(stroke
				(width 0)
				(type default)
			)
			(fill no)
			(layer "F.CrtYd")
		)
		(fp_line
			(start -0.2794 0.9906)
			(end 0.2794 0.9906)
			(stroke
				(width 0.1)
				(type default)
			)
			(layer "F.Fab")
		)
		(fp_line
			(start 0.2794 0.9906)
			(end 0.2794 -0.1016)
			(stroke
				(width 0.1)
				(type default)
			)
			(layer "F.Fab")
		)
		(fp_line
			(start -0.2794 -0.1016)
			(end -0.2794 0.9906)
			(stroke
				(width 0.1)
				(type default)
			)
			(layer "F.Fab")
		)
		(fp_line
			(start 0.2794 -0.1016)
			(end -0.2794 -0.1016)
			(stroke
				(width 0.1)
				(type default)
			)
			(layer "F.Fab")
		)
		(pad "1" smd rect
			(at 0 0 270)
			(size 0.508 0.508)
			(layers "F.Cu" "F.Mask" "F.Paste")
			(net "P3V3_STBY")
		)
		(pad "2" smd rect
			(at 0 0.889 270)
			(size 0.508 0.508)
			(layers "F.Cu" "F.Mask" "F.Paste")
			(net "IRQ_BMC_PCH_SMI_LPC_N")
		)
		(zone
			(layer "F.Cu")
			(hatch none 0.5)
			(connect_pads
				(clearance 0)
			)
			(min_thickness 0.25)
			(keepout
				(tracks not_allowed)
				(vias allowed)
				(pads allowed)
				(copperpour not_allowed)
				(footprints allowed)
			)
			(placement
				(enabled no)
				(sheetname "")
			)
			(fill
				(thermal_gap 0.5)
				(thermal_bridge_width 0.5)
				(island_removal_mode 0)
			)
			(polygon
				(pts
					(xy 408.1145 -110.871) (xy 408.1145 -110.363) (xy 408.4955 -110.363) (xy 408.4955 -110.871)
				)
			)
		)
		(zone
			(layer "F.Cu")
			(hatch none 0.5)
			(connect_pads
				(clearance 0)
			)
			(min_thickness 0.25)
			(keepout
				(tracks allowed)
				(vias not_allowed)
				(pads allowed)
				(copperpour not_allowed)
				(footprints allowed)
			)
			(placement
				(enabled no)
				(sheetname "")
			)
			(fill
				(thermal_gap 0.5)
				(thermal_bridge_width 0.5)
				(island_removal_mode 0)
			)
			(polygon
				(pts
					(xy 408.4955 -110.871) (xy 408.4955 -110.363) (xy 408.1145 -110.363) (xy 408.1145 -110.871)
				)
			)
		)
	)
	(footprint ""
		(layer "F.Cu")
		(at 142.810484 12.014454 -90)
		(property "Reference" "T1P12"
			(at 0 0 270)
			(layer "F.SilkS")
			(hide yes)
			(effects
				(font
					(size 1.27 1.27)
				)
			)
		)
		(property "Value" "*"
			(at -3.302 1.12395 270)
			(unlocked yes)
			(layer "F.Fab")
			(hide yes)
			(effects
				(font
					(size 0.889 0.889)
					(thickness 0.1524)
				)
			)
		)
		(property "Device Type" "TPAD-DIFF-4P-GP_DISCRET-GB3-TPA"
			(at -3.302 -0.40005 270)
			(unlocked yes)
			(layer "F.Fab")
			(hide yes)
			(effects
				(font
					(size 0.889 0.889)
					(thickness 0.1524)
				)
			)
		)
		(duplicate_pad_numbers_are_jumpers no)
		(fp_line
			(start -2.286 2.286)
			(end 2.286 2.286)
			(stroke
				(width 0.1524)
				(type default)
			)
			(layer "F.SilkS")
		)
		(fp_line
			(start 2.286 2.286)
			(end 2.286 -2.286)
			(stroke
				(width 0.1524)
				(type default)
			)
			(layer "F.SilkS")
		)
		(fp_line
			(start -2.286 -2.286)
			(end -2.286 2.286)
			(stroke
				(width 0.1524)
				(type default)
			)
			(layer "F.SilkS")
		)
		(fp_line
			(start 2.286 -2.286)
			(end -2.286 -2.286)
			(stroke
				(width 0.1524)
				(type default)
			)
			(layer "F.SilkS")
		)
		(fp_line
			(start -2.413 -2.413)
			(end -2.413 -1.143)
			(stroke
				(width 0.4064)
				(type default)
			)
			(layer "F.SilkS")
		)
		(fp_line
			(start -1.143 -2.413)
			(end -2.413 -2.413)
			(stroke
				(width 0.4064)
				(type default)
			)
			(layer "F.SilkS")
		)
		(fp_rect
			(start -2.54 2.54)
			(end 2.54 -2.54)
			(stroke
				(width 0)
				(type default)
			)
			(fill no)
			(layer "F.CrtYd")
		)
		(fp_rect
			(start -2.54 2.54)
			(end 2.54 -2.54)
			(stroke
				(width 0)
				(type default)
			)
			(fill no)
			(layer "F.Fab")
		)
		(pad "1" thru_hole circle
			(at -1.27 -1.27 270)
			(size 1.524 1.524)
			(drill 0.9144)
			(layers "*.Cu" "*.Mask")
			(remove_unused_layers no)
			(net "L14_73OHM_6INCH_DP")
			(clearance -0.0508)
			(thermal_gap 0.127)
			(padstack
				(mode front_inner_back)
				(layer "Inner"
					(shape circle)
					(size 1.1684 1.1684)
					(clearance 0.127)
				)
				(layer "B.Cu"
					(shape circle)
					(size 1.524 1.524)
					(clearance -0.0508)
				)
			)
		)
		(pad "2" thru_hole circle
			(at 1.27 -1.27 270)
			(size 1.524 1.524)
			(drill 0.9144)
			(layers "*.Cu" "*.Mask")
			(remove_unused_layers no)
			(net "L14_73OHM_6INCH_DN")
			(clearance -0.0508)
			(thermal_gap 0.127)
			(padstack
				(mode front_inner_back)
				(layer "Inner"
					(shape circle)
					(size 1.1684 1.1684)
					(clearance 0.127)
				)
				(layer "B.Cu"
					(shape circle)
					(size 1.524 1.524)
					(clearance -0.0508)
				)
			)
		)
		(pad "GND1" thru_hole rect
			(at -1.27 1.27 270)
			(size 1.524 1.524)
			(drill 0.9144)
			(layers "*.Cu" "*.Mask")
			(remove_unused_layers no)
			(net "GND")
			(clearance -0.0508)
			(thermal_gap 0.127)
			(padstack
				(mode front_inner_back)
				(layer "Inner"
					(shape circle)
					(size 1.1684 1.1684)
					(clearance 0.127)
				)
				(layer "B.Cu"
					(shape rect)
					(size 1.524 1.524)
					(clearance -0.0508)
				)
			)
		)
		(pad "GND2" thru_hole rect
			(at 1.27 1.27 270)
			(size 1.524 1.524)
			(drill 0.9144)
			(layers "*.Cu" "*.Mask")
			(remove_unused_layers no)
			(net "GND")
			(clearance -0.0508)
			(thermal_gap 0.127)
			(padstack
				(mode front_inner_back)
				(layer "Inner"
					(shape circle)
					(size 1.1684 1.1684)
					(clearance 0.127)
				)
				(layer "B.Cu"
					(shape rect)
					(size 1.524 1.524)
					(clearance -0.0508)
				)
			)
		)
	)
	(footprint ""
		(layer "F.Cu")
		(at 27.888946 -75.024742 90)
		(property "Reference" "C1D20"
			(at 0 0 90)
			(layer "F.SilkS")
			(hide yes)
			(effects
				(font
					(size 1.27 1.27)
				)
			)
		)
		(property "Value" ""
			(at 0 0 90)
			(layer "F.Fab")
			(effects
				(font
					(size 1.27 1.27)
				)
			)
		)
		(duplicate_pad_numbers_are_jumpers no)
		(fp_rect
			(start -0.3048 0.9906)
			(end 0.3048 -0.1016)
			(stroke
				(width 0)
				(type default)
			)
			(fill no)
			(layer "F.CrtYd")
		)
		(fp_line
			(start 0.3048 -0.1016)
			(end -0.3048 -0.1016)
			(stroke
				(width 0.1)
				(type default)
			)
			(layer "F.Fab")
		)
		(fp_line
			(start -0.3048 -0.1016)
			(end -0.3048 0.9906)
			(stroke
				(width 0.1)
				(type default)
			)
			(layer "F.Fab")
		)
		(fp_line
			(start 0.3048 0.9906)
			(end 0.3048 -0.1016)
			(stroke
				(width 0.1)
				(type default)
			)
			(layer "F.Fab")
		)
		(fp_line
			(start -0.3048 0.9906)
			(end 0.3048 0.9906)
			(stroke
				(width 0.1)
				(type default)
			)
			(layer "F.Fab")
		)
		(pad "1" smd rect
			(at 0 0 90)
			(size 0.508 0.508)
			(layers "F.Cu" "F.Mask" "F.Paste")
			(net "VR_PVCCIN_CPU1_PH3_BOOT")
		)
		(pad "2" smd rect
			(at 0 0.889 90)
			(size 0.508 0.508)
			(layers "F.Cu" "F.Mask" "F.Paste")
			(net "VR_PVCCIN_CPU1_PH3_PHASE")
		)
		(zone
			(layer "F.Cu")
			(hatch none 0.5)
			(connect_pads
				(clearance 0)
			)
			(min_thickness 0.25)
			(keepout
				(tracks allowed)
				(vias not_allowed)
				(pads allowed)
				(copperpour not_allowed)
				(footprints allowed)
			)
			(placement
				(enabled no)
				(sheetname "")
			)
			(fill
				(thermal_gap 0.5)
				(thermal_bridge_width 0.5)
				(island_removal_mode 0)
			)
			(polygon
				(pts
					(xy 28.523946 -74.770742) (xy 28.523946 -75.278742) (xy 28.142946 -75.278742) (xy 28.142946 -74.770742)
				)
			)
		)
		(zone
			(layer "F.Cu")
			(hatch none 0.5)
			(connect_pads
				(clearance 0)
			)
			(min_thickness 0.25)
			(keepout
				(tracks not_allowed)
				(vias allowed)
				(pads allowed)
				(copperpour not_allowed)
				(footprints allowed)
			)
			(placement
				(enabled no)
				(sheetname "")
			)
			(fill
				(thermal_gap 0.5)
				(thermal_bridge_width 0.5)
				(island_removal_mode 0)
			)
			(polygon
				(pts
					(xy 28.523946 -74.770742) (xy 28.523946 -75.278742) (xy 28.142946 -75.278742) (xy 28.142946 -74.770742)
				)
			)
		)
	)
	(footprint ""
		(layer "F.Cu")
		(at 473.075 -38.1 180)
		(property "Reference" "C9F10"
			(at 0 0 180)
			(layer "F.SilkS")
			(hide yes)
			(effects
				(font
					(size 1.27 1.27)
				)
			)
		)
		(property "Value" ""
			(at 0 0 180)
			(layer "F.Fab")
			(effects
				(font
					(size 1.27 1.27)
				)
			)
		)
		(duplicate_pad_numbers_are_jumpers no)
		(fp_poly
			(pts
				(xy 0.3048 -0.1016) (xy 0.3048 0.9906) (xy -0.3048 0.9906) (xy -0.3048 -0.1016)
			)
			(stroke
				(width 0)
				(type default)
			)
			(fill no)
			(layer "F.CrtYd")
		)
		(fp_line
			(start 0.3048 0.9906)
			(end 0.3048 -0.1016)
			(stroke
				(width 0.1)
				(type default)
			)
			(layer "F.Fab")
		)
		(fp_line
			(start 0.3048 -0.1016)
			(end -0.3048 -0.1016)
			(stroke
				(width 0.1)
				(type default)
			)
			(layer "F.Fab")
		)
		(fp_line
			(start -0.3048 0.9906)
			(end 0.3048 0.9906)
			(stroke
				(width 0.1)
				(type default)
			)
			(layer "F.Fab")
		)
		(fp_line
			(start -0.3048 -0.1016)
			(end -0.3048 0.9906)
			(stroke
				(width 0.1)
				(type default)
			)
			(layer "F.Fab")
		)
		(pad "1" smd rect
			(at 0 0 180)
			(size 0.508 0.508)
			(layers "F.Cu" "F.Mask" "F.Paste")
			(net "PWRGD_P1V2_BMC_STBY_R")
		)
		(pad "2" smd rect
			(at 0 0.889 180)
			(size 0.508 0.508)
			(layers "F.Cu" "F.Mask" "F.Paste")
			(net "GND")
		)
		(zone
			(layer "F.Cu")
			(hatch none 0.5)
			(connect_pads
				(clearance 0)
			)
			(min_thickness 0.25)
			(keepout
				(tracks not_allowed)
				(vias allowed)
				(pads allowed)
				(copperpour not_allowed)
				(footprints allowed)
			)
			(placement
				(enabled no)
				(sheetname "")
			)
			(fill
				(thermal_gap 0.5)
				(thermal_bridge_width 0.5)
				(island_removal_mode 0)
			)
			(polygon
				(pts
					(xy 473.329 -38.735) (xy 472.821 -38.735) (xy 472.821 -38.354) (xy 473.329 -38.354)
				)
			)
		)
		(zone
			(layer "F.Cu")
			(hatch none 0.5)
			(connect_pads
				(clearance 0)
			)
			(min_thickness 0.25)
			(keepout
				(tracks allowed)
				(vias not_allowed)
				(pads allowed)
				(copperpour not_allowed)
				(footprints allowed)
			)
			(placement
				(enabled no)
				(sheetname "")
			)
			(fill
				(thermal_gap 0.5)
				(thermal_bridge_width 0.5)
				(island_removal_mode 0)
			)
			(polygon
				(pts
					(xy 473.329 -38.354) (xy 472.821 -38.354) (xy 472.821 -38.735) (xy 473.329 -38.735)
				)
			)
		)
	)
	(footprint ""
		(layer "F.Cu")
		(at 343.281 -20.447)
		(property "Reference" "R7F22"
			(at 0 0 0)
			(layer "F.SilkS")
			(hide yes)
			(effects
				(font
					(size 1.27 1.27)
				)
			)
		)
		(property "Value" ""
			(at 0 0 0)
			(layer "F.Fab")
			(effects
				(font
					(size 1.27 1.27)
				)
			)
		)
		(duplicate_pad_numbers_are_jumpers no)
		(fp_rect
			(start -0.2794 0.9906)
			(end 0.2794 -0.1016)
			(stroke
				(width 0)
				(type default)
			)
			(fill no)
			(layer "F.CrtYd")
		)
		(fp_line
			(start -0.2794 -0.1016)
			(end -0.2794 0.9906)
			(stroke
				(width 0.1)
				(type default)
			)
			(layer "F.Fab")
		)
		(fp_line
			(start -0.2794 0.9906)
			(end 0.2794 0.9906)
			(stroke
				(width 0.1)
				(type default)
			)
			(layer "F.Fab")
		)
		(fp_line
			(start 0.2794 -0.1016)
			(end -0.2794 -0.1016)
			(stroke
				(width 0.1)
				(type default)
			)
			(layer "F.Fab")
		)
		(fp_line
			(start 0.2794 0.9906)
			(end 0.2794 -0.1016)
			(stroke
				(width 0.1)
				(type default)
			)
			(layer "F.Fab")
		)
		(pad "1" smd rect
			(at 0 0)
			(size 0.508 0.508)
			(layers "F.Cu" "F.Mask" "F.Paste")
			(net "P3V3_STBY")
		)
		(pad "2" smd rect
			(at 0 0.889)
			(size 0.508 0.508)
			(layers "F.Cu" "F.Mask" "F.Paste")
			(net "PWRGD_PVDDQ_ABC_R")
		)
		(zone
			(layer "F.Cu")
			(hatch none 0.5)
			(connect_pads
				(clearance 0)
			)
			(min_thickness 0.25)
			(keepout
				(tracks not_allowed)
				(vias allowed)
				(pads allowed)
				(copperpour not_allowed)
				(footprints allowed)
			)
			(placement
				(enabled no)
				(sheetname "")
			)
			(fill
				(thermal_gap 0.5)
				(thermal_bridge_width 0.5)
				(island_removal_mode 0)
			)
			(polygon
				(pts
					(xy 343.027 -19.812) (xy 343.535 -19.812) (xy 343.535 -20.193) (xy 343.027 -20.193)
				)
			)
		)
		(zone
			(layer "F.Cu")
			(hatch none 0.5)
			(connect_pads
				(clearance 0)
			)
			(min_thickness 0.25)
			(keepout
				(tracks allowed)
				(vias not_allowed)
				(pads allowed)
				(copperpour not_allowed)
				(footprints allowed)
			)
			(placement
				(enabled no)
				(sheetname "")
			)
			(fill
				(thermal_gap 0.5)
				(thermal_bridge_width 0.5)
				(island_removal_mode 0)
			)
			(polygon
				(pts
					(xy 343.027 -19.812) (xy 343.535 -19.812) (xy 343.535 -20.193) (xy 343.027 -20.193)
				)
			)
		)
	)
	(footprint ""
		(layer "F.Cu")
		(at 24.257 10.7315 -90)
		(property "Reference" "T1P28"
			(at 0 0 270)
			(layer "F.SilkS")
			(hide yes)
			(effects
				(font
					(size 1.27 1.27)
				)
			)
		)
		(property "Value" "*"
			(at 0 -3.44805 270)
			(unlocked yes)
			(layer "F.Fab")
			(hide yes)
			(effects
				(font
					(size 0.889 0.889)
					(thickness 0.1524)
				)
			)
		)
		(property "Device Type" "TPAD-SE-2P-GP_DISCRET-GA1-TPADA"
			(at 0 -4.97205 270)
			(unlocked yes)
			(layer "F.Fab")
			(hide yes)
			(effects
				(font
					(size 0.889 0.889)
					(thickness 0.1524)
				)
			)
		)
		(duplicate_pad_numbers_are_jumpers no)
		(fp_line
			(start -1.016 2.286)
			(end -1.016 -2.286)
			(stroke
				(width 0.1524)
				(type default)
			)
			(layer "F.SilkS")
		)
		(fp_line
			(start 1.016 2.286)
			(end -1.016 2.286)
			(stroke
				(width 0.1524)
				(type default)
			)
			(layer "F.SilkS")
		)
		(fp_line
			(start -1.016 -2.286)
			(end 1.016 -2.286)
			(stroke
				(width 0.1524)
				(type default)
			)
			(layer "F.SilkS")
		)
		(fp_line
			(start 1.016 -2.286)
			(end 1.016 2.286)
			(stroke
				(width 0.1524)
				(type default)
			)
			(layer "F.SilkS")
		)
		(fp_rect
			(start -1.27 2.54)
			(end 1.27 -2.54)
			(stroke
				(width 0)
				(type default)
			)
			(fill no)
			(layer "F.CrtYd")
		)
		(fp_rect
			(start -1.27 2.54)
			(end 1.27 -2.54)
			(stroke
				(width 0)
				(type default)
			)
			(fill no)
			(layer "F.Fab")
		)
		(pad "1" thru_hole circle
			(at 0 -1.27 270)
			(size 1.524 1.524)
			(drill 0.9144)
			(layers "*.Cu" "*.Mask")
			(remove_unused_layers no)
			(net "L10_40OHM_6INCH")
			(clearance -0.0508)
			(thermal_gap 0.127)
			(padstack
				(mode front_inner_back)
				(layer "Inner"
					(shape circle)
					(size 1.1684 1.1684)
					(clearance 0.127)
				)
				(layer "B.Cu"
					(shape circle)
					(size 1.524 1.524)
					(clearance -0.0508)
				)
			)
		)
		(pad "GND1" thru_hole rect
			(at 0 1.27 270)
			(size 1.524 1.524)
			(drill 0.9144)
			(layers "*.Cu" "*.Mask")
			(remove_unused_layers no)
			(net "GND")
			(clearance -0.0508)
			(thermal_gap 0.127)
			(padstack
				(mode front_inner_back)
				(layer "Inner"
					(shape circle)
					(size 1.1684 1.1684)
					(clearance 0.127)
				)
				(layer "B.Cu"
					(shape rect)
					(size 1.524 1.524)
					(clearance -0.0508)
				)
			)
		)
	)
	(footprint ""
		(layer "F.Cu")
		(at 426.4533 -124.9172 -90)
		(property "Reference" "R8B16"
			(at 0 0 270)
			(layer "F.SilkS")
			(hide yes)
			(effects
				(font
					(size 1.27 1.27)
				)
			)
		)
		(property "Value" ""
			(at 0 0 270)
			(layer "F.Fab")
			(effects
				(font
					(size 1.27 1.27)
				)
			)
		)
		(duplicate_pad_numbers_are_jumpers no)
		(fp_poly
			(pts
				(xy -0.2794 -0.1016) (xy 0.2794 -0.1016) (xy 0.2794 0.9906) (xy -0.2794 0.9906)
			)
			(stroke
				(width 0)
				(type default)
			)
			(fill no)
			(layer "F.CrtYd")
		)
		(fp_line
			(start -0.2794 0.9906)
			(end 0.2794 0.9906)
			(stroke
				(width 0.1)
				(type default)
			)
			(layer "F.Fab")
		)
		(fp_line
			(start 0.2794 0.9906)
			(end 0.2794 -0.1016)
			(stroke
				(width 0.1)
				(type default)
			)
			(layer "F.Fab")
		)
		(fp_line
			(start -0.2794 -0.1016)
			(end -0.2794 0.9906)
			(stroke
				(width 0.1)
				(type default)
			)
			(layer "F.Fab")
		)
		(fp_line
			(start 0.2794 -0.1016)
			(end -0.2794 -0.1016)
			(stroke
				(width 0.1)
				(type default)
			)
			(layer "F.Fab")
		)
		(pad "1" smd rect
			(at 0 0 270)
			(size 0.508 0.508)
			(layers "F.Cu" "F.Mask" "F.Paste")
			(net "PVPP_ABC")
		)
		(pad "2" smd rect
			(at 0 0.889 270)
			(size 0.508 0.508)
			(layers "F.Cu" "F.Mask" "F.Paste")
			(net "RST_HFI1_CPU0_LVT2_N")
		)
		(zone
			(layer "F.Cu")
			(hatch none 0.5)
			(connect_pads
				(clearance 0)
			)
			(min_thickness 0.25)
			(keepout
				(tracks not_allowed)
				(vias allowed)
				(pads allowed)
				(copperpour not_allowed)
				(footprints allowed)
			)
			(placement
				(enabled no)
				(sheetname "")
			)
			(fill
				(thermal_gap 0.5)
				(thermal_bridge_width 0.5)
				(island_removal_mode 0)
			)
			(polygon
				(pts
					(xy 425.8183 -125.1712) (xy 425.8183 -124.6632) (xy 426.1993 -124.6632) (xy 426.1993 -125.1712)
				)
			)
		)
		(zone
			(layer "F.Cu")
			(hatch none 0.5)
			(connect_pads
				(clearance 0)
			)
			(min_thickness 0.25)
			(keepout
				(tracks allowed)
				(vias not_allowed)
				(pads allowed)
				(copperpour not_allowed)
				(footprints allowed)
			)
			(placement
				(enabled no)
				(sheetname "")
			)
			(fill
				(thermal_gap 0.5)
				(thermal_bridge_width 0.5)
				(island_removal_mode 0)
			)
			(polygon
				(pts
					(xy 426.1993 -125.1712) (xy 426.1993 -124.6632) (xy 425.8183 -124.6632) (xy 425.8183 -125.1712)
				)
			)
		)
	)
	(footprint ""
		(layer "F.Cu")
		(at 271.898872 -73.279)
		(property "Reference" "C5D53"
			(at 0 0 0)
			(layer "F.SilkS")
			(hide yes)
			(effects
				(font
					(size 1.27 1.27)
				)
			)
		)
		(property "Value" ""
			(at 0 0 0)
			(layer "F.Fab")
			(effects
				(font
					(size 1.27 1.27)
				)
			)
		)
		(duplicate_pad_numbers_are_jumpers no)
		(fp_poly
			(pts
				(xy -0.4953 -0.2032) (xy 0.4953 -0.2032) (xy 0.4953 1.6002) (xy -0.4953 1.6002)
			)
			(stroke
				(width 0)
				(type default)
			)
			(fill no)
			(layer "F.CrtYd")
		)
		(fp_line
			(start -0.4953 -0.2032)
			(end 0.4953 -0.2032)
			(stroke
				(width 0.1)
				(type default)
			)
			(layer "F.Fab")
		)
		(fp_line
			(start -0.4953 1.6002)
			(end -0.4953 -0.2032)
			(stroke
				(width 0.1)
				(type default)
			)
			(layer "F.Fab")
		)
		(fp_line
			(start 0.4953 -0.2032)
			(end 0.4953 1.6002)
			(stroke
				(width 0.1)
				(type default)
			)
			(layer "F.Fab")
		)
		(fp_line
			(start 0.4953 1.6002)
			(end -0.4953 1.6002)
			(stroke
				(width 0.1)
				(type default)
			)
			(layer "F.Fab")
		)
		(pad "1" smd rect
			(at 0 0)
			(size 0.762 0.889)
			(layers "F.Cu" "F.Mask" "F.Paste")
			(net "PVCCMCP_CPU0")
		)
		(pad "2" smd rect
			(at 0 1.397)
			(size 0.762 0.889)
			(layers "F.Cu" "F.Mask" "F.Paste")
			(net "GND")
		)
		(zone
			(layer "F.Cu")
			(hatch none 0.5)
			(connect_pads
				(clearance 0)
			)
			(min_thickness 0.25)
			(keepout
				(tracks not_allowed)
				(vias allowed)
				(pads allowed)
				(copperpour not_allowed)
				(footprints allowed)
			)
			(placement
				(enabled no)
				(sheetname "")
			)
			(fill
				(thermal_gap 0.5)
				(thermal_bridge_width 0.5)
				(island_removal_mode 0)
			)
			(polygon
				(pts
					(xy 271.517872 -72.8345) (xy 272.279872 -72.8345) (xy 272.279872 -72.3265) (xy 271.517872 -72.3265)
				)
			)
		)
	)
	(footprint ""
		(layer "F.Cu")
		(at 194.700398 3.778758 90)
		(property "Reference" "J4G3"
			(at 6.800088 37.20211 0)
			(unlocked yes)
			(layer "F.SilkS")
			(effects
				(font
					(size 0.7874 0.5842)
					(thickness 0.1524)
				)
				(justify left)
			)
		)
		(property "Value" ""
			(at 0 0 90)
			(layer "F.Fab")
			(effects
				(font
					(size 1.27 1.27)
				)
			)
		)
		(duplicate_pad_numbers_are_jumpers no)
		(fp_line
			(start 5.5499 -7.675118)
			(end 5.5499 -1.480058)
			(stroke
				(width 0.1524)
				(type default)
			)
			(layer "F.SilkS")
		)
		(fp_line
			(start -0.94996 -7.675118)
			(end 5.5499 -7.675118)
			(stroke
				(width 0.1524)
				(type default)
			)
			(layer "F.SilkS")
		)
		(fp_line
			(start -0.94996 -1.480058)
			(end -0.94996 -7.675118)
			(stroke
				(width 0.1524)
				(type default)
			)
			(layer "F.SilkS")
		)
		(fp_line
			(start 5.5499 128.130046)
			(end 5.5499 134.325106)
			(stroke
				(width 0.1524)
				(type default)
			)
			(layer "F.SilkS")
		)
		(fp_line
			(start 5.5499 134.325106)
			(end -0.94996 134.325106)
			(stroke
				(width 0.1524)
				(type default)
			)
			(layer "F.SilkS")
		)
		(fp_line
			(start -0.94996 134.325106)
			(end -0.94996 128.130046)
			(stroke
				(width 0.1524)
				(type default)
			)
			(layer "F.SilkS")
		)
		(fp_poly
			(pts
				(xy -2.984246 -0.461264) (xy -2.984246 0.554736) (xy -1.714246 0.046736)
			)
			(stroke
				(width 0)
				(type default)
			)
			(fill yes)
			(layer "F.SilkS")
		)
		(fp_poly
			(pts
				(xy -0.94996 -7.675118) (xy -0.94996 134.325106) (xy 5.5499 134.325106) (xy 5.5499 -7.675118)
			)
			(stroke
				(width 0)
				(type default)
			)
			(fill no)
			(layer "F.CrtYd")
		)
		(fp_line
			(start 5.5499 -7.675118)
			(end 5.5499 134.325106)
			(stroke
				(width 0.1)
				(type default)
			)
			(layer "F.Fab")
		)
		(fp_line
			(start -0.94996 -7.675118)
			(end 5.5499 -7.675118)
			(stroke
				(width 0.1)
				(type default)
			)
			(layer "F.Fab")
		)
		(fp_line
			(start 5.5499 134.325106)
			(end -0.94996 134.325106)
			(stroke
				(width 0.1)
				(type default)
			)
			(layer "F.Fab")
		)
		(fp_line
			(start -0.94996 134.325106)
			(end -0.94996 -7.675118)
			(stroke
				(width 0.1)
				(type default)
			)
			(layer "F.Fab")
		)
		(fp_poly
			(pts
				(xy -2.984246 -0.461264) (xy -2.984246 0.554736) (xy -1.714246 0.046736)
			)
			(stroke
				(width 0)
				(type default)
			)
			(fill yes)
			(layer "F.Fab")
		)
		(fp_text user "145"
			(at 6.050788 0.23241 0)
			(unlocked yes)
			(layer "F.SilkS")
			(effects
				(font
					(size 0.7874 0.5842)
					(thickness 0.1524)
				)
				(justify left)
			)
		)
		(fp_text user "77"
			(at -1.620012 64.94145 0)
			(unlocked yes)
			(layer "F.SilkS")
			(effects
				(font
					(size 0.7874 0.5842)
					(thickness 0.1524)
				)
				(justify left)
			)
		)
		(fp_text user "221"
			(at 5.911088 65.01511 0)
			(unlocked yes)
			(layer "F.SilkS")
			(effects
				(font
					(size 0.7874 0.5842)
					(thickness 0.1524)
				)
				(justify left)
			)
		)
		(fp_text user "78"
			(at -1.581912 69.58711 0)
			(unlocked yes)
			(layer "F.SilkS")
			(effects
				(font
					(size 0.7874 0.5842)
					(thickness 0.1524)
				)
				(justify left)
			)
		)
		(fp_text user "222"
			(at 6.038088 69.71411 0)
			(unlocked yes)
			(layer "F.SilkS")
			(effects
				(font
					(size 0.7874 0.5842)
					(thickness 0.1524)
				)
				(justify left)
			)
		)
		(fp_text user "144"
			(at -1.708912 126.99111 0)
			(unlocked yes)
			(layer "F.SilkS")
			(effects
				(font
					(size 0.7874 0.5842)
					(thickness 0.1524)
				)
				(justify left)
			)
		)
		(fp_text user "288"
			(at 6.292088 128.00711 0)
			(unlocked yes)
			(layer "F.SilkS")
			(effects
				(font
					(size 0.7874 0.5842)
					(thickness 0.1524)
				)
				(justify left)
			)
		)
		(fp_text user "145"
			(at 3.143758 -0.74422 90)
			(unlocked yes)
			(layer "F.Fab")
			(effects
				(font
					(size 0.7874 0.5842)
					(thickness 0.1524)
				)
				(justify left)
			)
		)
		(fp_text user "221"
			(at 3.778758 65.93078 90)
			(unlocked yes)
			(layer "F.Fab")
			(effects
				(font
					(size 0.7874 0.5842)
					(thickness 0.1524)
				)
				(justify left)
			)
		)
		(fp_text user "77"
			(at -0.666242 65.93078 90)
			(unlocked yes)
			(layer "F.Fab")
			(effects
				(font
					(size 0.7874 0.5842)
					(thickness 0.1524)
				)
				(justify left)
			)
		)
		(fp_text user "222"
			(at 3.778758 69.10578 90)
			(unlocked yes)
			(layer "F.Fab")
			(effects
				(font
					(size 0.7874 0.5842)
					(thickness 0.1524)
				)
				(justify left)
			)
		)
		(fp_text user "78"
			(at -0.666242 69.74078 90)
			(unlocked yes)
			(layer "F.Fab")
			(effects
				(font
					(size 0.7874 0.5842)
					(thickness 0.1524)
				)
				(justify left)
			)
		)
		(fp_text user "288"
			(at 3.143758 128.16078 90)
			(unlocked yes)
			(layer "F.Fab")
			(effects
				(font
					(size 0.7874 0.5842)
					(thickness 0.1524)
				)
				(justify left)
			)
		)
		(fp_text user "144"
			(at -0.666242 128.16078 90)
			(unlocked yes)
			(layer "F.Fab")
			(effects
				(font
					(size 0.7874 0.5842)
					(thickness 0.1524)
				)
				(justify left)
			)
		)
		(pad "" thru_hole circle
			(at 2.29997 -5.649976 90)
			(size 2.8194 2.8194)
			(drill 2.4384)
			(layers "*.Cu" "*.Mask")
			(remove_unused_layers no)
			(clearance 0.127)
			(thermal_gap 0.127)
		)
		(pad "" thru_hole oval
			(at 2.29997 68.90004 90)
			(size 2.8194 1.5748)
			(drill oval 2.4384 1.1938)
			(layers "*.Cu" "*.Mask")
			(remove_unused_layers no)
			(clearance 0.127)
			(thermal_gap 0.127)
		)
		(pad "" thru_hole circle
			(at 2.29997 132.299964 90)
			(size 2.8194 2.8194)
			(drill 2.4384)
			(layers "*.Cu" "*.Mask")
			(remove_unused_layers no)
			(clearance 0.127)
			(thermal_gap 0.127)
		)
		(pad "1" smd rect
			(at 0 0 90)
			(size 1.8034 0.508)
			(layers "F.Cu" "F.Mask" "F.Paste")
			(net "P12V_NVDIMM_ABC")
		)
		(pad "2" smd rect
			(at 0 0.849884 90)
			(size 1.8034 0.508)
			(layers "F.Cu" "F.Mask" "F.Paste")
			(net "GND")
		)
		(pad "3" smd rect
			(at 0 1.700022 90)
			(size 1.8034 0.508)
			(layers "F.Cu" "F.Mask" "F.Paste")
			(net "M_C_DQ<5>")
		)
		(pad "4" smd rect
			(at 0 2.549906 90)
			(size 1.8034 0.508)
			(layers "F.Cu" "F.Mask" "F.Paste")
			(net "GND")
		)
		(pad "5" smd rect
			(at 0 3.400044 90)
			(size 1.8034 0.508)
			(layers "F.Cu" "F.Mask" "F.Paste")
			(net "M_C_DQ<1>")
		)
		(pad "6" smd rect
			(at 0 4.249928 90)
			(size 1.8034 0.508)
			(layers "F.Cu" "F.Mask" "F.Paste")
			(net "GND")
		)
		(pad "7" smd rect
			(at 0 5.100066 90)
			(size 1.8034 0.508)
			(layers "F.Cu" "F.Mask" "F.Paste")
			(net "M_C_DQS_DP<9>")
		)
		(pad "8" smd rect
			(at 0 5.94995 90)
			(size 1.8034 0.508)
			(layers "F.Cu" "F.Mask" "F.Paste")
			(net "M_C_DQS_DN<9>")
		)
		(pad "9" smd rect
			(at 0 6.800088 90)
			(size 1.8034 0.508)
			(layers "F.Cu" "F.Mask" "F.Paste")
			(net "GND")
		)
		(pad "10" smd rect
			(at 0 7.649972 90)
			(size 1.8034 0.508)
			(layers "F.Cu" "F.Mask" "F.Paste")
			(net "M_C_DQ<7>")
		)
		(pad "11" smd rect
			(at 0 8.50011 90)
			(size 1.8034 0.508)
			(layers "F.Cu" "F.Mask" "F.Paste")
			(net "GND")
		)
		(pad "12" smd rect
			(at 0 9.349994 90)
			(size 1.8034 0.508)
			(layers "F.Cu" "F.Mask" "F.Paste")
			(net "M_C_DQ<3>")
		)
		(pad "13" smd rect
			(at 0 10.199878 90)
			(size 1.8034 0.508)
			(layers "F.Cu" "F.Mask" "F.Paste")
			(net "GND")
		)
		(pad "14" smd rect
			(at 0 11.050016 90)
			(size 1.8034 0.508)
			(layers "F.Cu" "F.Mask" "F.Paste")
			(net "M_C_DQ<13>")
		)
		(pad "15" smd rect
			(at 0 11.8999 90)
			(size 1.8034 0.508)
			(layers "F.Cu" "F.Mask" "F.Paste")
			(net "GND")
		)
		(pad "16" smd rect
			(at 0 12.750038 90)
			(size 1.8034 0.508)
			(layers "F.Cu" "F.Mask" "F.Paste")
			(net "M_C_DQ<9>")
		)
		(pad "17" smd rect
			(at 0 13.599922 90)
			(size 1.8034 0.508)
			(layers "F.Cu" "F.Mask" "F.Paste")
			(net "GND")
		)
		(pad "18" smd rect
			(at 0 14.45006 90)
			(size 1.8034 0.508)
			(layers "F.Cu" "F.Mask" "F.Paste")
			(net "M_C_DQS_DP<10>")
		)
		(pad "19" smd rect
			(at 0 15.299944 90)
			(size 1.8034 0.508)
			(layers "F.Cu" "F.Mask" "F.Paste")
			(net "M_C_DQS_DN<10>")
		)
		(pad "20" smd rect
			(at 0 16.150082 90)
			(size 1.8034 0.508)
			(layers "F.Cu" "F.Mask" "F.Paste")
			(net "GND")
		)
		(pad "21" smd rect
			(at 0 16.999966 90)
			(size 1.8034 0.508)
			(layers "F.Cu" "F.Mask" "F.Paste")
			(net "M_C_DQ<15>")
		)
		(pad "22" smd rect
			(at 0 17.850104 90)
			(size 1.8034 0.508)
			(layers "F.Cu" "F.Mask" "F.Paste")
			(net "GND")
		)
		(pad "23" smd rect
			(at 0 18.699988 90)
			(size 1.8034 0.508)
			(layers "F.Cu" "F.Mask" "F.Paste")
			(net "M_C_DQ<11>")
		)
		(pad "24" smd rect
			(at 0 19.550126 90)
			(size 1.8034 0.508)
			(layers "F.Cu" "F.Mask" "F.Paste")
			(net "GND")
		)
		(pad "25" smd rect
			(at 0 20.40001 90)
			(size 1.8034 0.508)
			(layers "F.Cu" "F.Mask" "F.Paste")
			(net "M_C_DQ<21>")
		)
		(pad "26" smd rect
			(at 0 21.249894 90)
			(size 1.8034 0.508)
			(layers "F.Cu" "F.Mask" "F.Paste")
			(net "GND")
		)
		(pad "27" smd rect
			(at 0 22.100032 90)
			(size 1.8034 0.508)
			(layers "F.Cu" "F.Mask" "F.Paste")
			(net "M_C_DQ<17>")
		)
		(pad "28" smd rect
			(at 0 22.949916 90)
			(size 1.8034 0.508)
			(layers "F.Cu" "F.Mask" "F.Paste")
			(net "GND")
		)
		(pad "29" smd rect
			(at 0 23.800054 90)
			(size 1.8034 0.508)
			(layers "F.Cu" "F.Mask" "F.Paste")
			(net "M_C_DQS_DP<11>")
		)
		(pad "30" smd rect
			(at 0 24.649938 90)
			(size 1.8034 0.508)
			(layers "F.Cu" "F.Mask" "F.Paste")
			(net "M_C_DQS_DN<11>")
		)
		(pad "31" smd rect
			(at 0 25.500076 90)
			(size 1.8034 0.508)
			(layers "F.Cu" "F.Mask" "F.Paste")
			(net "GND")
		)
		(pad "32" smd rect
			(at 0 26.34996 90)
			(size 1.8034 0.508)
			(layers "F.Cu" "F.Mask" "F.Paste")
			(net "M_C_DQ<23>")
		)
		(pad "33" smd rect
			(at 0 27.200098 90)
			(size 1.8034 0.508)
			(layers "F.Cu" "F.Mask" "F.Paste")
			(net "GND")
		)
		(pad "34" smd rect
			(at 0 28.049982 90)
			(size 1.8034 0.508)
			(layers "F.Cu" "F.Mask" "F.Paste")
			(net "M_C_DQ<19>")
		)
		(pad "35" smd rect
			(at 0 28.90012 90)
			(size 1.8034 0.508)
			(layers "F.Cu" "F.Mask" "F.Paste")
			(net "GND")
		)
		(pad "36" smd rect
			(at 0 29.750004 90)
			(size 1.8034 0.508)
			(layers "F.Cu" "F.Mask" "F.Paste")
			(net "M_C_DQ<29>")
		)
		(pad "37" smd rect
			(at 0 30.599888 90)
			(size 1.8034 0.508)
			(layers "F.Cu" "F.Mask" "F.Paste")
			(net "GND")
		)
		(pad "38" smd rect
			(at 0 31.450026 90)
			(size 1.8034 0.508)
			(layers "F.Cu" "F.Mask" "F.Paste")
			(net "M_C_DQ<25>")
		)
		(pad "39" smd rect
			(at 0 32.29991 90)
			(size 1.8034 0.508)
			(layers "F.Cu" "F.Mask" "F.Paste")
			(net "GND")
		)
		(pad "40" smd rect
			(at 0 33.150048 90)
			(size 1.8034 0.508)
			(layers "F.Cu" "F.Mask" "F.Paste")
			(net "M_C_DQS_DP<12>")
		)
		(pad "41" smd rect
			(at 0 33.999932 90)
			(size 1.8034 0.508)
			(layers "F.Cu" "F.Mask" "F.Paste")
			(net "M_C_DQS_DN<12>")
		)
		(pad "42" smd rect
			(at 0 34.85007 90)
			(size 1.8034 0.508)
			(layers "F.Cu" "F.Mask" "F.Paste")
			(net "GND")
		)
		(pad "43" smd rect
			(at 0 35.699954 90)
			(size 1.8034 0.508)
			(layers "F.Cu" "F.Mask" "F.Paste")
			(net "M_C_DQ<31>")
		)
		(pad "44" smd rect
			(at 0 36.550092 90)
			(size 1.8034 0.508)
			(layers "F.Cu" "F.Mask" "F.Paste")
			(net "GND")
		)
		(pad "45" smd rect
			(at 0 37.399976 90)
			(size 1.8034 0.508)
			(layers "F.Cu" "F.Mask" "F.Paste")
			(net "M_C_DQ<27>")
		)
		(pad "46" smd rect
			(at 0 38.250114 90)
			(size 1.8034 0.508)
			(layers "F.Cu" "F.Mask" "F.Paste")
			(net "GND")
		)
		(pad "47" smd rect
			(at 0 39.099998 90)
			(size 1.8034 0.508)
			(layers "F.Cu" "F.Mask" "F.Paste")
			(net "M_C_ECC<5>")
		)
		(pad "48" smd rect
			(at 0 39.949882 90)
			(size 1.8034 0.508)
			(layers "F.Cu" "F.Mask" "F.Paste")
			(net "GND")
		)
		(pad "49" smd rect
			(at 0 40.80002 90)
			(size 1.8034 0.508)
			(layers "F.Cu" "F.Mask" "F.Paste")
			(net "M_C_ECC<1>")
		)
		(pad "50" smd rect
			(at 0 41.649904 90)
			(size 1.8034 0.508)
			(layers "F.Cu" "F.Mask" "F.Paste")
			(net "GND")
		)
		(pad "51" smd rect
			(at 0 42.500042 90)
			(size 1.8034 0.508)
			(layers "F.Cu" "F.Mask" "F.Paste")
			(net "M_C_DQS_DP<17>")
		)
		(pad "52" smd rect
			(at 0 43.349926 90)
			(size 1.8034 0.508)
			(layers "F.Cu" "F.Mask" "F.Paste")
			(net "M_C_DQS_DN<17>")
		)
		(pad "53" smd rect
			(at 0 44.200064 90)
			(size 1.8034 0.508)
			(layers "F.Cu" "F.Mask" "F.Paste")
			(net "GND")
		)
		(pad "54" smd rect
			(at 0 45.049948 90)
			(size 1.8034 0.508)
			(layers "F.Cu" "F.Mask" "F.Paste")
			(net "M_C_ECC<7>")
		)
		(pad "55" smd rect
			(at 0 45.900086 90)
			(size 1.8034 0.508)
			(layers "F.Cu" "F.Mask" "F.Paste")
			(net "GND")
		)
		(pad "56" smd rect
			(at 0 46.74997 90)
			(size 1.8034 0.508)
			(layers "F.Cu" "F.Mask" "F.Paste")
			(net "M_C_ECC<3>")
		)
		(pad "57" smd rect
			(at 0 47.600108 90)
			(size 1.8034 0.508)
			(layers "F.Cu" "F.Mask" "F.Paste")
			(net "GND")
		)
		(pad "58" smd rect
			(at 0 48.449992 90)
			(size 1.8034 0.508)
			(layers "F.Cu" "F.Mask" "F.Paste")
			(net "M_ABC_RST_N")
		)
		(pad "59" smd rect
			(at 0 49.299876 90)
			(size 1.8034 0.508)
			(layers "F.Cu" "F.Mask" "F.Paste")
			(net "PVDDQ_ABC")
		)
		(pad "60" smd rect
			(at 0 50.150014 90)
			(size 1.8034 0.508)
			(layers "F.Cu" "F.Mask" "F.Paste")
			(net "M_C_CKE<0>")
		)
		(pad "61" smd rect
			(at 0 50.999898 90)
			(size 1.8034 0.508)
			(layers "F.Cu" "F.Mask" "F.Paste")
			(net "PVDDQ_ABC")
		)
		(pad "62" smd rect
			(at 0 51.850036 90)
			(size 1.8034 0.508)
			(layers "F.Cu" "F.Mask" "F.Paste")
			(net "M_C_ACT_N")
		)
		(pad "63" smd rect
			(at 0 52.69992 90)
			(size 1.8034 0.508)
			(layers "F.Cu" "F.Mask" "F.Paste")
			(net "M_C_BG<0>")
		)
		(pad "64" smd rect
			(at 0 53.550058 90)
			(size 1.8034 0.508)
			(layers "F.Cu" "F.Mask" "F.Paste")
			(net "PVDDQ_ABC")
		)
		(pad "65" smd rect
			(at 0 54.399942 90)
			(size 1.8034 0.508)
			(layers "F.Cu" "F.Mask" "F.Paste")
			(net "M_C_MA<12>")
		)
		(pad "66" smd rect
			(at 0 55.25008 90)
			(size 1.8034 0.508)
			(layers "F.Cu" "F.Mask" "F.Paste")
			(net "M_C_MA<9>")
		)
		(pad "67" smd rect
			(at 0 56.099964 90)
			(size 1.8034 0.508)
			(layers "F.Cu" "F.Mask" "F.Paste")
			(net "PVDDQ_ABC")
		)
		(pad "68" smd rect
			(at 0 56.950102 90)
			(size 1.8034 0.508)
			(layers "F.Cu" "F.Mask" "F.Paste")
			(net "M_C_MA<8>")
		)
		(pad "69" smd rect
			(at 0 57.799986 90)
			(size 1.8034 0.508)
			(layers "F.Cu" "F.Mask" "F.Paste")
			(net "M_C_MA<6>")
		)
		(pad "70" smd rect
			(at 0 58.650124 90)
			(size 1.8034 0.508)
			(layers "F.Cu" "F.Mask" "F.Paste")
			(net "PVDDQ_ABC")
		)
		(pad "71" smd rect
			(at 0 59.500008 90)
			(size 1.8034 0.508)
			(layers "F.Cu" "F.Mask" "F.Paste")
			(net "M_C_MA<3>")
		)
		(pad "72" smd rect
			(at 0 60.349892 90)
			(size 1.8034 0.508)
			(layers "F.Cu" "F.Mask" "F.Paste")
			(net "M_C_MA<1>")
		)
		(pad "73" smd rect
			(at 0 61.20003 90)
			(size 1.8034 0.508)
			(layers "F.Cu" "F.Mask" "F.Paste")
			(net "PVDDQ_ABC")
		)
		(pad "74" smd rect
			(at 0 62.049914 90)
			(size 1.8034 0.508)
			(layers "F.Cu" "F.Mask" "F.Paste")
			(net "M_C_CLK_DP<0>")
		)
		(pad "75" smd rect
			(at 0 62.900052 90)
			(size 1.8034 0.508)
			(layers "F.Cu" "F.Mask" "F.Paste")
			(net "M_C_CLK_DN<0>")
		)
		(pad "76" smd rect
			(at 0 63.749936 90)
			(size 1.8034 0.508)
			(layers "F.Cu" "F.Mask" "F.Paste")
			(net "PVDDQ_ABC")
		)
		(pad "77" smd rect
			(at 0 64.600074 90)
			(size 1.8034 0.508)
			(layers "F.Cu" "F.Mask" "F.Paste")
			(net "PVTT_ABC")
		)
		(pad "78" smd rect
			(at 0 70.550024 90)
			(size 1.8034 0.508)
			(layers "F.Cu" "F.Mask" "F.Paste")
			(net "FM_DIMM_EVENT_COD_N")
		)
		(pad "79" smd rect
			(at 0 71.399908 90)
			(size 1.8034 0.508)
			(layers "F.Cu" "F.Mask" "F.Paste")
			(net "M_C_MA<0>")
		)
		(pad "80" smd rect
			(at 0 72.250046 90)
			(size 1.8034 0.508)
			(layers "F.Cu" "F.Mask" "F.Paste")
			(net "PVDDQ_ABC")
		)
		(pad "81" smd rect
			(at 0 73.09993 90)
			(size 1.8034 0.508)
			(layers "F.Cu" "F.Mask" "F.Paste")
			(net "M_C_BA<0>")
		)
		(pad "82" smd rect
			(at 0 73.950068 90)
			(size 1.8034 0.508)
			(layers "F.Cu" "F.Mask" "F.Paste")
			(net "M_C_MA<16>")
		)
		(pad "83" smd rect
			(at 0 74.799952 90)
			(size 1.8034 0.508)
			(layers "F.Cu" "F.Mask" "F.Paste")
			(net "PVDDQ_ABC")
		)
		(pad "84" smd rect
			(at 0 75.65009 90)
			(size 1.8034 0.508)
			(layers "F.Cu" "F.Mask" "F.Paste")
			(net "M_C_CS_N<0>")
		)
		(pad "85" smd rect
			(at 0 76.499974 90)
			(size 1.8034 0.508)
			(layers "F.Cu" "F.Mask" "F.Paste")
			(net "PVDDQ_ABC")
		)
		(pad "86" smd rect
			(at 0 77.350112 90)
			(size 1.8034 0.508)
			(layers "F.Cu" "F.Mask" "F.Paste")
			(net "M_C_MA<15>")
		)
		(pad "87" smd rect
			(at 0 78.199996 90)
			(size 1.8034 0.508)
			(layers "F.Cu" "F.Mask" "F.Paste")
			(net "M_C_ODT<0>")
		)
		(pad "88" smd rect
			(at 0 79.04988 90)
			(size 1.8034 0.508)
			(layers "F.Cu" "F.Mask" "F.Paste")
			(net "PVDDQ_ABC")
		)
		(pad "89" smd rect
			(at 0 79.900018 90)
			(size 1.8034 0.508)
			(layers "F.Cu" "F.Mask" "F.Paste")
			(net "M_C_CS_N<1>")
		)
		(pad "90" smd rect
			(at 0 80.749902 90)
			(size 1.8034 0.508)
			(layers "F.Cu" "F.Mask" "F.Paste")
			(net "PVDDQ_ABC")
		)
		(pad "91" smd rect
			(at 0 81.60004 90)
			(size 1.8034 0.508)
			(layers "F.Cu" "F.Mask" "F.Paste")
			(net "M_C_ODT<1>")
		)
		(pad "92" smd rect
			(at 0 82.449924 90)
			(size 1.8034 0.508)
			(layers "F.Cu" "F.Mask" "F.Paste")
			(net "PVDDQ_ABC")
		)
		(pad "93" smd rect
			(at 0 83.300062 90)
			(size 1.8034 0.508)
			(layers "F.Cu" "F.Mask" "F.Paste")
			(net "M_C_CS_N<2>")
		)
		(pad "94" smd rect
			(at 0 84.149946 90)
			(size 1.8034 0.508)
			(layers "F.Cu" "F.Mask" "F.Paste")
			(net "GND")
		)
		(pad "95" smd rect
			(at 0 85.000084 90)
			(size 1.8034 0.508)
			(layers "F.Cu" "F.Mask" "F.Paste")
			(net "M_C_DQ<37>")
		)
		(pad "96" smd rect
			(at 0 85.849968 90)
			(size 1.8034 0.508)
			(layers "F.Cu" "F.Mask" "F.Paste")
			(net "GND")
		)
		(pad "97" smd rect
			(at 0 86.700106 90)
			(size 1.8034 0.508)
			(layers "F.Cu" "F.Mask" "F.Paste")
			(net "M_C_DQ<33>")
		)
		(pad "98" smd rect
			(at 0 87.54999 90)
			(size 1.8034 0.508)
			(layers "F.Cu" "F.Mask" "F.Paste")
			(net "GND")
		)
		(pad "99" smd rect
			(at 0 88.399874 90)
			(size 1.8034 0.508)
			(layers "F.Cu" "F.Mask" "F.Paste")
			(net "M_C_DQS_DP<13>")
		)
		(pad "100" smd rect
			(at 0 89.250012 90)
			(size 1.8034 0.508)
			(layers "F.Cu" "F.Mask" "F.Paste")
			(net "M_C_DQS_DN<13>")
		)
		(pad "101" smd rect
			(at 0 90.099896 90)
			(size 1.8034 0.508)
			(layers "F.Cu" "F.Mask" "F.Paste")
			(net "GND")
		)
		(pad "102" smd rect
			(at 0 90.950034 90)
			(size 1.8034 0.508)
			(layers "F.Cu" "F.Mask" "F.Paste")
			(net "M_C_DQ<39>")
		)
		(pad "103" smd rect
			(at 0 91.799918 90)
			(size 1.8034 0.508)
			(layers "F.Cu" "F.Mask" "F.Paste")
			(net "GND")
		)
		(pad "104" smd rect
			(at 0 92.650056 90)
			(size 1.8034 0.508)
			(layers "F.Cu" "F.Mask" "F.Paste")
			(net "M_C_DQ<35>")
		)
		(pad "105" smd rect
			(at 0 93.49994 90)
			(size 1.8034 0.508)
			(layers "F.Cu" "F.Mask" "F.Paste")
			(net "GND")
		)
		(pad "106" smd rect
			(at 0 94.350078 90)
			(size 1.8034 0.508)
			(layers "F.Cu" "F.Mask" "F.Paste")
			(net "M_C_DQ<45>")
		)
		(pad "107" smd rect
			(at 0 95.199962 90)
			(size 1.8034 0.508)
			(layers "F.Cu" "F.Mask" "F.Paste")
			(net "GND")
		)
		(pad "108" smd rect
			(at 0 96.0501 90)
			(size 1.8034 0.508)
			(layers "F.Cu" "F.Mask" "F.Paste")
			(net "M_C_DQ<41>")
		)
		(pad "109" smd rect
			(at 0 96.899984 90)
			(size 1.8034 0.508)
			(layers "F.Cu" "F.Mask" "F.Paste")
			(net "GND")
		)
		(pad "110" smd rect
			(at 0 97.750122 90)
			(size 1.8034 0.508)
			(layers "F.Cu" "F.Mask" "F.Paste")
			(net "M_C_DQS_DP<14>")
		)
		(pad "111" smd rect
			(at 0 98.600006 90)
			(size 1.8034 0.508)
			(layers "F.Cu" "F.Mask" "F.Paste")
			(net "M_C_DQS_DN<14>")
		)
		(pad "112" smd rect
			(at 0 99.44989 90)
			(size 1.8034 0.508)
			(layers "F.Cu" "F.Mask" "F.Paste")
			(net "GND")
		)
		(pad "113" smd rect
			(at 0 100.300028 90)
			(size 1.8034 0.508)
			(layers "F.Cu" "F.Mask" "F.Paste")
			(net "M_C_DQ<47>")
		)
		(pad "114" smd rect
			(at 0 101.149912 90)
			(size 1.8034 0.508)
			(layers "F.Cu" "F.Mask" "F.Paste")
			(net "GND")
		)
		(pad "115" smd rect
			(at 0 102.00005 90)
			(size 1.8034 0.508)
			(layers "F.Cu" "F.Mask" "F.Paste")
			(net "M_C_DQ<43>")
		)
		(pad "116" smd rect
			(at 0 102.849934 90)
			(size 1.8034 0.508)
			(layers "F.Cu" "F.Mask" "F.Paste")
			(net "GND")
		)
		(pad "117" smd rect
			(at 0 103.700072 90)
			(size 1.8034 0.508)
			(layers "F.Cu" "F.Mask" "F.Paste")
			(net "M_C_DQ<53>")
		)
		(pad "118" smd rect
			(at 0 104.549956 90)
			(size 1.8034 0.508)
			(layers "F.Cu" "F.Mask" "F.Paste")
			(net "GND")
		)
		(pad "119" smd rect
			(at 0 105.400094 90)
			(size 1.8034 0.508)
			(layers "F.Cu" "F.Mask" "F.Paste")
			(net "M_C_DQ<49>")
		)
		(pad "120" smd rect
			(at 0 106.249978 90)
			(size 1.8034 0.508)
			(layers "F.Cu" "F.Mask" "F.Paste")
			(net "GND")
		)
		(pad "121" smd rect
			(at 0 107.100116 90)
			(size 1.8034 0.508)
			(layers "F.Cu" "F.Mask" "F.Paste")
			(net "M_C_DQS_DP<15>")
		)
		(pad "122" smd rect
			(at 0 107.95 90)
			(size 1.8034 0.508)
			(layers "F.Cu" "F.Mask" "F.Paste")
			(net "M_C_DQS_DN<15>")
		)
		(pad "123" smd rect
			(at 0 108.799884 90)
			(size 1.8034 0.508)
			(layers "F.Cu" "F.Mask" "F.Paste")
			(net "GND")
		)
		(pad "124" smd rect
			(at 0 109.650022 90)
			(size 1.8034 0.508)
			(layers "F.Cu" "F.Mask" "F.Paste")
			(net "M_C_DQ<55>")
		)
		(pad "125" smd rect
			(at 0 110.499906 90)
			(size 1.8034 0.508)
			(layers "F.Cu" "F.Mask" "F.Paste")
			(net "GND")
		)
		(pad "126" smd rect
			(at 0 111.350044 90)
			(size 1.8034 0.508)
			(layers "F.Cu" "F.Mask" "F.Paste")
			(net "M_C_DQ<51>")
		)
		(pad "127" smd rect
			(at 0 112.199928 90)
			(size 1.8034 0.508)
			(layers "F.Cu" "F.Mask" "F.Paste")
			(net "GND")
		)
		(pad "128" smd rect
			(at 0 113.050066 90)
			(size 1.8034 0.508)
			(layers "F.Cu" "F.Mask" "F.Paste")
			(net "M_C_DQ<61>")
		)
		(pad "129" smd rect
			(at 0 113.89995 90)
			(size 1.8034 0.508)
			(layers "F.Cu" "F.Mask" "F.Paste")
			(net "GND")
		)
		(pad "130" smd rect
			(at 0 114.750088 90)
			(size 1.8034 0.508)
			(layers "F.Cu" "F.Mask" "F.Paste")
			(net "M_C_DQ<57>")
		)
		(pad "131" smd rect
			(at 0 115.599972 90)
			(size 1.8034 0.508)
			(layers "F.Cu" "F.Mask" "F.Paste")
			(net "GND")
		)
		(pad "132" smd rect
			(at 0 116.45011 90)
			(size 1.8034 0.508)
			(layers "F.Cu" "F.Mask" "F.Paste")
			(net "M_C_DQS_DP<16>")
		)
		(pad "133" smd rect
			(at 0 117.299994 90)
			(size 1.8034 0.508)
			(layers "F.Cu" "F.Mask" "F.Paste")
			(net "M_C_DQS_DN<16>")
		)
		(pad "134" smd rect
			(at 0 118.149878 90)
			(size 1.8034 0.508)
			(layers "F.Cu" "F.Mask" "F.Paste")
			(net "GND")
		)
		(pad "135" smd rect
			(at 0 119.000016 90)
			(size 1.8034 0.508)
			(layers "F.Cu" "F.Mask" "F.Paste")
			(net "M_C_DQ<63>")
		)
		(pad "136" smd rect
			(at 0 119.8499 90)
			(size 1.8034 0.508)
			(layers "F.Cu" "F.Mask" "F.Paste")
			(net "GND")
		)
		(pad "137" smd rect
			(at 0 120.700038 90)
			(size 1.8034 0.508)
			(layers "F.Cu" "F.Mask" "F.Paste")
			(net "M_C_DQ<59>")
		)
		(pad "138" smd rect
			(at 0 121.549922 90)
			(size 1.8034 0.508)
			(layers "F.Cu" "F.Mask" "F.Paste")
			(net "GND")
		)
		(pad "139" smd rect
			(at 0 122.40006 90)
			(size 1.8034 0.508)
			(layers "F.Cu" "F.Mask" "F.Paste")
			(net "GND")
		)
		(pad "140" smd rect
			(at 0 123.249944 90)
			(size 1.8034 0.508)
			(layers "F.Cu" "F.Mask" "F.Paste")
			(net "GND")
		)
		(pad "141" smd rect
			(at 0 124.100082 90)
			(size 1.8034 0.508)
			(layers "F.Cu" "F.Mask" "F.Paste")
			(net "SMB_DDR_ABC_VPP_SCL")
		)
		(pad "142" smd rect
			(at 0 124.949966 90)
			(size 1.8034 0.508)
			(layers "F.Cu" "F.Mask" "F.Paste")
			(net "PVPP_ABC")
		)
		(pad "143" smd rect
			(at 0 125.800104 90)
			(size 1.8034 0.508)
			(layers "F.Cu" "F.Mask" "F.Paste")
			(net "PVPP_ABC")
		)
		(pad "144" smd rect
			(at 0 126.649988 90)
			(size 1.8034 0.508)
			(layers "F.Cu" "F.Mask" "F.Paste")
			(net "TP_CH_C_DIMM_C0_RFU_2")
		)
		(pad "145" smd rect
			(at 4.59994 0 90)
			(size 1.8034 0.508)
			(layers "F.Cu" "F.Mask" "F.Paste")
			(net "P12V_NVDIMM_ABC")
		)
		(pad "146" smd rect
			(at 4.59994 0.849884 90)
			(size 1.8034 0.508)
			(layers "F.Cu" "F.Mask" "F.Paste")
			(net "M_C_VREF")
		)
		(pad "147" smd rect
			(at 4.59994 1.700022 90)
			(size 1.8034 0.508)
			(layers "F.Cu" "F.Mask" "F.Paste")
			(net "GND")
		)
		(pad "148" smd rect
			(at 4.59994 2.549906 90)
			(size 1.8034 0.508)
			(layers "F.Cu" "F.Mask" "F.Paste")
			(net "M_C_DQ<4>")
		)
		(pad "149" smd rect
			(at 4.59994 3.400044 90)
			(size 1.8034 0.508)
			(layers "F.Cu" "F.Mask" "F.Paste")
			(net "GND")
		)
		(pad "150" smd rect
			(at 4.59994 4.249928 90)
			(size 1.8034 0.508)
			(layers "F.Cu" "F.Mask" "F.Paste")
			(net "M_C_DQ<0>")
		)
		(pad "151" smd rect
			(at 4.59994 5.100066 90)
			(size 1.8034 0.508)
			(layers "F.Cu" "F.Mask" "F.Paste")
			(net "GND")
		)
		(pad "152" smd rect
			(at 4.59994 5.94995 90)
			(size 1.8034 0.508)
			(layers "F.Cu" "F.Mask" "F.Paste")
			(net "M_C_DQS_DN<0>")
		)
		(pad "153" smd rect
			(at 4.59994 6.800088 90)
			(size 1.8034 0.508)
			(layers "F.Cu" "F.Mask" "F.Paste")
			(net "M_C_DQS_DP<0>")
		)
		(pad "154" smd rect
			(at 4.59994 7.649972 90)
			(size 1.8034 0.508)
			(layers "F.Cu" "F.Mask" "F.Paste")
			(net "GND")
		)
		(pad "155" smd rect
			(at 4.59994 8.50011 90)
			(size 1.8034 0.508)
			(layers "F.Cu" "F.Mask" "F.Paste")
			(net "M_C_DQ<6>")
		)
		(pad "156" smd rect
			(at 4.59994 9.349994 90)
			(size 1.8034 0.508)
			(layers "F.Cu" "F.Mask" "F.Paste")
			(net "GND")
		)
		(pad "157" smd rect
			(at 4.59994 10.199878 90)
			(size 1.8034 0.508)
			(layers "F.Cu" "F.Mask" "F.Paste")
			(net "M_C_DQ<2>")
		)
		(pad "158" smd rect
			(at 4.59994 11.050016 90)
			(size 1.8034 0.508)
			(layers "F.Cu" "F.Mask" "F.Paste")
			(net "GND")
		)
		(pad "159" smd rect
			(at 4.59994 11.8999 90)
			(size 1.8034 0.508)
			(layers "F.Cu" "F.Mask" "F.Paste")
			(net "M_C_DQ<12>")
		)
		(pad "160" smd rect
			(at 4.59994 12.750038 90)
			(size 1.8034 0.508)
			(layers "F.Cu" "F.Mask" "F.Paste")
			(net "GND")
		)
		(pad "161" smd rect
			(at 4.59994 13.599922 90)
			(size 1.8034 0.508)
			(layers "F.Cu" "F.Mask" "F.Paste")
			(net "M_C_DQ<8>")
		)
		(pad "162" smd rect
			(at 4.59994 14.45006 90)
			(size 1.8034 0.508)
			(layers "F.Cu" "F.Mask" "F.Paste")
			(net "GND")
		)
		(pad "163" smd rect
			(at 4.59994 15.299944 90)
			(size 1.8034 0.508)
			(layers "F.Cu" "F.Mask" "F.Paste")
			(net "M_C_DQS_DN<1>")
		)
		(pad "164" smd rect
			(at 4.59994 16.150082 90)
			(size 1.8034 0.508)
			(layers "F.Cu" "F.Mask" "F.Paste")
			(net "M_C_DQS_DP<1>")
		)
		(pad "165" smd rect
			(at 4.59994 16.999966 90)
			(size 1.8034 0.508)
			(layers "F.Cu" "F.Mask" "F.Paste")
			(net "GND")
		)
		(pad "166" smd rect
			(at 4.59994 17.850104 90)
			(size 1.8034 0.508)
			(layers "F.Cu" "F.Mask" "F.Paste")
			(net "M_C_DQ<14>")
		)
		(pad "167" smd rect
			(at 4.59994 18.699988 90)
			(size 1.8034 0.508)
			(layers "F.Cu" "F.Mask" "F.Paste")
			(net "GND")
		)
		(pad "168" smd rect
			(at 4.59994 19.550126 90)
			(size 1.8034 0.508)
			(layers "F.Cu" "F.Mask" "F.Paste")
			(net "M_C_DQ<10>")
		)
		(pad "169" smd rect
			(at 4.59994 20.40001 90)
			(size 1.8034 0.508)
			(layers "F.Cu" "F.Mask" "F.Paste")
			(net "GND")
		)
		(pad "170" smd rect
			(at 4.59994 21.249894 90)
			(size 1.8034 0.508)
			(layers "F.Cu" "F.Mask" "F.Paste")
			(net "M_C_DQ<20>")
		)
		(pad "171" smd rect
			(at 4.59994 22.100032 90)
			(size 1.8034 0.508)
			(layers "F.Cu" "F.Mask" "F.Paste")
			(net "GND")
		)
		(pad "172" smd rect
			(at 4.59994 22.949916 90)
			(size 1.8034 0.508)
			(layers "F.Cu" "F.Mask" "F.Paste")
			(net "M_C_DQ<16>")
		)
		(pad "173" smd rect
			(at 4.59994 23.800054 90)
			(size 1.8034 0.508)
			(layers "F.Cu" "F.Mask" "F.Paste")
			(net "GND")
		)
		(pad "174" smd rect
			(at 4.59994 24.649938 90)
			(size 1.8034 0.508)
			(layers "F.Cu" "F.Mask" "F.Paste")
			(net "M_C_DQS_DN<2>")
		)
		(pad "175" smd rect
			(at 4.59994 25.500076 90)
			(size 1.8034 0.508)
			(layers "F.Cu" "F.Mask" "F.Paste")
			(net "M_C_DQS_DP<2>")
		)
		(pad "176" smd rect
			(at 4.59994 26.34996 90)
			(size 1.8034 0.508)
			(layers "F.Cu" "F.Mask" "F.Paste")
			(net "GND")
		)
		(pad "177" smd rect
			(at 4.59994 27.200098 90)
			(size 1.8034 0.508)
			(layers "F.Cu" "F.Mask" "F.Paste")
			(net "M_C_DQ<22>")
		)
		(pad "178" smd rect
			(at 4.59994 28.049982 90)
			(size 1.8034 0.508)
			(layers "F.Cu" "F.Mask" "F.Paste")
			(net "GND")
		)
		(pad "179" smd rect
			(at 4.59994 28.90012 90)
			(size 1.8034 0.508)
			(layers "F.Cu" "F.Mask" "F.Paste")
			(net "M_C_DQ<18>")
		)
		(pad "180" smd rect
			(at 4.59994 29.750004 90)
			(size 1.8034 0.508)
			(layers "F.Cu" "F.Mask" "F.Paste")
			(net "GND")
		)
		(pad "181" smd rect
			(at 4.59994 30.599888 90)
			(size 1.8034 0.508)
			(layers "F.Cu" "F.Mask" "F.Paste")
			(net "M_C_DQ<28>")
		)
		(pad "182" smd rect
			(at 4.59994 31.450026 90)
			(size 1.8034 0.508)
			(layers "F.Cu" "F.Mask" "F.Paste")
			(net "GND")
		)
		(pad "183" smd rect
			(at 4.59994 32.29991 90)
			(size 1.8034 0.508)
			(layers "F.Cu" "F.Mask" "F.Paste")
			(net "M_C_DQ<24>")
		)
		(pad "184" smd rect
			(at 4.59994 33.150048 90)
			(size 1.8034 0.508)
			(layers "F.Cu" "F.Mask" "F.Paste")
			(net "GND")
		)
		(pad "185" smd rect
			(at 4.59994 33.999932 90)
			(size 1.8034 0.508)
			(layers "F.Cu" "F.Mask" "F.Paste")
			(net "M_C_DQS_DN<3>")
		)
		(pad "186" smd rect
			(at 4.59994 34.85007 90)
			(size 1.8034 0.508)
			(layers "F.Cu" "F.Mask" "F.Paste")
			(net "M_C_DQS_DP<3>")
		)
		(pad "187" smd rect
			(at 4.59994 35.699954 90)
			(size 1.8034 0.508)
			(layers "F.Cu" "F.Mask" "F.Paste")
			(net "GND")
		)
		(pad "188" smd rect
			(at 4.59994 36.550092 90)
			(size 1.8034 0.508)
			(layers "F.Cu" "F.Mask" "F.Paste")
			(net "M_C_DQ<30>")
		)
		(pad "189" smd rect
			(at 4.59994 37.399976 90)
			(size 1.8034 0.508)
			(layers "F.Cu" "F.Mask" "F.Paste")
			(net "GND")
		)
		(pad "190" smd rect
			(at 4.59994 38.250114 90)
			(size 1.8034 0.508)
			(layers "F.Cu" "F.Mask" "F.Paste")
			(net "M_C_DQ<26>")
		)
		(pad "191" smd rect
			(at 4.59994 39.099998 90)
			(size 1.8034 0.508)
			(layers "F.Cu" "F.Mask" "F.Paste")
			(net "GND")
		)
		(pad "192" smd rect
			(at 4.59994 39.949882 90)
			(size 1.8034 0.508)
			(layers "F.Cu" "F.Mask" "F.Paste")
			(net "M_C_ECC<4>")
		)
		(pad "193" smd rect
			(at 4.59994 40.80002 90)
			(size 1.8034 0.508)
			(layers "F.Cu" "F.Mask" "F.Paste")
			(net "GND")
		)
		(pad "194" smd rect
			(at 4.59994 41.649904 90)
			(size 1.8034 0.508)
			(layers "F.Cu" "F.Mask" "F.Paste")
			(net "M_C_ECC<0>")
		)
		(pad "195" smd rect
			(at 4.59994 42.500042 90)
			(size 1.8034 0.508)
			(layers "F.Cu" "F.Mask" "F.Paste")
			(net "GND")
		)
		(pad "196" smd rect
			(at 4.59994 43.349926 90)
			(size 1.8034 0.508)
			(layers "F.Cu" "F.Mask" "F.Paste")
			(net "M_C_DQS_DN<8>")
		)
		(pad "197" smd rect
			(at 4.59994 44.200064 90)
			(size 1.8034 0.508)
			(layers "F.Cu" "F.Mask" "F.Paste")
			(net "M_C_DQS_DP<8>")
		)
		(pad "198" smd rect
			(at 4.59994 45.049948 90)
			(size 1.8034 0.508)
			(layers "F.Cu" "F.Mask" "F.Paste")
			(net "GND")
		)
		(pad "199" smd rect
			(at 4.59994 45.900086 90)
			(size 1.8034 0.508)
			(layers "F.Cu" "F.Mask" "F.Paste")
			(net "M_C_ECC<6>")
		)
		(pad "200" smd rect
			(at 4.59994 46.74997 90)
			(size 1.8034 0.508)
			(layers "F.Cu" "F.Mask" "F.Paste")
			(net "GND")
		)
		(pad "201" smd rect
			(at 4.59994 47.600108 90)
			(size 1.8034 0.508)
			(layers "F.Cu" "F.Mask" "F.Paste")
			(net "M_C_ECC<2>")
		)
		(pad "202" smd rect
			(at 4.59994 48.449992 90)
			(size 1.8034 0.508)
			(layers "F.Cu" "F.Mask" "F.Paste")
			(net "GND")
		)
		(pad "203" smd rect
			(at 4.59994 49.299876 90)
			(size 1.8034 0.508)
			(layers "F.Cu" "F.Mask" "F.Paste")
			(net "M_C_CKE<1>")
		)
		(pad "204" smd rect
			(at 4.59994 50.150014 90)
			(size 1.8034 0.508)
			(layers "F.Cu" "F.Mask" "F.Paste")
			(net "PVDDQ_ABC")
		)
		(pad "205" smd rect
			(at 4.59994 50.999898 90)
			(size 1.8034 0.508)
			(layers "F.Cu" "F.Mask" "F.Paste")
			(net "TP_CH_C_DIMM_C0_RFU_0")
		)
		(pad "206" smd rect
			(at 4.59994 51.850036 90)
			(size 1.8034 0.508)
			(layers "F.Cu" "F.Mask" "F.Paste")
			(net "PVDDQ_ABC")
		)
		(pad "207" smd rect
			(at 4.59994 52.69992 90)
			(size 1.8034 0.508)
			(layers "F.Cu" "F.Mask" "F.Paste")
			(net "M_C_BG<1>")
		)
		(pad "208" smd rect
			(at 4.59994 53.550058 90)
			(size 1.8034 0.508)
			(layers "F.Cu" "F.Mask" "F.Paste")
			(net "M_C_ALERT_N")
		)
		(pad "209" smd rect
			(at 4.59994 54.399942 90)
			(size 1.8034 0.508)
			(layers "F.Cu" "F.Mask" "F.Paste")
			(net "PVDDQ_ABC")
		)
		(pad "210" smd rect
			(at 4.59994 55.25008 90)
			(size 1.8034 0.508)
			(layers "F.Cu" "F.Mask" "F.Paste")
			(net "M_C_MA<11>")
		)
		(pad "211" smd rect
			(at 4.59994 56.099964 90)
			(size 1.8034 0.508)
			(layers "F.Cu" "F.Mask" "F.Paste")
			(net "M_C_MA<7>")
		)
		(pad "212" smd rect
			(at 4.59994 56.950102 90)
			(size 1.8034 0.508)
			(layers "F.Cu" "F.Mask" "F.Paste")
			(net "PVDDQ_ABC")
		)
		(pad "213" smd rect
			(at 4.59994 57.799986 90)
			(size 1.8034 0.508)
			(layers "F.Cu" "F.Mask" "F.Paste")
			(net "M_C_MA<5>")
		)
		(pad "214" smd rect
			(at 4.59994 58.650124 90)
			(size 1.8034 0.508)
			(layers "F.Cu" "F.Mask" "F.Paste")
			(net "M_C_MA<4>")
		)
		(pad "215" smd rect
			(at 4.59994 59.500008 90)
			(size 1.8034 0.508)
			(layers "F.Cu" "F.Mask" "F.Paste")
			(net "PVDDQ_ABC")
		)
		(pad "216" smd rect
			(at 4.59994 60.349892 90)
			(size 1.8034 0.508)
			(layers "F.Cu" "F.Mask" "F.Paste")
			(net "M_C_MA<2>")
		)
		(pad "217" smd rect
			(at 4.59994 61.20003 90)
			(size 1.8034 0.508)
			(layers "F.Cu" "F.Mask" "F.Paste")
			(net "PVDDQ_ABC")
		)
		(pad "218" smd rect
			(at 4.59994 62.049914 90)
			(size 1.8034 0.508)
			(layers "F.Cu" "F.Mask" "F.Paste")
			(net "M_C_CLK_DP<1>")
		)
		(pad "219" smd rect
			(at 4.59994 62.900052 90)
			(size 1.8034 0.508)
			(layers "F.Cu" "F.Mask" "F.Paste")
			(net "M_C_CLK_DN<1>")
		)
		(pad "220" smd rect
			(at 4.59994 63.749936 90)
			(size 1.8034 0.508)
			(layers "F.Cu" "F.Mask" "F.Paste")
			(net "PVDDQ_ABC")
		)
		(pad "221" smd rect
			(at 4.59994 64.600074 90)
			(size 1.8034 0.508)
			(layers "F.Cu" "F.Mask" "F.Paste")
			(net "PVTT_ABC")
		)
		(pad "222" smd rect
			(at 4.59994 70.550024 90)
			(size 1.8034 0.508)
			(layers "F.Cu" "F.Mask" "F.Paste")
			(net "M_C_PAR")
		)
		(pad "223" smd rect
			(at 4.59994 71.399908 90)
			(size 1.8034 0.508)
			(layers "F.Cu" "F.Mask" "F.Paste")
			(net "PVDDQ_ABC")
		)
		(pad "224" smd rect
			(at 4.59994 72.250046 90)
			(size 1.8034 0.508)
			(layers "F.Cu" "F.Mask" "F.Paste")
			(net "M_C_BA<1>")
		)
		(pad "225" smd rect
			(at 4.59994 73.09993 90)
			(size 1.8034 0.508)
			(layers "F.Cu" "F.Mask" "F.Paste")
			(net "M_C_MA<10>")
		)
		(pad "226" smd rect
			(at 4.59994 73.950068 90)
			(size 1.8034 0.508)
			(layers "F.Cu" "F.Mask" "F.Paste")
			(net "PVDDQ_ABC")
		)
		(pad "227" smd rect
			(at 4.59994 74.799952 90)
			(size 1.8034 0.508)
			(layers "F.Cu" "F.Mask" "F.Paste")
			(net "TP_CH_C_DIMM_C0_RFU_1")
		)
		(pad "228" smd rect
			(at 4.59994 75.65009 90)
			(size 1.8034 0.508)
			(layers "F.Cu" "F.Mask" "F.Paste")
			(net "M_C_MA<14>")
		)
		(pad "229" smd rect
			(at 4.59994 76.499974 90)
			(size 1.8034 0.508)
			(layers "F.Cu" "F.Mask" "F.Paste")
			(net "PVDDQ_ABC")
		)
		(pad "230" smd rect
			(at 4.59994 77.350112 90)
			(size 1.8034 0.508)
			(layers "F.Cu" "F.Mask" "F.Paste")
			(net "FM_ADR_COMPLETE_ABC_N")
		)
		(pad "231" smd rect
			(at 4.59994 78.199996 90)
			(size 1.8034 0.508)
			(layers "F.Cu" "F.Mask" "F.Paste")
			(net "PVDDQ_ABC")
		)
		(pad "232" smd rect
			(at 4.59994 79.04988 90)
			(size 1.8034 0.508)
			(layers "F.Cu" "F.Mask" "F.Paste")
			(net "M_C_MA<13>")
		)
		(pad "233" smd rect
			(at 4.59994 79.900018 90)
			(size 1.8034 0.508)
			(layers "F.Cu" "F.Mask" "F.Paste")
			(net "PVDDQ_ABC")
		)
		(pad "234" smd rect
			(at 4.59994 80.749902 90)
			(size 1.8034 0.508)
			(layers "F.Cu" "F.Mask" "F.Paste")
			(net "M_C_MA<17>")
		)
		(pad "235" smd rect
			(at 4.59994 81.60004 90)
			(size 1.8034 0.508)
			(layers "F.Cu" "F.Mask" "F.Paste")
			(net "M_C_C<2>")
		)
		(pad "236" smd rect
			(at 4.59994 82.449924 90)
			(size 1.8034 0.508)
			(layers "F.Cu" "F.Mask" "F.Paste")
			(net "PVDDQ_ABC")
		)
		(pad "237" smd rect
			(at 4.59994 83.300062 90)
			(size 1.8034 0.508)
			(layers "F.Cu" "F.Mask" "F.Paste")
			(net "M_C_CS_N<3>")
		)
		(pad "238" smd rect
			(at 4.59994 84.149946 90)
			(size 1.8034 0.508)
			(layers "F.Cu" "F.Mask" "F.Paste")
			(net "PVPP_ABC")
		)
		(pad "239" smd rect
			(at 4.59994 85.000084 90)
			(size 1.8034 0.508)
			(layers "F.Cu" "F.Mask" "F.Paste")
			(net "GND")
		)
		(pad "240" smd rect
			(at 4.59994 85.849968 90)
			(size 1.8034 0.508)
			(layers "F.Cu" "F.Mask" "F.Paste")
			(net "M_C_DQ<36>")
		)
		(pad "241" smd rect
			(at 4.59994 86.700106 90)
			(size 1.8034 0.508)
			(layers "F.Cu" "F.Mask" "F.Paste")
			(net "GND")
		)
		(pad "242" smd rect
			(at 4.59994 87.54999 90)
			(size 1.8034 0.508)
			(layers "F.Cu" "F.Mask" "F.Paste")
			(net "M_C_DQ<32>")
		)
		(pad "243" smd rect
			(at 4.59994 88.399874 90)
			(size 1.8034 0.508)
			(layers "F.Cu" "F.Mask" "F.Paste")
			(net "GND")
		)
		(pad "244" smd rect
			(at 4.59994 89.250012 90)
			(size 1.8034 0.508)
			(layers "F.Cu" "F.Mask" "F.Paste")
			(net "M_C_DQS_DN<4>")
		)
		(pad "245" smd rect
			(at 4.59994 90.099896 90)
			(size 1.8034 0.508)
			(layers "F.Cu" "F.Mask" "F.Paste")
			(net "M_C_DQS_DP<4>")
		)
		(pad "246" smd rect
			(at 4.59994 90.950034 90)
			(size 1.8034 0.508)
			(layers "F.Cu" "F.Mask" "F.Paste")
			(net "GND")
		)
		(pad "247" smd rect
			(at 4.59994 91.799918 90)
			(size 1.8034 0.508)
			(layers "F.Cu" "F.Mask" "F.Paste")
			(net "M_C_DQ<38>")
		)
		(pad "248" smd rect
			(at 4.59994 92.650056 90)
			(size 1.8034 0.508)
			(layers "F.Cu" "F.Mask" "F.Paste")
			(net "GND")
		)
		(pad "249" smd rect
			(at 4.59994 93.49994 90)
			(size 1.8034 0.508)
			(layers "F.Cu" "F.Mask" "F.Paste")
			(net "M_C_DQ<34>")
		)
		(pad "250" smd rect
			(at 4.59994 94.350078 90)
			(size 1.8034 0.508)
			(layers "F.Cu" "F.Mask" "F.Paste")
			(net "GND")
		)
		(pad "251" smd rect
			(at 4.59994 95.199962 90)
			(size 1.8034 0.508)
			(layers "F.Cu" "F.Mask" "F.Paste")
			(net "M_C_DQ<44>")
		)
		(pad "252" smd rect
			(at 4.59994 96.0501 90)
			(size 1.8034 0.508)
			(layers "F.Cu" "F.Mask" "F.Paste")
			(net "GND")
		)
		(pad "253" smd rect
			(at 4.59994 96.899984 90)
			(size 1.8034 0.508)
			(layers "F.Cu" "F.Mask" "F.Paste")
			(net "M_C_DQ<40>")
		)
		(pad "254" smd rect
			(at 4.59994 97.750122 90)
			(size 1.8034 0.508)
			(layers "F.Cu" "F.Mask" "F.Paste")
			(net "GND")
		)
		(pad "255" smd rect
			(at 4.59994 98.600006 90)
			(size 1.8034 0.508)
			(layers "F.Cu" "F.Mask" "F.Paste")
			(net "M_C_DQS_DN<5>")
		)
		(pad "256" smd rect
			(at 4.59994 99.44989 90)
			(size 1.8034 0.508)
			(layers "F.Cu" "F.Mask" "F.Paste")
			(net "M_C_DQS_DP<5>")
		)
		(pad "257" smd rect
			(at 4.59994 100.300028 90)
			(size 1.8034 0.508)
			(layers "F.Cu" "F.Mask" "F.Paste")
			(net "GND")
		)
		(pad "258" smd rect
			(at 4.59994 101.149912 90)
			(size 1.8034 0.508)
			(layers "F.Cu" "F.Mask" "F.Paste")
			(net "M_C_DQ<46>")
		)
		(pad "259" smd rect
			(at 4.59994 102.00005 90)
			(size 1.8034 0.508)
			(layers "F.Cu" "F.Mask" "F.Paste")
			(net "GND")
		)
		(pad "260" smd rect
			(at 4.59994 102.849934 90)
			(size 1.8034 0.508)
			(layers "F.Cu" "F.Mask" "F.Paste")
			(net "M_C_DQ<42>")
		)
		(pad "261" smd rect
			(at 4.59994 103.700072 90)
			(size 1.8034 0.508)
			(layers "F.Cu" "F.Mask" "F.Paste")
			(net "GND")
		)
		(pad "262" smd rect
			(at 4.59994 104.549956 90)
			(size 1.8034 0.508)
			(layers "F.Cu" "F.Mask" "F.Paste")
			(net "M_C_DQ<52>")
		)
		(pad "263" smd rect
			(at 4.59994 105.400094 90)
			(size 1.8034 0.508)
			(layers "F.Cu" "F.Mask" "F.Paste")
			(net "GND")
		)
		(pad "264" smd rect
			(at 4.59994 106.249978 90)
			(size 1.8034 0.508)
			(layers "F.Cu" "F.Mask" "F.Paste")
			(net "M_C_DQ<48>")
		)
		(pad "265" smd rect
			(at 4.59994 107.100116 90)
			(size 1.8034 0.508)
			(layers "F.Cu" "F.Mask" "F.Paste")
			(net "GND")
		)
		(pad "266" smd rect
			(at 4.59994 107.95 90)
			(size 1.8034 0.508)
			(layers "F.Cu" "F.Mask" "F.Paste")
			(net "M_C_DQS_DN<6>")
		)
		(pad "267" smd rect
			(at 4.59994 108.799884 90)
			(size 1.8034 0.508)
			(layers "F.Cu" "F.Mask" "F.Paste")
			(net "M_C_DQS_DP<6>")
		)
		(pad "268" smd rect
			(at 4.59994 109.650022 90)
			(size 1.8034 0.508)
			(layers "F.Cu" "F.Mask" "F.Paste")
			(net "GND")
		)
		(pad "269" smd rect
			(at 4.59994 110.499906 90)
			(size 1.8034 0.508)
			(layers "F.Cu" "F.Mask" "F.Paste")
			(net "M_C_DQ<54>")
		)
		(pad "270" smd rect
			(at 4.59994 111.350044 90)
			(size 1.8034 0.508)
			(layers "F.Cu" "F.Mask" "F.Paste")
			(net "GND")
		)
		(pad "271" smd rect
			(at 4.59994 112.199928 90)
			(size 1.8034 0.508)
			(layers "F.Cu" "F.Mask" "F.Paste")
			(net "M_C_DQ<50>")
		)
		(pad "272" smd rect
			(at 4.59994 113.050066 90)
			(size 1.8034 0.508)
			(layers "F.Cu" "F.Mask" "F.Paste")
			(net "GND")
		)
		(pad "273" smd rect
			(at 4.59994 113.89995 90)
			(size 1.8034 0.508)
			(layers "F.Cu" "F.Mask" "F.Paste")
			(net "M_C_DQ<60>")
		)
		(pad "274" smd rect
			(at 4.59994 114.750088 90)
			(size 1.8034 0.508)
			(layers "F.Cu" "F.Mask" "F.Paste")
			(net "GND")
		)
		(pad "275" smd rect
			(at 4.59994 115.599972 90)
			(size 1.8034 0.508)
			(layers "F.Cu" "F.Mask" "F.Paste")
			(net "M_C_DQ<56>")
		)
		(pad "276" smd rect
			(at 4.59994 116.45011 90)
			(size 1.8034 0.508)
			(layers "F.Cu" "F.Mask" "F.Paste")
			(net "GND")
		)
		(pad "277" smd rect
			(at 4.59994 117.299994 90)
			(size 1.8034 0.508)
			(layers "F.Cu" "F.Mask" "F.Paste")
			(net "M_C_DQS_DN<7>")
		)
		(pad "278" smd rect
			(at 4.59994 118.149878 90)
			(size 1.8034 0.508)
			(layers "F.Cu" "F.Mask" "F.Paste")
			(net "M_C_DQS_DP<7>")
		)
		(pad "279" smd rect
			(at 4.59994 119.000016 90)
			(size 1.8034 0.508)
			(layers "F.Cu" "F.Mask" "F.Paste")
			(net "GND")
		)
		(pad "280" smd rect
			(at 4.59994 119.8499 90)
			(size 1.8034 0.508)
			(layers "F.Cu" "F.Mask" "F.Paste")
			(net "M_C_DQ<62>")
		)
		(pad "281" smd rect
			(at 4.59994 120.700038 90)
			(size 1.8034 0.508)
			(layers "F.Cu" "F.Mask" "F.Paste")
			(net "GND")
		)
		(pad "282" smd rect
			(at 4.59994 121.549922 90)
			(size 1.8034 0.508)
			(layers "F.Cu" "F.Mask" "F.Paste")
			(net "M_C_DQ<58>")
		)
		(pad "283" smd rect
			(at 4.59994 122.40006 90)
			(size 1.8034 0.508)
			(layers "F.Cu" "F.Mask" "F.Paste")
			(net "GND")
		)
		(pad "284" smd rect
			(at 4.59994 123.249944 90)
			(size 1.8034 0.508)
			(layers "F.Cu" "F.Mask" "F.Paste")
			(net "PVPP_ABC")
		)
		(pad "285" smd rect
			(at 4.59994 124.100082 90)
			(size 1.8034 0.508)
			(layers "F.Cu" "F.Mask" "F.Paste")
			(net "SMB_DDR_ABC_VPP_SDA")
		)
		(pad "286" smd rect
			(at 4.59994 124.949966 90)
			(size 1.8034 0.508)
			(layers "F.Cu" "F.Mask" "F.Paste")
			(net "PVPP_ABC")
		)
		(pad "287" smd rect
			(at 4.59994 125.800104 90)
			(size 1.8034 0.508)
			(layers "F.Cu" "F.Mask" "F.Paste")
			(net "PVPP_ABC")
		)
		(pad "288" smd rect
			(at 4.59994 126.649988 90)
			(size 1.8034 0.508)
			(layers "F.Cu" "F.Mask" "F.Paste")
			(net "PVPP_ABC")
		)
	)
	(footprint ""
		(layer "F.Cu")
		(at 198.925434 -89.551764 90)
		(property "Reference" "EU4C2"
			(at 3.309366 -1.618234 0)
			(unlocked yes)
			(layer "F.SilkS")
			(effects
				(font
					(size 0.7874 0.5842)
					(thickness 0.1524)
				)
			)
		)
		(property "Value" ""
			(at 0 0 90)
			(layer "F.Fab")
			(effects
				(font
					(size 1.27 1.27)
				)
			)
		)
		(duplicate_pad_numbers_are_jumpers no)
		(fp_line
			(start 2.9718 -3.5052)
			(end 2.9718 3.429)
			(stroke
				(width 0.1524)
				(type default)
			)
			(layer "F.SilkS")
		)
		(fp_line
			(start -3.0099 -3.5052)
			(end 2.9718 -3.5052)
			(stroke
				(width 0.1524)
				(type default)
			)
			(layer "F.SilkS")
		)
		(fp_line
			(start 2.9718 3.429)
			(end -3.0099 3.429)
			(stroke
				(width 0.1524)
				(type default)
			)
			(layer "F.SilkS")
		)
		(fp_line
			(start -3.0099 3.429)
			(end -3.0099 -3.5052)
			(stroke
				(width 0.1524)
				(type default)
			)
			(layer "F.SilkS")
		)
		(fp_circle
			(center -3.373374 -3.160522)
			(end -3.373374 -3.033522)
			(stroke
				(width 0.254)
				(type default)
			)
			(fill no)
			(layer "F.SilkS")
		)
		(fp_poly
			(pts
				(xy -2.9972 -3.4925) (xy -2.9972 -2.6924) (xy -2.1971 -3.4925)
			)
			(stroke
				(width 0)
				(type default)
			)
			(fill yes)
			(layer "F.SilkS")
		)
		(fp_poly
			(pts
				(xy -2.549906 -3.050032) (xy -2.549906 3.050032) (xy 2.549906 3.050032) (xy 2.549906 -3.050032)
			)
			(stroke
				(width 0)
				(type default)
			)
			(fill no)
			(layer "F.CrtYd")
		)
		(fp_line
			(start 2.549906 -3.050032)
			(end 2.549906 3.050032)
			(stroke
				(width 0.1)
				(type default)
			)
			(layer "F.Fab")
		)
		(fp_line
			(start -2.549906 -3.050032)
			(end 2.549906 -3.050032)
			(stroke
				(width 0.1)
				(type default)
			)
			(layer "F.Fab")
		)
		(fp_line
			(start 2.549906 3.050032)
			(end -2.549906 3.050032)
			(stroke
				(width 0.1)
				(type default)
			)
			(layer "F.Fab")
		)
		(fp_line
			(start -2.549906 3.050032)
			(end -2.549906 -3.050032)
			(stroke
				(width 0.1)
				(type default)
			)
			(layer "F.Fab")
		)
		(fp_circle
			(center -3.057398 -2.678684)
			(end -3.057398 -2.551684)
			(stroke
				(width 0.254)
				(type default)
			)
			(fill no)
			(layer "F.Fab")
		)
		(pad "1" smd rect
			(at -2.39522 -2.279904 90)
			(size 0.7112 0.254)
			(layers "F.Cu" "F.Mask" "F.Paste")
			(net "PVCCIN_CPU0")
		)
		(pad "2" smd rect
			(at -2.39522 -1.83007 90)
			(size 0.7112 0.254)
			(layers "F.Cu" "F.Mask" "F.Paste")
			(net "GND")
		)
		(pad "3" smd rect
			(at -2.39522 -1.379982 90)
			(size 0.7112 0.254)
			(layers "F.Cu" "F.Mask" "F.Paste")
			(net "VR_PVCCIN_CPU0_PH5_VCIN")
		)
		(pad "4" smd rect
			(at -2.39522 -0.929894 90)
			(size 0.7112 0.254)
			(layers "F.Cu" "F.Mask" "F.Paste")
			(net "P5V_STBY")
		)
		(pad "5" smd rect
			(at -2.39522 -0.48006 90)
			(size 0.7112 0.254)
			(layers "F.Cu" "F.Mask" "F.Paste")
			(net "GND")
		)
		(pad "6" smd rect
			(at -2.39522 -0.029972 90)
			(size 0.7112 0.254)
			(layers "F.Cu" "F.Mask" "F.Paste")
			(net "TP_PVCCIN_CPU0_PH5_GL_0")
		)
		(pad "7" smd custom
			(at 0.016764 1.145032 90)
			(size 0.53975 0.53975)
			(layers "F.Cu" "F.Mask" "F.Paste")
			(net "GND")
			(options
				(clearance outline)
				(anchor circle)
			)
			(primitives
				(gr_poly
					(pts
						(xy -2.7051 1.0795) (xy -2.7051 -0.3683) (xy -0.9271 -0.3683) (xy -0.9271 -1.0795) (xy 2.7051 -1.0795)
						(xy 2.7051 1.0795)
					)
					(width 0)
					(fill yes)
				)
			)
		)
		(pad "10" smd rect
			(at -0.008382 2.874772 90)
			(size 4.3434 0.6096)
			(layers "F.Cu" "F.Mask" "F.Paste")
			(net "VR_PVCCIN_CPU0_PHASE5")
		)
		(pad "25" smd rect
			(at 1.548384 -1.283208 90)
			(size 2.3368 2.0066)
			(layers "F.Cu" "F.Mask" "F.Paste")
			(net "VR_FET_SW_P12V_STBY_PVCCIN_CPU0")
		)
		(pad "30" smd rect
			(at 2.050034 -2.895092 90)
			(size 0.254 0.7112)
			(layers "F.Cu" "F.Mask" "F.Paste")
			(net "VR_FET_SW_P12V_STBY_PVCCIN_CPU0")
		)
		(pad "31" smd rect
			(at 1.599946 -2.895092 90)
			(size 0.254 0.7112)
			(layers "F.Cu" "F.Mask" "F.Paste")
			(net "Net_365")
		)
		(pad "32" smd rect
			(at 1.150112 -2.895092 90)
			(size 0.254 0.7112)
			(layers "F.Cu" "F.Mask" "F.Paste")
			(net "VR_PVCCIN_CPU0_PH5_PHASE")
		)
		(pad "33" smd rect
			(at 0.700024 -2.895092 90)
			(size 0.254 0.7112)
			(layers "F.Cu" "F.Mask" "F.Paste")
			(net "VR_PVCCIN_CPU0_PH5_BOOT_R")
		)
		(pad "34" smd rect
			(at 0.249936 -2.895092 90)
			(size 0.254 0.7112)
			(layers "F.Cu" "F.Mask" "F.Paste")
			(net "VR_PVCCIN_CPU0_PWM5")
		)
		(pad "35" smd rect
			(at -0.199898 -2.895092 90)
			(size 0.254 0.7112)
			(layers "F.Cu" "F.Mask" "F.Paste")
			(net "P5V_STBY")
		)
		(pad "36" smd rect
			(at -0.649986 -2.895092 90)
			(size 0.254 0.7112)
			(layers "F.Cu" "F.Mask" "F.Paste")
			(net "A_TSENSE_PVCCIN_CPU0")
		)
		(pad "37" smd rect
			(at -1.100074 -2.895092 90)
			(size 0.254 0.7112)
			(layers "F.Cu" "F.Mask" "F.Paste")
			(net "VR_PVCCIN_CPU0_PH5_OCSET")
		)
		(pad "38" smd rect
			(at -1.549908 -2.895092 90)
			(size 0.254 0.7112)
			(layers "F.Cu" "F.Mask" "F.Paste")
			(net "ISENSE_PVCCIN_CPU0_PH5_IMON")
		)
		(pad "39" smd rect
			(at -1.999996 -2.895092 90)
			(size 0.254 0.7112)
			(layers "F.Cu" "F.Mask" "F.Paste")
			(net "VR_PVCCIN_CPU0_AIREF5")
		)
		(pad "40" smd rect
			(at -0.871728 -1.283208 90)
			(size 1.8034 2.0066)
			(layers "F.Cu" "F.Mask" "F.Paste")
			(net "GND")
		)
		(pad "41" smd rect
			(at -1.533906 0.247904 90)
			(size 0.508 0.3556)
			(layers "F.Cu" "F.Mask" "F.Paste")
			(net "TP_PVCCIN_CPU0_PH5_GL_1")
		)
	)
	(footprint ""
		(layer "F.Cu")
		(at 491.49 -39.0144 -90)
		(property "Reference" "R9F5"
			(at 0 0 270)
			(layer "F.SilkS")
			(hide yes)
			(effects
				(font
					(size 1.27 1.27)
				)
			)
		)
		(property "Value" ""
			(at 0 0 270)
			(layer "F.Fab")
			(effects
				(font
					(size 1.27 1.27)
				)
			)
		)
		(duplicate_pad_numbers_are_jumpers no)
		(fp_poly
			(pts
				(xy -0.2794 -0.1016) (xy 0.2794 -0.1016) (xy 0.2794 0.9906) (xy -0.2794 0.9906)
			)
			(stroke
				(width 0)
				(type default)
			)
			(fill no)
			(layer "F.CrtYd")
		)
		(fp_line
			(start -0.2794 0.9906)
			(end 0.2794 0.9906)
			(stroke
				(width 0.1)
				(type default)
			)
			(layer "F.Fab")
		)
		(fp_line
			(start 0.2794 0.9906)
			(end 0.2794 -0.1016)
			(stroke
				(width 0.1)
				(type default)
			)
			(layer "F.Fab")
		)
		(fp_line
			(start -0.2794 -0.1016)
			(end -0.2794 0.9906)
			(stroke
				(width 0.1)
				(type default)
			)
			(layer "F.Fab")
		)
		(fp_line
			(start 0.2794 -0.1016)
			(end -0.2794 -0.1016)
			(stroke
				(width 0.1)
				(type default)
			)
			(layer "F.Fab")
		)
		(pad "1" smd rect
			(at 0 0 270)
			(size 0.508 0.508)
			(layers "F.Cu" "F.Mask" "F.Paste")
			(net "P3V3_STBY")
		)
		(pad "2" smd rect
			(at 0 0.889 270)
			(size 0.508 0.508)
			(layers "F.Cu" "F.Mask" "F.Paste")
			(net "PU_SPRV_LAN_PWR_GOOD")
		)
		(zone
			(layer "F.Cu")
			(hatch none 0.5)
			(connect_pads
				(clearance 0)
			)
			(min_thickness 0.25)
			(keepout
				(tracks not_allowed)
				(vias allowed)
				(pads allowed)
				(copperpour not_allowed)
				(footprints allowed)
			)
			(placement
				(enabled no)
				(sheetname "")
			)
			(fill
				(thermal_gap 0.5)
				(thermal_bridge_width 0.5)
				(island_removal_mode 0)
			)
			(polygon
				(pts
					(xy 490.855 -39.2684) (xy 490.855 -38.7604) (xy 491.236 -38.7604) (xy 491.236 -39.2684)
				)
			)
		)
		(zone
			(layer "F.Cu")
			(hatch none 0.5)
			(connect_pads
				(clearance 0)
			)
			(min_thickness 0.25)
			(keepout
				(tracks allowed)
				(vias not_allowed)
				(pads allowed)
				(copperpour not_allowed)
				(footprints allowed)
			)
			(placement
				(enabled no)
				(sheetname "")
			)
			(fill
				(thermal_gap 0.5)
				(thermal_bridge_width 0.5)
				(island_removal_mode 0)
			)
			(polygon
				(pts
					(xy 491.236 -39.2684) (xy 491.236 -38.7604) (xy 490.855 -38.7604) (xy 490.855 -39.2684)
				)
			)
		)
	)
	(footprint ""
		(layer "F.Cu")
		(at 369.7224 -108.6104)
		(property "Reference" "R7C1"
			(at 0 0 0)
			(layer "F.SilkS")
			(hide yes)
			(effects
				(font
					(size 1.27 1.27)
				)
			)
		)
		(property "Value" ""
			(at 0 0 0)
			(layer "F.Fab")
			(effects
				(font
					(size 1.27 1.27)
				)
			)
		)
		(duplicate_pad_numbers_are_jumpers no)
		(fp_poly
			(pts
				(xy -0.4953 -0.2032) (xy 0.4953 -0.2032) (xy 0.4953 1.6002) (xy -0.4953 1.6002)
			)
			(stroke
				(width 0)
				(type default)
			)
			(fill no)
			(layer "F.CrtYd")
		)
		(fp_line
			(start -0.4953 -0.2032)
			(end 0.4953 -0.2032)
			(stroke
				(width 0.1)
				(type default)
			)
			(layer "F.Fab")
		)
		(fp_line
			(start -0.4953 1.6002)
			(end -0.4953 -0.2032)
			(stroke
				(width 0.1)
				(type default)
			)
			(layer "F.Fab")
		)
		(fp_line
			(start 0.4953 -0.2032)
			(end 0.4953 1.6002)
			(stroke
				(width 0.1)
				(type default)
			)
			(layer "F.Fab")
		)
		(fp_line
			(start 0.4953 1.6002)
			(end -0.4953 1.6002)
			(stroke
				(width 0.1)
				(type default)
			)
			(layer "F.Fab")
		)
		(pad "1" smd rect
			(at 0 0)
			(size 0.762 0.889)
			(layers "F.Cu" "F.Mask" "F.Paste")
			(net "XTAL_PCH_48M_IN")
		)
		(pad "2" smd rect
			(at 0 1.397)
			(size 0.762 0.889)
			(layers "F.Cu" "F.Mask" "F.Paste")
			(net "XTAL_PCH_48M_OUT")
		)
		(zone
			(layer "F.Cu")
			(hatch none 0.5)
			(connect_pads
				(clearance 0)
			)
			(min_thickness 0.25)
			(keepout
				(tracks not_allowed)
				(vias allowed)
				(pads allowed)
				(copperpour not_allowed)
				(footprints allowed)
			)
			(placement
				(enabled no)
				(sheetname "")
			)
			(fill
				(thermal_gap 0.5)
				(thermal_bridge_width 0.5)
				(island_removal_mode 0)
			)
			(polygon
				(pts
					(xy 369.3414 -107.6579) (xy 370.1034 -107.6579) (xy 370.1034 -108.1659) (xy 369.3414 -108.1659)
				)
			)
		)
		(zone
			(layer "F.Cu")
			(hatch none 0.5)
			(connect_pads
				(clearance 0)
			)
			(min_thickness 0.25)
			(keepout
				(tracks allowed)
				(vias not_allowed)
				(pads allowed)
				(copperpour not_allowed)
				(footprints allowed)
			)
			(placement
				(enabled no)
				(sheetname "")
			)
			(fill
				(thermal_gap 0.5)
				(thermal_bridge_width 0.5)
				(island_removal_mode 0)
			)
			(polygon
				(pts
					(xy 370.1034 -107.6579) (xy 370.1034 -108.1659) (xy 369.3414 -108.1659) (xy 369.3414 -107.6579)
				)
			)
		)
	)
	(footprint ""
		(layer "F.Cu")
		(at 394.462 -41.3766)
		(property "Reference" "R25W182"
			(at -0.8382 -0.67818 0)
			(unlocked yes)
			(layer "F.SilkS")
			(effects
				(font
					(size 0.4064 0.254)
					(thickness 0.1524)
				)
				(justify left)
			)
		)
		(property "Value" ""
			(at 0 0 0)
			(layer "F.Fab")
			(effects
				(font
					(size 1.27 1.27)
				)
			)
		)
		(duplicate_pad_numbers_are_jumpers no)
		(fp_poly
			(pts
				(xy -0.2794 -0.1016) (xy 0.2794 -0.1016) (xy 0.2794 0.9906) (xy -0.2794 0.9906)
			)
			(stroke
				(width 0)
				(type default)
			)
			(fill no)
			(layer "F.CrtYd")
		)
		(fp_line
			(start -0.2794 -0.1016)
			(end -0.2794 0.9906)
			(stroke
				(width 0.1)
				(type default)
			)
			(layer "F.Fab")
		)
		(fp_line
			(start -0.2794 0.9906)
			(end 0.2794 0.9906)
			(stroke
				(width 0.1)
				(type default)
			)
			(layer "F.Fab")
		)
		(fp_line
			(start 0.2794 -0.1016)
			(end -0.2794 -0.1016)
			(stroke
				(width 0.1)
				(type default)
			)
			(layer "F.Fab")
		)
		(fp_line
			(start 0.2794 0.9906)
			(end 0.2794 -0.1016)
			(stroke
				(width 0.1)
				(type default)
			)
			(layer "F.Fab")
		)
		(pad "1" smd rect
			(at 0 0)
			(size 0.508 0.508)
			(layers "F.Cu" "F.Mask" "F.Paste")
			(net "XDP_SYSPWROK")
		)
		(pad "2" smd rect
			(at 0 0.889)
			(size 0.508 0.508)
			(layers "F.Cu" "F.Mask" "F.Paste")
			(net "PWRGD_SYS_PWROK")
		)
		(zone
			(layer "F.Cu")
			(hatch none 0.5)
			(connect_pads
				(clearance 0)
			)
			(min_thickness 0.25)
			(keepout
				(tracks allowed)
				(vias not_allowed)
				(pads allowed)
				(copperpour not_allowed)
				(footprints allowed)
			)
			(placement
				(enabled no)
				(sheetname "")
			)
			(fill
				(thermal_gap 0.5)
				(thermal_bridge_width 0.5)
				(island_removal_mode 0)
			)
			(polygon
				(pts
					(xy 394.208 -41.1226) (xy 394.716 -41.1226) (xy 394.716 -40.7416) (xy 394.208 -40.7416)
				)
			)
		)
		(zone
			(layer "F.Cu")
			(hatch none 0.5)
			(connect_pads
				(clearance 0)
			)
			(min_thickness 0.25)
			(keepout
				(tracks not_allowed)
				(vias allowed)
				(pads allowed)
				(copperpour not_allowed)
				(footprints allowed)
			)
			(placement
				(enabled no)
				(sheetname "")
			)
			(fill
				(thermal_gap 0.5)
				(thermal_bridge_width 0.5)
				(island_removal_mode 0)
			)
			(polygon
				(pts
					(xy 394.208 -40.7416) (xy 394.716 -40.7416) (xy 394.716 -41.1226) (xy 394.208 -41.1226)
				)
			)
		)
	)
	(footprint ""
		(layer "F.Cu")
		(at 338.836 -15.494 -90)
		(property "Reference" "R7G4"
			(at 0 0 270)
			(layer "F.SilkS")
			(hide yes)
			(effects
				(font
					(size 1.27 1.27)
				)
			)
		)
		(property "Value" ""
			(at 0 0 270)
			(layer "F.Fab")
			(effects
				(font
					(size 1.27 1.27)
				)
			)
		)
		(duplicate_pad_numbers_are_jumpers no)
		(fp_rect
			(start 0.2794 0.9906)
			(end -0.2794 -0.1016)
			(stroke
				(width 0)
				(type default)
			)
			(fill no)
			(layer "F.CrtYd")
		)
		(fp_line
			(start -0.2794 0.9906)
			(end 0.2794 0.9906)
			(stroke
				(width 0.1)
				(type default)
			)
			(layer "F.Fab")
		)
		(fp_line
			(start 0.2794 0.9906)
			(end 0.2794 -0.1016)
			(stroke
				(width 0.1)
				(type default)
			)
			(layer "F.Fab")
		)
		(fp_line
			(start -0.2794 -0.1016)
			(end -0.2794 0.9906)
			(stroke
				(width 0.1)
				(type default)
			)
			(layer "F.Fab")
		)
		(fp_line
			(start 0.2794 -0.1016)
			(end -0.2794 -0.1016)
			(stroke
				(width 0.1)
				(type default)
			)
			(layer "F.Fab")
		)
		(pad "1" smd rect
			(at 0 0 270)
			(size 0.508 0.508)
			(layers "F.Cu" "F.Mask" "F.Paste")
			(net "SVID_ALERT_PVDDQ_ABC")
		)
		(pad "2" smd rect
			(at 0 0.889 270)
			(size 0.508 0.508)
			(layers "F.Cu" "F.Mask" "F.Paste")
			(net "SVID_ALERT1_CPU0_R_N")
		)
		(zone
			(layer "F.Cu")
			(hatch none 0.5)
			(connect_pads
				(clearance 0)
			)
			(min_thickness 0.25)
			(keepout
				(tracks not_allowed)
				(vias allowed)
				(pads allowed)
				(copperpour not_allowed)
				(footprints allowed)
			)
			(placement
				(enabled no)
				(sheetname "")
			)
			(fill
				(thermal_gap 0.5)
				(thermal_bridge_width 0.5)
				(island_removal_mode 0)
			)
			(polygon
				(pts
					(xy 338.201 -15.24) (xy 338.582 -15.24) (xy 338.582 -15.748) (xy 338.201 -15.748)
				)
			)
		)
		(zone
			(layer "F.Cu")
			(hatch none 0.5)
			(connect_pads
				(clearance 0)
			)
			(min_thickness 0.25)
			(keepout
				(tracks allowed)
				(vias not_allowed)
				(pads allowed)
				(copperpour not_allowed)
				(footprints allowed)
			)
			(placement
				(enabled no)
				(sheetname "")
			)
			(fill
				(thermal_gap 0.5)
				(thermal_bridge_width 0.5)
				(island_removal_mode 0)
			)
			(polygon
				(pts
					(xy 338.201 -15.24) (xy 338.582 -15.24) (xy 338.582 -15.748) (xy 338.201 -15.748)
				)
			)
		)
	)
	(footprint ""
		(layer "F.Cu")
		(at 85.777578 -75.65009 180)
		(property "Reference" "XLU2"
			(at 22.150578 34.43224 0)
			(unlocked yes)
			(layer "F.SilkS")
			(effects
				(font
					(size 0.7874 0.5842)
					(thickness 0.1524)
				)
				(justify left)
			)
		)
		(property "Value" ""
			(at 0 0 180)
			(layer "F.Fab")
			(effects
				(font
					(size 1.27 1.27)
				)
			)
		)
		(duplicate_pad_numbers_are_jumpers no)
		(fp_line
			(start 21.77796 31.949898)
			(end 21.77796 8.899906)
			(stroke
				(width 0.1524)
				(type default)
			)
			(layer "F.SilkS")
		)
		(fp_line
			(start 21.77796 8.899906)
			(end 18.278094 5.40004)
			(stroke
				(width 0.1524)
				(type default)
			)
			(layer "F.SilkS")
		)
		(fp_line
			(start 21.77796 -7.100062)
			(end 21.77796 -30.150054)
			(stroke
				(width 0.1524)
				(type default)
			)
			(layer "F.SilkS")
		)
		(fp_line
			(start 21.77796 -30.150054)
			(end 14.777974 -30.150054)
			(stroke
				(width 0.1524)
				(type default)
			)
			(layer "F.SilkS")
		)
		(fp_line
			(start 18.278094 5.40004)
			(end 18.278094 3.899916)
			(stroke
				(width 0.1524)
				(type default)
			)
			(layer "F.SilkS")
		)
		(fp_line
			(start 18.278094 3.899916)
			(end 17.777968 3.899916)
			(stroke
				(width 0.1524)
				(type default)
			)
			(layer "F.SilkS")
		)
		(fp_line
			(start 18.278094 -2.100072)
			(end 18.278094 -3.599942)
			(stroke
				(width 0.1524)
				(type default)
			)
			(layer "F.SilkS")
		)
		(fp_line
			(start 18.278094 -3.599942)
			(end 21.77796 -7.100062)
			(stroke
				(width 0.1524)
				(type default)
			)
			(layer "F.SilkS")
		)
		(fp_line
			(start 17.777968 3.899916)
			(end 17.777968 -2.100072)
			(stroke
				(width 0.1524)
				(type default)
			)
			(layer "F.SilkS")
		)
		(fp_line
			(start 17.777968 -2.100072)
			(end 18.278094 -2.100072)
			(stroke
				(width 0.1524)
				(type default)
			)
			(layer "F.SilkS")
		)
		(fp_line
			(start 14.777974 31.949898)
			(end 21.77796 31.949898)
			(stroke
				(width 0.1524)
				(type default)
			)
			(layer "F.SilkS")
		)
		(fp_line
			(start 14.777974 29.399992)
			(end 14.777974 31.949898)
			(stroke
				(width 0.1524)
				(type default)
			)
			(layer "F.SilkS")
		)
		(fp_line
			(start 14.777974 -27.599894)
			(end -17.622012 -27.599894)
			(stroke
				(width 0.1524)
				(type default)
			)
			(layer "F.SilkS")
		)
		(fp_line
			(start 14.777974 -30.150054)
			(end 14.777974 -27.599894)
			(stroke
				(width 0.1524)
				(type default)
			)
			(layer "F.SilkS")
		)
		(fp_line
			(start -6.171946 6.690106)
			(end -12.761976 10.649966)
			(stroke
				(width 0.1524)
				(type default)
			)
			(layer "F.SilkS")
		)
		(fp_line
			(start -6.171946 -4.890008)
			(end -6.171946 6.690106)
			(stroke
				(width 0.1524)
				(type default)
			)
			(layer "F.SilkS")
		)
		(fp_line
			(start -12.761976 10.649966)
			(end -19.221958 10.649966)
			(stroke
				(width 0.1524)
				(type default)
			)
			(layer "F.SilkS")
		)
		(fp_line
			(start -12.761976 -8.850122)
			(end -6.171946 -4.890008)
			(stroke
				(width 0.1524)
				(type default)
			)
			(layer "F.SilkS")
		)
		(fp_line
			(start -17.622012 30.39999)
			(end -17.622012 29.399992)
			(stroke
				(width 0.1524)
				(type default)
			)
			(layer "F.SilkS")
		)
		(fp_line
			(start -17.622012 29.399992)
			(end 14.777974 29.399992)
			(stroke
				(width 0.1524)
				(type default)
			)
			(layer "F.SilkS")
		)
		(fp_line
			(start -17.622012 -27.599894)
			(end -17.622012 -28.599892)
			(stroke
				(width 0.1524)
				(type default)
			)
			(layer "F.SilkS")
		)
		(fp_line
			(start -17.622012 -28.599892)
			(end -18.62201 -28.599892)
			(stroke
				(width 0.1524)
				(type default)
			)
			(layer "F.SilkS")
		)
		(fp_line
			(start -18.62201 30.39999)
			(end -17.622012 30.39999)
			(stroke
				(width 0.1524)
				(type default)
			)
			(layer "F.SilkS")
		)
		(fp_line
			(start -18.62201 29.399992)
			(end -18.62201 30.39999)
			(stroke
				(width 0.1524)
				(type default)
			)
			(layer "F.SilkS")
		)
		(fp_line
			(start -18.62201 -8.850122)
			(end -12.761976 -8.850122)
			(stroke
				(width 0.1524)
				(type default)
			)
			(layer "F.SilkS")
		)
		(fp_line
			(start -18.62201 -28.599892)
			(end -18.62201 -8.850122)
			(stroke
				(width 0.1524)
				(type default)
			)
			(layer "F.SilkS")
		)
		(fp_line
			(start -19.221958 29.399992)
			(end -18.62201 29.399992)
			(stroke
				(width 0.1524)
				(type default)
			)
			(layer "F.SilkS")
		)
		(fp_line
			(start -19.221958 10.649966)
			(end -19.221958 29.399992)
			(stroke
				(width 0.1524)
				(type default)
			)
			(layer "F.SilkS")
		)
		(fp_poly
			(pts
				(xy 19.777964 -5.100066) (xy 19.777964 -22.649942) (xy 18.839434 -22.649942) (xy 18.839434 -27.410918)
				(xy 14.777974 -27.410918) (xy 14.777974 -30.150054) (xy 21.77796 -30.150054) (xy 21.77796 -7.100062)
			)
			(stroke
				(width 0)
				(type default)
			)
			(fill no)
			(layer "F.CrtYd")
		)
		(fp_poly
			(pts
				(arc
					(start 19.777964 17.616678)
					(mid 20.051978 16.900049)
					(end 19.777964 16.183356)
				)
				(xy 19.777964 6.89991) (xy 21.77796 8.899906) (xy 21.77796 31.949898) (xy 14.777974 31.949898) (xy 14.777974 29.211016)
				(xy 18.839434 29.211016) (xy 18.839434 24.449786) (xy 19.777964 24.449786)
			)
			(stroke
				(width 0)
				(type default)
			)
			(fill no)
			(layer "F.CrtYd")
		)
		(fp_line
			(start 21.77796 31.949898)
			(end 14.777974 31.949898)
			(stroke
				(width 0.1)
				(type default)
			)
			(layer "F.Fab")
		)
		(fp_line
			(start 21.77796 8.899906)
			(end 21.77796 31.949898)
			(stroke
				(width 0.1)
				(type default)
			)
			(layer "F.Fab")
		)
		(fp_line
			(start 21.77796 -7.100062)
			(end 19.777964 -5.100066)
			(stroke
				(width 0.1)
				(type default)
			)
			(layer "F.Fab")
		)
		(fp_line
			(start 21.77796 -30.150054)
			(end 21.77796 -7.100062)
			(stroke
				(width 0.1)
				(type default)
			)
			(layer "F.Fab")
		)
		(fp_line
			(start 19.777964 24.449786)
			(end 19.777964 22.078696)
			(stroke
				(width 0.1)
				(type default)
			)
			(layer "F.Fab")
		)
		(fp_line
			(start 19.777964 21.179028)
			(end 19.777964 17.616678)
			(stroke
				(width 0.1)
				(type default)
			)
			(layer "F.Fab")
		)
		(fp_line
			(start 19.777964 16.183356)
			(end 19.777964 6.89991)
			(stroke
				(width 0.1)
				(type default)
			)
			(layer "F.Fab")
		)
		(fp_line
			(start 19.777964 6.89991)
			(end 21.77796 8.899906)
			(stroke
				(width 0.1)
				(type default)
			)
			(layer "F.Fab")
		)
		(fp_line
			(start 19.777964 -5.100066)
			(end 19.777964 -22.649942)
			(stroke
				(width 0.1)
				(type default)
			)
			(layer "F.Fab")
		)
		(fp_line
			(start 19.777964 -22.649942)
			(end 18.839434 -22.649942)
			(stroke
				(width 0.1)
				(type default)
			)
			(layer "F.Fab")
		)
		(fp_line
			(start 18.839434 29.211016)
			(end 18.839434 24.449786)
			(stroke
				(width 0.1)
				(type default)
			)
			(layer "F.Fab")
		)
		(fp_line
			(start 18.839434 24.449786)
			(end 19.777964 24.449786)
			(stroke
				(width 0.1)
				(type default)
			)
			(layer "F.Fab")
		)
		(fp_line
			(start 18.839434 -22.649942)
			(end 18.839434 -27.410918)
			(stroke
				(width 0.1)
				(type default)
			)
			(layer "F.Fab")
		)
		(fp_line
			(start 18.839434 -27.410918)
			(end 14.777974 -27.410918)
			(stroke
				(width 0.1)
				(type default)
			)
			(layer "F.Fab")
		)
		(fp_line
			(start 14.777974 31.949898)
			(end 14.777974 29.211016)
			(stroke
				(width 0.1)
				(type default)
			)
			(layer "F.Fab")
		)
		(fp_line
			(start 14.777974 29.211016)
			(end 18.839434 29.211016)
			(stroke
				(width 0.1)
				(type default)
			)
			(layer "F.Fab")
		)
		(fp_line
			(start 14.777974 -27.410918)
			(end 14.777974 -30.150054)
			(stroke
				(width 0.1)
				(type default)
			)
			(layer "F.Fab")
		)
		(fp_line
			(start 14.777974 -30.150054)
			(end 21.77796 -30.150054)
			(stroke
				(width 0.1)
				(type default)
			)
			(layer "F.Fab")
		)
		(fp_arc
			(start 19.777964 22.078696)
			(mid 19.777668 21.628862)
			(end 19.777964 21.179028)
			(stroke
				(width 0.1)
				(type default)
			)
			(layer "F.Fab")
		)
		(fp_arc
			(start 19.777964 16.183356)
			(mid 20.051971 16.900015)
			(end 19.777964 17.616678)
			(stroke
				(width 0.1)
				(type default)
			)
			(layer "F.Fab")
		)
	)
	(footprint ""
		(layer "F.Cu")
		(at 21.80971 -119.62765 -90)
		(property "Reference" "CR1B2"
			(at 2.58699 1.60528 0)
			(unlocked yes)
			(layer "F.SilkS")
			(effects
				(font
					(size 0.7874 0.5842)
					(thickness 0.1524)
				)
				(justify left)
			)
		)
		(property "Value" ""
			(at 0 0 270)
			(layer "F.Fab")
			(effects
				(font
					(size 1.27 1.27)
				)
			)
		)
		(duplicate_pad_numbers_are_jumpers no)
		(fp_line
			(start -0.931418 2.543048)
			(end -0.931418 1.631442)
			(stroke
				(width 0.1524)
				(type default)
			)
			(layer "F.SilkS")
		)
		(fp_line
			(start -1.41224 1.631442)
			(end -0.931418 0.798576)
			(stroke
				(width 0.1524)
				(type default)
			)
			(layer "F.SilkS")
		)
		(fp_line
			(start -0.931418 1.631442)
			(end -1.41224 1.631442)
			(stroke
				(width 0.1524)
				(type default)
			)
			(layer "F.SilkS")
		)
		(fp_line
			(start -0.450596 1.631442)
			(end -0.931418 1.631442)
			(stroke
				(width 0.1524)
				(type default)
			)
			(layer "F.SilkS")
		)
		(fp_line
			(start -0.931418 0.798576)
			(end -0.450596 1.631442)
			(stroke
				(width 0.1524)
				(type default)
			)
			(layer "F.SilkS")
		)
		(fp_line
			(start -0.450596 0.798576)
			(end -1.41224 0.798576)
			(stroke
				(width 0.1524)
				(type default)
			)
			(layer "F.SilkS")
		)
		(fp_line
			(start -0.931418 -0.324866)
			(end -0.931418 0.798576)
			(stroke
				(width 0.1524)
				(type default)
			)
			(layer "F.SilkS")
		)
		(fp_rect
			(start 0.67437 2.04216)
			(end -0.67437 0.24384)
			(stroke
				(width 0)
				(type default)
			)
			(fill no)
			(layer "F.CrtYd")
		)
		(fp_line
			(start -0.67437 2.04216)
			(end 0.67437 2.04216)
			(stroke
				(width 0.1)
				(type default)
			)
			(layer "F.Fab")
		)
		(fp_line
			(start 0.67437 2.04216)
			(end 0.67437 0.24384)
			(stroke
				(width 0.1)
				(type default)
			)
			(layer "F.Fab")
		)
		(fp_line
			(start -1.412748 1.621536)
			(end -0.931926 0.78867)
			(stroke
				(width 0.1)
				(type default)
			)
			(layer "F.Fab")
		)
		(fp_line
			(start -0.931926 1.621536)
			(end -0.931926 2.533142)
			(stroke
				(width 0.1)
				(type default)
			)
			(layer "F.Fab")
		)
		(fp_line
			(start -0.451104 1.621536)
			(end -1.412748 1.621536)
			(stroke
				(width 0.1)
				(type default)
			)
			(layer "F.Fab")
		)
		(fp_line
			(start -0.931926 0.78867)
			(end -0.451104 1.621536)
			(stroke
				(width 0.1)
				(type default)
			)
			(layer "F.Fab")
		)
		(fp_line
			(start -0.931926 0.78867)
			(end -0.931926 -0.334772)
			(stroke
				(width 0.1)
				(type default)
			)
			(layer "F.Fab")
		)
		(fp_line
			(start -0.451104 0.78867)
			(end -1.412748 0.78867)
			(stroke
				(width 0.1)
				(type default)
			)
			(layer "F.Fab")
		)
		(fp_line
			(start -0.67437 0.24384)
			(end -0.67437 2.04216)
			(stroke
				(width 0.1)
				(type default)
			)
			(layer "F.Fab")
		)
		(fp_line
			(start 0.67437 0.24384)
			(end -0.67437 0.24384)
			(stroke
				(width 0.1)
				(type default)
			)
			(layer "F.Fab")
		)
		(pad "1" smd rect
			(at 0 0 270)
			(size 0.4064 1.016)
			(layers "F.Cu" "F.Mask" "F.Paste")
			(net "FAN_TACH2_CPU1_D1")
		)
		(pad "2" smd rect
			(at 0 2.286 270)
			(size 0.4064 1.016)
			(layers "F.Cu" "F.Mask" "F.Paste")
			(net "FAN_TACH2_CPU1_D2")
		)
	)
	(footprint ""
		(layer "F.Cu")
		(at 173.6217 -128.9558 180)
		(property "Reference" "R4B14"
			(at 0 0 180)
			(layer "F.SilkS")
			(hide yes)
			(effects
				(font
					(size 1.27 1.27)
				)
			)
		)
		(property "Value" ""
			(at 0 0 180)
			(layer "F.Fab")
			(effects
				(font
					(size 1.27 1.27)
				)
			)
		)
		(duplicate_pad_numbers_are_jumpers no)
		(fp_rect
			(start -0.2794 0.9906)
			(end 0.2794 -0.1016)
			(stroke
				(width 0)
				(type default)
			)
			(fill no)
			(layer "F.CrtYd")
		)
		(fp_line
			(start 0.2794 0.9906)
			(end 0.2794 -0.1016)
			(stroke
				(width 0.1)
				(type default)
			)
			(layer "F.Fab")
		)
		(fp_line
			(start 0.2794 -0.1016)
			(end -0.2794 -0.1016)
			(stroke
				(width 0.1)
				(type default)
			)
			(layer "F.Fab")
		)
		(fp_line
			(start -0.2794 0.9906)
			(end 0.2794 0.9906)
			(stroke
				(width 0.1)
				(type default)
			)
			(layer "F.Fab")
		)
		(fp_line
			(start -0.2794 -0.1016)
			(end -0.2794 0.9906)
			(stroke
				(width 0.1)
				(type default)
			)
			(layer "F.Fab")
		)
		(pad "1" smd rect
			(at 0 0 180)
			(size 0.508 0.508)
			(layers "F.Cu" "F.Mask" "F.Paste")
			(net "GND")
		)
		(pad "2" smd rect
			(at 0 0.889 180)
			(size 0.508 0.508)
			(layers "F.Cu" "F.Mask" "F.Paste")
			(net "AGND_PVPP_KLM")
		)
		(zone
			(layer "F.Cu")
			(hatch none 0.5)
			(connect_pads
				(clearance 0)
			)
			(min_thickness 0.25)
			(keepout
				(tracks allowed)
				(vias not_allowed)
				(pads allowed)
				(copperpour not_allowed)
				(footprints allowed)
			)
			(placement
				(enabled no)
				(sheetname "")
			)
			(fill
				(thermal_gap 0.5)
				(thermal_bridge_width 0.5)
				(island_removal_mode 0)
			)
			(polygon
				(pts
					(xy 173.8757 -129.5908) (xy 173.3677 -129.5908) (xy 173.3677 -129.2098) (xy 173.8757 -129.2098)
				)
			)
		)
		(zone
			(layer "F.Cu")
			(hatch none 0.5)
			(connect_pads
				(clearance 0)
			)
			(min_thickness 0.25)
			(keepout
				(tracks not_allowed)
				(vias allowed)
				(pads allowed)
				(copperpour not_allowed)
				(footprints allowed)
			)
			(placement
				(enabled no)
				(sheetname "")
			)
			(fill
				(thermal_gap 0.5)
				(thermal_bridge_width 0.5)
				(island_removal_mode 0)
			)
			(polygon
				(pts
					(xy 173.8757 -129.5908) (xy 173.3677 -129.5908) (xy 173.3677 -129.2098) (xy 173.8757 -129.2098)
				)
			)
		)
	)
	(footprint ""
		(layer "F.Cu")
		(at 376.682 -87.3125 180)
		(property "Reference" "R2T1"
			(at -0.8382 -0.67818 180)
			(unlocked yes)
			(layer "F.SilkS")
			(effects
				(font
					(size 0.4064 0.254)
					(thickness 0.1524)
				)
				(justify left)
			)
		)
		(property "Value" ""
			(at 0 0 180)
			(layer "F.Fab")
			(effects
				(font
					(size 1.27 1.27)
				)
			)
		)
		(duplicate_pad_numbers_are_jumpers no)
		(fp_poly
			(pts
				(xy -0.2794 -0.1016) (xy 0.2794 -0.1016) (xy 0.2794 0.9906) (xy -0.2794 0.9906)
			)
			(stroke
				(width 0)
				(type default)
			)
			(fill no)
			(layer "F.CrtYd")
		)
		(fp_line
			(start 0.2794 0.9906)
			(end 0.2794 -0.1016)
			(stroke
				(width 0.1)
				(type default)
			)
			(layer "F.Fab")
		)
		(fp_line
			(start 0.2794 -0.1016)
			(end -0.2794 -0.1016)
			(stroke
				(width 0.1)
				(type default)
			)
			(layer "F.Fab")
		)
		(fp_line
			(start -0.2794 0.9906)
			(end 0.2794 0.9906)
			(stroke
				(width 0.1)
				(type default)
			)
			(layer "F.Fab")
		)
		(fp_line
			(start -0.2794 -0.1016)
			(end -0.2794 0.9906)
			(stroke
				(width 0.1)
				(type default)
			)
			(layer "F.Fab")
		)
		(pad "1" smd rect
			(at 0 0 180)
			(size 0.508 0.508)
			(layers "F.Cu" "F.Mask" "F.Paste")
			(net "SPI_PCH_IO3")
		)
		(pad "2" smd rect
			(at 0 0.889 180)
			(size 0.508 0.508)
			(layers "F.Cu" "F.Mask" "F.Paste")
			(net "GND")
		)
		(zone
			(layer "F.Cu")
			(hatch none 0.5)
			(connect_pads
				(clearance 0)
			)
			(min_thickness 0.25)
			(keepout
				(tracks not_allowed)
				(vias allowed)
				(pads allowed)
				(copperpour not_allowed)
				(footprints allowed)
			)
			(placement
				(enabled no)
				(sheetname "")
			)
			(fill
				(thermal_gap 0.5)
				(thermal_bridge_width 0.5)
				(island_removal_mode 0)
			)
			(polygon
				(pts
					(xy 376.936 -87.9475) (xy 376.428 -87.9475) (xy 376.428 -87.5665) (xy 376.936 -87.5665)
				)
			)
		)
		(zone
			(layer "F.Cu")
			(hatch none 0.5)
			(connect_pads
				(clearance 0)
			)
			(min_thickness 0.25)
			(keepout
				(tracks allowed)
				(vias not_allowed)
				(pads allowed)
				(copperpour not_allowed)
				(footprints allowed)
			)
			(placement
				(enabled no)
				(sheetname "")
			)
			(fill
				(thermal_gap 0.5)
				(thermal_bridge_width 0.5)
				(island_removal_mode 0)
			)
			(polygon
				(pts
					(xy 376.936 -87.5665) (xy 376.428 -87.5665) (xy 376.428 -87.9475) (xy 376.936 -87.9475)
				)
			)
		)
	)
	(footprint ""
		(layer "F.Cu")
		(at 204.649832 -93.36024 -90)
		(property "Reference" "CT59"
			(at -0.8382 -0.67818 270)
			(unlocked yes)
			(layer "F.SilkS")
			(effects
				(font
					(size 0.4064 0.254)
					(thickness 0.1524)
				)
				(justify left)
			)
		)
		(property "Value" ""
			(at 0 0 270)
			(layer "F.Fab")
			(effects
				(font
					(size 1.27 1.27)
				)
			)
		)
		(duplicate_pad_numbers_are_jumpers no)
		(fp_poly
			(pts
				(xy 0.3048 -0.1016) (xy 0.3048 0.9906) (xy -0.3048 0.9906) (xy -0.3048 -0.1016)
			)
			(stroke
				(width 0)
				(type default)
			)
			(fill no)
			(layer "F.CrtYd")
		)
		(fp_line
			(start -0.3048 0.9906)
			(end 0.3048 0.9906)
			(stroke
				(width 0.1)
				(type default)
			)
			(layer "F.Fab")
		)
		(fp_line
			(start 0.3048 0.9906)
			(end 0.3048 -0.1016)
			(stroke
				(width 0.1)
				(type default)
			)
			(layer "F.Fab")
		)
		(fp_line
			(start -0.3048 -0.1016)
			(end -0.3048 0.9906)
			(stroke
				(width 0.1)
				(type default)
			)
			(layer "F.Fab")
		)
		(fp_line
			(start 0.3048 -0.1016)
			(end -0.3048 -0.1016)
			(stroke
				(width 0.1)
				(type default)
			)
			(layer "F.Fab")
		)
		(pad "1" smd rect
			(at 0 0 270)
			(size 0.508 0.508)
			(layers "F.Cu" "F.Mask" "F.Paste")
			(net "VR_PVSA_CPU0_PHASE_SW")
		)
		(pad "2" smd rect
			(at 0 0.889 270)
			(size 0.508 0.508)
			(layers "F.Cu" "F.Mask" "F.Paste")
			(net "VR_PVSA_CPU0_PHASE_SW_RC")
		)
		(zone
			(layer "F.Cu")
			(hatch none 0.5)
			(connect_pads
				(clearance 0)
			)
			(min_thickness 0.25)
			(keepout
				(tracks not_allowed)
				(vias allowed)
				(pads allowed)
				(copperpour not_allowed)
				(footprints allowed)
			)
			(placement
				(enabled no)
				(sheetname "")
			)
			(fill
				(thermal_gap 0.5)
				(thermal_bridge_width 0.5)
				(island_removal_mode 0)
			)
			(polygon
				(pts
					(xy 204.014832 -93.61424) (xy 204.014832 -93.10624) (xy 204.395832 -93.10624) (xy 204.395832 -93.61424)
				)
			)
		)
		(zone
			(layer "F.Cu")
			(hatch none 0.5)
			(connect_pads
				(clearance 0)
			)
			(min_thickness 0.25)
			(keepout
				(tracks allowed)
				(vias not_allowed)
				(pads allowed)
				(copperpour not_allowed)
				(footprints allowed)
			)
			(placement
				(enabled no)
				(sheetname "")
			)
			(fill
				(thermal_gap 0.5)
				(thermal_bridge_width 0.5)
				(island_removal_mode 0)
			)
			(polygon
				(pts
					(xy 204.395832 -93.61424) (xy 204.395832 -93.10624) (xy 204.014832 -93.10624) (xy 204.014832 -93.61424)
				)
			)
		)
	)
	(footprint ""
		(layer "F.Cu")
		(at 366.154716 -147.914106)
		(property "Reference" "C7W5"
			(at 0 0 0)
			(layer "F.SilkS")
			(hide yes)
			(effects
				(font
					(size 1.27 1.27)
				)
			)
		)
		(property "Value" "*"
			(at -0.0762 -6.2357 0)
			(unlocked yes)
			(layer "F.Fab")
			(hide yes)
			(effects
				(font
					(size 1.27 1.016)
					(thickness 0.1524)
				)
			)
		)
		(property "Device Type" "SC22U16V5MX-4-GP_SMD-BCG5-SC22A"
			(at -0.0762 -8.2677 0)
			(unlocked yes)
			(layer "F.Fab")
			(hide yes)
			(effects
				(font
					(size 1.27 1.016)
					(thickness 0.1524)
				)
			)
		)
		(duplicate_pad_numbers_are_jumpers no)
		(fp_line
			(start 0.635 0)
			(end -0.635 0)
			(stroke
				(width 0.508)
				(type default)
			)
			(layer "F.SilkS")
		)
		(fp_rect
			(start -0.9652 1.778)
			(end 0.9652 -1.778)
			(stroke
				(width 0)
				(type default)
			)
			(fill no)
			(layer "F.CrtYd")
		)
		(fp_poly
			(pts
				(xy -0.9652 -1.778) (xy 0.9652 -1.778) (xy 0.9652 1.778) (xy -0.9652 1.778)
			)
			(stroke
				(width 0)
				(type default)
			)
			(fill no)
			(layer "F.Fab")
		)
		(pad "1" smd rect
			(at 0 -0.9652)
			(size 1.397 1.143)
			(layers "F.Cu" "F.Mask" "F.Paste")
			(net "VR_FET_SW_P12V_STBY_PVDDQ_DEF")
		)
		(pad "2" smd rect
			(at 0 0.9652)
			(size 1.397 1.143)
			(layers "F.Cu" "F.Mask" "F.Paste")
			(net "GND")
		)
	)
	(footprint ""
		(layer "F.Cu")
		(at 466.476842 -25.77846 -90)
		(property "Reference" "R8E34"
			(at 0 0 270)
			(layer "F.SilkS")
			(hide yes)
			(effects
				(font
					(size 1.27 1.27)
				)
			)
		)
		(property "Value" ""
			(at 0 0 270)
			(layer "F.Fab")
			(effects
				(font
					(size 1.27 1.27)
				)
			)
		)
		(duplicate_pad_numbers_are_jumpers no)
		(fp_rect
			(start 0.2794 -0.1016)
			(end -0.2794 0.9906)
			(stroke
				(width 0)
				(type default)
			)
			(fill no)
			(layer "F.CrtYd")
		)
		(fp_line
			(start -0.2794 0.9906)
			(end 0.2794 0.9906)
			(stroke
				(width 0.1)
				(type default)
			)
			(layer "F.Fab")
		)
		(fp_line
			(start 0.2794 0.9906)
			(end 0.2794 -0.1016)
			(stroke
				(width 0.1)
				(type default)
			)
			(layer "F.Fab")
		)
		(fp_line
			(start -0.2794 -0.1016)
			(end -0.2794 0.9906)
			(stroke
				(width 0.1)
				(type default)
			)
			(layer "F.Fab")
		)
		(fp_line
			(start 0.2794 -0.1016)
			(end -0.2794 -0.1016)
			(stroke
				(width 0.1)
				(type default)
			)
			(layer "F.Fab")
		)
		(pad "1" smd rect
			(at 0 0 270)
			(size 0.508 0.508)
			(layers "F.Cu" "F.Mask" "F.Paste")
			(net "VSENSE_VOUT_P3V3_STBY")
		)
		(pad "2" smd rect
			(at 0 0.889 270)
			(size 0.508 0.508)
			(layers "F.Cu" "F.Mask" "F.Paste")
			(net "AGND_P3V3_STBY")
		)
		(zone
			(layer "F.Cu")
			(hatch none 0.5)
			(connect_pads
				(clearance 0)
			)
			(min_thickness 0.25)
			(keepout
				(tracks not_allowed)
				(vias allowed)
				(pads allowed)
				(copperpour not_allowed)
				(footprints allowed)
			)
			(placement
				(enabled no)
				(sheetname "")
			)
			(fill
				(thermal_gap 0.5)
				(thermal_bridge_width 0.5)
				(island_removal_mode 0)
			)
			(polygon
				(pts
					(xy 466.222842 -25.52446) (xy 466.222842 -26.03246) (xy 465.841842 -26.03246) (xy 465.841842 -25.52446)
				)
			)
		)
		(zone
			(layer "F.Cu")
			(hatch none 0.5)
			(connect_pads
				(clearance 0)
			)
			(min_thickness 0.25)
			(keepout
				(tracks allowed)
				(vias not_allowed)
				(pads allowed)
				(copperpour not_allowed)
				(footprints allowed)
			)
			(placement
				(enabled no)
				(sheetname "")
			)
			(fill
				(thermal_gap 0.5)
				(thermal_bridge_width 0.5)
				(island_removal_mode 0)
			)
			(polygon
				(pts
					(xy 466.222842 -25.52446) (xy 466.222842 -26.03246) (xy 465.841842 -26.03246) (xy 465.841842 -25.52446)
				)
			)
		)
	)
	(footprint ""
		(layer "F.Cu")
		(at 389.60679 -157.493462 -90)
		(property "Reference" "C7A44"
			(at 0 0 270)
			(layer "F.SilkS")
			(hide yes)
			(effects
				(font
					(size 1.27 1.27)
				)
			)
		)
		(property "Value" ""
			(at 0 0 270)
			(layer "F.Fab")
			(effects
				(font
					(size 1.27 1.27)
				)
			)
		)
		(duplicate_pad_numbers_are_jumpers no)
		(fp_poly
			(pts
				(xy 0.3048 -0.1016) (xy 0.3048 0.9906) (xy -0.3048 0.9906) (xy -0.3048 -0.1016)
			)
			(stroke
				(width 0)
				(type default)
			)
			(fill no)
			(layer "F.CrtYd")
		)
		(fp_line
			(start -0.3048 0.9906)
			(end 0.3048 0.9906)
			(stroke
				(width 0.1)
				(type default)
			)
			(layer "F.Fab")
		)
		(fp_line
			(start 0.3048 0.9906)
			(end 0.3048 -0.1016)
			(stroke
				(width 0.1)
				(type default)
			)
			(layer "F.Fab")
		)
		(fp_line
			(start -0.3048 -0.1016)
			(end -0.3048 0.9906)
			(stroke
				(width 0.1)
				(type default)
			)
			(layer "F.Fab")
		)
		(fp_line
			(start 0.3048 -0.1016)
			(end -0.3048 -0.1016)
			(stroke
				(width 0.1)
				(type default)
			)
			(layer "F.Fab")
		)
		(pad "1" smd rect
			(at 0 0 270)
			(size 0.508 0.508)
			(layers "F.Cu" "F.Mask" "F.Paste")
			(net "VR_P1V05_PCH_STBY_PH1_BOOT")
		)
		(pad "2" smd rect
			(at 0 0.889 270)
			(size 0.508 0.508)
			(layers "F.Cu" "F.Mask" "F.Paste")
			(net "VR_P1V05_PCH_STBY_PH1_PHASE")
		)
		(zone
			(layer "F.Cu")
			(hatch none 0.5)
			(connect_pads
				(clearance 0)
			)
			(min_thickness 0.25)
			(keepout
				(tracks not_allowed)
				(vias allowed)
				(pads allowed)
				(copperpour not_allowed)
				(footprints allowed)
			)
			(placement
				(enabled no)
				(sheetname "")
			)
			(fill
				(thermal_gap 0.5)
				(thermal_bridge_width 0.5)
				(island_removal_mode 0)
			)
			(polygon
				(pts
					(xy 388.97179 -157.747462) (xy 388.97179 -157.239462) (xy 389.35279 -157.239462) (xy 389.35279 -157.747462)
				)
			)
		)
		(zone
			(layer "F.Cu")
			(hatch none 0.5)
			(connect_pads
				(clearance 0)
			)
			(min_thickness 0.25)
			(keepout
				(tracks allowed)
				(vias not_allowed)
				(pads allowed)
				(copperpour not_allowed)
				(footprints allowed)
			)
			(placement
				(enabled no)
				(sheetname "")
			)
			(fill
				(thermal_gap 0.5)
				(thermal_bridge_width 0.5)
				(island_removal_mode 0)
			)
			(polygon
				(pts
					(xy 389.35279 -157.747462) (xy 389.35279 -157.239462) (xy 388.97179 -157.239462) (xy 388.97179 -157.747462)
				)
			)
		)
	)
	(footprint ""
		(layer "F.Cu")
		(at 418.973 -83.580986)
		(property "Reference" "U8D5"
			(at 3.27025 2.02692 90)
			(unlocked yes)
			(layer "F.SilkS")
			(effects
				(font
					(size 0.7874 0.5842)
					(thickness 0.1524)
				)
				(justify left)
			)
		)
		(property "Value" ""
			(at 0 0 0)
			(layer "F.Fab")
			(effects
				(font
					(size 1.27 1.27)
				)
			)
		)
		(duplicate_pad_numbers_are_jumpers no)
		(fp_circle
			(center -0.4699 -0.8382)
			(end -0.3429 -0.8382)
			(stroke
				(width 0.254)
				(type default)
			)
			(fill no)
			(layer "F.SilkS")
		)
		(fp_poly
			(pts
				(xy 0.21463 -0.450088) (xy 1.56337 -0.450088) (xy 1.56337 1.75006) (xy 0.21463 1.75006)
			)
			(stroke
				(width 0)
				(type default)
			)
			(fill no)
			(layer "F.CrtYd")
		)
		(fp_line
			(start 0.21463 -0.450088)
			(end 1.56337 -0.450088)
			(stroke
				(width 0.1)
				(type default)
			)
			(layer "F.Fab")
		)
		(fp_line
			(start 0.21463 1.75006)
			(end 0.21463 -0.450088)
			(stroke
				(width 0.1)
				(type default)
			)
			(layer "F.Fab")
		)
		(fp_line
			(start 1.56337 -0.450088)
			(end 1.56337 1.75006)
			(stroke
				(width 0.1)
				(type default)
			)
			(layer "F.Fab")
		)
		(fp_line
			(start 1.56337 1.75006)
			(end 0.21463 1.75006)
			(stroke
				(width 0.1)
				(type default)
			)
			(layer "F.Fab")
		)
		(fp_circle
			(center -0.4699 -0.8382)
			(end -0.3429 -0.8382)
			(stroke
				(width 0.254)
				(type default)
			)
			(fill no)
			(layer "F.Fab")
		)
		(pad "1" smd rect
			(at 0 0)
			(size 1.016 0.381)
			(layers "F.Cu" "F.Mask" "F.Paste")
			(net "FM_PMBUS_ALERT_BUF_EN")
		)
		(pad "2" smd rect
			(at 0 0.649986)
			(size 1.016 0.381)
			(layers "F.Cu" "F.Mask" "F.Paste")
			(net "IRQ_SML1_PMBUS_ALERT_N")
		)
		(pad "3" smd rect
			(at 0 1.299972)
			(size 1.016 0.381)
			(layers "F.Cu" "F.Mask" "F.Paste")
			(net "GND")
		)
		(pad "4" smd rect
			(at 1.778 1.299972)
			(size 1.016 0.381)
			(layers "F.Cu" "F.Mask" "F.Paste")
			(net "IRQ_SML1_PMBUS_ALERT_BUF_N")
		)
		(pad "5" smd rect
			(at 1.778 0)
			(size 1.016 0.381)
			(layers "F.Cu" "F.Mask" "F.Paste")
			(net "P3V3_STBY")
		)
	)
	(footprint ""
		(layer "F.Cu")
		(at 269.75181 -84.890102)
		(property "Reference" "C5D2"
			(at 0 0 0)
			(layer "F.SilkS")
			(hide yes)
			(effects
				(font
					(size 1.27 1.27)
				)
			)
		)
		(property "Value" ""
			(at 0 0 0)
			(layer "F.Fab")
			(effects
				(font
					(size 1.27 1.27)
				)
			)
		)
		(duplicate_pad_numbers_are_jumpers no)
		(fp_poly
			(pts
				(xy -0.4953 -0.2032) (xy 0.4953 -0.2032) (xy 0.4953 1.6002) (xy -0.4953 1.6002)
			)
			(stroke
				(width 0)
				(type default)
			)
			(fill no)
			(layer "F.CrtYd")
		)
		(fp_line
			(start -0.4953 -0.2032)
			(end 0.4953 -0.2032)
			(stroke
				(width 0.1)
				(type default)
			)
			(layer "F.Fab")
		)
		(fp_line
			(start -0.4953 1.6002)
			(end -0.4953 -0.2032)
			(stroke
				(width 0.1)
				(type default)
			)
			(layer "F.Fab")
		)
		(fp_line
			(start 0.4953 -0.2032)
			(end 0.4953 1.6002)
			(stroke
				(width 0.1)
				(type default)
			)
			(layer "F.Fab")
		)
		(fp_line
			(start 0.4953 1.6002)
			(end -0.4953 1.6002)
			(stroke
				(width 0.1)
				(type default)
			)
			(layer "F.Fab")
		)
		(pad "1" smd rect
			(at 0 0)
			(size 0.762 0.889)
			(layers "F.Cu" "F.Mask" "F.Paste")
			(net "PVDDQ_DEF")
		)
		(pad "2" smd rect
			(at 0 1.397)
			(size 0.762 0.889)
			(layers "F.Cu" "F.Mask" "F.Paste")
			(net "GND")
		)
		(zone
			(layer "F.Cu")
			(hatch none 0.5)
			(connect_pads
				(clearance 0)
			)
			(min_thickness 0.25)
			(keepout
				(tracks not_allowed)
				(vias allowed)
				(pads allowed)
				(copperpour not_allowed)
				(footprints allowed)
			)
			(placement
				(enabled no)
				(sheetname "")
			)
			(fill
				(thermal_gap 0.5)
				(thermal_bridge_width 0.5)
				(island_removal_mode 0)
			)
			(polygon
				(pts
					(xy 269.37081 -84.445602) (xy 270.13281 -84.445602) (xy 270.13281 -83.937602) (xy 269.37081 -83.937602)
				)
			)
		)
	)
	(footprint ""
		(layer "F.Cu")
		(at 175.133 -7.8105 180)
		(property "Reference" "R4G13"
			(at 0 0 180)
			(layer "F.SilkS")
			(hide yes)
			(effects
				(font
					(size 1.27 1.27)
				)
			)
		)
		(property "Value" ""
			(at 0 0 180)
			(layer "F.Fab")
			(effects
				(font
					(size 1.27 1.27)
				)
			)
		)
		(duplicate_pad_numbers_are_jumpers no)
		(fp_rect
			(start 0.2794 -0.1016)
			(end -0.2794 0.9906)
			(stroke
				(width 0)
				(type default)
			)
			(fill no)
			(layer "F.CrtYd")
		)
		(fp_line
			(start 0.2794 0.9906)
			(end 0.2794 -0.1016)
			(stroke
				(width 0.1)
				(type default)
			)
			(layer "F.Fab")
		)
		(fp_line
			(start 0.2794 -0.1016)
			(end -0.2794 -0.1016)
			(stroke
				(width 0.1)
				(type default)
			)
			(layer "F.Fab")
		)
		(fp_line
			(start -0.2794 0.9906)
			(end 0.2794 0.9906)
			(stroke
				(width 0.1)
				(type default)
			)
			(layer "F.Fab")
		)
		(fp_line
			(start -0.2794 -0.1016)
			(end -0.2794 0.9906)
			(stroke
				(width 0.1)
				(type default)
			)
			(layer "F.Fab")
		)
		(pad "1" smd rect
			(at 0 0 180)
			(size 0.508 0.508)
			(layers "F.Cu" "F.Mask" "F.Paste")
			(net "VR_COMP_RC_PVPP_GHJ")
		)
		(pad "2" smd rect
			(at 0 0.889 180)
			(size 0.508 0.508)
			(layers "F.Cu" "F.Mask" "F.Paste")
			(net "VR_FB_PVPP_GHJ")
		)
		(zone
			(layer "F.Cu")
			(hatch none 0.5)
			(connect_pads
				(clearance 0)
			)
			(min_thickness 0.25)
			(keepout
				(tracks allowed)
				(vias not_allowed)
				(pads allowed)
				(copperpour not_allowed)
				(footprints allowed)
			)
			(placement
				(enabled no)
				(sheetname "")
			)
			(fill
				(thermal_gap 0.5)
				(thermal_bridge_width 0.5)
				(island_removal_mode 0)
			)
			(polygon
				(pts
					(xy 174.879 -8.0645) (xy 175.387 -8.0645) (xy 175.387 -8.4455) (xy 174.879 -8.4455)
				)
			)
		)
		(zone
			(layer "F.Cu")
			(hatch none 0.5)
			(connect_pads
				(clearance 0)
			)
			(min_thickness 0.25)
			(keepout
				(tracks not_allowed)
				(vias allowed)
				(pads allowed)
				(copperpour not_allowed)
				(footprints allowed)
			)
			(placement
				(enabled no)
				(sheetname "")
			)
			(fill
				(thermal_gap 0.5)
				(thermal_bridge_width 0.5)
				(island_removal_mode 0)
			)
			(polygon
				(pts
					(xy 174.879 -8.0645) (xy 175.387 -8.0645) (xy 175.387 -8.4455) (xy 174.879 -8.4455)
				)
			)
		)
	)
	(footprint ""
		(layer "F.Cu")
		(at 266.9286 -79.6036 180)
		(property "Reference" "C5D18"
			(at 0 0 180)
			(layer "F.SilkS")
			(hide yes)
			(effects
				(font
					(size 1.27 1.27)
				)
			)
		)
		(property "Value" ""
			(at 0 0 180)
			(layer "F.Fab")
			(effects
				(font
					(size 1.27 1.27)
				)
			)
		)
		(duplicate_pad_numbers_are_jumpers no)
		(fp_poly
			(pts
				(xy -0.4953 -0.2032) (xy 0.4953 -0.2032) (xy 0.4953 1.6002) (xy -0.4953 1.6002)
			)
			(stroke
				(width 0)
				(type default)
			)
			(fill no)
			(layer "F.CrtYd")
		)
		(fp_line
			(start 0.4953 1.6002)
			(end -0.4953 1.6002)
			(stroke
				(width 0.1)
				(type default)
			)
			(layer "F.Fab")
		)
		(fp_line
			(start 0.4953 -0.2032)
			(end 0.4953 1.6002)
			(stroke
				(width 0.1)
				(type default)
			)
			(layer "F.Fab")
		)
		(fp_line
			(start -0.4953 1.6002)
			(end -0.4953 -0.2032)
			(stroke
				(width 0.1)
				(type default)
			)
			(layer "F.Fab")
		)
		(fp_line
			(start -0.4953 -0.2032)
			(end 0.4953 -0.2032)
			(stroke
				(width 0.1)
				(type default)
			)
			(layer "F.Fab")
		)
		(pad "1" smd rect
			(at 0 0 180)
			(size 0.762 0.889)
			(layers "F.Cu" "F.Mask" "F.Paste")
			(net "PVCCIN_CPU0")
		)
		(pad "2" smd rect
			(at 0 1.397 180)
			(size 0.762 0.889)
			(layers "F.Cu" "F.Mask" "F.Paste")
			(net "GND")
		)
		(zone
			(layer "F.Cu")
			(hatch none 0.5)
			(connect_pads
				(clearance 0)
			)
			(min_thickness 0.25)
			(keepout
				(tracks not_allowed)
				(vias allowed)
				(pads allowed)
				(copperpour not_allowed)
				(footprints allowed)
			)
			(placement
				(enabled no)
				(sheetname "")
			)
			(fill
				(thermal_gap 0.5)
				(thermal_bridge_width 0.5)
				(island_removal_mode 0)
			)
			(polygon
				(pts
					(xy 267.3096 -80.0481) (xy 266.5476 -80.0481) (xy 266.5476 -80.5561) (xy 267.3096 -80.5561)
				)
			)
		)
	)
	(footprint ""
		(layer "F.Cu")
		(at 341.249 -98.425 180)
		(property "Reference" "L7C2"
			(at 3.378708 -4.251706 180)
			(unlocked yes)
			(layer "F.SilkS")
			(effects
				(font
					(size 0.4064 0.254)
					(thickness 0.1524)
				)
			)
		)
		(property "Value" ""
			(at 0 0 180)
			(layer "F.Fab")
			(effects
				(font
					(size 1.27 1.27)
				)
			)
		)
		(duplicate_pad_numbers_are_jumpers no)
		(fp_line
			(start 8.3693 3.199892)
			(end -1.1303 3.199892)
			(stroke
				(width 0.1524)
				(type default)
			)
			(layer "F.SilkS")
		)
		(fp_line
			(start 8.3693 1.6637)
			(end 8.3693 3.199892)
			(stroke
				(width 0.1524)
				(type default)
			)
			(layer "F.SilkS")
		)
		(fp_line
			(start 8.3693 -3.199892)
			(end 8.3693 -1.6637)
			(stroke
				(width 0.1524)
				(type default)
			)
			(layer "F.SilkS")
		)
		(fp_line
			(start -1.1303 3.199892)
			(end -1.1303 1.6637)
			(stroke
				(width 0.1524)
				(type default)
			)
			(layer "F.SilkS")
		)
		(fp_line
			(start -1.1303 -1.6637)
			(end -1.1303 -3.199892)
			(stroke
				(width 0.1524)
				(type default)
			)
			(layer "F.SilkS")
		)
		(fp_line
			(start -1.1303 -3.199892)
			(end 8.3693 -3.199892)
			(stroke
				(width 0.1524)
				(type default)
			)
			(layer "F.SilkS")
		)
		(fp_rect
			(start -1.1303 3.199892)
			(end 8.3693 -3.199892)
			(stroke
				(width 0)
				(type default)
			)
			(fill no)
			(layer "F.CrtYd")
		)
		(fp_line
			(start 8.3693 3.199892)
			(end -1.1303 3.199892)
			(stroke
				(width 0.1)
				(type default)
			)
			(layer "F.Fab")
		)
		(fp_line
			(start 8.3693 -3.199892)
			(end 8.3693 3.199892)
			(stroke
				(width 0.1)
				(type default)
			)
			(layer "F.Fab")
		)
		(fp_line
			(start -1.1303 3.199892)
			(end -1.1303 -3.199892)
			(stroke
				(width 0.1)
				(type default)
			)
			(layer "F.Fab")
		)
		(fp_line
			(start -1.1303 -3.199892)
			(end 8.3693 -3.199892)
			(stroke
				(width 0.1)
				(type default)
			)
			(layer "F.Fab")
		)
		(pad "1" smd rect
			(at 0 0 180)
			(size 3.683 2.667)
			(layers "F.Cu" "F.Mask" "F.Paste")
			(net "VR_PVCCIO_CPU0_PH1_SW")
		)
		(pad "2" smd rect
			(at 7.239 0 180)
			(size 3.683 2.667)
			(layers "F.Cu" "F.Mask" "F.Paste")
			(net "PVCCIO_CPU0")
		)
	)
	(footprint ""
		(layer "F.Cu")
		(at 262.133334 -83.84159)
		(property "Reference" "C5D10"
			(at 0 0 0)
			(layer "F.SilkS")
			(hide yes)
			(effects
				(font
					(size 1.27 1.27)
				)
			)
		)
		(property "Value" ""
			(at 0 0 0)
			(layer "F.Fab")
			(effects
				(font
					(size 1.27 1.27)
				)
			)
		)
		(duplicate_pad_numbers_are_jumpers no)
		(fp_poly
			(pts
				(xy -0.4953 -0.2032) (xy 0.4953 -0.2032) (xy 0.4953 1.6002) (xy -0.4953 1.6002)
			)
			(stroke
				(width 0)
				(type default)
			)
			(fill no)
			(layer "F.CrtYd")
		)
		(fp_line
			(start -0.4953 -0.2032)
			(end 0.4953 -0.2032)
			(stroke
				(width 0.1)
				(type default)
			)
			(layer "F.Fab")
		)
		(fp_line
			(start -0.4953 1.6002)
			(end -0.4953 -0.2032)
			(stroke
				(width 0.1)
				(type default)
			)
			(layer "F.Fab")
		)
		(fp_line
			(start 0.4953 -0.2032)
			(end 0.4953 1.6002)
			(stroke
				(width 0.1)
				(type default)
			)
			(layer "F.Fab")
		)
		(fp_line
			(start 0.4953 1.6002)
			(end -0.4953 1.6002)
			(stroke
				(width 0.1)
				(type default)
			)
			(layer "F.Fab")
		)
		(pad "1" smd rect
			(at 0 0)
			(size 0.762 0.889)
			(layers "F.Cu" "F.Mask" "F.Paste")
			(net "PVSA_CPU0")
		)
		(pad "2" smd rect
			(at 0 1.397)
			(size 0.762 0.889)
			(layers "F.Cu" "F.Mask" "F.Paste")
			(net "GND")
		)
		(zone
			(layer "F.Cu")
			(hatch none 0.5)
			(connect_pads
				(clearance 0)
			)
			(min_thickness 0.25)
			(keepout
				(tracks not_allowed)
				(vias allowed)
				(pads allowed)
				(copperpour not_allowed)
				(footprints allowed)
			)
			(placement
				(enabled no)
				(sheetname "")
			)
			(fill
				(thermal_gap 0.5)
				(thermal_bridge_width 0.5)
				(island_removal_mode 0)
			)
			(polygon
				(pts
					(xy 261.752334 -83.39709) (xy 262.514334 -83.39709) (xy 262.514334 -82.88909) (xy 261.752334 -82.88909)
				)
			)
		)
	)
	(footprint ""
		(layer "F.Cu")
		(at 268.165072 -77.636116)
		(property "Reference" "C5D32"
			(at 0 0 0)
			(layer "F.SilkS")
			(hide yes)
			(effects
				(font
					(size 1.27 1.27)
				)
			)
		)
		(property "Value" ""
			(at 0 0 0)
			(layer "F.Fab")
			(effects
				(font
					(size 1.27 1.27)
				)
			)
		)
		(duplicate_pad_numbers_are_jumpers no)
		(fp_poly
			(pts
				(xy -0.4953 -0.2032) (xy 0.4953 -0.2032) (xy 0.4953 1.6002) (xy -0.4953 1.6002)
			)
			(stroke
				(width 0)
				(type default)
			)
			(fill no)
			(layer "F.CrtYd")
		)
		(fp_line
			(start -0.4953 -0.2032)
			(end 0.4953 -0.2032)
			(stroke
				(width 0.1)
				(type default)
			)
			(layer "F.Fab")
		)
		(fp_line
			(start -0.4953 1.6002)
			(end -0.4953 -0.2032)
			(stroke
				(width 0.1)
				(type default)
			)
			(layer "F.Fab")
		)
		(fp_line
			(start 0.4953 -0.2032)
			(end 0.4953 1.6002)
			(stroke
				(width 0.1)
				(type default)
			)
			(layer "F.Fab")
		)
		(fp_line
			(start 0.4953 1.6002)
			(end -0.4953 1.6002)
			(stroke
				(width 0.1)
				(type default)
			)
			(layer "F.Fab")
		)
		(pad "1" smd rect
			(at 0 0)
			(size 0.762 0.889)
			(layers "F.Cu" "F.Mask" "F.Paste")
			(net "PVCCIN_CPU0")
		)
		(pad "2" smd rect
			(at 0 1.397)
			(size 0.762 0.889)
			(layers "F.Cu" "F.Mask" "F.Paste")
			(net "GND")
		)
		(zone
			(layer "F.Cu")
			(hatch none 0.5)
			(connect_pads
				(clearance 0)
			)
			(min_thickness 0.25)
			(keepout
				(tracks not_allowed)
				(vias allowed)
				(pads allowed)
				(copperpour not_allowed)
				(footprints allowed)
			)
			(placement
				(enabled no)
				(sheetname "")
			)
			(fill
				(thermal_gap 0.5)
				(thermal_bridge_width 0.5)
				(island_removal_mode 0)
			)
			(polygon
				(pts
					(xy 267.784072 -77.191616) (xy 268.546072 -77.191616) (xy 268.546072 -76.683616) (xy 267.784072 -76.683616)
				)
			)
		)
	)
	(footprint ""
		(layer "F.Cu")
		(at 266.920472 -73.318116)
		(property "Reference" "C5D46"
			(at 0 0 0)
			(layer "F.SilkS")
			(hide yes)
			(effects
				(font
					(size 1.27 1.27)
				)
			)
		)
		(property "Value" ""
			(at 0 0 0)
			(layer "F.Fab")
			(effects
				(font
					(size 1.27 1.27)
				)
			)
		)
		(duplicate_pad_numbers_are_jumpers no)
		(fp_poly
			(pts
				(xy -0.4953 -0.2032) (xy 0.4953 -0.2032) (xy 0.4953 1.6002) (xy -0.4953 1.6002)
			)
			(stroke
				(width 0)
				(type default)
			)
			(fill no)
			(layer "F.CrtYd")
		)
		(fp_line
			(start -0.4953 -0.2032)
			(end 0.4953 -0.2032)
			(stroke
				(width 0.1)
				(type default)
			)
			(layer "F.Fab")
		)
		(fp_line
			(start -0.4953 1.6002)
			(end -0.4953 -0.2032)
			(stroke
				(width 0.1)
				(type default)
			)
			(layer "F.Fab")
		)
		(fp_line
			(start 0.4953 -0.2032)
			(end 0.4953 1.6002)
			(stroke
				(width 0.1)
				(type default)
			)
			(layer "F.Fab")
		)
		(fp_line
			(start 0.4953 1.6002)
			(end -0.4953 1.6002)
			(stroke
				(width 0.1)
				(type default)
			)
			(layer "F.Fab")
		)
		(pad "1" smd rect
			(at 0 0)
			(size 0.762 0.889)
			(layers "F.Cu" "F.Mask" "F.Paste")
			(net "PVCCIN_CPU0")
		)
		(pad "2" smd rect
			(at 0 1.397)
			(size 0.762 0.889)
			(layers "F.Cu" "F.Mask" "F.Paste")
			(net "GND")
		)
		(zone
			(layer "F.Cu")
			(hatch none 0.5)
			(connect_pads
				(clearance 0)
			)
			(min_thickness 0.25)
			(keepout
				(tracks not_allowed)
				(vias allowed)
				(pads allowed)
				(copperpour not_allowed)
				(footprints allowed)
			)
			(placement
				(enabled no)
				(sheetname "")
			)
			(fill
				(thermal_gap 0.5)
				(thermal_bridge_width 0.5)
				(island_removal_mode 0)
			)
			(polygon
				(pts
					(xy 266.539472 -72.873616) (xy 267.301472 -72.873616) (xy 267.301472 -72.365616) (xy 266.539472 -72.365616)
				)
			)
		)
	)
	(footprint ""
		(layer "F.Cu")
		(at 13.8938 -32.131 90)
		(property "Reference" "C1F8"
			(at 0 0 90)
			(layer "F.SilkS")
			(hide yes)
			(effects
				(font
					(size 1.27 1.27)
				)
			)
		)
		(property "Value" ""
			(at 0 0 90)
			(layer "F.Fab")
			(effects
				(font
					(size 1.27 1.27)
				)
			)
		)
		(duplicate_pad_numbers_are_jumpers no)
		(fp_rect
			(start -0.3048 -0.1016)
			(end 0.3048 0.9906)
			(stroke
				(width 0)
				(type default)
			)
			(fill no)
			(layer "F.CrtYd")
		)
		(fp_line
			(start 0.3048 -0.1016)
			(end -0.3048 -0.1016)
			(stroke
				(width 0.1)
				(type default)
			)
			(layer "F.Fab")
		)
		(fp_line
			(start -0.3048 -0.1016)
			(end -0.3048 0.9906)
			(stroke
				(width 0.1)
				(type default)
			)
			(layer "F.Fab")
		)
		(fp_line
			(start 0.3048 0.9906)
			(end 0.3048 -0.1016)
			(stroke
				(width 0.1)
				(type default)
			)
			(layer "F.Fab")
		)
		(fp_line
			(start -0.3048 0.9906)
			(end 0.3048 0.9906)
			(stroke
				(width 0.1)
				(type default)
			)
			(layer "F.Fab")
		)
		(pad "1" smd rect
			(at 0 0 90)
			(size 0.508 0.508)
			(layers "F.Cu" "F.Mask" "F.Paste")
			(net "P3E_CPU1_PE3_MP_C_TXN<5>")
		)
		(pad "2" smd rect
			(at 0 0.889 90)
			(size 0.508 0.508)
			(layers "F.Cu" "F.Mask" "F.Paste")
			(net "P3E_CPU1_PE3_MP_TXN<5>")
		)
		(zone
			(layer "F.Cu")
			(hatch none 0.5)
			(connect_pads
				(clearance 0)
			)
			(min_thickness 0.25)
			(keepout
				(tracks allowed)
				(vias not_allowed)
				(pads allowed)
				(copperpour not_allowed)
				(footprints allowed)
			)
			(placement
				(enabled no)
				(sheetname "")
			)
			(fill
				(thermal_gap 0.5)
				(thermal_bridge_width 0.5)
				(island_removal_mode 0)
			)
			(polygon
				(pts
					(xy 14.1478 -31.877) (xy 14.5288 -31.877) (xy 14.5288 -32.385) (xy 14.1478 -32.385)
				)
			)
		)
		(zone
			(layer "F.Cu")
			(hatch none 0.5)
			(connect_pads
				(clearance 0)
			)
			(min_thickness 0.25)
			(keepout
				(tracks not_allowed)
				(vias allowed)
				(pads allowed)
				(copperpour not_allowed)
				(footprints allowed)
			)
			(placement
				(enabled no)
				(sheetname "")
			)
			(fill
				(thermal_gap 0.5)
				(thermal_bridge_width 0.5)
				(island_removal_mode 0)
			)
			(polygon
				(pts
					(xy 14.1478 -31.877) (xy 14.5288 -31.877) (xy 14.5288 -32.385) (xy 14.1478 -32.385)
				)
			)
		)
	)
	(footprint ""
		(layer "F.Cu")
		(at 443.253876 -12.599924 90)
		(property "Reference" "R9G34"
			(at 0 0 90)
			(layer "F.SilkS")
			(hide yes)
			(effects
				(font
					(size 1.27 1.27)
				)
			)
		)
		(property "Value" ""
			(at 0 0 90)
			(layer "F.Fab")
			(effects
				(font
					(size 1.27 1.27)
				)
			)
		)
		(duplicate_pad_numbers_are_jumpers no)
		(fp_poly
			(pts
				(xy -0.2794 -0.1016) (xy 0.2794 -0.1016) (xy 0.2794 0.9906) (xy -0.2794 0.9906)
			)
			(stroke
				(width 0)
				(type default)
			)
			(fill no)
			(layer "F.CrtYd")
		)
		(fp_line
			(start 0.2794 -0.1016)
			(end -0.2794 -0.1016)
			(stroke
				(width 0.1)
				(type default)
			)
			(layer "F.Fab")
		)
		(fp_line
			(start -0.2794 -0.1016)
			(end -0.2794 0.9906)
			(stroke
				(width 0.1)
				(type default)
			)
			(layer "F.Fab")
		)
		(fp_line
			(start 0.2794 0.9906)
			(end 0.2794 -0.1016)
			(stroke
				(width 0.1)
				(type default)
			)
			(layer "F.Fab")
		)
		(fp_line
			(start -0.2794 0.9906)
			(end 0.2794 0.9906)
			(stroke
				(width 0.1)
				(type default)
			)
			(layer "F.Fab")
		)
		(pad "1" smd rect
			(at 0 0 90)
			(size 0.508 0.508)
			(layers "F.Cu" "F.Mask" "F.Paste")
			(net "H_CPU0_MEMABC_MEMHOT_G_N")
		)
		(pad "2" smd rect
			(at 0 0.889 90)
			(size 0.508 0.508)
			(layers "F.Cu" "F.Mask" "F.Paste")
			(net "H_CPU0_MEMABC_MEMHOT_G_R_N")
		)
		(zone
			(layer "F.Cu")
			(hatch none 0.5)
			(connect_pads
				(clearance 0)
			)
			(min_thickness 0.25)
			(keepout
				(tracks allowed)
				(vias not_allowed)
				(pads allowed)
				(copperpour not_allowed)
				(footprints allowed)
			)
			(placement
				(enabled no)
				(sheetname "")
			)
			(fill
				(thermal_gap 0.5)
				(thermal_bridge_width 0.5)
				(island_removal_mode 0)
			)
			(polygon
				(pts
					(xy 443.507876 -12.345924) (xy 443.507876 -12.853924) (xy 443.888876 -12.853924) (xy 443.888876 -12.345924)
				)
			)
		)
		(zone
			(layer "F.Cu")
			(hatch none 0.5)
			(connect_pads
				(clearance 0)
			)
			(min_thickness 0.25)
			(keepout
				(tracks not_allowed)
				(vias allowed)
				(pads allowed)
				(copperpour not_allowed)
				(footprints allowed)
			)
			(placement
				(enabled no)
				(sheetname "")
			)
			(fill
				(thermal_gap 0.5)
				(thermal_bridge_width 0.5)
				(island_removal_mode 0)
			)
			(polygon
				(pts
					(xy 443.888876 -12.345924) (xy 443.888876 -12.853924) (xy 443.507876 -12.853924) (xy 443.507876 -12.345924)
				)
			)
		)
	)
	(footprint ""
		(layer "F.Cu")
		(at 2.29997 -32.71012 -90)
		(property "Reference" "J1F1"
			(at 0 0 270)
			(layer "F.SilkS")
			(hide yes)
			(effects
				(font
					(size 1.27 1.27)
				)
			)
		)
		(property "Value" "*"
			(at -20.8026 -3.4036 270)
			(unlocked yes)
			(layer "F.Fab")
			(hide yes)
			(effects
				(font
					(size 1.27 1.016)
					(thickness 0.1524)
				)
			)
		)
		(property "Device Type" "DM-FCI-CONN76-8R-GP-U-01_CONN-A"
			(at -20.8026 -4.9276 270)
			(unlocked yes)
			(layer "F.Fab")
			(hide yes)
			(effects
				(font
					(size 1.27 1.016)
					(thickness 0.1524)
				)
			)
		)
		(duplicate_pad_numbers_are_jumpers no)
		(fp_line
			(start -9.1948 8.299958)
			(end -9.1948 -9.271)
			(stroke
				(width 0.1524)
				(type default)
			)
			(layer "F.SilkS")
		)
		(fp_line
			(start 9.1948 8.299958)
			(end -9.1948 8.299958)
			(stroke
				(width 0.1524)
				(type default)
			)
			(layer "F.SilkS")
		)
		(fp_line
			(start -9.1948 -9.271)
			(end 9.1948 -9.271)
			(stroke
				(width 0.1524)
				(type default)
			)
			(layer "F.SilkS")
		)
		(fp_line
			(start 9.1948 -9.271)
			(end 9.1948 8.299958)
			(stroke
				(width 0.1524)
				(type default)
			)
			(layer "F.SilkS")
		)
		(fp_poly
			(pts
				(xy -9.1948 8.299958) (xy -9.1948 -9.271) (xy 9.1948 -9.271) (xy 9.1948 8.299958)
			)
			(stroke
				(width 0)
				(type default)
			)
			(fill yes)
			(layer "F.SilkS")
		)
		(fp_poly
			(pts
				(arc
					(start -8.0518 6.183884)
					(mid -8.3058 6.437884)
					(end -8.5598 6.183884)
				)
				(arc
					(start -8.5598 4.913884)
					(mid -8.3058 4.659884)
					(end -8.0518 4.913884)
				)
			)
			(stroke
				(width 0)
				(type default)
			)
			(fill yes)
			(layer "F.SilkS")
		)
		(fp_poly
			(pts
				(arc
					(start -8.0518 3.383788)
					(mid -8.3058 3.637788)
					(end -8.5598 3.383788)
				)
				(arc
					(start -8.5598 2.113788)
					(mid -8.3058 1.859788)
					(end -8.0518 2.113788)
				)
			)
			(stroke
				(width 0)
				(type default)
			)
			(fill yes)
			(layer "F.SilkS")
		)
		(fp_poly
			(pts
				(arc
					(start -8.0518 0.583692)
					(mid -8.3058 0.837692)
					(end -8.5598 0.583692)
				)
				(arc
					(start -8.5598 -0.686308)
					(mid -8.3058 -0.940308)
					(end -8.0518 -0.686308)
				)
			)
			(stroke
				(width 0)
				(type default)
			)
			(fill yes)
			(layer "F.SilkS")
		)
		(fp_poly
			(pts
				(arc
					(start -8.0518 -2.216404)
					(mid -8.3058 -1.962404)
					(end -8.5598 -2.216404)
				)
				(arc
					(start -8.5598 -3.486404)
					(mid -8.3058 -3.740404)
					(end -8.0518 -3.486404)
				)
			)
			(stroke
				(width 0)
				(type default)
			)
			(fill yes)
			(layer "F.SilkS")
		)
		(fp_poly
			(pts
				(arc
					(start -8.0518 -5.0165)
					(mid -8.3058 -4.7625)
					(end -8.5598 -5.0165)
				)
				(arc
					(start -8.5598 -6.2865)
					(mid -8.3058 -6.5405)
					(end -8.0518 -6.2865)
				)
			)
			(stroke
				(width 0)
				(type default)
			)
			(fill yes)
			(layer "F.SilkS")
		)
		(fp_rect
			(start -12.4333 11.7348)
			(end 12.4333 -11.7348)
			(stroke
				(width 0)
				(type default)
			)
			(fill no)
			(layer "B.CrtYd")
		)
		(fp_rect
			(start -8.9408 20.4978)
			(end 8.9408 -9.017)
			(stroke
				(width 0)
				(type default)
			)
			(fill no)
			(layer "F.CrtYd")
		)
		(fp_poly
			(pts
				(xy -13.9446 25.5016) (xy -13.9446 -14.0208) (xy 13.9446 -14.0208) (xy 13.9446 -0.3048) (xy 9.4488 -0.3048)
				(xy 9.4488 -9.525) (xy -9.4488 -9.525) (xy -9.4488 21.0058) (xy 9.4488 21.0058) (xy 9.4488 -0.2921)
				(xy 13.9446 -0.2921) (xy 13.9446 25.5016)
			)
			(stroke
				(width 0)
				(type default)
			)
			(fill no)
			(layer "F.CrtYd")
		)
		(fp_poly
			(pts
				(xy -9.4488 21.0058) (xy -9.4488 -9.525) (xy 9.4488 -9.525) (xy 9.4488 -0.3048) (xy 8.9408 -0.3048)
				(xy 8.9408 -9.017) (xy -8.9408 -9.017) (xy -8.9408 20.4978) (xy 8.9408 20.4978) (xy 8.9408 -0.2921)
				(xy 9.4488 -0.2921) (xy 9.4488 21.0058)
			)
			(stroke
				(width 0)
				(type default)
			)
			(fill no)
			(layer "F.CrtYd")
		)
		(fp_rect
			(start -17.4371 16.7386)
			(end 17.4371 -16.7386)
			(stroke
				(width 0)
				(type default)
			)
			(fill no)
			(layer "B.Fab")
		)
		(fp_rect
			(start -12.4333 11.7348)
			(end 12.4333 -11.7348)
			(stroke
				(width 0)
				(type default)
			)
			(fill no)
			(layer "B.Fab")
		)
		(fp_rect
			(start -18.9484 30.5054)
			(end 18.9484 -19.0246)
			(stroke
				(width 0)
				(type default)
			)
			(fill no)
			(layer "F.Fab")
		)
		(fp_rect
			(start -13.9446 25.5016)
			(end 13.9446 -14.0208)
			(stroke
				(width 0)
				(type default)
			)
			(fill no)
			(layer "F.Fab")
		)
		(fp_rect
			(start -9.4488 21.0058)
			(end 9.4488 -9.525)
			(stroke
				(width 0)
				(type default)
			)
			(fill no)
			(layer "F.Fab")
		)
		(fp_text user "Slit"
			(at -8.8392 12.0523 270)
			(unlocked yes)
			(layer "F.SilkS")
			(effects
				(font
					(size 1.27 1.016)
					(thickness 0.1524)
				)
				(justify left)
			)
		)
		(fp_text user "Press Fit"
			(at -5.207 -8.0645 270)
			(unlocked yes)
			(layer "F.SilkS")
			(effects
				(font
					(size 1.27 1.016)
					(thickness 0.1524)
				)
				(justify left)
			)
		)
		(fp_text user "Can not place BGA,CSP,Wave Solder Component"
			(at -25.6286 13.9827 270)
			(unlocked yes)
			(layer "B.Fab")
			(effects
				(font
					(size 1.27 1.016)
					(thickness 0.1524)
				)
				(justify left)
			)
		)
		(fp_text user "Can not place BGA,CSP,Wave Solder Component"
			(at -24.892 27.3685 270)
			(unlocked yes)
			(layer "F.Fab")
			(effects
				(font
					(size 1.27 1.016)
					(thickness 0.1524)
				)
				(justify left)
			)
		)
		(fp_text user "High Limit 2mm"
			(at -8.4328 23.0759 270)
			(unlocked yes)
			(layer "F.Fab")
			(effects
				(font
					(size 1.27 1.016)
					(thickness 0.1524)
				)
				(justify left)
			)
		)
		(pad "A1" thru_hole circle
			(at -6.999986 6.199886 270)
			(size 0.8128 0.8128)
			(drill 0.399796)
			(layers "*.Cu" "*.Mask")
			(remove_unused_layers no)
			(net "P3E_CPU1_PE3_MP_RXN<0>")
			(clearance 0.2921)
			(thermal_gap 0.2921)
		)
		(pad "A2" thru_hole circle
			(at -4.99999 6.299962 270)
			(size 0.8636 0.8636)
			(drill 0.499872)
			(layers "*.Cu" "*.Mask")
			(remove_unused_layers no)
			(net "GND")
			(clearance 0.1778)
			(thermal_gap 0.1778)
		)
		(pad "A3" thru_hole circle
			(at -2.999994 6.199886 270)
			(size 0.8128 0.8128)
			(drill 0.399796)
			(layers "*.Cu" "*.Mask")
			(remove_unused_layers no)
			(net "P3E_CPU1_PE3_MP_RXP<6>")
			(clearance 0.2921)
			(thermal_gap 0.2921)
		)
		(pad "A4" thru_hole circle
			(at -0.999998 6.299962 270)
			(size 0.8636 0.8636)
			(drill 0.499872)
			(layers "*.Cu" "*.Mask")
			(remove_unused_layers no)
			(net "FAN_TACH3_R")
			(clearance 0.1778)
			(thermal_gap 0.1778)
		)
		(pad "A5" thru_hole circle
			(at 0.999998 6.199886 270)
			(size 0.8128 0.8128)
			(drill 0.399796)
			(layers "*.Cu" "*.Mask")
			(remove_unused_layers no)
			(net "NIC_MDI_MNG_TX_DP")
			(clearance 0.2921)
			(thermal_gap 0.2921)
		)
		(pad "A6" thru_hole circle
			(at 2.999994 6.299962 270)
			(size 0.8636 0.8636)
			(drill 0.499872)
			(layers "*.Cu" "*.Mask")
			(remove_unused_layers no)
			(net "IRQ_SML1_PMBUS_ALERT_R_N")
			(clearance 0.1778)
			(thermal_gap 0.1778)
		)
		(pad "A7" thru_hole circle
			(at 4.99999 6.199886 270)
			(size 0.8128 0.8128)
			(drill 0.399796)
			(layers "*.Cu" "*.Mask")
			(remove_unused_layers no)
			(net "P3E_CPU1_PE3_MP_C_TXN<3>")
			(clearance 0.2921)
			(thermal_gap 0.2921)
		)
		(pad "A8" thru_hole circle
			(at 6.999986 6.299962 270)
			(size 0.8636 0.8636)
			(drill 0.499872)
			(layers "*.Cu" "*.Mask")
			(remove_unused_layers no)
			(net "GND")
			(clearance 0.1778)
			(thermal_gap 0.1778)
		)
		(pad "B1" thru_hole circle
			(at -6.999986 4.800092 270)
			(size 0.8128 0.8128)
			(drill 0.399796)
			(layers "*.Cu" "*.Mask")
			(remove_unused_layers no)
			(net "P3E_CPU1_PE3_MP_RXP<0>")
			(clearance 0.2921)
			(thermal_gap 0.2921)
		)
		(pad "B2" thru_hole circle
			(at -4.99999 4.899914 270)
			(size 0.8128 0.8128)
			(drill 0.399796)
			(layers "*.Cu" "*.Mask")
			(remove_unused_layers no)
			(net "P3E_CPU1_PE3_MP_RXN<3>")
			(clearance 0.2921)
			(thermal_gap 0.2921)
		)
		(pad "B3" thru_hole circle
			(at -2.999994 4.800092 270)
			(size 0.8128 0.8128)
			(drill 0.399796)
			(layers "*.Cu" "*.Mask")
			(remove_unused_layers no)
			(net "P3E_CPU1_PE3_MP_RXN<6>")
			(clearance 0.2921)
			(thermal_gap 0.2921)
		)
		(pad "B4" thru_hole circle
			(at -0.999998 4.899914 270)
			(size 0.8128 0.8128)
			(drill 0.399796)
			(layers "*.Cu" "*.Mask")
			(remove_unused_layers no)
			(net "FAN_TACH2_R")
			(clearance 0.1524)
			(thermal_gap 0.1524)
		)
		(pad "B5" thru_hole circle
			(at 0.999998 4.800092 270)
			(size 0.8128 0.8128)
			(drill 0.399796)
			(layers "*.Cu" "*.Mask")
			(remove_unused_layers no)
			(net "NIC_MDI_MNG_TX_DN")
			(clearance 0.2921)
			(thermal_gap 0.2921)
		)
		(pad "B6" thru_hole circle
			(at 2.999994 4.899914 270)
			(size 0.8128 0.8128)
			(drill 0.399796)
			(layers "*.Cu" "*.Mask")
			(remove_unused_layers no)
			(net "SMB_BMC_PMBUS_STBY_LVC3_SDA")
			(clearance 0.1524)
			(thermal_gap 0.1524)
		)
		(pad "B7" thru_hole circle
			(at 4.99999 4.800092 270)
			(size 0.8128 0.8128)
			(drill 0.399796)
			(layers "*.Cu" "*.Mask")
			(remove_unused_layers no)
			(net "P3E_CPU1_PE3_MP_C_TXP<3>")
			(clearance 0.2921)
			(thermal_gap 0.2921)
		)
		(pad "B8" thru_hole circle
			(at 6.999986 4.899914 270)
			(size 0.8128 0.8128)
			(drill 0.399796)
			(layers "*.Cu" "*.Mask")
			(remove_unused_layers no)
			(net "P3E_CPU1_PE3_MP_C_TXN<0>")
			(clearance 0.2921)
			(thermal_gap 0.2921)
		)
		(pad "C1" thru_hole circle
			(at -6.999986 3.400044 270)
			(size 0.8636 0.8636)
			(drill 0.499872)
			(layers "*.Cu" "*.Mask")
			(remove_unused_layers no)
			(net "GND")
			(clearance 0.1778)
			(thermal_gap 0.1778)
		)
		(pad "C2" thru_hole circle
			(at -4.99999 3.50012 270)
			(size 0.8128 0.8128)
			(drill 0.399796)
			(layers "*.Cu" "*.Mask")
			(remove_unused_layers no)
			(net "P3E_CPU1_PE3_MP_RXP<3>")
			(clearance 0.2921)
			(thermal_gap 0.2921)
		)
		(pad "C3" thru_hole circle
			(at -2.999994 3.400044 270)
			(size 0.8636 0.8636)
			(drill 0.499872)
			(layers "*.Cu" "*.Mask")
			(remove_unused_layers no)
			(net "GND")
			(clearance 0.1778)
			(thermal_gap 0.1778)
		)
		(pad "C4" thru_hole circle
			(at -0.999998 3.50012 270)
			(size 0.8128 0.8128)
			(drill 0.399796)
			(layers "*.Cu" "*.Mask")
			(remove_unused_layers no)
			(net "FAN_TACH1_R")
			(clearance 0.1524)
			(thermal_gap 0.1524)
		)
		(pad "C5" thru_hole circle
			(at 0.999998 3.400044 270)
			(size 0.8636 0.8636)
			(drill 0.499872)
			(layers "*.Cu" "*.Mask")
			(remove_unused_layers no)
			(net "GND")
			(clearance 0.1778)
			(thermal_gap 0.1778)
		)
		(pad "C6" thru_hole circle
			(at 2.999994 3.50012 270)
			(size 0.8128 0.8128)
			(drill 0.399796)
			(layers "*.Cu" "*.Mask")
			(remove_unused_layers no)
			(net "SMB_BMC_PMBUS_STBY_LVC3_SCL")
			(clearance 0.1524)
			(thermal_gap 0.1524)
		)
		(pad "C7" thru_hole circle
			(at 4.99999 3.400044 270)
			(size 0.8636 0.8636)
			(drill 0.499872)
			(layers "*.Cu" "*.Mask")
			(remove_unused_layers no)
			(net "GND")
			(clearance 0.1778)
			(thermal_gap 0.1778)
		)
		(pad "C8" thru_hole circle
			(at 6.999986 3.50012 270)
			(size 0.8128 0.8128)
			(drill 0.399796)
			(layers "*.Cu" "*.Mask")
			(remove_unused_layers no)
			(net "P3E_CPU1_PE3_MP_C_TXP<0>")
			(clearance 0.2921)
			(thermal_gap 0.2921)
		)
		(pad "D1" thru_hole circle
			(at -6.999986 1.999996 270)
			(size 0.8128 0.8128)
			(drill 0.399796)
			(layers "*.Cu" "*.Mask")
			(remove_unused_layers no)
			(net "P3E_CPU1_PE3_MP_RXN<1>")
			(clearance 0.2921)
			(thermal_gap 0.2921)
		)
		(pad "D2" thru_hole circle
			(at -4.99999 2.100072 270)
			(size 0.8636 0.8636)
			(drill 0.499872)
			(layers "*.Cu" "*.Mask")
			(remove_unused_layers no)
			(net "GND")
			(clearance 0.1778)
			(thermal_gap 0.1778)
		)
		(pad "D3" thru_hole circle
			(at -2.999994 1.999996 270)
			(size 0.8128 0.8128)
			(drill 0.399796)
			(layers "*.Cu" "*.Mask")
			(remove_unused_layers no)
			(net "P3E_CPU1_PE3_MP_RXN<7>")
			(clearance 0.2921)
			(thermal_gap 0.2921)
		)
		(pad "D4" thru_hole circle
			(at -0.999998 2.100072 270)
			(size 0.8636 0.8636)
			(drill 0.499872)
			(layers "*.Cu" "*.Mask")
			(remove_unused_layers no)
			(net "FAN_TACH0_R")
			(clearance 0.1778)
			(thermal_gap 0.1778)
		)
		(pad "D5" thru_hole circle
			(at 0.999998 1.999996 270)
			(size 0.8128 0.8128)
			(drill 0.399796)
			(layers "*.Cu" "*.Mask")
			(remove_unused_layers no)
			(net "NIC_MDI_MNG_RX_DP")
			(clearance 0.2921)
			(thermal_gap 0.2921)
		)
		(pad "D6" thru_hole circle
			(at 2.999994 2.100072 270)
			(size 0.8636 0.8636)
			(drill 0.499872)
			(layers "*.Cu" "*.Mask")
			(remove_unused_layers no)
			(net "GND")
			(clearance 0.1778)
			(thermal_gap 0.1778)
		)
		(pad "D7" thru_hole circle
			(at 4.99999 1.999996 270)
			(size 0.8128 0.8128)
			(drill 0.399796)
			(layers "*.Cu" "*.Mask")
			(remove_unused_layers no)
			(net "P3E_CPU1_PE3_MP_C_TXN<4>")
			(clearance 0.2921)
			(thermal_gap 0.2921)
		)
		(pad "D8" thru_hole circle
			(at 6.999986 2.100072 270)
			(size 0.8636 0.8636)
			(drill 0.499872)
			(layers "*.Cu" "*.Mask")
			(remove_unused_layers no)
			(net "GND")
			(clearance 0.1778)
			(thermal_gap 0.1778)
		)
		(pad "E1" thru_hole circle
			(at -6.999986 0.599948 270)
			(size 0.8128 0.8128)
			(drill 0.399796)
			(layers "*.Cu" "*.Mask")
			(remove_unused_layers no)
			(net "P3E_CPU1_PE3_MP_RXP<1>")
			(clearance 0.2921)
			(thermal_gap 0.2921)
		)
		(pad "E2" thru_hole circle
			(at -4.99999 0.700024 270)
			(size 0.8128 0.8128)
			(drill 0.399796)
			(layers "*.Cu" "*.Mask")
			(remove_unused_layers no)
			(net "P3E_CPU1_PE3_MP_RXN<4>")
			(clearance 0.2921)
			(thermal_gap 0.2921)
		)
		(pad "E3" thru_hole circle
			(at -2.999994 0.599948 270)
			(size 0.8128 0.8128)
			(drill 0.399796)
			(layers "*.Cu" "*.Mask")
			(remove_unused_layers no)
			(net "P3E_CPU1_PE3_MP_RXP<7>")
			(clearance 0.2921)
			(thermal_gap 0.2921)
		)
		(pad "E4" thru_hole circle
			(at -0.999998 0.700024 270)
			(size 0.8128 0.8128)
			(drill 0.399796)
			(layers "*.Cu" "*.Mask")
			(remove_unused_layers no)
			(net "FM_MATED_IN_N")
			(clearance 0.1524)
			(thermal_gap 0.1524)
		)
		(pad "E5" thru_hole circle
			(at 0.999998 0.599948 270)
			(size 0.8128 0.8128)
			(drill 0.399796)
			(layers "*.Cu" "*.Mask")
			(remove_unused_layers no)
			(net "NIC_MDI_MNG_RX_DN")
			(clearance 0.2921)
			(thermal_gap 0.2921)
		)
		(pad "E6" thru_hole circle
			(at 2.999994 0.700024 270)
			(size 0.8128 0.8128)
			(drill 0.399796)
			(layers "*.Cu" "*.Mask")
			(remove_unused_layers no)
			(net "P3E_CPU1_PE3_MP_C_TXN<6>")
			(clearance 0.2921)
			(thermal_gap 0.2921)
		)
		(pad "E7" thru_hole circle
			(at 4.99999 0.599948 270)
			(size 0.8128 0.8128)
			(drill 0.399796)
			(layers "*.Cu" "*.Mask")
			(remove_unused_layers no)
			(net "P3E_CPU1_PE3_MP_C_TXP<4>")
			(clearance 0.2921)
			(thermal_gap 0.2921)
		)
		(pad "E8" thru_hole circle
			(at 6.999986 0.700024 270)
			(size 0.8128 0.8128)
			(drill 0.399796)
			(layers "*.Cu" "*.Mask")
			(remove_unused_layers no)
			(net "P3E_CPU1_PE3_MP_C_TXN<1>")
			(clearance 0.2921)
			(thermal_gap 0.2921)
		)
		(pad "F1" thru_hole circle
			(at -6.999986 -0.8001 270)
			(size 0.8636 0.8636)
			(drill 0.499872)
			(layers "*.Cu" "*.Mask")
			(remove_unused_layers no)
			(net "GND")
			(clearance 0.1778)
			(thermal_gap 0.1778)
		)
		(pad "F2" thru_hole circle
			(at -4.99999 -0.700024 270)
			(size 0.8128 0.8128)
			(drill 0.399796)
			(layers "*.Cu" "*.Mask")
			(remove_unused_layers no)
			(net "P3E_CPU1_PE3_MP_RXP<4>")
			(clearance 0.2921)
			(thermal_gap 0.2921)
		)
		(pad "F3" thru_hole circle
			(at -2.999994 -0.8001 270)
			(size 0.8636 0.8636)
			(drill 0.499872)
			(layers "*.Cu" "*.Mask")
			(remove_unused_layers no)
			(net "GND")
			(clearance 0.1778)
			(thermal_gap 0.1778)
		)
		(pad "F4" thru_hole circle
			(at -0.999998 -0.700024 270)
			(size 0.8128 0.8128)
			(drill 0.399796)
			(layers "*.Cu" "*.Mask")
			(remove_unused_layers no)
			(net "FAN_PWM_OUT_SYS0_R1")
			(clearance 0.1524)
			(thermal_gap 0.1524)
		)
		(pad "F5" thru_hole circle
			(at 0.999998 -0.8001 270)
			(size 0.8636 0.8636)
			(drill 0.499872)
			(layers "*.Cu" "*.Mask")
			(remove_unused_layers no)
			(net "FM_MB_SLOT_ID0")
			(clearance 0.1778)
			(thermal_gap 0.1778)
		)
		(pad "F6" thru_hole circle
			(at 2.999994 -0.700024 270)
			(size 0.8128 0.8128)
			(drill 0.399796)
			(layers "*.Cu" "*.Mask")
			(remove_unused_layers no)
			(net "P3E_CPU1_PE3_MP_C_TXP<6>")
			(clearance 0.2921)
			(thermal_gap 0.2921)
		)
		(pad "F7" thru_hole circle
			(at 4.99999 -0.8001 270)
			(size 0.8636 0.8636)
			(drill 0.499872)
			(layers "*.Cu" "*.Mask")
			(remove_unused_layers no)
			(net "GND")
			(clearance 0.1778)
			(thermal_gap 0.1778)
		)
		(pad "F8" thru_hole circle
			(at 6.999986 -0.700024 270)
			(size 0.8128 0.8128)
			(drill 0.399796)
			(layers "*.Cu" "*.Mask")
			(remove_unused_layers no)
			(net "P3E_CPU1_PE3_MP_C_TXP<1>")
			(clearance 0.2921)
			(thermal_gap 0.2921)
		)
		(pad "G1" thru_hole circle
			(at -6.999986 -2.199894 270)
			(size 0.8128 0.8128)
			(drill 0.399796)
			(layers "*.Cu" "*.Mask")
			(remove_unused_layers no)
			(net "P3E_CPU1_PE3_MP_RXP<2>")
			(clearance 0.2921)
			(thermal_gap 0.2921)
		)
		(pad "G2" thru_hole circle
			(at -4.99999 -2.100072 270)
			(size 0.8636 0.8636)
			(drill 0.499872)
			(layers "*.Cu" "*.Mask")
			(remove_unused_layers no)
			(net "GND")
			(clearance 0.1778)
			(thermal_gap 0.1778)
		)
		(pad "G3" thru_hole circle
			(at -2.999994 -2.199894 270)
			(size 0.8128 0.8128)
			(drill 0.399796)
			(layers "*.Cu" "*.Mask")
			(remove_unused_layers no)
			(net "SPA_MID_DBG_TX_R")
			(clearance 0.1524)
			(thermal_gap 0.1524)
		)
		(pad "G4" thru_hole circle
			(at -0.999998 -2.100072 270)
			(size 0.8636 0.8636)
			(drill 0.499872)
			(layers "*.Cu" "*.Mask")
			(remove_unused_layers no)
			(net "GND")
			(clearance 0.1778)
			(thermal_gap 0.1778)
		)
		(pad "G5" thru_hole circle
			(at 0.999998 -2.199894 270)
			(size 0.8128 0.8128)
			(drill 0.399796)
			(layers "*.Cu" "*.Mask")
			(remove_unused_layers no)
			(net "FM_MB_SLOT_ID1")
			(clearance 0.1524)
			(thermal_gap 0.1524)
		)
		(pad "G6" thru_hole circle
			(at 2.999994 -2.100072 270)
			(size 0.8636 0.8636)
			(drill 0.499872)
			(layers "*.Cu" "*.Mask")
			(remove_unused_layers no)
			(net "GND")
			(clearance 0.1778)
			(thermal_gap 0.1778)
		)
		(pad "G7" thru_hole circle
			(at 4.99999 -2.199894 270)
			(size 0.8128 0.8128)
			(drill 0.399796)
			(layers "*.Cu" "*.Mask")
			(remove_unused_layers no)
			(net "P3E_CPU1_PE3_MP_C_TXP<5>")
			(clearance 0.2921)
			(thermal_gap 0.2921)
		)
		(pad "G8" thru_hole circle
			(at 6.999986 -2.100072 270)
			(size 0.8636 0.8636)
			(drill 0.499872)
			(layers "*.Cu" "*.Mask")
			(remove_unused_layers no)
			(net "GND")
			(clearance 0.1778)
			(thermal_gap 0.1778)
		)
		(pad "H1" thru_hole circle
			(at -6.999986 -3.599942 270)
			(size 0.8128 0.8128)
			(drill 0.399796)
			(layers "*.Cu" "*.Mask")
			(remove_unused_layers no)
			(net "P3E_CPU1_PE3_MP_RXN<2>")
			(clearance 0.2921)
			(thermal_gap 0.2921)
		)
		(pad "H2" thru_hole circle
			(at -4.99999 -3.50012 270)
			(size 0.8128 0.8128)
			(drill 0.399796)
			(layers "*.Cu" "*.Mask")
			(remove_unused_layers no)
			(net "P3E_CPU1_PE3_MP_RXP<5>")
			(clearance 0.2921)
			(thermal_gap 0.2921)
		)
		(pad "H3" thru_hole circle
			(at -2.999994 -3.599942 270)
			(size 0.8128 0.8128)
			(drill 0.399796)
			(layers "*.Cu" "*.Mask")
			(remove_unused_layers no)
			(net "SPA_MID_DBG_RX_R")
			(clearance 0.1524)
			(thermal_gap 0.1524)
		)
		(pad "H4" thru_hole circle
			(at -0.999998 -3.50012 270)
			(size 0.8128 0.8128)
			(drill 0.399796)
			(layers "*.Cu" "*.Mask")
			(remove_unused_layers no)
			(net "CLK_100M_AIRMAX8_PE1_DP")
			(clearance 0.2921)
			(thermal_gap 0.2921)
		)
		(pad "H5" thru_hole circle
			(at 0.999998 -3.599942 270)
			(size 0.8128 0.8128)
			(drill 0.399796)
			(layers "*.Cu" "*.Mask")
			(remove_unused_layers no)
			(net "FM_MB_SLOT_ID2")
			(clearance 0.1524)
			(thermal_gap 0.1524)
		)
		(pad "H6" thru_hole circle
			(at 2.999994 -3.50012 270)
			(size 0.8128 0.8128)
			(drill 0.399796)
			(layers "*.Cu" "*.Mask")
			(remove_unused_layers no)
			(net "P3E_CPU1_PE3_MP_C_TXP<7>")
			(clearance 0.2921)
			(thermal_gap 0.2921)
		)
		(pad "H7" thru_hole circle
			(at 4.99999 -3.599942 270)
			(size 0.8128 0.8128)
			(drill 0.399796)
			(layers "*.Cu" "*.Mask")
			(remove_unused_layers no)
			(net "P3E_CPU1_PE3_MP_C_TXN<5>")
			(clearance 0.2921)
			(thermal_gap 0.2921)
		)
		(pad "H8" thru_hole circle
			(at 6.999986 -3.50012 270)
			(size 0.8128 0.8128)
			(drill 0.399796)
			(layers "*.Cu" "*.Mask")
			(remove_unused_layers no)
			(net "P3E_CPU1_PE3_MP_C_TXN<2>")
			(clearance 0.2921)
			(thermal_gap 0.2921)
		)
		(pad "I1" thru_hole circle
			(at -6.999986 -4.99999 270)
			(size 0.8636 0.8636)
			(drill 0.499872)
			(layers "*.Cu" "*.Mask")
			(remove_unused_layers no)
			(net "GND")
			(clearance 0.1778)
			(thermal_gap 0.1778)
		)
		(pad "I2" thru_hole circle
			(at -4.99999 -4.899914 270)
			(size 0.8128 0.8128)
			(drill 0.399796)
			(layers "*.Cu" "*.Mask")
			(remove_unused_layers no)
			(net "P3E_CPU1_PE3_MP_RXN<5>")
			(clearance 0.2921)
			(thermal_gap 0.2921)
		)
		(pad "I3" thru_hole circle
			(at -2.999994 -4.99999 270)
			(size 0.8636 0.8636)
			(drill 0.499872)
			(layers "*.Cu" "*.Mask")
			(remove_unused_layers no)
			(net "FM_ENABLE_FAN_POWER")
			(clearance 0.1778)
			(thermal_gap 0.1778)
		)
		(pad "I4" thru_hole circle
			(at -0.999998 -4.899914 270)
			(size 0.8128 0.8128)
			(drill 0.399796)
			(layers "*.Cu" "*.Mask")
			(remove_unused_layers no)
			(net "CLK_100M_AIRMAX8_PE1_DN")
			(clearance 0.2921)
			(thermal_gap 0.2921)
		)
		(pad "I5" thru_hole circle
			(at 0.999998 -4.99999 270)
			(size 0.8636 0.8636)
			(drill 0.499872)
			(layers "*.Cu" "*.Mask")
			(remove_unused_layers no)
			(net "RST_PCIE_MIDPLANE_N")
			(clearance 0.1778)
			(thermal_gap 0.1778)
		)
		(pad "I6" thru_hole circle
			(at 2.999994 -4.899914 270)
			(size 0.8128 0.8128)
			(drill 0.399796)
			(layers "*.Cu" "*.Mask")
			(remove_unused_layers no)
			(net "P3E_CPU1_PE3_MP_C_TXN<7>")
			(clearance 0.2921)
			(thermal_gap 0.2921)
		)
		(pad "I7" thru_hole circle
			(at 4.99999 -4.99999 270)
			(size 0.8636 0.8636)
			(drill 0.499872)
			(layers "*.Cu" "*.Mask")
			(remove_unused_layers no)
			(net "GND")
			(clearance 0.1778)
			(thermal_gap 0.1778)
		)
		(pad "I8" thru_hole circle
			(at 6.999986 -4.899914 270)
			(size 0.8128 0.8128)
			(drill 0.399796)
			(layers "*.Cu" "*.Mask")
			(remove_unused_layers no)
			(net "P3E_CPU1_PE3_MP_C_TXP<2>")
			(clearance 0.2921)
			(thermal_gap 0.2921)
		)
		(pad "J2" thru_hole circle
			(at -4.99999 -6.299962 270)
			(size 0.8636 0.8636)
			(drill 0.499872)
			(layers "*.Cu" "*.Mask")
			(remove_unused_layers no)
			(net "GND")
			(clearance 0.1778)
			(thermal_gap 0.1778)
		)
		(pad "J4" thru_hole circle
			(at -0.999998 -6.299962 270)
			(size 0.8636 0.8636)
			(drill 0.499872)
			(layers "*.Cu" "*.Mask")
			(remove_unused_layers no)
			(net "GND")
			(clearance 0.1778)
			(thermal_gap 0.1778)
		)
		(pad "J6" thru_hole circle
			(at 2.999994 -6.299962 270)
			(size 0.8636 0.8636)
			(drill 0.499872)
			(layers "*.Cu" "*.Mask")
			(remove_unused_layers no)
			(net "GND")
			(clearance 0.1778)
			(thermal_gap 0.1778)
		)
		(pad "J8" thru_hole circle
			(at 6.999986 -6.299962 270)
			(size 0.8636 0.8636)
			(drill 0.499872)
			(layers "*.Cu" "*.Mask")
			(remove_unused_layers no)
			(net "GND")
			(clearance 0.1778)
			(thermal_gap 0.1778)
		)
	)
	(footprint ""
		(layer "F.Cu")
		(at 353.427284 -96.501204 -90)
		(property "Reference" "RT47"
			(at 1.01473 0.656336 180)
			(unlocked yes)
			(layer "F.SilkS")
			(effects
				(font
					(size 0.4064 0.254)
					(thickness 0.1524)
				)
			)
		)
		(property "Value" ""
			(at 0 0 270)
			(layer "F.Fab")
			(effects
				(font
					(size 1.27 1.27)
				)
			)
		)
		(duplicate_pad_numbers_are_jumpers no)
		(fp_poly
			(pts
				(xy -0.4953 -0.2032) (xy 0.4953 -0.2032) (xy 0.4953 1.6002) (xy -0.4953 1.6002)
			)
			(stroke
				(width 0)
				(type default)
			)
			(fill no)
			(layer "F.CrtYd")
		)
		(fp_line
			(start -0.4953 1.6002)
			(end -0.4953 -0.2032)
			(stroke
				(width 0.1)
				(type default)
			)
			(layer "F.Fab")
		)
		(fp_line
			(start 0.4953 1.6002)
			(end -0.4953 1.6002)
			(stroke
				(width 0.1)
				(type default)
			)
			(layer "F.Fab")
		)
		(fp_line
			(start -0.4953 -0.2032)
			(end 0.4953 -0.2032)
			(stroke
				(width 0.1)
				(type default)
			)
			(layer "F.Fab")
		)
		(fp_line
			(start 0.4953 -0.2032)
			(end 0.4953 1.6002)
			(stroke
				(width 0.1)
				(type default)
			)
			(layer "F.Fab")
		)
		(pad "1" smd rect
			(at 0 0 270)
			(size 0.762 0.889)
			(layers "F.Cu" "F.Mask" "F.Paste")
			(net "VR_PVCCIO_CPU0_PH1_BOOT")
		)
		(pad "2" smd rect
			(at 0 1.397 270)
			(size 0.762 0.889)
			(layers "F.Cu" "F.Mask" "F.Paste")
			(net "VR_PVCCIO_CPU0_PH1_BOOT_R")
		)
		(zone
			(layer "F.Cu")
			(hatch none 0.5)
			(connect_pads
				(clearance 0)
			)
			(min_thickness 0.25)
			(keepout
				(tracks not_allowed)
				(vias allowed)
				(pads allowed)
				(copperpour not_allowed)
				(footprints allowed)
			)
			(placement
				(enabled no)
				(sheetname "")
			)
			(fill
				(thermal_gap 0.5)
				(thermal_bridge_width 0.5)
				(island_removal_mode 0)
			)
			(polygon
				(pts
					(xy 352.474784 -96.882204) (xy 352.474784 -96.120204) (xy 352.982784 -96.120204) (xy 352.982784 -96.882204)
				)
			)
		)
		(zone
			(layer "F.Cu")
			(hatch none 0.5)
			(connect_pads
				(clearance 0)
			)
			(min_thickness 0.25)
			(keepout
				(tracks allowed)
				(vias not_allowed)
				(pads allowed)
				(copperpour not_allowed)
				(footprints allowed)
			)
			(placement
				(enabled no)
				(sheetname "")
			)
			(fill
				(thermal_gap 0.5)
				(thermal_bridge_width 0.5)
				(island_removal_mode 0)
			)
			(polygon
				(pts
					(xy 352.474784 -96.120204) (xy 352.982784 -96.120204) (xy 352.982784 -96.882204) (xy 352.474784 -96.882204)
				)
			)
		)
	)
	(footprint ""
		(layer "F.Cu")
		(at 417.481766 -22.049232)
		(property "Reference" "R1U13"
			(at 0 0 0)
			(layer "F.SilkS")
			(hide yes)
			(effects
				(font
					(size 1.27 1.27)
				)
			)
		)
		(property "Value" ""
			(at 0 0 0)
			(layer "F.Fab")
			(effects
				(font
					(size 1.27 1.27)
				)
			)
		)
		(duplicate_pad_numbers_are_jumpers no)
		(fp_poly
			(pts
				(xy -0.2794 -0.1016) (xy 0.2794 -0.1016) (xy 0.2794 0.9906) (xy -0.2794 0.9906)
			)
			(stroke
				(width 0)
				(type default)
			)
			(fill no)
			(layer "F.CrtYd")
		)
		(fp_line
			(start -0.2794 -0.1016)
			(end -0.2794 0.9906)
			(stroke
				(width 0.1)
				(type default)
			)
			(layer "F.Fab")
		)
		(fp_line
			(start -0.2794 0.9906)
			(end 0.2794 0.9906)
			(stroke
				(width 0.1)
				(type default)
			)
			(layer "F.Fab")
		)
		(fp_line
			(start 0.2794 -0.1016)
			(end -0.2794 -0.1016)
			(stroke
				(width 0.1)
				(type default)
			)
			(layer "F.Fab")
		)
		(fp_line
			(start 0.2794 0.9906)
			(end 0.2794 -0.1016)
			(stroke
				(width 0.1)
				(type default)
			)
			(layer "F.Fab")
		)
		(pad "1" smd rect
			(at 0 0)
			(size 0.508 0.508)
			(layers "F.Cu" "F.Mask" "F.Paste")
			(net "SGPIO_BMC_DOUT_R")
		)
		(pad "2" smd rect
			(at 0 0.889)
			(size 0.508 0.508)
			(layers "F.Cu" "F.Mask" "F.Paste")
			(net "SGPIO_BMC_DOUT")
		)
		(zone
			(layer "F.Cu")
			(hatch none 0.5)
			(connect_pads
				(clearance 0)
			)
			(min_thickness 0.25)
			(keepout
				(tracks allowed)
				(vias not_allowed)
				(pads allowed)
				(copperpour not_allowed)
				(footprints allowed)
			)
			(placement
				(enabled no)
				(sheetname "")
			)
			(fill
				(thermal_gap 0.5)
				(thermal_bridge_width 0.5)
				(island_removal_mode 0)
			)
			(polygon
				(pts
					(xy 417.227766 -21.795232) (xy 417.735766 -21.795232) (xy 417.735766 -21.414232) (xy 417.227766 -21.414232)
				)
			)
		)
		(zone
			(layer "F.Cu")
			(hatch none 0.5)
			(connect_pads
				(clearance 0)
			)
			(min_thickness 0.25)
			(keepout
				(tracks not_allowed)
				(vias allowed)
				(pads allowed)
				(copperpour not_allowed)
				(footprints allowed)
			)
			(placement
				(enabled no)
				(sheetname "")
			)
			(fill
				(thermal_gap 0.5)
				(thermal_bridge_width 0.5)
				(island_removal_mode 0)
			)
			(polygon
				(pts
					(xy 417.227766 -21.414232) (xy 417.735766 -21.414232) (xy 417.735766 -21.795232) (xy 417.227766 -21.795232)
				)
			)
		)
	)
	(footprint ""
		(layer "F.Cu")
		(at 106.89844 -77.636116)
		(property "Reference" "C3D10"
			(at 0 0 0)
			(layer "F.SilkS")
			(hide yes)
			(effects
				(font
					(size 1.27 1.27)
				)
			)
		)
		(property "Value" ""
			(at 0 0 0)
			(layer "F.Fab")
			(effects
				(font
					(size 1.27 1.27)
				)
			)
		)
		(duplicate_pad_numbers_are_jumpers no)
		(fp_poly
			(pts
				(xy -0.4953 -0.2032) (xy 0.4953 -0.2032) (xy 0.4953 1.6002) (xy -0.4953 1.6002)
			)
			(stroke
				(width 0)
				(type default)
			)
			(fill no)
			(layer "F.CrtYd")
		)
		(fp_line
			(start -0.4953 -0.2032)
			(end 0.4953 -0.2032)
			(stroke
				(width 0.1)
				(type default)
			)
			(layer "F.Fab")
		)
		(fp_line
			(start -0.4953 1.6002)
			(end -0.4953 -0.2032)
			(stroke
				(width 0.1)
				(type default)
			)
			(layer "F.Fab")
		)
		(fp_line
			(start 0.4953 -0.2032)
			(end 0.4953 1.6002)
			(stroke
				(width 0.1)
				(type default)
			)
			(layer "F.Fab")
		)
		(fp_line
			(start 0.4953 1.6002)
			(end -0.4953 1.6002)
			(stroke
				(width 0.1)
				(type default)
			)
			(layer "F.Fab")
		)
		(pad "1" smd rect
			(at 0 0)
			(size 0.762 0.889)
			(layers "F.Cu" "F.Mask" "F.Paste")
			(net "PVCCMCP_CPU1")
		)
		(pad "2" smd rect
			(at 0 1.397)
			(size 0.762 0.889)
			(layers "F.Cu" "F.Mask" "F.Paste")
			(net "GND")
		)
		(zone
			(layer "F.Cu")
			(hatch none 0.5)
			(connect_pads
				(clearance 0)
			)
			(min_thickness 0.25)
			(keepout
				(tracks not_allowed)
				(vias allowed)
				(pads allowed)
				(copperpour not_allowed)
				(footprints allowed)
			)
			(placement
				(enabled no)
				(sheetname "")
			)
			(fill
				(thermal_gap 0.5)
				(thermal_bridge_width 0.5)
				(island_removal_mode 0)
			)
			(polygon
				(pts
					(xy 106.51744 -77.191616) (xy 107.27944 -77.191616) (xy 107.27944 -76.683616) (xy 106.51744 -76.683616)
				)
			)
		)
	)
	(footprint ""
		(layer "F.Cu")
		(at 403.6314 -128.3335)
		(property "Reference" "C7D3"
			(at 0 0 0)
			(layer "F.SilkS")
			(hide yes)
			(effects
				(font
					(size 1.27 1.27)
				)
			)
		)
		(property "Value" ""
			(at 0 0 0)
			(layer "F.Fab")
			(effects
				(font
					(size 1.27 1.27)
				)
			)
		)
		(duplicate_pad_numbers_are_jumpers no)
		(fp_poly
			(pts
				(xy -0.4953 -0.2032) (xy 0.4953 -0.2032) (xy 0.4953 1.6002) (xy -0.4953 1.6002)
			)
			(stroke
				(width 0)
				(type default)
			)
			(fill no)
			(layer "F.CrtYd")
		)
		(fp_line
			(start -0.4953 -0.2032)
			(end 0.4953 -0.2032)
			(stroke
				(width 0.1)
				(type default)
			)
			(layer "F.Fab")
		)
		(fp_line
			(start -0.4953 1.6002)
			(end -0.4953 -0.2032)
			(stroke
				(width 0.1)
				(type default)
			)
			(layer "F.Fab")
		)
		(fp_line
			(start 0.4953 -0.2032)
			(end 0.4953 1.6002)
			(stroke
				(width 0.1)
				(type default)
			)
			(layer "F.Fab")
		)
		(fp_line
			(start 0.4953 1.6002)
			(end -0.4953 1.6002)
			(stroke
				(width 0.1)
				(type default)
			)
			(layer "F.Fab")
		)
		(pad "1" smd rect
			(at 0 0)
			(size 0.762 0.889)
			(layers "F.Cu" "F.Mask" "F.Paste")
			(net "P1V8_PCH_STBY")
		)
		(pad "2" smd rect
			(at 0 1.397)
			(size 0.762 0.889)
			(layers "F.Cu" "F.Mask" "F.Paste")
			(net "GND")
		)
		(zone
			(layer "F.Cu")
			(hatch none 0.5)
			(connect_pads
				(clearance 0)
			)
			(min_thickness 0.25)
			(keepout
				(tracks not_allowed)
				(vias allowed)
				(pads allowed)
				(copperpour not_allowed)
				(footprints allowed)
			)
			(placement
				(enabled no)
				(sheetname "")
			)
			(fill
				(thermal_gap 0.5)
				(thermal_bridge_width 0.5)
				(island_removal_mode 0)
			)
			(polygon
				(pts
					(xy 403.2504 -127.889) (xy 404.0124 -127.889) (xy 404.0124 -127.381) (xy 403.2504 -127.381)
				)
			)
		)
	)
	(footprint ""
		(layer "F.Cu")
		(at 14.097 -79.4385 180)
		(property "Reference" "R1D28"
			(at 0 0 180)
			(layer "F.SilkS")
			(hide yes)
			(effects
				(font
					(size 1.27 1.27)
				)
			)
		)
		(property "Value" ""
			(at 0 0 180)
			(layer "F.Fab")
			(effects
				(font
					(size 1.27 1.27)
				)
			)
		)
		(duplicate_pad_numbers_are_jumpers no)
		(fp_poly
			(pts
				(xy -0.2794 -0.1016) (xy 0.2794 -0.1016) (xy 0.2794 0.9906) (xy -0.2794 0.9906)
			)
			(stroke
				(width 0)
				(type default)
			)
			(fill no)
			(layer "F.CrtYd")
		)
		(fp_line
			(start 0.2794 0.9906)
			(end 0.2794 -0.1016)
			(stroke
				(width 0.1)
				(type default)
			)
			(layer "F.Fab")
		)
		(fp_line
			(start 0.2794 -0.1016)
			(end -0.2794 -0.1016)
			(stroke
				(width 0.1)
				(type default)
			)
			(layer "F.Fab")
		)
		(fp_line
			(start -0.2794 0.9906)
			(end 0.2794 0.9906)
			(stroke
				(width 0.1)
				(type default)
			)
			(layer "F.Fab")
		)
		(fp_line
			(start -0.2794 -0.1016)
			(end -0.2794 0.9906)
			(stroke
				(width 0.1)
				(type default)
			)
			(layer "F.Fab")
		)
		(pad "1" smd rect
			(at 0 0 180)
			(size 0.508 0.508)
			(layers "F.Cu" "F.Mask" "F.Paste")
			(net "PD_HSC_RETRY_N")
		)
		(pad "2" smd rect
			(at 0 0.889 180)
			(size 0.508 0.508)
			(layers "F.Cu" "F.Mask" "F.Paste")
			(net "AGND_HSC")
		)
		(zone
			(layer "F.Cu")
			(hatch none 0.5)
			(connect_pads
				(clearance 0)
			)
			(min_thickness 0.25)
			(keepout
				(tracks not_allowed)
				(vias allowed)
				(pads allowed)
				(copperpour not_allowed)
				(footprints allowed)
			)
			(placement
				(enabled no)
				(sheetname "")
			)
			(fill
				(thermal_gap 0.5)
				(thermal_bridge_width 0.5)
				(island_removal_mode 0)
			)
			(polygon
				(pts
					(xy 14.351 -80.0735) (xy 13.843 -80.0735) (xy 13.843 -79.6925) (xy 14.351 -79.6925)
				)
			)
		)
		(zone
			(layer "F.Cu")
			(hatch none 0.5)
			(connect_pads
				(clearance 0)
			)
			(min_thickness 0.25)
			(keepout
				(tracks allowed)
				(vias not_allowed)
				(pads allowed)
				(copperpour not_allowed)
				(footprints allowed)
			)
			(placement
				(enabled no)
				(sheetname "")
			)
			(fill
				(thermal_gap 0.5)
				(thermal_bridge_width 0.5)
				(island_removal_mode 0)
			)
			(polygon
				(pts
					(xy 14.351 -79.6925) (xy 13.843 -79.6925) (xy 13.843 -80.0735) (xy 14.351 -80.0735)
				)
			)
		)
	)
	(footprint ""
		(layer "F.Cu")
		(at 438.531 -12.954 180)
		(property "Reference" "R1U56"
			(at 0 0 180)
			(layer "F.SilkS")
			(hide yes)
			(effects
				(font
					(size 1.27 1.27)
				)
			)
		)
		(property "Value" ""
			(at 0 0 180)
			(layer "F.Fab")
			(effects
				(font
					(size 1.27 1.27)
				)
			)
		)
		(duplicate_pad_numbers_are_jumpers no)
		(fp_poly
			(pts
				(xy -0.2794 -0.1016) (xy 0.2794 -0.1016) (xy 0.2794 0.9906) (xy -0.2794 0.9906)
			)
			(stroke
				(width 0)
				(type default)
			)
			(fill no)
			(layer "F.CrtYd")
		)
		(fp_line
			(start 0.2794 0.9906)
			(end 0.2794 -0.1016)
			(stroke
				(width 0.1)
				(type default)
			)
			(layer "F.Fab")
		)
		(fp_line
			(start 0.2794 -0.1016)
			(end -0.2794 -0.1016)
			(stroke
				(width 0.1)
				(type default)
			)
			(layer "F.Fab")
		)
		(fp_line
			(start -0.2794 0.9906)
			(end 0.2794 0.9906)
			(stroke
				(width 0.1)
				(type default)
			)
			(layer "F.Fab")
		)
		(fp_line
			(start -0.2794 -0.1016)
			(end -0.2794 0.9906)
			(stroke
				(width 0.1)
				(type default)
			)
			(layer "F.Fab")
		)
		(pad "1" smd rect
			(at 0 0 180)
			(size 0.508 0.508)
			(layers "F.Cu" "F.Mask" "F.Paste")
			(net "H_CPU0_MEMDEF_MEMHOT_G_PCH_N")
		)
		(pad "2" smd rect
			(at 0 0.889 180)
			(size 0.508 0.508)
			(layers "F.Cu" "F.Mask" "F.Paste")
			(net "H_CPU0_MEMDEF_MEMHOT_G_N")
		)
		(zone
			(layer "F.Cu")
			(hatch none 0.5)
			(connect_pads
				(clearance 0)
			)
			(min_thickness 0.25)
			(keepout
				(tracks not_allowed)
				(vias allowed)
				(pads allowed)
				(copperpour not_allowed)
				(footprints allowed)
			)
			(placement
				(enabled no)
				(sheetname "")
			)
			(fill
				(thermal_gap 0.5)
				(thermal_bridge_width 0.5)
				(island_removal_mode 0)
			)
			(polygon
				(pts
					(xy 438.785 -13.589) (xy 438.277 -13.589) (xy 438.277 -13.208) (xy 438.785 -13.208)
				)
			)
		)
		(zone
			(layer "F.Cu")
			(hatch none 0.5)
			(connect_pads
				(clearance 0)
			)
			(min_thickness 0.25)
			(keepout
				(tracks allowed)
				(vias not_allowed)
				(pads allowed)
				(copperpour not_allowed)
				(footprints allowed)
			)
			(placement
				(enabled no)
				(sheetname "")
			)
			(fill
				(thermal_gap 0.5)
				(thermal_bridge_width 0.5)
				(island_removal_mode 0)
			)
			(polygon
				(pts
					(xy 438.785 -13.208) (xy 438.277 -13.208) (xy 438.277 -13.589) (xy 438.785 -13.589)
				)
			)
		)
	)
	(footprint ""
		(layer "F.Cu")
		(at 396.875 -149.0472)
		(property "Reference" "R2L16"
			(at 0 0 0)
			(layer "F.SilkS")
			(hide yes)
			(effects
				(font
					(size 1.27 1.27)
				)
			)
		)
		(property "Value" ""
			(at 0 0 0)
			(layer "F.Fab")
			(effects
				(font
					(size 1.27 1.27)
				)
			)
		)
		(duplicate_pad_numbers_are_jumpers no)
		(fp_poly
			(pts
				(xy -0.2794 -0.1016) (xy 0.2794 -0.1016) (xy 0.2794 0.9906) (xy -0.2794 0.9906)
			)
			(stroke
				(width 0)
				(type default)
			)
			(fill no)
			(layer "F.CrtYd")
		)
		(fp_line
			(start -0.2794 -0.1016)
			(end -0.2794 0.9906)
			(stroke
				(width 0.1)
				(type default)
			)
			(layer "F.Fab")
		)
		(fp_line
			(start -0.2794 0.9906)
			(end 0.2794 0.9906)
			(stroke
				(width 0.1)
				(type default)
			)
			(layer "F.Fab")
		)
		(fp_line
			(start 0.2794 -0.1016)
			(end -0.2794 -0.1016)
			(stroke
				(width 0.1)
				(type default)
			)
			(layer "F.Fab")
		)
		(fp_line
			(start 0.2794 0.9906)
			(end 0.2794 -0.1016)
			(stroke
				(width 0.1)
				(type default)
			)
			(layer "F.Fab")
		)
		(pad "1" smd rect
			(at 0 0)
			(size 0.508 0.508)
			(layers "F.Cu" "F.Mask" "F.Paste")
			(net "PWRGD_PVNN_PCH_R")
		)
		(pad "2" smd rect
			(at 0 0.889)
			(size 0.508 0.508)
			(layers "F.Cu" "F.Mask" "F.Paste")
			(net "PWRGD_PVNN_P1V05_PCH")
		)
		(zone
			(layer "F.Cu")
			(hatch none 0.5)
			(connect_pads
				(clearance 0)
			)
			(min_thickness 0.25)
			(keepout
				(tracks allowed)
				(vias not_allowed)
				(pads allowed)
				(copperpour not_allowed)
				(footprints allowed)
			)
			(placement
				(enabled no)
				(sheetname "")
			)
			(fill
				(thermal_gap 0.5)
				(thermal_bridge_width 0.5)
				(island_removal_mode 0)
			)
			(polygon
				(pts
					(xy 396.621 -148.7932) (xy 397.129 -148.7932) (xy 397.129 -148.4122) (xy 396.621 -148.4122)
				)
			)
		)
		(zone
			(layer "F.Cu")
			(hatch none 0.5)
			(connect_pads
				(clearance 0)
			)
			(min_thickness 0.25)
			(keepout
				(tracks not_allowed)
				(vias allowed)
				(pads allowed)
				(copperpour not_allowed)
				(footprints allowed)
			)
			(placement
				(enabled no)
				(sheetname "")
			)
			(fill
				(thermal_gap 0.5)
				(thermal_bridge_width 0.5)
				(island_removal_mode 0)
			)
			(polygon
				(pts
					(xy 396.621 -148.4122) (xy 397.129 -148.4122) (xy 397.129 -148.7932) (xy 396.621 -148.7932)
				)
			)
		)
	)
	(footprint ""
		(layer "F.Cu")
		(at 2.4003 -114.554 -90)
		(property "Reference" "R10W7"
			(at -0.8382 -0.67818 270)
			(unlocked yes)
			(layer "F.SilkS")
			(effects
				(font
					(size 0.4064 0.254)
					(thickness 0.1524)
				)
				(justify left)
			)
		)
		(property "Value" ""
			(at 0 0 270)
			(layer "F.Fab")
			(effects
				(font
					(size 1.27 1.27)
				)
			)
		)
		(duplicate_pad_numbers_are_jumpers no)
		(fp_poly
			(pts
				(xy -0.2794 -0.1016) (xy 0.2794 -0.1016) (xy 0.2794 0.9906) (xy -0.2794 0.9906)
			)
			(stroke
				(width 0)
				(type default)
			)
			(fill no)
			(layer "F.CrtYd")
		)
		(fp_line
			(start -0.2794 0.9906)
			(end 0.2794 0.9906)
			(stroke
				(width 0.1)
				(type default)
			)
			(layer "F.Fab")
		)
		(fp_line
			(start 0.2794 0.9906)
			(end 0.2794 -0.1016)
			(stroke
				(width 0.1)
				(type default)
			)
			(layer "F.Fab")
		)
		(fp_line
			(start -0.2794 -0.1016)
			(end -0.2794 0.9906)
			(stroke
				(width 0.1)
				(type default)
			)
			(layer "F.Fab")
		)
		(fp_line
			(start 0.2794 -0.1016)
			(end -0.2794 -0.1016)
			(stroke
				(width 0.1)
				(type default)
			)
			(layer "F.Fab")
		)
		(pad "1" smd rect
			(at 0 0 270)
			(size 0.508 0.508)
			(layers "F.Cu" "F.Mask" "F.Paste")
			(net "P3V3_STBY")
		)
		(pad "2" smd rect
			(at 0 0.889 270)
			(size 0.508 0.508)
			(layers "F.Cu" "F.Mask" "F.Paste")
			(net "PUMP_TACH1")
		)
		(zone
			(layer "F.Cu")
			(hatch none 0.5)
			(connect_pads
				(clearance 0)
			)
			(min_thickness 0.25)
			(keepout
				(tracks not_allowed)
				(vias allowed)
				(pads allowed)
				(copperpour not_allowed)
				(footprints allowed)
			)
			(placement
				(enabled no)
				(sheetname "")
			)
			(fill
				(thermal_gap 0.5)
				(thermal_bridge_width 0.5)
				(island_removal_mode 0)
			)
			(polygon
				(pts
					(xy 1.7653 -114.808) (xy 1.7653 -114.3) (xy 2.1463 -114.3) (xy 2.1463 -114.808)
				)
			)
		)
		(zone
			(layer "F.Cu")
			(hatch none 0.5)
			(connect_pads
				(clearance 0)
			)
			(min_thickness 0.25)
			(keepout
				(tracks allowed)
				(vias not_allowed)
				(pads allowed)
				(copperpour not_allowed)
				(footprints allowed)
			)
			(placement
				(enabled no)
				(sheetname "")
			)
			(fill
				(thermal_gap 0.5)
				(thermal_bridge_width 0.5)
				(island_removal_mode 0)
			)
			(polygon
				(pts
					(xy 2.1463 -114.808) (xy 2.1463 -114.3) (xy 1.7653 -114.3) (xy 1.7653 -114.808)
				)
			)
		)
	)
	(footprint ""
		(layer "F.Cu")
		(at 475.2594 -148.9456 180)
		(property "Reference" "R9A9"
			(at 0 0 180)
			(layer "F.SilkS")
			(hide yes)
			(effects
				(font
					(size 1.27 1.27)
				)
			)
		)
		(property "Value" ""
			(at 0 0 180)
			(layer "F.Fab")
			(effects
				(font
					(size 1.27 1.27)
				)
			)
		)
		(duplicate_pad_numbers_are_jumpers no)
		(fp_poly
			(pts
				(xy -0.2794 -0.1016) (xy 0.2794 -0.1016) (xy 0.2794 0.9906) (xy -0.2794 0.9906)
			)
			(stroke
				(width 0)
				(type default)
			)
			(fill no)
			(layer "F.CrtYd")
		)
		(fp_line
			(start 0.2794 0.9906)
			(end 0.2794 -0.1016)
			(stroke
				(width 0.1)
				(type default)
			)
			(layer "F.Fab")
		)
		(fp_line
			(start 0.2794 -0.1016)
			(end -0.2794 -0.1016)
			(stroke
				(width 0.1)
				(type default)
			)
			(layer "F.Fab")
		)
		(fp_line
			(start -0.2794 0.9906)
			(end 0.2794 0.9906)
			(stroke
				(width 0.1)
				(type default)
			)
			(layer "F.Fab")
		)
		(fp_line
			(start -0.2794 -0.1016)
			(end -0.2794 0.9906)
			(stroke
				(width 0.1)
				(type default)
			)
			(layer "F.Fab")
		)
		(pad "1" smd rect
			(at 0 0 180)
			(size 0.508 0.508)
			(layers "F.Cu" "F.Mask" "F.Paste")
			(net "RST_SYSTEM_BTN_BUF_N")
		)
		(pad "2" smd rect
			(at 0 0.889 180)
			(size 0.508 0.508)
			(layers "F.Cu" "F.Mask" "F.Paste")
			(net "RST_SYSTEM_BTN_N")
		)
		(zone
			(layer "F.Cu")
			(hatch none 0.5)
			(connect_pads
				(clearance 0)
			)
			(min_thickness 0.25)
			(keepout
				(tracks not_allowed)
				(vias allowed)
				(pads allowed)
				(copperpour not_allowed)
				(footprints allowed)
			)
			(placement
				(enabled no)
				(sheetname "")
			)
			(fill
				(thermal_gap 0.5)
				(thermal_bridge_width 0.5)
				(island_removal_mode 0)
			)
			(polygon
				(pts
					(xy 475.5134 -149.5806) (xy 475.0054 -149.5806) (xy 475.0054 -149.1996) (xy 475.5134 -149.1996)
				)
			)
		)
		(zone
			(layer "F.Cu")
			(hatch none 0.5)
			(connect_pads
				(clearance 0)
			)
			(min_thickness 0.25)
			(keepout
				(tracks allowed)
				(vias not_allowed)
				(pads allowed)
				(copperpour not_allowed)
				(footprints allowed)
			)
			(placement
				(enabled no)
				(sheetname "")
			)
			(fill
				(thermal_gap 0.5)
				(thermal_bridge_width 0.5)
				(island_removal_mode 0)
			)
			(polygon
				(pts
					(xy 475.5134 -149.1996) (xy 475.0054 -149.1996) (xy 475.0054 -149.5806) (xy 475.5134 -149.5806)
				)
			)
		)
	)
	(footprint ""
		(layer "F.Cu")
		(at 410.997146 -22.996652 90)
		(property "Reference" "C25W9"
			(at -0.8382 -0.67818 90)
			(unlocked yes)
			(layer "F.SilkS")
			(effects
				(font
					(size 0.4064 0.254)
					(thickness 0.1524)
				)
				(justify left)
			)
		)
		(property "Value" ""
			(at 0 0 90)
			(layer "F.Fab")
			(effects
				(font
					(size 1.27 1.27)
				)
			)
		)
		(duplicate_pad_numbers_are_jumpers no)
		(fp_poly
			(pts
				(xy 0.3048 -0.1016) (xy 0.3048 0.9906) (xy -0.3048 0.9906) (xy -0.3048 -0.1016)
			)
			(stroke
				(width 0)
				(type default)
			)
			(fill no)
			(layer "F.CrtYd")
		)
		(fp_line
			(start 0.3048 -0.1016)
			(end -0.3048 -0.1016)
			(stroke
				(width 0.1)
				(type default)
			)
			(layer "F.Fab")
		)
		(fp_line
			(start -0.3048 -0.1016)
			(end -0.3048 0.9906)
			(stroke
				(width 0.1)
				(type default)
			)
			(layer "F.Fab")
		)
		(fp_line
			(start 0.3048 0.9906)
			(end 0.3048 -0.1016)
			(stroke
				(width 0.1)
				(type default)
			)
			(layer "F.Fab")
		)
		(fp_line
			(start -0.3048 0.9906)
			(end 0.3048 0.9906)
			(stroke
				(width 0.1)
				(type default)
			)
			(layer "F.Fab")
		)
		(pad "1" smd rect
			(at 0 0 90)
			(size 0.508 0.508)
			(layers "F.Cu" "F.Mask" "F.Paste")
			(net "P3V3_STBY_BMC_ADCVREFP")
		)
		(pad "2" smd rect
			(at 0 0.889 90)
			(size 0.508 0.508)
			(layers "F.Cu" "F.Mask" "F.Paste")
			(net "P3V3_STBY_BMC_ADCVREFN")
		)
		(zone
			(layer "F.Cu")
			(hatch none 0.5)
			(connect_pads
				(clearance 0)
			)
			(min_thickness 0.25)
			(keepout
				(tracks allowed)
				(vias not_allowed)
				(pads allowed)
				(copperpour not_allowed)
				(footprints allowed)
			)
			(placement
				(enabled no)
				(sheetname "")
			)
			(fill
				(thermal_gap 0.5)
				(thermal_bridge_width 0.5)
				(island_removal_mode 0)
			)
			(polygon
				(pts
					(xy 411.251146 -22.742652) (xy 411.251146 -23.250652) (xy 411.632146 -23.250652) (xy 411.632146 -22.742652)
				)
			)
		)
		(zone
			(layer "F.Cu")
			(hatch none 0.5)
			(connect_pads
				(clearance 0)
			)
			(min_thickness 0.25)
			(keepout
				(tracks not_allowed)
				(vias allowed)
				(pads allowed)
				(copperpour not_allowed)
				(footprints allowed)
			)
			(placement
				(enabled no)
				(sheetname "")
			)
			(fill
				(thermal_gap 0.5)
				(thermal_bridge_width 0.5)
				(island_removal_mode 0)
			)
			(polygon
				(pts
					(xy 411.632146 -22.742652) (xy 411.632146 -23.250652) (xy 411.251146 -23.250652) (xy 411.251146 -22.742652)
				)
			)
		)
	)
	(footprint ""
		(layer "F.Cu")
		(at 385.2164 -50.8508 90)
		(property "Reference" "R8F8"
			(at 0 0 90)
			(layer "F.SilkS")
			(hide yes)
			(effects
				(font
					(size 1.27 1.27)
				)
			)
		)
		(property "Value" ""
			(at 0 0 90)
			(layer "F.Fab")
			(effects
				(font
					(size 1.27 1.27)
				)
			)
		)
		(duplicate_pad_numbers_are_jumpers no)
		(fp_poly
			(pts
				(xy -0.2794 -0.1016) (xy 0.2794 -0.1016) (xy 0.2794 0.9906) (xy -0.2794 0.9906)
			)
			(stroke
				(width 0)
				(type default)
			)
			(fill no)
			(layer "F.CrtYd")
		)
		(fp_line
			(start 0.2794 -0.1016)
			(end -0.2794 -0.1016)
			(stroke
				(width 0.1)
				(type default)
			)
			(layer "F.Fab")
		)
		(fp_line
			(start -0.2794 -0.1016)
			(end -0.2794 0.9906)
			(stroke
				(width 0.1)
				(type default)
			)
			(layer "F.Fab")
		)
		(fp_line
			(start 0.2794 0.9906)
			(end 0.2794 -0.1016)
			(stroke
				(width 0.1)
				(type default)
			)
			(layer "F.Fab")
		)
		(fp_line
			(start -0.2794 0.9906)
			(end 0.2794 0.9906)
			(stroke
				(width 0.1)
				(type default)
			)
			(layer "F.Fab")
		)
		(pad "1" smd rect
			(at 0 0 90)
			(size 0.508 0.508)
			(layers "F.Cu" "F.Mask" "F.Paste")
			(net "SPI_SWITCH_CLK")
		)
		(pad "2" smd rect
			(at 0 0.889 90)
			(size 0.508 0.508)
			(layers "F.Cu" "F.Mask" "F.Paste")
			(net "SPI_CLK_R0")
		)
		(zone
			(layer "F.Cu")
			(hatch none 0.5)
			(connect_pads
				(clearance 0)
			)
			(min_thickness 0.25)
			(keepout
				(tracks allowed)
				(vias not_allowed)
				(pads allowed)
				(copperpour not_allowed)
				(footprints allowed)
			)
			(placement
				(enabled no)
				(sheetname "")
			)
			(fill
				(thermal_gap 0.5)
				(thermal_bridge_width 0.5)
				(island_removal_mode 0)
			)
			(polygon
				(pts
					(xy 385.4704 -50.5968) (xy 385.4704 -51.1048) (xy 385.8514 -51.1048) (xy 385.8514 -50.5968)
				)
			)
		)
		(zone
			(layer "F.Cu")
			(hatch none 0.5)
			(connect_pads
				(clearance 0)
			)
			(min_thickness 0.25)
			(keepout
				(tracks not_allowed)
				(vias allowed)
				(pads allowed)
				(copperpour not_allowed)
				(footprints allowed)
			)
			(placement
				(enabled no)
				(sheetname "")
			)
			(fill
				(thermal_gap 0.5)
				(thermal_bridge_width 0.5)
				(island_removal_mode 0)
			)
			(polygon
				(pts
					(xy 385.8514 -50.5968) (xy 385.8514 -51.1048) (xy 385.4704 -51.1048) (xy 385.4704 -50.5968)
				)
			)
		)
	)
	(footprint ""
		(layer "F.Cu")
		(at 318.543432 -140.208 -90)
		(property "Reference" "C6A6"
			(at 0 0 270)
			(layer "F.SilkS")
			(hide yes)
			(effects
				(font
					(size 1.27 1.27)
				)
			)
		)
		(property "Value" ""
			(at 0 0 270)
			(layer "F.Fab")
			(effects
				(font
					(size 1.27 1.27)
				)
			)
		)
		(duplicate_pad_numbers_are_jumpers no)
		(fp_poly
			(pts
				(xy -0.4953 -0.2032) (xy 0.4953 -0.2032) (xy 0.4953 1.6002) (xy -0.4953 1.6002)
			)
			(stroke
				(width 0)
				(type default)
			)
			(fill no)
			(layer "F.CrtYd")
		)
		(fp_line
			(start -0.4953 1.6002)
			(end -0.4953 -0.2032)
			(stroke
				(width 0.1)
				(type default)
			)
			(layer "F.Fab")
		)
		(fp_line
			(start 0.4953 1.6002)
			(end -0.4953 1.6002)
			(stroke
				(width 0.1)
				(type default)
			)
			(layer "F.Fab")
		)
		(fp_line
			(start -0.4953 -0.2032)
			(end 0.4953 -0.2032)
			(stroke
				(width 0.1)
				(type default)
			)
			(layer "F.Fab")
		)
		(fp_line
			(start 0.4953 -0.2032)
			(end 0.4953 1.6002)
			(stroke
				(width 0.1)
				(type default)
			)
			(layer "F.Fab")
		)
		(pad "1" smd rect
			(at 0 0 270)
			(size 0.762 0.889)
			(layers "F.Cu" "F.Mask" "F.Paste")
			(net "PVPP_DEF")
		)
		(pad "2" smd rect
			(at 0 1.397 270)
			(size 0.762 0.889)
			(layers "F.Cu" "F.Mask" "F.Paste")
			(net "GND")
		)
		(zone
			(layer "F.Cu")
			(hatch none 0.5)
			(connect_pads
				(clearance 0)
			)
			(min_thickness 0.25)
			(keepout
				(tracks not_allowed)
				(vias allowed)
				(pads allowed)
				(copperpour not_allowed)
				(footprints allowed)
			)
			(placement
				(enabled no)
				(sheetname "")
			)
			(fill
				(thermal_gap 0.5)
				(thermal_bridge_width 0.5)
				(island_removal_mode 0)
			)
			(polygon
				(pts
					(xy 318.098932 -140.589) (xy 318.098932 -139.827) (xy 317.590932 -139.827) (xy 317.590932 -140.589)
				)
			)
		)
	)
	(footprint ""
		(layer "F.Cu")
		(at 369.7224 -130.429 180)
		(property "Reference" "C7B22"
			(at 0 0 180)
			(layer "F.SilkS")
			(hide yes)
			(effects
				(font
					(size 1.27 1.27)
				)
			)
		)
		(property "Value" ""
			(at 0 0 180)
			(layer "F.Fab")
			(effects
				(font
					(size 1.27 1.27)
				)
			)
		)
		(duplicate_pad_numbers_are_jumpers no)
		(fp_poly
			(pts
				(xy -0.4953 -0.2032) (xy 0.4953 -0.2032) (xy 0.4953 1.6002) (xy -0.4953 1.6002)
			)
			(stroke
				(width 0)
				(type default)
			)
			(fill no)
			(layer "F.CrtYd")
		)
		(fp_line
			(start 0.4953 1.6002)
			(end -0.4953 1.6002)
			(stroke
				(width 0.1)
				(type default)
			)
			(layer "F.Fab")
		)
		(fp_line
			(start 0.4953 -0.2032)
			(end 0.4953 1.6002)
			(stroke
				(width 0.1)
				(type default)
			)
			(layer "F.Fab")
		)
		(fp_line
			(start -0.4953 1.6002)
			(end -0.4953 -0.2032)
			(stroke
				(width 0.1)
				(type default)
			)
			(layer "F.Fab")
		)
		(fp_line
			(start -0.4953 -0.2032)
			(end 0.4953 -0.2032)
			(stroke
				(width 0.1)
				(type default)
			)
			(layer "F.Fab")
		)
		(pad "1" smd rect
			(at 0 0 180)
			(size 0.762 0.889)
			(layers "F.Cu" "F.Mask" "F.Paste")
			(net "P1V05_PCH_STBY")
		)
		(pad "2" smd rect
			(at 0 1.397 180)
			(size 0.762 0.889)
			(layers "F.Cu" "F.Mask" "F.Paste")
			(net "GND")
		)
		(zone
			(layer "F.Cu")
			(hatch none 0.5)
			(connect_pads
				(clearance 0)
			)
			(min_thickness 0.25)
			(keepout
				(tracks not_allowed)
				(vias allowed)
				(pads allowed)
				(copperpour not_allowed)
				(footprints allowed)
			)
			(placement
				(enabled no)
				(sheetname "")
			)
			(fill
				(thermal_gap 0.5)
				(thermal_bridge_width 0.5)
				(island_removal_mode 0)
			)
			(polygon
				(pts
					(xy 370.1034 -130.8735) (xy 369.3414 -130.8735) (xy 369.3414 -131.3815) (xy 370.1034 -131.3815)
				)
			)
		)
	)
	(footprint ""
		(layer "F.Cu")
		(at 352.153982 -95.497904 -90)
		(property "Reference" "C7C14"
			(at 0 0 270)
			(layer "F.SilkS")
			(hide yes)
			(effects
				(font
					(size 1.27 1.27)
				)
			)
		)
		(property "Value" ""
			(at 0 0 270)
			(layer "F.Fab")
			(effects
				(font
					(size 1.27 1.27)
				)
			)
		)
		(duplicate_pad_numbers_are_jumpers no)
		(fp_poly
			(pts
				(xy 0.3048 -0.1016) (xy 0.3048 0.9906) (xy -0.3048 0.9906) (xy -0.3048 -0.1016)
			)
			(stroke
				(width 0)
				(type default)
			)
			(fill no)
			(layer "F.CrtYd")
		)
		(fp_line
			(start -0.3048 0.9906)
			(end 0.3048 0.9906)
			(stroke
				(width 0.1)
				(type default)
			)
			(layer "F.Fab")
		)
		(fp_line
			(start 0.3048 0.9906)
			(end 0.3048 -0.1016)
			(stroke
				(width 0.1)
				(type default)
			)
			(layer "F.Fab")
		)
		(fp_line
			(start -0.3048 -0.1016)
			(end -0.3048 0.9906)
			(stroke
				(width 0.1)
				(type default)
			)
			(layer "F.Fab")
		)
		(fp_line
			(start 0.3048 -0.1016)
			(end -0.3048 -0.1016)
			(stroke
				(width 0.1)
				(type default)
			)
			(layer "F.Fab")
		)
		(pad "1" smd rect
			(at 0 0 270)
			(size 0.508 0.508)
			(layers "F.Cu" "F.Mask" "F.Paste")
			(net "VR_PVCCIO_CPU0_PH1_BOOT")
		)
		(pad "2" smd rect
			(at 0 0.889 270)
			(size 0.508 0.508)
			(layers "F.Cu" "F.Mask" "F.Paste")
			(net "VR_PVCCIO_CPU0_PH1_PHASE")
		)
		(zone
			(layer "F.Cu")
			(hatch none 0.5)
			(connect_pads
				(clearance 0)
			)
			(min_thickness 0.25)
			(keepout
				(tracks not_allowed)
				(vias allowed)
				(pads allowed)
				(copperpour not_allowed)
				(footprints allowed)
			)
			(placement
				(enabled no)
				(sheetname "")
			)
			(fill
				(thermal_gap 0.5)
				(thermal_bridge_width 0.5)
				(island_removal_mode 0)
			)
			(polygon
				(pts
					(xy 351.518982 -95.751904) (xy 351.518982 -95.243904) (xy 351.899982 -95.243904) (xy 351.899982 -95.751904)
				)
			)
		)
		(zone
			(layer "F.Cu")
			(hatch none 0.5)
			(connect_pads
				(clearance 0)
			)
			(min_thickness 0.25)
			(keepout
				(tracks allowed)
				(vias not_allowed)
				(pads allowed)
				(copperpour not_allowed)
				(footprints allowed)
			)
			(placement
				(enabled no)
				(sheetname "")
			)
			(fill
				(thermal_gap 0.5)
				(thermal_bridge_width 0.5)
				(island_removal_mode 0)
			)
			(polygon
				(pts
					(xy 351.899982 -95.751904) (xy 351.899982 -95.243904) (xy 351.518982 -95.243904) (xy 351.518982 -95.751904)
				)
			)
		)
	)
	(footprint ""
		(layer "F.Cu")
		(at 194.564 -2.8575 180)
		(property "Reference" "R4G22"
			(at 0 0 180)
			(layer "F.SilkS")
			(hide yes)
			(effects
				(font
					(size 1.27 1.27)
				)
			)
		)
		(property "Value" ""
			(at 0 0 180)
			(layer "F.Fab")
			(effects
				(font
					(size 1.27 1.27)
				)
			)
		)
		(duplicate_pad_numbers_are_jumpers no)
		(fp_poly
			(pts
				(xy -0.2794 -0.1016) (xy 0.2794 -0.1016) (xy 0.2794 0.9906) (xy -0.2794 0.9906)
			)
			(stroke
				(width 0)
				(type default)
			)
			(fill no)
			(layer "F.CrtYd")
		)
		(fp_line
			(start 0.2794 0.9906)
			(end 0.2794 -0.1016)
			(stroke
				(width 0.1)
				(type default)
			)
			(layer "F.Fab")
		)
		(fp_line
			(start 0.2794 -0.1016)
			(end -0.2794 -0.1016)
			(stroke
				(width 0.1)
				(type default)
			)
			(layer "F.Fab")
		)
		(fp_line
			(start -0.2794 0.9906)
			(end 0.2794 0.9906)
			(stroke
				(width 0.1)
				(type default)
			)
			(layer "F.Fab")
		)
		(fp_line
			(start -0.2794 -0.1016)
			(end -0.2794 0.9906)
			(stroke
				(width 0.1)
				(type default)
			)
			(layer "F.Fab")
		)
		(pad "1" smd rect
			(at 0 0 180)
			(size 0.508 0.508)
			(layers "F.Cu" "F.Mask" "F.Paste")
			(net "M_C_VREF")
		)
		(pad "2" smd rect
			(at 0 0.889 180)
			(size 0.508 0.508)
			(layers "F.Cu" "F.Mask" "F.Paste")
			(net "GND")
		)
		(zone
			(layer "F.Cu")
			(hatch none 0.5)
			(connect_pads
				(clearance 0)
			)
			(min_thickness 0.25)
			(keepout
				(tracks not_allowed)
				(vias allowed)
				(pads allowed)
				(copperpour not_allowed)
				(footprints allowed)
			)
			(placement
				(enabled no)
				(sheetname "")
			)
			(fill
				(thermal_gap 0.5)
				(thermal_bridge_width 0.5)
				(island_removal_mode 0)
			)
			(polygon
				(pts
					(xy 194.818 -3.4925) (xy 194.31 -3.4925) (xy 194.31 -3.1115) (xy 194.818 -3.1115)
				)
			)
		)
		(zone
			(layer "F.Cu")
			(hatch none 0.5)
			(connect_pads
				(clearance 0)
			)
			(min_thickness 0.25)
			(keepout
				(tracks allowed)
				(vias not_allowed)
				(pads allowed)
				(copperpour not_allowed)
				(footprints allowed)
			)
			(placement
				(enabled no)
				(sheetname "")
			)
			(fill
				(thermal_gap 0.5)
				(thermal_bridge_width 0.5)
				(island_removal_mode 0)
			)
			(polygon
				(pts
					(xy 194.818 -3.1115) (xy 194.31 -3.1115) (xy 194.31 -3.4925) (xy 194.818 -3.4925)
				)
			)
		)
	)
	(footprint ""
		(layer "F.Cu")
		(at 382.002284 -56.32958 90)
		(property "Reference" "R7F37"
			(at 0 0 90)
			(layer "F.SilkS")
			(hide yes)
			(effects
				(font
					(size 1.27 1.27)
				)
			)
		)
		(property "Value" ""
			(at 0 0 90)
			(layer "F.Fab")
			(effects
				(font
					(size 1.27 1.27)
				)
			)
		)
		(duplicate_pad_numbers_are_jumpers no)
		(fp_poly
			(pts
				(xy -0.2794 -0.1016) (xy 0.2794 -0.1016) (xy 0.2794 0.9906) (xy -0.2794 0.9906)
			)
			(stroke
				(width 0)
				(type default)
			)
			(fill no)
			(layer "F.CrtYd")
		)
		(fp_line
			(start 0.2794 -0.1016)
			(end -0.2794 -0.1016)
			(stroke
				(width 0.1)
				(type default)
			)
			(layer "F.Fab")
		)
		(fp_line
			(start -0.2794 -0.1016)
			(end -0.2794 0.9906)
			(stroke
				(width 0.1)
				(type default)
			)
			(layer "F.Fab")
		)
		(fp_line
			(start 0.2794 0.9906)
			(end 0.2794 -0.1016)
			(stroke
				(width 0.1)
				(type default)
			)
			(layer "F.Fab")
		)
		(fp_line
			(start -0.2794 0.9906)
			(end 0.2794 0.9906)
			(stroke
				(width 0.1)
				(type default)
			)
			(layer "F.Fab")
		)
		(pad "1" smd rect
			(at 0 0 90)
			(size 0.508 0.508)
			(layers "F.Cu" "F.Mask" "F.Paste")
			(net "SPI_BIOS_SOCKET_IO2")
		)
		(pad "2" smd rect
			(at 0 0.889 90)
			(size 0.508 0.508)
			(layers "F.Cu" "F.Mask" "F.Paste")
			(net "PU_BIOS_SPI_WP0_N")
		)
		(zone
			(layer "F.Cu")
			(hatch none 0.5)
			(connect_pads
				(clearance 0)
			)
			(min_thickness 0.25)
			(keepout
				(tracks allowed)
				(vias not_allowed)
				(pads allowed)
				(copperpour not_allowed)
				(footprints allowed)
			)
			(placement
				(enabled no)
				(sheetname "")
			)
			(fill
				(thermal_gap 0.5)
				(thermal_bridge_width 0.5)
				(island_removal_mode 0)
			)
			(polygon
				(pts
					(xy 382.256284 -56.07558) (xy 382.256284 -56.58358) (xy 382.637284 -56.58358) (xy 382.637284 -56.07558)
				)
			)
		)
		(zone
			(layer "F.Cu")
			(hatch none 0.5)
			(connect_pads
				(clearance 0)
			)
			(min_thickness 0.25)
			(keepout
				(tracks not_allowed)
				(vias allowed)
				(pads allowed)
				(copperpour not_allowed)
				(footprints allowed)
			)
			(placement
				(enabled no)
				(sheetname "")
			)
			(fill
				(thermal_gap 0.5)
				(thermal_bridge_width 0.5)
				(island_removal_mode 0)
			)
			(polygon
				(pts
					(xy 382.637284 -56.07558) (xy 382.637284 -56.58358) (xy 382.256284 -56.58358) (xy 382.256284 -56.07558)
				)
			)
		)
	)
	(footprint ""
		(layer "F.Cu")
		(at 351.505266 -156.4005 180)
		(property "Reference" "CT45"
			(at 0.7366 1.85293 0)
			(unlocked yes)
			(layer "F.SilkS")
			(effects
				(font
					(size 0.7874 0.5842)
					(thickness 0.1524)
				)
				(justify left)
			)
		)
		(property "Value" ""
			(at 0 0 180)
			(layer "F.Fab")
			(effects
				(font
					(size 1.27 1.27)
				)
			)
		)
		(duplicate_pad_numbers_are_jumpers no)
		(fp_poly
			(pts
				(xy 0.3048 -0.1016) (xy 0.3048 0.9906) (xy -0.3048 0.9906) (xy -0.3048 -0.1016)
			)
			(stroke
				(width 0)
				(type default)
			)
			(fill no)
			(layer "F.CrtYd")
		)
		(fp_line
			(start 0.3048 0.9906)
			(end 0.3048 -0.1016)
			(stroke
				(width 0.1)
				(type default)
			)
			(layer "F.Fab")
		)
		(fp_line
			(start 0.3048 -0.1016)
			(end -0.3048 -0.1016)
			(stroke
				(width 0.1)
				(type default)
			)
			(layer "F.Fab")
		)
		(fp_line
			(start -0.3048 0.9906)
			(end 0.3048 0.9906)
			(stroke
				(width 0.1)
				(type default)
			)
			(layer "F.Fab")
		)
		(fp_line
			(start -0.3048 -0.1016)
			(end -0.3048 0.9906)
			(stroke
				(width 0.1)
				(type default)
			)
			(layer "F.Fab")
		)
		(pad "1" smd rect
			(at 0 0 180)
			(size 0.508 0.508)
			(layers "F.Cu" "F.Mask" "F.Paste")
			(net "VR_PVDDQ_DEF_AIREF1")
		)
		(pad "2" smd rect
			(at 0 0.889 180)
			(size 0.508 0.508)
			(layers "F.Cu" "F.Mask" "F.Paste")
			(net "GND")
		)
		(zone
			(layer "F.Cu")
			(hatch none 0.5)
			(connect_pads
				(clearance 0)
			)
			(min_thickness 0.25)
			(keepout
				(tracks not_allowed)
				(vias allowed)
				(pads allowed)
				(copperpour not_allowed)
				(footprints allowed)
			)
			(placement
				(enabled no)
				(sheetname "")
			)
			(fill
				(thermal_gap 0.5)
				(thermal_bridge_width 0.5)
				(island_removal_mode 0)
			)
			(polygon
				(pts
					(xy 351.759266 -157.0355) (xy 351.251266 -157.0355) (xy 351.251266 -156.6545) (xy 351.759266 -156.6545)
				)
			)
		)
		(zone
			(layer "F.Cu")
			(hatch none 0.5)
			(connect_pads
				(clearance 0)
			)
			(min_thickness 0.25)
			(keepout
				(tracks allowed)
				(vias not_allowed)
				(pads allowed)
				(copperpour not_allowed)
				(footprints allowed)
			)
			(placement
				(enabled no)
				(sheetname "")
			)
			(fill
				(thermal_gap 0.5)
				(thermal_bridge_width 0.5)
				(island_removal_mode 0)
			)
			(polygon
				(pts
					(xy 351.759266 -156.6545) (xy 351.251266 -156.6545) (xy 351.251266 -157.0355) (xy 351.759266 -157.0355)
				)
			)
		)
	)
	(footprint ""
		(layer "F.Cu")
		(at 481.251006 -131.655312 90)
		(property "Reference" "J9B1"
			(at -2.522728 5.79501 0)
			(unlocked yes)
			(layer "B.SilkS")
			(effects
				(font
					(size 0.7874 0.5842)
					(thickness 0.1524)
				)
				(justify left mirror)
			)
		)
		(property "Value" ""
			(at 0 0 90)
			(layer "F.Fab")
			(effects
				(font
					(size 1.27 1.27)
				)
			)
		)
		(duplicate_pad_numbers_are_jumpers no)
		(fp_line
			(start 4.234942 -3.97002)
			(end 4.234942 -3.299968)
			(stroke
				(width 0.1524)
				(type default)
			)
			(layer "F.SilkS")
		)
		(fp_line
			(start -2.435098 -3.97002)
			(end 4.234942 -3.97002)
			(stroke
				(width 0.1524)
				(type default)
			)
			(layer "F.SilkS")
		)
		(fp_line
			(start -2.435098 -3.299968)
			(end -2.435098 -3.97002)
			(stroke
				(width 0.1524)
				(type default)
			)
			(layer "F.SilkS")
		)
		(fp_line
			(start 4.234942 -0.299974)
			(end 4.234942 6.75005)
			(stroke
				(width 0.1524)
				(type default)
			)
			(layer "F.SilkS")
		)
		(fp_line
			(start -2.435098 6.75005)
			(end -2.435098 -0.299974)
			(stroke
				(width 0.1524)
				(type default)
			)
			(layer "F.SilkS")
		)
		(fp_line
			(start -2.435098 10.500106)
			(end -2.435098 21.100034)
			(stroke
				(width 0.1524)
				(type default)
			)
			(layer "F.SilkS")
		)
		(fp_line
			(start 4.234942 21.100034)
			(end 4.234942 10.500106)
			(stroke
				(width 0.1524)
				(type default)
			)
			(layer "F.SilkS")
		)
		(fp_poly
			(pts
				(xy -3.922776 -0.556514) (xy -3.922776 0.459486) (xy -2.652776 -0.048514)
			)
			(stroke
				(width 0)
				(type default)
			)
			(fill yes)
			(layer "F.SilkS")
		)
		(fp_poly
			(pts
				(xy -4.303776 -0.556514) (xy -4.303776 0.459486) (xy -3.033776 -0.048514)
			)
			(stroke
				(width 0)
				(type default)
			)
			(fill yes)
			(layer "B.SilkS")
		)
		(fp_rect
			(start -2.435098 22.029928)
			(end 4.234942 -3.97002)
			(stroke
				(width 0)
				(type default)
			)
			(fill no)
			(layer "F.CrtYd")
		)
		(fp_poly
			(pts
				(xy -4.303776 -0.556514) (xy -4.303776 0.459486) (xy -3.033776 -0.048514)
			)
			(stroke
				(width 0)
				(type default)
			)
			(fill yes)
			(layer "B.Fab")
		)
		(fp_line
			(start 4.234942 -3.97002)
			(end -2.435098 -3.97002)
			(stroke
				(width 0.1)
				(type default)
			)
			(layer "F.Fab")
		)
		(fp_line
			(start -2.435098 -3.97002)
			(end -2.435098 22.029928)
			(stroke
				(width 0.1)
				(type default)
			)
			(layer "F.Fab")
		)
		(fp_line
			(start 4.234942 22.029928)
			(end 4.234942 -3.97002)
			(stroke
				(width 0.1)
				(type default)
			)
			(layer "F.Fab")
		)
		(fp_line
			(start -2.435098 22.029928)
			(end 4.234942 22.029928)
			(stroke
				(width 0.1)
				(type default)
			)
			(layer "F.Fab")
		)
		(fp_poly
			(pts
				(xy -4.303776 -0.556514) (xy -4.303776 0.459486) (xy -3.033776 -0.048514)
			)
			(stroke
				(width 0)
				(type default)
			)
			(fill yes)
			(layer "F.Fab")
		)
		(fp_text user "9"
			(at 1.18364 -4.63423 0)
			(unlocked yes)
			(layer "F.SilkS")
			(effects
				(font
					(size 0.7874 0.5842)
					(thickness 0.1524)
				)
				(justify left)
			)
		)
		(fp_text user "4"
			(at -3.109468 4.33705 0)
			(unlocked yes)
			(layer "F.SilkS")
			(effects
				(font
					(size 0.7874 0.5842)
					(thickness 0.1524)
				)
				(justify left)
			)
		)
		(fp_text user "5"
			(at 4.335018 7.315454 0)
			(unlocked yes)
			(layer "F.SilkS")
			(effects
				(font
					(size 0.7874 0.5842)
					(thickness 0.1524)
				)
				(justify left)
			)
		)
		(fp_text user "9"
			(at 3.319272 0.33401 0)
			(unlocked yes)
			(layer "B.SilkS")
			(effects
				(font
					(size 0.7874 0.5842)
					(thickness 0.1524)
				)
				(justify left mirror)
			)
		)
		(fp_text user " 4"
			(at -2.251964 6.809994 0)
			(unlocked yes)
			(layer "B.SilkS")
			(effects
				(font
					(size 0.7874 0.5842)
					(thickness 0.1524)
				)
				(justify left mirror)
			)
		)
		(fp_text user "5"
			(at 3.565398 7.61111 0)
			(unlocked yes)
			(layer "B.SilkS")
			(effects
				(font
					(size 0.7874 0.5842)
					(thickness 0.1524)
				)
				(justify left mirror)
			)
		)
		(fp_text user "9"
			(at 5.343144 -0.38608 90)
			(unlocked yes)
			(layer "B.Fab")
			(effects
				(font
					(size 0.635 0.635)
					(thickness 0.1524)
				)
				(justify left mirror)
			)
		)
		(fp_text user "4"
			(at -2.783332 7.02056 90)
			(unlocked yes)
			(layer "B.Fab")
			(effects
				(font
					(size 0.7874 0.5842)
					(thickness 0.1524)
				)
				(justify left mirror)
			)
		)
		(fp_text user "5"
			(at 5.291074 7.411212 90)
			(unlocked yes)
			(layer "B.Fab")
			(effects
				(font
					(size 0.7874 0.5842)
					(thickness 0.1524)
				)
				(justify left mirror)
			)
		)
		(fp_text user "9"
			(at 4.57327 -2.42316 90)
			(unlocked yes)
			(layer "F.Fab")
			(effects
				(font
					(size 0.7874 0.5842)
					(thickness 0.1524)
				)
				(justify left)
			)
		)
		(fp_text user "4"
			(at -3.105658 4.33832 0)
			(unlocked yes)
			(layer "F.Fab")
			(effects
				(font
					(size 0.7874 0.5842)
					(thickness 0.1524)
				)
				(justify left)
			)
		)
		(fp_text user "5"
			(at 4.882388 10.311384 0)
			(unlocked yes)
			(layer "F.Fab")
			(effects
				(font
					(size 0.7874 0.5842)
					(thickness 0.1524)
				)
				(justify left)
			)
		)
		(pad "1" thru_hole rect
			(at 0 0 90)
			(size 1.143 1.143)
			(drill 0.762)
			(layers "*.Cu" "*.Mask")
			(remove_unused_layers no)
			(net "P5V_USB")
			(clearance 0.127)
			(thermal_gap 0.127)
			(padstack
				(mode front_inner_back)
				(layer "Inner"
					(shape circle)
					(size 1.143 1.143)
					(clearance 0.127)
				)
				(layer "B.Cu"
					(shape rect)
					(size 1.143 1.143)
					(clearance 0.127)
				)
			)
		)
		(pad "2" thru_hole circle
			(at 0 2.500122 90)
			(size 1.143 1.143)
			(drill 0.762)
			(layers "*.Cu" "*.Mask")
			(remove_unused_layers no)
			(net "USB2_P01_ESD_DN")
			(clearance 0.127)
			(thermal_gap 0.127)
		)
		(pad "3" thru_hole circle
			(at 0 4.500118 90)
			(size 1.143 1.143)
			(drill 0.762)
			(layers "*.Cu" "*.Mask")
			(remove_unused_layers no)
			(net "USB2_P01_ESD_DP")
			(clearance 0.127)
			(thermal_gap 0.127)
		)
		(pad "4" thru_hole circle
			(at 0 6.999986 90)
			(size 1.143 1.143)
			(drill 0.762)
			(layers "*.Cu" "*.Mask")
			(remove_unused_layers no)
			(net "GND")
			(clearance 0.127)
			(thermal_gap 0.127)
		)
		(pad "5" thru_hole circle
			(at 1.800098 7.500112 90)
			(size 1.143 1.143)
			(drill 0.762)
			(layers "*.Cu" "*.Mask")
			(remove_unused_layers no)
			(net "SMB_DEBUG_STBY_LVC3_SCL_CONN")
			(clearance 0.127)
			(thermal_gap 0.127)
		)
		(pad "6" thru_hole circle
			(at 1.800098 5.500116 90)
			(size 1.143 1.143)
			(drill 0.762)
			(layers "*.Cu" "*.Mask")
			(remove_unused_layers no)
			(net "SMB_DEBUG_STBY_LVC3_SDA_CONN")
			(clearance 0.127)
			(thermal_gap 0.127)
		)
		(pad "7" thru_hole circle
			(at 1.800098 3.50012 90)
			(size 1.143 1.143)
			(drill 0.762)
			(layers "*.Cu" "*.Mask")
			(remove_unused_layers no)
			(net "DEBUG_CARD2_PRSNT")
			(clearance 0.127)
			(thermal_gap 0.127)
		)
		(pad "8" thru_hole circle
			(at 1.800098 1.500124 90)
			(size 1.143 1.143)
			(drill 0.762)
			(layers "*.Cu" "*.Mask")
			(remove_unused_layers no)
			(net "SPA_MID_DBG2_TX")
			(clearance 0.127)
			(thermal_gap 0.127)
		)
		(pad "9" thru_hole circle
			(at 1.800098 -0.500126 90)
			(size 1.143 1.143)
			(drill 0.762)
			(layers "*.Cu" "*.Mask")
			(remove_unused_layers no)
			(net "SPA_MID_DBG2_RX")
			(clearance 0.127)
			(thermal_gap 0.127)
		)
		(pad "MH1" thru_hole oval
			(at -1.810004 -1.869948 90)
			(size 1.1684 1.778)
			(drill oval 0.7874 1.397)
			(layers "*.Cu" "*.Mask")
			(remove_unused_layers no)
			(net "GND")
			(clearance 0.127)
			(thermal_gap 0.127)
		)
		(pad "MH2" thru_hole oval
			(at -1.810004 8.830056 90)
			(size 1.1684 2.4892)
			(drill oval 0.7874 2.1082)
			(layers "*.Cu" "*.Mask")
			(remove_unused_layers no)
			(net "GND")
			(clearance 0.127)
			(thermal_gap 0.127)
		)
		(pad "MH3" thru_hole oval
			(at 3.610102 8.830056 90)
			(size 1.1684 1.778)
			(drill oval 0.7874 1.397)
			(layers "*.Cu" "*.Mask")
			(remove_unused_layers no)
			(net "GND")
			(clearance 0.127)
			(thermal_gap 0.127)
		)
		(pad "MH4" thru_hole oval
			(at 3.610102 -1.869948 90)
			(size 1.1684 2.4892)
			(drill oval 0.7874 2.1082)
			(layers "*.Cu" "*.Mask")
			(remove_unused_layers no)
			(net "GND")
			(clearance 0.127)
			(thermal_gap 0.127)
		)
		(zone
			(layer "F.Cu")
			(hatch none 0.5)
			(connect_pads
				(clearance 0)
			)
			(min_thickness 0.25)
			(keepout
				(tracks not_allowed)
				(vias allowed)
				(pads allowed)
				(copperpour not_allowed)
				(footprints allowed)
			)
			(placement
				(enabled no)
				(sheetname "")
			)
			(fill
				(thermal_gap 0.5)
				(thermal_bridge_width 0.5)
				(island_removal_mode 0)
			)
			(polygon
				(pts
					(xy 479.580956 -130.555238) (xy 479.580956 -134.55523) (xy 477.58096 -134.55523) (xy 477.58096 -130.555238)
				)
			)
		)
		(zone
			(layer "F.Cu")
			(hatch none 0.5)
			(connect_pads
				(clearance 0)
			)
			(min_thickness 0.25)
			(keepout
				(tracks not_allowed)
				(vias allowed)
				(pads allowed)
				(copperpour not_allowed)
				(footprints allowed)
			)
			(placement
				(enabled no)
				(sheetname "")
			)
			(fill
				(thermal_gap 0.5)
				(thermal_bridge_width 0.5)
				(island_removal_mode 0)
			)
			(polygon
				(pts
					(xy 496.031012 -129.55524) (xy 496.031012 -135.555228) (xy 491.63097 -135.555228) (xy 491.63097 -134.40537)
					(xy 489.630974 -134.40537) (xy 489.630974 -130.705352) (xy 491.63097 -130.705352) (xy 491.63097 -129.55524)
				)
			)
		)
	)
	(footprint ""
		(layer "F.Cu")
		(at 183.167274 -10.91057 90)
		(property "Reference" "C6U8"
			(at 1.47828 0.78994 0)
			(unlocked yes)
			(layer "F.SilkS")
			(effects
				(font
					(size 0.4064 0.254)
					(thickness 0.1524)
				)
			)
		)
		(property "Value" ""
			(at 0 0 90)
			(layer "F.Fab")
			(effects
				(font
					(size 1.27 1.27)
				)
			)
		)
		(duplicate_pad_numbers_are_jumpers no)
		(fp_poly
			(pts
				(xy -0.7239 -0.2159) (xy 0.7239 -0.2159) (xy 0.7239 1.9939) (xy -0.7239 1.9939)
			)
			(stroke
				(width 0)
				(type default)
			)
			(fill no)
			(layer "F.CrtYd")
		)
		(fp_line
			(start 0.7239 -0.2159)
			(end -0.7239 -0.2159)
			(stroke
				(width 0.1)
				(type default)
			)
			(layer "F.Fab")
		)
		(fp_line
			(start -0.7239 -0.2159)
			(end -0.7239 1.9939)
			(stroke
				(width 0.1)
				(type default)
			)
			(layer "F.Fab")
		)
		(fp_line
			(start 0.7239 1.9939)
			(end 0.7239 -0.2159)
			(stroke
				(width 0.1)
				(type default)
			)
			(layer "F.Fab")
		)
		(fp_line
			(start -0.7239 1.9939)
			(end 0.7239 1.9939)
			(stroke
				(width 0.1)
				(type default)
			)
			(layer "F.Fab")
		)
		(pad "1" smd rect
			(at 0 0 90)
			(size 1.27 1.016)
			(layers "F.Cu" "F.Mask" "F.Paste")
			(net "VR_FET_SW_P12V_STBY_PVPP_GHJ")
		)
		(pad "2" smd rect
			(at 0 1.778 90)
			(size 1.27 1.016)
			(layers "F.Cu" "F.Mask" "F.Paste")
			(net "GND")
		)
		(zone
			(layer "F.Cu")
			(hatch none 0.5)
			(connect_pads
				(clearance 0)
			)
			(min_thickness 0.25)
			(keepout
				(tracks not_allowed)
				(vias allowed)
				(pads allowed)
				(copperpour not_allowed)
				(footprints allowed)
			)
			(placement
				(enabled no)
				(sheetname "")
			)
			(fill
				(thermal_gap 0.5)
				(thermal_bridge_width 0.5)
				(island_removal_mode 0)
			)
			(polygon
				(pts
					(xy 183.675274 -10.27557) (xy 183.675274 -11.54557) (xy 184.437274 -11.54557) (xy 184.437274 -10.27557)
				)
			)
		)
	)
	(footprint ""
		(layer "F.Cu")
		(at 25.4 -81.026 180)
		(property "Reference" "R1D21"
			(at 0 0 180)
			(layer "F.SilkS")
			(hide yes)
			(effects
				(font
					(size 1.27 1.27)
				)
			)
		)
		(property "Value" ""
			(at 0 0 180)
			(layer "F.Fab")
			(effects
				(font
					(size 1.27 1.27)
				)
			)
		)
		(duplicate_pad_numbers_are_jumpers no)
		(fp_poly
			(pts
				(xy -0.2794 -0.1016) (xy 0.2794 -0.1016) (xy 0.2794 0.9906) (xy -0.2794 0.9906)
			)
			(stroke
				(width 0)
				(type default)
			)
			(fill no)
			(layer "F.CrtYd")
		)
		(fp_line
			(start 0.2794 0.9906)
			(end 0.2794 -0.1016)
			(stroke
				(width 0.1)
				(type default)
			)
			(layer "F.Fab")
		)
		(fp_line
			(start 0.2794 -0.1016)
			(end -0.2794 -0.1016)
			(stroke
				(width 0.1)
				(type default)
			)
			(layer "F.Fab")
		)
		(fp_line
			(start -0.2794 0.9906)
			(end 0.2794 0.9906)
			(stroke
				(width 0.1)
				(type default)
			)
			(layer "F.Fab")
		)
		(fp_line
			(start -0.2794 -0.1016)
			(end -0.2794 0.9906)
			(stroke
				(width 0.1)
				(type default)
			)
			(layer "F.Fab")
		)
		(pad "1" smd rect
			(at 0 0 180)
			(size 0.508 0.508)
			(layers "F.Cu" "F.Mask" "F.Paste")
			(net "P3V3_STBY")
		)
		(pad "2" smd rect
			(at 0 0.889 180)
			(size 0.508 0.508)
			(layers "F.Cu" "F.Mask" "F.Paste")
			(net "FM_OC_DETECT_EN")
		)
		(zone
			(layer "F.Cu")
			(hatch none 0.5)
			(connect_pads
				(clearance 0)
			)
			(min_thickness 0.25)
			(keepout
				(tracks not_allowed)
				(vias allowed)
				(pads allowed)
				(copperpour not_allowed)
				(footprints allowed)
			)
			(placement
				(enabled no)
				(sheetname "")
			)
			(fill
				(thermal_gap 0.5)
				(thermal_bridge_width 0.5)
				(island_removal_mode 0)
			)
			(polygon
				(pts
					(xy 25.654 -81.661) (xy 25.146 -81.661) (xy 25.146 -81.28) (xy 25.654 -81.28)
				)
			)
		)
		(zone
			(layer "F.Cu")
			(hatch none 0.5)
			(connect_pads
				(clearance 0)
			)
			(min_thickness 0.25)
			(keepout
				(tracks allowed)
				(vias not_allowed)
				(pads allowed)
				(copperpour not_allowed)
				(footprints allowed)
			)
			(placement
				(enabled no)
				(sheetname "")
			)
			(fill
				(thermal_gap 0.5)
				(thermal_bridge_width 0.5)
				(island_removal_mode 0)
			)
			(polygon
				(pts
					(xy 25.654 -81.28) (xy 25.146 -81.28) (xy 25.146 -81.661) (xy 25.654 -81.661)
				)
			)
		)
	)
	(footprint ""
		(layer "F.Cu")
		(at 421.386 -113.8555 180)
		(property "Reference" "R9W13"
			(at -0.8382 -0.67818 180)
			(unlocked yes)
			(layer "F.SilkS")
			(effects
				(font
					(size 0.4064 0.254)
					(thickness 0.1524)
				)
				(justify left)
			)
		)
		(property "Value" ""
			(at 0 0 180)
			(layer "F.Fab")
			(effects
				(font
					(size 1.27 1.27)
				)
			)
		)
		(duplicate_pad_numbers_are_jumpers no)
		(fp_poly
			(pts
				(xy -0.2794 -0.1016) (xy 0.2794 -0.1016) (xy 0.2794 0.9906) (xy -0.2794 0.9906)
			)
			(stroke
				(width 0)
				(type default)
			)
			(fill no)
			(layer "F.CrtYd")
		)
		(fp_line
			(start 0.2794 0.9906)
			(end 0.2794 -0.1016)
			(stroke
				(width 0.1)
				(type default)
			)
			(layer "F.Fab")
		)
		(fp_line
			(start 0.2794 -0.1016)
			(end -0.2794 -0.1016)
			(stroke
				(width 0.1)
				(type default)
			)
			(layer "F.Fab")
		)
		(fp_line
			(start -0.2794 0.9906)
			(end 0.2794 0.9906)
			(stroke
				(width 0.1)
				(type default)
			)
			(layer "F.Fab")
		)
		(fp_line
			(start -0.2794 -0.1016)
			(end -0.2794 0.9906)
			(stroke
				(width 0.1)
				(type default)
			)
			(layer "F.Fab")
		)
		(pad "1" smd rect
			(at 0 0 180)
			(size 0.508 0.508)
			(layers "F.Cu" "F.Mask" "F.Paste")
			(net "SMB_PEHPCPU0_STBY_LVC3_R_SDA")
		)
		(pad "2" smd rect
			(at 0 0.889 180)
			(size 0.508 0.508)
			(layers "F.Cu" "F.Mask" "F.Paste")
			(net "SMB_PEHPCPU0_STBY_LVC3_SDA")
		)
		(zone
			(layer "F.Cu")
			(hatch none 0.5)
			(connect_pads
				(clearance 0)
			)
			(min_thickness 0.25)
			(keepout
				(tracks not_allowed)
				(vias allowed)
				(pads allowed)
				(copperpour not_allowed)
				(footprints allowed)
			)
			(placement
				(enabled no)
				(sheetname "")
			)
			(fill
				(thermal_gap 0.5)
				(thermal_bridge_width 0.5)
				(island_removal_mode 0)
			)
			(polygon
				(pts
					(xy 421.64 -114.4905) (xy 421.132 -114.4905) (xy 421.132 -114.1095) (xy 421.64 -114.1095)
				)
			)
		)
		(zone
			(layer "F.Cu")
			(hatch none 0.5)
			(connect_pads
				(clearance 0)
			)
			(min_thickness 0.25)
			(keepout
				(tracks allowed)
				(vias not_allowed)
				(pads allowed)
				(copperpour not_allowed)
				(footprints allowed)
			)
			(placement
				(enabled no)
				(sheetname "")
			)
			(fill
				(thermal_gap 0.5)
				(thermal_bridge_width 0.5)
				(island_removal_mode 0)
			)
			(polygon
				(pts
					(xy 421.64 -114.1095) (xy 421.132 -114.1095) (xy 421.132 -114.4905) (xy 421.64 -114.4905)
				)
			)
		)
	)
	(footprint ""
		(layer "F.Cu")
		(at 491.426246 -152.15616 -90)
		(property "Reference" "R9A7"
			(at 0 0 270)
			(layer "F.SilkS")
			(hide yes)
			(effects
				(font
					(size 1.27 1.27)
				)
			)
		)
		(property "Value" ""
			(at 0 0 270)
			(layer "F.Fab")
			(effects
				(font
					(size 1.27 1.27)
				)
			)
		)
		(duplicate_pad_numbers_are_jumpers no)
		(fp_poly
			(pts
				(xy -0.2794 -0.1016) (xy 0.2794 -0.1016) (xy 0.2794 0.9906) (xy -0.2794 0.9906)
			)
			(stroke
				(width 0)
				(type default)
			)
			(fill no)
			(layer "F.CrtYd")
		)
		(fp_line
			(start -0.2794 0.9906)
			(end 0.2794 0.9906)
			(stroke
				(width 0.1)
				(type default)
			)
			(layer "F.Fab")
		)
		(fp_line
			(start 0.2794 0.9906)
			(end 0.2794 -0.1016)
			(stroke
				(width 0.1)
				(type default)
			)
			(layer "F.Fab")
		)
		(fp_line
			(start -0.2794 -0.1016)
			(end -0.2794 0.9906)
			(stroke
				(width 0.1)
				(type default)
			)
			(layer "F.Fab")
		)
		(fp_line
			(start 0.2794 -0.1016)
			(end -0.2794 -0.1016)
			(stroke
				(width 0.1)
				(type default)
			)
			(layer "F.Fab")
		)
		(pad "1" smd rect
			(at 0 0 270)
			(size 0.508 0.508)
			(layers "F.Cu" "F.Mask" "F.Paste")
			(net "P3V3_STBY")
		)
		(pad "2" smd rect
			(at 0 0.889 270)
			(size 0.508 0.508)
			(layers "F.Cu" "F.Mask" "F.Paste")
			(net "SPA_SIN_SW_R")
		)
		(zone
			(layer "F.Cu")
			(hatch none 0.5)
			(connect_pads
				(clearance 0)
			)
			(min_thickness 0.25)
			(keepout
				(tracks not_allowed)
				(vias allowed)
				(pads allowed)
				(copperpour not_allowed)
				(footprints allowed)
			)
			(placement
				(enabled no)
				(sheetname "")
			)
			(fill
				(thermal_gap 0.5)
				(thermal_bridge_width 0.5)
				(island_removal_mode 0)
			)
			(polygon
				(pts
					(xy 490.791246 -152.41016) (xy 490.791246 -151.90216) (xy 491.172246 -151.90216) (xy 491.172246 -152.41016)
				)
			)
		)
		(zone
			(layer "F.Cu")
			(hatch none 0.5)
			(connect_pads
				(clearance 0)
			)
			(min_thickness 0.25)
			(keepout
				(tracks allowed)
				(vias not_allowed)
				(pads allowed)
				(copperpour not_allowed)
				(footprints allowed)
			)
			(placement
				(enabled no)
				(sheetname "")
			)
			(fill
				(thermal_gap 0.5)
				(thermal_bridge_width 0.5)
				(island_removal_mode 0)
			)
			(polygon
				(pts
					(xy 491.172246 -152.41016) (xy 491.172246 -151.90216) (xy 490.791246 -151.90216) (xy 490.791246 -152.41016)
				)
			)
		)
	)
	(footprint ""
		(layer "F.Cu")
		(at 101.928168 -79.6036 180)
		(property "Reference" "C2D16"
			(at 0 0 180)
			(layer "F.SilkS")
			(hide yes)
			(effects
				(font
					(size 1.27 1.27)
				)
			)
		)
		(property "Value" ""
			(at 0 0 180)
			(layer "F.Fab")
			(effects
				(font
					(size 1.27 1.27)
				)
			)
		)
		(duplicate_pad_numbers_are_jumpers no)
		(fp_poly
			(pts
				(xy -0.4953 -0.2032) (xy 0.4953 -0.2032) (xy 0.4953 1.6002) (xy -0.4953 1.6002)
			)
			(stroke
				(width 0)
				(type default)
			)
			(fill no)
			(layer "F.CrtYd")
		)
		(fp_line
			(start 0.4953 1.6002)
			(end -0.4953 1.6002)
			(stroke
				(width 0.1)
				(type default)
			)
			(layer "F.Fab")
		)
		(fp_line
			(start 0.4953 -0.2032)
			(end 0.4953 1.6002)
			(stroke
				(width 0.1)
				(type default)
			)
			(layer "F.Fab")
		)
		(fp_line
			(start -0.4953 1.6002)
			(end -0.4953 -0.2032)
			(stroke
				(width 0.1)
				(type default)
			)
			(layer "F.Fab")
		)
		(fp_line
			(start -0.4953 -0.2032)
			(end 0.4953 -0.2032)
			(stroke
				(width 0.1)
				(type default)
			)
			(layer "F.Fab")
		)
		(pad "1" smd rect
			(at 0 0 180)
			(size 0.762 0.889)
			(layers "F.Cu" "F.Mask" "F.Paste")
			(net "PVCCIN_CPU1")
		)
		(pad "2" smd rect
			(at 0 1.397 180)
			(size 0.762 0.889)
			(layers "F.Cu" "F.Mask" "F.Paste")
			(net "GND")
		)
		(zone
			(layer "F.Cu")
			(hatch none 0.5)
			(connect_pads
				(clearance 0)
			)
			(min_thickness 0.25)
			(keepout
				(tracks not_allowed)
				(vias allowed)
				(pads allowed)
				(copperpour not_allowed)
				(footprints allowed)
			)
			(placement
				(enabled no)
				(sheetname "")
			)
			(fill
				(thermal_gap 0.5)
				(thermal_bridge_width 0.5)
				(island_removal_mode 0)
			)
			(polygon
				(pts
					(xy 102.309168 -80.0481) (xy 101.547168 -80.0481) (xy 101.547168 -80.5561) (xy 102.309168 -80.5561)
				)
			)
		)
	)
	(footprint ""
		(layer "F.Cu")
		(at 180.3781 2.4003 180)
		(property "Reference" "R4G23"
			(at 0 0 180)
			(layer "F.SilkS")
			(hide yes)
			(effects
				(font
					(size 1.27 1.27)
				)
			)
		)
		(property "Value" ""
			(at 0 0 180)
			(layer "F.Fab")
			(effects
				(font
					(size 1.27 1.27)
				)
			)
		)
		(duplicate_pad_numbers_are_jumpers no)
		(fp_poly
			(pts
				(xy -0.2794 -0.1016) (xy 0.2794 -0.1016) (xy 0.2794 0.9906) (xy -0.2794 0.9906)
			)
			(stroke
				(width 0)
				(type default)
			)
			(fill no)
			(layer "F.CrtYd")
		)
		(fp_line
			(start 0.2794 0.9906)
			(end 0.2794 -0.1016)
			(stroke
				(width 0.1)
				(type default)
			)
			(layer "F.Fab")
		)
		(fp_line
			(start 0.2794 -0.1016)
			(end -0.2794 -0.1016)
			(stroke
				(width 0.1)
				(type default)
			)
			(layer "F.Fab")
		)
		(fp_line
			(start -0.2794 0.9906)
			(end 0.2794 0.9906)
			(stroke
				(width 0.1)
				(type default)
			)
			(layer "F.Fab")
		)
		(fp_line
			(start -0.2794 -0.1016)
			(end -0.2794 0.9906)
			(stroke
				(width 0.1)
				(type default)
			)
			(layer "F.Fab")
		)
		(pad "1" smd rect
			(at 0 0 180)
			(size 0.508 0.508)
			(layers "F.Cu" "F.Mask" "F.Paste")
			(net "PWRGD_PVDDQ_ABC_R")
		)
		(pad "2" smd rect
			(at 0 0.889 180)
			(size 0.508 0.508)
			(layers "F.Cu" "F.Mask" "F.Paste")
			(net "FM_PVTT_ABC_EN_R")
		)
		(zone
			(layer "F.Cu")
			(hatch none 0.5)
			(connect_pads
				(clearance 0)
			)
			(min_thickness 0.25)
			(keepout
				(tracks not_allowed)
				(vias allowed)
				(pads allowed)
				(copperpour not_allowed)
				(footprints allowed)
			)
			(placement
				(enabled no)
				(sheetname "")
			)
			(fill
				(thermal_gap 0.5)
				(thermal_bridge_width 0.5)
				(island_removal_mode 0)
			)
			(polygon
				(pts
					(xy 180.6321 1.7653) (xy 180.1241 1.7653) (xy 180.1241 2.1463) (xy 180.6321 2.1463)
				)
			)
		)
		(zone
			(layer "F.Cu")
			(hatch none 0.5)
			(connect_pads
				(clearance 0)
			)
			(min_thickness 0.25)
			(keepout
				(tracks allowed)
				(vias not_allowed)
				(pads allowed)
				(copperpour not_allowed)
				(footprints allowed)
			)
			(placement
				(enabled no)
				(sheetname "")
			)
			(fill
				(thermal_gap 0.5)
				(thermal_bridge_width 0.5)
				(island_removal_mode 0)
			)
			(polygon
				(pts
					(xy 180.6321 2.1463) (xy 180.1241 2.1463) (xy 180.1241 1.7653) (xy 180.6321 1.7653)
				)
			)
		)
	)
	(footprint ""
		(layer "F.Cu")
		(at 195.5292 -149.6568 90)
		(property "Reference" "C4A5"
			(at 0 0 90)
			(layer "F.SilkS")
			(hide yes)
			(effects
				(font
					(size 1.27 1.27)
				)
			)
		)
		(property "Value" ""
			(at 0 0 90)
			(layer "F.Fab")
			(effects
				(font
					(size 1.27 1.27)
				)
			)
		)
		(duplicate_pad_numbers_are_jumpers no)
		(fp_poly
			(pts
				(xy 0.3048 -0.1016) (xy 0.3048 0.9906) (xy -0.3048 0.9906) (xy -0.3048 -0.1016)
			)
			(stroke
				(width 0)
				(type default)
			)
			(fill no)
			(layer "F.CrtYd")
		)
		(fp_line
			(start 0.3048 -0.1016)
			(end -0.3048 -0.1016)
			(stroke
				(width 0.1)
				(type default)
			)
			(layer "F.Fab")
		)
		(fp_line
			(start -0.3048 -0.1016)
			(end -0.3048 0.9906)
			(stroke
				(width 0.1)
				(type default)
			)
			(layer "F.Fab")
		)
		(fp_line
			(start 0.3048 0.9906)
			(end 0.3048 -0.1016)
			(stroke
				(width 0.1)
				(type default)
			)
			(layer "F.Fab")
		)
		(fp_line
			(start -0.3048 0.9906)
			(end 0.3048 0.9906)
			(stroke
				(width 0.1)
				(type default)
			)
			(layer "F.Fab")
		)
		(pad "1" smd rect
			(at 0 0 90)
			(size 0.508 0.508)
			(layers "F.Cu" "F.Mask" "F.Paste")
			(net "M_F_VREF")
		)
		(pad "2" smd rect
			(at 0 0.889 90)
			(size 0.508 0.508)
			(layers "F.Cu" "F.Mask" "F.Paste")
			(net "GND")
		)
		(zone
			(layer "F.Cu")
			(hatch none 0.5)
			(connect_pads
				(clearance 0)
			)
			(min_thickness 0.25)
			(keepout
				(tracks allowed)
				(vias not_allowed)
				(pads allowed)
				(copperpour not_allowed)
				(footprints allowed)
			)
			(placement
				(enabled no)
				(sheetname "")
			)
			(fill
				(thermal_gap 0.5)
				(thermal_bridge_width 0.5)
				(island_removal_mode 0)
			)
			(polygon
				(pts
					(xy 195.7832 -149.4028) (xy 195.7832 -149.9108) (xy 196.1642 -149.9108) (xy 196.1642 -149.4028)
				)
			)
		)
		(zone
			(layer "F.Cu")
			(hatch none 0.5)
			(connect_pads
				(clearance 0)
			)
			(min_thickness 0.25)
			(keepout
				(tracks not_allowed)
				(vias allowed)
				(pads allowed)
				(copperpour not_allowed)
				(footprints allowed)
			)
			(placement
				(enabled no)
				(sheetname "")
			)
			(fill
				(thermal_gap 0.5)
				(thermal_bridge_width 0.5)
				(island_removal_mode 0)
			)
			(polygon
				(pts
					(xy 196.1642 -149.4028) (xy 196.1642 -149.9108) (xy 195.7832 -149.9108) (xy 195.7832 -149.4028)
				)
			)
		)
	)
	(footprint ""
		(layer "F.Cu")
		(at 183.388 -4.2545 180)
		(property "Reference" "C4G15"
			(at 0 0 180)
			(layer "F.SilkS")
			(hide yes)
			(effects
				(font
					(size 1.27 1.27)
				)
			)
		)
		(property "Value" ""
			(at 0 0 180)
			(layer "F.Fab")
			(effects
				(font
					(size 1.27 1.27)
				)
			)
		)
		(duplicate_pad_numbers_are_jumpers no)
		(fp_rect
			(start 0.3048 -0.1016)
			(end -0.3048 0.9906)
			(stroke
				(width 0)
				(type default)
			)
			(fill no)
			(layer "F.CrtYd")
		)
		(fp_line
			(start 0.3048 0.9906)
			(end 0.3048 -0.1016)
			(stroke
				(width 0.1)
				(type default)
			)
			(layer "F.Fab")
		)
		(fp_line
			(start 0.3048 -0.1016)
			(end -0.3048 -0.1016)
			(stroke
				(width 0.1)
				(type default)
			)
			(layer "F.Fab")
		)
		(fp_line
			(start -0.3048 0.9906)
			(end 0.3048 0.9906)
			(stroke
				(width 0.1)
				(type default)
			)
			(layer "F.Fab")
		)
		(fp_line
			(start -0.3048 -0.1016)
			(end -0.3048 0.9906)
			(stroke
				(width 0.1)
				(type default)
			)
			(layer "F.Fab")
		)
		(pad "1" smd rect
			(at 0 0 180)
			(size 0.508 0.508)
			(layers "F.Cu" "F.Mask" "F.Paste")
			(net "VR_PVTT_ABC_BIAS")
		)
		(pad "2" smd rect
			(at 0 0.889 180)
			(size 0.508 0.508)
			(layers "F.Cu" "F.Mask" "F.Paste")
			(net "GND")
		)
		(zone
			(layer "F.Cu")
			(hatch none 0.5)
			(connect_pads
				(clearance 0)
			)
			(min_thickness 0.25)
			(keepout
				(tracks not_allowed)
				(vias allowed)
				(pads allowed)
				(copperpour not_allowed)
				(footprints allowed)
			)
			(placement
				(enabled no)
				(sheetname "")
			)
			(fill
				(thermal_gap 0.5)
				(thermal_bridge_width 0.5)
				(island_removal_mode 0)
			)
			(polygon
				(pts
					(xy 183.134 -4.5085) (xy 183.642 -4.5085) (xy 183.642 -4.8895) (xy 183.134 -4.8895)
				)
			)
		)
		(zone
			(layer "F.Cu")
			(hatch none 0.5)
			(connect_pads
				(clearance 0)
			)
			(min_thickness 0.25)
			(keepout
				(tracks allowed)
				(vias not_allowed)
				(pads allowed)
				(copperpour not_allowed)
				(footprints allowed)
			)
			(placement
				(enabled no)
				(sheetname "")
			)
			(fill
				(thermal_gap 0.5)
				(thermal_bridge_width 0.5)
				(island_removal_mode 0)
			)
			(polygon
				(pts
					(xy 183.134 -4.5085) (xy 183.642 -4.5085) (xy 183.642 -4.8895) (xy 183.134 -4.8895)
				)
			)
		)
	)
	(footprint ""
		(layer "F.Cu")
		(at 439.3438 -128.778 180)
		(property "Reference" "C8B6"
			(at 0 0 180)
			(layer "F.SilkS")
			(hide yes)
			(effects
				(font
					(size 1.27 1.27)
				)
			)
		)
		(property "Value" ""
			(at 0 0 180)
			(layer "F.Fab")
			(effects
				(font
					(size 1.27 1.27)
				)
			)
		)
		(duplicate_pad_numbers_are_jumpers no)
		(fp_poly
			(pts
				(xy -0.7239 -0.2159) (xy 0.7239 -0.2159) (xy 0.7239 1.9939) (xy -0.7239 1.9939)
			)
			(stroke
				(width 0)
				(type default)
			)
			(fill no)
			(layer "F.CrtYd")
		)
		(fp_line
			(start 0.7239 1.9939)
			(end 0.7239 -0.2159)
			(stroke
				(width 0.1)
				(type default)
			)
			(layer "F.Fab")
		)
		(fp_line
			(start 0.7239 -0.2159)
			(end -0.7239 -0.2159)
			(stroke
				(width 0.1)
				(type default)
			)
			(layer "F.Fab")
		)
		(fp_line
			(start -0.7239 1.9939)
			(end 0.7239 1.9939)
			(stroke
				(width 0.1)
				(type default)
			)
			(layer "F.Fab")
		)
		(fp_line
			(start -0.7239 -0.2159)
			(end -0.7239 1.9939)
			(stroke
				(width 0.1)
				(type default)
			)
			(layer "F.Fab")
		)
		(pad "1" smd rect
			(at 0 0 180)
			(size 1.27 1.016)
			(layers "F.Cu" "F.Mask" "F.Paste")
			(net "P5V")
		)
		(pad "2" smd rect
			(at 0 1.778 180)
			(size 1.27 1.016)
			(layers "F.Cu" "F.Mask" "F.Paste")
			(net "GND")
		)
		(zone
			(layer "F.Cu")
			(hatch none 0.5)
			(connect_pads
				(clearance 0)
			)
			(min_thickness 0.25)
			(keepout
				(tracks not_allowed)
				(vias allowed)
				(pads allowed)
				(copperpour not_allowed)
				(footprints allowed)
			)
			(placement
				(enabled no)
				(sheetname "")
			)
			(fill
				(thermal_gap 0.5)
				(thermal_bridge_width 0.5)
				(island_removal_mode 0)
			)
			(polygon
				(pts
					(xy 439.9788 -129.286) (xy 438.7088 -129.286) (xy 438.7088 -130.048) (xy 439.9788 -130.048)
				)
			)
		)
	)
	(footprint ""
		(layer "F.Cu")
		(at 485.89184 -123.79706 90)
		(property "Reference" "R9B4"
			(at 0 0 90)
			(layer "F.SilkS")
			(hide yes)
			(effects
				(font
					(size 1.27 1.27)
				)
			)
		)
		(property "Value" ""
			(at 0 0 90)
			(layer "F.Fab")
			(effects
				(font
					(size 1.27 1.27)
				)
			)
		)
		(duplicate_pad_numbers_are_jumpers no)
		(fp_poly
			(pts
				(xy -0.2794 -0.1016) (xy 0.2794 -0.1016) (xy 0.2794 0.9906) (xy -0.2794 0.9906)
			)
			(stroke
				(width 0)
				(type default)
			)
			(fill no)
			(layer "F.CrtYd")
		)
		(fp_line
			(start 0.2794 -0.1016)
			(end -0.2794 -0.1016)
			(stroke
				(width 0.1)
				(type default)
			)
			(layer "F.Fab")
		)
		(fp_line
			(start -0.2794 -0.1016)
			(end -0.2794 0.9906)
			(stroke
				(width 0.1)
				(type default)
			)
			(layer "F.Fab")
		)
		(fp_line
			(start 0.2794 0.9906)
			(end 0.2794 -0.1016)
			(stroke
				(width 0.1)
				(type default)
			)
			(layer "F.Fab")
		)
		(fp_line
			(start -0.2794 0.9906)
			(end 0.2794 0.9906)
			(stroke
				(width 0.1)
				(type default)
			)
			(layer "F.Fab")
		)
		(pad "1" smd rect
			(at 0 0 90)
			(size 0.508 0.508)
			(layers "F.Cu" "F.Mask" "F.Paste")
			(net "ISENSE_TMP421_1_E")
		)
		(pad "2" smd rect
			(at 0 0.889 90)
			(size 0.508 0.508)
			(layers "F.Cu" "F.Mask" "F.Paste")
			(net "ISENSE_TMP421_1_DXP")
		)
		(zone
			(layer "F.Cu")
			(hatch none 0.5)
			(connect_pads
				(clearance 0)
			)
			(min_thickness 0.25)
			(keepout
				(tracks allowed)
				(vias not_allowed)
				(pads allowed)
				(copperpour not_allowed)
				(footprints allowed)
			)
			(placement
				(enabled no)
				(sheetname "")
			)
			(fill
				(thermal_gap 0.5)
				(thermal_bridge_width 0.5)
				(island_removal_mode 0)
			)
			(polygon
				(pts
					(xy 486.14584 -123.54306) (xy 486.14584 -124.05106) (xy 486.52684 -124.05106) (xy 486.52684 -123.54306)
				)
			)
		)
		(zone
			(layer "F.Cu")
			(hatch none 0.5)
			(connect_pads
				(clearance 0)
			)
			(min_thickness 0.25)
			(keepout
				(tracks not_allowed)
				(vias allowed)
				(pads allowed)
				(copperpour not_allowed)
				(footprints allowed)
			)
			(placement
				(enabled no)
				(sheetname "")
			)
			(fill
				(thermal_gap 0.5)
				(thermal_bridge_width 0.5)
				(island_removal_mode 0)
			)
			(polygon
				(pts
					(xy 486.52684 -123.54306) (xy 486.52684 -124.05106) (xy 486.14584 -124.05106) (xy 486.14584 -123.54306)
				)
			)
		)
	)
	(footprint ""
		(layer "F.Cu")
		(at 14.6812 -99.5934 90)
		(property "Reference" "R1C14"
			(at 0 0 90)
			(layer "F.SilkS")
			(hide yes)
			(effects
				(font
					(size 1.27 1.27)
				)
			)
		)
		(property "Value" ""
			(at 0 0 90)
			(layer "F.Fab")
			(effects
				(font
					(size 1.27 1.27)
				)
			)
		)
		(duplicate_pad_numbers_are_jumpers no)
		(fp_rect
			(start -0.2794 -0.1016)
			(end 0.2794 0.9906)
			(stroke
				(width 0)
				(type default)
			)
			(fill no)
			(layer "F.CrtYd")
		)
		(fp_line
			(start 0.2794 -0.1016)
			(end -0.2794 -0.1016)
			(stroke
				(width 0.1)
				(type default)
			)
			(layer "F.Fab")
		)
		(fp_line
			(start -0.2794 -0.1016)
			(end -0.2794 0.9906)
			(stroke
				(width 0.1)
				(type default)
			)
			(layer "F.Fab")
		)
		(fp_line
			(start 0.2794 0.9906)
			(end 0.2794 -0.1016)
			(stroke
				(width 0.1)
				(type default)
			)
			(layer "F.Fab")
		)
		(fp_line
			(start -0.2794 0.9906)
			(end 0.2794 0.9906)
			(stroke
				(width 0.1)
				(type default)
			)
			(layer "F.Fab")
		)
		(pad "1" smd rect
			(at 0 0 90)
			(size 0.508 0.508)
			(layers "F.Cu" "F.Mask" "F.Paste")
			(net "P3V3_STBY")
		)
		(pad "2" smd rect
			(at 0 0.889 90)
			(size 0.508 0.508)
			(layers "F.Cu" "F.Mask" "F.Paste")
			(net "VR_PVCCIN_CPU1_VDD")
		)
		(zone
			(layer "F.Cu")
			(hatch none 0.5)
			(connect_pads
				(clearance 0)
			)
			(min_thickness 0.25)
			(keepout
				(tracks allowed)
				(vias not_allowed)
				(pads allowed)
				(copperpour not_allowed)
				(footprints allowed)
			)
			(placement
				(enabled no)
				(sheetname "")
			)
			(fill
				(thermal_gap 0.5)
				(thermal_bridge_width 0.5)
				(island_removal_mode 0)
			)
			(polygon
				(pts
					(xy 14.9352 -99.3394) (xy 15.3162 -99.3394) (xy 15.3162 -99.8474) (xy 14.9352 -99.8474)
				)
			)
		)
		(zone
			(layer "F.Cu")
			(hatch none 0.5)
			(connect_pads
				(clearance 0)
			)
			(min_thickness 0.25)
			(keepout
				(tracks not_allowed)
				(vias allowed)
				(pads allowed)
				(copperpour not_allowed)
				(footprints allowed)
			)
			(placement
				(enabled no)
				(sheetname "")
			)
			(fill
				(thermal_gap 0.5)
				(thermal_bridge_width 0.5)
				(island_removal_mode 0)
			)
			(polygon
				(pts
					(xy 14.9352 -99.3394) (xy 15.3162 -99.3394) (xy 15.3162 -99.8474) (xy 14.9352 -99.8474)
				)
			)
		)
	)
	(footprint ""
		(layer "F.Cu")
		(at 276.000464 -12.954 90)
		(property "Reference" "C5G8"
			(at 1.848866 0.752348 90)
			(unlocked yes)
			(layer "F.SilkS")
			(effects
				(font
					(size 1.27 0.9652)
					(thickness 0.1524)
				)
			)
		)
		(property "Value" ""
			(at 0 0 90)
			(layer "F.Fab")
			(effects
				(font
					(size 1.27 1.27)
				)
			)
		)
		(duplicate_pad_numbers_are_jumpers no)
		(fp_rect
			(start -0.500126 1.598422)
			(end 0.500126 -0.201422)
			(stroke
				(width 0)
				(type default)
			)
			(fill no)
			(layer "F.CrtYd")
		)
		(fp_line
			(start 0.500126 -0.201422)
			(end 0.500126 1.598422)
			(stroke
				(width 0.1)
				(type default)
			)
			(layer "F.Fab")
		)
		(fp_line
			(start -0.500126 -0.201422)
			(end 0.500126 -0.201422)
			(stroke
				(width 0.1)
				(type default)
			)
			(layer "F.Fab")
		)
		(fp_line
			(start 0.500126 1.598422)
			(end -0.500126 1.598422)
			(stroke
				(width 0.1)
				(type default)
			)
			(layer "F.Fab")
		)
		(fp_line
			(start -0.500126 1.598422)
			(end -0.500126 -0.201422)
			(stroke
				(width 0.1)
				(type default)
			)
			(layer "F.Fab")
		)
		(pad "1" smd rect
			(at 0 0)
			(size 0.889 0.9906)
			(layers "F.Cu" "F.Mask" "F.Paste")
			(net "PVDDQ_ABC")
		)
		(pad "2" smd rect
			(at 0 1.397)
			(size 0.889 0.9906)
			(layers "F.Cu" "F.Mask" "F.Paste")
			(net "GND")
		)
		(zone
			(layer "F.Cu")
			(hatch none 0.5)
			(connect_pads
				(clearance 0)
			)
			(min_thickness 0.25)
			(keepout
				(tracks not_allowed)
				(vias allowed)
				(pads allowed)
				(copperpour not_allowed)
				(footprints allowed)
			)
			(placement
				(enabled no)
				(sheetname "")
			)
			(fill
				(thermal_gap 0.5)
				(thermal_bridge_width 0.5)
				(island_removal_mode 0)
			)
			(polygon
				(pts
					(xy 276.952964 -12.4587) (xy 276.952964 -13.4493) (xy 276.444964 -13.4493) (xy 276.444964 -12.4587)
				)
			)
		)
		(zone
			(layer "F.Cu")
			(hatch none 0.5)
			(connect_pads
				(clearance 0)
			)
			(min_thickness 0.25)
			(keepout
				(tracks allowed)
				(vias not_allowed)
				(pads allowed)
				(copperpour not_allowed)
				(footprints allowed)
			)
			(placement
				(enabled no)
				(sheetname "")
			)
			(fill
				(thermal_gap 0.5)
				(thermal_bridge_width 0.5)
				(island_removal_mode 0)
			)
			(polygon
				(pts
					(xy 276.952964 -12.4587) (xy 276.952964 -13.4493) (xy 276.444964 -13.4493) (xy 276.444964 -12.4587)
				)
			)
		)
	)
	(footprint ""
		(layer "F.Cu")
		(at 417.7919 -58.801 -90)
		(property "Reference" "R8E16"
			(at 0 0 270)
			(layer "F.SilkS")
			(hide yes)
			(effects
				(font
					(size 1.27 1.27)
				)
			)
		)
		(property "Value" ""
			(at 0 0 270)
			(layer "F.Fab")
			(effects
				(font
					(size 1.27 1.27)
				)
			)
		)
		(duplicate_pad_numbers_are_jumpers no)
		(fp_poly
			(pts
				(xy -0.2794 -0.1016) (xy 0.2794 -0.1016) (xy 0.2794 0.9906) (xy -0.2794 0.9906)
			)
			(stroke
				(width 0)
				(type default)
			)
			(fill no)
			(layer "F.CrtYd")
		)
		(fp_line
			(start -0.2794 0.9906)
			(end 0.2794 0.9906)
			(stroke
				(width 0.1)
				(type default)
			)
			(layer "F.Fab")
		)
		(fp_line
			(start 0.2794 0.9906)
			(end 0.2794 -0.1016)
			(stroke
				(width 0.1)
				(type default)
			)
			(layer "F.Fab")
		)
		(fp_line
			(start -0.2794 -0.1016)
			(end -0.2794 0.9906)
			(stroke
				(width 0.1)
				(type default)
			)
			(layer "F.Fab")
		)
		(fp_line
			(start 0.2794 -0.1016)
			(end -0.2794 -0.1016)
			(stroke
				(width 0.1)
				(type default)
			)
			(layer "F.Fab")
		)
		(pad "1" smd rect
			(at 0 0 270)
			(size 0.508 0.508)
			(layers "F.Cu" "F.Mask" "F.Paste")
			(net "FM_BIOS_TOP_SWAP")
		)
		(pad "2" smd rect
			(at 0 0.889 270)
			(size 0.508 0.508)
			(layers "F.Cu" "F.Mask" "F.Paste")
			(net "GND")
		)
		(zone
			(layer "F.Cu")
			(hatch none 0.5)
			(connect_pads
				(clearance 0)
			)
			(min_thickness 0.25)
			(keepout
				(tracks not_allowed)
				(vias allowed)
				(pads allowed)
				(copperpour not_allowed)
				(footprints allowed)
			)
			(placement
				(enabled no)
				(sheetname "")
			)
			(fill
				(thermal_gap 0.5)
				(thermal_bridge_width 0.5)
				(island_removal_mode 0)
			)
			(polygon
				(pts
					(xy 417.1569 -59.055) (xy 417.1569 -58.547) (xy 417.5379 -58.547) (xy 417.5379 -59.055)
				)
			)
		)
		(zone
			(layer "F.Cu")
			(hatch none 0.5)
			(connect_pads
				(clearance 0)
			)
			(min_thickness 0.25)
			(keepout
				(tracks allowed)
				(vias not_allowed)
				(pads allowed)
				(copperpour not_allowed)
				(footprints allowed)
			)
			(placement
				(enabled no)
				(sheetname "")
			)
			(fill
				(thermal_gap 0.5)
				(thermal_bridge_width 0.5)
				(island_removal_mode 0)
			)
			(polygon
				(pts
					(xy 417.5379 -59.055) (xy 417.5379 -58.547) (xy 417.1569 -58.547) (xy 417.1569 -59.055)
				)
			)
		)
	)
	(footprint ""
		(layer "F.Cu")
		(at 351.339658 -1.261364 90)
		(property "Reference" "CT52"
			(at 0.4318 2.74447 90)
			(unlocked yes)
			(layer "F.SilkS")
			(effects
				(font
					(size 0.7874 0.5842)
					(thickness 0.1524)
				)
				(justify left)
			)
		)
		(property "Value" ""
			(at 0 0 90)
			(layer "F.Fab")
			(effects
				(font
					(size 1.27 1.27)
				)
			)
		)
		(duplicate_pad_numbers_are_jumpers no)
		(fp_poly
			(pts
				(xy 0.3048 -0.1016) (xy 0.3048 0.9906) (xy -0.3048 0.9906) (xy -0.3048 -0.1016)
			)
			(stroke
				(width 0)
				(type default)
			)
			(fill no)
			(layer "F.CrtYd")
		)
		(fp_line
			(start 0.3048 -0.1016)
			(end -0.3048 -0.1016)
			(stroke
				(width 0.1)
				(type default)
			)
			(layer "F.Fab")
		)
		(fp_line
			(start -0.3048 -0.1016)
			(end -0.3048 0.9906)
			(stroke
				(width 0.1)
				(type default)
			)
			(layer "F.Fab")
		)
		(fp_line
			(start 0.3048 0.9906)
			(end 0.3048 -0.1016)
			(stroke
				(width 0.1)
				(type default)
			)
			(layer "F.Fab")
		)
		(fp_line
			(start -0.3048 0.9906)
			(end 0.3048 0.9906)
			(stroke
				(width 0.1)
				(type default)
			)
			(layer "F.Fab")
		)
		(pad "1" smd rect
			(at 0 0 90)
			(size 0.508 0.508)
			(layers "F.Cu" "F.Mask" "F.Paste")
			(net "VR_PVDDQ_ABC_AIREF2")
		)
		(pad "2" smd rect
			(at 0 0.889 90)
			(size 0.508 0.508)
			(layers "F.Cu" "F.Mask" "F.Paste")
			(net "GND")
		)
		(zone
			(layer "F.Cu")
			(hatch none 0.5)
			(connect_pads
				(clearance 0)
			)
			(min_thickness 0.25)
			(keepout
				(tracks allowed)
				(vias not_allowed)
				(pads allowed)
				(copperpour not_allowed)
				(footprints allowed)
			)
			(placement
				(enabled no)
				(sheetname "")
			)
			(fill
				(thermal_gap 0.5)
				(thermal_bridge_width 0.5)
				(island_removal_mode 0)
			)
			(polygon
				(pts
					(xy 351.593658 -1.007364) (xy 351.593658 -1.515364) (xy 351.974658 -1.515364) (xy 351.974658 -1.007364)
				)
			)
		)
		(zone
			(layer "F.Cu")
			(hatch none 0.5)
			(connect_pads
				(clearance 0)
			)
			(min_thickness 0.25)
			(keepout
				(tracks not_allowed)
				(vias allowed)
				(pads allowed)
				(copperpour not_allowed)
				(footprints allowed)
			)
			(placement
				(enabled no)
				(sheetname "")
			)
			(fill
				(thermal_gap 0.5)
				(thermal_bridge_width 0.5)
				(island_removal_mode 0)
			)
			(polygon
				(pts
					(xy 351.974658 -1.007364) (xy 351.974658 -1.515364) (xy 351.593658 -1.515364) (xy 351.593658 -1.007364)
				)
			)
		)
	)
	(footprint ""
		(layer "F.Cu")
		(at 214.503 -86.4235)
		(property "Reference" "C4D4"
			(at 0 0 0)
			(layer "F.SilkS")
			(hide yes)
			(effects
				(font
					(size 1.27 1.27)
				)
			)
		)
		(property "Value" ""
			(at 0 0 0)
			(layer "F.Fab")
			(effects
				(font
					(size 1.27 1.27)
				)
			)
		)
		(duplicate_pad_numbers_are_jumpers no)
		(fp_poly
			(pts
				(xy -0.4953 -0.2032) (xy 0.4953 -0.2032) (xy 0.4953 1.6002) (xy -0.4953 1.6002)
			)
			(stroke
				(width 0)
				(type default)
			)
			(fill no)
			(layer "F.CrtYd")
		)
		(fp_line
			(start -0.4953 -0.2032)
			(end 0.4953 -0.2032)
			(stroke
				(width 0.1)
				(type default)
			)
			(layer "F.Fab")
		)
		(fp_line
			(start -0.4953 1.6002)
			(end -0.4953 -0.2032)
			(stroke
				(width 0.1)
				(type default)
			)
			(layer "F.Fab")
		)
		(fp_line
			(start 0.4953 -0.2032)
			(end 0.4953 1.6002)
			(stroke
				(width 0.1)
				(type default)
			)
			(layer "F.Fab")
		)
		(fp_line
			(start 0.4953 1.6002)
			(end -0.4953 1.6002)
			(stroke
				(width 0.1)
				(type default)
			)
			(layer "F.Fab")
		)
		(pad "1" smd rect
			(at 0 0)
			(size 0.762 0.889)
			(layers "F.Cu" "F.Mask" "F.Paste")
			(net "PVCCIN_CPU0")
		)
		(pad "2" smd rect
			(at 0 1.397)
			(size 0.762 0.889)
			(layers "F.Cu" "F.Mask" "F.Paste")
			(net "GND")
		)
		(zone
			(layer "F.Cu")
			(hatch none 0.5)
			(connect_pads
				(clearance 0)
			)
			(min_thickness 0.25)
			(keepout
				(tracks not_allowed)
				(vias allowed)
				(pads allowed)
				(copperpour not_allowed)
				(footprints allowed)
			)
			(placement
				(enabled no)
				(sheetname "")
			)
			(fill
				(thermal_gap 0.5)
				(thermal_bridge_width 0.5)
				(island_removal_mode 0)
			)
			(polygon
				(pts
					(xy 214.122 -85.979) (xy 214.884 -85.979) (xy 214.884 -85.471) (xy 214.122 -85.471)
				)
			)
		)
	)
	(footprint ""
		(layer "F.Cu")
		(at 472.227402 -36.880292)
		(property "Reference" "R9F32"
			(at 0 0 0)
			(layer "F.SilkS")
			(hide yes)
			(effects
				(font
					(size 1.27 1.27)
				)
			)
		)
		(property "Value" ""
			(at 0 0 0)
			(layer "F.Fab")
			(effects
				(font
					(size 1.27 1.27)
				)
			)
		)
		(duplicate_pad_numbers_are_jumpers no)
		(fp_poly
			(pts
				(xy -0.2794 -0.1016) (xy 0.2794 -0.1016) (xy 0.2794 0.9906) (xy -0.2794 0.9906)
			)
			(stroke
				(width 0)
				(type default)
			)
			(fill no)
			(layer "F.CrtYd")
		)
		(fp_line
			(start -0.2794 -0.1016)
			(end -0.2794 0.9906)
			(stroke
				(width 0.1)
				(type default)
			)
			(layer "F.Fab")
		)
		(fp_line
			(start -0.2794 0.9906)
			(end 0.2794 0.9906)
			(stroke
				(width 0.1)
				(type default)
			)
			(layer "F.Fab")
		)
		(fp_line
			(start 0.2794 -0.1016)
			(end -0.2794 -0.1016)
			(stroke
				(width 0.1)
				(type default)
			)
			(layer "F.Fab")
		)
		(fp_line
			(start 0.2794 0.9906)
			(end 0.2794 -0.1016)
			(stroke
				(width 0.1)
				(type default)
			)
			(layer "F.Fab")
		)
		(pad "1" smd rect
			(at 0 0)
			(size 0.508 0.508)
			(layers "F.Cu" "F.Mask" "F.Paste")
			(net "VR_P1V2_BMC_STBY_FB")
		)
		(pad "2" smd rect
			(at 0 0.889)
			(size 0.508 0.508)
			(layers "F.Cu" "F.Mask" "F.Paste")
			(net "GND")
		)
		(zone
			(layer "F.Cu")
			(hatch none 0.5)
			(connect_pads
				(clearance 0)
			)
			(min_thickness 0.25)
			(keepout
				(tracks allowed)
				(vias not_allowed)
				(pads allowed)
				(copperpour not_allowed)
				(footprints allowed)
			)
			(placement
				(enabled no)
				(sheetname "")
			)
			(fill
				(thermal_gap 0.5)
				(thermal_bridge_width 0.5)
				(island_removal_mode 0)
			)
			(polygon
				(pts
					(xy 471.973402 -36.626292) (xy 472.481402 -36.626292) (xy 472.481402 -36.245292) (xy 471.973402 -36.245292)
				)
			)
		)
		(zone
			(layer "F.Cu")
			(hatch none 0.5)
			(connect_pads
				(clearance 0)
			)
			(min_thickness 0.25)
			(keepout
				(tracks not_allowed)
				(vias allowed)
				(pads allowed)
				(copperpour not_allowed)
				(footprints allowed)
			)
			(placement
				(enabled no)
				(sheetname "")
			)
			(fill
				(thermal_gap 0.5)
				(thermal_bridge_width 0.5)
				(island_removal_mode 0)
			)
			(polygon
				(pts
					(xy 471.973402 -36.245292) (xy 472.481402 -36.245292) (xy 472.481402 -36.626292) (xy 471.973402 -36.626292)
				)
			)
		)
	)
	(footprint ""
		(layer "F.Cu")
		(at 337.82 -10.3378 90)
		(property "Reference" "CT50"
			(at -0.8382 -0.67818 90)
			(unlocked yes)
			(layer "F.SilkS")
			(effects
				(font
					(size 0.4064 0.254)
					(thickness 0.1524)
				)
				(justify left)
			)
		)
		(property "Value" ""
			(at 0 0 90)
			(layer "F.Fab")
			(effects
				(font
					(size 1.27 1.27)
				)
			)
		)
		(duplicate_pad_numbers_are_jumpers no)
		(fp_poly
			(pts
				(xy 0.3048 -0.1016) (xy 0.3048 0.9906) (xy -0.3048 0.9906) (xy -0.3048 -0.1016)
			)
			(stroke
				(width 0)
				(type default)
			)
			(fill no)
			(layer "F.CrtYd")
		)
		(fp_line
			(start 0.3048 -0.1016)
			(end -0.3048 -0.1016)
			(stroke
				(width 0.1)
				(type default)
			)
			(layer "F.Fab")
		)
		(fp_line
			(start -0.3048 -0.1016)
			(end -0.3048 0.9906)
			(stroke
				(width 0.1)
				(type default)
			)
			(layer "F.Fab")
		)
		(fp_line
			(start 0.3048 0.9906)
			(end 0.3048 -0.1016)
			(stroke
				(width 0.1)
				(type default)
			)
			(layer "F.Fab")
		)
		(fp_line
			(start -0.3048 0.9906)
			(end 0.3048 0.9906)
			(stroke
				(width 0.1)
				(type default)
			)
			(layer "F.Fab")
		)
		(pad "1" smd rect
			(at 0 0 90)
			(size 0.508 0.508)
			(layers "F.Cu" "F.Mask" "F.Paste")
			(net "VR_PVDDQ_ABC_PH1_SW")
		)
		(pad "2" smd rect
			(at 0 0.889 90)
			(size 0.508 0.508)
			(layers "F.Cu" "F.Mask" "F.Paste")
			(net "VR_PVDDQ_ABC_PH1_SW_RC")
		)
		(zone
			(layer "F.Cu")
			(hatch none 0.5)
			(connect_pads
				(clearance 0)
			)
			(min_thickness 0.25)
			(keepout
				(tracks allowed)
				(vias not_allowed)
				(pads allowed)
				(copperpour not_allowed)
				(footprints allowed)
			)
			(placement
				(enabled no)
				(sheetname "")
			)
			(fill
				(thermal_gap 0.5)
				(thermal_bridge_width 0.5)
				(island_removal_mode 0)
			)
			(polygon
				(pts
					(xy 338.074 -10.0838) (xy 338.074 -10.5918) (xy 338.455 -10.5918) (xy 338.455 -10.0838)
				)
			)
		)
		(zone
			(layer "F.Cu")
			(hatch none 0.5)
			(connect_pads
				(clearance 0)
			)
			(min_thickness 0.25)
			(keepout
				(tracks not_allowed)
				(vias allowed)
				(pads allowed)
				(copperpour not_allowed)
				(footprints allowed)
			)
			(placement
				(enabled no)
				(sheetname "")
			)
			(fill
				(thermal_gap 0.5)
				(thermal_bridge_width 0.5)
				(island_removal_mode 0)
			)
			(polygon
				(pts
					(xy 338.455 -10.0838) (xy 338.455 -10.5918) (xy 338.074 -10.5918) (xy 338.074 -10.0838)
				)
			)
		)
	)
	(footprint ""
		(layer "F.Cu")
		(at 28.6004 -41.4782 180)
		(property "Reference" "C1E21"
			(at 0 0 180)
			(layer "F.SilkS")
			(hide yes)
			(effects
				(font
					(size 1.27 1.27)
				)
			)
		)
		(property "Value" ""
			(at 0 0 180)
			(layer "F.Fab")
			(effects
				(font
					(size 1.27 1.27)
				)
			)
		)
		(duplicate_pad_numbers_are_jumpers no)
		(fp_rect
			(start 0.7239 -0.2159)
			(end -0.7239 1.9939)
			(stroke
				(width 0)
				(type default)
			)
			(fill no)
			(layer "F.CrtYd")
		)
		(fp_line
			(start 0.7239 1.9939)
			(end 0.7239 -0.2159)
			(stroke
				(width 0.1)
				(type default)
			)
			(layer "F.Fab")
		)
		(fp_line
			(start 0.7239 -0.2159)
			(end -0.7239 -0.2159)
			(stroke
				(width 0.1)
				(type default)
			)
			(layer "F.Fab")
		)
		(fp_line
			(start -0.7239 1.9939)
			(end 0.7239 1.9939)
			(stroke
				(width 0.1)
				(type default)
			)
			(layer "F.Fab")
		)
		(fp_line
			(start -0.7239 -0.2159)
			(end -0.7239 1.9939)
			(stroke
				(width 0.1)
				(type default)
			)
			(layer "F.Fab")
		)
		(pad "1" smd rect
			(at 0 0 180)
			(size 1.27 1.016)
			(layers "F.Cu" "F.Mask" "F.Paste")
			(net "P12V_FAN")
		)
		(pad "2" smd rect
			(at 0 1.778 180)
			(size 1.27 1.016)
			(layers "F.Cu" "F.Mask" "F.Paste")
			(net "GND")
		)
		(zone
			(layer "F.Cu")
			(hatch none 0.5)
			(connect_pads
				(clearance 0)
			)
			(min_thickness 0.25)
			(keepout
				(tracks not_allowed)
				(vias allowed)
				(pads allowed)
				(copperpour not_allowed)
				(footprints allowed)
			)
			(placement
				(enabled no)
				(sheetname "")
			)
			(fill
				(thermal_gap 0.5)
				(thermal_bridge_width 0.5)
				(island_removal_mode 0)
			)
			(polygon
				(pts
					(xy 27.9654 -41.9862) (xy 29.2354 -41.9862) (xy 29.2354 -42.7482) (xy 27.9654 -42.7482)
				)
			)
		)
	)
	(footprint ""
		(layer "F.Cu")
		(at 383.660904 -76.026264 180)
		(property "Reference" "R2T37"
			(at 0 0 180)
			(layer "F.SilkS")
			(hide yes)
			(effects
				(font
					(size 1.27 1.27)
				)
			)
		)
		(property "Value" ""
			(at 0 0 180)
			(layer "F.Fab")
			(effects
				(font
					(size 1.27 1.27)
				)
			)
		)
		(duplicate_pad_numbers_are_jumpers no)
		(fp_poly
			(pts
				(xy -0.2794 -0.1016) (xy 0.2794 -0.1016) (xy 0.2794 0.9906) (xy -0.2794 0.9906)
			)
			(stroke
				(width 0)
				(type default)
			)
			(fill no)
			(layer "F.CrtYd")
		)
		(fp_line
			(start 0.2794 0.9906)
			(end 0.2794 -0.1016)
			(stroke
				(width 0.1)
				(type default)
			)
			(layer "F.Fab")
		)
		(fp_line
			(start 0.2794 -0.1016)
			(end -0.2794 -0.1016)
			(stroke
				(width 0.1)
				(type default)
			)
			(layer "F.Fab")
		)
		(fp_line
			(start -0.2794 0.9906)
			(end 0.2794 0.9906)
			(stroke
				(width 0.1)
				(type default)
			)
			(layer "F.Fab")
		)
		(fp_line
			(start -0.2794 -0.1016)
			(end -0.2794 0.9906)
			(stroke
				(width 0.1)
				(type default)
			)
			(layer "F.Fab")
		)
		(pad "1" smd rect
			(at 0 0 180)
			(size 0.508 0.508)
			(layers "F.Cu" "F.Mask" "F.Paste")
			(net "PVCCIO_CPU0")
		)
		(pad "2" smd rect
			(at 0 0.889 180)
			(size 0.508 0.508)
			(layers "F.Cu" "F.Mask" "F.Paste")
			(net "H_CPU_ERR2_G_R_N")
		)
		(zone
			(layer "F.Cu")
			(hatch none 0.5)
			(connect_pads
				(clearance 0)
			)
			(min_thickness 0.25)
			(keepout
				(tracks not_allowed)
				(vias allowed)
				(pads allowed)
				(copperpour not_allowed)
				(footprints allowed)
			)
			(placement
				(enabled no)
				(sheetname "")
			)
			(fill
				(thermal_gap 0.5)
				(thermal_bridge_width 0.5)
				(island_removal_mode 0)
			)
			(polygon
				(pts
					(xy 383.914904 -76.661264) (xy 383.406904 -76.661264) (xy 383.406904 -76.280264) (xy 383.914904 -76.280264)
				)
			)
		)
		(zone
			(layer "F.Cu")
			(hatch none 0.5)
			(connect_pads
				(clearance 0)
			)
			(min_thickness 0.25)
			(keepout
				(tracks allowed)
				(vias not_allowed)
				(pads allowed)
				(copperpour not_allowed)
				(footprints allowed)
			)
			(placement
				(enabled no)
				(sheetname "")
			)
			(fill
				(thermal_gap 0.5)
				(thermal_bridge_width 0.5)
				(island_removal_mode 0)
			)
			(polygon
				(pts
					(xy 383.914904 -76.280264) (xy 383.406904 -76.280264) (xy 383.406904 -76.661264) (xy 383.914904 -76.661264)
				)
			)
		)
	)
	(footprint ""
		(layer "F.Cu")
		(at 274.447 -69.977)
		(property "Reference" "R5D3"
			(at 0 0 0)
			(layer "F.SilkS")
			(hide yes)
			(effects
				(font
					(size 1.27 1.27)
				)
			)
		)
		(property "Value" ""
			(at 0 0 0)
			(layer "F.Fab")
			(effects
				(font
					(size 1.27 1.27)
				)
			)
		)
		(duplicate_pad_numbers_are_jumpers no)
		(fp_poly
			(pts
				(xy -0.2794 -0.1016) (xy 0.2794 -0.1016) (xy 0.2794 0.9906) (xy -0.2794 0.9906)
			)
			(stroke
				(width 0)
				(type default)
			)
			(fill no)
			(layer "F.CrtYd")
		)
		(fp_line
			(start -0.2794 -0.1016)
			(end -0.2794 0.9906)
			(stroke
				(width 0.1)
				(type default)
			)
			(layer "F.Fab")
		)
		(fp_line
			(start -0.2794 0.9906)
			(end 0.2794 0.9906)
			(stroke
				(width 0.1)
				(type default)
			)
			(layer "F.Fab")
		)
		(fp_line
			(start 0.2794 -0.1016)
			(end -0.2794 -0.1016)
			(stroke
				(width 0.1)
				(type default)
			)
			(layer "F.Fab")
		)
		(fp_line
			(start 0.2794 0.9906)
			(end 0.2794 -0.1016)
			(stroke
				(width 0.1)
				(type default)
			)
			(layer "F.Fab")
		)
		(pad "1" smd rect
			(at 0 0)
			(size 0.508 0.508)
			(layers "F.Cu" "F.Mask" "F.Paste")
			(net "PVCCIO_CPU0")
		)
		(pad "2" smd rect
			(at 0 0.889)
			(size 0.508 0.508)
			(layers "F.Cu" "F.Mask" "F.Paste")
			(net "PU_CPU0_FRMAGENT")
		)
		(zone
			(layer "F.Cu")
			(hatch none 0.5)
			(connect_pads
				(clearance 0)
			)
			(min_thickness 0.25)
			(keepout
				(tracks allowed)
				(vias not_allowed)
				(pads allowed)
				(copperpour not_allowed)
				(footprints allowed)
			)
			(placement
				(enabled no)
				(sheetname "")
			)
			(fill
				(thermal_gap 0.5)
				(thermal_bridge_width 0.5)
				(island_removal_mode 0)
			)
			(polygon
				(pts
					(xy 274.193 -69.723) (xy 274.701 -69.723) (xy 274.701 -69.342) (xy 274.193 -69.342)
				)
			)
		)
		(zone
			(layer "F.Cu")
			(hatch none 0.5)
			(connect_pads
				(clearance 0)
			)
			(min_thickness 0.25)
			(keepout
				(tracks not_allowed)
				(vias allowed)
				(pads allowed)
				(copperpour not_allowed)
				(footprints allowed)
			)
			(placement
				(enabled no)
				(sheetname "")
			)
			(fill
				(thermal_gap 0.5)
				(thermal_bridge_width 0.5)
				(island_removal_mode 0)
			)
			(polygon
				(pts
					(xy 274.193 -69.342) (xy 274.701 -69.342) (xy 274.701 -69.723) (xy 274.193 -69.723)
				)
			)
		)
	)
	(footprint ""
		(layer "F.Cu")
		(at 174.4218 -6.2103 180)
		(property "Reference" "R4G25"
			(at 0 0 180)
			(layer "F.SilkS")
			(hide yes)
			(effects
				(font
					(size 1.27 1.27)
				)
			)
		)
		(property "Value" ""
			(at 0 0 180)
			(layer "F.Fab")
			(effects
				(font
					(size 1.27 1.27)
				)
			)
		)
		(duplicate_pad_numbers_are_jumpers no)
		(fp_rect
			(start 0.2794 -0.1016)
			(end -0.2794 0.9906)
			(stroke
				(width 0)
				(type default)
			)
			(fill no)
			(layer "F.CrtYd")
		)
		(fp_line
			(start 0.2794 0.9906)
			(end 0.2794 -0.1016)
			(stroke
				(width 0.1)
				(type default)
			)
			(layer "F.Fab")
		)
		(fp_line
			(start 0.2794 -0.1016)
			(end -0.2794 -0.1016)
			(stroke
				(width 0.1)
				(type default)
			)
			(layer "F.Fab")
		)
		(fp_line
			(start -0.2794 0.9906)
			(end 0.2794 0.9906)
			(stroke
				(width 0.1)
				(type default)
			)
			(layer "F.Fab")
		)
		(fp_line
			(start -0.2794 -0.1016)
			(end -0.2794 0.9906)
			(stroke
				(width 0.1)
				(type default)
			)
			(layer "F.Fab")
		)
		(pad "1" smd rect
			(at 0 0 180)
			(size 0.508 0.508)
			(layers "F.Cu" "F.Mask" "F.Paste")
			(net "GND")
		)
		(pad "2" smd rect
			(at 0 0.889 180)
			(size 0.508 0.508)
			(layers "F.Cu" "F.Mask" "F.Paste")
			(net "AGND_PVPP_GHJ")
		)
		(zone
			(layer "F.Cu")
			(hatch none 0.5)
			(connect_pads
				(clearance 0)
			)
			(min_thickness 0.25)
			(keepout
				(tracks allowed)
				(vias not_allowed)
				(pads allowed)
				(copperpour not_allowed)
				(footprints allowed)
			)
			(placement
				(enabled no)
				(sheetname "")
			)
			(fill
				(thermal_gap 0.5)
				(thermal_bridge_width 0.5)
				(island_removal_mode 0)
			)
			(polygon
				(pts
					(xy 174.1678 -6.4643) (xy 174.6758 -6.4643) (xy 174.6758 -6.8453) (xy 174.1678 -6.8453)
				)
			)
		)
		(zone
			(layer "F.Cu")
			(hatch none 0.5)
			(connect_pads
				(clearance 0)
			)
			(min_thickness 0.25)
			(keepout
				(tracks not_allowed)
				(vias allowed)
				(pads allowed)
				(copperpour not_allowed)
				(footprints allowed)
			)
			(placement
				(enabled no)
				(sheetname "")
			)
			(fill
				(thermal_gap 0.5)
				(thermal_bridge_width 0.5)
				(island_removal_mode 0)
			)
			(polygon
				(pts
					(xy 174.1678 -6.4643) (xy 174.6758 -6.4643) (xy 174.6758 -6.8453) (xy 174.1678 -6.8453)
				)
			)
		)
	)
	(footprint ""
		(layer "F.Cu")
		(at 451.85838 -32.4485 90)
		(property "Reference" "R25W52"
			(at 0 0 90)
			(layer "F.SilkS")
			(hide yes)
			(effects
				(font
					(size 1.27 1.27)
				)
			)
		)
		(property "Value" "*"
			(at 0.064008 -4.108196 90)
			(unlocked yes)
			(layer "F.Fab")
			(hide yes)
			(effects
				(font
					(size 1.27 1.016)
					(thickness 0.1524)
				)
			)
		)
		(property "Device Type" "120R2F-GP_RCL_GP-120R2F-GP,64.A"
			(at 0.064008 -5.632196 90)
			(unlocked yes)
			(layer "F.Fab")
			(hide yes)
			(effects
				(font
					(size 1.27 1.016)
					(thickness 0.1524)
				)
			)
		)
		(duplicate_pad_numbers_are_jumpers no)
		(fp_line
			(start 0.508 -0.9398)
			(end -0.508 -0.9398)
			(stroke
				(width 0.1524)
				(type default)
			)
			(layer "F.SilkS")
		)
		(fp_line
			(start -0.508 -0.9398)
			(end -0.508 0.9398)
			(stroke
				(width 0.1524)
				(type default)
			)
			(layer "F.SilkS")
		)
		(fp_rect
			(start -0.508 0.9398)
			(end 0.508 -0.9398)
			(stroke
				(width 0)
				(type default)
			)
			(fill no)
			(layer "F.CrtYd")
		)
		(fp_rect
			(start -0.508 0.9398)
			(end 0.508 -0.9398)
			(stroke
				(width 0)
				(type default)
			)
			(fill no)
			(layer "F.Fab")
		)
		(pad "1" smd custom
			(at 0 -0.4445 90)
			(size 0.1397 0.1397)
			(layers "F.Cu" "F.Mask" "F.Paste")
			(net "BMC_M_MACT_N")
			(options
				(clearance outline)
				(anchor circle)
			)
			(primitives
				(gr_poly
					(pts
						(arc
							(start -0.1778 -0.2794)
							(mid -0.249642 -0.249642)
							(end -0.2794 -0.1778)
						)
						(arc
							(start -0.2794 0.1778)
							(mid -0.249642 0.249642)
							(end -0.1778 0.2794)
						)
						(arc
							(start 0.1778 0.2794)
							(mid 0.249642 0.249642)
							(end 0.2794 0.1778)
						)
						(arc
							(start 0.2794 -0.1778)
							(mid 0.249642 -0.249642)
							(end 0.1778 -0.2794)
						)
					)
					(width 0)
					(fill yes)
				)
			)
		)
		(pad "2" smd custom
			(at 0 0.4445 90)
			(size 0.1397 0.1397)
			(layers "F.Cu" "F.Mask" "F.Paste")
			(net "P1V2_AUX_BMC")
			(options
				(clearance outline)
				(anchor circle)
			)
			(primitives
				(gr_poly
					(pts
						(arc
							(start -0.1778 -0.2794)
							(mid -0.249642 -0.249642)
							(end -0.2794 -0.1778)
						)
						(arc
							(start -0.2794 0.1778)
							(mid -0.249642 0.249642)
							(end -0.1778 0.2794)
						)
						(arc
							(start 0.1778 0.2794)
							(mid 0.249642 0.249642)
							(end 0.2794 0.1778)
						)
						(arc
							(start 0.2794 -0.1778)
							(mid 0.249642 -0.249642)
							(end 0.1778 -0.2794)
						)
					)
					(width 0)
					(fill yes)
				)
			)
		)
	)
	(footprint ""
		(layer "F.Cu")
		(at 369.954556 -156.250894 180)
		(property "Reference" "C7A14"
			(at 0 0 180)
			(layer "F.SilkS")
			(hide yes)
			(effects
				(font
					(size 1.27 1.27)
				)
			)
		)
		(property "Value" "*"
			(at -0.0762 -6.2357 180)
			(unlocked yes)
			(layer "F.Fab")
			(hide yes)
			(effects
				(font
					(size 1.27 1.016)
					(thickness 0.1524)
				)
			)
		)
		(property "Device Type" "SC22U16V5MX-4-GP_SMD-BCG5-SC22A"
			(at -0.0762 -8.2677 180)
			(unlocked yes)
			(layer "F.Fab")
			(hide yes)
			(effects
				(font
					(size 1.27 1.016)
					(thickness 0.1524)
				)
			)
		)
		(duplicate_pad_numbers_are_jumpers no)
		(fp_line
			(start 0.635 0)
			(end -0.635 0)
			(stroke
				(width 0.508)
				(type default)
			)
			(layer "F.SilkS")
		)
		(fp_rect
			(start -0.9652 1.778)
			(end 0.9652 -1.778)
			(stroke
				(width 0)
				(type default)
			)
			(fill no)
			(layer "F.CrtYd")
		)
		(fp_poly
			(pts
				(xy -0.9652 -1.778) (xy 0.9652 -1.778) (xy 0.9652 1.778) (xy -0.9652 1.778)
			)
			(stroke
				(width 0)
				(type default)
			)
			(fill no)
			(layer "F.Fab")
		)
		(pad "1" smd rect
			(at 0 -0.9652 180)
			(size 1.397 1.143)
			(layers "F.Cu" "F.Mask" "F.Paste")
			(net "VR_FET_SW_P12V_STBY_PVDDQ_DEF")
		)
		(pad "2" smd rect
			(at 0 0.9652 180)
			(size 1.397 1.143)
			(layers "F.Cu" "F.Mask" "F.Paste")
			(net "GND")
		)
	)
	(footprint ""
		(layer "F.Cu")
		(at 320.296032 -140.208 90)
		(property "Reference" "C6A7"
			(at 0 0 90)
			(layer "F.SilkS")
			(hide yes)
			(effects
				(font
					(size 1.27 1.27)
				)
			)
		)
		(property "Value" ""
			(at 0 0 90)
			(layer "F.Fab")
			(effects
				(font
					(size 1.27 1.27)
				)
			)
		)
		(duplicate_pad_numbers_are_jumpers no)
		(fp_poly
			(pts
				(xy -0.4953 -0.2032) (xy 0.4953 -0.2032) (xy 0.4953 1.6002) (xy -0.4953 1.6002)
			)
			(stroke
				(width 0)
				(type default)
			)
			(fill no)
			(layer "F.CrtYd")
		)
		(fp_line
			(start 0.4953 -0.2032)
			(end 0.4953 1.6002)
			(stroke
				(width 0.1)
				(type default)
			)
			(layer "F.Fab")
		)
		(fp_line
			(start -0.4953 -0.2032)
			(end 0.4953 -0.2032)
			(stroke
				(width 0.1)
				(type default)
			)
			(layer "F.Fab")
		)
		(fp_line
			(start 0.4953 1.6002)
			(end -0.4953 1.6002)
			(stroke
				(width 0.1)
				(type default)
			)
			(layer "F.Fab")
		)
		(fp_line
			(start -0.4953 1.6002)
			(end -0.4953 -0.2032)
			(stroke
				(width 0.1)
				(type default)
			)
			(layer "F.Fab")
		)
		(pad "1" smd rect
			(at 0 0 90)
			(size 0.762 0.889)
			(layers "F.Cu" "F.Mask" "F.Paste")
			(net "PVPP_DEF")
		)
		(pad "2" smd rect
			(at 0 1.397 90)
			(size 0.762 0.889)
			(layers "F.Cu" "F.Mask" "F.Paste")
			(net "GND")
		)
		(zone
			(layer "F.Cu")
			(hatch none 0.5)
			(connect_pads
				(clearance 0)
			)
			(min_thickness 0.25)
			(keepout
				(tracks not_allowed)
				(vias allowed)
				(pads allowed)
				(copperpour not_allowed)
				(footprints allowed)
			)
			(placement
				(enabled no)
				(sheetname "")
			)
			(fill
				(thermal_gap 0.5)
				(thermal_bridge_width 0.5)
				(island_removal_mode 0)
			)
			(polygon
				(pts
					(xy 320.740532 -139.827) (xy 320.740532 -140.589) (xy 321.248532 -140.589) (xy 321.248532 -139.827)
				)
			)
		)
	)
	(footprint ""
		(layer "F.Cu")
		(at 332.888844 -117.35562 90)
		(property "Reference" "C6B20"
			(at -0.8382 -0.67818 90)
			(unlocked yes)
			(layer "F.SilkS")
			(effects
				(font
					(size 0.4064 0.254)
					(thickness 0.1524)
				)
				(justify left)
			)
		)
		(property "Value" ""
			(at 0 0 90)
			(layer "F.Fab")
			(effects
				(font
					(size 1.27 1.27)
				)
			)
		)
		(duplicate_pad_numbers_are_jumpers no)
		(fp_poly
			(pts
				(xy 0.3048 -0.1016) (xy 0.3048 0.9906) (xy -0.3048 0.9906) (xy -0.3048 -0.1016)
			)
			(stroke
				(width 0)
				(type default)
			)
			(fill no)
			(layer "F.CrtYd")
		)
		(fp_line
			(start 0.3048 -0.1016)
			(end -0.3048 -0.1016)
			(stroke
				(width 0.1)
				(type default)
			)
			(layer "F.Fab")
		)
		(fp_line
			(start -0.3048 -0.1016)
			(end -0.3048 0.9906)
			(stroke
				(width 0.1)
				(type default)
			)
			(layer "F.Fab")
		)
		(fp_line
			(start 0.3048 0.9906)
			(end 0.3048 -0.1016)
			(stroke
				(width 0.1)
				(type default)
			)
			(layer "F.Fab")
		)
		(fp_line
			(start -0.3048 0.9906)
			(end 0.3048 0.9906)
			(stroke
				(width 0.1)
				(type default)
			)
			(layer "F.Fab")
		)
		(pad "1" smd rect
			(at 0 0 90)
			(size 0.508 0.508)
			(layers "F.Cu" "F.Mask" "F.Paste")
			(net "P3E_CPU0_PE1_PCH_TXP<8>")
		)
		(pad "2" smd rect
			(at 0 0.889 90)
			(size 0.508 0.508)
			(layers "F.Cu" "F.Mask" "F.Paste")
			(net "P3E_CPU0_PE1_PCH_C_TXP<8>")
		)
		(zone
			(layer "F.Cu")
			(hatch none 0.5)
			(connect_pads
				(clearance 0)
			)
			(min_thickness 0.25)
			(keepout
				(tracks allowed)
				(vias not_allowed)
				(pads allowed)
				(copperpour not_allowed)
				(footprints allowed)
			)
			(placement
				(enabled no)
				(sheetname "")
			)
			(fill
				(thermal_gap 0.5)
				(thermal_bridge_width 0.5)
				(island_removal_mode 0)
			)
			(polygon
				(pts
					(xy 333.142844 -117.10162) (xy 333.142844 -117.60962) (xy 333.523844 -117.60962) (xy 333.523844 -117.10162)
				)
			)
		)
		(zone
			(layer "F.Cu")
			(hatch none 0.5)
			(connect_pads
				(clearance 0)
			)
			(min_thickness 0.25)
			(keepout
				(tracks not_allowed)
				(vias allowed)
				(pads allowed)
				(copperpour not_allowed)
				(footprints allowed)
			)
			(placement
				(enabled no)
				(sheetname "")
			)
			(fill
				(thermal_gap 0.5)
				(thermal_bridge_width 0.5)
				(island_removal_mode 0)
			)
			(polygon
				(pts
					(xy 333.523844 -117.10162) (xy 333.523844 -117.60962) (xy 333.142844 -117.60962) (xy 333.142844 -117.10162)
				)
			)
		)
	)
	(footprint ""
		(layer "F.Cu")
		(at 184.133998 -2.705608 -90)
		(property "Reference" "EU4G3"
			(at 3.086608 -1.617472 90)
			(unlocked yes)
			(layer "F.SilkS")
			(effects
				(font
					(size 0.7874 0.5842)
					(thickness 0.1524)
				)
				(justify left)
			)
		)
		(property "Value" ""
			(at 0 0 270)
			(layer "F.Fab")
			(effects
				(font
					(size 1.27 1.27)
				)
			)
		)
		(duplicate_pad_numbers_are_jumpers no)
		(fp_circle
			(center -0.835152 -0.417322)
			(end -0.835152 -0.544068)
			(stroke
				(width 0.254)
				(type default)
			)
			(fill no)
			(layer "F.SilkS")
		)
		(fp_poly
			(pts
				(xy -0.064516 -1.0922) (xy -0.064516 -0.3302) (xy 0.697484 -1.0922)
			)
			(stroke
				(width 0)
				(type default)
			)
			(fill yes)
			(layer "F.SilkS")
		)
		(fp_rect
			(start 0.597408 2.295398)
			(end 2.273808 -0.295402)
			(stroke
				(width 0)
				(type default)
			)
			(fill yes)
			(layer "F.Paste")
		)
		(fp_rect
			(start -0.064516 2.500122)
			(end 2.935478 -0.500126)
			(stroke
				(width 0)
				(type default)
			)
			(fill no)
			(layer "F.CrtYd")
		)
		(fp_line
			(start -0.064516 2.500122)
			(end -0.064516 -0.500126)
			(stroke
				(width 0.1)
				(type default)
			)
			(layer "F.Fab")
		)
		(fp_line
			(start 2.935478 2.500122)
			(end -0.064516 2.500122)
			(stroke
				(width 0.1)
				(type default)
			)
			(layer "F.Fab")
		)
		(fp_line
			(start -0.064516 -0.500126)
			(end 2.935478 -0.500126)
			(stroke
				(width 0.1)
				(type default)
			)
			(layer "F.Fab")
		)
		(fp_line
			(start 2.935478 -0.500126)
			(end 2.935478 2.500122)
			(stroke
				(width 0.1)
				(type default)
			)
			(layer "F.Fab")
		)
		(fp_circle
			(center -0.835152 -0.417322)
			(end -0.835152 -0.544068)
			(stroke
				(width 0.254)
				(type default)
			)
			(fill no)
			(layer "F.Fab")
		)
		(pad "1" smd rect
			(at 0 0 270)
			(size 0.6858 0.3048)
			(layers "F.Cu" "F.Mask" "F.Paste")
			(net "VR_PVTT_ABC_VREF")
		)
		(pad "2" smd rect
			(at 0 0.500126 270)
			(size 0.6858 0.3048)
			(layers "F.Cu" "F.Mask" "F.Paste")
			(net "VR_PVTT_ABC_BIAS")
		)
		(pad "3" smd rect
			(at 0 0.999998 270)
			(size 0.6858 0.3048)
			(layers "F.Cu" "F.Mask" "F.Paste")
			(net "GND")
		)
		(pad "4" smd rect
			(at 0 1.500124 270)
			(size 0.6858 0.3048)
			(layers "F.Cu" "F.Mask" "F.Paste")
			(net "VSENSE_PVDDQ_ABC_VTT")
		)
		(pad "5" smd rect
			(at 0 1.999996 270)
			(size 0.6858 0.3048)
			(layers "F.Cu" "F.Mask" "F.Paste")
			(net "PWRGD_PVTT_ABC_CPU0_R")
		)
		(pad "6" smd rect
			(at 2.871216 1.999996 270)
			(size 0.6858 0.3048)
			(layers "F.Cu" "F.Mask" "F.Paste")
			(net "VR_PVTT_ABC_SNS")
		)
		(pad "7" smd rect
			(at 2.871216 1.500124 270)
			(size 0.6858 0.3048)
			(layers "F.Cu" "F.Mask" "F.Paste")
			(net "FM_PVTT_ABC_EN_R")
		)
		(pad "8" smd rect
			(at 2.871216 0.999998 270)
			(size 0.6858 0.3048)
			(layers "F.Cu" "F.Mask" "F.Paste")
			(net "GND")
		)
		(pad "9" smd rect
			(at 2.871216 0.500126 270)
			(size 0.6858 0.3048)
			(layers "F.Cu" "F.Mask" "F.Paste")
			(net "PVTT_ABC")
		)
		(pad "10" smd rect
			(at 2.871216 0 270)
			(size 0.6858 0.3048)
			(layers "F.Cu" "F.Mask" "F.Paste")
			(net "PVDDQ_ABC")
		)
		(pad "11" smd rect
			(at 1.435608 0.999998 270)
			(size 1.6764 2.5908)
			(layers "F.Cu" "F.Mask" "F.Paste")
			(net "GND")
		)
	)
	(footprint ""
		(layer "F.Cu")
		(at 340.429088 -10.34161 90)
		(property "Reference" "RT34"
			(at 0 0 90)
			(layer "F.SilkS")
			(hide yes)
			(effects
				(font
					(size 1.27 1.27)
				)
			)
		)
		(property "Value" "*"
			(at -0.0254 -2.6289 90)
			(unlocked yes)
			(layer "F.Fab")
			(hide yes)
			(effects
				(font
					(size 1.27 1.016)
					(thickness 0.1524)
				)
			)
		)
		(property "Device Type" "1R3F-GP_RCL_GP-1R3F-GP,64.1R00A"
			(at -0.0254 -4.1529 90)
			(unlocked yes)
			(layer "F.Fab")
			(hide yes)
			(effects
				(font
					(size 1.27 1.016)
					(thickness 0.1524)
				)
			)
		)
		(duplicate_pad_numbers_are_jumpers no)
		(fp_line
			(start 0.2032 0)
			(end 0.4826 0)
			(stroke
				(width 0.2032)
				(type default)
			)
			(layer "F.SilkS")
		)
		(fp_line
			(start -0.4826 0)
			(end -0.2032 0)
			(stroke
				(width 0.2032)
				(type default)
			)
			(layer "F.SilkS")
		)
		(fp_rect
			(start -0.5842 1.3335)
			(end 0.5842 -1.3335)
			(stroke
				(width 0)
				(type default)
			)
			(fill no)
			(layer "F.CrtYd")
		)
		(fp_rect
			(start -0.5842 1.3335)
			(end 0.5842 -1.3335)
			(stroke
				(width 0)
				(type default)
			)
			(fill no)
			(layer "F.Fab")
		)
		(pad "1" smd custom
			(at 0 -0.762 90)
			(size 0.2159 0.2159)
			(layers "F.Cu" "F.Mask" "F.Paste")
			(net "VR_PVDDQ_ABC_PH1_SW_RC")
			(options
				(clearance outline)
				(anchor circle)
			)
			(primitives
				(gr_poly
					(pts
						(arc
							(start -0.3302 -0.4318)
							(mid -0.402042 -0.402042)
							(end -0.4318 -0.3302)
						)
						(arc
							(start -0.4318 0.3302)
							(mid -0.402042 0.402042)
							(end -0.3302 0.4318)
						)
						(arc
							(start 0.3302 0.4318)
							(mid 0.402042 0.402042)
							(end 0.4318 0.3302)
						)
						(arc
							(start 0.4318 -0.3302)
							(mid 0.402042 -0.402042)
							(end 0.3302 -0.4318)
						)
					)
					(width 0)
					(fill yes)
				)
			)
		)
		(pad "2" smd custom
			(at 0 0.762 90)
			(size 0.2159 0.2159)
			(layers "F.Cu" "F.Mask" "F.Paste")
			(net "GND")
			(options
				(clearance outline)
				(anchor circle)
			)
			(primitives
				(gr_poly
					(pts
						(arc
							(start -0.3302 -0.4318)
							(mid -0.402042 -0.402042)
							(end -0.4318 -0.3302)
						)
						(arc
							(start -0.4318 0.3302)
							(mid -0.402042 0.402042)
							(end -0.3302 0.4318)
						)
						(arc
							(start 0.3302 0.4318)
							(mid 0.402042 0.402042)
							(end 0.4318 0.3302)
						)
						(arc
							(start 0.4318 -0.3302)
							(mid 0.402042 -0.402042)
							(end 0.3302 -0.4318)
						)
					)
					(width 0)
					(fill yes)
				)
			)
		)
	)
	(footprint ""
		(layer "F.Cu")
		(at 166.649146 -146.302222 180)
		(property "Reference" "C4A13"
			(at 0 0 180)
			(layer "F.SilkS")
			(hide yes)
			(effects
				(font
					(size 1.27 1.27)
				)
			)
		)
		(property "Value" ""
			(at 0 0 180)
			(layer "F.Fab")
			(effects
				(font
					(size 1.27 1.27)
				)
			)
		)
		(duplicate_pad_numbers_are_jumpers no)
		(fp_rect
			(start -0.7239 1.9939)
			(end 0.7239 -0.2159)
			(stroke
				(width 0)
				(type default)
			)
			(fill no)
			(layer "F.CrtYd")
		)
		(fp_line
			(start 0.7239 1.9939)
			(end 0.7239 -0.2159)
			(stroke
				(width 0.1)
				(type default)
			)
			(layer "F.Fab")
		)
		(fp_line
			(start 0.7239 -0.2159)
			(end -0.7239 -0.2159)
			(stroke
				(width 0.1)
				(type default)
			)
			(layer "F.Fab")
		)
		(fp_line
			(start -0.7239 1.9939)
			(end 0.7239 1.9939)
			(stroke
				(width 0.1)
				(type default)
			)
			(layer "F.Fab")
		)
		(fp_line
			(start -0.7239 -0.2159)
			(end -0.7239 1.9939)
			(stroke
				(width 0.1)
				(type default)
			)
			(layer "F.Fab")
		)
		(pad "1" smd rect
			(at 0 0 180)
			(size 1.27 1.016)
			(layers "F.Cu" "F.Mask" "F.Paste")
			(net "PVTT_KLM")
		)
		(pad "2" smd rect
			(at 0 1.778 180)
			(size 1.27 1.016)
			(layers "F.Cu" "F.Mask" "F.Paste")
			(net "GND")
		)
		(zone
			(layer "F.Cu")
			(hatch none 0.5)
			(connect_pads
				(clearance 0)
			)
			(min_thickness 0.25)
			(keepout
				(tracks not_allowed)
				(vias allowed)
				(pads allowed)
				(copperpour not_allowed)
				(footprints allowed)
			)
			(placement
				(enabled no)
				(sheetname "")
			)
			(fill
				(thermal_gap 0.5)
				(thermal_bridge_width 0.5)
				(island_removal_mode 0)
			)
			(polygon
				(pts
					(xy 167.284146 -147.572222) (xy 166.014146 -147.572222) (xy 166.014146 -146.810222) (xy 167.284146 -146.810222)
				)
			)
		)
	)
	(footprint ""
		(layer "F.Cu")
		(at 13.8938 -33.909 90)
		(property "Reference" "C1F5"
			(at 0 0 90)
			(layer "F.SilkS")
			(hide yes)
			(effects
				(font
					(size 1.27 1.27)
				)
			)
		)
		(property "Value" ""
			(at 0 0 90)
			(layer "F.Fab")
			(effects
				(font
					(size 1.27 1.27)
				)
			)
		)
		(duplicate_pad_numbers_are_jumpers no)
		(fp_rect
			(start -0.3048 -0.1016)
			(end 0.3048 0.9906)
			(stroke
				(width 0)
				(type default)
			)
			(fill no)
			(layer "F.CrtYd")
		)
		(fp_line
			(start 0.3048 -0.1016)
			(end -0.3048 -0.1016)
			(stroke
				(width 0.1)
				(type default)
			)
			(layer "F.Fab")
		)
		(fp_line
			(start -0.3048 -0.1016)
			(end -0.3048 0.9906)
			(stroke
				(width 0.1)
				(type default)
			)
			(layer "F.Fab")
		)
		(fp_line
			(start 0.3048 0.9906)
			(end 0.3048 -0.1016)
			(stroke
				(width 0.1)
				(type default)
			)
			(layer "F.Fab")
		)
		(fp_line
			(start -0.3048 0.9906)
			(end 0.3048 0.9906)
			(stroke
				(width 0.1)
				(type default)
			)
			(layer "F.Fab")
		)
		(pad "1" smd rect
			(at 0 0 90)
			(size 0.508 0.508)
			(layers "F.Cu" "F.Mask" "F.Paste")
			(net "P3E_CPU1_PE3_MP_C_TXP<6>")
		)
		(pad "2" smd rect
			(at 0 0.889 90)
			(size 0.508 0.508)
			(layers "F.Cu" "F.Mask" "F.Paste")
			(net "P3E_CPU1_PE3_MP_TXP<6>")
		)
		(zone
			(layer "F.Cu")
			(hatch none 0.5)
			(connect_pads
				(clearance 0)
			)
			(min_thickness 0.25)
			(keepout
				(tracks not_allowed)
				(vias allowed)
				(pads allowed)
				(copperpour not_allowed)
				(footprints allowed)
			)
			(placement
				(enabled no)
				(sheetname "")
			)
			(fill
				(thermal_gap 0.5)
				(thermal_bridge_width 0.5)
				(island_removal_mode 0)
			)
			(polygon
				(pts
					(xy 14.1478 -33.655) (xy 14.5288 -33.655) (xy 14.5288 -34.163) (xy 14.1478 -34.163)
				)
			)
		)
		(zone
			(layer "F.Cu")
			(hatch none 0.5)
			(connect_pads
				(clearance 0)
			)
			(min_thickness 0.25)
			(keepout
				(tracks allowed)
				(vias not_allowed)
				(pads allowed)
				(copperpour not_allowed)
				(footprints allowed)
			)
			(placement
				(enabled no)
				(sheetname "")
			)
			(fill
				(thermal_gap 0.5)
				(thermal_bridge_width 0.5)
				(island_removal_mode 0)
			)
			(polygon
				(pts
					(xy 14.1478 -33.655) (xy 14.5288 -33.655) (xy 14.5288 -34.163) (xy 14.1478 -34.163)
				)
			)
		)
	)
	(footprint ""
		(layer "F.Cu")
		(at 398.145 -77.7875 180)
		(property "Reference" "R8E7"
			(at 0 0 180)
			(layer "F.SilkS")
			(hide yes)
			(effects
				(font
					(size 1.27 1.27)
				)
			)
		)
		(property "Value" ""
			(at 0 0 180)
			(layer "F.Fab")
			(effects
				(font
					(size 1.27 1.27)
				)
			)
		)
		(duplicate_pad_numbers_are_jumpers no)
		(fp_poly
			(pts
				(xy -0.2794 -0.1016) (xy 0.2794 -0.1016) (xy 0.2794 0.9906) (xy -0.2794 0.9906)
			)
			(stroke
				(width 0)
				(type default)
			)
			(fill no)
			(layer "F.CrtYd")
		)
		(fp_line
			(start 0.2794 0.9906)
			(end 0.2794 -0.1016)
			(stroke
				(width 0.1)
				(type default)
			)
			(layer "F.Fab")
		)
		(fp_line
			(start 0.2794 -0.1016)
			(end -0.2794 -0.1016)
			(stroke
				(width 0.1)
				(type default)
			)
			(layer "F.Fab")
		)
		(fp_line
			(start -0.2794 0.9906)
			(end 0.2794 0.9906)
			(stroke
				(width 0.1)
				(type default)
			)
			(layer "F.Fab")
		)
		(fp_line
			(start -0.2794 -0.1016)
			(end -0.2794 0.9906)
			(stroke
				(width 0.1)
				(type default)
			)
			(layer "F.Fab")
		)
		(pad "1" smd rect
			(at 0 0 180)
			(size 0.508 0.508)
			(layers "F.Cu" "F.Mask" "F.Paste")
			(net "PWRGD_P12V_HSC_DLY_R")
		)
		(pad "2" smd rect
			(at 0 0.889 180)
			(size 0.508 0.508)
			(layers "F.Cu" "F.Mask" "F.Paste")
			(net "PWRGD_P12V_HSC_DLY")
		)
		(zone
			(layer "F.Cu")
			(hatch none 0.5)
			(connect_pads
				(clearance 0)
			)
			(min_thickness 0.25)
			(keepout
				(tracks not_allowed)
				(vias allowed)
				(pads allowed)
				(copperpour not_allowed)
				(footprints allowed)
			)
			(placement
				(enabled no)
				(sheetname "")
			)
			(fill
				(thermal_gap 0.5)
				(thermal_bridge_width 0.5)
				(island_removal_mode 0)
			)
			(polygon
				(pts
					(xy 398.399 -78.4225) (xy 397.891 -78.4225) (xy 397.891 -78.0415) (xy 398.399 -78.0415)
				)
			)
		)
		(zone
			(layer "F.Cu")
			(hatch none 0.5)
			(connect_pads
				(clearance 0)
			)
			(min_thickness 0.25)
			(keepout
				(tracks allowed)
				(vias not_allowed)
				(pads allowed)
				(copperpour not_allowed)
				(footprints allowed)
			)
			(placement
				(enabled no)
				(sheetname "")
			)
			(fill
				(thermal_gap 0.5)
				(thermal_bridge_width 0.5)
				(island_removal_mode 0)
			)
			(polygon
				(pts
					(xy 398.399 -78.0415) (xy 397.891 -78.0415) (xy 397.891 -78.4225) (xy 398.399 -78.4225)
				)
			)
		)
	)
	(footprint ""
		(layer "F.Cu")
		(at 411.0355 -110.617 -90)
		(property "Reference" "R8C9"
			(at 0 0 270)
			(layer "F.SilkS")
			(hide yes)
			(effects
				(font
					(size 1.27 1.27)
				)
			)
		)
		(property "Value" ""
			(at 0 0 270)
			(layer "F.Fab")
			(effects
				(font
					(size 1.27 1.27)
				)
			)
		)
		(duplicate_pad_numbers_are_jumpers no)
		(fp_poly
			(pts
				(xy -0.2794 -0.1016) (xy 0.2794 -0.1016) (xy 0.2794 0.9906) (xy -0.2794 0.9906)
			)
			(stroke
				(width 0)
				(type default)
			)
			(fill no)
			(layer "F.CrtYd")
		)
		(fp_line
			(start -0.2794 0.9906)
			(end 0.2794 0.9906)
			(stroke
				(width 0.1)
				(type default)
			)
			(layer "F.Fab")
		)
		(fp_line
			(start 0.2794 0.9906)
			(end 0.2794 -0.1016)
			(stroke
				(width 0.1)
				(type default)
			)
			(layer "F.Fab")
		)
		(fp_line
			(start -0.2794 -0.1016)
			(end -0.2794 0.9906)
			(stroke
				(width 0.1)
				(type default)
			)
			(layer "F.Fab")
		)
		(fp_line
			(start 0.2794 -0.1016)
			(end -0.2794 -0.1016)
			(stroke
				(width 0.1)
				(type default)
			)
			(layer "F.Fab")
		)
		(pad "1" smd rect
			(at 0 0 270)
			(size 0.508 0.508)
			(layers "F.Cu" "F.Mask" "F.Paste")
			(net "P3V3_STBY")
		)
		(pad "2" smd rect
			(at 0 0.889 270)
			(size 0.508 0.508)
			(layers "F.Cu" "F.Mask" "F.Paste")
			(net "IRQ_SML0_ALERT_N")
		)
		(zone
			(layer "F.Cu")
			(hatch none 0.5)
			(connect_pads
				(clearance 0)
			)
			(min_thickness 0.25)
			(keepout
				(tracks not_allowed)
				(vias allowed)
				(pads allowed)
				(copperpour not_allowed)
				(footprints allowed)
			)
			(placement
				(enabled no)
				(sheetname "")
			)
			(fill
				(thermal_gap 0.5)
				(thermal_bridge_width 0.5)
				(island_removal_mode 0)
			)
			(polygon
				(pts
					(xy 410.4005 -110.871) (xy 410.4005 -110.363) (xy 410.7815 -110.363) (xy 410.7815 -110.871)
				)
			)
		)
		(zone
			(layer "F.Cu")
			(hatch none 0.5)
			(connect_pads
				(clearance 0)
			)
			(min_thickness 0.25)
			(keepout
				(tracks allowed)
				(vias not_allowed)
				(pads allowed)
				(copperpour not_allowed)
				(footprints allowed)
			)
			(placement
				(enabled no)
				(sheetname "")
			)
			(fill
				(thermal_gap 0.5)
				(thermal_bridge_width 0.5)
				(island_removal_mode 0)
			)
			(polygon
				(pts
					(xy 410.7815 -110.871) (xy 410.7815 -110.363) (xy 410.4005 -110.363) (xy 410.4005 -110.871)
				)
			)
		)
	)
	(footprint ""
		(layer "F.Cu")
		(at 96.94164 -77.636116)
		(property "Reference" "C2D22"
			(at 0 0 0)
			(layer "F.SilkS")
			(hide yes)
			(effects
				(font
					(size 1.27 1.27)
				)
			)
		)
		(property "Value" ""
			(at 0 0 0)
			(layer "F.Fab")
			(effects
				(font
					(size 1.27 1.27)
				)
			)
		)
		(duplicate_pad_numbers_are_jumpers no)
		(fp_poly
			(pts
				(xy -0.4953 -0.2032) (xy 0.4953 -0.2032) (xy 0.4953 1.6002) (xy -0.4953 1.6002)
			)
			(stroke
				(width 0)
				(type default)
			)
			(fill no)
			(layer "F.CrtYd")
		)
		(fp_line
			(start -0.4953 -0.2032)
			(end 0.4953 -0.2032)
			(stroke
				(width 0.1)
				(type default)
			)
			(layer "F.Fab")
		)
		(fp_line
			(start -0.4953 1.6002)
			(end -0.4953 -0.2032)
			(stroke
				(width 0.1)
				(type default)
			)
			(layer "F.Fab")
		)
		(fp_line
			(start 0.4953 -0.2032)
			(end 0.4953 1.6002)
			(stroke
				(width 0.1)
				(type default)
			)
			(layer "F.Fab")
		)
		(fp_line
			(start 0.4953 1.6002)
			(end -0.4953 1.6002)
			(stroke
				(width 0.1)
				(type default)
			)
			(layer "F.Fab")
		)
		(pad "1" smd rect
			(at 0 0)
			(size 0.762 0.889)
			(layers "F.Cu" "F.Mask" "F.Paste")
			(net "PVCCIN_CPU1")
		)
		(pad "2" smd rect
			(at 0 1.397)
			(size 0.762 0.889)
			(layers "F.Cu" "F.Mask" "F.Paste")
			(net "GND")
		)
		(zone
			(layer "F.Cu")
			(hatch none 0.5)
			(connect_pads
				(clearance 0)
			)
			(min_thickness 0.25)
			(keepout
				(tracks not_allowed)
				(vias allowed)
				(pads allowed)
				(copperpour not_allowed)
				(footprints allowed)
			)
			(placement
				(enabled no)
				(sheetname "")
			)
			(fill
				(thermal_gap 0.5)
				(thermal_bridge_width 0.5)
				(island_removal_mode 0)
			)
			(polygon
				(pts
					(xy 96.56064 -77.191616) (xy 97.32264 -77.191616) (xy 97.32264 -76.683616) (xy 96.56064 -76.683616)
				)
			)
		)
	)
	(footprint ""
		(layer "F.Cu")
		(at 422.148 -84.3915)
		(property "Reference" "R8D26"
			(at 0 0 0)
			(layer "F.SilkS")
			(hide yes)
			(effects
				(font
					(size 1.27 1.27)
				)
			)
		)
		(property "Value" ""
			(at 0 0 0)
			(layer "F.Fab")
			(effects
				(font
					(size 1.27 1.27)
				)
			)
		)
		(duplicate_pad_numbers_are_jumpers no)
		(fp_poly
			(pts
				(xy -0.2794 -0.1016) (xy 0.2794 -0.1016) (xy 0.2794 0.9906) (xy -0.2794 0.9906)
			)
			(stroke
				(width 0)
				(type default)
			)
			(fill no)
			(layer "F.CrtYd")
		)
		(fp_line
			(start -0.2794 -0.1016)
			(end -0.2794 0.9906)
			(stroke
				(width 0.1)
				(type default)
			)
			(layer "F.Fab")
		)
		(fp_line
			(start -0.2794 0.9906)
			(end 0.2794 0.9906)
			(stroke
				(width 0.1)
				(type default)
			)
			(layer "F.Fab")
		)
		(fp_line
			(start 0.2794 -0.1016)
			(end -0.2794 -0.1016)
			(stroke
				(width 0.1)
				(type default)
			)
			(layer "F.Fab")
		)
		(fp_line
			(start 0.2794 0.9906)
			(end 0.2794 -0.1016)
			(stroke
				(width 0.1)
				(type default)
			)
			(layer "F.Fab")
		)
		(pad "1" smd rect
			(at 0 0)
			(size 0.508 0.508)
			(layers "F.Cu" "F.Mask" "F.Paste")
			(net "P3V3_STBY")
		)
		(pad "2" smd rect
			(at 0 0.889)
			(size 0.508 0.508)
			(layers "F.Cu" "F.Mask" "F.Paste")
			(net "IRQ_SML1_PMBUS_ALERT_BUF_N")
		)
		(zone
			(layer "F.Cu")
			(hatch none 0.5)
			(connect_pads
				(clearance 0)
			)
			(min_thickness 0.25)
			(keepout
				(tracks allowed)
				(vias not_allowed)
				(pads allowed)
				(copperpour not_allowed)
				(footprints allowed)
			)
			(placement
				(enabled no)
				(sheetname "")
			)
			(fill
				(thermal_gap 0.5)
				(thermal_bridge_width 0.5)
				(island_removal_mode 0)
			)
			(polygon
				(pts
					(xy 421.894 -84.1375) (xy 422.402 -84.1375) (xy 422.402 -83.7565) (xy 421.894 -83.7565)
				)
			)
		)
		(zone
			(layer "F.Cu")
			(hatch none 0.5)
			(connect_pads
				(clearance 0)
			)
			(min_thickness 0.25)
			(keepout
				(tracks not_allowed)
				(vias allowed)
				(pads allowed)
				(copperpour not_allowed)
				(footprints allowed)
			)
			(placement
				(enabled no)
				(sheetname "")
			)
			(fill
				(thermal_gap 0.5)
				(thermal_bridge_width 0.5)
				(island_removal_mode 0)
			)
			(polygon
				(pts
					(xy 421.894 -83.7565) (xy 422.402 -83.7565) (xy 422.402 -84.1375) (xy 421.894 -84.1375)
				)
			)
		)
	)
	(footprint ""
		(layer "F.Cu")
		(at 29.337 13.2715 -90)
		(property "Reference" "T1P35"
			(at 0 0 270)
			(layer "F.SilkS")
			(hide yes)
			(effects
				(font
					(size 1.27 1.27)
				)
			)
		)
		(property "Value" "*"
			(at 0 -3.44805 270)
			(unlocked yes)
			(layer "F.Fab")
			(hide yes)
			(effects
				(font
					(size 0.889 0.889)
					(thickness 0.1524)
				)
			)
		)
		(property "Device Type" "TPAD-SE-2P-GP_DISCRET-GA1-TPADA"
			(at 0 -4.97205 270)
			(unlocked yes)
			(layer "F.Fab")
			(hide yes)
			(effects
				(font
					(size 0.889 0.889)
					(thickness 0.1524)
				)
			)
		)
		(duplicate_pad_numbers_are_jumpers no)
		(fp_line
			(start -1.016 2.286)
			(end -1.016 -2.286)
			(stroke
				(width 0.1524)
				(type default)
			)
			(layer "F.SilkS")
		)
		(fp_line
			(start 1.016 2.286)
			(end -1.016 2.286)
			(stroke
				(width 0.1524)
				(type default)
			)
			(layer "F.SilkS")
		)
		(fp_line
			(start -1.016 -2.286)
			(end 1.016 -2.286)
			(stroke
				(width 0.1524)
				(type default)
			)
			(layer "F.SilkS")
		)
		(fp_line
			(start 1.016 -2.286)
			(end 1.016 2.286)
			(stroke
				(width 0.1524)
				(type default)
			)
			(layer "F.SilkS")
		)
		(fp_rect
			(start -1.27 2.54)
			(end 1.27 -2.54)
			(stroke
				(width 0)
				(type default)
			)
			(fill no)
			(layer "F.CrtYd")
		)
		(fp_rect
			(start -1.27 2.54)
			(end 1.27 -2.54)
			(stroke
				(width 0)
				(type default)
			)
			(fill no)
			(layer "F.Fab")
		)
		(pad "1" thru_hole circle
			(at 0 -1.27 270)
			(size 1.524 1.524)
			(drill 0.9144)
			(layers "*.Cu" "*.Mask")
			(remove_unused_layers no)
			(net "L12_50OHM_6INCH")
			(clearance -0.0508)
			(thermal_gap 0.127)
			(padstack
				(mode front_inner_back)
				(layer "Inner"
					(shape circle)
					(size 1.1684 1.1684)
					(clearance 0.127)
				)
				(layer "B.Cu"
					(shape circle)
					(size 1.524 1.524)
					(clearance -0.0508)
				)
			)
		)
		(pad "GND1" thru_hole rect
			(at 0 1.27 270)
			(size 1.524 1.524)
			(drill 0.9144)
			(layers "*.Cu" "*.Mask")
			(remove_unused_layers no)
			(net "GND")
			(clearance -0.0508)
			(thermal_gap 0.127)
			(padstack
				(mode front_inner_back)
				(layer "Inner"
					(shape circle)
					(size 1.1684 1.1684)
					(clearance 0.127)
				)
				(layer "B.Cu"
					(shape rect)
					(size 1.524 1.524)
					(clearance -0.0508)
				)
			)
		)
	)
	(footprint ""
		(layer "F.Cu")
		(at 451.85838 -35.8775 90)
		(property "Reference" "R25W29"
			(at 0 0 90)
			(layer "F.SilkS")
			(hide yes)
			(effects
				(font
					(size 1.27 1.27)
				)
			)
		)
		(property "Value" "*"
			(at 0.064008 -4.108196 90)
			(unlocked yes)
			(layer "F.Fab")
			(hide yes)
			(effects
				(font
					(size 1.27 1.016)
					(thickness 0.1524)
				)
			)
		)
		(property "Device Type" "120R2F-GP_RCL_GP-120R2F-GP,64.A"
			(at 0.064008 -5.632196 90)
			(unlocked yes)
			(layer "F.Fab")
			(hide yes)
			(effects
				(font
					(size 1.27 1.016)
					(thickness 0.1524)
				)
			)
		)
		(duplicate_pad_numbers_are_jumpers no)
		(fp_line
			(start 0.508 -0.9398)
			(end -0.508 -0.9398)
			(stroke
				(width 0.1524)
				(type default)
			)
			(layer "F.SilkS")
		)
		(fp_line
			(start -0.508 -0.9398)
			(end -0.508 0.9398)
			(stroke
				(width 0.1524)
				(type default)
			)
			(layer "F.SilkS")
		)
		(fp_rect
			(start -0.508 0.9398)
			(end 0.508 -0.9398)
			(stroke
				(width 0)
				(type default)
			)
			(fill no)
			(layer "F.CrtYd")
		)
		(fp_rect
			(start -0.508 0.9398)
			(end 0.508 -0.9398)
			(stroke
				(width 0)
				(type default)
			)
			(fill no)
			(layer "F.Fab")
		)
		(pad "1" smd custom
			(at 0 -0.4445 90)
			(size 0.1397 0.1397)
			(layers "F.Cu" "F.Mask" "F.Paste")
			(net "BMC_M_RST_N")
			(options
				(clearance outline)
				(anchor circle)
			)
			(primitives
				(gr_poly
					(pts
						(arc
							(start -0.1778 -0.2794)
							(mid -0.249642 -0.249642)
							(end -0.2794 -0.1778)
						)
						(arc
							(start -0.2794 0.1778)
							(mid -0.249642 0.249642)
							(end -0.1778 0.2794)
						)
						(arc
							(start 0.1778 0.2794)
							(mid 0.249642 0.249642)
							(end 0.2794 0.1778)
						)
						(arc
							(start 0.2794 -0.1778)
							(mid 0.249642 -0.249642)
							(end 0.1778 -0.2794)
						)
					)
					(width 0)
					(fill yes)
				)
			)
		)
		(pad "2" smd custom
			(at 0 0.4445 90)
			(size 0.1397 0.1397)
			(layers "F.Cu" "F.Mask" "F.Paste")
			(net "P1V2_AUX_BMC")
			(options
				(clearance outline)
				(anchor circle)
			)
			(primitives
				(gr_poly
					(pts
						(arc
							(start -0.1778 -0.2794)
							(mid -0.249642 -0.249642)
							(end -0.2794 -0.1778)
						)
						(arc
							(start -0.2794 0.1778)
							(mid -0.249642 0.249642)
							(end -0.1778 0.2794)
						)
						(arc
							(start 0.1778 0.2794)
							(mid 0.249642 0.249642)
							(end 0.2794 0.1778)
						)
						(arc
							(start 0.2794 -0.1778)
							(mid 0.249642 -0.249642)
							(end 0.1778 -0.2794)
						)
					)
					(width 0)
					(fill yes)
				)
			)
		)
	)
	(footprint ""
		(layer "F.Cu")
		(at 415.1249 -51.5747 180)
		(property "Reference" "R1W6"
			(at 0 0 180)
			(layer "F.SilkS")
			(hide yes)
			(effects
				(font
					(size 1.27 1.27)
				)
			)
		)
		(property "Value" "*"
			(at 0.064008 -4.108196 180)
			(unlocked yes)
			(layer "F.Fab")
			(hide yes)
			(effects
				(font
					(size 1.27 1.016)
					(thickness 0.1524)
				)
			)
		)
		(property "Device Type" "1MR2F-L-GP_SMD-RG1-1MR2F-L-GP,A"
			(at 0.064008 -5.632196 180)
			(unlocked yes)
			(layer "F.Fab")
			(hide yes)
			(effects
				(font
					(size 1.27 1.016)
					(thickness 0.1524)
				)
			)
		)
		(duplicate_pad_numbers_are_jumpers no)
		(fp_line
			(start 0.508 -0.9398)
			(end -0.508 -0.9398)
			(stroke
				(width 0.1524)
				(type default)
			)
			(layer "F.SilkS")
		)
		(fp_line
			(start -0.508 -0.9398)
			(end -0.508 0.9398)
			(stroke
				(width 0.1524)
				(type default)
			)
			(layer "F.SilkS")
		)
		(fp_rect
			(start -0.508 0.9398)
			(end 0.508 -0.9398)
			(stroke
				(width 0)
				(type default)
			)
			(fill no)
			(layer "F.CrtYd")
		)
		(fp_rect
			(start -0.508 0.9398)
			(end 0.508 -0.9398)
			(stroke
				(width 0)
				(type default)
			)
			(fill no)
			(layer "F.Fab")
		)
		(pad "1" smd custom
			(at 0 -0.4445 180)
			(size 0.1397 0.1397)
			(layers "F.Cu" "F.Mask" "F.Paste")
			(net "P3V3_STBY")
			(options
				(clearance outline)
				(anchor circle)
			)
			(primitives
				(gr_poly
					(pts
						(arc
							(start -0.1778 -0.2794)
							(mid -0.249642 -0.249642)
							(end -0.2794 -0.1778)
						)
						(arc
							(start -0.2794 0.1778)
							(mid -0.249642 0.249642)
							(end -0.1778 0.2794)
						)
						(arc
							(start 0.1778 0.2794)
							(mid 0.249642 0.249642)
							(end 0.2794 0.1778)
						)
						(arc
							(start 0.2794 -0.1778)
							(mid 0.249642 -0.249642)
							(end 0.1778 -0.2794)
						)
					)
					(width 0)
					(fill yes)
				)
			)
		)
		(pad "2" smd custom
			(at 0 0.4445 180)
			(size 0.1397 0.1397)
			(layers "F.Cu" "F.Mask" "F.Paste")
			(net "FM_OCP_MEZZC_PRES_N")
			(options
				(clearance outline)
				(anchor circle)
			)
			(primitives
				(gr_poly
					(pts
						(arc
							(start -0.1778 -0.2794)
							(mid -0.249642 -0.249642)
							(end -0.2794 -0.1778)
						)
						(arc
							(start -0.2794 0.1778)
							(mid -0.249642 0.249642)
							(end -0.1778 0.2794)
						)
						(arc
							(start 0.1778 0.2794)
							(mid 0.249642 0.249642)
							(end 0.2794 0.1778)
						)
						(arc
							(start 0.2794 -0.1778)
							(mid 0.249642 -0.249642)
							(end 0.1778 -0.2794)
						)
					)
					(width 0)
					(fill yes)
				)
			)
		)
	)
	(footprint ""
		(layer "F.Cu")
		(at 460.463392 -41.512998)
		(property "Reference" "EU9F1"
			(at -0.256286 -1.396238 0)
			(unlocked yes)
			(layer "F.SilkS")
			(effects
				(font
					(size 0.7874 0.5842)
					(thickness 0.1524)
				)
				(justify left)
			)
		)
		(property "Value" ""
			(at 0 0 0)
			(layer "F.Fab")
			(effects
				(font
					(size 1.27 1.27)
				)
			)
		)
		(duplicate_pad_numbers_are_jumpers no)
		(fp_circle
			(center -0.835152 -0.417322)
			(end -0.708406 -0.417322)
			(stroke
				(width 0.254)
				(type default)
			)
			(fill no)
			(layer "F.SilkS")
		)
		(fp_poly
			(pts
				(xy -0.064516 -1.0922) (xy -0.064516 -0.3302) (xy 0.697484 -1.0922)
			)
			(stroke
				(width 0)
				(type default)
			)
			(fill yes)
			(layer "F.SilkS")
		)
		(fp_rect
			(start 0.597408 2.295398)
			(end 2.273808 -0.295402)
			(stroke
				(width 0)
				(type default)
			)
			(fill yes)
			(layer "F.Paste")
		)
		(fp_rect
			(start -0.064516 2.500122)
			(end 2.935478 -0.500126)
			(stroke
				(width 0)
				(type default)
			)
			(fill no)
			(layer "F.CrtYd")
		)
		(fp_line
			(start -0.064516 -0.500126)
			(end 2.935478 -0.500126)
			(stroke
				(width 0.1)
				(type default)
			)
			(layer "F.Fab")
		)
		(fp_line
			(start -0.064516 2.500122)
			(end -0.064516 -0.500126)
			(stroke
				(width 0.1)
				(type default)
			)
			(layer "F.Fab")
		)
		(fp_line
			(start 2.935478 -0.500126)
			(end 2.935478 2.500122)
			(stroke
				(width 0.1)
				(type default)
			)
			(layer "F.Fab")
		)
		(fp_line
			(start 2.935478 2.500122)
			(end -0.064516 2.500122)
			(stroke
				(width 0.1)
				(type default)
			)
			(layer "F.Fab")
		)
		(fp_circle
			(center -0.835152 -0.417322)
			(end -0.708406 -0.417322)
			(stroke
				(width 0.254)
				(type default)
			)
			(fill no)
			(layer "F.Fab")
		)
		(pad "1" smd rect
			(at 0 0)
			(size 0.6858 0.3048)
			(layers "F.Cu" "F.Mask" "F.Paste")
			(net "P1V15_AUX_BMC")
		)
		(pad "2" smd rect
			(at 0 0.500126)
			(size 0.6858 0.3048)
			(layers "F.Cu" "F.Mask" "F.Paste")
			(net "P1V15_AUX_BMC")
		)
		(pad "3" smd rect
			(at 0 0.999998)
			(size 0.6858 0.3048)
			(layers "F.Cu" "F.Mask" "F.Paste")
			(net "P1V15_AUX_BMC")
		)
		(pad "4" smd rect
			(at 0 1.500124)
			(size 0.6858 0.3048)
			(layers "F.Cu" "F.Mask" "F.Paste")
			(net "VR_P1V15_BMC_STBY_FB")
		)
		(pad "5" smd rect
			(at 0 1.999996)
			(size 0.6858 0.3048)
			(layers "F.Cu" "F.Mask" "F.Paste")
			(net "PWRGD_P1V15_BMC_STBY_R")
		)
		(pad "6" smd rect
			(at 2.871216 1.999996)
			(size 0.6858 0.3048)
			(layers "F.Cu" "F.Mask" "F.Paste")
			(net "PWRGD_P1V2_BMC_STBY")
		)
		(pad "7" smd rect
			(at 2.871216 1.500124)
			(size 0.6858 0.3048)
			(layers "F.Cu" "F.Mask" "F.Paste")
			(net "P3V3_STBY")
		)
		(pad "8" smd rect
			(at 2.871216 0.999998)
			(size 0.6858 0.3048)
			(layers "F.Cu" "F.Mask" "F.Paste")
			(net "P3V3_STBY")
		)
		(pad "9" smd rect
			(at 2.871216 0.500126)
			(size 0.6858 0.3048)
			(layers "F.Cu" "F.Mask" "F.Paste")
			(net "P3V3_STBY")
		)
		(pad "10" smd rect
			(at 2.871216 0)
			(size 0.6858 0.3048)
			(layers "F.Cu" "F.Mask" "F.Paste")
			(net "P3V3_STBY")
		)
		(pad "11" smd rect
			(at 1.435608 0.999998)
			(size 1.6764 2.5908)
			(layers "F.Cu" "F.Mask" "F.Paste")
			(net "GND")
		)
	)
	(footprint ""
		(layer "F.Cu")
		(at 378.254768 -33.7185 90)
		(property "Reference" "C8F6"
			(at 0 0 90)
			(layer "F.SilkS")
			(hide yes)
			(effects
				(font
					(size 1.27 1.27)
				)
			)
		)
		(property "Value" ""
			(at 0 0 90)
			(layer "F.Fab")
			(effects
				(font
					(size 1.27 1.27)
				)
			)
		)
		(duplicate_pad_numbers_are_jumpers no)
		(fp_poly
			(pts
				(xy 0.3048 -0.1016) (xy 0.3048 0.9906) (xy -0.3048 0.9906) (xy -0.3048 -0.1016)
			)
			(stroke
				(width 0)
				(type default)
			)
			(fill no)
			(layer "F.CrtYd")
		)
		(fp_line
			(start 0.3048 -0.1016)
			(end -0.3048 -0.1016)
			(stroke
				(width 0.1)
				(type default)
			)
			(layer "F.Fab")
		)
		(fp_line
			(start -0.3048 -0.1016)
			(end -0.3048 0.9906)
			(stroke
				(width 0.1)
				(type default)
			)
			(layer "F.Fab")
		)
		(fp_line
			(start 0.3048 0.9906)
			(end 0.3048 -0.1016)
			(stroke
				(width 0.1)
				(type default)
			)
			(layer "F.Fab")
		)
		(fp_line
			(start -0.3048 0.9906)
			(end 0.3048 0.9906)
			(stroke
				(width 0.1)
				(type default)
			)
			(layer "F.Fab")
		)
		(pad "1" smd rect
			(at 0 0 90)
			(size 0.508 0.508)
			(layers "F.Cu" "F.Mask" "F.Paste")
			(net "SATA6G_S0_TX_DP")
		)
		(pad "2" smd rect
			(at 0 0.889 90)
			(size 0.508 0.508)
			(layers "F.Cu" "F.Mask" "F.Paste")
			(net "P3E_PCH_M2_SATA6G_TX_R_DP")
		)
		(zone
			(layer "F.Cu")
			(hatch none 0.5)
			(connect_pads
				(clearance 0)
			)
			(min_thickness 0.25)
			(keepout
				(tracks allowed)
				(vias not_allowed)
				(pads allowed)
				(copperpour not_allowed)
				(footprints allowed)
			)
			(placement
				(enabled no)
				(sheetname "")
			)
			(fill
				(thermal_gap 0.5)
				(thermal_bridge_width 0.5)
				(island_removal_mode 0)
			)
			(polygon
				(pts
					(xy 378.508768 -33.4645) (xy 378.508768 -33.9725) (xy 378.889768 -33.9725) (xy 378.889768 -33.4645)
				)
			)
		)
		(zone
			(layer "F.Cu")
			(hatch none 0.5)
			(connect_pads
				(clearance 0)
			)
			(min_thickness 0.25)
			(keepout
				(tracks not_allowed)
				(vias allowed)
				(pads allowed)
				(copperpour not_allowed)
				(footprints allowed)
			)
			(placement
				(enabled no)
				(sheetname "")
			)
			(fill
				(thermal_gap 0.5)
				(thermal_bridge_width 0.5)
				(island_removal_mode 0)
			)
			(polygon
				(pts
					(xy 378.889768 -33.4645) (xy 378.889768 -33.9725) (xy 378.508768 -33.9725) (xy 378.508768 -33.4645)
				)
			)
		)
	)
	(footprint ""
		(layer "F.Cu")
		(at 339.222588 -117.941598 -90)
		(property "Reference" "C845"
			(at -0.8382 -0.67818 270)
			(unlocked yes)
			(layer "F.SilkS")
			(effects
				(font
					(size 0.4064 0.254)
					(thickness 0.1524)
				)
				(justify left)
			)
		)
		(property "Value" ""
			(at 0 0 270)
			(layer "F.Fab")
			(effects
				(font
					(size 1.27 1.27)
				)
			)
		)
		(duplicate_pad_numbers_are_jumpers no)
		(fp_poly
			(pts
				(xy 0.3048 -0.1016) (xy 0.3048 0.9906) (xy -0.3048 0.9906) (xy -0.3048 -0.1016)
			)
			(stroke
				(width 0)
				(type default)
			)
			(fill no)
			(layer "F.CrtYd")
		)
		(fp_line
			(start -0.3048 0.9906)
			(end 0.3048 0.9906)
			(stroke
				(width 0.1)
				(type default)
			)
			(layer "F.Fab")
		)
		(fp_line
			(start 0.3048 0.9906)
			(end 0.3048 -0.1016)
			(stroke
				(width 0.1)
				(type default)
			)
			(layer "F.Fab")
		)
		(fp_line
			(start -0.3048 -0.1016)
			(end -0.3048 0.9906)
			(stroke
				(width 0.1)
				(type default)
			)
			(layer "F.Fab")
		)
		(fp_line
			(start 0.3048 -0.1016)
			(end -0.3048 -0.1016)
			(stroke
				(width 0.1)
				(type default)
			)
			(layer "F.Fab")
		)
		(pad "1" smd rect
			(at 0 0 270)
			(size 0.508 0.508)
			(layers "F.Cu" "F.Mask" "F.Paste")
			(net "P3E_CPU0_PE1_PCH_TXP<9>")
		)
		(pad "2" smd rect
			(at 0 0.889 270)
			(size 0.508 0.508)
			(layers "F.Cu" "F.Mask" "F.Paste")
			(net "P3E_CPU0_PE1_PCH_CON_TXP<9>")
		)
		(zone
			(layer "F.Cu")
			(hatch none 0.5)
			(connect_pads
				(clearance 0)
			)
			(min_thickness 0.25)
			(keepout
				(tracks not_allowed)
				(vias allowed)
				(pads allowed)
				(copperpour not_allowed)
				(footprints allowed)
			)
			(placement
				(enabled no)
				(sheetname "")
			)
			(fill
				(thermal_gap 0.5)
				(thermal_bridge_width 0.5)
				(island_removal_mode 0)
			)
			(polygon
				(pts
					(xy 338.587588 -118.195598) (xy 338.587588 -117.687598) (xy 338.968588 -117.687598) (xy 338.968588 -118.195598)
				)
			)
		)
		(zone
			(layer "F.Cu")
			(hatch none 0.5)
			(connect_pads
				(clearance 0)
			)
			(min_thickness 0.25)
			(keepout
				(tracks allowed)
				(vias not_allowed)
				(pads allowed)
				(copperpour not_allowed)
				(footprints allowed)
			)
			(placement
				(enabled no)
				(sheetname "")
			)
			(fill
				(thermal_gap 0.5)
				(thermal_bridge_width 0.5)
				(island_removal_mode 0)
			)
			(polygon
				(pts
					(xy 338.968588 -118.195598) (xy 338.968588 -117.687598) (xy 338.587588 -117.687598) (xy 338.587588 -118.195598)
				)
			)
		)
	)
	(footprint ""
		(layer "F.Cu")
		(at 348.053914 -149.939502 -90)
		(property "Reference" "C7A5"
			(at 0 0 270)
			(layer "F.SilkS")
			(hide yes)
			(effects
				(font
					(size 1.27 1.27)
				)
			)
		)
		(property "Value" ""
			(at 0 0 270)
			(layer "F.Fab")
			(effects
				(font
					(size 1.27 1.27)
				)
			)
		)
		(duplicate_pad_numbers_are_jumpers no)
		(fp_poly
			(pts
				(xy 0.3048 -0.1016) (xy 0.3048 0.9906) (xy -0.3048 0.9906) (xy -0.3048 -0.1016)
			)
			(stroke
				(width 0)
				(type default)
			)
			(fill no)
			(layer "F.CrtYd")
		)
		(fp_line
			(start -0.3048 0.9906)
			(end 0.3048 0.9906)
			(stroke
				(width 0.1)
				(type default)
			)
			(layer "F.Fab")
		)
		(fp_line
			(start 0.3048 0.9906)
			(end 0.3048 -0.1016)
			(stroke
				(width 0.1)
				(type default)
			)
			(layer "F.Fab")
		)
		(fp_line
			(start -0.3048 -0.1016)
			(end -0.3048 0.9906)
			(stroke
				(width 0.1)
				(type default)
			)
			(layer "F.Fab")
		)
		(fp_line
			(start 0.3048 -0.1016)
			(end -0.3048 -0.1016)
			(stroke
				(width 0.1)
				(type default)
			)
			(layer "F.Fab")
		)
		(pad "1" smd rect
			(at 0 0 270)
			(size 0.508 0.508)
			(layers "F.Cu" "F.Mask" "F.Paste")
			(net "VR_FET_SW_P12V_STBY_PVDDQ_DEF")
		)
		(pad "2" smd rect
			(at 0 0.889 270)
			(size 0.508 0.508)
			(layers "F.Cu" "F.Mask" "F.Paste")
			(net "GND")
		)
		(zone
			(layer "F.Cu")
			(hatch none 0.5)
			(connect_pads
				(clearance 0)
			)
			(min_thickness 0.25)
			(keepout
				(tracks not_allowed)
				(vias allowed)
				(pads allowed)
				(copperpour not_allowed)
				(footprints allowed)
			)
			(placement
				(enabled no)
				(sheetname "")
			)
			(fill
				(thermal_gap 0.5)
				(thermal_bridge_width 0.5)
				(island_removal_mode 0)
			)
			(polygon
				(pts
					(xy 347.418914 -150.193502) (xy 347.418914 -149.685502) (xy 347.799914 -149.685502) (xy 347.799914 -150.193502)
				)
			)
		)
		(zone
			(layer "F.Cu")
			(hatch none 0.5)
			(connect_pads
				(clearance 0)
			)
			(min_thickness 0.25)
			(keepout
				(tracks allowed)
				(vias not_allowed)
				(pads allowed)
				(copperpour not_allowed)
				(footprints allowed)
			)
			(placement
				(enabled no)
				(sheetname "")
			)
			(fill
				(thermal_gap 0.5)
				(thermal_bridge_width 0.5)
				(island_removal_mode 0)
			)
			(polygon
				(pts
					(xy 347.799914 -150.193502) (xy 347.799914 -149.685502) (xy 347.418914 -149.685502) (xy 347.418914 -150.193502)
				)
			)
		)
	)
	(footprint ""
		(layer "F.Cu")
		(at 340.806278 -24.508206 90)
		(property "Reference" "R7F9"
			(at 0 0 90)
			(layer "F.SilkS")
			(hide yes)
			(effects
				(font
					(size 1.27 1.27)
				)
			)
		)
		(property "Value" ""
			(at 0 0 90)
			(layer "F.Fab")
			(effects
				(font
					(size 1.27 1.27)
				)
			)
		)
		(duplicate_pad_numbers_are_jumpers no)
		(fp_poly
			(pts
				(xy -0.2794 -0.1016) (xy 0.2794 -0.1016) (xy 0.2794 0.9906) (xy -0.2794 0.9906)
			)
			(stroke
				(width 0)
				(type default)
			)
			(fill no)
			(layer "F.CrtYd")
		)
		(fp_line
			(start 0.2794 -0.1016)
			(end -0.2794 -0.1016)
			(stroke
				(width 0.1)
				(type default)
			)
			(layer "F.Fab")
		)
		(fp_line
			(start -0.2794 -0.1016)
			(end -0.2794 0.9906)
			(stroke
				(width 0.1)
				(type default)
			)
			(layer "F.Fab")
		)
		(fp_line
			(start 0.2794 0.9906)
			(end 0.2794 -0.1016)
			(stroke
				(width 0.1)
				(type default)
			)
			(layer "F.Fab")
		)
		(fp_line
			(start -0.2794 0.9906)
			(end 0.2794 0.9906)
			(stroke
				(width 0.1)
				(type default)
			)
			(layer "F.Fab")
		)
		(pad "1" smd rect
			(at 0 0 90)
			(size 0.508 0.508)
			(layers "F.Cu" "F.Mask" "F.Paste")
			(net "FM_PVPP_CPU0_EN")
		)
		(pad "2" smd rect
			(at 0 0.889 90)
			(size 0.508 0.508)
			(layers "F.Cu" "F.Mask" "F.Paste")
			(net "FM_PVPP_PVDDQ_CPU0_EN_ABC")
		)
		(zone
			(layer "F.Cu")
			(hatch none 0.5)
			(connect_pads
				(clearance 0)
			)
			(min_thickness 0.25)
			(keepout
				(tracks allowed)
				(vias not_allowed)
				(pads allowed)
				(copperpour not_allowed)
				(footprints allowed)
			)
			(placement
				(enabled no)
				(sheetname "")
			)
			(fill
				(thermal_gap 0.5)
				(thermal_bridge_width 0.5)
				(island_removal_mode 0)
			)
			(polygon
				(pts
					(xy 341.060278 -24.254206) (xy 341.060278 -24.762206) (xy 341.441278 -24.762206) (xy 341.441278 -24.254206)
				)
			)
		)
		(zone
			(layer "F.Cu")
			(hatch none 0.5)
			(connect_pads
				(clearance 0)
			)
			(min_thickness 0.25)
			(keepout
				(tracks not_allowed)
				(vias allowed)
				(pads allowed)
				(copperpour not_allowed)
				(footprints allowed)
			)
			(placement
				(enabled no)
				(sheetname "")
			)
			(fill
				(thermal_gap 0.5)
				(thermal_bridge_width 0.5)
				(island_removal_mode 0)
			)
			(polygon
				(pts
					(xy 341.441278 -24.254206) (xy 341.441278 -24.762206) (xy 341.060278 -24.762206) (xy 341.060278 -24.254206)
				)
			)
		)
	)
	(footprint ""
		(layer "F.Cu")
		(at 193.127122 -140.177012 -90)
		(property "Reference" "C4A17"
			(at 0 0 270)
			(layer "F.SilkS")
			(hide yes)
			(effects
				(font
					(size 1.27 1.27)
				)
			)
		)
		(property "Value" ""
			(at 0 0 270)
			(layer "F.Fab")
			(effects
				(font
					(size 1.27 1.27)
				)
			)
		)
		(duplicate_pad_numbers_are_jumpers no)
		(fp_rect
			(start -0.7239 1.9939)
			(end 0.7239 -0.2159)
			(stroke
				(width 0)
				(type default)
			)
			(fill no)
			(layer "F.CrtYd")
		)
		(fp_line
			(start -0.7239 1.9939)
			(end 0.7239 1.9939)
			(stroke
				(width 0.1)
				(type default)
			)
			(layer "F.Fab")
		)
		(fp_line
			(start 0.7239 1.9939)
			(end 0.7239 -0.2159)
			(stroke
				(width 0.1)
				(type default)
			)
			(layer "F.Fab")
		)
		(fp_line
			(start -0.7239 -0.2159)
			(end -0.7239 1.9939)
			(stroke
				(width 0.1)
				(type default)
			)
			(layer "F.Fab")
		)
		(fp_line
			(start 0.7239 -0.2159)
			(end -0.7239 -0.2159)
			(stroke
				(width 0.1)
				(type default)
			)
			(layer "F.Fab")
		)
		(pad "1" smd rect
			(at 0 0 270)
			(size 1.27 1.016)
			(layers "F.Cu" "F.Mask" "F.Paste")
			(net "P12V_NVDIMM_DEF")
		)
		(pad "2" smd rect
			(at 0 1.778 270)
			(size 1.27 1.016)
			(layers "F.Cu" "F.Mask" "F.Paste")
			(net "GND")
		)
		(zone
			(layer "F.Cu")
			(hatch none 0.5)
			(connect_pads
				(clearance 0)
			)
			(min_thickness 0.25)
			(keepout
				(tracks not_allowed)
				(vias allowed)
				(pads allowed)
				(copperpour not_allowed)
				(footprints allowed)
			)
			(placement
				(enabled no)
				(sheetname "")
			)
			(fill
				(thermal_gap 0.5)
				(thermal_bridge_width 0.5)
				(island_removal_mode 0)
			)
			(polygon
				(pts
					(xy 191.857122 -140.812012) (xy 191.857122 -139.542012) (xy 192.619122 -139.542012) (xy 192.619122 -140.812012)
				)
			)
		)
	)
	(footprint ""
		(layer "F.Cu")
		(at 100.67544 -73.318116)
		(property "Reference" "C2D36"
			(at 0 0 0)
			(layer "F.SilkS")
			(hide yes)
			(effects
				(font
					(size 1.27 1.27)
				)
			)
		)
		(property "Value" ""
			(at 0 0 0)
			(layer "F.Fab")
			(effects
				(font
					(size 1.27 1.27)
				)
			)
		)
		(duplicate_pad_numbers_are_jumpers no)
		(fp_poly
			(pts
				(xy -0.4953 -0.2032) (xy 0.4953 -0.2032) (xy 0.4953 1.6002) (xy -0.4953 1.6002)
			)
			(stroke
				(width 0)
				(type default)
			)
			(fill no)
			(layer "F.CrtYd")
		)
		(fp_line
			(start -0.4953 -0.2032)
			(end 0.4953 -0.2032)
			(stroke
				(width 0.1)
				(type default)
			)
			(layer "F.Fab")
		)
		(fp_line
			(start -0.4953 1.6002)
			(end -0.4953 -0.2032)
			(stroke
				(width 0.1)
				(type default)
			)
			(layer "F.Fab")
		)
		(fp_line
			(start 0.4953 -0.2032)
			(end 0.4953 1.6002)
			(stroke
				(width 0.1)
				(type default)
			)
			(layer "F.Fab")
		)
		(fp_line
			(start 0.4953 1.6002)
			(end -0.4953 1.6002)
			(stroke
				(width 0.1)
				(type default)
			)
			(layer "F.Fab")
		)
		(pad "1" smd rect
			(at 0 0)
			(size 0.762 0.889)
			(layers "F.Cu" "F.Mask" "F.Paste")
			(net "PVCCIN_CPU1")
		)
		(pad "2" smd rect
			(at 0 1.397)
			(size 0.762 0.889)
			(layers "F.Cu" "F.Mask" "F.Paste")
			(net "GND")
		)
		(zone
			(layer "F.Cu")
			(hatch none 0.5)
			(connect_pads
				(clearance 0)
			)
			(min_thickness 0.25)
			(keepout
				(tracks not_allowed)
				(vias allowed)
				(pads allowed)
				(copperpour not_allowed)
				(footprints allowed)
			)
			(placement
				(enabled no)
				(sheetname "")
			)
			(fill
				(thermal_gap 0.5)
				(thermal_bridge_width 0.5)
				(island_removal_mode 0)
			)
			(polygon
				(pts
					(xy 100.29444 -72.873616) (xy 101.05644 -72.873616) (xy 101.05644 -72.365616) (xy 100.29444 -72.365616)
				)
			)
		)
	)
	(footprint ""
		(layer "F.Cu")
		(at 33.925002 -57.039764 90)
		(property "Reference" "EU1E2"
			(at 3.360166 -1.768602 0)
			(unlocked yes)
			(layer "F.SilkS")
			(effects
				(font
					(size 0.7874 0.5842)
					(thickness 0.1524)
				)
			)
		)
		(property "Value" ""
			(at 0 0 90)
			(layer "F.Fab")
			(effects
				(font
					(size 1.27 1.27)
				)
			)
		)
		(duplicate_pad_numbers_are_jumpers no)
		(fp_line
			(start 2.9718 -3.5052)
			(end 2.9718 3.429)
			(stroke
				(width 0.1524)
				(type default)
			)
			(layer "F.SilkS")
		)
		(fp_line
			(start -3.0099 -3.5052)
			(end 2.9718 -3.5052)
			(stroke
				(width 0.1524)
				(type default)
			)
			(layer "F.SilkS")
		)
		(fp_line
			(start 2.9718 3.429)
			(end -3.0099 3.429)
			(stroke
				(width 0.1524)
				(type default)
			)
			(layer "F.SilkS")
		)
		(fp_line
			(start -3.0099 3.429)
			(end -3.0099 -3.5052)
			(stroke
				(width 0.1524)
				(type default)
			)
			(layer "F.SilkS")
		)
		(fp_circle
			(center -3.057398 -2.678684)
			(end -3.057398 -2.551684)
			(stroke
				(width 0.254)
				(type default)
			)
			(fill no)
			(layer "F.SilkS")
		)
		(fp_poly
			(pts
				(xy -2.9972 -3.4925) (xy -2.9972 -2.6924) (xy -2.1971 -3.4925)
			)
			(stroke
				(width 0)
				(type default)
			)
			(fill yes)
			(layer "F.SilkS")
		)
		(fp_poly
			(pts
				(xy -2.549906 -3.050032) (xy -2.549906 3.050032) (xy 2.549906 3.050032) (xy 2.549906 -3.050032)
			)
			(stroke
				(width 0)
				(type default)
			)
			(fill no)
			(layer "F.CrtYd")
		)
		(fp_line
			(start 2.549906 -3.050032)
			(end 2.549906 3.050032)
			(stroke
				(width 0.1)
				(type default)
			)
			(layer "F.Fab")
		)
		(fp_line
			(start -2.549906 -3.050032)
			(end 2.549906 -3.050032)
			(stroke
				(width 0.1)
				(type default)
			)
			(layer "F.Fab")
		)
		(fp_line
			(start 2.549906 3.050032)
			(end -2.549906 3.050032)
			(stroke
				(width 0.1)
				(type default)
			)
			(layer "F.Fab")
		)
		(fp_line
			(start -2.549906 3.050032)
			(end -2.549906 -3.050032)
			(stroke
				(width 0.1)
				(type default)
			)
			(layer "F.Fab")
		)
		(fp_circle
			(center -3.057398 -2.678684)
			(end -3.057398 -2.551684)
			(stroke
				(width 0.254)
				(type default)
			)
			(fill no)
			(layer "F.Fab")
		)
		(pad "1" smd rect
			(at -2.39522 -2.279904 90)
			(size 0.7112 0.254)
			(layers "F.Cu" "F.Mask" "F.Paste")
			(net "PVCCIN_CPU1")
		)
		(pad "2" smd rect
			(at -2.39522 -1.83007 90)
			(size 0.7112 0.254)
			(layers "F.Cu" "F.Mask" "F.Paste")
			(net "GND")
		)
		(pad "3" smd rect
			(at -2.39522 -1.379982 90)
			(size 0.7112 0.254)
			(layers "F.Cu" "F.Mask" "F.Paste")
			(net "VR_PVCCIN_CPU1_PH1_VCIN")
		)
		(pad "4" smd rect
			(at -2.39522 -0.929894 90)
			(size 0.7112 0.254)
			(layers "F.Cu" "F.Mask" "F.Paste")
			(net "P5V_STBY")
		)
		(pad "5" smd rect
			(at -2.39522 -0.48006 90)
			(size 0.7112 0.254)
			(layers "F.Cu" "F.Mask" "F.Paste")
			(net "GND")
		)
		(pad "6" smd rect
			(at -2.39522 -0.029972 90)
			(size 0.7112 0.254)
			(layers "F.Cu" "F.Mask" "F.Paste")
			(net "TP_PVCCINC_CPU1_PH1_GL_0")
		)
		(pad "7" smd custom
			(at 0.016764 1.145032 90)
			(size 0.53975 0.53975)
			(layers "F.Cu" "F.Mask" "F.Paste")
			(net "GND")
			(options
				(clearance outline)
				(anchor circle)
			)
			(primitives
				(gr_poly
					(pts
						(xy -2.7051 1.0795) (xy -2.7051 -0.3683) (xy -0.9271 -0.3683) (xy -0.9271 -1.0795) (xy 2.7051 -1.0795)
						(xy 2.7051 1.0795)
					)
					(width 0)
					(fill yes)
				)
			)
		)
		(pad "10" smd rect
			(at -0.008382 2.874772 90)
			(size 4.3434 0.6096)
			(layers "F.Cu" "F.Mask" "F.Paste")
			(net "VR_PVCCIN_CPU1_PHASE1")
		)
		(pad "25" smd rect
			(at 1.548384 -1.283208 90)
			(size 2.3368 2.0066)
			(layers "F.Cu" "F.Mask" "F.Paste")
			(net "VR_FET_SW_P12V_STBY_PVCCIN_CPU1")
		)
		(pad "30" smd rect
			(at 2.050034 -2.895092 90)
			(size 0.254 0.7112)
			(layers "F.Cu" "F.Mask" "F.Paste")
			(net "VR_FET_SW_P12V_STBY_PVCCIN_CPU1")
		)
		(pad "31" smd rect
			(at 1.599946 -2.895092 90)
			(size 0.254 0.7112)
			(layers "F.Cu" "F.Mask" "F.Paste")
			(net "Net_356")
		)
		(pad "32" smd rect
			(at 1.150112 -2.895092 90)
			(size 0.254 0.7112)
			(layers "F.Cu" "F.Mask" "F.Paste")
			(net "VR_PVCCIN_CPU1_PH1_PHASE")
		)
		(pad "33" smd rect
			(at 0.700024 -2.895092 90)
			(size 0.254 0.7112)
			(layers "F.Cu" "F.Mask" "F.Paste")
			(net "VR_PVCCIN_CPU1_PH1_BOOT_R")
		)
		(pad "34" smd rect
			(at 0.249936 -2.895092 90)
			(size 0.254 0.7112)
			(layers "F.Cu" "F.Mask" "F.Paste")
			(net "VR_PVCCIN_CPU1_PWM1")
		)
		(pad "35" smd rect
			(at -0.199898 -2.895092 90)
			(size 0.254 0.7112)
			(layers "F.Cu" "F.Mask" "F.Paste")
			(net "P5V_STBY")
		)
		(pad "36" smd rect
			(at -0.649986 -2.895092 90)
			(size 0.254 0.7112)
			(layers "F.Cu" "F.Mask" "F.Paste")
			(net "A_TSENSE_PVCCIN_CPU1")
		)
		(pad "37" smd rect
			(at -1.100074 -2.895092 90)
			(size 0.254 0.7112)
			(layers "F.Cu" "F.Mask" "F.Paste")
			(net "VR_PVCCIN_CPU1_PH1_OCSET")
		)
		(pad "38" smd rect
			(at -1.549908 -2.895092 90)
			(size 0.254 0.7112)
			(layers "F.Cu" "F.Mask" "F.Paste")
			(net "ISENSE_PVCCIN_CPU1_PH1_IMON")
		)
		(pad "39" smd rect
			(at -1.999996 -2.895092 90)
			(size 0.254 0.7112)
			(layers "F.Cu" "F.Mask" "F.Paste")
			(net "VR_PVCCIN_CPU1_AIREF1")
		)
		(pad "40" smd rect
			(at -0.871728 -1.283208 90)
			(size 1.8034 2.0066)
			(layers "F.Cu" "F.Mask" "F.Paste")
			(net "GND")
		)
		(pad "41" smd rect
			(at -1.533906 0.247904 90)
			(size 0.508 0.3556)
			(layers "F.Cu" "F.Mask" "F.Paste")
			(net "TP_PVCCINC_CPU1_PH1_GL_1")
		)
	)
	(footprint ""
		(layer "F.Cu")
		(at 16.891 -80.4545)
		(property "Reference" "R1D25"
			(at 0 0 0)
			(layer "F.SilkS")
			(hide yes)
			(effects
				(font
					(size 1.27 1.27)
				)
			)
		)
		(property "Value" ""
			(at 0 0 0)
			(layer "F.Fab")
			(effects
				(font
					(size 1.27 1.27)
				)
			)
		)
		(duplicate_pad_numbers_are_jumpers no)
		(fp_rect
			(start 0.2794 0.9906)
			(end -0.2794 -0.1016)
			(stroke
				(width 0)
				(type default)
			)
			(fill no)
			(layer "F.CrtYd")
		)
		(fp_line
			(start -0.2794 -0.1016)
			(end -0.2794 0.9906)
			(stroke
				(width 0.1)
				(type default)
			)
			(layer "F.Fab")
		)
		(fp_line
			(start -0.2794 0.9906)
			(end 0.2794 0.9906)
			(stroke
				(width 0.1)
				(type default)
			)
			(layer "F.Fab")
		)
		(fp_line
			(start 0.2794 -0.1016)
			(end -0.2794 -0.1016)
			(stroke
				(width 0.1)
				(type default)
			)
			(layer "F.Fab")
		)
		(fp_line
			(start 0.2794 0.9906)
			(end 0.2794 -0.1016)
			(stroke
				(width 0.1)
				(type default)
			)
			(layer "F.Fab")
		)
		(pad "1" smd rect
			(at 0 0)
			(size 0.508 0.508)
			(layers "F.Cu" "F.Mask" "F.Paste")
			(net "SMB_BMC_PMBUS_STBY_LVC3_SDA")
		)
		(pad "2" smd rect
			(at 0 0.889)
			(size 0.508 0.508)
			(layers "F.Cu" "F.Mask" "F.Paste")
			(net "SMB_3V3SB_HSC_SDA_R")
		)
		(zone
			(layer "F.Cu")
			(hatch none 0.5)
			(connect_pads
				(clearance 0)
			)
			(min_thickness 0.25)
			(keepout
				(tracks allowed)
				(vias not_allowed)
				(pads allowed)
				(copperpour not_allowed)
				(footprints allowed)
			)
			(placement
				(enabled no)
				(sheetname "")
			)
			(fill
				(thermal_gap 0.5)
				(thermal_bridge_width 0.5)
				(island_removal_mode 0)
			)
			(polygon
				(pts
					(xy 17.145 -79.8195) (xy 17.145 -80.2005) (xy 16.637 -80.2005) (xy 16.637 -79.8195)
				)
			)
		)
		(zone
			(layer "F.Cu")
			(hatch none 0.5)
			(connect_pads
				(clearance 0)
			)
			(min_thickness 0.25)
			(keepout
				(tracks not_allowed)
				(vias allowed)
				(pads allowed)
				(copperpour not_allowed)
				(footprints allowed)
			)
			(placement
				(enabled no)
				(sheetname "")
			)
			(fill
				(thermal_gap 0.5)
				(thermal_bridge_width 0.5)
				(island_removal_mode 0)
			)
			(polygon
				(pts
					(xy 17.145 -79.8195) (xy 17.145 -80.2005) (xy 16.637 -80.2005) (xy 16.637 -79.8195)
				)
			)
		)
	)
	(footprint ""
		(layer "F.Cu")
		(at 244.551454 -125.88113 -90)
		(property "Reference" "C5B2"
			(at 0 0 270)
			(layer "F.SilkS")
			(hide yes)
			(effects
				(font
					(size 1.27 1.27)
				)
			)
		)
		(property "Value" ""
			(at 0 0 270)
			(layer "F.Fab")
			(effects
				(font
					(size 1.27 1.27)
				)
			)
		)
		(duplicate_pad_numbers_are_jumpers no)
		(fp_rect
			(start -0.500126 1.598422)
			(end 0.500126 -0.201422)
			(stroke
				(width 0)
				(type default)
			)
			(fill no)
			(layer "F.CrtYd")
		)
		(fp_line
			(start -0.500126 1.598422)
			(end -0.500126 -0.201422)
			(stroke
				(width 0.1)
				(type default)
			)
			(layer "F.Fab")
		)
		(fp_line
			(start 0.500126 1.598422)
			(end -0.500126 1.598422)
			(stroke
				(width 0.1)
				(type default)
			)
			(layer "F.Fab")
		)
		(fp_line
			(start -0.500126 -0.201422)
			(end 0.500126 -0.201422)
			(stroke
				(width 0.1)
				(type default)
			)
			(layer "F.Fab")
		)
		(fp_line
			(start 0.500126 -0.201422)
			(end 0.500126 1.598422)
			(stroke
				(width 0.1)
				(type default)
			)
			(layer "F.Fab")
		)
		(pad "1" smd rect
			(at 0 0 180)
			(size 0.889 0.9906)
			(layers "F.Cu" "F.Mask" "F.Paste")
			(net "PVDDQ_DEF")
		)
		(pad "2" smd rect
			(at 0 1.397 180)
			(size 0.889 0.9906)
			(layers "F.Cu" "F.Mask" "F.Paste")
			(net "GND")
		)
		(zone
			(layer "F.Cu")
			(hatch none 0.5)
			(connect_pads
				(clearance 0)
			)
			(min_thickness 0.25)
			(keepout
				(tracks allowed)
				(vias not_allowed)
				(pads allowed)
				(copperpour not_allowed)
				(footprints allowed)
			)
			(placement
				(enabled no)
				(sheetname "")
			)
			(fill
				(thermal_gap 0.5)
				(thermal_bridge_width 0.5)
				(island_removal_mode 0)
			)
			(polygon
				(pts
					(xy 243.598954 -126.37643) (xy 243.598954 -125.38583) (xy 244.106954 -125.38583) (xy 244.106954 -126.37643)
				)
			)
		)
		(zone
			(layer "F.Cu")
			(hatch none 0.5)
			(connect_pads
				(clearance 0)
			)
			(min_thickness 0.25)
			(keepout
				(tracks not_allowed)
				(vias allowed)
				(pads allowed)
				(copperpour not_allowed)
				(footprints allowed)
			)
			(placement
				(enabled no)
				(sheetname "")
			)
			(fill
				(thermal_gap 0.5)
				(thermal_bridge_width 0.5)
				(island_removal_mode 0)
			)
			(polygon
				(pts
					(xy 243.598954 -126.37643) (xy 243.598954 -125.38583) (xy 244.106954 -125.38583) (xy 244.106954 -126.37643)
				)
			)
		)
	)
	(footprint ""
		(layer "F.Cu")
		(at 389.89 -87.3125 180)
		(property "Reference" "R3P2"
			(at 0 0 180)
			(layer "F.SilkS")
			(hide yes)
			(effects
				(font
					(size 1.27 1.27)
				)
			)
		)
		(property "Value" ""
			(at 0 0 180)
			(layer "F.Fab")
			(effects
				(font
					(size 1.27 1.27)
				)
			)
		)
		(duplicate_pad_numbers_are_jumpers no)
		(fp_poly
			(pts
				(xy -0.2794 -0.1016) (xy 0.2794 -0.1016) (xy 0.2794 0.9906) (xy -0.2794 0.9906)
			)
			(stroke
				(width 0)
				(type default)
			)
			(fill no)
			(layer "F.CrtYd")
		)
		(fp_line
			(start 0.2794 0.9906)
			(end 0.2794 -0.1016)
			(stroke
				(width 0.1)
				(type default)
			)
			(layer "F.Fab")
		)
		(fp_line
			(start 0.2794 -0.1016)
			(end -0.2794 -0.1016)
			(stroke
				(width 0.1)
				(type default)
			)
			(layer "F.Fab")
		)
		(fp_line
			(start -0.2794 0.9906)
			(end 0.2794 0.9906)
			(stroke
				(width 0.1)
				(type default)
			)
			(layer "F.Fab")
		)
		(fp_line
			(start -0.2794 -0.1016)
			(end -0.2794 0.9906)
			(stroke
				(width 0.1)
				(type default)
			)
			(layer "F.Fab")
		)
		(pad "1" smd rect
			(at 0 0 180)
			(size 0.508 0.508)
			(layers "F.Cu" "F.Mask" "F.Paste")
			(net "RMII_BMC_PCH_SPRNGVLLE_CRSDV")
		)
		(pad "2" smd rect
			(at 0 0.889 180)
			(size 0.508 0.508)
			(layers "F.Cu" "F.Mask" "F.Paste")
			(net "RMII_BMC_PCH_SPRNGVLLE_CRSDV_R1")
		)
		(zone
			(layer "F.Cu")
			(hatch none 0.5)
			(connect_pads
				(clearance 0)
			)
			(min_thickness 0.25)
			(keepout
				(tracks not_allowed)
				(vias allowed)
				(pads allowed)
				(copperpour not_allowed)
				(footprints allowed)
			)
			(placement
				(enabled no)
				(sheetname "")
			)
			(fill
				(thermal_gap 0.5)
				(thermal_bridge_width 0.5)
				(island_removal_mode 0)
			)
			(polygon
				(pts
					(xy 390.144 -87.9475) (xy 389.636 -87.9475) (xy 389.636 -87.5665) (xy 390.144 -87.5665)
				)
			)
		)
		(zone
			(layer "F.Cu")
			(hatch none 0.5)
			(connect_pads
				(clearance 0)
			)
			(min_thickness 0.25)
			(keepout
				(tracks allowed)
				(vias not_allowed)
				(pads allowed)
				(copperpour not_allowed)
				(footprints allowed)
			)
			(placement
				(enabled no)
				(sheetname "")
			)
			(fill
				(thermal_gap 0.5)
				(thermal_bridge_width 0.5)
				(island_removal_mode 0)
			)
			(polygon
				(pts
					(xy 390.144 -87.5665) (xy 389.636 -87.5665) (xy 389.636 -87.9475) (xy 390.144 -87.9475)
				)
			)
		)
	)
	(footprint ""
		(layer "F.Cu")
		(at 368.69624 -107.893866 180)
		(property "Reference" "C7C4"
			(at 0 0 180)
			(layer "F.SilkS")
			(hide yes)
			(effects
				(font
					(size 1.27 1.27)
				)
			)
		)
		(property "Value" ""
			(at 0 0 180)
			(layer "F.Fab")
			(effects
				(font
					(size 1.27 1.27)
				)
			)
		)
		(duplicate_pad_numbers_are_jumpers no)
		(fp_poly
			(pts
				(xy 0.3048 -0.1016) (xy 0.3048 0.9906) (xy -0.3048 0.9906) (xy -0.3048 -0.1016)
			)
			(stroke
				(width 0)
				(type default)
			)
			(fill no)
			(layer "F.CrtYd")
		)
		(fp_line
			(start 0.3048 0.9906)
			(end 0.3048 -0.1016)
			(stroke
				(width 0.1)
				(type default)
			)
			(layer "F.Fab")
		)
		(fp_line
			(start 0.3048 -0.1016)
			(end -0.3048 -0.1016)
			(stroke
				(width 0.1)
				(type default)
			)
			(layer "F.Fab")
		)
		(fp_line
			(start -0.3048 0.9906)
			(end 0.3048 0.9906)
			(stroke
				(width 0.1)
				(type default)
			)
			(layer "F.Fab")
		)
		(fp_line
			(start -0.3048 -0.1016)
			(end -0.3048 0.9906)
			(stroke
				(width 0.1)
				(type default)
			)
			(layer "F.Fab")
		)
		(pad "1" smd rect
			(at 0 0 180)
			(size 0.508 0.508)
			(layers "F.Cu" "F.Mask" "F.Paste")
			(net "XTAL_PCH_48M_IN")
		)
		(pad "2" smd rect
			(at 0 0.889 180)
			(size 0.508 0.508)
			(layers "F.Cu" "F.Mask" "F.Paste")
			(net "GND")
		)
		(zone
			(layer "F.Cu")
			(hatch none 0.5)
			(connect_pads
				(clearance 0)
			)
			(min_thickness 0.25)
			(keepout
				(tracks not_allowed)
				(vias allowed)
				(pads allowed)
				(copperpour not_allowed)
				(footprints allowed)
			)
			(placement
				(enabled no)
				(sheetname "")
			)
			(fill
				(thermal_gap 0.5)
				(thermal_bridge_width 0.5)
				(island_removal_mode 0)
			)
			(polygon
				(pts
					(xy 368.95024 -108.528866) (xy 368.44224 -108.528866) (xy 368.44224 -108.147866) (xy 368.95024 -108.147866)
				)
			)
		)
		(zone
			(layer "F.Cu")
			(hatch none 0.5)
			(connect_pads
				(clearance 0)
			)
			(min_thickness 0.25)
			(keepout
				(tracks allowed)
				(vias not_allowed)
				(pads allowed)
				(copperpour not_allowed)
				(footprints allowed)
			)
			(placement
				(enabled no)
				(sheetname "")
			)
			(fill
				(thermal_gap 0.5)
				(thermal_bridge_width 0.5)
				(island_removal_mode 0)
			)
			(polygon
				(pts
					(xy 368.95024 -108.147866) (xy 368.44224 -108.147866) (xy 368.44224 -108.528866) (xy 368.95024 -108.528866)
				)
			)
		)
	)
	(footprint ""
		(layer "F.Cu")
		(at 351.9932 -154.686 180)
		(property "Reference" "R7A20"
			(at 0 0 180)
			(layer "F.SilkS")
			(hide yes)
			(effects
				(font
					(size 1.27 1.27)
				)
			)
		)
		(property "Value" ""
			(at 0 0 180)
			(layer "F.Fab")
			(effects
				(font
					(size 1.27 1.27)
				)
			)
		)
		(duplicate_pad_numbers_are_jumpers no)
		(fp_poly
			(pts
				(xy -0.2794 -0.1016) (xy 0.2794 -0.1016) (xy 0.2794 0.9906) (xy -0.2794 0.9906)
			)
			(stroke
				(width 0)
				(type default)
			)
			(fill no)
			(layer "F.CrtYd")
		)
		(fp_line
			(start 0.2794 0.9906)
			(end 0.2794 -0.1016)
			(stroke
				(width 0.1)
				(type default)
			)
			(layer "F.Fab")
		)
		(fp_line
			(start 0.2794 -0.1016)
			(end -0.2794 -0.1016)
			(stroke
				(width 0.1)
				(type default)
			)
			(layer "F.Fab")
		)
		(fp_line
			(start -0.2794 0.9906)
			(end 0.2794 0.9906)
			(stroke
				(width 0.1)
				(type default)
			)
			(layer "F.Fab")
		)
		(fp_line
			(start -0.2794 -0.1016)
			(end -0.2794 0.9906)
			(stroke
				(width 0.1)
				(type default)
			)
			(layer "F.Fab")
		)
		(pad "1" smd rect
			(at 0 0 180)
			(size 0.508 0.508)
			(layers "F.Cu" "F.Mask" "F.Paste")
			(net "VR_PVDDQ_DEF_PH1_OCSET")
		)
		(pad "2" smd rect
			(at 0 0.889 180)
			(size 0.508 0.508)
			(layers "F.Cu" "F.Mask" "F.Paste")
			(net "GND")
		)
		(zone
			(layer "F.Cu")
			(hatch none 0.5)
			(connect_pads
				(clearance 0)
			)
			(min_thickness 0.25)
			(keepout
				(tracks not_allowed)
				(vias allowed)
				(pads allowed)
				(copperpour not_allowed)
				(footprints allowed)
			)
			(placement
				(enabled no)
				(sheetname "")
			)
			(fill
				(thermal_gap 0.5)
				(thermal_bridge_width 0.5)
				(island_removal_mode 0)
			)
			(polygon
				(pts
					(xy 352.2472 -155.321) (xy 351.7392 -155.321) (xy 351.7392 -154.94) (xy 352.2472 -154.94)
				)
			)
		)
		(zone
			(layer "F.Cu")
			(hatch none 0.5)
			(connect_pads
				(clearance 0)
			)
			(min_thickness 0.25)
			(keepout
				(tracks allowed)
				(vias not_allowed)
				(pads allowed)
				(copperpour not_allowed)
				(footprints allowed)
			)
			(placement
				(enabled no)
				(sheetname "")
			)
			(fill
				(thermal_gap 0.5)
				(thermal_bridge_width 0.5)
				(island_removal_mode 0)
			)
			(polygon
				(pts
					(xy 352.2472 -154.94) (xy 351.7392 -154.94) (xy 351.7392 -155.321) (xy 352.2472 -155.321)
				)
			)
		)
	)
	(footprint ""
		(layer "F.Cu")
		(at 187.833 -63.627 -90)
		(property "Reference" "R4E8"
			(at 0 0 270)
			(layer "F.SilkS")
			(hide yes)
			(effects
				(font
					(size 1.27 1.27)
				)
			)
		)
		(property "Value" ""
			(at 0 0 270)
			(layer "F.Fab")
			(effects
				(font
					(size 1.27 1.27)
				)
			)
		)
		(duplicate_pad_numbers_are_jumpers no)
		(fp_poly
			(pts
				(xy -0.2794 -0.1016) (xy 0.2794 -0.1016) (xy 0.2794 0.9906) (xy -0.2794 0.9906)
			)
			(stroke
				(width 0)
				(type default)
			)
			(fill no)
			(layer "F.CrtYd")
		)
		(fp_line
			(start -0.2794 0.9906)
			(end 0.2794 0.9906)
			(stroke
				(width 0.1)
				(type default)
			)
			(layer "F.Fab")
		)
		(fp_line
			(start 0.2794 0.9906)
			(end 0.2794 -0.1016)
			(stroke
				(width 0.1)
				(type default)
			)
			(layer "F.Fab")
		)
		(fp_line
			(start -0.2794 -0.1016)
			(end -0.2794 0.9906)
			(stroke
				(width 0.1)
				(type default)
			)
			(layer "F.Fab")
		)
		(fp_line
			(start 0.2794 -0.1016)
			(end -0.2794 -0.1016)
			(stroke
				(width 0.1)
				(type default)
			)
			(layer "F.Fab")
		)
		(pad "1" smd rect
			(at 0 0 270)
			(size 0.508 0.508)
			(layers "F.Cu" "F.Mask" "F.Paste")
			(net "VSENSE_PVCCIN_CPU0_P")
		)
		(pad "2" smd rect
			(at 0 0.889 270)
			(size 0.508 0.508)
			(layers "F.Cu" "F.Mask" "F.Paste")
			(net "VSENSE_PVCCIN_CPU0_AVSP")
		)
		(zone
			(layer "F.Cu")
			(hatch none 0.5)
			(connect_pads
				(clearance 0)
			)
			(min_thickness 0.25)
			(keepout
				(tracks not_allowed)
				(vias allowed)
				(pads allowed)
				(copperpour not_allowed)
				(footprints allowed)
			)
			(placement
				(enabled no)
				(sheetname "")
			)
			(fill
				(thermal_gap 0.5)
				(thermal_bridge_width 0.5)
				(island_removal_mode 0)
			)
			(polygon
				(pts
					(xy 187.198 -63.881) (xy 187.198 -63.373) (xy 187.579 -63.373) (xy 187.579 -63.881)
				)
			)
		)
		(zone
			(layer "F.Cu")
			(hatch none 0.5)
			(connect_pads
				(clearance 0)
			)
			(min_thickness 0.25)
			(keepout
				(tracks allowed)
				(vias not_allowed)
				(pads allowed)
				(copperpour not_allowed)
				(footprints allowed)
			)
			(placement
				(enabled no)
				(sheetname "")
			)
			(fill
				(thermal_gap 0.5)
				(thermal_bridge_width 0.5)
				(island_removal_mode 0)
			)
			(polygon
				(pts
					(xy 187.579 -63.881) (xy 187.579 -63.373) (xy 187.198 -63.373) (xy 187.198 -63.881)
				)
			)
		)
	)
	(footprint ""
		(layer "F.Cu")
		(at 422.2115 -113.03 -90)
		(property "Reference" "R9W16"
			(at -0.8382 -0.67818 270)
			(unlocked yes)
			(layer "F.SilkS")
			(effects
				(font
					(size 0.4064 0.254)
					(thickness 0.1524)
				)
				(justify left)
			)
		)
		(property "Value" ""
			(at 0 0 270)
			(layer "F.Fab")
			(effects
				(font
					(size 1.27 1.27)
				)
			)
		)
		(duplicate_pad_numbers_are_jumpers no)
		(fp_poly
			(pts
				(xy -0.2794 -0.1016) (xy 0.2794 -0.1016) (xy 0.2794 0.9906) (xy -0.2794 0.9906)
			)
			(stroke
				(width 0)
				(type default)
			)
			(fill no)
			(layer "F.CrtYd")
		)
		(fp_line
			(start -0.2794 0.9906)
			(end 0.2794 0.9906)
			(stroke
				(width 0.1)
				(type default)
			)
			(layer "F.Fab")
		)
		(fp_line
			(start 0.2794 0.9906)
			(end 0.2794 -0.1016)
			(stroke
				(width 0.1)
				(type default)
			)
			(layer "F.Fab")
		)
		(fp_line
			(start -0.2794 -0.1016)
			(end -0.2794 0.9906)
			(stroke
				(width 0.1)
				(type default)
			)
			(layer "F.Fab")
		)
		(fp_line
			(start 0.2794 -0.1016)
			(end -0.2794 -0.1016)
			(stroke
				(width 0.1)
				(type default)
			)
			(layer "F.Fab")
		)
		(pad "1" smd rect
			(at 0 0 270)
			(size 0.508 0.508)
			(layers "F.Cu" "F.Mask" "F.Paste")
			(net "P3V3_STBY")
		)
		(pad "2" smd rect
			(at 0 0.889 270)
			(size 0.508 0.508)
			(layers "F.Cu" "F.Mask" "F.Paste")
			(net "SMB_PEHPCPU0_STBY_LVC3_R_SDA")
		)
		(zone
			(layer "F.Cu")
			(hatch none 0.5)
			(connect_pads
				(clearance 0)
			)
			(min_thickness 0.25)
			(keepout
				(tracks not_allowed)
				(vias allowed)
				(pads allowed)
				(copperpour not_allowed)
				(footprints allowed)
			)
			(placement
				(enabled no)
				(sheetname "")
			)
			(fill
				(thermal_gap 0.5)
				(thermal_bridge_width 0.5)
				(island_removal_mode 0)
			)
			(polygon
				(pts
					(xy 421.5765 -113.284) (xy 421.5765 -112.776) (xy 421.9575 -112.776) (xy 421.9575 -113.284)
				)
			)
		)
		(zone
			(layer "F.Cu")
			(hatch none 0.5)
			(connect_pads
				(clearance 0)
			)
			(min_thickness 0.25)
			(keepout
				(tracks allowed)
				(vias not_allowed)
				(pads allowed)
				(copperpour not_allowed)
				(footprints allowed)
			)
			(placement
				(enabled no)
				(sheetname "")
			)
			(fill
				(thermal_gap 0.5)
				(thermal_bridge_width 0.5)
				(island_removal_mode 0)
			)
			(polygon
				(pts
					(xy 421.9575 -113.284) (xy 421.9575 -112.776) (xy 421.5765 -112.776) (xy 421.5765 -113.284)
				)
			)
		)
	)
	(footprint ""
		(layer "F.Cu")
		(at 14.36116 4.269232)
		(property "Reference" "C1G27"
			(at 0 0 0)
			(layer "F.SilkS")
			(hide yes)
			(effects
				(font
					(size 1.27 1.27)
				)
			)
		)
		(property "Value" ""
			(at 0 0 0)
			(layer "F.Fab")
			(effects
				(font
					(size 1.27 1.27)
				)
			)
		)
		(duplicate_pad_numbers_are_jumpers no)
		(fp_poly
			(pts
				(xy 0.3048 -0.1016) (xy 0.3048 0.9906) (xy -0.3048 0.9906) (xy -0.3048 -0.1016)
			)
			(stroke
				(width 0)
				(type default)
			)
			(fill no)
			(layer "F.CrtYd")
		)
		(fp_line
			(start -0.3048 -0.1016)
			(end -0.3048 0.9906)
			(stroke
				(width 0.1)
				(type default)
			)
			(layer "F.Fab")
		)
		(fp_line
			(start -0.3048 0.9906)
			(end 0.3048 0.9906)
			(stroke
				(width 0.1)
				(type default)
			)
			(layer "F.Fab")
		)
		(fp_line
			(start 0.3048 -0.1016)
			(end -0.3048 -0.1016)
			(stroke
				(width 0.1)
				(type default)
			)
			(layer "F.Fab")
		)
		(fp_line
			(start 0.3048 0.9906)
			(end 0.3048 -0.1016)
			(stroke
				(width 0.1)
				(type default)
			)
			(layer "F.Fab")
		)
		(pad "1" smd rect
			(at 0 0)
			(size 0.508 0.508)
			(layers "F.Cu" "F.Mask" "F.Paste")
			(net "VR_PVDDQ_GHJ_VDD")
		)
		(pad "2" smd rect
			(at 0 0.889)
			(size 0.508 0.508)
			(layers "F.Cu" "F.Mask" "F.Paste")
			(net "GND")
		)
		(zone
			(layer "F.Cu")
			(hatch none 0.5)
			(connect_pads
				(clearance 0)
			)
			(min_thickness 0.25)
			(keepout
				(tracks allowed)
				(vias not_allowed)
				(pads allowed)
				(copperpour not_allowed)
				(footprints allowed)
			)
			(placement
				(enabled no)
				(sheetname "")
			)
			(fill
				(thermal_gap 0.5)
				(thermal_bridge_width 0.5)
				(island_removal_mode 0)
			)
			(polygon
				(pts
					(xy 14.10716 4.523232) (xy 14.61516 4.523232) (xy 14.61516 4.904232) (xy 14.10716 4.904232)
				)
			)
		)
		(zone
			(layer "F.Cu")
			(hatch none 0.5)
			(connect_pads
				(clearance 0)
			)
			(min_thickness 0.25)
			(keepout
				(tracks not_allowed)
				(vias allowed)
				(pads allowed)
				(copperpour not_allowed)
				(footprints allowed)
			)
			(placement
				(enabled no)
				(sheetname "")
			)
			(fill
				(thermal_gap 0.5)
				(thermal_bridge_width 0.5)
				(island_removal_mode 0)
			)
			(polygon
				(pts
					(xy 14.10716 4.904232) (xy 14.61516 4.904232) (xy 14.61516 4.523232) (xy 14.10716 4.523232)
				)
			)
		)
	)
	(footprint ""
		(layer "F.Cu")
		(at 38.07968 -34.912808)
		(property "Reference" "CR1F5"
			(at 4.29133 1.397 270)
			(unlocked yes)
			(layer "F.SilkS")
			(effects
				(font
					(size 0.7874 0.5842)
					(thickness 0.1524)
				)
				(justify left)
			)
		)
		(property "Value" ""
			(at 0 0 0)
			(layer "F.Fab")
			(effects
				(font
					(size 1.27 1.27)
				)
			)
		)
		(duplicate_pad_numbers_are_jumpers no)
		(fp_line
			(start -3.111754 7.5946)
			(end -3.1115 -0.228346)
			(stroke
				(width 0.1524)
				(type default)
			)
			(layer "F.SilkS")
		)
		(fp_line
			(start -3.111754 7.5946)
			(end -1.9431 7.5946)
			(stroke
				(width 0.1524)
				(type default)
			)
			(layer "F.SilkS")
		)
		(fp_line
			(start -3.1115 -0.228346)
			(end -1.9431 -0.2286)
			(stroke
				(width 0.1524)
				(type default)
			)
			(layer "F.SilkS")
		)
		(fp_line
			(start 1.9431 -0.2286)
			(end 3.1115 -0.228346)
			(stroke
				(width 0.1524)
				(type default)
			)
			(layer "F.SilkS")
		)
		(fp_line
			(start 1.9431 7.5946)
			(end 3.111754 7.5946)
			(stroke
				(width 0.1524)
				(type default)
			)
			(layer "F.SilkS")
		)
		(fp_line
			(start 3.1115 -0.228346)
			(end 3.111754 7.5946)
			(stroke
				(width 0.1524)
				(type default)
			)
			(layer "F.SilkS")
		)
		(fp_circle
			(center -2.413 -1.016)
			(end -2.286 -1.016)
			(stroke
				(width 0.254)
				(type default)
			)
			(fill no)
			(layer "F.SilkS")
		)
		(fp_poly
			(pts
				(xy -3.111754 7.5946) (xy 3.111754 7.5946) (xy 3.1115 -0.228346) (xy -3.1115 -0.228346)
			)
			(stroke
				(width 0)
				(type default)
			)
			(fill no)
			(layer "F.CrtYd")
		)
		(fp_line
			(start -3.111754 7.5946)
			(end 3.111754 7.5946)
			(stroke
				(width 0.1)
				(type default)
			)
			(layer "F.Fab")
		)
		(fp_line
			(start -3.1115 -0.228346)
			(end -3.111754 7.5946)
			(stroke
				(width 0.1)
				(type default)
			)
			(layer "F.Fab")
		)
		(fp_line
			(start 3.1115 -0.228346)
			(end -3.1115 -0.228346)
			(stroke
				(width 0.1)
				(type default)
			)
			(layer "F.Fab")
		)
		(fp_line
			(start 3.111754 7.5946)
			(end 3.1115 -0.228346)
			(stroke
				(width 0.1)
				(type default)
			)
			(layer "F.Fab")
		)
		(fp_circle
			(center -2.413 -0.9906)
			(end -2.286 -0.9906)
			(stroke
				(width 0.254)
				(type default)
			)
			(fill no)
			(layer "F.Fab")
		)
		(pad "1" smd rect
			(at 0 0)
			(size 3.048 2.286)
			(layers "F.Cu" "F.Mask" "F.Paste")
			(net "P12V_STBY")
		)
		(pad "2" smd rect
			(at 0 7.366)
			(size 3.048 2.286)
			(layers "F.Cu" "F.Mask" "F.Paste")
			(net "GND")
		)
	)
	(footprint ""
		(layer "F.Cu")
		(at 417.83 -56.2229)
		(property "Reference" "C8E8"
			(at 0 0 0)
			(layer "F.SilkS")
			(hide yes)
			(effects
				(font
					(size 1.27 1.27)
				)
			)
		)
		(property "Value" ""
			(at 0 0 0)
			(layer "F.Fab")
			(effects
				(font
					(size 1.27 1.27)
				)
			)
		)
		(duplicate_pad_numbers_are_jumpers no)
		(fp_poly
			(pts
				(xy 0.3048 -0.1016) (xy 0.3048 0.9906) (xy -0.3048 0.9906) (xy -0.3048 -0.1016)
			)
			(stroke
				(width 0)
				(type default)
			)
			(fill no)
			(layer "F.CrtYd")
		)
		(fp_line
			(start -0.3048 -0.1016)
			(end -0.3048 0.9906)
			(stroke
				(width 0.1)
				(type default)
			)
			(layer "F.Fab")
		)
		(fp_line
			(start -0.3048 0.9906)
			(end 0.3048 0.9906)
			(stroke
				(width 0.1)
				(type default)
			)
			(layer "F.Fab")
		)
		(fp_line
			(start 0.3048 -0.1016)
			(end -0.3048 -0.1016)
			(stroke
				(width 0.1)
				(type default)
			)
			(layer "F.Fab")
		)
		(fp_line
			(start 0.3048 0.9906)
			(end 0.3048 -0.1016)
			(stroke
				(width 0.1)
				(type default)
			)
			(layer "F.Fab")
		)
		(pad "1" smd rect
			(at 0 0)
			(size 0.508 0.508)
			(layers "F.Cu" "F.Mask" "F.Paste")
			(net "P3V3_STBY")
		)
		(pad "2" smd rect
			(at 0 0.889)
			(size 0.508 0.508)
			(layers "F.Cu" "F.Mask" "F.Paste")
			(net "GND")
		)
		(zone
			(layer "F.Cu")
			(hatch none 0.5)
			(connect_pads
				(clearance 0)
			)
			(min_thickness 0.25)
			(keepout
				(tracks allowed)
				(vias not_allowed)
				(pads allowed)
				(copperpour not_allowed)
				(footprints allowed)
			)
			(placement
				(enabled no)
				(sheetname "")
			)
			(fill
				(thermal_gap 0.5)
				(thermal_bridge_width 0.5)
				(island_removal_mode 0)
			)
			(polygon
				(pts
					(xy 417.576 -55.9689) (xy 418.084 -55.9689) (xy 418.084 -55.5879) (xy 417.576 -55.5879)
				)
			)
		)
		(zone
			(layer "F.Cu")
			(hatch none 0.5)
			(connect_pads
				(clearance 0)
			)
			(min_thickness 0.25)
			(keepout
				(tracks not_allowed)
				(vias allowed)
				(pads allowed)
				(copperpour not_allowed)
				(footprints allowed)
			)
			(placement
				(enabled no)
				(sheetname "")
			)
			(fill
				(thermal_gap 0.5)
				(thermal_bridge_width 0.5)
				(island_removal_mode 0)
			)
			(polygon
				(pts
					(xy 417.576 -55.5879) (xy 418.084 -55.5879) (xy 418.084 -55.9689) (xy 417.576 -55.9689)
				)
			)
		)
	)
	(footprint ""
		(layer "F.Cu")
		(at 479.806 -145.288)
		(property "Reference" "U9A3"
			(at 0 0 0)
			(layer "F.SilkS")
			(hide yes)
			(effects
				(font
					(size 1.27 1.27)
				)
			)
		)
		(property "Value" "*"
			(at -2.3622 -8.3185 0)
			(unlocked yes)
			(layer "F.Fab")
			(hide yes)
			(effects
				(font
					(size 1.27 1.016)
					(thickness 0.1524)
				)
			)
		)
		(property "Device Type" "TC7PZ14FU-GP_DISCRET-GA1-TC7PZA"
			(at -2.3622 -10.2235 0)
			(unlocked yes)
			(layer "F.Fab")
			(hide yes)
			(effects
				(font
					(size 1.27 1.016)
					(thickness 0.1524)
				)
			)
		)
		(duplicate_pad_numbers_are_jumpers no)
		(fp_line
			(start -1.5494 1.7907)
			(end -1.5494 0.8255)
			(stroke
				(width 0.3302)
				(type default)
			)
			(layer "F.SilkS")
		)
		(fp_line
			(start -1.4478 -1.7018)
			(end -1.4478 1.7018)
			(stroke
				(width 0.1524)
				(type default)
			)
			(layer "F.SilkS")
		)
		(fp_line
			(start -1.4478 1.7018)
			(end 1.4478 1.7018)
			(stroke
				(width 0.1524)
				(type default)
			)
			(layer "F.SilkS")
		)
		(fp_line
			(start -0.5715 1.7907)
			(end -1.5494 1.7907)
			(stroke
				(width 0.3302)
				(type default)
			)
			(layer "F.SilkS")
		)
		(fp_line
			(start 1.4478 -1.7018)
			(end -1.4478 -1.7018)
			(stroke
				(width 0.1524)
				(type default)
			)
			(layer "F.SilkS")
		)
		(fp_line
			(start 1.4478 1.7018)
			(end 1.4478 -1.7018)
			(stroke
				(width 0.1524)
				(type default)
			)
			(layer "F.SilkS")
		)
		(fp_poly
			(pts
				(xy -0.6604 1.7272) (xy -1.016 2.0828) (xy -0.3048 2.0828)
			)
			(stroke
				(width 0)
				(type default)
			)
			(fill yes)
			(layer "F.SilkS")
		)
		(fp_poly
			(pts
				(xy -1.524 -1.778) (xy 1.524 -1.778) (xy 1.524 1.778) (xy -1.524 1.778)
			)
			(stroke
				(width 0)
				(type default)
			)
			(fill no)
			(layer "F.CrtYd")
		)
		(fp_poly
			(pts
				(xy -1.524 -1.778) (xy 1.524 -1.778) (xy 1.524 1.778) (xy -1.524 1.778)
			)
			(stroke
				(width 0)
				(type default)
			)
			(fill no)
			(layer "F.Fab")
		)
		(pad "1" smd rect
			(at -0.65024 0.9398)
			(size 0.4064 1.016)
			(layers "F.Cu" "F.Mask" "F.Paste")
			(net "FP_RST_BTN_R_N")
		)
		(pad "2" smd rect
			(at 0 0.9398)
			(size 0.4064 1.016)
			(layers "F.Cu" "F.Mask" "F.Paste")
			(net "GND")
		)
		(pad "3" smd rect
			(at 0.65024 0.9398)
			(size 0.4064 1.016)
			(layers "F.Cu" "F.Mask" "F.Paste")
			(net "FP_RST_BTN_BUF1_N")
		)
		(pad "4" smd rect
			(at 0.65024 -0.9398)
			(size 0.4064 1.016)
			(layers "F.Cu" "F.Mask" "F.Paste")
			(net "RST_SYSTEM_BTN_BUF_N")
		)
		(pad "5" smd rect
			(at 0 -0.9398)
			(size 0.4064 1.016)
			(layers "F.Cu" "F.Mask" "F.Paste")
			(net "P3V3_STBY")
		)
		(pad "6" smd rect
			(at -0.65024 -0.9398)
			(size 0.4064 1.016)
			(layers "F.Cu" "F.Mask" "F.Paste")
			(net "FP_RST_BTN_BUF1_N")
		)
	)
	(footprint ""
		(layer "F.Cu")
		(at 97.132902 -83.84159)
		(property "Reference" "C2D8"
			(at 0 0 0)
			(layer "F.SilkS")
			(hide yes)
			(effects
				(font
					(size 1.27 1.27)
				)
			)
		)
		(property "Value" ""
			(at 0 0 0)
			(layer "F.Fab")
			(effects
				(font
					(size 1.27 1.27)
				)
			)
		)
		(duplicate_pad_numbers_are_jumpers no)
		(fp_poly
			(pts
				(xy -0.4953 -0.2032) (xy 0.4953 -0.2032) (xy 0.4953 1.6002) (xy -0.4953 1.6002)
			)
			(stroke
				(width 0)
				(type default)
			)
			(fill no)
			(layer "F.CrtYd")
		)
		(fp_line
			(start -0.4953 -0.2032)
			(end 0.4953 -0.2032)
			(stroke
				(width 0.1)
				(type default)
			)
			(layer "F.Fab")
		)
		(fp_line
			(start -0.4953 1.6002)
			(end -0.4953 -0.2032)
			(stroke
				(width 0.1)
				(type default)
			)
			(layer "F.Fab")
		)
		(fp_line
			(start 0.4953 -0.2032)
			(end 0.4953 1.6002)
			(stroke
				(width 0.1)
				(type default)
			)
			(layer "F.Fab")
		)
		(fp_line
			(start 0.4953 1.6002)
			(end -0.4953 1.6002)
			(stroke
				(width 0.1)
				(type default)
			)
			(layer "F.Fab")
		)
		(pad "1" smd rect
			(at 0 0)
			(size 0.762 0.889)
			(layers "F.Cu" "F.Mask" "F.Paste")
			(net "PVSA_CPU1")
		)
		(pad "2" smd rect
			(at 0 1.397)
			(size 0.762 0.889)
			(layers "F.Cu" "F.Mask" "F.Paste")
			(net "GND")
		)
		(zone
			(layer "F.Cu")
			(hatch none 0.5)
			(connect_pads
				(clearance 0)
			)
			(min_thickness 0.25)
			(keepout
				(tracks not_allowed)
				(vias allowed)
				(pads allowed)
				(copperpour not_allowed)
				(footprints allowed)
			)
			(placement
				(enabled no)
				(sheetname "")
			)
			(fill
				(thermal_gap 0.5)
				(thermal_bridge_width 0.5)
				(island_removal_mode 0)
			)
			(polygon
				(pts
					(xy 96.751902 -83.39709) (xy 97.513902 -83.39709) (xy 97.513902 -82.88909) (xy 96.751902 -82.88909)
				)
			)
		)
	)
	(footprint ""
		(layer "F.Cu")
		(at 473.075 -148.0185 180)
		(property "Reference" "R9A12"
			(at 0 0 180)
			(layer "F.SilkS")
			(hide yes)
			(effects
				(font
					(size 1.27 1.27)
				)
			)
		)
		(property "Value" ""
			(at 0 0 180)
			(layer "F.Fab")
			(effects
				(font
					(size 1.27 1.27)
				)
			)
		)
		(duplicate_pad_numbers_are_jumpers no)
		(fp_poly
			(pts
				(xy -0.2794 -0.1016) (xy 0.2794 -0.1016) (xy 0.2794 0.9906) (xy -0.2794 0.9906)
			)
			(stroke
				(width 0)
				(type default)
			)
			(fill no)
			(layer "F.CrtYd")
		)
		(fp_line
			(start 0.2794 0.9906)
			(end 0.2794 -0.1016)
			(stroke
				(width 0.1)
				(type default)
			)
			(layer "F.Fab")
		)
		(fp_line
			(start 0.2794 -0.1016)
			(end -0.2794 -0.1016)
			(stroke
				(width 0.1)
				(type default)
			)
			(layer "F.Fab")
		)
		(fp_line
			(start -0.2794 0.9906)
			(end 0.2794 0.9906)
			(stroke
				(width 0.1)
				(type default)
			)
			(layer "F.Fab")
		)
		(fp_line
			(start -0.2794 -0.1016)
			(end -0.2794 0.9906)
			(stroke
				(width 0.1)
				(type default)
			)
			(layer "F.Fab")
		)
		(pad "1" smd rect
			(at 0 0 180)
			(size 0.508 0.508)
			(layers "F.Cu" "F.Mask" "F.Paste")
			(net "FM_PCH_SATA_RAID_KEY_R")
		)
		(pad "2" smd rect
			(at 0 0.889 180)
			(size 0.508 0.508)
			(layers "F.Cu" "F.Mask" "F.Paste")
			(net "P3V3_STBY")
		)
		(zone
			(layer "F.Cu")
			(hatch none 0.5)
			(connect_pads
				(clearance 0)
			)
			(min_thickness 0.25)
			(keepout
				(tracks not_allowed)
				(vias allowed)
				(pads allowed)
				(copperpour not_allowed)
				(footprints allowed)
			)
			(placement
				(enabled no)
				(sheetname "")
			)
			(fill
				(thermal_gap 0.5)
				(thermal_bridge_width 0.5)
				(island_removal_mode 0)
			)
			(polygon
				(pts
					(xy 473.329 -148.6535) (xy 472.821 -148.6535) (xy 472.821 -148.2725) (xy 473.329 -148.2725)
				)
			)
		)
		(zone
			(layer "F.Cu")
			(hatch none 0.5)
			(connect_pads
				(clearance 0)
			)
			(min_thickness 0.25)
			(keepout
				(tracks allowed)
				(vias not_allowed)
				(pads allowed)
				(copperpour not_allowed)
				(footprints allowed)
			)
			(placement
				(enabled no)
				(sheetname "")
			)
			(fill
				(thermal_gap 0.5)
				(thermal_bridge_width 0.5)
				(island_removal_mode 0)
			)
			(polygon
				(pts
					(xy 473.329 -148.2725) (xy 472.821 -148.2725) (xy 472.821 -148.6535) (xy 473.329 -148.6535)
				)
			)
		)
	)
	(footprint ""
		(layer "F.Cu")
		(at 449.69938 -31.3055 90)
		(property "Reference" "R25W8"
			(at 0 0 90)
			(layer "F.SilkS")
			(hide yes)
			(effects
				(font
					(size 1.27 1.27)
				)
			)
		)
		(property "Value" "*"
			(at 0.064008 -4.108196 90)
			(unlocked yes)
			(layer "F.Fab")
			(hide yes)
			(effects
				(font
					(size 1.27 1.016)
					(thickness 0.1524)
				)
			)
		)
		(property "Device Type" "120R2F-GP_RCL_GP-120R2F-GP,64.A"
			(at 0.064008 -5.632196 90)
			(unlocked yes)
			(layer "F.Fab")
			(hide yes)
			(effects
				(font
					(size 1.27 1.016)
					(thickness 0.1524)
				)
			)
		)
		(duplicate_pad_numbers_are_jumpers no)
		(fp_line
			(start 0.508 -0.9398)
			(end -0.508 -0.9398)
			(stroke
				(width 0.1524)
				(type default)
			)
			(layer "F.SilkS")
		)
		(fp_line
			(start -0.508 -0.9398)
			(end -0.508 0.9398)
			(stroke
				(width 0.1524)
				(type default)
			)
			(layer "F.SilkS")
		)
		(fp_rect
			(start -0.508 0.9398)
			(end 0.508 -0.9398)
			(stroke
				(width 0)
				(type default)
			)
			(fill no)
			(layer "F.CrtYd")
		)
		(fp_rect
			(start -0.508 0.9398)
			(end 0.508 -0.9398)
			(stroke
				(width 0)
				(type default)
			)
			(fill no)
			(layer "F.Fab")
		)
		(pad "1" smd custom
			(at 0 -0.4445 90)
			(size 0.1397 0.1397)
			(layers "F.Cu" "F.Mask" "F.Paste")
			(net "GND")
			(options
				(clearance outline)
				(anchor circle)
			)
			(primitives
				(gr_poly
					(pts
						(arc
							(start -0.1778 -0.2794)
							(mid -0.249642 -0.249642)
							(end -0.2794 -0.1778)
						)
						(arc
							(start -0.2794 0.1778)
							(mid -0.249642 0.249642)
							(end -0.1778 0.2794)
						)
						(arc
							(start 0.1778 0.2794)
							(mid 0.249642 0.249642)
							(end 0.2794 0.1778)
						)
						(arc
							(start 0.2794 -0.1778)
							(mid 0.249642 -0.249642)
							(end 0.1778 -0.2794)
						)
					)
					(width 0)
					(fill yes)
				)
			)
		)
		(pad "2" smd custom
			(at 0 0.4445 90)
			(size 0.1397 0.1397)
			(layers "F.Cu" "F.Mask" "F.Paste")
			(net "BMC_M_WE_N")
			(options
				(clearance outline)
				(anchor circle)
			)
			(primitives
				(gr_poly
					(pts
						(arc
							(start -0.1778 -0.2794)
							(mid -0.249642 -0.249642)
							(end -0.2794 -0.1778)
						)
						(arc
							(start -0.2794 0.1778)
							(mid -0.249642 0.249642)
							(end -0.1778 0.2794)
						)
						(arc
							(start 0.1778 0.2794)
							(mid 0.249642 0.249642)
							(end 0.2794 0.1778)
						)
						(arc
							(start 0.2794 -0.1778)
							(mid 0.249642 -0.249642)
							(end 0.1778 -0.2794)
						)
					)
					(width 0)
					(fill yes)
				)
			)
		)
	)
	(footprint ""
		(layer "F.Cu")
		(at 368.554 -113.792 90)
		(property "Reference" "C7B27"
			(at 0 0 90)
			(layer "F.SilkS")
			(hide yes)
			(effects
				(font
					(size 1.27 1.27)
				)
			)
		)
		(property "Value" ""
			(at 0 0 90)
			(layer "F.Fab")
			(effects
				(font
					(size 1.27 1.27)
				)
			)
		)
		(duplicate_pad_numbers_are_jumpers no)
		(fp_poly
			(pts
				(xy 0.3048 -0.1016) (xy 0.3048 0.9906) (xy -0.3048 0.9906) (xy -0.3048 -0.1016)
			)
			(stroke
				(width 0)
				(type default)
			)
			(fill no)
			(layer "F.CrtYd")
		)
		(fp_line
			(start 0.3048 -0.1016)
			(end -0.3048 -0.1016)
			(stroke
				(width 0.1)
				(type default)
			)
			(layer "F.Fab")
		)
		(fp_line
			(start -0.3048 -0.1016)
			(end -0.3048 0.9906)
			(stroke
				(width 0.1)
				(type default)
			)
			(layer "F.Fab")
		)
		(fp_line
			(start 0.3048 0.9906)
			(end 0.3048 -0.1016)
			(stroke
				(width 0.1)
				(type default)
			)
			(layer "F.Fab")
		)
		(fp_line
			(start -0.3048 0.9906)
			(end 0.3048 0.9906)
			(stroke
				(width 0.1)
				(type default)
			)
			(layer "F.Fab")
		)
		(pad "1" smd rect
			(at 0 0 90)
			(size 0.508 0.508)
			(layers "F.Cu" "F.Mask" "F.Paste")
			(net "DMI_CPU0_PCH_TX_DP<2>")
		)
		(pad "2" smd rect
			(at 0 0.889 90)
			(size 0.508 0.508)
			(layers "F.Cu" "F.Mask" "F.Paste")
			(net "DMI_CPU0_PCH_TX_C_DP<2>")
		)
		(zone
			(layer "F.Cu")
			(hatch none 0.5)
			(connect_pads
				(clearance 0)
			)
			(min_thickness 0.25)
			(keepout
				(tracks allowed)
				(vias not_allowed)
				(pads allowed)
				(copperpour not_allowed)
				(footprints allowed)
			)
			(placement
				(enabled no)
				(sheetname "")
			)
			(fill
				(thermal_gap 0.5)
				(thermal_bridge_width 0.5)
				(island_removal_mode 0)
			)
			(polygon
				(pts
					(xy 368.808 -113.538) (xy 368.808 -114.046) (xy 369.189 -114.046) (xy 369.189 -113.538)
				)
			)
		)
		(zone
			(layer "F.Cu")
			(hatch none 0.5)
			(connect_pads
				(clearance 0)
			)
			(min_thickness 0.25)
			(keepout
				(tracks not_allowed)
				(vias allowed)
				(pads allowed)
				(copperpour not_allowed)
				(footprints allowed)
			)
			(placement
				(enabled no)
				(sheetname "")
			)
			(fill
				(thermal_gap 0.5)
				(thermal_bridge_width 0.5)
				(island_removal_mode 0)
			)
			(polygon
				(pts
					(xy 369.189 -113.538) (xy 369.189 -114.046) (xy 368.808 -114.046) (xy 368.808 -113.538)
				)
			)
		)
	)
	(footprint ""
		(layer "F.Cu")
		(at 352.7298 -100.29063 90)
		(property "Reference" "CT70"
			(at 0.86233 -0.5842 0)
			(unlocked yes)
			(layer "F.SilkS")
			(effects
				(font
					(size 0.7874 0.5842)
					(thickness 0.1524)
				)
				(justify left)
			)
		)
		(property "Value" ""
			(at 0 0 90)
			(layer "F.Fab")
			(effects
				(font
					(size 1.27 1.27)
				)
			)
		)
		(duplicate_pad_numbers_are_jumpers no)
		(fp_poly
			(pts
				(xy 0.3048 -0.1016) (xy 0.3048 0.9906) (xy -0.3048 0.9906) (xy -0.3048 -0.1016)
			)
			(stroke
				(width 0)
				(type default)
			)
			(fill no)
			(layer "F.CrtYd")
		)
		(fp_line
			(start 0.3048 -0.1016)
			(end -0.3048 -0.1016)
			(stroke
				(width 0.1)
				(type default)
			)
			(layer "F.Fab")
		)
		(fp_line
			(start -0.3048 -0.1016)
			(end -0.3048 0.9906)
			(stroke
				(width 0.1)
				(type default)
			)
			(layer "F.Fab")
		)
		(fp_line
			(start 0.3048 0.9906)
			(end 0.3048 -0.1016)
			(stroke
				(width 0.1)
				(type default)
			)
			(layer "F.Fab")
		)
		(fp_line
			(start -0.3048 0.9906)
			(end 0.3048 0.9906)
			(stroke
				(width 0.1)
				(type default)
			)
			(layer "F.Fab")
		)
		(pad "1" smd rect
			(at 0 0 90)
			(size 0.508 0.508)
			(layers "F.Cu" "F.Mask" "F.Paste")
			(net "VR_PVCCIO_CPU0_AIREF1")
		)
		(pad "2" smd rect
			(at 0 0.889 90)
			(size 0.508 0.508)
			(layers "F.Cu" "F.Mask" "F.Paste")
			(net "GND")
		)
		(zone
			(layer "F.Cu")
			(hatch none 0.5)
			(connect_pads
				(clearance 0)
			)
			(min_thickness 0.25)
			(keepout
				(tracks allowed)
				(vias not_allowed)
				(pads allowed)
				(copperpour not_allowed)
				(footprints allowed)
			)
			(placement
				(enabled no)
				(sheetname "")
			)
			(fill
				(thermal_gap 0.5)
				(thermal_bridge_width 0.5)
				(island_removal_mode 0)
			)
			(polygon
				(pts
					(xy 352.9838 -100.03663) (xy 352.9838 -100.54463) (xy 353.3648 -100.54463) (xy 353.3648 -100.03663)
				)
			)
		)
		(zone
			(layer "F.Cu")
			(hatch none 0.5)
			(connect_pads
				(clearance 0)
			)
			(min_thickness 0.25)
			(keepout
				(tracks not_allowed)
				(vias allowed)
				(pads allowed)
				(copperpour not_allowed)
				(footprints allowed)
			)
			(placement
				(enabled no)
				(sheetname "")
			)
			(fill
				(thermal_gap 0.5)
				(thermal_bridge_width 0.5)
				(island_removal_mode 0)
			)
			(polygon
				(pts
					(xy 353.3648 -100.03663) (xy 353.3648 -100.54463) (xy 352.9838 -100.54463) (xy 352.9838 -100.03663)
				)
			)
		)
	)
	(footprint ""
		(layer "F.Cu")
		(at 43.311064 -38.008306 180)
		(property "Reference" "C1F7"
			(at 6.17347 4.1656 270)
			(unlocked yes)
			(layer "F.SilkS")
			(effects
				(font
					(size 0.7874 0.5842)
					(thickness 0.1524)
				)
			)
		)
		(property "Value" ""
			(at 0 0 180)
			(layer "F.Fab")
			(effects
				(font
					(size 1.27 1.27)
				)
			)
		)
		(duplicate_pad_numbers_are_jumpers no)
		(fp_line
			(start 5.1435 9.271)
			(end 1.4097 9.271)
			(stroke
				(width 0.1524)
				(type default)
			)
			(layer "F.SilkS")
		)
		(fp_line
			(start 5.1435 -0.127)
			(end 5.1435 9.271)
			(stroke
				(width 0.1524)
				(type default)
			)
			(layer "F.SilkS")
		)
		(fp_line
			(start 4.3815 -1.016)
			(end 5.1435 -0.127)
			(stroke
				(width 0.1524)
				(type default)
			)
			(layer "F.SilkS")
		)
		(fp_line
			(start 1.8415 2.0955)
			(end 1.4097 2.0955)
			(stroke
				(width 0.1524)
				(type default)
			)
			(layer "F.SilkS")
		)
		(fp_line
			(start 1.8415 -1.016)
			(end 4.3815 -1.016)
			(stroke
				(width 0.1524)
				(type default)
			)
			(layer "F.SilkS")
		)
		(fp_line
			(start 1.8415 -2.0955)
			(end 1.8415 2.0955)
			(stroke
				(width 0.1524)
				(type default)
			)
			(layer "F.SilkS")
		)
		(fp_line
			(start 1.4097 -2.0955)
			(end 1.8415 -2.0955)
			(stroke
				(width 0.1524)
				(type default)
			)
			(layer "F.SilkS")
		)
		(fp_line
			(start -1.4097 9.271)
			(end -5.1435 9.271)
			(stroke
				(width 0.1524)
				(type default)
			)
			(layer "F.SilkS")
		)
		(fp_line
			(start -1.4097 -2.0955)
			(end -1.8415 -2.0955)
			(stroke
				(width 0.1524)
				(type default)
			)
			(layer "F.SilkS")
		)
		(fp_line
			(start -1.8415 2.0955)
			(end -1.4097 2.0955)
			(stroke
				(width 0.1524)
				(type default)
			)
			(layer "F.SilkS")
		)
		(fp_line
			(start -1.8415 -2.0955)
			(end -1.8415 2.0955)
			(stroke
				(width 0.1524)
				(type default)
			)
			(layer "F.SilkS")
		)
		(fp_line
			(start -4.3815 -1.016)
			(end -1.8415 -1.016)
			(stroke
				(width 0.1524)
				(type default)
			)
			(layer "F.SilkS")
		)
		(fp_line
			(start -5.1435 9.271)
			(end -5.1435 -0.127)
			(stroke
				(width 0.1524)
				(type default)
			)
			(layer "F.SilkS")
		)
		(fp_line
			(start -5.1435 -0.127)
			(end -4.3815 -1.016)
			(stroke
				(width 0.1524)
				(type default)
			)
			(layer "F.SilkS")
		)
		(fp_poly
			(pts
				(xy -5.14604 -0.12954) (xy -4.38404 -1.01346) (xy 4.37896 -1.016) (xy 5.1435 -0.12954) (xy 5.14096 9.271)
				(xy -5.14604 9.27354)
			)
			(stroke
				(width 0)
				(type default)
			)
			(fill no)
			(layer "F.CrtYd")
		)
		(fp_line
			(start 5.1435 9.271)
			(end -5.1435 9.271)
			(stroke
				(width 0.1)
				(type default)
			)
			(layer "F.Fab")
		)
		(fp_line
			(start 5.1435 -0.127)
			(end 5.1435 9.271)
			(stroke
				(width 0.1)
				(type default)
			)
			(layer "F.Fab")
		)
		(fp_line
			(start 4.3815 -1.016)
			(end 5.1435 -0.127)
			(stroke
				(width 0.1)
				(type default)
			)
			(layer "F.Fab")
		)
		(fp_line
			(start -4.3815 -1.016)
			(end 4.3815 -1.016)
			(stroke
				(width 0.1)
				(type default)
			)
			(layer "F.Fab")
		)
		(fp_line
			(start -5.1435 9.271)
			(end -5.1435 -0.127)
			(stroke
				(width 0.1)
				(type default)
			)
			(layer "F.Fab")
		)
		(fp_line
			(start -5.1435 -0.127)
			(end -4.3815 -1.016)
			(stroke
				(width 0.1)
				(type default)
			)
			(layer "F.Fab")
		)
		(fp_circle
			(center 0 4.1275)
			(end -4.9911 4.1275)
			(stroke
				(width 0.1)
				(type default)
			)
			(fill no)
			(layer "F.Fab")
		)
		(pad "1" smd rect
			(at 0 0 180)
			(size 1.905 4.191)
			(layers "F.Cu" "F.Mask" "F.Paste")
			(net "P12V_STBY")
		)
		(pad "2" smd rect
			(at 0 8.255 180)
			(size 1.905 4.191)
			(layers "F.Cu" "F.Mask" "F.Paste")
			(net "GND")
		)
		(zone
			(layer "F.Cu")
			(hatch none 0.5)
			(connect_pads
				(clearance 0)
			)
			(min_thickness 0.25)
			(keepout
				(tracks allowed)
				(vias not_allowed)
				(pads allowed)
				(copperpour not_allowed)
				(footprints allowed)
			)
			(placement
				(enabled no)
				(sheetname "")
			)
			(fill
				(thermal_gap 0.5)
				(thermal_bridge_width 0.5)
				(island_removal_mode 0)
			)
			(polygon
				(pts
					(xy 48.454564 -47.279306) (xy 38.167564 -47.279306) (xy 38.167564 -37.881306) (xy 38.929564 -36.992306)
					(xy 47.692564 -36.992306) (xy 48.454564 -37.881306)
				)
			)
		)
	)
	(footprint ""
		(layer "F.Cu")
		(at 489.0262 -34.8742 -90)
		(property "Reference" "R25W127"
			(at -0.8382 -0.67818 270)
			(unlocked yes)
			(layer "F.SilkS")
			(effects
				(font
					(size 0.4064 0.254)
					(thickness 0.1524)
				)
				(justify left)
			)
		)
		(property "Value" ""
			(at 0 0 270)
			(layer "F.Fab")
			(effects
				(font
					(size 1.27 1.27)
				)
			)
		)
		(duplicate_pad_numbers_are_jumpers no)
		(fp_poly
			(pts
				(xy -0.2794 -0.1016) (xy 0.2794 -0.1016) (xy 0.2794 0.9906) (xy -0.2794 0.9906)
			)
			(stroke
				(width 0)
				(type default)
			)
			(fill no)
			(layer "F.CrtYd")
		)
		(fp_line
			(start -0.2794 0.9906)
			(end 0.2794 0.9906)
			(stroke
				(width 0.1)
				(type default)
			)
			(layer "F.Fab")
		)
		(fp_line
			(start 0.2794 0.9906)
			(end 0.2794 -0.1016)
			(stroke
				(width 0.1)
				(type default)
			)
			(layer "F.Fab")
		)
		(fp_line
			(start -0.2794 -0.1016)
			(end -0.2794 0.9906)
			(stroke
				(width 0.1)
				(type default)
			)
			(layer "F.Fab")
		)
		(fp_line
			(start 0.2794 -0.1016)
			(end -0.2794 -0.1016)
			(stroke
				(width 0.1)
				(type default)
			)
			(layer "F.Fab")
		)
		(pad "1" smd rect
			(at 0 0 270)
			(size 0.508 0.508)
			(layers "F.Cu" "F.Mask" "F.Paste")
			(net "V_IO_G_J")
		)
		(pad "2" smd rect
			(at 0 0.889 270)
			(size 0.508 0.508)
			(layers "F.Cu" "F.Mask" "F.Paste")
			(net "GND")
		)
		(zone
			(layer "F.Cu")
			(hatch none 0.5)
			(connect_pads
				(clearance 0)
			)
			(min_thickness 0.25)
			(keepout
				(tracks not_allowed)
				(vias allowed)
				(pads allowed)
				(copperpour not_allowed)
				(footprints allowed)
			)
			(placement
				(enabled no)
				(sheetname "")
			)
			(fill
				(thermal_gap 0.5)
				(thermal_bridge_width 0.5)
				(island_removal_mode 0)
			)
			(polygon
				(pts
					(xy 488.3912 -35.1282) (xy 488.3912 -34.6202) (xy 488.7722 -34.6202) (xy 488.7722 -35.1282)
				)
			)
		)
		(zone
			(layer "F.Cu")
			(hatch none 0.5)
			(connect_pads
				(clearance 0)
			)
			(min_thickness 0.25)
			(keepout
				(tracks allowed)
				(vias not_allowed)
				(pads allowed)
				(copperpour not_allowed)
				(footprints allowed)
			)
			(placement
				(enabled no)
				(sheetname "")
			)
			(fill
				(thermal_gap 0.5)
				(thermal_bridge_width 0.5)
				(island_removal_mode 0)
			)
			(polygon
				(pts
					(xy 488.7722 -35.1282) (xy 488.7722 -34.6202) (xy 488.3912 -34.6202) (xy 488.3912 -35.1282)
				)
			)
		)
	)
	(footprint ""
		(layer "F.Cu")
		(at 318.543432 -3.302 -90)
		(property "Reference" "C6G4"
			(at 0 0 270)
			(layer "F.SilkS")
			(hide yes)
			(effects
				(font
					(size 1.27 1.27)
				)
			)
		)
		(property "Value" ""
			(at 0 0 270)
			(layer "F.Fab")
			(effects
				(font
					(size 1.27 1.27)
				)
			)
		)
		(duplicate_pad_numbers_are_jumpers no)
		(fp_poly
			(pts
				(xy -0.4953 -0.2032) (xy 0.4953 -0.2032) (xy 0.4953 1.6002) (xy -0.4953 1.6002)
			)
			(stroke
				(width 0)
				(type default)
			)
			(fill no)
			(layer "F.CrtYd")
		)
		(fp_line
			(start -0.4953 1.6002)
			(end -0.4953 -0.2032)
			(stroke
				(width 0.1)
				(type default)
			)
			(layer "F.Fab")
		)
		(fp_line
			(start 0.4953 1.6002)
			(end -0.4953 1.6002)
			(stroke
				(width 0.1)
				(type default)
			)
			(layer "F.Fab")
		)
		(fp_line
			(start -0.4953 -0.2032)
			(end 0.4953 -0.2032)
			(stroke
				(width 0.1)
				(type default)
			)
			(layer "F.Fab")
		)
		(fp_line
			(start 0.4953 -0.2032)
			(end 0.4953 1.6002)
			(stroke
				(width 0.1)
				(type default)
			)
			(layer "F.Fab")
		)
		(pad "1" smd rect
			(at 0 0 270)
			(size 0.762 0.889)
			(layers "F.Cu" "F.Mask" "F.Paste")
			(net "PVPP_ABC")
		)
		(pad "2" smd rect
			(at 0 1.397 270)
			(size 0.762 0.889)
			(layers "F.Cu" "F.Mask" "F.Paste")
			(net "GND")
		)
		(zone
			(layer "F.Cu")
			(hatch none 0.5)
			(connect_pads
				(clearance 0)
			)
			(min_thickness 0.25)
			(keepout
				(tracks not_allowed)
				(vias allowed)
				(pads allowed)
				(copperpour not_allowed)
				(footprints allowed)
			)
			(placement
				(enabled no)
				(sheetname "")
			)
			(fill
				(thermal_gap 0.5)
				(thermal_bridge_width 0.5)
				(island_removal_mode 0)
			)
			(polygon
				(pts
					(xy 318.098932 -3.683) (xy 318.098932 -2.921) (xy 317.590932 -2.921) (xy 317.590932 -3.683)
				)
			)
		)
	)
	(footprint ""
		(layer "F.Cu")
		(at 153.543 -3.302 -90)
		(property "Reference" "C3G7"
			(at 0 0 270)
			(layer "F.SilkS")
			(hide yes)
			(effects
				(font
					(size 1.27 1.27)
				)
			)
		)
		(property "Value" ""
			(at 0 0 270)
			(layer "F.Fab")
			(effects
				(font
					(size 1.27 1.27)
				)
			)
		)
		(duplicate_pad_numbers_are_jumpers no)
		(fp_poly
			(pts
				(xy -0.4953 -0.2032) (xy 0.4953 -0.2032) (xy 0.4953 1.6002) (xy -0.4953 1.6002)
			)
			(stroke
				(width 0)
				(type default)
			)
			(fill no)
			(layer "F.CrtYd")
		)
		(fp_line
			(start -0.4953 1.6002)
			(end -0.4953 -0.2032)
			(stroke
				(width 0.1)
				(type default)
			)
			(layer "F.Fab")
		)
		(fp_line
			(start 0.4953 1.6002)
			(end -0.4953 1.6002)
			(stroke
				(width 0.1)
				(type default)
			)
			(layer "F.Fab")
		)
		(fp_line
			(start -0.4953 -0.2032)
			(end 0.4953 -0.2032)
			(stroke
				(width 0.1)
				(type default)
			)
			(layer "F.Fab")
		)
		(fp_line
			(start 0.4953 -0.2032)
			(end 0.4953 1.6002)
			(stroke
				(width 0.1)
				(type default)
			)
			(layer "F.Fab")
		)
		(pad "1" smd rect
			(at 0 0 270)
			(size 0.762 0.889)
			(layers "F.Cu" "F.Mask" "F.Paste")
			(net "PVPP_GHJ")
		)
		(pad "2" smd rect
			(at 0 1.397 270)
			(size 0.762 0.889)
			(layers "F.Cu" "F.Mask" "F.Paste")
			(net "GND")
		)
		(zone
			(layer "F.Cu")
			(hatch none 0.5)
			(connect_pads
				(clearance 0)
			)
			(min_thickness 0.25)
			(keepout
				(tracks not_allowed)
				(vias allowed)
				(pads allowed)
				(copperpour not_allowed)
				(footprints allowed)
			)
			(placement
				(enabled no)
				(sheetname "")
			)
			(fill
				(thermal_gap 0.5)
				(thermal_bridge_width 0.5)
				(island_removal_mode 0)
			)
			(polygon
				(pts
					(xy 153.0985 -3.683) (xy 153.0985 -2.921) (xy 152.5905 -2.921) (xy 152.5905 -3.683)
				)
			)
		)
	)
	(footprint ""
		(layer "F.Cu")
		(at 171.069 -74.041 180)
		(property "Reference" "R4D35"
			(at 0 0 180)
			(layer "F.SilkS")
			(hide yes)
			(effects
				(font
					(size 1.27 1.27)
				)
			)
		)
		(property "Value" ""
			(at 0 0 180)
			(layer "F.Fab")
			(effects
				(font
					(size 1.27 1.27)
				)
			)
		)
		(duplicate_pad_numbers_are_jumpers no)
		(fp_poly
			(pts
				(xy -0.2794 -0.1016) (xy 0.2794 -0.1016) (xy 0.2794 0.9906) (xy -0.2794 0.9906)
			)
			(stroke
				(width 0)
				(type default)
			)
			(fill no)
			(layer "F.CrtYd")
		)
		(fp_line
			(start 0.2794 0.9906)
			(end 0.2794 -0.1016)
			(stroke
				(width 0.1)
				(type default)
			)
			(layer "F.Fab")
		)
		(fp_line
			(start 0.2794 -0.1016)
			(end -0.2794 -0.1016)
			(stroke
				(width 0.1)
				(type default)
			)
			(layer "F.Fab")
		)
		(fp_line
			(start -0.2794 0.9906)
			(end 0.2794 0.9906)
			(stroke
				(width 0.1)
				(type default)
			)
			(layer "F.Fab")
		)
		(fp_line
			(start -0.2794 -0.1016)
			(end -0.2794 0.9906)
			(stroke
				(width 0.1)
				(type default)
			)
			(layer "F.Fab")
		)
		(pad "1" smd rect
			(at 0 0 180)
			(size 0.508 0.508)
			(layers "F.Cu" "F.Mask" "F.Paste")
			(net "P3V3_DB1200")
		)
		(pad "2" smd rect
			(at 0 0.889 180)
			(size 0.508 0.508)
			(layers "F.Cu" "F.Mask" "F.Paste")
			(net "FM_DB1200_SMB_SA0")
		)
		(zone
			(layer "F.Cu")
			(hatch none 0.5)
			(connect_pads
				(clearance 0)
			)
			(min_thickness 0.25)
			(keepout
				(tracks not_allowed)
				(vias allowed)
				(pads allowed)
				(copperpour not_allowed)
				(footprints allowed)
			)
			(placement
				(enabled no)
				(sheetname "")
			)
			(fill
				(thermal_gap 0.5)
				(thermal_bridge_width 0.5)
				(island_removal_mode 0)
			)
			(polygon
				(pts
					(xy 171.323 -74.676) (xy 170.815 -74.676) (xy 170.815 -74.295) (xy 171.323 -74.295)
				)
			)
		)
		(zone
			(layer "F.Cu")
			(hatch none 0.5)
			(connect_pads
				(clearance 0)
			)
			(min_thickness 0.25)
			(keepout
				(tracks allowed)
				(vias not_allowed)
				(pads allowed)
				(copperpour not_allowed)
				(footprints allowed)
			)
			(placement
				(enabled no)
				(sheetname "")
			)
			(fill
				(thermal_gap 0.5)
				(thermal_bridge_width 0.5)
				(island_removal_mode 0)
			)
			(polygon
				(pts
					(xy 171.323 -74.295) (xy 170.815 -74.295) (xy 170.815 -74.676) (xy 171.323 -74.676)
				)
			)
		)
	)
	(footprint ""
		(layer "F.Cu")
		(at 13.35024 -165.01618 -90)
		(property "Reference" "T1D1"
			(at 0 0 270)
			(layer "F.SilkS")
			(hide yes)
			(effects
				(font
					(size 1.27 1.27)
				)
			)
		)
		(property "Value" "*"
			(at -3.4036 -4.46405 270)
			(unlocked yes)
			(layer "F.Fab")
			(hide yes)
			(effects
				(font
					(size 0.889 0.889)
					(thickness 0.1524)
				)
			)
		)
		(property "Device Type" "TEST-PAD-12P-1-GP-U_DISCRET-GBA"
			(at -3.4036 -5.98805 270)
			(unlocked yes)
			(layer "F.Fab")
			(hide yes)
			(effects
				(font
					(size 0.889 0.889)
					(thickness 0.1524)
				)
			)
		)
		(duplicate_pad_numbers_are_jumpers no)
		(fp_line
			(start -2.3876 3.4798)
			(end -2.3876 -4.826)
			(stroke
				(width 0.1524)
				(type default)
			)
			(layer "F.SilkS")
		)
		(fp_line
			(start 2.3622 3.4798)
			(end -2.3876 3.4798)
			(stroke
				(width 0.1524)
				(type default)
			)
			(layer "F.SilkS")
		)
		(fp_line
			(start -2.3876 -4.826)
			(end 2.3622 -4.826)
			(stroke
				(width 0.1524)
				(type default)
			)
			(layer "F.SilkS")
		)
		(fp_line
			(start 2.3622 -4.826)
			(end 2.3622 3.4798)
			(stroke
				(width 0.1524)
				(type default)
			)
			(layer "F.SilkS")
		)
		(fp_rect
			(start -2.6416 3.7338)
			(end 2.6162 -5.08)
			(stroke
				(width 0)
				(type default)
			)
			(fill no)
			(layer "F.CrtYd")
		)
		(fp_rect
			(start -2.6416 3.7338)
			(end 2.6162 -5.08)
			(stroke
				(width 0)
				(type default)
			)
			(fill no)
			(layer "F.Fab")
		)
		(pad "1" smd circle
			(at 0.496824 -1.301496 270)
			(size 0.6604 0.6604)
			(layers "F.Cu" "F.Mask" "F.Paste")
			(net "L1_85OHM_5INCH_DP")
		)
		(pad "2" smd circle
			(at -0.503936 -1.301496 270)
			(size 0.6604 0.6604)
			(layers "F.Cu" "F.Mask" "F.Paste")
			(net "L1_85OHM_5INCH_DN")
		)
		(pad "3" smd custom
			(at -0.00889 0.370078 270)
			(size 0.74295 0.74295)
			(layers "F.Cu" "F.Mask" "F.Paste")
			(net "GND")
			(options
				(clearance outline)
				(anchor circle)
			)
			(primitives
				(gr_poly
					(pts
						(xy -2.1209 1.4859) (xy 2.1209 1.4859) (xy 2.1209 -1.4859) (xy 1.08585 -1.4859) (xy 1.08585 -0.4699)
						(xy -1.08585 -0.4699) (xy -1.08585 -1.4859) (xy -2.1209 -1.4859)
					)
					(width 0)
					(fill yes)
				)
			)
		)
		(pad "4" thru_hole circle
			(at 1.266444 -3.851656 270)
			(size 1.4478 1.4478)
			(drill 1.0414)
			(layers "*.Cu" "*.Mask")
			(remove_unused_layers no)
			(net "GND")
			(clearance 0.1524)
			(thermal_gap 0.1524)
		)
		(pad "5" thru_hole circle
			(at -1.273556 -3.851656 270)
			(size 1.4478 1.4478)
			(drill 1.0414)
			(layers "*.Cu" "*.Mask")
			(remove_unused_layers no)
			(net "GND")
			(clearance 0.1524)
			(thermal_gap 0.1524)
		)
		(pad "6" thru_hole circle
			(at 1.266444 2.498344 270)
			(size 1.4478 1.4478)
			(drill 1.0414)
			(layers "*.Cu" "*.Mask")
			(remove_unused_layers no)
			(net "GND")
			(clearance 0.1524)
			(thermal_gap 0.1524)
		)
		(pad "7" thru_hole circle
			(at -1.273556 2.498344 270)
			(size 1.4478 1.4478)
			(drill 1.0414)
			(layers "*.Cu" "*.Mask")
			(remove_unused_layers no)
			(net "GND")
			(clearance 0.1524)
			(thermal_gap 0.1524)
		)
		(pad "8" thru_hole circle
			(at 1.27 -0.4572 270)
			(size 0.7112 0.7112)
			(drill 0.4064)
			(layers "*.Cu" "*.Mask")
			(remove_unused_layers no)
			(net "GND")
			(clearance 0.1016)
			(thermal_gap 0.1016)
		)
		(pad "9" thru_hole circle
			(at 1.27 0.762 270)
			(size 0.7112 0.7112)
			(drill 0.4064)
			(layers "*.Cu" "*.Mask")
			(remove_unused_layers no)
			(net "GND")
			(clearance 0.1016)
			(thermal_gap 0.1016)
		)
		(pad "10" thru_hole circle
			(at -0.0254 0.762 270)
			(size 0.7112 0.7112)
			(drill 0.4064)
			(layers "*.Cu" "*.Mask")
			(remove_unused_layers no)
			(net "GND")
			(clearance 0.1016)
			(thermal_gap 0.1016)
		)
		(pad "11" thru_hole circle
			(at -1.27 0.762 270)
			(size 0.7112 0.7112)
			(drill 0.4064)
			(layers "*.Cu" "*.Mask")
			(remove_unused_layers no)
			(net "GND")
			(clearance 0.1016)
			(thermal_gap 0.1016)
		)
		(pad "12" thru_hole circle
			(at -1.27 -0.4572 270)
			(size 0.7112 0.7112)
			(drill 0.4064)
			(layers "*.Cu" "*.Mask")
			(remove_unused_layers no)
			(net "GND")
			(clearance 0.1016)
			(thermal_gap 0.1016)
		)
	)
	(footprint ""
		(layer "F.Cu")
		(at 204.0509 -52.7304 -90)
		(property "Reference" "CT3"
			(at -0.8382 -0.67818 270)
			(unlocked yes)
			(layer "F.SilkS")
			(effects
				(font
					(size 0.4064 0.254)
					(thickness 0.1524)
				)
				(justify left)
			)
		)
		(property "Value" ""
			(at 0 0 270)
			(layer "F.Fab")
			(effects
				(font
					(size 1.27 1.27)
				)
			)
		)
		(duplicate_pad_numbers_are_jumpers no)
		(fp_poly
			(pts
				(xy 0.3048 -0.1016) (xy 0.3048 0.9906) (xy -0.3048 0.9906) (xy -0.3048 -0.1016)
			)
			(stroke
				(width 0)
				(type default)
			)
			(fill no)
			(layer "F.CrtYd")
		)
		(fp_line
			(start -0.3048 0.9906)
			(end 0.3048 0.9906)
			(stroke
				(width 0.1)
				(type default)
			)
			(layer "F.Fab")
		)
		(fp_line
			(start 0.3048 0.9906)
			(end 0.3048 -0.1016)
			(stroke
				(width 0.1)
				(type default)
			)
			(layer "F.Fab")
		)
		(fp_line
			(start -0.3048 -0.1016)
			(end -0.3048 0.9906)
			(stroke
				(width 0.1)
				(type default)
			)
			(layer "F.Fab")
		)
		(fp_line
			(start 0.3048 -0.1016)
			(end -0.3048 -0.1016)
			(stroke
				(width 0.1)
				(type default)
			)
			(layer "F.Fab")
		)
		(pad "1" smd rect
			(at 0 0 270)
			(size 0.508 0.508)
			(layers "F.Cu" "F.Mask" "F.Paste")
			(net "VR_PVCCIN_CPU0_PHASE1")
		)
		(pad "2" smd rect
			(at 0 0.889 270)
			(size 0.508 0.508)
			(layers "F.Cu" "F.Mask" "F.Paste")
			(net "VR_PVCCIN_CPU0_PHASE1_RC")
		)
		(zone
			(layer "F.Cu")
			(hatch none 0.5)
			(connect_pads
				(clearance 0)
			)
			(min_thickness 0.25)
			(keepout
				(tracks not_allowed)
				(vias allowed)
				(pads allowed)
				(copperpour not_allowed)
				(footprints allowed)
			)
			(placement
				(enabled no)
				(sheetname "")
			)
			(fill
				(thermal_gap 0.5)
				(thermal_bridge_width 0.5)
				(island_removal_mode 0)
			)
			(polygon
				(pts
					(xy 203.4159 -52.9844) (xy 203.4159 -52.4764) (xy 203.7969 -52.4764) (xy 203.7969 -52.9844)
				)
			)
		)
		(zone
			(layer "F.Cu")
			(hatch none 0.5)
			(connect_pads
				(clearance 0)
			)
			(min_thickness 0.25)
			(keepout
				(tracks allowed)
				(vias not_allowed)
				(pads allowed)
				(copperpour not_allowed)
				(footprints allowed)
			)
			(placement
				(enabled no)
				(sheetname "")
			)
			(fill
				(thermal_gap 0.5)
				(thermal_bridge_width 0.5)
				(island_removal_mode 0)
			)
			(polygon
				(pts
					(xy 203.7969 -52.9844) (xy 203.7969 -52.4764) (xy 203.4159 -52.4764) (xy 203.4159 -52.9844)
				)
			)
		)
	)
	(footprint ""
		(layer "F.Cu")
		(at 339.471 -21.971 90)
		(property "Reference" "R7F35"
			(at 0 0 90)
			(layer "F.SilkS")
			(hide yes)
			(effects
				(font
					(size 1.27 1.27)
				)
			)
		)
		(property "Value" ""
			(at 0 0 90)
			(layer "F.Fab")
			(effects
				(font
					(size 1.27 1.27)
				)
			)
		)
		(duplicate_pad_numbers_are_jumpers no)
		(fp_rect
			(start 0.2794 -0.1016)
			(end -0.2794 0.9906)
			(stroke
				(width 0)
				(type default)
			)
			(fill no)
			(layer "F.CrtYd")
		)
		(fp_line
			(start 0.2794 -0.1016)
			(end -0.2794 -0.1016)
			(stroke
				(width 0.1)
				(type default)
			)
			(layer "F.Fab")
		)
		(fp_line
			(start -0.2794 -0.1016)
			(end -0.2794 0.9906)
			(stroke
				(width 0.1)
				(type default)
			)
			(layer "F.Fab")
		)
		(fp_line
			(start 0.2794 0.9906)
			(end 0.2794 -0.1016)
			(stroke
				(width 0.1)
				(type default)
			)
			(layer "F.Fab")
		)
		(fp_line
			(start -0.2794 0.9906)
			(end 0.2794 0.9906)
			(stroke
				(width 0.1)
				(type default)
			)
			(layer "F.Fab")
		)
		(pad "1" smd rect
			(at 0 0 90)
			(size 0.508 0.508)
			(layers "F.Cu" "F.Mask" "F.Paste")
			(net "GND")
		)
		(pad "2" smd rect
			(at 0 0.889 90)
			(size 0.508 0.508)
			(layers "F.Cu" "F.Mask" "F.Paste")
			(net "AGND_PVPP_ABC")
		)
		(zone
			(layer "F.Cu")
			(hatch none 0.5)
			(connect_pads
				(clearance 0)
			)
			(min_thickness 0.25)
			(keepout
				(tracks not_allowed)
				(vias allowed)
				(pads allowed)
				(copperpour not_allowed)
				(footprints allowed)
			)
			(placement
				(enabled no)
				(sheetname "")
			)
			(fill
				(thermal_gap 0.5)
				(thermal_bridge_width 0.5)
				(island_removal_mode 0)
			)
			(polygon
				(pts
					(xy 339.725 -22.225) (xy 339.725 -21.717) (xy 340.106 -21.717) (xy 340.106 -22.225)
				)
			)
		)
		(zone
			(layer "F.Cu")
			(hatch none 0.5)
			(connect_pads
				(clearance 0)
			)
			(min_thickness 0.25)
			(keepout
				(tracks allowed)
				(vias not_allowed)
				(pads allowed)
				(copperpour not_allowed)
				(footprints allowed)
			)
			(placement
				(enabled no)
				(sheetname "")
			)
			(fill
				(thermal_gap 0.5)
				(thermal_bridge_width 0.5)
				(island_removal_mode 0)
			)
			(polygon
				(pts
					(xy 339.725 -22.225) (xy 339.725 -21.717) (xy 340.106 -21.717) (xy 340.106 -22.225)
				)
			)
		)
	)
	(footprint ""
		(layer "F.Cu")
		(at 198.37908 -101.221286 90)
		(property "Reference" "C4C9"
			(at 0 0 90)
			(layer "F.SilkS")
			(hide yes)
			(effects
				(font
					(size 1.27 1.27)
				)
			)
		)
		(property "Value" ""
			(at 0 0 90)
			(layer "F.Fab")
			(effects
				(font
					(size 1.27 1.27)
				)
			)
		)
		(duplicate_pad_numbers_are_jumpers no)
		(fp_poly
			(pts
				(xy 0.3048 -0.1016) (xy 0.3048 0.9906) (xy -0.3048 0.9906) (xy -0.3048 -0.1016)
			)
			(stroke
				(width 0)
				(type default)
			)
			(fill no)
			(layer "F.CrtYd")
		)
		(fp_line
			(start 0.3048 -0.1016)
			(end -0.3048 -0.1016)
			(stroke
				(width 0.1)
				(type default)
			)
			(layer "F.Fab")
		)
		(fp_line
			(start -0.3048 -0.1016)
			(end -0.3048 0.9906)
			(stroke
				(width 0.1)
				(type default)
			)
			(layer "F.Fab")
		)
		(fp_line
			(start 0.3048 0.9906)
			(end 0.3048 -0.1016)
			(stroke
				(width 0.1)
				(type default)
			)
			(layer "F.Fab")
		)
		(fp_line
			(start -0.3048 0.9906)
			(end 0.3048 0.9906)
			(stroke
				(width 0.1)
				(type default)
			)
			(layer "F.Fab")
		)
		(pad "1" smd rect
			(at 0 0 90)
			(size 0.508 0.508)
			(layers "F.Cu" "F.Mask" "F.Paste")
			(net "VR_FET_SW_P12V_STBY_PVCCIN_CPU0")
		)
		(pad "2" smd rect
			(at 0 0.889 90)
			(size 0.508 0.508)
			(layers "F.Cu" "F.Mask" "F.Paste")
			(net "GND")
		)
		(zone
			(layer "F.Cu")
			(hatch none 0.5)
			(connect_pads
				(clearance 0)
			)
			(min_thickness 0.25)
			(keepout
				(tracks allowed)
				(vias not_allowed)
				(pads allowed)
				(copperpour not_allowed)
				(footprints allowed)
			)
			(placement
				(enabled no)
				(sheetname "")
			)
			(fill
				(thermal_gap 0.5)
				(thermal_bridge_width 0.5)
				(island_removal_mode 0)
			)
			(polygon
				(pts
					(xy 198.63308 -100.967286) (xy 198.63308 -101.475286) (xy 199.01408 -101.475286) (xy 199.01408 -100.967286)
				)
			)
		)
		(zone
			(layer "F.Cu")
			(hatch none 0.5)
			(connect_pads
				(clearance 0)
			)
			(min_thickness 0.25)
			(keepout
				(tracks not_allowed)
				(vias allowed)
				(pads allowed)
				(copperpour not_allowed)
				(footprints allowed)
			)
			(placement
				(enabled no)
				(sheetname "")
			)
			(fill
				(thermal_gap 0.5)
				(thermal_bridge_width 0.5)
				(island_removal_mode 0)
			)
			(polygon
				(pts
					(xy 199.01408 -100.967286) (xy 199.01408 -101.475286) (xy 198.63308 -101.475286) (xy 198.63308 -100.967286)
				)
			)
		)
	)
	(footprint ""
		(layer "F.Cu")
		(at 453.8472 -15.3924)
		(property "Reference" "C8F8"
			(at 0 0 0)
			(layer "F.SilkS")
			(hide yes)
			(effects
				(font
					(size 1.27 1.27)
				)
			)
		)
		(property "Value" "*"
			(at 0 -9.7155 0)
			(unlocked yes)
			(layer "F.Fab")
			(hide yes)
			(effects
				(font
					(size 1.27 1.016)
					(thickness 0.1524)
				)
			)
		)
		(property "Device Type" "ST470U6D3VDM-7-GP_SMD-TCG4-ST4A"
			(at 0 -11.2395 0)
			(unlocked yes)
			(layer "F.Fab")
			(hide yes)
			(effects
				(font
					(size 1.27 1.016)
					(thickness 0.1524)
				)
			)
		)
		(duplicate_pad_numbers_are_jumpers no)
		(fp_line
			(start -2.286 -4.8768)
			(end -2.286 -2.032)
			(stroke
				(width 0.1524)
				(type default)
			)
			(layer "F.SilkS")
		)
		(fp_line
			(start -2.286 4.8768)
			(end -2.286 2.032)
			(stroke
				(width 0.1524)
				(type default)
			)
			(layer "F.SilkS")
		)
		(fp_line
			(start 2.1082 -4.699)
			(end -2.1082 -4.699)
			(stroke
				(width 0.508)
				(type default)
			)
			(layer "F.SilkS")
		)
		(fp_line
			(start 2.286 -4.8768)
			(end -2.286 -4.8768)
			(stroke
				(width 0.1524)
				(type default)
			)
			(layer "F.SilkS")
		)
		(fp_line
			(start 2.286 -2.032)
			(end 2.286 -4.8768)
			(stroke
				(width 0.1524)
				(type default)
			)
			(layer "F.SilkS")
		)
		(fp_line
			(start 2.286 2.032)
			(end 2.286 4.8768)
			(stroke
				(width 0.1524)
				(type default)
			)
			(layer "F.SilkS")
		)
		(fp_line
			(start 2.286 4.8768)
			(end -2.286 4.8768)
			(stroke
				(width 0.1524)
				(type default)
			)
			(layer "F.SilkS")
		)
		(fp_rect
			(start -2.1463 3.6449)
			(end 2.1463 -3.6449)
			(stroke
				(width 0)
				(type default)
			)
			(fill no)
			(layer "F.CrtYd")
		)
		(fp_poly
			(pts
				(xy -2.54 4.953) (xy -2.54 4.2926) (xy -3.81 4.2926) (xy -3.81 -4.2926) (xy -2.54 -4.2926) (xy -2.54 -4.953)
				(xy 2.54 -4.953) (xy 2.54 -4.2926) (xy 3.81 -4.2926) (xy 3.81 -1.6256) (xy 2.1463 -1.6256) (xy 2.1463 -3.6449)
				(xy -2.1463 -3.6449) (xy -2.1463 3.6449) (xy 2.1463 3.6449) (xy 2.1463 -1.6129) (xy 3.81 -1.6129)
				(xy 3.81 4.2926) (xy 2.54 4.2926) (xy 2.54 4.953)
			)
			(stroke
				(width 0)
				(type default)
			)
			(fill no)
			(layer "F.CrtYd")
		)
		(fp_rect
			(start -3.81 4.2926)
			(end -2.54 -4.2926)
			(stroke
				(width 0)
				(type default)
			)
			(fill no)
			(layer "F.Fab")
		)
		(fp_rect
			(start -2.54 4.953)
			(end 2.54 -4.953)
			(stroke
				(width 0)
				(type default)
			)
			(fill no)
			(layer "F.Fab")
		)
		(fp_rect
			(start 2.54 4.2926)
			(end 3.81 -4.2926)
			(stroke
				(width 0)
				(type default)
			)
			(fill no)
			(layer "F.Fab")
		)
		(pad "1" smd rect
			(at 0 -3.1496)
			(size 2.413 2.286)
			(layers "F.Cu" "F.Mask" "F.Paste")
			(net "P3V3_STBY")
		)
		(pad "2" smd rect
			(at 0 3.1496)
			(size 2.413 2.286)
			(layers "F.Cu" "F.Mask" "F.Paste")
			(net "GND")
		)
		(zone
			(layer "F.Cu")
			(hatch none 0.5)
			(connect_pads
				(clearance 0)
			)
			(min_thickness 0.25)
			(keepout
				(tracks allowed)
				(vias not_allowed)
				(pads allowed)
				(copperpour not_allowed)
				(footprints allowed)
			)
			(placement
				(enabled no)
				(sheetname "")
			)
			(fill
				(thermal_gap 0.5)
				(thermal_bridge_width 0.5)
				(island_removal_mode 0)
			)
			(polygon
				(pts
					(xy 452.3359 -10.795) (xy 455.3585 -10.795) (xy 455.3585 -13.6906) (xy 455.3585 -14.0208) (xy 452.3359 -14.0208)
					(xy 452.3359 -13.6906)
				)
			)
		)
		(zone
			(layer "F.Cu")
			(hatch none 0.5)
			(connect_pads
				(clearance 0)
			)
			(min_thickness 0.25)
			(keepout
				(tracks allowed)
				(vias not_allowed)
				(pads allowed)
				(copperpour not_allowed)
				(footprints allowed)
			)
			(placement
				(enabled no)
				(sheetname "")
			)
			(fill
				(thermal_gap 0.5)
				(thermal_bridge_width 0.5)
				(island_removal_mode 0)
			)
			(polygon
				(pts
					(xy 455.3585 -17.0815) (xy 455.3585 -19.9898) (xy 452.3359 -19.9898) (xy 452.3359 -17.0942) (xy 452.3359 -16.764)
					(xy 455.3585 -16.764)
				)
			)
		)
	)
	(footprint ""
		(layer "F.Cu")
		(at 351.779332 3.530854 -90)
		(property "Reference" "C7G38"
			(at 0 0 270)
			(layer "F.SilkS")
			(hide yes)
			(effects
				(font
					(size 1.27 1.27)
				)
			)
		)
		(property "Value" ""
			(at 0 0 270)
			(layer "F.Fab")
			(effects
				(font
					(size 1.27 1.27)
				)
			)
		)
		(duplicate_pad_numbers_are_jumpers no)
		(fp_poly
			(pts
				(xy 0.3048 -0.1016) (xy 0.3048 0.9906) (xy -0.3048 0.9906) (xy -0.3048 -0.1016)
			)
			(stroke
				(width 0)
				(type default)
			)
			(fill no)
			(layer "F.CrtYd")
		)
		(fp_line
			(start -0.3048 0.9906)
			(end 0.3048 0.9906)
			(stroke
				(width 0.1)
				(type default)
			)
			(layer "F.Fab")
		)
		(fp_line
			(start 0.3048 0.9906)
			(end 0.3048 -0.1016)
			(stroke
				(width 0.1)
				(type default)
			)
			(layer "F.Fab")
		)
		(fp_line
			(start -0.3048 -0.1016)
			(end -0.3048 0.9906)
			(stroke
				(width 0.1)
				(type default)
			)
			(layer "F.Fab")
		)
		(fp_line
			(start 0.3048 -0.1016)
			(end -0.3048 -0.1016)
			(stroke
				(width 0.1)
				(type default)
			)
			(layer "F.Fab")
		)
		(pad "1" smd rect
			(at 0 0 270)
			(size 0.508 0.508)
			(layers "F.Cu" "F.Mask" "F.Paste")
			(net "VR_PVDDQ_ABC_PH2_BOOT")
		)
		(pad "2" smd rect
			(at 0 0.889 270)
			(size 0.508 0.508)
			(layers "F.Cu" "F.Mask" "F.Paste")
			(net "VR_PVDDQ_ABC_PH2_PHASE")
		)
		(zone
			(layer "F.Cu")
			(hatch none 0.5)
			(connect_pads
				(clearance 0)
			)
			(min_thickness 0.25)
			(keepout
				(tracks not_allowed)
				(vias allowed)
				(pads allowed)
				(copperpour not_allowed)
				(footprints allowed)
			)
			(placement
				(enabled no)
				(sheetname "")
			)
			(fill
				(thermal_gap 0.5)
				(thermal_bridge_width 0.5)
				(island_removal_mode 0)
			)
			(polygon
				(pts
					(xy 351.144332 3.276854) (xy 351.144332 3.784854) (xy 351.525332 3.784854) (xy 351.525332 3.276854)
				)
			)
		)
		(zone
			(layer "F.Cu")
			(hatch none 0.5)
			(connect_pads
				(clearance 0)
			)
			(min_thickness 0.25)
			(keepout
				(tracks allowed)
				(vias not_allowed)
				(pads allowed)
				(copperpour not_allowed)
				(footprints allowed)
			)
			(placement
				(enabled no)
				(sheetname "")
			)
			(fill
				(thermal_gap 0.5)
				(thermal_bridge_width 0.5)
				(island_removal_mode 0)
			)
			(polygon
				(pts
					(xy 351.525332 3.276854) (xy 351.525332 3.784854) (xy 351.144332 3.784854) (xy 351.144332 3.276854)
				)
			)
		)
	)
	(footprint ""
		(layer "F.Cu")
		(at 333.849218 -129.921)
		(property "Reference" "C7B7"
			(at 0 0 0)
			(layer "F.SilkS")
			(hide yes)
			(effects
				(font
					(size 1.27 1.27)
				)
			)
		)
		(property "Value" ""
			(at 0 0 0)
			(layer "F.Fab")
			(effects
				(font
					(size 1.27 1.27)
				)
			)
		)
		(duplicate_pad_numbers_are_jumpers no)
		(fp_poly
			(pts
				(xy -0.7239 -0.2159) (xy 0.7239 -0.2159) (xy 0.7239 1.9939) (xy -0.7239 1.9939)
			)
			(stroke
				(width 0)
				(type default)
			)
			(fill no)
			(layer "F.CrtYd")
		)
		(fp_line
			(start -0.7239 -0.2159)
			(end -0.7239 1.9939)
			(stroke
				(width 0.1)
				(type default)
			)
			(layer "F.Fab")
		)
		(fp_line
			(start -0.7239 1.9939)
			(end 0.7239 1.9939)
			(stroke
				(width 0.1)
				(type default)
			)
			(layer "F.Fab")
		)
		(fp_line
			(start 0.7239 -0.2159)
			(end -0.7239 -0.2159)
			(stroke
				(width 0.1)
				(type default)
			)
			(layer "F.Fab")
		)
		(fp_line
			(start 0.7239 1.9939)
			(end 0.7239 -0.2159)
			(stroke
				(width 0.1)
				(type default)
			)
			(layer "F.Fab")
		)
		(pad "1" smd rect
			(at 0 0)
			(size 1.27 1.016)
			(layers "F.Cu" "F.Mask" "F.Paste")
			(net "PVPP_DEF")
		)
		(pad "2" smd rect
			(at 0 1.778)
			(size 1.27 1.016)
			(layers "F.Cu" "F.Mask" "F.Paste")
			(net "GND")
		)
		(zone
			(layer "F.Cu")
			(hatch none 0.5)
			(connect_pads
				(clearance 0)
			)
			(min_thickness 0.25)
			(keepout
				(tracks not_allowed)
				(vias allowed)
				(pads allowed)
				(copperpour not_allowed)
				(footprints allowed)
			)
			(placement
				(enabled no)
				(sheetname "")
			)
			(fill
				(thermal_gap 0.5)
				(thermal_bridge_width 0.5)
				(island_removal_mode 0)
			)
			(polygon
				(pts
					(xy 333.214218 -129.413) (xy 334.484218 -129.413) (xy 334.484218 -128.651) (xy 333.214218 -128.651)
				)
			)
		)
	)
	(footprint ""
		(layer "F.Cu")
		(at 18.288 -97.917 -90)
		(property "Reference" "C1C8"
			(at 0 0 270)
			(layer "F.SilkS")
			(hide yes)
			(effects
				(font
					(size 1.27 1.27)
				)
			)
		)
		(property "Value" ""
			(at 0 0 270)
			(layer "F.Fab")
			(effects
				(font
					(size 1.27 1.27)
				)
			)
		)
		(duplicate_pad_numbers_are_jumpers no)
		(fp_rect
			(start 0.3048 0.9906)
			(end -0.3048 -0.1016)
			(stroke
				(width 0)
				(type default)
			)
			(fill no)
			(layer "F.CrtYd")
		)
		(fp_line
			(start -0.3048 0.9906)
			(end 0.3048 0.9906)
			(stroke
				(width 0.1)
				(type default)
			)
			(layer "F.Fab")
		)
		(fp_line
			(start 0.3048 0.9906)
			(end 0.3048 -0.1016)
			(stroke
				(width 0.1)
				(type default)
			)
			(layer "F.Fab")
		)
		(fp_line
			(start -0.3048 -0.1016)
			(end -0.3048 0.9906)
			(stroke
				(width 0.1)
				(type default)
			)
			(layer "F.Fab")
		)
		(fp_line
			(start 0.3048 -0.1016)
			(end -0.3048 -0.1016)
			(stroke
				(width 0.1)
				(type default)
			)
			(layer "F.Fab")
		)
		(pad "1" smd rect
			(at 0 0 270)
			(size 0.508 0.508)
			(layers "F.Cu" "F.Mask" "F.Paste")
			(net "VR_PVCCIN_CPU1_AVINSEN")
		)
		(pad "2" smd rect
			(at 0 0.889 270)
			(size 0.508 0.508)
			(layers "F.Cu" "F.Mask" "F.Paste")
			(net "GND")
		)
		(zone
			(layer "F.Cu")
			(hatch none 0.5)
			(connect_pads
				(clearance 0)
			)
			(min_thickness 0.25)
			(keepout
				(tracks allowed)
				(vias not_allowed)
				(pads allowed)
				(copperpour not_allowed)
				(footprints allowed)
			)
			(placement
				(enabled no)
				(sheetname "")
			)
			(fill
				(thermal_gap 0.5)
				(thermal_bridge_width 0.5)
				(island_removal_mode 0)
			)
			(polygon
				(pts
					(xy 17.653 -97.663) (xy 18.034 -97.663) (xy 18.034 -98.171) (xy 17.653 -98.171)
				)
			)
		)
		(zone
			(layer "F.Cu")
			(hatch none 0.5)
			(connect_pads
				(clearance 0)
			)
			(min_thickness 0.25)
			(keepout
				(tracks not_allowed)
				(vias allowed)
				(pads allowed)
				(copperpour not_allowed)
				(footprints allowed)
			)
			(placement
				(enabled no)
				(sheetname "")
			)
			(fill
				(thermal_gap 0.5)
				(thermal_bridge_width 0.5)
				(island_removal_mode 0)
			)
			(polygon
				(pts
					(xy 17.653 -97.663) (xy 18.034 -97.663) (xy 18.034 -98.171) (xy 17.653 -98.171)
				)
			)
		)
	)
	(footprint ""
		(layer "F.Cu")
		(at 113.867692 -71.714614 180)
		(property "Reference" "C3D23"
			(at 0 0 180)
			(layer "F.SilkS")
			(hide yes)
			(effects
				(font
					(size 1.27 1.27)
				)
			)
		)
		(property "Value" ""
			(at 0 0 180)
			(layer "F.Fab")
			(effects
				(font
					(size 1.27 1.27)
				)
			)
		)
		(duplicate_pad_numbers_are_jumpers no)
		(fp_poly
			(pts
				(xy -0.4953 -0.2032) (xy 0.4953 -0.2032) (xy 0.4953 1.6002) (xy -0.4953 1.6002)
			)
			(stroke
				(width 0)
				(type default)
			)
			(fill no)
			(layer "F.CrtYd")
		)
		(fp_line
			(start 0.4953 1.6002)
			(end -0.4953 1.6002)
			(stroke
				(width 0.1)
				(type default)
			)
			(layer "F.Fab")
		)
		(fp_line
			(start 0.4953 -0.2032)
			(end 0.4953 1.6002)
			(stroke
				(width 0.1)
				(type default)
			)
			(layer "F.Fab")
		)
		(fp_line
			(start -0.4953 1.6002)
			(end -0.4953 -0.2032)
			(stroke
				(width 0.1)
				(type default)
			)
			(layer "F.Fab")
		)
		(fp_line
			(start -0.4953 -0.2032)
			(end 0.4953 -0.2032)
			(stroke
				(width 0.1)
				(type default)
			)
			(layer "F.Fab")
		)
		(pad "1" smd rect
			(at 0 0 180)
			(size 0.762 0.889)
			(layers "F.Cu" "F.Mask" "F.Paste")
			(net "PVCCIO_CPU1")
		)
		(pad "2" smd rect
			(at 0 1.397 180)
			(size 0.762 0.889)
			(layers "F.Cu" "F.Mask" "F.Paste")
			(net "GND")
		)
		(zone
			(layer "F.Cu")
			(hatch none 0.5)
			(connect_pads
				(clearance 0)
			)
			(min_thickness 0.25)
			(keepout
				(tracks not_allowed)
				(vias allowed)
				(pads allowed)
				(copperpour not_allowed)
				(footprints allowed)
			)
			(placement
				(enabled no)
				(sheetname "")
			)
			(fill
				(thermal_gap 0.5)
				(thermal_bridge_width 0.5)
				(island_removal_mode 0)
			)
			(polygon
				(pts
					(xy 114.248692 -72.159114) (xy 113.486692 -72.159114) (xy 113.486692 -72.667114) (xy 114.248692 -72.667114)
				)
			)
		)
	)
	(footprint ""
		(layer "F.Cu")
		(at 318.8716 -30.585918 -90)
		(property "Reference" "R6F10"
			(at 0 0 270)
			(layer "F.SilkS")
			(hide yes)
			(effects
				(font
					(size 1.27 1.27)
				)
			)
		)
		(property "Value" ""
			(at 0 0 270)
			(layer "F.Fab")
			(effects
				(font
					(size 1.27 1.27)
				)
			)
		)
		(duplicate_pad_numbers_are_jumpers no)
		(fp_poly
			(pts
				(xy -0.2794 -0.1016) (xy 0.2794 -0.1016) (xy 0.2794 0.9906) (xy -0.2794 0.9906)
			)
			(stroke
				(width 0)
				(type default)
			)
			(fill no)
			(layer "F.CrtYd")
		)
		(fp_line
			(start -0.2794 0.9906)
			(end 0.2794 0.9906)
			(stroke
				(width 0.1)
				(type default)
			)
			(layer "F.Fab")
		)
		(fp_line
			(start 0.2794 0.9906)
			(end 0.2794 -0.1016)
			(stroke
				(width 0.1)
				(type default)
			)
			(layer "F.Fab")
		)
		(fp_line
			(start -0.2794 -0.1016)
			(end -0.2794 0.9906)
			(stroke
				(width 0.1)
				(type default)
			)
			(layer "F.Fab")
		)
		(fp_line
			(start 0.2794 -0.1016)
			(end -0.2794 -0.1016)
			(stroke
				(width 0.1)
				(type default)
			)
			(layer "F.Fab")
		)
		(pad "1" smd rect
			(at 0 0 270)
			(size 0.508 0.508)
			(layers "F.Cu" "F.Mask" "F.Paste")
			(net "CLK_322M_156M_CPU0_OSC_VRM_DN")
		)
		(pad "2" smd rect
			(at 0 0.889 270)
			(size 0.508 0.508)
			(layers "F.Cu" "F.Mask" "F.Paste")
			(net "CLK_322M_OSC_CPU0_RC_DN")
		)
		(zone
			(layer "F.Cu")
			(hatch none 0.5)
			(connect_pads
				(clearance 0)
			)
			(min_thickness 0.25)
			(keepout
				(tracks not_allowed)
				(vias allowed)
				(pads allowed)
				(copperpour not_allowed)
				(footprints allowed)
			)
			(placement
				(enabled no)
				(sheetname "")
			)
			(fill
				(thermal_gap 0.5)
				(thermal_bridge_width 0.5)
				(island_removal_mode 0)
			)
			(polygon
				(pts
					(xy 318.2366 -30.839918) (xy 318.2366 -30.331918) (xy 318.6176 -30.331918) (xy 318.6176 -30.839918)
				)
			)
		)
		(zone
			(layer "F.Cu")
			(hatch none 0.5)
			(connect_pads
				(clearance 0)
			)
			(min_thickness 0.25)
			(keepout
				(tracks allowed)
				(vias not_allowed)
				(pads allowed)
				(copperpour not_allowed)
				(footprints allowed)
			)
			(placement
				(enabled no)
				(sheetname "")
			)
			(fill
				(thermal_gap 0.5)
				(thermal_bridge_width 0.5)
				(island_removal_mode 0)
			)
			(polygon
				(pts
					(xy 318.6176 -30.839918) (xy 318.6176 -30.331918) (xy 318.2366 -30.331918) (xy 318.2366 -30.839918)
				)
			)
		)
	)
	(footprint ""
		(layer "F.Cu")
		(at 193.8782 -58.928 90)
		(property "Reference" "C4E17"
			(at 0 0 90)
			(layer "F.SilkS")
			(hide yes)
			(effects
				(font
					(size 1.27 1.27)
				)
			)
		)
		(property "Value" ""
			(at 0 0 90)
			(layer "F.Fab")
			(effects
				(font
					(size 1.27 1.27)
				)
			)
		)
		(duplicate_pad_numbers_are_jumpers no)
		(fp_rect
			(start -0.3048 0.9906)
			(end 0.3048 -0.1016)
			(stroke
				(width 0)
				(type default)
			)
			(fill no)
			(layer "F.CrtYd")
		)
		(fp_line
			(start 0.3048 -0.1016)
			(end -0.3048 -0.1016)
			(stroke
				(width 0.1)
				(type default)
			)
			(layer "F.Fab")
		)
		(fp_line
			(start -0.3048 -0.1016)
			(end -0.3048 0.9906)
			(stroke
				(width 0.1)
				(type default)
			)
			(layer "F.Fab")
		)
		(fp_line
			(start 0.3048 0.9906)
			(end 0.3048 -0.1016)
			(stroke
				(width 0.1)
				(type default)
			)
			(layer "F.Fab")
		)
		(fp_line
			(start -0.3048 0.9906)
			(end 0.3048 0.9906)
			(stroke
				(width 0.1)
				(type default)
			)
			(layer "F.Fab")
		)
		(pad "1" smd rect
			(at 0 0 90)
			(size 0.508 0.508)
			(layers "F.Cu" "F.Mask" "F.Paste")
			(net "VR_PVCCIN_CPU0_PH1_BOOT")
		)
		(pad "2" smd rect
			(at 0 0.889 90)
			(size 0.508 0.508)
			(layers "F.Cu" "F.Mask" "F.Paste")
			(net "VR_PVCCIN_CPU0_PH1_PHASE")
		)
		(zone
			(layer "F.Cu")
			(hatch none 0.5)
			(connect_pads
				(clearance 0)
			)
			(min_thickness 0.25)
			(keepout
				(tracks allowed)
				(vias not_allowed)
				(pads allowed)
				(copperpour not_allowed)
				(footprints allowed)
			)
			(placement
				(enabled no)
				(sheetname "")
			)
			(fill
				(thermal_gap 0.5)
				(thermal_bridge_width 0.5)
				(island_removal_mode 0)
			)
			(polygon
				(pts
					(xy 194.5132 -58.674) (xy 194.5132 -59.182) (xy 194.1322 -59.182) (xy 194.1322 -58.674)
				)
			)
		)
		(zone
			(layer "F.Cu")
			(hatch none 0.5)
			(connect_pads
				(clearance 0)
			)
			(min_thickness 0.25)
			(keepout
				(tracks not_allowed)
				(vias allowed)
				(pads allowed)
				(copperpour not_allowed)
				(footprints allowed)
			)
			(placement
				(enabled no)
				(sheetname "")
			)
			(fill
				(thermal_gap 0.5)
				(thermal_bridge_width 0.5)
				(island_removal_mode 0)
			)
			(polygon
				(pts
					(xy 194.5132 -58.674) (xy 194.5132 -59.182) (xy 194.1322 -59.182) (xy 194.1322 -58.674)
				)
			)
		)
	)
	(footprint ""
		(layer "F.Cu")
		(at 272.134838 -68.365116 180)
		(property "Reference" "C5D61"
			(at 0 0 180)
			(layer "F.SilkS")
			(hide yes)
			(effects
				(font
					(size 1.27 1.27)
				)
			)
		)
		(property "Value" ""
			(at 0 0 180)
			(layer "F.Fab")
			(effects
				(font
					(size 1.27 1.27)
				)
			)
		)
		(duplicate_pad_numbers_are_jumpers no)
		(fp_poly
			(pts
				(xy -0.4953 -0.2032) (xy 0.4953 -0.2032) (xy 0.4953 1.6002) (xy -0.4953 1.6002)
			)
			(stroke
				(width 0)
				(type default)
			)
			(fill no)
			(layer "F.CrtYd")
		)
		(fp_line
			(start 0.4953 1.6002)
			(end -0.4953 1.6002)
			(stroke
				(width 0.1)
				(type default)
			)
			(layer "F.Fab")
		)
		(fp_line
			(start 0.4953 -0.2032)
			(end 0.4953 1.6002)
			(stroke
				(width 0.1)
				(type default)
			)
			(layer "F.Fab")
		)
		(fp_line
			(start -0.4953 1.6002)
			(end -0.4953 -0.2032)
			(stroke
				(width 0.1)
				(type default)
			)
			(layer "F.Fab")
		)
		(fp_line
			(start -0.4953 -0.2032)
			(end 0.4953 -0.2032)
			(stroke
				(width 0.1)
				(type default)
			)
			(layer "F.Fab")
		)
		(pad "1" smd rect
			(at 0 0 180)
			(size 0.762 0.889)
			(layers "F.Cu" "F.Mask" "F.Paste")
			(net "PVDDQ_ABC")
		)
		(pad "2" smd rect
			(at 0 1.397 180)
			(size 0.762 0.889)
			(layers "F.Cu" "F.Mask" "F.Paste")
			(net "GND")
		)
		(zone
			(layer "F.Cu")
			(hatch none 0.5)
			(connect_pads
				(clearance 0)
			)
			(min_thickness 0.25)
			(keepout
				(tracks not_allowed)
				(vias allowed)
				(pads allowed)
				(copperpour not_allowed)
				(footprints allowed)
			)
			(placement
				(enabled no)
				(sheetname "")
			)
			(fill
				(thermal_gap 0.5)
				(thermal_bridge_width 0.5)
				(island_removal_mode 0)
			)
			(polygon
				(pts
					(xy 272.515838 -68.809616) (xy 271.753838 -68.809616) (xy 271.753838 -69.317616) (xy 272.515838 -69.317616)
				)
			)
		)
	)
	(footprint ""
		(layer "F.Cu")
		(at 451.866 -26.8478 90)
		(property "Reference" "C1W15"
			(at 0.97536 0.76708 0)
			(unlocked yes)
			(layer "F.SilkS")
			(effects
				(font
					(size 0.4064 0.254)
					(thickness 0.1524)
				)
			)
		)
		(property "Value" ""
			(at 0 0 90)
			(layer "F.Fab")
			(effects
				(font
					(size 1.27 1.27)
				)
			)
		)
		(duplicate_pad_numbers_are_jumpers no)
		(fp_poly
			(pts
				(xy -0.4953 -0.2032) (xy 0.4953 -0.2032) (xy 0.4953 1.6002) (xy -0.4953 1.6002)
			)
			(stroke
				(width 0)
				(type default)
			)
			(fill no)
			(layer "F.CrtYd")
		)
		(fp_line
			(start 0.4953 -0.2032)
			(end 0.4953 1.6002)
			(stroke
				(width 0.1)
				(type default)
			)
			(layer "F.Fab")
		)
		(fp_line
			(start -0.4953 -0.2032)
			(end 0.4953 -0.2032)
			(stroke
				(width 0.1)
				(type default)
			)
			(layer "F.Fab")
		)
		(fp_line
			(start 0.4953 1.6002)
			(end -0.4953 1.6002)
			(stroke
				(width 0.1)
				(type default)
			)
			(layer "F.Fab")
		)
		(fp_line
			(start -0.4953 1.6002)
			(end -0.4953 -0.2032)
			(stroke
				(width 0.1)
				(type default)
			)
			(layer "F.Fab")
		)
		(pad "1" smd rect
			(at 0 0 90)
			(size 0.762 0.889)
			(layers "F.Cu" "F.Mask" "F.Paste")
			(net "P2V5_AUX_BMC")
		)
		(pad "2" smd rect
			(at 0 1.397 90)
			(size 0.762 0.889)
			(layers "F.Cu" "F.Mask" "F.Paste")
			(net "GND")
		)
		(zone
			(layer "F.Cu")
			(hatch none 0.5)
			(connect_pads
				(clearance 0)
			)
			(min_thickness 0.25)
			(keepout
				(tracks not_allowed)
				(vias allowed)
				(pads allowed)
				(copperpour not_allowed)
				(footprints allowed)
			)
			(placement
				(enabled no)
				(sheetname "")
			)
			(fill
				(thermal_gap 0.5)
				(thermal_bridge_width 0.5)
				(island_removal_mode 0)
			)
			(polygon
				(pts
					(xy 452.3105 -26.4668) (xy 452.3105 -27.2288) (xy 452.8185 -27.2288) (xy 452.8185 -26.4668)
				)
			)
		)
	)
	(footprint ""
		(layer "F.Cu")
		(at 451.85838 -31.3055 90)
		(property "Reference" "R25W34"
			(at 0 0 90)
			(layer "F.SilkS")
			(hide yes)
			(effects
				(font
					(size 1.27 1.27)
				)
			)
		)
		(property "Value" "*"
			(at 0.064008 -4.108196 90)
			(unlocked yes)
			(layer "F.Fab")
			(hide yes)
			(effects
				(font
					(size 1.27 1.016)
					(thickness 0.1524)
				)
			)
		)
		(property "Device Type" "120R2F-GP_RCL_GP-120R2F-GP,64.A"
			(at 0.064008 -5.632196 90)
			(unlocked yes)
			(layer "F.Fab")
			(hide yes)
			(effects
				(font
					(size 1.27 1.016)
					(thickness 0.1524)
				)
			)
		)
		(duplicate_pad_numbers_are_jumpers no)
		(fp_line
			(start 0.508 -0.9398)
			(end -0.508 -0.9398)
			(stroke
				(width 0.1524)
				(type default)
			)
			(layer "F.SilkS")
		)
		(fp_line
			(start -0.508 -0.9398)
			(end -0.508 0.9398)
			(stroke
				(width 0.1524)
				(type default)
			)
			(layer "F.SilkS")
		)
		(fp_rect
			(start -0.508 0.9398)
			(end 0.508 -0.9398)
			(stroke
				(width 0)
				(type default)
			)
			(fill no)
			(layer "F.CrtYd")
		)
		(fp_rect
			(start -0.508 0.9398)
			(end 0.508 -0.9398)
			(stroke
				(width 0)
				(type default)
			)
			(fill no)
			(layer "F.Fab")
		)
		(pad "1" smd custom
			(at 0 -0.4445 90)
			(size 0.1397 0.1397)
			(layers "F.Cu" "F.Mask" "F.Paste")
			(net "BMC_M_WE_N")
			(options
				(clearance outline)
				(anchor circle)
			)
			(primitives
				(gr_poly
					(pts
						(arc
							(start -0.1778 -0.2794)
							(mid -0.249642 -0.249642)
							(end -0.2794 -0.1778)
						)
						(arc
							(start -0.2794 0.1778)
							(mid -0.249642 0.249642)
							(end -0.1778 0.2794)
						)
						(arc
							(start 0.1778 0.2794)
							(mid 0.249642 0.249642)
							(end 0.2794 0.1778)
						)
						(arc
							(start 0.2794 -0.1778)
							(mid 0.249642 -0.249642)
							(end 0.1778 -0.2794)
						)
					)
					(width 0)
					(fill yes)
				)
			)
		)
		(pad "2" smd custom
			(at 0 0.4445 90)
			(size 0.1397 0.1397)
			(layers "F.Cu" "F.Mask" "F.Paste")
			(net "P1V2_AUX_BMC")
			(options
				(clearance outline)
				(anchor circle)
			)
			(primitives
				(gr_poly
					(pts
						(arc
							(start -0.1778 -0.2794)
							(mid -0.249642 -0.249642)
							(end -0.2794 -0.1778)
						)
						(arc
							(start -0.2794 0.1778)
							(mid -0.249642 0.249642)
							(end -0.1778 0.2794)
						)
						(arc
							(start 0.1778 0.2794)
							(mid 0.249642 0.249642)
							(end 0.2794 0.1778)
						)
						(arc
							(start 0.2794 -0.1778)
							(mid 0.249642 -0.249642)
							(end 0.1778 -0.2794)
						)
					)
					(width 0)
					(fill yes)
				)
			)
		)
	)
	(footprint ""
		(layer "F.Cu")
		(at 248.8819 -140.208 -90)
		(property "Reference" "C5A12"
			(at 1.848866 0.752348 270)
			(unlocked yes)
			(layer "F.SilkS")
			(effects
				(font
					(size 1.27 0.9652)
					(thickness 0.1524)
				)
			)
		)
		(property "Value" ""
			(at 0 0 270)
			(layer "F.Fab")
			(effects
				(font
					(size 1.27 1.27)
				)
			)
		)
		(duplicate_pad_numbers_are_jumpers no)
		(fp_rect
			(start -0.500126 1.598422)
			(end 0.500126 -0.201422)
			(stroke
				(width 0)
				(type default)
			)
			(fill no)
			(layer "F.CrtYd")
		)
		(fp_line
			(start -0.500126 1.598422)
			(end -0.500126 -0.201422)
			(stroke
				(width 0.1)
				(type default)
			)
			(layer "F.Fab")
		)
		(fp_line
			(start 0.500126 1.598422)
			(end -0.500126 1.598422)
			(stroke
				(width 0.1)
				(type default)
			)
			(layer "F.Fab")
		)
		(fp_line
			(start -0.500126 -0.201422)
			(end 0.500126 -0.201422)
			(stroke
				(width 0.1)
				(type default)
			)
			(layer "F.Fab")
		)
		(fp_line
			(start 0.500126 -0.201422)
			(end 0.500126 1.598422)
			(stroke
				(width 0.1)
				(type default)
			)
			(layer "F.Fab")
		)
		(pad "1" smd rect
			(at 0 0 180)
			(size 0.889 0.9906)
			(layers "F.Cu" "F.Mask" "F.Paste")
			(net "PVDDQ_DEF")
		)
		(pad "2" smd rect
			(at 0 1.397 180)
			(size 0.889 0.9906)
			(layers "F.Cu" "F.Mask" "F.Paste")
			(net "GND")
		)
		(zone
			(layer "F.Cu")
			(hatch none 0.5)
			(connect_pads
				(clearance 0)
			)
			(min_thickness 0.25)
			(keepout
				(tracks not_allowed)
				(vias allowed)
				(pads allowed)
				(copperpour not_allowed)
				(footprints allowed)
			)
			(placement
				(enabled no)
				(sheetname "")
			)
			(fill
				(thermal_gap 0.5)
				(thermal_bridge_width 0.5)
				(island_removal_mode 0)
			)
			(polygon
				(pts
					(xy 247.9294 -140.7033) (xy 247.9294 -139.7127) (xy 248.4374 -139.7127) (xy 248.4374 -140.7033)
				)
			)
		)
		(zone
			(layer "F.Cu")
			(hatch none 0.5)
			(connect_pads
				(clearance 0)
			)
			(min_thickness 0.25)
			(keepout
				(tracks allowed)
				(vias not_allowed)
				(pads allowed)
				(copperpour not_allowed)
				(footprints allowed)
			)
			(placement
				(enabled no)
				(sheetname "")
			)
			(fill
				(thermal_gap 0.5)
				(thermal_bridge_width 0.5)
				(island_removal_mode 0)
			)
			(polygon
				(pts
					(xy 247.9294 -140.7033) (xy 247.9294 -139.7127) (xy 248.4374 -139.7127) (xy 248.4374 -140.7033)
				)
			)
		)
	)
	(footprint ""
		(layer "F.Cu")
		(at 117.029992 -71.460614 -90)
		(property "Reference" "R3D19"
			(at 0 0 270)
			(layer "F.SilkS")
			(hide yes)
			(effects
				(font
					(size 1.27 1.27)
				)
			)
		)
		(property "Value" ""
			(at 0 0 270)
			(layer "F.Fab")
			(effects
				(font
					(size 1.27 1.27)
				)
			)
		)
		(duplicate_pad_numbers_are_jumpers no)
		(fp_poly
			(pts
				(xy -0.2794 -0.1016) (xy 0.2794 -0.1016) (xy 0.2794 0.9906) (xy -0.2794 0.9906)
			)
			(stroke
				(width 0)
				(type default)
			)
			(fill no)
			(layer "F.CrtYd")
		)
		(fp_line
			(start -0.2794 0.9906)
			(end 0.2794 0.9906)
			(stroke
				(width 0.1)
				(type default)
			)
			(layer "F.Fab")
		)
		(fp_line
			(start 0.2794 0.9906)
			(end 0.2794 -0.1016)
			(stroke
				(width 0.1)
				(type default)
			)
			(layer "F.Fab")
		)
		(fp_line
			(start -0.2794 -0.1016)
			(end -0.2794 0.9906)
			(stroke
				(width 0.1)
				(type default)
			)
			(layer "F.Fab")
		)
		(fp_line
			(start 0.2794 -0.1016)
			(end -0.2794 -0.1016)
			(stroke
				(width 0.1)
				(type default)
			)
			(layer "F.Fab")
		)
		(pad "1" smd rect
			(at 0 0 270)
			(size 0.508 0.508)
			(layers "F.Cu" "F.Mask" "F.Paste")
			(net "A_CPU1_UPI01_RBIAS")
		)
		(pad "2" smd rect
			(at 0 0.889 270)
			(size 0.508 0.508)
			(layers "F.Cu" "F.Mask" "F.Paste")
			(net "GND")
		)
		(zone
			(layer "F.Cu")
			(hatch none 0.5)
			(connect_pads
				(clearance 0)
			)
			(min_thickness 0.25)
			(keepout
				(tracks not_allowed)
				(vias allowed)
				(pads allowed)
				(copperpour not_allowed)
				(footprints allowed)
			)
			(placement
				(enabled no)
				(sheetname "")
			)
			(fill
				(thermal_gap 0.5)
				(thermal_bridge_width 0.5)
				(island_removal_mode 0)
			)
			(polygon
				(pts
					(xy 116.394992 -71.714614) (xy 116.394992 -71.206614) (xy 116.775992 -71.206614) (xy 116.775992 -71.714614)
				)
			)
		)
		(zone
			(layer "F.Cu")
			(hatch none 0.5)
			(connect_pads
				(clearance 0)
			)
			(min_thickness 0.25)
			(keepout
				(tracks allowed)
				(vias not_allowed)
				(pads allowed)
				(copperpour not_allowed)
				(footprints allowed)
			)
			(placement
				(enabled no)
				(sheetname "")
			)
			(fill
				(thermal_gap 0.5)
				(thermal_bridge_width 0.5)
				(island_removal_mode 0)
			)
			(polygon
				(pts
					(xy 116.775992 -71.714614) (xy 116.775992 -71.206614) (xy 116.394992 -71.206614) (xy 116.394992 -71.714614)
				)
			)
		)
	)
	(footprint ""
		(layer "F.Cu")
		(at 39.723568 -102.616 180)
		(property "Reference" "R1C6"
			(at 0 0 180)
			(layer "F.SilkS")
			(hide yes)
			(effects
				(font
					(size 1.27 1.27)
				)
			)
		)
		(property "Value" ""
			(at 0 0 180)
			(layer "F.Fab")
			(effects
				(font
					(size 1.27 1.27)
				)
			)
		)
		(duplicate_pad_numbers_are_jumpers no)
		(fp_poly
			(pts
				(xy -0.2794 -0.1016) (xy 0.2794 -0.1016) (xy 0.2794 0.9906) (xy -0.2794 0.9906)
			)
			(stroke
				(width 0)
				(type default)
			)
			(fill no)
			(layer "F.CrtYd")
		)
		(fp_line
			(start 0.2794 0.9906)
			(end 0.2794 -0.1016)
			(stroke
				(width 0.1)
				(type default)
			)
			(layer "F.Fab")
		)
		(fp_line
			(start 0.2794 -0.1016)
			(end -0.2794 -0.1016)
			(stroke
				(width 0.1)
				(type default)
			)
			(layer "F.Fab")
		)
		(fp_line
			(start -0.2794 0.9906)
			(end 0.2794 0.9906)
			(stroke
				(width 0.1)
				(type default)
			)
			(layer "F.Fab")
		)
		(fp_line
			(start -0.2794 -0.1016)
			(end -0.2794 0.9906)
			(stroke
				(width 0.1)
				(type default)
			)
			(layer "F.Fab")
		)
		(pad "1" smd rect
			(at 0 0 180)
			(size 0.508 0.508)
			(layers "F.Cu" "F.Mask" "F.Paste")
			(net "VSENSE_PVSA_CPU1_P")
		)
		(pad "2" smd rect
			(at 0 0.889 180)
			(size 0.508 0.508)
			(layers "F.Cu" "F.Mask" "F.Paste")
			(net "VSENSE_PVSA_CPU1_N")
		)
		(zone
			(layer "F.Cu")
			(hatch none 0.5)
			(connect_pads
				(clearance 0)
			)
			(min_thickness 0.25)
			(keepout
				(tracks not_allowed)
				(vias allowed)
				(pads allowed)
				(copperpour not_allowed)
				(footprints allowed)
			)
			(placement
				(enabled no)
				(sheetname "")
			)
			(fill
				(thermal_gap 0.5)
				(thermal_bridge_width 0.5)
				(island_removal_mode 0)
			)
			(polygon
				(pts
					(xy 39.977568 -103.251) (xy 39.469568 -103.251) (xy 39.469568 -102.87) (xy 39.977568 -102.87)
				)
			)
		)
		(zone
			(layer "F.Cu")
			(hatch none 0.5)
			(connect_pads
				(clearance 0)
			)
			(min_thickness 0.25)
			(keepout
				(tracks allowed)
				(vias not_allowed)
				(pads allowed)
				(copperpour not_allowed)
				(footprints allowed)
			)
			(placement
				(enabled no)
				(sheetname "")
			)
			(fill
				(thermal_gap 0.5)
				(thermal_bridge_width 0.5)
				(island_removal_mode 0)
			)
			(polygon
				(pts
					(xy 39.977568 -102.87) (xy 39.469568 -102.87) (xy 39.469568 -103.251) (xy 39.977568 -103.251)
				)
			)
		)
	)
	(footprint ""
		(layer "F.Cu")
		(at 149.065488 -164.91712 90)
		(property "Reference" "T1D8"
			(at 0 0 90)
			(layer "F.SilkS")
			(hide yes)
			(effects
				(font
					(size 1.27 1.27)
				)
			)
		)
		(property "Value" "*"
			(at -3.4036 -4.46405 90)
			(unlocked yes)
			(layer "F.Fab")
			(hide yes)
			(effects
				(font
					(size 0.889 0.889)
					(thickness 0.1524)
				)
			)
		)
		(property "Device Type" "TEST-PAD-12P-1-GP-U_DISCRET-GBA"
			(at -3.4036 -5.98805 90)
			(unlocked yes)
			(layer "F.Fab")
			(hide yes)
			(effects
				(font
					(size 0.889 0.889)
					(thickness 0.1524)
				)
			)
		)
		(duplicate_pad_numbers_are_jumpers no)
		(fp_line
			(start 2.3622 -4.826)
			(end 2.3622 3.4798)
			(stroke
				(width 0.1524)
				(type default)
			)
			(layer "F.SilkS")
		)
		(fp_line
			(start -2.3876 -4.826)
			(end 2.3622 -4.826)
			(stroke
				(width 0.1524)
				(type default)
			)
			(layer "F.SilkS")
		)
		(fp_line
			(start 2.3622 3.4798)
			(end -2.3876 3.4798)
			(stroke
				(width 0.1524)
				(type default)
			)
			(layer "F.SilkS")
		)
		(fp_line
			(start -2.3876 3.4798)
			(end -2.3876 -4.826)
			(stroke
				(width 0.1524)
				(type default)
			)
			(layer "F.SilkS")
		)
		(fp_rect
			(start -2.6416 3.7338)
			(end 2.6162 -5.08)
			(stroke
				(width 0)
				(type default)
			)
			(fill no)
			(layer "F.CrtYd")
		)
		(fp_rect
			(start -2.6416 3.7338)
			(end 2.6162 -5.08)
			(stroke
				(width 0)
				(type default)
			)
			(fill no)
			(layer "F.Fab")
		)
		(pad "1" smd circle
			(at 0.496824 -1.301496 90)
			(size 0.6604 0.6604)
			(layers "F.Cu" "F.Mask" "F.Paste")
			(net "L10_85OHM_5INCH_DN")
		)
		(pad "2" smd circle
			(at -0.503936 -1.301496 90)
			(size 0.6604 0.6604)
			(layers "F.Cu" "F.Mask" "F.Paste")
			(net "L10_85OHM_5INCH_DP")
		)
		(pad "3" smd custom
			(at -0.00889 0.370078 90)
			(size 0.74295 0.74295)
			(layers "F.Cu" "F.Mask" "F.Paste")
			(net "GND")
			(options
				(clearance outline)
				(anchor circle)
			)
			(primitives
				(gr_poly
					(pts
						(xy -2.1209 1.4859) (xy 2.1209 1.4859) (xy 2.1209 -1.4859) (xy 1.08585 -1.4859) (xy 1.08585 -0.4699)
						(xy -1.08585 -0.4699) (xy -1.08585 -1.4859) (xy -2.1209 -1.4859)
					)
					(width 0)
					(fill yes)
				)
			)
		)
		(pad "4" thru_hole circle
			(at 1.266444 -3.851656 90)
			(size 1.4478 1.4478)
			(drill 1.0414)
			(layers "*.Cu" "*.Mask")
			(remove_unused_layers no)
			(net "GND")
			(clearance 0.1524)
			(thermal_gap 0.1524)
		)
		(pad "5" thru_hole circle
			(at -1.273556 -3.851656 90)
			(size 1.4478 1.4478)
			(drill 1.0414)
			(layers "*.Cu" "*.Mask")
			(remove_unused_layers no)
			(net "GND")
			(clearance 0.1524)
			(thermal_gap 0.1524)
		)
		(pad "6" thru_hole circle
			(at 1.266444 2.498344 90)
			(size 1.4478 1.4478)
			(drill 1.0414)
			(layers "*.Cu" "*.Mask")
			(remove_unused_layers no)
			(net "GND")
			(clearance 0.1524)
			(thermal_gap 0.1524)
		)
		(pad "7" thru_hole circle
			(at -1.273556 2.498344 90)
			(size 1.4478 1.4478)
			(drill 1.0414)
			(layers "*.Cu" "*.Mask")
			(remove_unused_layers no)
			(net "GND")
			(clearance 0.1524)
			(thermal_gap 0.1524)
		)
		(pad "8" thru_hole circle
			(at 1.27 -0.4572 90)
			(size 0.7112 0.7112)
			(drill 0.4064)
			(layers "*.Cu" "*.Mask")
			(remove_unused_layers no)
			(net "GND")
			(clearance 0.1016)
			(thermal_gap 0.1016)
		)
		(pad "9" thru_hole circle
			(at 1.27 0.762 90)
			(size 0.7112 0.7112)
			(drill 0.4064)
			(layers "*.Cu" "*.Mask")
			(remove_unused_layers no)
			(net "GND")
			(clearance 0.1016)
			(thermal_gap 0.1016)
		)
		(pad "10" thru_hole circle
			(at -0.0254 0.762 90)
			(size 0.7112 0.7112)
			(drill 0.4064)
			(layers "*.Cu" "*.Mask")
			(remove_unused_layers no)
			(net "GND")
			(clearance 0.1016)
			(thermal_gap 0.1016)
		)
		(pad "11" thru_hole circle
			(at -1.27 0.762 90)
			(size 0.7112 0.7112)
			(drill 0.4064)
			(layers "*.Cu" "*.Mask")
			(remove_unused_layers no)
			(net "GND")
			(clearance 0.1016)
			(thermal_gap 0.1016)
		)
		(pad "12" thru_hole circle
			(at -1.27 -0.4572 90)
			(size 0.7112 0.7112)
			(drill 0.4064)
			(layers "*.Cu" "*.Mask")
			(remove_unused_layers no)
			(net "GND")
			(clearance 0.1016)
			(thermal_gap 0.1016)
		)
	)
	(footprint ""
		(layer "F.Cu")
		(at 17.399 -84.455 -90)
		(property "Reference" "Q1D1"
			(at 2.94767 1.905 0)
			(unlocked yes)
			(layer "F.SilkS")
			(effects
				(font
					(size 0.7874 0.5842)
					(thickness 0.1524)
				)
				(justify left)
			)
		)
		(property "Value" ""
			(at 0 0 270)
			(layer "F.Fab")
			(effects
				(font
					(size 1.27 1.27)
				)
			)
		)
		(duplicate_pad_numbers_are_jumpers no)
		(fp_circle
			(center -0.848614 -0.6477)
			(end -0.848614 -0.7747)
			(stroke
				(width 0.254)
				(type default)
			)
			(fill no)
			(layer "F.SilkS")
		)
		(fp_poly
			(pts
				(xy 0.21463 -0.450088) (xy 1.56337 -0.450088) (xy 1.56337 1.75006) (xy 0.21463 1.75006)
			)
			(stroke
				(width 0)
				(type default)
			)
			(fill no)
			(layer "F.CrtYd")
		)
		(fp_line
			(start 0.21463 1.75006)
			(end 0.21463 -0.450088)
			(stroke
				(width 0.1)
				(type default)
			)
			(layer "F.Fab")
		)
		(fp_line
			(start 1.56337 1.75006)
			(end 0.21463 1.75006)
			(stroke
				(width 0.1)
				(type default)
			)
			(layer "F.Fab")
		)
		(fp_line
			(start 0.21463 -0.450088)
			(end 1.56337 -0.450088)
			(stroke
				(width 0.1)
				(type default)
			)
			(layer "F.Fab")
		)
		(fp_line
			(start 1.56337 -0.450088)
			(end 1.56337 1.75006)
			(stroke
				(width 0.1)
				(type default)
			)
			(layer "F.Fab")
		)
		(fp_circle
			(center -0.848614 -0.6477)
			(end -0.848614 -0.7747)
			(stroke
				(width 0.254)
				(type default)
			)
			(fill no)
			(layer "F.Fab")
		)
		(pad "1" smd rect
			(at 0 0 270)
			(size 1.016 0.381)
			(layers "F.Cu" "F.Mask" "F.Paste")
			(net "AGND_HSC")
		)
		(pad "2" smd rect
			(at 0 0.649986 270)
			(size 1.016 0.381)
			(layers "F.Cu" "F.Mask" "F.Paste")
			(net "A_HSC_LOW_EN")
		)
		(pad "3" smd rect
			(at 0 1.299972 270)
			(size 1.016 0.381)
			(layers "F.Cu" "F.Mask" "F.Paste")
			(net "A_HSC_ISET_S")
		)
		(pad "4" smd rect
			(at 1.778 1.299972 270)
			(size 1.016 0.381)
			(layers "F.Cu" "F.Mask" "F.Paste")
			(net "AGND_HSC")
		)
		(pad "5" smd rect
			(at 1.778 0.649986 270)
			(size 1.016 0.381)
			(layers "F.Cu" "F.Mask" "F.Paste")
			(net "A_HSC_HIGH_EN")
		)
		(pad "6" smd rect
			(at 1.778 0 270)
			(size 1.016 0.381)
			(layers "F.Cu" "F.Mask" "F.Paste")
			(net "A_HSC_ISET_S2")
		)
	)
	(footprint ""
		(layer "F.Cu")
		(at 393.674346 -64.172338 -90)
		(property "Reference" "C8F1"
			(at 0 0 270)
			(layer "F.SilkS")
			(hide yes)
			(effects
				(font
					(size 1.27 1.27)
				)
			)
		)
		(property "Value" ""
			(at 0 0 270)
			(layer "F.Fab")
			(effects
				(font
					(size 1.27 1.27)
				)
			)
		)
		(duplicate_pad_numbers_are_jumpers no)
		(fp_poly
			(pts
				(xy 0.3048 -0.1016) (xy 0.3048 0.9906) (xy -0.3048 0.9906) (xy -0.3048 -0.1016)
			)
			(stroke
				(width 0)
				(type default)
			)
			(fill no)
			(layer "F.CrtYd")
		)
		(fp_line
			(start -0.3048 0.9906)
			(end 0.3048 0.9906)
			(stroke
				(width 0.1)
				(type default)
			)
			(layer "F.Fab")
		)
		(fp_line
			(start 0.3048 0.9906)
			(end 0.3048 -0.1016)
			(stroke
				(width 0.1)
				(type default)
			)
			(layer "F.Fab")
		)
		(fp_line
			(start -0.3048 -0.1016)
			(end -0.3048 0.9906)
			(stroke
				(width 0.1)
				(type default)
			)
			(layer "F.Fab")
		)
		(fp_line
			(start 0.3048 -0.1016)
			(end -0.3048 -0.1016)
			(stroke
				(width 0.1)
				(type default)
			)
			(layer "F.Fab")
		)
		(pad "1" smd rect
			(at 0 0 270)
			(size 0.508 0.508)
			(layers "F.Cu" "F.Mask" "F.Paste")
			(net "VR_P5V_STBY_RC_COMP")
		)
		(pad "2" smd rect
			(at 0 0.889 270)
			(size 0.508 0.508)
			(layers "F.Cu" "F.Mask" "F.Paste")
			(net "AGND_P5V_STBY")
		)
		(zone
			(layer "F.Cu")
			(hatch none 0.5)
			(connect_pads
				(clearance 0)
			)
			(min_thickness 0.25)
			(keepout
				(tracks not_allowed)
				(vias allowed)
				(pads allowed)
				(copperpour not_allowed)
				(footprints allowed)
			)
			(placement
				(enabled no)
				(sheetname "")
			)
			(fill
				(thermal_gap 0.5)
				(thermal_bridge_width 0.5)
				(island_removal_mode 0)
			)
			(polygon
				(pts
					(xy 393.039346 -64.426338) (xy 393.039346 -63.918338) (xy 393.420346 -63.918338) (xy 393.420346 -64.426338)
				)
			)
		)
		(zone
			(layer "F.Cu")
			(hatch none 0.5)
			(connect_pads
				(clearance 0)
			)
			(min_thickness 0.25)
			(keepout
				(tracks allowed)
				(vias not_allowed)
				(pads allowed)
				(copperpour not_allowed)
				(footprints allowed)
			)
			(placement
				(enabled no)
				(sheetname "")
			)
			(fill
				(thermal_gap 0.5)
				(thermal_bridge_width 0.5)
				(island_removal_mode 0)
			)
			(polygon
				(pts
					(xy 393.420346 -64.426338) (xy 393.420346 -63.918338) (xy 393.039346 -63.918338) (xy 393.039346 -64.426338)
				)
			)
		)
	)
	(footprint ""
		(layer "F.Cu")
		(at 266.397232 -149.8092 90)
		(property "Reference" "C5A6"
			(at 1.848866 0.752348 90)
			(unlocked yes)
			(layer "F.SilkS")
			(effects
				(font
					(size 1.27 0.9652)
					(thickness 0.1524)
				)
			)
		)
		(property "Value" ""
			(at 0 0 90)
			(layer "F.Fab")
			(effects
				(font
					(size 1.27 1.27)
				)
			)
		)
		(duplicate_pad_numbers_are_jumpers no)
		(fp_rect
			(start -0.500126 1.598422)
			(end 0.500126 -0.201422)
			(stroke
				(width 0)
				(type default)
			)
			(fill no)
			(layer "F.CrtYd")
		)
		(fp_line
			(start 0.500126 -0.201422)
			(end 0.500126 1.598422)
			(stroke
				(width 0.1)
				(type default)
			)
			(layer "F.Fab")
		)
		(fp_line
			(start -0.500126 -0.201422)
			(end 0.500126 -0.201422)
			(stroke
				(width 0.1)
				(type default)
			)
			(layer "F.Fab")
		)
		(fp_line
			(start 0.500126 1.598422)
			(end -0.500126 1.598422)
			(stroke
				(width 0.1)
				(type default)
			)
			(layer "F.Fab")
		)
		(fp_line
			(start -0.500126 1.598422)
			(end -0.500126 -0.201422)
			(stroke
				(width 0.1)
				(type default)
			)
			(layer "F.Fab")
		)
		(pad "1" smd rect
			(at 0 0)
			(size 0.889 0.9906)
			(layers "F.Cu" "F.Mask" "F.Paste")
			(net "PVDDQ_DEF")
		)
		(pad "2" smd rect
			(at 0 1.397)
			(size 0.889 0.9906)
			(layers "F.Cu" "F.Mask" "F.Paste")
			(net "GND")
		)
		(zone
			(layer "F.Cu")
			(hatch none 0.5)
			(connect_pads
				(clearance 0)
			)
			(min_thickness 0.25)
			(keepout
				(tracks not_allowed)
				(vias allowed)
				(pads allowed)
				(copperpour not_allowed)
				(footprints allowed)
			)
			(placement
				(enabled no)
				(sheetname "")
			)
			(fill
				(thermal_gap 0.5)
				(thermal_bridge_width 0.5)
				(island_removal_mode 0)
			)
			(polygon
				(pts
					(xy 267.349732 -149.3139) (xy 267.349732 -150.3045) (xy 266.841732 -150.3045) (xy 266.841732 -149.3139)
				)
			)
		)
		(zone
			(layer "F.Cu")
			(hatch none 0.5)
			(connect_pads
				(clearance 0)
			)
			(min_thickness 0.25)
			(keepout
				(tracks allowed)
				(vias not_allowed)
				(pads allowed)
				(copperpour not_allowed)
				(footprints allowed)
			)
			(placement
				(enabled no)
				(sheetname "")
			)
			(fill
				(thermal_gap 0.5)
				(thermal_bridge_width 0.5)
				(island_removal_mode 0)
			)
			(polygon
				(pts
					(xy 267.349732 -149.3139) (xy 267.349732 -150.3045) (xy 266.841732 -150.3045) (xy 266.841732 -149.3139)
				)
			)
		)
	)
	(footprint ""
		(layer "F.Cu")
		(at 349.123 -14.859 90)
		(property "Reference" "R7G8"
			(at 0 0 90)
			(layer "F.SilkS")
			(hide yes)
			(effects
				(font
					(size 1.27 1.27)
				)
			)
		)
		(property "Value" ""
			(at 0 0 90)
			(layer "F.Fab")
			(effects
				(font
					(size 1.27 1.27)
				)
			)
		)
		(duplicate_pad_numbers_are_jumpers no)
		(fp_poly
			(pts
				(xy -0.2794 -0.1016) (xy 0.2794 -0.1016) (xy 0.2794 0.9906) (xy -0.2794 0.9906)
			)
			(stroke
				(width 0)
				(type default)
			)
			(fill no)
			(layer "F.CrtYd")
		)
		(fp_line
			(start 0.2794 -0.1016)
			(end -0.2794 -0.1016)
			(stroke
				(width 0.1)
				(type default)
			)
			(layer "F.Fab")
		)
		(fp_line
			(start -0.2794 -0.1016)
			(end -0.2794 0.9906)
			(stroke
				(width 0.1)
				(type default)
			)
			(layer "F.Fab")
		)
		(fp_line
			(start 0.2794 0.9906)
			(end 0.2794 -0.1016)
			(stroke
				(width 0.1)
				(type default)
			)
			(layer "F.Fab")
		)
		(fp_line
			(start -0.2794 0.9906)
			(end 0.2794 0.9906)
			(stroke
				(width 0.1)
				(type default)
			)
			(layer "F.Fab")
		)
		(pad "1" smd rect
			(at 0 0 90)
			(size 0.508 0.508)
			(layers "F.Cu" "F.Mask" "F.Paste")
			(net "VR_PVDDQ_ABC_XADDR1")
		)
		(pad "2" smd rect
			(at 0 0.889 90)
			(size 0.508 0.508)
			(layers "F.Cu" "F.Mask" "F.Paste")
			(net "GND")
		)
		(zone
			(layer "F.Cu")
			(hatch none 0.5)
			(connect_pads
				(clearance 0)
			)
			(min_thickness 0.25)
			(keepout
				(tracks allowed)
				(vias not_allowed)
				(pads allowed)
				(copperpour not_allowed)
				(footprints allowed)
			)
			(placement
				(enabled no)
				(sheetname "")
			)
			(fill
				(thermal_gap 0.5)
				(thermal_bridge_width 0.5)
				(island_removal_mode 0)
			)
			(polygon
				(pts
					(xy 349.377 -14.605) (xy 349.377 -15.113) (xy 349.758 -15.113) (xy 349.758 -14.605)
				)
			)
		)
		(zone
			(layer "F.Cu")
			(hatch none 0.5)
			(connect_pads
				(clearance 0)
			)
			(min_thickness 0.25)
			(keepout
				(tracks not_allowed)
				(vias allowed)
				(pads allowed)
				(copperpour not_allowed)
				(footprints allowed)
			)
			(placement
				(enabled no)
				(sheetname "")
			)
			(fill
				(thermal_gap 0.5)
				(thermal_bridge_width 0.5)
				(island_removal_mode 0)
			)
			(polygon
				(pts
					(xy 349.758 -14.605) (xy 349.758 -15.113) (xy 349.377 -15.113) (xy 349.377 -14.605)
				)
			)
		)
	)
	(footprint ""
		(layer "F.Cu")
		(at 273.168872 -73.318116)
		(property "Reference" "C5D48"
			(at 0 0 0)
			(layer "F.SilkS")
			(hide yes)
			(effects
				(font
					(size 1.27 1.27)
				)
			)
		)
		(property "Value" ""
			(at 0 0 0)
			(layer "F.Fab")
			(effects
				(font
					(size 1.27 1.27)
				)
			)
		)
		(duplicate_pad_numbers_are_jumpers no)
		(fp_poly
			(pts
				(xy -0.4953 -0.2032) (xy 0.4953 -0.2032) (xy 0.4953 1.6002) (xy -0.4953 1.6002)
			)
			(stroke
				(width 0)
				(type default)
			)
			(fill no)
			(layer "F.CrtYd")
		)
		(fp_line
			(start -0.4953 -0.2032)
			(end 0.4953 -0.2032)
			(stroke
				(width 0.1)
				(type default)
			)
			(layer "F.Fab")
		)
		(fp_line
			(start -0.4953 1.6002)
			(end -0.4953 -0.2032)
			(stroke
				(width 0.1)
				(type default)
			)
			(layer "F.Fab")
		)
		(fp_line
			(start 0.4953 -0.2032)
			(end 0.4953 1.6002)
			(stroke
				(width 0.1)
				(type default)
			)
			(layer "F.Fab")
		)
		(fp_line
			(start 0.4953 1.6002)
			(end -0.4953 1.6002)
			(stroke
				(width 0.1)
				(type default)
			)
			(layer "F.Fab")
		)
		(pad "1" smd rect
			(at 0 0)
			(size 0.762 0.889)
			(layers "F.Cu" "F.Mask" "F.Paste")
			(net "PVCCMCP_CPU0")
		)
		(pad "2" smd rect
			(at 0 1.397)
			(size 0.762 0.889)
			(layers "F.Cu" "F.Mask" "F.Paste")
			(net "GND")
		)
		(zone
			(layer "F.Cu")
			(hatch none 0.5)
			(connect_pads
				(clearance 0)
			)
			(min_thickness 0.25)
			(keepout
				(tracks not_allowed)
				(vias allowed)
				(pads allowed)
				(copperpour not_allowed)
				(footprints allowed)
			)
			(placement
				(enabled no)
				(sheetname "")
			)
			(fill
				(thermal_gap 0.5)
				(thermal_bridge_width 0.5)
				(island_removal_mode 0)
			)
			(polygon
				(pts
					(xy 272.787872 -72.873616) (xy 273.549872 -72.873616) (xy 273.549872 -72.365616) (xy 272.787872 -72.365616)
				)
			)
		)
	)
	(footprint ""
		(layer "F.Cu")
		(at 465.836 -134.366 180)
		(property "Reference" "R9B9"
			(at 0 0 180)
			(layer "F.SilkS")
			(hide yes)
			(effects
				(font
					(size 1.27 1.27)
				)
			)
		)
		(property "Value" ""
			(at 0 0 180)
			(layer "F.Fab")
			(effects
				(font
					(size 1.27 1.27)
				)
			)
		)
		(duplicate_pad_numbers_are_jumpers no)
		(fp_poly
			(pts
				(xy -0.2794 -0.1016) (xy 0.2794 -0.1016) (xy 0.2794 0.9906) (xy -0.2794 0.9906)
			)
			(stroke
				(width 0)
				(type default)
			)
			(fill no)
			(layer "F.CrtYd")
		)
		(fp_line
			(start 0.2794 0.9906)
			(end 0.2794 -0.1016)
			(stroke
				(width 0.1)
				(type default)
			)
			(layer "F.Fab")
		)
		(fp_line
			(start 0.2794 -0.1016)
			(end -0.2794 -0.1016)
			(stroke
				(width 0.1)
				(type default)
			)
			(layer "F.Fab")
		)
		(fp_line
			(start -0.2794 0.9906)
			(end 0.2794 0.9906)
			(stroke
				(width 0.1)
				(type default)
			)
			(layer "F.Fab")
		)
		(fp_line
			(start -0.2794 -0.1016)
			(end -0.2794 0.9906)
			(stroke
				(width 0.1)
				(type default)
			)
			(layer "F.Fab")
		)
		(pad "1" smd rect
			(at 0 0 180)
			(size 0.508 0.508)
			(layers "F.Cu" "F.Mask" "F.Paste")
			(net "JTAG_MCP_TCK")
		)
		(pad "2" smd rect
			(at 0 0.889 180)
			(size 0.508 0.508)
			(layers "F.Cu" "F.Mask" "F.Paste")
			(net "GND")
		)
		(zone
			(layer "F.Cu")
			(hatch none 0.5)
			(connect_pads
				(clearance 0)
			)
			(min_thickness 0.25)
			(keepout
				(tracks not_allowed)
				(vias allowed)
				(pads allowed)
				(copperpour not_allowed)
				(footprints allowed)
			)
			(placement
				(enabled no)
				(sheetname "")
			)
			(fill
				(thermal_gap 0.5)
				(thermal_bridge_width 0.5)
				(island_removal_mode 0)
			)
			(polygon
				(pts
					(xy 466.09 -135.001) (xy 465.582 -135.001) (xy 465.582 -134.62) (xy 466.09 -134.62)
				)
			)
		)
		(zone
			(layer "F.Cu")
			(hatch none 0.5)
			(connect_pads
				(clearance 0)
			)
			(min_thickness 0.25)
			(keepout
				(tracks allowed)
				(vias not_allowed)
				(pads allowed)
				(copperpour not_allowed)
				(footprints allowed)
			)
			(placement
				(enabled no)
				(sheetname "")
			)
			(fill
				(thermal_gap 0.5)
				(thermal_bridge_width 0.5)
				(island_removal_mode 0)
			)
			(polygon
				(pts
					(xy 466.09 -134.62) (xy 465.582 -134.62) (xy 465.582 -135.001) (xy 466.09 -135.001)
				)
			)
		)
	)
	(footprint ""
		(layer "F.Cu")
		(at 188.2775 -74.295 -90)
		(property "Reference" "RF6"
			(at -0.8382 -0.67818 270)
			(unlocked yes)
			(layer "F.SilkS")
			(effects
				(font
					(size 0.4064 0.254)
					(thickness 0.1524)
				)
				(justify left)
			)
		)
		(property "Value" ""
			(at 0 0 270)
			(layer "F.Fab")
			(effects
				(font
					(size 1.27 1.27)
				)
			)
		)
		(duplicate_pad_numbers_are_jumpers no)
		(fp_poly
			(pts
				(xy -0.2794 -0.1016) (xy 0.2794 -0.1016) (xy 0.2794 0.9906) (xy -0.2794 0.9906)
			)
			(stroke
				(width 0)
				(type default)
			)
			(fill no)
			(layer "F.CrtYd")
		)
		(fp_line
			(start -0.2794 0.9906)
			(end 0.2794 0.9906)
			(stroke
				(width 0.1)
				(type default)
			)
			(layer "F.Fab")
		)
		(fp_line
			(start 0.2794 0.9906)
			(end 0.2794 -0.1016)
			(stroke
				(width 0.1)
				(type default)
			)
			(layer "F.Fab")
		)
		(fp_line
			(start -0.2794 -0.1016)
			(end -0.2794 0.9906)
			(stroke
				(width 0.1)
				(type default)
			)
			(layer "F.Fab")
		)
		(fp_line
			(start 0.2794 -0.1016)
			(end -0.2794 -0.1016)
			(stroke
				(width 0.1)
				(type default)
			)
			(layer "F.Fab")
		)
		(pad "1" smd rect
			(at 0 0 270)
			(size 0.508 0.508)
			(layers "F.Cu" "F.Mask" "F.Paste")
			(net "VR_PVSA_CPU0_BIREF1")
		)
		(pad "2" smd rect
			(at 0 0.889 270)
			(size 0.508 0.508)
			(layers "F.Cu" "F.Mask" "F.Paste")
			(net "ISENSE_PVSA_CPU0_IMON")
		)
		(zone
			(layer "F.Cu")
			(hatch none 0.5)
			(connect_pads
				(clearance 0)
			)
			(min_thickness 0.25)
			(keepout
				(tracks not_allowed)
				(vias allowed)
				(pads allowed)
				(copperpour not_allowed)
				(footprints allowed)
			)
			(placement
				(enabled no)
				(sheetname "")
			)
			(fill
				(thermal_gap 0.5)
				(thermal_bridge_width 0.5)
				(island_removal_mode 0)
			)
			(polygon
				(pts
					(xy 187.6425 -74.549) (xy 187.6425 -74.041) (xy 188.0235 -74.041) (xy 188.0235 -74.549)
				)
			)
		)
		(zone
			(layer "F.Cu")
			(hatch none 0.5)
			(connect_pads
				(clearance 0)
			)
			(min_thickness 0.25)
			(keepout
				(tracks allowed)
				(vias not_allowed)
				(pads allowed)
				(copperpour not_allowed)
				(footprints allowed)
			)
			(placement
				(enabled no)
				(sheetname "")
			)
			(fill
				(thermal_gap 0.5)
				(thermal_bridge_width 0.5)
				(island_removal_mode 0)
			)
			(polygon
				(pts
					(xy 188.0235 -74.549) (xy 188.0235 -74.041) (xy 187.6425 -74.041) (xy 187.6425 -74.549)
				)
			)
		)
	)
	(footprint ""
		(layer "F.Cu")
		(at 38.40734 -93.8276 -90)
		(property "Reference" "CT56"
			(at -0.8382 -0.67818 270)
			(unlocked yes)
			(layer "F.SilkS")
			(effects
				(font
					(size 0.4064 0.254)
					(thickness 0.1524)
				)
				(justify left)
			)
		)
		(property "Value" ""
			(at 0 0 270)
			(layer "F.Fab")
			(effects
				(font
					(size 1.27 1.27)
				)
			)
		)
		(duplicate_pad_numbers_are_jumpers no)
		(fp_poly
			(pts
				(xy 0.3048 -0.1016) (xy 0.3048 0.9906) (xy -0.3048 0.9906) (xy -0.3048 -0.1016)
			)
			(stroke
				(width 0)
				(type default)
			)
			(fill no)
			(layer "F.CrtYd")
		)
		(fp_line
			(start -0.3048 0.9906)
			(end 0.3048 0.9906)
			(stroke
				(width 0.1)
				(type default)
			)
			(layer "F.Fab")
		)
		(fp_line
			(start 0.3048 0.9906)
			(end 0.3048 -0.1016)
			(stroke
				(width 0.1)
				(type default)
			)
			(layer "F.Fab")
		)
		(fp_line
			(start -0.3048 -0.1016)
			(end -0.3048 0.9906)
			(stroke
				(width 0.1)
				(type default)
			)
			(layer "F.Fab")
		)
		(fp_line
			(start 0.3048 -0.1016)
			(end -0.3048 -0.1016)
			(stroke
				(width 0.1)
				(type default)
			)
			(layer "F.Fab")
		)
		(pad "1" smd rect
			(at 0 0 270)
			(size 0.508 0.508)
			(layers "F.Cu" "F.Mask" "F.Paste")
			(net "VR_PVSA_CPU1_PHASE_SW")
		)
		(pad "2" smd rect
			(at 0 0.889 270)
			(size 0.508 0.508)
			(layers "F.Cu" "F.Mask" "F.Paste")
			(net "VR_PVSA_CPU1_PHASE_SW_RC")
		)
		(zone
			(layer "F.Cu")
			(hatch none 0.5)
			(connect_pads
				(clearance 0)
			)
			(min_thickness 0.25)
			(keepout
				(tracks not_allowed)
				(vias allowed)
				(pads allowed)
				(copperpour not_allowed)
				(footprints allowed)
			)
			(placement
				(enabled no)
				(sheetname "")
			)
			(fill
				(thermal_gap 0.5)
				(thermal_bridge_width 0.5)
				(island_removal_mode 0)
			)
			(polygon
				(pts
					(xy 37.77234 -94.0816) (xy 37.77234 -93.5736) (xy 38.15334 -93.5736) (xy 38.15334 -94.0816)
				)
			)
		)
		(zone
			(layer "F.Cu")
			(hatch none 0.5)
			(connect_pads
				(clearance 0)
			)
			(min_thickness 0.25)
			(keepout
				(tracks allowed)
				(vias not_allowed)
				(pads allowed)
				(copperpour not_allowed)
				(footprints allowed)
			)
			(placement
				(enabled no)
				(sheetname "")
			)
			(fill
				(thermal_gap 0.5)
				(thermal_bridge_width 0.5)
				(island_removal_mode 0)
			)
			(polygon
				(pts
					(xy 38.15334 -94.0816) (xy 38.15334 -93.5736) (xy 37.77234 -93.5736) (xy 37.77234 -94.0816)
				)
			)
		)
	)
	(footprint ""
		(layer "F.Cu")
		(at -3.405124 -16.925798)
		(property "Reference" "L1F1"
			(at 0 0 0)
			(layer "F.SilkS")
			(hide yes)
			(effects
				(font
					(size 1.27 1.27)
				)
			)
		)
		(property "Value" "*"
			(at -3.5941 0.3429 0)
			(unlocked yes)
			(layer "F.Fab")
			(hide yes)
			(effects
				(font
					(size 1.27 1.016)
					(thickness 0.1524)
				)
			)
		)
		(property "Device Type" "IND-100NH-35-GP_DISCRET-G8-INDA"
			(at -3.5941 -1.1811 0)
			(unlocked yes)
			(layer "F.Fab")
			(hide yes)
			(effects
				(font
					(size 1.27 1.016)
					(thickness 0.1524)
				)
			)
		)
		(duplicate_pad_numbers_are_jumpers no)
		(fp_line
			(start -2.2479 -2.794)
			(end 2.2479 -2.794)
			(stroke
				(width 0.1524)
				(type default)
			)
			(layer "F.SilkS")
		)
		(fp_line
			(start -2.2479 2.794)
			(end -2.2479 -2.794)
			(stroke
				(width 0.1524)
				(type default)
			)
			(layer "F.SilkS")
		)
		(fp_line
			(start 2.2479 -2.794)
			(end 2.2479 2.794)
			(stroke
				(width 0.1524)
				(type default)
			)
			(layer "F.SilkS")
		)
		(fp_line
			(start 2.2479 2.794)
			(end -2.2479 2.794)
			(stroke
				(width 0.1524)
				(type default)
			)
			(layer "F.SilkS")
		)
		(fp_rect
			(start -1.9939 1.9939)
			(end 1.9939 -1.9939)
			(stroke
				(width 0)
				(type default)
			)
			(fill no)
			(layer "F.CrtYd")
		)
		(fp_poly
			(pts
				(xy -2.5019 2.8702) (xy -2.5019 1.9939) (xy 1.9939 1.9939) (xy 1.9939 -1.9939) (xy -1.9939 -1.9939)
				(xy -1.9939 1.9812) (xy -2.5019 1.9812) (xy -2.5019 -2.8702) (xy 2.5019 -2.8702) (xy 2.5019 2.8702)
			)
			(stroke
				(width 0)
				(type default)
			)
			(fill no)
			(layer "F.CrtYd")
		)
		(fp_rect
			(start -2.5019 2.8702)
			(end 2.5019 -2.8702)
			(stroke
				(width 0)
				(type default)
			)
			(fill no)
			(layer "F.Fab")
		)
		(pad "1" smd rect
			(at 0 -1.745996)
			(size 1.5494 1.6002)
			(layers "F.Cu" "F.Mask" "F.Paste")
			(net "P12V_STBY")
		)
		(pad "2" smd rect
			(at 0 1.745996)
			(size 1.5494 1.6002)
			(layers "F.Cu" "F.Mask" "F.Paste")
			(net "VR_FET_SW_P12V_STBY_PVDDQ_GHJ")
		)
	)
	(footprint ""
		(layer "F.Cu")
		(at 436.499 -21.1455)
		(property "Reference" "R10W2"
			(at -0.8382 -0.67818 0)
			(unlocked yes)
			(layer "F.SilkS")
			(effects
				(font
					(size 0.4064 0.254)
					(thickness 0.1524)
				)
				(justify left)
			)
		)
		(property "Value" ""
			(at 0 0 0)
			(layer "F.Fab")
			(effects
				(font
					(size 1.27 1.27)
				)
			)
		)
		(duplicate_pad_numbers_are_jumpers no)
		(fp_poly
			(pts
				(xy -0.2794 -0.1016) (xy 0.2794 -0.1016) (xy 0.2794 0.9906) (xy -0.2794 0.9906)
			)
			(stroke
				(width 0)
				(type default)
			)
			(fill no)
			(layer "F.CrtYd")
		)
		(fp_line
			(start -0.2794 -0.1016)
			(end -0.2794 0.9906)
			(stroke
				(width 0.1)
				(type default)
			)
			(layer "F.Fab")
		)
		(fp_line
			(start -0.2794 0.9906)
			(end 0.2794 0.9906)
			(stroke
				(width 0.1)
				(type default)
			)
			(layer "F.Fab")
		)
		(fp_line
			(start 0.2794 -0.1016)
			(end -0.2794 -0.1016)
			(stroke
				(width 0.1)
				(type default)
			)
			(layer "F.Fab")
		)
		(fp_line
			(start 0.2794 0.9906)
			(end 0.2794 -0.1016)
			(stroke
				(width 0.1)
				(type default)
			)
			(layer "F.Fab")
		)
		(pad "1" smd rect
			(at 0 0)
			(size 0.508 0.508)
			(layers "F.Cu" "F.Mask" "F.Paste")
			(net "P3V3_STBY")
		)
		(pad "2" smd rect
			(at 0 0.889)
			(size 0.508 0.508)
			(layers "F.Cu" "F.Mask" "F.Paste")
			(net "PUMP_TACH0")
		)
		(zone
			(layer "F.Cu")
			(hatch none 0.5)
			(connect_pads
				(clearance 0)
			)
			(min_thickness 0.25)
			(keepout
				(tracks allowed)
				(vias not_allowed)
				(pads allowed)
				(copperpour not_allowed)
				(footprints allowed)
			)
			(placement
				(enabled no)
				(sheetname "")
			)
			(fill
				(thermal_gap 0.5)
				(thermal_bridge_width 0.5)
				(island_removal_mode 0)
			)
			(polygon
				(pts
					(xy 436.245 -20.8915) (xy 436.753 -20.8915) (xy 436.753 -20.5105) (xy 436.245 -20.5105)
				)
			)
		)
		(zone
			(layer "F.Cu")
			(hatch none 0.5)
			(connect_pads
				(clearance 0)
			)
			(min_thickness 0.25)
			(keepout
				(tracks not_allowed)
				(vias allowed)
				(pads allowed)
				(copperpour not_allowed)
				(footprints allowed)
			)
			(placement
				(enabled no)
				(sheetname "")
			)
			(fill
				(thermal_gap 0.5)
				(thermal_bridge_width 0.5)
				(island_removal_mode 0)
			)
			(polygon
				(pts
					(xy 436.245 -20.5105) (xy 436.753 -20.5105) (xy 436.753 -20.8915) (xy 436.245 -20.8915)
				)
			)
		)
	)
	(footprint ""
		(layer "F.Cu")
		(at 1.148588 -14.695932)
		(property "Reference" "CT31"
			(at -0.81153 0.6096 90)
			(unlocked yes)
			(layer "F.SilkS")
			(effects
				(font
					(size 0.7874 0.5842)
					(thickness 0.1524)
				)
				(justify left)
			)
		)
		(property "Value" ""
			(at 0 0 0)
			(layer "F.Fab")
			(effects
				(font
					(size 1.27 1.27)
				)
			)
		)
		(duplicate_pad_numbers_are_jumpers no)
		(fp_rect
			(start -0.3048 0.9906)
			(end 0.3048 -0.1016)
			(stroke
				(width 0)
				(type default)
			)
			(fill no)
			(layer "F.CrtYd")
		)
		(fp_line
			(start -0.3048 -0.1016)
			(end -0.3048 0.9906)
			(stroke
				(width 0.1)
				(type default)
			)
			(layer "F.Fab")
		)
		(fp_line
			(start -0.3048 0.9906)
			(end 0.3048 0.9906)
			(stroke
				(width 0.1)
				(type default)
			)
			(layer "F.Fab")
		)
		(fp_line
			(start 0.3048 -0.1016)
			(end -0.3048 -0.1016)
			(stroke
				(width 0.1)
				(type default)
			)
			(layer "F.Fab")
		)
		(fp_line
			(start 0.3048 0.9906)
			(end 0.3048 -0.1016)
			(stroke
				(width 0.1)
				(type default)
			)
			(layer "F.Fab")
		)
		(pad "1" smd rect
			(at 0 0)
			(size 0.508 0.508)
			(layers "F.Cu" "F.Mask" "F.Paste")
			(net "VR_PVDDQ_GHJ_AIREF2")
		)
		(pad "2" smd rect
			(at 0 0.889)
			(size 0.508 0.508)
			(layers "F.Cu" "F.Mask" "F.Paste")
			(net "GND")
		)
		(zone
			(layer "F.Cu")
			(hatch none 0.5)
			(connect_pads
				(clearance 0)
			)
			(min_thickness 0.25)
			(keepout
				(tracks allowed)
				(vias not_allowed)
				(pads allowed)
				(copperpour not_allowed)
				(footprints allowed)
			)
			(placement
				(enabled no)
				(sheetname "")
			)
			(fill
				(thermal_gap 0.5)
				(thermal_bridge_width 0.5)
				(island_removal_mode 0)
			)
			(polygon
				(pts
					(xy 0.894588 -14.060932) (xy 1.402588 -14.060932) (xy 1.402588 -14.441932) (xy 0.894588 -14.441932)
				)
			)
		)
		(zone
			(layer "F.Cu")
			(hatch none 0.5)
			(connect_pads
				(clearance 0)
			)
			(min_thickness 0.25)
			(keepout
				(tracks not_allowed)
				(vias allowed)
				(pads allowed)
				(copperpour not_allowed)
				(footprints allowed)
			)
			(placement
				(enabled no)
				(sheetname "")
			)
			(fill
				(thermal_gap 0.5)
				(thermal_bridge_width 0.5)
				(island_removal_mode 0)
			)
			(polygon
				(pts
					(xy 0.894588 -14.060932) (xy 1.402588 -14.060932) (xy 1.402588 -14.441932) (xy 0.894588 -14.441932)
				)
			)
		)
	)
	(footprint ""
		(layer "F.Cu")
		(at 410.048964 -23.070566)
		(property "Reference" "R25W143"
			(at -0.8382 -0.67818 0)
			(unlocked yes)
			(layer "F.SilkS")
			(effects
				(font
					(size 0.4064 0.254)
					(thickness 0.1524)
				)
				(justify left)
			)
		)
		(property "Value" ""
			(at 0 0 0)
			(layer "F.Fab")
			(effects
				(font
					(size 1.27 1.27)
				)
			)
		)
		(duplicate_pad_numbers_are_jumpers no)
		(fp_poly
			(pts
				(xy -0.2794 -0.1016) (xy 0.2794 -0.1016) (xy 0.2794 0.9906) (xy -0.2794 0.9906)
			)
			(stroke
				(width 0)
				(type default)
			)
			(fill no)
			(layer "F.CrtYd")
		)
		(fp_line
			(start -0.2794 -0.1016)
			(end -0.2794 0.9906)
			(stroke
				(width 0.1)
				(type default)
			)
			(layer "F.Fab")
		)
		(fp_line
			(start -0.2794 0.9906)
			(end 0.2794 0.9906)
			(stroke
				(width 0.1)
				(type default)
			)
			(layer "F.Fab")
		)
		(fp_line
			(start 0.2794 -0.1016)
			(end -0.2794 -0.1016)
			(stroke
				(width 0.1)
				(type default)
			)
			(layer "F.Fab")
		)
		(fp_line
			(start 0.2794 0.9906)
			(end 0.2794 -0.1016)
			(stroke
				(width 0.1)
				(type default)
			)
			(layer "F.Fab")
		)
		(pad "1" smd rect
			(at 0 0)
			(size 0.508 0.508)
			(layers "F.Cu" "F.Mask" "F.Paste")
			(net "FM_GLOBAL_RST_WARN_N_R")
		)
		(pad "2" smd rect
			(at 0 0.889)
			(size 0.508 0.508)
			(layers "F.Cu" "F.Mask" "F.Paste")
			(net "FM_GLOBAL_RST_WARN_N")
		)
		(zone
			(layer "F.Cu")
			(hatch none 0.5)
			(connect_pads
				(clearance 0)
			)
			(min_thickness 0.25)
			(keepout
				(tracks allowed)
				(vias not_allowed)
				(pads allowed)
				(copperpour not_allowed)
				(footprints allowed)
			)
			(placement
				(enabled no)
				(sheetname "")
			)
			(fill
				(thermal_gap 0.5)
				(thermal_bridge_width 0.5)
				(island_removal_mode 0)
			)
			(polygon
				(pts
					(xy 409.794964 -22.816566) (xy 410.302964 -22.816566) (xy 410.302964 -22.435566) (xy 409.794964 -22.435566)
				)
			)
		)
		(zone
			(layer "F.Cu")
			(hatch none 0.5)
			(connect_pads
				(clearance 0)
			)
			(min_thickness 0.25)
			(keepout
				(tracks not_allowed)
				(vias allowed)
				(pads allowed)
				(copperpour not_allowed)
				(footprints allowed)
			)
			(placement
				(enabled no)
				(sheetname "")
			)
			(fill
				(thermal_gap 0.5)
				(thermal_bridge_width 0.5)
				(island_removal_mode 0)
			)
			(polygon
				(pts
					(xy 409.794964 -22.435566) (xy 410.302964 -22.435566) (xy 410.302964 -22.816566) (xy 409.794964 -22.816566)
				)
			)
		)
	)
	(footprint ""
		(layer "F.Cu")
		(at 19.177 10.7315 -90)
		(property "Reference" "T1P27"
			(at 0 0 270)
			(layer "F.SilkS")
			(hide yes)
			(effects
				(font
					(size 1.27 1.27)
				)
			)
		)
		(property "Value" "*"
			(at 0 -3.44805 270)
			(unlocked yes)
			(layer "F.Fab")
			(hide yes)
			(effects
				(font
					(size 0.889 0.889)
					(thickness 0.1524)
				)
			)
		)
		(property "Device Type" "TPAD-SE-2P-GP_DISCRET-GA1-TPADA"
			(at 0 -4.97205 270)
			(unlocked yes)
			(layer "F.Fab")
			(hide yes)
			(effects
				(font
					(size 0.889 0.889)
					(thickness 0.1524)
				)
			)
		)
		(duplicate_pad_numbers_are_jumpers no)
		(fp_line
			(start -1.016 2.286)
			(end -1.016 -2.286)
			(stroke
				(width 0.1524)
				(type default)
			)
			(layer "F.SilkS")
		)
		(fp_line
			(start 1.016 2.286)
			(end -1.016 2.286)
			(stroke
				(width 0.1524)
				(type default)
			)
			(layer "F.SilkS")
		)
		(fp_line
			(start -1.016 -2.286)
			(end 1.016 -2.286)
			(stroke
				(width 0.1524)
				(type default)
			)
			(layer "F.SilkS")
		)
		(fp_line
			(start 1.016 -2.286)
			(end 1.016 2.286)
			(stroke
				(width 0.1524)
				(type default)
			)
			(layer "F.SilkS")
		)
		(fp_rect
			(start -1.27 2.54)
			(end 1.27 -2.54)
			(stroke
				(width 0)
				(type default)
			)
			(fill no)
			(layer "F.CrtYd")
		)
		(fp_rect
			(start -1.27 2.54)
			(end 1.27 -2.54)
			(stroke
				(width 0)
				(type default)
			)
			(fill no)
			(layer "F.Fab")
		)
		(pad "1" thru_hole circle
			(at 0 -1.27 270)
			(size 1.524 1.524)
			(drill 0.9144)
			(layers "*.Cu" "*.Mask")
			(remove_unused_layers no)
			(net "L5_40OHM_6INCH")
			(clearance -0.0508)
			(thermal_gap 0.127)
			(padstack
				(mode front_inner_back)
				(layer "Inner"
					(shape circle)
					(size 1.1684 1.1684)
					(clearance 0.127)
				)
				(layer "B.Cu"
					(shape circle)
					(size 1.524 1.524)
					(clearance -0.0508)
				)
			)
		)
		(pad "GND1" thru_hole rect
			(at 0 1.27 270)
			(size 1.524 1.524)
			(drill 0.9144)
			(layers "*.Cu" "*.Mask")
			(remove_unused_layers no)
			(net "GND")
			(clearance -0.0508)
			(thermal_gap 0.127)
			(padstack
				(mode front_inner_back)
				(layer "Inner"
					(shape circle)
					(size 1.1684 1.1684)
					(clearance 0.127)
				)
				(layer "B.Cu"
					(shape rect)
					(size 1.524 1.524)
					(clearance -0.0508)
				)
			)
		)
	)
	(footprint ""
		(layer "F.Cu")
		(at 169.0497 -132.5372)
		(property "Reference" "R4B2"
			(at 0 0 0)
			(layer "F.SilkS")
			(hide yes)
			(effects
				(font
					(size 1.27 1.27)
				)
			)
		)
		(property "Value" ""
			(at 0 0 0)
			(layer "F.Fab")
			(effects
				(font
					(size 1.27 1.27)
				)
			)
		)
		(duplicate_pad_numbers_are_jumpers no)
		(fp_poly
			(pts
				(xy -0.4953 -0.2032) (xy 0.4953 -0.2032) (xy 0.4953 1.6002) (xy -0.4953 1.6002)
			)
			(stroke
				(width 0)
				(type default)
			)
			(fill no)
			(layer "F.CrtYd")
		)
		(fp_line
			(start -0.4953 -0.2032)
			(end 0.4953 -0.2032)
			(stroke
				(width 0.1)
				(type default)
			)
			(layer "F.Fab")
		)
		(fp_line
			(start -0.4953 1.6002)
			(end -0.4953 -0.2032)
			(stroke
				(width 0.1)
				(type default)
			)
			(layer "F.Fab")
		)
		(fp_line
			(start 0.4953 -0.2032)
			(end 0.4953 1.6002)
			(stroke
				(width 0.1)
				(type default)
			)
			(layer "F.Fab")
		)
		(fp_line
			(start 0.4953 1.6002)
			(end -0.4953 1.6002)
			(stroke
				(width 0.1)
				(type default)
			)
			(layer "F.Fab")
		)
		(pad "1" smd rect
			(at 0 0)
			(size 0.762 0.889)
			(layers "F.Cu" "F.Mask" "F.Paste")
			(net "PVPP_KLM")
		)
		(pad "2" smd rect
			(at 0 1.397)
			(size 0.762 0.889)
			(layers "F.Cu" "F.Mask" "F.Paste")
			(net "GND")
		)
		(zone
			(layer "F.Cu")
			(hatch none 0.5)
			(connect_pads
				(clearance 0)
			)
			(min_thickness 0.25)
			(keepout
				(tracks not_allowed)
				(vias allowed)
				(pads allowed)
				(copperpour not_allowed)
				(footprints allowed)
			)
			(placement
				(enabled no)
				(sheetname "")
			)
			(fill
				(thermal_gap 0.5)
				(thermal_bridge_width 0.5)
				(island_removal_mode 0)
			)
			(polygon
				(pts
					(xy 168.6687 -131.5847) (xy 169.4307 -131.5847) (xy 169.4307 -132.0927) (xy 168.6687 -132.0927)
				)
			)
		)
		(zone
			(layer "F.Cu")
			(hatch none 0.5)
			(connect_pads
				(clearance 0)
			)
			(min_thickness 0.25)
			(keepout
				(tracks allowed)
				(vias not_allowed)
				(pads allowed)
				(copperpour not_allowed)
				(footprints allowed)
			)
			(placement
				(enabled no)
				(sheetname "")
			)
			(fill
				(thermal_gap 0.5)
				(thermal_bridge_width 0.5)
				(island_removal_mode 0)
			)
			(polygon
				(pts
					(xy 169.4307 -131.5847) (xy 169.4307 -132.0927) (xy 168.6687 -132.0927) (xy 168.6687 -131.5847)
				)
			)
		)
	)
	(footprint ""
		(layer "F.Cu")
		(at 436.753 -125.603 180)
		(property "Reference" "Q8B1"
			(at 3.36804 -2.27203 0)
			(unlocked yes)
			(layer "F.SilkS")
			(effects
				(font
					(size 0.7874 0.5842)
					(thickness 0.1524)
				)
				(justify left)
			)
		)
		(property "Value" ""
			(at 0 0 180)
			(layer "F.Fab")
			(effects
				(font
					(size 1.27 1.27)
				)
			)
		)
		(duplicate_pad_numbers_are_jumpers no)
		(fp_line
			(start -0.245364 2.020062)
			(end 3.15468 2.020062)
			(stroke
				(width 0.1524)
				(type default)
			)
			(layer "F.SilkS")
		)
		(fp_line
			(start -0.245364 -1.379982)
			(end 3.15468 -1.379982)
			(stroke
				(width 0.1524)
				(type default)
			)
			(layer "F.SilkS")
		)
		(fp_circle
			(center -0.94996 -1.512316)
			(end -1.07696 -1.512316)
			(stroke
				(width 0.254)
				(type default)
			)
			(fill no)
			(layer "F.SilkS")
		)
		(fp_poly
			(pts
				(xy 0.890016 -0.82296) (xy 0.890016 1.46304) (xy 3.404616 1.46304) (xy 3.404616 1.13284) (xy 2.617216 1.13284)
				(xy 2.617216 0.811022) (xy 3.404616 0.811022) (xy 3.404616 0.480822) (xy 2.617216 0.480822) (xy 2.617216 0.159258)
				(xy 3.404616 0.159258) (xy 3.404616 -0.170942) (xy 2.617216 -0.170942) (xy 2.617216 -0.49276) (xy 3.404616 -0.49276)
				(xy 3.404616 -0.82296)
			)
			(stroke
				(width 0)
				(type default)
			)
			(fill yes)
			(layer "F.Paste")
		)
		(fp_poly
			(pts
				(xy -0.245364 -1.379982) (xy -0.245364 2.020062) (xy 3.15468 2.020062) (xy 3.15468 -1.379982)
			)
			(stroke
				(width 0)
				(type default)
			)
			(fill no)
			(layer "F.CrtYd")
		)
		(fp_line
			(start 3.15468 2.020062)
			(end -0.245364 2.020062)
			(stroke
				(width 0.1)
				(type default)
			)
			(layer "F.Fab")
		)
		(fp_line
			(start 3.15468 -1.379982)
			(end 3.15468 2.020062)
			(stroke
				(width 0.1)
				(type default)
			)
			(layer "F.Fab")
		)
		(fp_line
			(start -0.245364 2.020062)
			(end -0.245364 -1.379982)
			(stroke
				(width 0.1)
				(type default)
			)
			(layer "F.Fab")
		)
		(fp_line
			(start -0.245364 -1.379982)
			(end 3.15468 -1.379982)
			(stroke
				(width 0.1)
				(type default)
			)
			(layer "F.Fab")
		)
		(fp_circle
			(center -0.94996 -1.512316)
			(end -1.07696 -1.512316)
			(stroke
				(width 0.254)
				(type default)
			)
			(fill no)
			(layer "F.Fab")
		)
		(pad "1" smd custom
			(at 0 0 180)
			(size 0.24765 0.24765)
			(layers "F.Cu" "F.Mask" "F.Paste")
			(net "P5V")
			(options
				(clearance outline)
				(anchor circle)
			)
			(primitives
				(gr_poly
					(pts
						(xy 0.4953 0.8255) (xy 0.4953 -0.8255) (xy -0.4953 -0.8255) (xy -0.4953 -0.4953) (xy 0.0127 -0.4953)
						(xy 0.0127 -0.1651) (xy -0.4953 -0.1651) (xy -0.4953 0.1651) (xy 0.0127 0.1651) (xy 0.0127 0.4953)
						(xy -0.4953 0.4953) (xy -0.4953 0.8255)
					)
					(width 0)
					(fill yes)
				)
			)
		)
		(pad "4" smd rect
			(at 0 1.30048 180)
			(size 0.9906 0.3302)
			(layers "F.Cu" "F.Mask" "F.Paste")
			(net "P5V_SWITCH_G")
		)
		(pad "5" smd custom
			(at 2.147316 0.32004 180)
			(size 0.5715 0.5715)
			(layers "F.Cu" "F.Mask" "F.Paste")
			(net "P5V_STBY")
			(options
				(clearance outline)
				(anchor circle)
			)
			(primitives
				(gr_poly
					(pts
						(xy -1.2573 -1.143) (xy -1.2573 1.143) (xy 1.2573 1.143) (xy 1.2573 0.8128) (xy 0.4699 0.8128)
						(xy 0.4699 0.490982) (xy 1.2573 0.490982) (xy 1.2573 0.160782) (xy 0.4699 0.160782) (xy 0.4699 -0.160782)
						(xy 1.2573 -0.160782) (xy 1.2573 -0.490982) (xy 0.4699 -0.490982) (xy 0.4699 -0.8128) (xy 1.2573 -0.8128)
						(xy 1.2573 -1.143)
					)
					(width 0)
					(fill yes)
				)
			)
		)
	)
	(footprint ""
		(layer "F.Cu")
		(at 164.480494 -34.671)
		(property "Reference" "C4F2"
			(at 0 0 0)
			(layer "F.SilkS")
			(hide yes)
			(effects
				(font
					(size 1.27 1.27)
				)
			)
		)
		(property "Value" ""
			(at 0 0 0)
			(layer "F.Fab")
			(effects
				(font
					(size 1.27 1.27)
				)
			)
		)
		(duplicate_pad_numbers_are_jumpers no)
		(fp_rect
			(start -0.500126 1.598422)
			(end 0.500126 -0.201422)
			(stroke
				(width 0)
				(type default)
			)
			(fill no)
			(layer "F.CrtYd")
		)
		(fp_line
			(start -0.500126 -0.201422)
			(end 0.500126 -0.201422)
			(stroke
				(width 0.1)
				(type default)
			)
			(layer "F.Fab")
		)
		(fp_line
			(start -0.500126 1.598422)
			(end -0.500126 -0.201422)
			(stroke
				(width 0.1)
				(type default)
			)
			(layer "F.Fab")
		)
		(fp_line
			(start 0.500126 -0.201422)
			(end 0.500126 1.598422)
			(stroke
				(width 0.1)
				(type default)
			)
			(layer "F.Fab")
		)
		(fp_line
			(start 0.500126 1.598422)
			(end -0.500126 1.598422)
			(stroke
				(width 0.1)
				(type default)
			)
			(layer "F.Fab")
		)
		(pad "1" smd rect
			(at 0 0 270)
			(size 0.889 0.9906)
			(layers "F.Cu" "F.Mask" "F.Paste")
			(net "P1V8_MCP_CPU1")
		)
		(pad "2" smd rect
			(at 0 1.397 270)
			(size 0.889 0.9906)
			(layers "F.Cu" "F.Mask" "F.Paste")
			(net "GND")
		)
		(zone
			(layer "F.Cu")
			(hatch none 0.5)
			(connect_pads
				(clearance 0)
			)
			(min_thickness 0.25)
			(keepout
				(tracks not_allowed)
				(vias allowed)
				(pads allowed)
				(copperpour not_allowed)
				(footprints allowed)
			)
			(placement
				(enabled no)
				(sheetname "")
			)
			(fill
				(thermal_gap 0.5)
				(thermal_bridge_width 0.5)
				(island_removal_mode 0)
			)
			(polygon
				(pts
					(xy 163.985194 -33.7185) (xy 164.975794 -33.7185) (xy 164.975794 -34.2265) (xy 163.985194 -34.2265)
				)
			)
		)
		(zone
			(layer "F.Cu")
			(hatch none 0.5)
			(connect_pads
				(clearance 0)
			)
			(min_thickness 0.25)
			(keepout
				(tracks allowed)
				(vias not_allowed)
				(pads allowed)
				(copperpour not_allowed)
				(footprints allowed)
			)
			(placement
				(enabled no)
				(sheetname "")
			)
			(fill
				(thermal_gap 0.5)
				(thermal_bridge_width 0.5)
				(island_removal_mode 0)
			)
			(polygon
				(pts
					(xy 163.985194 -33.7185) (xy 164.975794 -33.7185) (xy 164.975794 -34.2265) (xy 163.985194 -34.2265)
				)
			)
		)
	)
	(footprint ""
		(layer "F.Cu")
		(at 111.000032 -12.954 90)
		(property "Reference" "C3G2"
			(at 1.848866 0.752348 90)
			(unlocked yes)
			(layer "F.SilkS")
			(effects
				(font
					(size 1.27 0.9652)
					(thickness 0.1524)
				)
			)
		)
		(property "Value" ""
			(at 0 0 90)
			(layer "F.Fab")
			(effects
				(font
					(size 1.27 1.27)
				)
			)
		)
		(duplicate_pad_numbers_are_jumpers no)
		(fp_rect
			(start -0.500126 1.598422)
			(end 0.500126 -0.201422)
			(stroke
				(width 0)
				(type default)
			)
			(fill no)
			(layer "F.CrtYd")
		)
		(fp_line
			(start 0.500126 -0.201422)
			(end 0.500126 1.598422)
			(stroke
				(width 0.1)
				(type default)
			)
			(layer "F.Fab")
		)
		(fp_line
			(start -0.500126 -0.201422)
			(end 0.500126 -0.201422)
			(stroke
				(width 0.1)
				(type default)
			)
			(layer "F.Fab")
		)
		(fp_line
			(start 0.500126 1.598422)
			(end -0.500126 1.598422)
			(stroke
				(width 0.1)
				(type default)
			)
			(layer "F.Fab")
		)
		(fp_line
			(start -0.500126 1.598422)
			(end -0.500126 -0.201422)
			(stroke
				(width 0.1)
				(type default)
			)
			(layer "F.Fab")
		)
		(pad "1" smd rect
			(at 0 0)
			(size 0.889 0.9906)
			(layers "F.Cu" "F.Mask" "F.Paste")
			(net "PVDDQ_GHJ")
		)
		(pad "2" smd rect
			(at 0 1.397)
			(size 0.889 0.9906)
			(layers "F.Cu" "F.Mask" "F.Paste")
			(net "GND")
		)
		(zone
			(layer "F.Cu")
			(hatch none 0.5)
			(connect_pads
				(clearance 0)
			)
			(min_thickness 0.25)
			(keepout
				(tracks not_allowed)
				(vias allowed)
				(pads allowed)
				(copperpour not_allowed)
				(footprints allowed)
			)
			(placement
				(enabled no)
				(sheetname "")
			)
			(fill
				(thermal_gap 0.5)
				(thermal_bridge_width 0.5)
				(island_removal_mode 0)
			)
			(polygon
				(pts
					(xy 111.952532 -12.4587) (xy 111.952532 -13.4493) (xy 111.444532 -13.4493) (xy 111.444532 -12.4587)
				)
			)
		)
		(zone
			(layer "F.Cu")
			(hatch none 0.5)
			(connect_pads
				(clearance 0)
			)
			(min_thickness 0.25)
			(keepout
				(tracks allowed)
				(vias not_allowed)
				(pads allowed)
				(copperpour not_allowed)
				(footprints allowed)
			)
			(placement
				(enabled no)
				(sheetname "")
			)
			(fill
				(thermal_gap 0.5)
				(thermal_bridge_width 0.5)
				(island_removal_mode 0)
			)
			(polygon
				(pts
					(xy 111.952532 -12.4587) (xy 111.952532 -13.4493) (xy 111.444532 -13.4493) (xy 111.444532 -12.4587)
				)
			)
		)
	)
	(footprint ""
		(layer "F.Cu")
		(at 20.447 -70.866)
		(property "Reference" "R1D42"
			(at 0 0 0)
			(layer "F.SilkS")
			(hide yes)
			(effects
				(font
					(size 1.27 1.27)
				)
			)
		)
		(property "Value" ""
			(at 0 0 0)
			(layer "F.Fab")
			(effects
				(font
					(size 1.27 1.27)
				)
			)
		)
		(duplicate_pad_numbers_are_jumpers no)
		(fp_rect
			(start 0.2794 0.9906)
			(end -0.2794 -0.1016)
			(stroke
				(width 0)
				(type default)
			)
			(fill no)
			(layer "F.CrtYd")
		)
		(fp_line
			(start -0.2794 -0.1016)
			(end -0.2794 0.9906)
			(stroke
				(width 0.1)
				(type default)
			)
			(layer "F.Fab")
		)
		(fp_line
			(start -0.2794 0.9906)
			(end 0.2794 0.9906)
			(stroke
				(width 0.1)
				(type default)
			)
			(layer "F.Fab")
		)
		(fp_line
			(start 0.2794 -0.1016)
			(end -0.2794 -0.1016)
			(stroke
				(width 0.1)
				(type default)
			)
			(layer "F.Fab")
		)
		(fp_line
			(start 0.2794 0.9906)
			(end 0.2794 -0.1016)
			(stroke
				(width 0.1)
				(type default)
			)
			(layer "F.Fab")
		)
		(pad "1" smd rect
			(at 0 0)
			(size 0.508 0.508)
			(layers "F.Cu" "F.Mask" "F.Paste")
			(net "A_HSC_UV")
		)
		(pad "2" smd rect
			(at 0 0.889)
			(size 0.508 0.508)
			(layers "F.Cu" "F.Mask" "F.Paste")
			(net "AGND_HSC")
		)
		(zone
			(layer "F.Cu")
			(hatch none 0.5)
			(connect_pads
				(clearance 0)
			)
			(min_thickness 0.25)
			(keepout
				(tracks allowed)
				(vias not_allowed)
				(pads allowed)
				(copperpour not_allowed)
				(footprints allowed)
			)
			(placement
				(enabled no)
				(sheetname "")
			)
			(fill
				(thermal_gap 0.5)
				(thermal_bridge_width 0.5)
				(island_removal_mode 0)
			)
			(polygon
				(pts
					(xy 20.701 -70.231) (xy 20.701 -70.612) (xy 20.193 -70.612) (xy 20.193 -70.231)
				)
			)
		)
		(zone
			(layer "F.Cu")
			(hatch none 0.5)
			(connect_pads
				(clearance 0)
			)
			(min_thickness 0.25)
			(keepout
				(tracks not_allowed)
				(vias allowed)
				(pads allowed)
				(copperpour not_allowed)
				(footprints allowed)
			)
			(placement
				(enabled no)
				(sheetname "")
			)
			(fill
				(thermal_gap 0.5)
				(thermal_bridge_width 0.5)
				(island_removal_mode 0)
			)
			(polygon
				(pts
					(xy 20.701 -70.231) (xy 20.701 -70.612) (xy 20.193 -70.612) (xy 20.193 -70.231)
				)
			)
		)
	)
	(footprint ""
		(layer "F.Cu")
		(at 372.5672 -155.432506 180)
		(property "Reference" "C7A6"
			(at 0 0 180)
			(layer "F.SilkS")
			(hide yes)
			(effects
				(font
					(size 1.27 1.27)
				)
			)
		)
		(property "Value" ""
			(at 0 0 180)
			(layer "F.Fab")
			(effects
				(font
					(size 1.27 1.27)
				)
			)
		)
		(duplicate_pad_numbers_are_jumpers no)
		(fp_poly
			(pts
				(xy 0.3048 -0.1016) (xy 0.3048 0.9906) (xy -0.3048 0.9906) (xy -0.3048 -0.1016)
			)
			(stroke
				(width 0)
				(type default)
			)
			(fill no)
			(layer "F.CrtYd")
		)
		(fp_line
			(start 0.3048 0.9906)
			(end 0.3048 -0.1016)
			(stroke
				(width 0.1)
				(type default)
			)
			(layer "F.Fab")
		)
		(fp_line
			(start 0.3048 -0.1016)
			(end -0.3048 -0.1016)
			(stroke
				(width 0.1)
				(type default)
			)
			(layer "F.Fab")
		)
		(fp_line
			(start -0.3048 0.9906)
			(end 0.3048 0.9906)
			(stroke
				(width 0.1)
				(type default)
			)
			(layer "F.Fab")
		)
		(fp_line
			(start -0.3048 -0.1016)
			(end -0.3048 0.9906)
			(stroke
				(width 0.1)
				(type default)
			)
			(layer "F.Fab")
		)
		(pad "1" smd rect
			(at 0 0 180)
			(size 0.508 0.508)
			(layers "F.Cu" "F.Mask" "F.Paste")
			(net "VR_PVNN_PCH_PH1_VCIN")
		)
		(pad "2" smd rect
			(at 0 0.889 180)
			(size 0.508 0.508)
			(layers "F.Cu" "F.Mask" "F.Paste")
			(net "GND")
		)
		(zone
			(layer "F.Cu")
			(hatch none 0.5)
			(connect_pads
				(clearance 0)
			)
			(min_thickness 0.25)
			(keepout
				(tracks not_allowed)
				(vias allowed)
				(pads allowed)
				(copperpour not_allowed)
				(footprints allowed)
			)
			(placement
				(enabled no)
				(sheetname "")
			)
			(fill
				(thermal_gap 0.5)
				(thermal_bridge_width 0.5)
				(island_removal_mode 0)
			)
			(polygon
				(pts
					(xy 372.8212 -156.067506) (xy 372.3132 -156.067506) (xy 372.3132 -155.686506) (xy 372.8212 -155.686506)
				)
			)
		)
		(zone
			(layer "F.Cu")
			(hatch none 0.5)
			(connect_pads
				(clearance 0)
			)
			(min_thickness 0.25)
			(keepout
				(tracks allowed)
				(vias not_allowed)
				(pads allowed)
				(copperpour not_allowed)
				(footprints allowed)
			)
			(placement
				(enabled no)
				(sheetname "")
			)
			(fill
				(thermal_gap 0.5)
				(thermal_bridge_width 0.5)
				(island_removal_mode 0)
			)
			(polygon
				(pts
					(xy 372.8212 -155.686506) (xy 372.3132 -155.686506) (xy 372.3132 -156.067506) (xy 372.8212 -156.067506)
				)
			)
		)
	)
	(footprint ""
		(layer "F.Cu")
		(at 13.4366 -72.009 180)
		(property "Reference" "R1D41"
			(at 0 0 180)
			(layer "F.SilkS")
			(hide yes)
			(effects
				(font
					(size 1.27 1.27)
				)
			)
		)
		(property "Value" ""
			(at 0 0 180)
			(layer "F.Fab")
			(effects
				(font
					(size 1.27 1.27)
				)
			)
		)
		(duplicate_pad_numbers_are_jumpers no)
		(fp_poly
			(pts
				(xy -0.7239 -0.2159) (xy 0.7239 -0.2159) (xy 0.7239 1.9939) (xy -0.7239 1.9939)
			)
			(stroke
				(width 0)
				(type default)
			)
			(fill no)
			(layer "F.CrtYd")
		)
		(fp_line
			(start 0.7239 1.9939)
			(end 0.7239 -0.2159)
			(stroke
				(width 0.1)
				(type default)
			)
			(layer "F.Fab")
		)
		(fp_line
			(start 0.7239 -0.2159)
			(end -0.7239 -0.2159)
			(stroke
				(width 0.1)
				(type default)
			)
			(layer "F.Fab")
		)
		(fp_line
			(start -0.7239 1.9939)
			(end 0.7239 1.9939)
			(stroke
				(width 0.1)
				(type default)
			)
			(layer "F.Fab")
		)
		(fp_line
			(start -0.7239 -0.2159)
			(end -0.7239 1.9939)
			(stroke
				(width 0.1)
				(type default)
			)
			(layer "F.Fab")
		)
		(pad "1" smd rect
			(at 0 0 180)
			(size 1.27 1.016)
			(layers "F.Cu" "F.Mask" "F.Paste")
			(net "GND")
		)
		(pad "2" smd rect
			(at 0 1.778 180)
			(size 1.27 1.016)
			(layers "F.Cu" "F.Mask" "F.Paste")
			(net "AGND_HSC")
		)
		(zone
			(layer "F.Cu")
			(hatch none 0.5)
			(connect_pads
				(clearance 0)
			)
			(min_thickness 0.25)
			(keepout
				(tracks not_allowed)
				(vias allowed)
				(pads allowed)
				(copperpour not_allowed)
				(footprints allowed)
			)
			(placement
				(enabled no)
				(sheetname "")
			)
			(fill
				(thermal_gap 0.5)
				(thermal_bridge_width 0.5)
				(island_removal_mode 0)
			)
			(polygon
				(pts
					(xy 12.8016 -72.517) (xy 12.8016 -73.279) (xy 12.8905 -73.279) (xy 14.0716 -73.279) (xy 14.0716 -72.517)
				)
			)
		)
	)
	(footprint ""
		(layer "F.Cu")
		(at 433.9336 -16.0528 -90)
		(property "Reference" "R6W44"
			(at -0.8382 -0.67818 270)
			(unlocked yes)
			(layer "F.SilkS")
			(effects
				(font
					(size 0.4064 0.254)
					(thickness 0.1524)
				)
				(justify left)
			)
		)
		(property "Value" ""
			(at 0 0 270)
			(layer "F.Fab")
			(effects
				(font
					(size 1.27 1.27)
				)
			)
		)
		(duplicate_pad_numbers_are_jumpers no)
		(fp_poly
			(pts
				(xy -0.2794 -0.1016) (xy 0.2794 -0.1016) (xy 0.2794 0.9906) (xy -0.2794 0.9906)
			)
			(stroke
				(width 0)
				(type default)
			)
			(fill no)
			(layer "F.CrtYd")
		)
		(fp_line
			(start -0.2794 0.9906)
			(end 0.2794 0.9906)
			(stroke
				(width 0.1)
				(type default)
			)
			(layer "F.Fab")
		)
		(fp_line
			(start 0.2794 0.9906)
			(end 0.2794 -0.1016)
			(stroke
				(width 0.1)
				(type default)
			)
			(layer "F.Fab")
		)
		(fp_line
			(start -0.2794 -0.1016)
			(end -0.2794 0.9906)
			(stroke
				(width 0.1)
				(type default)
			)
			(layer "F.Fab")
		)
		(fp_line
			(start 0.2794 -0.1016)
			(end -0.2794 -0.1016)
			(stroke
				(width 0.1)
				(type default)
			)
			(layer "F.Fab")
		)
		(pad "1" smd rect
			(at 0 0 270)
			(size 0.508 0.508)
			(layers "F.Cu" "F.Mask" "F.Paste")
			(net "P3V3_STBY")
		)
		(pad "2" smd rect
			(at 0 0.889 270)
			(size 0.508 0.508)
			(layers "F.Cu" "F.Mask" "F.Paste")
			(net "PCA9554_A0")
		)
		(zone
			(layer "F.Cu")
			(hatch none 0.5)
			(connect_pads
				(clearance 0)
			)
			(min_thickness 0.25)
			(keepout
				(tracks not_allowed)
				(vias allowed)
				(pads allowed)
				(copperpour not_allowed)
				(footprints allowed)
			)
			(placement
				(enabled no)
				(sheetname "")
			)
			(fill
				(thermal_gap 0.5)
				(thermal_bridge_width 0.5)
				(island_removal_mode 0)
			)
			(polygon
				(pts
					(xy 433.2986 -16.3068) (xy 433.2986 -15.7988) (xy 433.6796 -15.7988) (xy 433.6796 -16.3068)
				)
			)
		)
		(zone
			(layer "F.Cu")
			(hatch none 0.5)
			(connect_pads
				(clearance 0)
			)
			(min_thickness 0.25)
			(keepout
				(tracks allowed)
				(vias not_allowed)
				(pads allowed)
				(copperpour not_allowed)
				(footprints allowed)
			)
			(placement
				(enabled no)
				(sheetname "")
			)
			(fill
				(thermal_gap 0.5)
				(thermal_bridge_width 0.5)
				(island_removal_mode 0)
			)
			(polygon
				(pts
					(xy 433.6796 -16.3068) (xy 433.6796 -15.7988) (xy 433.2986 -15.7988) (xy 433.2986 -16.3068)
				)
			)
		)
	)
	(footprint ""
		(layer "F.Cu")
		(at 407.73604 -112.32642 90)
		(property "Reference" "R7W17"
			(at -0.8382 -0.67818 90)
			(unlocked yes)
			(layer "F.SilkS")
			(effects
				(font
					(size 0.4064 0.254)
					(thickness 0.1524)
				)
				(justify left)
			)
		)
		(property "Value" ""
			(at 0 0 90)
			(layer "F.Fab")
			(effects
				(font
					(size 1.27 1.27)
				)
			)
		)
		(duplicate_pad_numbers_are_jumpers no)
		(fp_poly
			(pts
				(xy -0.2794 -0.1016) (xy 0.2794 -0.1016) (xy 0.2794 0.9906) (xy -0.2794 0.9906)
			)
			(stroke
				(width 0)
				(type default)
			)
			(fill no)
			(layer "F.CrtYd")
		)
		(fp_line
			(start 0.2794 -0.1016)
			(end -0.2794 -0.1016)
			(stroke
				(width 0.1)
				(type default)
			)
			(layer "F.Fab")
		)
		(fp_line
			(start -0.2794 -0.1016)
			(end -0.2794 0.9906)
			(stroke
				(width 0.1)
				(type default)
			)
			(layer "F.Fab")
		)
		(fp_line
			(start 0.2794 0.9906)
			(end 0.2794 -0.1016)
			(stroke
				(width 0.1)
				(type default)
			)
			(layer "F.Fab")
		)
		(fp_line
			(start -0.2794 0.9906)
			(end 0.2794 0.9906)
			(stroke
				(width 0.1)
				(type default)
			)
			(layer "F.Fab")
		)
		(pad "1" smd rect
			(at 0 0 90)
			(size 0.508 0.508)
			(layers "F.Cu" "F.Mask" "F.Paste")
			(net "FM_THROTTLE_R2_N")
		)
		(pad "2" smd rect
			(at 0 0.889 90)
			(size 0.508 0.508)
			(layers "F.Cu" "F.Mask" "F.Paste")
			(net "FM_THROTTLE_N")
		)
		(zone
			(layer "F.Cu")
			(hatch none 0.5)
			(connect_pads
				(clearance 0)
			)
			(min_thickness 0.25)
			(keepout
				(tracks allowed)
				(vias not_allowed)
				(pads allowed)
				(copperpour not_allowed)
				(footprints allowed)
			)
			(placement
				(enabled no)
				(sheetname "")
			)
			(fill
				(thermal_gap 0.5)
				(thermal_bridge_width 0.5)
				(island_removal_mode 0)
			)
			(polygon
				(pts
					(xy 407.99004 -112.07242) (xy 407.99004 -112.58042) (xy 408.37104 -112.58042) (xy 408.37104 -112.07242)
				)
			)
		)
		(zone
			(layer "F.Cu")
			(hatch none 0.5)
			(connect_pads
				(clearance 0)
			)
			(min_thickness 0.25)
			(keepout
				(tracks not_allowed)
				(vias allowed)
				(pads allowed)
				(copperpour not_allowed)
				(footprints allowed)
			)
			(placement
				(enabled no)
				(sheetname "")
			)
			(fill
				(thermal_gap 0.5)
				(thermal_bridge_width 0.5)
				(island_removal_mode 0)
			)
			(polygon
				(pts
					(xy 408.37104 -112.07242) (xy 408.37104 -112.58042) (xy 407.99004 -112.58042) (xy 407.99004 -112.07242)
				)
			)
		)
	)
	(footprint ""
		(layer "F.Cu")
		(at 28.242006 -22.941534)
		(property "Reference" "R1F4"
			(at 0 0 0)
			(layer "F.SilkS")
			(hide yes)
			(effects
				(font
					(size 1.27 1.27)
				)
			)
		)
		(property "Value" ""
			(at 0 0 0)
			(layer "F.Fab")
			(effects
				(font
					(size 1.27 1.27)
				)
			)
		)
		(duplicate_pad_numbers_are_jumpers no)
		(fp_poly
			(pts
				(xy -0.2794 -0.1016) (xy 0.2794 -0.1016) (xy 0.2794 0.9906) (xy -0.2794 0.9906)
			)
			(stroke
				(width 0)
				(type default)
			)
			(fill no)
			(layer "F.CrtYd")
		)
		(fp_line
			(start -0.2794 -0.1016)
			(end -0.2794 0.9906)
			(stroke
				(width 0.1)
				(type default)
			)
			(layer "F.Fab")
		)
		(fp_line
			(start -0.2794 0.9906)
			(end 0.2794 0.9906)
			(stroke
				(width 0.1)
				(type default)
			)
			(layer "F.Fab")
		)
		(fp_line
			(start 0.2794 -0.1016)
			(end -0.2794 -0.1016)
			(stroke
				(width 0.1)
				(type default)
			)
			(layer "F.Fab")
		)
		(fp_line
			(start 0.2794 0.9906)
			(end 0.2794 -0.1016)
			(stroke
				(width 0.1)
				(type default)
			)
			(layer "F.Fab")
		)
		(pad "1" smd rect
			(at 0 0)
			(size 0.508 0.508)
			(layers "F.Cu" "F.Mask" "F.Paste")
			(net "M_G_CPU_VREF")
		)
		(pad "2" smd rect
			(at 0 0.889)
			(size 0.508 0.508)
			(layers "F.Cu" "F.Mask" "F.Paste")
			(net "M_G_VREF")
		)
		(zone
			(layer "F.Cu")
			(hatch none 0.5)
			(connect_pads
				(clearance 0)
			)
			(min_thickness 0.25)
			(keepout
				(tracks allowed)
				(vias not_allowed)
				(pads allowed)
				(copperpour not_allowed)
				(footprints allowed)
			)
			(placement
				(enabled no)
				(sheetname "")
			)
			(fill
				(thermal_gap 0.5)
				(thermal_bridge_width 0.5)
				(island_removal_mode 0)
			)
			(polygon
				(pts
					(xy 27.988006 -22.687534) (xy 28.496006 -22.687534) (xy 28.496006 -22.306534) (xy 27.988006 -22.306534)
				)
			)
		)
		(zone
			(layer "F.Cu")
			(hatch none 0.5)
			(connect_pads
				(clearance 0)
			)
			(min_thickness 0.25)
			(keepout
				(tracks not_allowed)
				(vias allowed)
				(pads allowed)
				(copperpour not_allowed)
				(footprints allowed)
			)
			(placement
				(enabled no)
				(sheetname "")
			)
			(fill
				(thermal_gap 0.5)
				(thermal_bridge_width 0.5)
				(island_removal_mode 0)
			)
			(polygon
				(pts
					(xy 27.988006 -22.306534) (xy 28.496006 -22.306534) (xy 28.496006 -22.687534) (xy 27.988006 -22.687534)
				)
			)
		)
	)
	(footprint ""
		(layer "F.Cu")
		(at 406.7302 -104.648 -90)
		(property "Reference" "R2N9"
			(at 0 0 270)
			(layer "F.SilkS")
			(hide yes)
			(effects
				(font
					(size 1.27 1.27)
				)
			)
		)
		(property "Value" ""
			(at 0 0 270)
			(layer "F.Fab")
			(effects
				(font
					(size 1.27 1.27)
				)
			)
		)
		(duplicate_pad_numbers_are_jumpers no)
		(fp_poly
			(pts
				(xy -0.2794 -0.1016) (xy 0.2794 -0.1016) (xy 0.2794 0.9906) (xy -0.2794 0.9906)
			)
			(stroke
				(width 0)
				(type default)
			)
			(fill no)
			(layer "F.CrtYd")
		)
		(fp_line
			(start -0.2794 0.9906)
			(end 0.2794 0.9906)
			(stroke
				(width 0.1)
				(type default)
			)
			(layer "F.Fab")
		)
		(fp_line
			(start 0.2794 0.9906)
			(end 0.2794 -0.1016)
			(stroke
				(width 0.1)
				(type default)
			)
			(layer "F.Fab")
		)
		(fp_line
			(start -0.2794 -0.1016)
			(end -0.2794 0.9906)
			(stroke
				(width 0.1)
				(type default)
			)
			(layer "F.Fab")
		)
		(fp_line
			(start 0.2794 -0.1016)
			(end -0.2794 -0.1016)
			(stroke
				(width 0.1)
				(type default)
			)
			(layer "F.Fab")
		)
		(pad "1" smd rect
			(at 0 0 270)
			(size 0.508 0.508)
			(layers "F.Cu" "F.Mask" "F.Paste")
			(net "P3V3_STBY")
		)
		(pad "2" smd rect
			(at 0 0.889 270)
			(size 0.508 0.508)
			(layers "F.Cu" "F.Mask" "F.Paste")
			(net "PU_10GBE_LOM_PCI_DISABLE_N")
		)
		(zone
			(layer "F.Cu")
			(hatch none 0.5)
			(connect_pads
				(clearance 0)
			)
			(min_thickness 0.25)
			(keepout
				(tracks not_allowed)
				(vias allowed)
				(pads allowed)
				(copperpour not_allowed)
				(footprints allowed)
			)
			(placement
				(enabled no)
				(sheetname "")
			)
			(fill
				(thermal_gap 0.5)
				(thermal_bridge_width 0.5)
				(island_removal_mode 0)
			)
			(polygon
				(pts
					(xy 406.0952 -104.902) (xy 406.0952 -104.394) (xy 406.4762 -104.394) (xy 406.4762 -104.902)
				)
			)
		)
		(zone
			(layer "F.Cu")
			(hatch none 0.5)
			(connect_pads
				(clearance 0)
			)
			(min_thickness 0.25)
			(keepout
				(tracks allowed)
				(vias not_allowed)
				(pads allowed)
				(copperpour not_allowed)
				(footprints allowed)
			)
			(placement
				(enabled no)
				(sheetname "")
			)
			(fill
				(thermal_gap 0.5)
				(thermal_bridge_width 0.5)
				(island_removal_mode 0)
			)
			(polygon
				(pts
					(xy 406.4762 -104.902) (xy 406.4762 -104.394) (xy 406.0952 -104.394) (xy 406.0952 -104.902)
				)
			)
		)
	)
	(footprint ""
		(layer "F.Cu")
		(at 370.967 -97.155 180)
		(property "Reference" "R7W1"
			(at -0.8382 -0.67818 180)
			(unlocked yes)
			(layer "F.SilkS")
			(effects
				(font
					(size 0.4064 0.254)
					(thickness 0.1524)
				)
				(justify left)
			)
		)
		(property "Value" ""
			(at 0 0 180)
			(layer "F.Fab")
			(effects
				(font
					(size 1.27 1.27)
				)
			)
		)
		(duplicate_pad_numbers_are_jumpers no)
		(fp_poly
			(pts
				(xy -0.2794 -0.1016) (xy 0.2794 -0.1016) (xy 0.2794 0.9906) (xy -0.2794 0.9906)
			)
			(stroke
				(width 0)
				(type default)
			)
			(fill no)
			(layer "F.CrtYd")
		)
		(fp_line
			(start 0.2794 0.9906)
			(end 0.2794 -0.1016)
			(stroke
				(width 0.1)
				(type default)
			)
			(layer "F.Fab")
		)
		(fp_line
			(start 0.2794 -0.1016)
			(end -0.2794 -0.1016)
			(stroke
				(width 0.1)
				(type default)
			)
			(layer "F.Fab")
		)
		(fp_line
			(start -0.2794 0.9906)
			(end 0.2794 0.9906)
			(stroke
				(width 0.1)
				(type default)
			)
			(layer "F.Fab")
		)
		(fp_line
			(start -0.2794 -0.1016)
			(end -0.2794 0.9906)
			(stroke
				(width 0.1)
				(type default)
			)
			(layer "F.Fab")
		)
		(pad "1" smd rect
			(at 0 0 180)
			(size 0.508 0.508)
			(layers "F.Cu" "F.Mask" "F.Paste")
			(net "FM_SLPS3_N")
		)
		(pad "2" smd rect
			(at 0 0.889 180)
			(size 0.508 0.508)
			(layers "F.Cu" "F.Mask" "F.Paste")
			(net "FM_SLPS3_R_N")
		)
		(zone
			(layer "F.Cu")
			(hatch none 0.5)
			(connect_pads
				(clearance 0)
			)
			(min_thickness 0.25)
			(keepout
				(tracks not_allowed)
				(vias allowed)
				(pads allowed)
				(copperpour not_allowed)
				(footprints allowed)
			)
			(placement
				(enabled no)
				(sheetname "")
			)
			(fill
				(thermal_gap 0.5)
				(thermal_bridge_width 0.5)
				(island_removal_mode 0)
			)
			(polygon
				(pts
					(xy 371.221 -97.79) (xy 370.713 -97.79) (xy 370.713 -97.409) (xy 371.221 -97.409)
				)
			)
		)
		(zone
			(layer "F.Cu")
			(hatch none 0.5)
			(connect_pads
				(clearance 0)
			)
			(min_thickness 0.25)
			(keepout
				(tracks allowed)
				(vias not_allowed)
				(pads allowed)
				(copperpour not_allowed)
				(footprints allowed)
			)
			(placement
				(enabled no)
				(sheetname "")
			)
			(fill
				(thermal_gap 0.5)
				(thermal_bridge_width 0.5)
				(island_removal_mode 0)
			)
			(polygon
				(pts
					(xy 371.221 -97.409) (xy 370.713 -97.409) (xy 370.713 -97.79) (xy 371.221 -97.79)
				)
			)
		)
	)
	(footprint ""
		(layer "F.Cu")
		(at 407.67 -20.2565)
		(property "Reference" "C1U21"
			(at 0 0 0)
			(layer "F.SilkS")
			(hide yes)
			(effects
				(font
					(size 1.27 1.27)
				)
			)
		)
		(property "Value" ""
			(at 0 0 0)
			(layer "F.Fab")
			(effects
				(font
					(size 1.27 1.27)
				)
			)
		)
		(duplicate_pad_numbers_are_jumpers no)
		(fp_poly
			(pts
				(xy 0.3048 -0.1016) (xy 0.3048 0.9906) (xy -0.3048 0.9906) (xy -0.3048 -0.1016)
			)
			(stroke
				(width 0)
				(type default)
			)
			(fill no)
			(layer "F.CrtYd")
		)
		(fp_line
			(start -0.3048 -0.1016)
			(end -0.3048 0.9906)
			(stroke
				(width 0.1)
				(type default)
			)
			(layer "F.Fab")
		)
		(fp_line
			(start -0.3048 0.9906)
			(end 0.3048 0.9906)
			(stroke
				(width 0.1)
				(type default)
			)
			(layer "F.Fab")
		)
		(fp_line
			(start 0.3048 -0.1016)
			(end -0.3048 -0.1016)
			(stroke
				(width 0.1)
				(type default)
			)
			(layer "F.Fab")
		)
		(fp_line
			(start 0.3048 0.9906)
			(end 0.3048 -0.1016)
			(stroke
				(width 0.1)
				(type default)
			)
			(layer "F.Fab")
		)
		(pad "1" smd rect
			(at 0 0)
			(size 0.508 0.508)
			(layers "F.Cu" "F.Mask" "F.Paste")
			(net "A_P1V05_STBY_PCH_SENSOR")
		)
		(pad "2" smd rect
			(at 0 0.889)
			(size 0.508 0.508)
			(layers "F.Cu" "F.Mask" "F.Paste")
			(net "GND")
		)
		(zone
			(layer "F.Cu")
			(hatch none 0.5)
			(connect_pads
				(clearance 0)
			)
			(min_thickness 0.25)
			(keepout
				(tracks allowed)
				(vias not_allowed)
				(pads allowed)
				(copperpour not_allowed)
				(footprints allowed)
			)
			(placement
				(enabled no)
				(sheetname "")
			)
			(fill
				(thermal_gap 0.5)
				(thermal_bridge_width 0.5)
				(island_removal_mode 0)
			)
			(polygon
				(pts
					(xy 407.416 -20.0025) (xy 407.924 -20.0025) (xy 407.924 -19.6215) (xy 407.416 -19.6215)
				)
			)
		)
		(zone
			(layer "F.Cu")
			(hatch none 0.5)
			(connect_pads
				(clearance 0)
			)
			(min_thickness 0.25)
			(keepout
				(tracks not_allowed)
				(vias allowed)
				(pads allowed)
				(copperpour not_allowed)
				(footprints allowed)
			)
			(placement
				(enabled no)
				(sheetname "")
			)
			(fill
				(thermal_gap 0.5)
				(thermal_bridge_width 0.5)
				(island_removal_mode 0)
			)
			(polygon
				(pts
					(xy 407.416 -19.6215) (xy 407.924 -19.6215) (xy 407.924 -20.0025) (xy 407.416 -20.0025)
				)
			)
		)
	)
	(footprint ""
		(layer "F.Cu")
		(at 174.244 -8.6995)
		(property "Reference" "R4G9"
			(at 0 0 0)
			(layer "F.SilkS")
			(hide yes)
			(effects
				(font
					(size 1.27 1.27)
				)
			)
		)
		(property "Value" ""
			(at 0 0 0)
			(layer "F.Fab")
			(effects
				(font
					(size 1.27 1.27)
				)
			)
		)
		(duplicate_pad_numbers_are_jumpers no)
		(fp_rect
			(start -0.2794 0.9906)
			(end 0.2794 -0.1016)
			(stroke
				(width 0)
				(type default)
			)
			(fill no)
			(layer "F.CrtYd")
		)
		(fp_line
			(start -0.2794 -0.1016)
			(end -0.2794 0.9906)
			(stroke
				(width 0.1)
				(type default)
			)
			(layer "F.Fab")
		)
		(fp_line
			(start -0.2794 0.9906)
			(end 0.2794 0.9906)
			(stroke
				(width 0.1)
				(type default)
			)
			(layer "F.Fab")
		)
		(fp_line
			(start 0.2794 -0.1016)
			(end -0.2794 -0.1016)
			(stroke
				(width 0.1)
				(type default)
			)
			(layer "F.Fab")
		)
		(fp_line
			(start 0.2794 0.9906)
			(end 0.2794 -0.1016)
			(stroke
				(width 0.1)
				(type default)
			)
			(layer "F.Fab")
		)
		(pad "1" smd rect
			(at 0 0)
			(size 0.508 0.508)
			(layers "F.Cu" "F.Mask" "F.Paste")
			(net "VR_FB_PVPP_GHJ")
		)
		(pad "2" smd rect
			(at 0 0.889)
			(size 0.508 0.508)
			(layers "F.Cu" "F.Mask" "F.Paste")
			(net "AGND_PVPP_GHJ")
		)
		(zone
			(layer "F.Cu")
			(hatch none 0.5)
			(connect_pads
				(clearance 0)
			)
			(min_thickness 0.25)
			(keepout
				(tracks not_allowed)
				(vias allowed)
				(pads allowed)
				(copperpour not_allowed)
				(footprints allowed)
			)
			(placement
				(enabled no)
				(sheetname "")
			)
			(fill
				(thermal_gap 0.5)
				(thermal_bridge_width 0.5)
				(island_removal_mode 0)
			)
			(polygon
				(pts
					(xy 173.99 -8.0645) (xy 174.498 -8.0645) (xy 174.498 -8.4455) (xy 173.99 -8.4455)
				)
			)
		)
		(zone
			(layer "F.Cu")
			(hatch none 0.5)
			(connect_pads
				(clearance 0)
			)
			(min_thickness 0.25)
			(keepout
				(tracks allowed)
				(vias not_allowed)
				(pads allowed)
				(copperpour not_allowed)
				(footprints allowed)
			)
			(placement
				(enabled no)
				(sheetname "")
			)
			(fill
				(thermal_gap 0.5)
				(thermal_bridge_width 0.5)
				(island_removal_mode 0)
			)
			(polygon
				(pts
					(xy 173.99 -8.0645) (xy 174.498 -8.0645) (xy 174.498 -8.4455) (xy 173.99 -8.4455)
				)
			)
		)
	)
	(footprint ""
		(layer "F.Cu")
		(at 317.9826 -29.696918 90)
		(property "Reference" "R6F7"
			(at 0 0 90)
			(layer "F.SilkS")
			(hide yes)
			(effects
				(font
					(size 1.27 1.27)
				)
			)
		)
		(property "Value" ""
			(at 0 0 90)
			(layer "F.Fab")
			(effects
				(font
					(size 1.27 1.27)
				)
			)
		)
		(duplicate_pad_numbers_are_jumpers no)
		(fp_poly
			(pts
				(xy -0.2794 -0.1016) (xy 0.2794 -0.1016) (xy 0.2794 0.9906) (xy -0.2794 0.9906)
			)
			(stroke
				(width 0)
				(type default)
			)
			(fill no)
			(layer "F.CrtYd")
		)
		(fp_line
			(start 0.2794 -0.1016)
			(end -0.2794 -0.1016)
			(stroke
				(width 0.1)
				(type default)
			)
			(layer "F.Fab")
		)
		(fp_line
			(start -0.2794 -0.1016)
			(end -0.2794 0.9906)
			(stroke
				(width 0.1)
				(type default)
			)
			(layer "F.Fab")
		)
		(fp_line
			(start 0.2794 0.9906)
			(end 0.2794 -0.1016)
			(stroke
				(width 0.1)
				(type default)
			)
			(layer "F.Fab")
		)
		(fp_line
			(start -0.2794 0.9906)
			(end 0.2794 0.9906)
			(stroke
				(width 0.1)
				(type default)
			)
			(layer "F.Fab")
		)
		(pad "1" smd rect
			(at 0 0 90)
			(size 0.508 0.508)
			(layers "F.Cu" "F.Mask" "F.Paste")
			(net "CLK_156M_OSC_BRD_CPU0_DN")
		)
		(pad "2" smd rect
			(at 0 0.889 90)
			(size 0.508 0.508)
			(layers "F.Cu" "F.Mask" "F.Paste")
			(net "CLK_156M_OSC_CPU0_HFI_DN")
		)
		(zone
			(layer "F.Cu")
			(hatch none 0.5)
			(connect_pads
				(clearance 0)
			)
			(min_thickness 0.25)
			(keepout
				(tracks allowed)
				(vias not_allowed)
				(pads allowed)
				(copperpour not_allowed)
				(footprints allowed)
			)
			(placement
				(enabled no)
				(sheetname "")
			)
			(fill
				(thermal_gap 0.5)
				(thermal_bridge_width 0.5)
				(island_removal_mode 0)
			)
			(polygon
				(pts
					(xy 318.2366 -29.442918) (xy 318.2366 -29.950918) (xy 318.6176 -29.950918) (xy 318.6176 -29.442918)
				)
			)
		)
		(zone
			(layer "F.Cu")
			(hatch none 0.5)
			(connect_pads
				(clearance 0)
			)
			(min_thickness 0.25)
			(keepout
				(tracks not_allowed)
				(vias allowed)
				(pads allowed)
				(copperpour not_allowed)
				(footprints allowed)
			)
			(placement
				(enabled no)
				(sheetname "")
			)
			(fill
				(thermal_gap 0.5)
				(thermal_bridge_width 0.5)
				(island_removal_mode 0)
			)
			(polygon
				(pts
					(xy 318.6176 -29.442918) (xy 318.6176 -29.950918) (xy 318.2366 -29.950918) (xy 318.2366 -29.442918)
				)
			)
		)
	)
	(footprint ""
		(layer "F.Cu")
		(at 311.34685 -35.615626)
		(property "Reference" "R1W32"
			(at -0.8382 -0.67818 0)
			(unlocked yes)
			(layer "F.SilkS")
			(effects
				(font
					(size 0.4064 0.254)
					(thickness 0.1524)
				)
				(justify left)
			)
		)
		(property "Value" ""
			(at 0 0 0)
			(layer "F.Fab")
			(effects
				(font
					(size 1.27 1.27)
				)
			)
		)
		(duplicate_pad_numbers_are_jumpers no)
		(fp_poly
			(pts
				(xy -0.2794 -0.1016) (xy 0.2794 -0.1016) (xy 0.2794 0.9906) (xy -0.2794 0.9906)
			)
			(stroke
				(width 0)
				(type default)
			)
			(fill no)
			(layer "F.CrtYd")
		)
		(fp_line
			(start -0.2794 -0.1016)
			(end -0.2794 0.9906)
			(stroke
				(width 0.1)
				(type default)
			)
			(layer "F.Fab")
		)
		(fp_line
			(start -0.2794 0.9906)
			(end 0.2794 0.9906)
			(stroke
				(width 0.1)
				(type default)
			)
			(layer "F.Fab")
		)
		(fp_line
			(start 0.2794 -0.1016)
			(end -0.2794 -0.1016)
			(stroke
				(width 0.1)
				(type default)
			)
			(layer "F.Fab")
		)
		(fp_line
			(start 0.2794 0.9906)
			(end 0.2794 -0.1016)
			(stroke
				(width 0.1)
				(type default)
			)
			(layer "F.Fab")
		)
		(pad "1" smd rect
			(at 0 0)
			(size 0.508 0.508)
			(layers "F.Cu" "F.Mask" "F.Paste")
			(net "FM_ADR_COMPLETE_R")
		)
		(pad "2" smd rect
			(at 0 0.889)
			(size 0.508 0.508)
			(layers "F.Cu" "F.Mask" "F.Paste")
			(net "FM_ADR_COMPLETE_CPU0_R")
		)
		(zone
			(layer "F.Cu")
			(hatch none 0.5)
			(connect_pads
				(clearance 0)
			)
			(min_thickness 0.25)
			(keepout
				(tracks allowed)
				(vias not_allowed)
				(pads allowed)
				(copperpour not_allowed)
				(footprints allowed)
			)
			(placement
				(enabled no)
				(sheetname "")
			)
			(fill
				(thermal_gap 0.5)
				(thermal_bridge_width 0.5)
				(island_removal_mode 0)
			)
			(polygon
				(pts
					(xy 311.09285 -35.361626) (xy 311.60085 -35.361626) (xy 311.60085 -34.980626) (xy 311.09285 -34.980626)
				)
			)
		)
		(zone
			(layer "F.Cu")
			(hatch none 0.5)
			(connect_pads
				(clearance 0)
			)
			(min_thickness 0.25)
			(keepout
				(tracks not_allowed)
				(vias allowed)
				(pads allowed)
				(copperpour not_allowed)
				(footprints allowed)
			)
			(placement
				(enabled no)
				(sheetname "")
			)
			(fill
				(thermal_gap 0.5)
				(thermal_bridge_width 0.5)
				(island_removal_mode 0)
			)
			(polygon
				(pts
					(xy 311.09285 -34.980626) (xy 311.60085 -34.980626) (xy 311.60085 -35.361626) (xy 311.09285 -35.361626)
				)
			)
		)
	)
	(footprint ""
		(layer "F.Cu")
		(at 198.178928 -85.733382 90)
		(property "Reference" "C4D47"
			(at 0 0 90)
			(layer "F.SilkS")
			(hide yes)
			(effects
				(font
					(size 1.27 1.27)
				)
			)
		)
		(property "Value" ""
			(at 0 0 90)
			(layer "F.Fab")
			(effects
				(font
					(size 1.27 1.27)
				)
			)
		)
		(duplicate_pad_numbers_are_jumpers no)
		(fp_rect
			(start 0.3048 0.9906)
			(end -0.3048 -0.1016)
			(stroke
				(width 0)
				(type default)
			)
			(fill no)
			(layer "F.CrtYd")
		)
		(fp_line
			(start 0.3048 -0.1016)
			(end -0.3048 -0.1016)
			(stroke
				(width 0.1)
				(type default)
			)
			(layer "F.Fab")
		)
		(fp_line
			(start -0.3048 -0.1016)
			(end -0.3048 0.9906)
			(stroke
				(width 0.1)
				(type default)
			)
			(layer "F.Fab")
		)
		(fp_line
			(start 0.3048 0.9906)
			(end 0.3048 -0.1016)
			(stroke
				(width 0.1)
				(type default)
			)
			(layer "F.Fab")
		)
		(fp_line
			(start -0.3048 0.9906)
			(end 0.3048 0.9906)
			(stroke
				(width 0.1)
				(type default)
			)
			(layer "F.Fab")
		)
		(pad "1" smd rect
			(at 0 0 90)
			(size 0.508 0.508)
			(layers "F.Cu" "F.Mask" "F.Paste")
			(net "P5V_STBY")
		)
		(pad "2" smd rect
			(at 0 0.889 90)
			(size 0.508 0.508)
			(layers "F.Cu" "F.Mask" "F.Paste")
			(net "GND")
		)
		(zone
			(layer "F.Cu")
			(hatch none 0.5)
			(connect_pads
				(clearance 0)
			)
			(min_thickness 0.25)
			(keepout
				(tracks allowed)
				(vias not_allowed)
				(pads allowed)
				(copperpour not_allowed)
				(footprints allowed)
			)
			(placement
				(enabled no)
				(sheetname "")
			)
			(fill
				(thermal_gap 0.5)
				(thermal_bridge_width 0.5)
				(island_removal_mode 0)
			)
			(polygon
				(pts
					(xy 198.813928 -85.987382) (xy 198.432928 -85.987382) (xy 198.432928 -85.479382) (xy 198.813928 -85.479382)
				)
			)
		)
		(zone
			(layer "F.Cu")
			(hatch none 0.5)
			(connect_pads
				(clearance 0)
			)
			(min_thickness 0.25)
			(keepout
				(tracks not_allowed)
				(vias allowed)
				(pads allowed)
				(copperpour not_allowed)
				(footprints allowed)
			)
			(placement
				(enabled no)
				(sheetname "")
			)
			(fill
				(thermal_gap 0.5)
				(thermal_bridge_width 0.5)
				(island_removal_mode 0)
			)
			(polygon
				(pts
					(xy 198.813928 -85.987382) (xy 198.432928 -85.987382) (xy 198.432928 -85.479382) (xy 198.813928 -85.479382)
				)
			)
		)
	)
	(footprint ""
		(layer "F.Cu")
		(at 393.103354 -86.295484)
		(property "Reference" "R7D19"
			(at 0 0 0)
			(layer "F.SilkS")
			(hide yes)
			(effects
				(font
					(size 1.27 1.27)
				)
			)
		)
		(property "Value" ""
			(at 0 0 0)
			(layer "F.Fab")
			(effects
				(font
					(size 1.27 1.27)
				)
			)
		)
		(duplicate_pad_numbers_are_jumpers no)
		(fp_poly
			(pts
				(xy -0.2794 -0.1016) (xy 0.2794 -0.1016) (xy 0.2794 0.9906) (xy -0.2794 0.9906)
			)
			(stroke
				(width 0)
				(type default)
			)
			(fill no)
			(layer "F.CrtYd")
		)
		(fp_line
			(start -0.2794 -0.1016)
			(end -0.2794 0.9906)
			(stroke
				(width 0.1)
				(type default)
			)
			(layer "F.Fab")
		)
		(fp_line
			(start -0.2794 0.9906)
			(end 0.2794 0.9906)
			(stroke
				(width 0.1)
				(type default)
			)
			(layer "F.Fab")
		)
		(fp_line
			(start 0.2794 -0.1016)
			(end -0.2794 -0.1016)
			(stroke
				(width 0.1)
				(type default)
			)
			(layer "F.Fab")
		)
		(fp_line
			(start 0.2794 0.9906)
			(end 0.2794 -0.1016)
			(stroke
				(width 0.1)
				(type default)
			)
			(layer "F.Fab")
		)
		(pad "1" smd rect
			(at 0 0)
			(size 0.508 0.508)
			(layers "F.Cu" "F.Mask" "F.Paste")
			(net "FM_OC_DETECT_EN_N")
		)
		(pad "2" smd rect
			(at 0 0.889)
			(size 0.508 0.508)
			(layers "F.Cu" "F.Mask" "F.Paste")
			(net "GND")
		)
		(zone
			(layer "F.Cu")
			(hatch none 0.5)
			(connect_pads
				(clearance 0)
			)
			(min_thickness 0.25)
			(keepout
				(tracks allowed)
				(vias not_allowed)
				(pads allowed)
				(copperpour not_allowed)
				(footprints allowed)
			)
			(placement
				(enabled no)
				(sheetname "")
			)
			(fill
				(thermal_gap 0.5)
				(thermal_bridge_width 0.5)
				(island_removal_mode 0)
			)
			(polygon
				(pts
					(xy 392.849354 -86.041484) (xy 393.357354 -86.041484) (xy 393.357354 -85.660484) (xy 392.849354 -85.660484)
				)
			)
		)
		(zone
			(layer "F.Cu")
			(hatch none 0.5)
			(connect_pads
				(clearance 0)
			)
			(min_thickness 0.25)
			(keepout
				(tracks not_allowed)
				(vias allowed)
				(pads allowed)
				(copperpour not_allowed)
				(footprints allowed)
			)
			(placement
				(enabled no)
				(sheetname "")
			)
			(fill
				(thermal_gap 0.5)
				(thermal_bridge_width 0.5)
				(island_removal_mode 0)
			)
			(polygon
				(pts
					(xy 392.849354 -85.660484) (xy 393.357354 -85.660484) (xy 393.357354 -86.041484) (xy 392.849354 -86.041484)
				)
			)
		)
	)
	(footprint ""
		(layer "F.Cu")
		(at 183.0832 -75.565 -90)
		(property "Reference" "C4D20"
			(at 0 0 270)
			(layer "F.SilkS")
			(hide yes)
			(effects
				(font
					(size 1.27 1.27)
				)
			)
		)
		(property "Value" ""
			(at 0 0 270)
			(layer "F.Fab")
			(effects
				(font
					(size 1.27 1.27)
				)
			)
		)
		(duplicate_pad_numbers_are_jumpers no)
		(fp_rect
			(start 0.3048 0.9906)
			(end -0.3048 -0.1016)
			(stroke
				(width 0)
				(type default)
			)
			(fill no)
			(layer "F.CrtYd")
		)
		(fp_line
			(start -0.3048 0.9906)
			(end 0.3048 0.9906)
			(stroke
				(width 0.1)
				(type default)
			)
			(layer "F.Fab")
		)
		(fp_line
			(start 0.3048 0.9906)
			(end 0.3048 -0.1016)
			(stroke
				(width 0.1)
				(type default)
			)
			(layer "F.Fab")
		)
		(fp_line
			(start -0.3048 -0.1016)
			(end -0.3048 0.9906)
			(stroke
				(width 0.1)
				(type default)
			)
			(layer "F.Fab")
		)
		(fp_line
			(start 0.3048 -0.1016)
			(end -0.3048 -0.1016)
			(stroke
				(width 0.1)
				(type default)
			)
			(layer "F.Fab")
		)
		(pad "1" smd rect
			(at 0 0 270)
			(size 0.508 0.508)
			(layers "F.Cu" "F.Mask" "F.Paste")
			(net "VR_PVCCIN_CPU0_AVINSEN")
		)
		(pad "2" smd rect
			(at 0 0.889 270)
			(size 0.508 0.508)
			(layers "F.Cu" "F.Mask" "F.Paste")
			(net "GND")
		)
		(zone
			(layer "F.Cu")
			(hatch none 0.5)
			(connect_pads
				(clearance 0)
			)
			(min_thickness 0.25)
			(keepout
				(tracks allowed)
				(vias not_allowed)
				(pads allowed)
				(copperpour not_allowed)
				(footprints allowed)
			)
			(placement
				(enabled no)
				(sheetname "")
			)
			(fill
				(thermal_gap 0.5)
				(thermal_bridge_width 0.5)
				(island_removal_mode 0)
			)
			(polygon
				(pts
					(xy 182.4482 -75.311) (xy 182.8292 -75.311) (xy 182.8292 -75.819) (xy 182.4482 -75.819)
				)
			)
		)
		(zone
			(layer "F.Cu")
			(hatch none 0.5)
			(connect_pads
				(clearance 0)
			)
			(min_thickness 0.25)
			(keepout
				(tracks not_allowed)
				(vias allowed)
				(pads allowed)
				(copperpour not_allowed)
				(footprints allowed)
			)
			(placement
				(enabled no)
				(sheetname "")
			)
			(fill
				(thermal_gap 0.5)
				(thermal_bridge_width 0.5)
				(island_removal_mode 0)
			)
			(polygon
				(pts
					(xy 182.4482 -75.311) (xy 182.8292 -75.311) (xy 182.8292 -75.819) (xy 182.4482 -75.819)
				)
			)
		)
	)
	(footprint ""
		(layer "F.Cu")
		(at 451.85838 -33.5915 90)
		(property "Reference" "R25W37"
			(at 0 0 90)
			(layer "F.SilkS")
			(hide yes)
			(effects
				(font
					(size 1.27 1.27)
				)
			)
		)
		(property "Value" "*"
			(at 0.064008 -4.108196 90)
			(unlocked yes)
			(layer "F.Fab")
			(hide yes)
			(effects
				(font
					(size 1.27 1.016)
					(thickness 0.1524)
				)
			)
		)
		(property "Device Type" "120R2F-GP_RCL_GP-120R2F-GP,64.A"
			(at 0.064008 -5.632196 90)
			(unlocked yes)
			(layer "F.Fab")
			(hide yes)
			(effects
				(font
					(size 1.27 1.016)
					(thickness 0.1524)
				)
			)
		)
		(duplicate_pad_numbers_are_jumpers no)
		(fp_line
			(start 0.508 -0.9398)
			(end -0.508 -0.9398)
			(stroke
				(width 0.1524)
				(type default)
			)
			(layer "F.SilkS")
		)
		(fp_line
			(start -0.508 -0.9398)
			(end -0.508 0.9398)
			(stroke
				(width 0.1524)
				(type default)
			)
			(layer "F.SilkS")
		)
		(fp_rect
			(start -0.508 0.9398)
			(end 0.508 -0.9398)
			(stroke
				(width 0)
				(type default)
			)
			(fill no)
			(layer "F.CrtYd")
		)
		(fp_rect
			(start -0.508 0.9398)
			(end 0.508 -0.9398)
			(stroke
				(width 0)
				(type default)
			)
			(fill no)
			(layer "F.Fab")
		)
		(pad "1" smd custom
			(at 0 -0.4445 90)
			(size 0.1397 0.1397)
			(layers "F.Cu" "F.Mask" "F.Paste")
			(net "BMC_M_BG0")
			(options
				(clearance outline)
				(anchor circle)
			)
			(primitives
				(gr_poly
					(pts
						(arc
							(start -0.1778 -0.2794)
							(mid -0.249642 -0.249642)
							(end -0.2794 -0.1778)
						)
						(arc
							(start -0.2794 0.1778)
							(mid -0.249642 0.249642)
							(end -0.1778 0.2794)
						)
						(arc
							(start 0.1778 0.2794)
							(mid 0.249642 0.249642)
							(end 0.2794 0.1778)
						)
						(arc
							(start 0.2794 -0.1778)
							(mid 0.249642 -0.249642)
							(end 0.1778 -0.2794)
						)
					)
					(width 0)
					(fill yes)
				)
			)
		)
		(pad "2" smd custom
			(at 0 0.4445 90)
			(size 0.1397 0.1397)
			(layers "F.Cu" "F.Mask" "F.Paste")
			(net "P1V2_AUX_BMC")
			(options
				(clearance outline)
				(anchor circle)
			)
			(primitives
				(gr_poly
					(pts
						(arc
							(start -0.1778 -0.2794)
							(mid -0.249642 -0.249642)
							(end -0.2794 -0.1778)
						)
						(arc
							(start -0.2794 0.1778)
							(mid -0.249642 0.249642)
							(end -0.1778 0.2794)
						)
						(arc
							(start 0.1778 0.2794)
							(mid 0.249642 0.249642)
							(end 0.2794 0.1778)
						)
						(arc
							(start 0.2794 -0.1778)
							(mid 0.249642 -0.249642)
							(end 0.1778 -0.2794)
						)
					)
					(width 0)
					(fill yes)
				)
			)
		)
	)
	(footprint ""
		(layer "F.Cu")
		(at 348.361 -133.604 180)
		(property "Reference" "C7B6"
			(at 0 0 180)
			(layer "F.SilkS")
			(hide yes)
			(effects
				(font
					(size 1.27 1.27)
				)
			)
		)
		(property "Value" ""
			(at 0 0 180)
			(layer "F.Fab")
			(effects
				(font
					(size 1.27 1.27)
				)
			)
		)
		(duplicate_pad_numbers_are_jumpers no)
		(fp_poly
			(pts
				(xy 0.3048 -0.1016) (xy 0.3048 0.9906) (xy -0.3048 0.9906) (xy -0.3048 -0.1016)
			)
			(stroke
				(width 0)
				(type default)
			)
			(fill no)
			(layer "F.CrtYd")
		)
		(fp_line
			(start 0.3048 0.9906)
			(end 0.3048 -0.1016)
			(stroke
				(width 0.1)
				(type default)
			)
			(layer "F.Fab")
		)
		(fp_line
			(start 0.3048 -0.1016)
			(end -0.3048 -0.1016)
			(stroke
				(width 0.1)
				(type default)
			)
			(layer "F.Fab")
		)
		(fp_line
			(start -0.3048 0.9906)
			(end 0.3048 0.9906)
			(stroke
				(width 0.1)
				(type default)
			)
			(layer "F.Fab")
		)
		(fp_line
			(start -0.3048 -0.1016)
			(end -0.3048 0.9906)
			(stroke
				(width 0.1)
				(type default)
			)
			(layer "F.Fab")
		)
		(pad "1" smd rect
			(at 0 0 180)
			(size 0.508 0.508)
			(layers "F.Cu" "F.Mask" "F.Paste")
			(net "VR_FET_SW_P12V_STBY_PVPP_DEF")
		)
		(pad "2" smd rect
			(at 0 0.889 180)
			(size 0.508 0.508)
			(layers "F.Cu" "F.Mask" "F.Paste")
			(net "GND")
		)
		(zone
			(layer "F.Cu")
			(hatch none 0.5)
			(connect_pads
				(clearance 0)
			)
			(min_thickness 0.25)
			(keepout
				(tracks not_allowed)
				(vias allowed)
				(pads allowed)
				(copperpour not_allowed)
				(footprints allowed)
			)
			(placement
				(enabled no)
				(sheetname "")
			)
			(fill
				(thermal_gap 0.5)
				(thermal_bridge_width 0.5)
				(island_removal_mode 0)
			)
			(polygon
				(pts
					(xy 348.615 -134.239) (xy 348.107 -134.239) (xy 348.107 -133.858) (xy 348.615 -133.858)
				)
			)
		)
		(zone
			(layer "F.Cu")
			(hatch none 0.5)
			(connect_pads
				(clearance 0)
			)
			(min_thickness 0.25)
			(keepout
				(tracks allowed)
				(vias not_allowed)
				(pads allowed)
				(copperpour not_allowed)
				(footprints allowed)
			)
			(placement
				(enabled no)
				(sheetname "")
			)
			(fill
				(thermal_gap 0.5)
				(thermal_bridge_width 0.5)
				(island_removal_mode 0)
			)
			(polygon
				(pts
					(xy 348.615 -133.858) (xy 348.107 -133.858) (xy 348.107 -134.239) (xy 348.615 -134.239)
				)
			)
		)
	)
	(footprint ""
		(layer "F.Cu")
		(at -4.021074 -139.00531 90)
		(property "Reference" "RT5"
			(at 1.01473 0.656336 0)
			(unlocked yes)
			(layer "F.SilkS")
			(effects
				(font
					(size 0.4064 0.254)
					(thickness 0.1524)
				)
			)
		)
		(property "Value" ""
			(at 0 0 90)
			(layer "F.Fab")
			(effects
				(font
					(size 1.27 1.27)
				)
			)
		)
		(duplicate_pad_numbers_are_jumpers no)
		(fp_poly
			(pts
				(xy -0.4953 -0.2032) (xy 0.4953 -0.2032) (xy 0.4953 1.6002) (xy -0.4953 1.6002)
			)
			(stroke
				(width 0)
				(type default)
			)
			(fill no)
			(layer "F.CrtYd")
		)
		(fp_line
			(start 0.4953 -0.2032)
			(end 0.4953 1.6002)
			(stroke
				(width 0.1)
				(type default)
			)
			(layer "F.Fab")
		)
		(fp_line
			(start -0.4953 -0.2032)
			(end 0.4953 -0.2032)
			(stroke
				(width 0.1)
				(type default)
			)
			(layer "F.Fab")
		)
		(fp_line
			(start 0.4953 1.6002)
			(end -0.4953 1.6002)
			(stroke
				(width 0.1)
				(type default)
			)
			(layer "F.Fab")
		)
		(fp_line
			(start -0.4953 1.6002)
			(end -0.4953 -0.2032)
			(stroke
				(width 0.1)
				(type default)
			)
			(layer "F.Fab")
		)
		(pad "1" smd rect
			(at 0 0 90)
			(size 0.762 0.889)
			(layers "F.Cu" "F.Mask" "F.Paste")
			(net "VR_PVDDQ_KLM_PH1_BOOT")
		)
		(pad "2" smd rect
			(at 0 1.397 90)
			(size 0.762 0.889)
			(layers "F.Cu" "F.Mask" "F.Paste")
			(net "VR_PVDDQ_KLM_PH1_BOOT_R")
		)
		(zone
			(layer "F.Cu")
			(hatch none 0.5)
			(connect_pads
				(clearance 0)
			)
			(min_thickness 0.25)
			(keepout
				(tracks allowed)
				(vias not_allowed)
				(pads allowed)
				(copperpour not_allowed)
				(footprints allowed)
			)
			(placement
				(enabled no)
				(sheetname "")
			)
			(fill
				(thermal_gap 0.5)
				(thermal_bridge_width 0.5)
				(island_removal_mode 0)
			)
			(polygon
				(pts
					(xy -3.068574 -139.38631) (xy -3.576574 -139.38631) (xy -3.576574 -138.62431) (xy -3.068574 -138.62431)
				)
			)
		)
		(zone
			(layer "F.Cu")
			(hatch none 0.5)
			(connect_pads
				(clearance 0)
			)
			(min_thickness 0.25)
			(keepout
				(tracks not_allowed)
				(vias allowed)
				(pads allowed)
				(copperpour not_allowed)
				(footprints allowed)
			)
			(placement
				(enabled no)
				(sheetname "")
			)
			(fill
				(thermal_gap 0.5)
				(thermal_bridge_width 0.5)
				(island_removal_mode 0)
			)
			(polygon
				(pts
					(xy -3.068574 -138.62431) (xy -3.068574 -139.38631) (xy -3.576574 -139.38631) (xy -3.576574 -138.62431)
				)
			)
		)
	)
	(footprint ""
		(layer "F.Cu")
		(at 470.282016 -134.366)
		(property "Reference" "J9B4"
			(at -4.77012 9.83615 0)
			(unlocked yes)
			(layer "F.SilkS")
			(effects
				(font
					(size 0.7874 0.5842)
					(thickness 0.1524)
				)
				(justify left)
			)
		)
		(property "Value" ""
			(at 0 0 0)
			(layer "F.Fab")
			(effects
				(font
					(size 1.27 1.27)
				)
			)
		)
		(duplicate_pad_numbers_are_jumpers no)
		(fp_line
			(start -1.1303 -2.426208)
			(end 5.3721 -2.426208)
			(stroke
				(width 0.1524)
				(type default)
			)
			(layer "F.SilkS")
		)
		(fp_line
			(start -1.1303 10.426192)
			(end 5.3721 10.426192)
			(stroke
				(width 0.1524)
				(type default)
			)
			(layer "F.SilkS")
		)
		(fp_line
			(start -1.12903 -0.8382)
			(end -1.1303 -2.426208)
			(stroke
				(width 0.1524)
				(type default)
			)
			(layer "F.SilkS")
		)
		(fp_line
			(start -1.12903 8.838184)
			(end -1.1303 10.426192)
			(stroke
				(width 0.1524)
				(type default)
			)
			(layer "F.SilkS")
		)
		(fp_line
			(start 5.3721 -2.426208)
			(end 5.37083 -0.8382)
			(stroke
				(width 0.1524)
				(type default)
			)
			(layer "F.SilkS")
		)
		(fp_line
			(start 5.3721 10.426192)
			(end 5.37083 8.838184)
			(stroke
				(width 0.1524)
				(type default)
			)
			(layer "F.SilkS")
		)
		(fp_poly
			(pts
				(xy -2.565908 -1.155192) (xy -2.565908 -0.139192) (xy -1.295908 -0.647192)
			)
			(stroke
				(width 0)
				(type default)
			)
			(fill yes)
			(layer "F.SilkS")
		)
		(fp_poly
			(pts
				(xy -1.1303 -2.426208) (xy 5.3721 -2.426208) (xy 5.3721 10.426192) (xy -1.1303 10.426192)
			)
			(stroke
				(width 0)
				(type default)
			)
			(fill no)
			(layer "F.CrtYd")
		)
		(fp_line
			(start -1.1303 -2.426208)
			(end 5.3721 -2.426208)
			(stroke
				(width 0.1)
				(type default)
			)
			(layer "F.Fab")
		)
		(fp_line
			(start -1.1303 10.426192)
			(end -1.1303 -2.426208)
			(stroke
				(width 0.1)
				(type default)
			)
			(layer "F.Fab")
		)
		(fp_line
			(start 5.3721 -2.426208)
			(end 5.3721 10.426192)
			(stroke
				(width 0.1)
				(type default)
			)
			(layer "F.Fab")
		)
		(fp_line
			(start 5.3721 10.426192)
			(end -1.1303 10.426192)
			(stroke
				(width 0.1)
				(type default)
			)
			(layer "F.Fab")
		)
		(fp_poly
			(pts
				(xy -2.96291 -0.521462) (xy -2.96291 0.494538) (xy -1.69291 -0.013462)
			)
			(stroke
				(width 0)
				(type default)
			)
			(fill yes)
			(layer "F.Fab")
		)
		(fp_text user "9"
			(at -2.15138 6.54939 0)
			(unlocked yes)
			(layer "F.SilkS")
			(effects
				(font
					(size 0.7874 0.5842)
					(thickness 0.1524)
				)
				(justify left)
			)
		)
		(fp_text user "10"
			(at 5.673344 6.99643 0)
			(unlocked yes)
			(layer "F.SilkS")
			(effects
				(font
					(size 0.7874 0.5842)
					(thickness 0.1524)
				)
				(justify left)
			)
		)
		(fp_text user "2"
			(at 5.971286 -0.210312 0)
			(unlocked yes)
			(layer "F.SilkS")
			(effects
				(font
					(size 0.7874 0.5842)
					(thickness 0.1524)
				)
				(justify left)
			)
		)
		(fp_text user "9"
			(at -2.152142 6.550152 0)
			(unlocked yes)
			(layer "F.Fab")
			(effects
				(font
					(size 0.7874 0.5842)
					(thickness 0.1524)
				)
				(justify left)
			)
		)
		(fp_text user "10"
			(at 5.673344 6.99643 0)
			(unlocked yes)
			(layer "F.Fab")
			(effects
				(font
					(size 0.7874 0.5842)
					(thickness 0.1524)
				)
				(justify left)
			)
		)
		(fp_text user "2"
			(at 5.967222 -0.207772 0)
			(unlocked yes)
			(layer "F.Fab")
			(effects
				(font
					(size 0.7874 0.5842)
					(thickness 0.1524)
				)
				(justify left)
			)
		)
		(pad "" np_thru_hole circle
			(at 2.1209 0.999998)
			(size 0.254 0.254)
			(drill 1.016)
			(layers "*.Cu" "*.Mask")
			(clearance 0.6985)
			(thermal_gap 0.6985)
		)
		(pad "" np_thru_hole circle
			(at 2.1209 6.999986)
			(size 0.254 0.254)
			(drill 1.016)
			(layers "*.Cu" "*.Mask")
			(clearance 0.6985)
			(thermal_gap 0.6985)
		)
		(pad "1" smd rect
			(at 0 0)
			(size 2.7432 1.016)
			(layers "F.Cu" "F.Mask" "F.Paste")
			(net "JTAG_MCP_TCK_R")
		)
		(pad "2" smd rect
			(at 4.2418 0)
			(size 2.7432 1.016)
			(layers "F.Cu" "F.Mask" "F.Paste")
			(net "GND")
		)
		(pad "3" smd rect
			(at 0 1.999996)
			(size 2.7432 1.016)
			(layers "F.Cu" "F.Mask" "F.Paste")
			(net "JTAG_MCP_MUX_TDO")
		)
		(pad "4" smd rect
			(at 4.2418 1.999996)
			(size 2.7432 1.016)
			(layers "F.Cu" "F.Mask" "F.Paste")
			(net "P1V8_MCP_CPU0")
		)
		(pad "5" smd rect
			(at 0 3.999992)
			(size 2.7432 1.016)
			(layers "F.Cu" "F.Mask" "F.Paste")
			(net "JTAG_MCP_TMS_R")
		)
		(pad "6" smd rect
			(at 4.2418 3.999992)
			(size 2.7432 1.016)
			(layers "F.Cu" "F.Mask" "F.Paste")
			(net "JTAG_MCP_TRST_N")
		)
		(pad "7" smd rect
			(at 0 5.999988)
			(size 2.7432 1.016)
			(layers "F.Cu" "F.Mask" "F.Paste")
			(net "PWRGD_CPU0_G_R")
		)
		(pad "8" smd rect
			(at 4.2418 5.999988)
			(size 2.7432 1.016)
			(layers "F.Cu" "F.Mask" "F.Paste")
			(net "TP_JTAG_MCP_IO8_RSVD")
		)
		(pad "9" smd rect
			(at 0 7.999984)
			(size 2.7432 1.016)
			(layers "F.Cu" "F.Mask" "F.Paste")
			(net "JTAG_MCP_MUX_TDI")
		)
		(pad "10" smd rect
			(at 4.2418 7.999984)
			(size 2.7432 1.016)
			(layers "F.Cu" "F.Mask" "F.Paste")
			(net "GND")
		)
		(zone
			(layers "F.Cu" "B.Cu" "In1.Cu" "In2.Cu" "In3.Cu" "In4.Cu" "In5.Cu" "In6.Cu"
				"In7.Cu" "In8.Cu" "In9.Cu" "In10.Cu" "In11.Cu" "In12.Cu"
			)
			(hatch none 0.5)
			(connect_pads
				(clearance 0)
			)
			(min_thickness 0.25)
			(keepout
				(tracks allowed)
				(vias not_allowed)
				(pads allowed)
				(copperpour not_allowed)
				(footprints allowed)
			)
			(placement
				(enabled no)
				(sheetname "")
			)
			(fill
				(thermal_gap 0.5)
				(thermal_bridge_width 0.5)
				(island_removal_mode 0)
			)
			(polygon
				(pts
					(arc
						(start 473.228416 -133.366002)
						(mid 471.577416 -133.366002)
						(end 473.228416 -133.366002)
					)
				)
			)
		)
		(zone
			(layers "F.Cu" "B.Cu" "In1.Cu" "In2.Cu" "In3.Cu" "In4.Cu" "In5.Cu" "In6.Cu"
				"In7.Cu" "In8.Cu" "In9.Cu" "In10.Cu" "In11.Cu" "In12.Cu"
			)
			(hatch none 0.5)
			(connect_pads
				(clearance 0)
			)
			(min_thickness 0.25)
			(keepout
				(tracks not_allowed)
				(vias allowed)
				(pads allowed)
				(copperpour not_allowed)
				(footprints allowed)
			)
			(placement
				(enabled no)
				(sheetname "")
			)
			(fill
				(thermal_gap 0.5)
				(thermal_bridge_width 0.5)
				(island_removal_mode 0)
			)
			(polygon
				(pts
					(arc
						(start 473.228416 -133.366002)
						(mid 471.577416 -133.366002)
						(end 473.228416 -133.366002)
					)
				)
			)
		)
		(zone
			(layers "F.Cu" "B.Cu" "In1.Cu" "In2.Cu" "In3.Cu" "In4.Cu" "In5.Cu" "In6.Cu"
				"In7.Cu" "In8.Cu" "In9.Cu" "In10.Cu" "In11.Cu" "In12.Cu"
			)
			(hatch none 0.5)
			(connect_pads
				(clearance 0)
			)
			(min_thickness 0.25)
			(keepout
				(tracks allowed)
				(vias not_allowed)
				(pads allowed)
				(copperpour not_allowed)
				(footprints allowed)
			)
			(placement
				(enabled no)
				(sheetname "")
			)
			(fill
				(thermal_gap 0.5)
				(thermal_bridge_width 0.5)
				(island_removal_mode 0)
			)
			(polygon
				(pts
					(arc
						(start 473.228416 -127.366014)
						(mid 471.577416 -127.366014)
						(end 473.228416 -127.366014)
					)
				)
			)
		)
		(zone
			(layers "F.Cu" "B.Cu" "In1.Cu" "In2.Cu" "In3.Cu" "In4.Cu" "In5.Cu" "In6.Cu"
				"In7.Cu" "In8.Cu" "In9.Cu" "In10.Cu" "In11.Cu" "In12.Cu"
			)
			(hatch none 0.5)
			(connect_pads
				(clearance 0)
			)
			(min_thickness 0.25)
			(keepout
				(tracks not_allowed)
				(vias allowed)
				(pads allowed)
				(copperpour not_allowed)
				(footprints allowed)
			)
			(placement
				(enabled no)
				(sheetname "")
			)
			(fill
				(thermal_gap 0.5)
				(thermal_bridge_width 0.5)
				(island_removal_mode 0)
			)
			(polygon
				(pts
					(arc
						(start 473.228416 -127.366014)
						(mid 471.577416 -127.366014)
						(end 473.228416 -127.366014)
					)
				)
			)
		)
	)
	(footprint ""
		(layer "F.Cu")
		(at 494.18494 -124.25172 90)
		(property "Reference" "R1M9"
			(at 0 0 90)
			(layer "F.SilkS")
			(hide yes)
			(effects
				(font
					(size 1.27 1.27)
				)
			)
		)
		(property "Value" ""
			(at 0 0 90)
			(layer "F.Fab")
			(effects
				(font
					(size 1.27 1.27)
				)
			)
		)
		(duplicate_pad_numbers_are_jumpers no)
		(fp_rect
			(start 0.2794 -0.1016)
			(end -0.2794 0.9906)
			(stroke
				(width 0)
				(type default)
			)
			(fill no)
			(layer "F.CrtYd")
		)
		(fp_line
			(start 0.2794 -0.1016)
			(end -0.2794 -0.1016)
			(stroke
				(width 0.1)
				(type default)
			)
			(layer "F.Fab")
		)
		(fp_line
			(start -0.2794 -0.1016)
			(end -0.2794 0.9906)
			(stroke
				(width 0.1)
				(type default)
			)
			(layer "F.Fab")
		)
		(fp_line
			(start 0.2794 0.9906)
			(end 0.2794 -0.1016)
			(stroke
				(width 0.1)
				(type default)
			)
			(layer "F.Fab")
		)
		(fp_line
			(start -0.2794 0.9906)
			(end 0.2794 0.9906)
			(stroke
				(width 0.1)
				(type default)
			)
			(layer "F.Fab")
		)
		(pad "1" smd rect
			(at 0 0 90)
			(size 0.508 0.508)
			(layers "F.Cu" "F.Mask" "F.Paste")
			(net "SMB_SENSOR_TMP421_1_SDA")
		)
		(pad "2" smd rect
			(at 0 0.889 90)
			(size 0.508 0.508)
			(layers "F.Cu" "F.Mask" "F.Paste")
			(net "SMB_SENSOR_STBY_LVC3_SDA")
		)
		(zone
			(layer "F.Cu")
			(hatch none 0.5)
			(connect_pads
				(clearance 0)
			)
			(min_thickness 0.25)
			(keepout
				(tracks not_allowed)
				(vias allowed)
				(pads allowed)
				(copperpour not_allowed)
				(footprints allowed)
			)
			(placement
				(enabled no)
				(sheetname "")
			)
			(fill
				(thermal_gap 0.5)
				(thermal_bridge_width 0.5)
				(island_removal_mode 0)
			)
			(polygon
				(pts
					(xy 494.43894 -124.50572) (xy 494.43894 -123.99772) (xy 494.81994 -123.99772) (xy 494.81994 -124.50572)
				)
			)
		)
		(zone
			(layer "F.Cu")
			(hatch none 0.5)
			(connect_pads
				(clearance 0)
			)
			(min_thickness 0.25)
			(keepout
				(tracks allowed)
				(vias not_allowed)
				(pads allowed)
				(copperpour not_allowed)
				(footprints allowed)
			)
			(placement
				(enabled no)
				(sheetname "")
			)
			(fill
				(thermal_gap 0.5)
				(thermal_bridge_width 0.5)
				(island_removal_mode 0)
			)
			(polygon
				(pts
					(xy 494.43894 -124.50572) (xy 494.43894 -123.99772) (xy 494.81994 -123.99772) (xy 494.81994 -124.50572)
				)
			)
		)
	)
	(footprint ""
		(layer "F.Cu")
		(at 193.0146 -98.7298 90)
		(property "Reference" "RT40"
			(at 1.01473 0.656336 0)
			(unlocked yes)
			(layer "F.SilkS")
			(effects
				(font
					(size 0.4064 0.254)
					(thickness 0.1524)
				)
			)
		)
		(property "Value" ""
			(at 0 0 90)
			(layer "F.Fab")
			(effects
				(font
					(size 1.27 1.27)
				)
			)
		)
		(duplicate_pad_numbers_are_jumpers no)
		(fp_poly
			(pts
				(xy -0.4953 -0.2032) (xy 0.4953 -0.2032) (xy 0.4953 1.6002) (xy -0.4953 1.6002)
			)
			(stroke
				(width 0)
				(type default)
			)
			(fill no)
			(layer "F.CrtYd")
		)
		(fp_line
			(start 0.4953 -0.2032)
			(end 0.4953 1.6002)
			(stroke
				(width 0.1)
				(type default)
			)
			(layer "F.Fab")
		)
		(fp_line
			(start -0.4953 -0.2032)
			(end 0.4953 -0.2032)
			(stroke
				(width 0.1)
				(type default)
			)
			(layer "F.Fab")
		)
		(fp_line
			(start 0.4953 1.6002)
			(end -0.4953 1.6002)
			(stroke
				(width 0.1)
				(type default)
			)
			(layer "F.Fab")
		)
		(fp_line
			(start -0.4953 1.6002)
			(end -0.4953 -0.2032)
			(stroke
				(width 0.1)
				(type default)
			)
			(layer "F.Fab")
		)
		(pad "1" smd rect
			(at 0 0 90)
			(size 0.762 0.889)
			(layers "F.Cu" "F.Mask" "F.Paste")
			(net "VR_PVSA_CPU0_BOOT")
		)
		(pad "2" smd rect
			(at 0 1.397 90)
			(size 0.762 0.889)
			(layers "F.Cu" "F.Mask" "F.Paste")
			(net "VR_PVSA_CPU0_BOOT_R")
		)
		(zone
			(layer "F.Cu")
			(hatch none 0.5)
			(connect_pads
				(clearance 0)
			)
			(min_thickness 0.25)
			(keepout
				(tracks allowed)
				(vias not_allowed)
				(pads allowed)
				(copperpour not_allowed)
				(footprints allowed)
			)
			(placement
				(enabled no)
				(sheetname "")
			)
			(fill
				(thermal_gap 0.5)
				(thermal_bridge_width 0.5)
				(island_removal_mode 0)
			)
			(polygon
				(pts
					(xy 193.9671 -99.1108) (xy 193.4591 -99.1108) (xy 193.4591 -98.3488) (xy 193.9671 -98.3488)
				)
			)
		)
		(zone
			(layer "F.Cu")
			(hatch none 0.5)
			(connect_pads
				(clearance 0)
			)
			(min_thickness 0.25)
			(keepout
				(tracks not_allowed)
				(vias allowed)
				(pads allowed)
				(copperpour not_allowed)
				(footprints allowed)
			)
			(placement
				(enabled no)
				(sheetname "")
			)
			(fill
				(thermal_gap 0.5)
				(thermal_bridge_width 0.5)
				(island_removal_mode 0)
			)
			(polygon
				(pts
					(xy 193.9671 -98.3488) (xy 193.9671 -99.1108) (xy 193.4591 -99.1108) (xy 193.4591 -98.3488)
				)
			)
		)
	)
	(footprint ""
		(layer "F.Cu")
		(at 431.378868 -125.941582 -90)
		(property "Reference" "C8B12"
			(at 0 0 270)
			(layer "F.SilkS")
			(hide yes)
			(effects
				(font
					(size 1.27 1.27)
				)
			)
		)
		(property "Value" ""
			(at 0 0 270)
			(layer "F.Fab")
			(effects
				(font
					(size 1.27 1.27)
				)
			)
		)
		(duplicate_pad_numbers_are_jumpers no)
		(fp_poly
			(pts
				(xy -0.7239 -0.2159) (xy 0.7239 -0.2159) (xy 0.7239 1.9939) (xy -0.7239 1.9939)
			)
			(stroke
				(width 0)
				(type default)
			)
			(fill no)
			(layer "F.CrtYd")
		)
		(fp_line
			(start -0.7239 1.9939)
			(end 0.7239 1.9939)
			(stroke
				(width 0.1)
				(type default)
			)
			(layer "F.Fab")
		)
		(fp_line
			(start 0.7239 1.9939)
			(end 0.7239 -0.2159)
			(stroke
				(width 0.1)
				(type default)
			)
			(layer "F.Fab")
		)
		(fp_line
			(start -0.7239 -0.2159)
			(end -0.7239 1.9939)
			(stroke
				(width 0.1)
				(type default)
			)
			(layer "F.Fab")
		)
		(fp_line
			(start 0.7239 -0.2159)
			(end -0.7239 -0.2159)
			(stroke
				(width 0.1)
				(type default)
			)
			(layer "F.Fab")
		)
		(pad "1" smd rect
			(at 0 0 270)
			(size 1.27 1.016)
			(layers "F.Cu" "F.Mask" "F.Paste")
			(net "P5V_STBY")
		)
		(pad "2" smd rect
			(at 0 1.778 270)
			(size 1.27 1.016)
			(layers "F.Cu" "F.Mask" "F.Paste")
			(net "GND")
		)
		(zone
			(layer "F.Cu")
			(hatch none 0.5)
			(connect_pads
				(clearance 0)
			)
			(min_thickness 0.25)
			(keepout
				(tracks not_allowed)
				(vias allowed)
				(pads allowed)
				(copperpour not_allowed)
				(footprints allowed)
			)
			(placement
				(enabled no)
				(sheetname "")
			)
			(fill
				(thermal_gap 0.5)
				(thermal_bridge_width 0.5)
				(island_removal_mode 0)
			)
			(polygon
				(pts
					(xy 430.870868 -126.576582) (xy 430.870868 -125.306582) (xy 430.108868 -125.306582) (xy 430.108868 -126.576582)
				)
			)
		)
	)
	(footprint ""
		(layer "F.Cu")
		(at 15.370048 -118.679976 -90)
		(property "Reference" "J1B2"
			(at -1.9558 15.89913 90)
			(unlocked yes)
			(layer "F.SilkS")
			(effects
				(font
					(size 0.7874 0.5842)
					(thickness 0.1524)
				)
			)
		)
		(property "Value" ""
			(at 0 0 270)
			(layer "F.Fab")
			(effects
				(font
					(size 1.27 1.27)
				)
			)
		)
		(duplicate_pad_numbers_are_jumpers no)
		(fp_line
			(start -3.47472 14.14526)
			(end 2.71526 14.14526)
			(stroke
				(width 0.1524)
				(type default)
			)
			(layer "F.SilkS")
		)
		(fp_line
			(start 2.71526 14.14526)
			(end 2.71526 6.1722)
			(stroke
				(width 0.1524)
				(type default)
			)
			(layer "F.SilkS")
		)
		(fp_line
			(start 2.71526 3.9878)
			(end 2.71526 -1.44526)
			(stroke
				(width 0.1524)
				(type default)
			)
			(layer "F.SilkS")
		)
		(fp_line
			(start -3.47472 -1.44526)
			(end -3.47472 14.14526)
			(stroke
				(width 0.1524)
				(type default)
			)
			(layer "F.SilkS")
		)
		(fp_line
			(start 2.71526 -1.44526)
			(end -3.47472 -1.44526)
			(stroke
				(width 0.1524)
				(type default)
			)
			(layer "F.SilkS")
		)
		(fp_poly
			(pts
				(xy -5.2578 0.4445) (xy -5.2578 -0.5715) (xy -3.9878 -0.0635)
			)
			(stroke
				(width 0)
				(type default)
			)
			(fill yes)
			(layer "F.SilkS")
		)
		(fp_poly
			(pts
				(xy -2.4511 -0.13716) (xy -2.4511 -1.15316) (xy -1.1811 -0.64516)
			)
			(stroke
				(width 0)
				(type default)
			)
			(fill yes)
			(layer "B.SilkS")
		)
		(fp_poly
			(pts
				(xy 2.71526 -1.44526) (xy 2.71526 14.14526) (xy -3.47472 14.14526) (xy -3.47472 -1.44526)
			)
			(stroke
				(width 0)
				(type default)
			)
			(fill no)
			(layer "F.CrtYd")
		)
		(fp_poly
			(pts
				(xy -5.27558 0.4445) (xy -5.27558 -0.5715) (xy -4.00558 -0.0635)
			)
			(stroke
				(width 0)
				(type default)
			)
			(fill yes)
			(layer "B.Fab")
		)
		(fp_line
			(start -3.47472 14.14526)
			(end -3.47472 -1.44526)
			(stroke
				(width 0.1)
				(type default)
			)
			(layer "F.Fab")
		)
		(fp_line
			(start 2.71526 14.14526)
			(end -3.47472 14.14526)
			(stroke
				(width 0.1)
				(type default)
			)
			(layer "F.Fab")
		)
		(fp_line
			(start -3.47472 -1.44526)
			(end 2.71526 -1.44526)
			(stroke
				(width 0.1)
				(type default)
			)
			(layer "F.Fab")
		)
		(fp_line
			(start 2.71526 -1.44526)
			(end 2.71526 14.14526)
			(stroke
				(width 0.1)
				(type default)
			)
			(layer "F.Fab")
		)
		(fp_poly
			(pts
				(xy -5.2578 0.4445) (xy -5.2578 -0.5715) (xy -3.9878 -0.0635)
			)
			(stroke
				(width 0)
				(type default)
			)
			(fill yes)
			(layer "F.Fab")
		)
		(fp_text user "6"
			(at -3.434334 15.171928 0)
			(unlocked yes)
			(layer "F.SilkS")
			(effects
				(font
					(size 0.7874 0.5842)
					(thickness 0.1524)
				)
			)
		)
		(fp_text user "6"
			(at -3.628644 13.098018 270)
			(unlocked yes)
			(layer "B.SilkS")
			(effects
				(font
					(size 0.7874 0.5842)
					(thickness 0.1524)
				)
				(justify mirror)
			)
		)
		(fp_text user "6"
			(at -4.08178 12.91209 270)
			(unlocked yes)
			(layer "B.Fab")
			(effects
				(font
					(size 0.7874 0.5842)
					(thickness 0.1524)
				)
				(justify mirror)
			)
		)
		(fp_text user "6"
			(at -1.462024 -1.9939 270)
			(unlocked yes)
			(layer "F.Fab")
			(effects
				(font
					(size 0.7874 0.5842)
					(thickness 0.1524)
				)
			)
		)
		(pad "" np_thru_hole circle
			(at 2.159 5.08 270)
			(size 0.254 0.254)
			(drill 1.4986)
			(layers "*.Cu" "*.Mask")
			(clearance 0.9398)
			(thermal_gap 0.9398)
		)
		(pad "1" thru_hole rect
			(at 0 0 270)
			(size 1.524 1.524)
			(drill 1.143)
			(layers "*.Cu" "*.Mask")
			(remove_unused_layers no)
			(net "GND")
			(clearance 0.127)
			(thermal_gap 0.127)
			(padstack
				(mode front_inner_back)
				(layer "Inner"
					(shape circle)
					(size 1.524 1.524)
					(clearance 0.127)
				)
				(layer "B.Cu"
					(shape rect)
					(size 1.524 1.524)
					(clearance 0.127)
				)
			)
		)
		(pad "2" thru_hole circle
			(at 0 2.54 270)
			(size 1.524 1.524)
			(drill 1.143)
			(layers "*.Cu" "*.Mask")
			(remove_unused_layers no)
			(net "P12V_PUMP")
			(clearance 0.127)
			(thermal_gap 0.127)
		)
		(pad "3" thru_hole circle
			(at 0 5.08 270)
			(size 1.524 1.524)
			(drill 1.143)
			(layers "*.Cu" "*.Mask")
			(remove_unused_layers no)
			(net "PUMP_TACH_D")
			(clearance 0.127)
			(thermal_gap 0.127)
		)
		(pad "4" thru_hole circle
			(at 0 7.62 270)
			(size 1.524 1.524)
			(drill 1.143)
			(layers "*.Cu" "*.Mask")
			(remove_unused_layers no)
			(net "PUMP_PWM_OUT_R")
			(clearance 0.127)
			(thermal_gap 0.127)
		)
		(pad "5" thru_hole circle
			(at 0 10.16 270)
			(size 1.524 1.524)
			(drill 1.143)
			(layers "*.Cu" "*.Mask")
			(remove_unused_layers no)
			(net "PUMP_TACH1_D")
			(clearance 0.127)
			(thermal_gap 0.127)
		)
		(pad "6" thru_hole circle
			(at 0 12.7 270)
			(size 1.524 1.524)
			(drill 1.143)
			(layers "*.Cu" "*.Mask")
			(remove_unused_layers no)
			(net "TP_PUMP")
			(clearance 0.127)
			(thermal_gap 0.127)
		)
		(zone
			(layers "F.Cu" "B.Cu" "In1.Cu" "In2.Cu" "In3.Cu" "In4.Cu" "In5.Cu" "In6.Cu"
				"In7.Cu" "In8.Cu" "In9.Cu" "In10.Cu" "In11.Cu" "In12.Cu"
			)
			(hatch none 0.5)
			(connect_pads
				(clearance 0)
			)
			(min_thickness 0.25)
			(keepout
				(tracks not_allowed)
				(vias allowed)
				(pads allowed)
				(copperpour not_allowed)
				(footprints allowed)
			)
			(placement
				(enabled no)
				(sheetname "")
			)
			(fill
				(thermal_gap 0.5)
				(thermal_bridge_width 0.5)
				(island_removal_mode 0)
			)
			(polygon
				(pts
					(arc
						(start 11.356848 -116.520976)
						(mid 9.223248 -116.520976)
						(end 11.356848 -116.520976)
					)
				)
			)
		)
	)
	(footprint ""
		(layer "F.Cu")
		(at 399.6182 1.7272 90)
		(property "Reference" "R8G23"
			(at 0 0 90)
			(layer "F.SilkS")
			(hide yes)
			(effects
				(font
					(size 1.27 1.27)
				)
			)
		)
		(property "Value" ""
			(at 0 0 90)
			(layer "F.Fab")
			(effects
				(font
					(size 1.27 1.27)
				)
			)
		)
		(duplicate_pad_numbers_are_jumpers no)
		(fp_poly
			(pts
				(xy -0.2794 -0.1016) (xy 0.2794 -0.1016) (xy 0.2794 0.9906) (xy -0.2794 0.9906)
			)
			(stroke
				(width 0)
				(type default)
			)
			(fill no)
			(layer "F.CrtYd")
		)
		(fp_line
			(start 0.2794 -0.1016)
			(end -0.2794 -0.1016)
			(stroke
				(width 0.1)
				(type default)
			)
			(layer "F.Fab")
		)
		(fp_line
			(start -0.2794 -0.1016)
			(end -0.2794 0.9906)
			(stroke
				(width 0.1)
				(type default)
			)
			(layer "F.Fab")
		)
		(fp_line
			(start 0.2794 0.9906)
			(end 0.2794 -0.1016)
			(stroke
				(width 0.1)
				(type default)
			)
			(layer "F.Fab")
		)
		(fp_line
			(start -0.2794 0.9906)
			(end 0.2794 0.9906)
			(stroke
				(width 0.1)
				(type default)
			)
			(layer "F.Fab")
		)
		(pad "1" smd rect
			(at 0 0 90)
			(size 0.508 0.508)
			(layers "F.Cu" "F.Mask" "F.Paste")
			(net "JTAG_TCK_R")
		)
		(pad "2" smd rect
			(at 0 0.889 90)
			(size 0.508 0.508)
			(layers "F.Cu" "F.Mask" "F.Paste")
			(net "GND")
		)
		(zone
			(layer "F.Cu")
			(hatch none 0.5)
			(connect_pads
				(clearance 0)
			)
			(min_thickness 0.25)
			(keepout
				(tracks allowed)
				(vias not_allowed)
				(pads allowed)
				(copperpour not_allowed)
				(footprints allowed)
			)
			(placement
				(enabled no)
				(sheetname "")
			)
			(fill
				(thermal_gap 0.5)
				(thermal_bridge_width 0.5)
				(island_removal_mode 0)
			)
			(polygon
				(pts
					(xy 399.8722 1.9812) (xy 399.8722 1.4732) (xy 400.2532 1.4732) (xy 400.2532 1.9812)
				)
			)
		)
		(zone
			(layer "F.Cu")
			(hatch none 0.5)
			(connect_pads
				(clearance 0)
			)
			(min_thickness 0.25)
			(keepout
				(tracks not_allowed)
				(vias allowed)
				(pads allowed)
				(copperpour not_allowed)
				(footprints allowed)
			)
			(placement
				(enabled no)
				(sheetname "")
			)
			(fill
				(thermal_gap 0.5)
				(thermal_bridge_width 0.5)
				(island_removal_mode 0)
			)
			(polygon
				(pts
					(xy 400.2532 1.9812) (xy 400.2532 1.4732) (xy 399.8722 1.4732) (xy 399.8722 1.9812)
				)
			)
		)
	)
	(footprint ""
		(layer "F.Cu")
		(at 155.6512 -118.364 90)
		(property "Reference" "R3B5"
			(at 0 0 90)
			(layer "F.SilkS")
			(hide yes)
			(effects
				(font
					(size 1.27 1.27)
				)
			)
		)
		(property "Value" ""
			(at 0 0 90)
			(layer "F.Fab")
			(effects
				(font
					(size 1.27 1.27)
				)
			)
		)
		(duplicate_pad_numbers_are_jumpers no)
		(fp_poly
			(pts
				(xy -0.2794 -0.1016) (xy 0.2794 -0.1016) (xy 0.2794 0.9906) (xy -0.2794 0.9906)
			)
			(stroke
				(width 0)
				(type default)
			)
			(fill no)
			(layer "F.CrtYd")
		)
		(fp_line
			(start 0.2794 -0.1016)
			(end -0.2794 -0.1016)
			(stroke
				(width 0.1)
				(type default)
			)
			(layer "F.Fab")
		)
		(fp_line
			(start -0.2794 -0.1016)
			(end -0.2794 0.9906)
			(stroke
				(width 0.1)
				(type default)
			)
			(layer "F.Fab")
		)
		(fp_line
			(start 0.2794 0.9906)
			(end 0.2794 -0.1016)
			(stroke
				(width 0.1)
				(type default)
			)
			(layer "F.Fab")
		)
		(fp_line
			(start -0.2794 0.9906)
			(end 0.2794 0.9906)
			(stroke
				(width 0.1)
				(type default)
			)
			(layer "F.Fab")
		)
		(pad "1" smd rect
			(at 0 0 90)
			(size 0.508 0.508)
			(layers "F.Cu" "F.Mask" "F.Paste")
			(net "SVID_CLK0_CPU1")
		)
		(pad "2" smd rect
			(at 0 0.889 90)
			(size 0.508 0.508)
			(layers "F.Cu" "F.Mask" "F.Paste")
			(net "SVID_CLK0_CPU1_R")
		)
		(zone
			(layer "F.Cu")
			(hatch none 0.5)
			(connect_pads
				(clearance 0)
			)
			(min_thickness 0.25)
			(keepout
				(tracks allowed)
				(vias not_allowed)
				(pads allowed)
				(copperpour not_allowed)
				(footprints allowed)
			)
			(placement
				(enabled no)
				(sheetname "")
			)
			(fill
				(thermal_gap 0.5)
				(thermal_bridge_width 0.5)
				(island_removal_mode 0)
			)
			(polygon
				(pts
					(xy 155.9052 -118.11) (xy 155.9052 -118.618) (xy 156.2862 -118.618) (xy 156.2862 -118.11)
				)
			)
		)
		(zone
			(layer "F.Cu")
			(hatch none 0.5)
			(connect_pads
				(clearance 0)
			)
			(min_thickness 0.25)
			(keepout
				(tracks not_allowed)
				(vias allowed)
				(pads allowed)
				(copperpour not_allowed)
				(footprints allowed)
			)
			(placement
				(enabled no)
				(sheetname "")
			)
			(fill
				(thermal_gap 0.5)
				(thermal_bridge_width 0.5)
				(island_removal_mode 0)
			)
			(polygon
				(pts
					(xy 156.2862 -118.11) (xy 156.2862 -118.618) (xy 155.9052 -118.618) (xy 155.9052 -118.11)
				)
			)
		)
	)
	(footprint ""
		(layer "F.Cu")
		(at 21.863812 -68.6943)
		(property "Reference" "C1W16"
			(at -0.8382 -0.67818 0)
			(unlocked yes)
			(layer "F.SilkS")
			(effects
				(font
					(size 0.4064 0.254)
					(thickness 0.1524)
				)
				(justify left)
			)
		)
		(property "Value" ""
			(at 0 0 0)
			(layer "F.Fab")
			(effects
				(font
					(size 1.27 1.27)
				)
			)
		)
		(duplicate_pad_numbers_are_jumpers no)
		(fp_poly
			(pts
				(xy 0.3048 -0.1016) (xy 0.3048 0.9906) (xy -0.3048 0.9906) (xy -0.3048 -0.1016)
			)
			(stroke
				(width 0)
				(type default)
			)
			(fill no)
			(layer "F.CrtYd")
		)
		(fp_line
			(start -0.3048 -0.1016)
			(end -0.3048 0.9906)
			(stroke
				(width 0.1)
				(type default)
			)
			(layer "F.Fab")
		)
		(fp_line
			(start -0.3048 0.9906)
			(end 0.3048 0.9906)
			(stroke
				(width 0.1)
				(type default)
			)
			(layer "F.Fab")
		)
		(fp_line
			(start 0.3048 -0.1016)
			(end -0.3048 -0.1016)
			(stroke
				(width 0.1)
				(type default)
			)
			(layer "F.Fab")
		)
		(fp_line
			(start 0.3048 0.9906)
			(end 0.3048 -0.1016)
			(stroke
				(width 0.1)
				(type default)
			)
			(layer "F.Fab")
		)
		(pad "1" smd rect
			(at 0 0)
			(size 0.508 0.508)
			(layers "F.Cu" "F.Mask" "F.Paste")
			(net "A_HSC_TEMP")
		)
		(pad "2" smd rect
			(at 0 0.889)
			(size 0.508 0.508)
			(layers "F.Cu" "F.Mask" "F.Paste")
			(net "GND")
		)
		(zone
			(layer "F.Cu")
			(hatch none 0.5)
			(connect_pads
				(clearance 0)
			)
			(min_thickness 0.25)
			(keepout
				(tracks allowed)
				(vias not_allowed)
				(pads allowed)
				(copperpour not_allowed)
				(footprints allowed)
			)
			(placement
				(enabled no)
				(sheetname "")
			)
			(fill
				(thermal_gap 0.5)
				(thermal_bridge_width 0.5)
				(island_removal_mode 0)
			)
			(polygon
				(pts
					(xy 21.609812 -68.4403) (xy 22.117812 -68.4403) (xy 22.117812 -68.0593) (xy 21.609812 -68.0593)
				)
			)
		)
		(zone
			(layer "F.Cu")
			(hatch none 0.5)
			(connect_pads
				(clearance 0)
			)
			(min_thickness 0.25)
			(keepout
				(tracks not_allowed)
				(vias allowed)
				(pads allowed)
				(copperpour not_allowed)
				(footprints allowed)
			)
			(placement
				(enabled no)
				(sheetname "")
			)
			(fill
				(thermal_gap 0.5)
				(thermal_bridge_width 0.5)
				(island_removal_mode 0)
			)
			(polygon
				(pts
					(xy 21.609812 -68.0593) (xy 22.117812 -68.0593) (xy 22.117812 -68.4403) (xy 21.609812 -68.4403)
				)
			)
		)
	)
	(footprint ""
		(layer "F.Cu")
		(at 489.3056 -153.3398)
		(property "Reference" "CR9W1"
			(at 1.06934 -0.39116 270)
			(unlocked yes)
			(layer "F.SilkS")
			(effects
				(font
					(size 0.4064 0.254)
					(thickness 0.1524)
				)
				(justify left)
			)
		)
		(property "Value" ""
			(at 0 0 0)
			(layer "F.Fab")
			(effects
				(font
					(size 1.27 1.27)
				)
			)
		)
		(duplicate_pad_numbers_are_jumpers no)
		(fp_line
			(start -1.8161 1.664462)
			(end -1.335278 0.831596)
			(stroke
				(width 0.1524)
				(type default)
			)
			(layer "F.SilkS")
		)
		(fp_line
			(start -1.335278 -0.291846)
			(end -1.335278 0.831596)
			(stroke
				(width 0.1524)
				(type default)
			)
			(layer "F.SilkS")
		)
		(fp_line
			(start -1.335278 0.831596)
			(end -0.854456 1.664462)
			(stroke
				(width 0.1524)
				(type default)
			)
			(layer "F.SilkS")
		)
		(fp_line
			(start -1.335278 1.664462)
			(end -1.8161 1.664462)
			(stroke
				(width 0.1524)
				(type default)
			)
			(layer "F.SilkS")
		)
		(fp_line
			(start -1.335278 2.576068)
			(end -1.335278 1.664462)
			(stroke
				(width 0.1524)
				(type default)
			)
			(layer "F.SilkS")
		)
		(fp_line
			(start -0.854456 0.831596)
			(end -1.8161 0.831596)
			(stroke
				(width 0.1524)
				(type default)
			)
			(layer "F.SilkS")
		)
		(fp_line
			(start -0.854456 1.664462)
			(end -1.335278 1.664462)
			(stroke
				(width 0.1524)
				(type default)
			)
			(layer "F.SilkS")
		)
		(fp_poly
			(pts
				(xy -0.67437 0.24384) (xy -0.67437 2.04216) (xy 0.67437 2.04216) (xy 0.67437 0.24384)
			)
			(stroke
				(width 0)
				(type default)
			)
			(fill no)
			(layer "F.CrtYd")
		)
		(fp_line
			(start -1.8161 1.664462)
			(end -1.335278 0.831596)
			(stroke
				(width 0.1)
				(type default)
			)
			(layer "F.Fab")
		)
		(fp_line
			(start -1.335278 0.831596)
			(end -1.335278 -0.291846)
			(stroke
				(width 0.1)
				(type default)
			)
			(layer "F.Fab")
		)
		(fp_line
			(start -1.335278 0.831596)
			(end -0.854456 1.664462)
			(stroke
				(width 0.1)
				(type default)
			)
			(layer "F.Fab")
		)
		(fp_line
			(start -1.335278 1.664462)
			(end -1.335278 2.576068)
			(stroke
				(width 0.1)
				(type default)
			)
			(layer "F.Fab")
		)
		(fp_line
			(start -0.854456 0.831596)
			(end -1.8161 0.831596)
			(stroke
				(width 0.1)
				(type default)
			)
			(layer "F.Fab")
		)
		(fp_line
			(start -0.854456 1.664462)
			(end -1.8161 1.664462)
			(stroke
				(width 0.1)
				(type default)
			)
			(layer "F.Fab")
		)
		(fp_line
			(start -0.67437 0.24384)
			(end -0.67437 2.04216)
			(stroke
				(width 0.1)
				(type default)
			)
			(layer "F.Fab")
		)
		(fp_line
			(start -0.67437 2.04216)
			(end 0.67437 2.04216)
			(stroke
				(width 0.1)
				(type default)
			)
			(layer "F.Fab")
		)
		(fp_line
			(start 0.67437 0.24384)
			(end -0.67437 0.24384)
			(stroke
				(width 0.1)
				(type default)
			)
			(layer "F.Fab")
		)
		(fp_line
			(start 0.67437 2.04216)
			(end 0.67437 0.24384)
			(stroke
				(width 0.1)
				(type default)
			)
			(layer "F.Fab")
		)
		(pad "1" smd rect
			(at 0 0)
			(size 0.4064 1.016)
			(layers "F.Cu" "F.Mask" "F.Paste")
			(net "SPA_5V_SIN_SW")
		)
		(pad "2" smd rect
			(at 0 2.286)
			(size 0.4064 1.016)
			(layers "F.Cu" "F.Mask" "F.Paste")
			(net "SPA_5V_SIN_SW_D")
		)
	)
	(footprint ""
		(layer "F.Cu")
		(at 193.662808 -96.707452 -90)
		(property "Reference" "R4C13"
			(at 0 0 270)
			(layer "F.SilkS")
			(hide yes)
			(effects
				(font
					(size 1.27 1.27)
				)
			)
		)
		(property "Value" ""
			(at 0 0 270)
			(layer "F.Fab")
			(effects
				(font
					(size 1.27 1.27)
				)
			)
		)
		(duplicate_pad_numbers_are_jumpers no)
		(fp_poly
			(pts
				(xy -0.2794 -0.1016) (xy 0.2794 -0.1016) (xy 0.2794 0.9906) (xy -0.2794 0.9906)
			)
			(stroke
				(width 0)
				(type default)
			)
			(fill no)
			(layer "F.CrtYd")
		)
		(fp_line
			(start -0.2794 0.9906)
			(end 0.2794 0.9906)
			(stroke
				(width 0.1)
				(type default)
			)
			(layer "F.Fab")
		)
		(fp_line
			(start 0.2794 0.9906)
			(end 0.2794 -0.1016)
			(stroke
				(width 0.1)
				(type default)
			)
			(layer "F.Fab")
		)
		(fp_line
			(start -0.2794 -0.1016)
			(end -0.2794 0.9906)
			(stroke
				(width 0.1)
				(type default)
			)
			(layer "F.Fab")
		)
		(fp_line
			(start 0.2794 -0.1016)
			(end -0.2794 -0.1016)
			(stroke
				(width 0.1)
				(type default)
			)
			(layer "F.Fab")
		)
		(pad "1" smd rect
			(at 0 0 270)
			(size 0.508 0.508)
			(layers "F.Cu" "F.Mask" "F.Paste")
			(net "VR_PVSA_CPU0_OCSET")
		)
		(pad "2" smd rect
			(at 0 0.889 270)
			(size 0.508 0.508)
			(layers "F.Cu" "F.Mask" "F.Paste")
			(net "GND")
		)
		(zone
			(layer "F.Cu")
			(hatch none 0.5)
			(connect_pads
				(clearance 0)
			)
			(min_thickness 0.25)
			(keepout
				(tracks not_allowed)
				(vias allowed)
				(pads allowed)
				(copperpour not_allowed)
				(footprints allowed)
			)
			(placement
				(enabled no)
				(sheetname "")
			)
			(fill
				(thermal_gap 0.5)
				(thermal_bridge_width 0.5)
				(island_removal_mode 0)
			)
			(polygon
				(pts
					(xy 193.027808 -96.961452) (xy 193.027808 -96.453452) (xy 193.408808 -96.453452) (xy 193.408808 -96.961452)
				)
			)
		)
		(zone
			(layer "F.Cu")
			(hatch none 0.5)
			(connect_pads
				(clearance 0)
			)
			(min_thickness 0.25)
			(keepout
				(tracks allowed)
				(vias not_allowed)
				(pads allowed)
				(copperpour not_allowed)
				(footprints allowed)
			)
			(placement
				(enabled no)
				(sheetname "")
			)
			(fill
				(thermal_gap 0.5)
				(thermal_bridge_width 0.5)
				(island_removal_mode 0)
			)
			(polygon
				(pts
					(xy 193.408808 -96.961452) (xy 193.408808 -96.453452) (xy 193.027808 -96.453452) (xy 193.027808 -96.961452)
				)
			)
		)
	)
	(footprint ""
		(layer "F.Cu")
		(at 394.6525 -79.375 90)
		(property "Reference" "C7D4"
			(at 0 0 90)
			(layer "F.SilkS")
			(hide yes)
			(effects
				(font
					(size 1.27 1.27)
				)
			)
		)
		(property "Value" ""
			(at 0 0 90)
			(layer "F.Fab")
			(effects
				(font
					(size 1.27 1.27)
				)
			)
		)
		(duplicate_pad_numbers_are_jumpers no)
		(fp_poly
			(pts
				(xy 0.3048 -0.1016) (xy 0.3048 0.9906) (xy -0.3048 0.9906) (xy -0.3048 -0.1016)
			)
			(stroke
				(width 0)
				(type default)
			)
			(fill no)
			(layer "F.CrtYd")
		)
		(fp_line
			(start 0.3048 -0.1016)
			(end -0.3048 -0.1016)
			(stroke
				(width 0.1)
				(type default)
			)
			(layer "F.Fab")
		)
		(fp_line
			(start -0.3048 -0.1016)
			(end -0.3048 0.9906)
			(stroke
				(width 0.1)
				(type default)
			)
			(layer "F.Fab")
		)
		(fp_line
			(start 0.3048 0.9906)
			(end 0.3048 -0.1016)
			(stroke
				(width 0.1)
				(type default)
			)
			(layer "F.Fab")
		)
		(fp_line
			(start -0.3048 0.9906)
			(end 0.3048 0.9906)
			(stroke
				(width 0.1)
				(type default)
			)
			(layer "F.Fab")
		)
		(pad "1" smd rect
			(at 0 0 90)
			(size 0.508 0.508)
			(layers "F.Cu" "F.Mask" "F.Paste")
			(net "P3V3")
		)
		(pad "2" smd rect
			(at 0 0.889 90)
			(size 0.508 0.508)
			(layers "F.Cu" "F.Mask" "F.Paste")
			(net "GND")
		)
		(zone
			(layer "F.Cu")
			(hatch none 0.5)
			(connect_pads
				(clearance 0)
			)
			(min_thickness 0.25)
			(keepout
				(tracks allowed)
				(vias not_allowed)
				(pads allowed)
				(copperpour not_allowed)
				(footprints allowed)
			)
			(placement
				(enabled no)
				(sheetname "")
			)
			(fill
				(thermal_gap 0.5)
				(thermal_bridge_width 0.5)
				(island_removal_mode 0)
			)
			(polygon
				(pts
					(xy 394.9065 -79.121) (xy 394.9065 -79.629) (xy 395.2875 -79.629) (xy 395.2875 -79.121)
				)
			)
		)
		(zone
			(layer "F.Cu")
			(hatch none 0.5)
			(connect_pads
				(clearance 0)
			)
			(min_thickness 0.25)
			(keepout
				(tracks not_allowed)
				(vias allowed)
				(pads allowed)
				(copperpour not_allowed)
				(footprints allowed)
			)
			(placement
				(enabled no)
				(sheetname "")
			)
			(fill
				(thermal_gap 0.5)
				(thermal_bridge_width 0.5)
				(island_removal_mode 0)
			)
			(polygon
				(pts
					(xy 395.2875 -79.121) (xy 395.2875 -79.629) (xy 394.9065 -79.629) (xy 394.9065 -79.121)
				)
			)
		)
	)
	(footprint ""
		(layer "F.Cu")
		(at 363.8804 -135.9916 90)
		(property "Reference" "R12W28"
			(at -0.8382 -0.67818 90)
			(unlocked yes)
			(layer "F.SilkS")
			(effects
				(font
					(size 0.4064 0.254)
					(thickness 0.1524)
				)
				(justify left)
			)
		)
		(property "Value" ""
			(at 0 0 90)
			(layer "F.Fab")
			(effects
				(font
					(size 1.27 1.27)
				)
			)
		)
		(duplicate_pad_numbers_are_jumpers no)
		(fp_poly
			(pts
				(xy -0.2794 -0.1016) (xy 0.2794 -0.1016) (xy 0.2794 0.9906) (xy -0.2794 0.9906)
			)
			(stroke
				(width 0)
				(type default)
			)
			(fill no)
			(layer "F.CrtYd")
		)
		(fp_line
			(start 0.2794 -0.1016)
			(end -0.2794 -0.1016)
			(stroke
				(width 0.1)
				(type default)
			)
			(layer "F.Fab")
		)
		(fp_line
			(start -0.2794 -0.1016)
			(end -0.2794 0.9906)
			(stroke
				(width 0.1)
				(type default)
			)
			(layer "F.Fab")
		)
		(fp_line
			(start 0.2794 0.9906)
			(end 0.2794 -0.1016)
			(stroke
				(width 0.1)
				(type default)
			)
			(layer "F.Fab")
		)
		(fp_line
			(start -0.2794 0.9906)
			(end 0.2794 0.9906)
			(stroke
				(width 0.1)
				(type default)
			)
			(layer "F.Fab")
		)
		(pad "1" smd rect
			(at 0 0 90)
			(size 0.508 0.508)
			(layers "F.Cu" "F.Mask" "F.Paste")
			(net "PU_VR_PVDDQ_DEF_FAULT1")
		)
		(pad "2" smd rect
			(at 0 0.889 90)
			(size 0.508 0.508)
			(layers "F.Cu" "F.Mask" "F.Paste")
			(net "PWRGD_PVDDQ_DEF")
		)
		(zone
			(layer "F.Cu")
			(hatch none 0.5)
			(connect_pads
				(clearance 0)
			)
			(min_thickness 0.25)
			(keepout
				(tracks allowed)
				(vias not_allowed)
				(pads allowed)
				(copperpour not_allowed)
				(footprints allowed)
			)
			(placement
				(enabled no)
				(sheetname "")
			)
			(fill
				(thermal_gap 0.5)
				(thermal_bridge_width 0.5)
				(island_removal_mode 0)
			)
			(polygon
				(pts
					(xy 364.1344 -135.7376) (xy 364.1344 -136.2456) (xy 364.5154 -136.2456) (xy 364.5154 -135.7376)
				)
			)
		)
		(zone
			(layer "F.Cu")
			(hatch none 0.5)
			(connect_pads
				(clearance 0)
			)
			(min_thickness 0.25)
			(keepout
				(tracks not_allowed)
				(vias allowed)
				(pads allowed)
				(copperpour not_allowed)
				(footprints allowed)
			)
			(placement
				(enabled no)
				(sheetname "")
			)
			(fill
				(thermal_gap 0.5)
				(thermal_bridge_width 0.5)
				(island_removal_mode 0)
			)
			(polygon
				(pts
					(xy 364.5154 -135.7376) (xy 364.5154 -136.2456) (xy 364.1344 -136.2456) (xy 364.1344 -135.7376)
				)
			)
		)
	)
	(footprint ""
		(layer "F.Cu")
		(at 399.770092 -0.998474 90)
		(property "Reference" "R7G14"
			(at 0 0 90)
			(layer "F.SilkS")
			(hide yes)
			(effects
				(font
					(size 1.27 1.27)
				)
			)
		)
		(property "Value" ""
			(at 0 0 90)
			(layer "F.Fab")
			(effects
				(font
					(size 1.27 1.27)
				)
			)
		)
		(duplicate_pad_numbers_are_jumpers no)
		(fp_poly
			(pts
				(xy -0.2794 -0.1016) (xy 0.2794 -0.1016) (xy 0.2794 0.9906) (xy -0.2794 0.9906)
			)
			(stroke
				(width 0)
				(type default)
			)
			(fill no)
			(layer "F.CrtYd")
		)
		(fp_line
			(start 0.2794 -0.1016)
			(end -0.2794 -0.1016)
			(stroke
				(width 0.1)
				(type default)
			)
			(layer "F.Fab")
		)
		(fp_line
			(start -0.2794 -0.1016)
			(end -0.2794 0.9906)
			(stroke
				(width 0.1)
				(type default)
			)
			(layer "F.Fab")
		)
		(fp_line
			(start 0.2794 0.9906)
			(end 0.2794 -0.1016)
			(stroke
				(width 0.1)
				(type default)
			)
			(layer "F.Fab")
		)
		(fp_line
			(start -0.2794 0.9906)
			(end 0.2794 0.9906)
			(stroke
				(width 0.1)
				(type default)
			)
			(layer "F.Fab")
		)
		(pad "1" smd rect
			(at 0 0 90)
			(size 0.508 0.508)
			(layers "F.Cu" "F.Mask" "F.Paste")
			(net "JTAG_PLD_TDO_MUX_R")
		)
		(pad "2" smd rect
			(at 0 0.889 90)
			(size 0.508 0.508)
			(layers "F.Cu" "F.Mask" "F.Paste")
			(net "JTAG_PLD_TDO_MUX")
		)
		(zone
			(layer "F.Cu")
			(hatch none 0.5)
			(connect_pads
				(clearance 0)
			)
			(min_thickness 0.25)
			(keepout
				(tracks allowed)
				(vias not_allowed)
				(pads allowed)
				(copperpour not_allowed)
				(footprints allowed)
			)
			(placement
				(enabled no)
				(sheetname "")
			)
			(fill
				(thermal_gap 0.5)
				(thermal_bridge_width 0.5)
				(island_removal_mode 0)
			)
			(polygon
				(pts
					(xy 400.024092 -0.744474) (xy 400.024092 -1.252474) (xy 400.405092 -1.252474) (xy 400.405092 -0.744474)
				)
			)
		)
		(zone
			(layer "F.Cu")
			(hatch none 0.5)
			(connect_pads
				(clearance 0)
			)
			(min_thickness 0.25)
			(keepout
				(tracks not_allowed)
				(vias allowed)
				(pads allowed)
				(copperpour not_allowed)
				(footprints allowed)
			)
			(placement
				(enabled no)
				(sheetname "")
			)
			(fill
				(thermal_gap 0.5)
				(thermal_bridge_width 0.5)
				(island_removal_mode 0)
			)
			(polygon
				(pts
					(xy 400.405092 -0.744474) (xy 400.405092 -1.252474) (xy 400.024092 -1.252474) (xy 400.024092 -0.744474)
				)
			)
		)
	)
	(footprint ""
		(layer "F.Cu")
		(at 205.036928 -73.287382)
		(property "Reference" "L4D2"
			(at 3.378708 -4.251706 0)
			(unlocked yes)
			(layer "F.SilkS")
			(effects
				(font
					(size 0.4064 0.254)
					(thickness 0.1524)
				)
			)
		)
		(property "Value" ""
			(at 0 0 0)
			(layer "F.Fab")
			(effects
				(font
					(size 1.27 1.27)
				)
			)
		)
		(duplicate_pad_numbers_are_jumpers no)
		(fp_line
			(start -1.1303 -3.199892)
			(end 8.3693 -3.199892)
			(stroke
				(width 0.1524)
				(type default)
			)
			(layer "F.SilkS")
		)
		(fp_line
			(start -1.1303 -1.6637)
			(end -1.1303 -3.199892)
			(stroke
				(width 0.1524)
				(type default)
			)
			(layer "F.SilkS")
		)
		(fp_line
			(start -1.1303 3.199892)
			(end -1.1303 1.6637)
			(stroke
				(width 0.1524)
				(type default)
			)
			(layer "F.SilkS")
		)
		(fp_line
			(start 8.3693 -3.199892)
			(end 8.3693 -1.6637)
			(stroke
				(width 0.1524)
				(type default)
			)
			(layer "F.SilkS")
		)
		(fp_line
			(start 8.3693 1.6637)
			(end 8.3693 3.199892)
			(stroke
				(width 0.1524)
				(type default)
			)
			(layer "F.SilkS")
		)
		(fp_line
			(start 8.3693 3.199892)
			(end -1.1303 3.199892)
			(stroke
				(width 0.1524)
				(type default)
			)
			(layer "F.SilkS")
		)
		(fp_rect
			(start -1.1303 3.199892)
			(end 8.3693 -3.199892)
			(stroke
				(width 0)
				(type default)
			)
			(fill no)
			(layer "F.CrtYd")
		)
		(fp_line
			(start -1.1303 -3.199892)
			(end 8.3693 -3.199892)
			(stroke
				(width 0.1)
				(type default)
			)
			(layer "F.Fab")
		)
		(fp_line
			(start -1.1303 3.199892)
			(end -1.1303 -3.199892)
			(stroke
				(width 0.1)
				(type default)
			)
			(layer "F.Fab")
		)
		(fp_line
			(start 8.3693 -3.199892)
			(end 8.3693 3.199892)
			(stroke
				(width 0.1)
				(type default)
			)
			(layer "F.Fab")
		)
		(fp_line
			(start 8.3693 3.199892)
			(end -1.1303 3.199892)
			(stroke
				(width 0.1)
				(type default)
			)
			(layer "F.Fab")
		)
		(pad "1" smd rect
			(at 0 0)
			(size 3.683 2.667)
			(layers "F.Cu" "F.Mask" "F.Paste")
			(net "VR_PVCCIN_CPU0_PHASE3")
		)
		(pad "2" smd rect
			(at 7.239 0)
			(size 3.683 2.667)
			(layers "F.Cu" "F.Mask" "F.Paste")
			(net "PVCCIN_CPU0")
		)
	)
	(footprint ""
		(layer "F.Cu")
		(at 182.3466 -52.5907 -90)
		(property "Reference" "C4E18"
			(at 0 0 270)
			(layer "F.SilkS")
			(hide yes)
			(effects
				(font
					(size 1.27 1.27)
				)
			)
		)
		(property "Value" ""
			(at 0 0 270)
			(layer "F.Fab")
			(effects
				(font
					(size 1.27 1.27)
				)
			)
		)
		(duplicate_pad_numbers_are_jumpers no)
		(fp_poly
			(pts
				(xy 0.3048 -0.1016) (xy 0.3048 0.9906) (xy -0.3048 0.9906) (xy -0.3048 -0.1016)
			)
			(stroke
				(width 0)
				(type default)
			)
			(fill no)
			(layer "F.CrtYd")
		)
		(fp_line
			(start -0.3048 0.9906)
			(end 0.3048 0.9906)
			(stroke
				(width 0.1)
				(type default)
			)
			(layer "F.Fab")
		)
		(fp_line
			(start 0.3048 0.9906)
			(end 0.3048 -0.1016)
			(stroke
				(width 0.1)
				(type default)
			)
			(layer "F.Fab")
		)
		(fp_line
			(start -0.3048 -0.1016)
			(end -0.3048 0.9906)
			(stroke
				(width 0.1)
				(type default)
			)
			(layer "F.Fab")
		)
		(fp_line
			(start 0.3048 -0.1016)
			(end -0.3048 -0.1016)
			(stroke
				(width 0.1)
				(type default)
			)
			(layer "F.Fab")
		)
		(pad "1" smd rect
			(at 0 0 270)
			(size 0.508 0.508)
			(layers "F.Cu" "F.Mask" "F.Paste")
			(net "VR_PVCCIO_CPU1_PH1_BOOT")
		)
		(pad "2" smd rect
			(at 0 0.889 270)
			(size 0.508 0.508)
			(layers "F.Cu" "F.Mask" "F.Paste")
			(net "VR_PVCCIO_CPU1_PH1_PHASE")
		)
		(zone
			(layer "F.Cu")
			(hatch none 0.5)
			(connect_pads
				(clearance 0)
			)
			(min_thickness 0.25)
			(keepout
				(tracks not_allowed)
				(vias allowed)
				(pads allowed)
				(copperpour not_allowed)
				(footprints allowed)
			)
			(placement
				(enabled no)
				(sheetname "")
			)
			(fill
				(thermal_gap 0.5)
				(thermal_bridge_width 0.5)
				(island_removal_mode 0)
			)
			(polygon
				(pts
					(xy 181.7116 -52.8447) (xy 181.7116 -52.3367) (xy 182.0926 -52.3367) (xy 182.0926 -52.8447)
				)
			)
		)
		(zone
			(layer "F.Cu")
			(hatch none 0.5)
			(connect_pads
				(clearance 0)
			)
			(min_thickness 0.25)
			(keepout
				(tracks allowed)
				(vias not_allowed)
				(pads allowed)
				(copperpour not_allowed)
				(footprints allowed)
			)
			(placement
				(enabled no)
				(sheetname "")
			)
			(fill
				(thermal_gap 0.5)
				(thermal_bridge_width 0.5)
				(island_removal_mode 0)
			)
			(polygon
				(pts
					(xy 182.0926 -52.8447) (xy 182.0926 -52.3367) (xy 181.7116 -52.3367) (xy 181.7116 -52.8447)
				)
			)
		)
	)
	(footprint ""
		(layer "F.Cu")
		(at 336.9564 -20.5486)
		(property "Reference" "R7F36"
			(at -0.8382 -0.67818 0)
			(unlocked yes)
			(layer "F.SilkS")
			(effects
				(font
					(size 0.4064 0.254)
					(thickness 0.1524)
				)
				(justify left)
			)
		)
		(property "Value" ""
			(at 0 0 0)
			(layer "F.Fab")
			(effects
				(font
					(size 1.27 1.27)
				)
			)
		)
		(duplicate_pad_numbers_are_jumpers no)
		(fp_poly
			(pts
				(xy -0.2794 -0.1016) (xy 0.2794 -0.1016) (xy 0.2794 0.9906) (xy -0.2794 0.9906)
			)
			(stroke
				(width 0)
				(type default)
			)
			(fill no)
			(layer "F.CrtYd")
		)
		(fp_line
			(start -0.2794 -0.1016)
			(end -0.2794 0.9906)
			(stroke
				(width 0.1)
				(type default)
			)
			(layer "F.Fab")
		)
		(fp_line
			(start -0.2794 0.9906)
			(end 0.2794 0.9906)
			(stroke
				(width 0.1)
				(type default)
			)
			(layer "F.Fab")
		)
		(fp_line
			(start 0.2794 -0.1016)
			(end -0.2794 -0.1016)
			(stroke
				(width 0.1)
				(type default)
			)
			(layer "F.Fab")
		)
		(fp_line
			(start 0.2794 0.9906)
			(end 0.2794 -0.1016)
			(stroke
				(width 0.1)
				(type default)
			)
			(layer "F.Fab")
		)
		(pad "1" smd rect
			(at 0 0)
			(size 0.508 0.508)
			(layers "F.Cu" "F.Mask" "F.Paste")
			(net "P3V3_STBY")
		)
		(pad "2" smd rect
			(at 0 0.889)
			(size 0.508 0.508)
			(layers "F.Cu" "F.Mask" "F.Paste")
			(net "PWRGD_PVDDQ_ABC")
		)
		(zone
			(layer "F.Cu")
			(hatch none 0.5)
			(connect_pads
				(clearance 0)
			)
			(min_thickness 0.25)
			(keepout
				(tracks allowed)
				(vias not_allowed)
				(pads allowed)
				(copperpour not_allowed)
				(footprints allowed)
			)
			(placement
				(enabled no)
				(sheetname "")
			)
			(fill
				(thermal_gap 0.5)
				(thermal_bridge_width 0.5)
				(island_removal_mode 0)
			)
			(polygon
				(pts
					(xy 336.7024 -20.2946) (xy 337.2104 -20.2946) (xy 337.2104 -19.9136) (xy 336.7024 -19.9136)
				)
			)
		)
		(zone
			(layer "F.Cu")
			(hatch none 0.5)
			(connect_pads
				(clearance 0)
			)
			(min_thickness 0.25)
			(keepout
				(tracks not_allowed)
				(vias allowed)
				(pads allowed)
				(copperpour not_allowed)
				(footprints allowed)
			)
			(placement
				(enabled no)
				(sheetname "")
			)
			(fill
				(thermal_gap 0.5)
				(thermal_bridge_width 0.5)
				(island_removal_mode 0)
			)
			(polygon
				(pts
					(xy 336.7024 -19.9136) (xy 337.2104 -19.9136) (xy 337.2104 -20.2946) (xy 336.7024 -20.2946)
				)
			)
		)
	)
	(footprint ""
		(layer "F.Cu")
		(at 376.367548 -153.347928)
		(property "Reference" "EU7A3"
			(at 3.320288 -0.2032 90)
			(unlocked yes)
			(layer "F.SilkS")
			(effects
				(font
					(size 0.7874 0.5842)
					(thickness 0.1524)
				)
			)
		)
		(property "Value" ""
			(at 0 0 0)
			(layer "F.Fab")
			(effects
				(font
					(size 1.27 1.27)
				)
			)
		)
		(duplicate_pad_numbers_are_jumpers no)
		(fp_line
			(start -3.0099 -3.5052)
			(end 2.9718 -3.5052)
			(stroke
				(width 0.1524)
				(type default)
			)
			(layer "F.SilkS")
		)
		(fp_line
			(start -3.0099 3.429)
			(end -3.0099 -3.5052)
			(stroke
				(width 0.1524)
				(type default)
			)
			(layer "F.SilkS")
		)
		(fp_line
			(start 2.9718 -3.5052)
			(end 2.9718 3.429)
			(stroke
				(width 0.1524)
				(type default)
			)
			(layer "F.SilkS")
		)
		(fp_line
			(start 2.9718 3.429)
			(end -3.0099 3.429)
			(stroke
				(width 0.1524)
				(type default)
			)
			(layer "F.SilkS")
		)
		(fp_circle
			(center -3.057398 -2.678684)
			(end -2.930398 -2.678684)
			(stroke
				(width 0.254)
				(type default)
			)
			(fill no)
			(layer "F.SilkS")
		)
		(fp_poly
			(pts
				(xy -2.9972 -3.4925) (xy -2.9972 -2.6924) (xy -2.1971 -3.4925)
			)
			(stroke
				(width 0)
				(type default)
			)
			(fill yes)
			(layer "F.SilkS")
		)
		(fp_poly
			(pts
				(xy -2.549906 -3.050032) (xy -2.549906 3.050032) (xy 2.549906 3.050032) (xy 2.549906 -3.050032)
			)
			(stroke
				(width 0)
				(type default)
			)
			(fill no)
			(layer "F.CrtYd")
		)
		(fp_line
			(start -2.549906 -3.050032)
			(end 2.549906 -3.050032)
			(stroke
				(width 0.1)
				(type default)
			)
			(layer "F.Fab")
		)
		(fp_line
			(start -2.549906 3.050032)
			(end -2.549906 -3.050032)
			(stroke
				(width 0.1)
				(type default)
			)
			(layer "F.Fab")
		)
		(fp_line
			(start 2.549906 -3.050032)
			(end 2.549906 3.050032)
			(stroke
				(width 0.1)
				(type default)
			)
			(layer "F.Fab")
		)
		(fp_line
			(start 2.549906 3.050032)
			(end -2.549906 3.050032)
			(stroke
				(width 0.1)
				(type default)
			)
			(layer "F.Fab")
		)
		(fp_circle
			(center -3.057398 -2.678684)
			(end -2.930398 -2.678684)
			(stroke
				(width 0.254)
				(type default)
			)
			(fill no)
			(layer "F.Fab")
		)
		(pad "1" smd rect
			(at -2.39522 -2.279904)
			(size 0.7112 0.254)
			(layers "F.Cu" "F.Mask" "F.Paste")
			(net "PVNN_PCH_STBY")
		)
		(pad "2" smd rect
			(at -2.39522 -1.83007)
			(size 0.7112 0.254)
			(layers "F.Cu" "F.Mask" "F.Paste")
			(net "GND")
		)
		(pad "3" smd rect
			(at -2.39522 -1.379982)
			(size 0.7112 0.254)
			(layers "F.Cu" "F.Mask" "F.Paste")
			(net "VR_PVNN_PCH_PH1_VCIN")
		)
		(pad "4" smd rect
			(at -2.39522 -0.929894)
			(size 0.7112 0.254)
			(layers "F.Cu" "F.Mask" "F.Paste")
			(net "P5V_STBY")
		)
		(pad "5" smd rect
			(at -2.39522 -0.48006)
			(size 0.7112 0.254)
			(layers "F.Cu" "F.Mask" "F.Paste")
			(net "GND")
		)
		(pad "6" smd rect
			(at -2.39522 -0.029972)
			(size 0.7112 0.254)
			(layers "F.Cu" "F.Mask" "F.Paste")
			(net "TP_PVNN_PCH_GL_0")
		)
		(pad "7" smd custom
			(at 0.016764 1.145032)
			(size 0.53975 0.53975)
			(layers "F.Cu" "F.Mask" "F.Paste")
			(net "GND")
			(options
				(clearance outline)
				(anchor circle)
			)
			(primitives
				(gr_poly
					(pts
						(xy -2.7051 1.0795) (xy -2.7051 -0.3683) (xy -0.9271 -0.3683) (xy -0.9271 -1.0795) (xy 2.7051 -1.0795)
						(xy 2.7051 1.0795)
					)
					(width 0)
					(fill yes)
				)
			)
		)
		(pad "10" smd rect
			(at -0.008382 2.874772)
			(size 4.3434 0.6096)
			(layers "F.Cu" "F.Mask" "F.Paste")
			(net "VR_PVNN_PCH_PH1_PHASE_SW")
		)
		(pad "25" smd rect
			(at 1.548384 -1.283208)
			(size 2.3368 2.0066)
			(layers "F.Cu" "F.Mask" "F.Paste")
			(net "VR_FET_SW_P12V_STBY_PVDDQ_DEF")
		)
		(pad "30" smd rect
			(at 2.050034 -2.895092)
			(size 0.254 0.7112)
			(layers "F.Cu" "F.Mask" "F.Paste")
			(net "VR_FET_SW_P12V_STBY_PVDDQ_DEF")
		)
		(pad "31" smd rect
			(at 1.599946 -2.895092)
			(size 0.254 0.7112)
			(layers "F.Cu" "F.Mask" "F.Paste")
			(net "Net_374")
		)
		(pad "32" smd rect
			(at 1.150112 -2.895092)
			(size 0.254 0.7112)
			(layers "F.Cu" "F.Mask" "F.Paste")
			(net "VR_PVNN_PCH_PH1_PHASE")
		)
		(pad "33" smd rect
			(at 0.700024 -2.895092)
			(size 0.254 0.7112)
			(layers "F.Cu" "F.Mask" "F.Paste")
			(net "VR_PVNN_PCH_PH1_BOOT_R")
		)
		(pad "34" smd rect
			(at 0.249936 -2.895092)
			(size 0.254 0.7112)
			(layers "F.Cu" "F.Mask" "F.Paste")
			(net "VR_PVNN_PCH_PWM1")
		)
		(pad "35" smd rect
			(at -0.199898 -2.895092)
			(size 0.254 0.7112)
			(layers "F.Cu" "F.Mask" "F.Paste")
			(net "P5V_STBY")
		)
		(pad "36" smd rect
			(at -0.649986 -2.895092)
			(size 0.254 0.7112)
			(layers "F.Cu" "F.Mask" "F.Paste")
			(net "A_TSENSE_PVNN_PCH_TMON")
		)
		(pad "37" smd rect
			(at -1.100074 -2.895092)
			(size 0.254 0.7112)
			(layers "F.Cu" "F.Mask" "F.Paste")
			(net "VR_PVNN_PCH_STBY_OCSET")
		)
		(pad "38" smd rect
			(at -1.549908 -2.895092)
			(size 0.254 0.7112)
			(layers "F.Cu" "F.Mask" "F.Paste")
			(net "ISENSE_PVNN_PCH_PH1_IMON")
		)
		(pad "39" smd rect
			(at -1.999996 -2.895092)
			(size 0.254 0.7112)
			(layers "F.Cu" "F.Mask" "F.Paste")
			(net "VR_PVNN_PCH_AIREF1")
		)
		(pad "40" smd rect
			(at -0.871728 -1.283208)
			(size 1.8034 2.0066)
			(layers "F.Cu" "F.Mask" "F.Paste")
			(net "GND")
		)
		(pad "41" smd rect
			(at -1.533906 0.247904)
			(size 0.508 0.3556)
			(layers "F.Cu" "F.Mask" "F.Paste")
			(net "TP_PVNN_PCH_GL_1")
		)
	)
	(footprint ""
		(layer "F.Cu")
		(at 413.4612 -117.8814 180)
		(property "Reference" "R8B21"
			(at 0 0 180)
			(layer "F.SilkS")
			(hide yes)
			(effects
				(font
					(size 1.27 1.27)
				)
			)
		)
		(property "Value" ""
			(at 0 0 180)
			(layer "F.Fab")
			(effects
				(font
					(size 1.27 1.27)
				)
			)
		)
		(duplicate_pad_numbers_are_jumpers no)
		(fp_poly
			(pts
				(xy -0.2794 -0.1016) (xy 0.2794 -0.1016) (xy 0.2794 0.9906) (xy -0.2794 0.9906)
			)
			(stroke
				(width 0)
				(type default)
			)
			(fill no)
			(layer "F.CrtYd")
		)
		(fp_line
			(start 0.2794 0.9906)
			(end 0.2794 -0.1016)
			(stroke
				(width 0.1)
				(type default)
			)
			(layer "F.Fab")
		)
		(fp_line
			(start 0.2794 -0.1016)
			(end -0.2794 -0.1016)
			(stroke
				(width 0.1)
				(type default)
			)
			(layer "F.Fab")
		)
		(fp_line
			(start -0.2794 0.9906)
			(end 0.2794 0.9906)
			(stroke
				(width 0.1)
				(type default)
			)
			(layer "F.Fab")
		)
		(fp_line
			(start -0.2794 -0.1016)
			(end -0.2794 0.9906)
			(stroke
				(width 0.1)
				(type default)
			)
			(layer "F.Fab")
		)
		(pad "1" smd rect
			(at 0 0 180)
			(size 0.508 0.508)
			(layers "F.Cu" "F.Mask" "F.Paste")
			(net "H_PMSYNC_CLK_24M")
		)
		(pad "2" smd rect
			(at 0 0.889 180)
			(size 0.508 0.508)
			(layers "F.Cu" "F.Mask" "F.Paste")
			(net "GND")
		)
		(zone
			(layer "F.Cu")
			(hatch none 0.5)
			(connect_pads
				(clearance 0)
			)
			(min_thickness 0.25)
			(keepout
				(tracks not_allowed)
				(vias allowed)
				(pads allowed)
				(copperpour not_allowed)
				(footprints allowed)
			)
			(placement
				(enabled no)
				(sheetname "")
			)
			(fill
				(thermal_gap 0.5)
				(thermal_bridge_width 0.5)
				(island_removal_mode 0)
			)
			(polygon
				(pts
					(xy 413.7152 -118.5164) (xy 413.2072 -118.5164) (xy 413.2072 -118.1354) (xy 413.7152 -118.1354)
				)
			)
		)
		(zone
			(layer "F.Cu")
			(hatch none 0.5)
			(connect_pads
				(clearance 0)
			)
			(min_thickness 0.25)
			(keepout
				(tracks allowed)
				(vias not_allowed)
				(pads allowed)
				(copperpour not_allowed)
				(footprints allowed)
			)
			(placement
				(enabled no)
				(sheetname "")
			)
			(fill
				(thermal_gap 0.5)
				(thermal_bridge_width 0.5)
				(island_removal_mode 0)
			)
			(polygon
				(pts
					(xy 413.7152 -118.1354) (xy 413.2072 -118.1354) (xy 413.2072 -118.5164) (xy 413.7152 -118.5164)
				)
			)
		)
	)
	(footprint ""
		(layer "F.Cu")
		(at 470.2175 -142.494 180)
		(property "Reference" "J9A1"
			(at -2.29362 -1.86055 0)
			(unlocked yes)
			(layer "B.SilkS")
			(effects
				(font
					(size 0.7874 0.5842)
					(thickness 0.1524)
				)
				(justify left mirror)
			)
		)
		(property "Value" ""
			(at 0 0 180)
			(layer "F.Fab")
			(effects
				(font
					(size 1.27 1.27)
				)
			)
		)
		(duplicate_pad_numbers_are_jumpers no)
		(fp_line
			(start 2.153412 8.64997)
			(end -1.746504 8.64997)
			(stroke
				(width 0.1524)
				(type default)
			)
			(layer "F.SilkS")
		)
		(fp_line
			(start 2.153412 -2.649982)
			(end 2.153412 8.64997)
			(stroke
				(width 0.1524)
				(type default)
			)
			(layer "F.SilkS")
		)
		(fp_line
			(start -1.746504 8.64997)
			(end -1.746504 -2.649982)
			(stroke
				(width 0.1524)
				(type default)
			)
			(layer "F.SilkS")
		)
		(fp_line
			(start -1.746504 -2.649982)
			(end 2.153412 -2.649982)
			(stroke
				(width 0.1524)
				(type default)
			)
			(layer "F.SilkS")
		)
		(fp_poly
			(pts
				(xy -3.664204 -0.499618) (xy -3.664204 0.516382) (xy -2.394204 0.008382)
			)
			(stroke
				(width 0)
				(type default)
			)
			(fill yes)
			(layer "F.SilkS")
		)
		(fp_poly
			(pts
				(xy 1.950974 0.512064) (xy 1.950974 -0.503936) (xy 0.680974 0.004064)
			)
			(stroke
				(width 0)
				(type default)
			)
			(fill yes)
			(layer "B.SilkS")
		)
		(fp_poly
			(pts
				(xy -1.746504 -2.649982) (xy -1.746504 8.64997) (xy 2.153412 8.64997) (xy 2.153412 -2.649982)
			)
			(stroke
				(width 0)
				(type default)
			)
			(fill no)
			(layer "F.CrtYd")
		)
		(fp_poly
			(pts
				(xy -3.664204 -0.499618) (xy -3.664204 0.516382) (xy -2.394204 0.008382)
			)
			(stroke
				(width 0)
				(type default)
			)
			(fill yes)
			(layer "B.Fab")
		)
		(fp_line
			(start 2.153412 8.64997)
			(end -1.746504 8.64997)
			(stroke
				(width 0.1)
				(type default)
			)
			(layer "F.Fab")
		)
		(fp_line
			(start 2.153412 -2.649982)
			(end 2.153412 8.64997)
			(stroke
				(width 0.1)
				(type default)
			)
			(layer "F.Fab")
		)
		(fp_line
			(start -1.746504 8.64997)
			(end -1.746504 -2.649982)
			(stroke
				(width 0.1)
				(type default)
			)
			(layer "F.Fab")
		)
		(fp_line
			(start -1.746504 -2.649982)
			(end 2.153412 -2.649982)
			(stroke
				(width 0.1)
				(type default)
			)
			(layer "F.Fab")
		)
		(fp_poly
			(pts
				(xy -3.664204 -0.499618) (xy -3.664204 0.516382) (xy -2.394204 0.008382)
			)
			(stroke
				(width 0)
				(type default)
			)
			(fill yes)
			(layer "F.Fab")
		)
		(fp_text user "4"
			(at 0.7493 9.21893 0)
			(unlocked yes)
			(layer "F.SilkS")
			(effects
				(font
					(size 0.7874 0.5842)
					(thickness 0.1524)
				)
				(justify left)
			)
		)
		(fp_text user "4"
			(at -2.218436 6.033516 180)
			(unlocked yes)
			(layer "B.SilkS")
			(effects
				(font
					(size 0.7874 0.5842)
					(thickness 0.1524)
				)
				(justify left mirror)
			)
		)
		(fp_text user "4"
			(at -2.218436 6.033516 180)
			(unlocked yes)
			(layer "B.Fab")
			(effects
				(font
					(size 0.7874 0.5842)
					(thickness 0.1524)
				)
				(justify left mirror)
			)
		)
		(fp_text user "4"
			(at 2.962402 8.50265 0)
			(unlocked yes)
			(layer "F.Fab")
			(effects
				(font
					(size 0.7874 0.5842)
					(thickness 0.1524)
				)
				(justify left)
			)
		)
		(pad "1" thru_hole rect
			(at 0 0 180)
			(size 1.1938 1.1938)
			(drill 0.8128)
			(layers "*.Cu" "*.Mask")
			(remove_unused_layers no)
			(net "GND")
			(clearance 0.127)
			(thermal_gap 0.127)
			(padstack
				(mode front_inner_back)
				(layer "Inner"
					(shape circle)
					(size 1.1938 1.1938)
					(clearance 0.127)
				)
				(layer "B.Cu"
					(shape rect)
					(size 1.1938 1.1938)
					(clearance 0.127)
				)
			)
		)
		(pad "2" thru_hole circle
			(at 0 1.999996 180)
			(size 1.1938 1.1938)
			(drill 0.8128)
			(layers "*.Cu" "*.Mask")
			(remove_unused_layers no)
			(net "PU_KEY_CONN_PIN2_R")
			(clearance 0.127)
			(thermal_gap 0.127)
		)
		(pad "3" thru_hole circle
			(at 0 3.999992 180)
			(size 1.1938 1.1938)
			(drill 0.8128)
			(layers "*.Cu" "*.Mask")
			(remove_unused_layers no)
			(net "GND")
			(clearance 0.127)
			(thermal_gap 0.127)
		)
		(pad "4" thru_hole circle
			(at 0 5.999988 180)
			(size 1.1938 1.1938)
			(drill 0.8128)
			(layers "*.Cu" "*.Mask")
			(remove_unused_layers no)
			(net "FM_PCH_SATA_RAID_KEY_R")
			(clearance 0.127)
			(thermal_gap 0.127)
		)
	)
	(footprint ""
		(layer "F.Cu")
		(at 15.072106 -110.707424 -90)
		(property "Reference" "J1B4"
			(at 0 0 270)
			(layer "F.SilkS")
			(hide yes)
			(effects
				(font
					(size 1.27 1.27)
				)
			)
		)
		(property "Value" "*"
			(at 2.6924 -3.0734 270)
			(unlocked yes)
			(layer "F.Fab")
			(hide yes)
			(effects
				(font
					(size 1.27 1.016)
					(thickness 0.1524)
				)
			)
		)
		(property "Device Type" "CLX-CONN3A-1-GP_CONN-G3-CLX-COA"
			(at 2.6924 -4.5974 270)
			(unlocked yes)
			(layer "F.Fab")
			(hide yes)
			(effects
				(font
					(size 1.27 1.016)
					(thickness 0.1524)
				)
			)
		)
		(duplicate_pad_numbers_are_jumpers no)
		(fp_line
			(start -2.6543 3.1369)
			(end -1.3335 3.1369)
			(stroke
				(width 0.3302)
				(type default)
			)
			(layer "F.SilkS")
		)
		(fp_line
			(start -2.7432 3.048)
			(end -2.7432 1.2573)
			(stroke
				(width 0.1524)
				(type default)
			)
			(layer "F.SilkS")
		)
		(fp_line
			(start -1.2446 3.048)
			(end -2.7432 3.048)
			(stroke
				(width 0.1524)
				(type default)
			)
			(layer "F.SilkS")
		)
		(fp_line
			(start 1.2446 3.048)
			(end 1.2446 1.2573)
			(stroke
				(width 0.1524)
				(type default)
			)
			(layer "F.SilkS")
		)
		(fp_line
			(start 2.7432 3.048)
			(end 1.2446 3.048)
			(stroke
				(width 0.1524)
				(type default)
			)
			(layer "F.SilkS")
		)
		(fp_line
			(start -3.2512 1.2573)
			(end -3.2512 -1.2573)
			(stroke
				(width 0.1524)
				(type default)
			)
			(layer "F.SilkS")
		)
		(fp_line
			(start -2.7432 1.2573)
			(end -3.2512 1.2573)
			(stroke
				(width 0.1524)
				(type default)
			)
			(layer "F.SilkS")
		)
		(fp_line
			(start -1.2446 1.2573)
			(end -1.2446 3.048)
			(stroke
				(width 0.1524)
				(type default)
			)
			(layer "F.SilkS")
		)
		(fp_line
			(start 1.2446 1.2573)
			(end -1.2446 1.2573)
			(stroke
				(width 0.1524)
				(type default)
			)
			(layer "F.SilkS")
		)
		(fp_line
			(start 2.7432 1.2573)
			(end 2.7432 3.048)
			(stroke
				(width 0.1524)
				(type default)
			)
			(layer "F.SilkS")
		)
		(fp_line
			(start 3.2512 1.2573)
			(end 2.7432 1.2573)
			(stroke
				(width 0.1524)
				(type default)
			)
			(layer "F.SilkS")
		)
		(fp_line
			(start -3.2512 -1.2573)
			(end -0.7493 -1.2573)
			(stroke
				(width 0.1524)
				(type default)
			)
			(layer "F.SilkS")
		)
		(fp_line
			(start -0.7493 -1.2573)
			(end -0.7493 -3.048)
			(stroke
				(width 0.1524)
				(type default)
			)
			(layer "F.SilkS")
		)
		(fp_line
			(start 0.7493 -1.2573)
			(end 3.2512 -1.2573)
			(stroke
				(width 0.1524)
				(type default)
			)
			(layer "F.SilkS")
		)
		(fp_line
			(start 3.2512 -1.2573)
			(end 3.2512 1.2573)
			(stroke
				(width 0.1524)
				(type default)
			)
			(layer "F.SilkS")
		)
		(fp_line
			(start -0.7493 -3.048)
			(end 0.7493 -3.048)
			(stroke
				(width 0.1524)
				(type default)
			)
			(layer "F.SilkS")
		)
		(fp_line
			(start 0.7493 -3.048)
			(end 0.7493 -1.2573)
			(stroke
				(width 0.1524)
				(type default)
			)
			(layer "F.SilkS")
		)
		(fp_poly
			(pts
				(xy -2.014474 3.124708) (xy -2.649474 3.759708) (xy -1.379474 3.759708)
			)
			(stroke
				(width 0)
				(type default)
			)
			(fill yes)
			(layer "F.SilkS")
		)
		(fp_poly
			(pts
				(xy -0.254 -2.2987) (xy 0.254 -2.2987) (xy 0.254 -1.0033) (xy 2.9972 -1.0033) (xy 2.9972 1.0033)
				(xy 2.2479 1.0033) (xy 2.2479 2.2987) (xy 1.7399 2.2987) (xy 1.7399 1.0033) (xy -1.7399 1.0033)
				(xy -1.7399 2.2987) (xy -2.2479 2.2987) (xy -2.2479 1.0033) (xy -2.9972 1.0033) (xy -2.9972 -1.0033)
				(xy -0.254 -1.0033)
			)
			(stroke
				(width 0)
				(type default)
			)
			(fill no)
			(layer "F.CrtYd")
		)
		(fp_poly
			(pts
				(xy -2.9972 3.302) (xy -2.9972 1.5113) (xy -3.5052 1.5113) (xy -3.5052 -1.5113) (xy -1.0033 -1.5113)
				(xy -1.0033 -3.302) (xy 1.0033 -3.302) (xy 1.0033 -1.5113) (xy 3.5052 -1.5113) (xy 3.5052 -0.00635)
				(xy 2.9972 -0.00635) (xy 2.9972 -1.0033) (xy 0.254 -1.0033) (xy 0.254 -2.2987) (xy -0.254 -2.2987)
				(xy -0.254 -1.0033) (xy -2.9972 -1.0033) (xy -2.9972 1.0033) (xy -2.2479 1.0033) (xy -2.2479 2.2987)
				(xy -1.7399 2.2987) (xy -1.7399 1.0033) (xy 1.7399 1.0033) (xy 1.7399 2.2987) (xy 2.2479 2.2987)
				(xy 2.2479 1.0033) (xy 2.9972 1.0033) (xy 2.9972 0.00635) (xy 3.5052 0.00635) (xy 3.5052 1.5113)
				(xy 2.9972 1.5113) (xy 2.9972 3.302) (xy 0.9906 3.302) (xy 0.9906 1.5113) (xy -0.9906 1.5113) (xy -0.9906 3.302)
			)
			(stroke
				(width 0)
				(type default)
			)
			(fill no)
			(layer "F.CrtYd")
		)
		(fp_poly
			(pts
				(xy -2.9972 3.302) (xy -2.9972 1.5113) (xy -3.5052 1.5113) (xy -3.5052 -1.5113) (xy -1.0033 -1.5113)
				(xy -1.0033 -3.302) (xy 1.0033 -3.302) (xy 1.0033 -1.5113) (xy 3.5052 -1.5113) (xy 3.5052 1.5113)
				(xy 2.9972 1.5113) (xy 2.9972 3.302) (xy 0.9906 3.302) (xy 0.9906 1.5113) (xy -0.9906 1.5113) (xy -0.9906 3.302)
			)
			(stroke
				(width 0)
				(type default)
			)
			(fill no)
			(layer "F.Fab")
		)
		(pad "1" smd rect
			(at -1.999996 1.397 270)
			(size 0.9906 2.794)
			(layers "F.Cu" "F.Mask" "F.Paste")
			(net "A_HSC_HIGH_EN")
		)
		(pad "2" smd rect
			(at 0 -1.397 270)
			(size 0.9906 2.794)
			(layers "F.Cu" "F.Mask" "F.Paste")
			(net "A_HSC_OCP_SEL")
		)
		(pad "3" smd rect
			(at 1.999996 1.397 270)
			(size 0.9906 2.794)
			(layers "F.Cu" "F.Mask" "F.Paste")
			(net "A_HSC_LOW_EN")
		)
	)
	(footprint ""
		(layer "F.Cu")
		(at 437.7055 -16.891 -90)
		(property "Reference" "R1U62"
			(at 0 0 270)
			(layer "F.SilkS")
			(hide yes)
			(effects
				(font
					(size 1.27 1.27)
				)
			)
		)
		(property "Value" ""
			(at 0 0 270)
			(layer "F.Fab")
			(effects
				(font
					(size 1.27 1.27)
				)
			)
		)
		(duplicate_pad_numbers_are_jumpers no)
		(fp_poly
			(pts
				(xy -0.2794 -0.1016) (xy 0.2794 -0.1016) (xy 0.2794 0.9906) (xy -0.2794 0.9906)
			)
			(stroke
				(width 0)
				(type default)
			)
			(fill no)
			(layer "F.CrtYd")
		)
		(fp_line
			(start -0.2794 0.9906)
			(end 0.2794 0.9906)
			(stroke
				(width 0.1)
				(type default)
			)
			(layer "F.Fab")
		)
		(fp_line
			(start 0.2794 0.9906)
			(end 0.2794 -0.1016)
			(stroke
				(width 0.1)
				(type default)
			)
			(layer "F.Fab")
		)
		(fp_line
			(start -0.2794 -0.1016)
			(end -0.2794 0.9906)
			(stroke
				(width 0.1)
				(type default)
			)
			(layer "F.Fab")
		)
		(fp_line
			(start 0.2794 -0.1016)
			(end -0.2794 -0.1016)
			(stroke
				(width 0.1)
				(type default)
			)
			(layer "F.Fab")
		)
		(pad "1" smd rect
			(at 0 0 270)
			(size 0.508 0.508)
			(layers "F.Cu" "F.Mask" "F.Paste")
			(net "H_CPU1_MEMKLM_MEMHOT_G_N")
		)
		(pad "2" smd rect
			(at 0 0.889 270)
			(size 0.508 0.508)
			(layers "F.Cu" "F.Mask" "F.Paste")
			(net "H_CPU1_MEMKLM_MEMHOT_G_PCH_N")
		)
		(zone
			(layer "F.Cu")
			(hatch none 0.5)
			(connect_pads
				(clearance 0)
			)
			(min_thickness 0.25)
			(keepout
				(tracks not_allowed)
				(vias allowed)
				(pads allowed)
				(copperpour not_allowed)
				(footprints allowed)
			)
			(placement
				(enabled no)
				(sheetname "")
			)
			(fill
				(thermal_gap 0.5)
				(thermal_bridge_width 0.5)
				(island_removal_mode 0)
			)
			(polygon
				(pts
					(xy 437.0705 -17.145) (xy 437.0705 -16.637) (xy 437.4515 -16.637) (xy 437.4515 -17.145)
				)
			)
		)
		(zone
			(layer "F.Cu")
			(hatch none 0.5)
			(connect_pads
				(clearance 0)
			)
			(min_thickness 0.25)
			(keepout
				(tracks allowed)
				(vias not_allowed)
				(pads allowed)
				(copperpour not_allowed)
				(footprints allowed)
			)
			(placement
				(enabled no)
				(sheetname "")
			)
			(fill
				(thermal_gap 0.5)
				(thermal_bridge_width 0.5)
				(island_removal_mode 0)
			)
			(polygon
				(pts
					(xy 437.4515 -17.145) (xy 437.4515 -16.637) (xy 437.0705 -16.637) (xy 437.0705 -17.145)
				)
			)
		)
	)
	(footprint ""
		(layer "F.Cu")
		(at 155.583636 -120.080786 90)
		(property "Reference" "R3B1"
			(at 0 0 90)
			(layer "F.SilkS")
			(hide yes)
			(effects
				(font
					(size 1.27 1.27)
				)
			)
		)
		(property "Value" ""
			(at 0 0 90)
			(layer "F.Fab")
			(effects
				(font
					(size 1.27 1.27)
				)
			)
		)
		(duplicate_pad_numbers_are_jumpers no)
		(fp_poly
			(pts
				(xy -0.2794 -0.1016) (xy 0.2794 -0.1016) (xy 0.2794 0.9906) (xy -0.2794 0.9906)
			)
			(stroke
				(width 0)
				(type default)
			)
			(fill no)
			(layer "F.CrtYd")
		)
		(fp_line
			(start 0.2794 -0.1016)
			(end -0.2794 -0.1016)
			(stroke
				(width 0.1)
				(type default)
			)
			(layer "F.Fab")
		)
		(fp_line
			(start -0.2794 -0.1016)
			(end -0.2794 0.9906)
			(stroke
				(width 0.1)
				(type default)
			)
			(layer "F.Fab")
		)
		(fp_line
			(start 0.2794 0.9906)
			(end 0.2794 -0.1016)
			(stroke
				(width 0.1)
				(type default)
			)
			(layer "F.Fab")
		)
		(fp_line
			(start -0.2794 0.9906)
			(end 0.2794 0.9906)
			(stroke
				(width 0.1)
				(type default)
			)
			(layer "F.Fab")
		)
		(pad "1" smd rect
			(at 0 0 90)
			(size 0.508 0.508)
			(layers "F.Cu" "F.Mask" "F.Paste")
			(net "SVID_ALERT0_CPU1_N")
		)
		(pad "2" smd rect
			(at 0 0.889 90)
			(size 0.508 0.508)
			(layers "F.Cu" "F.Mask" "F.Paste")
			(net "SVID_ALERT0_CPU1_R_N")
		)
		(zone
			(layer "F.Cu")
			(hatch none 0.5)
			(connect_pads
				(clearance 0)
			)
			(min_thickness 0.25)
			(keepout
				(tracks allowed)
				(vias not_allowed)
				(pads allowed)
				(copperpour not_allowed)
				(footprints allowed)
			)
			(placement
				(enabled no)
				(sheetname "")
			)
			(fill
				(thermal_gap 0.5)
				(thermal_bridge_width 0.5)
				(island_removal_mode 0)
			)
			(polygon
				(pts
					(xy 155.837636 -119.826786) (xy 155.837636 -120.334786) (xy 156.218636 -120.334786) (xy 156.218636 -119.826786)
				)
			)
		)
		(zone
			(layer "F.Cu")
			(hatch none 0.5)
			(connect_pads
				(clearance 0)
			)
			(min_thickness 0.25)
			(keepout
				(tracks not_allowed)
				(vias allowed)
				(pads allowed)
				(copperpour not_allowed)
				(footprints allowed)
			)
			(placement
				(enabled no)
				(sheetname "")
			)
			(fill
				(thermal_gap 0.5)
				(thermal_bridge_width 0.5)
				(island_removal_mode 0)
			)
			(polygon
				(pts
					(xy 156.218636 -119.826786) (xy 156.218636 -120.334786) (xy 155.837636 -120.334786) (xy 155.837636 -119.826786)
				)
			)
		)
	)
	(footprint ""
		(layer "F.Cu")
		(at 8.787638 -7.129018)
		(property "Reference" "CT29"
			(at -0.8382 -0.67818 0)
			(unlocked yes)
			(layer "F.SilkS")
			(effects
				(font
					(size 0.4064 0.254)
					(thickness 0.1524)
				)
				(justify left)
			)
		)
		(property "Value" ""
			(at 0 0 0)
			(layer "F.Fab")
			(effects
				(font
					(size 1.27 1.27)
				)
			)
		)
		(duplicate_pad_numbers_are_jumpers no)
		(fp_poly
			(pts
				(xy 0.3048 -0.1016) (xy 0.3048 0.9906) (xy -0.3048 0.9906) (xy -0.3048 -0.1016)
			)
			(stroke
				(width 0)
				(type default)
			)
			(fill no)
			(layer "F.CrtYd")
		)
		(fp_line
			(start -0.3048 -0.1016)
			(end -0.3048 0.9906)
			(stroke
				(width 0.1)
				(type default)
			)
			(layer "F.Fab")
		)
		(fp_line
			(start -0.3048 0.9906)
			(end 0.3048 0.9906)
			(stroke
				(width 0.1)
				(type default)
			)
			(layer "F.Fab")
		)
		(fp_line
			(start 0.3048 -0.1016)
			(end -0.3048 -0.1016)
			(stroke
				(width 0.1)
				(type default)
			)
			(layer "F.Fab")
		)
		(fp_line
			(start 0.3048 0.9906)
			(end 0.3048 -0.1016)
			(stroke
				(width 0.1)
				(type default)
			)
			(layer "F.Fab")
		)
		(pad "1" smd rect
			(at 0 0)
			(size 0.508 0.508)
			(layers "F.Cu" "F.Mask" "F.Paste")
			(net "VR_PVDDQ_GHJ_PH1_SW")
		)
		(pad "2" smd rect
			(at 0 0.889)
			(size 0.508 0.508)
			(layers "F.Cu" "F.Mask" "F.Paste")
			(net "VR_PVDDQ_GHJ_PH1_SW_RC")
		)
		(zone
			(layer "F.Cu")
			(hatch none 0.5)
			(connect_pads
				(clearance 0)
			)
			(min_thickness 0.25)
			(keepout
				(tracks allowed)
				(vias not_allowed)
				(pads allowed)
				(copperpour not_allowed)
				(footprints allowed)
			)
			(placement
				(enabled no)
				(sheetname "")
			)
			(fill
				(thermal_gap 0.5)
				(thermal_bridge_width 0.5)
				(island_removal_mode 0)
			)
			(polygon
				(pts
					(xy 8.533638 -6.875018) (xy 9.041638 -6.875018) (xy 9.041638 -6.494018) (xy 8.533638 -6.494018)
				)
			)
		)
		(zone
			(layer "F.Cu")
			(hatch none 0.5)
			(connect_pads
				(clearance 0)
			)
			(min_thickness 0.25)
			(keepout
				(tracks not_allowed)
				(vias allowed)
				(pads allowed)
				(copperpour not_allowed)
				(footprints allowed)
			)
			(placement
				(enabled no)
				(sheetname "")
			)
			(fill
				(thermal_gap 0.5)
				(thermal_bridge_width 0.5)
				(island_removal_mode 0)
			)
			(polygon
				(pts
					(xy 8.533638 -6.494018) (xy 9.041638 -6.494018) (xy 9.041638 -6.875018) (xy 8.533638 -6.875018)
				)
			)
		)
	)
	(footprint ""
		(layer "F.Cu")
		(at 417.0045 -64.135 90)
		(property "Reference" "R8E1"
			(at 0 0 90)
			(layer "F.SilkS")
			(hide yes)
			(effects
				(font
					(size 1.27 1.27)
				)
			)
		)
		(property "Value" ""
			(at 0 0 90)
			(layer "F.Fab")
			(effects
				(font
					(size 1.27 1.27)
				)
			)
		)
		(duplicate_pad_numbers_are_jumpers no)
		(fp_poly
			(pts
				(xy -0.2794 -0.1016) (xy 0.2794 -0.1016) (xy 0.2794 0.9906) (xy -0.2794 0.9906)
			)
			(stroke
				(width 0)
				(type default)
			)
			(fill no)
			(layer "F.CrtYd")
		)
		(fp_line
			(start 0.2794 -0.1016)
			(end -0.2794 -0.1016)
			(stroke
				(width 0.1)
				(type default)
			)
			(layer "F.Fab")
		)
		(fp_line
			(start -0.2794 -0.1016)
			(end -0.2794 0.9906)
			(stroke
				(width 0.1)
				(type default)
			)
			(layer "F.Fab")
		)
		(fp_line
			(start 0.2794 0.9906)
			(end 0.2794 -0.1016)
			(stroke
				(width 0.1)
				(type default)
			)
			(layer "F.Fab")
		)
		(fp_line
			(start -0.2794 0.9906)
			(end 0.2794 0.9906)
			(stroke
				(width 0.1)
				(type default)
			)
			(layer "F.Fab")
		)
		(pad "1" smd rect
			(at 0 0 90)
			(size 0.508 0.508)
			(layers "F.Cu" "F.Mask" "F.Paste")
			(net "IRQ_SPI_TPM_N_R")
		)
		(pad "2" smd rect
			(at 0 0.889 90)
			(size 0.508 0.508)
			(layers "F.Cu" "F.Mask" "F.Paste")
			(net "IRQ_PIRQA_SPI_TPM_N")
		)
		(zone
			(layer "F.Cu")
			(hatch none 0.5)
			(connect_pads
				(clearance 0)
			)
			(min_thickness 0.25)
			(keepout
				(tracks allowed)
				(vias not_allowed)
				(pads allowed)
				(copperpour not_allowed)
				(footprints allowed)
			)
			(placement
				(enabled no)
				(sheetname "")
			)
			(fill
				(thermal_gap 0.5)
				(thermal_bridge_width 0.5)
				(island_removal_mode 0)
			)
			(polygon
				(pts
					(xy 417.2585 -63.881) (xy 417.2585 -64.389) (xy 417.6395 -64.389) (xy 417.6395 -63.881)
				)
			)
		)
		(zone
			(layer "F.Cu")
			(hatch none 0.5)
			(connect_pads
				(clearance 0)
			)
			(min_thickness 0.25)
			(keepout
				(tracks not_allowed)
				(vias allowed)
				(pads allowed)
				(copperpour not_allowed)
				(footprints allowed)
			)
			(placement
				(enabled no)
				(sheetname "")
			)
			(fill
				(thermal_gap 0.5)
				(thermal_bridge_width 0.5)
				(island_removal_mode 0)
			)
			(polygon
				(pts
					(xy 417.6395 -63.881) (xy 417.6395 -64.389) (xy 417.2585 -64.389) (xy 417.2585 -63.881)
				)
			)
		)
	)
	(footprint ""
		(layer "F.Cu")
		(at 490.524546 -152.91816 90)
		(property "Reference" "R9A8"
			(at 0 0 90)
			(layer "F.SilkS")
			(hide yes)
			(effects
				(font
					(size 1.27 1.27)
				)
			)
		)
		(property "Value" ""
			(at 0 0 90)
			(layer "F.Fab")
			(effects
				(font
					(size 1.27 1.27)
				)
			)
		)
		(duplicate_pad_numbers_are_jumpers no)
		(fp_poly
			(pts
				(xy -0.2794 -0.1016) (xy 0.2794 -0.1016) (xy 0.2794 0.9906) (xy -0.2794 0.9906)
			)
			(stroke
				(width 0)
				(type default)
			)
			(fill no)
			(layer "F.CrtYd")
		)
		(fp_line
			(start 0.2794 -0.1016)
			(end -0.2794 -0.1016)
			(stroke
				(width 0.1)
				(type default)
			)
			(layer "F.Fab")
		)
		(fp_line
			(start -0.2794 -0.1016)
			(end -0.2794 0.9906)
			(stroke
				(width 0.1)
				(type default)
			)
			(layer "F.Fab")
		)
		(fp_line
			(start 0.2794 0.9906)
			(end 0.2794 -0.1016)
			(stroke
				(width 0.1)
				(type default)
			)
			(layer "F.Fab")
		)
		(fp_line
			(start -0.2794 0.9906)
			(end 0.2794 0.9906)
			(stroke
				(width 0.1)
				(type default)
			)
			(layer "F.Fab")
		)
		(pad "1" smd rect
			(at 0 0 90)
			(size 0.508 0.508)
			(layers "F.Cu" "F.Mask" "F.Paste")
			(net "SPA_SIN_SW_R")
		)
		(pad "2" smd rect
			(at 0 0.889 90)
			(size 0.508 0.508)
			(layers "F.Cu" "F.Mask" "F.Paste")
			(net "SPA_MID_DBG1_RX")
		)
		(zone
			(layer "F.Cu")
			(hatch none 0.5)
			(connect_pads
				(clearance 0)
			)
			(min_thickness 0.25)
			(keepout
				(tracks allowed)
				(vias not_allowed)
				(pads allowed)
				(copperpour not_allowed)
				(footprints allowed)
			)
			(placement
				(enabled no)
				(sheetname "")
			)
			(fill
				(thermal_gap 0.5)
				(thermal_bridge_width 0.5)
				(island_removal_mode 0)
			)
			(polygon
				(pts
					(xy 490.778546 -152.66416) (xy 490.778546 -153.17216) (xy 491.159546 -153.17216) (xy 491.159546 -152.66416)
				)
			)
		)
		(zone
			(layer "F.Cu")
			(hatch none 0.5)
			(connect_pads
				(clearance 0)
			)
			(min_thickness 0.25)
			(keepout
				(tracks not_allowed)
				(vias allowed)
				(pads allowed)
				(copperpour not_allowed)
				(footprints allowed)
			)
			(placement
				(enabled no)
				(sheetname "")
			)
			(fill
				(thermal_gap 0.5)
				(thermal_bridge_width 0.5)
				(island_removal_mode 0)
			)
			(polygon
				(pts
					(xy 491.159546 -152.66416) (xy 491.159546 -153.17216) (xy 490.778546 -153.17216) (xy 490.778546 -152.66416)
				)
			)
		)
	)
	(footprint ""
		(layer "F.Cu")
		(at 98.194368 -79.6036 180)
		(property "Reference" "C2D13"
			(at 0 0 180)
			(layer "F.SilkS")
			(hide yes)
			(effects
				(font
					(size 1.27 1.27)
				)
			)
		)
		(property "Value" ""
			(at 0 0 180)
			(layer "F.Fab")
			(effects
				(font
					(size 1.27 1.27)
				)
			)
		)
		(duplicate_pad_numbers_are_jumpers no)
		(fp_poly
			(pts
				(xy -0.4953 -0.2032) (xy 0.4953 -0.2032) (xy 0.4953 1.6002) (xy -0.4953 1.6002)
			)
			(stroke
				(width 0)
				(type default)
			)
			(fill no)
			(layer "F.CrtYd")
		)
		(fp_line
			(start 0.4953 1.6002)
			(end -0.4953 1.6002)
			(stroke
				(width 0.1)
				(type default)
			)
			(layer "F.Fab")
		)
		(fp_line
			(start 0.4953 -0.2032)
			(end 0.4953 1.6002)
			(stroke
				(width 0.1)
				(type default)
			)
			(layer "F.Fab")
		)
		(fp_line
			(start -0.4953 1.6002)
			(end -0.4953 -0.2032)
			(stroke
				(width 0.1)
				(type default)
			)
			(layer "F.Fab")
		)
		(fp_line
			(start -0.4953 -0.2032)
			(end 0.4953 -0.2032)
			(stroke
				(width 0.1)
				(type default)
			)
			(layer "F.Fab")
		)
		(pad "1" smd rect
			(at 0 0 180)
			(size 0.762 0.889)
			(layers "F.Cu" "F.Mask" "F.Paste")
			(net "PVCCIN_CPU1")
		)
		(pad "2" smd rect
			(at 0 1.397 180)
			(size 0.762 0.889)
			(layers "F.Cu" "F.Mask" "F.Paste")
			(net "GND")
		)
		(zone
			(layer "F.Cu")
			(hatch none 0.5)
			(connect_pads
				(clearance 0)
			)
			(min_thickness 0.25)
			(keepout
				(tracks not_allowed)
				(vias allowed)
				(pads allowed)
				(copperpour not_allowed)
				(footprints allowed)
			)
			(placement
				(enabled no)
				(sheetname "")
			)
			(fill
				(thermal_gap 0.5)
				(thermal_bridge_width 0.5)
				(island_removal_mode 0)
			)
			(polygon
				(pts
					(xy 98.575368 -80.0481) (xy 97.813368 -80.0481) (xy 97.813368 -80.5561) (xy 98.575368 -80.5561)
				)
			)
		)
	)
	(footprint ""
		(layer "F.Cu")
		(at 153.543 -12.954 -90)
		(property "Reference" "C3G3"
			(at 0 0 270)
			(layer "F.SilkS")
			(hide yes)
			(effects
				(font
					(size 1.27 1.27)
				)
			)
		)
		(property "Value" ""
			(at 0 0 270)
			(layer "F.Fab")
			(effects
				(font
					(size 1.27 1.27)
				)
			)
		)
		(duplicate_pad_numbers_are_jumpers no)
		(fp_poly
			(pts
				(xy -0.4953 -0.2032) (xy 0.4953 -0.2032) (xy 0.4953 1.6002) (xy -0.4953 1.6002)
			)
			(stroke
				(width 0)
				(type default)
			)
			(fill no)
			(layer "F.CrtYd")
		)
		(fp_line
			(start -0.4953 1.6002)
			(end -0.4953 -0.2032)
			(stroke
				(width 0.1)
				(type default)
			)
			(layer "F.Fab")
		)
		(fp_line
			(start 0.4953 1.6002)
			(end -0.4953 1.6002)
			(stroke
				(width 0.1)
				(type default)
			)
			(layer "F.Fab")
		)
		(fp_line
			(start -0.4953 -0.2032)
			(end 0.4953 -0.2032)
			(stroke
				(width 0.1)
				(type default)
			)
			(layer "F.Fab")
		)
		(fp_line
			(start 0.4953 -0.2032)
			(end 0.4953 1.6002)
			(stroke
				(width 0.1)
				(type default)
			)
			(layer "F.Fab")
		)
		(pad "1" smd rect
			(at 0 0 270)
			(size 0.762 0.889)
			(layers "F.Cu" "F.Mask" "F.Paste")
			(net "PVPP_GHJ")
		)
		(pad "2" smd rect
			(at 0 1.397 270)
			(size 0.762 0.889)
			(layers "F.Cu" "F.Mask" "F.Paste")
			(net "GND")
		)
		(zone
			(layer "F.Cu")
			(hatch none 0.5)
			(connect_pads
				(clearance 0)
			)
			(min_thickness 0.25)
			(keepout
				(tracks not_allowed)
				(vias allowed)
				(pads allowed)
				(copperpour not_allowed)
				(footprints allowed)
			)
			(placement
				(enabled no)
				(sheetname "")
			)
			(fill
				(thermal_gap 0.5)
				(thermal_bridge_width 0.5)
				(island_removal_mode 0)
			)
			(polygon
				(pts
					(xy 153.0985 -13.335) (xy 153.0985 -12.573) (xy 152.5905 -12.573) (xy 152.5905 -13.335)
				)
			)
		)
	)
	(footprint ""
		(layer "F.Cu")
		(at 452.312024 -146.55546)
		(property "Reference" "R25W185"
			(at -0.8382 -0.67818 0)
			(unlocked yes)
			(layer "F.SilkS")
			(effects
				(font
					(size 0.4064 0.254)
					(thickness 0.1524)
				)
				(justify left)
			)
		)
		(property "Value" ""
			(at 0 0 0)
			(layer "F.Fab")
			(effects
				(font
					(size 1.27 1.27)
				)
			)
		)
		(duplicate_pad_numbers_are_jumpers no)
		(fp_poly
			(pts
				(xy -0.2794 -0.1016) (xy 0.2794 -0.1016) (xy 0.2794 0.9906) (xy -0.2794 0.9906)
			)
			(stroke
				(width 0)
				(type default)
			)
			(fill no)
			(layer "F.CrtYd")
		)
		(fp_line
			(start -0.2794 -0.1016)
			(end -0.2794 0.9906)
			(stroke
				(width 0.1)
				(type default)
			)
			(layer "F.Fab")
		)
		(fp_line
			(start -0.2794 0.9906)
			(end 0.2794 0.9906)
			(stroke
				(width 0.1)
				(type default)
			)
			(layer "F.Fab")
		)
		(fp_line
			(start 0.2794 -0.1016)
			(end -0.2794 -0.1016)
			(stroke
				(width 0.1)
				(type default)
			)
			(layer "F.Fab")
		)
		(fp_line
			(start 0.2794 0.9906)
			(end 0.2794 -0.1016)
			(stroke
				(width 0.1)
				(type default)
			)
			(layer "F.Fab")
		)
		(pad "1" smd rect
			(at 0 0)
			(size 0.508 0.508)
			(layers "F.Cu" "F.Mask" "F.Paste")
			(net "P3V3_STBY")
		)
		(pad "2" smd rect
			(at 0 0.889)
			(size 0.508 0.508)
			(layers "F.Cu" "F.Mask" "F.Paste")
			(net "BMC_JTAG_SEL")
		)
		(zone
			(layer "F.Cu")
			(hatch none 0.5)
			(connect_pads
				(clearance 0)
			)
			(min_thickness 0.25)
			(keepout
				(tracks allowed)
				(vias not_allowed)
				(pads allowed)
				(copperpour not_allowed)
				(footprints allowed)
			)
			(placement
				(enabled no)
				(sheetname "")
			)
			(fill
				(thermal_gap 0.5)
				(thermal_bridge_width 0.5)
				(island_removal_mode 0)
			)
			(polygon
				(pts
					(xy 452.058024 -146.30146) (xy 452.566024 -146.30146) (xy 452.566024 -145.92046) (xy 452.058024 -145.92046)
				)
			)
		)
		(zone
			(layer "F.Cu")
			(hatch none 0.5)
			(connect_pads
				(clearance 0)
			)
			(min_thickness 0.25)
			(keepout
				(tracks not_allowed)
				(vias allowed)
				(pads allowed)
				(copperpour not_allowed)
				(footprints allowed)
			)
			(placement
				(enabled no)
				(sheetname "")
			)
			(fill
				(thermal_gap 0.5)
				(thermal_bridge_width 0.5)
				(island_removal_mode 0)
			)
			(polygon
				(pts
					(xy 452.058024 -145.92046) (xy 452.566024 -145.92046) (xy 452.566024 -146.30146) (xy 452.058024 -146.30146)
				)
			)
		)
	)
	(footprint ""
		(layer "F.Cu")
		(at 111.000032 -140.208 90)
		(property "Reference" "C3A6"
			(at 1.848866 0.752348 90)
			(unlocked yes)
			(layer "F.SilkS")
			(effects
				(font
					(size 1.27 0.9652)
					(thickness 0.1524)
				)
			)
		)
		(property "Value" ""
			(at 0 0 90)
			(layer "F.Fab")
			(effects
				(font
					(size 1.27 1.27)
				)
			)
		)
		(duplicate_pad_numbers_are_jumpers no)
		(fp_rect
			(start -0.500126 1.598422)
			(end 0.500126 -0.201422)
			(stroke
				(width 0)
				(type default)
			)
			(fill no)
			(layer "F.CrtYd")
		)
		(fp_line
			(start 0.500126 -0.201422)
			(end 0.500126 1.598422)
			(stroke
				(width 0.1)
				(type default)
			)
			(layer "F.Fab")
		)
		(fp_line
			(start -0.500126 -0.201422)
			(end 0.500126 -0.201422)
			(stroke
				(width 0.1)
				(type default)
			)
			(layer "F.Fab")
		)
		(fp_line
			(start 0.500126 1.598422)
			(end -0.500126 1.598422)
			(stroke
				(width 0.1)
				(type default)
			)
			(layer "F.Fab")
		)
		(fp_line
			(start -0.500126 1.598422)
			(end -0.500126 -0.201422)
			(stroke
				(width 0.1)
				(type default)
			)
			(layer "F.Fab")
		)
		(pad "1" smd rect
			(at 0 0)
			(size 0.889 0.9906)
			(layers "F.Cu" "F.Mask" "F.Paste")
			(net "PVDDQ_KLM")
		)
		(pad "2" smd rect
			(at 0 1.397)
			(size 0.889 0.9906)
			(layers "F.Cu" "F.Mask" "F.Paste")
			(net "GND")
		)
		(zone
			(layer "F.Cu")
			(hatch none 0.5)
			(connect_pads
				(clearance 0)
			)
			(min_thickness 0.25)
			(keepout
				(tracks allowed)
				(vias not_allowed)
				(pads allowed)
				(copperpour not_allowed)
				(footprints allowed)
			)
			(placement
				(enabled no)
				(sheetname "")
			)
			(fill
				(thermal_gap 0.5)
				(thermal_bridge_width 0.5)
				(island_removal_mode 0)
			)
			(polygon
				(pts
					(xy 111.952532 -139.7127) (xy 111.952532 -140.7033) (xy 111.444532 -140.7033) (xy 111.444532 -139.7127)
				)
			)
		)
		(zone
			(layer "F.Cu")
			(hatch none 0.5)
			(connect_pads
				(clearance 0)
			)
			(min_thickness 0.25)
			(keepout
				(tracks not_allowed)
				(vias allowed)
				(pads allowed)
				(copperpour not_allowed)
				(footprints allowed)
			)
			(placement
				(enabled no)
				(sheetname "")
			)
			(fill
				(thermal_gap 0.5)
				(thermal_bridge_width 0.5)
				(island_removal_mode 0)
			)
			(polygon
				(pts
					(xy 111.952532 -139.7127) (xy 111.952532 -140.7033) (xy 111.444532 -140.7033) (xy 111.444532 -139.7127)
				)
			)
		)
	)
	(footprint ""
		(layer "F.Cu")
		(at 202.273154 -61.205364 -90)
		(property "Reference" "RT4"
			(at 0 0 270)
			(layer "F.SilkS")
			(hide yes)
			(effects
				(font
					(size 1.27 1.27)
				)
			)
		)
		(property "Value" "*"
			(at -0.0254 -2.6289 270)
			(unlocked yes)
			(layer "F.Fab")
			(hide yes)
			(effects
				(font
					(size 1.27 1.016)
					(thickness 0.1524)
				)
			)
		)
		(property "Device Type" "1R3F-GP_RCL_GP-1R3F-GP,64.1R00A"
			(at -0.0254 -4.1529 270)
			(unlocked yes)
			(layer "F.Fab")
			(hide yes)
			(effects
				(font
					(size 1.27 1.016)
					(thickness 0.1524)
				)
			)
		)
		(duplicate_pad_numbers_are_jumpers no)
		(fp_line
			(start -0.4826 0)
			(end -0.2032 0)
			(stroke
				(width 0.2032)
				(type default)
			)
			(layer "F.SilkS")
		)
		(fp_line
			(start 0.2032 0)
			(end 0.4826 0)
			(stroke
				(width 0.2032)
				(type default)
			)
			(layer "F.SilkS")
		)
		(fp_rect
			(start -0.5842 1.3335)
			(end 0.5842 -1.3335)
			(stroke
				(width 0)
				(type default)
			)
			(fill no)
			(layer "F.CrtYd")
		)
		(fp_rect
			(start -0.5842 1.3335)
			(end 0.5842 -1.3335)
			(stroke
				(width 0)
				(type default)
			)
			(fill no)
			(layer "F.Fab")
		)
		(pad "1" smd custom
			(at 0 -0.762 270)
			(size 0.2159 0.2159)
			(layers "F.Cu" "F.Mask" "F.Paste")
			(net "VR_PVCCIN_CPU0_PHASE2_RC")
			(options
				(clearance outline)
				(anchor circle)
			)
			(primitives
				(gr_poly
					(pts
						(arc
							(start -0.3302 -0.4318)
							(mid -0.402042 -0.402042)
							(end -0.4318 -0.3302)
						)
						(arc
							(start -0.4318 0.3302)
							(mid -0.402042 0.402042)
							(end -0.3302 0.4318)
						)
						(arc
							(start 0.3302 0.4318)
							(mid 0.402042 0.402042)
							(end 0.4318 0.3302)
						)
						(arc
							(start 0.4318 -0.3302)
							(mid 0.402042 -0.402042)
							(end 0.3302 -0.4318)
						)
					)
					(width 0)
					(fill yes)
				)
			)
		)
		(pad "2" smd custom
			(at 0 0.762 270)
			(size 0.2159 0.2159)
			(layers "F.Cu" "F.Mask" "F.Paste")
			(net "GND")
			(options
				(clearance outline)
				(anchor circle)
			)
			(primitives
				(gr_poly
					(pts
						(arc
							(start -0.3302 -0.4318)
							(mid -0.402042 -0.402042)
							(end -0.4318 -0.3302)
						)
						(arc
							(start -0.4318 0.3302)
							(mid -0.402042 0.402042)
							(end -0.3302 0.4318)
						)
						(arc
							(start 0.3302 0.4318)
							(mid 0.402042 0.402042)
							(end 0.4318 0.3302)
						)
						(arc
							(start 0.4318 -0.3302)
							(mid 0.402042 -0.402042)
							(end 0.3302 -0.4318)
						)
					)
					(width 0)
					(fill yes)
				)
			)
		)
	)
	(footprint ""
		(layer "F.Cu")
		(at 23.0505 -67.848988 90)
		(property "Reference" "R1W21"
			(at -0.8382 -0.67818 90)
			(unlocked yes)
			(layer "F.SilkS")
			(effects
				(font
					(size 0.4064 0.254)
					(thickness 0.1524)
				)
				(justify left)
			)
		)
		(property "Value" ""
			(at 0 0 90)
			(layer "F.Fab")
			(effects
				(font
					(size 1.27 1.27)
				)
			)
		)
		(duplicate_pad_numbers_are_jumpers no)
		(fp_poly
			(pts
				(xy -0.2794 -0.1016) (xy 0.2794 -0.1016) (xy 0.2794 0.9906) (xy -0.2794 0.9906)
			)
			(stroke
				(width 0)
				(type default)
			)
			(fill no)
			(layer "F.CrtYd")
		)
		(fp_line
			(start 0.2794 -0.1016)
			(end -0.2794 -0.1016)
			(stroke
				(width 0.1)
				(type default)
			)
			(layer "F.Fab")
		)
		(fp_line
			(start -0.2794 -0.1016)
			(end -0.2794 0.9906)
			(stroke
				(width 0.1)
				(type default)
			)
			(layer "F.Fab")
		)
		(fp_line
			(start 0.2794 0.9906)
			(end 0.2794 -0.1016)
			(stroke
				(width 0.1)
				(type default)
			)
			(layer "F.Fab")
		)
		(fp_line
			(start -0.2794 0.9906)
			(end 0.2794 0.9906)
			(stroke
				(width 0.1)
				(type default)
			)
			(layer "F.Fab")
		)
		(pad "1" smd rect
			(at 0 0 90)
			(size 0.508 0.508)
			(layers "F.Cu" "F.Mask" "F.Paste")
			(net "GND")
		)
		(pad "2" smd rect
			(at 0 0.889 90)
			(size 0.508 0.508)
			(layers "F.Cu" "F.Mask" "F.Paste")
			(net "TEMP_SENSOR_E")
		)
		(zone
			(layer "F.Cu")
			(hatch none 0.5)
			(connect_pads
				(clearance 0)
			)
			(min_thickness 0.25)
			(keepout
				(tracks allowed)
				(vias not_allowed)
				(pads allowed)
				(copperpour not_allowed)
				(footprints allowed)
			)
			(placement
				(enabled no)
				(sheetname "")
			)
			(fill
				(thermal_gap 0.5)
				(thermal_bridge_width 0.5)
				(island_removal_mode 0)
			)
			(polygon
				(pts
					(xy 23.3045 -67.594988) (xy 23.3045 -68.102988) (xy 23.6855 -68.102988) (xy 23.6855 -67.594988)
				)
			)
		)
		(zone
			(layer "F.Cu")
			(hatch none 0.5)
			(connect_pads
				(clearance 0)
			)
			(min_thickness 0.25)
			(keepout
				(tracks not_allowed)
				(vias allowed)
				(pads allowed)
				(copperpour not_allowed)
				(footprints allowed)
			)
			(placement
				(enabled no)
				(sheetname "")
			)
			(fill
				(thermal_gap 0.5)
				(thermal_bridge_width 0.5)
				(island_removal_mode 0)
			)
			(polygon
				(pts
					(xy 23.6855 -67.594988) (xy 23.6855 -68.102988) (xy 23.3045 -68.102988) (xy 23.3045 -67.594988)
				)
			)
		)
	)
	(footprint ""
		(layer "F.Cu")
		(at 474.98 -35.7505 180)
		(property "Reference" "R2T46"
			(at 0 0 180)
			(layer "F.SilkS")
			(hide yes)
			(effects
				(font
					(size 1.27 1.27)
				)
			)
		)
		(property "Value" ""
			(at 0 0 180)
			(layer "F.Fab")
			(effects
				(font
					(size 1.27 1.27)
				)
			)
		)
		(duplicate_pad_numbers_are_jumpers no)
		(fp_poly
			(pts
				(xy -0.2794 -0.1016) (xy 0.2794 -0.1016) (xy 0.2794 0.9906) (xy -0.2794 0.9906)
			)
			(stroke
				(width 0)
				(type default)
			)
			(fill no)
			(layer "F.CrtYd")
		)
		(fp_line
			(start 0.2794 0.9906)
			(end 0.2794 -0.1016)
			(stroke
				(width 0.1)
				(type default)
			)
			(layer "F.Fab")
		)
		(fp_line
			(start 0.2794 -0.1016)
			(end -0.2794 -0.1016)
			(stroke
				(width 0.1)
				(type default)
			)
			(layer "F.Fab")
		)
		(fp_line
			(start -0.2794 0.9906)
			(end 0.2794 0.9906)
			(stroke
				(width 0.1)
				(type default)
			)
			(layer "F.Fab")
		)
		(fp_line
			(start -0.2794 -0.1016)
			(end -0.2794 0.9906)
			(stroke
				(width 0.1)
				(type default)
			)
			(layer "F.Fab")
		)
		(pad "1" smd rect
			(at 0 0 180)
			(size 0.508 0.508)
			(layers "F.Cu" "F.Mask" "F.Paste")
			(net "CLK_50M_CKMNG_BMC_1_R")
		)
		(pad "2" smd rect
			(at 0 0.889 180)
			(size 0.508 0.508)
			(layers "F.Cu" "F.Mask" "F.Paste")
			(net "CLK_50M_CKMNG_BMC_1")
		)
		(zone
			(layer "F.Cu")
			(hatch none 0.5)
			(connect_pads
				(clearance 0)
			)
			(min_thickness 0.25)
			(keepout
				(tracks not_allowed)
				(vias allowed)
				(pads allowed)
				(copperpour not_allowed)
				(footprints allowed)
			)
			(placement
				(enabled no)
				(sheetname "")
			)
			(fill
				(thermal_gap 0.5)
				(thermal_bridge_width 0.5)
				(island_removal_mode 0)
			)
			(polygon
				(pts
					(xy 475.234 -36.3855) (xy 474.726 -36.3855) (xy 474.726 -36.0045) (xy 475.234 -36.0045)
				)
			)
		)
		(zone
			(layer "F.Cu")
			(hatch none 0.5)
			(connect_pads
				(clearance 0)
			)
			(min_thickness 0.25)
			(keepout
				(tracks allowed)
				(vias not_allowed)
				(pads allowed)
				(copperpour not_allowed)
				(footprints allowed)
			)
			(placement
				(enabled no)
				(sheetname "")
			)
			(fill
				(thermal_gap 0.5)
				(thermal_bridge_width 0.5)
				(island_removal_mode 0)
			)
			(polygon
				(pts
					(xy 475.234 -36.0045) (xy 474.726 -36.0045) (xy 474.726 -36.3855) (xy 475.234 -36.3855)
				)
			)
		)
	)
	(footprint ""
		(layer "F.Cu")
		(at 205.036928 -65.159382)
		(property "Reference" "L4D3"
			(at 3.378708 -4.251706 0)
			(unlocked yes)
			(layer "F.SilkS")
			(effects
				(font
					(size 0.4064 0.254)
					(thickness 0.1524)
				)
			)
		)
		(property "Value" ""
			(at 0 0 0)
			(layer "F.Fab")
			(effects
				(font
					(size 1.27 1.27)
				)
			)
		)
		(duplicate_pad_numbers_are_jumpers no)
		(fp_line
			(start -1.1303 -3.199892)
			(end 8.3693 -3.199892)
			(stroke
				(width 0.1524)
				(type default)
			)
			(layer "F.SilkS")
		)
		(fp_line
			(start -1.1303 -1.6637)
			(end -1.1303 -3.199892)
			(stroke
				(width 0.1524)
				(type default)
			)
			(layer "F.SilkS")
		)
		(fp_line
			(start -1.1303 3.199892)
			(end -1.1303 1.6637)
			(stroke
				(width 0.1524)
				(type default)
			)
			(layer "F.SilkS")
		)
		(fp_line
			(start 8.3693 -3.199892)
			(end 8.3693 -1.6637)
			(stroke
				(width 0.1524)
				(type default)
			)
			(layer "F.SilkS")
		)
		(fp_line
			(start 8.3693 1.6637)
			(end 8.3693 3.199892)
			(stroke
				(width 0.1524)
				(type default)
			)
			(layer "F.SilkS")
		)
		(fp_line
			(start 8.3693 3.199892)
			(end -1.1303 3.199892)
			(stroke
				(width 0.1524)
				(type default)
			)
			(layer "F.SilkS")
		)
		(fp_rect
			(start -1.1303 3.199892)
			(end 8.3693 -3.199892)
			(stroke
				(width 0)
				(type default)
			)
			(fill no)
			(layer "F.CrtYd")
		)
		(fp_line
			(start -1.1303 -3.199892)
			(end 8.3693 -3.199892)
			(stroke
				(width 0.1)
				(type default)
			)
			(layer "F.Fab")
		)
		(fp_line
			(start -1.1303 3.199892)
			(end -1.1303 -3.199892)
			(stroke
				(width 0.1)
				(type default)
			)
			(layer "F.Fab")
		)
		(fp_line
			(start 8.3693 -3.199892)
			(end 8.3693 3.199892)
			(stroke
				(width 0.1)
				(type default)
			)
			(layer "F.Fab")
		)
		(fp_line
			(start 8.3693 3.199892)
			(end -1.1303 3.199892)
			(stroke
				(width 0.1)
				(type default)
			)
			(layer "F.Fab")
		)
		(pad "1" smd rect
			(at 0 0)
			(size 3.683 2.667)
			(layers "F.Cu" "F.Mask" "F.Paste")
			(net "VR_PVCCIN_CPU0_PHASE2")
		)
		(pad "2" smd rect
			(at 7.239 0)
			(size 3.683 2.667)
			(layers "F.Cu" "F.Mask" "F.Paste")
			(net "PVCCIN_CPU0")
		)
	)
	(footprint ""
		(layer "F.Cu")
		(at 312.142124 -35.623754)
		(property "Reference" "R1W31"
			(at -0.8382 -0.67818 0)
			(unlocked yes)
			(layer "F.SilkS")
			(effects
				(font
					(size 0.4064 0.254)
					(thickness 0.1524)
				)
				(justify left)
			)
		)
		(property "Value" ""
			(at 0 0 0)
			(layer "F.Fab")
			(effects
				(font
					(size 1.27 1.27)
				)
			)
		)
		(duplicate_pad_numbers_are_jumpers no)
		(fp_poly
			(pts
				(xy -0.2794 -0.1016) (xy 0.2794 -0.1016) (xy 0.2794 0.9906) (xy -0.2794 0.9906)
			)
			(stroke
				(width 0)
				(type default)
			)
			(fill no)
			(layer "F.CrtYd")
		)
		(fp_line
			(start -0.2794 -0.1016)
			(end -0.2794 0.9906)
			(stroke
				(width 0.1)
				(type default)
			)
			(layer "F.Fab")
		)
		(fp_line
			(start -0.2794 0.9906)
			(end 0.2794 0.9906)
			(stroke
				(width 0.1)
				(type default)
			)
			(layer "F.Fab")
		)
		(fp_line
			(start 0.2794 -0.1016)
			(end -0.2794 -0.1016)
			(stroke
				(width 0.1)
				(type default)
			)
			(layer "F.Fab")
		)
		(fp_line
			(start 0.2794 0.9906)
			(end 0.2794 -0.1016)
			(stroke
				(width 0.1)
				(type default)
			)
			(layer "F.Fab")
		)
		(pad "1" smd rect
			(at 0 0)
			(size 0.508 0.508)
			(layers "F.Cu" "F.Mask" "F.Paste")
			(net "FM_ADR_COMPLETE_R")
		)
		(pad "2" smd rect
			(at 0 0.889)
			(size 0.508 0.508)
			(layers "F.Cu" "F.Mask" "F.Paste")
			(net "FM_ADR_COMPLETE_CPU1_R")
		)
		(zone
			(layer "F.Cu")
			(hatch none 0.5)
			(connect_pads
				(clearance 0)
			)
			(min_thickness 0.25)
			(keepout
				(tracks allowed)
				(vias not_allowed)
				(pads allowed)
				(copperpour not_allowed)
				(footprints allowed)
			)
			(placement
				(enabled no)
				(sheetname "")
			)
			(fill
				(thermal_gap 0.5)
				(thermal_bridge_width 0.5)
				(island_removal_mode 0)
			)
			(polygon
				(pts
					(xy 311.888124 -35.369754) (xy 312.396124 -35.369754) (xy 312.396124 -34.988754) (xy 311.888124 -34.988754)
				)
			)
		)
		(zone
			(layer "F.Cu")
			(hatch none 0.5)
			(connect_pads
				(clearance 0)
			)
			(min_thickness 0.25)
			(keepout
				(tracks not_allowed)
				(vias allowed)
				(pads allowed)
				(copperpour not_allowed)
				(footprints allowed)
			)
			(placement
				(enabled no)
				(sheetname "")
			)
			(fill
				(thermal_gap 0.5)
				(thermal_bridge_width 0.5)
				(island_removal_mode 0)
			)
			(polygon
				(pts
					(xy 311.888124 -34.988754) (xy 312.396124 -34.988754) (xy 312.396124 -35.369754) (xy 311.888124 -35.369754)
				)
			)
		)
	)
	(footprint ""
		(layer "F.Cu")
		(at 108.368592 -77.429614)
		(property "Reference" "C3D11"
			(at 0 0 0)
			(layer "F.SilkS")
			(hide yes)
			(effects
				(font
					(size 1.27 1.27)
				)
			)
		)
		(property "Value" ""
			(at 0 0 0)
			(layer "F.Fab")
			(effects
				(font
					(size 1.27 1.27)
				)
			)
		)
		(duplicate_pad_numbers_are_jumpers no)
		(fp_poly
			(pts
				(xy -0.4953 -0.2032) (xy 0.4953 -0.2032) (xy 0.4953 1.6002) (xy -0.4953 1.6002)
			)
			(stroke
				(width 0)
				(type default)
			)
			(fill no)
			(layer "F.CrtYd")
		)
		(fp_line
			(start -0.4953 -0.2032)
			(end 0.4953 -0.2032)
			(stroke
				(width 0.1)
				(type default)
			)
			(layer "F.Fab")
		)
		(fp_line
			(start -0.4953 1.6002)
			(end -0.4953 -0.2032)
			(stroke
				(width 0.1)
				(type default)
			)
			(layer "F.Fab")
		)
		(fp_line
			(start 0.4953 -0.2032)
			(end 0.4953 1.6002)
			(stroke
				(width 0.1)
				(type default)
			)
			(layer "F.Fab")
		)
		(fp_line
			(start 0.4953 1.6002)
			(end -0.4953 1.6002)
			(stroke
				(width 0.1)
				(type default)
			)
			(layer "F.Fab")
		)
		(pad "1" smd rect
			(at 0 0)
			(size 0.762 0.889)
			(layers "F.Cu" "F.Mask" "F.Paste")
			(net "PVCCMCP_CPU1")
		)
		(pad "2" smd rect
			(at 0 1.397)
			(size 0.762 0.889)
			(layers "F.Cu" "F.Mask" "F.Paste")
			(net "GND")
		)
		(zone
			(layer "F.Cu")
			(hatch none 0.5)
			(connect_pads
				(clearance 0)
			)
			(min_thickness 0.25)
			(keepout
				(tracks not_allowed)
				(vias allowed)
				(pads allowed)
				(copperpour not_allowed)
				(footprints allowed)
			)
			(placement
				(enabled no)
				(sheetname "")
			)
			(fill
				(thermal_gap 0.5)
				(thermal_bridge_width 0.5)
				(island_removal_mode 0)
			)
			(polygon
				(pts
					(xy 107.987592 -76.985114) (xy 108.749592 -76.985114) (xy 108.749592 -76.477114) (xy 107.987592 -76.477114)
				)
			)
		)
	)
	(footprint ""
		(layer "F.Cu")
		(at 491.0455 -44.0944 90)
		(property "Reference" "R9E13"
			(at 0 0 90)
			(layer "F.SilkS")
			(hide yes)
			(effects
				(font
					(size 1.27 1.27)
				)
			)
		)
		(property "Value" ""
			(at 0 0 90)
			(layer "F.Fab")
			(effects
				(font
					(size 1.27 1.27)
				)
			)
		)
		(duplicate_pad_numbers_are_jumpers no)
		(fp_poly
			(pts
				(xy -0.2794 -0.1016) (xy 0.2794 -0.1016) (xy 0.2794 0.9906) (xy -0.2794 0.9906)
			)
			(stroke
				(width 0)
				(type default)
			)
			(fill no)
			(layer "F.CrtYd")
		)
		(fp_line
			(start 0.2794 -0.1016)
			(end -0.2794 -0.1016)
			(stroke
				(width 0.1)
				(type default)
			)
			(layer "F.Fab")
		)
		(fp_line
			(start -0.2794 -0.1016)
			(end -0.2794 0.9906)
			(stroke
				(width 0.1)
				(type default)
			)
			(layer "F.Fab")
		)
		(fp_line
			(start 0.2794 0.9906)
			(end 0.2794 -0.1016)
			(stroke
				(width 0.1)
				(type default)
			)
			(layer "F.Fab")
		)
		(fp_line
			(start -0.2794 0.9906)
			(end 0.2794 0.9906)
			(stroke
				(width 0.1)
				(type default)
			)
			(layer "F.Fab")
		)
		(pad "1" smd rect
			(at 0 0 90)
			(size 0.508 0.508)
			(layers "F.Cu" "F.Mask" "F.Paste")
			(net "RMII_BMC_PCH_SPRNGVLLE_TXEN")
		)
		(pad "2" smd rect
			(at 0 0.889 90)
			(size 0.508 0.508)
			(layers "F.Cu" "F.Mask" "F.Paste")
			(net "GND")
		)
		(zone
			(layer "F.Cu")
			(hatch none 0.5)
			(connect_pads
				(clearance 0)
			)
			(min_thickness 0.25)
			(keepout
				(tracks allowed)
				(vias not_allowed)
				(pads allowed)
				(copperpour not_allowed)
				(footprints allowed)
			)
			(placement
				(enabled no)
				(sheetname "")
			)
			(fill
				(thermal_gap 0.5)
				(thermal_bridge_width 0.5)
				(island_removal_mode 0)
			)
			(polygon
				(pts
					(xy 491.2995 -43.8404) (xy 491.2995 -44.3484) (xy 491.6805 -44.3484) (xy 491.6805 -43.8404)
				)
			)
		)
		(zone
			(layer "F.Cu")
			(hatch none 0.5)
			(connect_pads
				(clearance 0)
			)
			(min_thickness 0.25)
			(keepout
				(tracks not_allowed)
				(vias allowed)
				(pads allowed)
				(copperpour not_allowed)
				(footprints allowed)
			)
			(placement
				(enabled no)
				(sheetname "")
			)
			(fill
				(thermal_gap 0.5)
				(thermal_bridge_width 0.5)
				(island_removal_mode 0)
			)
			(polygon
				(pts
					(xy 491.6805 -43.8404) (xy 491.6805 -44.3484) (xy 491.2995 -44.3484) (xy 491.2995 -43.8404)
				)
			)
		)
	)
	(footprint ""
		(layer "F.Cu")
		(at 406.7302 -103.7336 -90)
		(property "Reference" "R8C23"
			(at 0 0 270)
			(layer "F.SilkS")
			(hide yes)
			(effects
				(font
					(size 1.27 1.27)
				)
			)
		)
		(property "Value" ""
			(at 0 0 270)
			(layer "F.Fab")
			(effects
				(font
					(size 1.27 1.27)
				)
			)
		)
		(duplicate_pad_numbers_are_jumpers no)
		(fp_poly
			(pts
				(xy -0.2794 -0.1016) (xy 0.2794 -0.1016) (xy 0.2794 0.9906) (xy -0.2794 0.9906)
			)
			(stroke
				(width 0)
				(type default)
			)
			(fill no)
			(layer "F.CrtYd")
		)
		(fp_line
			(start -0.2794 0.9906)
			(end 0.2794 0.9906)
			(stroke
				(width 0.1)
				(type default)
			)
			(layer "F.Fab")
		)
		(fp_line
			(start 0.2794 0.9906)
			(end 0.2794 -0.1016)
			(stroke
				(width 0.1)
				(type default)
			)
			(layer "F.Fab")
		)
		(fp_line
			(start -0.2794 -0.1016)
			(end -0.2794 0.9906)
			(stroke
				(width 0.1)
				(type default)
			)
			(layer "F.Fab")
		)
		(fp_line
			(start 0.2794 -0.1016)
			(end -0.2794 -0.1016)
			(stroke
				(width 0.1)
				(type default)
			)
			(layer "F.Fab")
		)
		(pad "1" smd rect
			(at 0 0 270)
			(size 0.508 0.508)
			(layers "F.Cu" "F.Mask" "F.Paste")
			(net "FM_GBE_LOM_DISABLE_N")
		)
		(pad "2" smd rect
			(at 0 0.889 270)
			(size 0.508 0.508)
			(layers "F.Cu" "F.Mask" "F.Paste")
			(net "FM_10GBE_LOM_DISABLE_N")
		)
		(zone
			(layer "F.Cu")
			(hatch none 0.5)
			(connect_pads
				(clearance 0)
			)
			(min_thickness 0.25)
			(keepout
				(tracks not_allowed)
				(vias allowed)
				(pads allowed)
				(copperpour not_allowed)
				(footprints allowed)
			)
			(placement
				(enabled no)
				(sheetname "")
			)
			(fill
				(thermal_gap 0.5)
				(thermal_bridge_width 0.5)
				(island_removal_mode 0)
			)
			(polygon
				(pts
					(xy 406.0952 -103.9876) (xy 406.0952 -103.4796) (xy 406.4762 -103.4796) (xy 406.4762 -103.9876)
				)
			)
		)
		(zone
			(layer "F.Cu")
			(hatch none 0.5)
			(connect_pads
				(clearance 0)
			)
			(min_thickness 0.25)
			(keepout
				(tracks allowed)
				(vias not_allowed)
				(pads allowed)
				(copperpour not_allowed)
				(footprints allowed)
			)
			(placement
				(enabled no)
				(sheetname "")
			)
			(fill
				(thermal_gap 0.5)
				(thermal_bridge_width 0.5)
				(island_removal_mode 0)
			)
			(polygon
				(pts
					(xy 406.4762 -103.9876) (xy 406.4762 -103.4796) (xy 406.0952 -103.4796) (xy 406.0952 -103.9876)
				)
			)
		)
	)
	(footprint ""
		(layer "F.Cu")
		(at 426.5295 -127.3175 -90)
		(property "Reference" "R8B10"
			(at 0 0 270)
			(layer "F.SilkS")
			(hide yes)
			(effects
				(font
					(size 1.27 1.27)
				)
			)
		)
		(property "Value" ""
			(at 0 0 270)
			(layer "F.Fab")
			(effects
				(font
					(size 1.27 1.27)
				)
			)
		)
		(duplicate_pad_numbers_are_jumpers no)
		(fp_poly
			(pts
				(xy -0.2794 -0.1016) (xy 0.2794 -0.1016) (xy 0.2794 0.9906) (xy -0.2794 0.9906)
			)
			(stroke
				(width 0)
				(type default)
			)
			(fill no)
			(layer "F.CrtYd")
		)
		(fp_line
			(start -0.2794 0.9906)
			(end 0.2794 0.9906)
			(stroke
				(width 0.1)
				(type default)
			)
			(layer "F.Fab")
		)
		(fp_line
			(start 0.2794 0.9906)
			(end 0.2794 -0.1016)
			(stroke
				(width 0.1)
				(type default)
			)
			(layer "F.Fab")
		)
		(fp_line
			(start -0.2794 -0.1016)
			(end -0.2794 0.9906)
			(stroke
				(width 0.1)
				(type default)
			)
			(layer "F.Fab")
		)
		(fp_line
			(start 0.2794 -0.1016)
			(end -0.2794 -0.1016)
			(stroke
				(width 0.1)
				(type default)
			)
			(layer "F.Fab")
		)
		(pad "1" smd rect
			(at 0 0 270)
			(size 0.508 0.508)
			(layers "F.Cu" "F.Mask" "F.Paste")
			(net "PVPP_ABC")
		)
		(pad "2" smd rect
			(at 0 0.889 270)
			(size 0.508 0.508)
			(layers "F.Cu" "F.Mask" "F.Paste")
			(net "IRQ_HFI0_CPU0_LVT2_N")
		)
		(zone
			(layer "F.Cu")
			(hatch none 0.5)
			(connect_pads
				(clearance 0)
			)
			(min_thickness 0.25)
			(keepout
				(tracks not_allowed)
				(vias allowed)
				(pads allowed)
				(copperpour not_allowed)
				(footprints allowed)
			)
			(placement
				(enabled no)
				(sheetname "")
			)
			(fill
				(thermal_gap 0.5)
				(thermal_bridge_width 0.5)
				(island_removal_mode 0)
			)
			(polygon
				(pts
					(xy 425.8945 -127.5715) (xy 425.8945 -127.0635) (xy 426.2755 -127.0635) (xy 426.2755 -127.5715)
				)
			)
		)
		(zone
			(layer "F.Cu")
			(hatch none 0.5)
			(connect_pads
				(clearance 0)
			)
			(min_thickness 0.25)
			(keepout
				(tracks allowed)
				(vias not_allowed)
				(pads allowed)
				(copperpour not_allowed)
				(footprints allowed)
			)
			(placement
				(enabled no)
				(sheetname "")
			)
			(fill
				(thermal_gap 0.5)
				(thermal_bridge_width 0.5)
				(island_removal_mode 0)
			)
			(polygon
				(pts
					(xy 426.2755 -127.5715) (xy 426.2755 -127.0635) (xy 425.8945 -127.0635) (xy 425.8945 -127.5715)
				)
			)
		)
	)
	(footprint ""
		(layer "F.Cu")
		(at 449.69938 -37.1475 90)
		(property "Reference" "R25W20"
			(at 0 0 90)
			(layer "F.SilkS")
			(hide yes)
			(effects
				(font
					(size 1.27 1.27)
				)
			)
		)
		(property "Value" "*"
			(at 0.064008 -4.108196 90)
			(unlocked yes)
			(layer "F.Fab")
			(hide yes)
			(effects
				(font
					(size 1.27 1.016)
					(thickness 0.1524)
				)
			)
		)
		(property "Device Type" "120R2F-GP_RCL_GP-120R2F-GP,64.A"
			(at 0.064008 -5.632196 90)
			(unlocked yes)
			(layer "F.Fab")
			(hide yes)
			(effects
				(font
					(size 1.27 1.016)
					(thickness 0.1524)
				)
			)
		)
		(duplicate_pad_numbers_are_jumpers no)
		(fp_line
			(start 0.508 -0.9398)
			(end -0.508 -0.9398)
			(stroke
				(width 0.1524)
				(type default)
			)
			(layer "F.SilkS")
		)
		(fp_line
			(start -0.508 -0.9398)
			(end -0.508 0.9398)
			(stroke
				(width 0.1524)
				(type default)
			)
			(layer "F.SilkS")
		)
		(fp_rect
			(start -0.508 0.9398)
			(end 0.508 -0.9398)
			(stroke
				(width 0)
				(type default)
			)
			(fill no)
			(layer "F.CrtYd")
		)
		(fp_rect
			(start -0.508 0.9398)
			(end 0.508 -0.9398)
			(stroke
				(width 0)
				(type default)
			)
			(fill no)
			(layer "F.Fab")
		)
		(pad "1" smd custom
			(at 0 -0.4445 90)
			(size 0.1397 0.1397)
			(layers "F.Cu" "F.Mask" "F.Paste")
			(net "GND")
			(options
				(clearance outline)
				(anchor circle)
			)
			(primitives
				(gr_poly
					(pts
						(arc
							(start -0.1778 -0.2794)
							(mid -0.249642 -0.249642)
							(end -0.2794 -0.1778)
						)
						(arc
							(start -0.2794 0.1778)
							(mid -0.249642 0.249642)
							(end -0.1778 0.2794)
						)
						(arc
							(start 0.1778 0.2794)
							(mid 0.249642 0.249642)
							(end 0.2794 0.1778)
						)
						(arc
							(start 0.2794 -0.1778)
							(mid 0.249642 -0.249642)
							(end 0.1778 -0.2794)
						)
					)
					(width 0)
					(fill yes)
				)
			)
		)
		(pad "2" smd custom
			(at 0 0.4445 90)
			(size 0.1397 0.1397)
			(layers "F.Cu" "F.Mask" "F.Paste")
			(net "BMC_M_A8")
			(options
				(clearance outline)
				(anchor circle)
			)
			(primitives
				(gr_poly
					(pts
						(arc
							(start -0.1778 -0.2794)
							(mid -0.249642 -0.249642)
							(end -0.2794 -0.1778)
						)
						(arc
							(start -0.2794 0.1778)
							(mid -0.249642 0.249642)
							(end -0.1778 0.2794)
						)
						(arc
							(start 0.1778 0.2794)
							(mid 0.249642 0.249642)
							(end 0.2794 0.1778)
						)
						(arc
							(start 0.2794 -0.1778)
							(mid 0.249642 -0.249642)
							(end 0.1778 -0.2794)
						)
					)
					(width 0)
					(fill yes)
				)
			)
		)
	)
	(footprint ""
		(layer "F.Cu")
		(at 155.2956 -12.954 90)
		(property "Reference" "C3G4"
			(at 0 0 90)
			(layer "F.SilkS")
			(hide yes)
			(effects
				(font
					(size 1.27 1.27)
				)
			)
		)
		(property "Value" ""
			(at 0 0 90)
			(layer "F.Fab")
			(effects
				(font
					(size 1.27 1.27)
				)
			)
		)
		(duplicate_pad_numbers_are_jumpers no)
		(fp_poly
			(pts
				(xy -0.4953 -0.2032) (xy 0.4953 -0.2032) (xy 0.4953 1.6002) (xy -0.4953 1.6002)
			)
			(stroke
				(width 0)
				(type default)
			)
			(fill no)
			(layer "F.CrtYd")
		)
		(fp_line
			(start 0.4953 -0.2032)
			(end 0.4953 1.6002)
			(stroke
				(width 0.1)
				(type default)
			)
			(layer "F.Fab")
		)
		(fp_line
			(start -0.4953 -0.2032)
			(end 0.4953 -0.2032)
			(stroke
				(width 0.1)
				(type default)
			)
			(layer "F.Fab")
		)
		(fp_line
			(start 0.4953 1.6002)
			(end -0.4953 1.6002)
			(stroke
				(width 0.1)
				(type default)
			)
			(layer "F.Fab")
		)
		(fp_line
			(start -0.4953 1.6002)
			(end -0.4953 -0.2032)
			(stroke
				(width 0.1)
				(type default)
			)
			(layer "F.Fab")
		)
		(pad "1" smd rect
			(at 0 0 90)
			(size 0.762 0.889)
			(layers "F.Cu" "F.Mask" "F.Paste")
			(net "PVPP_GHJ")
		)
		(pad "2" smd rect
			(at 0 1.397 90)
			(size 0.762 0.889)
			(layers "F.Cu" "F.Mask" "F.Paste")
			(net "GND")
		)
		(zone
			(layer "F.Cu")
			(hatch none 0.5)
			(connect_pads
				(clearance 0)
			)
			(min_thickness 0.25)
			(keepout
				(tracks not_allowed)
				(vias allowed)
				(pads allowed)
				(copperpour not_allowed)
				(footprints allowed)
			)
			(placement
				(enabled no)
				(sheetname "")
			)
			(fill
				(thermal_gap 0.5)
				(thermal_bridge_width 0.5)
				(island_removal_mode 0)
			)
			(polygon
				(pts
					(xy 155.7401 -12.573) (xy 155.7401 -13.335) (xy 156.2481 -13.335) (xy 156.2481 -12.573)
				)
			)
		)
	)
	(footprint ""
		(layer "F.Cu")
		(at 492.315246 -20.549108 90)
		(property "Reference" "Q7E7"
			(at 4.16433 -1.143 0)
			(unlocked yes)
			(layer "F.SilkS")
			(effects
				(font
					(size 0.7874 0.5842)
					(thickness 0.1524)
				)
				(justify left)
			)
		)
		(property "Value" ""
			(at 0 0 90)
			(layer "F.Fab")
			(effects
				(font
					(size 1.27 1.27)
				)
			)
		)
		(duplicate_pad_numbers_are_jumpers no)
		(fp_line
			(start -0.245364 -1.379982)
			(end 3.15468 -1.379982)
			(stroke
				(width 0.1524)
				(type default)
			)
			(layer "F.SilkS")
		)
		(fp_line
			(start -0.245364 2.020062)
			(end 3.15468 2.020062)
			(stroke
				(width 0.1524)
				(type default)
			)
			(layer "F.SilkS")
		)
		(fp_circle
			(center -0.94996 -1.512316)
			(end -0.94996 -1.385316)
			(stroke
				(width 0.254)
				(type default)
			)
			(fill no)
			(layer "F.SilkS")
		)
		(fp_poly
			(pts
				(xy 0.890016 -0.82296) (xy 0.890016 1.46304) (xy 3.404616 1.46304) (xy 3.404616 1.13284) (xy 2.617216 1.13284)
				(xy 2.617216 0.811022) (xy 3.404616 0.811022) (xy 3.404616 0.480822) (xy 2.617216 0.480822) (xy 2.617216 0.159258)
				(xy 3.404616 0.159258) (xy 3.404616 -0.170942) (xy 2.617216 -0.170942) (xy 2.617216 -0.49276) (xy 3.404616 -0.49276)
				(xy 3.404616 -0.82296)
			)
			(stroke
				(width 0)
				(type default)
			)
			(fill yes)
			(layer "F.Paste")
		)
		(fp_poly
			(pts
				(xy -0.245364 -1.379982) (xy -0.245364 2.020062) (xy 3.15468 2.020062) (xy 3.15468 -1.379982)
			)
			(stroke
				(width 0)
				(type default)
			)
			(fill no)
			(layer "F.CrtYd")
		)
		(fp_line
			(start 3.15468 -1.379982)
			(end 3.15468 2.020062)
			(stroke
				(width 0.1)
				(type default)
			)
			(layer "F.Fab")
		)
		(fp_line
			(start -0.245364 -1.379982)
			(end 3.15468 -1.379982)
			(stroke
				(width 0.1)
				(type default)
			)
			(layer "F.Fab")
		)
		(fp_line
			(start 3.15468 2.020062)
			(end -0.245364 2.020062)
			(stroke
				(width 0.1)
				(type default)
			)
			(layer "F.Fab")
		)
		(fp_line
			(start -0.245364 2.020062)
			(end -0.245364 -1.379982)
			(stroke
				(width 0.1)
				(type default)
			)
			(layer "F.Fab")
		)
		(fp_circle
			(center -0.94996 -1.512316)
			(end -0.94996 -1.385316)
			(stroke
				(width 0.254)
				(type default)
			)
			(fill no)
			(layer "F.Fab")
		)
		(pad "1" smd custom
			(at 0 0 90)
			(size 0.24765 0.24765)
			(layers "F.Cu" "F.Mask" "F.Paste")
			(net "P12V")
			(options
				(clearance outline)
				(anchor circle)
			)
			(primitives
				(gr_poly
					(pts
						(xy 0.4953 0.8255) (xy 0.4953 -0.8255) (xy -0.4953 -0.8255) (xy -0.4953 -0.4953) (xy 0.0127 -0.4953)
						(xy 0.0127 -0.1651) (xy -0.4953 -0.1651) (xy -0.4953 0.1651) (xy 0.0127 0.1651) (xy 0.0127 0.4953)
						(xy -0.4953 0.4953) (xy -0.4953 0.8255)
					)
					(width 0)
					(fill yes)
				)
			)
		)
		(pad "4" smd rect
			(at 0 1.30048 90)
			(size 0.9906 0.3302)
			(layers "F.Cu" "F.Mask" "F.Paste")
			(net "P12V_SWITCH_G")
		)
		(pad "5" smd custom
			(at 2.147316 0.32004 90)
			(size 0.5715 0.5715)
			(layers "F.Cu" "F.Mask" "F.Paste")
			(net "P12V_STBY")
			(options
				(clearance outline)
				(anchor circle)
			)
			(primitives
				(gr_poly
					(pts
						(xy -1.2573 -1.143) (xy -1.2573 1.143) (xy 1.2573 1.143) (xy 1.2573 0.8128) (xy 0.4699 0.8128)
						(xy 0.4699 0.490982) (xy 1.2573 0.490982) (xy 1.2573 0.160782) (xy 0.4699 0.160782) (xy 0.4699 -0.160782)
						(xy 1.2573 -0.160782) (xy 1.2573 -0.490982) (xy 0.4699 -0.490982) (xy 0.4699 -0.8128) (xy 1.2573 -0.8128)
						(xy 1.2573 -1.143)
					)
					(width 0)
					(fill yes)
				)
			)
		)
	)
	(footprint ""
		(layer "F.Cu")
		(at 407.8351 -63.373 -90)
		(property "Reference" "R8E6"
			(at 0 0 270)
			(layer "F.SilkS")
			(hide yes)
			(effects
				(font
					(size 1.27 1.27)
				)
			)
		)
		(property "Value" ""
			(at 0 0 270)
			(layer "F.Fab")
			(effects
				(font
					(size 1.27 1.27)
				)
			)
		)
		(duplicate_pad_numbers_are_jumpers no)
		(fp_poly
			(pts
				(xy -0.2794 -0.1016) (xy 0.2794 -0.1016) (xy 0.2794 0.9906) (xy -0.2794 0.9906)
			)
			(stroke
				(width 0)
				(type default)
			)
			(fill no)
			(layer "F.CrtYd")
		)
		(pad "1" smd rect
			(at 0 0 270)
			(size 0.508 0.508)
			(layers "F.Cu" "F.Mask" "F.Paste")
			(net "P3V3_STBY")
		)
		(pad "2" smd rect
			(at 0 0.889 270)
			(size 0.508 0.508)
			(layers "F.Cu" "F.Mask" "F.Paste")
			(net "SPI_PCH_MOSI")
		)
		(zone
			(layer "F.Cu")
			(hatch none 0.5)
			(connect_pads
				(clearance 0)
			)
			(min_thickness 0.25)
			(keepout
				(tracks not_allowed)
				(vias allowed)
				(pads allowed)
				(copperpour not_allowed)
				(footprints allowed)
			)
			(placement
				(enabled no)
				(sheetname "")
			)
			(fill
				(thermal_gap 0.5)
				(thermal_bridge_width 0.5)
				(island_removal_mode 0)
			)
			(polygon
				(pts
					(xy 407.2001 -63.627) (xy 407.2001 -63.119) (xy 407.5811 -63.119) (xy 407.5811 -63.627)
				)
			)
		)
		(zone
			(layer "F.Cu")
			(hatch none 0.5)
			(connect_pads
				(clearance 0)
			)
			(min_thickness 0.25)
			(keepout
				(tracks allowed)
				(vias not_allowed)
				(pads allowed)
				(copperpour not_allowed)
				(footprints allowed)
			)
			(placement
				(enabled no)
				(sheetname "")
			)
			(fill
				(thermal_gap 0.5)
				(thermal_bridge_width 0.5)
				(island_removal_mode 0)
			)
			(polygon
				(pts
					(xy 407.5811 -63.627) (xy 407.5811 -63.119) (xy 407.2001 -63.119) (xy 407.2001 -63.627)
				)
			)
		)
	)
	(footprint ""
		(layer "F.Cu")
		(at 3.2004 -5.675376 -90)
		(property "Reference" "C1G6"
			(at 0 0 270)
			(layer "F.SilkS")
			(hide yes)
			(effects
				(font
					(size 1.27 1.27)
				)
			)
		)
		(property "Value" ""
			(at 0 0 270)
			(layer "F.Fab")
			(effects
				(font
					(size 1.27 1.27)
				)
			)
		)
		(duplicate_pad_numbers_are_jumpers no)
		(fp_poly
			(pts
				(xy 0.3048 -0.1016) (xy 0.3048 0.9906) (xy -0.3048 0.9906) (xy -0.3048 -0.1016)
			)
			(stroke
				(width 0)
				(type default)
			)
			(fill no)
			(layer "F.CrtYd")
		)
		(fp_line
			(start -0.3048 0.9906)
			(end 0.3048 0.9906)
			(stroke
				(width 0.1)
				(type default)
			)
			(layer "F.Fab")
		)
		(fp_line
			(start 0.3048 0.9906)
			(end 0.3048 -0.1016)
			(stroke
				(width 0.1)
				(type default)
			)
			(layer "F.Fab")
		)
		(fp_line
			(start -0.3048 -0.1016)
			(end -0.3048 0.9906)
			(stroke
				(width 0.1)
				(type default)
			)
			(layer "F.Fab")
		)
		(fp_line
			(start 0.3048 -0.1016)
			(end -0.3048 -0.1016)
			(stroke
				(width 0.1)
				(type default)
			)
			(layer "F.Fab")
		)
		(pad "1" smd rect
			(at 0 0 270)
			(size 0.508 0.508)
			(layers "F.Cu" "F.Mask" "F.Paste")
			(net "VR_PVDDQ_GHJ_PH1_VCIN")
		)
		(pad "2" smd rect
			(at 0 0.889 270)
			(size 0.508 0.508)
			(layers "F.Cu" "F.Mask" "F.Paste")
			(net "GND")
		)
		(zone
			(layer "F.Cu")
			(hatch none 0.5)
			(connect_pads
				(clearance 0)
			)
			(min_thickness 0.25)
			(keepout
				(tracks not_allowed)
				(vias allowed)
				(pads allowed)
				(copperpour not_allowed)
				(footprints allowed)
			)
			(placement
				(enabled no)
				(sheetname "")
			)
			(fill
				(thermal_gap 0.5)
				(thermal_bridge_width 0.5)
				(island_removal_mode 0)
			)
			(polygon
				(pts
					(xy 2.5654 -5.929376) (xy 2.5654 -5.421376) (xy 2.9464 -5.421376) (xy 2.9464 -5.929376)
				)
			)
		)
		(zone
			(layer "F.Cu")
			(hatch none 0.5)
			(connect_pads
				(clearance 0)
			)
			(min_thickness 0.25)
			(keepout
				(tracks allowed)
				(vias not_allowed)
				(pads allowed)
				(copperpour not_allowed)
				(footprints allowed)
			)
			(placement
				(enabled no)
				(sheetname "")
			)
			(fill
				(thermal_gap 0.5)
				(thermal_bridge_width 0.5)
				(island_removal_mode 0)
			)
			(polygon
				(pts
					(xy 2.9464 -5.929376) (xy 2.9464 -5.421376) (xy 2.5654 -5.421376) (xy 2.5654 -5.929376)
				)
			)
		)
	)
	(footprint ""
		(layer "F.Cu")
		(at 498.620034 -138.678666 90)
		(property "Reference" "DS9A4"
			(at -0.60071 0.94742 0)
			(unlocked yes)
			(layer "F.SilkS")
			(effects
				(font
					(size 0.7874 0.5842)
					(thickness 0.1524)
				)
			)
		)
		(property "Value" ""
			(at 0 0 90)
			(layer "F.Fab")
			(effects
				(font
					(size 1.27 1.27)
				)
			)
		)
		(duplicate_pad_numbers_are_jumpers no)
		(fp_line
			(start 0.992632 -1.34874)
			(end 0.992632 -0.437134)
			(stroke
				(width 0.1524)
				(type default)
			)
			(layer "F.SilkS")
		)
		(fp_line
			(start 1.473454 -0.437134)
			(end 0.992632 0.395732)
			(stroke
				(width 0.1524)
				(type default)
			)
			(layer "F.SilkS")
		)
		(fp_line
			(start 0.992632 -0.437134)
			(end 1.473454 -0.437134)
			(stroke
				(width 0.1524)
				(type default)
			)
			(layer "F.SilkS")
		)
		(fp_line
			(start 0.51181 -0.437134)
			(end 0.992632 -0.437134)
			(stroke
				(width 0.1524)
				(type default)
			)
			(layer "F.SilkS")
		)
		(fp_line
			(start 0.992632 0.395732)
			(end 0.51181 -0.437134)
			(stroke
				(width 0.1524)
				(type default)
			)
			(layer "F.SilkS")
		)
		(fp_line
			(start 0.51181 0.395732)
			(end 1.473454 0.395732)
			(stroke
				(width 0.1524)
				(type default)
			)
			(layer "F.SilkS")
		)
		(fp_line
			(start 0.992632 1.519174)
			(end 0.992632 0.395732)
			(stroke
				(width 0.1524)
				(type default)
			)
			(layer "F.SilkS")
		)
		(fp_rect
			(start -0.4064 1.6891)
			(end 0.4064 0.0889)
			(stroke
				(width 0)
				(type default)
			)
			(fill no)
			(layer "F.CrtYd")
		)
		(fp_line
			(start 1.473454 -0.437134)
			(end 0.992632 0.395732)
			(stroke
				(width 0.1)
				(type default)
			)
			(layer "F.Fab")
		)
		(fp_line
			(start 0.992632 -0.437134)
			(end 0.992632 -1.34874)
			(stroke
				(width 0.1)
				(type default)
			)
			(layer "F.Fab")
		)
		(fp_line
			(start 0.51181 -0.437134)
			(end 1.473454 -0.437134)
			(stroke
				(width 0.1)
				(type default)
			)
			(layer "F.Fab")
		)
		(fp_line
			(start 0.4064 0.0889)
			(end 0.4064 1.6891)
			(stroke
				(width 0.1)
				(type default)
			)
			(layer "F.Fab")
		)
		(fp_line
			(start -0.4064 0.0889)
			(end 0.4064 0.0889)
			(stroke
				(width 0.1)
				(type default)
			)
			(layer "F.Fab")
		)
		(fp_line
			(start 0.992632 0.395732)
			(end 0.51181 -0.437134)
			(stroke
				(width 0.1)
				(type default)
			)
			(layer "F.Fab")
		)
		(fp_line
			(start 0.992632 0.395732)
			(end 0.992632 1.519174)
			(stroke
				(width 0.1)
				(type default)
			)
			(layer "F.Fab")
		)
		(fp_line
			(start 0.51181 0.395732)
			(end 1.473454 0.395732)
			(stroke
				(width 0.1)
				(type default)
			)
			(layer "F.Fab")
		)
		(fp_line
			(start 0.4064 1.6891)
			(end -0.4064 1.6891)
			(stroke
				(width 0.1)
				(type default)
			)
			(layer "F.Fab")
		)
		(fp_line
			(start -0.4064 1.6891)
			(end -0.4064 0.0889)
			(stroke
				(width 0.1)
				(type default)
			)
			(layer "F.Fab")
		)
		(pad "1" smd rect
			(at 0 0 90)
			(size 0.762 1.27)
			(layers "F.Cu" "F.Mask" "F.Paste")
			(net "FM_UARTSW_LSB_R_N")
		)
		(pad "2" smd rect
			(at 0 1.778 90)
			(size 0.762 1.27)
			(layers "F.Cu" "F.Mask" "F.Paste")
			(net "FM_UARTSW_LSB_N")
		)
		(zone
			(layer "F.Cu")
			(hatch none 0.5)
			(connect_pads
				(clearance 0)
			)
			(min_thickness 0.25)
			(keepout
				(tracks not_allowed)
				(vias allowed)
				(pads allowed)
				(copperpour not_allowed)
				(footprints allowed)
			)
			(placement
				(enabled no)
				(sheetname "")
			)
			(fill
				(thermal_gap 0.5)
				(thermal_bridge_width 0.5)
				(island_removal_mode 0)
			)
			(polygon
				(pts
					(xy 499.280434 -138.297666) (xy 499.280434 -139.059666) (xy 499.737634 -139.059666) (xy 499.737634 -138.297666)
				)
			)
		)
		(zone
			(layer "F.Cu")
			(hatch none 0.5)
			(connect_pads
				(clearance 0)
			)
			(min_thickness 0.25)
			(keepout
				(tracks allowed)
				(vias not_allowed)
				(pads allowed)
				(copperpour not_allowed)
				(footprints allowed)
			)
			(placement
				(enabled no)
				(sheetname "")
			)
			(fill
				(thermal_gap 0.5)
				(thermal_bridge_width 0.5)
				(island_removal_mode 0)
			)
			(polygon
				(pts
					(xy 499.737634 -138.297666) (xy 499.737634 -139.059666) (xy 499.280434 -139.059666) (xy 499.280434 -138.297666)
				)
			)
		)
	)
	(footprint ""
		(layer "F.Cu")
		(at 92.911168 -149.8092 -90)
		(property "Reference" "C2A5"
			(at 0 0 270)
			(layer "F.SilkS")
			(hide yes)
			(effects
				(font
					(size 1.27 1.27)
				)
			)
		)
		(property "Value" ""
			(at 0 0 270)
			(layer "F.Fab")
			(effects
				(font
					(size 1.27 1.27)
				)
			)
		)
		(duplicate_pad_numbers_are_jumpers no)
		(fp_rect
			(start -0.500126 1.598422)
			(end 0.500126 -0.201422)
			(stroke
				(width 0)
				(type default)
			)
			(fill no)
			(layer "F.CrtYd")
		)
		(fp_line
			(start -0.500126 1.598422)
			(end -0.500126 -0.201422)
			(stroke
				(width 0.1)
				(type default)
			)
			(layer "F.Fab")
		)
		(fp_line
			(start 0.500126 1.598422)
			(end -0.500126 1.598422)
			(stroke
				(width 0.1)
				(type default)
			)
			(layer "F.Fab")
		)
		(fp_line
			(start -0.500126 -0.201422)
			(end 0.500126 -0.201422)
			(stroke
				(width 0.1)
				(type default)
			)
			(layer "F.Fab")
		)
		(fp_line
			(start 0.500126 -0.201422)
			(end 0.500126 1.598422)
			(stroke
				(width 0.1)
				(type default)
			)
			(layer "F.Fab")
		)
		(pad "1" smd rect
			(at 0 0 180)
			(size 0.889 0.9906)
			(layers "F.Cu" "F.Mask" "F.Paste")
			(net "PVDDQ_KLM")
		)
		(pad "2" smd rect
			(at 0 1.397 180)
			(size 0.889 0.9906)
			(layers "F.Cu" "F.Mask" "F.Paste")
			(net "GND")
		)
		(zone
			(layer "F.Cu")
			(hatch none 0.5)
			(connect_pads
				(clearance 0)
			)
			(min_thickness 0.25)
			(keepout
				(tracks allowed)
				(vias not_allowed)
				(pads allowed)
				(copperpour not_allowed)
				(footprints allowed)
			)
			(placement
				(enabled no)
				(sheetname "")
			)
			(fill
				(thermal_gap 0.5)
				(thermal_bridge_width 0.5)
				(island_removal_mode 0)
			)
			(polygon
				(pts
					(xy 91.958668 -150.3045) (xy 91.958668 -149.3139) (xy 92.466668 -149.3139) (xy 92.466668 -150.3045)
				)
			)
		)
		(zone
			(layer "F.Cu")
			(hatch none 0.5)
			(connect_pads
				(clearance 0)
			)
			(min_thickness 0.25)
			(keepout
				(tracks not_allowed)
				(vias allowed)
				(pads allowed)
				(copperpour not_allowed)
				(footprints allowed)
			)
			(placement
				(enabled no)
				(sheetname "")
			)
			(fill
				(thermal_gap 0.5)
				(thermal_bridge_width 0.5)
				(island_removal_mode 0)
			)
			(polygon
				(pts
					(xy 91.958668 -150.3045) (xy 91.958668 -149.3139) (xy 92.466668 -149.3139) (xy 92.466668 -150.3045)
				)
			)
		)
	)
	(footprint ""
		(layer "F.Cu")
		(at 194.7418 -84.3026 -90)
		(property "Reference" "C4D10"
			(at 0 0 270)
			(layer "F.SilkS")
			(hide yes)
			(effects
				(font
					(size 1.27 1.27)
				)
			)
		)
		(property "Value" ""
			(at 0 0 270)
			(layer "F.Fab")
			(effects
				(font
					(size 1.27 1.27)
				)
			)
		)
		(duplicate_pad_numbers_are_jumpers no)
		(fp_poly
			(pts
				(xy 0.3048 -0.1016) (xy 0.3048 0.9906) (xy -0.3048 0.9906) (xy -0.3048 -0.1016)
			)
			(stroke
				(width 0)
				(type default)
			)
			(fill no)
			(layer "F.CrtYd")
		)
		(fp_line
			(start -0.3048 0.9906)
			(end 0.3048 0.9906)
			(stroke
				(width 0.1)
				(type default)
			)
			(layer "F.Fab")
		)
		(fp_line
			(start 0.3048 0.9906)
			(end 0.3048 -0.1016)
			(stroke
				(width 0.1)
				(type default)
			)
			(layer "F.Fab")
		)
		(fp_line
			(start -0.3048 -0.1016)
			(end -0.3048 0.9906)
			(stroke
				(width 0.1)
				(type default)
			)
			(layer "F.Fab")
		)
		(fp_line
			(start 0.3048 -0.1016)
			(end -0.3048 -0.1016)
			(stroke
				(width 0.1)
				(type default)
			)
			(layer "F.Fab")
		)
		(pad "1" smd rect
			(at 0 0 270)
			(size 0.508 0.508)
			(layers "F.Cu" "F.Mask" "F.Paste")
			(net "VR_FET_SW_P12V_STBY_PVCCIN_CPU0")
		)
		(pad "2" smd rect
			(at 0 0.889 270)
			(size 0.508 0.508)
			(layers "F.Cu" "F.Mask" "F.Paste")
			(net "GND")
		)
		(zone
			(layer "F.Cu")
			(hatch none 0.5)
			(connect_pads
				(clearance 0)
			)
			(min_thickness 0.25)
			(keepout
				(tracks not_allowed)
				(vias allowed)
				(pads allowed)
				(copperpour not_allowed)
				(footprints allowed)
			)
			(placement
				(enabled no)
				(sheetname "")
			)
			(fill
				(thermal_gap 0.5)
				(thermal_bridge_width 0.5)
				(island_removal_mode 0)
			)
			(polygon
				(pts
					(xy 194.1068 -84.5566) (xy 194.1068 -84.0486) (xy 194.4878 -84.0486) (xy 194.4878 -84.5566)
				)
			)
		)
		(zone
			(layer "F.Cu")
			(hatch none 0.5)
			(connect_pads
				(clearance 0)
			)
			(min_thickness 0.25)
			(keepout
				(tracks allowed)
				(vias not_allowed)
				(pads allowed)
				(copperpour not_allowed)
				(footprints allowed)
			)
			(placement
				(enabled no)
				(sheetname "")
			)
			(fill
				(thermal_gap 0.5)
				(thermal_bridge_width 0.5)
				(island_removal_mode 0)
			)
			(polygon
				(pts
					(xy 194.4878 -84.5566) (xy 194.4878 -84.0486) (xy 194.1068 -84.0486) (xy 194.1068 -84.5566)
				)
			)
		)
	)
	(footprint ""
		(layer "F.Cu")
		(at 449.69938 -38.2905 90)
		(property "Reference" "R25W23"
			(at 0 0 90)
			(layer "F.SilkS")
			(hide yes)
			(effects
				(font
					(size 1.27 1.27)
				)
			)
		)
		(property "Value" "*"
			(at 0.064008 -4.108196 90)
			(unlocked yes)
			(layer "F.Fab")
			(hide yes)
			(effects
				(font
					(size 1.27 1.016)
					(thickness 0.1524)
				)
			)
		)
		(property "Device Type" "120R2F-GP_RCL_GP-120R2F-GP,64.A"
			(at 0.064008 -5.632196 90)
			(unlocked yes)
			(layer "F.Fab")
			(hide yes)
			(effects
				(font
					(size 1.27 1.016)
					(thickness 0.1524)
				)
			)
		)
		(duplicate_pad_numbers_are_jumpers no)
		(fp_line
			(start 0.508 -0.9398)
			(end -0.508 -0.9398)
			(stroke
				(width 0.1524)
				(type default)
			)
			(layer "F.SilkS")
		)
		(fp_line
			(start -0.508 -0.9398)
			(end -0.508 0.9398)
			(stroke
				(width 0.1524)
				(type default)
			)
			(layer "F.SilkS")
		)
		(fp_rect
			(start -0.508 0.9398)
			(end 0.508 -0.9398)
			(stroke
				(width 0)
				(type default)
			)
			(fill no)
			(layer "F.CrtYd")
		)
		(fp_rect
			(start -0.508 0.9398)
			(end 0.508 -0.9398)
			(stroke
				(width 0)
				(type default)
			)
			(fill no)
			(layer "F.Fab")
		)
		(pad "1" smd custom
			(at 0 -0.4445 90)
			(size 0.1397 0.1397)
			(layers "F.Cu" "F.Mask" "F.Paste")
			(net "GND")
			(options
				(clearance outline)
				(anchor circle)
			)
			(primitives
				(gr_poly
					(pts
						(arc
							(start -0.1778 -0.2794)
							(mid -0.249642 -0.249642)
							(end -0.2794 -0.1778)
						)
						(arc
							(start -0.2794 0.1778)
							(mid -0.249642 0.249642)
							(end -0.1778 0.2794)
						)
						(arc
							(start 0.1778 0.2794)
							(mid 0.249642 0.249642)
							(end 0.2794 0.1778)
						)
						(arc
							(start 0.2794 -0.1778)
							(mid 0.249642 -0.249642)
							(end 0.1778 -0.2794)
						)
					)
					(width 0)
					(fill yes)
				)
			)
		)
		(pad "2" smd custom
			(at 0 0.4445 90)
			(size 0.1397 0.1397)
			(layers "F.Cu" "F.Mask" "F.Paste")
			(net "BMC_M_A11")
			(options
				(clearance outline)
				(anchor circle)
			)
			(primitives
				(gr_poly
					(pts
						(arc
							(start -0.1778 -0.2794)
							(mid -0.249642 -0.249642)
							(end -0.2794 -0.1778)
						)
						(arc
							(start -0.2794 0.1778)
							(mid -0.249642 0.249642)
							(end -0.1778 0.2794)
						)
						(arc
							(start 0.1778 0.2794)
							(mid 0.249642 0.249642)
							(end 0.2794 0.1778)
						)
						(arc
							(start 0.2794 -0.1778)
							(mid 0.249642 -0.249642)
							(end 0.1778 -0.2794)
						)
					)
					(width 0)
					(fill yes)
				)
			)
		)
	)
	(footprint ""
		(layer "F.Cu")
		(at 363.249718 -72.133206 180)
		(property "Reference" "R7D42"
			(at 0 0 180)
			(layer "F.SilkS")
			(hide yes)
			(effects
				(font
					(size 1.27 1.27)
				)
			)
		)
		(property "Value" ""
			(at 0 0 180)
			(layer "F.Fab")
			(effects
				(font
					(size 1.27 1.27)
				)
			)
		)
		(duplicate_pad_numbers_are_jumpers no)
		(fp_poly
			(pts
				(xy -0.2794 -0.1016) (xy 0.2794 -0.1016) (xy 0.2794 0.9906) (xy -0.2794 0.9906)
			)
			(stroke
				(width 0)
				(type default)
			)
			(fill no)
			(layer "F.CrtYd")
		)
		(fp_line
			(start 0.2794 0.9906)
			(end 0.2794 -0.1016)
			(stroke
				(width 0.1)
				(type default)
			)
			(layer "F.Fab")
		)
		(fp_line
			(start 0.2794 -0.1016)
			(end -0.2794 -0.1016)
			(stroke
				(width 0.1)
				(type default)
			)
			(layer "F.Fab")
		)
		(fp_line
			(start -0.2794 0.9906)
			(end 0.2794 0.9906)
			(stroke
				(width 0.1)
				(type default)
			)
			(layer "F.Fab")
		)
		(fp_line
			(start -0.2794 -0.1016)
			(end -0.2794 0.9906)
			(stroke
				(width 0.1)
				(type default)
			)
			(layer "F.Fab")
		)
		(pad "1" smd rect
			(at 0 0 180)
			(size 0.508 0.508)
			(layers "F.Cu" "F.Mask" "F.Paste")
			(net "P3V3_STBY")
		)
		(pad "2" smd rect
			(at 0 0.889 180)
			(size 0.508 0.508)
			(layers "F.Cu" "F.Mask" "F.Paste")
			(net "PU_FAB2_MARKER_CPLD")
		)
		(zone
			(layer "F.Cu")
			(hatch none 0.5)
			(connect_pads
				(clearance 0)
			)
			(min_thickness 0.25)
			(keepout
				(tracks not_allowed)
				(vias allowed)
				(pads allowed)
				(copperpour not_allowed)
				(footprints allowed)
			)
			(placement
				(enabled no)
				(sheetname "")
			)
			(fill
				(thermal_gap 0.5)
				(thermal_bridge_width 0.5)
				(island_removal_mode 0)
			)
			(polygon
				(pts
					(xy 363.503718 -72.768206) (xy 362.995718 -72.768206) (xy 362.995718 -72.387206) (xy 363.503718 -72.387206)
				)
			)
		)
		(zone
			(layer "F.Cu")
			(hatch none 0.5)
			(connect_pads
				(clearance 0)
			)
			(min_thickness 0.25)
			(keepout
				(tracks allowed)
				(vias not_allowed)
				(pads allowed)
				(copperpour not_allowed)
				(footprints allowed)
			)
			(placement
				(enabled no)
				(sheetname "")
			)
			(fill
				(thermal_gap 0.5)
				(thermal_bridge_width 0.5)
				(island_removal_mode 0)
			)
			(polygon
				(pts
					(xy 363.503718 -72.387206) (xy 362.995718 -72.387206) (xy 362.995718 -72.768206) (xy 363.503718 -72.768206)
				)
			)
		)
	)
	(footprint ""
		(layer "F.Cu")
		(at 357.443532 12.003278 -90)
		(property "Reference" "T1P22"
			(at 0 0 270)
			(layer "F.SilkS")
			(hide yes)
			(effects
				(font
					(size 1.27 1.27)
				)
			)
		)
		(property "Value" "*"
			(at -3.302 1.12395 270)
			(unlocked yes)
			(layer "F.Fab")
			(hide yes)
			(effects
				(font
					(size 0.889 0.889)
					(thickness 0.1524)
				)
			)
		)
		(property "Device Type" "TPAD-DIFF-4P-GP_DISCRET-GB3-TPA"
			(at -3.302 -0.40005 270)
			(unlocked yes)
			(layer "F.Fab")
			(hide yes)
			(effects
				(font
					(size 0.889 0.889)
					(thickness 0.1524)
				)
			)
		)
		(duplicate_pad_numbers_are_jumpers no)
		(fp_line
			(start -2.286 2.286)
			(end 2.286 2.286)
			(stroke
				(width 0.1524)
				(type default)
			)
			(layer "F.SilkS")
		)
		(fp_line
			(start 2.286 2.286)
			(end 2.286 -2.286)
			(stroke
				(width 0.1524)
				(type default)
			)
			(layer "F.SilkS")
		)
		(fp_line
			(start -2.286 -2.286)
			(end -2.286 2.286)
			(stroke
				(width 0.1524)
				(type default)
			)
			(layer "F.SilkS")
		)
		(fp_line
			(start 2.286 -2.286)
			(end -2.286 -2.286)
			(stroke
				(width 0.1524)
				(type default)
			)
			(layer "F.SilkS")
		)
		(fp_line
			(start -2.413 -2.413)
			(end -2.413 -1.143)
			(stroke
				(width 0.4064)
				(type default)
			)
			(layer "F.SilkS")
		)
		(fp_line
			(start -1.143 -2.413)
			(end -2.413 -2.413)
			(stroke
				(width 0.4064)
				(type default)
			)
			(layer "F.SilkS")
		)
		(fp_rect
			(start -2.54 2.54)
			(end 2.54 -2.54)
			(stroke
				(width 0)
				(type default)
			)
			(fill no)
			(layer "F.CrtYd")
		)
		(fp_rect
			(start -2.54 2.54)
			(end 2.54 -2.54)
			(stroke
				(width 0)
				(type default)
			)
			(fill no)
			(layer "F.Fab")
		)
		(pad "1" thru_hole circle
			(at -1.27 -1.27 270)
			(size 1.524 1.524)
			(drill 0.9144)
			(layers "*.Cu" "*.Mask")
			(remove_unused_layers no)
			(net "L10_100OHM_6INCH_DP")
			(clearance -0.0508)
			(thermal_gap 0.127)
			(padstack
				(mode front_inner_back)
				(layer "Inner"
					(shape circle)
					(size 1.1684 1.1684)
					(clearance 0.127)
				)
				(layer "B.Cu"
					(shape circle)
					(size 1.524 1.524)
					(clearance -0.0508)
				)
			)
		)
		(pad "2" thru_hole circle
			(at 1.27 -1.27 270)
			(size 1.524 1.524)
			(drill 0.9144)
			(layers "*.Cu" "*.Mask")
			(remove_unused_layers no)
			(net "L10_100OHM_6INCH_DN")
			(clearance -0.0508)
			(thermal_gap 0.127)
			(padstack
				(mode front_inner_back)
				(layer "Inner"
					(shape circle)
					(size 1.1684 1.1684)
					(clearance 0.127)
				)
				(layer "B.Cu"
					(shape circle)
					(size 1.524 1.524)
					(clearance -0.0508)
				)
			)
		)
		(pad "GND1" thru_hole rect
			(at -1.27 1.27 270)
			(size 1.524 1.524)
			(drill 0.9144)
			(layers "*.Cu" "*.Mask")
			(remove_unused_layers no)
			(net "GND")
			(clearance -0.0508)
			(thermal_gap 0.127)
			(padstack
				(mode front_inner_back)
				(layer "Inner"
					(shape circle)
					(size 1.1684 1.1684)
					(clearance 0.127)
				)
				(layer "B.Cu"
					(shape rect)
					(size 1.524 1.524)
					(clearance -0.0508)
				)
			)
		)
		(pad "GND2" thru_hole rect
			(at 1.27 1.27 270)
			(size 1.524 1.524)
			(drill 0.9144)
			(layers "*.Cu" "*.Mask")
			(remove_unused_layers no)
			(net "GND")
			(clearance -0.0508)
			(thermal_gap 0.127)
			(padstack
				(mode front_inner_back)
				(layer "Inner"
					(shape circle)
					(size 1.1684 1.1684)
					(clearance 0.127)
				)
				(layer "B.Cu"
					(shape rect)
					(size 1.524 1.524)
					(clearance -0.0508)
				)
			)
		)
	)
	(footprint ""
		(layer "F.Cu")
		(at 173.9265 -67.945 90)
		(property "Reference" "C4D40"
			(at 0 0 90)
			(layer "F.SilkS")
			(hide yes)
			(effects
				(font
					(size 1.27 1.27)
				)
			)
		)
		(property "Value" ""
			(at 0 0 90)
			(layer "F.Fab")
			(effects
				(font
					(size 1.27 1.27)
				)
			)
		)
		(duplicate_pad_numbers_are_jumpers no)
		(fp_poly
			(pts
				(xy 0.3048 -0.1016) (xy 0.3048 0.9906) (xy -0.3048 0.9906) (xy -0.3048 -0.1016)
			)
			(stroke
				(width 0)
				(type default)
			)
			(fill no)
			(layer "F.CrtYd")
		)
		(fp_line
			(start 0.3048 -0.1016)
			(end -0.3048 -0.1016)
			(stroke
				(width 0.1)
				(type default)
			)
			(layer "F.Fab")
		)
		(fp_line
			(start -0.3048 -0.1016)
			(end -0.3048 0.9906)
			(stroke
				(width 0.1)
				(type default)
			)
			(layer "F.Fab")
		)
		(fp_line
			(start 0.3048 0.9906)
			(end 0.3048 -0.1016)
			(stroke
				(width 0.1)
				(type default)
			)
			(layer "F.Fab")
		)
		(fp_line
			(start -0.3048 0.9906)
			(end 0.3048 0.9906)
			(stroke
				(width 0.1)
				(type default)
			)
			(layer "F.Fab")
		)
		(pad "1" smd rect
			(at 0 0 90)
			(size 0.508 0.508)
			(layers "F.Cu" "F.Mask" "F.Paste")
			(net "VR_PVCCIO_CPU1_VINSEN")
		)
		(pad "2" smd rect
			(at 0 0.889 90)
			(size 0.508 0.508)
			(layers "F.Cu" "F.Mask" "F.Paste")
			(net "GND")
		)
		(zone
			(layer "F.Cu")
			(hatch none 0.5)
			(connect_pads
				(clearance 0)
			)
			(min_thickness 0.25)
			(keepout
				(tracks allowed)
				(vias not_allowed)
				(pads allowed)
				(copperpour not_allowed)
				(footprints allowed)
			)
			(placement
				(enabled no)
				(sheetname "")
			)
			(fill
				(thermal_gap 0.5)
				(thermal_bridge_width 0.5)
				(island_removal_mode 0)
			)
			(polygon
				(pts
					(xy 174.1805 -67.691) (xy 174.1805 -68.199) (xy 174.5615 -68.199) (xy 174.5615 -67.691)
				)
			)
		)
		(zone
			(layer "F.Cu")
			(hatch none 0.5)
			(connect_pads
				(clearance 0)
			)
			(min_thickness 0.25)
			(keepout
				(tracks not_allowed)
				(vias allowed)
				(pads allowed)
				(copperpour not_allowed)
				(footprints allowed)
			)
			(placement
				(enabled no)
				(sheetname "")
			)
			(fill
				(thermal_gap 0.5)
				(thermal_bridge_width 0.5)
				(island_removal_mode 0)
			)
			(polygon
				(pts
					(xy 174.5615 -67.691) (xy 174.5615 -68.199) (xy 174.1805 -68.199) (xy 174.1805 -67.691)
				)
			)
		)
	)
	(footprint ""
		(layer "F.Cu")
		(at 381.576072 -154.416506)
		(property "Reference" "C7A41"
			(at 0 0 0)
			(layer "F.SilkS")
			(hide yes)
			(effects
				(font
					(size 1.27 1.27)
				)
			)
		)
		(property "Value" ""
			(at 0 0 0)
			(layer "F.Fab")
			(effects
				(font
					(size 1.27 1.27)
				)
			)
		)
		(duplicate_pad_numbers_are_jumpers no)
		(fp_poly
			(pts
				(xy 0.3048 -0.1016) (xy 0.3048 0.9906) (xy -0.3048 0.9906) (xy -0.3048 -0.1016)
			)
			(stroke
				(width 0)
				(type default)
			)
			(fill no)
			(layer "F.CrtYd")
		)
		(fp_line
			(start -0.3048 -0.1016)
			(end -0.3048 0.9906)
			(stroke
				(width 0.1)
				(type default)
			)
			(layer "F.Fab")
		)
		(fp_line
			(start -0.3048 0.9906)
			(end 0.3048 0.9906)
			(stroke
				(width 0.1)
				(type default)
			)
			(layer "F.Fab")
		)
		(fp_line
			(start 0.3048 -0.1016)
			(end -0.3048 -0.1016)
			(stroke
				(width 0.1)
				(type default)
			)
			(layer "F.Fab")
		)
		(fp_line
			(start 0.3048 0.9906)
			(end 0.3048 -0.1016)
			(stroke
				(width 0.1)
				(type default)
			)
			(layer "F.Fab")
		)
		(pad "1" smd rect
			(at 0 0)
			(size 0.508 0.508)
			(layers "F.Cu" "F.Mask" "F.Paste")
			(net "P5V_STBY")
		)
		(pad "2" smd rect
			(at 0 0.889)
			(size 0.508 0.508)
			(layers "F.Cu" "F.Mask" "F.Paste")
			(net "GND")
		)
		(zone
			(layer "F.Cu")
			(hatch none 0.5)
			(connect_pads
				(clearance 0)
			)
			(min_thickness 0.25)
			(keepout
				(tracks allowed)
				(vias not_allowed)
				(pads allowed)
				(copperpour not_allowed)
				(footprints allowed)
			)
			(placement
				(enabled no)
				(sheetname "")
			)
			(fill
				(thermal_gap 0.5)
				(thermal_bridge_width 0.5)
				(island_removal_mode 0)
			)
			(polygon
				(pts
					(xy 381.322072 -154.162506) (xy 381.830072 -154.162506) (xy 381.830072 -153.781506) (xy 381.322072 -153.781506)
				)
			)
		)
		(zone
			(layer "F.Cu")
			(hatch none 0.5)
			(connect_pads
				(clearance 0)
			)
			(min_thickness 0.25)
			(keepout
				(tracks not_allowed)
				(vias allowed)
				(pads allowed)
				(copperpour not_allowed)
				(footprints allowed)
			)
			(placement
				(enabled no)
				(sheetname "")
			)
			(fill
				(thermal_gap 0.5)
				(thermal_bridge_width 0.5)
				(island_removal_mode 0)
			)
			(polygon
				(pts
					(xy 381.322072 -153.781506) (xy 381.830072 -153.781506) (xy 381.830072 -154.162506) (xy 381.322072 -154.162506)
				)
			)
		)
	)
	(footprint ""
		(layer "F.Cu")
		(at 98.524568 -84.709)
		(property "Reference" "C2D7"
			(at 0 0 0)
			(layer "F.SilkS")
			(hide yes)
			(effects
				(font
					(size 1.27 1.27)
				)
			)
		)
		(property "Value" ""
			(at 0 0 0)
			(layer "F.Fab")
			(effects
				(font
					(size 1.27 1.27)
				)
			)
		)
		(duplicate_pad_numbers_are_jumpers no)
		(fp_poly
			(pts
				(xy -0.4953 -0.2032) (xy 0.4953 -0.2032) (xy 0.4953 1.6002) (xy -0.4953 1.6002)
			)
			(stroke
				(width 0)
				(type default)
			)
			(fill no)
			(layer "F.CrtYd")
		)
		(fp_line
			(start -0.4953 -0.2032)
			(end 0.4953 -0.2032)
			(stroke
				(width 0.1)
				(type default)
			)
			(layer "F.Fab")
		)
		(fp_line
			(start -0.4953 1.6002)
			(end -0.4953 -0.2032)
			(stroke
				(width 0.1)
				(type default)
			)
			(layer "F.Fab")
		)
		(fp_line
			(start 0.4953 -0.2032)
			(end 0.4953 1.6002)
			(stroke
				(width 0.1)
				(type default)
			)
			(layer "F.Fab")
		)
		(fp_line
			(start 0.4953 1.6002)
			(end -0.4953 1.6002)
			(stroke
				(width 0.1)
				(type default)
			)
			(layer "F.Fab")
		)
		(pad "1" smd rect
			(at 0 0)
			(size 0.762 0.889)
			(layers "F.Cu" "F.Mask" "F.Paste")
			(net "PVDDQ_KLM")
		)
		(pad "2" smd rect
			(at 0 1.397)
			(size 0.762 0.889)
			(layers "F.Cu" "F.Mask" "F.Paste")
			(net "GND")
		)
		(zone
			(layer "F.Cu")
			(hatch none 0.5)
			(connect_pads
				(clearance 0)
			)
			(min_thickness 0.25)
			(keepout
				(tracks not_allowed)
				(vias allowed)
				(pads allowed)
				(copperpour not_allowed)
				(footprints allowed)
			)
			(placement
				(enabled no)
				(sheetname "")
			)
			(fill
				(thermal_gap 0.5)
				(thermal_bridge_width 0.5)
				(island_removal_mode 0)
			)
			(polygon
				(pts
					(xy 98.143568 -84.2645) (xy 98.905568 -84.2645) (xy 98.905568 -83.7565) (xy 98.143568 -83.7565)
				)
			)
		)
	)
	(footprint ""
		(layer "F.Cu")
		(at 13.8938 -26.797 90)
		(property "Reference" "C1F15"
			(at 0 0 90)
			(layer "F.SilkS")
			(hide yes)
			(effects
				(font
					(size 1.27 1.27)
				)
			)
		)
		(property "Value" ""
			(at 0 0 90)
			(layer "F.Fab")
			(effects
				(font
					(size 1.27 1.27)
				)
			)
		)
		(duplicate_pad_numbers_are_jumpers no)
		(fp_rect
			(start -0.3048 -0.1016)
			(end 0.3048 0.9906)
			(stroke
				(width 0)
				(type default)
			)
			(fill no)
			(layer "F.CrtYd")
		)
		(fp_line
			(start 0.3048 -0.1016)
			(end -0.3048 -0.1016)
			(stroke
				(width 0.1)
				(type default)
			)
			(layer "F.Fab")
		)
		(fp_line
			(start -0.3048 -0.1016)
			(end -0.3048 0.9906)
			(stroke
				(width 0.1)
				(type default)
			)
			(layer "F.Fab")
		)
		(fp_line
			(start 0.3048 0.9906)
			(end 0.3048 -0.1016)
			(stroke
				(width 0.1)
				(type default)
			)
			(layer "F.Fab")
		)
		(fp_line
			(start -0.3048 0.9906)
			(end 0.3048 0.9906)
			(stroke
				(width 0.1)
				(type default)
			)
			(layer "F.Fab")
		)
		(pad "1" smd rect
			(at 0 0 90)
			(size 0.508 0.508)
			(layers "F.Cu" "F.Mask" "F.Paste")
			(net "P3E_CPU1_PE3_MP_C_TXN<2>")
		)
		(pad "2" smd rect
			(at 0 0.889 90)
			(size 0.508 0.508)
			(layers "F.Cu" "F.Mask" "F.Paste")
			(net "P3E_CPU1_PE3_MP_TXN<2>")
		)
		(zone
			(layer "F.Cu")
			(hatch none 0.5)
			(connect_pads
				(clearance 0)
			)
			(min_thickness 0.25)
			(keepout
				(tracks not_allowed)
				(vias allowed)
				(pads allowed)
				(copperpour not_allowed)
				(footprints allowed)
			)
			(placement
				(enabled no)
				(sheetname "")
			)
			(fill
				(thermal_gap 0.5)
				(thermal_bridge_width 0.5)
				(island_removal_mode 0)
			)
			(polygon
				(pts
					(xy 14.1478 -26.543) (xy 14.5288 -26.543) (xy 14.5288 -27.051) (xy 14.1478 -27.051)
				)
			)
		)
		(zone
			(layer "F.Cu")
			(hatch none 0.5)
			(connect_pads
				(clearance 0)
			)
			(min_thickness 0.25)
			(keepout
				(tracks allowed)
				(vias not_allowed)
				(pads allowed)
				(copperpour not_allowed)
				(footprints allowed)
			)
			(placement
				(enabled no)
				(sheetname "")
			)
			(fill
				(thermal_gap 0.5)
				(thermal_bridge_width 0.5)
				(island_removal_mode 0)
			)
			(polygon
				(pts
					(xy 14.1478 -26.543) (xy 14.5288 -26.543) (xy 14.5288 -27.051) (xy 14.1478 -27.051)
				)
			)
		)
	)
	(footprint ""
		(layer "F.Cu")
		(at 401.472146 -37.220652 90)
		(property "Reference" "R6W17"
			(at -0.8382 -0.67818 90)
			(unlocked yes)
			(layer "F.SilkS")
			(effects
				(font
					(size 0.4064 0.254)
					(thickness 0.1524)
				)
				(justify left)
			)
		)
		(property "Value" ""
			(at 0 0 90)
			(layer "F.Fab")
			(effects
				(font
					(size 1.27 1.27)
				)
			)
		)
		(duplicate_pad_numbers_are_jumpers no)
		(fp_poly
			(pts
				(xy -0.2794 -0.1016) (xy 0.2794 -0.1016) (xy 0.2794 0.9906) (xy -0.2794 0.9906)
			)
			(stroke
				(width 0)
				(type default)
			)
			(fill no)
			(layer "F.CrtYd")
		)
		(fp_line
			(start 0.2794 -0.1016)
			(end -0.2794 -0.1016)
			(stroke
				(width 0.1)
				(type default)
			)
			(layer "F.Fab")
		)
		(fp_line
			(start -0.2794 -0.1016)
			(end -0.2794 0.9906)
			(stroke
				(width 0.1)
				(type default)
			)
			(layer "F.Fab")
		)
		(fp_line
			(start 0.2794 0.9906)
			(end 0.2794 -0.1016)
			(stroke
				(width 0.1)
				(type default)
			)
			(layer "F.Fab")
		)
		(fp_line
			(start -0.2794 0.9906)
			(end 0.2794 0.9906)
			(stroke
				(width 0.1)
				(type default)
			)
			(layer "F.Fab")
		)
		(pad "1" smd rect
			(at 0 0 90)
			(size 0.508 0.508)
			(layers "F.Cu" "F.Mask" "F.Paste")
			(net "SMB_DEBUG_STBY_LVC3_SCL")
		)
		(pad "2" smd rect
			(at 0 0.889 90)
			(size 0.508 0.508)
			(layers "F.Cu" "F.Mask" "F.Paste")
			(net "SMB_DEBUG_STBY_LVC3_SCL_R")
		)
		(zone
			(layer "F.Cu")
			(hatch none 0.5)
			(connect_pads
				(clearance 0)
			)
			(min_thickness 0.25)
			(keepout
				(tracks allowed)
				(vias not_allowed)
				(pads allowed)
				(copperpour not_allowed)
				(footprints allowed)
			)
			(placement
				(enabled no)
				(sheetname "")
			)
			(fill
				(thermal_gap 0.5)
				(thermal_bridge_width 0.5)
				(island_removal_mode 0)
			)
			(polygon
				(pts
					(xy 401.726146 -36.966652) (xy 401.726146 -37.474652) (xy 402.107146 -37.474652) (xy 402.107146 -36.966652)
				)
			)
		)
		(zone
			(layer "F.Cu")
			(hatch none 0.5)
			(connect_pads
				(clearance 0)
			)
			(min_thickness 0.25)
			(keepout
				(tracks not_allowed)
				(vias allowed)
				(pads allowed)
				(copperpour not_allowed)
				(footprints allowed)
			)
			(placement
				(enabled no)
				(sheetname "")
			)
			(fill
				(thermal_gap 0.5)
				(thermal_bridge_width 0.5)
				(island_removal_mode 0)
			)
			(polygon
				(pts
					(xy 402.107146 -36.966652) (xy 402.107146 -37.474652) (xy 401.726146 -37.474652) (xy 401.726146 -36.966652)
				)
			)
		)
	)
	(footprint ""
		(layer "F.Cu")
		(at 325.0057 -31.15818)
		(property "Reference" "C6F2"
			(at 0 0 0)
			(layer "F.SilkS")
			(hide yes)
			(effects
				(font
					(size 1.27 1.27)
				)
			)
		)
		(property "Value" ""
			(at 0 0 0)
			(layer "F.Fab")
			(effects
				(font
					(size 1.27 1.27)
				)
			)
		)
		(duplicate_pad_numbers_are_jumpers no)
		(fp_poly
			(pts
				(xy 0.3048 -0.1016) (xy 0.3048 0.9906) (xy -0.3048 0.9906) (xy -0.3048 -0.1016)
			)
			(stroke
				(width 0)
				(type default)
			)
			(fill no)
			(layer "F.CrtYd")
		)
		(fp_line
			(start -0.3048 -0.1016)
			(end -0.3048 0.9906)
			(stroke
				(width 0.1)
				(type default)
			)
			(layer "F.Fab")
		)
		(fp_line
			(start -0.3048 0.9906)
			(end 0.3048 0.9906)
			(stroke
				(width 0.1)
				(type default)
			)
			(layer "F.Fab")
		)
		(fp_line
			(start 0.3048 -0.1016)
			(end -0.3048 -0.1016)
			(stroke
				(width 0.1)
				(type default)
			)
			(layer "F.Fab")
		)
		(fp_line
			(start 0.3048 0.9906)
			(end 0.3048 -0.1016)
			(stroke
				(width 0.1)
				(type default)
			)
			(layer "F.Fab")
		)
		(pad "1" smd rect
			(at 0 0)
			(size 0.508 0.508)
			(layers "F.Cu" "F.Mask" "F.Paste")
			(net "PVCCIO_CPU0")
		)
		(pad "2" smd rect
			(at 0 0.889)
			(size 0.508 0.508)
			(layers "F.Cu" "F.Mask" "F.Paste")
			(net "GND")
		)
		(zone
			(layer "F.Cu")
			(hatch none 0.5)
			(connect_pads
				(clearance 0)
			)
			(min_thickness 0.25)
			(keepout
				(tracks allowed)
				(vias not_allowed)
				(pads allowed)
				(copperpour not_allowed)
				(footprints allowed)
			)
			(placement
				(enabled no)
				(sheetname "")
			)
			(fill
				(thermal_gap 0.5)
				(thermal_bridge_width 0.5)
				(island_removal_mode 0)
			)
			(polygon
				(pts
					(xy 324.7517 -30.90418) (xy 325.2597 -30.90418) (xy 325.2597 -30.52318) (xy 324.7517 -30.52318)
				)
			)
		)
		(zone
			(layer "F.Cu")
			(hatch none 0.5)
			(connect_pads
				(clearance 0)
			)
			(min_thickness 0.25)
			(keepout
				(tracks not_allowed)
				(vias allowed)
				(pads allowed)
				(copperpour not_allowed)
				(footprints allowed)
			)
			(placement
				(enabled no)
				(sheetname "")
			)
			(fill
				(thermal_gap 0.5)
				(thermal_bridge_width 0.5)
				(island_removal_mode 0)
			)
			(polygon
				(pts
					(xy 324.7517 -30.52318) (xy 325.2597 -30.52318) (xy 325.2597 -30.90418) (xy 324.7517 -30.90418)
				)
			)
		)
	)
	(footprint ""
		(layer "F.Cu")
		(at 408.161236 -47.825914 180)
		(property "Reference" "R1T12"
			(at 0 0 180)
			(layer "F.SilkS")
			(hide yes)
			(effects
				(font
					(size 1.27 1.27)
				)
			)
		)
		(property "Value" ""
			(at 0 0 180)
			(layer "F.Fab")
			(effects
				(font
					(size 1.27 1.27)
				)
			)
		)
		(duplicate_pad_numbers_are_jumpers no)
		(fp_poly
			(pts
				(xy -0.2794 -0.1016) (xy 0.2794 -0.1016) (xy 0.2794 0.9906) (xy -0.2794 0.9906)
			)
			(stroke
				(width 0)
				(type default)
			)
			(fill no)
			(layer "F.CrtYd")
		)
		(fp_line
			(start 0.2794 0.9906)
			(end 0.2794 -0.1016)
			(stroke
				(width 0.1)
				(type default)
			)
			(layer "F.Fab")
		)
		(fp_line
			(start 0.2794 -0.1016)
			(end -0.2794 -0.1016)
			(stroke
				(width 0.1)
				(type default)
			)
			(layer "F.Fab")
		)
		(fp_line
			(start -0.2794 0.9906)
			(end 0.2794 0.9906)
			(stroke
				(width 0.1)
				(type default)
			)
			(layer "F.Fab")
		)
		(fp_line
			(start -0.2794 -0.1016)
			(end -0.2794 0.9906)
			(stroke
				(width 0.1)
				(type default)
			)
			(layer "F.Fab")
		)
		(pad "1" smd rect
			(at 0 0 180)
			(size 0.508 0.508)
			(layers "F.Cu" "F.Mask" "F.Paste")
			(net "FM_BOARD_REV_ID1")
		)
		(pad "2" smd rect
			(at 0 0.889 180)
			(size 0.508 0.508)
			(layers "F.Cu" "F.Mask" "F.Paste")
			(net "GND")
		)
	)
	(footprint ""
		(layer "F.Cu")
		(at 171.99991 -155.10002 90)
		(property "Reference" "TH4A1"
			(at -0.94869 -7.15391 0)
			(unlocked yes)
			(layer "F.SilkS")
			(effects
				(font
					(size 0.7874 0.5842)
					(thickness 0.1524)
				)
				(justify left)
			)
		)
		(property "Value" ""
			(at 0 0 90)
			(layer "F.Fab")
			(effects
				(font
					(size 1.27 1.27)
				)
			)
		)
		(duplicate_pad_numbers_are_jumpers no)
		(fp_poly
			(pts
				(arc
					(start 3.0226 0.68834)
					(mid 3.042235 0.827855)
					(end 3.099562 0.956564)
				)
				(arc
					(start 3.099562 0.956564)
					(mid 4.012804 3.550073)
					(end 3.042158 6.12267)
				)
				(arc
					(start 3.042158 6.12267)
					(mid 0 7.518589)
					(end -3.042158 6.12267)
				)
				(arc
					(start -3.042158 6.12267)
					(mid -4.012854 3.55061)
					(end -3.100324 0.957326)
				)
				(arc
					(start -3.100324 0.957326)
					(mid -3.042498 0.827518)
					(end -3.0226 0.686816)
				)
				(arc
					(start -3.0226 -0.000254)
					(mid -2.137121 -2.137227)
					(end 0 -3.022346)
				)
				(arc
					(start 0 -3.022346)
					(mid 2.137227 -2.136973)
					(end 3.0226 0.000254)
				)
			)
			(stroke
				(width 0)
				(type default)
			)
			(fill no)
			(layer "F.CrtYd")
		)
		(pad "1" thru_hole custom
			(at 0 0 90)
			(size 2.00667 2.00667)
			(drill 0.3048)
			(layers "*.Cu" "*.Mask")
			(remove_unused_layers no)
			(net "GND")
			(clearance -0.889)
			(options
				(clearance outline)
				(anchor circle)
			)
			(primitives
				(gr_poly
					(pts
						(arc
							(start 3.042158 3.874516)
							(mid 0 5.270435)
							(end -3.042158 3.874516)
						)
						(arc
							(start -3.042158 3.874516)
							(mid -4.012854 1.302456)
							(end -3.100324 -1.290828)
						)
						(arc
							(start -3.100324 -1.290828)
							(mid -3.042498 -1.420636)
							(end -3.0226 -1.561338)
						)
						(arc
							(start -3.0226 -2.248408)
							(mid -2.137121 -4.385381)
							(end 0 -5.2705)
						)
						(arc
							(start 0 -5.2705)
							(mid 2.137227 -4.385127)
							(end 3.0226 -2.2479)
						)
						(arc
							(start 3.0226 -1.55956)
							(mid 3.04227 -1.420177)
							(end 3.099562 -1.29159)
						)
						(arc
							(start 3.099562 -1.29159)
							(mid 4.012804 1.301919)
							(end 3.042158 3.874516)
						)
					)
					(width 0)
					(fill yes)
				)
			)
		)
	)
	(footprint ""
		(layer "F.Cu")
		(at 438.4675 -16.129 90)
		(property "Reference" "R1U60"
			(at 0 0 90)
			(layer "F.SilkS")
			(hide yes)
			(effects
				(font
					(size 1.27 1.27)
				)
			)
		)
		(property "Value" ""
			(at 0 0 90)
			(layer "F.Fab")
			(effects
				(font
					(size 1.27 1.27)
				)
			)
		)
		(duplicate_pad_numbers_are_jumpers no)
		(fp_poly
			(pts
				(xy -0.2794 -0.1016) (xy 0.2794 -0.1016) (xy 0.2794 0.9906) (xy -0.2794 0.9906)
			)
			(stroke
				(width 0)
				(type default)
			)
			(fill no)
			(layer "F.CrtYd")
		)
		(fp_line
			(start 0.2794 -0.1016)
			(end -0.2794 -0.1016)
			(stroke
				(width 0.1)
				(type default)
			)
			(layer "F.Fab")
		)
		(fp_line
			(start -0.2794 -0.1016)
			(end -0.2794 0.9906)
			(stroke
				(width 0.1)
				(type default)
			)
			(layer "F.Fab")
		)
		(fp_line
			(start 0.2794 0.9906)
			(end 0.2794 -0.1016)
			(stroke
				(width 0.1)
				(type default)
			)
			(layer "F.Fab")
		)
		(fp_line
			(start -0.2794 0.9906)
			(end 0.2794 0.9906)
			(stroke
				(width 0.1)
				(type default)
			)
			(layer "F.Fab")
		)
		(pad "1" smd rect
			(at 0 0 90)
			(size 0.508 0.508)
			(layers "F.Cu" "F.Mask" "F.Paste")
			(net "H_CPU1_MEMKLM_MEMHOT_G_N")
		)
		(pad "2" smd rect
			(at 0 0.889 90)
			(size 0.508 0.508)
			(layers "F.Cu" "F.Mask" "F.Paste")
			(net "H_CPU1_MEMKLM_MEMHOT_G_R_N")
		)
		(zone
			(layer "F.Cu")
			(hatch none 0.5)
			(connect_pads
				(clearance 0)
			)
			(min_thickness 0.25)
			(keepout
				(tracks allowed)
				(vias not_allowed)
				(pads allowed)
				(copperpour not_allowed)
				(footprints allowed)
			)
			(placement
				(enabled no)
				(sheetname "")
			)
			(fill
				(thermal_gap 0.5)
				(thermal_bridge_width 0.5)
				(island_removal_mode 0)
			)
			(polygon
				(pts
					(xy 438.7215 -15.875) (xy 438.7215 -16.383) (xy 439.1025 -16.383) (xy 439.1025 -15.875)
				)
			)
		)
		(zone
			(layer "F.Cu")
			(hatch none 0.5)
			(connect_pads
				(clearance 0)
			)
			(min_thickness 0.25)
			(keepout
				(tracks not_allowed)
				(vias allowed)
				(pads allowed)
				(copperpour not_allowed)
				(footprints allowed)
			)
			(placement
				(enabled no)
				(sheetname "")
			)
			(fill
				(thermal_gap 0.5)
				(thermal_bridge_width 0.5)
				(island_removal_mode 0)
			)
			(polygon
				(pts
					(xy 439.1025 -15.875) (xy 439.1025 -16.383) (xy 438.7215 -16.383) (xy 438.7215 -15.875)
				)
			)
		)
	)
	(footprint ""
		(layer "F.Cu")
		(at 343.027 -22.64156 180)
		(property "Reference" "R7F18"
			(at 0 0 180)
			(layer "F.SilkS")
			(hide yes)
			(effects
				(font
					(size 1.27 1.27)
				)
			)
		)
		(property "Value" ""
			(at 0 0 180)
			(layer "F.Fab")
			(effects
				(font
					(size 1.27 1.27)
				)
			)
		)
		(duplicate_pad_numbers_are_jumpers no)
		(fp_rect
			(start 0.2794 -0.1016)
			(end -0.2794 0.9906)
			(stroke
				(width 0)
				(type default)
			)
			(fill no)
			(layer "F.CrtYd")
		)
		(fp_line
			(start 0.2794 0.9906)
			(end 0.2794 -0.1016)
			(stroke
				(width 0.1)
				(type default)
			)
			(layer "F.Fab")
		)
		(fp_line
			(start 0.2794 -0.1016)
			(end -0.2794 -0.1016)
			(stroke
				(width 0.1)
				(type default)
			)
			(layer "F.Fab")
		)
		(fp_line
			(start -0.2794 0.9906)
			(end 0.2794 0.9906)
			(stroke
				(width 0.1)
				(type default)
			)
			(layer "F.Fab")
		)
		(fp_line
			(start -0.2794 -0.1016)
			(end -0.2794 0.9906)
			(stroke
				(width 0.1)
				(type default)
			)
			(layer "F.Fab")
		)
		(pad "1" smd rect
			(at 0 0 180)
			(size 0.508 0.508)
			(layers "F.Cu" "F.Mask" "F.Paste")
			(net "VR_COMP_RC_PVPP_ABC")
		)
		(pad "2" smd rect
			(at 0 0.889 180)
			(size 0.508 0.508)
			(layers "F.Cu" "F.Mask" "F.Paste")
			(net "VR_FB_PVPP_ABC")
		)
		(zone
			(layer "F.Cu")
			(hatch none 0.5)
			(connect_pads
				(clearance 0)
			)
			(min_thickness 0.25)
			(keepout
				(tracks allowed)
				(vias not_allowed)
				(pads allowed)
				(copperpour not_allowed)
				(footprints allowed)
			)
			(placement
				(enabled no)
				(sheetname "")
			)
			(fill
				(thermal_gap 0.5)
				(thermal_bridge_width 0.5)
				(island_removal_mode 0)
			)
			(polygon
				(pts
					(xy 342.773 -22.89556) (xy 343.281 -22.89556) (xy 343.281 -23.27656) (xy 342.773 -23.27656)
				)
			)
		)
		(zone
			(layer "F.Cu")
			(hatch none 0.5)
			(connect_pads
				(clearance 0)
			)
			(min_thickness 0.25)
			(keepout
				(tracks not_allowed)
				(vias allowed)
				(pads allowed)
				(copperpour not_allowed)
				(footprints allowed)
			)
			(placement
				(enabled no)
				(sheetname "")
			)
			(fill
				(thermal_gap 0.5)
				(thermal_bridge_width 0.5)
				(island_removal_mode 0)
			)
			(polygon
				(pts
					(xy 342.773 -22.89556) (xy 343.281 -22.89556) (xy 343.281 -23.27656) (xy 342.773 -23.27656)
				)
			)
		)
	)
	(footprint ""
		(layer "F.Cu")
		(at 419.6207 -105.029 90)
		(property "Reference" "R9W19"
			(at -0.8382 -0.67818 90)
			(unlocked yes)
			(layer "F.SilkS")
			(effects
				(font
					(size 0.4064 0.254)
					(thickness 0.1524)
				)
				(justify left)
			)
		)
		(property "Value" ""
			(at 0 0 90)
			(layer "F.Fab")
			(effects
				(font
					(size 1.27 1.27)
				)
			)
		)
		(duplicate_pad_numbers_are_jumpers no)
		(fp_poly
			(pts
				(xy -0.2794 -0.1016) (xy 0.2794 -0.1016) (xy 0.2794 0.9906) (xy -0.2794 0.9906)
			)
			(stroke
				(width 0)
				(type default)
			)
			(fill no)
			(layer "F.CrtYd")
		)
		(fp_line
			(start 0.2794 -0.1016)
			(end -0.2794 -0.1016)
			(stroke
				(width 0.1)
				(type default)
			)
			(layer "F.Fab")
		)
		(fp_line
			(start -0.2794 -0.1016)
			(end -0.2794 0.9906)
			(stroke
				(width 0.1)
				(type default)
			)
			(layer "F.Fab")
		)
		(fp_line
			(start 0.2794 0.9906)
			(end 0.2794 -0.1016)
			(stroke
				(width 0.1)
				(type default)
			)
			(layer "F.Fab")
		)
		(fp_line
			(start -0.2794 0.9906)
			(end 0.2794 0.9906)
			(stroke
				(width 0.1)
				(type default)
			)
			(layer "F.Fab")
		)
		(pad "1" smd rect
			(at 0 0 90)
			(size 0.508 0.508)
			(layers "F.Cu" "F.Mask" "F.Paste")
			(net "PVCCIO_CPU0")
		)
		(pad "2" smd rect
			(at 0 0.889 90)
			(size 0.508 0.508)
			(layers "F.Cu" "F.Mask" "F.Paste")
			(net "SMB_CPU0_PE_HP_GTL_R_SCL")
		)
		(zone
			(layer "F.Cu")
			(hatch none 0.5)
			(connect_pads
				(clearance 0)
			)
			(min_thickness 0.25)
			(keepout
				(tracks allowed)
				(vias not_allowed)
				(pads allowed)
				(copperpour not_allowed)
				(footprints allowed)
			)
			(placement
				(enabled no)
				(sheetname "")
			)
			(fill
				(thermal_gap 0.5)
				(thermal_bridge_width 0.5)
				(island_removal_mode 0)
			)
			(polygon
				(pts
					(xy 419.8747 -104.775) (xy 419.8747 -105.283) (xy 420.2557 -105.283) (xy 420.2557 -104.775)
				)
			)
		)
		(zone
			(layer "F.Cu")
			(hatch none 0.5)
			(connect_pads
				(clearance 0)
			)
			(min_thickness 0.25)
			(keepout
				(tracks not_allowed)
				(vias allowed)
				(pads allowed)
				(copperpour not_allowed)
				(footprints allowed)
			)
			(placement
				(enabled no)
				(sheetname "")
			)
			(fill
				(thermal_gap 0.5)
				(thermal_bridge_width 0.5)
				(island_removal_mode 0)
			)
			(polygon
				(pts
					(xy 420.2557 -104.775) (xy 420.2557 -105.283) (xy 419.8747 -105.283) (xy 419.8747 -104.775)
				)
			)
		)
	)
	(footprint ""
		(layer "F.Cu")
		(at 420.865046 -48.968152)
		(property "Reference" "R25W99"
			(at -0.8382 -0.67818 0)
			(unlocked yes)
			(layer "F.SilkS")
			(effects
				(font
					(size 0.4064 0.254)
					(thickness 0.1524)
				)
				(justify left)
			)
		)
		(property "Value" ""
			(at 0 0 0)
			(layer "F.Fab")
			(effects
				(font
					(size 1.27 1.27)
				)
			)
		)
		(duplicate_pad_numbers_are_jumpers no)
		(fp_poly
			(pts
				(xy -0.2794 -0.1016) (xy 0.2794 -0.1016) (xy 0.2794 0.9906) (xy -0.2794 0.9906)
			)
			(stroke
				(width 0)
				(type default)
			)
			(fill no)
			(layer "F.CrtYd")
		)
		(fp_line
			(start -0.2794 -0.1016)
			(end -0.2794 0.9906)
			(stroke
				(width 0.1)
				(type default)
			)
			(layer "F.Fab")
		)
		(fp_line
			(start -0.2794 0.9906)
			(end 0.2794 0.9906)
			(stroke
				(width 0.1)
				(type default)
			)
			(layer "F.Fab")
		)
		(fp_line
			(start 0.2794 -0.1016)
			(end -0.2794 -0.1016)
			(stroke
				(width 0.1)
				(type default)
			)
			(layer "F.Fab")
		)
		(fp_line
			(start 0.2794 0.9906)
			(end 0.2794 -0.1016)
			(stroke
				(width 0.1)
				(type default)
			)
			(layer "F.Fab")
		)
		(pad "1" smd rect
			(at 0 0)
			(size 0.508 0.508)
			(layers "F.Cu" "F.Mask" "F.Paste")
			(net "P3V3_STBY")
		)
		(pad "2" smd rect
			(at 0 0.889)
			(size 0.508 0.508)
			(layers "F.Cu" "F.Mask" "F.Paste")
			(net "BMC_STRAP_BIT5")
		)
		(zone
			(layer "F.Cu")
			(hatch none 0.5)
			(connect_pads
				(clearance 0)
			)
			(min_thickness 0.25)
			(keepout
				(tracks allowed)
				(vias not_allowed)
				(pads allowed)
				(copperpour not_allowed)
				(footprints allowed)
			)
			(placement
				(enabled no)
				(sheetname "")
			)
			(fill
				(thermal_gap 0.5)
				(thermal_bridge_width 0.5)
				(island_removal_mode 0)
			)
			(polygon
				(pts
					(xy 420.611046 -48.714152) (xy 421.119046 -48.714152) (xy 421.119046 -48.333152) (xy 420.611046 -48.333152)
				)
			)
		)
		(zone
			(layer "F.Cu")
			(hatch none 0.5)
			(connect_pads
				(clearance 0)
			)
			(min_thickness 0.25)
			(keepout
				(tracks not_allowed)
				(vias allowed)
				(pads allowed)
				(copperpour not_allowed)
				(footprints allowed)
			)
			(placement
				(enabled no)
				(sheetname "")
			)
			(fill
				(thermal_gap 0.5)
				(thermal_bridge_width 0.5)
				(island_removal_mode 0)
			)
			(polygon
				(pts
					(xy 420.611046 -48.333152) (xy 421.119046 -48.333152) (xy 421.119046 -48.714152) (xy 420.611046 -48.714152)
				)
			)
		)
	)
	(footprint ""
		(layer "F.Cu")
		(at 198.02221 -68.49237 90)
		(property "Reference" "C4D49"
			(at -0.8382 -0.67818 90)
			(unlocked yes)
			(layer "F.SilkS")
			(effects
				(font
					(size 0.4064 0.254)
					(thickness 0.1524)
				)
				(justify left)
			)
		)
		(property "Value" ""
			(at 0 0 90)
			(layer "F.Fab")
			(effects
				(font
					(size 1.27 1.27)
				)
			)
		)
		(duplicate_pad_numbers_are_jumpers no)
		(fp_poly
			(pts
				(xy 0.3048 -0.1016) (xy 0.3048 0.9906) (xy -0.3048 0.9906) (xy -0.3048 -0.1016)
			)
			(stroke
				(width 0)
				(type default)
			)
			(fill no)
			(layer "F.CrtYd")
		)
		(fp_line
			(start 0.3048 -0.1016)
			(end -0.3048 -0.1016)
			(stroke
				(width 0.1)
				(type default)
			)
			(layer "F.Fab")
		)
		(fp_line
			(start -0.3048 -0.1016)
			(end -0.3048 0.9906)
			(stroke
				(width 0.1)
				(type default)
			)
			(layer "F.Fab")
		)
		(fp_line
			(start 0.3048 0.9906)
			(end 0.3048 -0.1016)
			(stroke
				(width 0.1)
				(type default)
			)
			(layer "F.Fab")
		)
		(fp_line
			(start -0.3048 0.9906)
			(end 0.3048 0.9906)
			(stroke
				(width 0.1)
				(type default)
			)
			(layer "F.Fab")
		)
		(pad "1" smd rect
			(at 0 0 90)
			(size 0.508 0.508)
			(layers "F.Cu" "F.Mask" "F.Paste")
			(net "VR_FET_SW_P12V_STBY_PVCCIN_CPU0")
		)
		(pad "2" smd rect
			(at 0 0.889 90)
			(size 0.508 0.508)
			(layers "F.Cu" "F.Mask" "F.Paste")
			(net "GND")
		)
		(zone
			(layer "F.Cu")
			(hatch none 0.5)
			(connect_pads
				(clearance 0)
			)
			(min_thickness 0.25)
			(keepout
				(tracks allowed)
				(vias not_allowed)
				(pads allowed)
				(copperpour not_allowed)
				(footprints allowed)
			)
			(placement
				(enabled no)
				(sheetname "")
			)
			(fill
				(thermal_gap 0.5)
				(thermal_bridge_width 0.5)
				(island_removal_mode 0)
			)
			(polygon
				(pts
					(xy 198.27621 -68.23837) (xy 198.27621 -68.74637) (xy 198.65721 -68.74637) (xy 198.65721 -68.23837)
				)
			)
		)
		(zone
			(layer "F.Cu")
			(hatch none 0.5)
			(connect_pads
				(clearance 0)
			)
			(min_thickness 0.25)
			(keepout
				(tracks not_allowed)
				(vias allowed)
				(pads allowed)
				(copperpour not_allowed)
				(footprints allowed)
			)
			(placement
				(enabled no)
				(sheetname "")
			)
			(fill
				(thermal_gap 0.5)
				(thermal_bridge_width 0.5)
				(island_removal_mode 0)
			)
			(polygon
				(pts
					(xy 198.65721 -68.23837) (xy 198.65721 -68.74637) (xy 198.27621 -68.74637) (xy 198.27621 -68.23837)
				)
			)
		)
	)
	(footprint ""
		(layer "F.Cu")
		(at 387.985 -109.855 90)
		(property "Reference" "U7C1"
			(at 17.75333 -13.335 0)
			(unlocked yes)
			(layer "F.SilkS")
			(effects
				(font
					(size 0.7874 0.5842)
					(thickness 0.1524)
				)
				(justify left)
			)
		)
		(property "Value" ""
			(at 0 0 90)
			(layer "F.Fab")
			(effects
				(font
					(size 1.27 1.27)
				)
			)
		)
		(duplicate_pad_numbers_are_jumpers no)
		(fp_line
			(start 16.999966 -13.999972)
			(end 16.999966 13.999972)
			(stroke
				(width 0.1524)
				(type default)
			)
			(layer "F.SilkS")
		)
		(fp_line
			(start -16.999966 -13.999972)
			(end 16.999966 -13.999972)
			(stroke
				(width 0.1524)
				(type default)
			)
			(layer "F.SilkS")
		)
		(fp_line
			(start 16.999966 13.999972)
			(end -16.999966 13.999972)
			(stroke
				(width 0.1524)
				(type default)
			)
			(layer "F.SilkS")
		)
		(fp_line
			(start -16.999966 13.999972)
			(end -16.999966 -13.999972)
			(stroke
				(width 0.1524)
				(type default)
			)
			(layer "F.SilkS")
		)
		(fp_rect
			(start -16.999966 13.999972)
			(end 16.999966 -13.999972)
			(stroke
				(width 0)
				(type default)
			)
			(fill no)
			(layer "F.CrtYd")
		)
		(fp_line
			(start 16.999966 -13.999972)
			(end 16.999966 13.999972)
			(stroke
				(width 0.1)
				(type default)
			)
			(layer "F.Fab")
		)
		(fp_line
			(start -16.999966 -13.999972)
			(end 16.999966 -13.999972)
			(stroke
				(width 0.1)
				(type default)
			)
			(layer "F.Fab")
		)
		(fp_line
			(start 16.999966 13.999972)
			(end -16.999966 13.999972)
			(stroke
				(width 0.1)
				(type default)
			)
			(layer "F.Fab")
		)
		(fp_line
			(start -16.999966 13.999972)
			(end -16.999966 -13.999972)
			(stroke
				(width 0.1)
				(type default)
			)
			(layer "F.Fab")
		)
		(fp_text user "35"
			(at -0.83058 -14.66215 90)
			(unlocked yes)
			(layer "F.SilkS")
			(effects
				(font
					(size 0.7874 0.5842)
					(thickness 0.1524)
				)
				(justify left)
			)
		)
		(fp_text user "70"
			(at 15.062708 -14.628622 90)
			(unlocked yes)
			(layer "F.SilkS")
			(effects
				(font
					(size 0.7874 0.5842)
					(thickness 0.1524)
				)
				(justify left)
			)
		)
		(fp_text user "65"
			(at 12.628372 -14.628622 90)
			(unlocked yes)
			(layer "F.SilkS")
			(effects
				(font
					(size 0.7874 0.5842)
					(thickness 0.1524)
				)
				(justify left)
			)
		)
		(fp_text user "60"
			(at 10.145268 -14.628622 90)
			(unlocked yes)
			(layer "F.SilkS")
			(effects
				(font
					(size 0.7874 0.5842)
					(thickness 0.1524)
				)
				(justify left)
			)
		)
		(fp_text user "55"
			(at 8.063992 -14.628622 90)
			(unlocked yes)
			(layer "F.SilkS")
			(effects
				(font
					(size 0.7874 0.5842)
					(thickness 0.1524)
				)
				(justify left)
			)
		)
		(fp_text user "50"
			(at 5.617464 -14.628622 90)
			(unlocked yes)
			(layer "F.SilkS")
			(effects
				(font
					(size 0.7874 0.5842)
					(thickness 0.1524)
				)
				(justify left)
			)
		)
		(fp_text user "45"
			(at 3.511804 -14.628622 90)
			(unlocked yes)
			(layer "F.SilkS")
			(effects
				(font
					(size 0.7874 0.5842)
					(thickness 0.1524)
				)
				(justify left)
			)
		)
		(fp_text user "25"
			(at -5.902198 -14.624812 90)
			(unlocked yes)
			(layer "F.SilkS")
			(effects
				(font
					(size 0.7874 0.5842)
					(thickness 0.1524)
				)
				(justify left)
			)
		)
		(fp_text user "20"
			(at -8.531098 -14.624812 90)
			(unlocked yes)
			(layer "F.SilkS")
			(effects
				(font
					(size 0.7874 0.5842)
					(thickness 0.1524)
				)
				(justify left)
			)
		)
		(fp_text user "15"
			(at -10.636758 -14.624812 90)
			(unlocked yes)
			(layer "F.SilkS")
			(effects
				(font
					(size 0.7874 0.5842)
					(thickness 0.1524)
				)
				(justify left)
			)
		)
		(fp_text user "10"
			(at -12.888722 -14.624812 90)
			(unlocked yes)
			(layer "F.SilkS")
			(effects
				(font
					(size 0.7874 0.5842)
					(thickness 0.1524)
				)
				(justify left)
			)
		)
		(fp_text user "40"
			(at 0.9779 -14.61643 90)
			(unlocked yes)
			(layer "F.SilkS")
			(effects
				(font
					(size 0.7874 0.5842)
					(thickness 0.1524)
				)
				(justify left)
			)
		)
		(fp_text user "5"
			(at -16.0782 -14.60373 90)
			(unlocked yes)
			(layer "F.SilkS")
			(effects
				(font
					(size 0.7874 0.5842)
					(thickness 0.1524)
				)
				(justify left)
			)
		)
		(fp_text user "30"
			(at -3.235198 -14.522196 90)
			(unlocked yes)
			(layer "F.SilkS")
			(effects
				(font
					(size 0.7874 0.5842)
					(thickness 0.1524)
				)
				(justify left)
			)
		)
		(fp_text user "A"
			(at -18.33626 -14.39545 90)
			(unlocked yes)
			(layer "F.SilkS")
			(effects
				(font
					(size 0.7874 0.5842)
					(thickness 0.1524)
				)
				(justify left)
			)
		)
		(fp_text user "C"
			(at -18.43024 -13.42771 90)
			(unlocked yes)
			(layer "F.SilkS")
			(effects
				(font
					(size 0.7874 0.5842)
					(thickness 0.1524)
				)
				(justify left)
			)
		)
		(fp_text user "E"
			(at -18.46326 -12.43457 90)
			(unlocked yes)
			(layer "F.SilkS")
			(effects
				(font
					(size 0.7874 0.5842)
					(thickness 0.1524)
				)
				(justify left)
			)
		)
		(fp_text user "G"
			(at -18.5293 -11.44905 90)
			(unlocked yes)
			(layer "F.SilkS")
			(effects
				(font
					(size 0.7874 0.5842)
					(thickness 0.1524)
				)
				(justify left)
			)
		)
		(fp_text user "J"
			(at -18.49882 -10.51687 90)
			(unlocked yes)
			(layer "F.SilkS")
			(effects
				(font
					(size 0.7874 0.5842)
					(thickness 0.1524)
				)
				(justify left)
			)
		)
		(fp_text user "L"
			(at -18.42262 -9.54151 90)
			(unlocked yes)
			(layer "F.SilkS")
			(effects
				(font
					(size 0.7874 0.5842)
					(thickness 0.1524)
				)
				(justify left)
			)
		)
		(fp_text user "N"
			(at -18.46326 -8.54075 90)
			(unlocked yes)
			(layer "F.SilkS")
			(effects
				(font
					(size 0.7874 0.5842)
					(thickness 0.1524)
				)
				(justify left)
			)
		)
		(fp_text user "R"
			(at -18.44548 -7.56285 90)
			(unlocked yes)
			(layer "F.SilkS")
			(effects
				(font
					(size 0.7874 0.5842)
					(thickness 0.1524)
				)
				(justify left)
			)
		)
		(fp_text user "V"
			(at -18.453862 -6.584188 90)
			(unlocked yes)
			(layer "F.SilkS")
			(effects
				(font
					(size 0.7874 0.5842)
					(thickness 0.1524)
				)
				(justify left)
			)
		)
		(fp_text user "Y"
			(at -18.478246 -5.72389 90)
			(unlocked yes)
			(layer "F.SilkS")
			(effects
				(font
					(size 0.7874 0.5842)
					(thickness 0.1524)
				)
				(justify left)
			)
		)
		(fp_text user "AB"
			(at -18.736564 -4.716272 90)
			(unlocked yes)
			(layer "F.SilkS")
			(effects
				(font
					(size 0.7874 0.5842)
					(thickness 0.1524)
				)
				(justify left)
			)
		)
		(fp_text user "AD"
			(at -18.675096 -3.659378 90)
			(unlocked yes)
			(layer "F.SilkS")
			(effects
				(font
					(size 0.7874 0.5842)
					(thickness 0.1524)
				)
				(justify left)
			)
		)
		(fp_text user "AF"
			(at -18.72742 -2.60223 90)
			(unlocked yes)
			(layer "F.SilkS")
			(effects
				(font
					(size 0.7874 0.5842)
					(thickness 0.1524)
				)
				(justify left)
			)
		)
		(fp_text user "AJ"
			(at -18.711926 -1.766824 90)
			(unlocked yes)
			(layer "F.SilkS")
			(effects
				(font
					(size 0.7874 0.5842)
					(thickness 0.1524)
				)
				(justify left)
			)
		)
		(fp_text user "AL"
			(at -18.69948 -0.771652 90)
			(unlocked yes)
			(layer "F.SilkS")
			(effects
				(font
					(size 0.7874 0.5842)
					(thickness 0.1524)
				)
				(justify left)
			)
		)
		(fp_text user "AN"
			(at -18.711926 0.309626 90)
			(unlocked yes)
			(layer "F.SilkS")
			(effects
				(font
					(size 0.7874 0.5842)
					(thickness 0.1524)
				)
				(justify left)
			)
		)
		(fp_text user "AR"
			(at -18.687288 1.354074 90)
			(unlocked yes)
			(layer "F.SilkS")
			(effects
				(font
					(size 0.7874 0.5842)
					(thickness 0.1524)
				)
				(justify left)
			)
		)
		(fp_text user "AV"
			(at -18.687288 2.337308 90)
			(unlocked yes)
			(layer "F.SilkS")
			(effects
				(font
					(size 0.7874 0.5842)
					(thickness 0.1524)
				)
				(justify left)
			)
		)
		(fp_text user "AY"
			(at -18.711926 3.271266 90)
			(unlocked yes)
			(layer "F.SilkS")
			(effects
				(font
					(size 0.7874 0.5842)
					(thickness 0.1524)
				)
				(justify left)
			)
		)
		(fp_text user "BB"
			(at -18.687288 4.278884 90)
			(unlocked yes)
			(layer "F.SilkS")
			(effects
				(font
					(size 0.7874 0.5842)
					(thickness 0.1524)
				)
				(justify left)
			)
		)
		(fp_text user "BD"
			(at -18.66265 5.31114 90)
			(unlocked yes)
			(layer "F.SilkS")
			(effects
				(font
					(size 0.7874 0.5842)
					(thickness 0.1524)
				)
				(justify left)
			)
		)
		(fp_text user "BF"
			(at -18.650458 6.392418 90)
			(unlocked yes)
			(layer "F.SilkS")
			(effects
				(font
					(size 0.7874 0.5842)
					(thickness 0.1524)
				)
				(justify left)
			)
		)
		(fp_text user "BJ"
			(at -18.687288 7.510526 90)
			(unlocked yes)
			(layer "F.SilkS")
			(effects
				(font
					(size 0.7874 0.5842)
					(thickness 0.1524)
				)
				(justify left)
			)
		)
		(fp_text user "BL"
			(at -18.66265 8.542782 90)
			(unlocked yes)
			(layer "F.SilkS")
			(effects
				(font
					(size 0.7874 0.5842)
					(thickness 0.1524)
				)
				(justify left)
			)
		)
		(fp_text user "BN"
			(at -18.67154 9.58469 90)
			(unlocked yes)
			(layer "F.SilkS")
			(effects
				(font
					(size 0.7874 0.5842)
					(thickness 0.1524)
				)
				(justify left)
			)
		)
		(fp_text user "BR"
			(at -18.71218 10.60323 90)
			(unlocked yes)
			(layer "F.SilkS")
			(effects
				(font
					(size 0.7874 0.5842)
					(thickness 0.1524)
				)
				(justify left)
			)
		)
		(fp_text user "BU"
			(at -18.7198 11.62939 90)
			(unlocked yes)
			(layer "F.SilkS")
			(effects
				(font
					(size 0.7874 0.5842)
					(thickness 0.1524)
				)
				(justify left)
			)
		)
		(fp_text user "BW"
			(at -18.7833 12.69619 90)
			(unlocked yes)
			(layer "F.SilkS")
			(effects
				(font
					(size 0.7874 0.5842)
					(thickness 0.1524)
				)
				(justify left)
			)
		)
		(fp_text user "CA"
			(at -18.79854 13.85697 90)
			(unlocked yes)
			(layer "F.SilkS")
			(effects
				(font
					(size 0.7874 0.5842)
					(thickness 0.1524)
				)
				(justify left)
			)
		)
		(fp_text user "30"
			(at -3.340354 -14.413992 90)
			(unlocked yes)
			(layer "F.Fab")
			(effects
				(font
					(size 0.635 0.635)
					(thickness 0.1524)
				)
				(justify left)
			)
		)
		(fp_text user "25"
			(at -5.823458 -14.413992 90)
			(unlocked yes)
			(layer "F.Fab")
			(effects
				(font
					(size 0.635 0.635)
					(thickness 0.1524)
				)
				(justify left)
			)
		)
		(fp_text user "20"
			(at -8.452358 -14.413992 90)
			(unlocked yes)
			(layer "F.Fab")
			(effects
				(font
					(size 0.635 0.635)
					(thickness 0.1524)
				)
				(justify left)
			)
		)
		(fp_text user "15"
			(at -10.558018 -14.413992 90)
			(unlocked yes)
			(layer "F.Fab")
			(effects
				(font
					(size 0.635 0.635)
					(thickness 0.1524)
				)
				(justify left)
			)
		)
		(fp_text user "10"
			(at -12.809982 -14.413992 90)
			(unlocked yes)
			(layer "F.Fab")
			(effects
				(font
					(size 0.635 0.635)
					(thickness 0.1524)
				)
				(justify left)
			)
		)
		(fp_text user "5"
			(at -14.879066 -14.413992 90)
			(unlocked yes)
			(layer "F.Fab")
			(effects
				(font
					(size 0.635 0.635)
					(thickness 0.1524)
				)
				(justify left)
			)
		)
		(fp_text user "70"
			(at 15.029688 -14.402562 90)
			(unlocked yes)
			(layer "F.Fab")
			(effects
				(font
					(size 0.635 0.635)
					(thickness 0.1524)
				)
				(justify left)
			)
		)
		(fp_text user "65"
			(at 12.595352 -14.402562 90)
			(unlocked yes)
			(layer "F.Fab")
			(effects
				(font
					(size 0.635 0.635)
					(thickness 0.1524)
				)
				(justify left)
			)
		)
		(fp_text user "60"
			(at 10.112248 -14.402562 90)
			(unlocked yes)
			(layer "F.Fab")
			(effects
				(font
					(size 0.635 0.635)
					(thickness 0.1524)
				)
				(justify left)
			)
		)
		(fp_text user "55"
			(at 8.030972 -14.402562 90)
			(unlocked yes)
			(layer "F.Fab")
			(effects
				(font
					(size 0.635 0.635)
					(thickness 0.1524)
				)
				(justify left)
			)
		)
		(fp_text user "50"
			(at 5.584444 -14.402562 90)
			(unlocked yes)
			(layer "F.Fab")
			(effects
				(font
					(size 0.635 0.635)
					(thickness 0.1524)
				)
				(justify left)
			)
		)
		(fp_text user "45"
			(at 3.478784 -14.402562 90)
			(unlocked yes)
			(layer "F.Fab")
			(effects
				(font
					(size 0.635 0.635)
					(thickness 0.1524)
				)
				(justify left)
			)
		)
		(fp_text user "40"
			(at 1.068832 -14.402562 90)
			(unlocked yes)
			(layer "F.Fab")
			(effects
				(font
					(size 0.635 0.635)
					(thickness 0.1524)
				)
				(justify left)
			)
		)
		(fp_text user "35"
			(at -0.781304 -14.402562 90)
			(unlocked yes)
			(layer "F.Fab")
			(effects
				(font
					(size 0.635 0.635)
					(thickness 0.1524)
				)
				(justify left)
			)
		)
		(fp_text user "A"
			(at -17.947894 -13.67028 90)
			(unlocked yes)
			(layer "F.Fab")
			(effects
				(font
					(size 0.635 0.635)
					(thickness 0.1524)
				)
				(justify left)
			)
		)
		(fp_text user "C"
			(at -17.972532 -12.79779 90)
			(unlocked yes)
			(layer "F.Fab")
			(effects
				(font
					(size 0.635 0.635)
					(thickness 0.1524)
				)
				(justify left)
			)
		)
		(fp_text user "E"
			(at -17.874234 -11.900662 90)
			(unlocked yes)
			(layer "F.Fab")
			(effects
				(font
					(size 0.635 0.635)
					(thickness 0.1524)
				)
				(justify left)
			)
		)
		(fp_text user "G"
			(at -17.92351 -11.077448 90)
			(unlocked yes)
			(layer "F.Fab")
			(effects
				(font
					(size 0.635 0.635)
					(thickness 0.1524)
				)
				(justify left)
			)
		)
		(fp_text user "J"
			(at -18.034 -10.21715 90)
			(unlocked yes)
			(layer "F.Fab")
			(effects
				(font
					(size 0.635 0.635)
					(thickness 0.1524)
				)
				(justify left)
			)
		)
		(fp_text user "L"
			(at -17.982692 -9.227058 90)
			(unlocked yes)
			(layer "F.Fab")
			(effects
				(font
					(size 0.635 0.635)
					(thickness 0.1524)
				)
				(justify left)
			)
		)
		(fp_text user "N"
			(at -17.982692 -8.18261 90)
			(unlocked yes)
			(layer "F.Fab")
			(effects
				(font
					(size 0.635 0.635)
					(thickness 0.1524)
				)
				(justify left)
			)
		)
		(fp_text user "R"
			(at -17.909032 -7.174738 90)
			(unlocked yes)
			(layer "F.Fab")
			(effects
				(font
					(size 0.635 0.635)
					(thickness 0.1524)
				)
				(justify left)
			)
		)
		(fp_text user "V"
			(at -17.945862 -6.007608 90)
			(unlocked yes)
			(layer "F.Fab")
			(effects
				(font
					(size 0.635 0.635)
					(thickness 0.1524)
				)
				(justify left)
			)
		)
		(fp_text user "Y"
			(at -17.970246 -5.14731 90)
			(unlocked yes)
			(layer "F.Fab")
			(effects
				(font
					(size 0.635 0.635)
					(thickness 0.1524)
				)
				(justify left)
			)
		)
		(fp_text user "AB"
			(at -18.228564 -4.139692 90)
			(unlocked yes)
			(layer "F.Fab")
			(effects
				(font
					(size 0.635 0.635)
					(thickness 0.1524)
				)
				(justify left)
			)
		)
		(fp_text user "AD"
			(at -18.167096 -3.082798 90)
			(unlocked yes)
			(layer "F.Fab")
			(effects
				(font
					(size 0.635 0.635)
					(thickness 0.1524)
				)
				(justify left)
			)
		)
		(fp_text user "AF"
			(at -18.15465 -2.14884 90)
			(unlocked yes)
			(layer "F.Fab")
			(effects
				(font
					(size 0.635 0.635)
					(thickness 0.1524)
				)
				(justify left)
			)
		)
		(fp_text user "AJ"
			(at -18.203926 -1.190244 90)
			(unlocked yes)
			(layer "F.Fab")
			(effects
				(font
					(size 0.635 0.635)
					(thickness 0.1524)
				)
				(justify left)
			)
		)
		(fp_text user "AL"
			(at -18.19148 -0.195072 90)
			(unlocked yes)
			(layer "F.Fab")
			(effects
				(font
					(size 0.635 0.635)
					(thickness 0.1524)
				)
				(justify left)
			)
		)
		(fp_text user "AN"
			(at -18.203926 0.886206 90)
			(unlocked yes)
			(layer "F.Fab")
			(effects
				(font
					(size 0.635 0.635)
					(thickness 0.1524)
				)
				(justify left)
			)
		)
		(fp_text user "AR"
			(at -18.179288 1.930654 90)
			(unlocked yes)
			(layer "F.Fab")
			(effects
				(font
					(size 0.635 0.635)
					(thickness 0.1524)
				)
				(justify left)
			)
		)
		(fp_text user "AV"
			(at -18.179288 2.913888 90)
			(unlocked yes)
			(layer "F.Fab")
			(effects
				(font
					(size 0.635 0.635)
					(thickness 0.1524)
				)
				(justify left)
			)
		)
		(fp_text user "AY"
			(at -18.203926 3.847846 90)
			(unlocked yes)
			(layer "F.Fab")
			(effects
				(font
					(size 0.635 0.635)
					(thickness 0.1524)
				)
				(justify left)
			)
		)
		(fp_text user "BB"
			(at -18.179288 4.855464 90)
			(unlocked yes)
			(layer "F.Fab")
			(effects
				(font
					(size 0.635 0.635)
					(thickness 0.1524)
				)
				(justify left)
			)
		)
		(fp_text user "BD"
			(at -18.15465 5.88772 90)
			(unlocked yes)
			(layer "F.Fab")
			(effects
				(font
					(size 0.635 0.635)
					(thickness 0.1524)
				)
				(justify left)
			)
		)
		(fp_text user "BF"
			(at -18.142458 6.968998 90)
			(unlocked yes)
			(layer "F.Fab")
			(effects
				(font
					(size 0.635 0.635)
					(thickness 0.1524)
				)
				(justify left)
			)
		)
		(fp_text user "BJ"
			(at -18.179288 8.087106 90)
			(unlocked yes)
			(layer "F.Fab")
			(effects
				(font
					(size 0.635 0.635)
					(thickness 0.1524)
				)
				(justify left)
			)
		)
		(fp_text user "BL"
			(at -18.15465 9.119362 90)
			(unlocked yes)
			(layer "F.Fab")
			(effects
				(font
					(size 0.635 0.635)
					(thickness 0.1524)
				)
				(justify left)
			)
		)
		(fp_text user "BN"
			(at -18.203926 9.955022 90)
			(unlocked yes)
			(layer "F.Fab")
			(effects
				(font
					(size 0.635 0.635)
					(thickness 0.1524)
				)
				(justify left)
			)
		)
		(fp_text user "BR"
			(at -18.154904 10.717022 90)
			(unlocked yes)
			(layer "F.Fab")
			(effects
				(font
					(size 0.635 0.635)
					(thickness 0.1524)
				)
				(justify left)
			)
		)
		(fp_text user "BU"
			(at -18.179542 11.552682 90)
			(unlocked yes)
			(layer "F.Fab")
			(effects
				(font
					(size 0.635 0.635)
					(thickness 0.1524)
				)
				(justify left)
			)
		)
		(fp_text user "BW"
			(at -18.228564 12.462002 90)
			(unlocked yes)
			(layer "F.Fab")
			(effects
				(font
					(size 0.635 0.635)
					(thickness 0.1524)
				)
				(justify left)
			)
		)
		(fp_text user "CA"
			(at -18.191734 13.555726 90)
			(unlocked yes)
			(layer "F.Fab")
			(effects
				(font
					(size 0.635 0.635)
					(thickness 0.1524)
				)
				(justify left)
			)
		)
		(pad "A5" smd circle
			(at -14.689328 -13.310108 90)
			(size 0.4064 0.4064)
			(layers "F.Cu" "F.Mask" "F.Paste")
			(net "GND")
		)
		(pad "A7" smd circle
			(at -13.876528 -13.310108 90)
			(size 0.4064 0.4064)
			(layers "F.Cu" "F.Mask" "F.Paste")
			(net "GND")
		)
		(pad "A9" smd circle
			(at -13.063728 -13.310108 90)
			(size 0.3556 0.3556)
			(layers "F.Cu" "F.Mask" "F.Paste")
			(net "GND")
		)
		(pad "A11" smd oval
			(at -11.999976 -13.310108 90)
			(size 0.254 0.3302)
			(layers "F.Cu" "F.Mask" "F.Paste")
			(net "TP_PCH_RSVD21")
		)
		(pad "A13" smd oval
			(at -10.999978 -13.310108 90)
			(size 0.254 0.3302)
			(layers "F.Cu" "F.Mask" "F.Paste")
			(net "FM_GBE_LOM_DISABLE_N")
		)
		(pad "A15" smd oval
			(at -9.99998 -13.310108 90)
			(size 0.254 0.3302)
			(layers "F.Cu" "F.Mask" "F.Paste")
			(net "FM_BMC_CPLD_MP_RST_N")
		)
		(pad "A18" smd oval
			(at -8.999982 -13.310108 90)
			(size 0.254 0.3302)
			(layers "F.Cu" "F.Mask" "F.Paste")
			(net "GND")
		)
		(pad "A20" smd oval
			(at -7.999984 -13.310108 90)
			(size 0.254 0.3302)
			(layers "F.Cu" "F.Mask" "F.Paste")
			(net "CLK_100M_SPRV_DP")
		)
		(pad "A22" smd oval
			(at -6.999986 -13.310108 90)
			(size 0.254 0.3302)
			(layers "F.Cu" "F.Mask" "F.Paste")
			(net "GND")
		)
		(pad "A24" smd oval
			(at -5.999988 -13.310108 90)
			(size 0.254 0.3302)
			(layers "F.Cu" "F.Mask" "F.Paste")
			(net "Net_4")
		)
		(pad "A26" smd oval
			(at -4.99999 -13.310108 90)
			(size 0.254 0.3302)
			(layers "F.Cu" "F.Mask" "F.Paste")
			(net "TP_PCH_RSVD65")
		)
		(pad "A28" smd oval
			(at -3.999992 -13.310108 90)
			(size 0.254 0.3302)
			(layers "F.Cu" "F.Mask" "F.Paste")
			(net "CLK_100M_PCH_SLOTX24_S2_DN")
		)
		(pad "A30" smd oval
			(at -2.999994 -13.310108 90)
			(size 0.254 0.3302)
			(layers "F.Cu" "F.Mask" "F.Paste")
			(net "GND")
		)
		(pad "A32" smd oval
			(at -1.999996 -13.310108 90)
			(size 0.254 0.3302)
			(layers "F.Cu" "F.Mask" "F.Paste")
			(net "TP_CLK_100M_NSSCC0_DN")
		)
		(pad "A34" smd oval
			(at -0.999998 -13.310108 90)
			(size 0.254 0.3302)
			(layers "F.Cu" "F.Mask" "F.Paste")
			(net "GND")
		)
		(pad "A37" smd oval
			(at 0 -13.310108 90)
			(size 0.254 0.3302)
			(layers "F.Cu" "F.Mask" "F.Paste")
			(net "GND")
		)
		(pad "A39" smd oval
			(at 0.999998 -13.310108 90)
			(size 0.254 0.3302)
			(layers "F.Cu" "F.Mask" "F.Paste")
			(net "CLK_100M_PCH_XDP_DN")
		)
		(pad "A41" smd oval
			(at 1.999996 -13.310108 90)
			(size 0.254 0.3302)
			(layers "F.Cu" "F.Mask" "F.Paste")
			(net "GND")
		)
		(pad "A43" smd oval
			(at 2.999994 -13.310108 90)
			(size 0.254 0.3302)
			(layers "F.Cu" "F.Mask" "F.Paste")
			(net "DMI_CPU0_PCH_TX_C_DP<1>")
		)
		(pad "A45" smd oval
			(at 3.999992 -13.310108 90)
			(size 0.254 0.3302)
			(layers "F.Cu" "F.Mask" "F.Paste")
			(net "DMI_CPU0_PCH_TX_C_DP<3>")
		)
		(pad "A48" smd oval
			(at 4.99999 -13.310108 90)
			(size 0.254 0.3302)
			(layers "F.Cu" "F.Mask" "F.Paste")
			(net "P3E_CPU0_PE1_PCH_TXP<0>")
		)
		(pad "A50" smd oval
			(at 5.999988 -13.310108 90)
			(size 0.254 0.3302)
			(layers "F.Cu" "F.Mask" "F.Paste")
			(net "P3E_CPU0_PE1_PCH_TXP<2>")
		)
		(pad "A52" smd oval
			(at 6.999986 -13.310108 90)
			(size 0.254 0.3302)
			(layers "F.Cu" "F.Mask" "F.Paste")
			(net "P3E_CPU0_PE1_PCH_TXP<4>")
		)
		(pad "A54" smd oval
			(at 7.999984 -13.310108 90)
			(size 0.254 0.3302)
			(layers "F.Cu" "F.Mask" "F.Paste")
			(net "P3E_CPU0_PE1_PCH_TXP<6>")
		)
		(pad "A57" smd oval
			(at 8.999982 -13.310108 90)
			(size 0.254 0.3302)
			(layers "F.Cu" "F.Mask" "F.Paste")
			(net "P3E_CPU0_PE1_PCH_C_TXN<8>")
		)
		(pad "A59" smd oval
			(at 9.99998 -13.310108 90)
			(size 0.254 0.3302)
			(layers "F.Cu" "F.Mask" "F.Paste")
			(net "P3E_CPU0_PE1_PCH_C_TXN<10>")
		)
		(pad "A61" smd oval
			(at 10.999978 -13.310108 90)
			(size 0.254 0.3302)
			(layers "F.Cu" "F.Mask" "F.Paste")
			(net "P3E_CPU0_PE1_PCH_C_TXN<12>")
		)
		(pad "A63" smd oval
			(at 11.999976 -13.310108 90)
			(size 0.254 0.3302)
			(layers "F.Cu" "F.Mask" "F.Paste")
			(net "P3E_CPU0_PE1_PCH_C_TXN<14>")
		)
		(pad "A65" smd circle
			(at 13.063728 -13.310108 90)
			(size 0.3556 0.3556)
			(layers "F.Cu" "F.Mask" "F.Paste")
			(net "GND")
		)
		(pad "A66" smd circle
			(at 13.876528 -13.310108 45)
			(size 0.4064 0.4064)
			(layers "F.Cu" "F.Mask" "F.Paste")
			(net "GND")
		)
		(pad "A68" smd circle
			(at 14.689328 -13.310108 45)
			(size 0.4064 0.4064)
			(layers "F.Cu" "F.Mask" "F.Paste")
			(net "GND")
		)
		(pad "A70" smd circle
			(at 15.502128 -13.310108 45)
			(size 0.5588 0.5588)
			(layers "F.Cu" "F.Mask" "F.Paste")
			(net "GND")
		)
		(pad "AA2" smd circle
			(at -15.895066 -4.500118 180)
			(size 0.3048 0.3048)
			(layers "F.Cu" "F.Mask" "F.Paste")
			(net "IRQ_PIRQA_SPI_TPM_N")
		)
		(pad "AA4" smd circle
			(at -15.064994 -4.500118 180)
			(size 0.3048 0.3048)
			(layers "F.Cu" "F.Mask" "F.Paste")
			(net "Net_482")
		)
		(pad "AA9" smd circle
			(at -12.8778 -4.21005)
			(size 0.381 0.381)
			(layers "F.Cu" "F.Mask" "F.Paste")
			(net "FM_CPU1_PROCHOT_PCH_N")
		)
		(pad "AA13" smd circle
			(at -11.16076 -4.21005)
			(size 0.381 0.381)
			(layers "F.Cu" "F.Mask" "F.Paste")
			(net "H_CPU1_MEMGHJ_MEMHOT_PCH_N")
		)
		(pad "AA17" smd circle
			(at -9.44372 -4.21005)
			(size 0.381 0.381)
			(layers "F.Cu" "F.Mask" "F.Paste")
			(net "FM_PRSNT_2_6_N")
		)
		(pad "AA20" smd circle
			(at -7.72668 -4.21005)
			(size 0.381 0.381)
			(layers "F.Cu" "F.Mask" "F.Paste")
			(net "FM_PRSNT_2_5_N")
		)
		(pad "AA24" smd circle
			(at -6.00964 -4.21005)
			(size 0.381 0.381)
			(layers "F.Cu" "F.Mask" "F.Paste")
			(net "P1V05_PCH_STBY")
		)
		(pad "AA26" smd circle
			(at -5.20065 -4.24815 180)
			(size 0.381 0.381)
			(layers "F.Cu" "F.Mask" "F.Paste")
			(net "GND")
		)
		(pad "AA27" smd circle
			(at -4.40055 -4.24815 180)
			(size 0.381 0.381)
			(layers "F.Cu" "F.Mask" "F.Paste")
			(net "GND")
		)
		(pad "AA29" smd circle
			(at -3.60045 -4.24815 180)
			(size 0.381 0.381)
			(layers "F.Cu" "F.Mask" "F.Paste")
			(net "PVNN_PCH_STBY")
		)
		(pad "AA30" smd circle
			(at -2.80035 -4.24815 180)
			(size 0.381 0.381)
			(layers "F.Cu" "F.Mask" "F.Paste")
			(net "PVNN_PCH_STBY")
		)
		(pad "AA32" smd circle
			(at -2.00025 -4.24815 180)
			(size 0.381 0.381)
			(layers "F.Cu" "F.Mask" "F.Paste")
			(net "PVNN_PCH_STBY")
		)
		(pad "AA34" smd circle
			(at -1.20015 -4.24815 180)
			(size 0.381 0.381)
			(layers "F.Cu" "F.Mask" "F.Paste")
			(net "PVNN_PCH_STBY")
		)
		(pad "AA36" smd circle
			(at -0.40005 -4.24815 180)
			(size 0.381 0.381)
			(layers "F.Cu" "F.Mask" "F.Paste")
			(net "PVNN_PCH_STBY")
		)
		(pad "AA37" smd circle
			(at 0.40005 -4.24815 180)
			(size 0.381 0.381)
			(layers "F.Cu" "F.Mask" "F.Paste")
			(net "PVNN_PCH_STBY")
		)
		(pad "AA39" smd circle
			(at 1.20015 -4.24815 180)
			(size 0.381 0.381)
			(layers "F.Cu" "F.Mask" "F.Paste")
			(net "PVNN_PCH_STBY")
		)
		(pad "AA41" smd circle
			(at 2.00025 -4.24815 180)
			(size 0.381 0.381)
			(layers "F.Cu" "F.Mask" "F.Paste")
			(net "PVNN_PCH_STBY")
		)
		(pad "AA43" smd circle
			(at 2.80035 -4.24815 180)
			(size 0.381 0.381)
			(layers "F.Cu" "F.Mask" "F.Paste")
			(net "GND")
		)
		(pad "AA45" smd circle
			(at 3.60045 -4.24815 180)
			(size 0.381 0.381)
			(layers "F.Cu" "F.Mask" "F.Paste")
			(net "P1V05_PCH_STBY")
		)
		(pad "AA46" smd circle
			(at 4.40055 -4.24815 180)
			(size 0.381 0.381)
			(layers "F.Cu" "F.Mask" "F.Paste")
			(net "P1V05_PCH_STBY")
		)
		(pad "AA48" smd circle
			(at 5.20065 -4.24815 180)
			(size 0.381 0.381)
			(layers "F.Cu" "F.Mask" "F.Paste")
			(net "GND")
		)
		(pad "AA50" smd circle
			(at 6.00964 -4.21005)
			(size 0.381 0.381)
			(layers "F.Cu" "F.Mask" "F.Paste")
			(net "GND")
		)
		(pad "AA54" smd circle
			(at 7.72668 -4.21005)
			(size 0.381 0.381)
			(layers "F.Cu" "F.Mask" "F.Paste")
			(net "TP_PCH_RSVD32")
		)
		(pad "AA58" smd circle
			(at 9.44372 -4.21005)
			(size 0.381 0.381)
			(layers "F.Cu" "F.Mask" "F.Paste")
			(net "TP_PCH_RSVD2")
		)
		(pad "AA61" smd circle
			(at 11.16076 -4.21005)
			(size 0.381 0.381)
			(layers "F.Cu" "F.Mask" "F.Paste")
			(net "SATA6G_PCH_PCIE_UP_SATA_RXN<7>")
		)
		(pad "AA65" smd circle
			(at 12.8778 -4.21005)
			(size 0.381 0.381)
			(layers "F.Cu" "F.Mask" "F.Paste")
			(net "P3E_CPU0_PE1_PCH_R_RXP<15>")
		)
		(pad "AA69" smd circle
			(at 15.064994 -4.500118)
			(size 0.3048 0.3048)
			(layers "F.Cu" "F.Mask" "F.Paste")
			(net "TP_PCH_RSVD51")
		)
		(pad "AA71" smd circle
			(at 15.895066 -4.500118)
			(size 0.3048 0.3048)
			(layers "F.Cu" "F.Mask" "F.Paste")
			(net "TP_PCH_RSVD52")
		)
		(pad "AB1" smd oval
			(at -16.310102 -3.999992 180)
			(size 0.254 0.3302)
			(layers "F.Cu" "F.Mask" "F.Paste")
			(net "PU_LPC_CLKRUN_N")
		)
		(pad "AB3" smd circle
			(at -15.48003 -3.999992 180)
			(size 0.3048 0.3048)
			(layers "F.Cu" "F.Mask" "F.Paste")
			(net "FM_MB_SLOT_ID1")
		)
		(pad "AB5" smd circle
			(at -14.649958 -3.999992 180)
			(size 0.3048 0.3048)
			(layers "F.Cu" "F.Mask" "F.Paste")
			(net "GND")
		)
		(pad "AB68" smd circle
			(at 14.649958 -3.999992)
			(size 0.3048 0.3048)
			(layers "F.Cu" "F.Mask" "F.Paste")
			(net "GND")
		)
		(pad "AB70" smd circle
			(at 15.48003 -3.999992)
			(size 0.3048 0.3048)
			(layers "F.Cu" "F.Mask" "F.Paste")
			(net "GND")
		)
		(pad "AB72" smd oval
			(at 16.310102 -3.999992 180)
			(size 0.254 0.3302)
			(layers "F.Cu" "F.Mask" "F.Paste")
			(net "GND")
		)
		(pad "AC2" smd circle
			(at -15.895066 -3.50012 180)
			(size 0.3048 0.3048)
			(layers "F.Cu" "F.Mask" "F.Paste")
			(net "PU_LPC_PME_N")
		)
		(pad "AC4" smd circle
			(at -15.064994 -3.50012 180)
			(size 0.3048 0.3048)
			(layers "F.Cu" "F.Mask" "F.Paste")
			(net "FM_MB_SLOT_ID2")
		)
		(pad "AC7" smd circle
			(at -13.73632 -3.71475)
			(size 0.381 0.381)
			(layers "F.Cu" "F.Mask" "F.Paste")
			(net "GND")
		)
		(pad "AC11" smd circle
			(at -12.01928 -3.71475)
			(size 0.381 0.381)
			(layers "F.Cu" "F.Mask" "F.Paste")
			(net "GND")
		)
		(pad "AC15" smd circle
			(at -10.30224 -3.71475)
			(size 0.381 0.381)
			(layers "F.Cu" "F.Mask" "F.Paste")
			(net "GND")
		)
		(pad "AC18" smd circle
			(at -8.5852 -3.71475)
			(size 0.381 0.381)
			(layers "F.Cu" "F.Mask" "F.Paste")
			(net "GND")
		)
		(pad "AC22" smd circle
			(at -6.86816 -3.71475)
			(size 0.381 0.381)
			(layers "F.Cu" "F.Mask" "F.Paste")
			(net "GND")
		)
		(pad "AC26" smd circle
			(at -5.20065 -3.44805 180)
			(size 0.381 0.381)
			(layers "F.Cu" "F.Mask" "F.Paste")
			(net "P1V05_PCH_STBY")
		)
		(pad "AC27" smd circle
			(at -4.40055 -3.44805 180)
			(size 0.381 0.381)
			(layers "F.Cu" "F.Mask" "F.Paste")
			(net "GND")
		)
		(pad "AC29" smd circle
			(at -3.60045 -3.44805 180)
			(size 0.381 0.381)
			(layers "F.Cu" "F.Mask" "F.Paste")
			(net "PVNN_PCH_STBY")
		)
		(pad "AC30" smd circle
			(at -2.80035 -3.44805 180)
			(size 0.381 0.381)
			(layers "F.Cu" "F.Mask" "F.Paste")
			(net "PVNN_PCH_STBY")
		)
		(pad "AC32" smd circle
			(at -2.00025 -3.44805 180)
			(size 0.381 0.381)
			(layers "F.Cu" "F.Mask" "F.Paste")
			(net "PVNN_PCH_STBY")
		)
		(pad "AC34" smd circle
			(at -1.20015 -3.44805 180)
			(size 0.381 0.381)
			(layers "F.Cu" "F.Mask" "F.Paste")
			(net "PVNN_PCH_STBY")
		)
		(pad "AC36" smd circle
			(at -0.40005 -3.44805 180)
			(size 0.381 0.381)
			(layers "F.Cu" "F.Mask" "F.Paste")
			(net "PVNN_PCH_STBY")
		)
		(pad "AC37" smd circle
			(at 0.40005 -3.44805 180)
			(size 0.381 0.381)
			(layers "F.Cu" "F.Mask" "F.Paste")
			(net "PVNN_PCH_STBY")
		)
		(pad "AC39" smd circle
			(at 1.20015 -3.44805 180)
			(size 0.381 0.381)
			(layers "F.Cu" "F.Mask" "F.Paste")
			(net "PVNN_PCH_STBY")
		)
		(pad "AC41" smd circle
			(at 2.00025 -3.44805 180)
			(size 0.381 0.381)
			(layers "F.Cu" "F.Mask" "F.Paste")
			(net "PVNN_PCH_STBY")
		)
		(pad "AC43" smd circle
			(at 2.80035 -3.44805 180)
			(size 0.381 0.381)
			(layers "F.Cu" "F.Mask" "F.Paste")
			(net "GND")
		)
		(pad "AC45" smd circle
			(at 3.60045 -3.44805 180)
			(size 0.381 0.381)
			(layers "F.Cu" "F.Mask" "F.Paste")
			(net "GND")
		)
		(pad "AC46" smd circle
			(at 4.40055 -3.44805 180)
			(size 0.381 0.381)
			(layers "F.Cu" "F.Mask" "F.Paste")
			(net "GND")
		)
		(pad "AC48" smd circle
			(at 5.20065 -3.44805 180)
			(size 0.381 0.381)
			(layers "F.Cu" "F.Mask" "F.Paste")
			(net "GND")
		)
		(pad "AC52" smd circle
			(at 6.86816 -3.71475)
			(size 0.381 0.381)
			(layers "F.Cu" "F.Mask" "F.Paste")
			(net "GND")
		)
		(pad "AC56" smd circle
			(at 8.5852 -3.71475)
			(size 0.381 0.381)
			(layers "F.Cu" "F.Mask" "F.Paste")
			(net "TP_PCH_RSVD1")
		)
		(pad "AC59" smd circle
			(at 10.30224 -3.71475)
			(size 0.381 0.381)
			(layers "F.Cu" "F.Mask" "F.Paste")
			(net "GND")
		)
		(pad "AC63" smd circle
			(at 12.01928 -3.71475)
			(size 0.381 0.381)
			(layers "F.Cu" "F.Mask" "F.Paste")
			(net "GND")
		)
		(pad "AC66" smd circle
			(at 13.73632 -3.71475)
			(size 0.381 0.381)
			(layers "F.Cu" "F.Mask" "F.Paste")
			(net "GND")
		)
		(pad "AC69" smd circle
			(at 15.064994 -3.50012)
			(size 0.3048 0.3048)
			(layers "F.Cu" "F.Mask" "F.Paste")
			(net "Net_145")
		)
		(pad "AC71" smd circle
			(at 15.895066 -3.50012)
			(size 0.3048 0.3048)
			(layers "F.Cu" "F.Mask" "F.Paste")
			(net "Net_149")
		)
		(pad "AD1" smd oval
			(at -16.310102 -2.999994 180)
			(size 0.254 0.3302)
			(layers "F.Cu" "F.Mask" "F.Paste")
			(net "FM_CPU_BMC_INIT")
		)
		(pad "AD3" smd circle
			(at -15.48003 -2.999994 180)
			(size 0.3048 0.3048)
			(layers "F.Cu" "F.Mask" "F.Paste")
			(net "RST_PCH_SYSRST_BTN_OUT_N")
		)
		(pad "AD5" smd circle
			(at -14.649958 -2.999994 180)
			(size 0.3048 0.3048)
			(layers "F.Cu" "F.Mask" "F.Paste")
			(net "GND")
		)
		(pad "AD9" smd circle
			(at -12.8778 -3.21945)
			(size 0.381 0.381)
			(layers "F.Cu" "F.Mask" "F.Paste")
			(net "FM_OCP_MEZZB_PRES_1V05_PCH_N")
		)
		(pad "AD13" smd circle
			(at -11.16076 -3.21945)
			(size 0.381 0.381)
			(layers "F.Cu" "F.Mask" "F.Paste")
			(net "H_CPU0_MEMDEF_MEMHOT_PCH_N")
		)
		(pad "AD17" smd circle
			(at -9.44372 -3.21945)
			(size 0.381 0.381)
			(layers "F.Cu" "F.Mask" "F.Paste")
			(net "FM_OCP_MEZZC_PRES_1V05_PCH_N")
		)
		(pad "AD20" smd circle
			(at -7.72668 -3.21945)
			(size 0.381 0.381)
			(layers "F.Cu" "F.Mask" "F.Paste")
			(net "TP_PCH_GPP_L11")
		)
		(pad "AD24" smd circle
			(at -6.00964 -3.21945)
			(size 0.381 0.381)
			(layers "F.Cu" "F.Mask" "F.Paste")
			(net "P3V3_STBY")
		)
		(pad "AD50" smd circle
			(at 6.00964 -3.21945)
			(size 0.381 0.381)
			(layers "F.Cu" "F.Mask" "F.Paste")
			(net "P1V05_PCH_STBY_VCCA_XTAL")
		)
		(pad "AD54" smd circle
			(at 7.72668 -3.21945)
			(size 0.381 0.381)
			(layers "F.Cu" "F.Mask" "F.Paste")
			(net "XDP_PRDY_N")
		)
		(pad "AD58" smd circle
			(at 9.44372 -3.21945)
			(size 0.381 0.381)
			(layers "F.Cu" "F.Mask" "F.Paste")
			(net "GND")
		)
		(pad "AD61" smd circle
			(at 11.16076 -3.21945)
			(size 0.381 0.381)
			(layers "F.Cu" "F.Mask" "F.Paste")
			(net "SATA6G_PCH_PCIE_UP_SATA_RXP<7>")
		)
		(pad "AD65" smd circle
			(at 12.8778 -3.21945)
			(size 0.381 0.381)
			(layers "F.Cu" "F.Mask" "F.Paste")
			(net "GND")
		)
		(pad "AD68" smd circle
			(at 14.649958 -2.999994)
			(size 0.3048 0.3048)
			(layers "F.Cu" "F.Mask" "F.Paste")
			(net "GND")
		)
		(pad "AD70" smd circle
			(at 15.48003 -2.999994)
			(size 0.3048 0.3048)
			(layers "F.Cu" "F.Mask" "F.Paste")
			(net "Net_144")
		)
		(pad "AD72" smd oval
			(at 16.310102 -2.999994 180)
			(size 0.254 0.3302)
			(layers "F.Cu" "F.Mask" "F.Paste")
			(net "Net_148")
		)
		(pad "AE2" smd circle
			(at -15.895066 -2.500122 180)
			(size 0.3048 0.3048)
			(layers "F.Cu" "F.Mask" "F.Paste")
			(net "FM_OCP_MEZZA_PRES_R")
		)
		(pad "AE4" smd circle
			(at -15.064994 -2.500122 180)
			(size 0.3048 0.3048)
			(layers "F.Cu" "F.Mask" "F.Paste")
			(net "FM_TPM_PRES_N")
		)
		(pad "AE7" smd circle
			(at -13.73632 -2.72415)
			(size 0.381 0.381)
			(layers "F.Cu" "F.Mask" "F.Paste")
			(net "FM_CPU_ERR0_PCH_N")
		)
		(pad "AE11" smd circle
			(at -12.01928 -2.72415)
			(size 0.381 0.381)
			(layers "F.Cu" "F.Mask" "F.Paste")
			(net "FM_PRSNT_2_3_N")
		)
		(pad "AE15" smd circle
			(at -10.30224 -2.72415)
			(size 0.381 0.381)
			(layers "F.Cu" "F.Mask" "F.Paste")
			(net "FM_PRSNT_2_2_N")
		)
		(pad "AE18" smd circle
			(at -8.5852 -2.72415)
			(size 0.381 0.381)
			(layers "F.Cu" "F.Mask" "F.Paste")
			(net "FM_PRSNT_2_1_N")
		)
		(pad "AE22" smd circle
			(at -6.86816 -2.72415)
			(size 0.381 0.381)
			(layers "F.Cu" "F.Mask" "F.Paste")
			(net "GND")
		)
		(pad "AE26" smd circle
			(at -5.20065 -2.64795 180)
			(size 0.381 0.381)
			(layers "F.Cu" "F.Mask" "F.Paste")
			(net "P1V8_PCH_STBY")
		)
		(pad "AE27" smd circle
			(at -4.40055 -2.64795 180)
			(size 0.381 0.381)
			(layers "F.Cu" "F.Mask" "F.Paste")
			(net "P1V05_PCH_STBY")
		)
		(pad "AE29" smd circle
			(at -3.60045 -2.64795 180)
			(size 0.381 0.381)
			(layers "F.Cu" "F.Mask" "F.Paste")
			(net "GND")
		)
		(pad "AE30" smd circle
			(at -2.80035 -2.64795 180)
			(size 0.381 0.381)
			(layers "F.Cu" "F.Mask" "F.Paste")
			(net "PVNN_PCH_STBY")
		)
		(pad "AE32" smd circle
			(at -2.00025 -2.64795 180)
			(size 0.381 0.381)
			(layers "F.Cu" "F.Mask" "F.Paste")
			(net "PVNN_PCH_STBY")
		)
		(pad "AE34" smd circle
			(at -1.20015 -2.64795 180)
			(size 0.381 0.381)
			(layers "F.Cu" "F.Mask" "F.Paste")
			(net "PVNN_PCH_STBY")
		)
		(pad "AE36" smd circle
			(at -0.40005 -2.64795 180)
			(size 0.381 0.381)
			(layers "F.Cu" "F.Mask" "F.Paste")
			(net "PVNN_PCH_STBY")
		)
		(pad "AE37" smd circle
			(at 0.40005 -2.64795 180)
			(size 0.381 0.381)
			(layers "F.Cu" "F.Mask" "F.Paste")
			(net "PVNN_PCH_STBY")
		)
		(pad "AE39" smd circle
			(at 1.20015 -2.64795 180)
			(size 0.381 0.381)
			(layers "F.Cu" "F.Mask" "F.Paste")
			(net "PVNN_PCH_STBY")
		)
		(pad "AE41" smd circle
			(at 2.00025 -2.64795 180)
			(size 0.381 0.381)
			(layers "F.Cu" "F.Mask" "F.Paste")
			(net "PVNN_PCH_STBY")
		)
		(pad "AE43" smd circle
			(at 2.80035 -2.64795 180)
			(size 0.381 0.381)
			(layers "F.Cu" "F.Mask" "F.Paste")
			(net "GND")
		)
		(pad "AE45" smd circle
			(at 3.60045 -2.64795 180)
			(size 0.381 0.381)
			(layers "F.Cu" "F.Mask" "F.Paste")
			(net "P1V05_PCH_STBY_VCCA_PLL1")
		)
		(pad "AE46" smd circle
			(at 4.40055 -2.64795 180)
			(size 0.381 0.381)
			(layers "F.Cu" "F.Mask" "F.Paste")
			(net "P1V05_PCH_STBY_ISCLK_PLL")
		)
		(pad "AE48" smd circle
			(at 5.20065 -2.64795 180)
			(size 0.381 0.381)
			(layers "F.Cu" "F.Mask" "F.Paste")
			(net "GND")
		)
		(pad "AE52" smd circle
			(at 6.86816 -2.72415)
			(size 0.381 0.381)
			(layers "F.Cu" "F.Mask" "F.Paste")
			(net "GND")
		)
		(pad "AE56" smd circle
			(at 8.5852 -2.72415)
			(size 0.381 0.381)
			(layers "F.Cu" "F.Mask" "F.Paste")
			(net "GND")
		)
		(pad "AE59" smd circle
			(at 10.30224 -2.72415)
			(size 0.381 0.381)
			(layers "F.Cu" "F.Mask" "F.Paste")
			(net "GND")
		)
		(pad "AE63" smd circle
			(at 12.01928 -2.72415)
			(size 0.381 0.381)
			(layers "F.Cu" "F.Mask" "F.Paste")
			(net "GND")
		)
		(pad "AE66" smd circle
			(at 13.73632 -2.72415)
			(size 0.381 0.381)
			(layers "F.Cu" "F.Mask" "F.Paste")
			(net "GND")
		)
		(pad "AE69" smd circle
			(at 15.064994 -2.500122)
			(size 0.3048 0.3048)
			(layers "F.Cu" "F.Mask" "F.Paste")
			(net "Net_143")
		)
		(pad "AE71" smd circle
			(at 15.895066 -2.500122)
			(size 0.3048 0.3048)
			(layers "F.Cu" "F.Mask" "F.Paste")
			(net "Net_147")
		)
		(pad "AF1" smd oval
			(at -16.310102 -1.999996 180)
			(size 0.254 0.3302)
			(layers "F.Cu" "F.Mask" "F.Paste")
			(net "GND")
		)
		(pad "AF3" smd circle
			(at -15.48003 -1.999996 180)
			(size 0.3048 0.3048)
			(layers "F.Cu" "F.Mask" "F.Paste")
			(net "GND")
		)
		(pad "AF5" smd circle
			(at -14.649958 -1.999996 180)
			(size 0.3048 0.3048)
			(layers "F.Cu" "F.Mask" "F.Paste")
			(net "GND")
		)
		(pad "AF9" smd circle
			(at -12.8778 -2.22885)
			(size 0.381 0.381)
			(layers "F.Cu" "F.Mask" "F.Paste")
			(net "GND")
		)
		(pad "AF13" smd circle
			(at -11.16076 -2.22885)
			(size 0.381 0.381)
			(layers "F.Cu" "F.Mask" "F.Paste")
			(net "GND")
		)
		(pad "AF17" smd circle
			(at -9.44372 -2.22885)
			(size 0.381 0.381)
			(layers "F.Cu" "F.Mask" "F.Paste")
			(net "GND")
		)
		(pad "AF20" smd circle
			(at -7.72668 -2.22885)
			(size 0.381 0.381)
			(layers "F.Cu" "F.Mask" "F.Paste")
			(net "TP_PCH_GPP_L10")
		)
		(pad "AF24" smd circle
			(at -6.00964 -2.22885)
			(size 0.381 0.381)
			(layers "F.Cu" "F.Mask" "F.Paste")
			(net "GND")
		)
		(pad "AF50" smd circle
			(at 6.00964 -2.22885)
			(size 0.381 0.381)
			(layers "F.Cu" "F.Mask" "F.Paste")
			(net "GND")
		)
		(pad "AF54" smd circle
			(at 7.72668 -2.22885)
			(size 0.381 0.381)
			(layers "F.Cu" "F.Mask" "F.Paste")
			(net "XDP_PCH_CPU_TCK0")
		)
		(pad "AF58" smd circle
			(at 9.44372 -2.22885)
			(size 0.381 0.381)
			(layers "F.Cu" "F.Mask" "F.Paste")
			(net "A_PCIEUP_RCOMP_N")
		)
		(pad "AF61" smd circle
			(at 11.16076 -2.22885)
			(size 0.381 0.381)
			(layers "F.Cu" "F.Mask" "F.Paste")
			(net "TP_PCH_RSVD0")
		)
		(pad "AF65" smd circle
			(at 12.8778 -2.22885)
			(size 0.381 0.381)
			(layers "F.Cu" "F.Mask" "F.Paste")
			(net "SATA6G_PCH_PCIE_UP_SATA_RXN<4>")
		)
		(pad "AF68" smd circle
			(at 14.649958 -1.999996)
			(size 0.3048 0.3048)
			(layers "F.Cu" "F.Mask" "F.Paste")
			(net "GND")
		)
		(pad "AF70" smd circle
			(at 15.48003 -1.999996)
			(size 0.3048 0.3048)
			(layers "F.Cu" "F.Mask" "F.Paste")
			(net "Net_142")
		)
		(pad "AF72" smd oval
			(at 16.310102 -1.999996 180)
			(size 0.254 0.3302)
			(layers "F.Cu" "F.Mask" "F.Paste")
			(net "Net_146")
		)
		(pad "AG7" smd circle
			(at -13.73632 -1.73355)
			(size 0.381 0.381)
			(layers "F.Cu" "F.Mask" "F.Paste")
			(net "IRQ_OC_DETECT_N")
		)
		(pad "AG11" smd circle
			(at -12.01928 -1.73355)
			(size 0.381 0.381)
			(layers "F.Cu" "F.Mask" "F.Paste")
			(net "FM_CPU_ERR1_PCH_N")
		)
		(pad "AG15" smd circle
			(at -10.30224 -1.73355)
			(size 0.381 0.381)
			(layers "F.Cu" "F.Mask" "F.Paste")
			(net "TP_PCH_RSVD5")
		)
		(pad "AG18" smd circle
			(at -8.5852 -1.73355)
			(size 0.381 0.381)
			(layers "F.Cu" "F.Mask" "F.Paste")
			(net "FM_INTRUDER_HDR_PCH_N")
		)
		(pad "AG22" smd circle
			(at -6.86816 -1.73355)
			(size 0.381 0.381)
			(layers "F.Cu" "F.Mask" "F.Paste")
			(net "A_PVCCRTC_EXT_CAP")
		)
		(pad "AG26" smd circle
			(at -5.20065 -1.84785 180)
			(size 0.381 0.381)
			(layers "F.Cu" "F.Mask" "F.Paste")
			(net "GND")
		)
		(pad "AG27" smd circle
			(at -4.40055 -1.84785 180)
			(size 0.381 0.381)
			(layers "F.Cu" "F.Mask" "F.Paste")
			(net "P1V8_PCH_STBY")
		)
		(pad "AG29" smd circle
			(at -3.60045 -1.84785 180)
			(size 0.381 0.381)
			(layers "F.Cu" "F.Mask" "F.Paste")
			(net "P3V3_STBY")
		)
		(pad "AG30" smd circle
			(at -2.80035 -1.84785 180)
			(size 0.381 0.381)
			(layers "F.Cu" "F.Mask" "F.Paste")
			(net "GND")
		)
		(pad "AG32" smd circle
			(at -2.00025 -1.84785 180)
			(size 0.381 0.381)
			(layers "F.Cu" "F.Mask" "F.Paste")
			(net "PVNN_PCH_STBY")
		)
		(pad "AG34" smd circle
			(at -1.20015 -1.84785 180)
			(size 0.381 0.381)
			(layers "F.Cu" "F.Mask" "F.Paste")
			(net "PVNN_PCH_STBY")
		)
		(pad "AG36" smd circle
			(at -0.40005 -1.84785 180)
			(size 0.381 0.381)
			(layers "F.Cu" "F.Mask" "F.Paste")
			(net "PVNN_PCH_STBY")
		)
		(pad "AG37" smd circle
			(at 0.40005 -1.84785 180)
			(size 0.381 0.381)
			(layers "F.Cu" "F.Mask" "F.Paste")
			(net "PVNN_PCH_STBY")
		)
		(pad "AG39" smd circle
			(at 1.20015 -1.84785 180)
			(size 0.381 0.381)
			(layers "F.Cu" "F.Mask" "F.Paste")
			(net "PVNN_PCH_STBY")
		)
		(pad "AG41" smd circle
			(at 2.00025 -1.84785 180)
			(size 0.381 0.381)
			(layers "F.Cu" "F.Mask" "F.Paste")
			(net "GND")
		)
		(pad "AG43" smd circle
			(at 2.80035 -1.84785 180)
			(size 0.381 0.381)
			(layers "F.Cu" "F.Mask" "F.Paste")
			(net "GND")
		)
		(pad "AG45" smd circle
			(at 3.60045 -1.84785 180)
			(size 0.381 0.381)
			(layers "F.Cu" "F.Mask" "F.Paste")
			(net "P1V05_PCH_STBY_ISCLK_PLL")
		)
		(pad "AG46" smd circle
			(at 4.40055 -1.84785 180)
			(size 0.381 0.381)
			(layers "F.Cu" "F.Mask" "F.Paste")
			(net "GND")
		)
		(pad "AG48" smd circle
			(at 5.20065 -1.84785 180)
			(size 0.381 0.381)
			(layers "F.Cu" "F.Mask" "F.Paste")
			(net "P1V05_PCH_STBY_VCCA_PLL0")
		)
		(pad "AG52" smd circle
			(at 6.86816 -1.73355)
			(size 0.381 0.381)
			(layers "F.Cu" "F.Mask" "F.Paste")
			(net "GND")
		)
		(pad "AG56" smd circle
			(at 8.5852 -1.73355)
			(size 0.381 0.381)
			(layers "F.Cu" "F.Mask" "F.Paste")
			(net "GND")
		)
		(pad "AG59" smd circle
			(at 10.30224 -1.73355)
			(size 0.381 0.381)
			(layers "F.Cu" "F.Mask" "F.Paste")
			(net "GND")
		)
		(pad "AG63" smd circle
			(at 12.01928 -1.73355)
			(size 0.381 0.381)
			(layers "F.Cu" "F.Mask" "F.Paste")
			(net "SATA6G_PCH_PCIE_UP_SATA_RXP<5>")
		)
		(pad "AG66" smd circle
			(at 13.73632 -1.73355)
			(size 0.381 0.381)
			(layers "F.Cu" "F.Mask" "F.Paste")
			(net "GND")
		)
		(pad "AH2" smd circle
			(at -15.895066 -1.500124 180)
			(size 0.3048 0.3048)
			(layers "F.Cu" "F.Mask" "F.Paste")
			(net "RMII_BMC_PCH_SPRNGVLLE_RXER_R")
		)
		(pad "AH4" smd circle
			(at -15.064994 -1.500124 180)
			(size 0.3048 0.3048)
			(layers "F.Cu" "F.Mask" "F.Paste")
			(net "RST_PCIE_PCH_PERST_N")
		)
		(pad "AH9" smd circle
			(at -12.8778 -1.23825)
			(size 0.381 0.381)
			(layers "F.Cu" "F.Mask" "F.Paste")
			(net "JTAG_PCH_PLD_TMS")
		)
		(pad "AH13" smd circle
			(at -11.16076 -1.23825)
			(size 0.381 0.381)
			(layers "F.Cu" "F.Mask" "F.Paste")
			(net "FM_BMC_READY_R1_N")
		)
		(pad "AH17" smd circle
			(at -9.44372 -1.23825)
			(size 0.381 0.381)
			(layers "F.Cu" "F.Mask" "F.Paste")
			(net "FM_BIOS_USB_RECOVERY")
		)
		(pad "AH20" smd circle
			(at -7.72668 -1.23825)
			(size 0.381 0.381)
			(layers "F.Cu" "F.Mask" "F.Paste")
			(net "GND")
		)
		(pad "AH24" smd circle
			(at -6.00964 -1.23825)
			(size 0.381 0.381)
			(layers "F.Cu" "F.Mask" "F.Paste")
			(net "P3V3_STBY")
		)
		(pad "AH50" smd circle
			(at 6.00964 -1.23825)
			(size 0.381 0.381)
			(layers "F.Cu" "F.Mask" "F.Paste")
			(net "P1V05_PCH_STBY")
		)
		(pad "AH54" smd circle
			(at 7.72668 -1.23825)
			(size 0.381 0.381)
			(layers "F.Cu" "F.Mask" "F.Paste")
			(net "XDP_TMS")
		)
		(pad "AH58" smd circle
			(at 9.44372 -1.23825)
			(size 0.381 0.381)
			(layers "F.Cu" "F.Mask" "F.Paste")
			(net "A_PCIEUP_RCOMP_P")
		)
		(pad "AH61" smd circle
			(at 11.16076 -1.23825)
			(size 0.381 0.381)
			(layers "F.Cu" "F.Mask" "F.Paste")
			(net "SATA6G_PCH_PCIE_UP_SATA_RXN<5>")
		)
		(pad "AH65" smd circle
			(at 12.8778 -1.23825)
			(size 0.381 0.381)
			(layers "F.Cu" "F.Mask" "F.Paste")
			(net "SATA6G_PCH_PCIE_UP_SATA_RXP<4>")
		)
		(pad "AH69" smd circle
			(at 15.064994 -1.500124)
			(size 0.3048 0.3048)
			(layers "F.Cu" "F.Mask" "F.Paste")
			(net "SATA6G_S1_TX_DN")
		)
		(pad "AH71" smd circle
			(at 15.895066 -1.500124)
			(size 0.3048 0.3048)
			(layers "F.Cu" "F.Mask" "F.Paste")
			(net "SATA6G_S1_TX_DP")
		)
		(pad "AJ1" smd oval
			(at -16.310102 -0.999998 180)
			(size 0.254 0.3302)
			(layers "F.Cu" "F.Mask" "F.Paste")
			(net "CLK_50M_CKMNG_PCH_10GBE")
		)
		(pad "AJ3" smd circle
			(at -15.48003 -0.999998 180)
			(size 0.3048 0.3048)
			(layers "F.Cu" "F.Mask" "F.Paste")
			(net "RMII_PCH_SPRNGVLLE_ARB_IN")
		)
		(pad "AJ5" smd circle
			(at -14.649958 -0.999998 180)
			(size 0.3048 0.3048)
			(layers "F.Cu" "F.Mask" "F.Paste")
			(net "GND")
		)
		(pad "AJ7" smd circle
			(at -13.73632 -0.74295)
			(size 0.381 0.381)
			(layers "F.Cu" "F.Mask" "F.Paste")
			(net "GND")
		)
		(pad "AJ11" smd circle
			(at -12.01928 -0.74295)
			(size 0.381 0.381)
			(layers "F.Cu" "F.Mask" "F.Paste")
			(net "GND")
		)
		(pad "AJ15" smd circle
			(at -10.30224 -0.74295)
			(size 0.381 0.381)
			(layers "F.Cu" "F.Mask" "F.Paste")
			(net "GND")
		)
		(pad "AJ18" smd circle
			(at -8.5852 -0.74295)
			(size 0.381 0.381)
			(layers "F.Cu" "F.Mask" "F.Paste")
			(net "GND")
		)
		(pad "AJ22" smd circle
			(at -6.86816 -0.74295)
			(size 0.381 0.381)
			(layers "F.Cu" "F.Mask" "F.Paste")
			(net "GND")
		)
		(pad "AJ26" smd circle
			(at -5.20065 -1.04775 180)
			(size 0.381 0.381)
			(layers "F.Cu" "F.Mask" "F.Paste")
			(net "GND")
		)
		(pad "AJ27" smd circle
			(at -4.40055 -1.04775 180)
			(size 0.381 0.381)
			(layers "F.Cu" "F.Mask" "F.Paste")
			(net "P3V3_RTC_STBY")
		)
		(pad "AJ29" smd circle
			(at -3.60045 -1.04775 180)
			(size 0.381 0.381)
			(layers "F.Cu" "F.Mask" "F.Paste")
			(net "P1V05_PCH_STBY")
		)
		(pad "AJ30" smd circle
			(at -2.80035 -1.04775 180)
			(size 0.381 0.381)
			(layers "F.Cu" "F.Mask" "F.Paste")
			(net "GND")
		)
		(pad "AJ32" smd circle
			(at -2.00025 -1.04775 180)
			(size 0.381 0.381)
			(layers "F.Cu" "F.Mask" "F.Paste")
			(net "GND")
		)
		(pad "AJ34" smd circle
			(at -1.20015 -1.04775 180)
			(size 0.381 0.381)
			(layers "F.Cu" "F.Mask" "F.Paste")
			(net "GND")
		)
		(pad "AJ36" smd circle
			(at -0.40005 -1.04775 180)
			(size 0.381 0.381)
			(layers "F.Cu" "F.Mask" "F.Paste")
			(net "GND")
		)
		(pad "AJ37" smd circle
			(at 0.40005 -1.04775 180)
			(size 0.381 0.381)
			(layers "F.Cu" "F.Mask" "F.Paste")
			(net "GND")
		)
		(pad "AJ39" smd circle
			(at 1.20015 -1.04775 180)
			(size 0.381 0.381)
			(layers "F.Cu" "F.Mask" "F.Paste")
			(net "GND")
		)
		(pad "AJ41" smd circle
			(at 2.00025 -1.04775 180)
			(size 0.381 0.381)
			(layers "F.Cu" "F.Mask" "F.Paste")
			(net "GND")
		)
		(pad "AJ43" smd circle
			(at 2.80035 -1.04775 180)
			(size 0.381 0.381)
			(layers "F.Cu" "F.Mask" "F.Paste")
			(net "P1V05_PCH_STBY")
		)
		(pad "AJ45" smd circle
			(at 3.60045 -1.04775 180)
			(size 0.381 0.381)
			(layers "F.Cu" "F.Mask" "F.Paste")
			(net "GND")
		)
		(pad "AJ46" smd circle
			(at 4.40055 -1.04775 180)
			(size 0.381 0.381)
			(layers "F.Cu" "F.Mask" "F.Paste")
			(net "P1V05_PCH_STBY_ISCLK_PLL")
		)
		(pad "AJ48" smd circle
			(at 5.20065 -1.04775 180)
			(size 0.381 0.381)
			(layers "F.Cu" "F.Mask" "F.Paste")
			(net "P1V05_PCH_STBY_ISCLK_PLL")
		)
		(pad "AJ52" smd circle
			(at 6.86816 -0.74295)
			(size 0.381 0.381)
			(layers "F.Cu" "F.Mask" "F.Paste")
			(net "GND")
		)
		(pad "AJ56" smd circle
			(at 8.5852 -0.74295)
			(size 0.381 0.381)
			(layers "F.Cu" "F.Mask" "F.Paste")
			(net "GND")
		)
		(pad "AJ59" smd circle
			(at 10.30224 -0.74295)
			(size 0.381 0.381)
			(layers "F.Cu" "F.Mask" "F.Paste")
			(net "GND")
		)
		(pad "AJ63" smd circle
			(at 12.01928 -0.74295)
			(size 0.381 0.381)
			(layers "F.Cu" "F.Mask" "F.Paste")
			(net "SATA6G_PCH_PCIE_UP_SATA_RXP<2>")
		)
		(pad "AJ66" smd circle
			(at 13.73632 -0.74295)
			(size 0.381 0.381)
			(layers "F.Cu" "F.Mask" "F.Paste")
			(net "GND")
		)
		(pad "AJ68" smd circle
			(at 14.649958 -0.999998)
			(size 0.3048 0.3048)
			(layers "F.Cu" "F.Mask" "F.Paste")
			(net "GND")
		)
		(pad "AJ70" smd circle
			(at 15.48003 -0.999998)
			(size 0.3048 0.3048)
			(layers "F.Cu" "F.Mask" "F.Paste")
			(net "SATA6G_S0_TX_DN")
		)
		(pad "AJ72" smd oval
			(at 16.310102 -0.999998 180)
			(size 0.254 0.3302)
			(layers "F.Cu" "F.Mask" "F.Paste")
			(net "SATA6G_S0_TX_DP")
		)
		(pad "AK2" smd circle
			(at -15.895066 -0.500126 180)
			(size 0.3048 0.3048)
			(layers "F.Cu" "F.Mask" "F.Paste")
			(net "RMII_BMC_PCH_SPRNGVLLE_TXD1")
		)
		(pad "AK4" smd circle
			(at -15.064994 -0.500126 180)
			(size 0.3048 0.3048)
			(layers "F.Cu" "F.Mask" "F.Paste")
			(net "RMII_PCH_SPRNGVLLE_ARB_OUT_R")
		)
		(pad "AK9" smd circle
			(at -12.8778 -0.24765)
			(size 0.381 0.381)
			(layers "F.Cu" "F.Mask" "F.Paste")
			(net "FM_HSC_TIMER_EXP_N")
		)
		(pad "AK13" smd circle
			(at -11.16076 -0.24765)
			(size 0.381 0.381)
			(layers "F.Cu" "F.Mask" "F.Paste")
			(net "FM_MP_PS_REDUNDANT_LOST_N")
		)
		(pad "AK17" smd circle
			(at -9.44372 -0.24765)
			(size 0.381 0.381)
			(layers "F.Cu" "F.Mask" "F.Paste")
			(net "JTAG_PCH_PLD_TDI")
		)
		(pad "AK20" smd circle
			(at -7.72668 -0.24765)
			(size 0.381 0.381)
			(layers "F.Cu" "F.Mask" "F.Paste")
			(net "FM_MP_PS_FAIL_N")
		)
		(pad "AK24" smd circle
			(at -6.00964 -0.24765)
			(size 0.381 0.381)
			(layers "F.Cu" "F.Mask" "F.Paste")
			(net "P1V8_PCH_STBY")
		)
		(pad "AK26" smd circle
			(at -5.20065 -0.24765 180)
			(size 0.381 0.381)
			(layers "F.Cu" "F.Mask" "F.Paste")
			(net "GND")
		)
		(pad "AK27" smd circle
			(at -4.40055 -0.24765 180)
			(size 0.381 0.381)
			(layers "F.Cu" "F.Mask" "F.Paste")
			(net "P1V05_PCH_STBY")
		)
		(pad "AK29" smd circle
			(at -3.60045 -0.24765 180)
			(size 0.381 0.381)
			(layers "F.Cu" "F.Mask" "F.Paste")
			(net "P1V8_PCH_STBY")
		)
		(pad "AK30" smd circle
			(at -2.80035 -0.24765 180)
			(size 0.381 0.381)
			(layers "F.Cu" "F.Mask" "F.Paste")
			(net "GND")
		)
		(pad "AK32" smd circle
			(at -2.00025 -0.24765 180)
			(size 0.381 0.381)
			(layers "F.Cu" "F.Mask" "F.Paste")
			(net "PVNN_PCH_STBY")
		)
		(pad "AK34" smd circle
			(at -1.20015 -0.24765 180)
			(size 0.381 0.381)
			(layers "F.Cu" "F.Mask" "F.Paste")
			(net "PVNN_PCH_STBY")
		)
		(pad "AK36" smd circle
			(at -0.40005 -0.24765 180)
			(size 0.381 0.381)
			(layers "F.Cu" "F.Mask" "F.Paste")
			(net "VSENSE_PVNN_PCH_STBY_FPK")
		)
		(pad "AK37" smd circle
			(at 0.40005 -0.24765 180)
			(size 0.381 0.381)
			(layers "F.Cu" "F.Mask" "F.Paste")
			(net "PVNN_PCH_STBY")
		)
		(pad "AK39" smd circle
			(at 1.20015 -0.24765 180)
			(size 0.381 0.381)
			(layers "F.Cu" "F.Mask" "F.Paste")
			(net "PVNN_PCH_STBY")
		)
		(pad "AK41" smd circle
			(at 2.00025 -0.24765 180)
			(size 0.381 0.381)
			(layers "F.Cu" "F.Mask" "F.Paste")
			(net "GND")
		)
		(pad "AK43" smd circle
			(at 2.80035 -0.24765 180)
			(size 0.381 0.381)
			(layers "F.Cu" "F.Mask" "F.Paste")
			(net "P1V05_PCH_STBY")
		)
		(pad "AK45" smd circle
			(at 3.60045 -0.24765 180)
			(size 0.381 0.381)
			(layers "F.Cu" "F.Mask" "F.Paste")
			(net "P1V05_PCH_STBY")
		)
		(pad "AK46" smd circle
			(at 4.40055 -0.24765 180)
			(size 0.381 0.381)
			(layers "F.Cu" "F.Mask" "F.Paste")
			(net "GND")
		)
		(pad "AK48" smd circle
			(at 5.20065 -0.24765 180)
			(size 0.381 0.381)
			(layers "F.Cu" "F.Mask" "F.Paste")
			(net "GND")
		)
		(pad "AK50" smd circle
			(at 6.00964 -0.24765)
			(size 0.381 0.381)
			(layers "F.Cu" "F.Mask" "F.Paste")
			(net "P1V05_PCH_STBY_WM20_PLL")
		)
		(pad "AK54" smd circle
			(at 7.72668 -0.24765)
			(size 0.381 0.381)
			(layers "F.Cu" "F.Mask" "F.Paste")
			(net "TP_PCH_RSVD36")
		)
		(pad "AK58" smd circle
			(at 9.44372 -0.24765)
			(size 0.381 0.381)
			(layers "F.Cu" "F.Mask" "F.Paste")
			(net "GND")
		)
		(pad "AK61" smd circle
			(at 11.16076 -0.24765)
			(size 0.381 0.381)
			(layers "F.Cu" "F.Mask" "F.Paste")
			(net "GND")
		)
		(pad "AK65" smd circle
			(at 12.8778 -0.24765)
			(size 0.381 0.381)
			(layers "F.Cu" "F.Mask" "F.Paste")
			(net "SATA6G_PCH_PCIE_UP_SATA_RXN<2>")
		)
		(pad "AK69" smd circle
			(at 15.064994 -0.500126)
			(size 0.3048 0.3048)
			(layers "F.Cu" "F.Mask" "F.Paste")
			(net "GND")
		)
		(pad "AK71" smd circle
			(at 15.895066 -0.500126)
			(size 0.3048 0.3048)
			(layers "F.Cu" "F.Mask" "F.Paste")
			(net "GND")
		)
		(pad "AL1" smd oval
			(at -16.310102 0 180)
			(size 0.254 0.3302)
			(layers "F.Cu" "F.Mask" "F.Paste")
			(net "RMII_SPRNGVLLE_BMC_PCH_RXD0_R1")
		)
		(pad "AL3" smd circle
			(at -15.48003 0 180)
			(size 0.3048 0.3048)
			(layers "F.Cu" "F.Mask" "F.Paste")
			(net "RMII_BMC_PCH_SPRNGVLLE_TXEN")
		)
		(pad "AL5" smd circle
			(at -14.649958 0 180)
			(size 0.3048 0.3048)
			(layers "F.Cu" "F.Mask" "F.Paste")
			(net "GND")
		)
		(pad "AL7" smd circle
			(at -13.73632 0.24765)
			(size 0.381 0.381)
			(layers "F.Cu" "F.Mask" "F.Paste")
			(net "SGPIO_PCH_SATA_CLOCK")
		)
		(pad "AL11" smd circle
			(at -12.01928 0.24765)
			(size 0.381 0.381)
			(layers "F.Cu" "F.Mask" "F.Paste")
			(net "LED_PCH_SSATA_HDD_N")
		)
		(pad "AL15" smd circle
			(at -10.30224 0.24765)
			(size 0.381 0.381)
			(layers "F.Cu" "F.Mask" "F.Paste")
			(net "FM_MEM_THERM_EVENT_PCH_N")
		)
		(pad "AL18" smd circle
			(at -8.5852 0.24765)
			(size 0.381 0.381)
			(layers "F.Cu" "F.Mask" "F.Paste")
			(net "JTAG_PCH_PLD_TCK")
		)
		(pad "AL22" smd circle
			(at -6.86816 0.24765)
			(size 0.381 0.381)
			(layers "F.Cu" "F.Mask" "F.Paste")
			(net "GND")
		)
		(pad "AL52" smd circle
			(at 6.86816 0.24765)
			(size 0.381 0.381)
			(layers "F.Cu" "F.Mask" "F.Paste")
			(net "GND")
		)
		(pad "AL56" smd circle
			(at 8.5852 0.24765)
			(size 0.381 0.381)
			(layers "F.Cu" "F.Mask" "F.Paste")
			(net "XDP_PCH_TCK1")
		)
		(pad "AL59" smd circle
			(at 10.30224 0.24765)
			(size 0.381 0.381)
			(layers "F.Cu" "F.Mask" "F.Paste")
			(net "GND")
		)
		(pad "AL63" smd circle
			(at 12.01928 0.24765)
			(size 0.381 0.381)
			(layers "F.Cu" "F.Mask" "F.Paste")
			(net "SATA6G_PCH_PCIE_UP_SATA_RXP<3>")
		)
		(pad "AL66" smd circle
			(at 13.73632 0.24765)
			(size 0.381 0.381)
			(layers "F.Cu" "F.Mask" "F.Paste")
			(net "SATA6G_PCH_PCIE_UP_SATA_RXN<1>")
		)
		(pad "AL68" smd circle
			(at 14.649958 0)
			(size 0.3048 0.3048)
			(layers "F.Cu" "F.Mask" "F.Paste")
			(net "GND")
		)
		(pad "AL70" smd circle
			(at 15.48003 0)
			(size 0.3048 0.3048)
			(layers "F.Cu" "F.Mask" "F.Paste")
			(net "GND")
		)
		(pad "AL72" smd oval
			(at 16.310102 0 180)
			(size 0.254 0.3302)
			(layers "F.Cu" "F.Mask" "F.Paste")
			(net "GND")
		)
		(pad "AM2" smd circle
			(at -15.895066 0.500126 180)
			(size 0.3048 0.3048)
			(layers "F.Cu" "F.Mask" "F.Paste")
			(net "RMII_BMC_PCH_SPRNGVLLE_TXD0")
		)
		(pad "AM4" smd circle
			(at -15.064994 0.500126 180)
			(size 0.3048 0.3048)
			(layers "F.Cu" "F.Mask" "F.Paste")
			(net "A_1P8_3P3_RCOMP")
		)
		(pad "AM26" smd circle
			(at -5.20065 0.55245 180)
			(size 0.381 0.381)
			(layers "F.Cu" "F.Mask" "F.Paste")
			(net "GND")
		)
		(pad "AM27" smd circle
			(at -4.40055 0.55245 180)
			(size 0.381 0.381)
			(layers "F.Cu" "F.Mask" "F.Paste")
			(net "P1V05_PCH_STBY")
		)
		(pad "AM29" smd circle
			(at -3.60045 0.55245 180)
			(size 0.381 0.381)
			(layers "F.Cu" "F.Mask" "F.Paste")
			(net "P1V8_PCH_STBY")
		)
		(pad "AM30" smd circle
			(at -2.80035 0.55245 180)
			(size 0.381 0.381)
			(layers "F.Cu" "F.Mask" "F.Paste")
			(net "GND")
		)
		(pad "AM32" smd circle
			(at -2.00025 0.55245 180)
			(size 0.381 0.381)
			(layers "F.Cu" "F.Mask" "F.Paste")
			(net "PVNN_PCH_STBY")
		)
		(pad "AM34" smd circle
			(at -1.20015 0.55245 180)
			(size 0.381 0.381)
			(layers "F.Cu" "F.Mask" "F.Paste")
			(net "PVNN_PCH_STBY")
		)
		(pad "AM36" smd circle
			(at -0.40005 0.55245 180)
			(size 0.381 0.381)
			(layers "F.Cu" "F.Mask" "F.Paste")
			(net "PVNN_PCH_STBY")
		)
		(pad "AM37" smd circle
			(at 0.40005 0.55245 180)
			(size 0.381 0.381)
			(layers "F.Cu" "F.Mask" "F.Paste")
			(net "PVNN_PCH_STBY")
		)
		(pad "AM39" smd circle
			(at 1.20015 0.55245 180)
			(size 0.381 0.381)
			(layers "F.Cu" "F.Mask" "F.Paste")
			(net "PVNN_PCH_STBY")
		)
		(pad "AM41" smd circle
			(at 2.00025 0.55245 180)
			(size 0.381 0.381)
			(layers "F.Cu" "F.Mask" "F.Paste")
			(net "GND")
		)
		(pad "AM43" smd circle
			(at 2.80035 0.55245 180)
			(size 0.381 0.381)
			(layers "F.Cu" "F.Mask" "F.Paste")
			(net "P1V05_PCH_STBY")
		)
		(pad "AM45" smd circle
			(at 3.60045 0.55245 180)
			(size 0.381 0.381)
			(layers "F.Cu" "F.Mask" "F.Paste")
			(net "P1V05_PCH_STBY")
		)
		(pad "AM46" smd circle
			(at 4.40055 0.55245 180)
			(size 0.381 0.381)
			(layers "F.Cu" "F.Mask" "F.Paste")
			(net "GND")
		)
		(pad "AM48" smd circle
			(at 5.20065 0.55245 180)
			(size 0.381 0.381)
			(layers "F.Cu" "F.Mask" "F.Paste")
			(net "P1V05_PCH_STBY")
		)
		(pad "AM69" smd circle
			(at 15.064994 0.500126)
			(size 0.3048 0.3048)
			(layers "F.Cu" "F.Mask" "F.Paste")
			(net "PE_PCH_SPRV_RX_C_DN")
		)
		(pad "AM71" smd circle
			(at 15.895066 0.500126)
			(size 0.3048 0.3048)
			(layers "F.Cu" "F.Mask" "F.Paste")
			(net "PE_PCH_SPRV_RX_C_DP")
		)
		(pad "AN1" smd oval
			(at -16.310102 0.999998 180)
			(size 0.254 0.3302)
			(layers "F.Cu" "F.Mask" "F.Paste")
			(net "RMII_SPRNGVLLE_BMC_PCH_RXD1_R1")
		)
		(pad "AN3" smd circle
			(at -15.48003 0.999998 180)
			(size 0.3048 0.3048)
			(layers "F.Cu" "F.Mask" "F.Paste")
			(net "RMII_BMC_PCH_SPRNGVLLE_CRSDV_R1")
		)
		(pad "AN5" smd circle
			(at -14.649958 0.999998 180)
			(size 0.3048 0.3048)
			(layers "F.Cu" "F.Mask" "F.Paste")
			(net "GND")
		)
		(pad "AN9" smd circle
			(at -12.8778 0.74295)
			(size 0.381 0.381)
			(layers "F.Cu" "F.Mask" "F.Paste")
			(net "GND")
		)
		(pad "AN13" smd circle
			(at -11.16076 0.74295)
			(size 0.381 0.381)
			(layers "F.Cu" "F.Mask" "F.Paste")
			(net "GND")
		)
		(pad "AN17" smd circle
			(at -9.44372 0.74295)
			(size 0.381 0.381)
			(layers "F.Cu" "F.Mask" "F.Paste")
			(net "GND")
		)
		(pad "AN20" smd circle
			(at -7.72668 0.74295)
			(size 0.381 0.381)
			(layers "F.Cu" "F.Mask" "F.Paste")
			(net "GND")
		)
		(pad "AN24" smd circle
			(at -6.00964 0.74295)
			(size 0.381 0.381)
			(layers "F.Cu" "F.Mask" "F.Paste")
			(net "P3V3_STBY")
		)
		(pad "AN50" smd circle
			(at 6.00964 0.74295)
			(size 0.381 0.381)
			(layers "F.Cu" "F.Mask" "F.Paste")
			(net "P1V05_PCH_STBY_WM20_PLL")
		)
		(pad "AN54" smd circle
			(at 7.72668 0.74295)
			(size 0.381 0.381)
			(layers "F.Cu" "F.Mask" "F.Paste")
			(net "XDP_TDI")
		)
		(pad "AN58" smd circle
			(at 9.44372 0.74295)
			(size 0.381 0.381)
			(layers "F.Cu" "F.Mask" "F.Paste")
			(net "GND")
		)
		(pad "AN61" smd circle
			(at 11.16076 0.74295)
			(size 0.381 0.381)
			(layers "F.Cu" "F.Mask" "F.Paste")
			(net "SATA6G_PCH_PCIE_UP_SATA_RXP<6>")
		)
		(pad "AN65" smd circle
			(at 12.8778 0.74295)
			(size 0.381 0.381)
			(layers "F.Cu" "F.Mask" "F.Paste")
			(net "SATA6G_PCH_PCIE_UP_SATA_RXP<1>")
		)
		(pad "AN68" smd circle
			(at 14.649958 0.999998)
			(size 0.3048 0.3048)
			(layers "F.Cu" "F.Mask" "F.Paste")
			(net "GND")
		)
		(pad "AN70" smd circle
			(at 15.48003 0.999998)
			(size 0.3048 0.3048)
			(layers "F.Cu" "F.Mask" "F.Paste")
			(net "P2E_SSB_BMC_RX_C_DN")
		)
		(pad "AN72" smd oval
			(at 16.310102 0.999998 180)
			(size 0.254 0.3302)
			(layers "F.Cu" "F.Mask" "F.Paste")
			(net "P2E_SSB_BMC_RX_C_DP")
		)
		(pad "AP2" smd circle
			(at -15.895066 1.500124 180)
			(size 0.3048 0.3048)
			(layers "F.Cu" "F.Mask" "F.Paste")
			(net "GND")
		)
		(pad "AP4" smd circle
			(at -15.064994 1.500124 180)
			(size 0.3048 0.3048)
			(layers "F.Cu" "F.Mask" "F.Paste")
			(net "GND")
		)
		(pad "AP7" smd circle
			(at -13.73632 1.23825)
			(size 0.381 0.381)
			(layers "F.Cu" "F.Mask" "F.Paste")
			(net "IRQ_SML1_PMBUS_ALERT_R1_N")
		)
		(pad "AP11" smd circle
			(at -12.01928 1.23825)
			(size 0.381 0.381)
			(layers "F.Cu" "F.Mask" "F.Paste")
			(net "SGPIO_PCH_SATA_DOUT0")
		)
		(pad "AP15" smd circle
			(at -10.30224 1.23825)
			(size 0.381 0.381)
			(layers "F.Cu" "F.Mask" "F.Paste")
			(net "FM_BIOS_TOP_SWAP")
		)
		(pad "AP18" smd circle
			(at -8.5852 1.23825)
			(size 0.381 0.381)
			(layers "F.Cu" "F.Mask" "F.Paste")
			(net "SGPIO_PCH_SSATA_CLOCK")
		)
		(pad "AP22" smd circle
			(at -6.86816 1.23825)
			(size 0.381 0.381)
			(layers "F.Cu" "F.Mask" "F.Paste")
			(net "GND")
		)
		(pad "AP26" smd circle
			(at -5.20065 1.35255 180)
			(size 0.381 0.381)
			(layers "F.Cu" "F.Mask" "F.Paste")
			(net "GND")
		)
		(pad "AP27" smd circle
			(at -4.40055 1.35255 180)
			(size 0.381 0.381)
			(layers "F.Cu" "F.Mask" "F.Paste")
			(net "TP_PCH_RSVD58")
		)
		(pad "AP29" smd circle
			(at -3.60045 1.35255 180)
			(size 0.381 0.381)
			(layers "F.Cu" "F.Mask" "F.Paste")
			(net "P1V8_PCH_STBY")
		)
		(pad "AP30" smd circle
			(at -2.80035 1.35255 180)
			(size 0.381 0.381)
			(layers "F.Cu" "F.Mask" "F.Paste")
			(net "GND")
		)
		(pad "AP32" smd circle
			(at -2.00025 1.35255 180)
			(size 0.381 0.381)
			(layers "F.Cu" "F.Mask" "F.Paste")
			(net "PVNN_PCH_STBY")
		)
		(pad "AP34" smd circle
			(at -1.20015 1.35255 180)
			(size 0.381 0.381)
			(layers "F.Cu" "F.Mask" "F.Paste")
			(net "PVNN_PCH_STBY")
		)
		(pad "AP36" smd circle
			(at -0.40005 1.35255 180)
			(size 0.381 0.381)
			(layers "F.Cu" "F.Mask" "F.Paste")
			(net "PVNN_PCH_STBY")
		)
		(pad "AP37" smd circle
			(at 0.40005 1.35255 180)
			(size 0.381 0.381)
			(layers "F.Cu" "F.Mask" "F.Paste")
			(net "PVNN_PCH_STBY")
		)
		(pad "AP39" smd circle
			(at 1.20015 1.35255 180)
			(size 0.381 0.381)
			(layers "F.Cu" "F.Mask" "F.Paste")
			(net "PVNN_PCH_STBY")
		)
		(pad "AP41" smd circle
			(at 2.00025 1.35255 180)
			(size 0.381 0.381)
			(layers "F.Cu" "F.Mask" "F.Paste")
			(net "GND")
		)
		(pad "AP43" smd circle
			(at 2.80035 1.35255 180)
			(size 0.381 0.381)
			(layers "F.Cu" "F.Mask" "F.Paste")
			(net "P1V05_PCH_STBY")
		)
		(pad "AP45" smd circle
			(at 3.60045 1.35255 180)
			(size 0.381 0.381)
			(layers "F.Cu" "F.Mask" "F.Paste")
			(net "P1V05_PCH_STBY")
		)
		(pad "AP46" smd circle
			(at 4.40055 1.35255 180)
			(size 0.381 0.381)
			(layers "F.Cu" "F.Mask" "F.Paste")
			(net "GND")
		)
		(pad "AP48" smd circle
			(at 5.20065 1.35255 180)
			(size 0.381 0.381)
			(layers "F.Cu" "F.Mask" "F.Paste")
			(net "P1V05_PCH_STBY_WM26_PLL")
		)
		(pad "AP52" smd circle
			(at 6.86816 1.23825)
			(size 0.381 0.381)
			(layers "F.Cu" "F.Mask" "F.Paste")
			(net "GND")
		)
		(pad "AP56" smd circle
			(at 8.5852 1.23825)
			(size 0.381 0.381)
			(layers "F.Cu" "F.Mask" "F.Paste")
			(net "XDP_TDO")
		)
		(pad "AP59" smd circle
			(at 10.30224 1.23825)
			(size 0.381 0.381)
			(layers "F.Cu" "F.Mask" "F.Paste")
			(net "SATA6G_PCH_PCIE_UP_SATA_RXN<6>")
		)
		(pad "AP63" smd circle
			(at 12.01928 1.23825)
			(size 0.381 0.381)
			(layers "F.Cu" "F.Mask" "F.Paste")
			(net "SATA6G_PCH_PCIE_UP_SATA_RXN<3>")
		)
		(pad "AP66" smd circle
			(at 13.73632 1.23825)
			(size 0.381 0.381)
			(layers "F.Cu" "F.Mask" "F.Paste")
			(net "GND")
		)
		(pad "AP69" smd circle
			(at 15.064994 1.500124)
			(size 0.3048 0.3048)
			(layers "F.Cu" "F.Mask" "F.Paste")
			(net "TP_PCH_RSVD47")
		)
		(pad "AP71" smd circle
			(at 15.895066 1.500124)
			(size 0.3048 0.3048)
			(layers "F.Cu" "F.Mask" "F.Paste")
			(net "TP_PCH_RSVD48")
		)
		(pad "AR1" smd oval
			(at -16.310102 1.999996 180)
			(size 0.254 0.3302)
			(layers "F.Cu" "F.Mask" "F.Paste")
			(net "Net_463")
		)
		(pad "AR3" smd circle
			(at -15.48003 1.999996 180)
			(size 0.3048 0.3048)
			(layers "F.Cu" "F.Mask" "F.Paste")
			(net "Net_458")
		)
		(pad "AR5" smd circle
			(at -14.649958 1.999996 180)
			(size 0.3048 0.3048)
			(layers "F.Cu" "F.Mask" "F.Paste")
			(net "GND")
		)
		(pad "AR9" smd circle
			(at -12.8778 1.73355)
			(size 0.381 0.381)
			(layers "F.Cu" "F.Mask" "F.Paste")
			(net "SGPIO_PCH_SATA_LOAD")
		)
		(pad "AR13" smd circle
			(at -11.16076 1.73355)
			(size 0.381 0.381)
			(layers "F.Cu" "F.Mask" "F.Paste")
			(net "FM_FORCE_ADR_N")
		)
		(pad "AR17" smd circle
			(at -9.44372 1.73355)
			(size 0.381 0.381)
			(layers "F.Cu" "F.Mask" "F.Paste")
			(net "IRQ_PCH_NIC_ALERT_N")
		)
		(pad "AR20" smd circle
			(at -7.72668 1.73355)
			(size 0.381 0.381)
			(layers "F.Cu" "F.Mask" "F.Paste")
			(net "JTAG_PCH_PLD_TDO")
		)
		(pad "AR24" smd circle
			(at -6.00964 1.73355)
			(size 0.381 0.381)
			(layers "F.Cu" "F.Mask" "F.Paste")
			(net "P3V3_STBY")
		)
		(pad "AR50" smd circle
			(at 6.00964 1.73355)
			(size 0.381 0.381)
			(layers "F.Cu" "F.Mask" "F.Paste")
			(net "GND")
		)
		(pad "AR54" smd circle
			(at 7.72668 1.73355)
			(size 0.381 0.381)
			(layers "F.Cu" "F.Mask" "F.Paste")
			(net "XDP_ITP_PMODE")
		)
		(pad "AR58" smd circle
			(at 9.44372 1.73355)
			(size 0.381 0.381)
			(layers "F.Cu" "F.Mask" "F.Paste")
			(net "GND")
		)
		(pad "AR61" smd circle
			(at 11.16076 1.73355)
			(size 0.381 0.381)
			(layers "F.Cu" "F.Mask" "F.Paste")
			(net "SATA6G_PCH_PCIE_UP_SATA_RXN<0>")
		)
		(pad "AR65" smd circle
			(at 12.8778 1.73355)
			(size 0.381 0.381)
			(layers "F.Cu" "F.Mask" "F.Paste")
			(net "GND")
		)
		(pad "AR68" smd circle
			(at 14.649958 1.999996)
			(size 0.3048 0.3048)
			(layers "F.Cu" "F.Mask" "F.Paste")
			(net "GND")
		)
		(pad "AR70" smd circle
			(at 15.48003 1.999996)
			(size 0.3048 0.3048)
			(layers "F.Cu" "F.Mask" "F.Paste")
			(net "GND")
		)
		(pad "AR72" smd oval
			(at 16.310102 1.999996 180)
			(size 0.254 0.3302)
			(layers "F.Cu" "F.Mask" "F.Paste")
			(net "GND")
		)
		(pad "AT2" smd circle
			(at -15.895066 2.500122 180)
			(size 0.3048 0.3048)
			(layers "F.Cu" "F.Mask" "F.Paste")
			(net "Net_462")
		)
		(pad "AT4" smd circle
			(at -15.064994 2.500122 180)
			(size 0.3048 0.3048)
			(layers "F.Cu" "F.Mask" "F.Paste")
			(net "FM_UARTSW_LSB_N")
		)
		(pad "AT7" smd circle
			(at -13.73632 2.22885)
			(size 0.381 0.381)
			(layers "F.Cu" "F.Mask" "F.Paste")
			(net "GND")
		)
		(pad "AT11" smd circle
			(at -12.01928 2.22885)
			(size 0.381 0.381)
			(layers "F.Cu" "F.Mask" "F.Paste")
			(net "GND")
		)
		(pad "AT15" smd circle
			(at -10.30224 2.22885)
			(size 0.381 0.381)
			(layers "F.Cu" "F.Mask" "F.Paste")
			(net "GND")
		)
		(pad "AT18" smd circle
			(at -8.5852 2.22885)
			(size 0.381 0.381)
			(layers "F.Cu" "F.Mask" "F.Paste")
			(net "GND")
		)
		(pad "AT22" smd circle
			(at -6.86816 2.22885)
			(size 0.381 0.381)
			(layers "F.Cu" "F.Mask" "F.Paste")
			(net "GND")
		)
		(pad "AT26" smd circle
			(at -5.20065 2.15265 180)
			(size 0.381 0.381)
			(layers "F.Cu" "F.Mask" "F.Paste")
			(net "GND")
		)
		(pad "AT27" smd circle
			(at -4.40055 2.15265 180)
			(size 0.381 0.381)
			(layers "F.Cu" "F.Mask" "F.Paste")
			(net "TP_PCH_RSVD59")
		)
		(pad "AT29" smd circle
			(at -3.60045 2.15265 180)
			(size 0.381 0.381)
			(layers "F.Cu" "F.Mask" "F.Paste")
			(net "P1V8_PCH_STBY")
		)
		(pad "AT30" smd circle
			(at -2.80035 2.15265 180)
			(size 0.381 0.381)
			(layers "F.Cu" "F.Mask" "F.Paste")
			(net "GND")
		)
		(pad "AT32" smd circle
			(at -2.00025 2.15265 180)
			(size 0.381 0.381)
			(layers "F.Cu" "F.Mask" "F.Paste")
			(net "PVNN_PCH_STBY")
		)
		(pad "AT34" smd circle
			(at -1.20015 2.15265 180)
			(size 0.381 0.381)
			(layers "F.Cu" "F.Mask" "F.Paste")
			(net "PVNN_PCH_STBY")
		)
		(pad "AT36" smd circle
			(at -0.40005 2.15265 180)
			(size 0.381 0.381)
			(layers "F.Cu" "F.Mask" "F.Paste")
			(net "PVNN_PCH_STBY")
		)
		(pad "AT37" smd circle
			(at 0.40005 2.15265 180)
			(size 0.381 0.381)
			(layers "F.Cu" "F.Mask" "F.Paste")
			(net "GND")
		)
		(pad "AT39" smd circle
			(at 1.20015 2.15265 180)
			(size 0.381 0.381)
			(layers "F.Cu" "F.Mask" "F.Paste")
			(net "P1V05_PCH_STBY")
		)
		(pad "AT41" smd circle
			(at 2.00025 2.15265 180)
			(size 0.381 0.381)
			(layers "F.Cu" "F.Mask" "F.Paste")
			(net "GND")
		)
		(pad "AT43" smd circle
			(at 2.80035 2.15265 180)
			(size 0.381 0.381)
			(layers "F.Cu" "F.Mask" "F.Paste")
			(net "P1V05_PCH_STBY")
		)
		(pad "AT45" smd circle
			(at 3.60045 2.15265 180)
			(size 0.381 0.381)
			(layers "F.Cu" "F.Mask" "F.Paste")
			(net "P1V05_PCH_STBY")
		)
		(pad "AT46" smd circle
			(at 4.40055 2.15265 180)
			(size 0.381 0.381)
			(layers "F.Cu" "F.Mask" "F.Paste")
			(net "GND")
		)
		(pad "AT48" smd circle
			(at 5.20065 2.15265 180)
			(size 0.381 0.381)
			(layers "F.Cu" "F.Mask" "F.Paste")
			(net "P1V05_PCH_STBY")
		)
		(pad "AT52" smd circle
			(at 6.86816 2.22885)
			(size 0.381 0.381)
			(layers "F.Cu" "F.Mask" "F.Paste")
			(net "FM_CPU_MSMI_LVT3_N")
		)
		(pad "AT56" smd circle
			(at 8.5852 2.22885)
			(size 0.381 0.381)
			(layers "F.Cu" "F.Mask" "F.Paste")
			(net "XDP_TRST_N")
		)
		(pad "AT59" smd circle
			(at 10.30224 2.22885)
			(size 0.381 0.381)
			(layers "F.Cu" "F.Mask" "F.Paste")
			(net "GND")
		)
		(pad "AT63" smd circle
			(at 12.01928 2.22885)
			(size 0.381 0.381)
			(layers "F.Cu" "F.Mask" "F.Paste")
			(net "SATA6G_PCH_PCIE_UP_SATA_RXP<0>")
		)
		(pad "AT66" smd circle
			(at 13.73632 2.22885)
			(size 0.381 0.381)
			(layers "F.Cu" "F.Mask" "F.Paste")
			(net "Net_137")
		)
		(pad "AT69" smd circle
			(at 15.064994 2.500122)
			(size 0.3048 0.3048)
			(layers "F.Cu" "F.Mask" "F.Paste")
			(net "TP_PCH_RSVD6")
		)
		(pad "AT71" smd circle
			(at 15.895066 2.500122)
			(size 0.3048 0.3048)
			(layers "F.Cu" "F.Mask" "F.Paste")
			(net "TP_PCH_RSVD22")
		)
		(pad "AU9" smd circle
			(at -12.8778 2.72415)
			(size 0.381 0.381)
			(layers "F.Cu" "F.Mask" "F.Paste")
			(net "SMB_LAN_STBY_LVC3_SCL_R2")
		)
		(pad "AU13" smd circle
			(at -11.16076 2.72415)
			(size 0.381 0.381)
			(layers "F.Cu" "F.Mask" "F.Paste")
			(net "FM_IE_DISABLE_N")
		)
		(pad "AU17" smd circle
			(at -9.44372 2.72415)
			(size 0.381 0.381)
			(layers "F.Cu" "F.Mask" "F.Paste")
			(net "SGPIO_PCH_SSATA_LOAD")
		)
		(pad "AU20" smd circle
			(at -7.72668 2.72415)
			(size 0.381 0.381)
			(layers "F.Cu" "F.Mask" "F.Paste")
			(net "SMB_LAN_STBY_LVC3_SDA_R2")
		)
		(pad "AU24" smd circle
			(at -6.00964 2.72415)
			(size 0.381 0.381)
			(layers "F.Cu" "F.Mask" "F.Paste")
			(net "P3V3_STBY")
		)
		(pad "AU26" smd circle
			(at -5.20065 2.95275 180)
			(size 0.381 0.381)
			(layers "F.Cu" "F.Mask" "F.Paste")
			(net "GND")
		)
		(pad "AU27" smd circle
			(at -4.40055 2.95275 180)
			(size 0.381 0.381)
			(layers "F.Cu" "F.Mask" "F.Paste")
			(net "P3V3_STBY")
		)
		(pad "AU29" smd circle
			(at -3.60045 2.95275 180)
			(size 0.381 0.381)
			(layers "F.Cu" "F.Mask" "F.Paste")
			(net "P1V8_PCH_STBY")
		)
		(pad "AU30" smd circle
			(at -2.80035 2.95275 180)
			(size 0.381 0.381)
			(layers "F.Cu" "F.Mask" "F.Paste")
			(net "GND")
		)
		(pad "AU32" smd circle
			(at -2.00025 2.95275 180)
			(size 0.381 0.381)
			(layers "F.Cu" "F.Mask" "F.Paste")
			(net "PVNN_PCH_STBY")
		)
		(pad "AU34" smd circle
			(at -1.20015 2.95275 180)
			(size 0.381 0.381)
			(layers "F.Cu" "F.Mask" "F.Paste")
			(net "PVNN_PCH_STBY")
		)
		(pad "AU36" smd circle
			(at -0.40005 2.95275 180)
			(size 0.381 0.381)
			(layers "F.Cu" "F.Mask" "F.Paste")
			(net "PVNN_PCH_STBY")
		)
		(pad "AU37" smd circle
			(at 0.40005 2.95275 180)
			(size 0.381 0.381)
			(layers "F.Cu" "F.Mask" "F.Paste")
			(net "P1V05_PCH_STBY")
		)
		(pad "AU39" smd circle
			(at 1.20015 2.95275 180)
			(size 0.381 0.381)
			(layers "F.Cu" "F.Mask" "F.Paste")
			(net "P1V05_PCH_STBY")
		)
		(pad "AU41" smd circle
			(at 2.00025 2.95275 180)
			(size 0.381 0.381)
			(layers "F.Cu" "F.Mask" "F.Paste")
			(net "GND")
		)
		(pad "AU43" smd circle
			(at 2.80035 2.95275 180)
			(size 0.381 0.381)
			(layers "F.Cu" "F.Mask" "F.Paste")
			(net "P1V05_PCH_STBY")
		)
		(pad "AU45" smd circle
			(at 3.60045 2.95275 180)
			(size 0.381 0.381)
			(layers "F.Cu" "F.Mask" "F.Paste")
			(net "P1V05_PCH_STBY")
		)
		(pad "AU46" smd circle
			(at 4.40055 2.95275 180)
			(size 0.381 0.381)
			(layers "F.Cu" "F.Mask" "F.Paste")
			(net "GND")
		)
		(pad "AU48" smd circle
			(at 5.20065 2.95275 180)
			(size 0.381 0.381)
			(layers "F.Cu" "F.Mask" "F.Paste")
			(net "P1V05_PCH_STBY_WM26_PLL")
		)
		(pad "AU50" smd circle
			(at 6.00964 2.72415)
			(size 0.381 0.381)
			(layers "F.Cu" "F.Mask" "F.Paste")
			(net "GND")
		)
		(pad "AU54" smd circle
			(at 7.72668 2.72415)
			(size 0.381 0.381)
			(layers "F.Cu" "F.Mask" "F.Paste")
			(net "GND")
		)
		(pad "AU58" smd circle
			(at 9.44372 2.72415)
			(size 0.381 0.381)
			(layers "F.Cu" "F.Mask" "F.Paste")
			(net "IRQ_UV_DETECT_N")
		)
		(pad "AU61" smd circle
			(at 11.16076 2.72415)
			(size 0.381 0.381)
			(layers "F.Cu" "F.Mask" "F.Paste")
			(net "GND")
		)
		(pad "AU65" smd circle
			(at 12.8778 2.72415)
			(size 0.381 0.381)
			(layers "F.Cu" "F.Mask" "F.Paste")
			(net "Net_140")
		)
		(pad "AV1" smd oval
			(at -16.310102 2.999994 180)
			(size 0.254 0.3302)
			(layers "F.Cu" "F.Mask" "F.Paste")
			(net "Net_459")
		)
		(pad "AV3" smd circle
			(at -15.48003 2.999994 180)
			(size 0.3048 0.3048)
			(layers "F.Cu" "F.Mask" "F.Paste")
			(net "Net_464")
		)
		(pad "AV5" smd circle
			(at -14.649958 2.999994 180)
			(size 0.3048 0.3048)
			(layers "F.Cu" "F.Mask" "F.Paste")
			(net "GND")
		)
		(pad "AV7" smd circle
			(at -13.73632 3.21945)
			(size 0.381 0.381)
			(layers "F.Cu" "F.Mask" "F.Paste")
			(net "FM_BOARD_SKU_ID2")
		)
		(pad "AV11" smd circle
			(at -12.01928 3.21945)
			(size 0.381 0.381)
			(layers "F.Cu" "F.Mask" "F.Paste")
			(net "Net_465")
		)
		(pad "AV15" smd circle
			(at -10.30224 3.21945)
			(size 0.381 0.381)
			(layers "F.Cu" "F.Mask" "F.Paste")
			(net "Net_472")
		)
		(pad "AV18" smd circle
			(at -8.5852 3.21945)
			(size 0.381 0.381)
			(layers "F.Cu" "F.Mask" "F.Paste")
			(net "FM_CPU1_THERMTRIP_LATCH_LVT3_N")
		)
		(pad "AV22" smd circle
			(at -6.86816 3.21945)
			(size 0.381 0.381)
			(layers "F.Cu" "F.Mask" "F.Paste")
			(net "GND")
		)
		(pad "AV52" smd circle
			(at 6.86816 3.21945)
			(size 0.381 0.381)
			(layers "F.Cu" "F.Mask" "F.Paste")
			(net "FM_CPU_ERR2_LVT3_N")
		)
		(pad "AV56" smd circle
			(at 8.5852 3.21945)
			(size 0.381 0.381)
			(layers "F.Cu" "F.Mask" "F.Paste")
			(net "LED_PCH_SATA_HDD_N")
		)
		(pad "AV59" smd circle
			(at 10.30224 3.21945)
			(size 0.381 0.381)
			(layers "F.Cu" "F.Mask" "F.Paste")
			(net "GND")
		)
		(pad "AV63" smd circle
			(at 12.01928 3.21945)
			(size 0.381 0.381)
			(layers "F.Cu" "F.Mask" "F.Paste")
			(net "Net_136")
		)
		(pad "AV66" smd circle
			(at 13.73632 3.21945)
			(size 0.381 0.381)
			(layers "F.Cu" "F.Mask" "F.Paste")
			(net "Net_141")
		)
		(pad "AV68" smd circle
			(at 14.649958 2.999994)
			(size 0.3048 0.3048)
			(layers "F.Cu" "F.Mask" "F.Paste")
			(net "GND")
		)
		(pad "AV70" smd circle
			(at 15.48003 2.999994)
			(size 0.3048 0.3048)
			(layers "F.Cu" "F.Mask" "F.Paste")
			(net "P3E_PCH_M2_RX_DP<3>")
		)
		(pad "AV72" smd oval
			(at 16.310102 2.999994 180)
			(size 0.254 0.3302)
			(layers "F.Cu" "F.Mask" "F.Paste")
			(net "P3E_PCH_M2_RX_DN<3>")
		)
		(pad "AW2" smd circle
			(at -15.895066 3.50012 180)
			(size 0.3048 0.3048)
			(layers "F.Cu" "F.Mask" "F.Paste")
			(net "Net_460")
		)
		(pad "AW4" smd circle
			(at -15.064994 3.50012 180)
			(size 0.3048 0.3048)
			(layers "F.Cu" "F.Mask" "F.Paste")
			(net "FM_BACKUP_BIOS_SEL_N")
		)
		(pad "AW9" smd circle
			(at -12.8778 3.71475)
			(size 0.381 0.381)
			(layers "F.Cu" "F.Mask" "F.Paste")
			(net "GND")
		)
		(pad "AW13" smd circle
			(at -11.16076 3.71475)
			(size 0.381 0.381)
			(layers "F.Cu" "F.Mask" "F.Paste")
			(net "GND")
		)
		(pad "AW17" smd circle
			(at -9.44372 3.71475)
			(size 0.381 0.381)
			(layers "F.Cu" "F.Mask" "F.Paste")
			(net "GND")
		)
		(pad "AW20" smd circle
			(at -7.72668 3.71475)
			(size 0.381 0.381)
			(layers "F.Cu" "F.Mask" "F.Paste")
			(net "Net_468")
		)
		(pad "AW24" smd circle
			(at -6.00964 3.71475)
			(size 0.381 0.381)
			(layers "F.Cu" "F.Mask" "F.Paste")
			(net "P3V3_STBY")
		)
		(pad "AW26" smd circle
			(at -5.20065 3.75285 180)
			(size 0.381 0.381)
			(layers "F.Cu" "F.Mask" "F.Paste")
			(net "GND")
		)
		(pad "AW27" smd circle
			(at -4.40055 3.75285 180)
			(size 0.381 0.381)
			(layers "F.Cu" "F.Mask" "F.Paste")
			(net "P1V8_PCH_STBY")
		)
		(pad "AW29" smd circle
			(at -3.60045 3.75285 180)
			(size 0.381 0.381)
			(layers "F.Cu" "F.Mask" "F.Paste")
			(net "P1V8_PCH_STBY")
		)
		(pad "AW30" smd circle
			(at -2.80035 3.75285 180)
			(size 0.381 0.381)
			(layers "F.Cu" "F.Mask" "F.Paste")
			(net "GND")
		)
		(pad "AW32" smd circle
			(at -2.00025 3.75285 180)
			(size 0.381 0.381)
			(layers "F.Cu" "F.Mask" "F.Paste")
			(net "GND")
		)
		(pad "AW34" smd circle
			(at -1.20015 3.75285 180)
			(size 0.381 0.381)
			(layers "F.Cu" "F.Mask" "F.Paste")
			(net "GND")
		)
		(pad "AW36" smd circle
			(at -0.40005 3.75285 180)
			(size 0.381 0.381)
			(layers "F.Cu" "F.Mask" "F.Paste")
			(net "GND")
		)
		(pad "AW37" smd circle
			(at 0.40005 3.75285 180)
			(size 0.381 0.381)
			(layers "F.Cu" "F.Mask" "F.Paste")
			(net "GND")
		)
		(pad "AW39" smd circle
			(at 1.20015 3.75285 180)
			(size 0.381 0.381)
			(layers "F.Cu" "F.Mask" "F.Paste")
			(net "GND")
		)
		(pad "AW41" smd circle
			(at 2.00025 3.75285 180)
			(size 0.381 0.381)
			(layers "F.Cu" "F.Mask" "F.Paste")
			(net "GND")
		)
		(pad "AW43" smd circle
			(at 2.80035 3.75285 180)
			(size 0.381 0.381)
			(layers "F.Cu" "F.Mask" "F.Paste")
			(net "P1V05_PCH_STBY")
		)
		(pad "AW45" smd circle
			(at 3.60045 3.75285 180)
			(size 0.381 0.381)
			(layers "F.Cu" "F.Mask" "F.Paste")
			(net "P1V05_PCH_STBY")
		)
		(pad "AW46" smd circle
			(at 4.40055 3.75285 180)
			(size 0.381 0.381)
			(layers "F.Cu" "F.Mask" "F.Paste")
			(net "GND")
		)
		(pad "AW48" smd circle
			(at 5.20065 3.75285 180)
			(size 0.381 0.381)
			(layers "F.Cu" "F.Mask" "F.Paste")
			(net "P1V05_PCH_STBY_WM26_PLL")
		)
		(pad "AW50" smd circle
			(at 6.00964 3.71475)
			(size 0.381 0.381)
			(layers "F.Cu" "F.Mask" "F.Paste")
			(net "GND")
		)
		(pad "AW54" smd circle
			(at 7.72668 3.71475)
			(size 0.381 0.381)
			(layers "F.Cu" "F.Mask" "F.Paste")
			(net "IRQ_BMC_PCH_SMI_LPC_N")
		)
		(pad "AW58" smd circle
			(at 9.44372 3.71475)
			(size 0.381 0.381)
			(layers "F.Cu" "F.Mask" "F.Paste")
			(net "GND")
		)
		(pad "AW61" smd circle
			(at 11.16076 3.71475)
			(size 0.381 0.381)
			(layers "F.Cu" "F.Mask" "F.Paste")
			(net "GND")
		)
		(pad "AW65" smd circle
			(at 12.8778 3.71475)
			(size 0.381 0.381)
			(layers "F.Cu" "F.Mask" "F.Paste")
			(net "Net_135")
		)
		(pad "AW69" smd circle
			(at 15.064994 3.50012)
			(size 0.3048 0.3048)
			(layers "F.Cu" "F.Mask" "F.Paste")
			(net "P3E_PCH_M2_RX_DP<2>")
		)
		(pad "AW71" smd circle
			(at 15.895066 3.50012)
			(size 0.3048 0.3048)
			(layers "F.Cu" "F.Mask" "F.Paste")
			(net "P3E_PCH_M2_RX_DN<2>")
		)
		(pad "AY1" smd oval
			(at -16.310102 3.999992 180)
			(size 0.254 0.3302)
			(layers "F.Cu" "F.Mask" "F.Paste")
			(net "Net_478")
		)
		(pad "AY3" smd circle
			(at -15.48003 3.999992 180)
			(size 0.3048 0.3048)
			(layers "F.Cu" "F.Mask" "F.Paste")
			(net "Net_461")
		)
		(pad "AY5" smd circle
			(at -14.649958 3.999992 180)
			(size 0.3048 0.3048)
			(layers "F.Cu" "F.Mask" "F.Paste")
			(net "GND")
		)
		(pad "AY7" smd circle
			(at -13.73632 4.21005)
			(size 0.381 0.381)
			(layers "F.Cu" "F.Mask" "F.Paste")
			(net "Net_470")
		)
		(pad "AY11" smd circle
			(at -12.01928 4.21005)
			(size 0.381 0.381)
			(layers "F.Cu" "F.Mask" "F.Paste")
			(net "Net_475")
		)
		(pad "AY15" smd circle
			(at -10.30224 4.21005)
			(size 0.381 0.381)
			(layers "F.Cu" "F.Mask" "F.Paste")
			(net "Net_467")
		)
		(pad "AY18" smd circle
			(at -8.5852 4.21005)
			(size 0.381 0.381)
			(layers "F.Cu" "F.Mask" "F.Paste")
			(net "FM_BOARD_SKU_ID1")
		)
		(pad "AY22" smd circle
			(at -6.86816 4.21005)
			(size 0.381 0.381)
			(layers "F.Cu" "F.Mask" "F.Paste")
			(net "GND")
		)
		(pad "AY52" smd circle
			(at 6.86816 4.21005)
			(size 0.381 0.381)
			(layers "F.Cu" "F.Mask" "F.Paste")
			(net "FM_CPU1_RC_ERROR_R1_N")
		)
		(pad "AY56" smd circle
			(at 8.5852 4.21005)
			(size 0.381 0.381)
			(layers "F.Cu" "F.Mask" "F.Paste")
			(net "GND")
		)
		(pad "AY59" smd circle
			(at 10.30224 4.21005)
			(size 0.381 0.381)
			(layers "F.Cu" "F.Mask" "F.Paste")
			(net "SATA6G_S1_RX_DN")
		)
		(pad "AY63" smd circle
			(at 12.01928 4.21005)
			(size 0.381 0.381)
			(layers "F.Cu" "F.Mask" "F.Paste")
			(net "GND")
		)
		(pad "AY66" smd circle
			(at 13.73632 4.21005)
			(size 0.381 0.381)
			(layers "F.Cu" "F.Mask" "F.Paste")
			(net "Net_139")
		)
		(pad "AY68" smd circle
			(at 14.649958 3.999992)
			(size 0.3048 0.3048)
			(layers "F.Cu" "F.Mask" "F.Paste")
			(net "GND")
		)
		(pad "AY70" smd circle
			(at 15.48003 3.999992)
			(size 0.3048 0.3048)
			(layers "F.Cu" "F.Mask" "F.Paste")
			(net "P3E_PCH_M2_RX_DP<1>")
		)
		(pad "AY72" smd oval
			(at 16.310102 3.999992 180)
			(size 0.254 0.3302)
			(layers "F.Cu" "F.Mask" "F.Paste")
			(net "P3E_PCH_M2_RX_DN<1>")
		)
		(pad "B10" smd circle
			(at -12.500102 -12.895072 90)
			(size 0.3048 0.3048)
			(layers "F.Cu" "F.Mask" "F.Paste")
			(net "TP_PCH_RSVD17")
		)
		(pad "B12" smd circle
			(at -11.500104 -12.895072 90)
			(size 0.3048 0.3048)
			(layers "F.Cu" "F.Mask" "F.Paste")
			(net "GND")
		)
		(pad "B14" smd circle
			(at -10.500106 -12.895072 90)
			(size 0.3048 0.3048)
			(layers "F.Cu" "F.Mask" "F.Paste")
			(net "FM_CPU0_RC_ERROR_R_N")
		)
		(pad "B16" smd circle
			(at -9.500108 -12.895072 90)
			(size 0.3048 0.3048)
			(layers "F.Cu" "F.Mask" "F.Paste")
			(net "FM_SLPS4_N")
		)
		(pad "B19" smd circle
			(at -8.50011 -12.895072 90)
			(size 0.3048 0.3048)
			(layers "F.Cu" "F.Mask" "F.Paste")
			(net "GND")
		)
		(pad "B21" smd circle
			(at -7.500112 -12.895072 90)
			(size 0.3048 0.3048)
			(layers "F.Cu" "F.Mask" "F.Paste")
			(net "CLK_100M_MEZZ4_DN")
		)
		(pad "B23" smd circle
			(at -6.500114 -12.895072 90)
			(size 0.3048 0.3048)
			(layers "F.Cu" "F.Mask" "F.Paste")
			(net "CLK_100M_MEZZ3_DN")
		)
		(pad "B25" smd circle
			(at -5.500116 -12.895072 90)
			(size 0.3048 0.3048)
			(layers "F.Cu" "F.Mask" "F.Paste")
			(net "GND")
		)
		(pad "B27" smd circle
			(at -4.500118 -12.895072 90)
			(size 0.3048 0.3048)
			(layers "F.Cu" "F.Mask" "F.Paste")
			(net "GND")
		)
		(pad "B29" smd circle
			(at -3.50012 -12.895072 90)
			(size 0.3048 0.3048)
			(layers "F.Cu" "F.Mask" "F.Paste")
			(net "CLK_100M_BMC_PE_DN")
		)
		(pad "B31" smd circle
			(at -2.500122 -12.895072 90)
			(size 0.3048 0.3048)
			(layers "F.Cu" "F.Mask" "F.Paste")
			(net "CLK_100M_MEZZ1_DP")
		)
		(pad "B33" smd circle
			(at -1.500124 -12.895072 90)
			(size 0.3048 0.3048)
			(layers "F.Cu" "F.Mask" "F.Paste")
			(net "CLK_100M_PCH_SLOTX24_S4_DP")
		)
		(pad "B35" smd circle
			(at -0.500126 -12.895072 90)
			(size 0.3048 0.3048)
			(layers "F.Cu" "F.Mask" "F.Paste")
			(net "XTAL_PCH_48M_IN")
		)
		(pad "B38" smd circle
			(at 0.500126 -12.895072 90)
			(size 0.3048 0.3048)
			(layers "F.Cu" "F.Mask" "F.Paste")
			(net "TP_CLK_100M_NSSCC1_DN")
		)
		(pad "B40" smd circle
			(at 1.500124 -12.895072 90)
			(size 0.3048 0.3048)
			(layers "F.Cu" "F.Mask" "F.Paste")
			(net "TP_CLK_100M_PLAT1_DN")
		)
		(pad "B42" smd circle
			(at 2.500122 -12.895072 90)
			(size 0.3048 0.3048)
			(layers "F.Cu" "F.Mask" "F.Paste")
			(net "DMI_CPU0_PCH_TX_C_DP<0>")
		)
		(pad "B44" smd circle
			(at 3.50012 -12.895072 90)
			(size 0.3048 0.3048)
			(layers "F.Cu" "F.Mask" "F.Paste")
			(net "DMI_CPU0_PCH_TX_C_DP<2>")
		)
		(pad "B47" smd circle
			(at 4.500118 -12.895072 90)
			(size 0.3048 0.3048)
			(layers "F.Cu" "F.Mask" "F.Paste")
			(net "GND")
		)
		(pad "B49" smd circle
			(at 5.500116 -12.895072 90)
			(size 0.3048 0.3048)
			(layers "F.Cu" "F.Mask" "F.Paste")
			(net "P3E_CPU0_PE1_PCH_TXP<1>")
		)
		(pad "B51" smd circle
			(at 6.500114 -12.895072 90)
			(size 0.3048 0.3048)
			(layers "F.Cu" "F.Mask" "F.Paste")
			(net "P3E_CPU0_PE1_PCH_TXP<3>")
		)
		(pad "B53" smd circle
			(at 7.500112 -12.895072 90)
			(size 0.3048 0.3048)
			(layers "F.Cu" "F.Mask" "F.Paste")
			(net "P3E_CPU0_PE1_PCH_TXP<5>")
		)
		(pad "B55" smd circle
			(at 8.50011 -12.895072 90)
			(size 0.3048 0.3048)
			(layers "F.Cu" "F.Mask" "F.Paste")
			(net "P3E_CPU0_PE1_PCH_TXP<7>")
		)
		(pad "B58" smd circle
			(at 9.500108 -12.895072 90)
			(size 0.3048 0.3048)
			(layers "F.Cu" "F.Mask" "F.Paste")
			(net "P3E_CPU0_PE1_PCH_C_TXN<9>")
		)
		(pad "B60" smd circle
			(at 10.500106 -12.895072 90)
			(size 0.3048 0.3048)
			(layers "F.Cu" "F.Mask" "F.Paste")
			(net "P3E_CPU0_PE1_PCH_C_TXP<11>")
		)
		(pad "B62" smd circle
			(at 11.500104 -12.895072 90)
			(size 0.3048 0.3048)
			(layers "F.Cu" "F.Mask" "F.Paste")
			(net "P3E_CPU0_PE1_PCH_C_TXN<13>")
		)
		(pad "B64" smd circle
			(at 12.500102 -12.895072 90)
			(size 0.3048 0.3048)
			(layers "F.Cu" "F.Mask" "F.Paste")
			(net "P3E_CPU0_PE1_PCH_C_TXN<15>")
		)
		(pad "BA2" smd circle
			(at -15.895066 4.500118 180)
			(size 0.3048 0.3048)
			(layers "F.Cu" "F.Mask" "F.Paste")
			(net "FM_BIOS_SMI_ACTIVE_N")
		)
		(pad "BA4" smd circle
			(at -15.064994 4.500118 180)
			(size 0.3048 0.3048)
			(layers "F.Cu" "F.Mask" "F.Paste")
			(net "SMB_VR_STBY_LVC3_SCL_R1")
		)
		(pad "BA9" smd circle
			(at -12.8778 4.70535)
			(size 0.381 0.381)
			(layers "F.Cu" "F.Mask" "F.Paste")
			(net "Net_469")
		)
		(pad "BA13" smd circle
			(at -11.16076 4.70535)
			(size 0.381 0.381)
			(layers "F.Cu" "F.Mask" "F.Paste")
			(net "FM_UARTSW_MSB_N")
		)
		(pad "BA17" smd circle
			(at -9.44372 4.70535)
			(size 0.381 0.381)
			(layers "F.Cu" "F.Mask" "F.Paste")
			(net "IRQ_FORCE_NM_THROTTLE_N")
		)
		(pad "BA20" smd circle
			(at -7.72668 4.70535)
			(size 0.381 0.381)
			(layers "F.Cu" "F.Mask" "F.Paste")
			(net "Net_473")
		)
		(pad "BA24" smd circle
			(at -6.00964 4.70535)
			(size 0.381 0.381)
			(layers "F.Cu" "F.Mask" "F.Paste")
			(net "P3V3_STBY")
		)
		(pad "BA26" smd circle
			(at -5.20065 4.55295 180)
			(size 0.381 0.381)
			(layers "F.Cu" "F.Mask" "F.Paste")
			(net "P3V3_STBY")
		)
		(pad "BA27" smd circle
			(at -4.40055 4.55295 180)
			(size 0.381 0.381)
			(layers "F.Cu" "F.Mask" "F.Paste")
			(net "P1V8_PCH_STBY")
		)
		(pad "BA29" smd circle
			(at -3.60045 4.55295 180)
			(size 0.381 0.381)
			(layers "F.Cu" "F.Mask" "F.Paste")
			(net "P1V8_PCH_STBY")
		)
		(pad "BA30" smd circle
			(at -2.80035 4.55295 180)
			(size 0.381 0.381)
			(layers "F.Cu" "F.Mask" "F.Paste")
			(net "P1V05_PCH_STBY")
		)
		(pad "BA32" smd circle
			(at -2.00025 4.55295 180)
			(size 0.381 0.381)
			(layers "F.Cu" "F.Mask" "F.Paste")
			(net "P1V05_PCH_STBY")
		)
		(pad "BA34" smd circle
			(at -1.20015 4.55295 180)
			(size 0.381 0.381)
			(layers "F.Cu" "F.Mask" "F.Paste")
			(net "P1V05_PCH_STBY")
		)
		(pad "BA36" smd circle
			(at -0.40005 4.55295 180)
			(size 0.381 0.381)
			(layers "F.Cu" "F.Mask" "F.Paste")
			(net "P1V05_PCH_STBY")
		)
		(pad "BA37" smd circle
			(at 0.40005 4.55295 180)
			(size 0.381 0.381)
			(layers "F.Cu" "F.Mask" "F.Paste")
			(net "P1V05_PCH_STBY")
		)
		(pad "BA39" smd circle
			(at 1.20015 4.55295 180)
			(size 0.381 0.381)
			(layers "F.Cu" "F.Mask" "F.Paste")
			(net "P1V05_PCH_STBY_KR_PLL")
		)
		(pad "BA41" smd circle
			(at 2.00025 4.55295 180)
			(size 0.381 0.381)
			(layers "F.Cu" "F.Mask" "F.Paste")
			(net "P1V05_PCH_STBY_KR_PLL")
		)
		(pad "BA43" smd circle
			(at 2.80035 4.55295 180)
			(size 0.381 0.381)
			(layers "F.Cu" "F.Mask" "F.Paste")
			(net "P3V3_STBY")
		)
		(pad "BA45" smd circle
			(at 3.60045 4.55295 180)
			(size 0.381 0.381)
			(layers "F.Cu" "F.Mask" "F.Paste")
			(net "P3V3_STBY")
		)
		(pad "BA46" smd circle
			(at 4.40055 4.55295 180)
			(size 0.381 0.381)
			(layers "F.Cu" "F.Mask" "F.Paste")
			(net "P3V3_STBY")
		)
		(pad "BA48" smd circle
			(at 5.20065 4.55295 180)
			(size 0.381 0.381)
			(layers "F.Cu" "F.Mask" "F.Paste")
			(net "P3V3_STBY")
		)
		(pad "BA50" smd circle
			(at 6.00964 4.70535)
			(size 0.381 0.381)
			(layers "F.Cu" "F.Mask" "F.Paste")
			(net "GND")
		)
		(pad "BA54" smd circle
			(at 7.72668 4.70535)
			(size 0.381 0.381)
			(layers "F.Cu" "F.Mask" "F.Paste")
			(net "GND")
		)
		(pad "BA58" smd circle
			(at 9.44372 4.70535)
			(size 0.381 0.381)
			(layers "F.Cu" "F.Mask" "F.Paste")
			(net "GND")
		)
		(pad "BA61" smd circle
			(at 11.16076 4.70535)
			(size 0.381 0.381)
			(layers "F.Cu" "F.Mask" "F.Paste")
			(net "SATA6G_S1_RX_DP")
		)
		(pad "BA65" smd circle
			(at 12.8778 4.70535)
			(size 0.381 0.381)
			(layers "F.Cu" "F.Mask" "F.Paste")
			(net "Net_134")
		)
		(pad "BA69" smd circle
			(at 15.064994 4.500118)
			(size 0.3048 0.3048)
			(layers "F.Cu" "F.Mask" "F.Paste")
			(net "P3E_PCH_RX_0_DP")
		)
		(pad "BA71" smd circle
			(at 15.895066 4.500118)
			(size 0.3048 0.3048)
			(layers "F.Cu" "F.Mask" "F.Paste")
			(net "P3E_PCH_RX_0_DN")
		)
		(pad "BB1" smd oval
			(at -16.310102 4.99999 180)
			(size 0.254 0.3302)
			(layers "F.Cu" "F.Mask" "F.Paste")
			(net "FM_FLASH_ATTACH_CFG_STRAP")
		)
		(pad "BB3" smd circle
			(at -15.48003 4.99999 180)
			(size 0.3048 0.3048)
			(layers "F.Cu" "F.Mask" "F.Paste")
			(net "PU_ADR_TIMER_HOLD_OFF_N")
		)
		(pad "BB5" smd circle
			(at -14.649958 4.99999 180)
			(size 0.3048 0.3048)
			(layers "F.Cu" "F.Mask" "F.Paste")
			(net "GND")
		)
		(pad "BB7" smd circle
			(at -13.73632 5.20065)
			(size 0.381 0.381)
			(layers "F.Cu" "F.Mask" "F.Paste")
			(net "GND")
		)
		(pad "BB11" smd circle
			(at -12.01928 5.20065)
			(size 0.381 0.381)
			(layers "F.Cu" "F.Mask" "F.Paste")
			(net "GND")
		)
		(pad "BB15" smd circle
			(at -10.30224 5.20065)
			(size 0.381 0.381)
			(layers "F.Cu" "F.Mask" "F.Paste")
			(net "GND")
		)
		(pad "BB18" smd circle
			(at -8.5852 5.20065)
			(size 0.381 0.381)
			(layers "F.Cu" "F.Mask" "F.Paste")
			(net "GND")
		)
		(pad "BB22" smd circle
			(at -6.86816 5.20065)
			(size 0.381 0.381)
			(layers "F.Cu" "F.Mask" "F.Paste")
			(net "GND")
		)
		(pad "BB26" smd circle
			(at -5.15112 5.201158)
			(size 0.381 0.381)
			(layers "F.Cu" "F.Mask" "F.Paste")
			(net "P3V3_STBY")
		)
		(pad "BB29" smd circle
			(at -3.43408 5.20065)
			(size 0.381 0.381)
			(layers "F.Cu" "F.Mask" "F.Paste")
			(net "A_KR0_RBIAS")
		)
		(pad "BB33" smd circle
			(at -1.71704 5.20065)
			(size 0.381 0.381)
			(layers "F.Cu" "F.Mask" "F.Paste")
			(net "P1V05_PCH_STBY")
		)
		(pad "BB37" smd circle
			(at 0 5.20065)
			(size 0.381 0.381)
			(layers "F.Cu" "F.Mask" "F.Paste")
			(net "P1V05_PCH_STBY")
		)
		(pad "BB40" smd circle
			(at 1.71704 5.20065)
			(size 0.381 0.381)
			(layers "F.Cu" "F.Mask" "F.Paste")
			(net "P1V05_PCH_STBY_KR_PLL")
		)
		(pad "BB44" smd circle
			(at 3.43408 5.20065)
			(size 0.381 0.381)
			(layers "F.Cu" "F.Mask" "F.Paste")
			(net "GND")
		)
		(pad "BB48" smd circle
			(at 5.15112 5.201158)
			(size 0.381 0.381)
			(layers "F.Cu" "F.Mask" "F.Paste")
			(net "GND")
		)
		(pad "BB52" smd circle
			(at 6.86816 5.20065)
			(size 0.381 0.381)
			(layers "F.Cu" "F.Mask" "F.Paste")
			(net "IRQ_BMC_PCH_NMI_STBY_N")
		)
		(pad "BB56" smd circle
			(at 8.5852 5.20065)
			(size 0.381 0.381)
			(layers "F.Cu" "F.Mask" "F.Paste")
			(net "A_PCIE_RCOMP_P")
		)
		(pad "BB59" smd circle
			(at 10.30224 5.20065)
			(size 0.381 0.381)
			(layers "F.Cu" "F.Mask" "F.Paste")
			(net "GND")
		)
		(pad "BB63" smd circle
			(at 12.01928 5.20065)
			(size 0.381 0.381)
			(layers "F.Cu" "F.Mask" "F.Paste")
			(net "SATA6G_S0_RX_DN")
		)
		(pad "BB66" smd circle
			(at 13.73632 5.20065)
			(size 0.381 0.381)
			(layers "F.Cu" "F.Mask" "F.Paste")
			(net "GND")
		)
		(pad "BB68" smd circle
			(at 14.649958 4.99999)
			(size 0.3048 0.3048)
			(layers "F.Cu" "F.Mask" "F.Paste")
			(net "GND")
		)
		(pad "BB70" smd circle
			(at 15.48003 4.99999)
			(size 0.3048 0.3048)
			(layers "F.Cu" "F.Mask" "F.Paste")
			(net "GND")
		)
		(pad "BB72" smd oval
			(at 16.310102 4.99999 180)
			(size 0.254 0.3302)
			(layers "F.Cu" "F.Mask" "F.Paste")
			(net "GND")
		)
		(pad "BC2" smd circle
			(at -15.895066 5.500116 180)
			(size 0.3048 0.3048)
			(layers "F.Cu" "F.Mask" "F.Paste")
			(net "Net_479")
		)
		(pad "BC4" smd circle
			(at -15.064994 5.500116 180)
			(size 0.3048 0.3048)
			(layers "F.Cu" "F.Mask" "F.Paste")
			(net "FM_OC_DETECT_EN_N")
		)
		(pad "BC69" smd circle
			(at 15.064994 5.500116)
			(size 0.3048 0.3048)
			(layers "F.Cu" "F.Mask" "F.Paste")
			(net "GND")
		)
		(pad "BC71" smd circle
			(at 15.895066 5.500116)
			(size 0.3048 0.3048)
			(layers "F.Cu" "F.Mask" "F.Paste")
			(net "GND")
		)
		(pad "BD1" smd oval
			(at -16.310102 5.999988 180)
			(size 0.254 0.3302)
			(layers "F.Cu" "F.Mask" "F.Paste")
			(net "SMB_VR_STBY_LVC3_SDA_R1")
		)
		(pad "BD3" smd circle
			(at -15.48003 5.999988 180)
			(size 0.3048 0.3048)
			(layers "F.Cu" "F.Mask" "F.Paste")
			(net "FP_PWR_ID_LED_N")
		)
		(pad "BD5" smd circle
			(at -14.649958 5.999988 180)
			(size 0.3048 0.3048)
			(layers "F.Cu" "F.Mask" "F.Paste")
			(net "GND")
		)
		(pad "BD9" smd circle
			(at -12.8778 5.69595)
			(size 0.381 0.381)
			(layers "F.Cu" "F.Mask" "F.Paste")
			(net "FM_ADR_COMPLETE_R1")
		)
		(pad "BD13" smd circle
			(at -11.16076 5.69595)
			(size 0.381 0.381)
			(layers "F.Cu" "F.Mask" "F.Paste")
			(net "FM_BOARD_SKU_ID0")
		)
		(pad "BD17" smd circle
			(at -9.44372 5.69595)
			(size 0.381 0.381)
			(layers "F.Cu" "F.Mask" "F.Paste")
			(net "FM_BOARD_SKU_ID4")
		)
		(pad "BD20" smd circle
			(at -7.72668 5.69595)
			(size 0.381 0.381)
			(layers "F.Cu" "F.Mask" "F.Paste")
			(net "FM_CPU0_RC_EN")
		)
		(pad "BD24" smd circle
			(at -6.00964 5.69595)
			(size 0.381 0.381)
			(layers "F.Cu" "F.Mask" "F.Paste")
			(net "GND")
		)
		(pad "BD27" smd circle
			(at -4.2926 5.69595)
			(size 0.381 0.381)
			(layers "F.Cu" "F.Mask" "F.Paste")
			(net "GND")
		)
		(pad "BD31" smd circle
			(at -2.57556 5.69595)
			(size 0.381 0.381)
			(layers "F.Cu" "F.Mask" "F.Paste")
			(net "GND")
		)
		(pad "BD35" smd circle
			(at -0.85852 5.69595)
			(size 0.381 0.381)
			(layers "F.Cu" "F.Mask" "F.Paste")
			(net "GND")
		)
		(pad "BD38" smd circle
			(at 0.85852 5.69595)
			(size 0.381 0.381)
			(layers "F.Cu" "F.Mask" "F.Paste")
			(net "P1V05_PCH_STBY_KR_PLL")
		)
		(pad "BD42" smd circle
			(at 2.57556 5.69595)
			(size 0.381 0.381)
			(layers "F.Cu" "F.Mask" "F.Paste")
			(net "A_KR1_RBIAS")
		)
		(pad "BD46" smd circle
			(at 4.2926 5.69595)
			(size 0.381 0.381)
			(layers "F.Cu" "F.Mask" "F.Paste")
			(net "P1V8_PCH_STBY")
		)
		(pad "BD50" smd circle
			(at 6.00964 5.69595)
			(size 0.381 0.381)
			(layers "F.Cu" "F.Mask" "F.Paste")
			(net "GND")
		)
		(pad "BD54" smd circle
			(at 7.72668 5.69595)
			(size 0.381 0.381)
			(layers "F.Cu" "F.Mask" "F.Paste")
			(net "GND")
		)
		(pad "BD58" smd circle
			(at 9.44372 5.69595)
			(size 0.381 0.381)
			(layers "F.Cu" "F.Mask" "F.Paste")
			(net "A_PCIE_RCOMP_N")
		)
		(pad "BD61" smd circle
			(at 11.16076 5.69595)
			(size 0.381 0.381)
			(layers "F.Cu" "F.Mask" "F.Paste")
			(net "SATA6G_S0_RX_DP")
		)
		(pad "BD65" smd circle
			(at 12.8778 5.69595)
			(size 0.381 0.381)
			(layers "F.Cu" "F.Mask" "F.Paste")
			(net "Net_138")
		)
		(pad "BD68" smd circle
			(at 14.649958 5.999988)
			(size 0.3048 0.3048)
			(layers "F.Cu" "F.Mask" "F.Paste")
			(net "GND")
		)
		(pad "BD70" smd circle
			(at 15.48003 5.999988)
			(size 0.3048 0.3048)
			(layers "F.Cu" "F.Mask" "F.Paste")
			(net "TP_USB3_P06_RXP")
		)
		(pad "BD72" smd oval
			(at 16.310102 5.999988 180)
			(size 0.254 0.3302)
			(layers "F.Cu" "F.Mask" "F.Paste")
			(net "TP_USB3_P06_RXN")
		)
		(pad "BE2" smd circle
			(at -15.895066 6.500114 180)
			(size 0.3048 0.3048)
			(layers "F.Cu" "F.Mask" "F.Paste")
			(net "Net_457")
		)
		(pad "BE4" smd circle
			(at -15.064994 6.500114 180)
			(size 0.3048 0.3048)
			(layers "F.Cu" "F.Mask" "F.Paste")
			(net "SMB_LAN_STBY_LVC3_SDA_R1")
		)
		(pad "BE7" smd circle
			(at -13.73632 6.19125)
			(size 0.381 0.381)
			(layers "F.Cu" "F.Mask" "F.Paste")
			(net "FM_NMI_EVENT_N")
		)
		(pad "BE11" smd circle
			(at -12.01928 6.19125)
			(size 0.381 0.381)
			(layers "F.Cu" "F.Mask" "F.Paste")
			(net "Net_474")
		)
		(pad "BE15" smd circle
			(at -10.30224 6.19125)
			(size 0.381 0.381)
			(layers "F.Cu" "F.Mask" "F.Paste")
			(net "FM_BIOS_SMI_ACTIVE_N")
		)
		(pad "BE18" smd circle
			(at -8.5852 6.19125)
			(size 0.381 0.381)
			(layers "F.Cu" "F.Mask" "F.Paste")
			(net "FM_BOARD_SKU_ID3")
		)
		(pad "BE22" smd circle
			(at -6.86816 6.19125)
			(size 0.381 0.381)
			(layers "F.Cu" "F.Mask" "F.Paste")
			(net "Net_471")
		)
		(pad "BE26" smd circle
			(at -5.15112 6.19125)
			(size 0.381 0.381)
			(layers "F.Cu" "F.Mask" "F.Paste")
			(net "P3V3_STBY")
		)
		(pad "BE29" smd circle
			(at -3.43408 6.19125)
			(size 0.381 0.381)
			(layers "F.Cu" "F.Mask" "F.Paste")
			(net "GND")
		)
		(pad "BE33" smd circle
			(at -1.71704 6.19125)
			(size 0.381 0.381)
			(layers "F.Cu" "F.Mask" "F.Paste")
			(net "GND")
		)
		(pad "BE37" smd circle
			(at 0 6.19125)
			(size 0.381 0.381)
			(layers "F.Cu" "F.Mask" "F.Paste")
			(net "GND")
		)
		(pad "BE40" smd circle
			(at 1.71704 6.19125)
			(size 0.381 0.381)
			(layers "F.Cu" "F.Mask" "F.Paste")
			(net "P3V3_STBY")
		)
		(pad "BE44" smd circle
			(at 3.43408 6.19125)
			(size 0.381 0.381)
			(layers "F.Cu" "F.Mask" "F.Paste")
			(net "P3V3_STBY")
		)
		(pad "BE48" smd circle
			(at 5.15112 6.19125)
			(size 0.381 0.381)
			(layers "F.Cu" "F.Mask" "F.Paste")
			(net "P1V05_PCH_STBY")
		)
		(pad "BE52" smd circle
			(at 6.86816 6.19125)
			(size 0.381 0.381)
			(layers "F.Cu" "F.Mask" "F.Paste")
			(net "FM_CPLD_ADR_TRIGGER_R_N")
		)
		(pad "BE56" smd circle
			(at 8.5852 6.19125)
			(size 0.381 0.381)
			(layers "F.Cu" "F.Mask" "F.Paste")
			(net "GND")
		)
		(pad "BE59" smd circle
			(at 10.30224 6.19125)
			(size 0.381 0.381)
			(layers "F.Cu" "F.Mask" "F.Paste")
			(net "GND")
		)
		(pad "BE63" smd circle
			(at 12.01928 6.19125)
			(size 0.381 0.381)
			(layers "F.Cu" "F.Mask" "F.Paste")
			(net "GND")
		)
		(pad "BE66" smd circle
			(at 13.73632 6.19125)
			(size 0.381 0.381)
			(layers "F.Cu" "F.Mask" "F.Paste")
			(net "GND")
		)
		(pad "BE69" smd circle
			(at 15.064994 6.500114)
			(size 0.3048 0.3048)
			(layers "F.Cu" "F.Mask" "F.Paste")
			(net "TP_USB3_P05_RXP")
		)
		(pad "BE71" smd circle
			(at 15.895066 6.500114)
			(size 0.3048 0.3048)
			(layers "F.Cu" "F.Mask" "F.Paste")
			(net "TP_USB3_P05_RXN")
		)
		(pad "BF1" smd oval
			(at -16.310102 6.999986 180)
			(size 0.254 0.3302)
			(layers "F.Cu" "F.Mask" "F.Paste")
			(net "SMB_LAN_STBY_LVC3_SCL_R1")
		)
		(pad "BF3" smd circle
			(at -15.48003 6.999986 180)
			(size 0.3048 0.3048)
			(layers "F.Cu" "F.Mask" "F.Paste")
			(net "FM_BMC_NMI_N")
		)
		(pad "BF5" smd circle
			(at -14.649958 6.999986 180)
			(size 0.3048 0.3048)
			(layers "F.Cu" "F.Mask" "F.Paste")
			(net "GND")
		)
		(pad "BF9" smd circle
			(at -12.8778 6.68655)
			(size 0.381 0.381)
			(layers "F.Cu" "F.Mask" "F.Paste")
			(net "GND")
		)
		(pad "BF13" smd circle
			(at -11.16076 6.68655)
			(size 0.381 0.381)
			(layers "F.Cu" "F.Mask" "F.Paste")
			(net "GND")
		)
		(pad "BF17" smd circle
			(at -9.44372 6.68655)
			(size 0.381 0.381)
			(layers "F.Cu" "F.Mask" "F.Paste")
			(net "GND")
		)
		(pad "BF20" smd circle
			(at -7.72668 6.68655)
			(size 0.381 0.381)
			(layers "F.Cu" "F.Mask" "F.Paste")
			(net "GND")
		)
		(pad "BF24" smd circle
			(at -6.00964 6.68655)
			(size 0.381 0.381)
			(layers "F.Cu" "F.Mask" "F.Paste")
			(net "GND")
		)
		(pad "BF27" smd circle
			(at -4.2926 6.68655)
			(size 0.381 0.381)
			(layers "F.Cu" "F.Mask" "F.Paste")
			(net "GND")
		)
		(pad "BF31" smd circle
			(at -2.57556 6.68655)
			(size 0.381 0.381)
			(layers "F.Cu" "F.Mask" "F.Paste")
			(net "KR_P0_OCP_RX_C_DP")
		)
		(pad "BF35" smd circle
			(at -0.85852 6.68655)
			(size 0.381 0.381)
			(layers "F.Cu" "F.Mask" "F.Paste")
			(net "Net_453")
		)
		(pad "BF38" smd circle
			(at 0.85852 6.68655)
			(size 0.381 0.381)
			(layers "F.Cu" "F.Mask" "F.Paste")
			(net "GND")
		)
		(pad "BF42" smd circle
			(at 2.57556 6.68655)
			(size 0.381 0.381)
			(layers "F.Cu" "F.Mask" "F.Paste")
			(net "GND")
		)
		(pad "BF46" smd circle
			(at 4.2926 6.68655)
			(size 0.381 0.381)
			(layers "F.Cu" "F.Mask" "F.Paste")
			(net "P1V05_PCH_STBY")
		)
		(pad "BF50" smd circle
			(at 6.00964 6.68655)
			(size 0.381 0.381)
			(layers "F.Cu" "F.Mask" "F.Paste")
			(net "GND")
		)
		(pad "BF54" smd circle
			(at 7.72668 6.68655)
			(size 0.381 0.381)
			(layers "F.Cu" "F.Mask" "F.Paste")
			(net "GND")
		)
		(pad "BF58" smd circle
			(at 9.44372 6.68655)
			(size 0.381 0.381)
			(layers "F.Cu" "F.Mask" "F.Paste")
			(net "GND")
		)
		(pad "BF61" smd circle
			(at 11.16076 6.68655)
			(size 0.381 0.381)
			(layers "F.Cu" "F.Mask" "F.Paste")
			(net "GND")
		)
		(pad "BF65" smd circle
			(at 12.8778 6.68655)
			(size 0.381 0.381)
			(layers "F.Cu" "F.Mask" "F.Paste")
			(net "GND")
		)
		(pad "BF68" smd circle
			(at 14.649958 6.999986)
			(size 0.3048 0.3048)
			(layers "F.Cu" "F.Mask" "F.Paste")
			(net "GND")
		)
		(pad "BF70" smd circle
			(at 15.48003 6.999986)
			(size 0.3048 0.3048)
			(layers "F.Cu" "F.Mask" "F.Paste")
			(net "TP_USB3_P04_RXP")
		)
		(pad "BF72" smd oval
			(at 16.310102 6.999986 180)
			(size 0.254 0.3302)
			(layers "F.Cu" "F.Mask" "F.Paste")
			(net "TP_USB3_P04_RXN")
		)
		(pad "BG7" smd circle
			(at -13.73632 7.18185)
			(size 0.381 0.381)
			(layers "F.Cu" "F.Mask" "F.Paste")
			(net "FM_SOL_UART_CH_SEL")
		)
		(pad "BG11" smd circle
			(at -12.01928 7.18185)
			(size 0.381 0.381)
			(layers "F.Cu" "F.Mask" "F.Paste")
			(net "Net_466")
		)
		(pad "BG15" smd circle
			(at -10.30224 7.18185)
			(size 0.381 0.381)
			(layers "F.Cu" "F.Mask" "F.Paste")
			(net "FM_PCH_PWRBTN_OUT_N")
		)
		(pad "BG18" smd circle
			(at -8.5852 7.18185)
			(size 0.381 0.381)
			(layers "F.Cu" "F.Mask" "F.Paste")
			(net "IRQ_PVDDQ_GHJ_VRHOT_LVT3_N")
		)
		(pad "BG22" smd circle
			(at -6.86816 7.18185)
			(size 0.381 0.381)
			(layers "F.Cu" "F.Mask" "F.Paste")
			(net "IRQ_PCH_NIC_ALERT_N")
		)
		(pad "BG26" smd circle
			(at -5.15112 7.18185)
			(size 0.381 0.381)
			(layers "F.Cu" "F.Mask" "F.Paste")
			(net "TP_PCH_RSVD27")
		)
		(pad "BG29" smd circle
			(at -3.43408 7.18185)
			(size 0.381 0.381)
			(layers "F.Cu" "F.Mask" "F.Paste")
			(net "KR_P1_OCP_RX_C_DN")
		)
		(pad "BG33" smd circle
			(at -1.71704 7.18185)
			(size 0.381 0.381)
			(layers "F.Cu" "F.Mask" "F.Paste")
			(net "GND")
		)
		(pad "BG37" smd circle
			(at 0 7.18185)
			(size 0.381 0.381)
			(layers "F.Cu" "F.Mask" "F.Paste")
			(net "Net_452")
		)
		(pad "BG40" smd circle
			(at 1.71704 7.18185)
			(size 0.381 0.381)
			(layers "F.Cu" "F.Mask" "F.Paste")
			(net "TP_PCH_RSVD42")
		)
		(pad "BG44" smd circle
			(at 3.43408 7.18185)
			(size 0.381 0.381)
			(layers "F.Cu" "F.Mask" "F.Paste")
			(net "GND")
		)
		(pad "BG48" smd circle
			(at 5.15112 7.18185)
			(size 0.381 0.381)
			(layers "F.Cu" "F.Mask" "F.Paste")
			(net "GND")
		)
		(pad "BG52" smd circle
			(at 6.86816 7.18185)
			(size 0.381 0.381)
			(layers "F.Cu" "F.Mask" "F.Paste")
			(net "FM_POST_CARD_PRES_BMC_R1_N")
		)
		(pad "BG56" smd circle
			(at 8.5852 7.18185)
			(size 0.381 0.381)
			(layers "F.Cu" "F.Mask" "F.Paste")
			(net "TP_USB3_P04_TXP")
		)
		(pad "BG59" smd circle
			(at 10.30224 7.18185)
			(size 0.381 0.381)
			(layers "F.Cu" "F.Mask" "F.Paste")
			(net "GND")
		)
		(pad "BG63" smd circle
			(at 12.01928 7.18185)
			(size 0.381 0.381)
			(layers "F.Cu" "F.Mask" "F.Paste")
			(net "GND")
		)
		(pad "BG66" smd circle
			(at 13.73632 7.18185)
			(size 0.381 0.381)
			(layers "F.Cu" "F.Mask" "F.Paste")
			(net "P2E_SSB_BMC_TX_DN")
		)
		(pad "BH2" smd circle
			(at -15.895066 7.500112 180)
			(size 0.3048 0.3048)
			(layers "F.Cu" "F.Mask" "F.Paste")
			(net "FM_PCH_BMC_THERMTRIP_N")
		)
		(pad "BH4" smd circle
			(at -15.064994 7.500112 180)
			(size 0.3048 0.3048)
			(layers "F.Cu" "F.Mask" "F.Paste")
			(net "FM_SSATA_PCIE_M2_SEL")
		)
		(pad "BH9" smd circle
			(at -12.8778 7.67715)
			(size 0.381 0.381)
			(layers "F.Cu" "F.Mask" "F.Paste")
			(net "VID_PCH_CORE_PVNN_AUX_VID_1")
		)
		(pad "BH13" smd circle
			(at -11.16076 7.67715)
			(size 0.381 0.381)
			(layers "F.Cu" "F.Mask" "F.Paste")
			(net "FM_BIOS_TOP_SWAP_SPKR")
		)
		(pad "BH17" smd circle
			(at -9.44372 7.67715)
			(size 0.381 0.381)
			(layers "F.Cu" "F.Mask" "F.Paste")
			(net "FM_FAST_PROCHOT_EN_N")
		)
		(pad "BH20" smd circle
			(at -7.72668 7.67715)
			(size 0.381 0.381)
			(layers "F.Cu" "F.Mask" "F.Paste")
			(net "FM_PWR_BTN_N")
		)
		(pad "BH24" smd circle
			(at -6.00964 7.67715)
			(size 0.381 0.381)
			(layers "F.Cu" "F.Mask" "F.Paste")
			(net "TP_PCH_RSVD26")
		)
		(pad "BH27" smd circle
			(at -4.2926 7.67715)
			(size 0.381 0.381)
			(layers "F.Cu" "F.Mask" "F.Paste")
			(net "GND")
		)
		(pad "BH31" smd circle
			(at -2.57556 7.67715)
			(size 0.381 0.381)
			(layers "F.Cu" "F.Mask" "F.Paste")
			(net "KR_P0_OCP_RX_C_DN")
		)
		(pad "BH35" smd circle
			(at -0.85852 7.67715)
			(size 0.381 0.381)
			(layers "F.Cu" "F.Mask" "F.Paste")
			(net "Net_454")
		)
		(pad "BH38" smd circle
			(at 0.85852 7.67715)
			(size 0.381 0.381)
			(layers "F.Cu" "F.Mask" "F.Paste")
			(net "GND")
		)
		(pad "BH42" smd circle
			(at 2.57556 7.67715)
			(size 0.381 0.381)
			(layers "F.Cu" "F.Mask" "F.Paste")
			(net "GND")
		)
		(pad "BH46" smd circle
			(at 4.2926 7.67715)
			(size 0.381 0.381)
			(layers "F.Cu" "F.Mask" "F.Paste")
			(net "GND")
		)
		(pad "BH50" smd circle
			(at 6.00964 7.67715)
			(size 0.381 0.381)
			(layers "F.Cu" "F.Mask" "F.Paste")
			(net "FM_CPU0_RC_ERROR_R1_N")
		)
		(pad "BH54" smd circle
			(at 7.72668 7.67715)
			(size 0.381 0.381)
			(layers "F.Cu" "F.Mask" "F.Paste")
			(net "GND")
		)
		(pad "BH58" smd circle
			(at 9.44372 7.67715)
			(size 0.381 0.381)
			(layers "F.Cu" "F.Mask" "F.Paste")
			(net "TP_USB3_P04_TXN")
		)
		(pad "BH61" smd circle
			(at 11.16076 7.67715)
			(size 0.381 0.381)
			(layers "F.Cu" "F.Mask" "F.Paste")
			(net "P3E_PCH_M2_TX_DN<3>")
		)
		(pad "BH65" smd circle
			(at 12.8778 7.67715)
			(size 0.381 0.381)
			(layers "F.Cu" "F.Mask" "F.Paste")
			(net "PE_PCH_SPRV_TX_DN")
		)
		(pad "BH69" smd circle
			(at 15.064994 7.500112)
			(size 0.3048 0.3048)
			(layers "F.Cu" "F.Mask" "F.Paste")
			(net "TP_USB3_P03_RXP")
		)
		(pad "BH71" smd circle
			(at 15.895066 7.500112)
			(size 0.3048 0.3048)
			(layers "F.Cu" "F.Mask" "F.Paste")
			(net "TP_USB3_P03_RXN")
		)
		(pad "BJ1" smd oval
			(at -16.310102 7.999984 180)
			(size 0.254 0.3302)
			(layers "F.Cu" "F.Mask" "F.Paste")
			(net "GND")
		)
		(pad "BJ3" smd circle
			(at -15.48003 7.999984 180)
			(size 0.3048 0.3048)
			(layers "F.Cu" "F.Mask" "F.Paste")
			(net "GND")
		)
		(pad "BJ5" smd circle
			(at -14.649958 7.999984 180)
			(size 0.3048 0.3048)
			(layers "F.Cu" "F.Mask" "F.Paste")
			(net "GND")
		)
		(pad "BJ7" smd circle
			(at -13.73632 8.17245)
			(size 0.381 0.381)
			(layers "F.Cu" "F.Mask" "F.Paste")
			(net "GND")
		)
		(pad "BJ11" smd circle
			(at -12.01928 8.17245)
			(size 0.381 0.381)
			(layers "F.Cu" "F.Mask" "F.Paste")
			(net "GND")
		)
		(pad "BJ15" smd circle
			(at -10.30224 8.17245)
			(size 0.381 0.381)
			(layers "F.Cu" "F.Mask" "F.Paste")
			(net "GND")
		)
		(pad "BJ18" smd circle
			(at -8.5852 8.17245)
			(size 0.381 0.381)
			(layers "F.Cu" "F.Mask" "F.Paste")
			(net "GND")
		)
		(pad "BJ22" smd circle
			(at -6.86816 8.17245)
			(size 0.381 0.381)
			(layers "F.Cu" "F.Mask" "F.Paste")
			(net "FM_BIOS_POST_CMPLT_N")
		)
		(pad "BJ26" smd circle
			(at -5.15112 8.17245)
			(size 0.381 0.381)
			(layers "F.Cu" "F.Mask" "F.Paste")
			(net "GND")
		)
		(pad "BJ29" smd circle
			(at -3.43408 8.17245)
			(size 0.381 0.381)
			(layers "F.Cu" "F.Mask" "F.Paste")
			(net "KR_P1_OCP_RX_C_DP")
		)
		(pad "BJ33" smd circle
			(at -1.71704 8.17245)
			(size 0.381 0.381)
			(layers "F.Cu" "F.Mask" "F.Paste")
			(net "GND")
		)
		(pad "BJ37" smd circle
			(at 0 8.17245)
			(size 0.381 0.381)
			(layers "F.Cu" "F.Mask" "F.Paste")
			(net "Net_451")
		)
		(pad "BJ40" smd circle
			(at 1.71704 8.17245)
			(size 0.381 0.381)
			(layers "F.Cu" "F.Mask" "F.Paste")
			(net "TP_PCH_RSVD41")
		)
		(pad "BJ44" smd circle
			(at 3.43408 8.17245)
			(size 0.381 0.381)
			(layers "F.Cu" "F.Mask" "F.Paste")
			(net "IRQ_HSC_FAULT_N")
		)
		(pad "BJ48" smd circle
			(at 5.15112 8.17245)
			(size 0.381 0.381)
			(layers "F.Cu" "F.Mask" "F.Paste")
			(net "FM_ADR_SMI_GPIO_N")
		)
		(pad "BJ52" smd circle
			(at 6.86816 8.17245)
			(size 0.381 0.381)
			(layers "F.Cu" "F.Mask" "F.Paste")
			(net "GND")
		)
		(pad "BJ56" smd circle
			(at 8.5852 8.17245)
			(size 0.381 0.381)
			(layers "F.Cu" "F.Mask" "F.Paste")
			(net "TP_USB3_P02_TXP")
		)
		(pad "BJ59" smd circle
			(at 10.30224 8.17245)
			(size 0.381 0.381)
			(layers "F.Cu" "F.Mask" "F.Paste")
			(net "TP_USB3_P05_TXP")
		)
		(pad "BJ63" smd circle
			(at 12.01928 8.17245)
			(size 0.381 0.381)
			(layers "F.Cu" "F.Mask" "F.Paste")
			(net "PE_PCH_SPRV_TX_DP")
		)
		(pad "BJ66" smd circle
			(at 13.73632 8.17245)
			(size 0.381 0.381)
			(layers "F.Cu" "F.Mask" "F.Paste")
			(net "P2E_SSB_BMC_TX_DP")
		)
		(pad "BJ68" smd circle
			(at 14.649958 7.999984)
			(size 0.3048 0.3048)
			(layers "F.Cu" "F.Mask" "F.Paste")
			(net "GND")
		)
		(pad "BJ70" smd circle
			(at 15.48003 7.999984)
			(size 0.3048 0.3048)
			(layers "F.Cu" "F.Mask" "F.Paste")
			(net "TP_USB3_P02_RXP")
		)
		(pad "BJ72" smd oval
			(at 16.310102 7.999984 180)
			(size 0.254 0.3302)
			(layers "F.Cu" "F.Mask" "F.Paste")
			(net "TP_USB3_P02_RXN")
		)
		(pad "BK2" smd circle
			(at -15.895066 8.50011 180)
			(size 0.3048 0.3048)
			(layers "F.Cu" "F.Mask" "F.Paste")
			(net "LED_GBE_P1_1")
		)
		(pad "BK4" smd circle
			(at -15.064994 8.50011 180)
			(size 0.3048 0.3048)
			(layers "F.Cu" "F.Mask" "F.Paste")
			(net "LED_GBE_P0_1")
		)
		(pad "BK9" smd circle
			(at -12.8778 8.66775)
			(size 0.381 0.381)
			(layers "F.Cu" "F.Mask" "F.Paste")
			(net "FM_PMBUS_ALERT_BUF_EN_R2_N")
		)
		(pad "BK13" smd circle
			(at -11.16076 8.66775)
			(size 0.381 0.381)
			(layers "F.Cu" "F.Mask" "F.Paste")
			(net "FM_UART_ALERT_N")
		)
		(pad "BK17" smd circle
			(at -9.44372 8.66775)
			(size 0.381 0.381)
			(layers "F.Cu" "F.Mask" "F.Paste")
			(net "IRQ_PVDDQ_DEF_VRHOT_LVT3_N")
		)
		(pad "BK20" smd circle
			(at -7.72668 8.66775)
			(size 0.381 0.381)
			(layers "F.Cu" "F.Mask" "F.Paste")
			(net "FM_BIOS_PREFRB2_GOOD")
		)
		(pad "BK24" smd circle
			(at -6.00964 8.66775)
			(size 0.381 0.381)
			(layers "F.Cu" "F.Mask" "F.Paste")
			(net "GND")
		)
		(pad "BK27" smd circle
			(at -4.2926 8.66775)
			(size 0.381 0.381)
			(layers "F.Cu" "F.Mask" "F.Paste")
			(net "GND")
		)
		(pad "BK31" smd circle
			(at -2.57556 8.66775)
			(size 0.381 0.381)
			(layers "F.Cu" "F.Mask" "F.Paste")
			(net "GND")
		)
		(pad "BK35" smd circle
			(at -0.85852 8.66775)
			(size 0.381 0.381)
			(layers "F.Cu" "F.Mask" "F.Paste")
			(net "GND")
		)
		(pad "BK38" smd circle
			(at 0.85852 8.66775)
			(size 0.381 0.381)
			(layers "F.Cu" "F.Mask" "F.Paste")
			(net "GND")
		)
		(pad "BK42" smd circle
			(at 2.57556 8.66775)
			(size 0.381 0.381)
			(layers "F.Cu" "F.Mask" "F.Paste")
			(net "GND")
		)
		(pad "BK46" smd circle
			(at 4.2926 8.66775)
			(size 0.381 0.381)
			(layers "F.Cu" "F.Mask" "F.Paste")
			(net "FM_PWR_LED_N")
		)
		(pad "BK50" smd circle
			(at 6.00964 8.66775)
			(size 0.381 0.381)
			(layers "F.Cu" "F.Mask" "F.Paste")
			(net "GND")
		)
		(pad "BK54" smd circle
			(at 7.72668 8.66775)
			(size 0.381 0.381)
			(layers "F.Cu" "F.Mask" "F.Paste")
			(net "USB3_P01_TXP")
		)
		(pad "BK58" smd circle
			(at 9.44372 8.66775)
			(size 0.381 0.381)
			(layers "F.Cu" "F.Mask" "F.Paste")
			(net "TP_USB3_P05_TXN")
		)
		(pad "BK61" smd circle
			(at 11.16076 8.66775)
			(size 0.381 0.381)
			(layers "F.Cu" "F.Mask" "F.Paste")
			(net "P3E_PCH_M2_TX_DP<3>")
		)
		(pad "BK65" smd circle
			(at 12.8778 8.66775)
			(size 0.381 0.381)
			(layers "F.Cu" "F.Mask" "F.Paste")
			(net "P3E_PCH_M2_TX_DN<2>")
		)
		(pad "BK69" smd circle
			(at 15.064994 8.50011)
			(size 0.3048 0.3048)
			(layers "F.Cu" "F.Mask" "F.Paste")
			(net "USB3_P01_RXP")
		)
		(pad "BK71" smd circle
			(at 15.895066 8.50011)
			(size 0.3048 0.3048)
			(layers "F.Cu" "F.Mask" "F.Paste")
			(net "USB3_P01_RXN")
		)
		(pad "BL1" smd oval
			(at -16.310102 8.999982 180)
			(size 0.254 0.3302)
			(layers "F.Cu" "F.Mask" "F.Paste")
			(net "LED_GBE_P0_0")
		)
		(pad "BL3" smd circle
			(at -15.48003 8.999982 180)
			(size 0.3048 0.3048)
			(layers "F.Cu" "F.Mask" "F.Paste")
			(net "LED_GBE_P2_0")
		)
		(pad "BL5" smd circle
			(at -14.649958 8.999982 180)
			(size 0.3048 0.3048)
			(layers "F.Cu" "F.Mask" "F.Paste")
			(net "GND")
		)
		(pad "BL7" smd circle
			(at -13.73632 9.16305)
			(size 0.381 0.381)
			(layers "F.Cu" "F.Mask" "F.Paste")
			(net "VID_PCH_CORE_PVNN_AUX_VID_0")
		)
		(pad "BL11" smd circle
			(at -12.01928 9.16305)
			(size 0.381 0.381)
			(layers "F.Cu" "F.Mask" "F.Paste")
			(net "RST_SYSTEM_BTN_N")
		)
		(pad "BL15" smd circle
			(at -10.30224 9.16305)
			(size 0.381 0.381)
			(layers "F.Cu" "F.Mask" "F.Paste")
			(net "FM_UV_ADR_TRIGGER_EN")
		)
		(pad "BL18" smd circle
			(at -8.5852 9.16305)
			(size 0.381 0.381)
			(layers "F.Cu" "F.Mask" "F.Paste")
			(net "FM_GLOBAL_RST_WARN_N")
		)
		(pad "BL22" smd circle
			(at -6.86816 9.16305)
			(size 0.381 0.381)
			(layers "F.Cu" "F.Mask" "F.Paste")
			(net "GND")
		)
		(pad "BL26" smd circle
			(at -5.15112 9.16305)
			(size 0.381 0.381)
			(layers "F.Cu" "F.Mask" "F.Paste")
			(net "TP_10GBE_KR0_MON_DN")
		)
		(pad "BL29" smd circle
			(at -3.43408 9.16305)
			(size 0.381 0.381)
			(layers "F.Cu" "F.Mask" "F.Paste")
			(net "TP_PCH_RSVD38")
		)
		(pad "BL33" smd circle
			(at -1.71704 9.16305)
			(size 0.381 0.381)
			(layers "F.Cu" "F.Mask" "F.Paste")
			(net "TP_10GBE_KR1_MON_DN")
		)
		(pad "BL37" smd circle
			(at 0 9.16305)
			(size 0.381 0.381)
			(layers "F.Cu" "F.Mask" "F.Paste")
			(net "GND")
		)
		(pad "BL40" smd circle
			(at 1.71704 9.16305)
			(size 0.381 0.381)
			(layers "F.Cu" "F.Mask" "F.Paste")
			(net "GND")
		)
		(pad "BL44" smd circle
			(at 3.43408 9.16305)
			(size 0.381 0.381)
			(layers "F.Cu" "F.Mask" "F.Paste")
			(net "SMB_SLOTX24_PCH_STBY_LVC3_SDA")
		)
		(pad "BL48" smd circle
			(at 5.15112 9.16305)
			(size 0.381 0.381)
			(layers "F.Cu" "F.Mask" "F.Paste")
			(net "FM_OC0_USB_N")
		)
		(pad "BL52" smd circle
			(at 6.86816 9.16305)
			(size 0.381 0.381)
			(layers "F.Cu" "F.Mask" "F.Paste")
			(net "USB3_P01_TXN")
		)
		(pad "BL56" smd circle
			(at 8.5852 9.16305)
			(size 0.381 0.381)
			(layers "F.Cu" "F.Mask" "F.Paste")
			(net "TP_USB3_P02_TXN")
		)
		(pad "BL59" smd circle
			(at 10.30224 9.16305)
			(size 0.381 0.381)
			(layers "F.Cu" "F.Mask" "F.Paste")
			(net "TP_USB3_P06_TXN")
		)
		(pad "BL63" smd circle
			(at 12.01928 9.16305)
			(size 0.381 0.381)
			(layers "F.Cu" "F.Mask" "F.Paste")
			(net "GND")
		)
		(pad "BL66" smd circle
			(at 13.73632 9.16305)
			(size 0.381 0.381)
			(layers "F.Cu" "F.Mask" "F.Paste")
			(net "P3E_PCH_M2_TX_DP<2>")
		)
		(pad "BL68" smd circle
			(at 14.649958 8.999982)
			(size 0.3048 0.3048)
			(layers "F.Cu" "F.Mask" "F.Paste")
			(net "GND")
		)
		(pad "BL70" smd circle
			(at 15.48003 8.999982)
			(size 0.3048 0.3048)
			(layers "F.Cu" "F.Mask" "F.Paste")
			(net "GND")
		)
		(pad "BL72" smd oval
			(at 16.310102 8.999982 180)
			(size 0.254 0.3302)
			(layers "F.Cu" "F.Mask" "F.Paste")
			(net "GND")
		)
		(pad "BM2" smd circle
			(at -15.895066 9.500108 180)
			(size 0.3048 0.3048)
			(layers "F.Cu" "F.Mask" "F.Paste")
			(net "LED_GBE_P3_1")
		)
		(pad "BM4" smd circle
			(at -15.064994 9.500108 180)
			(size 0.3048 0.3048)
			(layers "F.Cu" "F.Mask" "F.Paste")
			(net "SMB_PCH_MEZZ_LOM0_SCL")
		)
		(pad "BM9" smd circle
			(at -12.8778 9.65835)
			(size 0.381 0.381)
			(layers "F.Cu" "F.Mask" "F.Paste")
			(net "GND")
		)
		(pad "BM13" smd circle
			(at -11.16076 9.65835)
			(size 0.381 0.381)
			(layers "F.Cu" "F.Mask" "F.Paste")
			(net "GND")
		)
		(pad "BM17" smd circle
			(at -9.44372 9.65835)
			(size 0.381 0.381)
			(layers "F.Cu" "F.Mask" "F.Paste")
			(net "GND")
		)
		(pad "BM20" smd circle
			(at -7.72668 9.65835)
			(size 0.381 0.381)
			(layers "F.Cu" "F.Mask" "F.Paste")
			(net "FM_PCH_BMC_THERMTRIP_EXI_STRAP_")
		)
		(pad "BM24" smd circle
			(at -6.00964 9.65835)
			(size 0.381 0.381)
			(layers "F.Cu" "F.Mask" "F.Paste")
			(net "KR_P1_OCP_TX_DN")
		)
		(pad "BM27" smd circle
			(at -4.2926 9.65835)
			(size 0.381 0.381)
			(layers "F.Cu" "F.Mask" "F.Paste")
			(net "KR_P0_OCP_TX_DN")
		)
		(pad "BM31" smd circle
			(at -2.57556 9.65835)
			(size 0.381 0.381)
			(layers "F.Cu" "F.Mask" "F.Paste")
			(net "Net_442")
		)
		(pad "BM35" smd circle
			(at -0.85852 9.65835)
			(size 0.381 0.381)
			(layers "F.Cu" "F.Mask" "F.Paste")
			(net "Net_439")
		)
		(pad "BM38" smd circle
			(at 0.85852 9.65835)
			(size 0.381 0.381)
			(layers "F.Cu" "F.Mask" "F.Paste")
			(net "FM_BMC_ENABLE_N")
		)
		(pad "BM42" smd circle
			(at 2.57556 9.65835)
			(size 0.381 0.381)
			(layers "F.Cu" "F.Mask" "F.Paste")
			(net "FM_PCH_PLD_DATA_R")
		)
		(pad "BM46" smd circle
			(at 4.2926 9.65835)
			(size 0.381 0.381)
			(layers "F.Cu" "F.Mask" "F.Paste")
			(net "GND")
		)
		(pad "BM50" smd circle
			(at 6.00964 9.65835)
			(size 0.381 0.381)
			(layers "F.Cu" "F.Mask" "F.Paste")
			(net "GND")
		)
		(pad "BM54" smd circle
			(at 7.72668 9.65835)
			(size 0.381 0.381)
			(layers "F.Cu" "F.Mask" "F.Paste")
			(net "TP_USB3_P03_TXN")
		)
		(pad "BM58" smd circle
			(at 9.44372 9.65835)
			(size 0.381 0.381)
			(layers "F.Cu" "F.Mask" "F.Paste")
			(net "GND")
		)
		(pad "BM61" smd circle
			(at 11.16076 9.65835)
			(size 0.381 0.381)
			(layers "F.Cu" "F.Mask" "F.Paste")
			(net "TP_USB3_P06_TXP")
		)
		(pad "BM65" smd circle
			(at 12.8778 9.65835)
			(size 0.381 0.381)
			(layers "F.Cu" "F.Mask" "F.Paste")
			(net "P3E_PCH_M2_TX_DN<1>")
		)
		(pad "BM69" smd circle
			(at 15.064994 9.500108)
			(size 0.3048 0.3048)
			(layers "F.Cu" "F.Mask" "F.Paste")
			(net "GND")
		)
		(pad "BM71" smd circle
			(at 15.895066 9.500108)
			(size 0.3048 0.3048)
			(layers "F.Cu" "F.Mask" "F.Paste")
			(net "GND")
		)
		(pad "BN1" smd circle
			(at -16.310102 10.063734 90)
			(size 0.3556 0.3556)
			(layers "F.Cu" "F.Mask" "F.Paste")
			(net "GND")
		)
		(pad "BN3" smd circle
			(at -15.48003 9.99998 180)
			(size 0.3048 0.3048)
			(layers "F.Cu" "F.Mask" "F.Paste")
			(net "SMB_PCH_MEZZ_LOM0_SDA")
		)
		(pad "BN5" smd circle
			(at -14.649958 9.99998 180)
			(size 0.3048 0.3048)
			(layers "F.Cu" "F.Mask" "F.Paste")
			(net "GND")
		)
		(pad "BN7" smd circle
			(at -13.73632 10.15365)
			(size 0.381 0.381)
			(layers "F.Cu" "F.Mask" "F.Paste")
			(net "IRQ_PVDDQ_ABC_VRHOT_LVT3_N")
		)
		(pad "BN11" smd circle
			(at -12.01928 10.15365)
			(size 0.381 0.381)
			(layers "F.Cu" "F.Mask" "F.Paste")
			(net "FP_NMI_BTN_N")
		)
		(pad "BN15" smd circle
			(at -10.30224 10.15365)
			(size 0.381 0.381)
			(layers "F.Cu" "F.Mask" "F.Paste")
			(net "PU_IRQ_VRALERT_N")
		)
		(pad "BN18" smd circle
			(at -8.5852 10.15365)
			(size 0.381 0.381)
			(layers "F.Cu" "F.Mask" "F.Paste")
			(net "RST_PLTRST_N")
		)
		(pad "BN22" smd circle
			(at -6.86816 10.15365)
			(size 0.381 0.381)
			(layers "F.Cu" "F.Mask" "F.Paste")
			(net "GND")
		)
		(pad "BN26" smd circle
			(at -5.15112 10.15365)
			(size 0.381 0.381)
			(layers "F.Cu" "F.Mask" "F.Paste")
			(net "TP_10GBE_KR0_MON_DP")
		)
		(pad "BN29" smd circle
			(at -3.43408 10.15365)
			(size 0.381 0.381)
			(layers "F.Cu" "F.Mask" "F.Paste")
			(net "TP_PCH_RSVD37")
		)
		(pad "BN33" smd circle
			(at -1.71704 10.15365)
			(size 0.381 0.381)
			(layers "F.Cu" "F.Mask" "F.Paste")
			(net "TP_10GBE_KR1_MON_DP")
		)
		(pad "BN37" smd circle
			(at 0 10.15365)
			(size 0.381 0.381)
			(layers "F.Cu" "F.Mask" "F.Paste")
			(net "GND")
		)
		(pad "BN40" smd circle
			(at 1.71704 10.15365)
			(size 0.381 0.381)
			(layers "F.Cu" "F.Mask" "F.Paste")
			(net "FM_TPM_PRES_RST_N")
		)
		(pad "BN44" smd circle
			(at 3.43408 10.15365)
			(size 0.381 0.381)
			(layers "F.Cu" "F.Mask" "F.Paste")
			(net "FM_CPU0_THERMTRIP_LATCH_LVT3_N")
		)
		(pad "BN48" smd circle
			(at 5.15112 10.15365)
			(size 0.381 0.381)
			(layers "F.Cu" "F.Mask" "F.Paste")
			(net "IRQ_BMC_PCH_SCI_LPC_N")
		)
		(pad "BN52" smd circle
			(at 6.86816 10.15365)
			(size 0.381 0.381)
			(layers "F.Cu" "F.Mask" "F.Paste")
			(net "GND")
		)
		(pad "BN56" smd circle
			(at 8.5852 10.15365)
			(size 0.381 0.381)
			(layers "F.Cu" "F.Mask" "F.Paste")
			(net "TP_USB3_P03_TXP")
		)
		(pad "BN59" smd circle
			(at 10.30224 10.15365)
			(size 0.381 0.381)
			(layers "F.Cu" "F.Mask" "F.Paste")
			(net "GND")
		)
		(pad "BN63" smd circle
			(at 12.01928 10.15365)
			(size 0.381 0.381)
			(layers "F.Cu" "F.Mask" "F.Paste")
			(net "P3E_PCH_TX_0_DP")
		)
		(pad "BN66" smd circle
			(at 13.73632 10.15365)
			(size 0.381 0.381)
			(layers "F.Cu" "F.Mask" "F.Paste")
			(net "GND")
		)
		(pad "BN68" smd circle
			(at 14.649958 9.99998)
			(size 0.3048 0.3048)
			(layers "F.Cu" "F.Mask" "F.Paste")
			(net "TP_PCH_RSVD55")
		)
		(pad "BN70" smd circle
			(at 15.48003 9.99998)
			(size 0.3048 0.3048)
			(layers "F.Cu" "F.Mask" "F.Paste")
			(net "A_USB2_COMP")
		)
		(pad "BN72" smd circle
			(at 16.310102 10.063734 90)
			(size 0.3556 0.3556)
			(layers "F.Cu" "F.Mask" "F.Paste")
			(net "GND")
		)
		(pad "BP4" smd circle
			(at -15.064994 10.500106 180)
			(size 0.3048 0.3048)
			(layers "F.Cu" "F.Mask" "F.Paste")
			(net "LED_GBE_P1_0")
		)
		(pad "BP69" smd circle
			(at 15.064994 10.500106)
			(size 0.3048 0.3048)
			(layers "F.Cu" "F.Mask" "F.Paste")
			(net "GND")
		)
		(pad "BR1" smd circle
			(at -16.310102 10.876534 225)
			(size 0.4064 0.4064)
			(layers "F.Cu" "F.Mask" "F.Paste")
			(net "GND")
		)
		(pad "BR3" smd circle
			(at -15.580106 10.999978 90)
			(size 0.3556 0.3556)
			(layers "F.Cu" "F.Mask" "F.Paste")
			(net "GND")
		)
		(pad "BR6" smd circle
			(at -14.356334 10.891012 90)
			(size 0.3048 0.3048)
			(layers "F.Cu" "F.Mask" "F.Paste")
			(net "GND")
		)
		(pad "BR9" smd circle
			(at -12.8778 10.64895)
			(size 0.381 0.381)
			(layers "F.Cu" "F.Mask" "F.Paste")
			(net "FM_QAT_EN_N")
		)
		(pad "BR13" smd circle
			(at -11.16076 10.64895)
			(size 0.381 0.381)
			(layers "F.Cu" "F.Mask" "F.Paste")
			(net "IRQ_PVDDQ_KLM_VRHOT_LVT3_N")
		)
		(pad "BR17" smd circle
			(at -9.44372 10.64895)
			(size 0.381 0.381)
			(layers "F.Cu" "F.Mask" "F.Paste")
			(net "FM_USB_P0_EN_BOOT_BIOS_STRAP_N")
		)
		(pad "BR20" smd circle
			(at -7.72668 10.64895)
			(size 0.381 0.381)
			(layers "F.Cu" "F.Mask" "F.Paste")
			(net "GND")
		)
		(pad "BR24" smd circle
			(at -6.00964 10.64895)
			(size 0.381 0.381)
			(layers "F.Cu" "F.Mask" "F.Paste")
			(net "KR_P1_OCP_TX_DP")
		)
		(pad "BR27" smd circle
			(at -4.2926 10.64895)
			(size 0.381 0.381)
			(layers "F.Cu" "F.Mask" "F.Paste")
			(net "KR_P0_OCP_TX_DP")
		)
		(pad "BR31" smd circle
			(at -2.57556 10.64895)
			(size 0.381 0.381)
			(layers "F.Cu" "F.Mask" "F.Paste")
			(net "Net_441")
		)
		(pad "BR35" smd circle
			(at -0.85852 10.64895)
			(size 0.381 0.381)
			(layers "F.Cu" "F.Mask" "F.Paste")
			(net "Net_440")
		)
		(pad "BR38" smd circle
			(at 0.85852 10.64895)
			(size 0.381 0.381)
			(layers "F.Cu" "F.Mask" "F.Paste")
			(net "FM_BMC_FAULT_LED_N")
		)
		(pad "BR42" smd circle
			(at 2.57556 10.64895)
			(size 0.381 0.381)
			(layers "F.Cu" "F.Mask" "F.Paste")
			(net "IRQ_BMC_PCH_NMI_STBY_R_N")
		)
		(pad "BR46" smd circle
			(at 4.2926 10.64895)
			(size 0.381 0.381)
			(layers "F.Cu" "F.Mask" "F.Paste")
			(net "Net_476")
		)
		(pad "BR50" smd circle
			(at 6.00964 10.64895)
			(size 0.381 0.381)
			(layers "F.Cu" "F.Mask" "F.Paste")
			(net "GND")
		)
		(pad "BR54" smd circle
			(at 7.72668 10.64895)
			(size 0.381 0.381)
			(layers "F.Cu" "F.Mask" "F.Paste")
			(net "GND")
		)
		(pad "BR58" smd circle
			(at 9.44372 10.64895)
			(size 0.381 0.381)
			(layers "F.Cu" "F.Mask" "F.Paste")
			(net "GND")
		)
		(pad "BR61" smd circle
			(at 11.16076 10.64895)
			(size 0.381 0.381)
			(layers "F.Cu" "F.Mask" "F.Paste")
			(net "P3E_PCH_TX_0_DN")
		)
		(pad "BR65" smd circle
			(at 12.8778 10.64895)
			(size 0.381 0.381)
			(layers "F.Cu" "F.Mask" "F.Paste")
			(net "P3E_PCH_M2_TX_DP<1>")
		)
		(pad "BR67" smd circle
			(at 14.356334 10.891012 90)
			(size 0.3048 0.3048)
			(layers "F.Cu" "F.Mask" "F.Paste")
			(net "A_USB2_VBUS")
		)
		(pad "BR70" smd circle
			(at 15.580106 10.999978 90)
			(size 0.3556 0.3556)
			(layers "F.Cu" "F.Mask" "F.Paste")
			(net "GND")
		)
		(pad "BR72" smd circle
			(at 16.310102 10.876534 315)
			(size 0.4064 0.4064)
			(layers "F.Cu" "F.Mask" "F.Paste")
			(net "GND")
		)
		(pad "BT5" smd circle
			(at -14.85138 11.386058 90)
			(size 0.3048 0.3048)
			(layers "F.Cu" "F.Mask" "F.Paste")
			(net "SMB_PCH_MEZZ_LOM2_SCL")
		)
		(pad "BT8" smd circle
			(at -13.5001 11.234928 90)
			(size 0.3048 0.3048)
			(layers "F.Cu" "F.Mask" "F.Paste")
			(net "GND")
		)
		(pad "BT66" smd circle
			(at 13.5001 11.234928 90)
			(size 0.3048 0.3048)
			(layers "F.Cu" "F.Mask" "F.Paste")
			(net "GND")
		)
		(pad "BT69" smd circle
			(at 14.85138 11.386058 90)
			(size 0.3048 0.3048)
			(layers "F.Cu" "F.Mask" "F.Paste")
			(net "GND")
		)
		(pad "BU1" smd circle
			(at -16.310102 11.689334 180)
			(size 0.4064 0.4064)
			(layers "F.Cu" "F.Mask" "F.Paste")
			(net "GND")
		)
		(pad "BU3" smd circle
			(at -15.580106 11.78433 90)
			(size 0.3556 0.3556)
			(layers "F.Cu" "F.Mask" "F.Paste")
			(net "GND")
		)
		(pad "BU6" smd circle
			(at -13.999972 11.649964 90)
			(size 0.3048 0.3048)
			(layers "F.Cu" "F.Mask" "F.Paste")
			(net "LED_GBE_P2_1")
		)
		(pad "BU9" smd circle
			(at -12.999974 11.649964 270)
			(size 0.3048 0.3048)
			(layers "F.Cu" "F.Mask" "F.Paste")
			(net "GND")
		)
		(pad "BU11" smd circle
			(at -11.999976 11.649964 270)
			(size 0.3048 0.3048)
			(layers "F.Cu" "F.Mask" "F.Paste")
			(net "GND")
		)
		(pad "BU13" smd circle
			(at -10.999978 11.649964 270)
			(size 0.3048 0.3048)
			(layers "F.Cu" "F.Mask" "F.Paste")
			(net "GND")
		)
		(pad "BU15" smd circle
			(at -9.99998 11.649964 270)
			(size 0.3048 0.3048)
			(layers "F.Cu" "F.Mask" "F.Paste")
			(net "GND")
		)
		(pad "BU18" smd circle
			(at -8.999982 11.649964 270)
			(size 0.3048 0.3048)
			(layers "F.Cu" "F.Mask" "F.Paste")
			(net "GND")
		)
		(pad "BU20" smd circle
			(at -7.999984 11.649964 270)
			(size 0.3048 0.3048)
			(layers "F.Cu" "F.Mask" "F.Paste")
			(net "GND")
		)
		(pad "BU22" smd circle
			(at -6.999986 11.649964 270)
			(size 0.3048 0.3048)
			(layers "F.Cu" "F.Mask" "F.Paste")
			(net "GND")
		)
		(pad "BU24" smd circle
			(at -5.999988 11.649964 270)
			(size 0.3048 0.3048)
			(layers "F.Cu" "F.Mask" "F.Paste")
			(net "GND")
		)
		(pad "BU26" smd circle
			(at -4.99999 11.649964 270)
			(size 0.3048 0.3048)
			(layers "F.Cu" "F.Mask" "F.Paste")
			(net "GND")
		)
		(pad "BU28" smd circle
			(at -3.999992 11.649964 270)
			(size 0.3048 0.3048)
			(layers "F.Cu" "F.Mask" "F.Paste")
			(net "GND")
		)
		(pad "BU30" smd circle
			(at -2.999994 11.649964 270)
			(size 0.3048 0.3048)
			(layers "F.Cu" "F.Mask" "F.Paste")
			(net "GND")
		)
		(pad "BU32" smd circle
			(at -1.999996 11.649964 270)
			(size 0.3048 0.3048)
			(layers "F.Cu" "F.Mask" "F.Paste")
			(net "GND")
		)
		(pad "BU34" smd circle
			(at -0.999998 11.649964 270)
			(size 0.3048 0.3048)
			(layers "F.Cu" "F.Mask" "F.Paste")
			(net "GND")
		)
		(pad "BU37" smd circle
			(at 0 11.649964 270)
			(size 0.3048 0.3048)
			(layers "F.Cu" "F.Mask" "F.Paste")
			(net "GND")
		)
		(pad "BU39" smd circle
			(at 0.999998 11.649964 270)
			(size 0.3048 0.3048)
			(layers "F.Cu" "F.Mask" "F.Paste")
			(net "GND")
		)
		(pad "BU41" smd circle
			(at 1.999996 11.649964 270)
			(size 0.3048 0.3048)
			(layers "F.Cu" "F.Mask" "F.Paste")
			(net "GND")
		)
		(pad "BU43" smd circle
			(at 2.999994 11.649964 270)
			(size 0.3048 0.3048)
			(layers "F.Cu" "F.Mask" "F.Paste")
			(net "GND")
		)
		(pad "BU45" smd circle
			(at 3.999992 11.649964 270)
			(size 0.3048 0.3048)
			(layers "F.Cu" "F.Mask" "F.Paste")
			(net "GND")
		)
		(pad "BU48" smd circle
			(at 4.99999 11.649964 270)
			(size 0.3048 0.3048)
			(layers "F.Cu" "F.Mask" "F.Paste")
			(net "GND")
		)
		(pad "BU50" smd circle
			(at 5.999988 11.649964 270)
			(size 0.3048 0.3048)
			(layers "F.Cu" "F.Mask" "F.Paste")
			(net "GND")
		)
		(pad "BU52" smd circle
			(at 6.999986 11.649964 270)
			(size 0.3048 0.3048)
			(layers "F.Cu" "F.Mask" "F.Paste")
			(net "GND")
		)
		(pad "BU54" smd circle
			(at 7.999984 11.649964 270)
			(size 0.3048 0.3048)
			(layers "F.Cu" "F.Mask" "F.Paste")
			(net "GND")
		)
		(pad "BU57" smd circle
			(at 8.999982 11.649964 270)
			(size 0.3048 0.3048)
			(layers "F.Cu" "F.Mask" "F.Paste")
			(net "GND")
		)
		(pad "BU59" smd circle
			(at 9.99998 11.649964 270)
			(size 0.3048 0.3048)
			(layers "F.Cu" "F.Mask" "F.Paste")
			(net "GND")
		)
		(pad "BU61" smd circle
			(at 10.999978 11.649964 270)
			(size 0.3048 0.3048)
			(layers "F.Cu" "F.Mask" "F.Paste")
			(net "GND")
		)
		(pad "BU63" smd circle
			(at 11.999976 11.649964 270)
			(size 0.3048 0.3048)
			(layers "F.Cu" "F.Mask" "F.Paste")
			(net "GND")
		)
		(pad "BU65" smd circle
			(at 12.999974 11.649964 270)
			(size 0.3048 0.3048)
			(layers "F.Cu" "F.Mask" "F.Paste")
			(net "TP_USB2_P10_DP")
		)
		(pad "BU67" smd circle
			(at 13.999972 11.649964 90)
			(size 0.3048 0.3048)
			(layers "F.Cu" "F.Mask" "F.Paste")
			(net "TP_USB2_P14_DP")
		)
		(pad "BU70" smd circle
			(at 15.580106 11.78433 90)
			(size 0.3556 0.3556)
			(layers "F.Cu" "F.Mask" "F.Paste")
			(net "GND")
		)
		(pad "BU72" smd circle
			(at 16.310102 11.689334 315)
			(size 0.4064 0.4064)
			(layers "F.Cu" "F.Mask" "F.Paste")
			(net "GND")
		)
		(pad "BV8" smd circle
			(at -13.5001 12.065 270)
			(size 0.3048 0.3048)
			(layers "F.Cu" "F.Mask" "F.Paste")
			(net "SMB_PCH_MEZZ_LOM1_SDA")
		)
		(pad "BV10" smd circle
			(at -12.500102 12.065 270)
			(size 0.3048 0.3048)
			(layers "F.Cu" "F.Mask" "F.Paste")
			(net "FM_GBE0_LVC3_MOD_ABS")
		)
		(pad "BV12" smd circle
			(at -11.500104 12.065 270)
			(size 0.3048 0.3048)
			(layers "F.Cu" "F.Mask" "F.Paste")
			(net "TP_PCH_GPP_J21")
		)
		(pad "BV14" smd circle
			(at -10.500106 12.065 270)
			(size 0.3048 0.3048)
			(layers "F.Cu" "F.Mask" "F.Paste")
			(net "TP_PCH_GPP_J23")
		)
		(pad "BV16" smd circle
			(at -9.500108 12.065 270)
			(size 0.3048 0.3048)
			(layers "F.Cu" "F.Mask" "F.Paste")
			(net "XTAL_KR_25M_IN")
		)
		(pad "BV19" smd circle
			(at -8.50011 12.065 270)
			(size 0.3048 0.3048)
			(layers "F.Cu" "F.Mask" "F.Paste")
			(net "RST_BMC_SYSRST_BTN_OUT_B_N")
		)
		(pad "BV21" smd circle
			(at -7.500112 12.065 270)
			(size 0.3048 0.3048)
			(layers "F.Cu" "F.Mask" "F.Paste")
			(net "JTAG_PCH_GBE_CLK")
		)
		(pad "BV23" smd circle
			(at -6.500114 12.065 270)
			(size 0.3048 0.3048)
			(layers "F.Cu" "F.Mask" "F.Paste")
			(net "FM_CPU1_RC_ERROR_R_N")
		)
		(pad "BV25" smd circle
			(at -5.500116 12.065 270)
			(size 0.3048 0.3048)
			(layers "F.Cu" "F.Mask" "F.Paste")
			(net "FM_BIOS_MRC_DEBUG_MSG_DIS_N")
		)
		(pad "BV27" smd circle
			(at -4.500118 12.065 270)
			(size 0.3048 0.3048)
			(layers "F.Cu" "F.Mask" "F.Paste")
			(net "SMB_HOST_STBY_LVC3_SDA_R1")
		)
		(pad "BV29" smd circle
			(at -3.50012 12.065 270)
			(size 0.3048 0.3048)
			(layers "F.Cu" "F.Mask" "F.Paste")
			(net "SMB_SMLINK0_STBY_LVC3_SCL_R1")
		)
		(pad "BV31" smd circle
			(at -2.500122 12.065 270)
			(size 0.3048 0.3048)
			(layers "F.Cu" "F.Mask" "F.Paste")
			(net "FM_PCH_SATA_RAID_KEY")
		)
		(pad "BV33" smd circle
			(at -1.500124 12.065 270)
			(size 0.3048 0.3048)
			(layers "F.Cu" "F.Mask" "F.Paste")
			(net "FM_BOARD_REV_ID2")
		)
		(pad "BV35" smd circle
			(at -0.500126 12.065 270)
			(size 0.3048 0.3048)
			(layers "F.Cu" "F.Mask" "F.Paste")
			(net "SMB_PMBUS_BMC_STBY_LVC3_SDA_R1")
		)
		(pad "BV38" smd circle
			(at 0.500126 12.065 270)
			(size 0.3048 0.3048)
			(layers "F.Cu" "F.Mask" "F.Paste")
			(net "FM_BOARD_REV_ID1")
		)
		(pad "BV40" smd circle
			(at 1.500124 12.065 270)
			(size 0.3048 0.3048)
			(layers "F.Cu" "F.Mask" "F.Paste")
			(net "GND")
		)
		(pad "BV42" smd circle
			(at 2.500122 12.065 270)
			(size 0.3048 0.3048)
			(layers "F.Cu" "F.Mask" "F.Paste")
			(net "IRQ_OOB_MGMT_RISER_ALERT_N")
		)
		(pad "BV44" smd circle
			(at 3.50012 12.065 270)
			(size 0.3048 0.3048)
			(layers "F.Cu" "F.Mask" "F.Paste")
			(net "Net_477")
		)
		(pad "BV47" smd circle
			(at 4.500118 12.065 270)
			(size 0.3048 0.3048)
			(layers "F.Cu" "F.Mask" "F.Paste")
			(net "H_CPU0_FAST_WAKE_LVT3_N")
		)
		(pad "BV49" smd circle
			(at 5.500116 12.065 270)
			(size 0.3048 0.3048)
			(layers "F.Cu" "F.Mask" "F.Paste")
			(net "GND")
		)
		(pad "BV51" smd circle
			(at 6.500114 12.065 270)
			(size 0.3048 0.3048)
			(layers "F.Cu" "F.Mask" "F.Paste")
			(net "TP_CLK_24M_PMSYNC2")
		)
		(pad "BV53" smd circle
			(at 7.500112 12.065 270)
			(size 0.3048 0.3048)
			(layers "F.Cu" "F.Mask" "F.Paste")
			(net "TP_USB2_P13_DP")
		)
		(pad "BV55" smd circle
			(at 8.50011 12.065 270)
			(size 0.3048 0.3048)
			(layers "F.Cu" "F.Mask" "F.Paste")
			(net "TP_USB2_P9_DP")
		)
		(pad "BV58" smd circle
			(at 9.500108 12.065 270)
			(size 0.3048 0.3048)
			(layers "F.Cu" "F.Mask" "F.Paste")
			(net "USB2_PCH_BMC_P5_DP_R")
		)
		(pad "BV60" smd circle
			(at 10.500106 12.065 270)
			(size 0.3048 0.3048)
			(layers "F.Cu" "F.Mask" "F.Paste")
			(net "USB2_P01_DP")
		)
		(pad "BV62" smd circle
			(at 11.500104 12.065 270)
			(size 0.3048 0.3048)
			(layers "F.Cu" "F.Mask" "F.Paste")
			(net "USB_PCH_BMC_P4_DP_R")
		)
		(pad "BV64" smd circle
			(at 12.500102 12.065 270)
			(size 0.3048 0.3048)
			(layers "F.Cu" "F.Mask" "F.Paste")
			(net "TP_USB2_P8_DP")
		)
		(pad "BV66" smd circle
			(at 13.5001 12.065 270)
			(size 0.3048 0.3048)
			(layers "F.Cu" "F.Mask" "F.Paste")
			(net "TP_USB2_P12_DP")
		)
		(pad "BW1" smd circle
			(at -16.310102 12.502134 225)
			(size 0.5588 0.5588)
			(layers "F.Cu" "F.Mask" "F.Paste")
			(net "GND")
		)
		(pad "BW3" smd circle
			(at -15.497302 12.497308 180)
			(size 0.4064 0.4064)
			(layers "F.Cu" "F.Mask" "F.Paste")
			(net "TP_PCH_RSVD46")
		)
		(pad "BW5" smd circle
			(at -14.784324 12.580112 90)
			(size 0.3556 0.3556)
			(layers "F.Cu" "F.Mask" "F.Paste")
			(net "SMB_PCH_MEZZ_LOM1_SCL")
		)
		(pad "BW6" smd circle
			(at -13.999972 12.580112 90)
			(size 0.3556 0.3556)
			(layers "F.Cu" "F.Mask" "F.Paste")
			(net "SMB_PCH_MEZZ_LOM3_SCL")
		)
		(pad "BW9" smd circle
			(at -12.999974 12.480036 270)
			(size 0.3048 0.3048)
			(layers "F.Cu" "F.Mask" "F.Paste")
			(net "SMB_PCH_MEZZ_LOM3_SDA")
		)
		(pad "BW11" smd circle
			(at -11.999976 12.480036 270)
			(size 0.3048 0.3048)
			(layers "F.Cu" "F.Mask" "F.Paste")
			(net "SMB_PCH_MEZZ_LOM2_SDA")
		)
		(pad "BW13" smd circle
			(at -10.999978 12.480036 270)
			(size 0.3048 0.3048)
			(layers "F.Cu" "F.Mask" "F.Paste")
			(net "FM_GBE2_LVC3_MOD_ABS")
		)
		(pad "BW15" smd circle
			(at -9.99998 12.480036 270)
			(size 0.3048 0.3048)
			(layers "F.Cu" "F.Mask" "F.Paste")
			(net "GND")
		)
		(pad "BW18" smd circle
			(at -8.999982 12.480036 270)
			(size 0.3048 0.3048)
			(layers "F.Cu" "F.Mask" "F.Paste")
			(net "GND")
		)
		(pad "BW20" smd circle
			(at -7.999984 12.480036 270)
			(size 0.3048 0.3048)
			(layers "F.Cu" "F.Mask" "F.Paste")
			(net "IRQ_DIMM_SAVE_LVT3_R_N")
		)
		(pad "BW22" smd circle
			(at -6.999986 12.480036 270)
			(size 0.3048 0.3048)
			(layers "F.Cu" "F.Mask" "F.Paste")
			(net "PU_10GBE_LOM_PCI_DISABLE_N")
		)
		(pad "BW24" smd circle
			(at -5.999988 12.480036 270)
			(size 0.3048 0.3048)
			(layers "F.Cu" "F.Mask" "F.Paste")
			(net "IRQ_BOARD_BMC_ALERT_N")
		)
		(pad "BW26" smd circle
			(at -4.99999 12.480036 270)
			(size 0.3048 0.3048)
			(layers "F.Cu" "F.Mask" "F.Paste")
			(net "GND")
		)
		(pad "BW28" smd circle
			(at -3.999992 12.480036 270)
			(size 0.3048 0.3048)
			(layers "F.Cu" "F.Mask" "F.Paste")
			(net "SMB_HOST_STBY_LVC3_SCL_R1")
		)
		(pad "BW30" smd circle
			(at -2.999994 12.480036 270)
			(size 0.3048 0.3048)
			(layers "F.Cu" "F.Mask" "F.Paste")
			(net "SMB_SMLINK0_STBY_LVC3_SDA_R1")
		)
		(pad "BW32" smd circle
			(at -1.999996 12.480036 270)
			(size 0.3048 0.3048)
			(layers "F.Cu" "F.Mask" "F.Paste")
			(net "FM_PASSWORD_CLEAR_N")
		)
		(pad "BW34" smd circle
			(at -0.999998 12.480036 270)
			(size 0.3048 0.3048)
			(layers "F.Cu" "F.Mask" "F.Paste")
			(net "IRQ_SML0_ALERT_N")
		)
		(pad "BW37" smd circle
			(at 0 12.480036 270)
			(size 0.3048 0.3048)
			(layers "F.Cu" "F.Mask" "F.Paste")
			(net "FM_SLT_CFG1")
		)
		(pad "BW39" smd circle
			(at 0.999998 12.480036 270)
			(size 0.3048 0.3048)
			(layers "F.Cu" "F.Mask" "F.Paste")
			(net "FM_BB_BMC_MP_GPIO")
		)
		(pad "BW41" smd circle
			(at 1.999996 12.480036 270)
			(size 0.3048 0.3048)
			(layers "F.Cu" "F.Mask" "F.Paste")
			(net "FM_CPLD_BMC_PWRDN_N")
		)
		(pad "BW43" smd circle
			(at 2.999994 12.480036 270)
			(size 0.3048 0.3048)
			(layers "F.Cu" "F.Mask" "F.Paste")
			(net "SGPIO_PCH_SSATA_DOUT0")
		)
		(pad "BW45" smd circle
			(at 3.999992 12.480036 270)
			(size 0.3048 0.3048)
			(layers "F.Cu" "F.Mask" "F.Paste")
			(net "IRQ_MEZZ_LAN_ALERT_N")
		)
		(pad "BW48" smd circle
			(at 4.99999 12.480036 270)
			(size 0.3048 0.3048)
			(layers "F.Cu" "F.Mask" "F.Paste")
			(net "FM_XRC_PRESENT_N")
		)
		(pad "BW50" smd circle
			(at 5.999988 12.480036 270)
			(size 0.3048 0.3048)
			(layers "F.Cu" "F.Mask" "F.Paste")
			(net "CLK_48M_USB_BMC")
		)
		(pad "BW52" smd circle
			(at 6.999986 12.480036 270)
			(size 0.3048 0.3048)
			(layers "F.Cu" "F.Mask" "F.Paste")
			(net "GND")
		)
		(pad "BW54" smd circle
			(at 7.999984 12.480036 270)
			(size 0.3048 0.3048)
			(layers "F.Cu" "F.Mask" "F.Paste")
			(net "TP_USB2_P11_DP")
		)
		(pad "BW57" smd circle
			(at 8.999982 12.480036 270)
			(size 0.3048 0.3048)
			(layers "F.Cu" "F.Mask" "F.Paste")
			(net "TP_USB2_P07_DP")
		)
		(pad "BW59" smd circle
			(at 9.99998 12.480036 270)
			(size 0.3048 0.3048)
			(layers "F.Cu" "F.Mask" "F.Paste")
			(net "TP_USB2_P03_DP")
		)
		(pad "BW61" smd circle
			(at 10.999978 12.480036 270)
			(size 0.3048 0.3048)
			(layers "F.Cu" "F.Mask" "F.Paste")
			(net "USB2_P02_DP_R")
		)
		(pad "BW63" smd circle
			(at 11.999976 12.480036 270)
			(size 0.3048 0.3048)
			(layers "F.Cu" "F.Mask" "F.Paste")
			(net "TP_USB2_P06_DP")
		)
		(pad "BW65" smd circle
			(at 12.999974 12.480036 270)
			(size 0.3048 0.3048)
			(layers "F.Cu" "F.Mask" "F.Paste")
			(net "TP_USB2_P10_DN")
		)
		(pad "BW67" smd circle
			(at 13.999972 12.580112 90)
			(size 0.3556 0.3556)
			(layers "F.Cu" "F.Mask" "F.Paste")
			(net "TP_USB2_P12_DN")
		)
		(pad "BW68" smd circle
			(at 14.784324 12.580112 90)
			(size 0.3556 0.3556)
			(layers "F.Cu" "F.Mask" "F.Paste")
			(net "TP_USB2_P14_DN")
		)
		(pad "BW70" smd circle
			(at 15.497302 12.497308 315)
			(size 0.4064 0.4064)
			(layers "F.Cu" "F.Mask" "F.Paste")
			(net "GND")
		)
		(pad "BW72" smd circle
			(at 16.310102 12.502134 315)
			(size 0.5588 0.5588)
			(layers "F.Cu" "F.Mask" "F.Paste")
			(net "GND")
		)
		(pad "BY10" smd circle
			(at -12.500102 12.895072 270)
			(size 0.3048 0.3048)
			(layers "F.Cu" "F.Mask" "F.Paste")
			(net "FM_GBE1_LVC3_MOD_ABS")
		)
		(pad "BY12" smd circle
			(at -11.500104 12.895072 270)
			(size 0.3048 0.3048)
			(layers "F.Cu" "F.Mask" "F.Paste")
			(net "FM_GBE3_LVC3_MOD_ABS")
		)
		(pad "BY14" smd circle
			(at -10.500106 12.895072 270)
			(size 0.3048 0.3048)
			(layers "F.Cu" "F.Mask" "F.Paste")
			(net "TP_PCH_GPP_J19")
		)
		(pad "BY16" smd circle
			(at -9.500108 12.895072 270)
			(size 0.3048 0.3048)
			(layers "F.Cu" "F.Mask" "F.Paste")
			(net "XTAL_KR_25M_OUT")
		)
		(pad "BY19" smd circle
			(at -8.50011 12.895072 270)
			(size 0.3048 0.3048)
			(layers "F.Cu" "F.Mask" "F.Paste")
			(net "PWRGD_SYS_PWROK")
		)
		(pad "BY21" smd circle
			(at -7.500112 12.895072 270)
			(size 0.3048 0.3048)
			(layers "F.Cu" "F.Mask" "F.Paste")
			(net "FM_10GBE_LOM_DISABLE_N")
		)
		(pad "BY23" smd circle
			(at -6.500114 12.895072 270)
			(size 0.3048 0.3048)
			(layers "F.Cu" "F.Mask" "F.Paste")
			(net "JTAG_PCH_GBE_TDI")
		)
		(pad "BY25" smd circle
			(at -5.500116 12.895072 270)
			(size 0.3048 0.3048)
			(layers "F.Cu" "F.Mask" "F.Paste")
			(net "A_RCOMP_3P3")
		)
		(pad "BY27" smd circle
			(at -4.500118 12.895072 270)
			(size 0.3048 0.3048)
			(layers "F.Cu" "F.Mask" "F.Paste")
			(net "PU_PCH_TLS_ENABLE_STRAP")
		)
		(pad "BY29" smd circle
			(at -3.50012 12.895072 270)
			(size 0.3048 0.3048)
			(layers "F.Cu" "F.Mask" "F.Paste")
			(net "FM_CPU1_RC_EN")
		)
		(pad "BY31" smd circle
			(at -2.500122 12.895072 270)
			(size 0.3048 0.3048)
			(layers "F.Cu" "F.Mask" "F.Paste")
			(net "FM_SLT_CFG2_R")
		)
		(pad "BY33" smd circle
			(at -1.500124 12.895072 270)
			(size 0.3048 0.3048)
			(layers "F.Cu" "F.Mask" "F.Paste")
			(net "FM_BIOS_POST_CMPLT_N")
		)
		(pad "BY35" smd circle
			(at -0.500126 12.895072 270)
			(size 0.3048 0.3048)
			(layers "F.Cu" "F.Mask" "F.Paste")
			(net "FM_PMBUS_ALERT_BUF_EN_R_N")
		)
		(pad "BY38" smd circle
			(at 0.500126 12.895072 270)
			(size 0.3048 0.3048)
			(layers "F.Cu" "F.Mask" "F.Paste")
			(net "IRQ_BMC_PCH_SCI_LPC_N")
		)
		(pad "BY40" smd circle
			(at 1.500124 12.895072 270)
			(size 0.3048 0.3048)
			(layers "F.Cu" "F.Mask" "F.Paste")
			(net "GND")
		)
		(pad "BY42" smd circle
			(at 2.500122 12.895072 270)
			(size 0.3048 0.3048)
			(layers "F.Cu" "F.Mask" "F.Paste")
			(net "IRQ_FORCE_NM_THROTTLE_N")
		)
		(pad "BY44" smd circle
			(at 3.50012 12.895072 270)
			(size 0.3048 0.3048)
			(layers "F.Cu" "F.Mask" "F.Paste")
			(net "SMB_SLOTX24_PCH_STBY_LVC3_SCL")
		)
		(pad "BY47" smd circle
			(at 4.500118 12.895072 270)
			(size 0.3048 0.3048)
			(layers "F.Cu" "F.Mask" "F.Paste")
			(net "IRQ_LOM_ALERT_N")
		)
		(pad "BY49" smd circle
			(at 5.500116 12.895072 270)
			(size 0.3048 0.3048)
			(layers "F.Cu" "F.Mask" "F.Paste")
			(net "GND")
		)
		(pad "BY51" smd circle
			(at 6.500114 12.895072 270)
			(size 0.3048 0.3048)
			(layers "F.Cu" "F.Mask" "F.Paste")
			(net "H_PMSYNC_CLK_24M_R")
		)
		(pad "BY53" smd circle
			(at 7.500112 12.895072 270)
			(size 0.3048 0.3048)
			(layers "F.Cu" "F.Mask" "F.Paste")
			(net "TP_USB2_P13_DN")
		)
		(pad "BY55" smd circle
			(at 8.50011 12.895072 270)
			(size 0.3048 0.3048)
			(layers "F.Cu" "F.Mask" "F.Paste")
			(net "TP_USB2_P9_DN")
		)
		(pad "BY58" smd circle
			(at 9.500108 12.895072 270)
			(size 0.3048 0.3048)
			(layers "F.Cu" "F.Mask" "F.Paste")
			(net "USB2_PCH_BMC_P5_DN_R")
		)
		(pad "BY60" smd circle
			(at 10.500106 12.895072 270)
			(size 0.3048 0.3048)
			(layers "F.Cu" "F.Mask" "F.Paste")
			(net "USB2_P01_DN")
		)
		(pad "BY62" smd circle
			(at 11.500104 12.895072 270)
			(size 0.3048 0.3048)
			(layers "F.Cu" "F.Mask" "F.Paste")
			(net "USB_PCH_BMC_P4_DN_R")
		)
		(pad "BY64" smd circle
			(at 12.500102 12.895072 270)
			(size 0.3048 0.3048)
			(layers "F.Cu" "F.Mask" "F.Paste")
			(net "TP_USB2_P8_DN")
		)
		(pad "C3" smd circle
			(at -15.497302 -12.497308 135)
			(size 0.4064 0.4064)
			(layers "F.Cu" "F.Mask" "F.Paste")
			(net "GND")
		)
		(pad "C5" smd circle
			(at -14.784324 -12.580112 90)
			(size 0.3556 0.3556)
			(layers "F.Cu" "F.Mask" "F.Paste")
			(net "TP_PCH_RSVD16")
		)
		(pad "C6" smd circle
			(at -13.999972 -12.580112 90)
			(size 0.3556 0.3556)
			(layers "F.Cu" "F.Mask" "F.Paste")
			(net "TP_PCH_RSVD15")
		)
		(pad "C9" smd circle
			(at -12.999974 -12.480036 90)
			(size 0.3048 0.3048)
			(layers "F.Cu" "F.Mask" "F.Paste")
			(net "TP_PCH_RSVD19")
		)
		(pad "C11" smd circle
			(at -11.999976 -12.480036 90)
			(size 0.3048 0.3048)
			(layers "F.Cu" "F.Mask" "F.Paste")
			(net "TP_PCH_RSVD18")
		)
		(pad "C13" smd circle
			(at -10.999978 -12.480036 90)
			(size 0.3048 0.3048)
			(layers "F.Cu" "F.Mask" "F.Paste")
			(net "TP_PCH_GDP8_SUSCLK")
		)
		(pad "C15" smd circle
			(at -9.99998 -12.480036 90)
			(size 0.3048 0.3048)
			(layers "F.Cu" "F.Mask" "F.Paste")
			(net "FM_PCH_PWRBTN_N")
		)
		(pad "C18" smd circle
			(at -8.999982 -12.480036 90)
			(size 0.3048 0.3048)
			(layers "F.Cu" "F.Mask" "F.Paste")
			(net "FM_SINT_PRSNT_N")
		)
		(pad "C20" smd circle
			(at -7.999984 -12.480036 90)
			(size 0.3048 0.3048)
			(layers "F.Cu" "F.Mask" "F.Paste")
			(net "CLK_100M_SPRV_DN")
		)
		(pad "C22" smd circle
			(at -6.999986 -12.480036 90)
			(size 0.3048 0.3048)
			(layers "F.Cu" "F.Mask" "F.Paste")
			(net "GND")
		)
		(pad "C24" smd circle
			(at -5.999988 -12.480036 90)
			(size 0.3048 0.3048)
			(layers "F.Cu" "F.Mask" "F.Paste")
			(net "Net_3")
		)
		(pad "C26" smd circle
			(at -4.99999 -12.480036 90)
			(size 0.3048 0.3048)
			(layers "F.Cu" "F.Mask" "F.Paste")
			(net "TP_PCH_RSVD64")
		)
		(pad "C28" smd circle
			(at -3.999992 -12.480036 90)
			(size 0.3048 0.3048)
			(layers "F.Cu" "F.Mask" "F.Paste")
			(net "CLK_100M_PCH_SLOTX24_S2_DP")
		)
		(pad "C30" smd circle
			(at -2.999994 -12.480036 90)
			(size 0.3048 0.3048)
			(layers "F.Cu" "F.Mask" "F.Paste")
			(net "GND")
		)
		(pad "C32" smd circle
			(at -1.999996 -12.480036 90)
			(size 0.3048 0.3048)
			(layers "F.Cu" "F.Mask" "F.Paste")
			(net "TP_CLK_100M_NSSCC0_DP")
		)
		(pad "C34" smd circle
			(at -0.999998 -12.480036 90)
			(size 0.3048 0.3048)
			(layers "F.Cu" "F.Mask" "F.Paste")
			(net "GND")
		)
		(pad "C37" smd circle
			(at 0 -12.480036 90)
			(size 0.3048 0.3048)
			(layers "F.Cu" "F.Mask" "F.Paste")
			(net "GND")
		)
		(pad "C39" smd circle
			(at 0.999998 -12.480036 90)
			(size 0.3048 0.3048)
			(layers "F.Cu" "F.Mask" "F.Paste")
			(net "CLK_100M_PCH_XDP_DP")
		)
		(pad "C41" smd circle
			(at 1.999996 -12.480036 90)
			(size 0.3048 0.3048)
			(layers "F.Cu" "F.Mask" "F.Paste")
			(net "GND")
		)
		(pad "C43" smd circle
			(at 2.999994 -12.480036 90)
			(size 0.3048 0.3048)
			(layers "F.Cu" "F.Mask" "F.Paste")
			(net "DMI_CPU0_PCH_TX_C_DN<1>")
		)
		(pad "C45" smd circle
			(at 3.999992 -12.480036 90)
			(size 0.3048 0.3048)
			(layers "F.Cu" "F.Mask" "F.Paste")
			(net "DMI_CPU0_PCH_TX_C_DN<3>")
		)
		(pad "C48" smd circle
			(at 4.99999 -12.480036 90)
			(size 0.3048 0.3048)
			(layers "F.Cu" "F.Mask" "F.Paste")
			(net "P3E_CPU0_PE1_PCH_TXN<0>")
		)
		(pad "C50" smd circle
			(at 5.999988 -12.480036 90)
			(size 0.3048 0.3048)
			(layers "F.Cu" "F.Mask" "F.Paste")
			(net "P3E_CPU0_PE1_PCH_TXN<2>")
		)
		(pad "C52" smd circle
			(at 6.999986 -12.480036 90)
			(size 0.3048 0.3048)
			(layers "F.Cu" "F.Mask" "F.Paste")
			(net "P3E_CPU0_PE1_PCH_TXN<4>")
		)
		(pad "C54" smd circle
			(at 7.999984 -12.480036 90)
			(size 0.3048 0.3048)
			(layers "F.Cu" "F.Mask" "F.Paste")
			(net "P3E_CPU0_PE1_PCH_TXN<6>")
		)
		(pad "C57" smd circle
			(at 8.999982 -12.480036 90)
			(size 0.3048 0.3048)
			(layers "F.Cu" "F.Mask" "F.Paste")
			(net "P3E_CPU0_PE1_PCH_C_TXP<8>")
		)
		(pad "C59" smd circle
			(at 9.99998 -12.480036 90)
			(size 0.3048 0.3048)
			(layers "F.Cu" "F.Mask" "F.Paste")
			(net "P3E_CPU0_PE1_PCH_C_TXP<10>")
		)
		(pad "C61" smd circle
			(at 10.999978 -12.480036 90)
			(size 0.3048 0.3048)
			(layers "F.Cu" "F.Mask" "F.Paste")
			(net "P3E_CPU0_PE1_PCH_C_TXP<12>")
		)
		(pad "C63" smd circle
			(at 11.999976 -12.480036 90)
			(size 0.3048 0.3048)
			(layers "F.Cu" "F.Mask" "F.Paste")
			(net "P3E_CPU0_PE1_PCH_C_TXP<14>")
		)
		(pad "C65" smd circle
			(at 12.999974 -12.480036 90)
			(size 0.3048 0.3048)
			(layers "F.Cu" "F.Mask" "F.Paste")
			(net "GND")
		)
		(pad "C67" smd circle
			(at 13.999972 -12.580112 90)
			(size 0.3556 0.3556)
			(layers "F.Cu" "F.Mask" "F.Paste")
			(net "TP_PCH_RSVD13")
		)
		(pad "C68" smd circle
			(at 14.784324 -12.580112 90)
			(size 0.3556 0.3556)
			(layers "F.Cu" "F.Mask" "F.Paste")
			(net "TP_PCH_RSVD12")
		)
		(pad "C70" smd circle
			(at 15.497302 -12.497308 45)
			(size 0.4064 0.4064)
			(layers "F.Cu" "F.Mask" "F.Paste")
			(net "FM_PCH_PRSNT_N")
		)
		(pad "C72" smd circle
			(at 16.310102 -12.502134 45)
			(size 0.5588 0.5588)
			(layers "F.Cu" "F.Mask" "F.Paste")
			(net "GND")
		)
		(pad "CA3" smd circle
			(at -15.502128 13.310108 225)
			(size 0.5588 0.5588)
			(layers "F.Cu" "F.Mask" "F.Paste")
			(net "GND")
		)
		(pad "CA5" smd circle
			(at -14.689328 13.310108 225)
			(size 0.4064 0.4064)
			(layers "F.Cu" "F.Mask" "F.Paste")
			(net "GND")
		)
		(pad "CA7" smd circle
			(at -13.876528 13.310108 225)
			(size 0.4064 0.4064)
			(layers "F.Cu" "F.Mask" "F.Paste")
			(net "GND")
		)
		(pad "CA9" smd circle
			(at -13.063728 13.310108 90)
			(size 0.3556 0.3556)
			(layers "F.Cu" "F.Mask" "F.Paste")
			(net "GND")
		)
		(pad "CA11" smd oval
			(at -11.999976 13.310108 90)
			(size 0.254 0.3302)
			(layers "F.Cu" "F.Mask" "F.Paste")
			(net "TP_PCH_GPP_J17")
		)
		(pad "CA13" smd oval
			(at -10.999978 13.310108 90)
			(size 0.254 0.3302)
			(layers "F.Cu" "F.Mask" "F.Paste")
			(net "LED_GBE_P3_0")
		)
		(pad "CA15" smd oval
			(at -9.99998 13.310108 90)
			(size 0.254 0.3302)
			(layers "F.Cu" "F.Mask" "F.Paste")
			(net "GND")
		)
		(pad "CA18" smd oval
			(at -8.999982 13.310108 90)
			(size 0.254 0.3302)
			(layers "F.Cu" "F.Mask" "F.Paste")
			(net "GND")
		)
		(pad "CA20" smd oval
			(at -7.999984 13.310108 90)
			(size 0.254 0.3302)
			(layers "F.Cu" "F.Mask" "F.Paste")
			(net "JTAG_PCH_GBE_TDO")
		)
		(pad "CA22" smd oval
			(at -6.999986 13.310108 90)
			(size 0.254 0.3302)
			(layers "F.Cu" "F.Mask" "F.Paste")
			(net "JTAG_PCH_GBE_TMS")
		)
		(pad "CA24" smd oval
			(at -5.999988 13.310108 90)
			(size 0.254 0.3302)
			(layers "F.Cu" "F.Mask" "F.Paste")
			(net "JTAG_PCH_GBE_TRST_N")
		)
		(pad "CA26" smd oval
			(at -4.99999 13.310108 90)
			(size 0.254 0.3302)
			(layers "F.Cu" "F.Mask" "F.Paste")
			(net "GND")
		)
		(pad "CA28" smd oval
			(at -3.999992 13.310108 90)
			(size 0.254 0.3302)
			(layers "F.Cu" "F.Mask" "F.Paste")
			(net "SMB_PMBUS_BMC_STBY_LVC3_SCL_R1")
		)
		(pad "CA30" smd oval
			(at -2.999994 13.310108 90)
			(size 0.254 0.3302)
			(layers "F.Cu" "F.Mask" "F.Paste")
			(net "FM_BOARD_REV_ID0")
		)
		(pad "CA32" smd oval
			(at -1.999996 13.310108 90)
			(size 0.254 0.3302)
			(layers "F.Cu" "F.Mask" "F.Paste")
			(net "FM_SLT_CFG0")
		)
		(pad "CA34" smd oval
			(at -0.999998 13.310108 90)
			(size 0.254 0.3302)
			(layers "F.Cu" "F.Mask" "F.Paste")
			(net "IRQ_BMC_PCH_SMI_LPC_N")
		)
		(pad "CA37" smd oval
			(at 0 13.310108 90)
			(size 0.254 0.3302)
			(layers "F.Cu" "F.Mask" "F.Paste")
			(net "FM_CPU_CATERR_DLY_LVT3_R_N")
		)
		(pad "CA39" smd oval
			(at 0.999998 13.310108 90)
			(size 0.254 0.3302)
			(layers "F.Cu" "F.Mask" "F.Paste")
			(net "FM_THROTTLE_R2_N")
		)
		(pad "CA41" smd oval
			(at 1.999996 13.310108 90)
			(size 0.254 0.3302)
			(layers "F.Cu" "F.Mask" "F.Paste")
			(net "FM_XRC_READY_N")
		)
		(pad "CA43" smd oval
			(at 2.999994 13.310108 90)
			(size 0.254 0.3302)
			(layers "F.Cu" "F.Mask" "F.Paste")
			(net "FM_ADR_MODE_SEL_R")
		)
		(pad "CA45" smd oval
			(at 3.999992 13.310108 90)
			(size 0.254 0.3302)
			(layers "F.Cu" "F.Mask" "F.Paste")
			(net "FM_BMC_CPLD_GPO")
		)
		(pad "CA48" smd oval
			(at 4.99999 13.310108 90)
			(size 0.254 0.3302)
			(layers "F.Cu" "F.Mask" "F.Paste")
			(net "FM_BMC_HEARTBEAT_N")
		)
		(pad "CA50" smd oval
			(at 5.999988 13.310108 90)
			(size 0.254 0.3302)
			(layers "F.Cu" "F.Mask" "F.Paste")
			(net "GND")
		)
		(pad "CA52" smd oval
			(at 6.999986 13.310108 90)
			(size 0.254 0.3302)
			(layers "F.Cu" "F.Mask" "F.Paste")
			(net "GND")
		)
		(pad "CA54" smd oval
			(at 7.999984 13.310108 90)
			(size 0.254 0.3302)
			(layers "F.Cu" "F.Mask" "F.Paste")
			(net "TP_USB2_P11_DN")
		)
		(pad "CA57" smd oval
			(at 8.999982 13.310108 90)
			(size 0.254 0.3302)
			(layers "F.Cu" "F.Mask" "F.Paste")
			(net "TP_USB2_P07_DN")
		)
		(pad "CA59" smd oval
			(at 9.99998 13.310108 90)
			(size 0.254 0.3302)
			(layers "F.Cu" "F.Mask" "F.Paste")
			(net "TP_USB2_P03_DN")
		)
		(pad "CA61" smd oval
			(at 10.999978 13.310108 90)
			(size 0.254 0.3302)
			(layers "F.Cu" "F.Mask" "F.Paste")
			(net "USB2_P02_DN_R")
		)
		(pad "CA63" smd oval
			(at 11.999976 13.310108 90)
			(size 0.254 0.3302)
			(layers "F.Cu" "F.Mask" "F.Paste")
			(net "TP_USB2_P06_DN")
		)
		(pad "CA65" smd circle
			(at 13.063728 13.310108 90)
			(size 0.3556 0.3556)
			(layers "F.Cu" "F.Mask" "F.Paste")
			(net "GND")
		)
		(pad "CA66" smd circle
			(at 13.876528 13.310108 315)
			(size 0.4064 0.4064)
			(layers "F.Cu" "F.Mask" "F.Paste")
			(net "GND")
		)
		(pad "CA68" smd circle
			(at 14.689328 13.310108 315)
			(size 0.4064 0.4064)
			(layers "F.Cu" "F.Mask" "F.Paste")
			(net "GND")
		)
		(pad "CA70" smd circle
			(at 15.502128 13.310108 315)
			(size 0.5588 0.5588)
			(layers "F.Cu" "F.Mask" "F.Paste")
			(net "GND")
		)
		(pad "D8" smd circle
			(at -13.5001 -12.065 90)
			(size 0.3048 0.3048)
			(layers "F.Cu" "F.Mask" "F.Paste")
			(net "FM_WBG_PRSNT_N")
		)
		(pad "D10" smd circle
			(at -12.500102 -12.065 90)
			(size 0.3048 0.3048)
			(layers "F.Cu" "F.Mask" "F.Paste")
			(net "TP_PCH_RSVD20")
		)
		(pad "D12" smd circle
			(at -11.500104 -12.065 90)
			(size 0.3048 0.3048)
			(layers "F.Cu" "F.Mask" "F.Paste")
			(net "GND")
		)
		(pad "D14" smd circle
			(at -10.500106 -12.065 90)
			(size 0.3048 0.3048)
			(layers "F.Cu" "F.Mask" "F.Paste")
			(net "FM_SLPS3_R_N")
		)
		(pad "D16" smd circle
			(at -9.500108 -12.065 90)
			(size 0.3048 0.3048)
			(layers "F.Cu" "F.Mask" "F.Paste")
			(net "GND")
		)
		(pad "D19" smd circle
			(at -8.50011 -12.065 90)
			(size 0.3048 0.3048)
			(layers "F.Cu" "F.Mask" "F.Paste")
			(net "GND")
		)
		(pad "D21" smd circle
			(at -7.500112 -12.065 90)
			(size 0.3048 0.3048)
			(layers "F.Cu" "F.Mask" "F.Paste")
			(net "CLK_100M_MEZZ4_DP")
		)
		(pad "D23" smd circle
			(at -6.500114 -12.065 90)
			(size 0.3048 0.3048)
			(layers "F.Cu" "F.Mask" "F.Paste")
			(net "CLK_100M_MEZZ3_DP")
		)
		(pad "D25" smd circle
			(at -5.500116 -12.065 90)
			(size 0.3048 0.3048)
			(layers "F.Cu" "F.Mask" "F.Paste")
			(net "GND")
		)
		(pad "D27" smd circle
			(at -4.500118 -12.065 90)
			(size 0.3048 0.3048)
			(layers "F.Cu" "F.Mask" "F.Paste")
			(net "GND")
		)
		(pad "D29" smd circle
			(at -3.50012 -12.065 90)
			(size 0.3048 0.3048)
			(layers "F.Cu" "F.Mask" "F.Paste")
			(net "CLK_100M_BMC_PE_DP")
		)
		(pad "D31" smd circle
			(at -2.500122 -12.065 90)
			(size 0.3048 0.3048)
			(layers "F.Cu" "F.Mask" "F.Paste")
			(net "CLK_100M_MEZZ1_DN")
		)
		(pad "D33" smd circle
			(at -1.500124 -12.065 90)
			(size 0.3048 0.3048)
			(layers "F.Cu" "F.Mask" "F.Paste")
			(net "CLK_100M_PCH_SLOTX24_S4_DN")
		)
		(pad "D35" smd circle
			(at -0.500126 -12.065 90)
			(size 0.3048 0.3048)
			(layers "F.Cu" "F.Mask" "F.Paste")
			(net "XTAL_PCH_48M_OUT")
		)
		(pad "D38" smd circle
			(at 0.500126 -12.065 90)
			(size 0.3048 0.3048)
			(layers "F.Cu" "F.Mask" "F.Paste")
			(net "TP_CLK_100M_NSSCC1_DP")
		)
		(pad "D40" smd circle
			(at 1.500124 -12.065 90)
			(size 0.3048 0.3048)
			(layers "F.Cu" "F.Mask" "F.Paste")
			(net "TP_CLK_100M_PLAT1_DP")
		)
		(pad "D42" smd circle
			(at 2.500122 -12.065 90)
			(size 0.3048 0.3048)
			(layers "F.Cu" "F.Mask" "F.Paste")
			(net "DMI_CPU0_PCH_TX_C_DN<0>")
		)
		(pad "D44" smd circle
			(at 3.50012 -12.065 90)
			(size 0.3048 0.3048)
			(layers "F.Cu" "F.Mask" "F.Paste")
			(net "DMI_CPU0_PCH_TX_C_DN<2>")
		)
		(pad "D47" smd circle
			(at 4.500118 -12.065 90)
			(size 0.3048 0.3048)
			(layers "F.Cu" "F.Mask" "F.Paste")
			(net "GND")
		)
		(pad "D49" smd circle
			(at 5.500116 -12.065 90)
			(size 0.3048 0.3048)
			(layers "F.Cu" "F.Mask" "F.Paste")
			(net "P3E_CPU0_PE1_PCH_TXN<1>")
		)
		(pad "D51" smd circle
			(at 6.500114 -12.065 90)
			(size 0.3048 0.3048)
			(layers "F.Cu" "F.Mask" "F.Paste")
			(net "P3E_CPU0_PE1_PCH_TXN<3>")
		)
		(pad "D53" smd circle
			(at 7.500112 -12.065 90)
			(size 0.3048 0.3048)
			(layers "F.Cu" "F.Mask" "F.Paste")
			(net "P3E_CPU0_PE1_PCH_TXN<5>")
		)
		(pad "D55" smd circle
			(at 8.50011 -12.065 90)
			(size 0.3048 0.3048)
			(layers "F.Cu" "F.Mask" "F.Paste")
			(net "P3E_CPU0_PE1_PCH_TXN<7>")
		)
		(pad "D58" smd circle
			(at 9.500108 -12.065 90)
			(size 0.3048 0.3048)
			(layers "F.Cu" "F.Mask" "F.Paste")
			(net "P3E_CPU0_PE1_PCH_C_TXP<9>")
		)
		(pad "D60" smd circle
			(at 10.500106 -12.065 90)
			(size 0.3048 0.3048)
			(layers "F.Cu" "F.Mask" "F.Paste")
			(net "P3E_CPU0_PE1_PCH_C_TXN<11>")
		)
		(pad "D62" smd circle
			(at 11.500104 -12.065 90)
			(size 0.3048 0.3048)
			(layers "F.Cu" "F.Mask" "F.Paste")
			(net "P3E_CPU0_PE1_PCH_C_TXP<13>")
		)
		(pad "D64" smd circle
			(at 12.500102 -12.065 90)
			(size 0.3048 0.3048)
			(layers "F.Cu" "F.Mask" "F.Paste")
			(net "P3E_CPU0_PE1_PCH_C_TXP<15>")
		)
		(pad "D66" smd circle
			(at 13.5001 -12.065 90)
			(size 0.3048 0.3048)
			(layers "F.Cu" "F.Mask" "F.Paste")
			(net "A_EXTCLKN")
		)
		(pad "E1" smd circle
			(at -16.310102 -11.689334 135)
			(size 0.4064 0.4064)
			(layers "F.Cu" "F.Mask" "F.Paste")
			(net "GND")
		)
		(pad "E3" smd circle
			(at -15.580106 -11.78433 90)
			(size 0.3556 0.3556)
			(layers "F.Cu" "F.Mask" "F.Paste")
			(net "GND")
		)
		(pad "E6" smd circle
			(at -14.100048 -11.700002 90)
			(size 0.3048 0.3048)
			(layers "F.Cu" "F.Mask" "F.Paste")
			(net "GND")
		)
		(pad "E9" smd circle
			(at -12.999974 -11.649964 90)
			(size 0.3048 0.3048)
			(layers "F.Cu" "F.Mask" "F.Paste")
			(net "GND")
		)
		(pad "E11" smd circle
			(at -11.999976 -11.649964 90)
			(size 0.3048 0.3048)
			(layers "F.Cu" "F.Mask" "F.Paste")
			(net "GND")
		)
		(pad "E13" smd circle
			(at -10.999978 -11.649964 90)
			(size 0.3048 0.3048)
			(layers "F.Cu" "F.Mask" "F.Paste")
			(net "GND")
		)
		(pad "E15" smd circle
			(at -9.99998 -11.649964 90)
			(size 0.3048 0.3048)
			(layers "F.Cu" "F.Mask" "F.Paste")
			(net "GND")
		)
		(pad "E18" smd circle
			(at -8.999982 -11.649964 90)
			(size 0.3048 0.3048)
			(layers "F.Cu" "F.Mask" "F.Paste")
			(net "TP_PCH_RSVD14")
		)
		(pad "E20" smd circle
			(at -7.999984 -11.649964 90)
			(size 0.3048 0.3048)
			(layers "F.Cu" "F.Mask" "F.Paste")
			(net "GND")
		)
		(pad "E22" smd circle
			(at -6.999986 -11.649964 90)
			(size 0.3048 0.3048)
			(layers "F.Cu" "F.Mask" "F.Paste")
			(net "GND")
		)
		(pad "E24" smd circle
			(at -5.999988 -11.649964 90)
			(size 0.3048 0.3048)
			(layers "F.Cu" "F.Mask" "F.Paste")
			(net "GND")
		)
		(pad "E26" smd circle
			(at -4.99999 -11.649964 90)
			(size 0.3048 0.3048)
			(layers "F.Cu" "F.Mask" "F.Paste")
			(net "GND")
		)
		(pad "E28" smd circle
			(at -3.999992 -11.649964 90)
			(size 0.3048 0.3048)
			(layers "F.Cu" "F.Mask" "F.Paste")
			(net "GND")
		)
		(pad "E30" smd circle
			(at -2.999994 -11.649964 90)
			(size 0.3048 0.3048)
			(layers "F.Cu" "F.Mask" "F.Paste")
			(net "GND")
		)
		(pad "E32" smd circle
			(at -1.999996 -11.649964 90)
			(size 0.3048 0.3048)
			(layers "F.Cu" "F.Mask" "F.Paste")
			(net "GND")
		)
		(pad "E34" smd circle
			(at -0.999998 -11.649964 90)
			(size 0.3048 0.3048)
			(layers "F.Cu" "F.Mask" "F.Paste")
			(net "GND")
		)
		(pad "E37" smd circle
			(at 0 -11.649964 90)
			(size 0.3048 0.3048)
			(layers "F.Cu" "F.Mask" "F.Paste")
			(net "GND")
		)
		(pad "E39" smd circle
			(at 0.999998 -11.649964 90)
			(size 0.3048 0.3048)
			(layers "F.Cu" "F.Mask" "F.Paste")
			(net "GND")
		)
		(pad "E41" smd circle
			(at 1.999996 -11.649964 90)
			(size 0.3048 0.3048)
			(layers "F.Cu" "F.Mask" "F.Paste")
			(net "GND")
		)
		(pad "E43" smd circle
			(at 2.999994 -11.649964 90)
			(size 0.3048 0.3048)
			(layers "F.Cu" "F.Mask" "F.Paste")
			(net "GND")
		)
		(pad "E45" smd circle
			(at 3.999992 -11.649964 90)
			(size 0.3048 0.3048)
			(layers "F.Cu" "F.Mask" "F.Paste")
			(net "GND")
		)
		(pad "E48" smd circle
			(at 4.99999 -11.649964 90)
			(size 0.3048 0.3048)
			(layers "F.Cu" "F.Mask" "F.Paste")
			(net "GND")
		)
		(pad "E50" smd circle
			(at 5.999988 -11.649964 90)
			(size 0.3048 0.3048)
			(layers "F.Cu" "F.Mask" "F.Paste")
			(net "GND")
		)
		(pad "E52" smd circle
			(at 6.999986 -11.649964 90)
			(size 0.3048 0.3048)
			(layers "F.Cu" "F.Mask" "F.Paste")
			(net "GND")
		)
		(pad "E54" smd circle
			(at 7.999984 -11.649964 90)
			(size 0.3048 0.3048)
			(layers "F.Cu" "F.Mask" "F.Paste")
			(net "GND")
		)
		(pad "E57" smd circle
			(at 8.999982 -11.649964 90)
			(size 0.3048 0.3048)
			(layers "F.Cu" "F.Mask" "F.Paste")
			(net "GND")
		)
		(pad "E59" smd circle
			(at 9.99998 -11.649964 90)
			(size 0.3048 0.3048)
			(layers "F.Cu" "F.Mask" "F.Paste")
			(net "GND")
		)
		(pad "E61" smd circle
			(at 10.999978 -11.649964 90)
			(size 0.3048 0.3048)
			(layers "F.Cu" "F.Mask" "F.Paste")
			(net "GND")
		)
		(pad "E63" smd circle
			(at 11.999976 -11.649964 90)
			(size 0.3048 0.3048)
			(layers "F.Cu" "F.Mask" "F.Paste")
			(net "GND")
		)
		(pad "E65" smd circle
			(at 12.999974 -11.649964 90)
			(size 0.3048 0.3048)
			(layers "F.Cu" "F.Mask" "F.Paste")
			(net "GND")
		)
		(pad "E67" smd circle
			(at 13.999972 -11.649964 90)
			(size 0.3048 0.3048)
			(layers "F.Cu" "F.Mask" "F.Paste")
			(net "A_EXTCLKP")
		)
		(pad "E70" smd circle
			(at 15.580106 -11.78433 90)
			(size 0.3556 0.3556)
			(layers "F.Cu" "F.Mask" "F.Paste")
			(net "GND")
		)
		(pad "E72" smd circle
			(at 16.310102 -11.689334 45)
			(size 0.4064 0.4064)
			(layers "F.Cu" "F.Mask" "F.Paste")
			(net "GND")
		)
		(pad "F3" smd circle
			(at -15.580106 -10.999978 90)
			(size 0.3556 0.3556)
			(layers "F.Cu" "F.Mask" "F.Paste")
			(net "GND")
		)
		(pad "F5" smd circle
			(at -14.85138 -11.386058 90)
			(size 0.3048 0.3048)
			(layers "F.Cu" "F.Mask" "F.Paste")
			(net "SPI_PCH_IO2")
		)
		(pad "F8" smd circle
			(at -13.599922 -11.284966 90)
			(size 0.3048 0.3048)
			(layers "F.Cu" "F.Mask" "F.Paste")
			(net "TP_PCH_RSVD7")
		)
		(pad "F66" smd circle
			(at 13.200126 -11.025124 315)
			(size 0.3048 0.3048)
			(layers "F.Cu" "F.Mask" "F.Paste")
			(net "TP_PCH_RSVD9")
		)
		(pad "F69" smd circle
			(at 14.85138 -11.386058 90)
			(size 0.3048 0.3048)
			(layers "F.Cu" "F.Mask" "F.Paste")
			(net "TP_PCH_RSVD8")
		)
		(pad "F70" smd circle
			(at 15.580106 -10.999978 90)
			(size 0.3556 0.3556)
			(layers "F.Cu" "F.Mask" "F.Paste")
			(net "GND")
		)
		(pad "G1" smd circle
			(at -16.310102 -10.876534 135)
			(size 0.4064 0.4064)
			(layers "F.Cu" "F.Mask" "F.Paste")
			(net "GND")
		)
		(pad "G6" smd circle
			(at -14.356334 -10.891012 90)
			(size 0.3048 0.3048)
			(layers "F.Cu" "F.Mask" "F.Paste")
			(net "GND")
		)
		(pad "G7" smd circle
			(at -13.73632 -10.64895)
			(size 0.381 0.381)
			(layers "F.Cu" "F.Mask" "F.Paste")
			(net "TP_SPI_PCH_CS1_R1_N")
		)
		(pad "G11" smd circle
			(at -12.01928 -10.64895)
			(size 0.381 0.381)
			(layers "F.Cu" "F.Mask" "F.Paste")
			(net "FM_CPU0_SKTOCC_LVT3_N")
		)
		(pad "G15" smd circle
			(at -10.30224 -10.64895)
			(size 0.381 0.381)
			(layers "F.Cu" "F.Mask" "F.Paste")
			(net "XDP_PCH_PWR_DEBUG_N")
		)
		(pad "G18" smd circle
			(at -8.5852 -10.64895)
			(size 0.381 0.381)
			(layers "F.Cu" "F.Mask" "F.Paste")
			(net "RST_SRTCRST_N")
		)
		(pad "G22" smd circle
			(at -6.86816 -10.64895)
			(size 0.381 0.381)
			(layers "F.Cu" "F.Mask" "F.Paste")
			(net "GND")
		)
		(pad "G26" smd circle
			(at -5.15112 -10.64895)
			(size 0.381 0.381)
			(layers "F.Cu" "F.Mask" "F.Paste")
			(net "CLK_100M_MEZZ2_DP")
		)
		(pad "G29" smd circle
			(at -3.43408 -10.64895)
			(size 0.381 0.381)
			(layers "F.Cu" "F.Mask" "F.Paste")
			(net "GND")
		)
		(pad "G33" smd circle
			(at -1.71704 -10.64895)
			(size 0.381 0.381)
			(layers "F.Cu" "F.Mask" "F.Paste")
			(net "CLK_100M_PCH_SLOTX24_S0_DP")
		)
		(pad "G37" smd circle
			(at 0 -10.64895)
			(size 0.381 0.381)
			(layers "F.Cu" "F.Mask" "F.Paste")
			(net "GND")
		)
		(pad "G40" smd circle
			(at 1.71704 -10.64895)
			(size 0.381 0.381)
			(layers "F.Cu" "F.Mask" "F.Paste")
			(net "CLK_100M_PCH_SLOTX24_S3_DP")
		)
		(pad "G44" smd circle
			(at 3.43408 -10.64895)
			(size 0.381 0.381)
			(layers "F.Cu" "F.Mask" "F.Paste")
			(net "A_PCH_XCLK_BIASREF")
		)
		(pad "G48" smd circle
			(at 5.15112 -10.64895)
			(size 0.381 0.381)
			(layers "F.Cu" "F.Mask" "F.Paste")
			(net "GND")
		)
		(pad "G52" smd circle
			(at 6.86816 -10.64895)
			(size 0.381 0.381)
			(layers "F.Cu" "F.Mask" "F.Paste")
			(net "P3E_CPU0_PE1_PCH_RXP<0>")
		)
		(pad "G56" smd circle
			(at 8.5852 -10.64895)
			(size 0.381 0.381)
			(layers "F.Cu" "F.Mask" "F.Paste")
			(net "P3E_CPU0_PE1_PCH_RXP<2>")
		)
		(pad "G59" smd circle
			(at 10.30224 -10.64895)
			(size 0.381 0.381)
			(layers "F.Cu" "F.Mask" "F.Paste")
			(net "GND")
		)
		(pad "G63" smd circle
			(at 12.01928 -10.64895)
			(size 0.381 0.381)
			(layers "F.Cu" "F.Mask" "F.Paste")
			(net "GND")
		)
		(pad "G66" smd circle
			(at 13.73632 -10.64895)
			(size 0.381 0.381)
			(layers "F.Cu" "F.Mask" "F.Paste")
			(net "GND")
		)
		(pad "G67" smd circle
			(at 14.356334 -10.891012 90)
			(size 0.3048 0.3048)
			(layers "F.Cu" "F.Mask" "F.Paste")
			(net "TP_PCH_RSVD49")
		)
		(pad "G72" smd circle
			(at 16.310102 -10.876534 45)
			(size 0.4064 0.4064)
			(layers "F.Cu" "F.Mask" "F.Paste")
			(net "GND")
		)
		(pad "H4" smd circle
			(at -15.064994 -10.500106 180)
			(size 0.3048 0.3048)
			(layers "F.Cu" "F.Mask" "F.Paste")
			(net "SPI_PCH_MOSI_R")
		)
		(pad "H9" smd circle
			(at -12.8778 -10.15365)
			(size 0.381 0.381)
			(layers "F.Cu" "F.Mask" "F.Paste")
			(net "FM_BATTERY_SENSE_EN_R_N")
		)
		(pad "H13" smd circle
			(at -11.16076 -10.15365)
			(size 0.381 0.381)
			(layers "F.Cu" "F.Mask" "F.Paste")
			(net "FM_CPU1_SKTOCC_LVT3_N")
		)
		(pad "H17" smd circle
			(at -9.44372 -10.15365)
			(size 0.381 0.381)
			(layers "F.Cu" "F.Mask" "F.Paste")
			(net "XTAL_33K_RTC2")
		)
		(pad "H20" smd circle
			(at -7.72668 -10.15365)
			(size 0.381 0.381)
			(layers "F.Cu" "F.Mask" "F.Paste")
			(net "TP_PCH_HDA_SYNC")
		)
		(pad "H24" smd circle
			(at -6.00964 -10.15365)
			(size 0.381 0.381)
			(layers "F.Cu" "F.Mask" "F.Paste")
			(net "Net_2")
		)
		(pad "H27" smd circle
			(at -4.2926 -10.15365)
			(size 0.381 0.381)
			(layers "F.Cu" "F.Mask" "F.Paste")
			(net "CLK_100M_M2_DP")
		)
		(pad "H31" smd circle
			(at -2.57556 -10.15365)
			(size 0.381 0.381)
			(layers "F.Cu" "F.Mask" "F.Paste")
			(net "CLK_100M_PCH_SLOTX24_S5_DN")
		)
		(pad "H35" smd circle
			(at -0.85852 -10.15365)
			(size 0.381 0.381)
			(layers "F.Cu" "F.Mask" "F.Paste")
			(net "CLK_100M_DB1200_DP")
		)
		(pad "H38" smd circle
			(at 0.85852 -10.15365)
			(size 0.381 0.381)
			(layers "F.Cu" "F.Mask" "F.Paste")
			(net "CLK_100M_AIRMAX8_PE1_DP")
		)
		(pad "H42" smd circle
			(at 2.57556 -10.15365)
			(size 0.381 0.381)
			(layers "F.Cu" "F.Mask" "F.Paste")
			(net "CLK_100M_PCH_SLOTX24_S1_DP")
		)
		(pad "H46" smd circle
			(at 4.2926 -10.15365)
			(size 0.381 0.381)
			(layers "F.Cu" "F.Mask" "F.Paste")
			(net "DMI_CPU0_PCH_RX_DN<0>")
		)
		(pad "H50" smd circle
			(at 6.00964 -10.15365)
			(size 0.381 0.381)
			(layers "F.Cu" "F.Mask" "F.Paste")
			(net "DMI_CPU0_PCH_RX_DP<1>")
		)
		(pad "H54" smd circle
			(at 7.72668 -10.15365)
			(size 0.381 0.381)
			(layers "F.Cu" "F.Mask" "F.Paste")
			(net "P3E_CPU0_PE1_PCH_RXN<2>")
		)
		(pad "H58" smd circle
			(at 9.44372 -10.15365)
			(size 0.381 0.381)
			(layers "F.Cu" "F.Mask" "F.Paste")
			(net "GND")
		)
		(pad "H61" smd circle
			(at 11.16076 -10.15365)
			(size 0.381 0.381)
			(layers "F.Cu" "F.Mask" "F.Paste")
			(net "P3E_CPU0_PE1_PCH_RXN<6>")
		)
		(pad "H65" smd circle
			(at 12.8778 -10.15365)
			(size 0.381 0.381)
			(layers "F.Cu" "F.Mask" "F.Paste")
			(net "GND")
		)
		(pad "H69" smd circle
			(at 15.064994 -10.500106)
			(size 0.3048 0.3048)
			(layers "F.Cu" "F.Mask" "F.Paste")
			(net "TP_PCH_RSVD50")
		)
		(pad "J1" smd circle
			(at -16.310102 -10.063734 90)
			(size 0.3556 0.3556)
			(layers "F.Cu" "F.Mask" "F.Paste")
			(net "GND")
		)
		(pad "J3" smd circle
			(at -15.48003 -9.99998 180)
			(size 0.3048 0.3048)
			(layers "F.Cu" "F.Mask" "F.Paste")
			(net "SPI_PCH_CS0_R_N")
		)
		(pad "J5" smd circle
			(at -14.649958 -9.99998 180)
			(size 0.3048 0.3048)
			(layers "F.Cu" "F.Mask" "F.Paste")
			(net "GND")
		)
		(pad "J7" smd circle
			(at -13.73632 -9.65835)
			(size 0.381 0.381)
			(layers "F.Cu" "F.Mask" "F.Paste")
			(net "GND")
		)
		(pad "J11" smd circle
			(at -12.01928 -9.65835)
			(size 0.381 0.381)
			(layers "F.Cu" "F.Mask" "F.Paste")
			(net "GND")
		)
		(pad "J15" smd circle
			(at -10.30224 -9.65835)
			(size 0.381 0.381)
			(layers "F.Cu" "F.Mask" "F.Paste")
			(net "GND")
		)
		(pad "J18" smd circle
			(at -8.5852 -9.65835)
			(size 0.381 0.381)
			(layers "F.Cu" "F.Mask" "F.Paste")
			(net "GND")
		)
		(pad "J22" smd circle
			(at -6.86816 -9.65835)
			(size 0.381 0.381)
			(layers "F.Cu" "F.Mask" "F.Paste")
			(net "GND")
		)
		(pad "J26" smd circle
			(at -5.15112 -9.65835)
			(size 0.381 0.381)
			(layers "F.Cu" "F.Mask" "F.Paste")
			(net "CLK_100M_MEZZ2_DN")
		)
		(pad "J29" smd circle
			(at -3.43408 -9.65835)
			(size 0.381 0.381)
			(layers "F.Cu" "F.Mask" "F.Paste")
			(net "GND")
		)
		(pad "J33" smd circle
			(at -1.71704 -9.65835)
			(size 0.381 0.381)
			(layers "F.Cu" "F.Mask" "F.Paste")
			(net "CLK_100M_PCH_SLOTX24_S0_DN")
		)
		(pad "J37" smd circle
			(at 0 -9.65835)
			(size 0.381 0.381)
			(layers "F.Cu" "F.Mask" "F.Paste")
			(net "GND")
		)
		(pad "J40" smd circle
			(at 1.71704 -9.65835)
			(size 0.381 0.381)
			(layers "F.Cu" "F.Mask" "F.Paste")
			(net "CLK_100M_PCH_SLOTX24_S3_DN")
		)
		(pad "J44" smd circle
			(at 3.43408 -9.65835)
			(size 0.381 0.381)
			(layers "F.Cu" "F.Mask" "F.Paste")
			(net "GND")
		)
		(pad "J48" smd circle
			(at 5.15112 -9.65835)
			(size 0.381 0.381)
			(layers "F.Cu" "F.Mask" "F.Paste")
			(net "DMI_CPU0_PCH_RX_DN<1>")
		)
		(pad "J52" smd circle
			(at 6.86816 -9.65835)
			(size 0.381 0.381)
			(layers "F.Cu" "F.Mask" "F.Paste")
			(net "P3E_CPU0_PE1_PCH_RXN<0>")
		)
		(pad "J56" smd circle
			(at 8.5852 -9.65835)
			(size 0.381 0.381)
			(layers "F.Cu" "F.Mask" "F.Paste")
			(net "P3E_CPU0_PE1_PCH_RXN<3>")
		)
		(pad "J59" smd circle
			(at 10.30224 -9.65835)
			(size 0.381 0.381)
			(layers "F.Cu" "F.Mask" "F.Paste")
			(net "GND")
		)
		(pad "J63" smd circle
			(at 12.01928 -9.65835)
			(size 0.381 0.381)
			(layers "F.Cu" "F.Mask" "F.Paste")
			(net "P3E_CPU0_PE1_PCH_RXP<6>")
		)
		(pad "J66" smd circle
			(at 13.73632 -9.65835)
			(size 0.381 0.381)
			(layers "F.Cu" "F.Mask" "F.Paste")
			(net "P3E_CPU0_PE1_PCH_R_RXN<9>")
		)
		(pad "J68" smd circle
			(at 14.649958 -9.99998)
			(size 0.3048 0.3048)
			(layers "F.Cu" "F.Mask" "F.Paste")
			(net "GND")
		)
		(pad "J70" smd circle
			(at 15.48003 -9.99998)
			(size 0.3048 0.3048)
			(layers "F.Cu" "F.Mask" "F.Paste")
			(net "GND")
		)
		(pad "J72" smd circle
			(at 16.310102 -10.063734 90)
			(size 0.3556 0.3556)
			(layers "F.Cu" "F.Mask" "F.Paste")
			(net "GND")
		)
		(pad "K2" smd circle
			(at -15.895066 -9.500108 180)
			(size 0.3048 0.3048)
			(layers "F.Cu" "F.Mask" "F.Paste")
			(net "SPI_PCH_CLK")
		)
		(pad "K4" smd circle
			(at -15.064994 -9.500108 180)
			(size 0.3048 0.3048)
			(layers "F.Cu" "F.Mask" "F.Paste")
			(net "SPI_PCH_TPM_CS_N")
		)
		(pad "K9" smd circle
			(at -12.8778 -9.16305)
			(size 0.381 0.381)
			(layers "F.Cu" "F.Mask" "F.Paste")
			(net "IRQ_LVC3_WAKE_N")
		)
		(pad "K13" smd circle
			(at -11.16076 -9.16305)
			(size 0.381 0.381)
			(layers "F.Cu" "F.Mask" "F.Paste")
			(net "PWRGD_DSW_PWROK")
		)
		(pad "K17" smd circle
			(at -9.44372 -9.16305)
			(size 0.381 0.381)
			(layers "F.Cu" "F.Mask" "F.Paste")
			(net "XTAL_33K_RTC1")
		)
		(pad "K20" smd circle
			(at -7.72668 -9.16305)
			(size 0.381 0.381)
			(layers "F.Cu" "F.Mask" "F.Paste")
			(net "TP_PCH_HDA_SDI_0")
		)
		(pad "K24" smd circle
			(at -6.00964 -9.16305)
			(size 0.381 0.381)
			(layers "F.Cu" "F.Mask" "F.Paste")
			(net "Net_1")
		)
		(pad "K27" smd circle
			(at -4.2926 -9.16305)
			(size 0.381 0.381)
			(layers "F.Cu" "F.Mask" "F.Paste")
			(net "CLK_100M_M2_DN")
		)
		(pad "K31" smd circle
			(at -2.57556 -9.16305)
			(size 0.381 0.381)
			(layers "F.Cu" "F.Mask" "F.Paste")
			(net "CLK_100M_PCH_SLOTX24_S5_DP")
		)
		(pad "K35" smd circle
			(at -0.85852 -9.16305)
			(size 0.381 0.381)
			(layers "F.Cu" "F.Mask" "F.Paste")
			(net "CLK_100M_DB1200_DN")
		)
		(pad "K38" smd circle
			(at 0.85852 -9.16305)
			(size 0.381 0.381)
			(layers "F.Cu" "F.Mask" "F.Paste")
			(net "CLK_100M_AIRMAX8_PE1_DN")
		)
		(pad "K42" smd circle
			(at 2.57556 -9.16305)
			(size 0.381 0.381)
			(layers "F.Cu" "F.Mask" "F.Paste")
			(net "CLK_100M_PCH_SLOTX24_S1_DN")
		)
		(pad "K46" smd circle
			(at 4.2926 -9.16305)
			(size 0.381 0.381)
			(layers "F.Cu" "F.Mask" "F.Paste")
			(net "DMI_CPU0_PCH_RX_DP<0>")
		)
		(pad "K50" smd circle
			(at 6.00964 -9.16305)
			(size 0.381 0.381)
			(layers "F.Cu" "F.Mask" "F.Paste")
			(net "DMI_CPU0_PCH_RX_DN<2>")
		)
		(pad "K54" smd circle
			(at 7.72668 -9.16305)
			(size 0.381 0.381)
			(layers "F.Cu" "F.Mask" "F.Paste")
			(net "GND")
		)
		(pad "K58" smd circle
			(at 9.44372 -9.16305)
			(size 0.381 0.381)
			(layers "F.Cu" "F.Mask" "F.Paste")
			(net "P3E_CPU0_PE1_PCH_RXP<3>")
		)
		(pad "K61" smd circle
			(at 11.16076 -9.16305)
			(size 0.381 0.381)
			(layers "F.Cu" "F.Mask" "F.Paste")
			(net "P3E_CPU0_PE1_PCH_RXP<5>")
		)
		(pad "K65" smd circle
			(at 12.8778 -9.16305)
			(size 0.381 0.381)
			(layers "F.Cu" "F.Mask" "F.Paste")
			(net "P3E_CPU0_PE1_PCH_R_RXN<8>")
		)
		(pad "K69" smd circle
			(at 15.064994 -9.500108)
			(size 0.3048 0.3048)
			(layers "F.Cu" "F.Mask" "F.Paste")
			(net "GND")
		)
		(pad "K71" smd circle
			(at 15.895066 -9.500108)
			(size 0.3048 0.3048)
			(layers "F.Cu" "F.Mask" "F.Paste")
			(net "GND")
		)
		(pad "L1" smd oval
			(at -16.310102 -8.999982 180)
			(size 0.254 0.3302)
			(layers "F.Cu" "F.Mask" "F.Paste")
			(net "SPI_PCH_IO3")
		)
		(pad "L3" smd circle
			(at -15.48003 -8.999982 180)
			(size 0.3048 0.3048)
			(layers "F.Cu" "F.Mask" "F.Paste")
			(net "SPI_PCH_MISO")
		)
		(pad "L5" smd circle
			(at -14.649958 -8.999982 180)
			(size 0.3048 0.3048)
			(layers "F.Cu" "F.Mask" "F.Paste")
			(net "GND")
		)
		(pad "L68" smd circle
			(at 14.649958 -8.999982)
			(size 0.3048 0.3048)
			(layers "F.Cu" "F.Mask" "F.Paste")
			(net "GND")
		)
		(pad "L70" smd circle
			(at 15.48003 -8.999982)
			(size 0.3048 0.3048)
			(layers "F.Cu" "F.Mask" "F.Paste")
			(net "SATA6G_PCH_PCIE_UP_SATA_TXN<7>")
		)
		(pad "L72" smd oval
			(at 16.310102 -8.999982 180)
			(size 0.254 0.3302)
			(layers "F.Cu" "F.Mask" "F.Paste")
			(net "SATA6G_PCH_PCIE_UP_SATA_TXP<7>")
		)
		(pad "M2" smd circle
			(at -15.895066 -8.50011 180)
			(size 0.3048 0.3048)
			(layers "F.Cu" "F.Mask" "F.Paste")
			(net "GND")
		)
		(pad "M4" smd circle
			(at -15.064994 -8.50011 180)
			(size 0.3048 0.3048)
			(layers "F.Cu" "F.Mask" "F.Paste")
			(net "GND")
		)
		(pad "M7" smd circle
			(at -13.73632 -8.66775)
			(size 0.381 0.381)
			(layers "F.Cu" "F.Mask" "F.Paste")
			(net "TP_CPU_PCH_TRIGGER_IN")
		)
		(pad "M11" smd circle
			(at -12.01928 -8.66775)
			(size 0.381 0.381)
			(layers "F.Cu" "F.Mask" "F.Paste")
			(net "RST_BMC_SRST_R_N")
		)
		(pad "M15" smd circle
			(at -10.30224 -8.66775)
			(size 0.381 0.381)
			(layers "F.Cu" "F.Mask" "F.Paste")
			(net "TP_SLP_LAN_N")
		)
		(pad "M18" smd circle
			(at -8.5852 -8.66775)
			(size 0.381 0.381)
			(layers "F.Cu" "F.Mask" "F.Paste")
			(net "TP_PCH_HSA_RST_N")
		)
		(pad "M22" smd circle
			(at -6.86816 -8.66775)
			(size 0.381 0.381)
			(layers "F.Cu" "F.Mask" "F.Paste")
			(net "GND")
		)
		(pad "M26" smd circle
			(at -5.15112 -8.66775)
			(size 0.381 0.381)
			(layers "F.Cu" "F.Mask" "F.Paste")
			(net "GND")
		)
		(pad "M29" smd circle
			(at -3.43408 -8.66775)
			(size 0.381 0.381)
			(layers "F.Cu" "F.Mask" "F.Paste")
			(net "GND")
		)
		(pad "M33" smd circle
			(at -1.71704 -8.66775)
			(size 0.381 0.381)
			(layers "F.Cu" "F.Mask" "F.Paste")
			(net "GND")
		)
		(pad "M37" smd circle
			(at 0 -8.66775)
			(size 0.381 0.381)
			(layers "F.Cu" "F.Mask" "F.Paste")
			(net "GND")
		)
		(pad "M40" smd circle
			(at 1.71704 -8.66775)
			(size 0.381 0.381)
			(layers "F.Cu" "F.Mask" "F.Paste")
			(net "GND")
		)
		(pad "M44" smd circle
			(at 3.43408 -8.66775)
			(size 0.381 0.381)
			(layers "F.Cu" "F.Mask" "F.Paste")
			(net "GND")
		)
		(pad "M48" smd circle
			(at 5.15112 -8.66775)
			(size 0.381 0.381)
			(layers "F.Cu" "F.Mask" "F.Paste")
			(net "GND")
		)
		(pad "M52" smd circle
			(at 6.86816 -8.66775)
			(size 0.381 0.381)
			(layers "F.Cu" "F.Mask" "F.Paste")
			(net "DMI_CPU0_PCH_RX_DP<2>")
		)
		(pad "M56" smd circle
			(at 8.5852 -8.66775)
			(size 0.381 0.381)
			(layers "F.Cu" "F.Mask" "F.Paste")
			(net "P3E_CPU0_PE1_PCH_RXP<1>")
		)
		(pad "M59" smd circle
			(at 10.30224 -8.66775)
			(size 0.381 0.381)
			(layers "F.Cu" "F.Mask" "F.Paste")
			(net "P3E_CPU0_PE1_PCH_RXP<4>")
		)
		(pad "M63" smd circle
			(at 12.01928 -8.66775)
			(size 0.381 0.381)
			(layers "F.Cu" "F.Mask" "F.Paste")
			(net "P3E_CPU0_PE1_PCH_R_RXP<8>")
		)
		(pad "M66" smd circle
			(at 13.73632 -8.66775)
			(size 0.381 0.381)
			(layers "F.Cu" "F.Mask" "F.Paste")
			(net "P3E_CPU0_PE1_PCH_R_RXP<9>")
		)
		(pad "M69" smd circle
			(at 15.064994 -8.50011)
			(size 0.3048 0.3048)
			(layers "F.Cu" "F.Mask" "F.Paste")
			(net "SATA6G_PCH_PCIE_UP_SATA_TXN<6>")
		)
		(pad "M71" smd circle
			(at 15.895066 -8.50011)
			(size 0.3048 0.3048)
			(layers "F.Cu" "F.Mask" "F.Paste")
			(net "SATA6G_PCH_PCIE_UP_SATA_TXP<6>")
		)
		(pad "N1" smd oval
			(at -16.310102 -7.999984 180)
			(size 0.254 0.3302)
			(layers "F.Cu" "F.Mask" "F.Paste")
			(net "LPC_LAD1_IO1")
		)
		(pad "N3" smd circle
			(at -15.48003 -7.999984 180)
			(size 0.3048 0.3048)
			(layers "F.Cu" "F.Mask" "F.Paste")
			(net "PU_FM_RCIN_N")
		)
		(pad "N5" smd circle
			(at -14.649958 -7.999984 180)
			(size 0.3048 0.3048)
			(layers "F.Cu" "F.Mask" "F.Paste")
			(net "GND")
		)
		(pad "N9" smd circle
			(at -12.8778 -8.17245)
			(size 0.381 0.381)
			(layers "F.Cu" "F.Mask" "F.Paste")
			(net "GND")
		)
		(pad "N13" smd circle
			(at -11.16076 -8.17245)
			(size 0.381 0.381)
			(layers "F.Cu" "F.Mask" "F.Paste")
			(net "GND")
		)
		(pad "N17" smd circle
			(at -9.44372 -8.17245)
			(size 0.381 0.381)
			(layers "F.Cu" "F.Mask" "F.Paste")
			(net "GND")
		)
		(pad "N20" smd circle
			(at -7.72668 -8.17245)
			(size 0.381 0.381)
			(layers "F.Cu" "F.Mask" "F.Paste")
			(net "GND")
		)
		(pad "N24" smd circle
			(at -6.00964 -8.17245)
			(size 0.381 0.381)
			(layers "F.Cu" "F.Mask" "F.Paste")
			(net "GND")
		)
		(pad "N27" smd circle
			(at -4.2926 -8.17245)
			(size 0.381 0.381)
			(layers "F.Cu" "F.Mask" "F.Paste")
			(net "GND")
		)
		(pad "N31" smd circle
			(at -2.57556 -8.17245)
			(size 0.381 0.381)
			(layers "F.Cu" "F.Mask" "F.Paste")
			(net "GND")
		)
		(pad "N35" smd circle
			(at -0.85852 -8.17245)
			(size 0.381 0.381)
			(layers "F.Cu" "F.Mask" "F.Paste")
			(net "GND")
		)
		(pad "N38" smd circle
			(at 0.85852 -8.17245)
			(size 0.381 0.381)
			(layers "F.Cu" "F.Mask" "F.Paste")
			(net "GND")
		)
		(pad "N42" smd circle
			(at 2.57556 -8.17245)
			(size 0.381 0.381)
			(layers "F.Cu" "F.Mask" "F.Paste")
			(net "GND")
		)
		(pad "N46" smd circle
			(at 4.2926 -8.17245)
			(size 0.381 0.381)
			(layers "F.Cu" "F.Mask" "F.Paste")
			(net "GND")
		)
		(pad "N50" smd circle
			(at 6.00964 -8.17245)
			(size 0.381 0.381)
			(layers "F.Cu" "F.Mask" "F.Paste")
			(net "GND")
		)
		(pad "N54" smd circle
			(at 7.72668 -8.17245)
			(size 0.381 0.381)
			(layers "F.Cu" "F.Mask" "F.Paste")
			(net "DMI_CPU0_PCH_RX_DP<3>")
		)
		(pad "N58" smd circle
			(at 9.44372 -8.17245)
			(size 0.381 0.381)
			(layers "F.Cu" "F.Mask" "F.Paste")
			(net "P3E_CPU0_PE1_PCH_RXN<4>")
		)
		(pad "N61" smd circle
			(at 11.16076 -8.17245)
			(size 0.381 0.381)
			(layers "F.Cu" "F.Mask" "F.Paste")
			(net "P3E_CPU0_PE1_PCH_RXN<5>")
		)
		(pad "N65" smd circle
			(at 12.8778 -8.17245)
			(size 0.381 0.381)
			(layers "F.Cu" "F.Mask" "F.Paste")
			(net "P3E_CPU0_PE1_PCH_R_RXN<10>")
		)
		(pad "N68" smd circle
			(at 14.649958 -7.999984)
			(size 0.3048 0.3048)
			(layers "F.Cu" "F.Mask" "F.Paste")
			(net "GND")
		)
		(pad "N70" smd circle
			(at 15.48003 -7.999984)
			(size 0.3048 0.3048)
			(layers "F.Cu" "F.Mask" "F.Paste")
			(net "SATA6G_PCH_PCIE_UP_SATA_TXN<5>")
		)
		(pad "N72" smd oval
			(at 16.310102 -7.999984 180)
			(size 0.254 0.3302)
			(layers "F.Cu" "F.Mask" "F.Paste")
			(net "SATA6G_PCH_PCIE_UP_SATA_TXP<5>")
		)
		(pad "P2" smd circle
			(at -15.895066 -7.500112 180)
			(size 0.3048 0.3048)
			(layers "F.Cu" "F.Mask" "F.Paste")
			(net "IRQ_LPC_SERIRQ_N")
		)
		(pad "P4" smd circle
			(at -15.064994 -7.500112 180)
			(size 0.3048 0.3048)
			(layers "F.Cu" "F.Mask" "F.Paste")
			(net "LPC_LFRAME_N_CS0_N")
		)
		(pad "P7" smd circle
			(at -13.73632 -7.67715)
			(size 0.381 0.381)
			(layers "F.Cu" "F.Mask" "F.Paste")
			(net "FM_SLP_SUS_N")
		)
		(pad "P11" smd circle
			(at -12.01928 -7.67715)
			(size 0.381 0.381)
			(layers "F.Cu" "F.Mask" "F.Paste")
			(net "RST_RTCRST_N")
		)
		(pad "P15" smd circle
			(at -10.30224 -7.67715)
			(size 0.381 0.381)
			(layers "F.Cu" "F.Mask" "F.Paste")
			(net "RST_RSMRST_N")
		)
		(pad "P18" smd circle
			(at -8.5852 -7.67715)
			(size 0.381 0.381)
			(layers "F.Cu" "F.Mask" "F.Paste")
			(net "TP_PCH_HDA_BCLK")
		)
		(pad "P22" smd circle
			(at -6.86816 -7.67715)
			(size 0.381 0.381)
			(layers "F.Cu" "F.Mask" "F.Paste")
			(net "TP_PCH_RSVD45")
		)
		(pad "P26" smd circle
			(at -5.15112 -7.67715)
			(size 0.381 0.381)
			(layers "F.Cu" "F.Mask" "F.Paste")
			(net "TP_PCH_RSVD53")
		)
		(pad "P29" smd circle
			(at -3.43408 -7.67715)
			(size 0.381 0.381)
			(layers "F.Cu" "F.Mask" "F.Paste")
			(net "TP_PCH_RSVD31")
		)
		(pad "P33" smd circle
			(at -1.71704 -7.67715)
			(size 0.381 0.381)
			(layers "F.Cu" "F.Mask" "F.Paste")
			(net "TP_PCH_RSVD29")
		)
		(pad "P37" smd circle
			(at 0 -7.67715)
			(size 0.381 0.381)
			(layers "F.Cu" "F.Mask" "F.Paste")
			(net "TP_PCH_RSVD4")
		)
		(pad "P40" smd circle
			(at 1.71704 -7.67715)
			(size 0.381 0.381)
			(layers "F.Cu" "F.Mask" "F.Paste")
			(net "TP_PCH_RSVD23")
		)
		(pad "P44" smd circle
			(at 3.43408 -7.67715)
			(size 0.381 0.381)
			(layers "F.Cu" "F.Mask" "F.Paste")
			(net "TP_PCH_RSVD24")
		)
		(pad "P48" smd circle
			(at 5.15112 -7.67715)
			(size 0.381 0.381)
			(layers "F.Cu" "F.Mask" "F.Paste")
			(net "TP_PCH_RSVD25")
		)
		(pad "P52" smd circle
			(at 6.86816 -7.67715)
			(size 0.381 0.381)
			(layers "F.Cu" "F.Mask" "F.Paste")
			(net "DMI_CPU0_PCH_RX_DN<3>")
		)
		(pad "P56" smd circle
			(at 8.5852 -7.67715)
			(size 0.381 0.381)
			(layers "F.Cu" "F.Mask" "F.Paste")
			(net "P3E_CPU0_PE1_PCH_RXN<1>")
		)
		(pad "P59" smd circle
			(at 10.30224 -7.67715)
			(size 0.381 0.381)
			(layers "F.Cu" "F.Mask" "F.Paste")
			(net "P3E_CPU0_PE1_PCH_RXN<7>")
		)
		(pad "P63" smd circle
			(at 12.01928 -7.67715)
			(size 0.381 0.381)
			(layers "F.Cu" "F.Mask" "F.Paste")
			(net "GND")
		)
		(pad "P66" smd circle
			(at 13.73632 -7.67715)
			(size 0.381 0.381)
			(layers "F.Cu" "F.Mask" "F.Paste")
			(net "P3E_CPU0_PE1_PCH_R_RXP<10>")
		)
		(pad "P69" smd circle
			(at 15.064994 -7.500112)
			(size 0.3048 0.3048)
			(layers "F.Cu" "F.Mask" "F.Paste")
			(net "SATA6G_PCH_PCIE_UP_SATA_TXN<4>")
		)
		(pad "P71" smd circle
			(at 15.895066 -7.500112)
			(size 0.3048 0.3048)
			(layers "F.Cu" "F.Mask" "F.Paste")
			(net "SATA6G_PCH_PCIE_UP_SATA_TXP<4>")
		)
		(pad "R1" smd oval
			(at -16.310102 -6.999986 180)
			(size 0.254 0.3302)
			(layers "F.Cu" "F.Mask" "F.Paste")
			(net "PU_IRQ_PCH_SCI_WHEA_N")
		)
		(pad "R3" smd circle
			(at -15.48003 -6.999986 180)
			(size 0.3048 0.3048)
			(layers "F.Cu" "F.Mask" "F.Paste")
			(net "CLK_24M_BMC_LPC_R")
		)
		(pad "R5" smd circle
			(at -14.649958 -6.999986 180)
			(size 0.3048 0.3048)
			(layers "F.Cu" "F.Mask" "F.Paste")
			(net "GND")
		)
		(pad "R9" smd circle
			(at -12.8778 -7.18185)
			(size 0.381 0.381)
			(layers "F.Cu" "F.Mask" "F.Paste")
			(net "PWRGD_CPUPWRGD_GTL")
		)
		(pad "R13" smd circle
			(at -11.16076 -7.18185)
			(size 0.381 0.381)
			(layers "F.Cu" "F.Mask" "F.Paste")
			(net "TP_CPU_PCH_TRIGGER_OUT")
		)
		(pad "R17" smd circle
			(at -9.44372 -7.18185)
			(size 0.381 0.381)
			(layers "F.Cu" "F.Mask" "F.Paste")
			(net "PWRGD_PCH_PWROK")
		)
		(pad "R20" smd circle
			(at -7.72668 -7.18185)
			(size 0.381 0.381)
			(layers "F.Cu" "F.Mask" "F.Paste")
			(net "TP_PCH_DISPA_SDI")
		)
		(pad "R24" smd circle
			(at -6.00964 -7.18185)
			(size 0.381 0.381)
			(layers "F.Cu" "F.Mask" "F.Paste")
			(net "TP_PCH_RSVD54")
		)
		(pad "R27" smd circle
			(at -4.2926 -7.18185)
			(size 0.381 0.381)
			(layers "F.Cu" "F.Mask" "F.Paste")
			(net "GND")
		)
		(pad "R31" smd circle
			(at -2.57556 -7.18185)
			(size 0.381 0.381)
			(layers "F.Cu" "F.Mask" "F.Paste")
			(net "TP_PCH_RSVD30")
		)
		(pad "R35" smd circle
			(at -0.85852 -7.18185)
			(size 0.381 0.381)
			(layers "F.Cu" "F.Mask" "F.Paste")
			(net "TP_PCH_RSVD28")
		)
		(pad "R38" smd circle
			(at 0.85852 -7.18185)
			(size 0.381 0.381)
			(layers "F.Cu" "F.Mask" "F.Paste")
			(net "GND")
		)
		(pad "R42" smd circle
			(at 2.57556 -7.18185)
			(size 0.381 0.381)
			(layers "F.Cu" "F.Mask" "F.Paste")
			(net "P1V05_PCH_STBY")
		)
		(pad "R46" smd circle
			(at 4.2926 -7.18185)
			(size 0.381 0.381)
			(layers "F.Cu" "F.Mask" "F.Paste")
			(net "P1V05_PCH_STBY")
		)
		(pad "R50" smd circle
			(at 6.00964 -7.18185)
			(size 0.381 0.381)
			(layers "F.Cu" "F.Mask" "F.Paste")
			(net "GND")
		)
		(pad "R54" smd circle
			(at 7.72668 -7.18185)
			(size 0.381 0.381)
			(layers "F.Cu" "F.Mask" "F.Paste")
			(net "GND")
		)
		(pad "R58" smd circle
			(at 9.44372 -7.18185)
			(size 0.381 0.381)
			(layers "F.Cu" "F.Mask" "F.Paste")
			(net "GND")
		)
		(pad "R61" smd circle
			(at 11.16076 -7.18185)
			(size 0.381 0.381)
			(layers "F.Cu" "F.Mask" "F.Paste")
			(net "P3E_CPU0_PE1_PCH_RXP<7>")
		)
		(pad "R65" smd circle
			(at 12.8778 -7.18185)
			(size 0.381 0.381)
			(layers "F.Cu" "F.Mask" "F.Paste")
			(net "P3E_CPU0_PE1_PCH_R_RXN<12>")
		)
		(pad "R68" smd circle
			(at 14.649958 -6.999986)
			(size 0.3048 0.3048)
			(layers "F.Cu" "F.Mask" "F.Paste")
			(net "GND")
		)
		(pad "R70" smd circle
			(at 15.48003 -6.999986)
			(size 0.3048 0.3048)
			(layers "F.Cu" "F.Mask" "F.Paste")
			(net "SATA6G_PCH_PCIE_UP_SATA_TXN<3>")
		)
		(pad "R72" smd oval
			(at 16.310102 -6.999986 180)
			(size 0.254 0.3302)
			(layers "F.Cu" "F.Mask" "F.Paste")
			(net "SATA6G_PCH_PCIE_UP_SATA_TXP<3>")
		)
		(pad "T2" smd circle
			(at -15.895066 -6.500114 180)
			(size 0.3048 0.3048)
			(layers "F.Cu" "F.Mask" "F.Paste")
			(net "FM_UART_PRES_N")
		)
		(pad "T4" smd circle
			(at -15.064994 -6.500114 180)
			(size 0.3048 0.3048)
			(layers "F.Cu" "F.Mask" "F.Paste")
			(net "FM_MB_SLOT_ID0")
		)
		(pad "T7" smd circle
			(at -13.73632 -6.68655)
			(size 0.381 0.381)
			(layers "F.Cu" "F.Mask" "F.Paste")
			(net "GND")
		)
		(pad "T11" smd circle
			(at -12.01928 -6.68655)
			(size 0.381 0.381)
			(layers "F.Cu" "F.Mask" "F.Paste")
			(net "GND")
		)
		(pad "T15" smd circle
			(at -10.30224 -6.68655)
			(size 0.381 0.381)
			(layers "F.Cu" "F.Mask" "F.Paste")
			(net "GND")
		)
		(pad "T18" smd circle
			(at -8.5852 -6.68655)
			(size 0.381 0.381)
			(layers "F.Cu" "F.Mask" "F.Paste")
			(net "GND")
		)
		(pad "T22" smd circle
			(at -6.86816 -6.68655)
			(size 0.381 0.381)
			(layers "F.Cu" "F.Mask" "F.Paste")
			(net "GND")
		)
		(pad "T26" smd circle
			(at -5.15112 -6.68655)
			(size 0.381 0.381)
			(layers "F.Cu" "F.Mask" "F.Paste")
			(net "GND")
		)
		(pad "T29" smd circle
			(at -3.43408 -6.68655)
			(size 0.381 0.381)
			(layers "F.Cu" "F.Mask" "F.Paste")
			(net "GND")
		)
		(pad "T33" smd circle
			(at -1.71704 -6.68655)
			(size 0.381 0.381)
			(layers "F.Cu" "F.Mask" "F.Paste")
			(net "GND")
		)
		(pad "T37" smd circle
			(at 0 -6.68655)
			(size 0.381 0.381)
			(layers "F.Cu" "F.Mask" "F.Paste")
			(net "GND")
		)
		(pad "T40" smd circle
			(at 1.71704 -6.68655)
			(size 0.381 0.381)
			(layers "F.Cu" "F.Mask" "F.Paste")
			(net "GND")
		)
		(pad "T44" smd circle
			(at 3.43408 -6.68655)
			(size 0.381 0.381)
			(layers "F.Cu" "F.Mask" "F.Paste")
			(net "P1V05_PCH_STBY")
		)
		(pad "T48" smd circle
			(at 5.15112 -6.68655)
			(size 0.381 0.381)
			(layers "F.Cu" "F.Mask" "F.Paste")
			(net "GND")
		)
		(pad "T52" smd circle
			(at 6.86816 -6.68655)
			(size 0.381 0.381)
			(layers "F.Cu" "F.Mask" "F.Paste")
			(net "GND")
		)
		(pad "T56" smd circle
			(at 8.5852 -6.68655)
			(size 0.381 0.381)
			(layers "F.Cu" "F.Mask" "F.Paste")
			(net "GND")
		)
		(pad "T59" smd circle
			(at 10.30224 -6.68655)
			(size 0.381 0.381)
			(layers "F.Cu" "F.Mask" "F.Paste")
			(net "P3E_CPU0_PE1_PCH_R_RXN<11>")
		)
		(pad "T63" smd circle
			(at 12.01928 -6.68655)
			(size 0.381 0.381)
			(layers "F.Cu" "F.Mask" "F.Paste")
			(net "P3E_CPU0_PE1_PCH_R_RXN<13>")
		)
		(pad "T66" smd circle
			(at 13.73632 -6.68655)
			(size 0.381 0.381)
			(layers "F.Cu" "F.Mask" "F.Paste")
			(net "GND")
		)
		(pad "T69" smd circle
			(at 15.064994 -6.500114)
			(size 0.3048 0.3048)
			(layers "F.Cu" "F.Mask" "F.Paste")
			(net "SATA6G_PCH_PCIE_UP_SATA_TXN<2>")
		)
		(pad "T71" smd circle
			(at 15.895066 -6.500114)
			(size 0.3048 0.3048)
			(layers "F.Cu" "F.Mask" "F.Paste")
			(net "SATA6G_PCH_PCIE_UP_SATA_TXP<2>")
		)
		(pad "U9" smd circle
			(at -12.8778 -6.19125)
			(size 0.381 0.381)
			(layers "F.Cu" "F.Mask" "F.Paste")
			(net "PECI_PCH")
		)
		(pad "U13" smd circle
			(at -11.16076 -6.19125)
			(size 0.381 0.381)
			(layers "F.Cu" "F.Mask" "F.Paste")
			(net "H_PM_SYNC1_GTL_R")
		)
		(pad "U17" smd circle
			(at -9.44372 -6.19125)
			(size 0.381 0.381)
			(layers "F.Cu" "F.Mask" "F.Paste")
			(net "TP_PLTRST_CPU_N")
		)
		(pad "U20" smd circle
			(at -7.72668 -6.19125)
			(size 0.381 0.381)
			(layers "F.Cu" "F.Mask" "F.Paste")
			(net "TP_PCH_DISPA_BCLK")
		)
		(pad "U24" smd circle
			(at -6.00964 -6.19125)
			(size 0.381 0.381)
			(layers "F.Cu" "F.Mask" "F.Paste")
			(net "FM_FLASH_DESC_OVERRIDE")
		)
		(pad "U27" smd circle
			(at -4.2926 -6.19125)
			(size 0.381 0.381)
			(layers "F.Cu" "F.Mask" "F.Paste")
			(net "PVNN_PCH_STBY")
		)
		(pad "U31" smd circle
			(at -2.57556 -6.19125)
			(size 0.381 0.381)
			(layers "F.Cu" "F.Mask" "F.Paste")
			(net "PVNN_PCH_STBY")
		)
		(pad "U35" smd circle
			(at -0.85852 -6.19125)
			(size 0.381 0.381)
			(layers "F.Cu" "F.Mask" "F.Paste")
			(net "PVNN_PCH_STBY")
		)
		(pad "U38" smd circle
			(at 0.85852 -6.19125)
			(size 0.381 0.381)
			(layers "F.Cu" "F.Mask" "F.Paste")
			(net "PVNN_PCH_STBY")
		)
		(pad "U42" smd circle
			(at 2.57556 -6.19125)
			(size 0.381 0.381)
			(layers "F.Cu" "F.Mask" "F.Paste")
			(net "GND")
		)
		(pad "U46" smd circle
			(at 4.2926 -6.19125)
			(size 0.381 0.381)
			(layers "F.Cu" "F.Mask" "F.Paste")
			(net "P1V05_PCH_STBY")
		)
		(pad "U50" smd circle
			(at 6.00964 -6.19125)
			(size 0.381 0.381)
			(layers "F.Cu" "F.Mask" "F.Paste")
			(net "P1V05_PCH_STBY")
		)
		(pad "U54" smd circle
			(at 7.72668 -6.19125)
			(size 0.381 0.381)
			(layers "F.Cu" "F.Mask" "F.Paste")
			(net "XDP_PREQ_N")
		)
		(pad "U58" smd circle
			(at 9.44372 -6.19125)
			(size 0.381 0.381)
			(layers "F.Cu" "F.Mask" "F.Paste")
			(net "GND")
		)
		(pad "U61" smd circle
			(at 11.16076 -6.19125)
			(size 0.381 0.381)
			(layers "F.Cu" "F.Mask" "F.Paste")
			(net "P3E_CPU0_PE1_PCH_R_RXP<13>")
		)
		(pad "U65" smd circle
			(at 12.8778 -6.19125)
			(size 0.381 0.381)
			(layers "F.Cu" "F.Mask" "F.Paste")
			(net "P3E_CPU0_PE1_PCH_R_RXP<12>")
		)
		(pad "V1" smd oval
			(at -16.310102 -5.999988 180)
			(size 0.254 0.3302)
			(layers "F.Cu" "F.Mask" "F.Paste")
			(net "FM_BMC_READY_R_N")
		)
		(pad "V3" smd circle
			(at -15.48003 -5.999988 180)
			(size 0.3048 0.3048)
			(layers "F.Cu" "F.Mask" "F.Paste")
			(net "FM_ME_RECOVER_N")
		)
		(pad "V5" smd circle
			(at -14.649958 -5.999988 180)
			(size 0.3048 0.3048)
			(layers "F.Cu" "F.Mask" "F.Paste")
			(net "GND")
		)
		(pad "V7" smd circle
			(at -13.73632 -5.69595)
			(size 0.381 0.381)
			(layers "F.Cu" "F.Mask" "F.Paste")
			(net "TP_PM_SYNC_GTL")
		)
		(pad "V11" smd circle
			(at -12.01928 -5.69595)
			(size 0.381 0.381)
			(layers "F.Cu" "F.Mask" "F.Paste")
			(net "TP_PCH_RSVD3")
		)
		(pad "V15" smd circle
			(at -10.30224 -5.69595)
			(size 0.381 0.381)
			(layers "F.Cu" "F.Mask" "F.Paste")
			(net "FM_PCH_LVC1_THERMTRIP_N")
		)
		(pad "V18" smd circle
			(at -8.5852 -5.69595)
			(size 0.381 0.381)
			(layers "F.Cu" "F.Mask" "F.Paste")
			(net "TP_PCH_HDA_SDI_1")
		)
		(pad "V22" smd circle
			(at -6.86816 -5.69595)
			(size 0.381 0.381)
			(layers "F.Cu" "F.Mask" "F.Paste")
			(net "TP_PCH_DISPA_SDO")
		)
		(pad "V26" smd circle
			(at -5.15112 -5.696458)
			(size 0.381 0.381)
			(layers "F.Cu" "F.Mask" "F.Paste")
			(net "GND")
		)
		(pad "V29" smd circle
			(at -3.43408 -5.69595)
			(size 0.381 0.381)
			(layers "F.Cu" "F.Mask" "F.Paste")
			(net "PVNN_PCH_STBY")
		)
		(pad "V33" smd circle
			(at -1.71704 -5.69595)
			(size 0.381 0.381)
			(layers "F.Cu" "F.Mask" "F.Paste")
			(net "PVNN_PCH_STBY")
		)
		(pad "V37" smd circle
			(at 0 -5.69595)
			(size 0.381 0.381)
			(layers "F.Cu" "F.Mask" "F.Paste")
			(net "VSENSE_PVNN_PCH_STBY_QAT")
		)
		(pad "V40" smd circle
			(at 1.71704 -5.69595)
			(size 0.381 0.381)
			(layers "F.Cu" "F.Mask" "F.Paste")
			(net "PVNN_PCH_STBY")
		)
		(pad "V44" smd circle
			(at 3.43408 -5.69595)
			(size 0.381 0.381)
			(layers "F.Cu" "F.Mask" "F.Paste")
			(net "P1V05_PCH_STBY")
		)
		(pad "V48" smd circle
			(at 5.15112 -5.696458)
			(size 0.381 0.381)
			(layers "F.Cu" "F.Mask" "F.Paste")
			(net "GND")
		)
		(pad "V52" smd circle
			(at 6.86816 -5.69595)
			(size 0.381 0.381)
			(layers "F.Cu" "F.Mask" "F.Paste")
			(net "GND")
		)
		(pad "V56" smd circle
			(at 8.5852 -5.69595)
			(size 0.381 0.381)
			(layers "F.Cu" "F.Mask" "F.Paste")
			(net "TP_PCH_RSVD33")
		)
		(pad "V59" smd circle
			(at 10.30224 -5.69595)
			(size 0.381 0.381)
			(layers "F.Cu" "F.Mask" "F.Paste")
			(net "P3E_CPU0_PE1_PCH_R_RXP<11>")
		)
		(pad "V63" smd circle
			(at 12.01928 -5.69595)
			(size 0.381 0.381)
			(layers "F.Cu" "F.Mask" "F.Paste")
			(net "P3E_CPU0_PE1_PCH_R_RXP<14>")
		)
		(pad "V66" smd circle
			(at 13.73632 -5.69595)
			(size 0.381 0.381)
			(layers "F.Cu" "F.Mask" "F.Paste")
			(net "GND")
		)
		(pad "V68" smd circle
			(at 14.649958 -5.999988)
			(size 0.3048 0.3048)
			(layers "F.Cu" "F.Mask" "F.Paste")
			(net "GND")
		)
		(pad "V70" smd circle
			(at 15.48003 -5.999988)
			(size 0.3048 0.3048)
			(layers "F.Cu" "F.Mask" "F.Paste")
			(net "SATA6G_PCH_PCIE_UP_SATA_TXN<1>")
		)
		(pad "V72" smd oval
			(at 16.310102 -5.999988 180)
			(size 0.254 0.3302)
			(layers "F.Cu" "F.Mask" "F.Paste")
			(net "SATA6G_PCH_PCIE_UP_SATA_TXP<1>")
		)
		(pad "W2" smd circle
			(at -15.895066 -5.500116 180)
			(size 0.3048 0.3048)
			(layers "F.Cu" "F.Mask" "F.Paste")
			(net "LPC_LAD2_IO2")
		)
		(pad "W4" smd circle
			(at -15.064994 -5.500116 180)
			(size 0.3048 0.3048)
			(layers "F.Cu" "F.Mask" "F.Paste")
			(net "Net_16")
		)
		(pad "W9" smd circle
			(at -12.8778 -5.20065)
			(size 0.381 0.381)
			(layers "F.Cu" "F.Mask" "F.Paste")
			(net "GND")
		)
		(pad "W13" smd circle
			(at -11.16076 -5.20065)
			(size 0.381 0.381)
			(layers "F.Cu" "F.Mask" "F.Paste")
			(net "GND")
		)
		(pad "W17" smd circle
			(at -9.44372 -5.20065)
			(size 0.381 0.381)
			(layers "F.Cu" "F.Mask" "F.Paste")
			(net "GND")
		)
		(pad "W20" smd circle
			(at -7.72668 -5.20065)
			(size 0.381 0.381)
			(layers "F.Cu" "F.Mask" "F.Paste")
			(net "GND")
		)
		(pad "W24" smd circle
			(at -6.00964 -5.20065)
			(size 0.381 0.381)
			(layers "F.Cu" "F.Mask" "F.Paste")
			(net "GND")
		)
		(pad "W50" smd circle
			(at 6.00964 -5.20065)
			(size 0.381 0.381)
			(layers "F.Cu" "F.Mask" "F.Paste")
			(net "P1V05_PCH_STBY_ISCLK_PLL")
		)
		(pad "W54" smd circle
			(at 7.72668 -5.20065)
			(size 0.381 0.381)
			(layers "F.Cu" "F.Mask" "F.Paste")
			(net "TP_PCH_RSVD35")
		)
		(pad "W58" smd circle
			(at 9.44372 -5.20065)
			(size 0.381 0.381)
			(layers "F.Cu" "F.Mask" "F.Paste")
			(net "GND")
		)
		(pad "W61" smd circle
			(at 11.16076 -5.20065)
			(size 0.381 0.381)
			(layers "F.Cu" "F.Mask" "F.Paste")
			(net "GND")
		)
		(pad "W65" smd circle
			(at 12.8778 -5.20065)
			(size 0.381 0.381)
			(layers "F.Cu" "F.Mask" "F.Paste")
			(net "P3E_CPU0_PE1_PCH_R_RXN<14>")
		)
		(pad "W69" smd circle
			(at 15.064994 -5.500116)
			(size 0.3048 0.3048)
			(layers "F.Cu" "F.Mask" "F.Paste")
			(net "SATA6G_PCH_PCIE_UP_SATA_TXN<0>")
		)
		(pad "W71" smd circle
			(at 15.895066 -5.500116)
			(size 0.3048 0.3048)
			(layers "F.Cu" "F.Mask" "F.Paste")
			(net "SATA6G_PCH_PCIE_UP_SATA_TXP<0>")
		)
		(pad "Y1" smd oval
			(at -16.310102 -4.99999 180)
			(size 0.254 0.3302)
			(layers "F.Cu" "F.Mask" "F.Paste")
			(net "LPC_LAD3_IO3")
		)
		(pad "Y3" smd circle
			(at -15.48003 -4.99999 180)
			(size 0.3048 0.3048)
			(layers "F.Cu" "F.Mask" "F.Paste")
			(net "LPC_LAD0_IO0")
		)
		(pad "Y5" smd circle
			(at -14.649958 -4.99999 180)
			(size 0.3048 0.3048)
			(layers "F.Cu" "F.Mask" "F.Paste")
			(net "GND")
		)
		(pad "Y7" smd circle
			(at -13.73632 -4.70535)
			(size 0.381 0.381)
			(layers "F.Cu" "F.Mask" "F.Paste")
			(net "FM_CPU0_PROCHOT_PCH_N")
		)
		(pad "Y11" smd circle
			(at -12.01928 -4.70535)
			(size 0.381 0.381)
			(layers "F.Cu" "F.Mask" "F.Paste")
			(net "H_CPU1_MEMKLM_MEMHOT_PCH_N")
		)
		(pad "Y15" smd circle
			(at -10.30224 -4.70535)
			(size 0.381 0.381)
			(layers "F.Cu" "F.Mask" "F.Paste")
			(net "H_CPU0_MEMABC_MEMHOT_PCH_N")
		)
		(pad "Y18" smd circle
			(at -8.5852 -4.70535)
			(size 0.381 0.381)
			(layers "F.Cu" "F.Mask" "F.Paste")
			(net "FM_PRSNT_2_4_N")
		)
		(pad "Y22" smd circle
			(at -6.86816 -4.70535)
			(size 0.381 0.381)
			(layers "F.Cu" "F.Mask" "F.Paste")
			(net "GND")
		)
		(pad "Y26" smd circle
			(at -5.20065 -5.04825 180)
			(size 0.381 0.381)
			(layers "F.Cu" "F.Mask" "F.Paste")
			(net "P1V05_PCH_STBY")
		)
		(pad "Y27" smd circle
			(at -4.40055 -5.04825 180)
			(size 0.381 0.381)
			(layers "F.Cu" "F.Mask" "F.Paste")
			(net "GND")
		)
		(pad "Y29" smd circle
			(at -3.60045 -5.04825 180)
			(size 0.381 0.381)
			(layers "F.Cu" "F.Mask" "F.Paste")
			(net "PVNN_PCH_STBY")
		)
		(pad "Y30" smd circle
			(at -2.80035 -5.04825 180)
			(size 0.381 0.381)
			(layers "F.Cu" "F.Mask" "F.Paste")
			(net "PVNN_PCH_STBY")
		)
		(pad "Y32" smd circle
			(at -2.00025 -5.04825 180)
			(size 0.381 0.381)
			(layers "F.Cu" "F.Mask" "F.Paste")
			(net "PVNN_PCH_STBY")
		)
		(pad "Y34" smd circle
			(at -1.20015 -5.04825 180)
			(size 0.381 0.381)
			(layers "F.Cu" "F.Mask" "F.Paste")
			(net "PVNN_PCH_STBY")
		)
		(pad "Y36" smd circle
			(at -0.40005 -5.04825 180)
			(size 0.381 0.381)
			(layers "F.Cu" "F.Mask" "F.Paste")
			(net "PVNN_PCH_STBY")
		)
		(pad "Y37" smd circle
			(at 0.40005 -5.04825 180)
			(size 0.381 0.381)
			(layers "F.Cu" "F.Mask" "F.Paste")
			(net "PVNN_PCH_STBY")
		)
		(pad "Y39" smd circle
			(at 1.20015 -5.04825 180)
			(size 0.381 0.381)
			(layers "F.Cu" "F.Mask" "F.Paste")
			(net "PVNN_PCH_STBY")
		)
		(pad "Y41" smd circle
			(at 2.00025 -5.04825 180)
			(size 0.381 0.381)
			(layers "F.Cu" "F.Mask" "F.Paste")
			(net "PVNN_PCH_STBY")
		)
		(pad "Y43" smd circle
			(at 2.80035 -5.04825 180)
			(size 0.381 0.381)
			(layers "F.Cu" "F.Mask" "F.Paste")
			(net "GND")
		)
		(pad "Y45" smd circle
			(at 3.60045 -5.04825 180)
			(size 0.381 0.381)
			(layers "F.Cu" "F.Mask" "F.Paste")
			(net "P1V05_PCH_STBY")
		)
		(pad "Y46" smd circle
			(at 4.40055 -5.04825 180)
			(size 0.381 0.381)
			(layers "F.Cu" "F.Mask" "F.Paste")
			(net "P1V05_PCH_STBY")
		)
		(pad "Y48" smd circle
			(at 5.20065 -5.04825 180)
			(size 0.381 0.381)
			(layers "F.Cu" "F.Mask" "F.Paste")
			(net "GND")
		)
		(pad "Y52" smd circle
			(at 6.86816 -4.70535)
			(size 0.381 0.381)
			(layers "F.Cu" "F.Mask" "F.Paste")
			(net "GND")
		)
		(pad "Y56" smd circle
			(at 8.5852 -4.70535)
			(size 0.381 0.381)
			(layers "F.Cu" "F.Mask" "F.Paste")
			(net "TP_PCH_RSVD34")
		)
		(pad "Y59" smd circle
			(at 10.30224 -4.70535)
			(size 0.381 0.381)
			(layers "F.Cu" "F.Mask" "F.Paste")
			(net "GND")
		)
		(pad "Y63" smd circle
			(at 12.01928 -4.70535)
			(size 0.381 0.381)
			(layers "F.Cu" "F.Mask" "F.Paste")
			(net "GND")
		)
		(pad "Y66" smd circle
			(at 13.73632 -4.70535)
			(size 0.381 0.381)
			(layers "F.Cu" "F.Mask" "F.Paste")
			(net "P3E_CPU0_PE1_PCH_R_RXN<15>")
		)
		(pad "Y68" smd circle
			(at 14.649958 -4.99999)
			(size 0.3048 0.3048)
			(layers "F.Cu" "F.Mask" "F.Paste")
			(net "GND")
		)
		(pad "Y70" smd circle
			(at 15.48003 -4.99999)
			(size 0.3048 0.3048)
			(layers "F.Cu" "F.Mask" "F.Paste")
			(net "GND")
		)
		(pad "Y72" smd oval
			(at 16.310102 -4.99999 180)
			(size 0.254 0.3302)
			(layers "F.Cu" "F.Mask" "F.Paste")
			(net "GND")
		)
		(zone
			(layer "F.Cu")
			(hatch none 0.5)
			(connect_pads
				(clearance 0)
			)
			(min_thickness 0.25)
			(keepout
				(tracks not_allowed)
				(vias allowed)
				(pads allowed)
				(copperpour not_allowed)
				(footprints allowed)
			)
			(placement
				(enabled no)
				(sheetname "")
			)
			(fill
				(thermal_gap 0.5)
				(thermal_bridge_width 0.5)
				(island_removal_mode 0)
			)
			(polygon
				(pts
					(arc
						(start 381.620268 -114.065812)
						(mid 381.601955 -114.1476)
						(end 381.620268 -114.229388)
					)
					(arc
						(start 381.548386 -114.30127)
						(mid 381.504237 -114.1476)
						(end 381.548386 -113.99393)
					)
				)
			)
		)
		(zone
			(layer "F.Cu")
			(hatch none 0.5)
			(connect_pads
				(clearance 0)
			)
			(min_thickness 0.25)
			(keepout
				(tracks not_allowed)
				(vias allowed)
				(pads allowed)
				(copperpour not_allowed)
				(footprints allowed)
			)
			(placement
				(enabled no)
				(sheetname "")
			)
			(fill
				(thermal_gap 0.5)
				(thermal_bridge_width 0.5)
				(island_removal_mode 0)
			)
			(polygon
				(pts
					(arc
						(start 381.620268 -108.914692)
						(mid 381.601955 -108.99648)
						(end 381.620268 -109.078268)
					)
					(arc
						(start 381.548386 -109.15015)
						(mid 381.504237 -108.99648)
						(end 381.548386 -108.84281)
					)
				)
			)
		)
		(zone
			(layer "F.Cu")
			(hatch none 0.5)
			(connect_pads
				(clearance 0)
			)
			(min_thickness 0.25)
			(keepout
				(tracks not_allowed)
				(vias allowed)
				(pads allowed)
				(copperpour not_allowed)
				(footprints allowed)
			)
			(placement
				(enabled no)
				(sheetname "")
			)
			(fill
				(thermal_gap 0.5)
				(thermal_bridge_width 0.5)
				(island_removal_mode 0)
			)
			(polygon
				(pts
					(arc
						(start 381.620268 -107.197652)
						(mid 381.601955 -107.27944)
						(end 381.620268 -107.361228)
					)
					(arc
						(start 381.548386 -107.43311)
						(mid 381.504237 -107.27944)
						(end 381.548386 -107.12577)
					)
				)
			)
		)
		(zone
			(layer "F.Cu")
			(hatch none 0.5)
			(connect_pads
				(clearance 0)
			)
			(min_thickness 0.25)
			(keepout
				(tracks not_allowed)
				(vias allowed)
				(pads allowed)
				(copperpour not_allowed)
				(footprints allowed)
			)
			(placement
				(enabled no)
				(sheetname "")
			)
			(fill
				(thermal_gap 0.5)
				(thermal_bridge_width 0.5)
				(island_removal_mode 0)
			)
			(polygon
				(pts
					(arc
						(start 381.711962 -114.321082)
						(mid 381.79375 -114.339395)
						(end 381.875538 -114.321082)
					)
					(arc
						(start 381.94742 -114.392964)
						(mid 381.79375 -114.437113)
						(end 381.64008 -114.392964)
					)
				)
			)
		)
		(zone
			(layer "F.Cu")
			(hatch none 0.5)
			(connect_pads
				(clearance 0)
			)
			(min_thickness 0.25)
			(keepout
				(tracks not_allowed)
				(vias allowed)
				(pads allowed)
				(copperpour not_allowed)
				(footprints allowed)
			)
			(placement
				(enabled no)
				(sheetname "")
			)
			(fill
				(thermal_gap 0.5)
				(thermal_bridge_width 0.5)
				(island_removal_mode 0)
			)
			(polygon
				(pts
					(arc
						(start 381.711962 -109.169962)
						(mid 381.79375 -109.188275)
						(end 381.875538 -109.169962)
					)
					(arc
						(start 381.94742 -109.241844)
						(mid 381.79375 -109.285993)
						(end 381.64008 -109.241844)
					)
				)
			)
		)
		(zone
			(layer "F.Cu")
			(hatch none 0.5)
			(connect_pads
				(clearance 0)
			)
			(min_thickness 0.25)
			(keepout
				(tracks not_allowed)
				(vias allowed)
				(pads allowed)
				(copperpour not_allowed)
				(footprints allowed)
			)
			(placement
				(enabled no)
				(sheetname "")
			)
			(fill
				(thermal_gap 0.5)
				(thermal_bridge_width 0.5)
				(island_removal_mode 0)
			)
			(polygon
				(pts
					(arc
						(start 381.711962 -107.452922)
						(mid 381.79375 -107.471235)
						(end 381.875538 -107.452922)
					)
					(arc
						(start 381.94742 -107.524804)
						(mid 381.79375 -107.568953)
						(end 381.64008 -107.524804)
					)
				)
			)
		)
		(zone
			(layer "F.Cu")
			(hatch none 0.5)
			(connect_pads
				(clearance 0)
			)
			(min_thickness 0.25)
			(keepout
				(tracks not_allowed)
				(vias allowed)
				(pads allowed)
				(copperpour not_allowed)
				(footprints allowed)
			)
			(placement
				(enabled no)
				(sheetname "")
			)
			(fill
				(thermal_gap 0.5)
				(thermal_bridge_width 0.5)
				(island_removal_mode 0)
			)
			(polygon
				(pts
					(arc
						(start 381.875538 -113.974118)
						(mid 381.79375 -113.955805)
						(end 381.711962 -113.974118)
					)
					(arc
						(start 381.64008 -113.902236)
						(mid 381.79375 -113.858087)
						(end 381.94742 -113.902236)
					)
				)
			)
		)
		(zone
			(layer "F.Cu")
			(hatch none 0.5)
			(connect_pads
				(clearance 0)
			)
			(min_thickness 0.25)
			(keepout
				(tracks not_allowed)
				(vias allowed)
				(pads allowed)
				(copperpour not_allowed)
				(footprints allowed)
			)
			(placement
				(enabled no)
				(sheetname "")
			)
			(fill
				(thermal_gap 0.5)
				(thermal_bridge_width 0.5)
				(island_removal_mode 0)
			)
			(polygon
				(pts
					(arc
						(start 381.875538 -108.822998)
						(mid 381.79375 -108.804685)
						(end 381.711962 -108.822998)
					)
					(arc
						(start 381.64008 -108.751116)
						(mid 381.79375 -108.706967)
						(end 381.94742 -108.751116)
					)
				)
			)
		)
		(zone
			(layer "F.Cu")
			(hatch none 0.5)
			(connect_pads
				(clearance 0)
			)
			(min_thickness 0.25)
			(keepout
				(tracks not_allowed)
				(vias allowed)
				(pads allowed)
				(copperpour not_allowed)
				(footprints allowed)
			)
			(placement
				(enabled no)
				(sheetname "")
			)
			(fill
				(thermal_gap 0.5)
				(thermal_bridge_width 0.5)
				(island_removal_mode 0)
			)
			(polygon
				(pts
					(arc
						(start 381.875538 -107.105958)
						(mid 381.79375 -107.087645)
						(end 381.711962 -107.105958)
					)
					(arc
						(start 381.64008 -107.034076)
						(mid 381.79375 -106.989927)
						(end 381.94742 -107.034076)
					)
				)
			)
		)
		(zone
			(layer "F.Cu")
			(hatch none 0.5)
			(connect_pads
				(clearance 0)
			)
			(min_thickness 0.25)
			(keepout
				(tracks not_allowed)
				(vias allowed)
				(pads allowed)
				(copperpour not_allowed)
				(footprints allowed)
			)
			(placement
				(enabled no)
				(sheetname "")
			)
			(fill
				(thermal_gap 0.5)
				(thermal_bridge_width 0.5)
				(island_removal_mode 0)
			)
			(polygon
				(pts
					(arc
						(start 381.967232 -114.229388)
						(mid 381.985545 -114.1476)
						(end 381.967232 -114.065812)
					)
					(arc
						(start 382.039114 -113.99393)
						(mid 382.083263 -114.1476)
						(end 382.039114 -114.30127)
					)
				)
			)
		)
		(zone
			(layer "F.Cu")
			(hatch none 0.5)
			(connect_pads
				(clearance 0)
			)
			(min_thickness 0.25)
			(keepout
				(tracks not_allowed)
				(vias allowed)
				(pads allowed)
				(copperpour not_allowed)
				(footprints allowed)
			)
			(placement
				(enabled no)
				(sheetname "")
			)
			(fill
				(thermal_gap 0.5)
				(thermal_bridge_width 0.5)
				(island_removal_mode 0)
			)
			(polygon
				(pts
					(arc
						(start 381.967232 -109.078268)
						(mid 381.985545 -108.99648)
						(end 381.967232 -108.914692)
					)
					(arc
						(start 382.039114 -108.84281)
						(mid 382.083263 -108.99648)
						(end 382.039114 -109.15015)
					)
				)
			)
		)
		(zone
			(layer "F.Cu")
			(hatch none 0.5)
			(connect_pads
				(clearance 0)
			)
			(min_thickness 0.25)
			(keepout
				(tracks not_allowed)
				(vias allowed)
				(pads allowed)
				(copperpour not_allowed)
				(footprints allowed)
			)
			(placement
				(enabled no)
				(sheetname "")
			)
			(fill
				(thermal_gap 0.5)
				(thermal_bridge_width 0.5)
				(island_removal_mode 0)
			)
			(polygon
				(pts
					(arc
						(start 381.967232 -107.361228)
						(mid 381.985545 -107.27944)
						(end 381.967232 -107.197652)
					)
					(arc
						(start 382.039114 -107.12577)
						(mid 382.083263 -107.27944)
						(end 382.039114 -107.43311)
					)
				)
			)
		)
		(zone
			(layer "F.Cu")
			(hatch none 0.5)
			(connect_pads
				(clearance 0)
			)
			(min_thickness 0.25)
			(keepout
				(tracks not_allowed)
				(vias allowed)
				(pads allowed)
				(copperpour not_allowed)
				(footprints allowed)
			)
			(placement
				(enabled no)
				(sheetname "")
			)
			(fill
				(thermal_gap 0.5)
				(thermal_bridge_width 0.5)
				(island_removal_mode 0)
			)
			(polygon
				(pts
					(arc
						(start 382.11506 -104.622092)
						(mid 382.096747 -104.70388)
						(end 382.11506 -104.785668)
					)
					(arc
						(start 382.043178 -104.85755)
						(mid 381.999029 -104.70388)
						(end 382.043178 -104.55021)
					)
				)
			)
		)
		(zone
			(layer "F.Cu")
			(hatch none 0.5)
			(connect_pads
				(clearance 0)
			)
			(min_thickness 0.25)
			(keepout
				(tracks not_allowed)
				(vias allowed)
				(pads allowed)
				(copperpour not_allowed)
				(footprints allowed)
			)
			(placement
				(enabled no)
				(sheetname "")
			)
			(fill
				(thermal_gap 0.5)
				(thermal_bridge_width 0.5)
				(island_removal_mode 0)
			)
			(polygon
				(pts
					(arc
						(start 382.115568 -108.056172)
						(mid 382.097255 -108.13796)
						(end 382.115568 -108.219748)
					)
					(arc
						(start 382.043686 -108.29163)
						(mid 381.999537 -108.13796)
						(end 382.043686 -107.98429)
					)
				)
			)
		)
		(zone
			(layer "F.Cu")
			(hatch none 0.5)
			(connect_pads
				(clearance 0)
			)
			(min_thickness 0.25)
			(keepout
				(tracks not_allowed)
				(vias allowed)
				(pads allowed)
				(copperpour not_allowed)
				(footprints allowed)
			)
			(placement
				(enabled no)
				(sheetname "")
			)
			(fill
				(thermal_gap 0.5)
				(thermal_bridge_width 0.5)
				(island_removal_mode 0)
			)
			(polygon
				(pts
					(arc
						(start 382.115568 -106.339132)
						(mid 382.097255 -106.42092)
						(end 382.115568 -106.502708)
					)
					(arc
						(start 382.043686 -106.57459)
						(mid 381.999537 -106.42092)
						(end 382.043686 -106.26725)
					)
				)
			)
		)
		(zone
			(layer "F.Cu")
			(hatch none 0.5)
			(connect_pads
				(clearance 0)
			)
			(min_thickness 0.25)
			(keepout
				(tracks not_allowed)
				(vias allowed)
				(pads allowed)
				(copperpour not_allowed)
				(footprints allowed)
			)
			(placement
				(enabled no)
				(sheetname "")
			)
			(fill
				(thermal_gap 0.5)
				(thermal_bridge_width 0.5)
				(island_removal_mode 0)
			)
			(polygon
				(pts
					(arc
						(start 382.206754 -104.877362)
						(mid 382.288542 -104.895675)
						(end 382.37033 -104.877362)
					)
					(arc
						(start 382.442212 -104.949244)
						(mid 382.288542 -104.993393)
						(end 382.134872 -104.949244)
					)
				)
			)
		)
		(zone
			(layer "F.Cu")
			(hatch none 0.5)
			(connect_pads
				(clearance 0)
			)
			(min_thickness 0.25)
			(keepout
				(tracks not_allowed)
				(vias allowed)
				(pads allowed)
				(copperpour not_allowed)
				(footprints allowed)
			)
			(placement
				(enabled no)
				(sheetname "")
			)
			(fill
				(thermal_gap 0.5)
				(thermal_bridge_width 0.5)
				(island_removal_mode 0)
			)
			(polygon
				(pts
					(arc
						(start 382.207262 -108.311442)
						(mid 382.28905 -108.329755)
						(end 382.370838 -108.311442)
					)
					(arc
						(start 382.44272 -108.383324)
						(mid 382.28905 -108.427473)
						(end 382.13538 -108.383324)
					)
				)
			)
		)
		(zone
			(layer "F.Cu")
			(hatch none 0.5)
			(connect_pads
				(clearance 0)
			)
			(min_thickness 0.25)
			(keepout
				(tracks not_allowed)
				(vias allowed)
				(pads allowed)
				(copperpour not_allowed)
				(footprints allowed)
			)
			(placement
				(enabled no)
				(sheetname "")
			)
			(fill
				(thermal_gap 0.5)
				(thermal_bridge_width 0.5)
				(island_removal_mode 0)
			)
			(polygon
				(pts
					(arc
						(start 382.207262 -106.594402)
						(mid 382.28905 -106.612715)
						(end 382.370838 -106.594402)
					)
					(arc
						(start 382.44272 -106.666284)
						(mid 382.28905 -106.710433)
						(end 382.13538 -106.666284)
					)
				)
			)
		)
		(zone
			(layer "F.Cu")
			(hatch none 0.5)
			(connect_pads
				(clearance 0)
			)
			(min_thickness 0.25)
			(keepout
				(tracks not_allowed)
				(vias allowed)
				(pads allowed)
				(copperpour not_allowed)
				(footprints allowed)
			)
			(placement
				(enabled no)
				(sheetname "")
			)
			(fill
				(thermal_gap 0.5)
				(thermal_bridge_width 0.5)
				(island_removal_mode 0)
			)
			(polygon
				(pts
					(arc
						(start 382.37033 -104.530398)
						(mid 382.288542 -104.512085)
						(end 382.206754 -104.530398)
					)
					(arc
						(start 382.134872 -104.458516)
						(mid 382.288542 -104.414367)
						(end 382.442212 -104.458516)
					)
				)
			)
		)
		(zone
			(layer "F.Cu")
			(hatch none 0.5)
			(connect_pads
				(clearance 0)
			)
			(min_thickness 0.25)
			(keepout
				(tracks not_allowed)
				(vias allowed)
				(pads allowed)
				(copperpour not_allowed)
				(footprints allowed)
			)
			(placement
				(enabled no)
				(sheetname "")
			)
			(fill
				(thermal_gap 0.5)
				(thermal_bridge_width 0.5)
				(island_removal_mode 0)
			)
			(polygon
				(pts
					(arc
						(start 382.370838 -107.964478)
						(mid 382.28905 -107.946165)
						(end 382.207262 -107.964478)
					)
					(arc
						(start 382.13538 -107.892596)
						(mid 382.28905 -107.848447)
						(end 382.44272 -107.892596)
					)
				)
			)
		)
		(zone
			(layer "F.Cu")
			(hatch none 0.5)
			(connect_pads
				(clearance 0)
			)
			(min_thickness 0.25)
			(keepout
				(tracks not_allowed)
				(vias allowed)
				(pads allowed)
				(copperpour not_allowed)
				(footprints allowed)
			)
			(placement
				(enabled no)
				(sheetname "")
			)
			(fill
				(thermal_gap 0.5)
				(thermal_bridge_width 0.5)
				(island_removal_mode 0)
			)
			(polygon
				(pts
					(arc
						(start 382.370838 -106.247438)
						(mid 382.28905 -106.229125)
						(end 382.207262 -106.247438)
					)
					(arc
						(start 382.13538 -106.175556)
						(mid 382.28905 -106.131407)
						(end 382.44272 -106.175556)
					)
				)
			)
		)
		(zone
			(layer "F.Cu")
			(hatch none 0.5)
			(connect_pads
				(clearance 0)
			)
			(min_thickness 0.25)
			(keepout
				(tracks not_allowed)
				(vias allowed)
				(pads allowed)
				(copperpour not_allowed)
				(footprints allowed)
			)
			(placement
				(enabled no)
				(sheetname "")
			)
			(fill
				(thermal_gap 0.5)
				(thermal_bridge_width 0.5)
				(island_removal_mode 0)
			)
			(polygon
				(pts
					(arc
						(start 382.462024 -104.785668)
						(mid 382.480337 -104.70388)
						(end 382.462024 -104.622092)
					)
					(arc
						(start 382.533906 -104.55021)
						(mid 382.578055 -104.70388)
						(end 382.533906 -104.85755)
					)
				)
			)
		)
		(zone
			(layer "F.Cu")
			(hatch none 0.5)
			(connect_pads
				(clearance 0)
			)
			(min_thickness 0.25)
			(keepout
				(tracks not_allowed)
				(vias allowed)
				(pads allowed)
				(copperpour not_allowed)
				(footprints allowed)
			)
			(placement
				(enabled no)
				(sheetname "")
			)
			(fill
				(thermal_gap 0.5)
				(thermal_bridge_width 0.5)
				(island_removal_mode 0)
			)
			(polygon
				(pts
					(arc
						(start 382.462532 -108.219748)
						(mid 382.480845 -108.13796)
						(end 382.462532 -108.056172)
					)
					(arc
						(start 382.534414 -107.98429)
						(mid 382.578563 -108.13796)
						(end 382.534414 -108.29163)
					)
				)
			)
		)
		(zone
			(layer "F.Cu")
			(hatch none 0.5)
			(connect_pads
				(clearance 0)
			)
			(min_thickness 0.25)
			(keepout
				(tracks not_allowed)
				(vias allowed)
				(pads allowed)
				(copperpour not_allowed)
				(footprints allowed)
			)
			(placement
				(enabled no)
				(sheetname "")
			)
			(fill
				(thermal_gap 0.5)
				(thermal_bridge_width 0.5)
				(island_removal_mode 0)
			)
			(polygon
				(pts
					(arc
						(start 382.462532 -106.502708)
						(mid 382.480845 -106.42092)
						(end 382.462532 -106.339132)
					)
					(arc
						(start 382.534414 -106.26725)
						(mid 382.578563 -106.42092)
						(end 382.534414 -106.57459)
					)
				)
			)
		)
		(zone
			(layer "F.Cu")
			(hatch none 0.5)
			(connect_pads
				(clearance 0)
			)
			(min_thickness 0.25)
			(keepout
				(tracks not_allowed)
				(vias allowed)
				(pads allowed)
				(copperpour not_allowed)
				(footprints allowed)
			)
			(placement
				(enabled no)
				(sheetname "")
			)
			(fill
				(thermal_gap 0.5)
				(thermal_bridge_width 0.5)
				(island_removal_mode 0)
			)
			(polygon
				(pts
					(arc
						(start 382.763268 -114.973862)
						(mid 382.744955 -115.05565)
						(end 382.763268 -115.137438)
					)
					(arc
						(start 382.691386 -115.20932)
						(mid 382.647237 -115.05565)
						(end 382.691386 -114.90198)
					)
				)
			)
		)
		(zone
			(layer "F.Cu")
			(hatch none 0.5)
			(connect_pads
				(clearance 0)
			)
			(min_thickness 0.25)
			(keepout
				(tracks not_allowed)
				(vias allowed)
				(pads allowed)
				(copperpour not_allowed)
				(footprints allowed)
			)
			(placement
				(enabled no)
				(sheetname "")
			)
			(fill
				(thermal_gap 0.5)
				(thermal_bridge_width 0.5)
				(island_removal_mode 0)
			)
			(polygon
				(pts
					(arc
						(start 382.763268 -114.173762)
						(mid 382.744955 -114.25555)
						(end 382.763268 -114.337338)
					)
					(arc
						(start 382.691386 -114.40922)
						(mid 382.647237 -114.25555)
						(end 382.691386 -114.10188)
					)
				)
			)
		)
		(zone
			(layer "F.Cu")
			(hatch none 0.5)
			(connect_pads
				(clearance 0)
			)
			(min_thickness 0.25)
			(keepout
				(tracks not_allowed)
				(vias allowed)
				(pads allowed)
				(copperpour not_allowed)
				(footprints allowed)
			)
			(placement
				(enabled no)
				(sheetname "")
			)
			(fill
				(thermal_gap 0.5)
				(thermal_bridge_width 0.5)
				(island_removal_mode 0)
			)
			(polygon
				(pts
					(arc
						(start 382.763268 -113.373662)
						(mid 382.744955 -113.45545)
						(end 382.763268 -113.537238)
					)
					(arc
						(start 382.691386 -113.60912)
						(mid 382.647237 -113.45545)
						(end 382.691386 -113.30178)
					)
				)
			)
		)
		(zone
			(layer "F.Cu")
			(hatch none 0.5)
			(connect_pads
				(clearance 0)
			)
			(min_thickness 0.25)
			(keepout
				(tracks not_allowed)
				(vias allowed)
				(pads allowed)
				(copperpour not_allowed)
				(footprints allowed)
			)
			(placement
				(enabled no)
				(sheetname "")
			)
			(fill
				(thermal_gap 0.5)
				(thermal_bridge_width 0.5)
				(island_removal_mode 0)
			)
			(polygon
				(pts
					(arc
						(start 382.763268 -112.573562)
						(mid 382.744955 -112.65535)
						(end 382.763268 -112.737138)
					)
					(arc
						(start 382.691386 -112.80902)
						(mid 382.647237 -112.65535)
						(end 382.691386 -112.50168)
					)
				)
			)
		)
		(zone
			(layer "F.Cu")
			(hatch none 0.5)
			(connect_pads
				(clearance 0)
			)
			(min_thickness 0.25)
			(keepout
				(tracks not_allowed)
				(vias allowed)
				(pads allowed)
				(copperpour not_allowed)
				(footprints allowed)
			)
			(placement
				(enabled no)
				(sheetname "")
			)
			(fill
				(thermal_gap 0.5)
				(thermal_bridge_width 0.5)
				(island_removal_mode 0)
			)
			(polygon
				(pts
					(arc
						(start 382.763268 -111.773462)
						(mid 382.744955 -111.85525)
						(end 382.763268 -111.937038)
					)
					(arc
						(start 382.691386 -112.00892)
						(mid 382.647237 -111.85525)
						(end 382.691386 -111.70158)
					)
				)
			)
		)
		(zone
			(layer "F.Cu")
			(hatch none 0.5)
			(connect_pads
				(clearance 0)
			)
			(min_thickness 0.25)
			(keepout
				(tracks not_allowed)
				(vias allowed)
				(pads allowed)
				(copperpour not_allowed)
				(footprints allowed)
			)
			(placement
				(enabled no)
				(sheetname "")
			)
			(fill
				(thermal_gap 0.5)
				(thermal_bridge_width 0.5)
				(island_removal_mode 0)
			)
			(polygon
				(pts
					(arc
						(start 382.763268 -110.973362)
						(mid 382.744955 -111.05515)
						(end 382.763268 -111.136938)
					)
					(arc
						(start 382.691386 -111.20882)
						(mid 382.647237 -111.05515)
						(end 382.691386 -110.90148)
					)
				)
			)
		)
		(zone
			(layer "F.Cu")
			(hatch none 0.5)
			(connect_pads
				(clearance 0)
			)
			(min_thickness 0.25)
			(keepout
				(tracks not_allowed)
				(vias allowed)
				(pads allowed)
				(copperpour not_allowed)
				(footprints allowed)
			)
			(placement
				(enabled no)
				(sheetname "")
			)
			(fill
				(thermal_gap 0.5)
				(thermal_bridge_width 0.5)
				(island_removal_mode 0)
			)
			(polygon
				(pts
					(arc
						(start 382.763268 -110.173262)
						(mid 382.744955 -110.25505)
						(end 382.763268 -110.336838)
					)
					(arc
						(start 382.691386 -110.40872)
						(mid 382.647237 -110.25505)
						(end 382.691386 -110.10138)
					)
				)
			)
		)
		(zone
			(layer "F.Cu")
			(hatch none 0.5)
			(connect_pads
				(clearance 0)
			)
			(min_thickness 0.25)
			(keepout
				(tracks not_allowed)
				(vias allowed)
				(pads allowed)
				(copperpour not_allowed)
				(footprints allowed)
			)
			(placement
				(enabled no)
				(sheetname "")
			)
			(fill
				(thermal_gap 0.5)
				(thermal_bridge_width 0.5)
				(island_removal_mode 0)
			)
			(polygon
				(pts
					(arc
						(start 382.763268 -109.373162)
						(mid 382.744955 -109.45495)
						(end 382.763268 -109.536738)
					)
					(arc
						(start 382.691386 -109.60862)
						(mid 382.647237 -109.45495)
						(end 382.691386 -109.30128)
					)
				)
			)
		)
		(zone
			(layer "F.Cu")
			(hatch none 0.5)
			(connect_pads
				(clearance 0)
			)
			(min_thickness 0.25)
			(keepout
				(tracks not_allowed)
				(vias allowed)
				(pads allowed)
				(copperpour not_allowed)
				(footprints allowed)
			)
			(placement
				(enabled no)
				(sheetname "")
			)
			(fill
				(thermal_gap 0.5)
				(thermal_bridge_width 0.5)
				(island_removal_mode 0)
			)
			(polygon
				(pts
					(arc
						(start 382.763268 -108.573062)
						(mid 382.744955 -108.65485)
						(end 382.763268 -108.736638)
					)
					(arc
						(start 382.691386 -108.80852)
						(mid 382.647237 -108.65485)
						(end 382.691386 -108.50118)
					)
				)
			)
		)
		(zone
			(layer "F.Cu")
			(hatch none 0.5)
			(connect_pads
				(clearance 0)
			)
			(min_thickness 0.25)
			(keepout
				(tracks not_allowed)
				(vias allowed)
				(pads allowed)
				(copperpour not_allowed)
				(footprints allowed)
			)
			(placement
				(enabled no)
				(sheetname "")
			)
			(fill
				(thermal_gap 0.5)
				(thermal_bridge_width 0.5)
				(island_removal_mode 0)
			)
			(polygon
				(pts
					(arc
						(start 382.763268 -107.772962)
						(mid 382.744955 -107.85475)
						(end 382.763268 -107.936538)
					)
					(arc
						(start 382.691386 -108.00842)
						(mid 382.647237 -107.85475)
						(end 382.691386 -107.70108)
					)
				)
			)
		)
		(zone
			(layer "F.Cu")
			(hatch none 0.5)
			(connect_pads
				(clearance 0)
			)
			(min_thickness 0.25)
			(keepout
				(tracks not_allowed)
				(vias allowed)
				(pads allowed)
				(copperpour not_allowed)
				(footprints allowed)
			)
			(placement
				(enabled no)
				(sheetname "")
			)
			(fill
				(thermal_gap 0.5)
				(thermal_bridge_width 0.5)
				(island_removal_mode 0)
			)
			(polygon
				(pts
					(arc
						(start 382.763268 -106.972862)
						(mid 382.744955 -107.05465)
						(end 382.763268 -107.136438)
					)
					(arc
						(start 382.691386 -107.20832)
						(mid 382.647237 -107.05465)
						(end 382.691386 -106.90098)
					)
				)
			)
		)
		(zone
			(layer "F.Cu")
			(hatch none 0.5)
			(connect_pads
				(clearance 0)
			)
			(min_thickness 0.25)
			(keepout
				(tracks not_allowed)
				(vias allowed)
				(pads allowed)
				(copperpour not_allowed)
				(footprints allowed)
			)
			(placement
				(enabled no)
				(sheetname "")
			)
			(fill
				(thermal_gap 0.5)
				(thermal_bridge_width 0.5)
				(island_removal_mode 0)
			)
			(polygon
				(pts
					(arc
						(start 382.763268 -106.172762)
						(mid 382.744955 -106.25455)
						(end 382.763268 -106.336338)
					)
					(arc
						(start 382.691386 -106.40822)
						(mid 382.647237 -106.25455)
						(end 382.691386 -106.10088)
					)
				)
			)
		)
		(zone
			(layer "F.Cu")
			(hatch none 0.5)
			(connect_pads
				(clearance 0)
			)
			(min_thickness 0.25)
			(keepout
				(tracks not_allowed)
				(vias allowed)
				(pads allowed)
				(copperpour not_allowed)
				(footprints allowed)
			)
			(placement
				(enabled no)
				(sheetname "")
			)
			(fill
				(thermal_gap 0.5)
				(thermal_bridge_width 0.5)
				(island_removal_mode 0)
			)
			(polygon
				(pts
					(arc
						(start 382.763268 -105.372662)
						(mid 382.744955 -105.45445)
						(end 382.763268 -105.536238)
					)
					(arc
						(start 382.691386 -105.60812)
						(mid 382.647237 -105.45445)
						(end 382.691386 -105.30078)
					)
				)
			)
		)
		(zone
			(layer "F.Cu")
			(hatch none 0.5)
			(connect_pads
				(clearance 0)
			)
			(min_thickness 0.25)
			(keepout
				(tracks not_allowed)
				(vias allowed)
				(pads allowed)
				(copperpour not_allowed)
				(footprints allowed)
			)
			(placement
				(enabled no)
				(sheetname "")
			)
			(fill
				(thermal_gap 0.5)
				(thermal_bridge_width 0.5)
				(island_removal_mode 0)
			)
			(polygon
				(pts
					(arc
						(start 382.854962 -115.229132)
						(mid 382.93675 -115.247445)
						(end 383.018538 -115.229132)
					)
					(arc
						(start 383.09042 -115.301014)
						(mid 382.93675 -115.345163)
						(end 382.78308 -115.301014)
					)
				)
			)
		)
		(zone
			(layer "F.Cu")
			(hatch none 0.5)
			(connect_pads
				(clearance 0)
			)
			(min_thickness 0.25)
			(keepout
				(tracks not_allowed)
				(vias allowed)
				(pads allowed)
				(copperpour not_allowed)
				(footprints allowed)
			)
			(placement
				(enabled no)
				(sheetname "")
			)
			(fill
				(thermal_gap 0.5)
				(thermal_bridge_width 0.5)
				(island_removal_mode 0)
			)
			(polygon
				(pts
					(arc
						(start 382.854962 -114.429032)
						(mid 382.93675 -114.447345)
						(end 383.018538 -114.429032)
					)
					(arc
						(start 383.09042 -114.500914)
						(mid 382.93675 -114.545063)
						(end 382.78308 -114.500914)
					)
				)
			)
		)
		(zone
			(layer "F.Cu")
			(hatch none 0.5)
			(connect_pads
				(clearance 0)
			)
			(min_thickness 0.25)
			(keepout
				(tracks not_allowed)
				(vias allowed)
				(pads allowed)
				(copperpour not_allowed)
				(footprints allowed)
			)
			(placement
				(enabled no)
				(sheetname "")
			)
			(fill
				(thermal_gap 0.5)
				(thermal_bridge_width 0.5)
				(island_removal_mode 0)
			)
			(polygon
				(pts
					(arc
						(start 382.854962 -113.628932)
						(mid 382.93675 -113.647245)
						(end 383.018538 -113.628932)
					)
					(arc
						(start 383.09042 -113.700814)
						(mid 382.93675 -113.744963)
						(end 382.78308 -113.700814)
					)
				)
			)
		)
		(zone
			(layer "F.Cu")
			(hatch none 0.5)
			(connect_pads
				(clearance 0)
			)
			(min_thickness 0.25)
			(keepout
				(tracks not_allowed)
				(vias allowed)
				(pads allowed)
				(copperpour not_allowed)
				(footprints allowed)
			)
			(placement
				(enabled no)
				(sheetname "")
			)
			(fill
				(thermal_gap 0.5)
				(thermal_bridge_width 0.5)
				(island_removal_mode 0)
			)
			(polygon
				(pts
					(arc
						(start 382.854962 -112.828832)
						(mid 382.93675 -112.847145)
						(end 383.018538 -112.828832)
					)
					(arc
						(start 383.09042 -112.900714)
						(mid 382.93675 -112.944863)
						(end 382.78308 -112.900714)
					)
				)
			)
		)
		(zone
			(layer "F.Cu")
			(hatch none 0.5)
			(connect_pads
				(clearance 0)
			)
			(min_thickness 0.25)
			(keepout
				(tracks not_allowed)
				(vias allowed)
				(pads allowed)
				(copperpour not_allowed)
				(footprints allowed)
			)
			(placement
				(enabled no)
				(sheetname "")
			)
			(fill
				(thermal_gap 0.5)
				(thermal_bridge_width 0.5)
				(island_removal_mode 0)
			)
			(polygon
				(pts
					(arc
						(start 382.854962 -112.028732)
						(mid 382.93675 -112.047045)
						(end 383.018538 -112.028732)
					)
					(arc
						(start 383.09042 -112.100614)
						(mid 382.93675 -112.144763)
						(end 382.78308 -112.100614)
					)
				)
			)
		)
		(zone
			(layer "F.Cu")
			(hatch none 0.5)
			(connect_pads
				(clearance 0)
			)
			(min_thickness 0.25)
			(keepout
				(tracks not_allowed)
				(vias allowed)
				(pads allowed)
				(copperpour not_allowed)
				(footprints allowed)
			)
			(placement
				(enabled no)
				(sheetname "")
			)
			(fill
				(thermal_gap 0.5)
				(thermal_bridge_width 0.5)
				(island_removal_mode 0)
			)
			(polygon
				(pts
					(arc
						(start 382.854962 -111.228632)
						(mid 382.93675 -111.246945)
						(end 383.018538 -111.228632)
					)
					(arc
						(start 383.09042 -111.300514)
						(mid 382.93675 -111.344663)
						(end 382.78308 -111.300514)
					)
				)
			)
		)
		(zone
			(layer "F.Cu")
			(hatch none 0.5)
			(connect_pads
				(clearance 0)
			)
			(min_thickness 0.25)
			(keepout
				(tracks not_allowed)
				(vias allowed)
				(pads allowed)
				(copperpour not_allowed)
				(footprints allowed)
			)
			(placement
				(enabled no)
				(sheetname "")
			)
			(fill
				(thermal_gap 0.5)
				(thermal_bridge_width 0.5)
				(island_removal_mode 0)
			)
			(polygon
				(pts
					(arc
						(start 382.854962 -110.428532)
						(mid 382.93675 -110.446845)
						(end 383.018538 -110.428532)
					)
					(arc
						(start 383.09042 -110.500414)
						(mid 382.93675 -110.544563)
						(end 382.78308 -110.500414)
					)
				)
			)
		)
		(zone
			(layer "F.Cu")
			(hatch none 0.5)
			(connect_pads
				(clearance 0)
			)
			(min_thickness 0.25)
			(keepout
				(tracks not_allowed)
				(vias allowed)
				(pads allowed)
				(copperpour not_allowed)
				(footprints allowed)
			)
			(placement
				(enabled no)
				(sheetname "")
			)
			(fill
				(thermal_gap 0.5)
				(thermal_bridge_width 0.5)
				(island_removal_mode 0)
			)
			(polygon
				(pts
					(arc
						(start 382.854962 -109.628432)
						(mid 382.93675 -109.646745)
						(end 383.018538 -109.628432)
					)
					(arc
						(start 383.09042 -109.700314)
						(mid 382.93675 -109.744463)
						(end 382.78308 -109.700314)
					)
				)
			)
		)
		(zone
			(layer "F.Cu")
			(hatch none 0.5)
			(connect_pads
				(clearance 0)
			)
			(min_thickness 0.25)
			(keepout
				(tracks not_allowed)
				(vias allowed)
				(pads allowed)
				(copperpour not_allowed)
				(footprints allowed)
			)
			(placement
				(enabled no)
				(sheetname "")
			)
			(fill
				(thermal_gap 0.5)
				(thermal_bridge_width 0.5)
				(island_removal_mode 0)
			)
			(polygon
				(pts
					(arc
						(start 382.854962 -108.828332)
						(mid 382.93675 -108.846645)
						(end 383.018538 -108.828332)
					)
					(arc
						(start 383.09042 -108.900214)
						(mid 382.93675 -108.944363)
						(end 382.78308 -108.900214)
					)
				)
			)
		)
		(zone
			(layer "F.Cu")
			(hatch none 0.5)
			(connect_pads
				(clearance 0)
			)
			(min_thickness 0.25)
			(keepout
				(tracks not_allowed)
				(vias allowed)
				(pads allowed)
				(copperpour not_allowed)
				(footprints allowed)
			)
			(placement
				(enabled no)
				(sheetname "")
			)
			(fill
				(thermal_gap 0.5)
				(thermal_bridge_width 0.5)
				(island_removal_mode 0)
			)
			(polygon
				(pts
					(arc
						(start 382.854962 -108.028232)
						(mid 382.93675 -108.046545)
						(end 383.018538 -108.028232)
					)
					(arc
						(start 383.09042 -108.100114)
						(mid 382.93675 -108.144263)
						(end 382.78308 -108.100114)
					)
				)
			)
		)
		(zone
			(layer "F.Cu")
			(hatch none 0.5)
			(connect_pads
				(clearance 0)
			)
			(min_thickness 0.25)
			(keepout
				(tracks not_allowed)
				(vias allowed)
				(pads allowed)
				(copperpour not_allowed)
				(footprints allowed)
			)
			(placement
				(enabled no)
				(sheetname "")
			)
			(fill
				(thermal_gap 0.5)
				(thermal_bridge_width 0.5)
				(island_removal_mode 0)
			)
			(polygon
				(pts
					(arc
						(start 382.854962 -107.228132)
						(mid 382.93675 -107.246445)
						(end 383.018538 -107.228132)
					)
					(arc
						(start 383.09042 -107.300014)
						(mid 382.93675 -107.344163)
						(end 382.78308 -107.300014)
					)
				)
			)
		)
		(zone
			(layer "F.Cu")
			(hatch none 0.5)
			(connect_pads
				(clearance 0)
			)
			(min_thickness 0.25)
			(keepout
				(tracks not_allowed)
				(vias allowed)
				(pads allowed)
				(copperpour not_allowed)
				(footprints allowed)
			)
			(placement
				(enabled no)
				(sheetname "")
			)
			(fill
				(thermal_gap 0.5)
				(thermal_bridge_width 0.5)
				(island_removal_mode 0)
			)
			(polygon
				(pts
					(arc
						(start 382.854962 -106.428032)
						(mid 382.93675 -106.446345)
						(end 383.018538 -106.428032)
					)
					(arc
						(start 383.09042 -106.499914)
						(mid 382.93675 -106.544063)
						(end 382.78308 -106.499914)
					)
				)
			)
		)
		(zone
			(layer "F.Cu")
			(hatch none 0.5)
			(connect_pads
				(clearance 0)
			)
			(min_thickness 0.25)
			(keepout
				(tracks not_allowed)
				(vias allowed)
				(pads allowed)
				(copperpour not_allowed)
				(footprints allowed)
			)
			(placement
				(enabled no)
				(sheetname "")
			)
			(fill
				(thermal_gap 0.5)
				(thermal_bridge_width 0.5)
				(island_removal_mode 0)
			)
			(polygon
				(pts
					(arc
						(start 382.854962 -105.627932)
						(mid 382.93675 -105.646245)
						(end 383.018538 -105.627932)
					)
					(arc
						(start 383.09042 -105.699814)
						(mid 382.93675 -105.743963)
						(end 382.78308 -105.699814)
					)
				)
			)
		)
		(zone
			(layer "F.Cu")
			(hatch none 0.5)
			(connect_pads
				(clearance 0)
			)
			(min_thickness 0.25)
			(keepout
				(tracks not_allowed)
				(vias allowed)
				(pads allowed)
				(copperpour not_allowed)
				(footprints allowed)
			)
			(placement
				(enabled no)
				(sheetname "")
			)
			(fill
				(thermal_gap 0.5)
				(thermal_bridge_width 0.5)
				(island_removal_mode 0)
			)
			(polygon
				(pts
					(arc
						(start 383.018538 -114.882168)
						(mid 382.93675 -114.863855)
						(end 382.854962 -114.882168)
					)
					(arc
						(start 382.78308 -114.810286)
						(mid 382.93675 -114.766137)
						(end 383.09042 -114.810286)
					)
				)
			)
		)
		(zone
			(layer "F.Cu")
			(hatch none 0.5)
			(connect_pads
				(clearance 0)
			)
			(min_thickness 0.25)
			(keepout
				(tracks not_allowed)
				(vias allowed)
				(pads allowed)
				(copperpour not_allowed)
				(footprints allowed)
			)
			(placement
				(enabled no)
				(sheetname "")
			)
			(fill
				(thermal_gap 0.5)
				(thermal_bridge_width 0.5)
				(island_removal_mode 0)
			)
			(polygon
				(pts
					(arc
						(start 383.018538 -114.082068)
						(mid 382.93675 -114.063755)
						(end 382.854962 -114.082068)
					)
					(arc
						(start 382.78308 -114.010186)
						(mid 382.93675 -113.966037)
						(end 383.09042 -114.010186)
					)
				)
			)
		)
		(zone
			(layer "F.Cu")
			(hatch none 0.5)
			(connect_pads
				(clearance 0)
			)
			(min_thickness 0.25)
			(keepout
				(tracks not_allowed)
				(vias allowed)
				(pads allowed)
				(copperpour not_allowed)
				(footprints allowed)
			)
			(placement
				(enabled no)
				(sheetname "")
			)
			(fill
				(thermal_gap 0.5)
				(thermal_bridge_width 0.5)
				(island_removal_mode 0)
			)
			(polygon
				(pts
					(arc
						(start 383.018538 -113.281968)
						(mid 382.93675 -113.263655)
						(end 382.854962 -113.281968)
					)
					(arc
						(start 382.78308 -113.210086)
						(mid 382.93675 -113.165937)
						(end 383.09042 -113.210086)
					)
				)
			)
		)
		(zone
			(layer "F.Cu")
			(hatch none 0.5)
			(connect_pads
				(clearance 0)
			)
			(min_thickness 0.25)
			(keepout
				(tracks not_allowed)
				(vias allowed)
				(pads allowed)
				(copperpour not_allowed)
				(footprints allowed)
			)
			(placement
				(enabled no)
				(sheetname "")
			)
			(fill
				(thermal_gap 0.5)
				(thermal_bridge_width 0.5)
				(island_removal_mode 0)
			)
			(polygon
				(pts
					(arc
						(start 383.018538 -112.481868)
						(mid 382.93675 -112.463555)
						(end 382.854962 -112.481868)
					)
					(arc
						(start 382.78308 -112.409986)
						(mid 382.93675 -112.365837)
						(end 383.09042 -112.409986)
					)
				)
			)
		)
		(zone
			(layer "F.Cu")
			(hatch none 0.5)
			(connect_pads
				(clearance 0)
			)
			(min_thickness 0.25)
			(keepout
				(tracks not_allowed)
				(vias allowed)
				(pads allowed)
				(copperpour not_allowed)
				(footprints allowed)
			)
			(placement
				(enabled no)
				(sheetname "")
			)
			(fill
				(thermal_gap 0.5)
				(thermal_bridge_width 0.5)
				(island_removal_mode 0)
			)
			(polygon
				(pts
					(arc
						(start 383.018538 -111.681768)
						(mid 382.93675 -111.663455)
						(end 382.854962 -111.681768)
					)
					(arc
						(start 382.78308 -111.609886)
						(mid 382.93675 -111.565737)
						(end 383.09042 -111.609886)
					)
				)
			)
		)
		(zone
			(layer "F.Cu")
			(hatch none 0.5)
			(connect_pads
				(clearance 0)
			)
			(min_thickness 0.25)
			(keepout
				(tracks not_allowed)
				(vias allowed)
				(pads allowed)
				(copperpour not_allowed)
				(footprints allowed)
			)
			(placement
				(enabled no)
				(sheetname "")
			)
			(fill
				(thermal_gap 0.5)
				(thermal_bridge_width 0.5)
				(island_removal_mode 0)
			)
			(polygon
				(pts
					(arc
						(start 383.018538 -110.881668)
						(mid 382.93675 -110.863355)
						(end 382.854962 -110.881668)
					)
					(arc
						(start 382.78308 -110.809786)
						(mid 382.93675 -110.765637)
						(end 383.09042 -110.809786)
					)
				)
			)
		)
		(zone
			(layer "F.Cu")
			(hatch none 0.5)
			(connect_pads
				(clearance 0)
			)
			(min_thickness 0.25)
			(keepout
				(tracks not_allowed)
				(vias allowed)
				(pads allowed)
				(copperpour not_allowed)
				(footprints allowed)
			)
			(placement
				(enabled no)
				(sheetname "")
			)
			(fill
				(thermal_gap 0.5)
				(thermal_bridge_width 0.5)
				(island_removal_mode 0)
			)
			(polygon
				(pts
					(arc
						(start 383.018538 -110.081568)
						(mid 382.93675 -110.063255)
						(end 382.854962 -110.081568)
					)
					(arc
						(start 382.78308 -110.009686)
						(mid 382.93675 -109.965537)
						(end 383.09042 -110.009686)
					)
				)
			)
		)
		(zone
			(layer "F.Cu")
			(hatch none 0.5)
			(connect_pads
				(clearance 0)
			)
			(min_thickness 0.25)
			(keepout
				(tracks not_allowed)
				(vias allowed)
				(pads allowed)
				(copperpour not_allowed)
				(footprints allowed)
			)
			(placement
				(enabled no)
				(sheetname "")
			)
			(fill
				(thermal_gap 0.5)
				(thermal_bridge_width 0.5)
				(island_removal_mode 0)
			)
			(polygon
				(pts
					(arc
						(start 383.018538 -109.281468)
						(mid 382.93675 -109.263155)
						(end 382.854962 -109.281468)
					)
					(arc
						(start 382.78308 -109.209586)
						(mid 382.93675 -109.165437)
						(end 383.09042 -109.209586)
					)
				)
			)
		)
		(zone
			(layer "F.Cu")
			(hatch none 0.5)
			(connect_pads
				(clearance 0)
			)
			(min_thickness 0.25)
			(keepout
				(tracks not_allowed)
				(vias allowed)
				(pads allowed)
				(copperpour not_allowed)
				(footprints allowed)
			)
			(placement
				(enabled no)
				(sheetname "")
			)
			(fill
				(thermal_gap 0.5)
				(thermal_bridge_width 0.5)
				(island_removal_mode 0)
			)
			(polygon
				(pts
					(arc
						(start 383.018538 -108.481368)
						(mid 382.93675 -108.463055)
						(end 382.854962 -108.481368)
					)
					(arc
						(start 382.78308 -108.409486)
						(mid 382.93675 -108.365337)
						(end 383.09042 -108.409486)
					)
				)
			)
		)
		(zone
			(layer "F.Cu")
			(hatch none 0.5)
			(connect_pads
				(clearance 0)
			)
			(min_thickness 0.25)
			(keepout
				(tracks not_allowed)
				(vias allowed)
				(pads allowed)
				(copperpour not_allowed)
				(footprints allowed)
			)
			(placement
				(enabled no)
				(sheetname "")
			)
			(fill
				(thermal_gap 0.5)
				(thermal_bridge_width 0.5)
				(island_removal_mode 0)
			)
			(polygon
				(pts
					(arc
						(start 383.018538 -107.681268)
						(mid 382.93675 -107.662955)
						(end 382.854962 -107.681268)
					)
					(arc
						(start 382.78308 -107.609386)
						(mid 382.93675 -107.565237)
						(end 383.09042 -107.609386)
					)
				)
			)
		)
		(zone
			(layer "F.Cu")
			(hatch none 0.5)
			(connect_pads
				(clearance 0)
			)
			(min_thickness 0.25)
			(keepout
				(tracks not_allowed)
				(vias allowed)
				(pads allowed)
				(copperpour not_allowed)
				(footprints allowed)
			)
			(placement
				(enabled no)
				(sheetname "")
			)
			(fill
				(thermal_gap 0.5)
				(thermal_bridge_width 0.5)
				(island_removal_mode 0)
			)
			(polygon
				(pts
					(arc
						(start 383.018538 -106.881168)
						(mid 382.93675 -106.862855)
						(end 382.854962 -106.881168)
					)
					(arc
						(start 382.78308 -106.809286)
						(mid 382.93675 -106.765137)
						(end 383.09042 -106.809286)
					)
				)
			)
		)
		(zone
			(layer "F.Cu")
			(hatch none 0.5)
			(connect_pads
				(clearance 0)
			)
			(min_thickness 0.25)
			(keepout
				(tracks not_allowed)
				(vias allowed)
				(pads allowed)
				(copperpour not_allowed)
				(footprints allowed)
			)
			(placement
				(enabled no)
				(sheetname "")
			)
			(fill
				(thermal_gap 0.5)
				(thermal_bridge_width 0.5)
				(island_removal_mode 0)
			)
			(polygon
				(pts
					(arc
						(start 383.018538 -106.081068)
						(mid 382.93675 -106.062755)
						(end 382.854962 -106.081068)
					)
					(arc
						(start 382.78308 -106.009186)
						(mid 382.93675 -105.965037)
						(end 383.09042 -106.009186)
					)
				)
			)
		)
		(zone
			(layer "F.Cu")
			(hatch none 0.5)
			(connect_pads
				(clearance 0)
			)
			(min_thickness 0.25)
			(keepout
				(tracks not_allowed)
				(vias allowed)
				(pads allowed)
				(copperpour not_allowed)
				(footprints allowed)
			)
			(placement
				(enabled no)
				(sheetname "")
			)
			(fill
				(thermal_gap 0.5)
				(thermal_bridge_width 0.5)
				(island_removal_mode 0)
			)
			(polygon
				(pts
					(arc
						(start 383.018538 -105.280968)
						(mid 382.93675 -105.262655)
						(end 382.854962 -105.280968)
					)
					(arc
						(start 382.78308 -105.209086)
						(mid 382.93675 -105.164937)
						(end 383.09042 -105.209086)
					)
				)
			)
		)
		(zone
			(layer "F.Cu")
			(hatch none 0.5)
			(connect_pads
				(clearance 0)
			)
			(min_thickness 0.25)
			(keepout
				(tracks not_allowed)
				(vias allowed)
				(pads allowed)
				(copperpour not_allowed)
				(footprints allowed)
			)
			(placement
				(enabled no)
				(sheetname "")
			)
			(fill
				(thermal_gap 0.5)
				(thermal_bridge_width 0.5)
				(island_removal_mode 0)
			)
			(polygon
				(pts
					(arc
						(start 383.110232 -115.137438)
						(mid 383.128545 -115.05565)
						(end 383.110232 -114.973862)
					)
					(arc
						(start 383.182114 -114.90198)
						(mid 383.226263 -115.05565)
						(end 383.182114 -115.20932)
					)
				)
			)
		)
		(zone
			(layer "F.Cu")
			(hatch none 0.5)
			(connect_pads
				(clearance 0)
			)
			(min_thickness 0.25)
			(keepout
				(tracks not_allowed)
				(vias allowed)
				(pads allowed)
				(copperpour not_allowed)
				(footprints allowed)
			)
			(placement
				(enabled no)
				(sheetname "")
			)
			(fill
				(thermal_gap 0.5)
				(thermal_bridge_width 0.5)
				(island_removal_mode 0)
			)
			(polygon
				(pts
					(arc
						(start 383.110232 -114.337338)
						(mid 383.128545 -114.25555)
						(end 383.110232 -114.173762)
					)
					(arc
						(start 383.182114 -114.10188)
						(mid 383.226263 -114.25555)
						(end 383.182114 -114.40922)
					)
				)
			)
		)
		(zone
			(layer "F.Cu")
			(hatch none 0.5)
			(connect_pads
				(clearance 0)
			)
			(min_thickness 0.25)
			(keepout
				(tracks not_allowed)
				(vias allowed)
				(pads allowed)
				(copperpour not_allowed)
				(footprints allowed)
			)
			(placement
				(enabled no)
				(sheetname "")
			)
			(fill
				(thermal_gap 0.5)
				(thermal_bridge_width 0.5)
				(island_removal_mode 0)
			)
			(polygon
				(pts
					(arc
						(start 383.110232 -113.537238)
						(mid 383.128545 -113.45545)
						(end 383.110232 -113.373662)
					)
					(arc
						(start 383.182114 -113.30178)
						(mid 383.226263 -113.45545)
						(end 383.182114 -113.60912)
					)
				)
			)
		)
		(zone
			(layer "F.Cu")
			(hatch none 0.5)
			(connect_pads
				(clearance 0)
			)
			(min_thickness 0.25)
			(keepout
				(tracks not_allowed)
				(vias allowed)
				(pads allowed)
				(copperpour not_allowed)
				(footprints allowed)
			)
			(placement
				(enabled no)
				(sheetname "")
			)
			(fill
				(thermal_gap 0.5)
				(thermal_bridge_width 0.5)
				(island_removal_mode 0)
			)
			(polygon
				(pts
					(arc
						(start 383.110232 -112.737138)
						(mid 383.128545 -112.65535)
						(end 383.110232 -112.573562)
					)
					(arc
						(start 383.182114 -112.50168)
						(mid 383.226263 -112.65535)
						(end 383.182114 -112.80902)
					)
				)
			)
		)
		(zone
			(layer "F.Cu")
			(hatch none 0.5)
			(connect_pads
				(clearance 0)
			)
			(min_thickness 0.25)
			(keepout
				(tracks not_allowed)
				(vias allowed)
				(pads allowed)
				(copperpour not_allowed)
				(footprints allowed)
			)
			(placement
				(enabled no)
				(sheetname "")
			)
			(fill
				(thermal_gap 0.5)
				(thermal_bridge_width 0.5)
				(island_removal_mode 0)
			)
			(polygon
				(pts
					(arc
						(start 383.110232 -111.937038)
						(mid 383.128545 -111.85525)
						(end 383.110232 -111.773462)
					)
					(arc
						(start 383.182114 -111.70158)
						(mid 383.226263 -111.85525)
						(end 383.182114 -112.00892)
					)
				)
			)
		)
		(zone
			(layer "F.Cu")
			(hatch none 0.5)
			(connect_pads
				(clearance 0)
			)
			(min_thickness 0.25)
			(keepout
				(tracks not_allowed)
				(vias allowed)
				(pads allowed)
				(copperpour not_allowed)
				(footprints allowed)
			)
			(placement
				(enabled no)
				(sheetname "")
			)
			(fill
				(thermal_gap 0.5)
				(thermal_bridge_width 0.5)
				(island_removal_mode 0)
			)
			(polygon
				(pts
					(arc
						(start 383.110232 -111.136938)
						(mid 383.128545 -111.05515)
						(end 383.110232 -110.973362)
					)
					(arc
						(start 383.182114 -110.90148)
						(mid 383.226263 -111.05515)
						(end 383.182114 -111.20882)
					)
				)
			)
		)
		(zone
			(layer "F.Cu")
			(hatch none 0.5)
			(connect_pads
				(clearance 0)
			)
			(min_thickness 0.25)
			(keepout
				(tracks not_allowed)
				(vias allowed)
				(pads allowed)
				(copperpour not_allowed)
				(footprints allowed)
			)
			(placement
				(enabled no)
				(sheetname "")
			)
			(fill
				(thermal_gap 0.5)
				(thermal_bridge_width 0.5)
				(island_removal_mode 0)
			)
			(polygon
				(pts
					(arc
						(start 383.110232 -110.336838)
						(mid 383.128545 -110.25505)
						(end 383.110232 -110.173262)
					)
					(arc
						(start 383.182114 -110.10138)
						(mid 383.226263 -110.25505)
						(end 383.182114 -110.40872)
					)
				)
			)
		)
		(zone
			(layer "F.Cu")
			(hatch none 0.5)
			(connect_pads
				(clearance 0)
			)
			(min_thickness 0.25)
			(keepout
				(tracks not_allowed)
				(vias allowed)
				(pads allowed)
				(copperpour not_allowed)
				(footprints allowed)
			)
			(placement
				(enabled no)
				(sheetname "")
			)
			(fill
				(thermal_gap 0.5)
				(thermal_bridge_width 0.5)
				(island_removal_mode 0)
			)
			(polygon
				(pts
					(arc
						(start 383.110232 -109.536738)
						(mid 383.128545 -109.45495)
						(end 383.110232 -109.373162)
					)
					(arc
						(start 383.182114 -109.30128)
						(mid 383.226263 -109.45495)
						(end 383.182114 -109.60862)
					)
				)
			)
		)
		(zone
			(layer "F.Cu")
			(hatch none 0.5)
			(connect_pads
				(clearance 0)
			)
			(min_thickness 0.25)
			(keepout
				(tracks not_allowed)
				(vias allowed)
				(pads allowed)
				(copperpour not_allowed)
				(footprints allowed)
			)
			(placement
				(enabled no)
				(sheetname "")
			)
			(fill
				(thermal_gap 0.5)
				(thermal_bridge_width 0.5)
				(island_removal_mode 0)
			)
			(polygon
				(pts
					(arc
						(start 383.110232 -108.736638)
						(mid 383.128545 -108.65485)
						(end 383.110232 -108.573062)
					)
					(arc
						(start 383.182114 -108.50118)
						(mid 383.226263 -108.65485)
						(end 383.182114 -108.80852)
					)
				)
			)
		)
		(zone
			(layer "F.Cu")
			(hatch none 0.5)
			(connect_pads
				(clearance 0)
			)
			(min_thickness 0.25)
			(keepout
				(tracks not_allowed)
				(vias allowed)
				(pads allowed)
				(copperpour not_allowed)
				(footprints allowed)
			)
			(placement
				(enabled no)
				(sheetname "")
			)
			(fill
				(thermal_gap 0.5)
				(thermal_bridge_width 0.5)
				(island_removal_mode 0)
			)
			(polygon
				(pts
					(arc
						(start 383.110232 -107.936538)
						(mid 383.128545 -107.85475)
						(end 383.110232 -107.772962)
					)
					(arc
						(start 383.182114 -107.70108)
						(mid 383.226263 -107.85475)
						(end 383.182114 -108.00842)
					)
				)
			)
		)
		(zone
			(layer "F.Cu")
			(hatch none 0.5)
			(connect_pads
				(clearance 0)
			)
			(min_thickness 0.25)
			(keepout
				(tracks not_allowed)
				(vias allowed)
				(pads allowed)
				(copperpour not_allowed)
				(footprints allowed)
			)
			(placement
				(enabled no)
				(sheetname "")
			)
			(fill
				(thermal_gap 0.5)
				(thermal_bridge_width 0.5)
				(island_removal_mode 0)
			)
			(polygon
				(pts
					(arc
						(start 383.110232 -107.136438)
						(mid 383.128545 -107.05465)
						(end 383.110232 -106.972862)
					)
					(arc
						(start 383.182114 -106.90098)
						(mid 383.226263 -107.05465)
						(end 383.182114 -107.20832)
					)
				)
			)
		)
		(zone
			(layer "F.Cu")
			(hatch none 0.5)
			(connect_pads
				(clearance 0)
			)
			(min_thickness 0.25)
			(keepout
				(tracks not_allowed)
				(vias allowed)
				(pads allowed)
				(copperpour not_allowed)
				(footprints allowed)
			)
			(placement
				(enabled no)
				(sheetname "")
			)
			(fill
				(thermal_gap 0.5)
				(thermal_bridge_width 0.5)
				(island_removal_mode 0)
			)
			(polygon
				(pts
					(arc
						(start 383.110232 -106.336338)
						(mid 383.128545 -106.25455)
						(end 383.110232 -106.172762)
					)
					(arc
						(start 383.182114 -106.10088)
						(mid 383.226263 -106.25455)
						(end 383.182114 -106.40822)
					)
				)
			)
		)
		(zone
			(layer "F.Cu")
			(hatch none 0.5)
			(connect_pads
				(clearance 0)
			)
			(min_thickness 0.25)
			(keepout
				(tracks not_allowed)
				(vias allowed)
				(pads allowed)
				(copperpour not_allowed)
				(footprints allowed)
			)
			(placement
				(enabled no)
				(sheetname "")
			)
			(fill
				(thermal_gap 0.5)
				(thermal_bridge_width 0.5)
				(island_removal_mode 0)
			)
			(polygon
				(pts
					(arc
						(start 383.110232 -105.536238)
						(mid 383.128545 -105.45445)
						(end 383.110232 -105.372662)
					)
					(arc
						(start 383.182114 -105.30078)
						(mid 383.226263 -105.45445)
						(end 383.182114 -105.60812)
					)
				)
			)
		)
		(zone
			(layer "F.Cu")
			(hatch none 0.5)
			(connect_pads
				(clearance 0)
			)
			(min_thickness 0.25)
			(keepout
				(tracks not_allowed)
				(vias allowed)
				(pads allowed)
				(copperpour not_allowed)
				(footprints allowed)
			)
			(placement
				(enabled no)
				(sheetname "")
			)
			(fill
				(thermal_gap 0.5)
				(thermal_bridge_width 0.5)
				(island_removal_mode 0)
			)
			(polygon
				(pts
					(arc
						(start 383.563368 -114.973862)
						(mid 383.545055 -115.05565)
						(end 383.563368 -115.137438)
					)
					(arc
						(start 383.491486 -115.20932)
						(mid 383.447337 -115.05565)
						(end 383.491486 -114.90198)
					)
				)
			)
		)
		(zone
			(layer "F.Cu")
			(hatch none 0.5)
			(connect_pads
				(clearance 0)
			)
			(min_thickness 0.25)
			(keepout
				(tracks not_allowed)
				(vias allowed)
				(pads allowed)
				(copperpour not_allowed)
				(footprints allowed)
			)
			(placement
				(enabled no)
				(sheetname "")
			)
			(fill
				(thermal_gap 0.5)
				(thermal_bridge_width 0.5)
				(island_removal_mode 0)
			)
			(polygon
				(pts
					(arc
						(start 383.563368 -114.173762)
						(mid 383.545055 -114.25555)
						(end 383.563368 -114.337338)
					)
					(arc
						(start 383.491486 -114.40922)
						(mid 383.447337 -114.25555)
						(end 383.491486 -114.10188)
					)
				)
			)
		)
		(zone
			(layer "F.Cu")
			(hatch none 0.5)
			(connect_pads
				(clearance 0)
			)
			(min_thickness 0.25)
			(keepout
				(tracks not_allowed)
				(vias allowed)
				(pads allowed)
				(copperpour not_allowed)
				(footprints allowed)
			)
			(placement
				(enabled no)
				(sheetname "")
			)
			(fill
				(thermal_gap 0.5)
				(thermal_bridge_width 0.5)
				(island_removal_mode 0)
			)
			(polygon
				(pts
					(arc
						(start 383.563368 -112.573562)
						(mid 383.545055 -112.65535)
						(end 383.563368 -112.737138)
					)
					(arc
						(start 383.491486 -112.80902)
						(mid 383.447337 -112.65535)
						(end 383.491486 -112.50168)
					)
				)
			)
		)
		(zone
			(layer "F.Cu")
			(hatch none 0.5)
			(connect_pads
				(clearance 0)
			)
			(min_thickness 0.25)
			(keepout
				(tracks not_allowed)
				(vias allowed)
				(pads allowed)
				(copperpour not_allowed)
				(footprints allowed)
			)
			(placement
				(enabled no)
				(sheetname "")
			)
			(fill
				(thermal_gap 0.5)
				(thermal_bridge_width 0.5)
				(island_removal_mode 0)
			)
			(polygon
				(pts
					(arc
						(start 383.563368 -111.773462)
						(mid 383.545055 -111.85525)
						(end 383.563368 -111.937038)
					)
					(arc
						(start 383.491486 -112.00892)
						(mid 383.447337 -111.85525)
						(end 383.491486 -111.70158)
					)
				)
			)
		)
		(zone
			(layer "F.Cu")
			(hatch none 0.5)
			(connect_pads
				(clearance 0)
			)
			(min_thickness 0.25)
			(keepout
				(tracks not_allowed)
				(vias allowed)
				(pads allowed)
				(copperpour not_allowed)
				(footprints allowed)
			)
			(placement
				(enabled no)
				(sheetname "")
			)
			(fill
				(thermal_gap 0.5)
				(thermal_bridge_width 0.5)
				(island_removal_mode 0)
			)
			(polygon
				(pts
					(arc
						(start 383.563368 -110.973362)
						(mid 383.545055 -111.05515)
						(end 383.563368 -111.136938)
					)
					(arc
						(start 383.491486 -111.20882)
						(mid 383.447337 -111.05515)
						(end 383.491486 -110.90148)
					)
				)
			)
		)
		(zone
			(layer "F.Cu")
			(hatch none 0.5)
			(connect_pads
				(clearance 0)
			)
			(min_thickness 0.25)
			(keepout
				(tracks not_allowed)
				(vias allowed)
				(pads allowed)
				(copperpour not_allowed)
				(footprints allowed)
			)
			(placement
				(enabled no)
				(sheetname "")
			)
			(fill
				(thermal_gap 0.5)
				(thermal_bridge_width 0.5)
				(island_removal_mode 0)
			)
			(polygon
				(pts
					(arc
						(start 383.563368 -110.173262)
						(mid 383.545055 -110.25505)
						(end 383.563368 -110.336838)
					)
					(arc
						(start 383.491486 -110.40872)
						(mid 383.447337 -110.25505)
						(end 383.491486 -110.10138)
					)
				)
			)
		)
		(zone
			(layer "F.Cu")
			(hatch none 0.5)
			(connect_pads
				(clearance 0)
			)
			(min_thickness 0.25)
			(keepout
				(tracks not_allowed)
				(vias allowed)
				(pads allowed)
				(copperpour not_allowed)
				(footprints allowed)
			)
			(placement
				(enabled no)
				(sheetname "")
			)
			(fill
				(thermal_gap 0.5)
				(thermal_bridge_width 0.5)
				(island_removal_mode 0)
			)
			(polygon
				(pts
					(arc
						(start 383.563368 -109.373162)
						(mid 383.545055 -109.45495)
						(end 383.563368 -109.536738)
					)
					(arc
						(start 383.491486 -109.60862)
						(mid 383.447337 -109.45495)
						(end 383.491486 -109.30128)
					)
				)
			)
		)
		(zone
			(layer "F.Cu")
			(hatch none 0.5)
			(connect_pads
				(clearance 0)
			)
			(min_thickness 0.25)
			(keepout
				(tracks not_allowed)
				(vias allowed)
				(pads allowed)
				(copperpour not_allowed)
				(footprints allowed)
			)
			(placement
				(enabled no)
				(sheetname "")
			)
			(fill
				(thermal_gap 0.5)
				(thermal_bridge_width 0.5)
				(island_removal_mode 0)
			)
			(polygon
				(pts
					(arc
						(start 383.563368 -108.573062)
						(mid 383.545055 -108.65485)
						(end 383.563368 -108.736638)
					)
					(arc
						(start 383.491486 -108.80852)
						(mid 383.447337 -108.65485)
						(end 383.491486 -108.50118)
					)
				)
			)
		)
		(zone
			(layer "F.Cu")
			(hatch none 0.5)
			(connect_pads
				(clearance 0)
			)
			(min_thickness 0.25)
			(keepout
				(tracks not_allowed)
				(vias allowed)
				(pads allowed)
				(copperpour not_allowed)
				(footprints allowed)
			)
			(placement
				(enabled no)
				(sheetname "")
			)
			(fill
				(thermal_gap 0.5)
				(thermal_bridge_width 0.5)
				(island_removal_mode 0)
			)
			(polygon
				(pts
					(arc
						(start 383.563368 -107.772962)
						(mid 383.545055 -107.85475)
						(end 383.563368 -107.936538)
					)
					(arc
						(start 383.491486 -108.00842)
						(mid 383.447337 -107.85475)
						(end 383.491486 -107.70108)
					)
				)
			)
		)
		(zone
			(layer "F.Cu")
			(hatch none 0.5)
			(connect_pads
				(clearance 0)
			)
			(min_thickness 0.25)
			(keepout
				(tracks not_allowed)
				(vias allowed)
				(pads allowed)
				(copperpour not_allowed)
				(footprints allowed)
			)
			(placement
				(enabled no)
				(sheetname "")
			)
			(fill
				(thermal_gap 0.5)
				(thermal_bridge_width 0.5)
				(island_removal_mode 0)
			)
			(polygon
				(pts
					(arc
						(start 383.563368 -106.972862)
						(mid 383.545055 -107.05465)
						(end 383.563368 -107.136438)
					)
					(arc
						(start 383.491486 -107.20832)
						(mid 383.447337 -107.05465)
						(end 383.491486 -106.90098)
					)
				)
			)
		)
		(zone
			(layer "F.Cu")
			(hatch none 0.5)
			(connect_pads
				(clearance 0)
			)
			(min_thickness 0.25)
			(keepout
				(tracks not_allowed)
				(vias allowed)
				(pads allowed)
				(copperpour not_allowed)
				(footprints allowed)
			)
			(placement
				(enabled no)
				(sheetname "")
			)
			(fill
				(thermal_gap 0.5)
				(thermal_bridge_width 0.5)
				(island_removal_mode 0)
			)
			(polygon
				(pts
					(arc
						(start 383.563368 -106.172762)
						(mid 383.545055 -106.25455)
						(end 383.563368 -106.336338)
					)
					(arc
						(start 383.491486 -106.40822)
						(mid 383.447337 -106.25455)
						(end 383.491486 -106.10088)
					)
				)
			)
		)
		(zone
			(layer "F.Cu")
			(hatch none 0.5)
			(connect_pads
				(clearance 0)
			)
			(min_thickness 0.25)
			(keepout
				(tracks not_allowed)
				(vias allowed)
				(pads allowed)
				(copperpour not_allowed)
				(footprints allowed)
			)
			(placement
				(enabled no)
				(sheetname "")
			)
			(fill
				(thermal_gap 0.5)
				(thermal_bridge_width 0.5)
				(island_removal_mode 0)
			)
			(polygon
				(pts
					(arc
						(start 383.563368 -105.372662)
						(mid 383.545055 -105.45445)
						(end 383.563368 -105.536238)
					)
					(arc
						(start 383.491486 -105.60812)
						(mid 383.447337 -105.45445)
						(end 383.491486 -105.30078)
					)
				)
			)
		)
		(zone
			(layer "F.Cu")
			(hatch none 0.5)
			(connect_pads
				(clearance 0)
			)
			(min_thickness 0.25)
			(keepout
				(tracks not_allowed)
				(vias allowed)
				(pads allowed)
				(copperpour not_allowed)
				(footprints allowed)
			)
			(placement
				(enabled no)
				(sheetname "")
			)
			(fill
				(thermal_gap 0.5)
				(thermal_bridge_width 0.5)
				(island_removal_mode 0)
			)
			(polygon
				(pts
					(arc
						(start 383.563368 -104.572562)
						(mid 383.545055 -104.65435)
						(end 383.563368 -104.736138)
					)
					(arc
						(start 383.491486 -104.80802)
						(mid 383.447337 -104.65435)
						(end 383.491486 -104.50068)
					)
				)
			)
		)
		(zone
			(layer "F.Cu")
			(hatch none 0.5)
			(connect_pads
				(clearance 0)
			)
			(min_thickness 0.25)
			(keepout
				(tracks not_allowed)
				(vias allowed)
				(pads allowed)
				(copperpour not_allowed)
				(footprints allowed)
			)
			(placement
				(enabled no)
				(sheetname "")
			)
			(fill
				(thermal_gap 0.5)
				(thermal_bridge_width 0.5)
				(island_removal_mode 0)
			)
			(polygon
				(pts
					(arc
						(start 383.601468 -115.782852)
						(mid 383.583155 -115.86464)
						(end 383.601468 -115.946428)
					)
					(arc
						(start 383.529586 -116.01831)
						(mid 383.485437 -115.86464)
						(end 383.529586 -115.71097)
					)
				)
			)
		)
		(zone
			(layer "F.Cu")
			(hatch none 0.5)
			(connect_pads
				(clearance 0)
			)
			(min_thickness 0.25)
			(keepout
				(tracks not_allowed)
				(vias allowed)
				(pads allowed)
				(copperpour not_allowed)
				(footprints allowed)
			)
			(placement
				(enabled no)
				(sheetname "")
			)
			(fill
				(thermal_gap 0.5)
				(thermal_bridge_width 0.5)
				(island_removal_mode 0)
			)
			(polygon
				(pts
					(arc
						(start 383.655062 -115.229132)
						(mid 383.73685 -115.247445)
						(end 383.818638 -115.229132)
					)
					(arc
						(start 383.89052 -115.301014)
						(mid 383.73685 -115.345163)
						(end 383.58318 -115.301014)
					)
				)
			)
		)
		(zone
			(layer "F.Cu")
			(hatch none 0.5)
			(connect_pads
				(clearance 0)
			)
			(min_thickness 0.25)
			(keepout
				(tracks not_allowed)
				(vias allowed)
				(pads allowed)
				(copperpour not_allowed)
				(footprints allowed)
			)
			(placement
				(enabled no)
				(sheetname "")
			)
			(fill
				(thermal_gap 0.5)
				(thermal_bridge_width 0.5)
				(island_removal_mode 0)
			)
			(polygon
				(pts
					(arc
						(start 383.655062 -114.429032)
						(mid 383.73685 -114.447345)
						(end 383.818638 -114.429032)
					)
					(arc
						(start 383.89052 -114.500914)
						(mid 383.73685 -114.545063)
						(end 383.58318 -114.500914)
					)
				)
			)
		)
		(zone
			(layer "F.Cu")
			(hatch none 0.5)
			(connect_pads
				(clearance 0)
			)
			(min_thickness 0.25)
			(keepout
				(tracks not_allowed)
				(vias allowed)
				(pads allowed)
				(copperpour not_allowed)
				(footprints allowed)
			)
			(placement
				(enabled no)
				(sheetname "")
			)
			(fill
				(thermal_gap 0.5)
				(thermal_bridge_width 0.5)
				(island_removal_mode 0)
			)
			(polygon
				(pts
					(arc
						(start 383.655062 -112.828832)
						(mid 383.73685 -112.847145)
						(end 383.818638 -112.828832)
					)
					(arc
						(start 383.89052 -112.900714)
						(mid 383.73685 -112.944863)
						(end 383.58318 -112.900714)
					)
				)
			)
		)
		(zone
			(layer "F.Cu")
			(hatch none 0.5)
			(connect_pads
				(clearance 0)
			)
			(min_thickness 0.25)
			(keepout
				(tracks not_allowed)
				(vias allowed)
				(pads allowed)
				(copperpour not_allowed)
				(footprints allowed)
			)
			(placement
				(enabled no)
				(sheetname "")
			)
			(fill
				(thermal_gap 0.5)
				(thermal_bridge_width 0.5)
				(island_removal_mode 0)
			)
			(polygon
				(pts
					(arc
						(start 383.655062 -112.028732)
						(mid 383.73685 -112.047045)
						(end 383.818638 -112.028732)
					)
					(arc
						(start 383.89052 -112.100614)
						(mid 383.73685 -112.144763)
						(end 383.58318 -112.100614)
					)
				)
			)
		)
		(zone
			(layer "F.Cu")
			(hatch none 0.5)
			(connect_pads
				(clearance 0)
			)
			(min_thickness 0.25)
			(keepout
				(tracks not_allowed)
				(vias allowed)
				(pads allowed)
				(copperpour not_allowed)
				(footprints allowed)
			)
			(placement
				(enabled no)
				(sheetname "")
			)
			(fill
				(thermal_gap 0.5)
				(thermal_bridge_width 0.5)
				(island_removal_mode 0)
			)
			(polygon
				(pts
					(arc
						(start 383.655062 -111.228632)
						(mid 383.73685 -111.246945)
						(end 383.818638 -111.228632)
					)
					(arc
						(start 383.89052 -111.300514)
						(mid 383.73685 -111.344663)
						(end 383.58318 -111.300514)
					)
				)
			)
		)
		(zone
			(layer "F.Cu")
			(hatch none 0.5)
			(connect_pads
				(clearance 0)
			)
			(min_thickness 0.25)
			(keepout
				(tracks not_allowed)
				(vias allowed)
				(pads allowed)
				(copperpour not_allowed)
				(footprints allowed)
			)
			(placement
				(enabled no)
				(sheetname "")
			)
			(fill
				(thermal_gap 0.5)
				(thermal_bridge_width 0.5)
				(island_removal_mode 0)
			)
			(polygon
				(pts
					(arc
						(start 383.655062 -110.428532)
						(mid 383.73685 -110.446845)
						(end 383.818638 -110.428532)
					)
					(arc
						(start 383.89052 -110.500414)
						(mid 383.73685 -110.544563)
						(end 383.58318 -110.500414)
					)
				)
			)
		)
		(zone
			(layer "F.Cu")
			(hatch none 0.5)
			(connect_pads
				(clearance 0)
			)
			(min_thickness 0.25)
			(keepout
				(tracks not_allowed)
				(vias allowed)
				(pads allowed)
				(copperpour not_allowed)
				(footprints allowed)
			)
			(placement
				(enabled no)
				(sheetname "")
			)
			(fill
				(thermal_gap 0.5)
				(thermal_bridge_width 0.5)
				(island_removal_mode 0)
			)
			(polygon
				(pts
					(arc
						(start 383.655062 -109.628432)
						(mid 383.73685 -109.646745)
						(end 383.818638 -109.628432)
					)
					(arc
						(start 383.89052 -109.700314)
						(mid 383.73685 -109.744463)
						(end 383.58318 -109.700314)
					)
				)
			)
		)
		(zone
			(layer "F.Cu")
			(hatch none 0.5)
			(connect_pads
				(clearance 0)
			)
			(min_thickness 0.25)
			(keepout
				(tracks not_allowed)
				(vias allowed)
				(pads allowed)
				(copperpour not_allowed)
				(footprints allowed)
			)
			(placement
				(enabled no)
				(sheetname "")
			)
			(fill
				(thermal_gap 0.5)
				(thermal_bridge_width 0.5)
				(island_removal_mode 0)
			)
			(polygon
				(pts
					(arc
						(start 383.655062 -108.828332)
						(mid 383.73685 -108.846645)
						(end 383.818638 -108.828332)
					)
					(arc
						(start 383.89052 -108.900214)
						(mid 383.73685 -108.944363)
						(end 383.58318 -108.900214)
					)
				)
			)
		)
		(zone
			(layer "F.Cu")
			(hatch none 0.5)
			(connect_pads
				(clearance 0)
			)
			(min_thickness 0.25)
			(keepout
				(tracks not_allowed)
				(vias allowed)
				(pads allowed)
				(copperpour not_allowed)
				(footprints allowed)
			)
			(placement
				(enabled no)
				(sheetname "")
			)
			(fill
				(thermal_gap 0.5)
				(thermal_bridge_width 0.5)
				(island_removal_mode 0)
			)
			(polygon
				(pts
					(arc
						(start 383.655062 -108.028232)
						(mid 383.73685 -108.046545)
						(end 383.818638 -108.028232)
					)
					(arc
						(start 383.89052 -108.100114)
						(mid 383.73685 -108.144263)
						(end 383.58318 -108.100114)
					)
				)
			)
		)
		(zone
			(layer "F.Cu")
			(hatch none 0.5)
			(connect_pads
				(clearance 0)
			)
			(min_thickness 0.25)
			(keepout
				(tracks not_allowed)
				(vias allowed)
				(pads allowed)
				(copperpour not_allowed)
				(footprints allowed)
			)
			(placement
				(enabled no)
				(sheetname "")
			)
			(fill
				(thermal_gap 0.5)
				(thermal_bridge_width 0.5)
				(island_removal_mode 0)
			)
			(polygon
				(pts
					(arc
						(start 383.655062 -107.228132)
						(mid 383.73685 -107.246445)
						(end 383.818638 -107.228132)
					)
					(arc
						(start 383.89052 -107.300014)
						(mid 383.73685 -107.344163)
						(end 383.58318 -107.300014)
					)
				)
			)
		)
		(zone
			(layer "F.Cu")
			(hatch none 0.5)
			(connect_pads
				(clearance 0)
			)
			(min_thickness 0.25)
			(keepout
				(tracks not_allowed)
				(vias allowed)
				(pads allowed)
				(copperpour not_allowed)
				(footprints allowed)
			)
			(placement
				(enabled no)
				(sheetname "")
			)
			(fill
				(thermal_gap 0.5)
				(thermal_bridge_width 0.5)
				(island_removal_mode 0)
			)
			(polygon
				(pts
					(arc
						(start 383.655062 -106.428032)
						(mid 383.73685 -106.446345)
						(end 383.818638 -106.428032)
					)
					(arc
						(start 383.89052 -106.499914)
						(mid 383.73685 -106.544063)
						(end 383.58318 -106.499914)
					)
				)
			)
		)
		(zone
			(layer "F.Cu")
			(hatch none 0.5)
			(connect_pads
				(clearance 0)
			)
			(min_thickness 0.25)
			(keepout
				(tracks not_allowed)
				(vias allowed)
				(pads allowed)
				(copperpour not_allowed)
				(footprints allowed)
			)
			(placement
				(enabled no)
				(sheetname "")
			)
			(fill
				(thermal_gap 0.5)
				(thermal_bridge_width 0.5)
				(island_removal_mode 0)
			)
			(polygon
				(pts
					(arc
						(start 383.655062 -105.627932)
						(mid 383.73685 -105.646245)
						(end 383.818638 -105.627932)
					)
					(arc
						(start 383.89052 -105.699814)
						(mid 383.73685 -105.743963)
						(end 383.58318 -105.699814)
					)
				)
			)
		)
		(zone
			(layer "F.Cu")
			(hatch none 0.5)
			(connect_pads
				(clearance 0)
			)
			(min_thickness 0.25)
			(keepout
				(tracks not_allowed)
				(vias allowed)
				(pads allowed)
				(copperpour not_allowed)
				(footprints allowed)
			)
			(placement
				(enabled no)
				(sheetname "")
			)
			(fill
				(thermal_gap 0.5)
				(thermal_bridge_width 0.5)
				(island_removal_mode 0)
			)
			(polygon
				(pts
					(arc
						(start 383.655062 -104.827832)
						(mid 383.73685 -104.846145)
						(end 383.818638 -104.827832)
					)
					(arc
						(start 383.89052 -104.899714)
						(mid 383.73685 -104.943863)
						(end 383.58318 -104.899714)
					)
				)
			)
		)
		(zone
			(layer "F.Cu")
			(hatch none 0.5)
			(connect_pads
				(clearance 0)
			)
			(min_thickness 0.25)
			(keepout
				(tracks not_allowed)
				(vias allowed)
				(pads allowed)
				(copperpour not_allowed)
				(footprints allowed)
			)
			(placement
				(enabled no)
				(sheetname "")
			)
			(fill
				(thermal_gap 0.5)
				(thermal_bridge_width 0.5)
				(island_removal_mode 0)
			)
			(polygon
				(pts
					(arc
						(start 383.693162 -116.038122)
						(mid 383.77495 -116.056435)
						(end 383.856738 -116.038122)
					)
					(arc
						(start 383.92862 -116.110004)
						(mid 383.77495 -116.154153)
						(end 383.62128 -116.110004)
					)
				)
			)
		)
		(zone
			(layer "F.Cu")
			(hatch none 0.5)
			(connect_pads
				(clearance 0)
			)
			(min_thickness 0.25)
			(keepout
				(tracks not_allowed)
				(vias allowed)
				(pads allowed)
				(copperpour not_allowed)
				(footprints allowed)
			)
			(placement
				(enabled no)
				(sheetname "")
			)
			(fill
				(thermal_gap 0.5)
				(thermal_bridge_width 0.5)
				(island_removal_mode 0)
			)
			(polygon
				(pts
					(arc
						(start 383.818638 -114.882168)
						(mid 383.73685 -114.863855)
						(end 383.655062 -114.882168)
					)
					(arc
						(start 383.58318 -114.810286)
						(mid 383.73685 -114.766137)
						(end 383.89052 -114.810286)
					)
				)
			)
		)
		(zone
			(layer "F.Cu")
			(hatch none 0.5)
			(connect_pads
				(clearance 0)
			)
			(min_thickness 0.25)
			(keepout
				(tracks not_allowed)
				(vias allowed)
				(pads allowed)
				(copperpour not_allowed)
				(footprints allowed)
			)
			(placement
				(enabled no)
				(sheetname "")
			)
			(fill
				(thermal_gap 0.5)
				(thermal_bridge_width 0.5)
				(island_removal_mode 0)
			)
			(polygon
				(pts
					(arc
						(start 383.818638 -114.082068)
						(mid 383.73685 -114.063755)
						(end 383.655062 -114.082068)
					)
					(arc
						(start 383.58318 -114.010186)
						(mid 383.73685 -113.966037)
						(end 383.89052 -114.010186)
					)
				)
			)
		)
		(zone
			(layer "F.Cu")
			(hatch none 0.5)
			(connect_pads
				(clearance 0)
			)
			(min_thickness 0.25)
			(keepout
				(tracks not_allowed)
				(vias allowed)
				(pads allowed)
				(copperpour not_allowed)
				(footprints allowed)
			)
			(placement
				(enabled no)
				(sheetname "")
			)
			(fill
				(thermal_gap 0.5)
				(thermal_bridge_width 0.5)
				(island_removal_mode 0)
			)
			(polygon
				(pts
					(arc
						(start 383.818638 -112.481868)
						(mid 383.73685 -112.463555)
						(end 383.655062 -112.481868)
					)
					(arc
						(start 383.58318 -112.409986)
						(mid 383.73685 -112.365837)
						(end 383.89052 -112.409986)
					)
				)
			)
		)
		(zone
			(layer "F.Cu")
			(hatch none 0.5)
			(connect_pads
				(clearance 0)
			)
			(min_thickness 0.25)
			(keepout
				(tracks not_allowed)
				(vias allowed)
				(pads allowed)
				(copperpour not_allowed)
				(footprints allowed)
			)
			(placement
				(enabled no)
				(sheetname "")
			)
			(fill
				(thermal_gap 0.5)
				(thermal_bridge_width 0.5)
				(island_removal_mode 0)
			)
			(polygon
				(pts
					(arc
						(start 383.818638 -111.681768)
						(mid 383.73685 -111.663455)
						(end 383.655062 -111.681768)
					)
					(arc
						(start 383.58318 -111.609886)
						(mid 383.73685 -111.565737)
						(end 383.89052 -111.609886)
					)
				)
			)
		)
		(zone
			(layer "F.Cu")
			(hatch none 0.5)
			(connect_pads
				(clearance 0)
			)
			(min_thickness 0.25)
			(keepout
				(tracks not_allowed)
				(vias allowed)
				(pads allowed)
				(copperpour not_allowed)
				(footprints allowed)
			)
			(placement
				(enabled no)
				(sheetname "")
			)
			(fill
				(thermal_gap 0.5)
				(thermal_bridge_width 0.5)
				(island_removal_mode 0)
			)
			(polygon
				(pts
					(arc
						(start 383.818638 -110.881668)
						(mid 383.73685 -110.863355)
						(end 383.655062 -110.881668)
					)
					(arc
						(start 383.58318 -110.809786)
						(mid 383.73685 -110.765637)
						(end 383.89052 -110.809786)
					)
				)
			)
		)
		(zone
			(layer "F.Cu")
			(hatch none 0.5)
			(connect_pads
				(clearance 0)
			)
			(min_thickness 0.25)
			(keepout
				(tracks not_allowed)
				(vias allowed)
				(pads allowed)
				(copperpour not_allowed)
				(footprints allowed)
			)
			(placement
				(enabled no)
				(sheetname "")
			)
			(fill
				(thermal_gap 0.5)
				(thermal_bridge_width 0.5)
				(island_removal_mode 0)
			)
			(polygon
				(pts
					(arc
						(start 383.818638 -110.081568)
						(mid 383.73685 -110.063255)
						(end 383.655062 -110.081568)
					)
					(arc
						(start 383.58318 -110.009686)
						(mid 383.73685 -109.965537)
						(end 383.89052 -110.009686)
					)
				)
			)
		)
		(zone
			(layer "F.Cu")
			(hatch none 0.5)
			(connect_pads
				(clearance 0)
			)
			(min_thickness 0.25)
			(keepout
				(tracks not_allowed)
				(vias allowed)
				(pads allowed)
				(copperpour not_allowed)
				(footprints allowed)
			)
			(placement
				(enabled no)
				(sheetname "")
			)
			(fill
				(thermal_gap 0.5)
				(thermal_bridge_width 0.5)
				(island_removal_mode 0)
			)
			(polygon
				(pts
					(arc
						(start 383.818638 -109.281468)
						(mid 383.73685 -109.263155)
						(end 383.655062 -109.281468)
					)
					(arc
						(start 383.58318 -109.209586)
						(mid 383.73685 -109.165437)
						(end 383.89052 -109.209586)
					)
				)
			)
		)
		(zone
			(layer "F.Cu")
			(hatch none 0.5)
			(connect_pads
				(clearance 0)
			)
			(min_thickness 0.25)
			(keepout
				(tracks not_allowed)
				(vias allowed)
				(pads allowed)
				(copperpour not_allowed)
				(footprints allowed)
			)
			(placement
				(enabled no)
				(sheetname "")
			)
			(fill
				(thermal_gap 0.5)
				(thermal_bridge_width 0.5)
				(island_removal_mode 0)
			)
			(polygon
				(pts
					(arc
						(start 383.818638 -108.481368)
						(mid 383.73685 -108.463055)
						(end 383.655062 -108.481368)
					)
					(arc
						(start 383.58318 -108.409486)
						(mid 383.73685 -108.365337)
						(end 383.89052 -108.409486)
					)
				)
			)
		)
		(zone
			(layer "F.Cu")
			(hatch none 0.5)
			(connect_pads
				(clearance 0)
			)
			(min_thickness 0.25)
			(keepout
				(tracks not_allowed)
				(vias allowed)
				(pads allowed)
				(copperpour not_allowed)
				(footprints allowed)
			)
			(placement
				(enabled no)
				(sheetname "")
			)
			(fill
				(thermal_gap 0.5)
				(thermal_bridge_width 0.5)
				(island_removal_mode 0)
			)
			(polygon
				(pts
					(arc
						(start 383.818638 -107.681268)
						(mid 383.73685 -107.662955)
						(end 383.655062 -107.681268)
					)
					(arc
						(start 383.58318 -107.609386)
						(mid 383.73685 -107.565237)
						(end 383.89052 -107.609386)
					)
				)
			)
		)
		(zone
			(layer "F.Cu")
			(hatch none 0.5)
			(connect_pads
				(clearance 0)
			)
			(min_thickness 0.25)
			(keepout
				(tracks not_allowed)
				(vias allowed)
				(pads allowed)
				(copperpour not_allowed)
				(footprints allowed)
			)
			(placement
				(enabled no)
				(sheetname "")
			)
			(fill
				(thermal_gap 0.5)
				(thermal_bridge_width 0.5)
				(island_removal_mode 0)
			)
			(polygon
				(pts
					(arc
						(start 383.818638 -106.881168)
						(mid 383.73685 -106.862855)
						(end 383.655062 -106.881168)
					)
					(arc
						(start 383.58318 -106.809286)
						(mid 383.73685 -106.765137)
						(end 383.89052 -106.809286)
					)
				)
			)
		)
		(zone
			(layer "F.Cu")
			(hatch none 0.5)
			(connect_pads
				(clearance 0)
			)
			(min_thickness 0.25)
			(keepout
				(tracks not_allowed)
				(vias allowed)
				(pads allowed)
				(copperpour not_allowed)
				(footprints allowed)
			)
			(placement
				(enabled no)
				(sheetname "")
			)
			(fill
				(thermal_gap 0.5)
				(thermal_bridge_width 0.5)
				(island_removal_mode 0)
			)
			(polygon
				(pts
					(arc
						(start 383.818638 -106.081068)
						(mid 383.73685 -106.062755)
						(end 383.655062 -106.081068)
					)
					(arc
						(start 383.58318 -106.009186)
						(mid 383.73685 -105.965037)
						(end 383.89052 -106.009186)
					)
				)
			)
		)
		(zone
			(layer "F.Cu")
			(hatch none 0.5)
			(connect_pads
				(clearance 0)
			)
			(min_thickness 0.25)
			(keepout
				(tracks not_allowed)
				(vias allowed)
				(pads allowed)
				(copperpour not_allowed)
				(footprints allowed)
			)
			(placement
				(enabled no)
				(sheetname "")
			)
			(fill
				(thermal_gap 0.5)
				(thermal_bridge_width 0.5)
				(island_removal_mode 0)
			)
			(polygon
				(pts
					(arc
						(start 383.818638 -105.280968)
						(mid 383.73685 -105.262655)
						(end 383.655062 -105.280968)
					)
					(arc
						(start 383.58318 -105.209086)
						(mid 383.73685 -105.164937)
						(end 383.89052 -105.209086)
					)
				)
			)
		)
		(zone
			(layer "F.Cu")
			(hatch none 0.5)
			(connect_pads
				(clearance 0)
			)
			(min_thickness 0.25)
			(keepout
				(tracks not_allowed)
				(vias allowed)
				(pads allowed)
				(copperpour not_allowed)
				(footprints allowed)
			)
			(placement
				(enabled no)
				(sheetname "")
			)
			(fill
				(thermal_gap 0.5)
				(thermal_bridge_width 0.5)
				(island_removal_mode 0)
			)
			(polygon
				(pts
					(arc
						(start 383.818638 -104.480868)
						(mid 383.73685 -104.462555)
						(end 383.655062 -104.480868)
					)
					(arc
						(start 383.58318 -104.408986)
						(mid 383.73685 -104.364837)
						(end 383.89052 -104.408986)
					)
				)
			)
		)
		(zone
			(layer "F.Cu")
			(hatch none 0.5)
			(connect_pads
				(clearance 0)
			)
			(min_thickness 0.25)
			(keepout
				(tracks not_allowed)
				(vias allowed)
				(pads allowed)
				(copperpour not_allowed)
				(footprints allowed)
			)
			(placement
				(enabled no)
				(sheetname "")
			)
			(fill
				(thermal_gap 0.5)
				(thermal_bridge_width 0.5)
				(island_removal_mode 0)
			)
			(polygon
				(pts
					(arc
						(start 383.856738 -115.691158)
						(mid 383.77495 -115.672845)
						(end 383.693162 -115.691158)
					)
					(arc
						(start 383.62128 -115.619276)
						(mid 383.77495 -115.575127)
						(end 383.92862 -115.619276)
					)
				)
			)
		)
		(zone
			(layer "F.Cu")
			(hatch none 0.5)
			(connect_pads
				(clearance 0)
			)
			(min_thickness 0.25)
			(keepout
				(tracks not_allowed)
				(vias allowed)
				(pads allowed)
				(copperpour not_allowed)
				(footprints allowed)
			)
			(placement
				(enabled no)
				(sheetname "")
			)
			(fill
				(thermal_gap 0.5)
				(thermal_bridge_width 0.5)
				(island_removal_mode 0)
			)
			(polygon
				(pts
					(arc
						(start 383.910332 -115.137438)
						(mid 383.928645 -115.05565)
						(end 383.910332 -114.973862)
					)
					(arc
						(start 383.982214 -114.90198)
						(mid 384.026363 -115.05565)
						(end 383.982214 -115.20932)
					)
				)
			)
		)
		(zone
			(layer "F.Cu")
			(hatch none 0.5)
			(connect_pads
				(clearance 0)
			)
			(min_thickness 0.25)
			(keepout
				(tracks not_allowed)
				(vias allowed)
				(pads allowed)
				(copperpour not_allowed)
				(footprints allowed)
			)
			(placement
				(enabled no)
				(sheetname "")
			)
			(fill
				(thermal_gap 0.5)
				(thermal_bridge_width 0.5)
				(island_removal_mode 0)
			)
			(polygon
				(pts
					(arc
						(start 383.910332 -114.337338)
						(mid 383.928645 -114.25555)
						(end 383.910332 -114.173762)
					)
					(arc
						(start 383.982214 -114.10188)
						(mid 384.026363 -114.25555)
						(end 383.982214 -114.40922)
					)
				)
			)
		)
		(zone
			(layer "F.Cu")
			(hatch none 0.5)
			(connect_pads
				(clearance 0)
			)
			(min_thickness 0.25)
			(keepout
				(tracks not_allowed)
				(vias allowed)
				(pads allowed)
				(copperpour not_allowed)
				(footprints allowed)
			)
			(placement
				(enabled no)
				(sheetname "")
			)
			(fill
				(thermal_gap 0.5)
				(thermal_bridge_width 0.5)
				(island_removal_mode 0)
			)
			(polygon
				(pts
					(arc
						(start 383.910332 -112.737138)
						(mid 383.928645 -112.65535)
						(end 383.910332 -112.573562)
					)
					(arc
						(start 383.982214 -112.50168)
						(mid 384.026363 -112.65535)
						(end 383.982214 -112.80902)
					)
				)
			)
		)
		(zone
			(layer "F.Cu")
			(hatch none 0.5)
			(connect_pads
				(clearance 0)
			)
			(min_thickness 0.25)
			(keepout
				(tracks not_allowed)
				(vias allowed)
				(pads allowed)
				(copperpour not_allowed)
				(footprints allowed)
			)
			(placement
				(enabled no)
				(sheetname "")
			)
			(fill
				(thermal_gap 0.5)
				(thermal_bridge_width 0.5)
				(island_removal_mode 0)
			)
			(polygon
				(pts
					(arc
						(start 383.910332 -111.937038)
						(mid 383.928645 -111.85525)
						(end 383.910332 -111.773462)
					)
					(arc
						(start 383.982214 -111.70158)
						(mid 384.026363 -111.85525)
						(end 383.982214 -112.00892)
					)
				)
			)
		)
		(zone
			(layer "F.Cu")
			(hatch none 0.5)
			(connect_pads
				(clearance 0)
			)
			(min_thickness 0.25)
			(keepout
				(tracks not_allowed)
				(vias allowed)
				(pads allowed)
				(copperpour not_allowed)
				(footprints allowed)
			)
			(placement
				(enabled no)
				(sheetname "")
			)
			(fill
				(thermal_gap 0.5)
				(thermal_bridge_width 0.5)
				(island_removal_mode 0)
			)
			(polygon
				(pts
					(arc
						(start 383.910332 -111.136938)
						(mid 383.928645 -111.05515)
						(end 383.910332 -110.973362)
					)
					(arc
						(start 383.982214 -110.90148)
						(mid 384.026363 -111.05515)
						(end 383.982214 -111.20882)
					)
				)
			)
		)
		(zone
			(layer "F.Cu")
			(hatch none 0.5)
			(connect_pads
				(clearance 0)
			)
			(min_thickness 0.25)
			(keepout
				(tracks not_allowed)
				(vias allowed)
				(pads allowed)
				(copperpour not_allowed)
				(footprints allowed)
			)
			(placement
				(enabled no)
				(sheetname "")
			)
			(fill
				(thermal_gap 0.5)
				(thermal_bridge_width 0.5)
				(island_removal_mode 0)
			)
			(polygon
				(pts
					(arc
						(start 383.910332 -110.336838)
						(mid 383.928645 -110.25505)
						(end 383.910332 -110.173262)
					)
					(arc
						(start 383.982214 -110.10138)
						(mid 384.026363 -110.25505)
						(end 383.982214 -110.40872)
					)
				)
			)
		)
		(zone
			(layer "F.Cu")
			(hatch none 0.5)
			(connect_pads
				(clearance 0)
			)
			(min_thickness 0.25)
			(keepout
				(tracks not_allowed)
				(vias allowed)
				(pads allowed)
				(copperpour not_allowed)
				(footprints allowed)
			)
			(placement
				(enabled no)
				(sheetname "")
			)
			(fill
				(thermal_gap 0.5)
				(thermal_bridge_width 0.5)
				(island_removal_mode 0)
			)
			(polygon
				(pts
					(arc
						(start 383.910332 -109.536738)
						(mid 383.928645 -109.45495)
						(end 383.910332 -109.373162)
					)
					(arc
						(start 383.982214 -109.30128)
						(mid 384.026363 -109.45495)
						(end 383.982214 -109.60862)
					)
				)
			)
		)
		(zone
			(layer "F.Cu")
			(hatch none 0.5)
			(connect_pads
				(clearance 0)
			)
			(min_thickness 0.25)
			(keepout
				(tracks not_allowed)
				(vias allowed)
				(pads allowed)
				(copperpour not_allowed)
				(footprints allowed)
			)
			(placement
				(enabled no)
				(sheetname "")
			)
			(fill
				(thermal_gap 0.5)
				(thermal_bridge_width 0.5)
				(island_removal_mode 0)
			)
			(polygon
				(pts
					(arc
						(start 383.910332 -108.736638)
						(mid 383.928645 -108.65485)
						(end 383.910332 -108.573062)
					)
					(arc
						(start 383.982214 -108.50118)
						(mid 384.026363 -108.65485)
						(end 383.982214 -108.80852)
					)
				)
			)
		)
		(zone
			(layer "F.Cu")
			(hatch none 0.5)
			(connect_pads
				(clearance 0)
			)
			(min_thickness 0.25)
			(keepout
				(tracks not_allowed)
				(vias allowed)
				(pads allowed)
				(copperpour not_allowed)
				(footprints allowed)
			)
			(placement
				(enabled no)
				(sheetname "")
			)
			(fill
				(thermal_gap 0.5)
				(thermal_bridge_width 0.5)
				(island_removal_mode 0)
			)
			(polygon
				(pts
					(arc
						(start 383.910332 -107.936538)
						(mid 383.928645 -107.85475)
						(end 383.910332 -107.772962)
					)
					(arc
						(start 383.982214 -107.70108)
						(mid 384.026363 -107.85475)
						(end 383.982214 -108.00842)
					)
				)
			)
		)
		(zone
			(layer "F.Cu")
			(hatch none 0.5)
			(connect_pads
				(clearance 0)
			)
			(min_thickness 0.25)
			(keepout
				(tracks not_allowed)
				(vias allowed)
				(pads allowed)
				(copperpour not_allowed)
				(footprints allowed)
			)
			(placement
				(enabled no)
				(sheetname "")
			)
			(fill
				(thermal_gap 0.5)
				(thermal_bridge_width 0.5)
				(island_removal_mode 0)
			)
			(polygon
				(pts
					(arc
						(start 383.910332 -107.136438)
						(mid 383.928645 -107.05465)
						(end 383.910332 -106.972862)
					)
					(arc
						(start 383.982214 -106.90098)
						(mid 384.026363 -107.05465)
						(end 383.982214 -107.20832)
					)
				)
			)
		)
		(zone
			(layer "F.Cu")
			(hatch none 0.5)
			(connect_pads
				(clearance 0)
			)
			(min_thickness 0.25)
			(keepout
				(tracks not_allowed)
				(vias allowed)
				(pads allowed)
				(copperpour not_allowed)
				(footprints allowed)
			)
			(placement
				(enabled no)
				(sheetname "")
			)
			(fill
				(thermal_gap 0.5)
				(thermal_bridge_width 0.5)
				(island_removal_mode 0)
			)
			(polygon
				(pts
					(arc
						(start 383.910332 -106.336338)
						(mid 383.928645 -106.25455)
						(end 383.910332 -106.172762)
					)
					(arc
						(start 383.982214 -106.10088)
						(mid 384.026363 -106.25455)
						(end 383.982214 -106.40822)
					)
				)
			)
		)
		(zone
			(layer "F.Cu")
			(hatch none 0.5)
			(connect_pads
				(clearance 0)
			)
			(min_thickness 0.25)
			(keepout
				(tracks not_allowed)
				(vias allowed)
				(pads allowed)
				(copperpour not_allowed)
				(footprints allowed)
			)
			(placement
				(enabled no)
				(sheetname "")
			)
			(fill
				(thermal_gap 0.5)
				(thermal_bridge_width 0.5)
				(island_removal_mode 0)
			)
			(polygon
				(pts
					(arc
						(start 383.910332 -105.536238)
						(mid 383.928645 -105.45445)
						(end 383.910332 -105.372662)
					)
					(arc
						(start 383.982214 -105.30078)
						(mid 384.026363 -105.45445)
						(end 383.982214 -105.60812)
					)
				)
			)
		)
		(zone
			(layer "F.Cu")
			(hatch none 0.5)
			(connect_pads
				(clearance 0)
			)
			(min_thickness 0.25)
			(keepout
				(tracks not_allowed)
				(vias allowed)
				(pads allowed)
				(copperpour not_allowed)
				(footprints allowed)
			)
			(placement
				(enabled no)
				(sheetname "")
			)
			(fill
				(thermal_gap 0.5)
				(thermal_bridge_width 0.5)
				(island_removal_mode 0)
			)
			(polygon
				(pts
					(arc
						(start 383.910332 -104.736138)
						(mid 383.928645 -104.65435)
						(end 383.910332 -104.572562)
					)
					(arc
						(start 383.982214 -104.50068)
						(mid 384.026363 -104.65435)
						(end 383.982214 -104.80802)
					)
				)
			)
		)
		(zone
			(layer "F.Cu")
			(hatch none 0.5)
			(connect_pads
				(clearance 0)
			)
			(min_thickness 0.25)
			(keepout
				(tracks not_allowed)
				(vias allowed)
				(pads allowed)
				(copperpour not_allowed)
				(footprints allowed)
			)
			(placement
				(enabled no)
				(sheetname "")
			)
			(fill
				(thermal_gap 0.5)
				(thermal_bridge_width 0.5)
				(island_removal_mode 0)
			)
			(polygon
				(pts
					(arc
						(start 383.948432 -115.946428)
						(mid 383.966745 -115.86464)
						(end 383.948432 -115.782852)
					)
					(arc
						(start 384.020314 -115.71097)
						(mid 384.064463 -115.86464)
						(end 384.020314 -116.01831)
					)
				)
			)
		)
		(zone
			(layer "F.Cu")
			(hatch none 0.5)
			(connect_pads
				(clearance 0)
			)
			(min_thickness 0.25)
			(keepout
				(tracks not_allowed)
				(vias allowed)
				(pads allowed)
				(copperpour not_allowed)
				(footprints allowed)
			)
			(placement
				(enabled no)
				(sheetname "")
			)
			(fill
				(thermal_gap 0.5)
				(thermal_bridge_width 0.5)
				(island_removal_mode 0)
			)
			(polygon
				(pts
					(arc
						(start 384.363468 -114.973862)
						(mid 384.345155 -115.05565)
						(end 384.363468 -115.137438)
					)
					(arc
						(start 384.291586 -115.20932)
						(mid 384.247437 -115.05565)
						(end 384.291586 -114.90198)
					)
				)
			)
		)
		(zone
			(layer "F.Cu")
			(hatch none 0.5)
			(connect_pads
				(clearance 0)
			)
			(min_thickness 0.25)
			(keepout
				(tracks not_allowed)
				(vias allowed)
				(pads allowed)
				(copperpour not_allowed)
				(footprints allowed)
			)
			(placement
				(enabled no)
				(sheetname "")
			)
			(fill
				(thermal_gap 0.5)
				(thermal_bridge_width 0.5)
				(island_removal_mode 0)
			)
			(polygon
				(pts
					(arc
						(start 384.363468 -114.173762)
						(mid 384.345155 -114.25555)
						(end 384.363468 -114.337338)
					)
					(arc
						(start 384.291586 -114.40922)
						(mid 384.247437 -114.25555)
						(end 384.291586 -114.10188)
					)
				)
			)
		)
		(zone
			(layer "F.Cu")
			(hatch none 0.5)
			(connect_pads
				(clearance 0)
			)
			(min_thickness 0.25)
			(keepout
				(tracks not_allowed)
				(vias allowed)
				(pads allowed)
				(copperpour not_allowed)
				(footprints allowed)
			)
			(placement
				(enabled no)
				(sheetname "")
			)
			(fill
				(thermal_gap 0.5)
				(thermal_bridge_width 0.5)
				(island_removal_mode 0)
			)
			(polygon
				(pts
					(arc
						(start 384.363468 -113.373662)
						(mid 384.345155 -113.45545)
						(end 384.363468 -113.537238)
					)
					(arc
						(start 384.291586 -113.60912)
						(mid 384.247437 -113.45545)
						(end 384.291586 -113.30178)
					)
				)
			)
		)
		(zone
			(layer "F.Cu")
			(hatch none 0.5)
			(connect_pads
				(clearance 0)
			)
			(min_thickness 0.25)
			(keepout
				(tracks not_allowed)
				(vias allowed)
				(pads allowed)
				(copperpour not_allowed)
				(footprints allowed)
			)
			(placement
				(enabled no)
				(sheetname "")
			)
			(fill
				(thermal_gap 0.5)
				(thermal_bridge_width 0.5)
				(island_removal_mode 0)
			)
			(polygon
				(pts
					(arc
						(start 384.363468 -112.573562)
						(mid 384.345155 -112.65535)
						(end 384.363468 -112.737138)
					)
					(arc
						(start 384.291586 -112.80902)
						(mid 384.247437 -112.65535)
						(end 384.291586 -112.50168)
					)
				)
			)
		)
		(zone
			(layer "F.Cu")
			(hatch none 0.5)
			(connect_pads
				(clearance 0)
			)
			(min_thickness 0.25)
			(keepout
				(tracks not_allowed)
				(vias allowed)
				(pads allowed)
				(copperpour not_allowed)
				(footprints allowed)
			)
			(placement
				(enabled no)
				(sheetname "")
			)
			(fill
				(thermal_gap 0.5)
				(thermal_bridge_width 0.5)
				(island_removal_mode 0)
			)
			(polygon
				(pts
					(arc
						(start 384.363468 -111.773462)
						(mid 384.345155 -111.85525)
						(end 384.363468 -111.937038)
					)
					(arc
						(start 384.291586 -112.00892)
						(mid 384.247437 -111.85525)
						(end 384.291586 -111.70158)
					)
				)
			)
		)
		(zone
			(layer "F.Cu")
			(hatch none 0.5)
			(connect_pads
				(clearance 0)
			)
			(min_thickness 0.25)
			(keepout
				(tracks not_allowed)
				(vias allowed)
				(pads allowed)
				(copperpour not_allowed)
				(footprints allowed)
			)
			(placement
				(enabled no)
				(sheetname "")
			)
			(fill
				(thermal_gap 0.5)
				(thermal_bridge_width 0.5)
				(island_removal_mode 0)
			)
			(polygon
				(pts
					(arc
						(start 384.363468 -110.973362)
						(mid 384.345155 -111.05515)
						(end 384.363468 -111.136938)
					)
					(arc
						(start 384.291586 -111.20882)
						(mid 384.247437 -111.05515)
						(end 384.291586 -110.90148)
					)
				)
			)
		)
		(zone
			(layer "F.Cu")
			(hatch none 0.5)
			(connect_pads
				(clearance 0)
			)
			(min_thickness 0.25)
			(keepout
				(tracks not_allowed)
				(vias allowed)
				(pads allowed)
				(copperpour not_allowed)
				(footprints allowed)
			)
			(placement
				(enabled no)
				(sheetname "")
			)
			(fill
				(thermal_gap 0.5)
				(thermal_bridge_width 0.5)
				(island_removal_mode 0)
			)
			(polygon
				(pts
					(arc
						(start 384.363468 -110.173262)
						(mid 384.345155 -110.25505)
						(end 384.363468 -110.336838)
					)
					(arc
						(start 384.291586 -110.40872)
						(mid 384.247437 -110.25505)
						(end 384.291586 -110.10138)
					)
				)
			)
		)
		(zone
			(layer "F.Cu")
			(hatch none 0.5)
			(connect_pads
				(clearance 0)
			)
			(min_thickness 0.25)
			(keepout
				(tracks not_allowed)
				(vias allowed)
				(pads allowed)
				(copperpour not_allowed)
				(footprints allowed)
			)
			(placement
				(enabled no)
				(sheetname "")
			)
			(fill
				(thermal_gap 0.5)
				(thermal_bridge_width 0.5)
				(island_removal_mode 0)
			)
			(polygon
				(pts
					(arc
						(start 384.363468 -109.373162)
						(mid 384.345155 -109.45495)
						(end 384.363468 -109.536738)
					)
					(arc
						(start 384.291586 -109.60862)
						(mid 384.247437 -109.45495)
						(end 384.291586 -109.30128)
					)
				)
			)
		)
		(zone
			(layer "F.Cu")
			(hatch none 0.5)
			(connect_pads
				(clearance 0)
			)
			(min_thickness 0.25)
			(keepout
				(tracks not_allowed)
				(vias allowed)
				(pads allowed)
				(copperpour not_allowed)
				(footprints allowed)
			)
			(placement
				(enabled no)
				(sheetname "")
			)
			(fill
				(thermal_gap 0.5)
				(thermal_bridge_width 0.5)
				(island_removal_mode 0)
			)
			(polygon
				(pts
					(arc
						(start 384.363468 -108.573062)
						(mid 384.345155 -108.65485)
						(end 384.363468 -108.736638)
					)
					(arc
						(start 384.291586 -108.80852)
						(mid 384.247437 -108.65485)
						(end 384.291586 -108.50118)
					)
				)
			)
		)
		(zone
			(layer "F.Cu")
			(hatch none 0.5)
			(connect_pads
				(clearance 0)
			)
			(min_thickness 0.25)
			(keepout
				(tracks not_allowed)
				(vias allowed)
				(pads allowed)
				(copperpour not_allowed)
				(footprints allowed)
			)
			(placement
				(enabled no)
				(sheetname "")
			)
			(fill
				(thermal_gap 0.5)
				(thermal_bridge_width 0.5)
				(island_removal_mode 0)
			)
			(polygon
				(pts
					(arc
						(start 384.363468 -107.772962)
						(mid 384.345155 -107.85475)
						(end 384.363468 -107.936538)
					)
					(arc
						(start 384.291586 -108.00842)
						(mid 384.247437 -107.85475)
						(end 384.291586 -107.70108)
					)
				)
			)
		)
		(zone
			(layer "F.Cu")
			(hatch none 0.5)
			(connect_pads
				(clearance 0)
			)
			(min_thickness 0.25)
			(keepout
				(tracks not_allowed)
				(vias allowed)
				(pads allowed)
				(copperpour not_allowed)
				(footprints allowed)
			)
			(placement
				(enabled no)
				(sheetname "")
			)
			(fill
				(thermal_gap 0.5)
				(thermal_bridge_width 0.5)
				(island_removal_mode 0)
			)
			(polygon
				(pts
					(arc
						(start 384.363468 -106.972862)
						(mid 384.345155 -107.05465)
						(end 384.363468 -107.136438)
					)
					(arc
						(start 384.291586 -107.20832)
						(mid 384.247437 -107.05465)
						(end 384.291586 -106.90098)
					)
				)
			)
		)
		(zone
			(layer "F.Cu")
			(hatch none 0.5)
			(connect_pads
				(clearance 0)
			)
			(min_thickness 0.25)
			(keepout
				(tracks not_allowed)
				(vias allowed)
				(pads allowed)
				(copperpour not_allowed)
				(footprints allowed)
			)
			(placement
				(enabled no)
				(sheetname "")
			)
			(fill
				(thermal_gap 0.5)
				(thermal_bridge_width 0.5)
				(island_removal_mode 0)
			)
			(polygon
				(pts
					(arc
						(start 384.363468 -106.172762)
						(mid 384.345155 -106.25455)
						(end 384.363468 -106.336338)
					)
					(arc
						(start 384.291586 -106.40822)
						(mid 384.247437 -106.25455)
						(end 384.291586 -106.10088)
					)
				)
			)
		)
		(zone
			(layer "F.Cu")
			(hatch none 0.5)
			(connect_pads
				(clearance 0)
			)
			(min_thickness 0.25)
			(keepout
				(tracks not_allowed)
				(vias allowed)
				(pads allowed)
				(copperpour not_allowed)
				(footprints allowed)
			)
			(placement
				(enabled no)
				(sheetname "")
			)
			(fill
				(thermal_gap 0.5)
				(thermal_bridge_width 0.5)
				(island_removal_mode 0)
			)
			(polygon
				(pts
					(arc
						(start 384.455162 -115.229132)
						(mid 384.53695 -115.247445)
						(end 384.618738 -115.229132)
					)
					(arc
						(start 384.69062 -115.301014)
						(mid 384.53695 -115.345163)
						(end 384.38328 -115.301014)
					)
				)
			)
		)
		(zone
			(layer "F.Cu")
			(hatch none 0.5)
			(connect_pads
				(clearance 0)
			)
			(min_thickness 0.25)
			(keepout
				(tracks not_allowed)
				(vias allowed)
				(pads allowed)
				(copperpour not_allowed)
				(footprints allowed)
			)
			(placement
				(enabled no)
				(sheetname "")
			)
			(fill
				(thermal_gap 0.5)
				(thermal_bridge_width 0.5)
				(island_removal_mode 0)
			)
			(polygon
				(pts
					(arc
						(start 384.455162 -114.429032)
						(mid 384.53695 -114.447345)
						(end 384.618738 -114.429032)
					)
					(arc
						(start 384.69062 -114.500914)
						(mid 384.53695 -114.545063)
						(end 384.38328 -114.500914)
					)
				)
			)
		)
		(zone
			(layer "F.Cu")
			(hatch none 0.5)
			(connect_pads
				(clearance 0)
			)
			(min_thickness 0.25)
			(keepout
				(tracks not_allowed)
				(vias allowed)
				(pads allowed)
				(copperpour not_allowed)
				(footprints allowed)
			)
			(placement
				(enabled no)
				(sheetname "")
			)
			(fill
				(thermal_gap 0.5)
				(thermal_bridge_width 0.5)
				(island_removal_mode 0)
			)
			(polygon
				(pts
					(arc
						(start 384.455162 -113.628932)
						(mid 384.53695 -113.647245)
						(end 384.618738 -113.628932)
					)
					(arc
						(start 384.69062 -113.700814)
						(mid 384.53695 -113.744963)
						(end 384.38328 -113.700814)
					)
				)
			)
		)
		(zone
			(layer "F.Cu")
			(hatch none 0.5)
			(connect_pads
				(clearance 0)
			)
			(min_thickness 0.25)
			(keepout
				(tracks not_allowed)
				(vias allowed)
				(pads allowed)
				(copperpour not_allowed)
				(footprints allowed)
			)
			(placement
				(enabled no)
				(sheetname "")
			)
			(fill
				(thermal_gap 0.5)
				(thermal_bridge_width 0.5)
				(island_removal_mode 0)
			)
			(polygon
				(pts
					(arc
						(start 384.455162 -112.828832)
						(mid 384.53695 -112.847145)
						(end 384.618738 -112.828832)
					)
					(arc
						(start 384.69062 -112.900714)
						(mid 384.53695 -112.944863)
						(end 384.38328 -112.900714)
					)
				)
			)
		)
		(zone
			(layer "F.Cu")
			(hatch none 0.5)
			(connect_pads
				(clearance 0)
			)
			(min_thickness 0.25)
			(keepout
				(tracks not_allowed)
				(vias allowed)
				(pads allowed)
				(copperpour not_allowed)
				(footprints allowed)
			)
			(placement
				(enabled no)
				(sheetname "")
			)
			(fill
				(thermal_gap 0.5)
				(thermal_bridge_width 0.5)
				(island_removal_mode 0)
			)
			(polygon
				(pts
					(arc
						(start 384.455162 -112.028732)
						(mid 384.53695 -112.047045)
						(end 384.618738 -112.028732)
					)
					(arc
						(start 384.69062 -112.100614)
						(mid 384.53695 -112.144763)
						(end 384.38328 -112.100614)
					)
				)
			)
		)
		(zone
			(layer "F.Cu")
			(hatch none 0.5)
			(connect_pads
				(clearance 0)
			)
			(min_thickness 0.25)
			(keepout
				(tracks not_allowed)
				(vias allowed)
				(pads allowed)
				(copperpour not_allowed)
				(footprints allowed)
			)
			(placement
				(enabled no)
				(sheetname "")
			)
			(fill
				(thermal_gap 0.5)
				(thermal_bridge_width 0.5)
				(island_removal_mode 0)
			)
			(polygon
				(pts
					(arc
						(start 384.455162 -111.228632)
						(mid 384.53695 -111.246945)
						(end 384.618738 -111.228632)
					)
					(arc
						(start 384.69062 -111.300514)
						(mid 384.53695 -111.344663)
						(end 384.38328 -111.300514)
					)
				)
			)
		)
		(zone
			(layer "F.Cu")
			(hatch none 0.5)
			(connect_pads
				(clearance 0)
			)
			(min_thickness 0.25)
			(keepout
				(tracks not_allowed)
				(vias allowed)
				(pads allowed)
				(copperpour not_allowed)
				(footprints allowed)
			)
			(placement
				(enabled no)
				(sheetname "")
			)
			(fill
				(thermal_gap 0.5)
				(thermal_bridge_width 0.5)
				(island_removal_mode 0)
			)
			(polygon
				(pts
					(arc
						(start 384.455162 -110.428532)
						(mid 384.53695 -110.446845)
						(end 384.618738 -110.428532)
					)
					(arc
						(start 384.69062 -110.500414)
						(mid 384.53695 -110.544563)
						(end 384.38328 -110.500414)
					)
				)
			)
		)
		(zone
			(layer "F.Cu")
			(hatch none 0.5)
			(connect_pads
				(clearance 0)
			)
			(min_thickness 0.25)
			(keepout
				(tracks not_allowed)
				(vias allowed)
				(pads allowed)
				(copperpour not_allowed)
				(footprints allowed)
			)
			(placement
				(enabled no)
				(sheetname "")
			)
			(fill
				(thermal_gap 0.5)
				(thermal_bridge_width 0.5)
				(island_removal_mode 0)
			)
			(polygon
				(pts
					(arc
						(start 384.455162 -109.628432)
						(mid 384.53695 -109.646745)
						(end 384.618738 -109.628432)
					)
					(arc
						(start 384.69062 -109.700314)
						(mid 384.53695 -109.744463)
						(end 384.38328 -109.700314)
					)
				)
			)
		)
		(zone
			(layer "F.Cu")
			(hatch none 0.5)
			(connect_pads
				(clearance 0)
			)
			(min_thickness 0.25)
			(keepout
				(tracks not_allowed)
				(vias allowed)
				(pads allowed)
				(copperpour not_allowed)
				(footprints allowed)
			)
			(placement
				(enabled no)
				(sheetname "")
			)
			(fill
				(thermal_gap 0.5)
				(thermal_bridge_width 0.5)
				(island_removal_mode 0)
			)
			(polygon
				(pts
					(arc
						(start 384.455162 -108.828332)
						(mid 384.53695 -108.846645)
						(end 384.618738 -108.828332)
					)
					(arc
						(start 384.69062 -108.900214)
						(mid 384.53695 -108.944363)
						(end 384.38328 -108.900214)
					)
				)
			)
		)
		(zone
			(layer "F.Cu")
			(hatch none 0.5)
			(connect_pads
				(clearance 0)
			)
			(min_thickness 0.25)
			(keepout
				(tracks not_allowed)
				(vias allowed)
				(pads allowed)
				(copperpour not_allowed)
				(footprints allowed)
			)
			(placement
				(enabled no)
				(sheetname "")
			)
			(fill
				(thermal_gap 0.5)
				(thermal_bridge_width 0.5)
				(island_removal_mode 0)
			)
			(polygon
				(pts
					(arc
						(start 384.455162 -108.028232)
						(mid 384.53695 -108.046545)
						(end 384.618738 -108.028232)
					)
					(arc
						(start 384.69062 -108.100114)
						(mid 384.53695 -108.144263)
						(end 384.38328 -108.100114)
					)
				)
			)
		)
		(zone
			(layer "F.Cu")
			(hatch none 0.5)
			(connect_pads
				(clearance 0)
			)
			(min_thickness 0.25)
			(keepout
				(tracks not_allowed)
				(vias allowed)
				(pads allowed)
				(copperpour not_allowed)
				(footprints allowed)
			)
			(placement
				(enabled no)
				(sheetname "")
			)
			(fill
				(thermal_gap 0.5)
				(thermal_bridge_width 0.5)
				(island_removal_mode 0)
			)
			(polygon
				(pts
					(arc
						(start 384.455162 -107.228132)
						(mid 384.53695 -107.246445)
						(end 384.618738 -107.228132)
					)
					(arc
						(start 384.69062 -107.300014)
						(mid 384.53695 -107.344163)
						(end 384.38328 -107.300014)
					)
				)
			)
		)
		(zone
			(layer "F.Cu")
			(hatch none 0.5)
			(connect_pads
				(clearance 0)
			)
			(min_thickness 0.25)
			(keepout
				(tracks not_allowed)
				(vias allowed)
				(pads allowed)
				(copperpour not_allowed)
				(footprints allowed)
			)
			(placement
				(enabled no)
				(sheetname "")
			)
			(fill
				(thermal_gap 0.5)
				(thermal_bridge_width 0.5)
				(island_removal_mode 0)
			)
			(polygon
				(pts
					(arc
						(start 384.455162 -106.428032)
						(mid 384.53695 -106.446345)
						(end 384.618738 -106.428032)
					)
					(arc
						(start 384.69062 -106.499914)
						(mid 384.53695 -106.544063)
						(end 384.38328 -106.499914)
					)
				)
			)
		)
		(zone
			(layer "F.Cu")
			(hatch none 0.5)
			(connect_pads
				(clearance 0)
			)
			(min_thickness 0.25)
			(keepout
				(tracks not_allowed)
				(vias allowed)
				(pads allowed)
				(copperpour not_allowed)
				(footprints allowed)
			)
			(placement
				(enabled no)
				(sheetname "")
			)
			(fill
				(thermal_gap 0.5)
				(thermal_bridge_width 0.5)
				(island_removal_mode 0)
			)
			(polygon
				(pts
					(arc
						(start 384.618738 -114.882168)
						(mid 384.53695 -114.863855)
						(end 384.455162 -114.882168)
					)
					(arc
						(start 384.38328 -114.810286)
						(mid 384.53695 -114.766137)
						(end 384.69062 -114.810286)
					)
				)
			)
		)
		(zone
			(layer "F.Cu")
			(hatch none 0.5)
			(connect_pads
				(clearance 0)
			)
			(min_thickness 0.25)
			(keepout
				(tracks not_allowed)
				(vias allowed)
				(pads allowed)
				(copperpour not_allowed)
				(footprints allowed)
			)
			(placement
				(enabled no)
				(sheetname "")
			)
			(fill
				(thermal_gap 0.5)
				(thermal_bridge_width 0.5)
				(island_removal_mode 0)
			)
			(polygon
				(pts
					(arc
						(start 384.618738 -114.082068)
						(mid 384.53695 -114.063755)
						(end 384.455162 -114.082068)
					)
					(arc
						(start 384.38328 -114.010186)
						(mid 384.53695 -113.966037)
						(end 384.69062 -114.010186)
					)
				)
			)
		)
		(zone
			(layer "F.Cu")
			(hatch none 0.5)
			(connect_pads
				(clearance 0)
			)
			(min_thickness 0.25)
			(keepout
				(tracks not_allowed)
				(vias allowed)
				(pads allowed)
				(copperpour not_allowed)
				(footprints allowed)
			)
			(placement
				(enabled no)
				(sheetname "")
			)
			(fill
				(thermal_gap 0.5)
				(thermal_bridge_width 0.5)
				(island_removal_mode 0)
			)
			(polygon
				(pts
					(arc
						(start 384.618738 -113.281968)
						(mid 384.53695 -113.263655)
						(end 384.455162 -113.281968)
					)
					(arc
						(start 384.38328 -113.210086)
						(mid 384.53695 -113.165937)
						(end 384.69062 -113.210086)
					)
				)
			)
		)
		(zone
			(layer "F.Cu")
			(hatch none 0.5)
			(connect_pads
				(clearance 0)
			)
			(min_thickness 0.25)
			(keepout
				(tracks not_allowed)
				(vias allowed)
				(pads allowed)
				(copperpour not_allowed)
				(footprints allowed)
			)
			(placement
				(enabled no)
				(sheetname "")
			)
			(fill
				(thermal_gap 0.5)
				(thermal_bridge_width 0.5)
				(island_removal_mode 0)
			)
			(polygon
				(pts
					(arc
						(start 384.618738 -112.481868)
						(mid 384.53695 -112.463555)
						(end 384.455162 -112.481868)
					)
					(arc
						(start 384.38328 -112.409986)
						(mid 384.53695 -112.365837)
						(end 384.69062 -112.409986)
					)
				)
			)
		)
		(zone
			(layer "F.Cu")
			(hatch none 0.5)
			(connect_pads
				(clearance 0)
			)
			(min_thickness 0.25)
			(keepout
				(tracks not_allowed)
				(vias allowed)
				(pads allowed)
				(copperpour not_allowed)
				(footprints allowed)
			)
			(placement
				(enabled no)
				(sheetname "")
			)
			(fill
				(thermal_gap 0.5)
				(thermal_bridge_width 0.5)
				(island_removal_mode 0)
			)
			(polygon
				(pts
					(arc
						(start 384.618738 -111.681768)
						(mid 384.53695 -111.663455)
						(end 384.455162 -111.681768)
					)
					(arc
						(start 384.38328 -111.609886)
						(mid 384.53695 -111.565737)
						(end 384.69062 -111.609886)
					)
				)
			)
		)
		(zone
			(layer "F.Cu")
			(hatch none 0.5)
			(connect_pads
				(clearance 0)
			)
			(min_thickness 0.25)
			(keepout
				(tracks not_allowed)
				(vias allowed)
				(pads allowed)
				(copperpour not_allowed)
				(footprints allowed)
			)
			(placement
				(enabled no)
				(sheetname "")
			)
			(fill
				(thermal_gap 0.5)
				(thermal_bridge_width 0.5)
				(island_removal_mode 0)
			)
			(polygon
				(pts
					(arc
						(start 384.618738 -110.881668)
						(mid 384.53695 -110.863355)
						(end 384.455162 -110.881668)
					)
					(arc
						(start 384.38328 -110.809786)
						(mid 384.53695 -110.765637)
						(end 384.69062 -110.809786)
					)
				)
			)
		)
		(zone
			(layer "F.Cu")
			(hatch none 0.5)
			(connect_pads
				(clearance 0)
			)
			(min_thickness 0.25)
			(keepout
				(tracks not_allowed)
				(vias allowed)
				(pads allowed)
				(copperpour not_allowed)
				(footprints allowed)
			)
			(placement
				(enabled no)
				(sheetname "")
			)
			(fill
				(thermal_gap 0.5)
				(thermal_bridge_width 0.5)
				(island_removal_mode 0)
			)
			(polygon
				(pts
					(arc
						(start 384.618738 -110.081568)
						(mid 384.53695 -110.063255)
						(end 384.455162 -110.081568)
					)
					(arc
						(start 384.38328 -110.009686)
						(mid 384.53695 -109.965537)
						(end 384.69062 -110.009686)
					)
				)
			)
		)
		(zone
			(layer "F.Cu")
			(hatch none 0.5)
			(connect_pads
				(clearance 0)
			)
			(min_thickness 0.25)
			(keepout
				(tracks not_allowed)
				(vias allowed)
				(pads allowed)
				(copperpour not_allowed)
				(footprints allowed)
			)
			(placement
				(enabled no)
				(sheetname "")
			)
			(fill
				(thermal_gap 0.5)
				(thermal_bridge_width 0.5)
				(island_removal_mode 0)
			)
			(polygon
				(pts
					(arc
						(start 384.618738 -109.281468)
						(mid 384.53695 -109.263155)
						(end 384.455162 -109.281468)
					)
					(arc
						(start 384.38328 -109.209586)
						(mid 384.53695 -109.165437)
						(end 384.69062 -109.209586)
					)
				)
			)
		)
		(zone
			(layer "F.Cu")
			(hatch none 0.5)
			(connect_pads
				(clearance 0)
			)
			(min_thickness 0.25)
			(keepout
				(tracks not_allowed)
				(vias allowed)
				(pads allowed)
				(copperpour not_allowed)
				(footprints allowed)
			)
			(placement
				(enabled no)
				(sheetname "")
			)
			(fill
				(thermal_gap 0.5)
				(thermal_bridge_width 0.5)
				(island_removal_mode 0)
			)
			(polygon
				(pts
					(arc
						(start 384.618738 -108.481368)
						(mid 384.53695 -108.463055)
						(end 384.455162 -108.481368)
					)
					(arc
						(start 384.38328 -108.409486)
						(mid 384.53695 -108.365337)
						(end 384.69062 -108.409486)
					)
				)
			)
		)
		(zone
			(layer "F.Cu")
			(hatch none 0.5)
			(connect_pads
				(clearance 0)
			)
			(min_thickness 0.25)
			(keepout
				(tracks not_allowed)
				(vias allowed)
				(pads allowed)
				(copperpour not_allowed)
				(footprints allowed)
			)
			(placement
				(enabled no)
				(sheetname "")
			)
			(fill
				(thermal_gap 0.5)
				(thermal_bridge_width 0.5)
				(island_removal_mode 0)
			)
			(polygon
				(pts
					(arc
						(start 384.618738 -107.681268)
						(mid 384.53695 -107.662955)
						(end 384.455162 -107.681268)
					)
					(arc
						(start 384.38328 -107.609386)
						(mid 384.53695 -107.565237)
						(end 384.69062 -107.609386)
					)
				)
			)
		)
		(zone
			(layer "F.Cu")
			(hatch none 0.5)
			(connect_pads
				(clearance 0)
			)
			(min_thickness 0.25)
			(keepout
				(tracks not_allowed)
				(vias allowed)
				(pads allowed)
				(copperpour not_allowed)
				(footprints allowed)
			)
			(placement
				(enabled no)
				(sheetname "")
			)
			(fill
				(thermal_gap 0.5)
				(thermal_bridge_width 0.5)
				(island_removal_mode 0)
			)
			(polygon
				(pts
					(arc
						(start 384.618738 -106.881168)
						(mid 384.53695 -106.862855)
						(end 384.455162 -106.881168)
					)
					(arc
						(start 384.38328 -106.809286)
						(mid 384.53695 -106.765137)
						(end 384.69062 -106.809286)
					)
				)
			)
		)
		(zone
			(layer "F.Cu")
			(hatch none 0.5)
			(connect_pads
				(clearance 0)
			)
			(min_thickness 0.25)
			(keepout
				(tracks not_allowed)
				(vias allowed)
				(pads allowed)
				(copperpour not_allowed)
				(footprints allowed)
			)
			(placement
				(enabled no)
				(sheetname "")
			)
			(fill
				(thermal_gap 0.5)
				(thermal_bridge_width 0.5)
				(island_removal_mode 0)
			)
			(polygon
				(pts
					(arc
						(start 384.618738 -106.081068)
						(mid 384.53695 -106.062755)
						(end 384.455162 -106.081068)
					)
					(arc
						(start 384.38328 -106.009186)
						(mid 384.53695 -105.965037)
						(end 384.69062 -106.009186)
					)
				)
			)
		)
		(zone
			(layer "F.Cu")
			(hatch none 0.5)
			(connect_pads
				(clearance 0)
			)
			(min_thickness 0.25)
			(keepout
				(tracks not_allowed)
				(vias allowed)
				(pads allowed)
				(copperpour not_allowed)
				(footprints allowed)
			)
			(placement
				(enabled no)
				(sheetname "")
			)
			(fill
				(thermal_gap 0.5)
				(thermal_bridge_width 0.5)
				(island_removal_mode 0)
			)
			(polygon
				(pts
					(arc
						(start 384.710432 -115.137438)
						(mid 384.728745 -115.05565)
						(end 384.710432 -114.973862)
					)
					(arc
						(start 384.782314 -114.90198)
						(mid 384.826463 -115.05565)
						(end 384.782314 -115.20932)
					)
				)
			)
		)
		(zone
			(layer "F.Cu")
			(hatch none 0.5)
			(connect_pads
				(clearance 0)
			)
			(min_thickness 0.25)
			(keepout
				(tracks not_allowed)
				(vias allowed)
				(pads allowed)
				(copperpour not_allowed)
				(footprints allowed)
			)
			(placement
				(enabled no)
				(sheetname "")
			)
			(fill
				(thermal_gap 0.5)
				(thermal_bridge_width 0.5)
				(island_removal_mode 0)
			)
			(polygon
				(pts
					(arc
						(start 384.710432 -114.337338)
						(mid 384.728745 -114.25555)
						(end 384.710432 -114.173762)
					)
					(arc
						(start 384.782314 -114.10188)
						(mid 384.826463 -114.25555)
						(end 384.782314 -114.40922)
					)
				)
			)
		)
		(zone
			(layer "F.Cu")
			(hatch none 0.5)
			(connect_pads
				(clearance 0)
			)
			(min_thickness 0.25)
			(keepout
				(tracks not_allowed)
				(vias allowed)
				(pads allowed)
				(copperpour not_allowed)
				(footprints allowed)
			)
			(placement
				(enabled no)
				(sheetname "")
			)
			(fill
				(thermal_gap 0.5)
				(thermal_bridge_width 0.5)
				(island_removal_mode 0)
			)
			(polygon
				(pts
					(arc
						(start 384.710432 -113.537238)
						(mid 384.728745 -113.45545)
						(end 384.710432 -113.373662)
					)
					(arc
						(start 384.782314 -113.30178)
						(mid 384.826463 -113.45545)
						(end 384.782314 -113.60912)
					)
				)
			)
		)
		(zone
			(layer "F.Cu")
			(hatch none 0.5)
			(connect_pads
				(clearance 0)
			)
			(min_thickness 0.25)
			(keepout
				(tracks not_allowed)
				(vias allowed)
				(pads allowed)
				(copperpour not_allowed)
				(footprints allowed)
			)
			(placement
				(enabled no)
				(sheetname "")
			)
			(fill
				(thermal_gap 0.5)
				(thermal_bridge_width 0.5)
				(island_removal_mode 0)
			)
			(polygon
				(pts
					(arc
						(start 384.710432 -112.737138)
						(mid 384.728745 -112.65535)
						(end 384.710432 -112.573562)
					)
					(arc
						(start 384.782314 -112.50168)
						(mid 384.826463 -112.65535)
						(end 384.782314 -112.80902)
					)
				)
			)
		)
		(zone
			(layer "F.Cu")
			(hatch none 0.5)
			(connect_pads
				(clearance 0)
			)
			(min_thickness 0.25)
			(keepout
				(tracks not_allowed)
				(vias allowed)
				(pads allowed)
				(copperpour not_allowed)
				(footprints allowed)
			)
			(placement
				(enabled no)
				(sheetname "")
			)
			(fill
				(thermal_gap 0.5)
				(thermal_bridge_width 0.5)
				(island_removal_mode 0)
			)
			(polygon
				(pts
					(arc
						(start 384.710432 -111.937038)
						(mid 384.728745 -111.85525)
						(end 384.710432 -111.773462)
					)
					(arc
						(start 384.782314 -111.70158)
						(mid 384.826463 -111.85525)
						(end 384.782314 -112.00892)
					)
				)
			)
		)
		(zone
			(layer "F.Cu")
			(hatch none 0.5)
			(connect_pads
				(clearance 0)
			)
			(min_thickness 0.25)
			(keepout
				(tracks not_allowed)
				(vias allowed)
				(pads allowed)
				(copperpour not_allowed)
				(footprints allowed)
			)
			(placement
				(enabled no)
				(sheetname "")
			)
			(fill
				(thermal_gap 0.5)
				(thermal_bridge_width 0.5)
				(island_removal_mode 0)
			)
			(polygon
				(pts
					(arc
						(start 384.710432 -111.136938)
						(mid 384.728745 -111.05515)
						(end 384.710432 -110.973362)
					)
					(arc
						(start 384.782314 -110.90148)
						(mid 384.826463 -111.05515)
						(end 384.782314 -111.20882)
					)
				)
			)
		)
		(zone
			(layer "F.Cu")
			(hatch none 0.5)
			(connect_pads
				(clearance 0)
			)
			(min_thickness 0.25)
			(keepout
				(tracks not_allowed)
				(vias allowed)
				(pads allowed)
				(copperpour not_allowed)
				(footprints allowed)
			)
			(placement
				(enabled no)
				(sheetname "")
			)
			(fill
				(thermal_gap 0.5)
				(thermal_bridge_width 0.5)
				(island_removal_mode 0)
			)
			(polygon
				(pts
					(arc
						(start 384.710432 -110.336838)
						(mid 384.728745 -110.25505)
						(end 384.710432 -110.173262)
					)
					(arc
						(start 384.782314 -110.10138)
						(mid 384.826463 -110.25505)
						(end 384.782314 -110.40872)
					)
				)
			)
		)
		(zone
			(layer "F.Cu")
			(hatch none 0.5)
			(connect_pads
				(clearance 0)
			)
			(min_thickness 0.25)
			(keepout
				(tracks not_allowed)
				(vias allowed)
				(pads allowed)
				(copperpour not_allowed)
				(footprints allowed)
			)
			(placement
				(enabled no)
				(sheetname "")
			)
			(fill
				(thermal_gap 0.5)
				(thermal_bridge_width 0.5)
				(island_removal_mode 0)
			)
			(polygon
				(pts
					(arc
						(start 384.710432 -109.536738)
						(mid 384.728745 -109.45495)
						(end 384.710432 -109.373162)
					)
					(arc
						(start 384.782314 -109.30128)
						(mid 384.826463 -109.45495)
						(end 384.782314 -109.60862)
					)
				)
			)
		)
		(zone
			(layer "F.Cu")
			(hatch none 0.5)
			(connect_pads
				(clearance 0)
			)
			(min_thickness 0.25)
			(keepout
				(tracks not_allowed)
				(vias allowed)
				(pads allowed)
				(copperpour not_allowed)
				(footprints allowed)
			)
			(placement
				(enabled no)
				(sheetname "")
			)
			(fill
				(thermal_gap 0.5)
				(thermal_bridge_width 0.5)
				(island_removal_mode 0)
			)
			(polygon
				(pts
					(arc
						(start 384.710432 -108.736638)
						(mid 384.728745 -108.65485)
						(end 384.710432 -108.573062)
					)
					(arc
						(start 384.782314 -108.50118)
						(mid 384.826463 -108.65485)
						(end 384.782314 -108.80852)
					)
				)
			)
		)
		(zone
			(layer "F.Cu")
			(hatch none 0.5)
			(connect_pads
				(clearance 0)
			)
			(min_thickness 0.25)
			(keepout
				(tracks not_allowed)
				(vias allowed)
				(pads allowed)
				(copperpour not_allowed)
				(footprints allowed)
			)
			(placement
				(enabled no)
				(sheetname "")
			)
			(fill
				(thermal_gap 0.5)
				(thermal_bridge_width 0.5)
				(island_removal_mode 0)
			)
			(polygon
				(pts
					(arc
						(start 384.710432 -107.936538)
						(mid 384.728745 -107.85475)
						(end 384.710432 -107.772962)
					)
					(arc
						(start 384.782314 -107.70108)
						(mid 384.826463 -107.85475)
						(end 384.782314 -108.00842)
					)
				)
			)
		)
		(zone
			(layer "F.Cu")
			(hatch none 0.5)
			(connect_pads
				(clearance 0)
			)
			(min_thickness 0.25)
			(keepout
				(tracks not_allowed)
				(vias allowed)
				(pads allowed)
				(copperpour not_allowed)
				(footprints allowed)
			)
			(placement
				(enabled no)
				(sheetname "")
			)
			(fill
				(thermal_gap 0.5)
				(thermal_bridge_width 0.5)
				(island_removal_mode 0)
			)
			(polygon
				(pts
					(arc
						(start 384.710432 -107.136438)
						(mid 384.728745 -107.05465)
						(end 384.710432 -106.972862)
					)
					(arc
						(start 384.782314 -106.90098)
						(mid 384.826463 -107.05465)
						(end 384.782314 -107.20832)
					)
				)
			)
		)
		(zone
			(layer "F.Cu")
			(hatch none 0.5)
			(connect_pads
				(clearance 0)
			)
			(min_thickness 0.25)
			(keepout
				(tracks not_allowed)
				(vias allowed)
				(pads allowed)
				(copperpour not_allowed)
				(footprints allowed)
			)
			(placement
				(enabled no)
				(sheetname "")
			)
			(fill
				(thermal_gap 0.5)
				(thermal_bridge_width 0.5)
				(island_removal_mode 0)
			)
			(polygon
				(pts
					(arc
						(start 384.710432 -106.336338)
						(mid 384.728745 -106.25455)
						(end 384.710432 -106.172762)
					)
					(arc
						(start 384.782314 -106.10088)
						(mid 384.826463 -106.25455)
						(end 384.782314 -106.40822)
					)
				)
			)
		)
		(zone
			(layer "F.Cu")
			(hatch none 0.5)
			(connect_pads
				(clearance 0)
			)
			(min_thickness 0.25)
			(keepout
				(tracks not_allowed)
				(vias allowed)
				(pads allowed)
				(copperpour not_allowed)
				(footprints allowed)
			)
			(placement
				(enabled no)
				(sheetname "")
			)
			(fill
				(thermal_gap 0.5)
				(thermal_bridge_width 0.5)
				(island_removal_mode 0)
			)
			(polygon
				(pts
					(arc
						(start 385.163568 -114.973862)
						(mid 385.145255 -115.05565)
						(end 385.163568 -115.137438)
					)
					(arc
						(start 385.091686 -115.20932)
						(mid 385.047537 -115.05565)
						(end 385.091686 -114.90198)
					)
				)
			)
		)
		(zone
			(layer "F.Cu")
			(hatch none 0.5)
			(connect_pads
				(clearance 0)
			)
			(min_thickness 0.25)
			(keepout
				(tracks not_allowed)
				(vias allowed)
				(pads allowed)
				(copperpour not_allowed)
				(footprints allowed)
			)
			(placement
				(enabled no)
				(sheetname "")
			)
			(fill
				(thermal_gap 0.5)
				(thermal_bridge_width 0.5)
				(island_removal_mode 0)
			)
			(polygon
				(pts
					(arc
						(start 385.163568 -112.573562)
						(mid 385.145255 -112.65535)
						(end 385.163568 -112.737138)
					)
					(arc
						(start 385.091686 -112.80902)
						(mid 385.047537 -112.65535)
						(end 385.091686 -112.50168)
					)
				)
			)
		)
		(zone
			(layer "F.Cu")
			(hatch none 0.5)
			(connect_pads
				(clearance 0)
			)
			(min_thickness 0.25)
			(keepout
				(tracks not_allowed)
				(vias allowed)
				(pads allowed)
				(copperpour not_allowed)
				(footprints allowed)
			)
			(placement
				(enabled no)
				(sheetname "")
			)
			(fill
				(thermal_gap 0.5)
				(thermal_bridge_width 0.5)
				(island_removal_mode 0)
			)
			(polygon
				(pts
					(arc
						(start 385.163568 -111.773462)
						(mid 385.145255 -111.85525)
						(end 385.163568 -111.937038)
					)
					(arc
						(start 385.091686 -112.00892)
						(mid 385.047537 -111.85525)
						(end 385.091686 -111.70158)
					)
				)
			)
		)
		(zone
			(layer "F.Cu")
			(hatch none 0.5)
			(connect_pads
				(clearance 0)
			)
			(min_thickness 0.25)
			(keepout
				(tracks not_allowed)
				(vias allowed)
				(pads allowed)
				(copperpour not_allowed)
				(footprints allowed)
			)
			(placement
				(enabled no)
				(sheetname "")
			)
			(fill
				(thermal_gap 0.5)
				(thermal_bridge_width 0.5)
				(island_removal_mode 0)
			)
			(polygon
				(pts
					(arc
						(start 385.163568 -110.973362)
						(mid 385.145255 -111.05515)
						(end 385.163568 -111.136938)
					)
					(arc
						(start 385.091686 -111.20882)
						(mid 385.047537 -111.05515)
						(end 385.091686 -110.90148)
					)
				)
			)
		)
		(zone
			(layer "F.Cu")
			(hatch none 0.5)
			(connect_pads
				(clearance 0)
			)
			(min_thickness 0.25)
			(keepout
				(tracks not_allowed)
				(vias allowed)
				(pads allowed)
				(copperpour not_allowed)
				(footprints allowed)
			)
			(placement
				(enabled no)
				(sheetname "")
			)
			(fill
				(thermal_gap 0.5)
				(thermal_bridge_width 0.5)
				(island_removal_mode 0)
			)
			(polygon
				(pts
					(arc
						(start 385.163568 -110.173262)
						(mid 385.145255 -110.25505)
						(end 385.163568 -110.336838)
					)
					(arc
						(start 385.091686 -110.40872)
						(mid 385.047537 -110.25505)
						(end 385.091686 -110.10138)
					)
				)
			)
		)
		(zone
			(layer "F.Cu")
			(hatch none 0.5)
			(connect_pads
				(clearance 0)
			)
			(min_thickness 0.25)
			(keepout
				(tracks not_allowed)
				(vias allowed)
				(pads allowed)
				(copperpour not_allowed)
				(footprints allowed)
			)
			(placement
				(enabled no)
				(sheetname "")
			)
			(fill
				(thermal_gap 0.5)
				(thermal_bridge_width 0.5)
				(island_removal_mode 0)
			)
			(polygon
				(pts
					(arc
						(start 385.163568 -109.373162)
						(mid 385.145255 -109.45495)
						(end 385.163568 -109.536738)
					)
					(arc
						(start 385.091686 -109.60862)
						(mid 385.047537 -109.45495)
						(end 385.091686 -109.30128)
					)
				)
			)
		)
		(zone
			(layer "F.Cu")
			(hatch none 0.5)
			(connect_pads
				(clearance 0)
			)
			(min_thickness 0.25)
			(keepout
				(tracks not_allowed)
				(vias allowed)
				(pads allowed)
				(copperpour not_allowed)
				(footprints allowed)
			)
			(placement
				(enabled no)
				(sheetname "")
			)
			(fill
				(thermal_gap 0.5)
				(thermal_bridge_width 0.5)
				(island_removal_mode 0)
			)
			(polygon
				(pts
					(arc
						(start 385.163568 -108.573062)
						(mid 385.145255 -108.65485)
						(end 385.163568 -108.736638)
					)
					(arc
						(start 385.091686 -108.80852)
						(mid 385.047537 -108.65485)
						(end 385.091686 -108.50118)
					)
				)
			)
		)
		(zone
			(layer "F.Cu")
			(hatch none 0.5)
			(connect_pads
				(clearance 0)
			)
			(min_thickness 0.25)
			(keepout
				(tracks not_allowed)
				(vias allowed)
				(pads allowed)
				(copperpour not_allowed)
				(footprints allowed)
			)
			(placement
				(enabled no)
				(sheetname "")
			)
			(fill
				(thermal_gap 0.5)
				(thermal_bridge_width 0.5)
				(island_removal_mode 0)
			)
			(polygon
				(pts
					(arc
						(start 385.163568 -107.772962)
						(mid 385.145255 -107.85475)
						(end 385.163568 -107.936538)
					)
					(arc
						(start 385.091686 -108.00842)
						(mid 385.047537 -107.85475)
						(end 385.091686 -107.70108)
					)
				)
			)
		)
		(zone
			(layer "F.Cu")
			(hatch none 0.5)
			(connect_pads
				(clearance 0)
			)
			(min_thickness 0.25)
			(keepout
				(tracks not_allowed)
				(vias allowed)
				(pads allowed)
				(copperpour not_allowed)
				(footprints allowed)
			)
			(placement
				(enabled no)
				(sheetname "")
			)
			(fill
				(thermal_gap 0.5)
				(thermal_bridge_width 0.5)
				(island_removal_mode 0)
			)
			(polygon
				(pts
					(arc
						(start 385.163568 -106.972862)
						(mid 385.145255 -107.05465)
						(end 385.163568 -107.136438)
					)
					(arc
						(start 385.091686 -107.20832)
						(mid 385.047537 -107.05465)
						(end 385.091686 -106.90098)
					)
				)
			)
		)
		(zone
			(layer "F.Cu")
			(hatch none 0.5)
			(connect_pads
				(clearance 0)
			)
			(min_thickness 0.25)
			(keepout
				(tracks not_allowed)
				(vias allowed)
				(pads allowed)
				(copperpour not_allowed)
				(footprints allowed)
			)
			(placement
				(enabled no)
				(sheetname "")
			)
			(fill
				(thermal_gap 0.5)
				(thermal_bridge_width 0.5)
				(island_removal_mode 0)
			)
			(polygon
				(pts
					(arc
						(start 385.163568 -104.572562)
						(mid 385.145255 -104.65435)
						(end 385.163568 -104.736138)
					)
					(arc
						(start 385.091686 -104.80802)
						(mid 385.047537 -104.65435)
						(end 385.091686 -104.50068)
					)
				)
			)
		)
		(zone
			(layer "F.Cu")
			(hatch none 0.5)
			(connect_pads
				(clearance 0)
			)
			(min_thickness 0.25)
			(keepout
				(tracks not_allowed)
				(vias allowed)
				(pads allowed)
				(copperpour not_allowed)
				(footprints allowed)
			)
			(placement
				(enabled no)
				(sheetname "")
			)
			(fill
				(thermal_gap 0.5)
				(thermal_bridge_width 0.5)
				(island_removal_mode 0)
			)
			(polygon
				(pts
					(arc
						(start 385.255262 -115.229132)
						(mid 385.33705 -115.247445)
						(end 385.418838 -115.229132)
					)
					(arc
						(start 385.49072 -115.301014)
						(mid 385.33705 -115.345163)
						(end 385.18338 -115.301014)
					)
				)
			)
		)
		(zone
			(layer "F.Cu")
			(hatch none 0.5)
			(connect_pads
				(clearance 0)
			)
			(min_thickness 0.25)
			(keepout
				(tracks not_allowed)
				(vias allowed)
				(pads allowed)
				(copperpour not_allowed)
				(footprints allowed)
			)
			(placement
				(enabled no)
				(sheetname "")
			)
			(fill
				(thermal_gap 0.5)
				(thermal_bridge_width 0.5)
				(island_removal_mode 0)
			)
			(polygon
				(pts
					(arc
						(start 385.255262 -112.828832)
						(mid 385.33705 -112.847145)
						(end 385.418838 -112.828832)
					)
					(arc
						(start 385.49072 -112.900714)
						(mid 385.33705 -112.944863)
						(end 385.18338 -112.900714)
					)
				)
			)
		)
		(zone
			(layer "F.Cu")
			(hatch none 0.5)
			(connect_pads
				(clearance 0)
			)
			(min_thickness 0.25)
			(keepout
				(tracks not_allowed)
				(vias allowed)
				(pads allowed)
				(copperpour not_allowed)
				(footprints allowed)
			)
			(placement
				(enabled no)
				(sheetname "")
			)
			(fill
				(thermal_gap 0.5)
				(thermal_bridge_width 0.5)
				(island_removal_mode 0)
			)
			(polygon
				(pts
					(arc
						(start 385.255262 -112.028732)
						(mid 385.33705 -112.047045)
						(end 385.418838 -112.028732)
					)
					(arc
						(start 385.49072 -112.100614)
						(mid 385.33705 -112.144763)
						(end 385.18338 -112.100614)
					)
				)
			)
		)
		(zone
			(layer "F.Cu")
			(hatch none 0.5)
			(connect_pads
				(clearance 0)
			)
			(min_thickness 0.25)
			(keepout
				(tracks not_allowed)
				(vias allowed)
				(pads allowed)
				(copperpour not_allowed)
				(footprints allowed)
			)
			(placement
				(enabled no)
				(sheetname "")
			)
			(fill
				(thermal_gap 0.5)
				(thermal_bridge_width 0.5)
				(island_removal_mode 0)
			)
			(polygon
				(pts
					(arc
						(start 385.255262 -111.228632)
						(mid 385.33705 -111.246945)
						(end 385.418838 -111.228632)
					)
					(arc
						(start 385.49072 -111.300514)
						(mid 385.33705 -111.344663)
						(end 385.18338 -111.300514)
					)
				)
			)
		)
		(zone
			(layer "F.Cu")
			(hatch none 0.5)
			(connect_pads
				(clearance 0)
			)
			(min_thickness 0.25)
			(keepout
				(tracks not_allowed)
				(vias allowed)
				(pads allowed)
				(copperpour not_allowed)
				(footprints allowed)
			)
			(placement
				(enabled no)
				(sheetname "")
			)
			(fill
				(thermal_gap 0.5)
				(thermal_bridge_width 0.5)
				(island_removal_mode 0)
			)
			(polygon
				(pts
					(arc
						(start 385.255262 -110.428532)
						(mid 385.33705 -110.446845)
						(end 385.418838 -110.428532)
					)
					(arc
						(start 385.49072 -110.500414)
						(mid 385.33705 -110.544563)
						(end 385.18338 -110.500414)
					)
				)
			)
		)
		(zone
			(layer "F.Cu")
			(hatch none 0.5)
			(connect_pads
				(clearance 0)
			)
			(min_thickness 0.25)
			(keepout
				(tracks not_allowed)
				(vias allowed)
				(pads allowed)
				(copperpour not_allowed)
				(footprints allowed)
			)
			(placement
				(enabled no)
				(sheetname "")
			)
			(fill
				(thermal_gap 0.5)
				(thermal_bridge_width 0.5)
				(island_removal_mode 0)
			)
			(polygon
				(pts
					(arc
						(start 385.255262 -109.628432)
						(mid 385.33705 -109.646745)
						(end 385.418838 -109.628432)
					)
					(arc
						(start 385.49072 -109.700314)
						(mid 385.33705 -109.744463)
						(end 385.18338 -109.700314)
					)
				)
			)
		)
		(zone
			(layer "F.Cu")
			(hatch none 0.5)
			(connect_pads
				(clearance 0)
			)
			(min_thickness 0.25)
			(keepout
				(tracks not_allowed)
				(vias allowed)
				(pads allowed)
				(copperpour not_allowed)
				(footprints allowed)
			)
			(placement
				(enabled no)
				(sheetname "")
			)
			(fill
				(thermal_gap 0.5)
				(thermal_bridge_width 0.5)
				(island_removal_mode 0)
			)
			(polygon
				(pts
					(arc
						(start 385.255262 -108.828332)
						(mid 385.33705 -108.846645)
						(end 385.418838 -108.828332)
					)
					(arc
						(start 385.49072 -108.900214)
						(mid 385.33705 -108.944363)
						(end 385.18338 -108.900214)
					)
				)
			)
		)
		(zone
			(layer "F.Cu")
			(hatch none 0.5)
			(connect_pads
				(clearance 0)
			)
			(min_thickness 0.25)
			(keepout
				(tracks not_allowed)
				(vias allowed)
				(pads allowed)
				(copperpour not_allowed)
				(footprints allowed)
			)
			(placement
				(enabled no)
				(sheetname "")
			)
			(fill
				(thermal_gap 0.5)
				(thermal_bridge_width 0.5)
				(island_removal_mode 0)
			)
			(polygon
				(pts
					(arc
						(start 385.255262 -108.028232)
						(mid 385.33705 -108.046545)
						(end 385.418838 -108.028232)
					)
					(arc
						(start 385.49072 -108.100114)
						(mid 385.33705 -108.144263)
						(end 385.18338 -108.100114)
					)
				)
			)
		)
		(zone
			(layer "F.Cu")
			(hatch none 0.5)
			(connect_pads
				(clearance 0)
			)
			(min_thickness 0.25)
			(keepout
				(tracks not_allowed)
				(vias allowed)
				(pads allowed)
				(copperpour not_allowed)
				(footprints allowed)
			)
			(placement
				(enabled no)
				(sheetname "")
			)
			(fill
				(thermal_gap 0.5)
				(thermal_bridge_width 0.5)
				(island_removal_mode 0)
			)
			(polygon
				(pts
					(arc
						(start 385.255262 -107.228132)
						(mid 385.33705 -107.246445)
						(end 385.418838 -107.228132)
					)
					(arc
						(start 385.49072 -107.300014)
						(mid 385.33705 -107.344163)
						(end 385.18338 -107.300014)
					)
				)
			)
		)
		(zone
			(layer "F.Cu")
			(hatch none 0.5)
			(connect_pads
				(clearance 0)
			)
			(min_thickness 0.25)
			(keepout
				(tracks not_allowed)
				(vias allowed)
				(pads allowed)
				(copperpour not_allowed)
				(footprints allowed)
			)
			(placement
				(enabled no)
				(sheetname "")
			)
			(fill
				(thermal_gap 0.5)
				(thermal_bridge_width 0.5)
				(island_removal_mode 0)
			)
			(polygon
				(pts
					(arc
						(start 385.255262 -104.827832)
						(mid 385.33705 -104.846145)
						(end 385.418838 -104.827832)
					)
					(arc
						(start 385.49072 -104.899714)
						(mid 385.33705 -104.943863)
						(end 385.18338 -104.899714)
					)
				)
			)
		)
		(zone
			(layer "F.Cu")
			(hatch none 0.5)
			(connect_pads
				(clearance 0)
			)
			(min_thickness 0.25)
			(keepout
				(tracks not_allowed)
				(vias allowed)
				(pads allowed)
				(copperpour not_allowed)
				(footprints allowed)
			)
			(placement
				(enabled no)
				(sheetname "")
			)
			(fill
				(thermal_gap 0.5)
				(thermal_bridge_width 0.5)
				(island_removal_mode 0)
			)
			(polygon
				(pts
					(arc
						(start 385.418838 -114.882168)
						(mid 385.33705 -114.863855)
						(end 385.255262 -114.882168)
					)
					(arc
						(start 385.18338 -114.810286)
						(mid 385.33705 -114.766137)
						(end 385.49072 -114.810286)
					)
				)
			)
		)
		(zone
			(layer "F.Cu")
			(hatch none 0.5)
			(connect_pads
				(clearance 0)
			)
			(min_thickness 0.25)
			(keepout
				(tracks not_allowed)
				(vias allowed)
				(pads allowed)
				(copperpour not_allowed)
				(footprints allowed)
			)
			(placement
				(enabled no)
				(sheetname "")
			)
			(fill
				(thermal_gap 0.5)
				(thermal_bridge_width 0.5)
				(island_removal_mode 0)
			)
			(polygon
				(pts
					(arc
						(start 385.418838 -112.481868)
						(mid 385.33705 -112.463555)
						(end 385.255262 -112.481868)
					)
					(arc
						(start 385.18338 -112.409986)
						(mid 385.33705 -112.365837)
						(end 385.49072 -112.409986)
					)
				)
			)
		)
		(zone
			(layer "F.Cu")
			(hatch none 0.5)
			(connect_pads
				(clearance 0)
			)
			(min_thickness 0.25)
			(keepout
				(tracks not_allowed)
				(vias allowed)
				(pads allowed)
				(copperpour not_allowed)
				(footprints allowed)
			)
			(placement
				(enabled no)
				(sheetname "")
			)
			(fill
				(thermal_gap 0.5)
				(thermal_bridge_width 0.5)
				(island_removal_mode 0)
			)
			(polygon
				(pts
					(arc
						(start 385.418838 -111.681768)
						(mid 385.33705 -111.663455)
						(end 385.255262 -111.681768)
					)
					(arc
						(start 385.18338 -111.609886)
						(mid 385.33705 -111.565737)
						(end 385.49072 -111.609886)
					)
				)
			)
		)
		(zone
			(layer "F.Cu")
			(hatch none 0.5)
			(connect_pads
				(clearance 0)
			)
			(min_thickness 0.25)
			(keepout
				(tracks not_allowed)
				(vias allowed)
				(pads allowed)
				(copperpour not_allowed)
				(footprints allowed)
			)
			(placement
				(enabled no)
				(sheetname "")
			)
			(fill
				(thermal_gap 0.5)
				(thermal_bridge_width 0.5)
				(island_removal_mode 0)
			)
			(polygon
				(pts
					(arc
						(start 385.418838 -110.881668)
						(mid 385.33705 -110.863355)
						(end 385.255262 -110.881668)
					)
					(arc
						(start 385.18338 -110.809786)
						(mid 385.33705 -110.765637)
						(end 385.49072 -110.809786)
					)
				)
			)
		)
		(zone
			(layer "F.Cu")
			(hatch none 0.5)
			(connect_pads
				(clearance 0)
			)
			(min_thickness 0.25)
			(keepout
				(tracks not_allowed)
				(vias allowed)
				(pads allowed)
				(copperpour not_allowed)
				(footprints allowed)
			)
			(placement
				(enabled no)
				(sheetname "")
			)
			(fill
				(thermal_gap 0.5)
				(thermal_bridge_width 0.5)
				(island_removal_mode 0)
			)
			(polygon
				(pts
					(arc
						(start 385.418838 -110.081568)
						(mid 385.33705 -110.063255)
						(end 385.255262 -110.081568)
					)
					(arc
						(start 385.18338 -110.009686)
						(mid 385.33705 -109.965537)
						(end 385.49072 -110.009686)
					)
				)
			)
		)
		(zone
			(layer "F.Cu")
			(hatch none 0.5)
			(connect_pads
				(clearance 0)
			)
			(min_thickness 0.25)
			(keepout
				(tracks not_allowed)
				(vias allowed)
				(pads allowed)
				(copperpour not_allowed)
				(footprints allowed)
			)
			(placement
				(enabled no)
				(sheetname "")
			)
			(fill
				(thermal_gap 0.5)
				(thermal_bridge_width 0.5)
				(island_removal_mode 0)
			)
			(polygon
				(pts
					(arc
						(start 385.418838 -109.281468)
						(mid 385.33705 -109.263155)
						(end 385.255262 -109.281468)
					)
					(arc
						(start 385.18338 -109.209586)
						(mid 385.33705 -109.165437)
						(end 385.49072 -109.209586)
					)
				)
			)
		)
		(zone
			(layer "F.Cu")
			(hatch none 0.5)
			(connect_pads
				(clearance 0)
			)
			(min_thickness 0.25)
			(keepout
				(tracks not_allowed)
				(vias allowed)
				(pads allowed)
				(copperpour not_allowed)
				(footprints allowed)
			)
			(placement
				(enabled no)
				(sheetname "")
			)
			(fill
				(thermal_gap 0.5)
				(thermal_bridge_width 0.5)
				(island_removal_mode 0)
			)
			(polygon
				(pts
					(arc
						(start 385.418838 -108.481368)
						(mid 385.33705 -108.463055)
						(end 385.255262 -108.481368)
					)
					(arc
						(start 385.18338 -108.409486)
						(mid 385.33705 -108.365337)
						(end 385.49072 -108.409486)
					)
				)
			)
		)
		(zone
			(layer "F.Cu")
			(hatch none 0.5)
			(connect_pads
				(clearance 0)
			)
			(min_thickness 0.25)
			(keepout
				(tracks not_allowed)
				(vias allowed)
				(pads allowed)
				(copperpour not_allowed)
				(footprints allowed)
			)
			(placement
				(enabled no)
				(sheetname "")
			)
			(fill
				(thermal_gap 0.5)
				(thermal_bridge_width 0.5)
				(island_removal_mode 0)
			)
			(polygon
				(pts
					(arc
						(start 385.418838 -107.681268)
						(mid 385.33705 -107.662955)
						(end 385.255262 -107.681268)
					)
					(arc
						(start 385.18338 -107.609386)
						(mid 385.33705 -107.565237)
						(end 385.49072 -107.609386)
					)
				)
			)
		)
		(zone
			(layer "F.Cu")
			(hatch none 0.5)
			(connect_pads
				(clearance 0)
			)
			(min_thickness 0.25)
			(keepout
				(tracks not_allowed)
				(vias allowed)
				(pads allowed)
				(copperpour not_allowed)
				(footprints allowed)
			)
			(placement
				(enabled no)
				(sheetname "")
			)
			(fill
				(thermal_gap 0.5)
				(thermal_bridge_width 0.5)
				(island_removal_mode 0)
			)
			(polygon
				(pts
					(arc
						(start 385.418838 -106.881168)
						(mid 385.33705 -106.862855)
						(end 385.255262 -106.881168)
					)
					(arc
						(start 385.18338 -106.809286)
						(mid 385.33705 -106.765137)
						(end 385.49072 -106.809286)
					)
				)
			)
		)
		(zone
			(layer "F.Cu")
			(hatch none 0.5)
			(connect_pads
				(clearance 0)
			)
			(min_thickness 0.25)
			(keepout
				(tracks not_allowed)
				(vias allowed)
				(pads allowed)
				(copperpour not_allowed)
				(footprints allowed)
			)
			(placement
				(enabled no)
				(sheetname "")
			)
			(fill
				(thermal_gap 0.5)
				(thermal_bridge_width 0.5)
				(island_removal_mode 0)
			)
			(polygon
				(pts
					(arc
						(start 385.418838 -104.480868)
						(mid 385.33705 -104.462555)
						(end 385.255262 -104.480868)
					)
					(arc
						(start 385.18338 -104.408986)
						(mid 385.33705 -104.364837)
						(end 385.49072 -104.408986)
					)
				)
			)
		)
		(zone
			(layer "F.Cu")
			(hatch none 0.5)
			(connect_pads
				(clearance 0)
			)
			(min_thickness 0.25)
			(keepout
				(tracks not_allowed)
				(vias allowed)
				(pads allowed)
				(copperpour not_allowed)
				(footprints allowed)
			)
			(placement
				(enabled no)
				(sheetname "")
			)
			(fill
				(thermal_gap 0.5)
				(thermal_bridge_width 0.5)
				(island_removal_mode 0)
			)
			(polygon
				(pts
					(arc
						(start 385.510532 -115.137438)
						(mid 385.528845 -115.05565)
						(end 385.510532 -114.973862)
					)
					(arc
						(start 385.582414 -114.90198)
						(mid 385.626563 -115.05565)
						(end 385.582414 -115.20932)
					)
				)
			)
		)
		(zone
			(layer "F.Cu")
			(hatch none 0.5)
			(connect_pads
				(clearance 0)
			)
			(min_thickness 0.25)
			(keepout
				(tracks not_allowed)
				(vias allowed)
				(pads allowed)
				(copperpour not_allowed)
				(footprints allowed)
			)
			(placement
				(enabled no)
				(sheetname "")
			)
			(fill
				(thermal_gap 0.5)
				(thermal_bridge_width 0.5)
				(island_removal_mode 0)
			)
			(polygon
				(pts
					(arc
						(start 385.510532 -112.737138)
						(mid 385.528845 -112.65535)
						(end 385.510532 -112.573562)
					)
					(arc
						(start 385.582414 -112.50168)
						(mid 385.626563 -112.65535)
						(end 385.582414 -112.80902)
					)
				)
			)
		)
		(zone
			(layer "F.Cu")
			(hatch none 0.5)
			(connect_pads
				(clearance 0)
			)
			(min_thickness 0.25)
			(keepout
				(tracks not_allowed)
				(vias allowed)
				(pads allowed)
				(copperpour not_allowed)
				(footprints allowed)
			)
			(placement
				(enabled no)
				(sheetname "")
			)
			(fill
				(thermal_gap 0.5)
				(thermal_bridge_width 0.5)
				(island_removal_mode 0)
			)
			(polygon
				(pts
					(arc
						(start 385.510532 -111.937038)
						(mid 385.528845 -111.85525)
						(end 385.510532 -111.773462)
					)
					(arc
						(start 385.582414 -111.70158)
						(mid 385.626563 -111.85525)
						(end 385.582414 -112.00892)
					)
				)
			)
		)
		(zone
			(layer "F.Cu")
			(hatch none 0.5)
			(connect_pads
				(clearance 0)
			)
			(min_thickness 0.25)
			(keepout
				(tracks not_allowed)
				(vias allowed)
				(pads allowed)
				(copperpour not_allowed)
				(footprints allowed)
			)
			(placement
				(enabled no)
				(sheetname "")
			)
			(fill
				(thermal_gap 0.5)
				(thermal_bridge_width 0.5)
				(island_removal_mode 0)
			)
			(polygon
				(pts
					(arc
						(start 385.510532 -111.136938)
						(mid 385.528845 -111.05515)
						(end 385.510532 -110.973362)
					)
					(arc
						(start 385.582414 -110.90148)
						(mid 385.626563 -111.05515)
						(end 385.582414 -111.20882)
					)
				)
			)
		)
		(zone
			(layer "F.Cu")
			(hatch none 0.5)
			(connect_pads
				(clearance 0)
			)
			(min_thickness 0.25)
			(keepout
				(tracks not_allowed)
				(vias allowed)
				(pads allowed)
				(copperpour not_allowed)
				(footprints allowed)
			)
			(placement
				(enabled no)
				(sheetname "")
			)
			(fill
				(thermal_gap 0.5)
				(thermal_bridge_width 0.5)
				(island_removal_mode 0)
			)
			(polygon
				(pts
					(arc
						(start 385.510532 -110.336838)
						(mid 385.528845 -110.25505)
						(end 385.510532 -110.173262)
					)
					(arc
						(start 385.582414 -110.10138)
						(mid 385.626563 -110.25505)
						(end 385.582414 -110.40872)
					)
				)
			)
		)
		(zone
			(layer "F.Cu")
			(hatch none 0.5)
			(connect_pads
				(clearance 0)
			)
			(min_thickness 0.25)
			(keepout
				(tracks not_allowed)
				(vias allowed)
				(pads allowed)
				(copperpour not_allowed)
				(footprints allowed)
			)
			(placement
				(enabled no)
				(sheetname "")
			)
			(fill
				(thermal_gap 0.5)
				(thermal_bridge_width 0.5)
				(island_removal_mode 0)
			)
			(polygon
				(pts
					(arc
						(start 385.510532 -109.536738)
						(mid 385.528845 -109.45495)
						(end 385.510532 -109.373162)
					)
					(arc
						(start 385.582414 -109.30128)
						(mid 385.626563 -109.45495)
						(end 385.582414 -109.60862)
					)
				)
			)
		)
		(zone
			(layer "F.Cu")
			(hatch none 0.5)
			(connect_pads
				(clearance 0)
			)
			(min_thickness 0.25)
			(keepout
				(tracks not_allowed)
				(vias allowed)
				(pads allowed)
				(copperpour not_allowed)
				(footprints allowed)
			)
			(placement
				(enabled no)
				(sheetname "")
			)
			(fill
				(thermal_gap 0.5)
				(thermal_bridge_width 0.5)
				(island_removal_mode 0)
			)
			(polygon
				(pts
					(arc
						(start 385.510532 -108.736638)
						(mid 385.528845 -108.65485)
						(end 385.510532 -108.573062)
					)
					(arc
						(start 385.582414 -108.50118)
						(mid 385.626563 -108.65485)
						(end 385.582414 -108.80852)
					)
				)
			)
		)
		(zone
			(layer "F.Cu")
			(hatch none 0.5)
			(connect_pads
				(clearance 0)
			)
			(min_thickness 0.25)
			(keepout
				(tracks not_allowed)
				(vias allowed)
				(pads allowed)
				(copperpour not_allowed)
				(footprints allowed)
			)
			(placement
				(enabled no)
				(sheetname "")
			)
			(fill
				(thermal_gap 0.5)
				(thermal_bridge_width 0.5)
				(island_removal_mode 0)
			)
			(polygon
				(pts
					(arc
						(start 385.510532 -107.936538)
						(mid 385.528845 -107.85475)
						(end 385.510532 -107.772962)
					)
					(arc
						(start 385.582414 -107.70108)
						(mid 385.626563 -107.85475)
						(end 385.582414 -108.00842)
					)
				)
			)
		)
		(zone
			(layer "F.Cu")
			(hatch none 0.5)
			(connect_pads
				(clearance 0)
			)
			(min_thickness 0.25)
			(keepout
				(tracks not_allowed)
				(vias allowed)
				(pads allowed)
				(copperpour not_allowed)
				(footprints allowed)
			)
			(placement
				(enabled no)
				(sheetname "")
			)
			(fill
				(thermal_gap 0.5)
				(thermal_bridge_width 0.5)
				(island_removal_mode 0)
			)
			(polygon
				(pts
					(arc
						(start 385.510532 -107.136438)
						(mid 385.528845 -107.05465)
						(end 385.510532 -106.972862)
					)
					(arc
						(start 385.582414 -106.90098)
						(mid 385.626563 -107.05465)
						(end 385.582414 -107.20832)
					)
				)
			)
		)
		(zone
			(layer "F.Cu")
			(hatch none 0.5)
			(connect_pads
				(clearance 0)
			)
			(min_thickness 0.25)
			(keepout
				(tracks not_allowed)
				(vias allowed)
				(pads allowed)
				(copperpour not_allowed)
				(footprints allowed)
			)
			(placement
				(enabled no)
				(sheetname "")
			)
			(fill
				(thermal_gap 0.5)
				(thermal_bridge_width 0.5)
				(island_removal_mode 0)
			)
			(polygon
				(pts
					(arc
						(start 385.510532 -104.736138)
						(mid 385.528845 -104.65435)
						(end 385.510532 -104.572562)
					)
					(arc
						(start 385.582414 -104.50068)
						(mid 385.626563 -104.65435)
						(end 385.582414 -104.80802)
					)
				)
			)
		)
		(zone
			(layer "F.Cu")
			(hatch none 0.5)
			(connect_pads
				(clearance 0)
			)
			(min_thickness 0.25)
			(keepout
				(tracks not_allowed)
				(vias allowed)
				(pads allowed)
				(copperpour not_allowed)
				(footprints allowed)
			)
			(placement
				(enabled no)
				(sheetname "")
			)
			(fill
				(thermal_gap 0.5)
				(thermal_bridge_width 0.5)
				(island_removal_mode 0)
			)
			(polygon
				(pts
					(arc
						(start 385.963668 -112.573562)
						(mid 385.945355 -112.65535)
						(end 385.963668 -112.737138)
					)
					(arc
						(start 385.891786 -112.80902)
						(mid 385.847637 -112.65535)
						(end 385.891786 -112.50168)
					)
				)
			)
		)
		(zone
			(layer "F.Cu")
			(hatch none 0.5)
			(connect_pads
				(clearance 0)
			)
			(min_thickness 0.25)
			(keepout
				(tracks not_allowed)
				(vias allowed)
				(pads allowed)
				(copperpour not_allowed)
				(footprints allowed)
			)
			(placement
				(enabled no)
				(sheetname "")
			)
			(fill
				(thermal_gap 0.5)
				(thermal_bridge_width 0.5)
				(island_removal_mode 0)
			)
			(polygon
				(pts
					(arc
						(start 385.963668 -111.773462)
						(mid 385.945355 -111.85525)
						(end 385.963668 -111.937038)
					)
					(arc
						(start 385.891786 -112.00892)
						(mid 385.847637 -111.85525)
						(end 385.891786 -111.70158)
					)
				)
			)
		)
		(zone
			(layer "F.Cu")
			(hatch none 0.5)
			(connect_pads
				(clearance 0)
			)
			(min_thickness 0.25)
			(keepout
				(tracks not_allowed)
				(vias allowed)
				(pads allowed)
				(copperpour not_allowed)
				(footprints allowed)
			)
			(placement
				(enabled no)
				(sheetname "")
			)
			(fill
				(thermal_gap 0.5)
				(thermal_bridge_width 0.5)
				(island_removal_mode 0)
			)
			(polygon
				(pts
					(arc
						(start 385.963668 -110.973362)
						(mid 385.945355 -111.05515)
						(end 385.963668 -111.136938)
					)
					(arc
						(start 385.891786 -111.20882)
						(mid 385.847637 -111.05515)
						(end 385.891786 -110.90148)
					)
				)
			)
		)
		(zone
			(layer "F.Cu")
			(hatch none 0.5)
			(connect_pads
				(clearance 0)
			)
			(min_thickness 0.25)
			(keepout
				(tracks not_allowed)
				(vias allowed)
				(pads allowed)
				(copperpour not_allowed)
				(footprints allowed)
			)
			(placement
				(enabled no)
				(sheetname "")
			)
			(fill
				(thermal_gap 0.5)
				(thermal_bridge_width 0.5)
				(island_removal_mode 0)
			)
			(polygon
				(pts
					(arc
						(start 385.963668 -110.173262)
						(mid 385.945355 -110.25505)
						(end 385.963668 -110.336838)
					)
					(arc
						(start 385.891786 -110.40872)
						(mid 385.847637 -110.25505)
						(end 385.891786 -110.10138)
					)
				)
			)
		)
		(zone
			(layer "F.Cu")
			(hatch none 0.5)
			(connect_pads
				(clearance 0)
			)
			(min_thickness 0.25)
			(keepout
				(tracks not_allowed)
				(vias allowed)
				(pads allowed)
				(copperpour not_allowed)
				(footprints allowed)
			)
			(placement
				(enabled no)
				(sheetname "")
			)
			(fill
				(thermal_gap 0.5)
				(thermal_bridge_width 0.5)
				(island_removal_mode 0)
			)
			(polygon
				(pts
					(arc
						(start 385.963668 -109.373162)
						(mid 385.945355 -109.45495)
						(end 385.963668 -109.536738)
					)
					(arc
						(start 385.891786 -109.60862)
						(mid 385.847637 -109.45495)
						(end 385.891786 -109.30128)
					)
				)
			)
		)
		(zone
			(layer "F.Cu")
			(hatch none 0.5)
			(connect_pads
				(clearance 0)
			)
			(min_thickness 0.25)
			(keepout
				(tracks not_allowed)
				(vias allowed)
				(pads allowed)
				(copperpour not_allowed)
				(footprints allowed)
			)
			(placement
				(enabled no)
				(sheetname "")
			)
			(fill
				(thermal_gap 0.5)
				(thermal_bridge_width 0.5)
				(island_removal_mode 0)
			)
			(polygon
				(pts
					(arc
						(start 385.963668 -108.573062)
						(mid 385.945355 -108.65485)
						(end 385.963668 -108.736638)
					)
					(arc
						(start 385.891786 -108.80852)
						(mid 385.847637 -108.65485)
						(end 385.891786 -108.50118)
					)
				)
			)
		)
		(zone
			(layer "F.Cu")
			(hatch none 0.5)
			(connect_pads
				(clearance 0)
			)
			(min_thickness 0.25)
			(keepout
				(tracks not_allowed)
				(vias allowed)
				(pads allowed)
				(copperpour not_allowed)
				(footprints allowed)
			)
			(placement
				(enabled no)
				(sheetname "")
			)
			(fill
				(thermal_gap 0.5)
				(thermal_bridge_width 0.5)
				(island_removal_mode 0)
			)
			(polygon
				(pts
					(arc
						(start 385.963668 -107.772962)
						(mid 385.945355 -107.85475)
						(end 385.963668 -107.936538)
					)
					(arc
						(start 385.891786 -108.00842)
						(mid 385.847637 -107.85475)
						(end 385.891786 -107.70108)
					)
				)
			)
		)
		(zone
			(layer "F.Cu")
			(hatch none 0.5)
			(connect_pads
				(clearance 0)
			)
			(min_thickness 0.25)
			(keepout
				(tracks not_allowed)
				(vias allowed)
				(pads allowed)
				(copperpour not_allowed)
				(footprints allowed)
			)
			(placement
				(enabled no)
				(sheetname "")
			)
			(fill
				(thermal_gap 0.5)
				(thermal_bridge_width 0.5)
				(island_removal_mode 0)
			)
			(polygon
				(pts
					(arc
						(start 385.963668 -105.372662)
						(mid 385.945355 -105.45445)
						(end 385.963668 -105.536238)
					)
					(arc
						(start 385.891786 -105.60812)
						(mid 385.847637 -105.45445)
						(end 385.891786 -105.30078)
					)
				)
			)
		)
		(zone
			(layer "F.Cu")
			(hatch none 0.5)
			(connect_pads
				(clearance 0)
			)
			(min_thickness 0.25)
			(keepout
				(tracks not_allowed)
				(vias allowed)
				(pads allowed)
				(copperpour not_allowed)
				(footprints allowed)
			)
			(placement
				(enabled no)
				(sheetname "")
			)
			(fill
				(thermal_gap 0.5)
				(thermal_bridge_width 0.5)
				(island_removal_mode 0)
			)
			(polygon
				(pts
					(arc
						(start 386.055362 -112.828832)
						(mid 386.13715 -112.847145)
						(end 386.218938 -112.828832)
					)
					(arc
						(start 386.29082 -112.900714)
						(mid 386.13715 -112.944863)
						(end 385.98348 -112.900714)
					)
				)
			)
		)
		(zone
			(layer "F.Cu")
			(hatch none 0.5)
			(connect_pads
				(clearance 0)
			)
			(min_thickness 0.25)
			(keepout
				(tracks not_allowed)
				(vias allowed)
				(pads allowed)
				(copperpour not_allowed)
				(footprints allowed)
			)
			(placement
				(enabled no)
				(sheetname "")
			)
			(fill
				(thermal_gap 0.5)
				(thermal_bridge_width 0.5)
				(island_removal_mode 0)
			)
			(polygon
				(pts
					(arc
						(start 386.055362 -112.028732)
						(mid 386.13715 -112.047045)
						(end 386.218938 -112.028732)
					)
					(arc
						(start 386.29082 -112.100614)
						(mid 386.13715 -112.144763)
						(end 385.98348 -112.100614)
					)
				)
			)
		)
		(zone
			(layer "F.Cu")
			(hatch none 0.5)
			(connect_pads
				(clearance 0)
			)
			(min_thickness 0.25)
			(keepout
				(tracks not_allowed)
				(vias allowed)
				(pads allowed)
				(copperpour not_allowed)
				(footprints allowed)
			)
			(placement
				(enabled no)
				(sheetname "")
			)
			(fill
				(thermal_gap 0.5)
				(thermal_bridge_width 0.5)
				(island_removal_mode 0)
			)
			(polygon
				(pts
					(arc
						(start 386.055362 -111.228632)
						(mid 386.13715 -111.246945)
						(end 386.218938 -111.228632)
					)
					(arc
						(start 386.29082 -111.300514)
						(mid 386.13715 -111.344663)
						(end 385.98348 -111.300514)
					)
				)
			)
		)
		(zone
			(layer "F.Cu")
			(hatch none 0.5)
			(connect_pads
				(clearance 0)
			)
			(min_thickness 0.25)
			(keepout
				(tracks not_allowed)
				(vias allowed)
				(pads allowed)
				(copperpour not_allowed)
				(footprints allowed)
			)
			(placement
				(enabled no)
				(sheetname "")
			)
			(fill
				(thermal_gap 0.5)
				(thermal_bridge_width 0.5)
				(island_removal_mode 0)
			)
			(polygon
				(pts
					(arc
						(start 386.055362 -110.428532)
						(mid 386.13715 -110.446845)
						(end 386.218938 -110.428532)
					)
					(arc
						(start 386.29082 -110.500414)
						(mid 386.13715 -110.544563)
						(end 385.98348 -110.500414)
					)
				)
			)
		)
		(zone
			(layer "F.Cu")
			(hatch none 0.5)
			(connect_pads
				(clearance 0)
			)
			(min_thickness 0.25)
			(keepout
				(tracks not_allowed)
				(vias allowed)
				(pads allowed)
				(copperpour not_allowed)
				(footprints allowed)
			)
			(placement
				(enabled no)
				(sheetname "")
			)
			(fill
				(thermal_gap 0.5)
				(thermal_bridge_width 0.5)
				(island_removal_mode 0)
			)
			(polygon
				(pts
					(arc
						(start 386.055362 -109.628432)
						(mid 386.13715 -109.646745)
						(end 386.218938 -109.628432)
					)
					(arc
						(start 386.29082 -109.700314)
						(mid 386.13715 -109.744463)
						(end 385.98348 -109.700314)
					)
				)
			)
		)
		(zone
			(layer "F.Cu")
			(hatch none 0.5)
			(connect_pads
				(clearance 0)
			)
			(min_thickness 0.25)
			(keepout
				(tracks not_allowed)
				(vias allowed)
				(pads allowed)
				(copperpour not_allowed)
				(footprints allowed)
			)
			(placement
				(enabled no)
				(sheetname "")
			)
			(fill
				(thermal_gap 0.5)
				(thermal_bridge_width 0.5)
				(island_removal_mode 0)
			)
			(polygon
				(pts
					(arc
						(start 386.055362 -108.828332)
						(mid 386.13715 -108.846645)
						(end 386.218938 -108.828332)
					)
					(arc
						(start 386.29082 -108.900214)
						(mid 386.13715 -108.944363)
						(end 385.98348 -108.900214)
					)
				)
			)
		)
		(zone
			(layer "F.Cu")
			(hatch none 0.5)
			(connect_pads
				(clearance 0)
			)
			(min_thickness 0.25)
			(keepout
				(tracks not_allowed)
				(vias allowed)
				(pads allowed)
				(copperpour not_allowed)
				(footprints allowed)
			)
			(placement
				(enabled no)
				(sheetname "")
			)
			(fill
				(thermal_gap 0.5)
				(thermal_bridge_width 0.5)
				(island_removal_mode 0)
			)
			(polygon
				(pts
					(arc
						(start 386.055362 -108.028232)
						(mid 386.13715 -108.046545)
						(end 386.218938 -108.028232)
					)
					(arc
						(start 386.29082 -108.100114)
						(mid 386.13715 -108.144263)
						(end 385.98348 -108.100114)
					)
				)
			)
		)
		(zone
			(layer "F.Cu")
			(hatch none 0.5)
			(connect_pads
				(clearance 0)
			)
			(min_thickness 0.25)
			(keepout
				(tracks not_allowed)
				(vias allowed)
				(pads allowed)
				(copperpour not_allowed)
				(footprints allowed)
			)
			(placement
				(enabled no)
				(sheetname "")
			)
			(fill
				(thermal_gap 0.5)
				(thermal_bridge_width 0.5)
				(island_removal_mode 0)
			)
			(polygon
				(pts
					(arc
						(start 386.055362 -105.627932)
						(mid 386.13715 -105.646245)
						(end 386.218938 -105.627932)
					)
					(arc
						(start 386.29082 -105.699814)
						(mid 386.13715 -105.743963)
						(end 385.98348 -105.699814)
					)
				)
			)
		)
		(zone
			(layer "F.Cu")
			(hatch none 0.5)
			(connect_pads
				(clearance 0)
			)
			(min_thickness 0.25)
			(keepout
				(tracks not_allowed)
				(vias allowed)
				(pads allowed)
				(copperpour not_allowed)
				(footprints allowed)
			)
			(placement
				(enabled no)
				(sheetname "")
			)
			(fill
				(thermal_gap 0.5)
				(thermal_bridge_width 0.5)
				(island_removal_mode 0)
			)
			(polygon
				(pts
					(arc
						(start 386.218938 -112.481868)
						(mid 386.13715 -112.463555)
						(end 386.055362 -112.481868)
					)
					(arc
						(start 385.98348 -112.409986)
						(mid 386.13715 -112.365837)
						(end 386.29082 -112.409986)
					)
				)
			)
		)
		(zone
			(layer "F.Cu")
			(hatch none 0.5)
			(connect_pads
				(clearance 0)
			)
			(min_thickness 0.25)
			(keepout
				(tracks not_allowed)
				(vias allowed)
				(pads allowed)
				(copperpour not_allowed)
				(footprints allowed)
			)
			(placement
				(enabled no)
				(sheetname "")
			)
			(fill
				(thermal_gap 0.5)
				(thermal_bridge_width 0.5)
				(island_removal_mode 0)
			)
			(polygon
				(pts
					(arc
						(start 386.218938 -111.681768)
						(mid 386.13715 -111.663455)
						(end 386.055362 -111.681768)
					)
					(arc
						(start 385.98348 -111.609886)
						(mid 386.13715 -111.565737)
						(end 386.29082 -111.609886)
					)
				)
			)
		)
		(zone
			(layer "F.Cu")
			(hatch none 0.5)
			(connect_pads
				(clearance 0)
			)
			(min_thickness 0.25)
			(keepout
				(tracks not_allowed)
				(vias allowed)
				(pads allowed)
				(copperpour not_allowed)
				(footprints allowed)
			)
			(placement
				(enabled no)
				(sheetname "")
			)
			(fill
				(thermal_gap 0.5)
				(thermal_bridge_width 0.5)
				(island_removal_mode 0)
			)
			(polygon
				(pts
					(arc
						(start 386.218938 -110.881668)
						(mid 386.13715 -110.863355)
						(end 386.055362 -110.881668)
					)
					(arc
						(start 385.98348 -110.809786)
						(mid 386.13715 -110.765637)
						(end 386.29082 -110.809786)
					)
				)
			)
		)
		(zone
			(layer "F.Cu")
			(hatch none 0.5)
			(connect_pads
				(clearance 0)
			)
			(min_thickness 0.25)
			(keepout
				(tracks not_allowed)
				(vias allowed)
				(pads allowed)
				(copperpour not_allowed)
				(footprints allowed)
			)
			(placement
				(enabled no)
				(sheetname "")
			)
			(fill
				(thermal_gap 0.5)
				(thermal_bridge_width 0.5)
				(island_removal_mode 0)
			)
			(polygon
				(pts
					(arc
						(start 386.218938 -110.081568)
						(mid 386.13715 -110.063255)
						(end 386.055362 -110.081568)
					)
					(arc
						(start 385.98348 -110.009686)
						(mid 386.13715 -109.965537)
						(end 386.29082 -110.009686)
					)
				)
			)
		)
		(zone
			(layer "F.Cu")
			(hatch none 0.5)
			(connect_pads
				(clearance 0)
			)
			(min_thickness 0.25)
			(keepout
				(tracks not_allowed)
				(vias allowed)
				(pads allowed)
				(copperpour not_allowed)
				(footprints allowed)
			)
			(placement
				(enabled no)
				(sheetname "")
			)
			(fill
				(thermal_gap 0.5)
				(thermal_bridge_width 0.5)
				(island_removal_mode 0)
			)
			(polygon
				(pts
					(arc
						(start 386.218938 -109.281468)
						(mid 386.13715 -109.263155)
						(end 386.055362 -109.281468)
					)
					(arc
						(start 385.98348 -109.209586)
						(mid 386.13715 -109.165437)
						(end 386.29082 -109.209586)
					)
				)
			)
		)
		(zone
			(layer "F.Cu")
			(hatch none 0.5)
			(connect_pads
				(clearance 0)
			)
			(min_thickness 0.25)
			(keepout
				(tracks not_allowed)
				(vias allowed)
				(pads allowed)
				(copperpour not_allowed)
				(footprints allowed)
			)
			(placement
				(enabled no)
				(sheetname "")
			)
			(fill
				(thermal_gap 0.5)
				(thermal_bridge_width 0.5)
				(island_removal_mode 0)
			)
			(polygon
				(pts
					(arc
						(start 386.218938 -108.481368)
						(mid 386.13715 -108.463055)
						(end 386.055362 -108.481368)
					)
					(arc
						(start 385.98348 -108.409486)
						(mid 386.13715 -108.365337)
						(end 386.29082 -108.409486)
					)
				)
			)
		)
		(zone
			(layer "F.Cu")
			(hatch none 0.5)
			(connect_pads
				(clearance 0)
			)
			(min_thickness 0.25)
			(keepout
				(tracks not_allowed)
				(vias allowed)
				(pads allowed)
				(copperpour not_allowed)
				(footprints allowed)
			)
			(placement
				(enabled no)
				(sheetname "")
			)
			(fill
				(thermal_gap 0.5)
				(thermal_bridge_width 0.5)
				(island_removal_mode 0)
			)
			(polygon
				(pts
					(arc
						(start 386.218938 -107.681268)
						(mid 386.13715 -107.662955)
						(end 386.055362 -107.681268)
					)
					(arc
						(start 385.98348 -107.609386)
						(mid 386.13715 -107.565237)
						(end 386.29082 -107.609386)
					)
				)
			)
		)
		(zone
			(layer "F.Cu")
			(hatch none 0.5)
			(connect_pads
				(clearance 0)
			)
			(min_thickness 0.25)
			(keepout
				(tracks not_allowed)
				(vias allowed)
				(pads allowed)
				(copperpour not_allowed)
				(footprints allowed)
			)
			(placement
				(enabled no)
				(sheetname "")
			)
			(fill
				(thermal_gap 0.5)
				(thermal_bridge_width 0.5)
				(island_removal_mode 0)
			)
			(polygon
				(pts
					(arc
						(start 386.218938 -105.280968)
						(mid 386.13715 -105.262655)
						(end 386.055362 -105.280968)
					)
					(arc
						(start 385.98348 -105.209086)
						(mid 386.13715 -105.164937)
						(end 386.29082 -105.209086)
					)
				)
			)
		)
		(zone
			(layer "F.Cu")
			(hatch none 0.5)
			(connect_pads
				(clearance 0)
			)
			(min_thickness 0.25)
			(keepout
				(tracks not_allowed)
				(vias allowed)
				(pads allowed)
				(copperpour not_allowed)
				(footprints allowed)
			)
			(placement
				(enabled no)
				(sheetname "")
			)
			(fill
				(thermal_gap 0.5)
				(thermal_bridge_width 0.5)
				(island_removal_mode 0)
			)
			(polygon
				(pts
					(arc
						(start 386.310632 -112.737138)
						(mid 386.328945 -112.65535)
						(end 386.310632 -112.573562)
					)
					(arc
						(start 386.382514 -112.50168)
						(mid 386.426663 -112.65535)
						(end 386.382514 -112.80902)
					)
				)
			)
		)
		(zone
			(layer "F.Cu")
			(hatch none 0.5)
			(connect_pads
				(clearance 0)
			)
			(min_thickness 0.25)
			(keepout
				(tracks not_allowed)
				(vias allowed)
				(pads allowed)
				(copperpour not_allowed)
				(footprints allowed)
			)
			(placement
				(enabled no)
				(sheetname "")
			)
			(fill
				(thermal_gap 0.5)
				(thermal_bridge_width 0.5)
				(island_removal_mode 0)
			)
			(polygon
				(pts
					(arc
						(start 386.310632 -111.937038)
						(mid 386.328945 -111.85525)
						(end 386.310632 -111.773462)
					)
					(arc
						(start 386.382514 -111.70158)
						(mid 386.426663 -111.85525)
						(end 386.382514 -112.00892)
					)
				)
			)
		)
		(zone
			(layer "F.Cu")
			(hatch none 0.5)
			(connect_pads
				(clearance 0)
			)
			(min_thickness 0.25)
			(keepout
				(tracks not_allowed)
				(vias allowed)
				(pads allowed)
				(copperpour not_allowed)
				(footprints allowed)
			)
			(placement
				(enabled no)
				(sheetname "")
			)
			(fill
				(thermal_gap 0.5)
				(thermal_bridge_width 0.5)
				(island_removal_mode 0)
			)
			(polygon
				(pts
					(arc
						(start 386.310632 -111.136938)
						(mid 386.328945 -111.05515)
						(end 386.310632 -110.973362)
					)
					(arc
						(start 386.382514 -110.90148)
						(mid 386.426663 -111.05515)
						(end 386.382514 -111.20882)
					)
				)
			)
		)
		(zone
			(layer "F.Cu")
			(hatch none 0.5)
			(connect_pads
				(clearance 0)
			)
			(min_thickness 0.25)
			(keepout
				(tracks not_allowed)
				(vias allowed)
				(pads allowed)
				(copperpour not_allowed)
				(footprints allowed)
			)
			(placement
				(enabled no)
				(sheetname "")
			)
			(fill
				(thermal_gap 0.5)
				(thermal_bridge_width 0.5)
				(island_removal_mode 0)
			)
			(polygon
				(pts
					(arc
						(start 386.310632 -110.336838)
						(mid 386.328945 -110.25505)
						(end 386.310632 -110.173262)
					)
					(arc
						(start 386.382514 -110.10138)
						(mid 386.426663 -110.25505)
						(end 386.382514 -110.40872)
					)
				)
			)
		)
		(zone
			(layer "F.Cu")
			(hatch none 0.5)
			(connect_pads
				(clearance 0)
			)
			(min_thickness 0.25)
			(keepout
				(tracks not_allowed)
				(vias allowed)
				(pads allowed)
				(copperpour not_allowed)
				(footprints allowed)
			)
			(placement
				(enabled no)
				(sheetname "")
			)
			(fill
				(thermal_gap 0.5)
				(thermal_bridge_width 0.5)
				(island_removal_mode 0)
			)
			(polygon
				(pts
					(arc
						(start 386.310632 -109.536738)
						(mid 386.328945 -109.45495)
						(end 386.310632 -109.373162)
					)
					(arc
						(start 386.382514 -109.30128)
						(mid 386.426663 -109.45495)
						(end 386.382514 -109.60862)
					)
				)
			)
		)
		(zone
			(layer "F.Cu")
			(hatch none 0.5)
			(connect_pads
				(clearance 0)
			)
			(min_thickness 0.25)
			(keepout
				(tracks not_allowed)
				(vias allowed)
				(pads allowed)
				(copperpour not_allowed)
				(footprints allowed)
			)
			(placement
				(enabled no)
				(sheetname "")
			)
			(fill
				(thermal_gap 0.5)
				(thermal_bridge_width 0.5)
				(island_removal_mode 0)
			)
			(polygon
				(pts
					(arc
						(start 386.310632 -108.736638)
						(mid 386.328945 -108.65485)
						(end 386.310632 -108.573062)
					)
					(arc
						(start 386.382514 -108.50118)
						(mid 386.426663 -108.65485)
						(end 386.382514 -108.80852)
					)
				)
			)
		)
		(zone
			(layer "F.Cu")
			(hatch none 0.5)
			(connect_pads
				(clearance 0)
			)
			(min_thickness 0.25)
			(keepout
				(tracks not_allowed)
				(vias allowed)
				(pads allowed)
				(copperpour not_allowed)
				(footprints allowed)
			)
			(placement
				(enabled no)
				(sheetname "")
			)
			(fill
				(thermal_gap 0.5)
				(thermal_bridge_width 0.5)
				(island_removal_mode 0)
			)
			(polygon
				(pts
					(arc
						(start 386.310632 -107.936538)
						(mid 386.328945 -107.85475)
						(end 386.310632 -107.772962)
					)
					(arc
						(start 386.382514 -107.70108)
						(mid 386.426663 -107.85475)
						(end 386.382514 -108.00842)
					)
				)
			)
		)
		(zone
			(layer "F.Cu")
			(hatch none 0.5)
			(connect_pads
				(clearance 0)
			)
			(min_thickness 0.25)
			(keepout
				(tracks not_allowed)
				(vias allowed)
				(pads allowed)
				(copperpour not_allowed)
				(footprints allowed)
			)
			(placement
				(enabled no)
				(sheetname "")
			)
			(fill
				(thermal_gap 0.5)
				(thermal_bridge_width 0.5)
				(island_removal_mode 0)
			)
			(polygon
				(pts
					(arc
						(start 386.310632 -105.536238)
						(mid 386.328945 -105.45445)
						(end 386.310632 -105.372662)
					)
					(arc
						(start 386.382514 -105.30078)
						(mid 386.426663 -105.45445)
						(end 386.382514 -105.60812)
					)
				)
			)
		)
		(zone
			(layer "F.Cu")
			(hatch none 0.5)
			(connect_pads
				(clearance 0)
			)
			(min_thickness 0.25)
			(keepout
				(tracks not_allowed)
				(vias allowed)
				(pads allowed)
				(copperpour not_allowed)
				(footprints allowed)
			)
			(placement
				(enabled no)
				(sheetname "")
			)
			(fill
				(thermal_gap 0.5)
				(thermal_bridge_width 0.5)
				(island_removal_mode 0)
			)
			(polygon
				(pts
					(arc
						(start 386.763768 -112.573562)
						(mid 386.745455 -112.65535)
						(end 386.763768 -112.737138)
					)
					(arc
						(start 386.691886 -112.80902)
						(mid 386.647737 -112.65535)
						(end 386.691886 -112.50168)
					)
				)
			)
		)
		(zone
			(layer "F.Cu")
			(hatch none 0.5)
			(connect_pads
				(clearance 0)
			)
			(min_thickness 0.25)
			(keepout
				(tracks not_allowed)
				(vias allowed)
				(pads allowed)
				(copperpour not_allowed)
				(footprints allowed)
			)
			(placement
				(enabled no)
				(sheetname "")
			)
			(fill
				(thermal_gap 0.5)
				(thermal_bridge_width 0.5)
				(island_removal_mode 0)
			)
			(polygon
				(pts
					(arc
						(start 386.763768 -111.773462)
						(mid 386.745455 -111.85525)
						(end 386.763768 -111.937038)
					)
					(arc
						(start 386.691886 -112.00892)
						(mid 386.647737 -111.85525)
						(end 386.691886 -111.70158)
					)
				)
			)
		)
		(zone
			(layer "F.Cu")
			(hatch none 0.5)
			(connect_pads
				(clearance 0)
			)
			(min_thickness 0.25)
			(keepout
				(tracks not_allowed)
				(vias allowed)
				(pads allowed)
				(copperpour not_allowed)
				(footprints allowed)
			)
			(placement
				(enabled no)
				(sheetname "")
			)
			(fill
				(thermal_gap 0.5)
				(thermal_bridge_width 0.5)
				(island_removal_mode 0)
			)
			(polygon
				(pts
					(arc
						(start 386.763768 -110.973362)
						(mid 386.745455 -111.05515)
						(end 386.763768 -111.136938)
					)
					(arc
						(start 386.691886 -111.20882)
						(mid 386.647737 -111.05515)
						(end 386.691886 -110.90148)
					)
				)
			)
		)
		(zone
			(layer "F.Cu")
			(hatch none 0.5)
			(connect_pads
				(clearance 0)
			)
			(min_thickness 0.25)
			(keepout
				(tracks not_allowed)
				(vias allowed)
				(pads allowed)
				(copperpour not_allowed)
				(footprints allowed)
			)
			(placement
				(enabled no)
				(sheetname "")
			)
			(fill
				(thermal_gap 0.5)
				(thermal_bridge_width 0.5)
				(island_removal_mode 0)
			)
			(polygon
				(pts
					(arc
						(start 386.763768 -110.173262)
						(mid 386.745455 -110.25505)
						(end 386.763768 -110.336838)
					)
					(arc
						(start 386.691886 -110.40872)
						(mid 386.647737 -110.25505)
						(end 386.691886 -110.10138)
					)
				)
			)
		)
		(zone
			(layer "F.Cu")
			(hatch none 0.5)
			(connect_pads
				(clearance 0)
			)
			(min_thickness 0.25)
			(keepout
				(tracks not_allowed)
				(vias allowed)
				(pads allowed)
				(copperpour not_allowed)
				(footprints allowed)
			)
			(placement
				(enabled no)
				(sheetname "")
			)
			(fill
				(thermal_gap 0.5)
				(thermal_bridge_width 0.5)
				(island_removal_mode 0)
			)
			(polygon
				(pts
					(arc
						(start 386.763768 -109.373162)
						(mid 386.745455 -109.45495)
						(end 386.763768 -109.536738)
					)
					(arc
						(start 386.691886 -109.60862)
						(mid 386.647737 -109.45495)
						(end 386.691886 -109.30128)
					)
				)
			)
		)
		(zone
			(layer "F.Cu")
			(hatch none 0.5)
			(connect_pads
				(clearance 0)
			)
			(min_thickness 0.25)
			(keepout
				(tracks not_allowed)
				(vias allowed)
				(pads allowed)
				(copperpour not_allowed)
				(footprints allowed)
			)
			(placement
				(enabled no)
				(sheetname "")
			)
			(fill
				(thermal_gap 0.5)
				(thermal_bridge_width 0.5)
				(island_removal_mode 0)
			)
			(polygon
				(pts
					(arc
						(start 386.763768 -108.573062)
						(mid 386.745455 -108.65485)
						(end 386.763768 -108.736638)
					)
					(arc
						(start 386.691886 -108.80852)
						(mid 386.647737 -108.65485)
						(end 386.691886 -108.50118)
					)
				)
			)
		)
		(zone
			(layer "F.Cu")
			(hatch none 0.5)
			(connect_pads
				(clearance 0)
			)
			(min_thickness 0.25)
			(keepout
				(tracks not_allowed)
				(vias allowed)
				(pads allowed)
				(copperpour not_allowed)
				(footprints allowed)
			)
			(placement
				(enabled no)
				(sheetname "")
			)
			(fill
				(thermal_gap 0.5)
				(thermal_bridge_width 0.5)
				(island_removal_mode 0)
			)
			(polygon
				(pts
					(arc
						(start 386.763768 -104.572562)
						(mid 386.745455 -104.65435)
						(end 386.763768 -104.736138)
					)
					(arc
						(start 386.691886 -104.80802)
						(mid 386.647737 -104.65435)
						(end 386.691886 -104.50068)
					)
				)
			)
		)
		(zone
			(layer "F.Cu")
			(hatch none 0.5)
			(connect_pads
				(clearance 0)
			)
			(min_thickness 0.25)
			(keepout
				(tracks not_allowed)
				(vias allowed)
				(pads allowed)
				(copperpour not_allowed)
				(footprints allowed)
			)
			(placement
				(enabled no)
				(sheetname "")
			)
			(fill
				(thermal_gap 0.5)
				(thermal_bridge_width 0.5)
				(island_removal_mode 0)
			)
			(polygon
				(pts
					(arc
						(start 386.855462 -112.828832)
						(mid 386.93725 -112.847145)
						(end 387.019038 -112.828832)
					)
					(arc
						(start 387.09092 -112.900714)
						(mid 386.93725 -112.944863)
						(end 386.78358 -112.900714)
					)
				)
			)
		)
		(zone
			(layer "F.Cu")
			(hatch none 0.5)
			(connect_pads
				(clearance 0)
			)
			(min_thickness 0.25)
			(keepout
				(tracks not_allowed)
				(vias allowed)
				(pads allowed)
				(copperpour not_allowed)
				(footprints allowed)
			)
			(placement
				(enabled no)
				(sheetname "")
			)
			(fill
				(thermal_gap 0.5)
				(thermal_bridge_width 0.5)
				(island_removal_mode 0)
			)
			(polygon
				(pts
					(arc
						(start 386.855462 -112.028732)
						(mid 386.93725 -112.047045)
						(end 387.019038 -112.028732)
					)
					(arc
						(start 387.09092 -112.100614)
						(mid 386.93725 -112.144763)
						(end 386.78358 -112.100614)
					)
				)
			)
		)
		(zone
			(layer "F.Cu")
			(hatch none 0.5)
			(connect_pads
				(clearance 0)
			)
			(min_thickness 0.25)
			(keepout
				(tracks not_allowed)
				(vias allowed)
				(pads allowed)
				(copperpour not_allowed)
				(footprints allowed)
			)
			(placement
				(enabled no)
				(sheetname "")
			)
			(fill
				(thermal_gap 0.5)
				(thermal_bridge_width 0.5)
				(island_removal_mode 0)
			)
			(polygon
				(pts
					(arc
						(start 386.855462 -111.228632)
						(mid 386.93725 -111.246945)
						(end 387.019038 -111.228632)
					)
					(arc
						(start 387.09092 -111.300514)
						(mid 386.93725 -111.344663)
						(end 386.78358 -111.300514)
					)
				)
			)
		)
		(zone
			(layer "F.Cu")
			(hatch none 0.5)
			(connect_pads
				(clearance 0)
			)
			(min_thickness 0.25)
			(keepout
				(tracks not_allowed)
				(vias allowed)
				(pads allowed)
				(copperpour not_allowed)
				(footprints allowed)
			)
			(placement
				(enabled no)
				(sheetname "")
			)
			(fill
				(thermal_gap 0.5)
				(thermal_bridge_width 0.5)
				(island_removal_mode 0)
			)
			(polygon
				(pts
					(arc
						(start 386.855462 -110.428532)
						(mid 386.93725 -110.446845)
						(end 387.019038 -110.428532)
					)
					(arc
						(start 387.09092 -110.500414)
						(mid 386.93725 -110.544563)
						(end 386.78358 -110.500414)
					)
				)
			)
		)
		(zone
			(layer "F.Cu")
			(hatch none 0.5)
			(connect_pads
				(clearance 0)
			)
			(min_thickness 0.25)
			(keepout
				(tracks not_allowed)
				(vias allowed)
				(pads allowed)
				(copperpour not_allowed)
				(footprints allowed)
			)
			(placement
				(enabled no)
				(sheetname "")
			)
			(fill
				(thermal_gap 0.5)
				(thermal_bridge_width 0.5)
				(island_removal_mode 0)
			)
			(polygon
				(pts
					(arc
						(start 386.855462 -109.628432)
						(mid 386.93725 -109.646745)
						(end 387.019038 -109.628432)
					)
					(arc
						(start 387.09092 -109.700314)
						(mid 386.93725 -109.744463)
						(end 386.78358 -109.700314)
					)
				)
			)
		)
		(zone
			(layer "F.Cu")
			(hatch none 0.5)
			(connect_pads
				(clearance 0)
			)
			(min_thickness 0.25)
			(keepout
				(tracks not_allowed)
				(vias allowed)
				(pads allowed)
				(copperpour not_allowed)
				(footprints allowed)
			)
			(placement
				(enabled no)
				(sheetname "")
			)
			(fill
				(thermal_gap 0.5)
				(thermal_bridge_width 0.5)
				(island_removal_mode 0)
			)
			(polygon
				(pts
					(arc
						(start 386.855462 -108.828332)
						(mid 386.93725 -108.846645)
						(end 387.019038 -108.828332)
					)
					(arc
						(start 387.09092 -108.900214)
						(mid 386.93725 -108.944363)
						(end 386.78358 -108.900214)
					)
				)
			)
		)
		(zone
			(layer "F.Cu")
			(hatch none 0.5)
			(connect_pads
				(clearance 0)
			)
			(min_thickness 0.25)
			(keepout
				(tracks not_allowed)
				(vias allowed)
				(pads allowed)
				(copperpour not_allowed)
				(footprints allowed)
			)
			(placement
				(enabled no)
				(sheetname "")
			)
			(fill
				(thermal_gap 0.5)
				(thermal_bridge_width 0.5)
				(island_removal_mode 0)
			)
			(polygon
				(pts
					(arc
						(start 386.855462 -104.827832)
						(mid 386.93725 -104.846145)
						(end 387.019038 -104.827832)
					)
					(arc
						(start 387.09092 -104.899714)
						(mid 386.93725 -104.943863)
						(end 386.78358 -104.899714)
					)
				)
			)
		)
		(zone
			(layer "F.Cu")
			(hatch none 0.5)
			(connect_pads
				(clearance 0)
			)
			(min_thickness 0.25)
			(keepout
				(tracks not_allowed)
				(vias allowed)
				(pads allowed)
				(copperpour not_allowed)
				(footprints allowed)
			)
			(placement
				(enabled no)
				(sheetname "")
			)
			(fill
				(thermal_gap 0.5)
				(thermal_bridge_width 0.5)
				(island_removal_mode 0)
			)
			(polygon
				(pts
					(arc
						(start 387.019038 -112.481868)
						(mid 386.93725 -112.463555)
						(end 386.855462 -112.481868)
					)
					(arc
						(start 386.78358 -112.409986)
						(mid 386.93725 -112.365837)
						(end 387.09092 -112.409986)
					)
				)
			)
		)
		(zone
			(layer "F.Cu")
			(hatch none 0.5)
			(connect_pads
				(clearance 0)
			)
			(min_thickness 0.25)
			(keepout
				(tracks not_allowed)
				(vias allowed)
				(pads allowed)
				(copperpour not_allowed)
				(footprints allowed)
			)
			(placement
				(enabled no)
				(sheetname "")
			)
			(fill
				(thermal_gap 0.5)
				(thermal_bridge_width 0.5)
				(island_removal_mode 0)
			)
			(polygon
				(pts
					(arc
						(start 387.019038 -111.681768)
						(mid 386.93725 -111.663455)
						(end 386.855462 -111.681768)
					)
					(arc
						(start 386.78358 -111.609886)
						(mid 386.93725 -111.565737)
						(end 387.09092 -111.609886)
					)
				)
			)
		)
		(zone
			(layer "F.Cu")
			(hatch none 0.5)
			(connect_pads
				(clearance 0)
			)
			(min_thickness 0.25)
			(keepout
				(tracks not_allowed)
				(vias allowed)
				(pads allowed)
				(copperpour not_allowed)
				(footprints allowed)
			)
			(placement
				(enabled no)
				(sheetname "")
			)
			(fill
				(thermal_gap 0.5)
				(thermal_bridge_width 0.5)
				(island_removal_mode 0)
			)
			(polygon
				(pts
					(arc
						(start 387.019038 -110.881668)
						(mid 386.93725 -110.863355)
						(end 386.855462 -110.881668)
					)
					(arc
						(start 386.78358 -110.809786)
						(mid 386.93725 -110.765637)
						(end 387.09092 -110.809786)
					)
				)
			)
		)
		(zone
			(layer "F.Cu")
			(hatch none 0.5)
			(connect_pads
				(clearance 0)
			)
			(min_thickness 0.25)
			(keepout
				(tracks not_allowed)
				(vias allowed)
				(pads allowed)
				(copperpour not_allowed)
				(footprints allowed)
			)
			(placement
				(enabled no)
				(sheetname "")
			)
			(fill
				(thermal_gap 0.5)
				(thermal_bridge_width 0.5)
				(island_removal_mode 0)
			)
			(polygon
				(pts
					(arc
						(start 387.019038 -110.081568)
						(mid 386.93725 -110.063255)
						(end 386.855462 -110.081568)
					)
					(arc
						(start 386.78358 -110.009686)
						(mid 386.93725 -109.965537)
						(end 387.09092 -110.009686)
					)
				)
			)
		)
		(zone
			(layer "F.Cu")
			(hatch none 0.5)
			(connect_pads
				(clearance 0)
			)
			(min_thickness 0.25)
			(keepout
				(tracks not_allowed)
				(vias allowed)
				(pads allowed)
				(copperpour not_allowed)
				(footprints allowed)
			)
			(placement
				(enabled no)
				(sheetname "")
			)
			(fill
				(thermal_gap 0.5)
				(thermal_bridge_width 0.5)
				(island_removal_mode 0)
			)
			(polygon
				(pts
					(arc
						(start 387.019038 -109.281468)
						(mid 386.93725 -109.263155)
						(end 386.855462 -109.281468)
					)
					(arc
						(start 386.78358 -109.209586)
						(mid 386.93725 -109.165437)
						(end 387.09092 -109.209586)
					)
				)
			)
		)
		(zone
			(layer "F.Cu")
			(hatch none 0.5)
			(connect_pads
				(clearance 0)
			)
			(min_thickness 0.25)
			(keepout
				(tracks not_allowed)
				(vias allowed)
				(pads allowed)
				(copperpour not_allowed)
				(footprints allowed)
			)
			(placement
				(enabled no)
				(sheetname "")
			)
			(fill
				(thermal_gap 0.5)
				(thermal_bridge_width 0.5)
				(island_removal_mode 0)
			)
			(polygon
				(pts
					(arc
						(start 387.019038 -108.481368)
						(mid 386.93725 -108.463055)
						(end 386.855462 -108.481368)
					)
					(arc
						(start 386.78358 -108.409486)
						(mid 386.93725 -108.365337)
						(end 387.09092 -108.409486)
					)
				)
			)
		)
		(zone
			(layer "F.Cu")
			(hatch none 0.5)
			(connect_pads
				(clearance 0)
			)
			(min_thickness 0.25)
			(keepout
				(tracks not_allowed)
				(vias allowed)
				(pads allowed)
				(copperpour not_allowed)
				(footprints allowed)
			)
			(placement
				(enabled no)
				(sheetname "")
			)
			(fill
				(thermal_gap 0.5)
				(thermal_bridge_width 0.5)
				(island_removal_mode 0)
			)
			(polygon
				(pts
					(arc
						(start 387.019038 -104.480868)
						(mid 386.93725 -104.462555)
						(end 386.855462 -104.480868)
					)
					(arc
						(start 386.78358 -104.408986)
						(mid 386.93725 -104.364837)
						(end 387.09092 -104.408986)
					)
				)
			)
		)
		(zone
			(layer "F.Cu")
			(hatch none 0.5)
			(connect_pads
				(clearance 0)
			)
			(min_thickness 0.25)
			(keepout
				(tracks not_allowed)
				(vias allowed)
				(pads allowed)
				(copperpour not_allowed)
				(footprints allowed)
			)
			(placement
				(enabled no)
				(sheetname "")
			)
			(fill
				(thermal_gap 0.5)
				(thermal_bridge_width 0.5)
				(island_removal_mode 0)
			)
			(polygon
				(pts
					(arc
						(start 387.110732 -112.737138)
						(mid 387.129045 -112.65535)
						(end 387.110732 -112.573562)
					)
					(arc
						(start 387.182614 -112.50168)
						(mid 387.226763 -112.65535)
						(end 387.182614 -112.80902)
					)
				)
			)
		)
		(zone
			(layer "F.Cu")
			(hatch none 0.5)
			(connect_pads
				(clearance 0)
			)
			(min_thickness 0.25)
			(keepout
				(tracks not_allowed)
				(vias allowed)
				(pads allowed)
				(copperpour not_allowed)
				(footprints allowed)
			)
			(placement
				(enabled no)
				(sheetname "")
			)
			(fill
				(thermal_gap 0.5)
				(thermal_bridge_width 0.5)
				(island_removal_mode 0)
			)
			(polygon
				(pts
					(arc
						(start 387.110732 -111.937038)
						(mid 387.129045 -111.85525)
						(end 387.110732 -111.773462)
					)
					(arc
						(start 387.182614 -111.70158)
						(mid 387.226763 -111.85525)
						(end 387.182614 -112.00892)
					)
				)
			)
		)
		(zone
			(layer "F.Cu")
			(hatch none 0.5)
			(connect_pads
				(clearance 0)
			)
			(min_thickness 0.25)
			(keepout
				(tracks not_allowed)
				(vias allowed)
				(pads allowed)
				(copperpour not_allowed)
				(footprints allowed)
			)
			(placement
				(enabled no)
				(sheetname "")
			)
			(fill
				(thermal_gap 0.5)
				(thermal_bridge_width 0.5)
				(island_removal_mode 0)
			)
			(polygon
				(pts
					(arc
						(start 387.110732 -111.136938)
						(mid 387.129045 -111.05515)
						(end 387.110732 -110.973362)
					)
					(arc
						(start 387.182614 -110.90148)
						(mid 387.226763 -111.05515)
						(end 387.182614 -111.20882)
					)
				)
			)
		)
		(zone
			(layer "F.Cu")
			(hatch none 0.5)
			(connect_pads
				(clearance 0)
			)
			(min_thickness 0.25)
			(keepout
				(tracks not_allowed)
				(vias allowed)
				(pads allowed)
				(copperpour not_allowed)
				(footprints allowed)
			)
			(placement
				(enabled no)
				(sheetname "")
			)
			(fill
				(thermal_gap 0.5)
				(thermal_bridge_width 0.5)
				(island_removal_mode 0)
			)
			(polygon
				(pts
					(arc
						(start 387.110732 -110.336838)
						(mid 387.129045 -110.25505)
						(end 387.110732 -110.173262)
					)
					(arc
						(start 387.182614 -110.10138)
						(mid 387.226763 -110.25505)
						(end 387.182614 -110.40872)
					)
				)
			)
		)
		(zone
			(layer "F.Cu")
			(hatch none 0.5)
			(connect_pads
				(clearance 0)
			)
			(min_thickness 0.25)
			(keepout
				(tracks not_allowed)
				(vias allowed)
				(pads allowed)
				(copperpour not_allowed)
				(footprints allowed)
			)
			(placement
				(enabled no)
				(sheetname "")
			)
			(fill
				(thermal_gap 0.5)
				(thermal_bridge_width 0.5)
				(island_removal_mode 0)
			)
			(polygon
				(pts
					(arc
						(start 387.110732 -109.536738)
						(mid 387.129045 -109.45495)
						(end 387.110732 -109.373162)
					)
					(arc
						(start 387.182614 -109.30128)
						(mid 387.226763 -109.45495)
						(end 387.182614 -109.60862)
					)
				)
			)
		)
		(zone
			(layer "F.Cu")
			(hatch none 0.5)
			(connect_pads
				(clearance 0)
			)
			(min_thickness 0.25)
			(keepout
				(tracks not_allowed)
				(vias allowed)
				(pads allowed)
				(copperpour not_allowed)
				(footprints allowed)
			)
			(placement
				(enabled no)
				(sheetname "")
			)
			(fill
				(thermal_gap 0.5)
				(thermal_bridge_width 0.5)
				(island_removal_mode 0)
			)
			(polygon
				(pts
					(arc
						(start 387.110732 -108.736638)
						(mid 387.129045 -108.65485)
						(end 387.110732 -108.573062)
					)
					(arc
						(start 387.182614 -108.50118)
						(mid 387.226763 -108.65485)
						(end 387.182614 -108.80852)
					)
				)
			)
		)
		(zone
			(layer "F.Cu")
			(hatch none 0.5)
			(connect_pads
				(clearance 0)
			)
			(min_thickness 0.25)
			(keepout
				(tracks not_allowed)
				(vias allowed)
				(pads allowed)
				(copperpour not_allowed)
				(footprints allowed)
			)
			(placement
				(enabled no)
				(sheetname "")
			)
			(fill
				(thermal_gap 0.5)
				(thermal_bridge_width 0.5)
				(island_removal_mode 0)
			)
			(polygon
				(pts
					(arc
						(start 387.110732 -104.736138)
						(mid 387.129045 -104.65435)
						(end 387.110732 -104.572562)
					)
					(arc
						(start 387.182614 -104.50068)
						(mid 387.226763 -104.65435)
						(end 387.182614 -104.80802)
					)
				)
			)
		)
		(zone
			(layer "F.Cu")
			(hatch none 0.5)
			(connect_pads
				(clearance 0)
			)
			(min_thickness 0.25)
			(keepout
				(tracks not_allowed)
				(vias allowed)
				(pads allowed)
				(copperpour not_allowed)
				(footprints allowed)
			)
			(placement
				(enabled no)
				(sheetname "")
			)
			(fill
				(thermal_gap 0.5)
				(thermal_bridge_width 0.5)
				(island_removal_mode 0)
			)
			(polygon
				(pts
					(arc
						(start 387.563868 -113.373662)
						(mid 387.545555 -113.45545)
						(end 387.563868 -113.537238)
					)
					(arc
						(start 387.491986 -113.60912)
						(mid 387.447837 -113.45545)
						(end 387.491986 -113.30178)
					)
				)
			)
		)
		(zone
			(layer "F.Cu")
			(hatch none 0.5)
			(connect_pads
				(clearance 0)
			)
			(min_thickness 0.25)
			(keepout
				(tracks not_allowed)
				(vias allowed)
				(pads allowed)
				(copperpour not_allowed)
				(footprints allowed)
			)
			(placement
				(enabled no)
				(sheetname "")
			)
			(fill
				(thermal_gap 0.5)
				(thermal_bridge_width 0.5)
				(island_removal_mode 0)
			)
			(polygon
				(pts
					(arc
						(start 387.563868 -112.573562)
						(mid 387.545555 -112.65535)
						(end 387.563868 -112.737138)
					)
					(arc
						(start 387.491986 -112.80902)
						(mid 387.447837 -112.65535)
						(end 387.491986 -112.50168)
					)
				)
			)
		)
		(zone
			(layer "F.Cu")
			(hatch none 0.5)
			(connect_pads
				(clearance 0)
			)
			(min_thickness 0.25)
			(keepout
				(tracks not_allowed)
				(vias allowed)
				(pads allowed)
				(copperpour not_allowed)
				(footprints allowed)
			)
			(placement
				(enabled no)
				(sheetname "")
			)
			(fill
				(thermal_gap 0.5)
				(thermal_bridge_width 0.5)
				(island_removal_mode 0)
			)
			(polygon
				(pts
					(arc
						(start 387.563868 -111.773462)
						(mid 387.545555 -111.85525)
						(end 387.563868 -111.937038)
					)
					(arc
						(start 387.491986 -112.00892)
						(mid 387.447837 -111.85525)
						(end 387.491986 -111.70158)
					)
				)
			)
		)
		(zone
			(layer "F.Cu")
			(hatch none 0.5)
			(connect_pads
				(clearance 0)
			)
			(min_thickness 0.25)
			(keepout
				(tracks not_allowed)
				(vias allowed)
				(pads allowed)
				(copperpour not_allowed)
				(footprints allowed)
			)
			(placement
				(enabled no)
				(sheetname "")
			)
			(fill
				(thermal_gap 0.5)
				(thermal_bridge_width 0.5)
				(island_removal_mode 0)
			)
			(polygon
				(pts
					(arc
						(start 387.563868 -110.973362)
						(mid 387.545555 -111.05515)
						(end 387.563868 -111.136938)
					)
					(arc
						(start 387.491986 -111.20882)
						(mid 387.447837 -111.05515)
						(end 387.491986 -110.90148)
					)
				)
			)
		)
		(zone
			(layer "F.Cu")
			(hatch none 0.5)
			(connect_pads
				(clearance 0)
			)
			(min_thickness 0.25)
			(keepout
				(tracks not_allowed)
				(vias allowed)
				(pads allowed)
				(copperpour not_allowed)
				(footprints allowed)
			)
			(placement
				(enabled no)
				(sheetname "")
			)
			(fill
				(thermal_gap 0.5)
				(thermal_bridge_width 0.5)
				(island_removal_mode 0)
			)
			(polygon
				(pts
					(arc
						(start 387.563868 -110.173262)
						(mid 387.545555 -110.25505)
						(end 387.563868 -110.336838)
					)
					(arc
						(start 387.491986 -110.40872)
						(mid 387.447837 -110.25505)
						(end 387.491986 -110.10138)
					)
				)
			)
		)
		(zone
			(layer "F.Cu")
			(hatch none 0.5)
			(connect_pads
				(clearance 0)
			)
			(min_thickness 0.25)
			(keepout
				(tracks not_allowed)
				(vias allowed)
				(pads allowed)
				(copperpour not_allowed)
				(footprints allowed)
			)
			(placement
				(enabled no)
				(sheetname "")
			)
			(fill
				(thermal_gap 0.5)
				(thermal_bridge_width 0.5)
				(island_removal_mode 0)
			)
			(polygon
				(pts
					(arc
						(start 387.563868 -108.573062)
						(mid 387.545555 -108.65485)
						(end 387.563868 -108.736638)
					)
					(arc
						(start 387.491986 -108.80852)
						(mid 387.447837 -108.65485)
						(end 387.491986 -108.50118)
					)
				)
			)
		)
		(zone
			(layer "F.Cu")
			(hatch none 0.5)
			(connect_pads
				(clearance 0)
			)
			(min_thickness 0.25)
			(keepout
				(tracks not_allowed)
				(vias allowed)
				(pads allowed)
				(copperpour not_allowed)
				(footprints allowed)
			)
			(placement
				(enabled no)
				(sheetname "")
			)
			(fill
				(thermal_gap 0.5)
				(thermal_bridge_width 0.5)
				(island_removal_mode 0)
			)
			(polygon
				(pts
					(arc
						(start 387.563868 -107.772962)
						(mid 387.545555 -107.85475)
						(end 387.563868 -107.936538)
					)
					(arc
						(start 387.491986 -108.00842)
						(mid 387.447837 -107.85475)
						(end 387.491986 -107.70108)
					)
				)
			)
		)
		(zone
			(layer "F.Cu")
			(hatch none 0.5)
			(connect_pads
				(clearance 0)
			)
			(min_thickness 0.25)
			(keepout
				(tracks not_allowed)
				(vias allowed)
				(pads allowed)
				(copperpour not_allowed)
				(footprints allowed)
			)
			(placement
				(enabled no)
				(sheetname "")
			)
			(fill
				(thermal_gap 0.5)
				(thermal_bridge_width 0.5)
				(island_removal_mode 0)
			)
			(polygon
				(pts
					(arc
						(start 387.563868 -106.172762)
						(mid 387.545555 -106.25455)
						(end 387.563868 -106.336338)
					)
					(arc
						(start 387.491986 -106.40822)
						(mid 387.447837 -106.25455)
						(end 387.491986 -106.10088)
					)
				)
			)
		)
		(zone
			(layer "F.Cu")
			(hatch none 0.5)
			(connect_pads
				(clearance 0)
			)
			(min_thickness 0.25)
			(keepout
				(tracks not_allowed)
				(vias allowed)
				(pads allowed)
				(copperpour not_allowed)
				(footprints allowed)
			)
			(placement
				(enabled no)
				(sheetname "")
			)
			(fill
				(thermal_gap 0.5)
				(thermal_bridge_width 0.5)
				(island_removal_mode 0)
			)
			(polygon
				(pts
					(arc
						(start 387.563868 -104.572562)
						(mid 387.545555 -104.65435)
						(end 387.563868 -104.736138)
					)
					(arc
						(start 387.491986 -104.80802)
						(mid 387.447837 -104.65435)
						(end 387.491986 -104.50068)
					)
				)
			)
		)
		(zone
			(layer "F.Cu")
			(hatch none 0.5)
			(connect_pads
				(clearance 0)
			)
			(min_thickness 0.25)
			(keepout
				(tracks not_allowed)
				(vias allowed)
				(pads allowed)
				(copperpour not_allowed)
				(footprints allowed)
			)
			(placement
				(enabled no)
				(sheetname "")
			)
			(fill
				(thermal_gap 0.5)
				(thermal_bridge_width 0.5)
				(island_removal_mode 0)
			)
			(polygon
				(pts
					(arc
						(start 387.655562 -113.628932)
						(mid 387.73735 -113.647245)
						(end 387.819138 -113.628932)
					)
					(arc
						(start 387.89102 -113.700814)
						(mid 387.73735 -113.744963)
						(end 387.58368 -113.700814)
					)
				)
			)
		)
		(zone
			(layer "F.Cu")
			(hatch none 0.5)
			(connect_pads
				(clearance 0)
			)
			(min_thickness 0.25)
			(keepout
				(tracks not_allowed)
				(vias allowed)
				(pads allowed)
				(copperpour not_allowed)
				(footprints allowed)
			)
			(placement
				(enabled no)
				(sheetname "")
			)
			(fill
				(thermal_gap 0.5)
				(thermal_bridge_width 0.5)
				(island_removal_mode 0)
			)
			(polygon
				(pts
					(arc
						(start 387.655562 -112.828832)
						(mid 387.73735 -112.847145)
						(end 387.819138 -112.828832)
					)
					(arc
						(start 387.89102 -112.900714)
						(mid 387.73735 -112.944863)
						(end 387.58368 -112.900714)
					)
				)
			)
		)
		(zone
			(layer "F.Cu")
			(hatch none 0.5)
			(connect_pads
				(clearance 0)
			)
			(min_thickness 0.25)
			(keepout
				(tracks not_allowed)
				(vias allowed)
				(pads allowed)
				(copperpour not_allowed)
				(footprints allowed)
			)
			(placement
				(enabled no)
				(sheetname "")
			)
			(fill
				(thermal_gap 0.5)
				(thermal_bridge_width 0.5)
				(island_removal_mode 0)
			)
			(polygon
				(pts
					(arc
						(start 387.655562 -112.028732)
						(mid 387.73735 -112.047045)
						(end 387.819138 -112.028732)
					)
					(arc
						(start 387.89102 -112.100614)
						(mid 387.73735 -112.144763)
						(end 387.58368 -112.100614)
					)
				)
			)
		)
		(zone
			(layer "F.Cu")
			(hatch none 0.5)
			(connect_pads
				(clearance 0)
			)
			(min_thickness 0.25)
			(keepout
				(tracks not_allowed)
				(vias allowed)
				(pads allowed)
				(copperpour not_allowed)
				(footprints allowed)
			)
			(placement
				(enabled no)
				(sheetname "")
			)
			(fill
				(thermal_gap 0.5)
				(thermal_bridge_width 0.5)
				(island_removal_mode 0)
			)
			(polygon
				(pts
					(arc
						(start 387.655562 -111.228632)
						(mid 387.73735 -111.246945)
						(end 387.819138 -111.228632)
					)
					(arc
						(start 387.89102 -111.300514)
						(mid 387.73735 -111.344663)
						(end 387.58368 -111.300514)
					)
				)
			)
		)
		(zone
			(layer "F.Cu")
			(hatch none 0.5)
			(connect_pads
				(clearance 0)
			)
			(min_thickness 0.25)
			(keepout
				(tracks not_allowed)
				(vias allowed)
				(pads allowed)
				(copperpour not_allowed)
				(footprints allowed)
			)
			(placement
				(enabled no)
				(sheetname "")
			)
			(fill
				(thermal_gap 0.5)
				(thermal_bridge_width 0.5)
				(island_removal_mode 0)
			)
			(polygon
				(pts
					(arc
						(start 387.655562 -110.428532)
						(mid 387.73735 -110.446845)
						(end 387.819138 -110.428532)
					)
					(arc
						(start 387.89102 -110.500414)
						(mid 387.73735 -110.544563)
						(end 387.58368 -110.500414)
					)
				)
			)
		)
		(zone
			(layer "F.Cu")
			(hatch none 0.5)
			(connect_pads
				(clearance 0)
			)
			(min_thickness 0.25)
			(keepout
				(tracks not_allowed)
				(vias allowed)
				(pads allowed)
				(copperpour not_allowed)
				(footprints allowed)
			)
			(placement
				(enabled no)
				(sheetname "")
			)
			(fill
				(thermal_gap 0.5)
				(thermal_bridge_width 0.5)
				(island_removal_mode 0)
			)
			(polygon
				(pts
					(arc
						(start 387.655562 -108.828332)
						(mid 387.73735 -108.846645)
						(end 387.819138 -108.828332)
					)
					(arc
						(start 387.89102 -108.900214)
						(mid 387.73735 -108.944363)
						(end 387.58368 -108.900214)
					)
				)
			)
		)
		(zone
			(layer "F.Cu")
			(hatch none 0.5)
			(connect_pads
				(clearance 0)
			)
			(min_thickness 0.25)
			(keepout
				(tracks not_allowed)
				(vias allowed)
				(pads allowed)
				(copperpour not_allowed)
				(footprints allowed)
			)
			(placement
				(enabled no)
				(sheetname "")
			)
			(fill
				(thermal_gap 0.5)
				(thermal_bridge_width 0.5)
				(island_removal_mode 0)
			)
			(polygon
				(pts
					(arc
						(start 387.655562 -108.028232)
						(mid 387.73735 -108.046545)
						(end 387.819138 -108.028232)
					)
					(arc
						(start 387.89102 -108.100114)
						(mid 387.73735 -108.144263)
						(end 387.58368 -108.100114)
					)
				)
			)
		)
		(zone
			(layer "F.Cu")
			(hatch none 0.5)
			(connect_pads
				(clearance 0)
			)
			(min_thickness 0.25)
			(keepout
				(tracks not_allowed)
				(vias allowed)
				(pads allowed)
				(copperpour not_allowed)
				(footprints allowed)
			)
			(placement
				(enabled no)
				(sheetname "")
			)
			(fill
				(thermal_gap 0.5)
				(thermal_bridge_width 0.5)
				(island_removal_mode 0)
			)
			(polygon
				(pts
					(arc
						(start 387.655562 -106.428032)
						(mid 387.73735 -106.446345)
						(end 387.819138 -106.428032)
					)
					(arc
						(start 387.89102 -106.499914)
						(mid 387.73735 -106.544063)
						(end 387.58368 -106.499914)
					)
				)
			)
		)
		(zone
			(layer "F.Cu")
			(hatch none 0.5)
			(connect_pads
				(clearance 0)
			)
			(min_thickness 0.25)
			(keepout
				(tracks not_allowed)
				(vias allowed)
				(pads allowed)
				(copperpour not_allowed)
				(footprints allowed)
			)
			(placement
				(enabled no)
				(sheetname "")
			)
			(fill
				(thermal_gap 0.5)
				(thermal_bridge_width 0.5)
				(island_removal_mode 0)
			)
			(polygon
				(pts
					(arc
						(start 387.655562 -104.827832)
						(mid 387.73735 -104.846145)
						(end 387.819138 -104.827832)
					)
					(arc
						(start 387.89102 -104.899714)
						(mid 387.73735 -104.943863)
						(end 387.58368 -104.899714)
					)
				)
			)
		)
		(zone
			(layer "F.Cu")
			(hatch none 0.5)
			(connect_pads
				(clearance 0)
			)
			(min_thickness 0.25)
			(keepout
				(tracks not_allowed)
				(vias allowed)
				(pads allowed)
				(copperpour not_allowed)
				(footprints allowed)
			)
			(placement
				(enabled no)
				(sheetname "")
			)
			(fill
				(thermal_gap 0.5)
				(thermal_bridge_width 0.5)
				(island_removal_mode 0)
			)
			(polygon
				(pts
					(arc
						(start 387.819138 -113.281968)
						(mid 387.73735 -113.263655)
						(end 387.655562 -113.281968)
					)
					(arc
						(start 387.58368 -113.210086)
						(mid 387.73735 -113.165937)
						(end 387.89102 -113.210086)
					)
				)
			)
		)
		(zone
			(layer "F.Cu")
			(hatch none 0.5)
			(connect_pads
				(clearance 0)
			)
			(min_thickness 0.25)
			(keepout
				(tracks not_allowed)
				(vias allowed)
				(pads allowed)
				(copperpour not_allowed)
				(footprints allowed)
			)
			(placement
				(enabled no)
				(sheetname "")
			)
			(fill
				(thermal_gap 0.5)
				(thermal_bridge_width 0.5)
				(island_removal_mode 0)
			)
			(polygon
				(pts
					(arc
						(start 387.819138 -112.481868)
						(mid 387.73735 -112.463555)
						(end 387.655562 -112.481868)
					)
					(arc
						(start 387.58368 -112.409986)
						(mid 387.73735 -112.365837)
						(end 387.89102 -112.409986)
					)
				)
			)
		)
		(zone
			(layer "F.Cu")
			(hatch none 0.5)
			(connect_pads
				(clearance 0)
			)
			(min_thickness 0.25)
			(keepout
				(tracks not_allowed)
				(vias allowed)
				(pads allowed)
				(copperpour not_allowed)
				(footprints allowed)
			)
			(placement
				(enabled no)
				(sheetname "")
			)
			(fill
				(thermal_gap 0.5)
				(thermal_bridge_width 0.5)
				(island_removal_mode 0)
			)
			(polygon
				(pts
					(arc
						(start 387.819138 -111.681768)
						(mid 387.73735 -111.663455)
						(end 387.655562 -111.681768)
					)
					(arc
						(start 387.58368 -111.609886)
						(mid 387.73735 -111.565737)
						(end 387.89102 -111.609886)
					)
				)
			)
		)
		(zone
			(layer "F.Cu")
			(hatch none 0.5)
			(connect_pads
				(clearance 0)
			)
			(min_thickness 0.25)
			(keepout
				(tracks not_allowed)
				(vias allowed)
				(pads allowed)
				(copperpour not_allowed)
				(footprints allowed)
			)
			(placement
				(enabled no)
				(sheetname "")
			)
			(fill
				(thermal_gap 0.5)
				(thermal_bridge_width 0.5)
				(island_removal_mode 0)
			)
			(polygon
				(pts
					(arc
						(start 387.819138 -110.881668)
						(mid 387.73735 -110.863355)
						(end 387.655562 -110.881668)
					)
					(arc
						(start 387.58368 -110.809786)
						(mid 387.73735 -110.765637)
						(end 387.89102 -110.809786)
					)
				)
			)
		)
		(zone
			(layer "F.Cu")
			(hatch none 0.5)
			(connect_pads
				(clearance 0)
			)
			(min_thickness 0.25)
			(keepout
				(tracks not_allowed)
				(vias allowed)
				(pads allowed)
				(copperpour not_allowed)
				(footprints allowed)
			)
			(placement
				(enabled no)
				(sheetname "")
			)
			(fill
				(thermal_gap 0.5)
				(thermal_bridge_width 0.5)
				(island_removal_mode 0)
			)
			(polygon
				(pts
					(arc
						(start 387.819138 -110.081568)
						(mid 387.73735 -110.063255)
						(end 387.655562 -110.081568)
					)
					(arc
						(start 387.58368 -110.009686)
						(mid 387.73735 -109.965537)
						(end 387.89102 -110.009686)
					)
				)
			)
		)
		(zone
			(layer "F.Cu")
			(hatch none 0.5)
			(connect_pads
				(clearance 0)
			)
			(min_thickness 0.25)
			(keepout
				(tracks not_allowed)
				(vias allowed)
				(pads allowed)
				(copperpour not_allowed)
				(footprints allowed)
			)
			(placement
				(enabled no)
				(sheetname "")
			)
			(fill
				(thermal_gap 0.5)
				(thermal_bridge_width 0.5)
				(island_removal_mode 0)
			)
			(polygon
				(pts
					(arc
						(start 387.819138 -108.481368)
						(mid 387.73735 -108.463055)
						(end 387.655562 -108.481368)
					)
					(arc
						(start 387.58368 -108.409486)
						(mid 387.73735 -108.365337)
						(end 387.89102 -108.409486)
					)
				)
			)
		)
		(zone
			(layer "F.Cu")
			(hatch none 0.5)
			(connect_pads
				(clearance 0)
			)
			(min_thickness 0.25)
			(keepout
				(tracks not_allowed)
				(vias allowed)
				(pads allowed)
				(copperpour not_allowed)
				(footprints allowed)
			)
			(placement
				(enabled no)
				(sheetname "")
			)
			(fill
				(thermal_gap 0.5)
				(thermal_bridge_width 0.5)
				(island_removal_mode 0)
			)
			(polygon
				(pts
					(arc
						(start 387.819138 -107.681268)
						(mid 387.73735 -107.662955)
						(end 387.655562 -107.681268)
					)
					(arc
						(start 387.58368 -107.609386)
						(mid 387.73735 -107.565237)
						(end 387.89102 -107.609386)
					)
				)
			)
		)
		(zone
			(layer "F.Cu")
			(hatch none 0.5)
			(connect_pads
				(clearance 0)
			)
			(min_thickness 0.25)
			(keepout
				(tracks not_allowed)
				(vias allowed)
				(pads allowed)
				(copperpour not_allowed)
				(footprints allowed)
			)
			(placement
				(enabled no)
				(sheetname "")
			)
			(fill
				(thermal_gap 0.5)
				(thermal_bridge_width 0.5)
				(island_removal_mode 0)
			)
			(polygon
				(pts
					(arc
						(start 387.819138 -106.081068)
						(mid 387.73735 -106.062755)
						(end 387.655562 -106.081068)
					)
					(arc
						(start 387.58368 -106.009186)
						(mid 387.73735 -105.965037)
						(end 387.89102 -106.009186)
					)
				)
			)
		)
		(zone
			(layer "F.Cu")
			(hatch none 0.5)
			(connect_pads
				(clearance 0)
			)
			(min_thickness 0.25)
			(keepout
				(tracks not_allowed)
				(vias allowed)
				(pads allowed)
				(copperpour not_allowed)
				(footprints allowed)
			)
			(placement
				(enabled no)
				(sheetname "")
			)
			(fill
				(thermal_gap 0.5)
				(thermal_bridge_width 0.5)
				(island_removal_mode 0)
			)
			(polygon
				(pts
					(arc
						(start 387.819138 -104.480868)
						(mid 387.73735 -104.462555)
						(end 387.655562 -104.480868)
					)
					(arc
						(start 387.58368 -104.408986)
						(mid 387.73735 -104.364837)
						(end 387.89102 -104.408986)
					)
				)
			)
		)
		(zone
			(layer "F.Cu")
			(hatch none 0.5)
			(connect_pads
				(clearance 0)
			)
			(min_thickness 0.25)
			(keepout
				(tracks not_allowed)
				(vias allowed)
				(pads allowed)
				(copperpour not_allowed)
				(footprints allowed)
			)
			(placement
				(enabled no)
				(sheetname "")
			)
			(fill
				(thermal_gap 0.5)
				(thermal_bridge_width 0.5)
				(island_removal_mode 0)
			)
			(polygon
				(pts
					(arc
						(start 387.910832 -113.537238)
						(mid 387.929145 -113.45545)
						(end 387.910832 -113.373662)
					)
					(arc
						(start 387.982714 -113.30178)
						(mid 388.026863 -113.45545)
						(end 387.982714 -113.60912)
					)
				)
			)
		)
		(zone
			(layer "F.Cu")
			(hatch none 0.5)
			(connect_pads
				(clearance 0)
			)
			(min_thickness 0.25)
			(keepout
				(tracks not_allowed)
				(vias allowed)
				(pads allowed)
				(copperpour not_allowed)
				(footprints allowed)
			)
			(placement
				(enabled no)
				(sheetname "")
			)
			(fill
				(thermal_gap 0.5)
				(thermal_bridge_width 0.5)
				(island_removal_mode 0)
			)
			(polygon
				(pts
					(arc
						(start 387.910832 -112.737138)
						(mid 387.929145 -112.65535)
						(end 387.910832 -112.573562)
					)
					(arc
						(start 387.982714 -112.50168)
						(mid 388.026863 -112.65535)
						(end 387.982714 -112.80902)
					)
				)
			)
		)
		(zone
			(layer "F.Cu")
			(hatch none 0.5)
			(connect_pads
				(clearance 0)
			)
			(min_thickness 0.25)
			(keepout
				(tracks not_allowed)
				(vias allowed)
				(pads allowed)
				(copperpour not_allowed)
				(footprints allowed)
			)
			(placement
				(enabled no)
				(sheetname "")
			)
			(fill
				(thermal_gap 0.5)
				(thermal_bridge_width 0.5)
				(island_removal_mode 0)
			)
			(polygon
				(pts
					(arc
						(start 387.910832 -111.937038)
						(mid 387.929145 -111.85525)
						(end 387.910832 -111.773462)
					)
					(arc
						(start 387.982714 -111.70158)
						(mid 388.026863 -111.85525)
						(end 387.982714 -112.00892)
					)
				)
			)
		)
		(zone
			(layer "F.Cu")
			(hatch none 0.5)
			(connect_pads
				(clearance 0)
			)
			(min_thickness 0.25)
			(keepout
				(tracks not_allowed)
				(vias allowed)
				(pads allowed)
				(copperpour not_allowed)
				(footprints allowed)
			)
			(placement
				(enabled no)
				(sheetname "")
			)
			(fill
				(thermal_gap 0.5)
				(thermal_bridge_width 0.5)
				(island_removal_mode 0)
			)
			(polygon
				(pts
					(arc
						(start 387.910832 -111.136938)
						(mid 387.929145 -111.05515)
						(end 387.910832 -110.973362)
					)
					(arc
						(start 387.982714 -110.90148)
						(mid 388.026863 -111.05515)
						(end 387.982714 -111.20882)
					)
				)
			)
		)
		(zone
			(layer "F.Cu")
			(hatch none 0.5)
			(connect_pads
				(clearance 0)
			)
			(min_thickness 0.25)
			(keepout
				(tracks not_allowed)
				(vias allowed)
				(pads allowed)
				(copperpour not_allowed)
				(footprints allowed)
			)
			(placement
				(enabled no)
				(sheetname "")
			)
			(fill
				(thermal_gap 0.5)
				(thermal_bridge_width 0.5)
				(island_removal_mode 0)
			)
			(polygon
				(pts
					(arc
						(start 387.910832 -110.336838)
						(mid 387.929145 -110.25505)
						(end 387.910832 -110.173262)
					)
					(arc
						(start 387.982714 -110.10138)
						(mid 388.026863 -110.25505)
						(end 387.982714 -110.40872)
					)
				)
			)
		)
		(zone
			(layer "F.Cu")
			(hatch none 0.5)
			(connect_pads
				(clearance 0)
			)
			(min_thickness 0.25)
			(keepout
				(tracks not_allowed)
				(vias allowed)
				(pads allowed)
				(copperpour not_allowed)
				(footprints allowed)
			)
			(placement
				(enabled no)
				(sheetname "")
			)
			(fill
				(thermal_gap 0.5)
				(thermal_bridge_width 0.5)
				(island_removal_mode 0)
			)
			(polygon
				(pts
					(arc
						(start 387.910832 -108.736638)
						(mid 387.929145 -108.65485)
						(end 387.910832 -108.573062)
					)
					(arc
						(start 387.982714 -108.50118)
						(mid 388.026863 -108.65485)
						(end 387.982714 -108.80852)
					)
				)
			)
		)
		(zone
			(layer "F.Cu")
			(hatch none 0.5)
			(connect_pads
				(clearance 0)
			)
			(min_thickness 0.25)
			(keepout
				(tracks not_allowed)
				(vias allowed)
				(pads allowed)
				(copperpour not_allowed)
				(footprints allowed)
			)
			(placement
				(enabled no)
				(sheetname "")
			)
			(fill
				(thermal_gap 0.5)
				(thermal_bridge_width 0.5)
				(island_removal_mode 0)
			)
			(polygon
				(pts
					(arc
						(start 387.910832 -107.936538)
						(mid 387.929145 -107.85475)
						(end 387.910832 -107.772962)
					)
					(arc
						(start 387.982714 -107.70108)
						(mid 388.026863 -107.85475)
						(end 387.982714 -108.00842)
					)
				)
			)
		)
		(zone
			(layer "F.Cu")
			(hatch none 0.5)
			(connect_pads
				(clearance 0)
			)
			(min_thickness 0.25)
			(keepout
				(tracks not_allowed)
				(vias allowed)
				(pads allowed)
				(copperpour not_allowed)
				(footprints allowed)
			)
			(placement
				(enabled no)
				(sheetname "")
			)
			(fill
				(thermal_gap 0.5)
				(thermal_bridge_width 0.5)
				(island_removal_mode 0)
			)
			(polygon
				(pts
					(arc
						(start 387.910832 -106.336338)
						(mid 387.929145 -106.25455)
						(end 387.910832 -106.172762)
					)
					(arc
						(start 387.982714 -106.10088)
						(mid 388.026863 -106.25455)
						(end 387.982714 -106.40822)
					)
				)
			)
		)
		(zone
			(layer "F.Cu")
			(hatch none 0.5)
			(connect_pads
				(clearance 0)
			)
			(min_thickness 0.25)
			(keepout
				(tracks not_allowed)
				(vias allowed)
				(pads allowed)
				(copperpour not_allowed)
				(footprints allowed)
			)
			(placement
				(enabled no)
				(sheetname "")
			)
			(fill
				(thermal_gap 0.5)
				(thermal_bridge_width 0.5)
				(island_removal_mode 0)
			)
			(polygon
				(pts
					(arc
						(start 387.910832 -104.736138)
						(mid 387.929145 -104.65435)
						(end 387.910832 -104.572562)
					)
					(arc
						(start 387.982714 -104.50068)
						(mid 388.026863 -104.65435)
						(end 387.982714 -104.80802)
					)
				)
			)
		)
		(zone
			(layer "F.Cu")
			(hatch none 0.5)
			(connect_pads
				(clearance 0)
			)
			(min_thickness 0.25)
			(keepout
				(tracks not_allowed)
				(vias allowed)
				(pads allowed)
				(copperpour not_allowed)
				(footprints allowed)
			)
			(placement
				(enabled no)
				(sheetname "")
			)
			(fill
				(thermal_gap 0.5)
				(thermal_bridge_width 0.5)
				(island_removal_mode 0)
			)
			(polygon
				(pts
					(arc
						(start 388.363968 -113.373662)
						(mid 388.345655 -113.45545)
						(end 388.363968 -113.537238)
					)
					(arc
						(start 388.292086 -113.60912)
						(mid 388.247937 -113.45545)
						(end 388.292086 -113.30178)
					)
				)
			)
		)
		(zone
			(layer "F.Cu")
			(hatch none 0.5)
			(connect_pads
				(clearance 0)
			)
			(min_thickness 0.25)
			(keepout
				(tracks not_allowed)
				(vias allowed)
				(pads allowed)
				(copperpour not_allowed)
				(footprints allowed)
			)
			(placement
				(enabled no)
				(sheetname "")
			)
			(fill
				(thermal_gap 0.5)
				(thermal_bridge_width 0.5)
				(island_removal_mode 0)
			)
			(polygon
				(pts
					(arc
						(start 388.363968 -112.573562)
						(mid 388.345655 -112.65535)
						(end 388.363968 -112.737138)
					)
					(arc
						(start 388.292086 -112.80902)
						(mid 388.247937 -112.65535)
						(end 388.292086 -112.50168)
					)
				)
			)
		)
		(zone
			(layer "F.Cu")
			(hatch none 0.5)
			(connect_pads
				(clearance 0)
			)
			(min_thickness 0.25)
			(keepout
				(tracks not_allowed)
				(vias allowed)
				(pads allowed)
				(copperpour not_allowed)
				(footprints allowed)
			)
			(placement
				(enabled no)
				(sheetname "")
			)
			(fill
				(thermal_gap 0.5)
				(thermal_bridge_width 0.5)
				(island_removal_mode 0)
			)
			(polygon
				(pts
					(arc
						(start 388.363968 -111.773462)
						(mid 388.345655 -111.85525)
						(end 388.363968 -111.937038)
					)
					(arc
						(start 388.292086 -112.00892)
						(mid 388.247937 -111.85525)
						(end 388.292086 -111.70158)
					)
				)
			)
		)
		(zone
			(layer "F.Cu")
			(hatch none 0.5)
			(connect_pads
				(clearance 0)
			)
			(min_thickness 0.25)
			(keepout
				(tracks not_allowed)
				(vias allowed)
				(pads allowed)
				(copperpour not_allowed)
				(footprints allowed)
			)
			(placement
				(enabled no)
				(sheetname "")
			)
			(fill
				(thermal_gap 0.5)
				(thermal_bridge_width 0.5)
				(island_removal_mode 0)
			)
			(polygon
				(pts
					(arc
						(start 388.363968 -110.973362)
						(mid 388.345655 -111.05515)
						(end 388.363968 -111.136938)
					)
					(arc
						(start 388.292086 -111.20882)
						(mid 388.247937 -111.05515)
						(end 388.292086 -110.90148)
					)
				)
			)
		)
		(zone
			(layer "F.Cu")
			(hatch none 0.5)
			(connect_pads
				(clearance 0)
			)
			(min_thickness 0.25)
			(keepout
				(tracks not_allowed)
				(vias allowed)
				(pads allowed)
				(copperpour not_allowed)
				(footprints allowed)
			)
			(placement
				(enabled no)
				(sheetname "")
			)
			(fill
				(thermal_gap 0.5)
				(thermal_bridge_width 0.5)
				(island_removal_mode 0)
			)
			(polygon
				(pts
					(arc
						(start 388.363968 -110.173262)
						(mid 388.345655 -110.25505)
						(end 388.363968 -110.336838)
					)
					(arc
						(start 388.292086 -110.40872)
						(mid 388.247937 -110.25505)
						(end 388.292086 -110.10138)
					)
				)
			)
		)
		(zone
			(layer "F.Cu")
			(hatch none 0.5)
			(connect_pads
				(clearance 0)
			)
			(min_thickness 0.25)
			(keepout
				(tracks not_allowed)
				(vias allowed)
				(pads allowed)
				(copperpour not_allowed)
				(footprints allowed)
			)
			(placement
				(enabled no)
				(sheetname "")
			)
			(fill
				(thermal_gap 0.5)
				(thermal_bridge_width 0.5)
				(island_removal_mode 0)
			)
			(polygon
				(pts
					(arc
						(start 388.363968 -109.373162)
						(mid 388.345655 -109.45495)
						(end 388.363968 -109.536738)
					)
					(arc
						(start 388.292086 -109.60862)
						(mid 388.247937 -109.45495)
						(end 388.292086 -109.30128)
					)
				)
			)
		)
		(zone
			(layer "F.Cu")
			(hatch none 0.5)
			(connect_pads
				(clearance 0)
			)
			(min_thickness 0.25)
			(keepout
				(tracks not_allowed)
				(vias allowed)
				(pads allowed)
				(copperpour not_allowed)
				(footprints allowed)
			)
			(placement
				(enabled no)
				(sheetname "")
			)
			(fill
				(thermal_gap 0.5)
				(thermal_bridge_width 0.5)
				(island_removal_mode 0)
			)
			(polygon
				(pts
					(arc
						(start 388.363968 -108.573062)
						(mid 388.345655 -108.65485)
						(end 388.363968 -108.736638)
					)
					(arc
						(start 388.292086 -108.80852)
						(mid 388.247937 -108.65485)
						(end 388.292086 -108.50118)
					)
				)
			)
		)
		(zone
			(layer "F.Cu")
			(hatch none 0.5)
			(connect_pads
				(clearance 0)
			)
			(min_thickness 0.25)
			(keepout
				(tracks not_allowed)
				(vias allowed)
				(pads allowed)
				(copperpour not_allowed)
				(footprints allowed)
			)
			(placement
				(enabled no)
				(sheetname "")
			)
			(fill
				(thermal_gap 0.5)
				(thermal_bridge_width 0.5)
				(island_removal_mode 0)
			)
			(polygon
				(pts
					(arc
						(start 388.363968 -107.772962)
						(mid 388.345655 -107.85475)
						(end 388.363968 -107.936538)
					)
					(arc
						(start 388.292086 -108.00842)
						(mid 388.247937 -107.85475)
						(end 388.292086 -107.70108)
					)
				)
			)
		)
		(zone
			(layer "F.Cu")
			(hatch none 0.5)
			(connect_pads
				(clearance 0)
			)
			(min_thickness 0.25)
			(keepout
				(tracks not_allowed)
				(vias allowed)
				(pads allowed)
				(copperpour not_allowed)
				(footprints allowed)
			)
			(placement
				(enabled no)
				(sheetname "")
			)
			(fill
				(thermal_gap 0.5)
				(thermal_bridge_width 0.5)
				(island_removal_mode 0)
			)
			(polygon
				(pts
					(arc
						(start 388.363968 -106.172762)
						(mid 388.345655 -106.25455)
						(end 388.363968 -106.336338)
					)
					(arc
						(start 388.292086 -106.40822)
						(mid 388.247937 -106.25455)
						(end 388.292086 -106.10088)
					)
				)
			)
		)
		(zone
			(layer "F.Cu")
			(hatch none 0.5)
			(connect_pads
				(clearance 0)
			)
			(min_thickness 0.25)
			(keepout
				(tracks not_allowed)
				(vias allowed)
				(pads allowed)
				(copperpour not_allowed)
				(footprints allowed)
			)
			(placement
				(enabled no)
				(sheetname "")
			)
			(fill
				(thermal_gap 0.5)
				(thermal_bridge_width 0.5)
				(island_removal_mode 0)
			)
			(polygon
				(pts
					(arc
						(start 388.363968 -104.572562)
						(mid 388.345655 -104.65435)
						(end 388.363968 -104.736138)
					)
					(arc
						(start 388.292086 -104.80802)
						(mid 388.247937 -104.65435)
						(end 388.292086 -104.50068)
					)
				)
			)
		)
		(zone
			(layer "F.Cu")
			(hatch none 0.5)
			(connect_pads
				(clearance 0)
			)
			(min_thickness 0.25)
			(keepout
				(tracks not_allowed)
				(vias allowed)
				(pads allowed)
				(copperpour not_allowed)
				(footprints allowed)
			)
			(placement
				(enabled no)
				(sheetname "")
			)
			(fill
				(thermal_gap 0.5)
				(thermal_bridge_width 0.5)
				(island_removal_mode 0)
			)
			(polygon
				(pts
					(arc
						(start 388.455662 -113.628932)
						(mid 388.53745 -113.647245)
						(end 388.619238 -113.628932)
					)
					(arc
						(start 388.69112 -113.700814)
						(mid 388.53745 -113.744963)
						(end 388.38378 -113.700814)
					)
				)
			)
		)
		(zone
			(layer "F.Cu")
			(hatch none 0.5)
			(connect_pads
				(clearance 0)
			)
			(min_thickness 0.25)
			(keepout
				(tracks not_allowed)
				(vias allowed)
				(pads allowed)
				(copperpour not_allowed)
				(footprints allowed)
			)
			(placement
				(enabled no)
				(sheetname "")
			)
			(fill
				(thermal_gap 0.5)
				(thermal_bridge_width 0.5)
				(island_removal_mode 0)
			)
			(polygon
				(pts
					(arc
						(start 388.455662 -112.828832)
						(mid 388.53745 -112.847145)
						(end 388.619238 -112.828832)
					)
					(arc
						(start 388.69112 -112.900714)
						(mid 388.53745 -112.944863)
						(end 388.38378 -112.900714)
					)
				)
			)
		)
		(zone
			(layer "F.Cu")
			(hatch none 0.5)
			(connect_pads
				(clearance 0)
			)
			(min_thickness 0.25)
			(keepout
				(tracks not_allowed)
				(vias allowed)
				(pads allowed)
				(copperpour not_allowed)
				(footprints allowed)
			)
			(placement
				(enabled no)
				(sheetname "")
			)
			(fill
				(thermal_gap 0.5)
				(thermal_bridge_width 0.5)
				(island_removal_mode 0)
			)
			(polygon
				(pts
					(arc
						(start 388.455662 -112.028732)
						(mid 388.53745 -112.047045)
						(end 388.619238 -112.028732)
					)
					(arc
						(start 388.69112 -112.100614)
						(mid 388.53745 -112.144763)
						(end 388.38378 -112.100614)
					)
				)
			)
		)
		(zone
			(layer "F.Cu")
			(hatch none 0.5)
			(connect_pads
				(clearance 0)
			)
			(min_thickness 0.25)
			(keepout
				(tracks not_allowed)
				(vias allowed)
				(pads allowed)
				(copperpour not_allowed)
				(footprints allowed)
			)
			(placement
				(enabled no)
				(sheetname "")
			)
			(fill
				(thermal_gap 0.5)
				(thermal_bridge_width 0.5)
				(island_removal_mode 0)
			)
			(polygon
				(pts
					(arc
						(start 388.455662 -111.228632)
						(mid 388.53745 -111.246945)
						(end 388.619238 -111.228632)
					)
					(arc
						(start 388.69112 -111.300514)
						(mid 388.53745 -111.344663)
						(end 388.38378 -111.300514)
					)
				)
			)
		)
		(zone
			(layer "F.Cu")
			(hatch none 0.5)
			(connect_pads
				(clearance 0)
			)
			(min_thickness 0.25)
			(keepout
				(tracks not_allowed)
				(vias allowed)
				(pads allowed)
				(copperpour not_allowed)
				(footprints allowed)
			)
			(placement
				(enabled no)
				(sheetname "")
			)
			(fill
				(thermal_gap 0.5)
				(thermal_bridge_width 0.5)
				(island_removal_mode 0)
			)
			(polygon
				(pts
					(arc
						(start 388.455662 -110.428532)
						(mid 388.53745 -110.446845)
						(end 388.619238 -110.428532)
					)
					(arc
						(start 388.69112 -110.500414)
						(mid 388.53745 -110.544563)
						(end 388.38378 -110.500414)
					)
				)
			)
		)
		(zone
			(layer "F.Cu")
			(hatch none 0.5)
			(connect_pads
				(clearance 0)
			)
			(min_thickness 0.25)
			(keepout
				(tracks not_allowed)
				(vias allowed)
				(pads allowed)
				(copperpour not_allowed)
				(footprints allowed)
			)
			(placement
				(enabled no)
				(sheetname "")
			)
			(fill
				(thermal_gap 0.5)
				(thermal_bridge_width 0.5)
				(island_removal_mode 0)
			)
			(polygon
				(pts
					(arc
						(start 388.455662 -109.628432)
						(mid 388.53745 -109.646745)
						(end 388.619238 -109.628432)
					)
					(arc
						(start 388.69112 -109.700314)
						(mid 388.53745 -109.744463)
						(end 388.38378 -109.700314)
					)
				)
			)
		)
		(zone
			(layer "F.Cu")
			(hatch none 0.5)
			(connect_pads
				(clearance 0)
			)
			(min_thickness 0.25)
			(keepout
				(tracks not_allowed)
				(vias allowed)
				(pads allowed)
				(copperpour not_allowed)
				(footprints allowed)
			)
			(placement
				(enabled no)
				(sheetname "")
			)
			(fill
				(thermal_gap 0.5)
				(thermal_bridge_width 0.5)
				(island_removal_mode 0)
			)
			(polygon
				(pts
					(arc
						(start 388.455662 -108.828332)
						(mid 388.53745 -108.846645)
						(end 388.619238 -108.828332)
					)
					(arc
						(start 388.69112 -108.900214)
						(mid 388.53745 -108.944363)
						(end 388.38378 -108.900214)
					)
				)
			)
		)
		(zone
			(layer "F.Cu")
			(hatch none 0.5)
			(connect_pads
				(clearance 0)
			)
			(min_thickness 0.25)
			(keepout
				(tracks not_allowed)
				(vias allowed)
				(pads allowed)
				(copperpour not_allowed)
				(footprints allowed)
			)
			(placement
				(enabled no)
				(sheetname "")
			)
			(fill
				(thermal_gap 0.5)
				(thermal_bridge_width 0.5)
				(island_removal_mode 0)
			)
			(polygon
				(pts
					(arc
						(start 388.455662 -108.028232)
						(mid 388.53745 -108.046545)
						(end 388.619238 -108.028232)
					)
					(arc
						(start 388.69112 -108.100114)
						(mid 388.53745 -108.144263)
						(end 388.38378 -108.100114)
					)
				)
			)
		)
		(zone
			(layer "F.Cu")
			(hatch none 0.5)
			(connect_pads
				(clearance 0)
			)
			(min_thickness 0.25)
			(keepout
				(tracks not_allowed)
				(vias allowed)
				(pads allowed)
				(copperpour not_allowed)
				(footprints allowed)
			)
			(placement
				(enabled no)
				(sheetname "")
			)
			(fill
				(thermal_gap 0.5)
				(thermal_bridge_width 0.5)
				(island_removal_mode 0)
			)
			(polygon
				(pts
					(arc
						(start 388.455662 -106.428032)
						(mid 388.53745 -106.446345)
						(end 388.619238 -106.428032)
					)
					(arc
						(start 388.69112 -106.499914)
						(mid 388.53745 -106.544063)
						(end 388.38378 -106.499914)
					)
				)
			)
		)
		(zone
			(layer "F.Cu")
			(hatch none 0.5)
			(connect_pads
				(clearance 0)
			)
			(min_thickness 0.25)
			(keepout
				(tracks not_allowed)
				(vias allowed)
				(pads allowed)
				(copperpour not_allowed)
				(footprints allowed)
			)
			(placement
				(enabled no)
				(sheetname "")
			)
			(fill
				(thermal_gap 0.5)
				(thermal_bridge_width 0.5)
				(island_removal_mode 0)
			)
			(polygon
				(pts
					(arc
						(start 388.455662 -104.827832)
						(mid 388.53745 -104.846145)
						(end 388.619238 -104.827832)
					)
					(arc
						(start 388.69112 -104.899714)
						(mid 388.53745 -104.943863)
						(end 388.38378 -104.899714)
					)
				)
			)
		)
		(zone
			(layer "F.Cu")
			(hatch none 0.5)
			(connect_pads
				(clearance 0)
			)
			(min_thickness 0.25)
			(keepout
				(tracks not_allowed)
				(vias allowed)
				(pads allowed)
				(copperpour not_allowed)
				(footprints allowed)
			)
			(placement
				(enabled no)
				(sheetname "")
			)
			(fill
				(thermal_gap 0.5)
				(thermal_bridge_width 0.5)
				(island_removal_mode 0)
			)
			(polygon
				(pts
					(arc
						(start 388.619238 -113.281968)
						(mid 388.53745 -113.263655)
						(end 388.455662 -113.281968)
					)
					(arc
						(start 388.38378 -113.210086)
						(mid 388.53745 -113.165937)
						(end 388.69112 -113.210086)
					)
				)
			)
		)
		(zone
			(layer "F.Cu")
			(hatch none 0.5)
			(connect_pads
				(clearance 0)
			)
			(min_thickness 0.25)
			(keepout
				(tracks not_allowed)
				(vias allowed)
				(pads allowed)
				(copperpour not_allowed)
				(footprints allowed)
			)
			(placement
				(enabled no)
				(sheetname "")
			)
			(fill
				(thermal_gap 0.5)
				(thermal_bridge_width 0.5)
				(island_removal_mode 0)
			)
			(polygon
				(pts
					(arc
						(start 388.619238 -112.481868)
						(mid 388.53745 -112.463555)
						(end 388.455662 -112.481868)
					)
					(arc
						(start 388.38378 -112.409986)
						(mid 388.53745 -112.365837)
						(end 388.69112 -112.409986)
					)
				)
			)
		)
		(zone
			(layer "F.Cu")
			(hatch none 0.5)
			(connect_pads
				(clearance 0)
			)
			(min_thickness 0.25)
			(keepout
				(tracks not_allowed)
				(vias allowed)
				(pads allowed)
				(copperpour not_allowed)
				(footprints allowed)
			)
			(placement
				(enabled no)
				(sheetname "")
			)
			(fill
				(thermal_gap 0.5)
				(thermal_bridge_width 0.5)
				(island_removal_mode 0)
			)
			(polygon
				(pts
					(arc
						(start 388.619238 -111.681768)
						(mid 388.53745 -111.663455)
						(end 388.455662 -111.681768)
					)
					(arc
						(start 388.38378 -111.609886)
						(mid 388.53745 -111.565737)
						(end 388.69112 -111.609886)
					)
				)
			)
		)
		(zone
			(layer "F.Cu")
			(hatch none 0.5)
			(connect_pads
				(clearance 0)
			)
			(min_thickness 0.25)
			(keepout
				(tracks not_allowed)
				(vias allowed)
				(pads allowed)
				(copperpour not_allowed)
				(footprints allowed)
			)
			(placement
				(enabled no)
				(sheetname "")
			)
			(fill
				(thermal_gap 0.5)
				(thermal_bridge_width 0.5)
				(island_removal_mode 0)
			)
			(polygon
				(pts
					(arc
						(start 388.619238 -110.881668)
						(mid 388.53745 -110.863355)
						(end 388.455662 -110.881668)
					)
					(arc
						(start 388.38378 -110.809786)
						(mid 388.53745 -110.765637)
						(end 388.69112 -110.809786)
					)
				)
			)
		)
		(zone
			(layer "F.Cu")
			(hatch none 0.5)
			(connect_pads
				(clearance 0)
			)
			(min_thickness 0.25)
			(keepout
				(tracks not_allowed)
				(vias allowed)
				(pads allowed)
				(copperpour not_allowed)
				(footprints allowed)
			)
			(placement
				(enabled no)
				(sheetname "")
			)
			(fill
				(thermal_gap 0.5)
				(thermal_bridge_width 0.5)
				(island_removal_mode 0)
			)
			(polygon
				(pts
					(arc
						(start 388.619238 -110.081568)
						(mid 388.53745 -110.063255)
						(end 388.455662 -110.081568)
					)
					(arc
						(start 388.38378 -110.009686)
						(mid 388.53745 -109.965537)
						(end 388.69112 -110.009686)
					)
				)
			)
		)
		(zone
			(layer "F.Cu")
			(hatch none 0.5)
			(connect_pads
				(clearance 0)
			)
			(min_thickness 0.25)
			(keepout
				(tracks not_allowed)
				(vias allowed)
				(pads allowed)
				(copperpour not_allowed)
				(footprints allowed)
			)
			(placement
				(enabled no)
				(sheetname "")
			)
			(fill
				(thermal_gap 0.5)
				(thermal_bridge_width 0.5)
				(island_removal_mode 0)
			)
			(polygon
				(pts
					(arc
						(start 388.619238 -109.281468)
						(mid 388.53745 -109.263155)
						(end 388.455662 -109.281468)
					)
					(arc
						(start 388.38378 -109.209586)
						(mid 388.53745 -109.165437)
						(end 388.69112 -109.209586)
					)
				)
			)
		)
		(zone
			(layer "F.Cu")
			(hatch none 0.5)
			(connect_pads
				(clearance 0)
			)
			(min_thickness 0.25)
			(keepout
				(tracks not_allowed)
				(vias allowed)
				(pads allowed)
				(copperpour not_allowed)
				(footprints allowed)
			)
			(placement
				(enabled no)
				(sheetname "")
			)
			(fill
				(thermal_gap 0.5)
				(thermal_bridge_width 0.5)
				(island_removal_mode 0)
			)
			(polygon
				(pts
					(arc
						(start 388.619238 -108.481368)
						(mid 388.53745 -108.463055)
						(end 388.455662 -108.481368)
					)
					(arc
						(start 388.38378 -108.409486)
						(mid 388.53745 -108.365337)
						(end 388.69112 -108.409486)
					)
				)
			)
		)
		(zone
			(layer "F.Cu")
			(hatch none 0.5)
			(connect_pads
				(clearance 0)
			)
			(min_thickness 0.25)
			(keepout
				(tracks not_allowed)
				(vias allowed)
				(pads allowed)
				(copperpour not_allowed)
				(footprints allowed)
			)
			(placement
				(enabled no)
				(sheetname "")
			)
			(fill
				(thermal_gap 0.5)
				(thermal_bridge_width 0.5)
				(island_removal_mode 0)
			)
			(polygon
				(pts
					(arc
						(start 388.619238 -107.681268)
						(mid 388.53745 -107.662955)
						(end 388.455662 -107.681268)
					)
					(arc
						(start 388.38378 -107.609386)
						(mid 388.53745 -107.565237)
						(end 388.69112 -107.609386)
					)
				)
			)
		)
		(zone
			(layer "F.Cu")
			(hatch none 0.5)
			(connect_pads
				(clearance 0)
			)
			(min_thickness 0.25)
			(keepout
				(tracks not_allowed)
				(vias allowed)
				(pads allowed)
				(copperpour not_allowed)
				(footprints allowed)
			)
			(placement
				(enabled no)
				(sheetname "")
			)
			(fill
				(thermal_gap 0.5)
				(thermal_bridge_width 0.5)
				(island_removal_mode 0)
			)
			(polygon
				(pts
					(arc
						(start 388.619238 -106.081068)
						(mid 388.53745 -106.062755)
						(end 388.455662 -106.081068)
					)
					(arc
						(start 388.38378 -106.009186)
						(mid 388.53745 -105.965037)
						(end 388.69112 -106.009186)
					)
				)
			)
		)
		(zone
			(layer "F.Cu")
			(hatch none 0.5)
			(connect_pads
				(clearance 0)
			)
			(min_thickness 0.25)
			(keepout
				(tracks not_allowed)
				(vias allowed)
				(pads allowed)
				(copperpour not_allowed)
				(footprints allowed)
			)
			(placement
				(enabled no)
				(sheetname "")
			)
			(fill
				(thermal_gap 0.5)
				(thermal_bridge_width 0.5)
				(island_removal_mode 0)
			)
			(polygon
				(pts
					(arc
						(start 388.619238 -104.480868)
						(mid 388.53745 -104.462555)
						(end 388.455662 -104.480868)
					)
					(arc
						(start 388.38378 -104.408986)
						(mid 388.53745 -104.364837)
						(end 388.69112 -104.408986)
					)
				)
			)
		)
		(zone
			(layer "F.Cu")
			(hatch none 0.5)
			(connect_pads
				(clearance 0)
			)
			(min_thickness 0.25)
			(keepout
				(tracks not_allowed)
				(vias allowed)
				(pads allowed)
				(copperpour not_allowed)
				(footprints allowed)
			)
			(placement
				(enabled no)
				(sheetname "")
			)
			(fill
				(thermal_gap 0.5)
				(thermal_bridge_width 0.5)
				(island_removal_mode 0)
			)
			(polygon
				(pts
					(arc
						(start 388.710932 -113.537238)
						(mid 388.729245 -113.45545)
						(end 388.710932 -113.373662)
					)
					(arc
						(start 388.782814 -113.30178)
						(mid 388.826963 -113.45545)
						(end 388.782814 -113.60912)
					)
				)
			)
		)
		(zone
			(layer "F.Cu")
			(hatch none 0.5)
			(connect_pads
				(clearance 0)
			)
			(min_thickness 0.25)
			(keepout
				(tracks not_allowed)
				(vias allowed)
				(pads allowed)
				(copperpour not_allowed)
				(footprints allowed)
			)
			(placement
				(enabled no)
				(sheetname "")
			)
			(fill
				(thermal_gap 0.5)
				(thermal_bridge_width 0.5)
				(island_removal_mode 0)
			)
			(polygon
				(pts
					(arc
						(start 388.710932 -112.737138)
						(mid 388.729245 -112.65535)
						(end 388.710932 -112.573562)
					)
					(arc
						(start 388.782814 -112.50168)
						(mid 388.826963 -112.65535)
						(end 388.782814 -112.80902)
					)
				)
			)
		)
		(zone
			(layer "F.Cu")
			(hatch none 0.5)
			(connect_pads
				(clearance 0)
			)
			(min_thickness 0.25)
			(keepout
				(tracks not_allowed)
				(vias allowed)
				(pads allowed)
				(copperpour not_allowed)
				(footprints allowed)
			)
			(placement
				(enabled no)
				(sheetname "")
			)
			(fill
				(thermal_gap 0.5)
				(thermal_bridge_width 0.5)
				(island_removal_mode 0)
			)
			(polygon
				(pts
					(arc
						(start 388.710932 -111.937038)
						(mid 388.729245 -111.85525)
						(end 388.710932 -111.773462)
					)
					(arc
						(start 388.782814 -111.70158)
						(mid 388.826963 -111.85525)
						(end 388.782814 -112.00892)
					)
				)
			)
		)
		(zone
			(layer "F.Cu")
			(hatch none 0.5)
			(connect_pads
				(clearance 0)
			)
			(min_thickness 0.25)
			(keepout
				(tracks not_allowed)
				(vias allowed)
				(pads allowed)
				(copperpour not_allowed)
				(footprints allowed)
			)
			(placement
				(enabled no)
				(sheetname "")
			)
			(fill
				(thermal_gap 0.5)
				(thermal_bridge_width 0.5)
				(island_removal_mode 0)
			)
			(polygon
				(pts
					(arc
						(start 388.710932 -111.136938)
						(mid 388.729245 -111.05515)
						(end 388.710932 -110.973362)
					)
					(arc
						(start 388.782814 -110.90148)
						(mid 388.826963 -111.05515)
						(end 388.782814 -111.20882)
					)
				)
			)
		)
		(zone
			(layer "F.Cu")
			(hatch none 0.5)
			(connect_pads
				(clearance 0)
			)
			(min_thickness 0.25)
			(keepout
				(tracks not_allowed)
				(vias allowed)
				(pads allowed)
				(copperpour not_allowed)
				(footprints allowed)
			)
			(placement
				(enabled no)
				(sheetname "")
			)
			(fill
				(thermal_gap 0.5)
				(thermal_bridge_width 0.5)
				(island_removal_mode 0)
			)
			(polygon
				(pts
					(arc
						(start 388.710932 -110.336838)
						(mid 388.729245 -110.25505)
						(end 388.710932 -110.173262)
					)
					(arc
						(start 388.782814 -110.10138)
						(mid 388.826963 -110.25505)
						(end 388.782814 -110.40872)
					)
				)
			)
		)
		(zone
			(layer "F.Cu")
			(hatch none 0.5)
			(connect_pads
				(clearance 0)
			)
			(min_thickness 0.25)
			(keepout
				(tracks not_allowed)
				(vias allowed)
				(pads allowed)
				(copperpour not_allowed)
				(footprints allowed)
			)
			(placement
				(enabled no)
				(sheetname "")
			)
			(fill
				(thermal_gap 0.5)
				(thermal_bridge_width 0.5)
				(island_removal_mode 0)
			)
			(polygon
				(pts
					(arc
						(start 388.710932 -109.536738)
						(mid 388.729245 -109.45495)
						(end 388.710932 -109.373162)
					)
					(arc
						(start 388.782814 -109.30128)
						(mid 388.826963 -109.45495)
						(end 388.782814 -109.60862)
					)
				)
			)
		)
		(zone
			(layer "F.Cu")
			(hatch none 0.5)
			(connect_pads
				(clearance 0)
			)
			(min_thickness 0.25)
			(keepout
				(tracks not_allowed)
				(vias allowed)
				(pads allowed)
				(copperpour not_allowed)
				(footprints allowed)
			)
			(placement
				(enabled no)
				(sheetname "")
			)
			(fill
				(thermal_gap 0.5)
				(thermal_bridge_width 0.5)
				(island_removal_mode 0)
			)
			(polygon
				(pts
					(arc
						(start 388.710932 -108.736638)
						(mid 388.729245 -108.65485)
						(end 388.710932 -108.573062)
					)
					(arc
						(start 388.782814 -108.50118)
						(mid 388.826963 -108.65485)
						(end 388.782814 -108.80852)
					)
				)
			)
		)
		(zone
			(layer "F.Cu")
			(hatch none 0.5)
			(connect_pads
				(clearance 0)
			)
			(min_thickness 0.25)
			(keepout
				(tracks not_allowed)
				(vias allowed)
				(pads allowed)
				(copperpour not_allowed)
				(footprints allowed)
			)
			(placement
				(enabled no)
				(sheetname "")
			)
			(fill
				(thermal_gap 0.5)
				(thermal_bridge_width 0.5)
				(island_removal_mode 0)
			)
			(polygon
				(pts
					(arc
						(start 388.710932 -107.936538)
						(mid 388.729245 -107.85475)
						(end 388.710932 -107.772962)
					)
					(arc
						(start 388.782814 -107.70108)
						(mid 388.826963 -107.85475)
						(end 388.782814 -108.00842)
					)
				)
			)
		)
		(zone
			(layer "F.Cu")
			(hatch none 0.5)
			(connect_pads
				(clearance 0)
			)
			(min_thickness 0.25)
			(keepout
				(tracks not_allowed)
				(vias allowed)
				(pads allowed)
				(copperpour not_allowed)
				(footprints allowed)
			)
			(placement
				(enabled no)
				(sheetname "")
			)
			(fill
				(thermal_gap 0.5)
				(thermal_bridge_width 0.5)
				(island_removal_mode 0)
			)
			(polygon
				(pts
					(arc
						(start 388.710932 -106.336338)
						(mid 388.729245 -106.25455)
						(end 388.710932 -106.172762)
					)
					(arc
						(start 388.782814 -106.10088)
						(mid 388.826963 -106.25455)
						(end 388.782814 -106.40822)
					)
				)
			)
		)
		(zone
			(layer "F.Cu")
			(hatch none 0.5)
			(connect_pads
				(clearance 0)
			)
			(min_thickness 0.25)
			(keepout
				(tracks not_allowed)
				(vias allowed)
				(pads allowed)
				(copperpour not_allowed)
				(footprints allowed)
			)
			(placement
				(enabled no)
				(sheetname "")
			)
			(fill
				(thermal_gap 0.5)
				(thermal_bridge_width 0.5)
				(island_removal_mode 0)
			)
			(polygon
				(pts
					(arc
						(start 388.710932 -104.736138)
						(mid 388.729245 -104.65435)
						(end 388.710932 -104.572562)
					)
					(arc
						(start 388.782814 -104.50068)
						(mid 388.826963 -104.65435)
						(end 388.782814 -104.80802)
					)
				)
			)
		)
		(zone
			(layer "F.Cu")
			(hatch none 0.5)
			(connect_pads
				(clearance 0)
			)
			(min_thickness 0.25)
			(keepout
				(tracks not_allowed)
				(vias allowed)
				(pads allowed)
				(copperpour not_allowed)
				(footprints allowed)
			)
			(placement
				(enabled no)
				(sheetname "")
			)
			(fill
				(thermal_gap 0.5)
				(thermal_bridge_width 0.5)
				(island_removal_mode 0)
			)
			(polygon
				(pts
					(arc
						(start 389.164068 -114.173762)
						(mid 389.145755 -114.25555)
						(end 389.164068 -114.337338)
					)
					(arc
						(start 389.092186 -114.40922)
						(mid 389.048037 -114.25555)
						(end 389.092186 -114.10188)
					)
				)
			)
		)
		(zone
			(layer "F.Cu")
			(hatch none 0.5)
			(connect_pads
				(clearance 0)
			)
			(min_thickness 0.25)
			(keepout
				(tracks not_allowed)
				(vias allowed)
				(pads allowed)
				(copperpour not_allowed)
				(footprints allowed)
			)
			(placement
				(enabled no)
				(sheetname "")
			)
			(fill
				(thermal_gap 0.5)
				(thermal_bridge_width 0.5)
				(island_removal_mode 0)
			)
			(polygon
				(pts
					(arc
						(start 389.164068 -113.373662)
						(mid 389.145755 -113.45545)
						(end 389.164068 -113.537238)
					)
					(arc
						(start 389.092186 -113.60912)
						(mid 389.048037 -113.45545)
						(end 389.092186 -113.30178)
					)
				)
			)
		)
		(zone
			(layer "F.Cu")
			(hatch none 0.5)
			(connect_pads
				(clearance 0)
			)
			(min_thickness 0.25)
			(keepout
				(tracks not_allowed)
				(vias allowed)
				(pads allowed)
				(copperpour not_allowed)
				(footprints allowed)
			)
			(placement
				(enabled no)
				(sheetname "")
			)
			(fill
				(thermal_gap 0.5)
				(thermal_bridge_width 0.5)
				(island_removal_mode 0)
			)
			(polygon
				(pts
					(arc
						(start 389.164068 -112.573562)
						(mid 389.145755 -112.65535)
						(end 389.164068 -112.737138)
					)
					(arc
						(start 389.092186 -112.80902)
						(mid 389.048037 -112.65535)
						(end 389.092186 -112.50168)
					)
				)
			)
		)
		(zone
			(layer "F.Cu")
			(hatch none 0.5)
			(connect_pads
				(clearance 0)
			)
			(min_thickness 0.25)
			(keepout
				(tracks not_allowed)
				(vias allowed)
				(pads allowed)
				(copperpour not_allowed)
				(footprints allowed)
			)
			(placement
				(enabled no)
				(sheetname "")
			)
			(fill
				(thermal_gap 0.5)
				(thermal_bridge_width 0.5)
				(island_removal_mode 0)
			)
			(polygon
				(pts
					(arc
						(start 389.164068 -111.773462)
						(mid 389.145755 -111.85525)
						(end 389.164068 -111.937038)
					)
					(arc
						(start 389.092186 -112.00892)
						(mid 389.048037 -111.85525)
						(end 389.092186 -111.70158)
					)
				)
			)
		)
		(zone
			(layer "F.Cu")
			(hatch none 0.5)
			(connect_pads
				(clearance 0)
			)
			(min_thickness 0.25)
			(keepout
				(tracks not_allowed)
				(vias allowed)
				(pads allowed)
				(copperpour not_allowed)
				(footprints allowed)
			)
			(placement
				(enabled no)
				(sheetname "")
			)
			(fill
				(thermal_gap 0.5)
				(thermal_bridge_width 0.5)
				(island_removal_mode 0)
			)
			(polygon
				(pts
					(arc
						(start 389.164068 -110.973362)
						(mid 389.145755 -111.05515)
						(end 389.164068 -111.136938)
					)
					(arc
						(start 389.092186 -111.20882)
						(mid 389.048037 -111.05515)
						(end 389.092186 -110.90148)
					)
				)
			)
		)
		(zone
			(layer "F.Cu")
			(hatch none 0.5)
			(connect_pads
				(clearance 0)
			)
			(min_thickness 0.25)
			(keepout
				(tracks not_allowed)
				(vias allowed)
				(pads allowed)
				(copperpour not_allowed)
				(footprints allowed)
			)
			(placement
				(enabled no)
				(sheetname "")
			)
			(fill
				(thermal_gap 0.5)
				(thermal_bridge_width 0.5)
				(island_removal_mode 0)
			)
			(polygon
				(pts
					(arc
						(start 389.164068 -110.173262)
						(mid 389.145755 -110.25505)
						(end 389.164068 -110.336838)
					)
					(arc
						(start 389.092186 -110.40872)
						(mid 389.048037 -110.25505)
						(end 389.092186 -110.10138)
					)
				)
			)
		)
		(zone
			(layer "F.Cu")
			(hatch none 0.5)
			(connect_pads
				(clearance 0)
			)
			(min_thickness 0.25)
			(keepout
				(tracks not_allowed)
				(vias allowed)
				(pads allowed)
				(copperpour not_allowed)
				(footprints allowed)
			)
			(placement
				(enabled no)
				(sheetname "")
			)
			(fill
				(thermal_gap 0.5)
				(thermal_bridge_width 0.5)
				(island_removal_mode 0)
			)
			(polygon
				(pts
					(arc
						(start 389.164068 -109.373162)
						(mid 389.145755 -109.45495)
						(end 389.164068 -109.536738)
					)
					(arc
						(start 389.092186 -109.60862)
						(mid 389.048037 -109.45495)
						(end 389.092186 -109.30128)
					)
				)
			)
		)
		(zone
			(layer "F.Cu")
			(hatch none 0.5)
			(connect_pads
				(clearance 0)
			)
			(min_thickness 0.25)
			(keepout
				(tracks not_allowed)
				(vias allowed)
				(pads allowed)
				(copperpour not_allowed)
				(footprints allowed)
			)
			(placement
				(enabled no)
				(sheetname "")
			)
			(fill
				(thermal_gap 0.5)
				(thermal_bridge_width 0.5)
				(island_removal_mode 0)
			)
			(polygon
				(pts
					(arc
						(start 389.164068 -108.573062)
						(mid 389.145755 -108.65485)
						(end 389.164068 -108.736638)
					)
					(arc
						(start 389.092186 -108.80852)
						(mid 389.048037 -108.65485)
						(end 389.092186 -108.50118)
					)
				)
			)
		)
		(zone
			(layer "F.Cu")
			(hatch none 0.5)
			(connect_pads
				(clearance 0)
			)
			(min_thickness 0.25)
			(keepout
				(tracks not_allowed)
				(vias allowed)
				(pads allowed)
				(copperpour not_allowed)
				(footprints allowed)
			)
			(placement
				(enabled no)
				(sheetname "")
			)
			(fill
				(thermal_gap 0.5)
				(thermal_bridge_width 0.5)
				(island_removal_mode 0)
			)
			(polygon
				(pts
					(arc
						(start 389.164068 -107.772962)
						(mid 389.145755 -107.85475)
						(end 389.164068 -107.936538)
					)
					(arc
						(start 389.092186 -108.00842)
						(mid 389.048037 -107.85475)
						(end 389.092186 -107.70108)
					)
				)
			)
		)
		(zone
			(layer "F.Cu")
			(hatch none 0.5)
			(connect_pads
				(clearance 0)
			)
			(min_thickness 0.25)
			(keepout
				(tracks not_allowed)
				(vias allowed)
				(pads allowed)
				(copperpour not_allowed)
				(footprints allowed)
			)
			(placement
				(enabled no)
				(sheetname "")
			)
			(fill
				(thermal_gap 0.5)
				(thermal_bridge_width 0.5)
				(island_removal_mode 0)
			)
			(polygon
				(pts
					(arc
						(start 389.164068 -106.172762)
						(mid 389.145755 -106.25455)
						(end 389.164068 -106.336338)
					)
					(arc
						(start 389.092186 -106.40822)
						(mid 389.048037 -106.25455)
						(end 389.092186 -106.10088)
					)
				)
			)
		)
		(zone
			(layer "F.Cu")
			(hatch none 0.5)
			(connect_pads
				(clearance 0)
			)
			(min_thickness 0.25)
			(keepout
				(tracks not_allowed)
				(vias allowed)
				(pads allowed)
				(copperpour not_allowed)
				(footprints allowed)
			)
			(placement
				(enabled no)
				(sheetname "")
			)
			(fill
				(thermal_gap 0.5)
				(thermal_bridge_width 0.5)
				(island_removal_mode 0)
			)
			(polygon
				(pts
					(arc
						(start 389.164068 -105.372662)
						(mid 389.145755 -105.45445)
						(end 389.164068 -105.536238)
					)
					(arc
						(start 389.092186 -105.60812)
						(mid 389.048037 -105.45445)
						(end 389.092186 -105.30078)
					)
				)
			)
		)
		(zone
			(layer "F.Cu")
			(hatch none 0.5)
			(connect_pads
				(clearance 0)
			)
			(min_thickness 0.25)
			(keepout
				(tracks not_allowed)
				(vias allowed)
				(pads allowed)
				(copperpour not_allowed)
				(footprints allowed)
			)
			(placement
				(enabled no)
				(sheetname "")
			)
			(fill
				(thermal_gap 0.5)
				(thermal_bridge_width 0.5)
				(island_removal_mode 0)
			)
			(polygon
				(pts
					(arc
						(start 389.164068 -104.572562)
						(mid 389.145755 -104.65435)
						(end 389.164068 -104.736138)
					)
					(arc
						(start 389.092186 -104.80802)
						(mid 389.048037 -104.65435)
						(end 389.092186 -104.50068)
					)
				)
			)
		)
		(zone
			(layer "F.Cu")
			(hatch none 0.5)
			(connect_pads
				(clearance 0)
			)
			(min_thickness 0.25)
			(keepout
				(tracks not_allowed)
				(vias allowed)
				(pads allowed)
				(copperpour not_allowed)
				(footprints allowed)
			)
			(placement
				(enabled no)
				(sheetname "")
			)
			(fill
				(thermal_gap 0.5)
				(thermal_bridge_width 0.5)
				(island_removal_mode 0)
			)
			(polygon
				(pts
					(arc
						(start 389.255762 -114.429032)
						(mid 389.33755 -114.447345)
						(end 389.419338 -114.429032)
					)
					(arc
						(start 389.49122 -114.500914)
						(mid 389.33755 -114.545063)
						(end 389.18388 -114.500914)
					)
				)
			)
		)
		(zone
			(layer "F.Cu")
			(hatch none 0.5)
			(connect_pads
				(clearance 0)
			)
			(min_thickness 0.25)
			(keepout
				(tracks not_allowed)
				(vias allowed)
				(pads allowed)
				(copperpour not_allowed)
				(footprints allowed)
			)
			(placement
				(enabled no)
				(sheetname "")
			)
			(fill
				(thermal_gap 0.5)
				(thermal_bridge_width 0.5)
				(island_removal_mode 0)
			)
			(polygon
				(pts
					(arc
						(start 389.255762 -113.628932)
						(mid 389.33755 -113.647245)
						(end 389.419338 -113.628932)
					)
					(arc
						(start 389.49122 -113.700814)
						(mid 389.33755 -113.744963)
						(end 389.18388 -113.700814)
					)
				)
			)
		)
		(zone
			(layer "F.Cu")
			(hatch none 0.5)
			(connect_pads
				(clearance 0)
			)
			(min_thickness 0.25)
			(keepout
				(tracks not_allowed)
				(vias allowed)
				(pads allowed)
				(copperpour not_allowed)
				(footprints allowed)
			)
			(placement
				(enabled no)
				(sheetname "")
			)
			(fill
				(thermal_gap 0.5)
				(thermal_bridge_width 0.5)
				(island_removal_mode 0)
			)
			(polygon
				(pts
					(arc
						(start 389.255762 -112.828832)
						(mid 389.33755 -112.847145)
						(end 389.419338 -112.828832)
					)
					(arc
						(start 389.49122 -112.900714)
						(mid 389.33755 -112.944863)
						(end 389.18388 -112.900714)
					)
				)
			)
		)
		(zone
			(layer "F.Cu")
			(hatch none 0.5)
			(connect_pads
				(clearance 0)
			)
			(min_thickness 0.25)
			(keepout
				(tracks not_allowed)
				(vias allowed)
				(pads allowed)
				(copperpour not_allowed)
				(footprints allowed)
			)
			(placement
				(enabled no)
				(sheetname "")
			)
			(fill
				(thermal_gap 0.5)
				(thermal_bridge_width 0.5)
				(island_removal_mode 0)
			)
			(polygon
				(pts
					(arc
						(start 389.255762 -112.028732)
						(mid 389.33755 -112.047045)
						(end 389.419338 -112.028732)
					)
					(arc
						(start 389.49122 -112.100614)
						(mid 389.33755 -112.144763)
						(end 389.18388 -112.100614)
					)
				)
			)
		)
		(zone
			(layer "F.Cu")
			(hatch none 0.5)
			(connect_pads
				(clearance 0)
			)
			(min_thickness 0.25)
			(keepout
				(tracks not_allowed)
				(vias allowed)
				(pads allowed)
				(copperpour not_allowed)
				(footprints allowed)
			)
			(placement
				(enabled no)
				(sheetname "")
			)
			(fill
				(thermal_gap 0.5)
				(thermal_bridge_width 0.5)
				(island_removal_mode 0)
			)
			(polygon
				(pts
					(arc
						(start 389.255762 -111.228632)
						(mid 389.33755 -111.246945)
						(end 389.419338 -111.228632)
					)
					(arc
						(start 389.49122 -111.300514)
						(mid 389.33755 -111.344663)
						(end 389.18388 -111.300514)
					)
				)
			)
		)
		(zone
			(layer "F.Cu")
			(hatch none 0.5)
			(connect_pads
				(clearance 0)
			)
			(min_thickness 0.25)
			(keepout
				(tracks not_allowed)
				(vias allowed)
				(pads allowed)
				(copperpour not_allowed)
				(footprints allowed)
			)
			(placement
				(enabled no)
				(sheetname "")
			)
			(fill
				(thermal_gap 0.5)
				(thermal_bridge_width 0.5)
				(island_removal_mode 0)
			)
			(polygon
				(pts
					(arc
						(start 389.255762 -110.428532)
						(mid 389.33755 -110.446845)
						(end 389.419338 -110.428532)
					)
					(arc
						(start 389.49122 -110.500414)
						(mid 389.33755 -110.544563)
						(end 389.18388 -110.500414)
					)
				)
			)
		)
		(zone
			(layer "F.Cu")
			(hatch none 0.5)
			(connect_pads
				(clearance 0)
			)
			(min_thickness 0.25)
			(keepout
				(tracks not_allowed)
				(vias allowed)
				(pads allowed)
				(copperpour not_allowed)
				(footprints allowed)
			)
			(placement
				(enabled no)
				(sheetname "")
			)
			(fill
				(thermal_gap 0.5)
				(thermal_bridge_width 0.5)
				(island_removal_mode 0)
			)
			(polygon
				(pts
					(arc
						(start 389.255762 -109.628432)
						(mid 389.33755 -109.646745)
						(end 389.419338 -109.628432)
					)
					(arc
						(start 389.49122 -109.700314)
						(mid 389.33755 -109.744463)
						(end 389.18388 -109.700314)
					)
				)
			)
		)
		(zone
			(layer "F.Cu")
			(hatch none 0.5)
			(connect_pads
				(clearance 0)
			)
			(min_thickness 0.25)
			(keepout
				(tracks not_allowed)
				(vias allowed)
				(pads allowed)
				(copperpour not_allowed)
				(footprints allowed)
			)
			(placement
				(enabled no)
				(sheetname "")
			)
			(fill
				(thermal_gap 0.5)
				(thermal_bridge_width 0.5)
				(island_removal_mode 0)
			)
			(polygon
				(pts
					(arc
						(start 389.255762 -108.828332)
						(mid 389.33755 -108.846645)
						(end 389.419338 -108.828332)
					)
					(arc
						(start 389.49122 -108.900214)
						(mid 389.33755 -108.944363)
						(end 389.18388 -108.900214)
					)
				)
			)
		)
		(zone
			(layer "F.Cu")
			(hatch none 0.5)
			(connect_pads
				(clearance 0)
			)
			(min_thickness 0.25)
			(keepout
				(tracks not_allowed)
				(vias allowed)
				(pads allowed)
				(copperpour not_allowed)
				(footprints allowed)
			)
			(placement
				(enabled no)
				(sheetname "")
			)
			(fill
				(thermal_gap 0.5)
				(thermal_bridge_width 0.5)
				(island_removal_mode 0)
			)
			(polygon
				(pts
					(arc
						(start 389.255762 -108.028232)
						(mid 389.33755 -108.046545)
						(end 389.419338 -108.028232)
					)
					(arc
						(start 389.49122 -108.100114)
						(mid 389.33755 -108.144263)
						(end 389.18388 -108.100114)
					)
				)
			)
		)
		(zone
			(layer "F.Cu")
			(hatch none 0.5)
			(connect_pads
				(clearance 0)
			)
			(min_thickness 0.25)
			(keepout
				(tracks not_allowed)
				(vias allowed)
				(pads allowed)
				(copperpour not_allowed)
				(footprints allowed)
			)
			(placement
				(enabled no)
				(sheetname "")
			)
			(fill
				(thermal_gap 0.5)
				(thermal_bridge_width 0.5)
				(island_removal_mode 0)
			)
			(polygon
				(pts
					(arc
						(start 389.255762 -106.428032)
						(mid 389.33755 -106.446345)
						(end 389.419338 -106.428032)
					)
					(arc
						(start 389.49122 -106.499914)
						(mid 389.33755 -106.544063)
						(end 389.18388 -106.499914)
					)
				)
			)
		)
		(zone
			(layer "F.Cu")
			(hatch none 0.5)
			(connect_pads
				(clearance 0)
			)
			(min_thickness 0.25)
			(keepout
				(tracks not_allowed)
				(vias allowed)
				(pads allowed)
				(copperpour not_allowed)
				(footprints allowed)
			)
			(placement
				(enabled no)
				(sheetname "")
			)
			(fill
				(thermal_gap 0.5)
				(thermal_bridge_width 0.5)
				(island_removal_mode 0)
			)
			(polygon
				(pts
					(arc
						(start 389.255762 -105.627932)
						(mid 389.33755 -105.646245)
						(end 389.419338 -105.627932)
					)
					(arc
						(start 389.49122 -105.699814)
						(mid 389.33755 -105.743963)
						(end 389.18388 -105.699814)
					)
				)
			)
		)
		(zone
			(layer "F.Cu")
			(hatch none 0.5)
			(connect_pads
				(clearance 0)
			)
			(min_thickness 0.25)
			(keepout
				(tracks not_allowed)
				(vias allowed)
				(pads allowed)
				(copperpour not_allowed)
				(footprints allowed)
			)
			(placement
				(enabled no)
				(sheetname "")
			)
			(fill
				(thermal_gap 0.5)
				(thermal_bridge_width 0.5)
				(island_removal_mode 0)
			)
			(polygon
				(pts
					(arc
						(start 389.255762 -104.827832)
						(mid 389.33755 -104.846145)
						(end 389.419338 -104.827832)
					)
					(arc
						(start 389.49122 -104.899714)
						(mid 389.33755 -104.943863)
						(end 389.18388 -104.899714)
					)
				)
			)
		)
		(zone
			(layer "F.Cu")
			(hatch none 0.5)
			(connect_pads
				(clearance 0)
			)
			(min_thickness 0.25)
			(keepout
				(tracks not_allowed)
				(vias allowed)
				(pads allowed)
				(copperpour not_allowed)
				(footprints allowed)
			)
			(placement
				(enabled no)
				(sheetname "")
			)
			(fill
				(thermal_gap 0.5)
				(thermal_bridge_width 0.5)
				(island_removal_mode 0)
			)
			(polygon
				(pts
					(arc
						(start 389.419338 -114.082068)
						(mid 389.33755 -114.063755)
						(end 389.255762 -114.082068)
					)
					(arc
						(start 389.18388 -114.010186)
						(mid 389.33755 -113.966037)
						(end 389.49122 -114.010186)
					)
				)
			)
		)
		(zone
			(layer "F.Cu")
			(hatch none 0.5)
			(connect_pads
				(clearance 0)
			)
			(min_thickness 0.25)
			(keepout
				(tracks not_allowed)
				(vias allowed)
				(pads allowed)
				(copperpour not_allowed)
				(footprints allowed)
			)
			(placement
				(enabled no)
				(sheetname "")
			)
			(fill
				(thermal_gap 0.5)
				(thermal_bridge_width 0.5)
				(island_removal_mode 0)
			)
			(polygon
				(pts
					(arc
						(start 389.419338 -113.281968)
						(mid 389.33755 -113.263655)
						(end 389.255762 -113.281968)
					)
					(arc
						(start 389.18388 -113.210086)
						(mid 389.33755 -113.165937)
						(end 389.49122 -113.210086)
					)
				)
			)
		)
		(zone
			(layer "F.Cu")
			(hatch none 0.5)
			(connect_pads
				(clearance 0)
			)
			(min_thickness 0.25)
			(keepout
				(tracks not_allowed)
				(vias allowed)
				(pads allowed)
				(copperpour not_allowed)
				(footprints allowed)
			)
			(placement
				(enabled no)
				(sheetname "")
			)
			(fill
				(thermal_gap 0.5)
				(thermal_bridge_width 0.5)
				(island_removal_mode 0)
			)
			(polygon
				(pts
					(arc
						(start 389.419338 -112.481868)
						(mid 389.33755 -112.463555)
						(end 389.255762 -112.481868)
					)
					(arc
						(start 389.18388 -112.409986)
						(mid 389.33755 -112.365837)
						(end 389.49122 -112.409986)
					)
				)
			)
		)
		(zone
			(layer "F.Cu")
			(hatch none 0.5)
			(connect_pads
				(clearance 0)
			)
			(min_thickness 0.25)
			(keepout
				(tracks not_allowed)
				(vias allowed)
				(pads allowed)
				(copperpour not_allowed)
				(footprints allowed)
			)
			(placement
				(enabled no)
				(sheetname "")
			)
			(fill
				(thermal_gap 0.5)
				(thermal_bridge_width 0.5)
				(island_removal_mode 0)
			)
			(polygon
				(pts
					(arc
						(start 389.419338 -111.681768)
						(mid 389.33755 -111.663455)
						(end 389.255762 -111.681768)
					)
					(arc
						(start 389.18388 -111.609886)
						(mid 389.33755 -111.565737)
						(end 389.49122 -111.609886)
					)
				)
			)
		)
		(zone
			(layer "F.Cu")
			(hatch none 0.5)
			(connect_pads
				(clearance 0)
			)
			(min_thickness 0.25)
			(keepout
				(tracks not_allowed)
				(vias allowed)
				(pads allowed)
				(copperpour not_allowed)
				(footprints allowed)
			)
			(placement
				(enabled no)
				(sheetname "")
			)
			(fill
				(thermal_gap 0.5)
				(thermal_bridge_width 0.5)
				(island_removal_mode 0)
			)
			(polygon
				(pts
					(arc
						(start 389.419338 -110.881668)
						(mid 389.33755 -110.863355)
						(end 389.255762 -110.881668)
					)
					(arc
						(start 389.18388 -110.809786)
						(mid 389.33755 -110.765637)
						(end 389.49122 -110.809786)
					)
				)
			)
		)
		(zone
			(layer "F.Cu")
			(hatch none 0.5)
			(connect_pads
				(clearance 0)
			)
			(min_thickness 0.25)
			(keepout
				(tracks not_allowed)
				(vias allowed)
				(pads allowed)
				(copperpour not_allowed)
				(footprints allowed)
			)
			(placement
				(enabled no)
				(sheetname "")
			)
			(fill
				(thermal_gap 0.5)
				(thermal_bridge_width 0.5)
				(island_removal_mode 0)
			)
			(polygon
				(pts
					(arc
						(start 389.419338 -110.081568)
						(mid 389.33755 -110.063255)
						(end 389.255762 -110.081568)
					)
					(arc
						(start 389.18388 -110.009686)
						(mid 389.33755 -109.965537)
						(end 389.49122 -110.009686)
					)
				)
			)
		)
		(zone
			(layer "F.Cu")
			(hatch none 0.5)
			(connect_pads
				(clearance 0)
			)
			(min_thickness 0.25)
			(keepout
				(tracks not_allowed)
				(vias allowed)
				(pads allowed)
				(copperpour not_allowed)
				(footprints allowed)
			)
			(placement
				(enabled no)
				(sheetname "")
			)
			(fill
				(thermal_gap 0.5)
				(thermal_bridge_width 0.5)
				(island_removal_mode 0)
			)
			(polygon
				(pts
					(arc
						(start 389.419338 -109.281468)
						(mid 389.33755 -109.263155)
						(end 389.255762 -109.281468)
					)
					(arc
						(start 389.18388 -109.209586)
						(mid 389.33755 -109.165437)
						(end 389.49122 -109.209586)
					)
				)
			)
		)
		(zone
			(layer "F.Cu")
			(hatch none 0.5)
			(connect_pads
				(clearance 0)
			)
			(min_thickness 0.25)
			(keepout
				(tracks not_allowed)
				(vias allowed)
				(pads allowed)
				(copperpour not_allowed)
				(footprints allowed)
			)
			(placement
				(enabled no)
				(sheetname "")
			)
			(fill
				(thermal_gap 0.5)
				(thermal_bridge_width 0.5)
				(island_removal_mode 0)
			)
			(polygon
				(pts
					(arc
						(start 389.419338 -108.481368)
						(mid 389.33755 -108.463055)
						(end 389.255762 -108.481368)
					)
					(arc
						(start 389.18388 -108.409486)
						(mid 389.33755 -108.365337)
						(end 389.49122 -108.409486)
					)
				)
			)
		)
		(zone
			(layer "F.Cu")
			(hatch none 0.5)
			(connect_pads
				(clearance 0)
			)
			(min_thickness 0.25)
			(keepout
				(tracks not_allowed)
				(vias allowed)
				(pads allowed)
				(copperpour not_allowed)
				(footprints allowed)
			)
			(placement
				(enabled no)
				(sheetname "")
			)
			(fill
				(thermal_gap 0.5)
				(thermal_bridge_width 0.5)
				(island_removal_mode 0)
			)
			(polygon
				(pts
					(arc
						(start 389.419338 -107.681268)
						(mid 389.33755 -107.662955)
						(end 389.255762 -107.681268)
					)
					(arc
						(start 389.18388 -107.609386)
						(mid 389.33755 -107.565237)
						(end 389.49122 -107.609386)
					)
				)
			)
		)
		(zone
			(layer "F.Cu")
			(hatch none 0.5)
			(connect_pads
				(clearance 0)
			)
			(min_thickness 0.25)
			(keepout
				(tracks not_allowed)
				(vias allowed)
				(pads allowed)
				(copperpour not_allowed)
				(footprints allowed)
			)
			(placement
				(enabled no)
				(sheetname "")
			)
			(fill
				(thermal_gap 0.5)
				(thermal_bridge_width 0.5)
				(island_removal_mode 0)
			)
			(polygon
				(pts
					(arc
						(start 389.419338 -106.081068)
						(mid 389.33755 -106.062755)
						(end 389.255762 -106.081068)
					)
					(arc
						(start 389.18388 -106.009186)
						(mid 389.33755 -105.965037)
						(end 389.49122 -106.009186)
					)
				)
			)
		)
		(zone
			(layer "F.Cu")
			(hatch none 0.5)
			(connect_pads
				(clearance 0)
			)
			(min_thickness 0.25)
			(keepout
				(tracks not_allowed)
				(vias allowed)
				(pads allowed)
				(copperpour not_allowed)
				(footprints allowed)
			)
			(placement
				(enabled no)
				(sheetname "")
			)
			(fill
				(thermal_gap 0.5)
				(thermal_bridge_width 0.5)
				(island_removal_mode 0)
			)
			(polygon
				(pts
					(arc
						(start 389.419338 -105.280968)
						(mid 389.33755 -105.262655)
						(end 389.255762 -105.280968)
					)
					(arc
						(start 389.18388 -105.209086)
						(mid 389.33755 -105.164937)
						(end 389.49122 -105.209086)
					)
				)
			)
		)
		(zone
			(layer "F.Cu")
			(hatch none 0.5)
			(connect_pads
				(clearance 0)
			)
			(min_thickness 0.25)
			(keepout
				(tracks not_allowed)
				(vias allowed)
				(pads allowed)
				(copperpour not_allowed)
				(footprints allowed)
			)
			(placement
				(enabled no)
				(sheetname "")
			)
			(fill
				(thermal_gap 0.5)
				(thermal_bridge_width 0.5)
				(island_removal_mode 0)
			)
			(polygon
				(pts
					(arc
						(start 389.419338 -104.480868)
						(mid 389.33755 -104.462555)
						(end 389.255762 -104.480868)
					)
					(arc
						(start 389.18388 -104.408986)
						(mid 389.33755 -104.364837)
						(end 389.49122 -104.408986)
					)
				)
			)
		)
		(zone
			(layer "F.Cu")
			(hatch none 0.5)
			(connect_pads
				(clearance 0)
			)
			(min_thickness 0.25)
			(keepout
				(tracks not_allowed)
				(vias allowed)
				(pads allowed)
				(copperpour not_allowed)
				(footprints allowed)
			)
			(placement
				(enabled no)
				(sheetname "")
			)
			(fill
				(thermal_gap 0.5)
				(thermal_bridge_width 0.5)
				(island_removal_mode 0)
			)
			(polygon
				(pts
					(arc
						(start 389.511032 -114.337338)
						(mid 389.529345 -114.25555)
						(end 389.511032 -114.173762)
					)
					(arc
						(start 389.582914 -114.10188)
						(mid 389.627063 -114.25555)
						(end 389.582914 -114.40922)
					)
				)
			)
		)
		(zone
			(layer "F.Cu")
			(hatch none 0.5)
			(connect_pads
				(clearance 0)
			)
			(min_thickness 0.25)
			(keepout
				(tracks not_allowed)
				(vias allowed)
				(pads allowed)
				(copperpour not_allowed)
				(footprints allowed)
			)
			(placement
				(enabled no)
				(sheetname "")
			)
			(fill
				(thermal_gap 0.5)
				(thermal_bridge_width 0.5)
				(island_removal_mode 0)
			)
			(polygon
				(pts
					(arc
						(start 389.511032 -113.537238)
						(mid 389.529345 -113.45545)
						(end 389.511032 -113.373662)
					)
					(arc
						(start 389.582914 -113.30178)
						(mid 389.627063 -113.45545)
						(end 389.582914 -113.60912)
					)
				)
			)
		)
		(zone
			(layer "F.Cu")
			(hatch none 0.5)
			(connect_pads
				(clearance 0)
			)
			(min_thickness 0.25)
			(keepout
				(tracks not_allowed)
				(vias allowed)
				(pads allowed)
				(copperpour not_allowed)
				(footprints allowed)
			)
			(placement
				(enabled no)
				(sheetname "")
			)
			(fill
				(thermal_gap 0.5)
				(thermal_bridge_width 0.5)
				(island_removal_mode 0)
			)
			(polygon
				(pts
					(arc
						(start 389.511032 -112.737138)
						(mid 389.529345 -112.65535)
						(end 389.511032 -112.573562)
					)
					(arc
						(start 389.582914 -112.50168)
						(mid 389.627063 -112.65535)
						(end 389.582914 -112.80902)
					)
				)
			)
		)
		(zone
			(layer "F.Cu")
			(hatch none 0.5)
			(connect_pads
				(clearance 0)
			)
			(min_thickness 0.25)
			(keepout
				(tracks not_allowed)
				(vias allowed)
				(pads allowed)
				(copperpour not_allowed)
				(footprints allowed)
			)
			(placement
				(enabled no)
				(sheetname "")
			)
			(fill
				(thermal_gap 0.5)
				(thermal_bridge_width 0.5)
				(island_removal_mode 0)
			)
			(polygon
				(pts
					(arc
						(start 389.511032 -111.937038)
						(mid 389.529345 -111.85525)
						(end 389.511032 -111.773462)
					)
					(arc
						(start 389.582914 -111.70158)
						(mid 389.627063 -111.85525)
						(end 389.582914 -112.00892)
					)
				)
			)
		)
		(zone
			(layer "F.Cu")
			(hatch none 0.5)
			(connect_pads
				(clearance 0)
			)
			(min_thickness 0.25)
			(keepout
				(tracks not_allowed)
				(vias allowed)
				(pads allowed)
				(copperpour not_allowed)
				(footprints allowed)
			)
			(placement
				(enabled no)
				(sheetname "")
			)
			(fill
				(thermal_gap 0.5)
				(thermal_bridge_width 0.5)
				(island_removal_mode 0)
			)
			(polygon
				(pts
					(arc
						(start 389.511032 -111.136938)
						(mid 389.529345 -111.05515)
						(end 389.511032 -110.973362)
					)
					(arc
						(start 389.582914 -110.90148)
						(mid 389.627063 -111.05515)
						(end 389.582914 -111.20882)
					)
				)
			)
		)
		(zone
			(layer "F.Cu")
			(hatch none 0.5)
			(connect_pads
				(clearance 0)
			)
			(min_thickness 0.25)
			(keepout
				(tracks not_allowed)
				(vias allowed)
				(pads allowed)
				(copperpour not_allowed)
				(footprints allowed)
			)
			(placement
				(enabled no)
				(sheetname "")
			)
			(fill
				(thermal_gap 0.5)
				(thermal_bridge_width 0.5)
				(island_removal_mode 0)
			)
			(polygon
				(pts
					(arc
						(start 389.511032 -110.336838)
						(mid 389.529345 -110.25505)
						(end 389.511032 -110.173262)
					)
					(arc
						(start 389.582914 -110.10138)
						(mid 389.627063 -110.25505)
						(end 389.582914 -110.40872)
					)
				)
			)
		)
		(zone
			(layer "F.Cu")
			(hatch none 0.5)
			(connect_pads
				(clearance 0)
			)
			(min_thickness 0.25)
			(keepout
				(tracks not_allowed)
				(vias allowed)
				(pads allowed)
				(copperpour not_allowed)
				(footprints allowed)
			)
			(placement
				(enabled no)
				(sheetname "")
			)
			(fill
				(thermal_gap 0.5)
				(thermal_bridge_width 0.5)
				(island_removal_mode 0)
			)
			(polygon
				(pts
					(arc
						(start 389.511032 -109.536738)
						(mid 389.529345 -109.45495)
						(end 389.511032 -109.373162)
					)
					(arc
						(start 389.582914 -109.30128)
						(mid 389.627063 -109.45495)
						(end 389.582914 -109.60862)
					)
				)
			)
		)
		(zone
			(layer "F.Cu")
			(hatch none 0.5)
			(connect_pads
				(clearance 0)
			)
			(min_thickness 0.25)
			(keepout
				(tracks not_allowed)
				(vias allowed)
				(pads allowed)
				(copperpour not_allowed)
				(footprints allowed)
			)
			(placement
				(enabled no)
				(sheetname "")
			)
			(fill
				(thermal_gap 0.5)
				(thermal_bridge_width 0.5)
				(island_removal_mode 0)
			)
			(polygon
				(pts
					(arc
						(start 389.511032 -108.736638)
						(mid 389.529345 -108.65485)
						(end 389.511032 -108.573062)
					)
					(arc
						(start 389.582914 -108.50118)
						(mid 389.627063 -108.65485)
						(end 389.582914 -108.80852)
					)
				)
			)
		)
		(zone
			(layer "F.Cu")
			(hatch none 0.5)
			(connect_pads
				(clearance 0)
			)
			(min_thickness 0.25)
			(keepout
				(tracks not_allowed)
				(vias allowed)
				(pads allowed)
				(copperpour not_allowed)
				(footprints allowed)
			)
			(placement
				(enabled no)
				(sheetname "")
			)
			(fill
				(thermal_gap 0.5)
				(thermal_bridge_width 0.5)
				(island_removal_mode 0)
			)
			(polygon
				(pts
					(arc
						(start 389.511032 -107.936538)
						(mid 389.529345 -107.85475)
						(end 389.511032 -107.772962)
					)
					(arc
						(start 389.582914 -107.70108)
						(mid 389.627063 -107.85475)
						(end 389.582914 -108.00842)
					)
				)
			)
		)
		(zone
			(layer "F.Cu")
			(hatch none 0.5)
			(connect_pads
				(clearance 0)
			)
			(min_thickness 0.25)
			(keepout
				(tracks not_allowed)
				(vias allowed)
				(pads allowed)
				(copperpour not_allowed)
				(footprints allowed)
			)
			(placement
				(enabled no)
				(sheetname "")
			)
			(fill
				(thermal_gap 0.5)
				(thermal_bridge_width 0.5)
				(island_removal_mode 0)
			)
			(polygon
				(pts
					(arc
						(start 389.511032 -106.336338)
						(mid 389.529345 -106.25455)
						(end 389.511032 -106.172762)
					)
					(arc
						(start 389.582914 -106.10088)
						(mid 389.627063 -106.25455)
						(end 389.582914 -106.40822)
					)
				)
			)
		)
		(zone
			(layer "F.Cu")
			(hatch none 0.5)
			(connect_pads
				(clearance 0)
			)
			(min_thickness 0.25)
			(keepout
				(tracks not_allowed)
				(vias allowed)
				(pads allowed)
				(copperpour not_allowed)
				(footprints allowed)
			)
			(placement
				(enabled no)
				(sheetname "")
			)
			(fill
				(thermal_gap 0.5)
				(thermal_bridge_width 0.5)
				(island_removal_mode 0)
			)
			(polygon
				(pts
					(arc
						(start 389.511032 -105.536238)
						(mid 389.529345 -105.45445)
						(end 389.511032 -105.372662)
					)
					(arc
						(start 389.582914 -105.30078)
						(mid 389.627063 -105.45445)
						(end 389.582914 -105.60812)
					)
				)
			)
		)
		(zone
			(layer "F.Cu")
			(hatch none 0.5)
			(connect_pads
				(clearance 0)
			)
			(min_thickness 0.25)
			(keepout
				(tracks not_allowed)
				(vias allowed)
				(pads allowed)
				(copperpour not_allowed)
				(footprints allowed)
			)
			(placement
				(enabled no)
				(sheetname "")
			)
			(fill
				(thermal_gap 0.5)
				(thermal_bridge_width 0.5)
				(island_removal_mode 0)
			)
			(polygon
				(pts
					(arc
						(start 389.511032 -104.736138)
						(mid 389.529345 -104.65435)
						(end 389.511032 -104.572562)
					)
					(arc
						(start 389.582914 -104.50068)
						(mid 389.627063 -104.65435)
						(end 389.582914 -104.80802)
					)
				)
			)
		)
		(zone
			(layer "F.Cu")
			(hatch none 0.5)
			(connect_pads
				(clearance 0)
			)
			(min_thickness 0.25)
			(keepout
				(tracks not_allowed)
				(vias allowed)
				(pads allowed)
				(copperpour not_allowed)
				(footprints allowed)
			)
			(placement
				(enabled no)
				(sheetname "")
			)
			(fill
				(thermal_gap 0.5)
				(thermal_bridge_width 0.5)
				(island_removal_mode 0)
			)
			(polygon
				(pts
					(arc
						(start 389.964168 -114.173762)
						(mid 389.945855 -114.25555)
						(end 389.964168 -114.337338)
					)
					(arc
						(start 389.892286 -114.40922)
						(mid 389.848137 -114.25555)
						(end 389.892286 -114.10188)
					)
				)
			)
		)
		(zone
			(layer "F.Cu")
			(hatch none 0.5)
			(connect_pads
				(clearance 0)
			)
			(min_thickness 0.25)
			(keepout
				(tracks not_allowed)
				(vias allowed)
				(pads allowed)
				(copperpour not_allowed)
				(footprints allowed)
			)
			(placement
				(enabled no)
				(sheetname "")
			)
			(fill
				(thermal_gap 0.5)
				(thermal_bridge_width 0.5)
				(island_removal_mode 0)
			)
			(polygon
				(pts
					(arc
						(start 389.964168 -113.373662)
						(mid 389.945855 -113.45545)
						(end 389.964168 -113.537238)
					)
					(arc
						(start 389.892286 -113.60912)
						(mid 389.848137 -113.45545)
						(end 389.892286 -113.30178)
					)
				)
			)
		)
		(zone
			(layer "F.Cu")
			(hatch none 0.5)
			(connect_pads
				(clearance 0)
			)
			(min_thickness 0.25)
			(keepout
				(tracks not_allowed)
				(vias allowed)
				(pads allowed)
				(copperpour not_allowed)
				(footprints allowed)
			)
			(placement
				(enabled no)
				(sheetname "")
			)
			(fill
				(thermal_gap 0.5)
				(thermal_bridge_width 0.5)
				(island_removal_mode 0)
			)
			(polygon
				(pts
					(arc
						(start 389.964168 -112.573562)
						(mid 389.945855 -112.65535)
						(end 389.964168 -112.737138)
					)
					(arc
						(start 389.892286 -112.80902)
						(mid 389.848137 -112.65535)
						(end 389.892286 -112.50168)
					)
				)
			)
		)
		(zone
			(layer "F.Cu")
			(hatch none 0.5)
			(connect_pads
				(clearance 0)
			)
			(min_thickness 0.25)
			(keepout
				(tracks not_allowed)
				(vias allowed)
				(pads allowed)
				(copperpour not_allowed)
				(footprints allowed)
			)
			(placement
				(enabled no)
				(sheetname "")
			)
			(fill
				(thermal_gap 0.5)
				(thermal_bridge_width 0.5)
				(island_removal_mode 0)
			)
			(polygon
				(pts
					(arc
						(start 389.964168 -111.773462)
						(mid 389.945855 -111.85525)
						(end 389.964168 -111.937038)
					)
					(arc
						(start 389.892286 -112.00892)
						(mid 389.848137 -111.85525)
						(end 389.892286 -111.70158)
					)
				)
			)
		)
		(zone
			(layer "F.Cu")
			(hatch none 0.5)
			(connect_pads
				(clearance 0)
			)
			(min_thickness 0.25)
			(keepout
				(tracks not_allowed)
				(vias allowed)
				(pads allowed)
				(copperpour not_allowed)
				(footprints allowed)
			)
			(placement
				(enabled no)
				(sheetname "")
			)
			(fill
				(thermal_gap 0.5)
				(thermal_bridge_width 0.5)
				(island_removal_mode 0)
			)
			(polygon
				(pts
					(arc
						(start 389.964168 -110.973362)
						(mid 389.945855 -111.05515)
						(end 389.964168 -111.136938)
					)
					(arc
						(start 389.892286 -111.20882)
						(mid 389.848137 -111.05515)
						(end 389.892286 -110.90148)
					)
				)
			)
		)
		(zone
			(layer "F.Cu")
			(hatch none 0.5)
			(connect_pads
				(clearance 0)
			)
			(min_thickness 0.25)
			(keepout
				(tracks not_allowed)
				(vias allowed)
				(pads allowed)
				(copperpour not_allowed)
				(footprints allowed)
			)
			(placement
				(enabled no)
				(sheetname "")
			)
			(fill
				(thermal_gap 0.5)
				(thermal_bridge_width 0.5)
				(island_removal_mode 0)
			)
			(polygon
				(pts
					(arc
						(start 389.964168 -109.373162)
						(mid 389.945855 -109.45495)
						(end 389.964168 -109.536738)
					)
					(arc
						(start 389.892286 -109.60862)
						(mid 389.848137 -109.45495)
						(end 389.892286 -109.30128)
					)
				)
			)
		)
		(zone
			(layer "F.Cu")
			(hatch none 0.5)
			(connect_pads
				(clearance 0)
			)
			(min_thickness 0.25)
			(keepout
				(tracks not_allowed)
				(vias allowed)
				(pads allowed)
				(copperpour not_allowed)
				(footprints allowed)
			)
			(placement
				(enabled no)
				(sheetname "")
			)
			(fill
				(thermal_gap 0.5)
				(thermal_bridge_width 0.5)
				(island_removal_mode 0)
			)
			(polygon
				(pts
					(arc
						(start 389.964168 -108.573062)
						(mid 389.945855 -108.65485)
						(end 389.964168 -108.736638)
					)
					(arc
						(start 389.892286 -108.80852)
						(mid 389.848137 -108.65485)
						(end 389.892286 -108.50118)
					)
				)
			)
		)
		(zone
			(layer "F.Cu")
			(hatch none 0.5)
			(connect_pads
				(clearance 0)
			)
			(min_thickness 0.25)
			(keepout
				(tracks not_allowed)
				(vias allowed)
				(pads allowed)
				(copperpour not_allowed)
				(footprints allowed)
			)
			(placement
				(enabled no)
				(sheetname "")
			)
			(fill
				(thermal_gap 0.5)
				(thermal_bridge_width 0.5)
				(island_removal_mode 0)
			)
			(polygon
				(pts
					(arc
						(start 389.964168 -107.772962)
						(mid 389.945855 -107.85475)
						(end 389.964168 -107.936538)
					)
					(arc
						(start 389.892286 -108.00842)
						(mid 389.848137 -107.85475)
						(end 389.892286 -107.70108)
					)
				)
			)
		)
		(zone
			(layer "F.Cu")
			(hatch none 0.5)
			(connect_pads
				(clearance 0)
			)
			(min_thickness 0.25)
			(keepout
				(tracks not_allowed)
				(vias allowed)
				(pads allowed)
				(copperpour not_allowed)
				(footprints allowed)
			)
			(placement
				(enabled no)
				(sheetname "")
			)
			(fill
				(thermal_gap 0.5)
				(thermal_bridge_width 0.5)
				(island_removal_mode 0)
			)
			(polygon
				(pts
					(arc
						(start 389.964168 -106.972862)
						(mid 389.945855 -107.05465)
						(end 389.964168 -107.136438)
					)
					(arc
						(start 389.892286 -107.20832)
						(mid 389.848137 -107.05465)
						(end 389.892286 -106.90098)
					)
				)
			)
		)
		(zone
			(layer "F.Cu")
			(hatch none 0.5)
			(connect_pads
				(clearance 0)
			)
			(min_thickness 0.25)
			(keepout
				(tracks not_allowed)
				(vias allowed)
				(pads allowed)
				(copperpour not_allowed)
				(footprints allowed)
			)
			(placement
				(enabled no)
				(sheetname "")
			)
			(fill
				(thermal_gap 0.5)
				(thermal_bridge_width 0.5)
				(island_removal_mode 0)
			)
			(polygon
				(pts
					(arc
						(start 389.964168 -106.172762)
						(mid 389.945855 -106.25455)
						(end 389.964168 -106.336338)
					)
					(arc
						(start 389.892286 -106.40822)
						(mid 389.848137 -106.25455)
						(end 389.892286 -106.10088)
					)
				)
			)
		)
		(zone
			(layer "F.Cu")
			(hatch none 0.5)
			(connect_pads
				(clearance 0)
			)
			(min_thickness 0.25)
			(keepout
				(tracks not_allowed)
				(vias allowed)
				(pads allowed)
				(copperpour not_allowed)
				(footprints allowed)
			)
			(placement
				(enabled no)
				(sheetname "")
			)
			(fill
				(thermal_gap 0.5)
				(thermal_bridge_width 0.5)
				(island_removal_mode 0)
			)
			(polygon
				(pts
					(arc
						(start 389.964168 -105.372662)
						(mid 389.945855 -105.45445)
						(end 389.964168 -105.536238)
					)
					(arc
						(start 389.892286 -105.60812)
						(mid 389.848137 -105.45445)
						(end 389.892286 -105.30078)
					)
				)
			)
		)
		(zone
			(layer "F.Cu")
			(hatch none 0.5)
			(connect_pads
				(clearance 0)
			)
			(min_thickness 0.25)
			(keepout
				(tracks not_allowed)
				(vias allowed)
				(pads allowed)
				(copperpour not_allowed)
				(footprints allowed)
			)
			(placement
				(enabled no)
				(sheetname "")
			)
			(fill
				(thermal_gap 0.5)
				(thermal_bridge_width 0.5)
				(island_removal_mode 0)
			)
			(polygon
				(pts
					(arc
						(start 389.964168 -104.572562)
						(mid 389.945855 -104.65435)
						(end 389.964168 -104.736138)
					)
					(arc
						(start 389.892286 -104.80802)
						(mid 389.848137 -104.65435)
						(end 389.892286 -104.50068)
					)
				)
			)
		)
		(zone
			(layer "F.Cu")
			(hatch none 0.5)
			(connect_pads
				(clearance 0)
			)
			(min_thickness 0.25)
			(keepout
				(tracks not_allowed)
				(vias allowed)
				(pads allowed)
				(copperpour not_allowed)
				(footprints allowed)
			)
			(placement
				(enabled no)
				(sheetname "")
			)
			(fill
				(thermal_gap 0.5)
				(thermal_bridge_width 0.5)
				(island_removal_mode 0)
			)
			(polygon
				(pts
					(arc
						(start 390.055862 -114.429032)
						(mid 390.13765 -114.447345)
						(end 390.219438 -114.429032)
					)
					(arc
						(start 390.29132 -114.500914)
						(mid 390.13765 -114.545063)
						(end 389.98398 -114.500914)
					)
				)
			)
		)
		(zone
			(layer "F.Cu")
			(hatch none 0.5)
			(connect_pads
				(clearance 0)
			)
			(min_thickness 0.25)
			(keepout
				(tracks not_allowed)
				(vias allowed)
				(pads allowed)
				(copperpour not_allowed)
				(footprints allowed)
			)
			(placement
				(enabled no)
				(sheetname "")
			)
			(fill
				(thermal_gap 0.5)
				(thermal_bridge_width 0.5)
				(island_removal_mode 0)
			)
			(polygon
				(pts
					(arc
						(start 390.055862 -113.628932)
						(mid 390.13765 -113.647245)
						(end 390.219438 -113.628932)
					)
					(arc
						(start 390.29132 -113.700814)
						(mid 390.13765 -113.744963)
						(end 389.98398 -113.700814)
					)
				)
			)
		)
		(zone
			(layer "F.Cu")
			(hatch none 0.5)
			(connect_pads
				(clearance 0)
			)
			(min_thickness 0.25)
			(keepout
				(tracks not_allowed)
				(vias allowed)
				(pads allowed)
				(copperpour not_allowed)
				(footprints allowed)
			)
			(placement
				(enabled no)
				(sheetname "")
			)
			(fill
				(thermal_gap 0.5)
				(thermal_bridge_width 0.5)
				(island_removal_mode 0)
			)
			(polygon
				(pts
					(arc
						(start 390.055862 -112.828832)
						(mid 390.13765 -112.847145)
						(end 390.219438 -112.828832)
					)
					(arc
						(start 390.29132 -112.900714)
						(mid 390.13765 -112.944863)
						(end 389.98398 -112.900714)
					)
				)
			)
		)
		(zone
			(layer "F.Cu")
			(hatch none 0.5)
			(connect_pads
				(clearance 0)
			)
			(min_thickness 0.25)
			(keepout
				(tracks not_allowed)
				(vias allowed)
				(pads allowed)
				(copperpour not_allowed)
				(footprints allowed)
			)
			(placement
				(enabled no)
				(sheetname "")
			)
			(fill
				(thermal_gap 0.5)
				(thermal_bridge_width 0.5)
				(island_removal_mode 0)
			)
			(polygon
				(pts
					(arc
						(start 390.055862 -112.028732)
						(mid 390.13765 -112.047045)
						(end 390.219438 -112.028732)
					)
					(arc
						(start 390.29132 -112.100614)
						(mid 390.13765 -112.144763)
						(end 389.98398 -112.100614)
					)
				)
			)
		)
		(zone
			(layer "F.Cu")
			(hatch none 0.5)
			(connect_pads
				(clearance 0)
			)
			(min_thickness 0.25)
			(keepout
				(tracks not_allowed)
				(vias allowed)
				(pads allowed)
				(copperpour not_allowed)
				(footprints allowed)
			)
			(placement
				(enabled no)
				(sheetname "")
			)
			(fill
				(thermal_gap 0.5)
				(thermal_bridge_width 0.5)
				(island_removal_mode 0)
			)
			(polygon
				(pts
					(arc
						(start 390.055862 -111.228632)
						(mid 390.13765 -111.246945)
						(end 390.219438 -111.228632)
					)
					(arc
						(start 390.29132 -111.300514)
						(mid 390.13765 -111.344663)
						(end 389.98398 -111.300514)
					)
				)
			)
		)
		(zone
			(layer "F.Cu")
			(hatch none 0.5)
			(connect_pads
				(clearance 0)
			)
			(min_thickness 0.25)
			(keepout
				(tracks not_allowed)
				(vias allowed)
				(pads allowed)
				(copperpour not_allowed)
				(footprints allowed)
			)
			(placement
				(enabled no)
				(sheetname "")
			)
			(fill
				(thermal_gap 0.5)
				(thermal_bridge_width 0.5)
				(island_removal_mode 0)
			)
			(polygon
				(pts
					(arc
						(start 390.055862 -109.628432)
						(mid 390.13765 -109.646745)
						(end 390.219438 -109.628432)
					)
					(arc
						(start 390.29132 -109.700314)
						(mid 390.13765 -109.744463)
						(end 389.98398 -109.700314)
					)
				)
			)
		)
		(zone
			(layer "F.Cu")
			(hatch none 0.5)
			(connect_pads
				(clearance 0)
			)
			(min_thickness 0.25)
			(keepout
				(tracks not_allowed)
				(vias allowed)
				(pads allowed)
				(copperpour not_allowed)
				(footprints allowed)
			)
			(placement
				(enabled no)
				(sheetname "")
			)
			(fill
				(thermal_gap 0.5)
				(thermal_bridge_width 0.5)
				(island_removal_mode 0)
			)
			(polygon
				(pts
					(arc
						(start 390.055862 -108.828332)
						(mid 390.13765 -108.846645)
						(end 390.219438 -108.828332)
					)
					(arc
						(start 390.29132 -108.900214)
						(mid 390.13765 -108.944363)
						(end 389.98398 -108.900214)
					)
				)
			)
		)
		(zone
			(layer "F.Cu")
			(hatch none 0.5)
			(connect_pads
				(clearance 0)
			)
			(min_thickness 0.25)
			(keepout
				(tracks not_allowed)
				(vias allowed)
				(pads allowed)
				(copperpour not_allowed)
				(footprints allowed)
			)
			(placement
				(enabled no)
				(sheetname "")
			)
			(fill
				(thermal_gap 0.5)
				(thermal_bridge_width 0.5)
				(island_removal_mode 0)
			)
			(polygon
				(pts
					(arc
						(start 390.055862 -108.028232)
						(mid 390.13765 -108.046545)
						(end 390.219438 -108.028232)
					)
					(arc
						(start 390.29132 -108.100114)
						(mid 390.13765 -108.144263)
						(end 389.98398 -108.100114)
					)
				)
			)
		)
		(zone
			(layer "F.Cu")
			(hatch none 0.5)
			(connect_pads
				(clearance 0)
			)
			(min_thickness 0.25)
			(keepout
				(tracks not_allowed)
				(vias allowed)
				(pads allowed)
				(copperpour not_allowed)
				(footprints allowed)
			)
			(placement
				(enabled no)
				(sheetname "")
			)
			(fill
				(thermal_gap 0.5)
				(thermal_bridge_width 0.5)
				(island_removal_mode 0)
			)
			(polygon
				(pts
					(arc
						(start 390.055862 -107.228132)
						(mid 390.13765 -107.246445)
						(end 390.219438 -107.228132)
					)
					(arc
						(start 390.29132 -107.300014)
						(mid 390.13765 -107.344163)
						(end 389.98398 -107.300014)
					)
				)
			)
		)
		(zone
			(layer "F.Cu")
			(hatch none 0.5)
			(connect_pads
				(clearance 0)
			)
			(min_thickness 0.25)
			(keepout
				(tracks not_allowed)
				(vias allowed)
				(pads allowed)
				(copperpour not_allowed)
				(footprints allowed)
			)
			(placement
				(enabled no)
				(sheetname "")
			)
			(fill
				(thermal_gap 0.5)
				(thermal_bridge_width 0.5)
				(island_removal_mode 0)
			)
			(polygon
				(pts
					(arc
						(start 390.055862 -106.428032)
						(mid 390.13765 -106.446345)
						(end 390.219438 -106.428032)
					)
					(arc
						(start 390.29132 -106.499914)
						(mid 390.13765 -106.544063)
						(end 389.98398 -106.499914)
					)
				)
			)
		)
		(zone
			(layer "F.Cu")
			(hatch none 0.5)
			(connect_pads
				(clearance 0)
			)
			(min_thickness 0.25)
			(keepout
				(tracks not_allowed)
				(vias allowed)
				(pads allowed)
				(copperpour not_allowed)
				(footprints allowed)
			)
			(placement
				(enabled no)
				(sheetname "")
			)
			(fill
				(thermal_gap 0.5)
				(thermal_bridge_width 0.5)
				(island_removal_mode 0)
			)
			(polygon
				(pts
					(arc
						(start 390.055862 -105.627932)
						(mid 390.13765 -105.646245)
						(end 390.219438 -105.627932)
					)
					(arc
						(start 390.29132 -105.699814)
						(mid 390.13765 -105.743963)
						(end 389.98398 -105.699814)
					)
				)
			)
		)
		(zone
			(layer "F.Cu")
			(hatch none 0.5)
			(connect_pads
				(clearance 0)
			)
			(min_thickness 0.25)
			(keepout
				(tracks not_allowed)
				(vias allowed)
				(pads allowed)
				(copperpour not_allowed)
				(footprints allowed)
			)
			(placement
				(enabled no)
				(sheetname "")
			)
			(fill
				(thermal_gap 0.5)
				(thermal_bridge_width 0.5)
				(island_removal_mode 0)
			)
			(polygon
				(pts
					(arc
						(start 390.055862 -104.827832)
						(mid 390.13765 -104.846145)
						(end 390.219438 -104.827832)
					)
					(arc
						(start 390.29132 -104.899714)
						(mid 390.13765 -104.943863)
						(end 389.98398 -104.899714)
					)
				)
			)
		)
		(zone
			(layer "F.Cu")
			(hatch none 0.5)
			(connect_pads
				(clearance 0)
			)
			(min_thickness 0.25)
			(keepout
				(tracks not_allowed)
				(vias allowed)
				(pads allowed)
				(copperpour not_allowed)
				(footprints allowed)
			)
			(placement
				(enabled no)
				(sheetname "")
			)
			(fill
				(thermal_gap 0.5)
				(thermal_bridge_width 0.5)
				(island_removal_mode 0)
			)
			(polygon
				(pts
					(arc
						(start 390.219438 -114.082068)
						(mid 390.13765 -114.063755)
						(end 390.055862 -114.082068)
					)
					(arc
						(start 389.98398 -114.010186)
						(mid 390.13765 -113.966037)
						(end 390.29132 -114.010186)
					)
				)
			)
		)
		(zone
			(layer "F.Cu")
			(hatch none 0.5)
			(connect_pads
				(clearance 0)
			)
			(min_thickness 0.25)
			(keepout
				(tracks not_allowed)
				(vias allowed)
				(pads allowed)
				(copperpour not_allowed)
				(footprints allowed)
			)
			(placement
				(enabled no)
				(sheetname "")
			)
			(fill
				(thermal_gap 0.5)
				(thermal_bridge_width 0.5)
				(island_removal_mode 0)
			)
			(polygon
				(pts
					(arc
						(start 390.219438 -113.281968)
						(mid 390.13765 -113.263655)
						(end 390.055862 -113.281968)
					)
					(arc
						(start 389.98398 -113.210086)
						(mid 390.13765 -113.165937)
						(end 390.29132 -113.210086)
					)
				)
			)
		)
		(zone
			(layer "F.Cu")
			(hatch none 0.5)
			(connect_pads
				(clearance 0)
			)
			(min_thickness 0.25)
			(keepout
				(tracks not_allowed)
				(vias allowed)
				(pads allowed)
				(copperpour not_allowed)
				(footprints allowed)
			)
			(placement
				(enabled no)
				(sheetname "")
			)
			(fill
				(thermal_gap 0.5)
				(thermal_bridge_width 0.5)
				(island_removal_mode 0)
			)
			(polygon
				(pts
					(arc
						(start 390.219438 -112.481868)
						(mid 390.13765 -112.463555)
						(end 390.055862 -112.481868)
					)
					(arc
						(start 389.98398 -112.409986)
						(mid 390.13765 -112.365837)
						(end 390.29132 -112.409986)
					)
				)
			)
		)
		(zone
			(layer "F.Cu")
			(hatch none 0.5)
			(connect_pads
				(clearance 0)
			)
			(min_thickness 0.25)
			(keepout
				(tracks not_allowed)
				(vias allowed)
				(pads allowed)
				(copperpour not_allowed)
				(footprints allowed)
			)
			(placement
				(enabled no)
				(sheetname "")
			)
			(fill
				(thermal_gap 0.5)
				(thermal_bridge_width 0.5)
				(island_removal_mode 0)
			)
			(polygon
				(pts
					(arc
						(start 390.219438 -111.681768)
						(mid 390.13765 -111.663455)
						(end 390.055862 -111.681768)
					)
					(arc
						(start 389.98398 -111.609886)
						(mid 390.13765 -111.565737)
						(end 390.29132 -111.609886)
					)
				)
			)
		)
		(zone
			(layer "F.Cu")
			(hatch none 0.5)
			(connect_pads
				(clearance 0)
			)
			(min_thickness 0.25)
			(keepout
				(tracks not_allowed)
				(vias allowed)
				(pads allowed)
				(copperpour not_allowed)
				(footprints allowed)
			)
			(placement
				(enabled no)
				(sheetname "")
			)
			(fill
				(thermal_gap 0.5)
				(thermal_bridge_width 0.5)
				(island_removal_mode 0)
			)
			(polygon
				(pts
					(arc
						(start 390.219438 -110.881668)
						(mid 390.13765 -110.863355)
						(end 390.055862 -110.881668)
					)
					(arc
						(start 389.98398 -110.809786)
						(mid 390.13765 -110.765637)
						(end 390.29132 -110.809786)
					)
				)
			)
		)
		(zone
			(layer "F.Cu")
			(hatch none 0.5)
			(connect_pads
				(clearance 0)
			)
			(min_thickness 0.25)
			(keepout
				(tracks not_allowed)
				(vias allowed)
				(pads allowed)
				(copperpour not_allowed)
				(footprints allowed)
			)
			(placement
				(enabled no)
				(sheetname "")
			)
			(fill
				(thermal_gap 0.5)
				(thermal_bridge_width 0.5)
				(island_removal_mode 0)
			)
			(polygon
				(pts
					(arc
						(start 390.219438 -109.281468)
						(mid 390.13765 -109.263155)
						(end 390.055862 -109.281468)
					)
					(arc
						(start 389.98398 -109.209586)
						(mid 390.13765 -109.165437)
						(end 390.29132 -109.209586)
					)
				)
			)
		)
		(zone
			(layer "F.Cu")
			(hatch none 0.5)
			(connect_pads
				(clearance 0)
			)
			(min_thickness 0.25)
			(keepout
				(tracks not_allowed)
				(vias allowed)
				(pads allowed)
				(copperpour not_allowed)
				(footprints allowed)
			)
			(placement
				(enabled no)
				(sheetname "")
			)
			(fill
				(thermal_gap 0.5)
				(thermal_bridge_width 0.5)
				(island_removal_mode 0)
			)
			(polygon
				(pts
					(arc
						(start 390.219438 -108.481368)
						(mid 390.13765 -108.463055)
						(end 390.055862 -108.481368)
					)
					(arc
						(start 389.98398 -108.409486)
						(mid 390.13765 -108.365337)
						(end 390.29132 -108.409486)
					)
				)
			)
		)
		(zone
			(layer "F.Cu")
			(hatch none 0.5)
			(connect_pads
				(clearance 0)
			)
			(min_thickness 0.25)
			(keepout
				(tracks not_allowed)
				(vias allowed)
				(pads allowed)
				(copperpour not_allowed)
				(footprints allowed)
			)
			(placement
				(enabled no)
				(sheetname "")
			)
			(fill
				(thermal_gap 0.5)
				(thermal_bridge_width 0.5)
				(island_removal_mode 0)
			)
			(polygon
				(pts
					(arc
						(start 390.219438 -107.681268)
						(mid 390.13765 -107.662955)
						(end 390.055862 -107.681268)
					)
					(arc
						(start 389.98398 -107.609386)
						(mid 390.13765 -107.565237)
						(end 390.29132 -107.609386)
					)
				)
			)
		)
		(zone
			(layer "F.Cu")
			(hatch none 0.5)
			(connect_pads
				(clearance 0)
			)
			(min_thickness 0.25)
			(keepout
				(tracks not_allowed)
				(vias allowed)
				(pads allowed)
				(copperpour not_allowed)
				(footprints allowed)
			)
			(placement
				(enabled no)
				(sheetname "")
			)
			(fill
				(thermal_gap 0.5)
				(thermal_bridge_width 0.5)
				(island_removal_mode 0)
			)
			(polygon
				(pts
					(arc
						(start 390.219438 -106.881168)
						(mid 390.13765 -106.862855)
						(end 390.055862 -106.881168)
					)
					(arc
						(start 389.98398 -106.809286)
						(mid 390.13765 -106.765137)
						(end 390.29132 -106.809286)
					)
				)
			)
		)
		(zone
			(layer "F.Cu")
			(hatch none 0.5)
			(connect_pads
				(clearance 0)
			)
			(min_thickness 0.25)
			(keepout
				(tracks not_allowed)
				(vias allowed)
				(pads allowed)
				(copperpour not_allowed)
				(footprints allowed)
			)
			(placement
				(enabled no)
				(sheetname "")
			)
			(fill
				(thermal_gap 0.5)
				(thermal_bridge_width 0.5)
				(island_removal_mode 0)
			)
			(polygon
				(pts
					(arc
						(start 390.219438 -106.081068)
						(mid 390.13765 -106.062755)
						(end 390.055862 -106.081068)
					)
					(arc
						(start 389.98398 -106.009186)
						(mid 390.13765 -105.965037)
						(end 390.29132 -106.009186)
					)
				)
			)
		)
		(zone
			(layer "F.Cu")
			(hatch none 0.5)
			(connect_pads
				(clearance 0)
			)
			(min_thickness 0.25)
			(keepout
				(tracks not_allowed)
				(vias allowed)
				(pads allowed)
				(copperpour not_allowed)
				(footprints allowed)
			)
			(placement
				(enabled no)
				(sheetname "")
			)
			(fill
				(thermal_gap 0.5)
				(thermal_bridge_width 0.5)
				(island_removal_mode 0)
			)
			(polygon
				(pts
					(arc
						(start 390.219438 -105.280968)
						(mid 390.13765 -105.262655)
						(end 390.055862 -105.280968)
					)
					(arc
						(start 389.98398 -105.209086)
						(mid 390.13765 -105.164937)
						(end 390.29132 -105.209086)
					)
				)
			)
		)
		(zone
			(layer "F.Cu")
			(hatch none 0.5)
			(connect_pads
				(clearance 0)
			)
			(min_thickness 0.25)
			(keepout
				(tracks not_allowed)
				(vias allowed)
				(pads allowed)
				(copperpour not_allowed)
				(footprints allowed)
			)
			(placement
				(enabled no)
				(sheetname "")
			)
			(fill
				(thermal_gap 0.5)
				(thermal_bridge_width 0.5)
				(island_removal_mode 0)
			)
			(polygon
				(pts
					(arc
						(start 390.219438 -104.480868)
						(mid 390.13765 -104.462555)
						(end 390.055862 -104.480868)
					)
					(arc
						(start 389.98398 -104.408986)
						(mid 390.13765 -104.364837)
						(end 390.29132 -104.408986)
					)
				)
			)
		)
		(zone
			(layer "F.Cu")
			(hatch none 0.5)
			(connect_pads
				(clearance 0)
			)
			(min_thickness 0.25)
			(keepout
				(tracks not_allowed)
				(vias allowed)
				(pads allowed)
				(copperpour not_allowed)
				(footprints allowed)
			)
			(placement
				(enabled no)
				(sheetname "")
			)
			(fill
				(thermal_gap 0.5)
				(thermal_bridge_width 0.5)
				(island_removal_mode 0)
			)
			(polygon
				(pts
					(arc
						(start 390.311132 -114.337338)
						(mid 390.329445 -114.25555)
						(end 390.311132 -114.173762)
					)
					(arc
						(start 390.383014 -114.10188)
						(mid 390.427163 -114.25555)
						(end 390.383014 -114.40922)
					)
				)
			)
		)
		(zone
			(layer "F.Cu")
			(hatch none 0.5)
			(connect_pads
				(clearance 0)
			)
			(min_thickness 0.25)
			(keepout
				(tracks not_allowed)
				(vias allowed)
				(pads allowed)
				(copperpour not_allowed)
				(footprints allowed)
			)
			(placement
				(enabled no)
				(sheetname "")
			)
			(fill
				(thermal_gap 0.5)
				(thermal_bridge_width 0.5)
				(island_removal_mode 0)
			)
			(polygon
				(pts
					(arc
						(start 390.311132 -113.537238)
						(mid 390.329445 -113.45545)
						(end 390.311132 -113.373662)
					)
					(arc
						(start 390.383014 -113.30178)
						(mid 390.427163 -113.45545)
						(end 390.383014 -113.60912)
					)
				)
			)
		)
		(zone
			(layer "F.Cu")
			(hatch none 0.5)
			(connect_pads
				(clearance 0)
			)
			(min_thickness 0.25)
			(keepout
				(tracks not_allowed)
				(vias allowed)
				(pads allowed)
				(copperpour not_allowed)
				(footprints allowed)
			)
			(placement
				(enabled no)
				(sheetname "")
			)
			(fill
				(thermal_gap 0.5)
				(thermal_bridge_width 0.5)
				(island_removal_mode 0)
			)
			(polygon
				(pts
					(arc
						(start 390.311132 -112.737138)
						(mid 390.329445 -112.65535)
						(end 390.311132 -112.573562)
					)
					(arc
						(start 390.383014 -112.50168)
						(mid 390.427163 -112.65535)
						(end 390.383014 -112.80902)
					)
				)
			)
		)
		(zone
			(layer "F.Cu")
			(hatch none 0.5)
			(connect_pads
				(clearance 0)
			)
			(min_thickness 0.25)
			(keepout
				(tracks not_allowed)
				(vias allowed)
				(pads allowed)
				(copperpour not_allowed)
				(footprints allowed)
			)
			(placement
				(enabled no)
				(sheetname "")
			)
			(fill
				(thermal_gap 0.5)
				(thermal_bridge_width 0.5)
				(island_removal_mode 0)
			)
			(polygon
				(pts
					(arc
						(start 390.311132 -111.937038)
						(mid 390.329445 -111.85525)
						(end 390.311132 -111.773462)
					)
					(arc
						(start 390.383014 -111.70158)
						(mid 390.427163 -111.85525)
						(end 390.383014 -112.00892)
					)
				)
			)
		)
		(zone
			(layer "F.Cu")
			(hatch none 0.5)
			(connect_pads
				(clearance 0)
			)
			(min_thickness 0.25)
			(keepout
				(tracks not_allowed)
				(vias allowed)
				(pads allowed)
				(copperpour not_allowed)
				(footprints allowed)
			)
			(placement
				(enabled no)
				(sheetname "")
			)
			(fill
				(thermal_gap 0.5)
				(thermal_bridge_width 0.5)
				(island_removal_mode 0)
			)
			(polygon
				(pts
					(arc
						(start 390.311132 -111.136938)
						(mid 390.329445 -111.05515)
						(end 390.311132 -110.973362)
					)
					(arc
						(start 390.383014 -110.90148)
						(mid 390.427163 -111.05515)
						(end 390.383014 -111.20882)
					)
				)
			)
		)
		(zone
			(layer "F.Cu")
			(hatch none 0.5)
			(connect_pads
				(clearance 0)
			)
			(min_thickness 0.25)
			(keepout
				(tracks not_allowed)
				(vias allowed)
				(pads allowed)
				(copperpour not_allowed)
				(footprints allowed)
			)
			(placement
				(enabled no)
				(sheetname "")
			)
			(fill
				(thermal_gap 0.5)
				(thermal_bridge_width 0.5)
				(island_removal_mode 0)
			)
			(polygon
				(pts
					(arc
						(start 390.311132 -109.536738)
						(mid 390.329445 -109.45495)
						(end 390.311132 -109.373162)
					)
					(arc
						(start 390.383014 -109.30128)
						(mid 390.427163 -109.45495)
						(end 390.383014 -109.60862)
					)
				)
			)
		)
		(zone
			(layer "F.Cu")
			(hatch none 0.5)
			(connect_pads
				(clearance 0)
			)
			(min_thickness 0.25)
			(keepout
				(tracks not_allowed)
				(vias allowed)
				(pads allowed)
				(copperpour not_allowed)
				(footprints allowed)
			)
			(placement
				(enabled no)
				(sheetname "")
			)
			(fill
				(thermal_gap 0.5)
				(thermal_bridge_width 0.5)
				(island_removal_mode 0)
			)
			(polygon
				(pts
					(arc
						(start 390.311132 -108.736638)
						(mid 390.329445 -108.65485)
						(end 390.311132 -108.573062)
					)
					(arc
						(start 390.383014 -108.50118)
						(mid 390.427163 -108.65485)
						(end 390.383014 -108.80852)
					)
				)
			)
		)
		(zone
			(layer "F.Cu")
			(hatch none 0.5)
			(connect_pads
				(clearance 0)
			)
			(min_thickness 0.25)
			(keepout
				(tracks not_allowed)
				(vias allowed)
				(pads allowed)
				(copperpour not_allowed)
				(footprints allowed)
			)
			(placement
				(enabled no)
				(sheetname "")
			)
			(fill
				(thermal_gap 0.5)
				(thermal_bridge_width 0.5)
				(island_removal_mode 0)
			)
			(polygon
				(pts
					(arc
						(start 390.311132 -107.936538)
						(mid 390.329445 -107.85475)
						(end 390.311132 -107.772962)
					)
					(arc
						(start 390.383014 -107.70108)
						(mid 390.427163 -107.85475)
						(end 390.383014 -108.00842)
					)
				)
			)
		)
		(zone
			(layer "F.Cu")
			(hatch none 0.5)
			(connect_pads
				(clearance 0)
			)
			(min_thickness 0.25)
			(keepout
				(tracks not_allowed)
				(vias allowed)
				(pads allowed)
				(copperpour not_allowed)
				(footprints allowed)
			)
			(placement
				(enabled no)
				(sheetname "")
			)
			(fill
				(thermal_gap 0.5)
				(thermal_bridge_width 0.5)
				(island_removal_mode 0)
			)
			(polygon
				(pts
					(arc
						(start 390.311132 -107.136438)
						(mid 390.329445 -107.05465)
						(end 390.311132 -106.972862)
					)
					(arc
						(start 390.383014 -106.90098)
						(mid 390.427163 -107.05465)
						(end 390.383014 -107.20832)
					)
				)
			)
		)
		(zone
			(layer "F.Cu")
			(hatch none 0.5)
			(connect_pads
				(clearance 0)
			)
			(min_thickness 0.25)
			(keepout
				(tracks not_allowed)
				(vias allowed)
				(pads allowed)
				(copperpour not_allowed)
				(footprints allowed)
			)
			(placement
				(enabled no)
				(sheetname "")
			)
			(fill
				(thermal_gap 0.5)
				(thermal_bridge_width 0.5)
				(island_removal_mode 0)
			)
			(polygon
				(pts
					(arc
						(start 390.311132 -106.336338)
						(mid 390.329445 -106.25455)
						(end 390.311132 -106.172762)
					)
					(arc
						(start 390.383014 -106.10088)
						(mid 390.427163 -106.25455)
						(end 390.383014 -106.40822)
					)
				)
			)
		)
		(zone
			(layer "F.Cu")
			(hatch none 0.5)
			(connect_pads
				(clearance 0)
			)
			(min_thickness 0.25)
			(keepout
				(tracks not_allowed)
				(vias allowed)
				(pads allowed)
				(copperpour not_allowed)
				(footprints allowed)
			)
			(placement
				(enabled no)
				(sheetname "")
			)
			(fill
				(thermal_gap 0.5)
				(thermal_bridge_width 0.5)
				(island_removal_mode 0)
			)
			(polygon
				(pts
					(arc
						(start 390.311132 -105.536238)
						(mid 390.329445 -105.45445)
						(end 390.311132 -105.372662)
					)
					(arc
						(start 390.383014 -105.30078)
						(mid 390.427163 -105.45445)
						(end 390.383014 -105.60812)
					)
				)
			)
		)
		(zone
			(layer "F.Cu")
			(hatch none 0.5)
			(connect_pads
				(clearance 0)
			)
			(min_thickness 0.25)
			(keepout
				(tracks not_allowed)
				(vias allowed)
				(pads allowed)
				(copperpour not_allowed)
				(footprints allowed)
			)
			(placement
				(enabled no)
				(sheetname "")
			)
			(fill
				(thermal_gap 0.5)
				(thermal_bridge_width 0.5)
				(island_removal_mode 0)
			)
			(polygon
				(pts
					(arc
						(start 390.311132 -104.736138)
						(mid 390.329445 -104.65435)
						(end 390.311132 -104.572562)
					)
					(arc
						(start 390.383014 -104.50068)
						(mid 390.427163 -104.65435)
						(end 390.383014 -104.80802)
					)
				)
			)
		)
		(zone
			(layer "F.Cu")
			(hatch none 0.5)
			(connect_pads
				(clearance 0)
			)
			(min_thickness 0.25)
			(keepout
				(tracks not_allowed)
				(vias allowed)
				(pads allowed)
				(copperpour not_allowed)
				(footprints allowed)
			)
			(placement
				(enabled no)
				(sheetname "")
			)
			(fill
				(thermal_gap 0.5)
				(thermal_bridge_width 0.5)
				(island_removal_mode 0)
			)
			(polygon
				(pts
					(arc
						(start 390.764268 -113.373662)
						(mid 390.745955 -113.45545)
						(end 390.764268 -113.537238)
					)
					(arc
						(start 390.692386 -113.60912)
						(mid 390.648237 -113.45545)
						(end 390.692386 -113.30178)
					)
				)
			)
		)
		(zone
			(layer "F.Cu")
			(hatch none 0.5)
			(connect_pads
				(clearance 0)
			)
			(min_thickness 0.25)
			(keepout
				(tracks not_allowed)
				(vias allowed)
				(pads allowed)
				(copperpour not_allowed)
				(footprints allowed)
			)
			(placement
				(enabled no)
				(sheetname "")
			)
			(fill
				(thermal_gap 0.5)
				(thermal_bridge_width 0.5)
				(island_removal_mode 0)
			)
			(polygon
				(pts
					(arc
						(start 390.764268 -110.973362)
						(mid 390.745955 -111.05515)
						(end 390.764268 -111.136938)
					)
					(arc
						(start 390.692386 -111.20882)
						(mid 390.648237 -111.05515)
						(end 390.692386 -110.90148)
					)
				)
			)
		)
		(zone
			(layer "F.Cu")
			(hatch none 0.5)
			(connect_pads
				(clearance 0)
			)
			(min_thickness 0.25)
			(keepout
				(tracks not_allowed)
				(vias allowed)
				(pads allowed)
				(copperpour not_allowed)
				(footprints allowed)
			)
			(placement
				(enabled no)
				(sheetname "")
			)
			(fill
				(thermal_gap 0.5)
				(thermal_bridge_width 0.5)
				(island_removal_mode 0)
			)
			(polygon
				(pts
					(arc
						(start 390.764268 -110.173262)
						(mid 390.745955 -110.25505)
						(end 390.764268 -110.336838)
					)
					(arc
						(start 390.692386 -110.40872)
						(mid 390.648237 -110.25505)
						(end 390.692386 -110.10138)
					)
				)
			)
		)
		(zone
			(layer "F.Cu")
			(hatch none 0.5)
			(connect_pads
				(clearance 0)
			)
			(min_thickness 0.25)
			(keepout
				(tracks not_allowed)
				(vias allowed)
				(pads allowed)
				(copperpour not_allowed)
				(footprints allowed)
			)
			(placement
				(enabled no)
				(sheetname "")
			)
			(fill
				(thermal_gap 0.5)
				(thermal_bridge_width 0.5)
				(island_removal_mode 0)
			)
			(polygon
				(pts
					(arc
						(start 390.764268 -109.373162)
						(mid 390.745955 -109.45495)
						(end 390.764268 -109.536738)
					)
					(arc
						(start 390.692386 -109.60862)
						(mid 390.648237 -109.45495)
						(end 390.692386 -109.30128)
					)
				)
			)
		)
		(zone
			(layer "F.Cu")
			(hatch none 0.5)
			(connect_pads
				(clearance 0)
			)
			(min_thickness 0.25)
			(keepout
				(tracks not_allowed)
				(vias allowed)
				(pads allowed)
				(copperpour not_allowed)
				(footprints allowed)
			)
			(placement
				(enabled no)
				(sheetname "")
			)
			(fill
				(thermal_gap 0.5)
				(thermal_bridge_width 0.5)
				(island_removal_mode 0)
			)
			(polygon
				(pts
					(arc
						(start 390.764268 -108.573062)
						(mid 390.745955 -108.65485)
						(end 390.764268 -108.736638)
					)
					(arc
						(start 390.692386 -108.80852)
						(mid 390.648237 -108.65485)
						(end 390.692386 -108.50118)
					)
				)
			)
		)
		(zone
			(layer "F.Cu")
			(hatch none 0.5)
			(connect_pads
				(clearance 0)
			)
			(min_thickness 0.25)
			(keepout
				(tracks not_allowed)
				(vias allowed)
				(pads allowed)
				(copperpour not_allowed)
				(footprints allowed)
			)
			(placement
				(enabled no)
				(sheetname "")
			)
			(fill
				(thermal_gap 0.5)
				(thermal_bridge_width 0.5)
				(island_removal_mode 0)
			)
			(polygon
				(pts
					(arc
						(start 390.764268 -107.772962)
						(mid 390.745955 -107.85475)
						(end 390.764268 -107.936538)
					)
					(arc
						(start 390.692386 -108.00842)
						(mid 390.648237 -107.85475)
						(end 390.692386 -107.70108)
					)
				)
			)
		)
		(zone
			(layer "F.Cu")
			(hatch none 0.5)
			(connect_pads
				(clearance 0)
			)
			(min_thickness 0.25)
			(keepout
				(tracks not_allowed)
				(vias allowed)
				(pads allowed)
				(copperpour not_allowed)
				(footprints allowed)
			)
			(placement
				(enabled no)
				(sheetname "")
			)
			(fill
				(thermal_gap 0.5)
				(thermal_bridge_width 0.5)
				(island_removal_mode 0)
			)
			(polygon
				(pts
					(arc
						(start 390.764268 -106.972862)
						(mid 390.745955 -107.05465)
						(end 390.764268 -107.136438)
					)
					(arc
						(start 390.692386 -107.20832)
						(mid 390.648237 -107.05465)
						(end 390.692386 -106.90098)
					)
				)
			)
		)
		(zone
			(layer "F.Cu")
			(hatch none 0.5)
			(connect_pads
				(clearance 0)
			)
			(min_thickness 0.25)
			(keepout
				(tracks not_allowed)
				(vias allowed)
				(pads allowed)
				(copperpour not_allowed)
				(footprints allowed)
			)
			(placement
				(enabled no)
				(sheetname "")
			)
			(fill
				(thermal_gap 0.5)
				(thermal_bridge_width 0.5)
				(island_removal_mode 0)
			)
			(polygon
				(pts
					(arc
						(start 390.764268 -106.172762)
						(mid 390.745955 -106.25455)
						(end 390.764268 -106.336338)
					)
					(arc
						(start 390.692386 -106.40822)
						(mid 390.648237 -106.25455)
						(end 390.692386 -106.10088)
					)
				)
			)
		)
		(zone
			(layer "F.Cu")
			(hatch none 0.5)
			(connect_pads
				(clearance 0)
			)
			(min_thickness 0.25)
			(keepout
				(tracks not_allowed)
				(vias allowed)
				(pads allowed)
				(copperpour not_allowed)
				(footprints allowed)
			)
			(placement
				(enabled no)
				(sheetname "")
			)
			(fill
				(thermal_gap 0.5)
				(thermal_bridge_width 0.5)
				(island_removal_mode 0)
			)
			(polygon
				(pts
					(arc
						(start 390.764268 -104.572562)
						(mid 390.745955 -104.65435)
						(end 390.764268 -104.736138)
					)
					(arc
						(start 390.692386 -104.80802)
						(mid 390.648237 -104.65435)
						(end 390.692386 -104.50068)
					)
				)
			)
		)
		(zone
			(layer "F.Cu")
			(hatch none 0.5)
			(connect_pads
				(clearance 0)
			)
			(min_thickness 0.25)
			(keepout
				(tracks not_allowed)
				(vias allowed)
				(pads allowed)
				(copperpour not_allowed)
				(footprints allowed)
			)
			(placement
				(enabled no)
				(sheetname "")
			)
			(fill
				(thermal_gap 0.5)
				(thermal_bridge_width 0.5)
				(island_removal_mode 0)
			)
			(polygon
				(pts
					(arc
						(start 390.855962 -113.628932)
						(mid 390.93775 -113.647245)
						(end 391.019538 -113.628932)
					)
					(arc
						(start 391.09142 -113.700814)
						(mid 390.93775 -113.744963)
						(end 390.78408 -113.700814)
					)
				)
			)
		)
		(zone
			(layer "F.Cu")
			(hatch none 0.5)
			(connect_pads
				(clearance 0)
			)
			(min_thickness 0.25)
			(keepout
				(tracks not_allowed)
				(vias allowed)
				(pads allowed)
				(copperpour not_allowed)
				(footprints allowed)
			)
			(placement
				(enabled no)
				(sheetname "")
			)
			(fill
				(thermal_gap 0.5)
				(thermal_bridge_width 0.5)
				(island_removal_mode 0)
			)
			(polygon
				(pts
					(arc
						(start 390.855962 -111.228632)
						(mid 390.93775 -111.246945)
						(end 391.019538 -111.228632)
					)
					(arc
						(start 391.09142 -111.300514)
						(mid 390.93775 -111.344663)
						(end 390.78408 -111.300514)
					)
				)
			)
		)
		(zone
			(layer "F.Cu")
			(hatch none 0.5)
			(connect_pads
				(clearance 0)
			)
			(min_thickness 0.25)
			(keepout
				(tracks not_allowed)
				(vias allowed)
				(pads allowed)
				(copperpour not_allowed)
				(footprints allowed)
			)
			(placement
				(enabled no)
				(sheetname "")
			)
			(fill
				(thermal_gap 0.5)
				(thermal_bridge_width 0.5)
				(island_removal_mode 0)
			)
			(polygon
				(pts
					(arc
						(start 390.855962 -110.428532)
						(mid 390.93775 -110.446845)
						(end 391.019538 -110.428532)
					)
					(arc
						(start 391.09142 -110.500414)
						(mid 390.93775 -110.544563)
						(end 390.78408 -110.500414)
					)
				)
			)
		)
		(zone
			(layer "F.Cu")
			(hatch none 0.5)
			(connect_pads
				(clearance 0)
			)
			(min_thickness 0.25)
			(keepout
				(tracks not_allowed)
				(vias allowed)
				(pads allowed)
				(copperpour not_allowed)
				(footprints allowed)
			)
			(placement
				(enabled no)
				(sheetname "")
			)
			(fill
				(thermal_gap 0.5)
				(thermal_bridge_width 0.5)
				(island_removal_mode 0)
			)
			(polygon
				(pts
					(arc
						(start 390.855962 -109.628432)
						(mid 390.93775 -109.646745)
						(end 391.019538 -109.628432)
					)
					(arc
						(start 391.09142 -109.700314)
						(mid 390.93775 -109.744463)
						(end 390.78408 -109.700314)
					)
				)
			)
		)
		(zone
			(layer "F.Cu")
			(hatch none 0.5)
			(connect_pads
				(clearance 0)
			)
			(min_thickness 0.25)
			(keepout
				(tracks not_allowed)
				(vias allowed)
				(pads allowed)
				(copperpour not_allowed)
				(footprints allowed)
			)
			(placement
				(enabled no)
				(sheetname "")
			)
			(fill
				(thermal_gap 0.5)
				(thermal_bridge_width 0.5)
				(island_removal_mode 0)
			)
			(polygon
				(pts
					(arc
						(start 390.855962 -108.828332)
						(mid 390.93775 -108.846645)
						(end 391.019538 -108.828332)
					)
					(arc
						(start 391.09142 -108.900214)
						(mid 390.93775 -108.944363)
						(end 390.78408 -108.900214)
					)
				)
			)
		)
		(zone
			(layer "F.Cu")
			(hatch none 0.5)
			(connect_pads
				(clearance 0)
			)
			(min_thickness 0.25)
			(keepout
				(tracks not_allowed)
				(vias allowed)
				(pads allowed)
				(copperpour not_allowed)
				(footprints allowed)
			)
			(placement
				(enabled no)
				(sheetname "")
			)
			(fill
				(thermal_gap 0.5)
				(thermal_bridge_width 0.5)
				(island_removal_mode 0)
			)
			(polygon
				(pts
					(arc
						(start 390.855962 -108.028232)
						(mid 390.93775 -108.046545)
						(end 391.019538 -108.028232)
					)
					(arc
						(start 391.09142 -108.100114)
						(mid 390.93775 -108.144263)
						(end 390.78408 -108.100114)
					)
				)
			)
		)
		(zone
			(layer "F.Cu")
			(hatch none 0.5)
			(connect_pads
				(clearance 0)
			)
			(min_thickness 0.25)
			(keepout
				(tracks not_allowed)
				(vias allowed)
				(pads allowed)
				(copperpour not_allowed)
				(footprints allowed)
			)
			(placement
				(enabled no)
				(sheetname "")
			)
			(fill
				(thermal_gap 0.5)
				(thermal_bridge_width 0.5)
				(island_removal_mode 0)
			)
			(polygon
				(pts
					(arc
						(start 390.855962 -107.228132)
						(mid 390.93775 -107.246445)
						(end 391.019538 -107.228132)
					)
					(arc
						(start 391.09142 -107.300014)
						(mid 390.93775 -107.344163)
						(end 390.78408 -107.300014)
					)
				)
			)
		)
		(zone
			(layer "F.Cu")
			(hatch none 0.5)
			(connect_pads
				(clearance 0)
			)
			(min_thickness 0.25)
			(keepout
				(tracks not_allowed)
				(vias allowed)
				(pads allowed)
				(copperpour not_allowed)
				(footprints allowed)
			)
			(placement
				(enabled no)
				(sheetname "")
			)
			(fill
				(thermal_gap 0.5)
				(thermal_bridge_width 0.5)
				(island_removal_mode 0)
			)
			(polygon
				(pts
					(arc
						(start 390.855962 -106.428032)
						(mid 390.93775 -106.446345)
						(end 391.019538 -106.428032)
					)
					(arc
						(start 391.09142 -106.499914)
						(mid 390.93775 -106.544063)
						(end 390.78408 -106.499914)
					)
				)
			)
		)
		(zone
			(layer "F.Cu")
			(hatch none 0.5)
			(connect_pads
				(clearance 0)
			)
			(min_thickness 0.25)
			(keepout
				(tracks not_allowed)
				(vias allowed)
				(pads allowed)
				(copperpour not_allowed)
				(footprints allowed)
			)
			(placement
				(enabled no)
				(sheetname "")
			)
			(fill
				(thermal_gap 0.5)
				(thermal_bridge_width 0.5)
				(island_removal_mode 0)
			)
			(polygon
				(pts
					(arc
						(start 390.855962 -104.827832)
						(mid 390.93775 -104.846145)
						(end 391.019538 -104.827832)
					)
					(arc
						(start 391.09142 -104.899714)
						(mid 390.93775 -104.943863)
						(end 390.78408 -104.899714)
					)
				)
			)
		)
		(zone
			(layer "F.Cu")
			(hatch none 0.5)
			(connect_pads
				(clearance 0)
			)
			(min_thickness 0.25)
			(keepout
				(tracks not_allowed)
				(vias allowed)
				(pads allowed)
				(copperpour not_allowed)
				(footprints allowed)
			)
			(placement
				(enabled no)
				(sheetname "")
			)
			(fill
				(thermal_gap 0.5)
				(thermal_bridge_width 0.5)
				(island_removal_mode 0)
			)
			(polygon
				(pts
					(arc
						(start 391.019538 -113.281968)
						(mid 390.93775 -113.263655)
						(end 390.855962 -113.281968)
					)
					(arc
						(start 390.78408 -113.210086)
						(mid 390.93775 -113.165937)
						(end 391.09142 -113.210086)
					)
				)
			)
		)
		(zone
			(layer "F.Cu")
			(hatch none 0.5)
			(connect_pads
				(clearance 0)
			)
			(min_thickness 0.25)
			(keepout
				(tracks not_allowed)
				(vias allowed)
				(pads allowed)
				(copperpour not_allowed)
				(footprints allowed)
			)
			(placement
				(enabled no)
				(sheetname "")
			)
			(fill
				(thermal_gap 0.5)
				(thermal_bridge_width 0.5)
				(island_removal_mode 0)
			)
			(polygon
				(pts
					(arc
						(start 391.019538 -110.881668)
						(mid 390.93775 -110.863355)
						(end 390.855962 -110.881668)
					)
					(arc
						(start 390.78408 -110.809786)
						(mid 390.93775 -110.765637)
						(end 391.09142 -110.809786)
					)
				)
			)
		)
		(zone
			(layer "F.Cu")
			(hatch none 0.5)
			(connect_pads
				(clearance 0)
			)
			(min_thickness 0.25)
			(keepout
				(tracks not_allowed)
				(vias allowed)
				(pads allowed)
				(copperpour not_allowed)
				(footprints allowed)
			)
			(placement
				(enabled no)
				(sheetname "")
			)
			(fill
				(thermal_gap 0.5)
				(thermal_bridge_width 0.5)
				(island_removal_mode 0)
			)
			(polygon
				(pts
					(arc
						(start 391.019538 -110.081568)
						(mid 390.93775 -110.063255)
						(end 390.855962 -110.081568)
					)
					(arc
						(start 390.78408 -110.009686)
						(mid 390.93775 -109.965537)
						(end 391.09142 -110.009686)
					)
				)
			)
		)
		(zone
			(layer "F.Cu")
			(hatch none 0.5)
			(connect_pads
				(clearance 0)
			)
			(min_thickness 0.25)
			(keepout
				(tracks not_allowed)
				(vias allowed)
				(pads allowed)
				(copperpour not_allowed)
				(footprints allowed)
			)
			(placement
				(enabled no)
				(sheetname "")
			)
			(fill
				(thermal_gap 0.5)
				(thermal_bridge_width 0.5)
				(island_removal_mode 0)
			)
			(polygon
				(pts
					(arc
						(start 391.019538 -109.281468)
						(mid 390.93775 -109.263155)
						(end 390.855962 -109.281468)
					)
					(arc
						(start 390.78408 -109.209586)
						(mid 390.93775 -109.165437)
						(end 391.09142 -109.209586)
					)
				)
			)
		)
		(zone
			(layer "F.Cu")
			(hatch none 0.5)
			(connect_pads
				(clearance 0)
			)
			(min_thickness 0.25)
			(keepout
				(tracks not_allowed)
				(vias allowed)
				(pads allowed)
				(copperpour not_allowed)
				(footprints allowed)
			)
			(placement
				(enabled no)
				(sheetname "")
			)
			(fill
				(thermal_gap 0.5)
				(thermal_bridge_width 0.5)
				(island_removal_mode 0)
			)
			(polygon
				(pts
					(arc
						(start 391.019538 -108.481368)
						(mid 390.93775 -108.463055)
						(end 390.855962 -108.481368)
					)
					(arc
						(start 390.78408 -108.409486)
						(mid 390.93775 -108.365337)
						(end 391.09142 -108.409486)
					)
				)
			)
		)
		(zone
			(layer "F.Cu")
			(hatch none 0.5)
			(connect_pads
				(clearance 0)
			)
			(min_thickness 0.25)
			(keepout
				(tracks not_allowed)
				(vias allowed)
				(pads allowed)
				(copperpour not_allowed)
				(footprints allowed)
			)
			(placement
				(enabled no)
				(sheetname "")
			)
			(fill
				(thermal_gap 0.5)
				(thermal_bridge_width 0.5)
				(island_removal_mode 0)
			)
			(polygon
				(pts
					(arc
						(start 391.019538 -107.681268)
						(mid 390.93775 -107.662955)
						(end 390.855962 -107.681268)
					)
					(arc
						(start 390.78408 -107.609386)
						(mid 390.93775 -107.565237)
						(end 391.09142 -107.609386)
					)
				)
			)
		)
		(zone
			(layer "F.Cu")
			(hatch none 0.5)
			(connect_pads
				(clearance 0)
			)
			(min_thickness 0.25)
			(keepout
				(tracks not_allowed)
				(vias allowed)
				(pads allowed)
				(copperpour not_allowed)
				(footprints allowed)
			)
			(placement
				(enabled no)
				(sheetname "")
			)
			(fill
				(thermal_gap 0.5)
				(thermal_bridge_width 0.5)
				(island_removal_mode 0)
			)
			(polygon
				(pts
					(arc
						(start 391.019538 -106.881168)
						(mid 390.93775 -106.862855)
						(end 390.855962 -106.881168)
					)
					(arc
						(start 390.78408 -106.809286)
						(mid 390.93775 -106.765137)
						(end 391.09142 -106.809286)
					)
				)
			)
		)
		(zone
			(layer "F.Cu")
			(hatch none 0.5)
			(connect_pads
				(clearance 0)
			)
			(min_thickness 0.25)
			(keepout
				(tracks not_allowed)
				(vias allowed)
				(pads allowed)
				(copperpour not_allowed)
				(footprints allowed)
			)
			(placement
				(enabled no)
				(sheetname "")
			)
			(fill
				(thermal_gap 0.5)
				(thermal_bridge_width 0.5)
				(island_removal_mode 0)
			)
			(polygon
				(pts
					(arc
						(start 391.019538 -106.081068)
						(mid 390.93775 -106.062755)
						(end 390.855962 -106.081068)
					)
					(arc
						(start 390.78408 -106.009186)
						(mid 390.93775 -105.965037)
						(end 391.09142 -106.009186)
					)
				)
			)
		)
		(zone
			(layer "F.Cu")
			(hatch none 0.5)
			(connect_pads
				(clearance 0)
			)
			(min_thickness 0.25)
			(keepout
				(tracks not_allowed)
				(vias allowed)
				(pads allowed)
				(copperpour not_allowed)
				(footprints allowed)
			)
			(placement
				(enabled no)
				(sheetname "")
			)
			(fill
				(thermal_gap 0.5)
				(thermal_bridge_width 0.5)
				(island_removal_mode 0)
			)
			(polygon
				(pts
					(arc
						(start 391.019538 -104.480868)
						(mid 390.93775 -104.462555)
						(end 390.855962 -104.480868)
					)
					(arc
						(start 390.78408 -104.408986)
						(mid 390.93775 -104.364837)
						(end 391.09142 -104.408986)
					)
				)
			)
		)
		(zone
			(layer "F.Cu")
			(hatch none 0.5)
			(connect_pads
				(clearance 0)
			)
			(min_thickness 0.25)
			(keepout
				(tracks not_allowed)
				(vias allowed)
				(pads allowed)
				(copperpour not_allowed)
				(footprints allowed)
			)
			(placement
				(enabled no)
				(sheetname "")
			)
			(fill
				(thermal_gap 0.5)
				(thermal_bridge_width 0.5)
				(island_removal_mode 0)
			)
			(polygon
				(pts
					(arc
						(start 391.111232 -113.537238)
						(mid 391.129545 -113.45545)
						(end 391.111232 -113.373662)
					)
					(arc
						(start 391.183114 -113.30178)
						(mid 391.227263 -113.45545)
						(end 391.183114 -113.60912)
					)
				)
			)
		)
		(zone
			(layer "F.Cu")
			(hatch none 0.5)
			(connect_pads
				(clearance 0)
			)
			(min_thickness 0.25)
			(keepout
				(tracks not_allowed)
				(vias allowed)
				(pads allowed)
				(copperpour not_allowed)
				(footprints allowed)
			)
			(placement
				(enabled no)
				(sheetname "")
			)
			(fill
				(thermal_gap 0.5)
				(thermal_bridge_width 0.5)
				(island_removal_mode 0)
			)
			(polygon
				(pts
					(arc
						(start 391.111232 -111.136938)
						(mid 391.129545 -111.05515)
						(end 391.111232 -110.973362)
					)
					(arc
						(start 391.183114 -110.90148)
						(mid 391.227263 -111.05515)
						(end 391.183114 -111.20882)
					)
				)
			)
		)
		(zone
			(layer "F.Cu")
			(hatch none 0.5)
			(connect_pads
				(clearance 0)
			)
			(min_thickness 0.25)
			(keepout
				(tracks not_allowed)
				(vias allowed)
				(pads allowed)
				(copperpour not_allowed)
				(footprints allowed)
			)
			(placement
				(enabled no)
				(sheetname "")
			)
			(fill
				(thermal_gap 0.5)
				(thermal_bridge_width 0.5)
				(island_removal_mode 0)
			)
			(polygon
				(pts
					(arc
						(start 391.111232 -110.336838)
						(mid 391.129545 -110.25505)
						(end 391.111232 -110.173262)
					)
					(arc
						(start 391.183114 -110.10138)
						(mid 391.227263 -110.25505)
						(end 391.183114 -110.40872)
					)
				)
			)
		)
		(zone
			(layer "F.Cu")
			(hatch none 0.5)
			(connect_pads
				(clearance 0)
			)
			(min_thickness 0.25)
			(keepout
				(tracks not_allowed)
				(vias allowed)
				(pads allowed)
				(copperpour not_allowed)
				(footprints allowed)
			)
			(placement
				(enabled no)
				(sheetname "")
			)
			(fill
				(thermal_gap 0.5)
				(thermal_bridge_width 0.5)
				(island_removal_mode 0)
			)
			(polygon
				(pts
					(arc
						(start 391.111232 -109.536738)
						(mid 391.129545 -109.45495)
						(end 391.111232 -109.373162)
					)
					(arc
						(start 391.183114 -109.30128)
						(mid 391.227263 -109.45495)
						(end 391.183114 -109.60862)
					)
				)
			)
		)
		(zone
			(layer "F.Cu")
			(hatch none 0.5)
			(connect_pads
				(clearance 0)
			)
			(min_thickness 0.25)
			(keepout
				(tracks not_allowed)
				(vias allowed)
				(pads allowed)
				(copperpour not_allowed)
				(footprints allowed)
			)
			(placement
				(enabled no)
				(sheetname "")
			)
			(fill
				(thermal_gap 0.5)
				(thermal_bridge_width 0.5)
				(island_removal_mode 0)
			)
			(polygon
				(pts
					(arc
						(start 391.111232 -108.736638)
						(mid 391.129545 -108.65485)
						(end 391.111232 -108.573062)
					)
					(arc
						(start 391.183114 -108.50118)
						(mid 391.227263 -108.65485)
						(end 391.183114 -108.80852)
					)
				)
			)
		)
		(zone
			(layer "F.Cu")
			(hatch none 0.5)
			(connect_pads
				(clearance 0)
			)
			(min_thickness 0.25)
			(keepout
				(tracks not_allowed)
				(vias allowed)
				(pads allowed)
				(copperpour not_allowed)
				(footprints allowed)
			)
			(placement
				(enabled no)
				(sheetname "")
			)
			(fill
				(thermal_gap 0.5)
				(thermal_bridge_width 0.5)
				(island_removal_mode 0)
			)
			(polygon
				(pts
					(arc
						(start 391.111232 -107.936538)
						(mid 391.129545 -107.85475)
						(end 391.111232 -107.772962)
					)
					(arc
						(start 391.183114 -107.70108)
						(mid 391.227263 -107.85475)
						(end 391.183114 -108.00842)
					)
				)
			)
		)
		(zone
			(layer "F.Cu")
			(hatch none 0.5)
			(connect_pads
				(clearance 0)
			)
			(min_thickness 0.25)
			(keepout
				(tracks not_allowed)
				(vias allowed)
				(pads allowed)
				(copperpour not_allowed)
				(footprints allowed)
			)
			(placement
				(enabled no)
				(sheetname "")
			)
			(fill
				(thermal_gap 0.5)
				(thermal_bridge_width 0.5)
				(island_removal_mode 0)
			)
			(polygon
				(pts
					(arc
						(start 391.111232 -107.136438)
						(mid 391.129545 -107.05465)
						(end 391.111232 -106.972862)
					)
					(arc
						(start 391.183114 -106.90098)
						(mid 391.227263 -107.05465)
						(end 391.183114 -107.20832)
					)
				)
			)
		)
		(zone
			(layer "F.Cu")
			(hatch none 0.5)
			(connect_pads
				(clearance 0)
			)
			(min_thickness 0.25)
			(keepout
				(tracks not_allowed)
				(vias allowed)
				(pads allowed)
				(copperpour not_allowed)
				(footprints allowed)
			)
			(placement
				(enabled no)
				(sheetname "")
			)
			(fill
				(thermal_gap 0.5)
				(thermal_bridge_width 0.5)
				(island_removal_mode 0)
			)
			(polygon
				(pts
					(arc
						(start 391.111232 -106.336338)
						(mid 391.129545 -106.25455)
						(end 391.111232 -106.172762)
					)
					(arc
						(start 391.183114 -106.10088)
						(mid 391.227263 -106.25455)
						(end 391.183114 -106.40822)
					)
				)
			)
		)
		(zone
			(layer "F.Cu")
			(hatch none 0.5)
			(connect_pads
				(clearance 0)
			)
			(min_thickness 0.25)
			(keepout
				(tracks not_allowed)
				(vias allowed)
				(pads allowed)
				(copperpour not_allowed)
				(footprints allowed)
			)
			(placement
				(enabled no)
				(sheetname "")
			)
			(fill
				(thermal_gap 0.5)
				(thermal_bridge_width 0.5)
				(island_removal_mode 0)
			)
			(polygon
				(pts
					(arc
						(start 391.111232 -104.736138)
						(mid 391.129545 -104.65435)
						(end 391.111232 -104.572562)
					)
					(arc
						(start 391.183114 -104.50068)
						(mid 391.227263 -104.65435)
						(end 391.183114 -104.80802)
					)
				)
			)
		)
		(zone
			(layer "F.Cu")
			(hatch none 0.5)
			(connect_pads
				(clearance 0)
			)
			(min_thickness 0.25)
			(keepout
				(tracks not_allowed)
				(vias allowed)
				(pads allowed)
				(copperpour not_allowed)
				(footprints allowed)
			)
			(placement
				(enabled no)
				(sheetname "")
			)
			(fill
				(thermal_gap 0.5)
				(thermal_bridge_width 0.5)
				(island_removal_mode 0)
			)
			(polygon
				(pts
					(arc
						(start 391.564368 -110.173262)
						(mid 391.546055 -110.25505)
						(end 391.564368 -110.336838)
					)
					(arc
						(start 391.492486 -110.40872)
						(mid 391.448337 -110.25505)
						(end 391.492486 -110.10138)
					)
				)
			)
		)
		(zone
			(layer "F.Cu")
			(hatch none 0.5)
			(connect_pads
				(clearance 0)
			)
			(min_thickness 0.25)
			(keepout
				(tracks not_allowed)
				(vias allowed)
				(pads allowed)
				(copperpour not_allowed)
				(footprints allowed)
			)
			(placement
				(enabled no)
				(sheetname "")
			)
			(fill
				(thermal_gap 0.5)
				(thermal_bridge_width 0.5)
				(island_removal_mode 0)
			)
			(polygon
				(pts
					(arc
						(start 391.564368 -109.373162)
						(mid 391.546055 -109.45495)
						(end 391.564368 -109.536738)
					)
					(arc
						(start 391.492486 -109.60862)
						(mid 391.448337 -109.45495)
						(end 391.492486 -109.30128)
					)
				)
			)
		)
		(zone
			(layer "F.Cu")
			(hatch none 0.5)
			(connect_pads
				(clearance 0)
			)
			(min_thickness 0.25)
			(keepout
				(tracks not_allowed)
				(vias allowed)
				(pads allowed)
				(copperpour not_allowed)
				(footprints allowed)
			)
			(placement
				(enabled no)
				(sheetname "")
			)
			(fill
				(thermal_gap 0.5)
				(thermal_bridge_width 0.5)
				(island_removal_mode 0)
			)
			(polygon
				(pts
					(arc
						(start 391.564368 -108.573062)
						(mid 391.546055 -108.65485)
						(end 391.564368 -108.736638)
					)
					(arc
						(start 391.492486 -108.80852)
						(mid 391.448337 -108.65485)
						(end 391.492486 -108.50118)
					)
				)
			)
		)
		(zone
			(layer "F.Cu")
			(hatch none 0.5)
			(connect_pads
				(clearance 0)
			)
			(min_thickness 0.25)
			(keepout
				(tracks not_allowed)
				(vias allowed)
				(pads allowed)
				(copperpour not_allowed)
				(footprints allowed)
			)
			(placement
				(enabled no)
				(sheetname "")
			)
			(fill
				(thermal_gap 0.5)
				(thermal_bridge_width 0.5)
				(island_removal_mode 0)
			)
			(polygon
				(pts
					(arc
						(start 391.564368 -107.772962)
						(mid 391.546055 -107.85475)
						(end 391.564368 -107.936538)
					)
					(arc
						(start 391.492486 -108.00842)
						(mid 391.448337 -107.85475)
						(end 391.492486 -107.70108)
					)
				)
			)
		)
		(zone
			(layer "F.Cu")
			(hatch none 0.5)
			(connect_pads
				(clearance 0)
			)
			(min_thickness 0.25)
			(keepout
				(tracks not_allowed)
				(vias allowed)
				(pads allowed)
				(copperpour not_allowed)
				(footprints allowed)
			)
			(placement
				(enabled no)
				(sheetname "")
			)
			(fill
				(thermal_gap 0.5)
				(thermal_bridge_width 0.5)
				(island_removal_mode 0)
			)
			(polygon
				(pts
					(arc
						(start 391.564368 -106.972862)
						(mid 391.546055 -107.05465)
						(end 391.564368 -107.136438)
					)
					(arc
						(start 391.492486 -107.20832)
						(mid 391.448337 -107.05465)
						(end 391.492486 -106.90098)
					)
				)
			)
		)
		(zone
			(layer "F.Cu")
			(hatch none 0.5)
			(connect_pads
				(clearance 0)
			)
			(min_thickness 0.25)
			(keepout
				(tracks not_allowed)
				(vias allowed)
				(pads allowed)
				(copperpour not_allowed)
				(footprints allowed)
			)
			(placement
				(enabled no)
				(sheetname "")
			)
			(fill
				(thermal_gap 0.5)
				(thermal_bridge_width 0.5)
				(island_removal_mode 0)
			)
			(polygon
				(pts
					(arc
						(start 391.564368 -106.172762)
						(mid 391.546055 -106.25455)
						(end 391.564368 -106.336338)
					)
					(arc
						(start 391.492486 -106.40822)
						(mid 391.448337 -106.25455)
						(end 391.492486 -106.10088)
					)
				)
			)
		)
		(zone
			(layer "F.Cu")
			(hatch none 0.5)
			(connect_pads
				(clearance 0)
			)
			(min_thickness 0.25)
			(keepout
				(tracks not_allowed)
				(vias allowed)
				(pads allowed)
				(copperpour not_allowed)
				(footprints allowed)
			)
			(placement
				(enabled no)
				(sheetname "")
			)
			(fill
				(thermal_gap 0.5)
				(thermal_bridge_width 0.5)
				(island_removal_mode 0)
			)
			(polygon
				(pts
					(arc
						(start 391.564368 -105.372662)
						(mid 391.546055 -105.45445)
						(end 391.564368 -105.536238)
					)
					(arc
						(start 391.492486 -105.60812)
						(mid 391.448337 -105.45445)
						(end 391.492486 -105.30078)
					)
				)
			)
		)
		(zone
			(layer "F.Cu")
			(hatch none 0.5)
			(connect_pads
				(clearance 0)
			)
			(min_thickness 0.25)
			(keepout
				(tracks not_allowed)
				(vias allowed)
				(pads allowed)
				(copperpour not_allowed)
				(footprints allowed)
			)
			(placement
				(enabled no)
				(sheetname "")
			)
			(fill
				(thermal_gap 0.5)
				(thermal_bridge_width 0.5)
				(island_removal_mode 0)
			)
			(polygon
				(pts
					(arc
						(start 391.656062 -110.428532)
						(mid 391.73785 -110.446845)
						(end 391.819638 -110.428532)
					)
					(arc
						(start 391.89152 -110.500414)
						(mid 391.73785 -110.544563)
						(end 391.58418 -110.500414)
					)
				)
			)
		)
		(zone
			(layer "F.Cu")
			(hatch none 0.5)
			(connect_pads
				(clearance 0)
			)
			(min_thickness 0.25)
			(keepout
				(tracks not_allowed)
				(vias allowed)
				(pads allowed)
				(copperpour not_allowed)
				(footprints allowed)
			)
			(placement
				(enabled no)
				(sheetname "")
			)
			(fill
				(thermal_gap 0.5)
				(thermal_bridge_width 0.5)
				(island_removal_mode 0)
			)
			(polygon
				(pts
					(arc
						(start 391.656062 -109.628432)
						(mid 391.73785 -109.646745)
						(end 391.819638 -109.628432)
					)
					(arc
						(start 391.89152 -109.700314)
						(mid 391.73785 -109.744463)
						(end 391.58418 -109.700314)
					)
				)
			)
		)
		(zone
			(layer "F.Cu")
			(hatch none 0.5)
			(connect_pads
				(clearance 0)
			)
			(min_thickness 0.25)
			(keepout
				(tracks not_allowed)
				(vias allowed)
				(pads allowed)
				(copperpour not_allowed)
				(footprints allowed)
			)
			(placement
				(enabled no)
				(sheetname "")
			)
			(fill
				(thermal_gap 0.5)
				(thermal_bridge_width 0.5)
				(island_removal_mode 0)
			)
			(polygon
				(pts
					(arc
						(start 391.656062 -108.828332)
						(mid 391.73785 -108.846645)
						(end 391.819638 -108.828332)
					)
					(arc
						(start 391.89152 -108.900214)
						(mid 391.73785 -108.944363)
						(end 391.58418 -108.900214)
					)
				)
			)
		)
		(zone
			(layer "F.Cu")
			(hatch none 0.5)
			(connect_pads
				(clearance 0)
			)
			(min_thickness 0.25)
			(keepout
				(tracks not_allowed)
				(vias allowed)
				(pads allowed)
				(copperpour not_allowed)
				(footprints allowed)
			)
			(placement
				(enabled no)
				(sheetname "")
			)
			(fill
				(thermal_gap 0.5)
				(thermal_bridge_width 0.5)
				(island_removal_mode 0)
			)
			(polygon
				(pts
					(arc
						(start 391.656062 -108.028232)
						(mid 391.73785 -108.046545)
						(end 391.819638 -108.028232)
					)
					(arc
						(start 391.89152 -108.100114)
						(mid 391.73785 -108.144263)
						(end 391.58418 -108.100114)
					)
				)
			)
		)
		(zone
			(layer "F.Cu")
			(hatch none 0.5)
			(connect_pads
				(clearance 0)
			)
			(min_thickness 0.25)
			(keepout
				(tracks not_allowed)
				(vias allowed)
				(pads allowed)
				(copperpour not_allowed)
				(footprints allowed)
			)
			(placement
				(enabled no)
				(sheetname "")
			)
			(fill
				(thermal_gap 0.5)
				(thermal_bridge_width 0.5)
				(island_removal_mode 0)
			)
			(polygon
				(pts
					(arc
						(start 391.656062 -107.228132)
						(mid 391.73785 -107.246445)
						(end 391.819638 -107.228132)
					)
					(arc
						(start 391.89152 -107.300014)
						(mid 391.73785 -107.344163)
						(end 391.58418 -107.300014)
					)
				)
			)
		)
		(zone
			(layer "F.Cu")
			(hatch none 0.5)
			(connect_pads
				(clearance 0)
			)
			(min_thickness 0.25)
			(keepout
				(tracks not_allowed)
				(vias allowed)
				(pads allowed)
				(copperpour not_allowed)
				(footprints allowed)
			)
			(placement
				(enabled no)
				(sheetname "")
			)
			(fill
				(thermal_gap 0.5)
				(thermal_bridge_width 0.5)
				(island_removal_mode 0)
			)
			(polygon
				(pts
					(arc
						(start 391.656062 -106.428032)
						(mid 391.73785 -106.446345)
						(end 391.819638 -106.428032)
					)
					(arc
						(start 391.89152 -106.499914)
						(mid 391.73785 -106.544063)
						(end 391.58418 -106.499914)
					)
				)
			)
		)
		(zone
			(layer "F.Cu")
			(hatch none 0.5)
			(connect_pads
				(clearance 0)
			)
			(min_thickness 0.25)
			(keepout
				(tracks not_allowed)
				(vias allowed)
				(pads allowed)
				(copperpour not_allowed)
				(footprints allowed)
			)
			(placement
				(enabled no)
				(sheetname "")
			)
			(fill
				(thermal_gap 0.5)
				(thermal_bridge_width 0.5)
				(island_removal_mode 0)
			)
			(polygon
				(pts
					(arc
						(start 391.656062 -105.627932)
						(mid 391.73785 -105.646245)
						(end 391.819638 -105.627932)
					)
					(arc
						(start 391.89152 -105.699814)
						(mid 391.73785 -105.743963)
						(end 391.58418 -105.699814)
					)
				)
			)
		)
		(zone
			(layer "F.Cu")
			(hatch none 0.5)
			(connect_pads
				(clearance 0)
			)
			(min_thickness 0.25)
			(keepout
				(tracks not_allowed)
				(vias allowed)
				(pads allowed)
				(copperpour not_allowed)
				(footprints allowed)
			)
			(placement
				(enabled no)
				(sheetname "")
			)
			(fill
				(thermal_gap 0.5)
				(thermal_bridge_width 0.5)
				(island_removal_mode 0)
			)
			(polygon
				(pts
					(arc
						(start 391.819638 -110.081568)
						(mid 391.73785 -110.063255)
						(end 391.656062 -110.081568)
					)
					(arc
						(start 391.58418 -110.009686)
						(mid 391.73785 -109.965537)
						(end 391.89152 -110.009686)
					)
				)
			)
		)
		(zone
			(layer "F.Cu")
			(hatch none 0.5)
			(connect_pads
				(clearance 0)
			)
			(min_thickness 0.25)
			(keepout
				(tracks not_allowed)
				(vias allowed)
				(pads allowed)
				(copperpour not_allowed)
				(footprints allowed)
			)
			(placement
				(enabled no)
				(sheetname "")
			)
			(fill
				(thermal_gap 0.5)
				(thermal_bridge_width 0.5)
				(island_removal_mode 0)
			)
			(polygon
				(pts
					(arc
						(start 391.819638 -109.281468)
						(mid 391.73785 -109.263155)
						(end 391.656062 -109.281468)
					)
					(arc
						(start 391.58418 -109.209586)
						(mid 391.73785 -109.165437)
						(end 391.89152 -109.209586)
					)
				)
			)
		)
		(zone
			(layer "F.Cu")
			(hatch none 0.5)
			(connect_pads
				(clearance 0)
			)
			(min_thickness 0.25)
			(keepout
				(tracks not_allowed)
				(vias allowed)
				(pads allowed)
				(copperpour not_allowed)
				(footprints allowed)
			)
			(placement
				(enabled no)
				(sheetname "")
			)
			(fill
				(thermal_gap 0.5)
				(thermal_bridge_width 0.5)
				(island_removal_mode 0)
			)
			(polygon
				(pts
					(arc
						(start 391.819638 -108.481368)
						(mid 391.73785 -108.463055)
						(end 391.656062 -108.481368)
					)
					(arc
						(start 391.58418 -108.409486)
						(mid 391.73785 -108.365337)
						(end 391.89152 -108.409486)
					)
				)
			)
		)
		(zone
			(layer "F.Cu")
			(hatch none 0.5)
			(connect_pads
				(clearance 0)
			)
			(min_thickness 0.25)
			(keepout
				(tracks not_allowed)
				(vias allowed)
				(pads allowed)
				(copperpour not_allowed)
				(footprints allowed)
			)
			(placement
				(enabled no)
				(sheetname "")
			)
			(fill
				(thermal_gap 0.5)
				(thermal_bridge_width 0.5)
				(island_removal_mode 0)
			)
			(polygon
				(pts
					(arc
						(start 391.819638 -107.681268)
						(mid 391.73785 -107.662955)
						(end 391.656062 -107.681268)
					)
					(arc
						(start 391.58418 -107.609386)
						(mid 391.73785 -107.565237)
						(end 391.89152 -107.609386)
					)
				)
			)
		)
		(zone
			(layer "F.Cu")
			(hatch none 0.5)
			(connect_pads
				(clearance 0)
			)
			(min_thickness 0.25)
			(keepout
				(tracks not_allowed)
				(vias allowed)
				(pads allowed)
				(copperpour not_allowed)
				(footprints allowed)
			)
			(placement
				(enabled no)
				(sheetname "")
			)
			(fill
				(thermal_gap 0.5)
				(thermal_bridge_width 0.5)
				(island_removal_mode 0)
			)
			(polygon
				(pts
					(arc
						(start 391.819638 -106.881168)
						(mid 391.73785 -106.862855)
						(end 391.656062 -106.881168)
					)
					(arc
						(start 391.58418 -106.809286)
						(mid 391.73785 -106.765137)
						(end 391.89152 -106.809286)
					)
				)
			)
		)
		(zone
			(layer "F.Cu")
			(hatch none 0.5)
			(connect_pads
				(clearance 0)
			)
			(min_thickness 0.25)
			(keepout
				(tracks not_allowed)
				(vias allowed)
				(pads allowed)
				(copperpour not_allowed)
				(footprints allowed)
			)
			(placement
				(enabled no)
				(sheetname "")
			)
			(fill
				(thermal_gap 0.5)
				(thermal_bridge_width 0.5)
				(island_removal_mode 0)
			)
			(polygon
				(pts
					(arc
						(start 391.819638 -106.081068)
						(mid 391.73785 -106.062755)
						(end 391.656062 -106.081068)
					)
					(arc
						(start 391.58418 -106.009186)
						(mid 391.73785 -105.965037)
						(end 391.89152 -106.009186)
					)
				)
			)
		)
		(zone
			(layer "F.Cu")
			(hatch none 0.5)
			(connect_pads
				(clearance 0)
			)
			(min_thickness 0.25)
			(keepout
				(tracks not_allowed)
				(vias allowed)
				(pads allowed)
				(copperpour not_allowed)
				(footprints allowed)
			)
			(placement
				(enabled no)
				(sheetname "")
			)
			(fill
				(thermal_gap 0.5)
				(thermal_bridge_width 0.5)
				(island_removal_mode 0)
			)
			(polygon
				(pts
					(arc
						(start 391.819638 -105.280968)
						(mid 391.73785 -105.262655)
						(end 391.656062 -105.280968)
					)
					(arc
						(start 391.58418 -105.209086)
						(mid 391.73785 -105.164937)
						(end 391.89152 -105.209086)
					)
				)
			)
		)
		(zone
			(layer "F.Cu")
			(hatch none 0.5)
			(connect_pads
				(clearance 0)
			)
			(min_thickness 0.25)
			(keepout
				(tracks not_allowed)
				(vias allowed)
				(pads allowed)
				(copperpour not_allowed)
				(footprints allowed)
			)
			(placement
				(enabled no)
				(sheetname "")
			)
			(fill
				(thermal_gap 0.5)
				(thermal_bridge_width 0.5)
				(island_removal_mode 0)
			)
			(polygon
				(pts
					(arc
						(start 391.911332 -110.336838)
						(mid 391.929645 -110.25505)
						(end 391.911332 -110.173262)
					)
					(arc
						(start 391.983214 -110.10138)
						(mid 392.027363 -110.25505)
						(end 391.983214 -110.40872)
					)
				)
			)
		)
		(zone
			(layer "F.Cu")
			(hatch none 0.5)
			(connect_pads
				(clearance 0)
			)
			(min_thickness 0.25)
			(keepout
				(tracks not_allowed)
				(vias allowed)
				(pads allowed)
				(copperpour not_allowed)
				(footprints allowed)
			)
			(placement
				(enabled no)
				(sheetname "")
			)
			(fill
				(thermal_gap 0.5)
				(thermal_bridge_width 0.5)
				(island_removal_mode 0)
			)
			(polygon
				(pts
					(arc
						(start 391.911332 -109.536738)
						(mid 391.929645 -109.45495)
						(end 391.911332 -109.373162)
					)
					(arc
						(start 391.983214 -109.30128)
						(mid 392.027363 -109.45495)
						(end 391.983214 -109.60862)
					)
				)
			)
		)
		(zone
			(layer "F.Cu")
			(hatch none 0.5)
			(connect_pads
				(clearance 0)
			)
			(min_thickness 0.25)
			(keepout
				(tracks not_allowed)
				(vias allowed)
				(pads allowed)
				(copperpour not_allowed)
				(footprints allowed)
			)
			(placement
				(enabled no)
				(sheetname "")
			)
			(fill
				(thermal_gap 0.5)
				(thermal_bridge_width 0.5)
				(island_removal_mode 0)
			)
			(polygon
				(pts
					(arc
						(start 391.911332 -108.736638)
						(mid 391.929645 -108.65485)
						(end 391.911332 -108.573062)
					)
					(arc
						(start 391.983214 -108.50118)
						(mid 392.027363 -108.65485)
						(end 391.983214 -108.80852)
					)
				)
			)
		)
		(zone
			(layer "F.Cu")
			(hatch none 0.5)
			(connect_pads
				(clearance 0)
			)
			(min_thickness 0.25)
			(keepout
				(tracks not_allowed)
				(vias allowed)
				(pads allowed)
				(copperpour not_allowed)
				(footprints allowed)
			)
			(placement
				(enabled no)
				(sheetname "")
			)
			(fill
				(thermal_gap 0.5)
				(thermal_bridge_width 0.5)
				(island_removal_mode 0)
			)
			(polygon
				(pts
					(arc
						(start 391.911332 -107.936538)
						(mid 391.929645 -107.85475)
						(end 391.911332 -107.772962)
					)
					(arc
						(start 391.983214 -107.70108)
						(mid 392.027363 -107.85475)
						(end 391.983214 -108.00842)
					)
				)
			)
		)
		(zone
			(layer "F.Cu")
			(hatch none 0.5)
			(connect_pads
				(clearance 0)
			)
			(min_thickness 0.25)
			(keepout
				(tracks not_allowed)
				(vias allowed)
				(pads allowed)
				(copperpour not_allowed)
				(footprints allowed)
			)
			(placement
				(enabled no)
				(sheetname "")
			)
			(fill
				(thermal_gap 0.5)
				(thermal_bridge_width 0.5)
				(island_removal_mode 0)
			)
			(polygon
				(pts
					(arc
						(start 391.911332 -107.136438)
						(mid 391.929645 -107.05465)
						(end 391.911332 -106.972862)
					)
					(arc
						(start 391.983214 -106.90098)
						(mid 392.027363 -107.05465)
						(end 391.983214 -107.20832)
					)
				)
			)
		)
		(zone
			(layer "F.Cu")
			(hatch none 0.5)
			(connect_pads
				(clearance 0)
			)
			(min_thickness 0.25)
			(keepout
				(tracks not_allowed)
				(vias allowed)
				(pads allowed)
				(copperpour not_allowed)
				(footprints allowed)
			)
			(placement
				(enabled no)
				(sheetname "")
			)
			(fill
				(thermal_gap 0.5)
				(thermal_bridge_width 0.5)
				(island_removal_mode 0)
			)
			(polygon
				(pts
					(arc
						(start 391.911332 -106.336338)
						(mid 391.929645 -106.25455)
						(end 391.911332 -106.172762)
					)
					(arc
						(start 391.983214 -106.10088)
						(mid 392.027363 -106.25455)
						(end 391.983214 -106.40822)
					)
				)
			)
		)
		(zone
			(layer "F.Cu")
			(hatch none 0.5)
			(connect_pads
				(clearance 0)
			)
			(min_thickness 0.25)
			(keepout
				(tracks not_allowed)
				(vias allowed)
				(pads allowed)
				(copperpour not_allowed)
				(footprints allowed)
			)
			(placement
				(enabled no)
				(sheetname "")
			)
			(fill
				(thermal_gap 0.5)
				(thermal_bridge_width 0.5)
				(island_removal_mode 0)
			)
			(polygon
				(pts
					(arc
						(start 391.911332 -105.536238)
						(mid 391.929645 -105.45445)
						(end 391.911332 -105.372662)
					)
					(arc
						(start 391.983214 -105.30078)
						(mid 392.027363 -105.45445)
						(end 391.983214 -105.60812)
					)
				)
			)
		)
		(zone
			(layer "F.Cu")
			(hatch none 0.5)
			(connect_pads
				(clearance 0)
			)
			(min_thickness 0.25)
			(keepout
				(tracks not_allowed)
				(vias allowed)
				(pads allowed)
				(copperpour not_allowed)
				(footprints allowed)
			)
			(placement
				(enabled no)
				(sheetname "")
			)
			(fill
				(thermal_gap 0.5)
				(thermal_bridge_width 0.5)
				(island_removal_mode 0)
			)
			(polygon
				(pts
					(arc
						(start 392.364468 -113.373662)
						(mid 392.346155 -113.45545)
						(end 392.364468 -113.537238)
					)
					(arc
						(start 392.292586 -113.60912)
						(mid 392.248437 -113.45545)
						(end 392.292586 -113.30178)
					)
				)
			)
		)
		(zone
			(layer "F.Cu")
			(hatch none 0.5)
			(connect_pads
				(clearance 0)
			)
			(min_thickness 0.25)
			(keepout
				(tracks not_allowed)
				(vias allowed)
				(pads allowed)
				(copperpour not_allowed)
				(footprints allowed)
			)
			(placement
				(enabled no)
				(sheetname "")
			)
			(fill
				(thermal_gap 0.5)
				(thermal_bridge_width 0.5)
				(island_removal_mode 0)
			)
			(polygon
				(pts
					(arc
						(start 392.364468 -111.773462)
						(mid 392.346155 -111.85525)
						(end 392.364468 -111.937038)
					)
					(arc
						(start 392.292586 -112.00892)
						(mid 392.248437 -111.85525)
						(end 392.292586 -111.70158)
					)
				)
			)
		)
		(zone
			(layer "F.Cu")
			(hatch none 0.5)
			(connect_pads
				(clearance 0)
			)
			(min_thickness 0.25)
			(keepout
				(tracks not_allowed)
				(vias allowed)
				(pads allowed)
				(copperpour not_allowed)
				(footprints allowed)
			)
			(placement
				(enabled no)
				(sheetname "")
			)
			(fill
				(thermal_gap 0.5)
				(thermal_bridge_width 0.5)
				(island_removal_mode 0)
			)
			(polygon
				(pts
					(arc
						(start 392.364468 -110.973362)
						(mid 392.346155 -111.05515)
						(end 392.364468 -111.136938)
					)
					(arc
						(start 392.292586 -111.20882)
						(mid 392.248437 -111.05515)
						(end 392.292586 -110.90148)
					)
				)
			)
		)
		(zone
			(layer "F.Cu")
			(hatch none 0.5)
			(connect_pads
				(clearance 0)
			)
			(min_thickness 0.25)
			(keepout
				(tracks not_allowed)
				(vias allowed)
				(pads allowed)
				(copperpour not_allowed)
				(footprints allowed)
			)
			(placement
				(enabled no)
				(sheetname "")
			)
			(fill
				(thermal_gap 0.5)
				(thermal_bridge_width 0.5)
				(island_removal_mode 0)
			)
			(polygon
				(pts
					(arc
						(start 392.364468 -110.173262)
						(mid 392.346155 -110.25505)
						(end 392.364468 -110.336838)
					)
					(arc
						(start 392.292586 -110.40872)
						(mid 392.248437 -110.25505)
						(end 392.292586 -110.10138)
					)
				)
			)
		)
		(zone
			(layer "F.Cu")
			(hatch none 0.5)
			(connect_pads
				(clearance 0)
			)
			(min_thickness 0.25)
			(keepout
				(tracks not_allowed)
				(vias allowed)
				(pads allowed)
				(copperpour not_allowed)
				(footprints allowed)
			)
			(placement
				(enabled no)
				(sheetname "")
			)
			(fill
				(thermal_gap 0.5)
				(thermal_bridge_width 0.5)
				(island_removal_mode 0)
			)
			(polygon
				(pts
					(arc
						(start 392.364468 -109.373162)
						(mid 392.346155 -109.45495)
						(end 392.364468 -109.536738)
					)
					(arc
						(start 392.292586 -109.60862)
						(mid 392.248437 -109.45495)
						(end 392.292586 -109.30128)
					)
				)
			)
		)
		(zone
			(layer "F.Cu")
			(hatch none 0.5)
			(connect_pads
				(clearance 0)
			)
			(min_thickness 0.25)
			(keepout
				(tracks not_allowed)
				(vias allowed)
				(pads allowed)
				(copperpour not_allowed)
				(footprints allowed)
			)
			(placement
				(enabled no)
				(sheetname "")
			)
			(fill
				(thermal_gap 0.5)
				(thermal_bridge_width 0.5)
				(island_removal_mode 0)
			)
			(polygon
				(pts
					(arc
						(start 392.364468 -108.573062)
						(mid 392.346155 -108.65485)
						(end 392.364468 -108.736638)
					)
					(arc
						(start 392.292586 -108.80852)
						(mid 392.248437 -108.65485)
						(end 392.292586 -108.50118)
					)
				)
			)
		)
		(zone
			(layer "F.Cu")
			(hatch none 0.5)
			(connect_pads
				(clearance 0)
			)
			(min_thickness 0.25)
			(keepout
				(tracks not_allowed)
				(vias allowed)
				(pads allowed)
				(copperpour not_allowed)
				(footprints allowed)
			)
			(placement
				(enabled no)
				(sheetname "")
			)
			(fill
				(thermal_gap 0.5)
				(thermal_bridge_width 0.5)
				(island_removal_mode 0)
			)
			(polygon
				(pts
					(arc
						(start 392.364468 -106.972862)
						(mid 392.346155 -107.05465)
						(end 392.364468 -107.136438)
					)
					(arc
						(start 392.292586 -107.20832)
						(mid 392.248437 -107.05465)
						(end 392.292586 -106.90098)
					)
				)
			)
		)
		(zone
			(layer "F.Cu")
			(hatch none 0.5)
			(connect_pads
				(clearance 0)
			)
			(min_thickness 0.25)
			(keepout
				(tracks not_allowed)
				(vias allowed)
				(pads allowed)
				(copperpour not_allowed)
				(footprints allowed)
			)
			(placement
				(enabled no)
				(sheetname "")
			)
			(fill
				(thermal_gap 0.5)
				(thermal_bridge_width 0.5)
				(island_removal_mode 0)
			)
			(polygon
				(pts
					(arc
						(start 392.364468 -106.172762)
						(mid 392.346155 -106.25455)
						(end 392.364468 -106.336338)
					)
					(arc
						(start 392.292586 -106.40822)
						(mid 392.248437 -106.25455)
						(end 392.292586 -106.10088)
					)
				)
			)
		)
		(zone
			(layer "F.Cu")
			(hatch none 0.5)
			(connect_pads
				(clearance 0)
			)
			(min_thickness 0.25)
			(keepout
				(tracks not_allowed)
				(vias allowed)
				(pads allowed)
				(copperpour not_allowed)
				(footprints allowed)
			)
			(placement
				(enabled no)
				(sheetname "")
			)
			(fill
				(thermal_gap 0.5)
				(thermal_bridge_width 0.5)
				(island_removal_mode 0)
			)
			(polygon
				(pts
					(arc
						(start 392.364468 -105.372662)
						(mid 392.346155 -105.45445)
						(end 392.364468 -105.536238)
					)
					(arc
						(start 392.292586 -105.60812)
						(mid 392.248437 -105.45445)
						(end 392.292586 -105.30078)
					)
				)
			)
		)
		(zone
			(layer "F.Cu")
			(hatch none 0.5)
			(connect_pads
				(clearance 0)
			)
			(min_thickness 0.25)
			(keepout
				(tracks not_allowed)
				(vias allowed)
				(pads allowed)
				(copperpour not_allowed)
				(footprints allowed)
			)
			(placement
				(enabled no)
				(sheetname "")
			)
			(fill
				(thermal_gap 0.5)
				(thermal_bridge_width 0.5)
				(island_removal_mode 0)
			)
			(polygon
				(pts
					(arc
						(start 392.456162 -113.628932)
						(mid 392.53795 -113.647245)
						(end 392.619738 -113.628932)
					)
					(arc
						(start 392.69162 -113.700814)
						(mid 392.53795 -113.744963)
						(end 392.38428 -113.700814)
					)
				)
			)
		)
		(zone
			(layer "F.Cu")
			(hatch none 0.5)
			(connect_pads
				(clearance 0)
			)
			(min_thickness 0.25)
			(keepout
				(tracks not_allowed)
				(vias allowed)
				(pads allowed)
				(copperpour not_allowed)
				(footprints allowed)
			)
			(placement
				(enabled no)
				(sheetname "")
			)
			(fill
				(thermal_gap 0.5)
				(thermal_bridge_width 0.5)
				(island_removal_mode 0)
			)
			(polygon
				(pts
					(arc
						(start 392.456162 -112.028732)
						(mid 392.53795 -112.047045)
						(end 392.619738 -112.028732)
					)
					(arc
						(start 392.69162 -112.100614)
						(mid 392.53795 -112.144763)
						(end 392.38428 -112.100614)
					)
				)
			)
		)
		(zone
			(layer "F.Cu")
			(hatch none 0.5)
			(connect_pads
				(clearance 0)
			)
			(min_thickness 0.25)
			(keepout
				(tracks not_allowed)
				(vias allowed)
				(pads allowed)
				(copperpour not_allowed)
				(footprints allowed)
			)
			(placement
				(enabled no)
				(sheetname "")
			)
			(fill
				(thermal_gap 0.5)
				(thermal_bridge_width 0.5)
				(island_removal_mode 0)
			)
			(polygon
				(pts
					(arc
						(start 392.456162 -111.228632)
						(mid 392.53795 -111.246945)
						(end 392.619738 -111.228632)
					)
					(arc
						(start 392.69162 -111.300514)
						(mid 392.53795 -111.344663)
						(end 392.38428 -111.300514)
					)
				)
			)
		)
		(zone
			(layer "F.Cu")
			(hatch none 0.5)
			(connect_pads
				(clearance 0)
			)
			(min_thickness 0.25)
			(keepout
				(tracks not_allowed)
				(vias allowed)
				(pads allowed)
				(copperpour not_allowed)
				(footprints allowed)
			)
			(placement
				(enabled no)
				(sheetname "")
			)
			(fill
				(thermal_gap 0.5)
				(thermal_bridge_width 0.5)
				(island_removal_mode 0)
			)
			(polygon
				(pts
					(arc
						(start 392.456162 -110.428532)
						(mid 392.53795 -110.446845)
						(end 392.619738 -110.428532)
					)
					(arc
						(start 392.69162 -110.500414)
						(mid 392.53795 -110.544563)
						(end 392.38428 -110.500414)
					)
				)
			)
		)
		(zone
			(layer "F.Cu")
			(hatch none 0.5)
			(connect_pads
				(clearance 0)
			)
			(min_thickness 0.25)
			(keepout
				(tracks not_allowed)
				(vias allowed)
				(pads allowed)
				(copperpour not_allowed)
				(footprints allowed)
			)
			(placement
				(enabled no)
				(sheetname "")
			)
			(fill
				(thermal_gap 0.5)
				(thermal_bridge_width 0.5)
				(island_removal_mode 0)
			)
			(polygon
				(pts
					(arc
						(start 392.456162 -109.628432)
						(mid 392.53795 -109.646745)
						(end 392.619738 -109.628432)
					)
					(arc
						(start 392.69162 -109.700314)
						(mid 392.53795 -109.744463)
						(end 392.38428 -109.700314)
					)
				)
			)
		)
		(zone
			(layer "F.Cu")
			(hatch none 0.5)
			(connect_pads
				(clearance 0)
			)
			(min_thickness 0.25)
			(keepout
				(tracks not_allowed)
				(vias allowed)
				(pads allowed)
				(copperpour not_allowed)
				(footprints allowed)
			)
			(placement
				(enabled no)
				(sheetname "")
			)
			(fill
				(thermal_gap 0.5)
				(thermal_bridge_width 0.5)
				(island_removal_mode 0)
			)
			(polygon
				(pts
					(arc
						(start 392.456162 -108.828332)
						(mid 392.53795 -108.846645)
						(end 392.619738 -108.828332)
					)
					(arc
						(start 392.69162 -108.900214)
						(mid 392.53795 -108.944363)
						(end 392.38428 -108.900214)
					)
				)
			)
		)
		(zone
			(layer "F.Cu")
			(hatch none 0.5)
			(connect_pads
				(clearance 0)
			)
			(min_thickness 0.25)
			(keepout
				(tracks not_allowed)
				(vias allowed)
				(pads allowed)
				(copperpour not_allowed)
				(footprints allowed)
			)
			(placement
				(enabled no)
				(sheetname "")
			)
			(fill
				(thermal_gap 0.5)
				(thermal_bridge_width 0.5)
				(island_removal_mode 0)
			)
			(polygon
				(pts
					(arc
						(start 392.456162 -107.228132)
						(mid 392.53795 -107.246445)
						(end 392.619738 -107.228132)
					)
					(arc
						(start 392.69162 -107.300014)
						(mid 392.53795 -107.344163)
						(end 392.38428 -107.300014)
					)
				)
			)
		)
		(zone
			(layer "F.Cu")
			(hatch none 0.5)
			(connect_pads
				(clearance 0)
			)
			(min_thickness 0.25)
			(keepout
				(tracks not_allowed)
				(vias allowed)
				(pads allowed)
				(copperpour not_allowed)
				(footprints allowed)
			)
			(placement
				(enabled no)
				(sheetname "")
			)
			(fill
				(thermal_gap 0.5)
				(thermal_bridge_width 0.5)
				(island_removal_mode 0)
			)
			(polygon
				(pts
					(arc
						(start 392.456162 -106.428032)
						(mid 392.53795 -106.446345)
						(end 392.619738 -106.428032)
					)
					(arc
						(start 392.69162 -106.499914)
						(mid 392.53795 -106.544063)
						(end 392.38428 -106.499914)
					)
				)
			)
		)
		(zone
			(layer "F.Cu")
			(hatch none 0.5)
			(connect_pads
				(clearance 0)
			)
			(min_thickness 0.25)
			(keepout
				(tracks not_allowed)
				(vias allowed)
				(pads allowed)
				(copperpour not_allowed)
				(footprints allowed)
			)
			(placement
				(enabled no)
				(sheetname "")
			)
			(fill
				(thermal_gap 0.5)
				(thermal_bridge_width 0.5)
				(island_removal_mode 0)
			)
			(polygon
				(pts
					(arc
						(start 392.456162 -105.627932)
						(mid 392.53795 -105.646245)
						(end 392.619738 -105.627932)
					)
					(arc
						(start 392.69162 -105.699814)
						(mid 392.53795 -105.743963)
						(end 392.38428 -105.699814)
					)
				)
			)
		)
		(zone
			(layer "F.Cu")
			(hatch none 0.5)
			(connect_pads
				(clearance 0)
			)
			(min_thickness 0.25)
			(keepout
				(tracks not_allowed)
				(vias allowed)
				(pads allowed)
				(copperpour not_allowed)
				(footprints allowed)
			)
			(placement
				(enabled no)
				(sheetname "")
			)
			(fill
				(thermal_gap 0.5)
				(thermal_bridge_width 0.5)
				(island_removal_mode 0)
			)
			(polygon
				(pts
					(arc
						(start 392.619738 -113.281968)
						(mid 392.53795 -113.263655)
						(end 392.456162 -113.281968)
					)
					(arc
						(start 392.38428 -113.210086)
						(mid 392.53795 -113.165937)
						(end 392.69162 -113.210086)
					)
				)
			)
		)
		(zone
			(layer "F.Cu")
			(hatch none 0.5)
			(connect_pads
				(clearance 0)
			)
			(min_thickness 0.25)
			(keepout
				(tracks not_allowed)
				(vias allowed)
				(pads allowed)
				(copperpour not_allowed)
				(footprints allowed)
			)
			(placement
				(enabled no)
				(sheetname "")
			)
			(fill
				(thermal_gap 0.5)
				(thermal_bridge_width 0.5)
				(island_removal_mode 0)
			)
			(polygon
				(pts
					(arc
						(start 392.619738 -111.681768)
						(mid 392.53795 -111.663455)
						(end 392.456162 -111.681768)
					)
					(arc
						(start 392.38428 -111.609886)
						(mid 392.53795 -111.565737)
						(end 392.69162 -111.609886)
					)
				)
			)
		)
		(zone
			(layer "F.Cu")
			(hatch none 0.5)
			(connect_pads
				(clearance 0)
			)
			(min_thickness 0.25)
			(keepout
				(tracks not_allowed)
				(vias allowed)
				(pads allowed)
				(copperpour not_allowed)
				(footprints allowed)
			)
			(placement
				(enabled no)
				(sheetname "")
			)
			(fill
				(thermal_gap 0.5)
				(thermal_bridge_width 0.5)
				(island_removal_mode 0)
			)
			(polygon
				(pts
					(arc
						(start 392.619738 -110.881668)
						(mid 392.53795 -110.863355)
						(end 392.456162 -110.881668)
					)
					(arc
						(start 392.38428 -110.809786)
						(mid 392.53795 -110.765637)
						(end 392.69162 -110.809786)
					)
				)
			)
		)
		(zone
			(layer "F.Cu")
			(hatch none 0.5)
			(connect_pads
				(clearance 0)
			)
			(min_thickness 0.25)
			(keepout
				(tracks not_allowed)
				(vias allowed)
				(pads allowed)
				(copperpour not_allowed)
				(footprints allowed)
			)
			(placement
				(enabled no)
				(sheetname "")
			)
			(fill
				(thermal_gap 0.5)
				(thermal_bridge_width 0.5)
				(island_removal_mode 0)
			)
			(polygon
				(pts
					(arc
						(start 392.619738 -110.081568)
						(mid 392.53795 -110.063255)
						(end 392.456162 -110.081568)
					)
					(arc
						(start 392.38428 -110.009686)
						(mid 392.53795 -109.965537)
						(end 392.69162 -110.009686)
					)
				)
			)
		)
		(zone
			(layer "F.Cu")
			(hatch none 0.5)
			(connect_pads
				(clearance 0)
			)
			(min_thickness 0.25)
			(keepout
				(tracks not_allowed)
				(vias allowed)
				(pads allowed)
				(copperpour not_allowed)
				(footprints allowed)
			)
			(placement
				(enabled no)
				(sheetname "")
			)
			(fill
				(thermal_gap 0.5)
				(thermal_bridge_width 0.5)
				(island_removal_mode 0)
			)
			(polygon
				(pts
					(arc
						(start 392.619738 -109.281468)
						(mid 392.53795 -109.263155)
						(end 392.456162 -109.281468)
					)
					(arc
						(start 392.38428 -109.209586)
						(mid 392.53795 -109.165437)
						(end 392.69162 -109.209586)
					)
				)
			)
		)
		(zone
			(layer "F.Cu")
			(hatch none 0.5)
			(connect_pads
				(clearance 0)
			)
			(min_thickness 0.25)
			(keepout
				(tracks not_allowed)
				(vias allowed)
				(pads allowed)
				(copperpour not_allowed)
				(footprints allowed)
			)
			(placement
				(enabled no)
				(sheetname "")
			)
			(fill
				(thermal_gap 0.5)
				(thermal_bridge_width 0.5)
				(island_removal_mode 0)
			)
			(polygon
				(pts
					(arc
						(start 392.619738 -108.481368)
						(mid 392.53795 -108.463055)
						(end 392.456162 -108.481368)
					)
					(arc
						(start 392.38428 -108.409486)
						(mid 392.53795 -108.365337)
						(end 392.69162 -108.409486)
					)
				)
			)
		)
		(zone
			(layer "F.Cu")
			(hatch none 0.5)
			(connect_pads
				(clearance 0)
			)
			(min_thickness 0.25)
			(keepout
				(tracks not_allowed)
				(vias allowed)
				(pads allowed)
				(copperpour not_allowed)
				(footprints allowed)
			)
			(placement
				(enabled no)
				(sheetname "")
			)
			(fill
				(thermal_gap 0.5)
				(thermal_bridge_width 0.5)
				(island_removal_mode 0)
			)
			(polygon
				(pts
					(arc
						(start 392.619738 -106.881168)
						(mid 392.53795 -106.862855)
						(end 392.456162 -106.881168)
					)
					(arc
						(start 392.38428 -106.809286)
						(mid 392.53795 -106.765137)
						(end 392.69162 -106.809286)
					)
				)
			)
		)
		(zone
			(layer "F.Cu")
			(hatch none 0.5)
			(connect_pads
				(clearance 0)
			)
			(min_thickness 0.25)
			(keepout
				(tracks not_allowed)
				(vias allowed)
				(pads allowed)
				(copperpour not_allowed)
				(footprints allowed)
			)
			(placement
				(enabled no)
				(sheetname "")
			)
			(fill
				(thermal_gap 0.5)
				(thermal_bridge_width 0.5)
				(island_removal_mode 0)
			)
			(polygon
				(pts
					(arc
						(start 392.619738 -106.081068)
						(mid 392.53795 -106.062755)
						(end 392.456162 -106.081068)
					)
					(arc
						(start 392.38428 -106.009186)
						(mid 392.53795 -105.965037)
						(end 392.69162 -106.009186)
					)
				)
			)
		)
		(zone
			(layer "F.Cu")
			(hatch none 0.5)
			(connect_pads
				(clearance 0)
			)
			(min_thickness 0.25)
			(keepout
				(tracks not_allowed)
				(vias allowed)
				(pads allowed)
				(copperpour not_allowed)
				(footprints allowed)
			)
			(placement
				(enabled no)
				(sheetname "")
			)
			(fill
				(thermal_gap 0.5)
				(thermal_bridge_width 0.5)
				(island_removal_mode 0)
			)
			(polygon
				(pts
					(arc
						(start 392.619738 -105.280968)
						(mid 392.53795 -105.262655)
						(end 392.456162 -105.280968)
					)
					(arc
						(start 392.38428 -105.209086)
						(mid 392.53795 -105.164937)
						(end 392.69162 -105.209086)
					)
				)
			)
		)
		(zone
			(layer "F.Cu")
			(hatch none 0.5)
			(connect_pads
				(clearance 0)
			)
			(min_thickness 0.25)
			(keepout
				(tracks not_allowed)
				(vias allowed)
				(pads allowed)
				(copperpour not_allowed)
				(footprints allowed)
			)
			(placement
				(enabled no)
				(sheetname "")
			)
			(fill
				(thermal_gap 0.5)
				(thermal_bridge_width 0.5)
				(island_removal_mode 0)
			)
			(polygon
				(pts
					(arc
						(start 392.711432 -113.537238)
						(mid 392.729745 -113.45545)
						(end 392.711432 -113.373662)
					)
					(arc
						(start 392.783314 -113.30178)
						(mid 392.827463 -113.45545)
						(end 392.783314 -113.60912)
					)
				)
			)
		)
		(zone
			(layer "F.Cu")
			(hatch none 0.5)
			(connect_pads
				(clearance 0)
			)
			(min_thickness 0.25)
			(keepout
				(tracks not_allowed)
				(vias allowed)
				(pads allowed)
				(copperpour not_allowed)
				(footprints allowed)
			)
			(placement
				(enabled no)
				(sheetname "")
			)
			(fill
				(thermal_gap 0.5)
				(thermal_bridge_width 0.5)
				(island_removal_mode 0)
			)
			(polygon
				(pts
					(arc
						(start 392.711432 -111.937038)
						(mid 392.729745 -111.85525)
						(end 392.711432 -111.773462)
					)
					(arc
						(start 392.783314 -111.70158)
						(mid 392.827463 -111.85525)
						(end 392.783314 -112.00892)
					)
				)
			)
		)
		(zone
			(layer "F.Cu")
			(hatch none 0.5)
			(connect_pads
				(clearance 0)
			)
			(min_thickness 0.25)
			(keepout
				(tracks not_allowed)
				(vias allowed)
				(pads allowed)
				(copperpour not_allowed)
				(footprints allowed)
			)
			(placement
				(enabled no)
				(sheetname "")
			)
			(fill
				(thermal_gap 0.5)
				(thermal_bridge_width 0.5)
				(island_removal_mode 0)
			)
			(polygon
				(pts
					(arc
						(start 392.711432 -111.136938)
						(mid 392.729745 -111.05515)
						(end 392.711432 -110.973362)
					)
					(arc
						(start 392.783314 -110.90148)
						(mid 392.827463 -111.05515)
						(end 392.783314 -111.20882)
					)
				)
			)
		)
		(zone
			(layer "F.Cu")
			(hatch none 0.5)
			(connect_pads
				(clearance 0)
			)
			(min_thickness 0.25)
			(keepout
				(tracks not_allowed)
				(vias allowed)
				(pads allowed)
				(copperpour not_allowed)
				(footprints allowed)
			)
			(placement
				(enabled no)
				(sheetname "")
			)
			(fill
				(thermal_gap 0.5)
				(thermal_bridge_width 0.5)
				(island_removal_mode 0)
			)
			(polygon
				(pts
					(arc
						(start 392.711432 -110.336838)
						(mid 392.729745 -110.25505)
						(end 392.711432 -110.173262)
					)
					(arc
						(start 392.783314 -110.10138)
						(mid 392.827463 -110.25505)
						(end 392.783314 -110.40872)
					)
				)
			)
		)
		(zone
			(layer "F.Cu")
			(hatch none 0.5)
			(connect_pads
				(clearance 0)
			)
			(min_thickness 0.25)
			(keepout
				(tracks not_allowed)
				(vias allowed)
				(pads allowed)
				(copperpour not_allowed)
				(footprints allowed)
			)
			(placement
				(enabled no)
				(sheetname "")
			)
			(fill
				(thermal_gap 0.5)
				(thermal_bridge_width 0.5)
				(island_removal_mode 0)
			)
			(polygon
				(pts
					(arc
						(start 392.711432 -109.536738)
						(mid 392.729745 -109.45495)
						(end 392.711432 -109.373162)
					)
					(arc
						(start 392.783314 -109.30128)
						(mid 392.827463 -109.45495)
						(end 392.783314 -109.60862)
					)
				)
			)
		)
		(zone
			(layer "F.Cu")
			(hatch none 0.5)
			(connect_pads
				(clearance 0)
			)
			(min_thickness 0.25)
			(keepout
				(tracks not_allowed)
				(vias allowed)
				(pads allowed)
				(copperpour not_allowed)
				(footprints allowed)
			)
			(placement
				(enabled no)
				(sheetname "")
			)
			(fill
				(thermal_gap 0.5)
				(thermal_bridge_width 0.5)
				(island_removal_mode 0)
			)
			(polygon
				(pts
					(arc
						(start 392.711432 -108.736638)
						(mid 392.729745 -108.65485)
						(end 392.711432 -108.573062)
					)
					(arc
						(start 392.783314 -108.50118)
						(mid 392.827463 -108.65485)
						(end 392.783314 -108.80852)
					)
				)
			)
		)
		(zone
			(layer "F.Cu")
			(hatch none 0.5)
			(connect_pads
				(clearance 0)
			)
			(min_thickness 0.25)
			(keepout
				(tracks not_allowed)
				(vias allowed)
				(pads allowed)
				(copperpour not_allowed)
				(footprints allowed)
			)
			(placement
				(enabled no)
				(sheetname "")
			)
			(fill
				(thermal_gap 0.5)
				(thermal_bridge_width 0.5)
				(island_removal_mode 0)
			)
			(polygon
				(pts
					(arc
						(start 392.711432 -107.136438)
						(mid 392.729745 -107.05465)
						(end 392.711432 -106.972862)
					)
					(arc
						(start 392.783314 -106.90098)
						(mid 392.827463 -107.05465)
						(end 392.783314 -107.20832)
					)
				)
			)
		)
		(zone
			(layer "F.Cu")
			(hatch none 0.5)
			(connect_pads
				(clearance 0)
			)
			(min_thickness 0.25)
			(keepout
				(tracks not_allowed)
				(vias allowed)
				(pads allowed)
				(copperpour not_allowed)
				(footprints allowed)
			)
			(placement
				(enabled no)
				(sheetname "")
			)
			(fill
				(thermal_gap 0.5)
				(thermal_bridge_width 0.5)
				(island_removal_mode 0)
			)
			(polygon
				(pts
					(arc
						(start 392.711432 -106.336338)
						(mid 392.729745 -106.25455)
						(end 392.711432 -106.172762)
					)
					(arc
						(start 392.783314 -106.10088)
						(mid 392.827463 -106.25455)
						(end 392.783314 -106.40822)
					)
				)
			)
		)
		(zone
			(layer "F.Cu")
			(hatch none 0.5)
			(connect_pads
				(clearance 0)
			)
			(min_thickness 0.25)
			(keepout
				(tracks not_allowed)
				(vias allowed)
				(pads allowed)
				(copperpour not_allowed)
				(footprints allowed)
			)
			(placement
				(enabled no)
				(sheetname "")
			)
			(fill
				(thermal_gap 0.5)
				(thermal_bridge_width 0.5)
				(island_removal_mode 0)
			)
			(polygon
				(pts
					(arc
						(start 392.711432 -105.536238)
						(mid 392.729745 -105.45445)
						(end 392.711432 -105.372662)
					)
					(arc
						(start 392.783314 -105.30078)
						(mid 392.827463 -105.45445)
						(end 392.783314 -105.60812)
					)
				)
			)
		)
		(zone
			(layer "F.Cu")
			(hatch none 0.5)
			(connect_pads
				(clearance 0)
			)
			(min_thickness 0.25)
			(keepout
				(tracks not_allowed)
				(vias allowed)
				(pads allowed)
				(copperpour not_allowed)
				(footprints allowed)
			)
			(placement
				(enabled no)
				(sheetname "")
			)
			(fill
				(thermal_gap 0.5)
				(thermal_bridge_width 0.5)
				(island_removal_mode 0)
			)
			(polygon
				(pts
					(arc
						(start 393.012168 -111.490252)
						(mid 392.993855 -111.57204)
						(end 393.012168 -111.653828)
					)
					(arc
						(start 392.940286 -111.72571)
						(mid 392.896137 -111.57204)
						(end 392.940286 -111.41837)
					)
				)
			)
		)
		(zone
			(layer "F.Cu")
			(hatch none 0.5)
			(connect_pads
				(clearance 0)
			)
			(min_thickness 0.25)
			(keepout
				(tracks not_allowed)
				(vias allowed)
				(pads allowed)
				(copperpour not_allowed)
				(footprints allowed)
			)
			(placement
				(enabled no)
				(sheetname "")
			)
			(fill
				(thermal_gap 0.5)
				(thermal_bridge_width 0.5)
				(island_removal_mode 0)
			)
			(polygon
				(pts
					(arc
						(start 393.012168 -109.773212)
						(mid 392.993855 -109.855)
						(end 393.012168 -109.936788)
					)
					(arc
						(start 392.940286 -110.00867)
						(mid 392.896137 -109.855)
						(end 392.940286 -109.70133)
					)
				)
			)
		)
		(zone
			(layer "F.Cu")
			(hatch none 0.5)
			(connect_pads
				(clearance 0)
			)
			(min_thickness 0.25)
			(keepout
				(tracks not_allowed)
				(vias allowed)
				(pads allowed)
				(copperpour not_allowed)
				(footprints allowed)
			)
			(placement
				(enabled no)
				(sheetname "")
			)
			(fill
				(thermal_gap 0.5)
				(thermal_bridge_width 0.5)
				(island_removal_mode 0)
			)
			(polygon
				(pts
					(arc
						(start 393.103862 -111.745522)
						(mid 393.18565 -111.763835)
						(end 393.267438 -111.745522)
					)
					(arc
						(start 393.33932 -111.817404)
						(mid 393.18565 -111.861553)
						(end 393.03198 -111.817404)
					)
				)
			)
		)
		(zone
			(layer "F.Cu")
			(hatch none 0.5)
			(connect_pads
				(clearance 0)
			)
			(min_thickness 0.25)
			(keepout
				(tracks not_allowed)
				(vias allowed)
				(pads allowed)
				(copperpour not_allowed)
				(footprints allowed)
			)
			(placement
				(enabled no)
				(sheetname "")
			)
			(fill
				(thermal_gap 0.5)
				(thermal_bridge_width 0.5)
				(island_removal_mode 0)
			)
			(polygon
				(pts
					(arc
						(start 393.103862 -110.028482)
						(mid 393.18565 -110.046795)
						(end 393.267438 -110.028482)
					)
					(arc
						(start 393.33932 -110.100364)
						(mid 393.18565 -110.144513)
						(end 393.03198 -110.100364)
					)
				)
			)
		)
		(zone
			(layer "F.Cu")
			(hatch none 0.5)
			(connect_pads
				(clearance 0)
			)
			(min_thickness 0.25)
			(keepout
				(tracks not_allowed)
				(vias allowed)
				(pads allowed)
				(copperpour not_allowed)
				(footprints allowed)
			)
			(placement
				(enabled no)
				(sheetname "")
			)
			(fill
				(thermal_gap 0.5)
				(thermal_bridge_width 0.5)
				(island_removal_mode 0)
			)
			(polygon
				(pts
					(arc
						(start 393.267438 -111.398558)
						(mid 393.18565 -111.380245)
						(end 393.103862 -111.398558)
					)
					(arc
						(start 393.03198 -111.326676)
						(mid 393.18565 -111.282527)
						(end 393.33932 -111.326676)
					)
				)
			)
		)
		(zone
			(layer "F.Cu")
			(hatch none 0.5)
			(connect_pads
				(clearance 0)
			)
			(min_thickness 0.25)
			(keepout
				(tracks not_allowed)
				(vias allowed)
				(pads allowed)
				(copperpour not_allowed)
				(footprints allowed)
			)
			(placement
				(enabled no)
				(sheetname "")
			)
			(fill
				(thermal_gap 0.5)
				(thermal_bridge_width 0.5)
				(island_removal_mode 0)
			)
			(polygon
				(pts
					(arc
						(start 393.267438 -109.681518)
						(mid 393.18565 -109.663205)
						(end 393.103862 -109.681518)
					)
					(arc
						(start 393.03198 -109.609636)
						(mid 393.18565 -109.565487)
						(end 393.33932 -109.609636)
					)
				)
			)
		)
		(zone
			(layer "F.Cu")
			(hatch none 0.5)
			(connect_pads
				(clearance 0)
			)
			(min_thickness 0.25)
			(keepout
				(tracks not_allowed)
				(vias allowed)
				(pads allowed)
				(copperpour not_allowed)
				(footprints allowed)
			)
			(placement
				(enabled no)
				(sheetname "")
			)
			(fill
				(thermal_gap 0.5)
				(thermal_bridge_width 0.5)
				(island_removal_mode 0)
			)
			(polygon
				(pts
					(arc
						(start 393.359132 -111.653828)
						(mid 393.377445 -111.57204)
						(end 393.359132 -111.490252)
					)
					(arc
						(start 393.431014 -111.41837)
						(mid 393.475163 -111.57204)
						(end 393.431014 -111.72571)
					)
				)
			)
		)
		(zone
			(layer "F.Cu")
			(hatch none 0.5)
			(connect_pads
				(clearance 0)
			)
			(min_thickness 0.25)
			(keepout
				(tracks not_allowed)
				(vias allowed)
				(pads allowed)
				(copperpour not_allowed)
				(footprints allowed)
			)
			(placement
				(enabled no)
				(sheetname "")
			)
			(fill
				(thermal_gap 0.5)
				(thermal_bridge_width 0.5)
				(island_removal_mode 0)
			)
			(polygon
				(pts
					(arc
						(start 393.359132 -109.936788)
						(mid 393.377445 -109.855)
						(end 393.359132 -109.773212)
					)
					(arc
						(start 393.431014 -109.70133)
						(mid 393.475163 -109.855)
						(end 393.431014 -110.00867)
					)
				)
			)
		)
		(zone
			(layer "F.Cu")
			(hatch none 0.5)
			(connect_pads
				(clearance 0)
			)
			(min_thickness 0.25)
			(keepout
				(tracks not_allowed)
				(vias allowed)
				(pads allowed)
				(copperpour not_allowed)
				(footprints allowed)
			)
			(placement
				(enabled no)
				(sheetname "")
			)
			(fill
				(thermal_gap 0.5)
				(thermal_bridge_width 0.5)
				(island_removal_mode 0)
			)
			(polygon
				(pts
					(arc
						(start 393.507468 -110.631732)
						(mid 393.489155 -110.71352)
						(end 393.507468 -110.795308)
					)
					(arc
						(start 393.435586 -110.86719)
						(mid 393.391437 -110.71352)
						(end 393.435586 -110.55985)
					)
				)
			)
		)
		(zone
			(layer "F.Cu")
			(hatch none 0.5)
			(connect_pads
				(clearance 0)
			)
			(min_thickness 0.25)
			(keepout
				(tracks not_allowed)
				(vias allowed)
				(pads allowed)
				(copperpour not_allowed)
				(footprints allowed)
			)
			(placement
				(enabled no)
				(sheetname "")
			)
			(fill
				(thermal_gap 0.5)
				(thermal_bridge_width 0.5)
				(island_removal_mode 0)
			)
			(polygon
				(pts
					(arc
						(start 393.599162 -110.887002)
						(mid 393.68095 -110.905315)
						(end 393.762738 -110.887002)
					)
					(arc
						(start 393.83462 -110.958884)
						(mid 393.68095 -111.003033)
						(end 393.52728 -110.958884)
					)
				)
			)
		)
		(zone
			(layer "F.Cu")
			(hatch none 0.5)
			(connect_pads
				(clearance 0)
			)
			(min_thickness 0.25)
			(keepout
				(tracks not_allowed)
				(vias allowed)
				(pads allowed)
				(copperpour not_allowed)
				(footprints allowed)
			)
			(placement
				(enabled no)
				(sheetname "")
			)
			(fill
				(thermal_gap 0.5)
				(thermal_bridge_width 0.5)
				(island_removal_mode 0)
			)
			(polygon
				(pts
					(arc
						(start 393.762738 -110.540038)
						(mid 393.68095 -110.521725)
						(end 393.599162 -110.540038)
					)
					(arc
						(start 393.52728 -110.468156)
						(mid 393.68095 -110.424007)
						(end 393.83462 -110.468156)
					)
				)
			)
		)
		(zone
			(layer "F.Cu")
			(hatch none 0.5)
			(connect_pads
				(clearance 0)
			)
			(min_thickness 0.25)
			(keepout
				(tracks not_allowed)
				(vias allowed)
				(pads allowed)
				(copperpour not_allowed)
				(footprints allowed)
			)
			(placement
				(enabled no)
				(sheetname "")
			)
			(fill
				(thermal_gap 0.5)
				(thermal_bridge_width 0.5)
				(island_removal_mode 0)
			)
			(polygon
				(pts
					(arc
						(start 393.854432 -110.795308)
						(mid 393.872745 -110.71352)
						(end 393.854432 -110.631732)
					)
					(arc
						(start 393.926314 -110.55985)
						(mid 393.970463 -110.71352)
						(end 393.926314 -110.86719)
					)
				)
			)
		)
		(zone
			(layer "F.Cu")
			(hatch none 0.5)
			(connect_pads
				(clearance 0)
			)
			(min_thickness 0.25)
			(keepout
				(tracks not_allowed)
				(vias allowed)
				(pads allowed)
				(copperpour not_allowed)
				(footprints allowed)
			)
			(placement
				(enabled no)
				(sheetname "")
			)
			(fill
				(thermal_gap 0.5)
				(thermal_bridge_width 0.5)
				(island_removal_mode 0)
			)
			(polygon
				(pts
					(arc
						(start 391.227056 -111.865664)
						(mid 390.948159 -111.565944)
						(end 390.64819 -111.844836)
					)
					(arc
						(start 390.74598 -111.848392)
						(mid 390.944608 -111.66348)
						(end 391.12952 -111.862108)
					)
				)
			)
		)
		(zone
			(layer "F.Cu")
			(hatch none 0.5)
			(connect_pads
				(clearance 0)
			)
			(min_thickness 0.25)
			(keepout
				(tracks not_allowed)
				(vias allowed)
				(pads allowed)
				(copperpour not_allowed)
				(footprints allowed)
			)
			(placement
				(enabled no)
				(sheetname "")
			)
			(fill
				(thermal_gap 0.5)
				(thermal_bridge_width 0.5)
				(island_removal_mode 0)
			)
			(polygon
				(pts
					(arc
						(start 392.53795 -115.34521)
						(mid 392.82751 -115.05565)
						(end 392.53795 -114.765836)
					)
					(arc
						(start 392.53795 -114.86388)
						(mid 392.72972 -115.05565)
						(end 392.53795 -115.24742)
					)
				)
			)
		)
		(zone
			(layer "F.Cu")
			(hatch none 0.5)
			(connect_pads
				(clearance 0)
			)
			(min_thickness 0.25)
			(keepout
				(tracks not_allowed)
				(vias allowed)
				(pads allowed)
				(copperpour not_allowed)
				(footprints allowed)
			)
			(placement
				(enabled no)
				(sheetname "")
			)
			(fill
				(thermal_gap 0.5)
				(thermal_bridge_width 0.5)
				(island_removal_mode 0)
			)
			(polygon
				(pts
					(arc
						(start 381.865632 -103.564944)
						(mid 381.545017 -103.993641)
						(end 382.074674 -103.916734)
					)
					(arc
						(start 381.978916 -103.89489)
						(mid 381.62879 -103.942971)
						(end 381.83947 -103.659178)
					)
				)
			)
		)
		(zone
			(layer "F.Cu")
			(hatch none 0.5)
			(connect_pads
				(clearance 0)
			)
			(min_thickness 0.25)
			(keepout
				(tracks not_allowed)
				(vias allowed)
				(pads allowed)
				(copperpour not_allowed)
				(footprints allowed)
			)
			(placement
				(enabled no)
				(sheetname "")
			)
			(fill
				(thermal_gap 0.5)
				(thermal_bridge_width 0.5)
				(island_removal_mode 0)
			)
			(polygon
				(pts
					(arc
						(start 382.050544 -105.428796)
						(mid 381.517432 -105.475996)
						(end 381.928116 -105.819194)
					)
					(arc
						(start 381.880364 -105.733342)
						(mid 381.611022 -105.504663)
						(end 381.962914 -105.47223)
					)
				)
			)
		)
		(zone
			(layer "F.Cu")
			(hatch none 0.5)
			(connect_pads
				(clearance 0)
			)
			(min_thickness 0.25)
			(keepout
				(tracks not_allowed)
				(vias allowed)
				(pads allowed)
				(copperpour not_allowed)
				(footprints allowed)
			)
			(placement
				(enabled no)
				(sheetname "")
			)
			(fill
				(thermal_gap 0.5)
				(thermal_bridge_width 0.5)
				(island_removal_mode 0)
			)
			(polygon
				(pts
					(arc
						(start 382.065276 -115.763802)
						(mid 381.530331 -115.744202)
						(end 381.895096 -116.135912)
					)
					(arc
						(start 381.85852 -116.045234)
						(mid 381.619336 -115.784708)
						(end 381.97282 -115.795806)
					)
				)
			)
		)
		(zone
			(layer "F.Cu")
			(hatch none 0.5)
			(connect_pads
				(clearance 0)
			)
			(min_thickness 0.25)
			(keepout
				(tracks not_allowed)
				(vias allowed)
				(pads allowed)
				(copperpour not_allowed)
				(footprints allowed)
			)
			(placement
				(enabled no)
				(sheetname "")
			)
			(fill
				(thermal_gap 0.5)
				(thermal_bridge_width 0.5)
				(island_removal_mode 0)
			)
			(polygon
				(pts
					(arc
						(start 382.073404 -110.63859)
						(mid 381.542899 -110.568971)
						(end 381.869188 -110.993174)
					)
					(arc
						(start 381.841248 -110.899448)
						(mid 381.627556 -110.617578)
						(end 381.978408 -110.661704)
					)
				)
			)
		)
		(zone
			(layer "F.Cu")
			(hatch none 0.5)
			(connect_pads
				(clearance 0)
			)
			(min_thickness 0.25)
			(keepout
				(tracks not_allowed)
				(vias allowed)
				(pads allowed)
				(copperpour not_allowed)
				(footprints allowed)
			)
			(placement
				(enabled no)
				(sheetname "")
			)
			(fill
				(thermal_gap 0.5)
				(thermal_bridge_width 0.5)
				(island_removal_mode 0)
			)
			(polygon
				(pts
					(arc
						(start 382.08331 -112.43056)
						(mid 381.588731 -112.226334)
						(end 381.794258 -112.720374)
					)
					(arc
						(start 381.791718 -112.62233)
						(mid 381.658141 -112.294951)
						(end 381.98552 -112.428528)
					)
				)
			)
		)
		(zone
			(layer "F.Cu")
			(hatch none 0.5)
			(connect_pads
				(clearance 0)
			)
			(min_thickness 0.25)
			(keepout
				(tracks not_allowed)
				(vias allowed)
				(pads allowed)
				(copperpour not_allowed)
				(footprints allowed)
			)
			(placement
				(enabled no)
				(sheetname "")
			)
			(fill
				(thermal_gap 0.5)
				(thermal_bridge_width 0.5)
				(island_removal_mode 0)
			)
			(polygon
				(pts
					(arc
						(start 382.116076 -111.33963)
						(mid 382.247299 -111.85873)
						(end 382.521206 -111.398558)
					)
					(arc
						(start 382.44399 -111.459264)
						(mid 382.261219 -111.761646)
						(end 382.172972 -111.419386)
					)
				)
			)
		)
		(zone
			(layer "F.Cu")
			(hatch none 0.5)
			(connect_pads
				(clearance 0)
			)
			(min_thickness 0.25)
			(keepout
				(tracks not_allowed)
				(vias allowed)
				(pads allowed)
				(copperpour not_allowed)
				(footprints allowed)
			)
			(placement
				(enabled no)
				(sheetname "")
			)
			(fill
				(thermal_gap 0.5)
				(thermal_bridge_width 0.5)
				(island_removal_mode 0)
			)
			(polygon
				(pts
					(arc
						(start 382.526286 -110.021116)
						(mid 382.238412 -109.569849)
						(end 382.123442 -110.092744)
					)
					(arc
						(start 382.17729 -110.010956)
						(mid 382.255716 -109.666052)
						(end 382.447292 -109.963204)
					)
				)
			)
		)
		(zone
			(layer "F.Cu")
			(hatch none 0.5)
			(connect_pads
				(clearance 0)
			)
			(min_thickness 0.25)
			(keepout
				(tracks not_allowed)
				(vias allowed)
				(pads allowed)
				(copperpour not_allowed)
				(footprints allowed)
			)
			(placement
				(enabled no)
				(sheetname "")
			)
			(fill
				(thermal_gap 0.5)
				(thermal_bridge_width 0.5)
				(island_removal_mode 0)
			)
			(polygon
				(pts
					(arc
						(start 382.545082 -113.424462)
						(mid 382.202925 -113.012246)
						(end 382.154176 -113.54562)
					)
					(arc
						(start 382.197356 -113.457736)
						(mid 382.232455 -113.105642)
						(end 382.459738 -113.37671)
					)
				)
			)
		)
		(zone
			(layer "F.Cu")
			(hatch none 0.5)
			(connect_pads
				(clearance 0)
			)
			(min_thickness 0.25)
			(keepout
				(tracks not_allowed)
				(vias allowed)
				(pads allowed)
				(copperpour not_allowed)
				(footprints allowed)
			)
			(placement
				(enabled no)
				(sheetname "")
			)
			(fill
				(thermal_gap 0.5)
				(thermal_bridge_width 0.5)
				(island_removal_mode 0)
			)
			(polygon
				(pts
					(arc
						(start 382.578102 -115.001548)
						(mid 382.080383 -114.804786)
						(end 382.293622 -115.29568)
					)
					(arc
						(start 382.289304 -115.19789)
						(mid 382.150801 -114.872689)
						(end 382.480312 -115.000786)
					)
				)
			)
		)
		(zone
			(layer "F.Cu")
			(hatch none 0.5)
			(connect_pads
				(clearance 0)
			)
			(min_thickness 0.25)
			(keepout
				(tracks not_allowed)
				(vias allowed)
				(pads allowed)
				(copperpour not_allowed)
				(footprints allowed)
			)
			(placement
				(enabled no)
				(sheetname "")
			)
			(fill
				(thermal_gap 0.5)
				(thermal_bridge_width 0.5)
				(island_removal_mode 0)
			)
			(polygon
				(pts
					(arc
						(start 382.856232 -103.564944)
						(mid 382.535617 -103.993641)
						(end 383.065274 -103.916734)
					)
					(arc
						(start 382.969516 -103.89489)
						(mid 382.61939 -103.942971)
						(end 382.83007 -103.659178)
					)
				)
			)
		)
		(zone
			(layer "F.Cu")
			(hatch none 0.5)
			(connect_pads
				(clearance 0)
			)
			(min_thickness 0.25)
			(keepout
				(tracks not_allowed)
				(vias allowed)
				(pads allowed)
				(copperpour not_allowed)
				(footprints allowed)
			)
			(placement
				(enabled no)
				(sheetname "")
			)
			(fill
				(thermal_gap 0.5)
				(thermal_bridge_width 0.5)
				(island_removal_mode 0)
			)
			(polygon
				(pts
					(arc
						(start 382.93675 -104.36479)
						(mid 382.732524 -104.859369)
						(end 383.226564 -104.653842)
					)
					(arc
						(start 383.12852 -104.656382)
						(mid 382.801141 -104.789959)
						(end 382.934718 -104.46258)
					)
				)
			)
		)
		(zone
			(layer "F.Cu")
			(hatch none 0.5)
			(connect_pads
				(clearance 0)
			)
			(min_thickness 0.25)
			(keepout
				(tracks not_allowed)
				(vias allowed)
				(pads allowed)
				(copperpour not_allowed)
				(footprints allowed)
			)
			(placement
				(enabled no)
				(sheetname "")
			)
			(fill
				(thermal_gap 0.5)
				(thermal_bridge_width 0.5)
				(island_removal_mode 0)
			)
			(polygon
				(pts
					(arc
						(start 383.05613 -115.764564)
						(mid 382.52116 -115.743809)
						(end 382.884934 -116.13642)
					)
					(arc
						(start 382.848612 -116.045488)
						(mid 382.61011 -115.784166)
						(end 382.963674 -115.796314)
					)
				)
			)
		)
		(zone
			(layer "F.Cu")
			(hatch none 0.5)
			(connect_pads
				(clearance 0)
			)
			(min_thickness 0.25)
			(keepout
				(tracks not_allowed)
				(vias allowed)
				(pads allowed)
				(copperpour not_allowed)
				(footprints allowed)
			)
			(placement
				(enabled no)
				(sheetname "")
			)
			(fill
				(thermal_gap 0.5)
				(thermal_bridge_width 0.5)
				(island_removal_mode 0)
			)
			(polygon
				(pts
					(arc
						(start 383.736342 -113.74501)
						(mid 383.94178 -113.25088)
						(end 383.44729 -113.45545)
					)
					(arc
						(start 383.54508 -113.45291)
						(mid 383.872733 -113.320106)
						(end 383.738628 -113.64722)
					)
				)
			)
		)
		(zone
			(layer "F.Cu")
			(hatch none 0.5)
			(connect_pads
				(clearance 0)
			)
			(min_thickness 0.25)
			(keepout
				(tracks not_allowed)
				(vias allowed)
				(pads allowed)
				(copperpour not_allowed)
				(footprints allowed)
			)
			(placement
				(enabled no)
				(sheetname "")
			)
			(fill
				(thermal_gap 0.5)
				(thermal_bridge_width 0.5)
				(island_removal_mode 0)
			)
			(polygon
				(pts
					(arc
						(start 383.77495 -104.13492)
						(mid 383.979176 -103.640341)
						(end 383.485136 -103.845868)
					)
					(arc
						(start 383.58318 -103.843328)
						(mid 383.910559 -103.709751)
						(end 383.776982 -104.03713)
					)
				)
			)
		)
		(zone
			(layer "F.Cu")
			(hatch none 0.5)
			(connect_pads
				(clearance 0)
			)
			(min_thickness 0.25)
			(keepout
				(tracks not_allowed)
				(vias allowed)
				(pads allowed)
				(copperpour not_allowed)
				(footprints allowed)
			)
			(placement
				(enabled no)
				(sheetname "")
			)
			(fill
				(thermal_gap 0.5)
				(thermal_bridge_width 0.5)
				(island_removal_mode 0)
			)
			(polygon
				(pts
					(arc
						(start 384.24739 -104.65435)
						(mid 384.741969 -104.858576)
						(end 384.536442 -104.364536)
					)
					(arc
						(start 384.538982 -104.46258)
						(mid 384.672559 -104.789959)
						(end 384.34518 -104.656382)
					)
				)
			)
		)
		(zone
			(layer "F.Cu")
			(hatch none 0.5)
			(connect_pads
				(clearance 0)
			)
			(min_thickness 0.25)
			(keepout
				(tracks not_allowed)
				(vias allowed)
				(pads allowed)
				(copperpour not_allowed)
				(footprints allowed)
			)
			(placement
				(enabled no)
				(sheetname "")
			)
			(fill
				(thermal_gap 0.5)
				(thermal_bridge_width 0.5)
				(island_removal_mode 0)
			)
			(polygon
				(pts
					(arc
						(start 384.49377 -103.944928)
						(mid 385.028233 -103.966916)
						(end 384.665474 -103.57358)
					)
					(arc
						(start 384.701542 -103.664512)
						(mid 384.939613 -103.926014)
						(end 384.586226 -103.913432)
					)
				)
			)
		)
		(zone
			(layer "F.Cu")
			(hatch none 0.5)
			(connect_pads
				(clearance 0)
			)
			(min_thickness 0.25)
			(keepout
				(tracks not_allowed)
				(vias allowed)
				(pads allowed)
				(copperpour not_allowed)
				(footprints allowed)
			)
			(placement
				(enabled no)
				(sheetname "")
			)
			(fill
				(thermal_gap 0.5)
				(thermal_bridge_width 0.5)
				(island_removal_mode 0)
			)
			(polygon
				(pts
					(arc
						(start 384.699002 -116.146326)
						(mid 385.011578 -115.712174)
						(end 384.48361 -115.798854)
					)
					(arc
						(start 384.579368 -115.818412)
						(mid 384.928734 -115.763784)
						(end 384.72364 -116.051838)
					)
				)
			)
		)
		(zone
			(layer "F.Cu")
			(hatch none 0.5)
			(connect_pads
				(clearance 0)
			)
			(min_thickness 0.25)
			(keepout
				(tracks not_allowed)
				(vias allowed)
				(pads allowed)
				(copperpour not_allowed)
				(footprints allowed)
			)
			(placement
				(enabled no)
				(sheetname "")
			)
			(fill
				(thermal_gap 0.5)
				(thermal_bridge_width 0.5)
				(island_removal_mode 0)
			)
			(polygon
				(pts
					(arc
						(start 384.826256 -105.442766)
						(mid 384.323852 -105.258669)
						(end 384.549142 -105.74401)
					)
					(arc
						(start 384.542538 -105.64622)
						(mid 384.396008 -105.324288)
						(end 384.728466 -105.444798)
					)
				)
			)
		)
		(zone
			(layer "F.Cu")
			(hatch none 0.5)
			(connect_pads
				(clearance 0)
			)
			(min_thickness 0.25)
			(keepout
				(tracks not_allowed)
				(vias allowed)
				(pads allowed)
				(copperpour not_allowed)
				(footprints allowed)
			)
			(placement
				(enabled no)
				(sheetname "")
			)
			(fill
				(thermal_gap 0.5)
				(thermal_bridge_width 0.5)
				(island_removal_mode 0)
			)
			(polygon
				(pts
					(arc
						(start 385.04749 -105.45445)
						(mid 385.542069 -105.658676)
						(end 385.336542 -105.164636)
					)
					(arc
						(start 385.339082 -105.26268)
						(mid 385.472659 -105.590059)
						(end 385.14528 -105.456482)
					)
				)
			)
		)
		(zone
			(layer "F.Cu")
			(hatch none 0.5)
			(connect_pads
				(clearance 0)
			)
			(min_thickness 0.25)
			(keepout
				(tracks not_allowed)
				(vias allowed)
				(pads allowed)
				(copperpour not_allowed)
				(footprints allowed)
			)
			(placement
				(enabled no)
				(sheetname "")
			)
			(fill
				(thermal_gap 0.5)
				(thermal_bridge_width 0.5)
				(island_removal_mode 0)
			)
			(polygon
				(pts
					(arc
						(start 385.33832 -113.74501)
						(mid 385.540631 -113.249534)
						(end 385.04749 -113.457482)
					)
					(arc
						(start 385.14528 -113.45418)
						(mid 385.472025 -113.319218)
						(end 385.340098 -113.64722)
					)
				)
			)
		)
		(zone
			(layer "F.Cu")
			(hatch none 0.5)
			(connect_pads
				(clearance 0)
			)
			(min_thickness 0.25)
			(keepout
				(tracks not_allowed)
				(vias allowed)
				(pads allowed)
				(copperpour not_allowed)
				(footprints allowed)
			)
			(placement
				(enabled no)
				(sheetname "")
			)
			(fill
				(thermal_gap 0.5)
				(thermal_bridge_width 0.5)
				(island_removal_mode 0)
			)
			(polygon
				(pts
					(arc
						(start 385.339844 -113.96599)
						(mid 385.130502 -114.458505)
						(end 385.62661 -114.257836)
					)
					(arc
						(start 385.52882 -114.259614)
						(mid 385.200077 -114.389829)
						(end 385.336796 -114.06378)
					)
				)
			)
		)
		(zone
			(layer "F.Cu")
			(hatch none 0.5)
			(connect_pads
				(clearance 0)
			)
			(min_thickness 0.25)
			(keepout
				(tracks not_allowed)
				(vias allowed)
				(pads allowed)
				(copperpour not_allowed)
				(footprints allowed)
			)
			(placement
				(enabled no)
				(sheetname "")
			)
			(fill
				(thermal_gap 0.5)
				(thermal_bridge_width 0.5)
				(island_removal_mode 0)
			)
			(polygon
				(pts
					(arc
						(start 385.625848 -106.274108)
						(mid 385.145865 -106.03693)
						(end 385.318 -106.543856)
					)
					(arc
						(start 385.322064 -106.445812)
						(mid 385.210863 -106.110042)
						(end 385.528566 -106.265472)
					)
				)
			)
		)
		(zone
			(layer "F.Cu")
			(hatch none 0.5)
			(connect_pads
				(clearance 0)
			)
			(min_thickness 0.25)
			(keepout
				(tracks not_allowed)
				(vias allowed)
				(pads allowed)
				(copperpour not_allowed)
				(footprints allowed)
			)
			(placement
				(enabled no)
				(sheetname "")
			)
			(fill
				(thermal_gap 0.5)
				(thermal_bridge_width 0.5)
				(island_removal_mode 0)
			)
			(polygon
				(pts
					(arc
						(start 385.84759 -106.25455)
						(mid 386.342169 -106.458776)
						(end 386.136642 -105.964736)
					)
					(arc
						(start 386.139182 -106.06278)
						(mid 386.272759 -106.390159)
						(end 385.94538 -106.256582)
					)
				)
			)
		)
		(zone
			(layer "F.Cu")
			(hatch none 0.5)
			(connect_pads
				(clearance 0)
			)
			(min_thickness 0.25)
			(keepout
				(tracks not_allowed)
				(vias allowed)
				(pads allowed)
				(copperpour not_allowed)
				(footprints allowed)
			)
			(placement
				(enabled no)
				(sheetname "")
			)
			(fill
				(thermal_gap 0.5)
				(thermal_bridge_width 0.5)
				(island_removal_mode 0)
			)
			(polygon
				(pts
					(arc
						(start 385.937506 -104.4448)
						(mid 386.130417 -104.9437)
						(end 386.346446 -104.454198)
					)
					(arc
						(start 386.277612 -104.52354)
						(mid 386.133004 -104.846053)
						(end 386.003292 -104.51719)
					)
				)
			)
		)
		(zone
			(layer "F.Cu")
			(hatch none 0.5)
			(connect_pads
				(clearance 0)
			)
			(min_thickness 0.25)
			(keepout
				(tracks not_allowed)
				(vias allowed)
				(pads allowed)
				(copperpour not_allowed)
				(footprints allowed)
			)
			(placement
				(enabled no)
				(sheetname "")
			)
			(fill
				(thermal_gap 0.5)
				(thermal_bridge_width 0.5)
				(island_removal_mode 0)
			)
			(polygon
				(pts
					(arc
						(start 386.026914 -115.76177)
						(mid 385.491835 -115.746179)
						(end 385.859528 -116.13515)
					)
					(arc
						(start 385.82219 -116.044726)
						(mid 385.581211 -115.785971)
						(end 385.934712 -115.794536)
					)
				)
			)
		)
		(zone
			(layer "F.Cu")
			(hatch none 0.5)
			(connect_pads
				(clearance 0)
			)
			(min_thickness 0.25)
			(keepout
				(tracks not_allowed)
				(vias allowed)
				(pads allowed)
				(copperpour not_allowed)
				(footprints allowed)
			)
			(placement
				(enabled no)
				(sheetname "")
			)
			(fill
				(thermal_gap 0.5)
				(thermal_bridge_width 0.5)
				(island_removal_mode 0)
			)
			(polygon
				(pts
					(arc
						(start 386.038598 -115.327938)
						(mid 386.399254 -114.932545)
						(end 385.864608 -114.957606)
					)
					(arc
						(start 385.957572 -114.98834)
						(mid 386.310817 -114.974294)
						(end 386.073904 -115.236752)
					)
				)
			)
		)
		(zone
			(layer "F.Cu")
			(hatch none 0.5)
			(connect_pads
				(clearance 0)
			)
			(min_thickness 0.25)
			(keepout
				(tracks not_allowed)
				(vias allowed)
				(pads allowed)
				(copperpour not_allowed)
				(footprints allowed)
			)
			(placement
				(enabled no)
				(sheetname "")
			)
			(fill
				(thermal_gap 0.5)
				(thermal_bridge_width 0.5)
				(island_removal_mode 0)
			)
			(polygon
				(pts
					(arc
						(start 386.13207 -113.96599)
						(mid 385.936517 -114.46416)
						(end 386.426964 -114.249962)
					)
					(arc
						(start 386.32892 -114.25428)
						(mid 386.0039 -114.393469)
						(end 386.131816 -114.06378)
					)
				)
			)
		)
		(zone
			(layer "F.Cu")
			(hatch none 0.5)
			(connect_pads
				(clearance 0)
			)
			(min_thickness 0.25)
			(keepout
				(tracks not_allowed)
				(vias allowed)
				(pads allowed)
				(copperpour not_allowed)
				(footprints allowed)
			)
			(placement
				(enabled no)
				(sheetname "")
			)
			(fill
				(thermal_gap 0.5)
				(thermal_bridge_width 0.5)
				(island_removal_mode 0)
			)
			(polygon
				(pts
					(arc
						(start 386.13842 -113.74501)
						(mid 386.340731 -113.249534)
						(end 385.84759 -113.457482)
					)
					(arc
						(start 385.94538 -113.45418)
						(mid 386.272125 -113.319218)
						(end 386.140198 -113.64722)
					)
				)
			)
		)
		(zone
			(layer "F.Cu")
			(hatch none 0.5)
			(connect_pads
				(clearance 0)
			)
			(min_thickness 0.25)
			(keepout
				(tracks not_allowed)
				(vias allowed)
				(pads allowed)
				(copperpour not_allowed)
				(footprints allowed)
			)
			(placement
				(enabled no)
				(sheetname "")
			)
			(fill
				(thermal_gap 0.5)
				(thermal_bridge_width 0.5)
				(island_removal_mode 0)
			)
			(polygon
				(pts
					(arc
						(start 386.425948 -107.074208)
						(mid 385.945965 -106.83703)
						(end 386.1181 -107.343956)
					)
					(arc
						(start 386.122164 -107.245912)
						(mid 386.010963 -106.910142)
						(end 386.328666 -107.065572)
					)
				)
			)
		)
		(zone
			(layer "F.Cu")
			(hatch none 0.5)
			(connect_pads
				(clearance 0)
			)
			(min_thickness 0.25)
			(keepout
				(tracks not_allowed)
				(vias allowed)
				(pads allowed)
				(copperpour not_allowed)
				(footprints allowed)
			)
			(placement
				(enabled no)
				(sheetname "")
			)
			(fill
				(thermal_gap 0.5)
				(thermal_bridge_width 0.5)
				(island_removal_mode 0)
			)
			(polygon
				(pts
					(arc
						(start 386.64769 -105.45445)
						(mid 387.142269 -105.658676)
						(end 386.936742 -105.164636)
					)
					(arc
						(start 386.939282 -105.26268)
						(mid 387.072859 -105.590059)
						(end 386.74548 -105.456482)
					)
				)
			)
		)
		(zone
			(layer "F.Cu")
			(hatch none 0.5)
			(connect_pads
				(clearance 0)
			)
			(min_thickness 0.25)
			(keepout
				(tracks not_allowed)
				(vias allowed)
				(pads allowed)
				(copperpour not_allowed)
				(footprints allowed)
			)
			(placement
				(enabled no)
				(sheetname "")
			)
			(fill
				(thermal_gap 0.5)
				(thermal_bridge_width 0.5)
				(island_removal_mode 0)
			)
			(polygon
				(pts
					(arc
						(start 386.809234 -103.562658)
						(mid 386.502815 -104.00131)
						(end 387.029706 -103.907336)
					)
					(arc
						(start 386.93344 -103.889048)
						(mid 386.585029 -103.948355)
						(end 386.78612 -103.657654)
					)
				)
			)
		)
		(zone
			(layer "F.Cu")
			(hatch none 0.5)
			(connect_pads
				(clearance 0)
			)
			(min_thickness 0.25)
			(keepout
				(tracks not_allowed)
				(vias allowed)
				(pads allowed)
				(copperpour not_allowed)
				(footprints allowed)
			)
			(placement
				(enabled no)
				(sheetname "")
			)
			(fill
				(thermal_gap 0.5)
				(thermal_bridge_width 0.5)
				(island_removal_mode 0)
			)
			(polygon
				(pts
					(arc
						(start 386.93344 -108.14431)
						(mid 387.144172 -107.652424)
						(end 386.647436 -107.851448)
					)
					(arc
						(start 386.74548 -107.850178)
						(mid 387.074675 -107.720918)
						(end 386.936742 -108.04652)
					)
				)
			)
		)
		(zone
			(layer "F.Cu")
			(hatch none 0.5)
			(connect_pads
				(clearance 0)
			)
			(min_thickness 0.25)
			(keepout
				(tracks not_allowed)
				(vias allowed)
				(pads allowed)
				(copperpour not_allowed)
				(footprints allowed)
			)
			(placement
				(enabled no)
				(sheetname "")
			)
			(fill
				(thermal_gap 0.5)
				(thermal_bridge_width 0.5)
				(island_removal_mode 0)
			)
			(polygon
				(pts
					(arc
						(start 386.93344 -106.54411)
						(mid 387.144172 -106.052224)
						(end 386.647436 -106.251248)
					)
					(arc
						(start 386.74548 -106.249978)
						(mid 387.074675 -106.120718)
						(end 386.936742 -106.44632)
					)
				)
			)
		)
		(zone
			(layer "F.Cu")
			(hatch none 0.5)
			(connect_pads
				(clearance 0)
			)
			(min_thickness 0.25)
			(keepout
				(tracks not_allowed)
				(vias allowed)
				(pads allowed)
				(copperpour not_allowed)
				(footprints allowed)
			)
			(placement
				(enabled no)
				(sheetname "")
			)
			(fill
				(thermal_gap 0.5)
				(thermal_bridge_width 0.5)
				(island_removal_mode 0)
			)
			(polygon
				(pts
					(arc
						(start 386.93725 -114.76609)
						(mid 386.733024 -115.260669)
						(end 387.227064 -115.055142)
					)
					(arc
						(start 387.12902 -115.057682)
						(mid 386.801641 -115.191259)
						(end 386.935218 -114.86388)
					)
				)
			)
		)
		(zone
			(layer "F.Cu")
			(hatch none 0.5)
			(connect_pads
				(clearance 0)
			)
			(min_thickness 0.25)
			(keepout
				(tracks not_allowed)
				(vias allowed)
				(pads allowed)
				(copperpour not_allowed)
				(footprints allowed)
			)
			(placement
				(enabled no)
				(sheetname "")
			)
			(fill
				(thermal_gap 0.5)
				(thermal_bridge_width 0.5)
				(island_removal_mode 0)
			)
			(polygon
				(pts
					(arc
						(start 386.93852 -113.74501)
						(mid 387.140831 -113.249534)
						(end 386.64769 -113.457482)
					)
					(arc
						(start 386.74548 -113.45418)
						(mid 387.072225 -113.319218)
						(end 386.940298 -113.64722)
					)
				)
			)
		)
		(zone
			(layer "F.Cu")
			(hatch none 0.5)
			(connect_pads
				(clearance 0)
			)
			(min_thickness 0.25)
			(keepout
				(tracks not_allowed)
				(vias allowed)
				(pads allowed)
				(copperpour not_allowed)
				(footprints allowed)
			)
			(placement
				(enabled no)
				(sheetname "")
			)
			(fill
				(thermal_gap 0.5)
				(thermal_bridge_width 0.5)
				(island_removal_mode 0)
			)
			(polygon
				(pts
					(arc
						(start 386.94614 -106.765344)
						(mid 386.726822 -107.253732)
						(end 387.227064 -107.063032)
					)
					(arc
						(start 387.128766 -107.062524)
						(mid 386.797646 -107.185993)
						(end 386.94106 -106.86288)
					)
				)
			)
		)
		(zone
			(layer "F.Cu")
			(hatch none 0.5)
			(connect_pads
				(clearance 0)
			)
			(min_thickness 0.25)
			(keepout
				(tracks not_allowed)
				(vias allowed)
				(pads allowed)
				(copperpour not_allowed)
				(footprints allowed)
			)
			(placement
				(enabled no)
				(sheetname "")
			)
			(fill
				(thermal_gap 0.5)
				(thermal_bridge_width 0.5)
				(island_removal_mode 0)
			)
			(polygon
				(pts
					(arc
						(start 387.01726 -115.76177)
						(mid 386.482633 -115.746317)
						(end 386.850128 -116.13515)
					)
					(arc
						(start 386.81279 -116.044726)
						(mid 386.571763 -115.786079)
						(end 386.925312 -115.794282)
					)
				)
			)
		)
		(zone
			(layer "F.Cu")
			(hatch none 0.5)
			(connect_pads
				(clearance 0)
			)
			(min_thickness 0.25)
			(keepout
				(tracks not_allowed)
				(vias allowed)
				(pads allowed)
				(copperpour not_allowed)
				(footprints allowed)
			)
			(placement
				(enabled no)
				(sheetname "")
			)
			(fill
				(thermal_gap 0.5)
				(thermal_bridge_width 0.5)
				(island_removal_mode 0)
			)
			(polygon
				(pts
					(arc
						(start 387.22681 -114.256058)
						(mid 386.73259 -114.050964)
						(end 386.93725 -114.545364)
					)
					(arc
						(start 386.93471 -114.447574)
						(mid 386.801726 -114.1201)
						(end 387.12902 -114.253518)
					)
				)
			)
		)
		(zone
			(layer "F.Cu")
			(hatch none 0.5)
			(connect_pads
				(clearance 0)
			)
			(min_thickness 0.25)
			(keepout
				(tracks not_allowed)
				(vias allowed)
				(pads allowed)
				(copperpour not_allowed)
				(footprints allowed)
			)
			(placement
				(enabled no)
				(sheetname "")
			)
			(fill
				(thermal_gap 0.5)
				(thermal_bridge_width 0.5)
				(island_removal_mode 0)
			)
			(polygon
				(pts
					(arc
						(start 387.44779 -109.45495)
						(mid 387.942369 -109.659176)
						(end 387.736842 -109.165136)
					)
					(arc
						(start 387.739382 -109.26318)
						(mid 387.872959 -109.590559)
						(end 387.54558 -109.456982)
					)
				)
			)
		)
		(zone
			(layer "F.Cu")
			(hatch none 0.5)
			(connect_pads
				(clearance 0)
			)
			(min_thickness 0.25)
			(keepout
				(tracks not_allowed)
				(vias allowed)
				(pads allowed)
				(copperpour not_allowed)
				(footprints allowed)
			)
			(placement
				(enabled no)
				(sheetname "")
			)
			(fill
				(thermal_gap 0.5)
				(thermal_bridge_width 0.5)
				(island_removal_mode 0)
			)
			(polygon
				(pts
					(arc
						(start 387.44779 -107.061508)
						(mid 387.947216 -107.254025)
						(end 387.729984 -106.764836)
					)
					(arc
						(start 387.73481 -106.86288)
						(mid 387.876157 -107.186993)
						(end 387.54558 -107.061254)
					)
				)
			)
		)
		(zone
			(layer "F.Cu")
			(hatch none 0.5)
			(connect_pads
				(clearance 0)
			)
			(min_thickness 0.25)
			(keepout
				(tracks not_allowed)
				(vias allowed)
				(pads allowed)
				(copperpour not_allowed)
				(footprints allowed)
			)
			(placement
				(enabled no)
				(sheetname "")
			)
			(fill
				(thermal_gap 0.5)
				(thermal_bridge_width 0.5)
				(island_removal_mode 0)
			)
			(polygon
				(pts
					(arc
						(start 387.718808 -114.766598)
						(mid 387.546599 -115.273415)
						(end 388.026656 -115.0366)
					)
					(arc
						(start 387.928866 -115.045236)
						(mid 387.610814 -115.199787)
						(end 387.722872 -114.864388)
					)
				)
			)
		)
		(zone
			(layer "F.Cu")
			(hatch none 0.5)
			(connect_pads
				(clearance 0)
			)
			(min_thickness 0.25)
			(keepout
				(tracks not_allowed)
				(vias allowed)
				(pads allowed)
				(copperpour not_allowed)
				(footprints allowed)
			)
			(placement
				(enabled no)
				(sheetname "")
			)
			(fill
				(thermal_gap 0.5)
				(thermal_bridge_width 0.5)
				(island_removal_mode 0)
			)
			(polygon
				(pts
					(arc
						(start 387.728968 -105.165144)
						(mid 387.539325 -105.665301)
						(end 388.02691 -105.445306)
					)
					(arc
						(start 387.92912 -105.451148)
						(mid 387.605735 -105.593964)
						(end 387.729476 -105.26268)
					)
				)
			)
		)
		(zone
			(layer "F.Cu")
			(hatch none 0.5)
			(connect_pads
				(clearance 0)
			)
			(min_thickness 0.25)
			(keepout
				(tracks not_allowed)
				(vias allowed)
				(pads allowed)
				(copperpour not_allowed)
				(footprints allowed)
			)
			(placement
				(enabled no)
				(sheetname "")
			)
			(fill
				(thermal_gap 0.5)
				(thermal_bridge_width 0.5)
				(island_removal_mode 0)
			)
			(polygon
				(pts
					(arc
						(start 387.832346 -103.571802)
						(mid 387.476866 -103.971876)
						(end 388.011162 -103.939848)
					)
					(arc
						(start 387.91769 -103.910384)
						(mid 387.564785 -103.928858)
						(end 387.79831 -103.663496)
					)
				)
			)
		)
		(zone
			(layer "F.Cu")
			(hatch none 0.5)
			(connect_pads
				(clearance 0)
			)
			(min_thickness 0.25)
			(keepout
				(tracks not_allowed)
				(vias allowed)
				(pads allowed)
				(copperpour not_allowed)
				(footprints allowed)
			)
			(placement
				(enabled no)
				(sheetname "")
			)
			(fill
				(thermal_gap 0.5)
				(thermal_bridge_width 0.5)
				(island_removal_mode 0)
			)
			(polygon
				(pts
					(arc
						(start 388.009638 -115.766088)
						(mid 387.474878 -115.742371)
						(end 387.83641 -116.136928)
					)
					(arc
						(start 387.800596 -116.045742)
						(mid 387.563638 -115.783263)
						(end 387.916928 -115.79733)
					)
				)
			)
		)
		(zone
			(layer "F.Cu")
			(hatch none 0.5)
			(connect_pads
				(clearance 0)
			)
			(min_thickness 0.25)
			(keepout
				(tracks not_allowed)
				(vias allowed)
				(pads allowed)
				(copperpour not_allowed)
				(footprints allowed)
			)
			(placement
				(enabled no)
				(sheetname "")
			)
			(fill
				(thermal_gap 0.5)
				(thermal_bridge_width 0.5)
				(island_removal_mode 0)
			)
			(polygon
				(pts
					(arc
						(start 388.026402 -114.270536)
						(mid 387.542755 -114.040987)
						(end 387.722872 -114.54511)
					)
					(arc
						(start 387.725412 -114.447066)
						(mid 387.608854 -114.113038)
						(end 387.928866 -114.263424)
					)
				)
			)
		)
		(zone
			(layer "F.Cu")
			(hatch none 0.5)
			(connect_pads
				(clearance 0)
			)
			(min_thickness 0.25)
			(keepout
				(tracks not_allowed)
				(vias allowed)
				(pads allowed)
				(copperpour not_allowed)
				(footprints allowed)
			)
			(placement
				(enabled no)
				(sheetname "")
			)
			(fill
				(thermal_gap 0.5)
				(thermal_bridge_width 0.5)
				(island_removal_mode 0)
			)
			(polygon
				(pts
					(arc
						(start 388.24789 -105.45445)
						(mid 388.742469 -105.658676)
						(end 388.536942 -105.164636)
					)
					(arc
						(start 388.539482 -105.26268)
						(mid 388.673059 -105.590059)
						(end 388.34568 -105.456482)
					)
				)
			)
		)
		(zone
			(layer "F.Cu")
			(hatch none 0.5)
			(connect_pads
				(clearance 0)
			)
			(min_thickness 0.25)
			(keepout
				(tracks not_allowed)
				(vias allowed)
				(pads allowed)
				(copperpour not_allowed)
				(footprints allowed)
			)
			(placement
				(enabled no)
				(sheetname "")
			)
			(fill
				(thermal_gap 0.5)
				(thermal_bridge_width 0.5)
				(island_removal_mode 0)
			)
			(polygon
				(pts
					(arc
						(start 388.53745 -115.34521)
						(mid 388.741676 -114.850631)
						(end 388.247636 -115.056158)
					)
					(arc
						(start 388.34568 -115.053618)
						(mid 388.673059 -114.920041)
						(end 388.539482 -115.24742)
					)
				)
			)
		)
		(zone
			(layer "F.Cu")
			(hatch none 0.5)
			(connect_pads
				(clearance 0)
			)
			(min_thickness 0.25)
			(keepout
				(tracks not_allowed)
				(vias allowed)
				(pads allowed)
				(copperpour not_allowed)
				(footprints allowed)
			)
			(placement
				(enabled no)
				(sheetname "")
			)
			(fill
				(thermal_gap 0.5)
				(thermal_bridge_width 0.5)
				(island_removal_mode 0)
			)
			(polygon
				(pts
					(arc
						(start 388.540752 -106.76509)
						(mid 388.330888 -107.257335)
						(end 388.827264 -107.057444)
					)
					(arc
						(start 388.72922 -107.058968)
						(mid 388.400207 -107.18866)
						(end 388.537704 -106.86288)
					)
				)
			)
		)
		(zone
			(layer "F.Cu")
			(hatch none 0.5)
			(connect_pads
				(clearance 0)
			)
			(min_thickness 0.25)
			(keepout
				(tracks not_allowed)
				(vias allowed)
				(pads allowed)
				(copperpour not_allowed)
				(footprints allowed)
			)
			(placement
				(enabled no)
				(sheetname "")
			)
			(fill
				(thermal_gap 0.5)
				(thermal_bridge_width 0.5)
				(island_removal_mode 0)
			)
			(polygon
				(pts
					(arc
						(start 388.627874 -116.13642)
						(mid 388.990538 -115.742397)
						(end 388.455662 -115.765072)
					)
					(arc
						(start 388.548626 -115.796568)
						(mid 388.902052 -115.784146)
						(end 388.663688 -116.045234)
					)
				)
			)
		)
		(zone
			(layer "F.Cu")
			(hatch none 0.5)
			(connect_pads
				(clearance 0)
			)
			(min_thickness 0.25)
			(keepout
				(tracks not_allowed)
				(vias allowed)
				(pads allowed)
				(copperpour not_allowed)
				(footprints allowed)
			)
			(placement
				(enabled no)
				(sheetname "")
			)
			(fill
				(thermal_gap 0.5)
				(thermal_bridge_width 0.5)
				(island_removal_mode 0)
			)
			(polygon
				(pts
					(arc
						(start 388.824216 -103.57231)
						(mid 388.466926 -103.970619)
						(end 389.001254 -103.941118)
					)
					(arc
						(start 388.908036 -103.911146)
						(mid 388.555018 -103.928144)
						(end 388.789672 -103.66375)
					)
				)
			)
		)
		(zone
			(layer "F.Cu")
			(hatch none 0.5)
			(connect_pads
				(clearance 0)
			)
			(min_thickness 0.25)
			(keepout
				(tracks not_allowed)
				(vias allowed)
				(pads allowed)
				(copperpour not_allowed)
				(footprints allowed)
			)
			(placement
				(enabled no)
				(sheetname "")
			)
			(fill
				(thermal_gap 0.5)
				(thermal_bridge_width 0.5)
				(island_removal_mode 0)
			)
			(polygon
				(pts
					(arc
						(start 388.826502 -114.270536)
						(mid 388.342855 -114.040987)
						(end 388.522972 -114.54511)
					)
					(arc
						(start 388.525512 -114.447066)
						(mid 388.408954 -114.113038)
						(end 388.728966 -114.263424)
					)
				)
			)
		)
		(zone
			(layer "F.Cu")
			(hatch none 0.5)
			(connect_pads
				(clearance 0)
			)
			(min_thickness 0.25)
			(keepout
				(tracks not_allowed)
				(vias allowed)
				(pads allowed)
				(copperpour not_allowed)
				(footprints allowed)
			)
			(placement
				(enabled no)
				(sheetname "")
			)
			(fill
				(thermal_gap 0.5)
				(thermal_bridge_width 0.5)
				(island_removal_mode 0)
			)
			(polygon
				(pts
					(arc
						(start 389.340852 -106.76509)
						(mid 389.130988 -107.257335)
						(end 389.627364 -107.057444)
					)
					(arc
						(start 389.52932 -107.058968)
						(mid 389.200307 -107.18866)
						(end 389.337804 -106.86288)
					)
				)
			)
		)
		(zone
			(layer "F.Cu")
			(hatch none 0.5)
			(connect_pads
				(clearance 0)
			)
			(min_thickness 0.25)
			(keepout
				(tracks not_allowed)
				(vias allowed)
				(pads allowed)
				(copperpour not_allowed)
				(footprints allowed)
			)
			(placement
				(enabled no)
				(sheetname "")
			)
			(fill
				(thermal_gap 0.5)
				(thermal_bridge_width 0.5)
				(island_removal_mode 0)
			)
			(polygon
				(pts
					(arc
						(start 389.494522 -115.298982)
						(mid 389.39834 -114.772533)
						(end 389.094472 -115.21313)
					)
					(arc
						(start 389.175244 -115.157758)
						(mid 389.377949 -114.868201)
						(end 389.443468 -115.21567)
					)
				)
			)
		)
		(zone
			(layer "F.Cu")
			(hatch none 0.5)
			(connect_pads
				(clearance 0)
			)
			(min_thickness 0.25)
			(keepout
				(tracks not_allowed)
				(vias allowed)
				(pads allowed)
				(copperpour not_allowed)
				(footprints allowed)
			)
			(placement
				(enabled no)
				(sheetname "")
			)
			(fill
				(thermal_gap 0.5)
				(thermal_bridge_width 0.5)
				(island_removal_mode 0)
			)
			(polygon
				(pts
					(arc
						(start 389.816848 -103.573072)
						(mid 389.456626 -103.968645)
						(end 389.991092 -103.94315)
					)
					(arc
						(start 389.898128 -103.91267)
						(mid 389.544934 -103.926824)
						(end 389.781542 -103.664258)
					)
				)
			)
		)
		(zone
			(layer "F.Cu")
			(hatch none 0.5)
			(connect_pads
				(clearance 0)
			)
			(min_thickness 0.25)
			(keepout
				(tracks not_allowed)
				(vias allowed)
				(pads allowed)
				(copperpour not_allowed)
				(footprints allowed)
			)
			(placement
				(enabled no)
				(sheetname "")
			)
			(fill
				(thermal_gap 0.5)
				(thermal_bridge_width 0.5)
				(island_removal_mode 0)
			)
			(polygon
				(pts
					(arc
						(start 389.849106 -110.278164)
						(mid 390.358287 -110.442207)
						(end 390.114028 -109.966252)
					)
					(arc
						(start 390.124442 -110.063534)
						(mid 390.28383 -110.379486)
						(end 389.946642 -110.272576)
					)
				)
			)
		)
		(zone
			(layer "F.Cu")
			(hatch none 0.5)
			(connect_pads
				(clearance 0)
			)
			(min_thickness 0.25)
			(keepout
				(tracks not_allowed)
				(vias allowed)
				(pads allowed)
				(copperpour not_allowed)
				(footprints allowed)
			)
			(placement
				(enabled no)
				(sheetname "")
			)
			(fill
				(thermal_gap 0.5)
				(thermal_bridge_width 0.5)
				(island_removal_mode 0)
			)
			(polygon
				(pts
					(arc
						(start 389.923274 -116.069364)
						(mid 389.717847 -115.574937)
						(end 389.51408 -116.069872)
					)
					(arc
						(start 389.58139 -115.998752)
						(mid 389.71855 -115.67281)
						(end 389.85571 -115.998752)
					)
				)
			)
		)
		(zone
			(layer "F.Cu")
			(hatch none 0.5)
			(connect_pads
				(clearance 0)
			)
			(min_thickness 0.25)
			(keepout
				(tracks not_allowed)
				(vias allowed)
				(pads allowed)
				(copperpour not_allowed)
				(footprints allowed)
			)
			(placement
				(enabled no)
				(sheetname "")
			)
			(fill
				(thermal_gap 0.5)
				(thermal_bridge_width 0.5)
				(island_removal_mode 0)
			)
			(polygon
				(pts
					(arc
						(start 390.363964 -115.23599)
						(mid 390.104432 -114.767954)
						(end 389.957564 -115.282472)
					)
					(arc
						(start 390.016492 -115.20424)
						(mid 390.116104 -114.86514)
						(end 390.289034 -115.173506)
					)
				)
			)
		)
		(zone
			(layer "F.Cu")
			(hatch none 0.5)
			(connect_pads
				(clearance 0)
			)
			(min_thickness 0.25)
			(keepout
				(tracks not_allowed)
				(vias allowed)
				(pads allowed)
				(copperpour not_allowed)
				(footprints allowed)
			)
			(placement
				(enabled no)
				(sheetname "")
			)
			(fill
				(thermal_gap 0.5)
				(thermal_bridge_width 0.5)
				(island_removal_mode 0)
			)
			(polygon
				(pts
					(arc
						(start 390.771888 -103.562658)
						(mid 390.465035 -104.00113)
						(end 390.992106 -103.90759)
					)
					(arc
						(start 390.89584 -103.889048)
						(mid 390.547429 -103.948355)
						(end 390.74852 -103.657654)
					)
				)
			)
		)
		(zone
			(layer "F.Cu")
			(hatch none 0.5)
			(connect_pads
				(clearance 0)
			)
			(min_thickness 0.25)
			(keepout
				(tracks not_allowed)
				(vias allowed)
				(pads allowed)
				(copperpour not_allowed)
				(footprints allowed)
			)
			(placement
				(enabled no)
				(sheetname "")
			)
			(fill
				(thermal_gap 0.5)
				(thermal_bridge_width 0.5)
				(island_removal_mode 0)
			)
			(polygon
				(pts
					(arc
						(start 390.932416 -112.94491)
						(mid 391.146095 -112.454189)
						(end 390.64819 -112.650524)
					)
					(arc
						(start 390.74598 -112.649762)
						(mid 391.075813 -112.522137)
						(end 390.93648 -112.84712)
					)
				)
			)
		)
		(zone
			(layer "F.Cu")
			(hatch none 0.5)
			(connect_pads
				(clearance 0)
			)
			(min_thickness 0.25)
			(keepout
				(tracks not_allowed)
				(vias allowed)
				(pads allowed)
				(copperpour not_allowed)
				(footprints allowed)
			)
			(placement
				(enabled no)
				(sheetname "")
			)
			(fill
				(thermal_gap 0.5)
				(thermal_bridge_width 0.5)
				(island_removal_mode 0)
			)
			(polygon
				(pts
					(arc
						(start 390.933178 -105.16489)
						(mid 390.736507 -105.662698)
						(end 391.22731 -105.449116)
					)
					(arc
						(start 391.12952 -105.453688)
						(mid 390.804319 -105.592191)
						(end 390.932416 -105.26268)
					)
				)
			)
		)
		(zone
			(layer "F.Cu")
			(hatch none 0.5)
			(connect_pads
				(clearance 0)
			)
			(min_thickness 0.25)
			(keepout
				(tracks not_allowed)
				(vias allowed)
				(pads allowed)
				(copperpour not_allowed)
				(footprints allowed)
			)
			(placement
				(enabled no)
				(sheetname "")
			)
			(fill
				(thermal_gap 0.5)
				(thermal_bridge_width 0.5)
				(island_removal_mode 0)
			)
			(polygon
				(pts
					(arc
						(start 390.98093 -115.765072)
						(mid 390.446467 -115.743084)
						(end 390.809226 -116.13642)
					)
					(arc
						(start 390.773158 -116.045488)
						(mid 390.535087 -115.783986)
						(end 390.888474 -115.796568)
					)
				)
			)
		)
		(zone
			(layer "F.Cu")
			(hatch none 0.5)
			(connect_pads
				(clearance 0)
			)
			(min_thickness 0.25)
			(keepout
				(tracks not_allowed)
				(vias allowed)
				(pads allowed)
				(copperpour not_allowed)
				(footprints allowed)
			)
			(placement
				(enabled no)
				(sheetname "")
			)
			(fill
				(thermal_gap 0.5)
				(thermal_bridge_width 0.5)
				(island_removal_mode 0)
			)
			(polygon
				(pts
					(arc
						(start 391.22731 -115.060984)
						(mid 390.736589 -114.847305)
						(end 390.932924 -115.34521)
					)
					(arc
						(start 390.932162 -115.24742)
						(mid 390.804537 -114.917587)
						(end 391.12952 -115.05692)
					)
				)
			)
		)
		(zone
			(layer "F.Cu")
			(hatch none 0.5)
			(connect_pads
				(clearance 0)
			)
			(min_thickness 0.25)
			(keepout
				(tracks not_allowed)
				(vias allowed)
				(pads allowed)
				(copperpour not_allowed)
				(footprints allowed)
			)
			(placement
				(enabled no)
				(sheetname "")
			)
			(fill
				(thermal_gap 0.5)
				(thermal_bridge_width 0.5)
				(island_removal_mode 0)
			)
			(polygon
				(pts
					(arc
						(start 391.22731 -114.260884)
						(mid 390.736589 -114.047205)
						(end 390.932924 -114.54511)
					)
					(arc
						(start 390.932162 -114.44732)
						(mid 390.804537 -114.117487)
						(end 391.12952 -114.25682)
					)
				)
			)
		)
		(zone
			(layer "F.Cu")
			(hatch none 0.5)
			(connect_pads
				(clearance 0)
			)
			(min_thickness 0.25)
			(keepout
				(tracks not_allowed)
				(vias allowed)
				(pads allowed)
				(copperpour not_allowed)
				(footprints allowed)
			)
			(placement
				(enabled no)
				(sheetname "")
			)
			(fill
				(thermal_gap 0.5)
				(thermal_bridge_width 0.5)
				(island_removal_mode 0)
			)
			(polygon
				(pts
					(arc
						(start 391.449052 -104.633776)
						(mid 391.927704 -104.872943)
						(end 391.757916 -104.365552)
					)
					(arc
						(start 391.753852 -104.463342)
						(mid 391.863343 -104.799235)
						(end 391.546334 -104.64292)
					)
				)
			)
		)
		(zone
			(layer "F.Cu")
			(hatch none 0.5)
			(connect_pads
				(clearance 0)
			)
			(min_thickness 0.25)
			(keepout
				(tracks not_allowed)
				(vias allowed)
				(pads allowed)
				(copperpour not_allowed)
				(footprints allowed)
			)
			(placement
				(enabled no)
				(sheetname "")
			)
			(fill
				(thermal_gap 0.5)
				(thermal_bridge_width 0.5)
				(island_removal_mode 0)
			)
			(polygon
				(pts
					(arc
						(start 391.732516 -115.34521)
						(mid 391.946195 -114.854489)
						(end 391.44829 -115.050824)
					)
					(arc
						(start 391.54608 -115.050062)
						(mid 391.875913 -114.922437)
						(end 391.73658 -115.24742)
					)
				)
			)
		)
		(zone
			(layer "F.Cu")
			(hatch none 0.5)
			(connect_pads
				(clearance 0)
			)
			(min_thickness 0.25)
			(keepout
				(tracks not_allowed)
				(vias allowed)
				(pads allowed)
				(copperpour not_allowed)
				(footprints allowed)
			)
			(placement
				(enabled no)
				(sheetname "")
			)
			(fill
				(thermal_gap 0.5)
				(thermal_bridge_width 0.5)
				(island_removal_mode 0)
			)
			(polygon
				(pts
					(arc
						(start 391.732516 -114.54511)
						(mid 391.946195 -114.054389)
						(end 391.44829 -114.250724)
					)
					(arc
						(start 391.54608 -114.249962)
						(mid 391.875913 -114.122337)
						(end 391.73658 -114.44732)
					)
				)
			)
		)
		(zone
			(layer "F.Cu")
			(hatch none 0.5)
			(connect_pads
				(clearance 0)
			)
			(min_thickness 0.25)
			(keepout
				(tracks not_allowed)
				(vias allowed)
				(pads allowed)
				(copperpour not_allowed)
				(footprints allowed)
			)
			(placement
				(enabled no)
				(sheetname "")
			)
			(fill
				(thermal_gap 0.5)
				(thermal_bridge_width 0.5)
				(island_removal_mode 0)
			)
			(polygon
				(pts
					(arc
						(start 391.732516 -113.74501)
						(mid 391.946195 -113.254289)
						(end 391.44829 -113.450624)
					)
					(arc
						(start 391.54608 -113.449862)
						(mid 391.875913 -113.322237)
						(end 391.73658 -113.64722)
					)
				)
			)
		)
		(zone
			(layer "F.Cu")
			(hatch none 0.5)
			(connect_pads
				(clearance 0)
			)
			(min_thickness 0.25)
			(keepout
				(tracks not_allowed)
				(vias allowed)
				(pads allowed)
				(copperpour not_allowed)
				(footprints allowed)
			)
			(placement
				(enabled no)
				(sheetname "")
			)
			(fill
				(thermal_gap 0.5)
				(thermal_bridge_width 0.5)
				(island_removal_mode 0)
			)
			(polygon
				(pts
					(arc
						(start 391.738866 -112.94491)
						(mid 391.941358 -112.449613)
						(end 391.448036 -112.656874)
					)
					(arc
						(start 391.545826 -112.653826)
						(mid 391.872662 -112.519206)
						(end 391.740644 -112.84712)
					)
				)
			)
		)
		(zone
			(layer "F.Cu")
			(hatch none 0.5)
			(connect_pads
				(clearance 0)
			)
			(min_thickness 0.25)
			(keepout
				(tracks not_allowed)
				(vias allowed)
				(pads allowed)
				(copperpour not_allowed)
				(footprints allowed)
			)
			(placement
				(enabled no)
				(sheetname "")
			)
			(fill
				(thermal_gap 0.5)
				(thermal_bridge_width 0.5)
				(island_removal_mode 0)
			)
			(polygon
				(pts
					(arc
						(start 391.738866 -112.14481)
						(mid 391.941358 -111.649513)
						(end 391.448036 -111.856774)
					)
					(arc
						(start 391.545826 -111.853726)
						(mid 391.872662 -111.719106)
						(end 391.740644 -112.04702)
					)
				)
			)
		)
		(zone
			(layer "F.Cu")
			(hatch none 0.5)
			(connect_pads
				(clearance 0)
			)
			(min_thickness 0.25)
			(keepout
				(tracks not_allowed)
				(vias allowed)
				(pads allowed)
				(copperpour not_allowed)
				(footprints allowed)
			)
			(placement
				(enabled no)
				(sheetname "")
			)
			(fill
				(thermal_gap 0.5)
				(thermal_bridge_width 0.5)
				(island_removal_mode 0)
			)
			(polygon
				(pts
					(arc
						(start 391.74166 -110.76559)
						(mid 391.530928 -111.257476)
						(end 392.027664 -111.058452)
					)
					(arc
						(start 391.929874 -111.059976)
						(mid 391.600857 -111.189418)
						(end 391.738104 -110.86338)
					)
				)
			)
		)
		(zone
			(layer "F.Cu")
			(hatch none 0.5)
			(connect_pads
				(clearance 0)
			)
			(min_thickness 0.25)
			(keepout
				(tracks not_allowed)
				(vias allowed)
				(pads allowed)
				(copperpour not_allowed)
				(footprints allowed)
			)
			(placement
				(enabled no)
				(sheetname "")
			)
			(fill
				(thermal_gap 0.5)
				(thermal_bridge_width 0.5)
				(island_removal_mode 0)
			)
			(polygon
				(pts
					(arc
						(start 391.971784 -115.765326)
						(mid 391.436919 -115.74309)
						(end 391.799572 -116.136674)
					)
					(arc
						(start 391.763504 -116.045742)
						(mid 391.525814 -115.784167)
						(end 391.879074 -115.796822)
					)
				)
			)
		)
		(zone
			(layer "F.Cu")
			(hatch none 0.5)
			(connect_pads
				(clearance 0)
			)
			(min_thickness 0.25)
			(keepout
				(tracks not_allowed)
				(vias allowed)
				(pads allowed)
				(copperpour not_allowed)
				(footprints allowed)
			)
			(placement
				(enabled no)
				(sheetname "")
			)
			(fill
				(thermal_gap 0.5)
				(thermal_bridge_width 0.5)
				(island_removal_mode 0)
			)
			(polygon
				(pts
					(arc
						(start 391.975848 -103.758238)
						(mid 391.442803 -103.711949)
						(end 391.78738 -104.121458)
					)
					(arc
						(start 391.755376 -104.029002)
						(mid 391.529494 -103.756864)
						(end 391.881868 -103.785416)
					)
				)
			)
		)
		(zone
			(layer "F.Cu")
			(hatch none 0.5)
			(connect_pads
				(clearance 0)
			)
			(min_thickness 0.25)
			(keepout
				(tracks not_allowed)
				(vias allowed)
				(pads allowed)
				(copperpour not_allowed)
				(footprints allowed)
			)
			(placement
				(enabled no)
				(sheetname "")
			)
			(fill
				(thermal_gap 0.5)
				(thermal_bridge_width 0.5)
				(island_removal_mode 0)
			)
			(polygon
				(pts
					(arc
						(start 392.532616 -114.54511)
						(mid 392.746295 -114.054389)
						(end 392.24839 -114.250724)
					)
					(arc
						(start 392.34618 -114.249962)
						(mid 392.676013 -114.122337)
						(end 392.53668 -114.44732)
					)
				)
			)
		)
		(zone
			(layer "F.Cu")
			(hatch none 0.5)
			(connect_pads
				(clearance 0)
			)
			(min_thickness 0.25)
			(keepout
				(tracks not_allowed)
				(vias allowed)
				(pads allowed)
				(copperpour not_allowed)
				(footprints allowed)
			)
			(placement
				(enabled no)
				(sheetname "")
			)
			(fill
				(thermal_gap 0.5)
				(thermal_bridge_width 0.5)
				(island_removal_mode 0)
			)
			(polygon
				(pts
					(arc
						(start 392.532616 -112.94491)
						(mid 392.746295 -112.454189)
						(end 392.24839 -112.650524)
					)
					(arc
						(start 392.34618 -112.649762)
						(mid 392.676013 -112.522137)
						(end 392.53668 -112.84712)
					)
				)
			)
		)
		(zone
			(layer "F.Cu")
			(hatch none 0.5)
			(connect_pads
				(clearance 0)
			)
			(min_thickness 0.25)
			(keepout
				(tracks not_allowed)
				(vias allowed)
				(pads allowed)
				(copperpour not_allowed)
				(footprints allowed)
			)
			(placement
				(enabled no)
				(sheetname "")
			)
			(fill
				(thermal_gap 0.5)
				(thermal_bridge_width 0.5)
				(island_removal_mode 0)
			)
			(polygon
				(pts
					(arc
						(start 392.563858 -104.36606)
						(mid 392.315948 -104.840085)
						(end 392.826494 -104.67975)
					)
					(arc
						(start 392.728704 -104.673908)
						(mid 392.390699 -104.777178)
						(end 392.552936 -104.463088)
					)
				)
			)
		)
		(zone
			(layer "F.Cu")
			(hatch none 0.5)
			(connect_pads
				(clearance 0)
			)
			(min_thickness 0.25)
			(keepout
				(tracks not_allowed)
				(vias allowed)
				(pads allowed)
				(copperpour not_allowed)
				(footprints allowed)
			)
			(placement
				(enabled no)
				(sheetname "")
			)
			(fill
				(thermal_gap 0.5)
				(thermal_bridge_width 0.5)
				(island_removal_mode 0)
			)
			(polygon
				(pts
					(arc
						(start 392.662664 -107.593638)
						(mid 392.265186 -107.951358)
						(end 392.799316 -107.97921)
					)
					(arc
						(start 392.710162 -107.939586)
						(mid 392.357115 -107.919113)
						(end 392.618468 -107.68076)
					)
				)
			)
		)
		(zone
			(layer "F.Cu")
			(hatch none 0.5)
			(connect_pads
				(clearance 0)
			)
			(min_thickness 0.25)
			(keepout
				(tracks not_allowed)
				(vias allowed)
				(pads allowed)
				(copperpour not_allowed)
				(footprints allowed)
			)
			(placement
				(enabled no)
				(sheetname "")
			)
			(fill
				(thermal_gap 0.5)
				(thermal_bridge_width 0.5)
				(island_removal_mode 0)
			)
			(polygon
				(pts
					(arc
						(start 392.754866 -103.563166)
						(mid 392.445336 -103.999515)
						(end 392.972798 -103.909368)
					)
					(arc
						(start 392.876786 -103.890318)
						(mid 392.527898 -103.947285)
						(end 392.73099 -103.657908)
					)
				)
			)
		)
		(zone
			(layer "F.Cu")
			(hatch none 0.5)
			(connect_pads
				(clearance 0)
			)
			(min_thickness 0.25)
			(keepout
				(tracks not_allowed)
				(vias allowed)
				(pads allowed)
				(copperpour not_allowed)
				(footprints allowed)
			)
			(placement
				(enabled no)
				(sheetname "")
			)
			(fill
				(thermal_gap 0.5)
				(thermal_bridge_width 0.5)
				(island_removal_mode 0)
			)
			(polygon
				(pts
					(arc
						(start 392.962638 -115.766088)
						(mid 392.428007 -115.742046)
						(end 392.78941 -116.136674)
					)
					(arc
						(start 392.753596 -116.045742)
						(mid 392.516588 -115.783371)
						(end 392.869928 -115.797076)
					)
				)
			)
		)
		(zone
			(layer "F.Cu")
			(hatch none 0.5)
			(connect_pads
				(clearance 0)
			)
			(min_thickness 0.25)
			(keepout
				(tracks not_allowed)
				(vias allowed)
				(pads allowed)
				(copperpour not_allowed)
				(footprints allowed)
			)
			(placement
				(enabled no)
				(sheetname "")
			)
			(fill
				(thermal_gap 0.5)
				(thermal_bridge_width 0.5)
				(island_removal_mode 0)
			)
			(polygon
				(pts
					(arc
						(start 393.26058 -106.141266)
						(mid 392.93506 -106.565923)
						(end 393.465558 -106.495342)
					)
					(arc
						(start 393.370308 -106.472736)
						(mid 393.019551 -106.516808)
						(end 393.233148 -106.234992)
					)
				)
			)
		)
		(zone
			(layer "F.Cu")
			(hatch none 0.5)
			(connect_pads
				(clearance 0)
			)
			(min_thickness 0.25)
			(keepout
				(tracks not_allowed)
				(vias allowed)
				(pads allowed)
				(copperpour not_allowed)
				(footprints allowed)
			)
			(placement
				(enabled no)
				(sheetname "")
			)
			(fill
				(thermal_gap 0.5)
				(thermal_bridge_width 0.5)
				(island_removal_mode 0)
			)
			(polygon
				(pts
					(arc
						(start 393.285472 -104.431846)
						(mid 392.923694 -104.826267)
						(end 393.458446 -104.802686)
					)
					(arc
						(start 393.365482 -104.771698)
						(mid 393.012174 -104.784376)
						(end 393.249912 -104.522778)
					)
				)
			)
		)
		(zone
			(layer "F.Cu")
			(hatch none 0.5)
			(connect_pads
				(clearance 0)
			)
			(min_thickness 0.25)
			(keepout
				(tracks not_allowed)
				(vias allowed)
				(pads allowed)
				(copperpour not_allowed)
				(footprints allowed)
			)
			(placement
				(enabled no)
				(sheetname "")
			)
			(fill
				(thermal_gap 0.5)
				(thermal_bridge_width 0.5)
				(island_removal_mode 0)
			)
			(polygon
				(pts
					(arc
						(start 393.343892 -108.380276)
						(mid 393.244823 -107.854665)
						(end 392.943588 -108.29671)
					)
					(arc
						(start 393.023852 -108.241084)
						(mid 393.2249 -107.95015)
						(end 393.292584 -108.297218)
					)
				)
			)
		)
		(zone
			(layer "F.Cu")
			(hatch none 0.5)
			(connect_pads
				(clearance 0)
			)
			(min_thickness 0.25)
			(keepout
				(tracks not_allowed)
				(vias allowed)
				(pads allowed)
				(copperpour not_allowed)
				(footprints allowed)
			)
			(placement
				(enabled no)
				(sheetname "")
			)
			(fill
				(thermal_gap 0.5)
				(thermal_bridge_width 0.5)
				(island_removal_mode 0)
			)
			(polygon
				(pts
					(arc
						(start 393.457684 -114.905282)
						(mid 392.922739 -114.885682)
						(end 393.287504 -115.277392)
					)
					(arc
						(start 393.250928 -115.186714)
						(mid 393.011744 -114.926188)
						(end 393.365228 -114.937286)
					)
				)
			)
		)
		(zone
			(layer "F.Cu")
			(hatch none 0.5)
			(connect_pads
				(clearance 0)
			)
			(min_thickness 0.25)
			(keepout
				(tracks not_allowed)
				(vias allowed)
				(pads allowed)
				(copperpour not_allowed)
				(footprints allowed)
			)
			(placement
				(enabled no)
				(sheetname "")
			)
			(fill
				(thermal_gap 0.5)
				(thermal_bridge_width 0.5)
				(island_removal_mode 0)
			)
			(polygon
				(pts
					(arc
						(start 393.465304 -113.21415)
						(mid 392.934799 -113.144531)
						(end 393.261088 -113.568734)
					)
					(arc
						(start 393.233148 -113.475008)
						(mid 393.019456 -113.193138)
						(end 393.370308 -113.237264)
					)
				)
			)
		)
		(zone
			(layer "F.Cu")
			(hatch none 0.5)
			(connect_pads
				(clearance 0)
			)
			(min_thickness 0.25)
			(keepout
				(tracks not_allowed)
				(vias allowed)
				(pads allowed)
				(copperpour not_allowed)
				(footprints allowed)
			)
			(placement
				(enabled no)
				(sheetname "")
			)
			(fill
				(thermal_gap 0.5)
				(thermal_bridge_width 0.5)
				(island_removal_mode 0)
			)
			(polygon
				(pts
					(arc
						(start 393.775184 -103.571548)
						(mid 393.420826 -103.972594)
						(end 393.955016 -103.939086)
					)
					(arc
						(start 393.861544 -103.909876)
						(mid 393.50857 -103.929394)
						(end 393.741402 -103.663242)
					)
				)
			)
		)
		(zone
			(layer "F.Cu")
			(hatch none 0.5)
			(connect_pads
				(clearance 0)
			)
			(min_thickness 0.25)
			(keepout
				(tracks not_allowed)
				(vias allowed)
				(pads allowed)
				(copperpour not_allowed)
				(footprints allowed)
			)
			(placement
				(enabled no)
				(sheetname "")
			)
			(fill
				(thermal_gap 0.5)
				(thermal_bridge_width 0.5)
				(island_removal_mode 0)
			)
			(polygon
				(pts
					(arc
						(start 393.776708 -107.006136)
						(mid 393.420054 -107.40513)
						(end 393.954508 -107.374944)
					)
					(arc
						(start 393.861036 -107.344972)
						(mid 393.50807 -107.362079)
						(end 393.742418 -107.097576)
					)
				)
			)
		)
		(zone
			(layer "F.Cu")
			(hatch none 0.5)
			(connect_pads
				(clearance 0)
			)
			(min_thickness 0.25)
			(keepout
				(tracks not_allowed)
				(vias allowed)
				(pads allowed)
				(copperpour not_allowed)
				(footprints allowed)
			)
			(placement
				(enabled no)
				(sheetname "")
			)
			(fill
				(thermal_gap 0.5)
				(thermal_bridge_width 0.5)
				(island_removal_mode 0)
			)
			(polygon
				(pts
					(arc
						(start 393.951714 -114.045238)
						(mid 393.417012 -114.028738)
						(end 393.78382 -114.418364)
					)
					(arc
						(start 393.746736 -114.32794)
						(mid 393.50614 -114.069112)
						(end 393.859512 -114.07775)
					)
				)
			)
		)
		(zone
			(layer "F.Cu")
			(hatch none 0.5)
			(connect_pads
				(clearance 0)
			)
			(min_thickness 0.25)
			(keepout
				(tracks not_allowed)
				(vias allowed)
				(pads allowed)
				(copperpour not_allowed)
				(footprints allowed)
			)
			(placement
				(enabled no)
				(sheetname "")
			)
			(fill
				(thermal_gap 0.5)
				(thermal_bridge_width 0.5)
				(island_removal_mode 0)
			)
			(polygon
				(pts
					(arc
						(start 393.952476 -108.896404)
						(mid 393.418088 -108.875463)
						(end 393.781534 -109.268006)
					)
					(arc
						(start 393.745212 -109.177328)
						(mid 393.506641 -108.916155)
						(end 393.86002 -108.9279)
					)
				)
			)
		)
		(zone
			(layer "F.Cu")
			(hatch none 0.5)
			(connect_pads
				(clearance 0)
			)
			(min_thickness 0.25)
			(keepout
				(tracks not_allowed)
				(vias allowed)
				(pads allowed)
				(copperpour not_allowed)
				(footprints allowed)
			)
			(placement
				(enabled no)
				(sheetname "")
			)
			(fill
				(thermal_gap 0.5)
				(thermal_bridge_width 0.5)
				(island_removal_mode 0)
			)
			(polygon
				(pts
					(arc
						(start 393.953492 -105.465118)
						(mid 393.419343 -105.438689)
						(end 393.77874 -105.834942)
					)
					(arc
						(start 393.743434 -105.743756)
						(mid 393.507589 -105.480301)
						(end 393.860782 -105.495852)
					)
				)
			)
		)
		(zone
			(layer "F.Cu")
			(hatch none 0.5)
			(connect_pads
				(clearance 0)
			)
			(min_thickness 0.25)
			(keepout
				(tracks not_allowed)
				(vias allowed)
				(pads allowed)
				(copperpour not_allowed)
				(footprints allowed)
			)
			(placement
				(enabled no)
				(sheetname "")
			)
			(fill
				(thermal_gap 0.5)
				(thermal_bridge_width 0.5)
				(island_removal_mode 0)
			)
			(polygon
				(pts
					(arc
						(start 393.953746 -115.767612)
						(mid 393.419196 -115.740934)
						(end 393.778486 -116.137436)
					)
					(arc
						(start 393.74318 -116.04625)
						(mid 393.507715 -115.782722)
						(end 393.860782 -115.798346)
					)
				)
			)
		)
		(zone
			(layer "F.Cu")
			(hatch none 0.5)
			(connect_pads
				(clearance 0)
			)
			(min_thickness 0.25)
			(keepout
				(tracks not_allowed)
				(vias allowed)
				(pads allowed)
				(copperpour not_allowed)
				(footprints allowed)
			)
			(placement
				(enabled no)
				(sheetname "")
			)
			(fill
				(thermal_gap 0.5)
				(thermal_bridge_width 0.5)
				(island_removal_mode 0)
			)
			(polygon
				(pts
					(arc
						(start 393.960604 -112.35563)
						(mid 393.430099 -112.286011)
						(end 393.756388 -112.710214)
					)
					(arc
						(start 393.728448 -112.616488)
						(mid 393.514756 -112.334618)
						(end 393.865608 -112.378744)
					)
				)
			)
		)
	)
	(footprint ""
		(layer "F.Cu")
		(at 392.785346 -64.959738 90)
		(property "Reference" "R8E39"
			(at 0 0 90)
			(layer "F.SilkS")
			(hide yes)
			(effects
				(font
					(size 1.27 1.27)
				)
			)
		)
		(property "Value" ""
			(at 0 0 90)
			(layer "F.Fab")
			(effects
				(font
					(size 1.27 1.27)
				)
			)
		)
		(duplicate_pad_numbers_are_jumpers no)
		(fp_poly
			(pts
				(xy -0.2794 -0.1016) (xy 0.2794 -0.1016) (xy 0.2794 0.9906) (xy -0.2794 0.9906)
			)
			(stroke
				(width 0)
				(type default)
			)
			(fill no)
			(layer "F.CrtYd")
		)
		(fp_line
			(start 0.2794 -0.1016)
			(end -0.2794 -0.1016)
			(stroke
				(width 0.1)
				(type default)
			)
			(layer "F.Fab")
		)
		(fp_line
			(start -0.2794 -0.1016)
			(end -0.2794 0.9906)
			(stroke
				(width 0.1)
				(type default)
			)
			(layer "F.Fab")
		)
		(fp_line
			(start 0.2794 0.9906)
			(end 0.2794 -0.1016)
			(stroke
				(width 0.1)
				(type default)
			)
			(layer "F.Fab")
		)
		(fp_line
			(start -0.2794 0.9906)
			(end 0.2794 0.9906)
			(stroke
				(width 0.1)
				(type default)
			)
			(layer "F.Fab")
		)
		(pad "1" smd rect
			(at 0 0 90)
			(size 0.508 0.508)
			(layers "F.Cu" "F.Mask" "F.Paste")
			(net "VR_P5V_STBY_COMP")
		)
		(pad "2" smd rect
			(at 0 0.889 90)
			(size 0.508 0.508)
			(layers "F.Cu" "F.Mask" "F.Paste")
			(net "VR_P5V_STBY_RC_COMP")
		)
		(zone
			(layer "F.Cu")
			(hatch none 0.5)
			(connect_pads
				(clearance 0)
			)
			(min_thickness 0.25)
			(keepout
				(tracks allowed)
				(vias not_allowed)
				(pads allowed)
				(copperpour not_allowed)
				(footprints allowed)
			)
			(placement
				(enabled no)
				(sheetname "")
			)
			(fill
				(thermal_gap 0.5)
				(thermal_bridge_width 0.5)
				(island_removal_mode 0)
			)
			(polygon
				(pts
					(xy 393.039346 -64.705738) (xy 393.039346 -65.213738) (xy 393.420346 -65.213738) (xy 393.420346 -64.705738)
				)
			)
		)
		(zone
			(layer "F.Cu")
			(hatch none 0.5)
			(connect_pads
				(clearance 0)
			)
			(min_thickness 0.25)
			(keepout
				(tracks not_allowed)
				(vias allowed)
				(pads allowed)
				(copperpour not_allowed)
				(footprints allowed)
			)
			(placement
				(enabled no)
				(sheetname "")
			)
			(fill
				(thermal_gap 0.5)
				(thermal_bridge_width 0.5)
				(island_removal_mode 0)
			)
			(polygon
				(pts
					(xy 393.420346 -64.705738) (xy 393.420346 -65.213738) (xy 393.039346 -65.213738) (xy 393.039346 -64.705738)
				)
			)
		)
	)
	(footprint ""
		(layer "F.Cu")
		(at 214.503 -78.4098)
		(property "Reference" "C4D12"
			(at 0 0 0)
			(layer "F.SilkS")
			(hide yes)
			(effects
				(font
					(size 1.27 1.27)
				)
			)
		)
		(property "Value" ""
			(at 0 0 0)
			(layer "F.Fab")
			(effects
				(font
					(size 1.27 1.27)
				)
			)
		)
		(duplicate_pad_numbers_are_jumpers no)
		(fp_poly
			(pts
				(xy -0.4953 -0.2032) (xy 0.4953 -0.2032) (xy 0.4953 1.6002) (xy -0.4953 1.6002)
			)
			(stroke
				(width 0)
				(type default)
			)
			(fill no)
			(layer "F.CrtYd")
		)
		(fp_line
			(start -0.4953 -0.2032)
			(end 0.4953 -0.2032)
			(stroke
				(width 0.1)
				(type default)
			)
			(layer "F.Fab")
		)
		(fp_line
			(start -0.4953 1.6002)
			(end -0.4953 -0.2032)
			(stroke
				(width 0.1)
				(type default)
			)
			(layer "F.Fab")
		)
		(fp_line
			(start 0.4953 -0.2032)
			(end 0.4953 1.6002)
			(stroke
				(width 0.1)
				(type default)
			)
			(layer "F.Fab")
		)
		(fp_line
			(start 0.4953 1.6002)
			(end -0.4953 1.6002)
			(stroke
				(width 0.1)
				(type default)
			)
			(layer "F.Fab")
		)
		(pad "1" smd rect
			(at 0 0)
			(size 0.762 0.889)
			(layers "F.Cu" "F.Mask" "F.Paste")
			(net "PVCCIN_CPU0")
		)
		(pad "2" smd rect
			(at 0 1.397)
			(size 0.762 0.889)
			(layers "F.Cu" "F.Mask" "F.Paste")
			(net "GND")
		)
		(zone
			(layer "F.Cu")
			(hatch none 0.5)
			(connect_pads
				(clearance 0)
			)
			(min_thickness 0.25)
			(keepout
				(tracks not_allowed)
				(vias allowed)
				(pads allowed)
				(copperpour not_allowed)
				(footprints allowed)
			)
			(placement
				(enabled no)
				(sheetname "")
			)
			(fill
				(thermal_gap 0.5)
				(thermal_bridge_width 0.5)
				(island_removal_mode 0)
			)
			(polygon
				(pts
					(xy 214.122 -77.9653) (xy 214.884 -77.9653) (xy 214.884 -77.4573) (xy 214.122 -77.4573)
				)
			)
		)
	)
	(footprint ""
		(layer "F.Cu")
		(at 386.417566 -141.471396 -90)
		(property "Reference" "C7B18"
			(at 0 0 270)
			(layer "F.SilkS")
			(hide yes)
			(effects
				(font
					(size 1.27 1.27)
				)
			)
		)
		(property "Value" ""
			(at 0 0 270)
			(layer "F.Fab")
			(effects
				(font
					(size 1.27 1.27)
				)
			)
		)
		(duplicate_pad_numbers_are_jumpers no)
		(fp_rect
			(start -0.4953 1.6002)
			(end 0.4953 -0.2032)
			(stroke
				(width 0)
				(type default)
			)
			(fill no)
			(layer "F.CrtYd")
		)
		(fp_line
			(start -0.4953 1.6002)
			(end -0.4953 -0.2032)
			(stroke
				(width 0.1)
				(type default)
			)
			(layer "F.Fab")
		)
		(fp_line
			(start 0.4953 1.6002)
			(end -0.4953 1.6002)
			(stroke
				(width 0.1)
				(type default)
			)
			(layer "F.Fab")
		)
		(fp_line
			(start -0.4953 -0.2032)
			(end 0.4953 -0.2032)
			(stroke
				(width 0.1)
				(type default)
			)
			(layer "F.Fab")
		)
		(fp_line
			(start 0.4953 -0.2032)
			(end 0.4953 1.6002)
			(stroke
				(width 0.1)
				(type default)
			)
			(layer "F.Fab")
		)
		(pad "1" smd rect
			(at 0 0 270)
			(size 0.762 0.889)
			(layers "F.Cu" "F.Mask" "F.Paste")
			(net "P1V05_PCH_STBY")
		)
		(pad "2" smd rect
			(at 0 1.397 270)
			(size 0.762 0.889)
			(layers "F.Cu" "F.Mask" "F.Paste")
			(net "GND")
		)
		(zone
			(layer "F.Cu")
			(hatch none 0.5)
			(connect_pads
				(clearance 0)
			)
			(min_thickness 0.25)
			(keepout
				(tracks not_allowed)
				(vias allowed)
				(pads allowed)
				(copperpour not_allowed)
				(footprints allowed)
			)
			(placement
				(enabled no)
				(sheetname "")
			)
			(fill
				(thermal_gap 0.5)
				(thermal_bridge_width 0.5)
				(island_removal_mode 0)
			)
			(polygon
				(pts
					(xy 385.465066 -141.852396) (xy 385.465066 -141.090396) (xy 385.973066 -141.090396) (xy 385.973066 -141.852396)
				)
			)
		)
	)
	(footprint ""
		(layer "F.Cu")
		(at 407.749502 -122.011186 90)
		(property "Reference" "R1W16"
			(at -0.8382 -0.67818 90)
			(unlocked yes)
			(layer "F.SilkS")
			(effects
				(font
					(size 0.4064 0.254)
					(thickness 0.1524)
				)
				(justify left)
			)
		)
		(property "Value" ""
			(at 0 0 90)
			(layer "F.Fab")
			(effects
				(font
					(size 1.27 1.27)
				)
			)
		)
		(duplicate_pad_numbers_are_jumpers no)
		(fp_poly
			(pts
				(xy -0.2794 -0.1016) (xy 0.2794 -0.1016) (xy 0.2794 0.9906) (xy -0.2794 0.9906)
			)
			(stroke
				(width 0)
				(type default)
			)
			(fill no)
			(layer "F.CrtYd")
		)
		(fp_line
			(start 0.2794 -0.1016)
			(end -0.2794 -0.1016)
			(stroke
				(width 0.1)
				(type default)
			)
			(layer "F.Fab")
		)
		(fp_line
			(start -0.2794 -0.1016)
			(end -0.2794 0.9906)
			(stroke
				(width 0.1)
				(type default)
			)
			(layer "F.Fab")
		)
		(fp_line
			(start 0.2794 0.9906)
			(end 0.2794 -0.1016)
			(stroke
				(width 0.1)
				(type default)
			)
			(layer "F.Fab")
		)
		(fp_line
			(start -0.2794 0.9906)
			(end 0.2794 0.9906)
			(stroke
				(width 0.1)
				(type default)
			)
			(layer "F.Fab")
		)
		(pad "1" smd rect
			(at 0 0 90)
			(size 0.508 0.508)
			(layers "F.Cu" "F.Mask" "F.Paste")
			(net "USB_PCH_BMC_P4_DP_R")
		)
		(pad "2" smd rect
			(at 0 0.889 90)
			(size 0.508 0.508)
			(layers "F.Cu" "F.Mask" "F.Paste")
			(net "USB_PCH_BMC_P4_DP")
		)
		(zone
			(layer "F.Cu")
			(hatch none 0.5)
			(connect_pads
				(clearance 0)
			)
			(min_thickness 0.25)
			(keepout
				(tracks allowed)
				(vias not_allowed)
				(pads allowed)
				(copperpour not_allowed)
				(footprints allowed)
			)
			(placement
				(enabled no)
				(sheetname "")
			)
			(fill
				(thermal_gap 0.5)
				(thermal_bridge_width 0.5)
				(island_removal_mode 0)
			)
			(polygon
				(pts
					(xy 408.003502 -121.757186) (xy 408.003502 -122.265186) (xy 408.384502 -122.265186) (xy 408.384502 -121.757186)
				)
			)
		)
		(zone
			(layer "F.Cu")
			(hatch none 0.5)
			(connect_pads
				(clearance 0)
			)
			(min_thickness 0.25)
			(keepout
				(tracks not_allowed)
				(vias allowed)
				(pads allowed)
				(copperpour not_allowed)
				(footprints allowed)
			)
			(placement
				(enabled no)
				(sheetname "")
			)
			(fill
				(thermal_gap 0.5)
				(thermal_bridge_width 0.5)
				(island_removal_mode 0)
			)
			(polygon
				(pts
					(xy 408.384502 -121.757186) (xy 408.384502 -122.265186) (xy 408.003502 -122.265186) (xy 408.003502 -121.757186)
				)
			)
		)
	)
	(footprint ""
		(layer "F.Cu")
		(at 351.51568 -139.37742 -90)
		(property "Reference" "R7A10"
			(at 0 0 270)
			(layer "F.SilkS")
			(hide yes)
			(effects
				(font
					(size 1.27 1.27)
				)
			)
		)
		(property "Value" ""
			(at 0 0 270)
			(layer "F.Fab")
			(effects
				(font
					(size 1.27 1.27)
				)
			)
		)
		(duplicate_pad_numbers_are_jumpers no)
		(fp_poly
			(pts
				(xy -0.2794 -0.1016) (xy 0.2794 -0.1016) (xy 0.2794 0.9906) (xy -0.2794 0.9906)
			)
			(stroke
				(width 0)
				(type default)
			)
			(fill no)
			(layer "F.CrtYd")
		)
		(fp_line
			(start -0.2794 0.9906)
			(end 0.2794 0.9906)
			(stroke
				(width 0.1)
				(type default)
			)
			(layer "F.Fab")
		)
		(fp_line
			(start 0.2794 0.9906)
			(end 0.2794 -0.1016)
			(stroke
				(width 0.1)
				(type default)
			)
			(layer "F.Fab")
		)
		(fp_line
			(start -0.2794 -0.1016)
			(end -0.2794 0.9906)
			(stroke
				(width 0.1)
				(type default)
			)
			(layer "F.Fab")
		)
		(fp_line
			(start 0.2794 -0.1016)
			(end -0.2794 -0.1016)
			(stroke
				(width 0.1)
				(type default)
			)
			(layer "F.Fab")
		)
		(pad "1" smd rect
			(at 0 0 270)
			(size 0.508 0.508)
			(layers "F.Cu" "F.Mask" "F.Paste")
			(net "VR_PVDDQ_DEF_XADDR1")
		)
		(pad "2" smd rect
			(at 0 0.889 270)
			(size 0.508 0.508)
			(layers "F.Cu" "F.Mask" "F.Paste")
			(net "GND")
		)
		(zone
			(layer "F.Cu")
			(hatch none 0.5)
			(connect_pads
				(clearance 0)
			)
			(min_thickness 0.25)
			(keepout
				(tracks not_allowed)
				(vias allowed)
				(pads allowed)
				(copperpour not_allowed)
				(footprints allowed)
			)
			(placement
				(enabled no)
				(sheetname "")
			)
			(fill
				(thermal_gap 0.5)
				(thermal_bridge_width 0.5)
				(island_removal_mode 0)
			)
			(polygon
				(pts
					(xy 350.88068 -139.63142) (xy 350.88068 -139.12342) (xy 351.26168 -139.12342) (xy 351.26168 -139.63142)
				)
			)
		)
		(zone
			(layer "F.Cu")
			(hatch none 0.5)
			(connect_pads
				(clearance 0)
			)
			(min_thickness 0.25)
			(keepout
				(tracks allowed)
				(vias not_allowed)
				(pads allowed)
				(copperpour not_allowed)
				(footprints allowed)
			)
			(placement
				(enabled no)
				(sheetname "")
			)
			(fill
				(thermal_gap 0.5)
				(thermal_bridge_width 0.5)
				(island_removal_mode 0)
			)
			(polygon
				(pts
					(xy 351.26168 -139.63142) (xy 351.26168 -139.12342) (xy 350.88068 -139.12342) (xy 350.88068 -139.63142)
				)
			)
		)
	)
	(footprint ""
		(layer "F.Cu")
		(at 193.675 -13.3985)
		(property "Reference" "R4G2"
			(at 0 0 0)
			(layer "F.SilkS")
			(hide yes)
			(effects
				(font
					(size 1.27 1.27)
				)
			)
		)
		(property "Value" ""
			(at 0 0 0)
			(layer "F.Fab")
			(effects
				(font
					(size 1.27 1.27)
				)
			)
		)
		(duplicate_pad_numbers_are_jumpers no)
		(fp_poly
			(pts
				(xy -0.2794 -0.1016) (xy 0.2794 -0.1016) (xy 0.2794 0.9906) (xy -0.2794 0.9906)
			)
			(stroke
				(width 0)
				(type default)
			)
			(fill no)
			(layer "F.CrtYd")
		)
		(fp_line
			(start -0.2794 -0.1016)
			(end -0.2794 0.9906)
			(stroke
				(width 0.1)
				(type default)
			)
			(layer "F.Fab")
		)
		(fp_line
			(start -0.2794 0.9906)
			(end 0.2794 0.9906)
			(stroke
				(width 0.1)
				(type default)
			)
			(layer "F.Fab")
		)
		(fp_line
			(start 0.2794 -0.1016)
			(end -0.2794 -0.1016)
			(stroke
				(width 0.1)
				(type default)
			)
			(layer "F.Fab")
		)
		(fp_line
			(start 0.2794 0.9906)
			(end 0.2794 -0.1016)
			(stroke
				(width 0.1)
				(type default)
			)
			(layer "F.Fab")
		)
		(pad "1" smd rect
			(at 0 0)
			(size 0.508 0.508)
			(layers "F.Cu" "F.Mask" "F.Paste")
			(net "PVDDQ_ABC")
		)
		(pad "2" smd rect
			(at 0 0.889)
			(size 0.508 0.508)
			(layers "F.Cu" "F.Mask" "F.Paste")
			(net "M_B_VREF")
		)
		(zone
			(layer "F.Cu")
			(hatch none 0.5)
			(connect_pads
				(clearance 0)
			)
			(min_thickness 0.25)
			(keepout
				(tracks allowed)
				(vias not_allowed)
				(pads allowed)
				(copperpour not_allowed)
				(footprints allowed)
			)
			(placement
				(enabled no)
				(sheetname "")
			)
			(fill
				(thermal_gap 0.5)
				(thermal_bridge_width 0.5)
				(island_removal_mode 0)
			)
			(polygon
				(pts
					(xy 193.421 -13.1445) (xy 193.929 -13.1445) (xy 193.929 -12.7635) (xy 193.421 -12.7635)
				)
			)
		)
		(zone
			(layer "F.Cu")
			(hatch none 0.5)
			(connect_pads
				(clearance 0)
			)
			(min_thickness 0.25)
			(keepout
				(tracks not_allowed)
				(vias allowed)
				(pads allowed)
				(copperpour not_allowed)
				(footprints allowed)
			)
			(placement
				(enabled no)
				(sheetname "")
			)
			(fill
				(thermal_gap 0.5)
				(thermal_bridge_width 0.5)
				(island_removal_mode 0)
			)
			(polygon
				(pts
					(xy 193.421 -12.7635) (xy 193.929 -12.7635) (xy 193.929 -13.1445) (xy 193.421 -13.1445)
				)
			)
		)
	)
	(footprint ""
		(layer "F.Cu")
		(at 5.1054 -22.2758 90)
		(property "Reference" "C1G2"
			(at 0 0 90)
			(layer "F.SilkS")
			(hide yes)
			(effects
				(font
					(size 1.27 1.27)
				)
			)
		)
		(property "Value" "*"
			(at -0.0762 -6.2357 90)
			(unlocked yes)
			(layer "F.Fab")
			(hide yes)
			(effects
				(font
					(size 1.27 1.016)
					(thickness 0.1524)
				)
			)
		)
		(property "Device Type" "SC22U16V5MX-4-GP_SMD-BCG5-SC22A"
			(at -0.0762 -8.2677 90)
			(unlocked yes)
			(layer "F.Fab")
			(hide yes)
			(effects
				(font
					(size 1.27 1.016)
					(thickness 0.1524)
				)
			)
		)
		(duplicate_pad_numbers_are_jumpers no)
		(fp_line
			(start 0.635 0)
			(end -0.635 0)
			(stroke
				(width 0.508)
				(type default)
			)
			(layer "F.SilkS")
		)
		(fp_rect
			(start -0.9652 1.778)
			(end 0.9652 -1.778)
			(stroke
				(width 0)
				(type default)
			)
			(fill no)
			(layer "F.CrtYd")
		)
		(fp_poly
			(pts
				(xy -0.9652 -1.778) (xy 0.9652 -1.778) (xy 0.9652 1.778) (xy -0.9652 1.778)
			)
			(stroke
				(width 0)
				(type default)
			)
			(fill no)
			(layer "F.Fab")
		)
		(pad "1" smd rect
			(at 0 -0.9652 90)
			(size 1.397 1.143)
			(layers "F.Cu" "F.Mask" "F.Paste")
			(net "VR_FET_SW_P12V_STBY_PVDDQ_GHJ")
		)
		(pad "2" smd rect
			(at 0 0.9652 90)
			(size 1.397 1.143)
			(layers "F.Cu" "F.Mask" "F.Paste")
			(net "GND")
		)
	)
	(footprint ""
		(layer "F.Cu")
		(at 24.8412 -69.3166 90)
		(property "Reference" "Q1D3"
			(at -1.34747 -0.1016 0)
			(unlocked yes)
			(layer "F.SilkS")
			(effects
				(font
					(size 0.7874 0.5842)
					(thickness 0.1524)
				)
				(justify left)
			)
		)
		(property "Value" ""
			(at 0 0 90)
			(layer "F.Fab")
			(effects
				(font
					(size 1.27 1.27)
				)
			)
		)
		(duplicate_pad_numbers_are_jumpers no)
		(fp_line
			(start 1.778 -0.5715)
			(end 1.778 0.3175)
			(stroke
				(width 0.1524)
				(type default)
			)
			(layer "F.SilkS")
		)
		(fp_line
			(start 0.9525 -0.5715)
			(end 1.778 -0.5715)
			(stroke
				(width 0.1524)
				(type default)
			)
			(layer "F.SilkS")
		)
		(fp_line
			(start 0.381 0.635)
			(end 0.381 1.27)
			(stroke
				(width 0.1524)
				(type default)
			)
			(layer "F.SilkS")
		)
		(fp_line
			(start 1.778 2.4765)
			(end 1.778 1.5875)
			(stroke
				(width 0.1524)
				(type default)
			)
			(layer "F.SilkS")
		)
		(fp_line
			(start 0.9525 2.4765)
			(end 1.778 2.4765)
			(stroke
				(width 0.1524)
				(type default)
			)
			(layer "F.SilkS")
		)
		(fp_circle
			(center -1.039368 -0.232156)
			(end -1.039368 -0.105156)
			(stroke
				(width 0.254)
				(type default)
			)
			(fill no)
			(layer "F.SilkS")
		)
		(fp_poly
			(pts
				(xy 1.778 2.4765) (xy 0.381 2.4765) (xy 0.381 -0.5715) (xy 1.778 -0.5715)
			)
			(stroke
				(width 0)
				(type default)
			)
			(fill no)
			(layer "F.CrtYd")
		)
		(fp_line
			(start 1.778 -0.5715)
			(end 0.381 -0.5715)
			(stroke
				(width 0.1)
				(type default)
			)
			(layer "F.Fab")
		)
		(fp_line
			(start 0.381 -0.5715)
			(end 0.381 2.4765)
			(stroke
				(width 0.1)
				(type default)
			)
			(layer "F.Fab")
		)
		(fp_line
			(start 1.778 2.4765)
			(end 1.778 -0.5715)
			(stroke
				(width 0.1)
				(type default)
			)
			(layer "F.Fab")
		)
		(fp_line
			(start 0.381 2.4765)
			(end 1.778 2.4765)
			(stroke
				(width 0.1)
				(type default)
			)
			(layer "F.Fab")
		)
		(fp_circle
			(center -0.9525 -0.9271)
			(end -0.9525 -0.8001)
			(stroke
				(width 0.254)
				(type default)
			)
			(fill no)
			(layer "F.Fab")
		)
		(pad "1" smd rect
			(at 0 0 90)
			(size 1.143 0.508)
			(layers "F.Cu" "F.Mask" "F.Paste")
			(net "TEMP_SENSOR_B")
		)
		(pad "2" smd rect
			(at 0 1.905 90)
			(size 1.143 0.508)
			(layers "F.Cu" "F.Mask" "F.Paste")
			(net "TEMP_SENSOR_E")
		)
		(pad "3" smd rect
			(at 2.159 0.9525 90)
			(size 1.143 0.508)
			(layers "F.Cu" "F.Mask" "F.Paste")
			(net "TEMP_SENSOR_B")
		)
	)
	(footprint ""
		(layer "F.Cu")
		(at 349.6437 -27.9654 180)
		(property "Reference" "C7F6"
			(at 0 0 180)
			(layer "F.SilkS")
			(hide yes)
			(effects
				(font
					(size 1.27 1.27)
				)
			)
		)
		(property "Value" ""
			(at 0 0 180)
			(layer "F.Fab")
			(effects
				(font
					(size 1.27 1.27)
				)
			)
		)
		(duplicate_pad_numbers_are_jumpers no)
		(fp_rect
			(start -0.3048 -0.1016)
			(end 0.3048 0.9906)
			(stroke
				(width 0)
				(type default)
			)
			(fill no)
			(layer "F.CrtYd")
		)
		(fp_line
			(start 0.3048 0.9906)
			(end 0.3048 -0.1016)
			(stroke
				(width 0.1)
				(type default)
			)
			(layer "F.Fab")
		)
		(fp_line
			(start 0.3048 -0.1016)
			(end -0.3048 -0.1016)
			(stroke
				(width 0.1)
				(type default)
			)
			(layer "F.Fab")
		)
		(fp_line
			(start -0.3048 0.9906)
			(end 0.3048 0.9906)
			(stroke
				(width 0.1)
				(type default)
			)
			(layer "F.Fab")
		)
		(fp_line
			(start -0.3048 -0.1016)
			(end -0.3048 0.9906)
			(stroke
				(width 0.1)
				(type default)
			)
			(layer "F.Fab")
		)
		(pad "1" smd rect
			(at 0 0 180)
			(size 0.508 0.508)
			(layers "F.Cu" "F.Mask" "F.Paste")
			(net "VR_FET_SW_P12V_STBY_PVPP_ABC")
		)
		(pad "2" smd rect
			(at 0 0.889 180)
			(size 0.508 0.508)
			(layers "F.Cu" "F.Mask" "F.Paste")
			(net "GND")
		)
		(zone
			(layer "F.Cu")
			(hatch none 0.5)
			(connect_pads
				(clearance 0)
			)
			(min_thickness 0.25)
			(keepout
				(tracks not_allowed)
				(vias allowed)
				(pads allowed)
				(copperpour not_allowed)
				(footprints allowed)
			)
			(placement
				(enabled no)
				(sheetname "")
			)
			(fill
				(thermal_gap 0.5)
				(thermal_bridge_width 0.5)
				(island_removal_mode 0)
			)
			(polygon
				(pts
					(xy 349.8977 -28.2194) (xy 349.8977 -28.6004) (xy 349.3897 -28.6004) (xy 349.3897 -28.2194)
				)
			)
		)
		(zone
			(layer "F.Cu")
			(hatch none 0.5)
			(connect_pads
				(clearance 0)
			)
			(min_thickness 0.25)
			(keepout
				(tracks allowed)
				(vias not_allowed)
				(pads allowed)
				(copperpour not_allowed)
				(footprints allowed)
			)
			(placement
				(enabled no)
				(sheetname "")
			)
			(fill
				(thermal_gap 0.5)
				(thermal_bridge_width 0.5)
				(island_removal_mode 0)
			)
			(polygon
				(pts
					(xy 349.8977 -28.2194) (xy 349.8977 -28.6004) (xy 349.3897 -28.6004) (xy 349.3897 -28.2194)
				)
			)
		)
	)
	(footprint ""
		(layer "F.Cu")
		(at 23.46198 -84.14258)
		(property "Reference" "R1D12"
			(at 0 0 0)
			(layer "F.SilkS")
			(hide yes)
			(effects
				(font
					(size 1.27 1.27)
				)
			)
		)
		(property "Value" ""
			(at 0 0 0)
			(layer "F.Fab")
			(effects
				(font
					(size 1.27 1.27)
				)
			)
		)
		(duplicate_pad_numbers_are_jumpers no)
		(fp_poly
			(pts
				(xy -0.2794 -0.1016) (xy 0.2794 -0.1016) (xy 0.2794 0.9906) (xy -0.2794 0.9906)
			)
			(stroke
				(width 0)
				(type default)
			)
			(fill no)
			(layer "F.CrtYd")
		)
		(fp_line
			(start -0.2794 -0.1016)
			(end -0.2794 0.9906)
			(stroke
				(width 0.1)
				(type default)
			)
			(layer "F.Fab")
		)
		(fp_line
			(start -0.2794 0.9906)
			(end 0.2794 0.9906)
			(stroke
				(width 0.1)
				(type default)
			)
			(layer "F.Fab")
		)
		(fp_line
			(start 0.2794 -0.1016)
			(end -0.2794 -0.1016)
			(stroke
				(width 0.1)
				(type default)
			)
			(layer "F.Fab")
		)
		(fp_line
			(start 0.2794 0.9906)
			(end 0.2794 -0.1016)
			(stroke
				(width 0.1)
				(type default)
			)
			(layer "F.Fab")
		)
		(pad "1" smd rect
			(at 0 0)
			(size 0.508 0.508)
			(layers "F.Cu" "F.Mask" "F.Paste")
			(net "A_HSC_LOW")
		)
		(pad "2" smd rect
			(at 0 0.889)
			(size 0.508 0.508)
			(layers "F.Cu" "F.Mask" "F.Paste")
			(net "AGND_HSC")
		)
		(zone
			(layer "F.Cu")
			(hatch none 0.5)
			(connect_pads
				(clearance 0)
			)
			(min_thickness 0.25)
			(keepout
				(tracks allowed)
				(vias not_allowed)
				(pads allowed)
				(copperpour not_allowed)
				(footprints allowed)
			)
			(placement
				(enabled no)
				(sheetname "")
			)
			(fill
				(thermal_gap 0.5)
				(thermal_bridge_width 0.5)
				(island_removal_mode 0)
			)
			(polygon
				(pts
					(xy 23.20798 -83.88858) (xy 23.71598 -83.88858) (xy 23.71598 -83.50758) (xy 23.20798 -83.50758)
				)
			)
		)
		(zone
			(layer "F.Cu")
			(hatch none 0.5)
			(connect_pads
				(clearance 0)
			)
			(min_thickness 0.25)
			(keepout
				(tracks not_allowed)
				(vias allowed)
				(pads allowed)
				(copperpour not_allowed)
				(footprints allowed)
			)
			(placement
				(enabled no)
				(sheetname "")
			)
			(fill
				(thermal_gap 0.5)
				(thermal_bridge_width 0.5)
				(island_removal_mode 0)
			)
			(polygon
				(pts
					(xy 23.20798 -83.50758) (xy 23.71598 -83.50758) (xy 23.71598 -83.88858) (xy 23.20798 -83.88858)
				)
			)
		)
	)
	(footprint ""
		(layer "F.Cu")
		(at 9.017 10.7315 -90)
		(property "Reference" "T1P25"
			(at 0 0 270)
			(layer "F.SilkS")
			(hide yes)
			(effects
				(font
					(size 1.27 1.27)
				)
			)
		)
		(property "Value" "*"
			(at 0 -3.44805 270)
			(unlocked yes)
			(layer "F.Fab")
			(hide yes)
			(effects
				(font
					(size 0.889 0.889)
					(thickness 0.1524)
				)
			)
		)
		(property "Device Type" "TPAD-SE-2P-GP_DISCRET-GA1-TPADA"
			(at 0 -4.97205 270)
			(unlocked yes)
			(layer "F.Fab")
			(hide yes)
			(effects
				(font
					(size 0.889 0.889)
					(thickness 0.1524)
				)
			)
		)
		(duplicate_pad_numbers_are_jumpers no)
		(fp_line
			(start -1.016 2.286)
			(end -1.016 -2.286)
			(stroke
				(width 0.1524)
				(type default)
			)
			(layer "F.SilkS")
		)
		(fp_line
			(start 1.016 2.286)
			(end -1.016 2.286)
			(stroke
				(width 0.1524)
				(type default)
			)
			(layer "F.SilkS")
		)
		(fp_line
			(start -1.016 -2.286)
			(end 1.016 -2.286)
			(stroke
				(width 0.1524)
				(type default)
			)
			(layer "F.SilkS")
		)
		(fp_line
			(start 1.016 -2.286)
			(end 1.016 2.286)
			(stroke
				(width 0.1524)
				(type default)
			)
			(layer "F.SilkS")
		)
		(fp_rect
			(start -1.27 2.54)
			(end 1.27 -2.54)
			(stroke
				(width 0)
				(type default)
			)
			(fill no)
			(layer "F.CrtYd")
		)
		(fp_rect
			(start -1.27 2.54)
			(end 1.27 -2.54)
			(stroke
				(width 0)
				(type default)
			)
			(fill no)
			(layer "F.Fab")
		)
		(pad "1" thru_hole circle
			(at 0 -1.27 270)
			(size 1.524 1.524)
			(drill 0.9144)
			(layers "*.Cu" "*.Mask")
			(remove_unused_layers no)
			(net "L1_40OHM_6INCH")
			(clearance -0.0508)
			(thermal_gap 0.127)
			(padstack
				(mode front_inner_back)
				(layer "Inner"
					(shape circle)
					(size 1.1684 1.1684)
					(clearance 0.127)
				)
				(layer "B.Cu"
					(shape circle)
					(size 1.524 1.524)
					(clearance -0.0508)
				)
			)
		)
		(pad "GND1" thru_hole rect
			(at 0 1.27 270)
			(size 1.524 1.524)
			(drill 0.9144)
			(layers "*.Cu" "*.Mask")
			(remove_unused_layers no)
			(net "GND")
			(clearance -0.0508)
			(thermal_gap 0.127)
			(padstack
				(mode front_inner_back)
				(layer "Inner"
					(shape circle)
					(size 1.1684 1.1684)
					(clearance 0.127)
				)
				(layer "B.Cu"
					(shape rect)
					(size 1.524 1.524)
					(clearance -0.0508)
				)
			)
		)
	)
	(footprint ""
		(layer "F.Cu")
		(at 33.2105 -92.9386 90)
		(property "Reference" "C1C25"
			(at 0 0 90)
			(layer "F.SilkS")
			(hide yes)
			(effects
				(font
					(size 1.27 1.27)
				)
			)
		)
		(property "Value" ""
			(at 0 0 90)
			(layer "F.Fab")
			(effects
				(font
					(size 1.27 1.27)
				)
			)
		)
		(duplicate_pad_numbers_are_jumpers no)
		(fp_rect
			(start 0.3048 0.9906)
			(end -0.3048 -0.1016)
			(stroke
				(width 0)
				(type default)
			)
			(fill no)
			(layer "F.CrtYd")
		)
		(fp_line
			(start 0.3048 -0.1016)
			(end -0.3048 -0.1016)
			(stroke
				(width 0.1)
				(type default)
			)
			(layer "F.Fab")
		)
		(fp_line
			(start -0.3048 -0.1016)
			(end -0.3048 0.9906)
			(stroke
				(width 0.1)
				(type default)
			)
			(layer "F.Fab")
		)
		(fp_line
			(start 0.3048 0.9906)
			(end 0.3048 -0.1016)
			(stroke
				(width 0.1)
				(type default)
			)
			(layer "F.Fab")
		)
		(fp_line
			(start -0.3048 0.9906)
			(end 0.3048 0.9906)
			(stroke
				(width 0.1)
				(type default)
			)
			(layer "F.Fab")
		)
		(pad "1" smd rect
			(at 0 0 90)
			(size 0.508 0.508)
			(layers "F.Cu" "F.Mask" "F.Paste")
			(net "VR_FET_SW_P12V_STBY_PVCCIN_CPU1")
		)
		(pad "2" smd rect
			(at 0 0.889 90)
			(size 0.508 0.508)
			(layers "F.Cu" "F.Mask" "F.Paste")
			(net "GND")
		)
		(zone
			(layer "F.Cu")
			(hatch none 0.5)
			(connect_pads
				(clearance 0)
			)
			(min_thickness 0.25)
			(keepout
				(tracks allowed)
				(vias not_allowed)
				(pads allowed)
				(copperpour not_allowed)
				(footprints allowed)
			)
			(placement
				(enabled no)
				(sheetname "")
			)
			(fill
				(thermal_gap 0.5)
				(thermal_bridge_width 0.5)
				(island_removal_mode 0)
			)
			(polygon
				(pts
					(xy 33.8455 -93.1926) (xy 33.4645 -93.1926) (xy 33.4645 -92.6846) (xy 33.8455 -92.6846)
				)
			)
		)
		(zone
			(layer "F.Cu")
			(hatch none 0.5)
			(connect_pads
				(clearance 0)
			)
			(min_thickness 0.25)
			(keepout
				(tracks not_allowed)
				(vias allowed)
				(pads allowed)
				(copperpour not_allowed)
				(footprints allowed)
			)
			(placement
				(enabled no)
				(sheetname "")
			)
			(fill
				(thermal_gap 0.5)
				(thermal_bridge_width 0.5)
				(island_removal_mode 0)
			)
			(polygon
				(pts
					(xy 33.8455 -93.1926) (xy 33.4645 -93.1926) (xy 33.4645 -92.6846) (xy 33.8455 -92.6846)
				)
			)
		)
	)
	(footprint ""
		(layer "F.Cu")
		(at 267.146024 -68.412614 180)
		(property "Reference" "C5D57"
			(at 0 0 180)
			(layer "F.SilkS")
			(hide yes)
			(effects
				(font
					(size 1.27 1.27)
				)
			)
		)
		(property "Value" ""
			(at 0 0 180)
			(layer "F.Fab")
			(effects
				(font
					(size 1.27 1.27)
				)
			)
		)
		(duplicate_pad_numbers_are_jumpers no)
		(fp_poly
			(pts
				(xy -0.4953 -0.2032) (xy 0.4953 -0.2032) (xy 0.4953 1.6002) (xy -0.4953 1.6002)
			)
			(stroke
				(width 0)
				(type default)
			)
			(fill no)
			(layer "F.CrtYd")
		)
		(fp_line
			(start 0.4953 1.6002)
			(end -0.4953 1.6002)
			(stroke
				(width 0.1)
				(type default)
			)
			(layer "F.Fab")
		)
		(fp_line
			(start 0.4953 -0.2032)
			(end 0.4953 1.6002)
			(stroke
				(width 0.1)
				(type default)
			)
			(layer "F.Fab")
		)
		(fp_line
			(start -0.4953 1.6002)
			(end -0.4953 -0.2032)
			(stroke
				(width 0.1)
				(type default)
			)
			(layer "F.Fab")
		)
		(fp_line
			(start -0.4953 -0.2032)
			(end 0.4953 -0.2032)
			(stroke
				(width 0.1)
				(type default)
			)
			(layer "F.Fab")
		)
		(pad "1" smd rect
			(at 0 0 180)
			(size 0.762 0.889)
			(layers "F.Cu" "F.Mask" "F.Paste")
			(net "PVDDQ_ABC")
		)
		(pad "2" smd rect
			(at 0 1.397 180)
			(size 0.762 0.889)
			(layers "F.Cu" "F.Mask" "F.Paste")
			(net "GND")
		)
		(zone
			(layer "F.Cu")
			(hatch none 0.5)
			(connect_pads
				(clearance 0)
			)
			(min_thickness 0.25)
			(keepout
				(tracks not_allowed)
				(vias allowed)
				(pads allowed)
				(copperpour not_allowed)
				(footprints allowed)
			)
			(placement
				(enabled no)
				(sheetname "")
			)
			(fill
				(thermal_gap 0.5)
				(thermal_bridge_width 0.5)
				(island_removal_mode 0)
			)
			(polygon
				(pts
					(xy 267.527024 -68.857114) (xy 266.765024 -68.857114) (xy 266.765024 -69.365114) (xy 267.527024 -69.365114)
				)
			)
		)
	)
	(footprint ""
		(layer "F.Cu")
		(at 190.1698 -69.3039 180)
		(property "Reference" "RF4"
			(at -0.8382 -0.67818 180)
			(unlocked yes)
			(layer "F.SilkS")
			(effects
				(font
					(size 0.4064 0.254)
					(thickness 0.1524)
				)
				(justify left)
			)
		)
		(property "Value" ""
			(at 0 0 180)
			(layer "F.Fab")
			(effects
				(font
					(size 1.27 1.27)
				)
			)
		)
		(duplicate_pad_numbers_are_jumpers no)
		(fp_poly
			(pts
				(xy -0.2794 -0.1016) (xy 0.2794 -0.1016) (xy 0.2794 0.9906) (xy -0.2794 0.9906)
			)
			(stroke
				(width 0)
				(type default)
			)
			(fill no)
			(layer "F.CrtYd")
		)
		(fp_line
			(start 0.2794 0.9906)
			(end 0.2794 -0.1016)
			(stroke
				(width 0.1)
				(type default)
			)
			(layer "F.Fab")
		)
		(fp_line
			(start 0.2794 -0.1016)
			(end -0.2794 -0.1016)
			(stroke
				(width 0.1)
				(type default)
			)
			(layer "F.Fab")
		)
		(fp_line
			(start -0.2794 0.9906)
			(end 0.2794 0.9906)
			(stroke
				(width 0.1)
				(type default)
			)
			(layer "F.Fab")
		)
		(fp_line
			(start -0.2794 -0.1016)
			(end -0.2794 0.9906)
			(stroke
				(width 0.1)
				(type default)
			)
			(layer "F.Fab")
		)
		(pad "1" smd rect
			(at 0 0 180)
			(size 0.508 0.508)
			(layers "F.Cu" "F.Mask" "F.Paste")
			(net "VR_PVCCIN_CPU0_AIREF4")
		)
		(pad "2" smd rect
			(at 0 0.889 180)
			(size 0.508 0.508)
			(layers "F.Cu" "F.Mask" "F.Paste")
			(net "ISENSE_PVCCIN_CPU0_PH4_IMON")
		)
		(zone
			(layer "F.Cu")
			(hatch none 0.5)
			(connect_pads
				(clearance 0)
			)
			(min_thickness 0.25)
			(keepout
				(tracks not_allowed)
				(vias allowed)
				(pads allowed)
				(copperpour not_allowed)
				(footprints allowed)
			)
			(placement
				(enabled no)
				(sheetname "")
			)
			(fill
				(thermal_gap 0.5)
				(thermal_bridge_width 0.5)
				(island_removal_mode 0)
			)
			(polygon
				(pts
					(xy 190.4238 -69.9389) (xy 189.9158 -69.9389) (xy 189.9158 -69.5579) (xy 190.4238 -69.5579)
				)
			)
		)
		(zone
			(layer "F.Cu")
			(hatch none 0.5)
			(connect_pads
				(clearance 0)
			)
			(min_thickness 0.25)
			(keepout
				(tracks allowed)
				(vias not_allowed)
				(pads allowed)
				(copperpour not_allowed)
				(footprints allowed)
			)
			(placement
				(enabled no)
				(sheetname "")
			)
			(fill
				(thermal_gap 0.5)
				(thermal_bridge_width 0.5)
				(island_removal_mode 0)
			)
			(polygon
				(pts
					(xy 190.4238 -69.5579) (xy 189.9158 -69.5579) (xy 189.9158 -69.9389) (xy 190.4238 -69.9389)
				)
			)
		)
	)
	(footprint ""
		(layer "F.Cu")
		(at 403.606 3.2004 90)
		(property "Reference" "R8G13"
			(at 0 0 90)
			(layer "F.SilkS")
			(hide yes)
			(effects
				(font
					(size 1.27 1.27)
				)
			)
		)
		(property "Value" ""
			(at 0 0 90)
			(layer "F.Fab")
			(effects
				(font
					(size 1.27 1.27)
				)
			)
		)
		(duplicate_pad_numbers_are_jumpers no)
		(fp_poly
			(pts
				(xy -0.2794 -0.1016) (xy 0.2794 -0.1016) (xy 0.2794 0.9906) (xy -0.2794 0.9906)
			)
			(stroke
				(width 0)
				(type default)
			)
			(fill no)
			(layer "F.CrtYd")
		)
		(fp_line
			(start 0.2794 -0.1016)
			(end -0.2794 -0.1016)
			(stroke
				(width 0.1)
				(type default)
			)
			(layer "F.Fab")
		)
		(fp_line
			(start -0.2794 -0.1016)
			(end -0.2794 0.9906)
			(stroke
				(width 0.1)
				(type default)
			)
			(layer "F.Fab")
		)
		(fp_line
			(start 0.2794 0.9906)
			(end 0.2794 -0.1016)
			(stroke
				(width 0.1)
				(type default)
			)
			(layer "F.Fab")
		)
		(fp_line
			(start -0.2794 0.9906)
			(end 0.2794 0.9906)
			(stroke
				(width 0.1)
				(type default)
			)
			(layer "F.Fab")
		)
		(pad "1" smd rect
			(at 0 0 90)
			(size 0.508 0.508)
			(layers "F.Cu" "F.Mask" "F.Paste")
			(net "JTAG_PLD_TMS")
		)
		(pad "2" smd rect
			(at 0 0.889 90)
			(size 0.508 0.508)
			(layers "F.Cu" "F.Mask" "F.Paste")
			(net "JTAG_PLD_TMS_MUX")
		)
		(zone
			(layer "F.Cu")
			(hatch none 0.5)
			(connect_pads
				(clearance 0)
			)
			(min_thickness 0.25)
			(keepout
				(tracks allowed)
				(vias not_allowed)
				(pads allowed)
				(copperpour not_allowed)
				(footprints allowed)
			)
			(placement
				(enabled no)
				(sheetname "")
			)
			(fill
				(thermal_gap 0.5)
				(thermal_bridge_width 0.5)
				(island_removal_mode 0)
			)
			(polygon
				(pts
					(xy 403.86 3.4544) (xy 403.86 2.9464) (xy 404.241 2.9464) (xy 404.241 3.4544)
				)
			)
		)
		(zone
			(layer "F.Cu")
			(hatch none 0.5)
			(connect_pads
				(clearance 0)
			)
			(min_thickness 0.25)
			(keepout
				(tracks not_allowed)
				(vias allowed)
				(pads allowed)
				(copperpour not_allowed)
				(footprints allowed)
			)
			(placement
				(enabled no)
				(sheetname "")
			)
			(fill
				(thermal_gap 0.5)
				(thermal_bridge_width 0.5)
				(island_removal_mode 0)
			)
			(polygon
				(pts
					(xy 404.241 3.4544) (xy 404.241 2.9464) (xy 403.86 2.9464) (xy 403.86 3.4544)
				)
			)
		)
	)
	(footprint ""
		(layer "F.Cu")
		(at 405.384 -46.8249 180)
		(property "Reference" "R2T63"
			(at 0 0 180)
			(layer "F.SilkS")
			(hide yes)
			(effects
				(font
					(size 1.27 1.27)
				)
			)
		)
		(property "Value" ""
			(at 0 0 180)
			(layer "F.Fab")
			(effects
				(font
					(size 1.27 1.27)
				)
			)
		)
		(duplicate_pad_numbers_are_jumpers no)
		(fp_poly
			(pts
				(xy -0.2794 -0.1016) (xy 0.2794 -0.1016) (xy 0.2794 0.9906) (xy -0.2794 0.9906)
			)
			(stroke
				(width 0)
				(type default)
			)
			(fill no)
			(layer "F.CrtYd")
		)
		(fp_line
			(start 0.2794 0.9906)
			(end 0.2794 -0.1016)
			(stroke
				(width 0.1)
				(type default)
			)
			(layer "F.Fab")
		)
		(fp_line
			(start 0.2794 -0.1016)
			(end -0.2794 -0.1016)
			(stroke
				(width 0.1)
				(type default)
			)
			(layer "F.Fab")
		)
		(fp_line
			(start -0.2794 0.9906)
			(end 0.2794 0.9906)
			(stroke
				(width 0.1)
				(type default)
			)
			(layer "F.Fab")
		)
		(fp_line
			(start -0.2794 -0.1016)
			(end -0.2794 0.9906)
			(stroke
				(width 0.1)
				(type default)
			)
			(layer "F.Fab")
		)
		(pad "1" smd rect
			(at 0 0 180)
			(size 0.508 0.508)
			(layers "F.Cu" "F.Mask" "F.Paste")
			(net "FM_CPU_ERR1_LVT3_N")
		)
		(pad "2" smd rect
			(at 0 0.889 180)
			(size 0.508 0.508)
			(layers "F.Cu" "F.Mask" "F.Paste")
			(net "FM_CPU_ERR1_PCH_N")
		)
		(zone
			(layer "F.Cu")
			(hatch none 0.5)
			(connect_pads
				(clearance 0)
			)
			(min_thickness 0.25)
			(keepout
				(tracks not_allowed)
				(vias allowed)
				(pads allowed)
				(copperpour not_allowed)
				(footprints allowed)
			)
			(placement
				(enabled no)
				(sheetname "")
			)
			(fill
				(thermal_gap 0.5)
				(thermal_bridge_width 0.5)
				(island_removal_mode 0)
			)
			(polygon
				(pts
					(xy 405.638 -47.4599) (xy 405.13 -47.4599) (xy 405.13 -47.0789) (xy 405.638 -47.0789)
				)
			)
		)
		(zone
			(layer "F.Cu")
			(hatch none 0.5)
			(connect_pads
				(clearance 0)
			)
			(min_thickness 0.25)
			(keepout
				(tracks allowed)
				(vias not_allowed)
				(pads allowed)
				(copperpour not_allowed)
				(footprints allowed)
			)
			(placement
				(enabled no)
				(sheetname "")
			)
			(fill
				(thermal_gap 0.5)
				(thermal_bridge_width 0.5)
				(island_removal_mode 0)
			)
			(polygon
				(pts
					(xy 405.638 -47.0789) (xy 405.13 -47.0789) (xy 405.13 -47.4599) (xy 405.638 -47.4599)
				)
			)
		)
	)
	(footprint ""
		(layer "F.Cu")
		(at 342.646 -137.1727 90)
		(property "Reference" "R7A15"
			(at 0 0 90)
			(layer "F.SilkS")
			(hide yes)
			(effects
				(font
					(size 1.27 1.27)
				)
			)
		)
		(property "Value" ""
			(at 0 0 90)
			(layer "F.Fab")
			(effects
				(font
					(size 1.27 1.27)
				)
			)
		)
		(duplicate_pad_numbers_are_jumpers no)
		(fp_poly
			(pts
				(xy -0.2794 -0.1016) (xy 0.2794 -0.1016) (xy 0.2794 0.9906) (xy -0.2794 0.9906)
			)
			(stroke
				(width 0)
				(type default)
			)
			(fill no)
			(layer "F.CrtYd")
		)
		(fp_line
			(start 0.2794 -0.1016)
			(end -0.2794 -0.1016)
			(stroke
				(width 0.1)
				(type default)
			)
			(layer "F.Fab")
		)
		(fp_line
			(start -0.2794 -0.1016)
			(end -0.2794 0.9906)
			(stroke
				(width 0.1)
				(type default)
			)
			(layer "F.Fab")
		)
		(fp_line
			(start 0.2794 0.9906)
			(end 0.2794 -0.1016)
			(stroke
				(width 0.1)
				(type default)
			)
			(layer "F.Fab")
		)
		(fp_line
			(start -0.2794 0.9906)
			(end 0.2794 0.9906)
			(stroke
				(width 0.1)
				(type default)
			)
			(layer "F.Fab")
		)
		(pad "1" smd rect
			(at 0 0 90)
			(size 0.508 0.508)
			(layers "F.Cu" "F.Mask" "F.Paste")
			(net "VR_PVPP_DEF_SNUB")
		)
		(pad "2" smd rect
			(at 0 0.889 90)
			(size 0.508 0.508)
			(layers "F.Cu" "F.Mask" "F.Paste")
			(net "GND")
		)
		(zone
			(layer "F.Cu")
			(hatch none 0.5)
			(connect_pads
				(clearance 0)
			)
			(min_thickness 0.25)
			(keepout
				(tracks allowed)
				(vias not_allowed)
				(pads allowed)
				(copperpour not_allowed)
				(footprints allowed)
			)
			(placement
				(enabled no)
				(sheetname "")
			)
			(fill
				(thermal_gap 0.5)
				(thermal_bridge_width 0.5)
				(island_removal_mode 0)
			)
			(polygon
				(pts
					(xy 342.9 -136.9187) (xy 342.9 -137.4267) (xy 343.281 -137.4267) (xy 343.281 -136.9187)
				)
			)
		)
		(zone
			(layer "F.Cu")
			(hatch none 0.5)
			(connect_pads
				(clearance 0)
			)
			(min_thickness 0.25)
			(keepout
				(tracks not_allowed)
				(vias allowed)
				(pads allowed)
				(copperpour not_allowed)
				(footprints allowed)
			)
			(placement
				(enabled no)
				(sheetname "")
			)
			(fill
				(thermal_gap 0.5)
				(thermal_bridge_width 0.5)
				(island_removal_mode 0)
			)
			(polygon
				(pts
					(xy 343.281 -136.9187) (xy 343.281 -137.4267) (xy 342.9 -137.4267) (xy 342.9 -136.9187)
				)
			)
		)
	)
	(footprint ""
		(layer "F.Cu")
		(at 14.224 -77.216 180)
		(property "Reference" "R1D31"
			(at 0 0 180)
			(layer "F.SilkS")
			(hide yes)
			(effects
				(font
					(size 1.27 1.27)
				)
			)
		)
		(property "Value" ""
			(at 0 0 180)
			(layer "F.Fab")
			(effects
				(font
					(size 1.27 1.27)
				)
			)
		)
		(duplicate_pad_numbers_are_jumpers no)
		(fp_rect
			(start 0.2794 0.9906)
			(end -0.2794 -0.1016)
			(stroke
				(width 0)
				(type default)
			)
			(fill no)
			(layer "F.CrtYd")
		)
		(fp_line
			(start 0.2794 0.9906)
			(end 0.2794 -0.1016)
			(stroke
				(width 0.1)
				(type default)
			)
			(layer "F.Fab")
		)
		(fp_line
			(start 0.2794 -0.1016)
			(end -0.2794 -0.1016)
			(stroke
				(width 0.1)
				(type default)
			)
			(layer "F.Fab")
		)
		(fp_line
			(start -0.2794 0.9906)
			(end 0.2794 0.9906)
			(stroke
				(width 0.1)
				(type default)
			)
			(layer "F.Fab")
		)
		(fp_line
			(start -0.2794 -0.1016)
			(end -0.2794 0.9906)
			(stroke
				(width 0.1)
				(type default)
			)
			(layer "F.Fab")
		)
		(pad "1" smd rect
			(at 0 0 180)
			(size 0.508 0.508)
			(layers "F.Cu" "F.Mask" "F.Paste")
			(net "PWRGD_P12V_R")
		)
		(pad "2" smd rect
			(at 0 0.889 180)
			(size 0.508 0.508)
			(layers "F.Cu" "F.Mask" "F.Paste")
			(net "GND")
		)
		(zone
			(layer "F.Cu")
			(hatch none 0.5)
			(connect_pads
				(clearance 0)
			)
			(min_thickness 0.25)
			(keepout
				(tracks not_allowed)
				(vias allowed)
				(pads allowed)
				(copperpour not_allowed)
				(footprints allowed)
			)
			(placement
				(enabled no)
				(sheetname "")
			)
			(fill
				(thermal_gap 0.5)
				(thermal_bridge_width 0.5)
				(island_removal_mode 0)
			)
			(polygon
				(pts
					(xy 13.97 -77.851) (xy 13.97 -77.47) (xy 14.478 -77.47) (xy 14.478 -77.851)
				)
			)
		)
		(zone
			(layer "F.Cu")
			(hatch none 0.5)
			(connect_pads
				(clearance 0)
			)
			(min_thickness 0.25)
			(keepout
				(tracks allowed)
				(vias not_allowed)
				(pads allowed)
				(copperpour not_allowed)
				(footprints allowed)
			)
			(placement
				(enabled no)
				(sheetname "")
			)
			(fill
				(thermal_gap 0.5)
				(thermal_bridge_width 0.5)
				(island_removal_mode 0)
			)
			(polygon
				(pts
					(xy 13.97 -77.851) (xy 13.97 -77.47) (xy 14.478 -77.47) (xy 14.478 -77.851)
				)
			)
		)
	)
	(footprint ""
		(layer "F.Cu")
		(at 193.04 -130.048 -90)
		(property "Reference" "C4B11"
			(at 0 0 270)
			(layer "F.SilkS")
			(hide yes)
			(effects
				(font
					(size 1.27 1.27)
				)
			)
		)
		(property "Value" ""
			(at 0 0 270)
			(layer "F.Fab")
			(effects
				(font
					(size 1.27 1.27)
				)
			)
		)
		(duplicate_pad_numbers_are_jumpers no)
		(fp_rect
			(start -0.7239 1.9939)
			(end 0.7239 -0.2159)
			(stroke
				(width 0)
				(type default)
			)
			(fill no)
			(layer "F.CrtYd")
		)
		(fp_line
			(start -0.7239 1.9939)
			(end 0.7239 1.9939)
			(stroke
				(width 0.1)
				(type default)
			)
			(layer "F.Fab")
		)
		(fp_line
			(start 0.7239 1.9939)
			(end 0.7239 -0.2159)
			(stroke
				(width 0.1)
				(type default)
			)
			(layer "F.Fab")
		)
		(fp_line
			(start -0.7239 -0.2159)
			(end -0.7239 1.9939)
			(stroke
				(width 0.1)
				(type default)
			)
			(layer "F.Fab")
		)
		(fp_line
			(start 0.7239 -0.2159)
			(end -0.7239 -0.2159)
			(stroke
				(width 0.1)
				(type default)
			)
			(layer "F.Fab")
		)
		(pad "1" smd rect
			(at 0 0 270)
			(size 1.27 1.016)
			(layers "F.Cu" "F.Mask" "F.Paste")
			(net "P12V_NVDIMM_DEF")
		)
		(pad "2" smd rect
			(at 0 1.778 270)
			(size 1.27 1.016)
			(layers "F.Cu" "F.Mask" "F.Paste")
			(net "GND")
		)
		(zone
			(layer "F.Cu")
			(hatch none 0.5)
			(connect_pads
				(clearance 0)
			)
			(min_thickness 0.25)
			(keepout
				(tracks not_allowed)
				(vias allowed)
				(pads allowed)
				(copperpour not_allowed)
				(footprints allowed)
			)
			(placement
				(enabled no)
				(sheetname "")
			)
			(fill
				(thermal_gap 0.5)
				(thermal_bridge_width 0.5)
				(island_removal_mode 0)
			)
			(polygon
				(pts
					(xy 191.77 -130.683) (xy 191.77 -129.413) (xy 192.532 -129.413) (xy 192.532 -130.683)
				)
			)
		)
	)
	(footprint ""
		(layer "F.Cu")
		(at 351.630234 -0.12192)
		(property "Reference" "CT54"
			(at -5.15747 -5.207 270)
			(unlocked yes)
			(layer "F.SilkS")
			(effects
				(font
					(size 0.7874 0.5842)
					(thickness 0.1524)
				)
				(justify left)
			)
		)
		(property "Value" ""
			(at 0 0 0)
			(layer "F.Fab")
			(effects
				(font
					(size 1.27 1.27)
				)
			)
		)
		(duplicate_pad_numbers_are_jumpers no)
		(fp_poly
			(pts
				(xy 0.3048 -0.1016) (xy 0.3048 0.9906) (xy -0.3048 0.9906) (xy -0.3048 -0.1016)
			)
			(stroke
				(width 0)
				(type default)
			)
			(fill no)
			(layer "F.CrtYd")
		)
		(fp_line
			(start -0.3048 -0.1016)
			(end -0.3048 0.9906)
			(stroke
				(width 0.1)
				(type default)
			)
			(layer "F.Fab")
		)
		(fp_line
			(start -0.3048 0.9906)
			(end 0.3048 0.9906)
			(stroke
				(width 0.1)
				(type default)
			)
			(layer "F.Fab")
		)
		(fp_line
			(start 0.3048 -0.1016)
			(end -0.3048 -0.1016)
			(stroke
				(width 0.1)
				(type default)
			)
			(layer "F.Fab")
		)
		(fp_line
			(start 0.3048 0.9906)
			(end 0.3048 -0.1016)
			(stroke
				(width 0.1)
				(type default)
			)
			(layer "F.Fab")
		)
		(pad "1" smd rect
			(at 0 0)
			(size 0.508 0.508)
			(layers "F.Cu" "F.Mask" "F.Paste")
			(net "A_TSENSE_PVDDQ_ABC")
		)
		(pad "2" smd rect
			(at 0 0.889)
			(size 0.508 0.508)
			(layers "F.Cu" "F.Mask" "F.Paste")
			(net "GND")
		)
		(zone
			(layer "F.Cu")
			(hatch none 0.5)
			(connect_pads
				(clearance 0)
			)
			(min_thickness 0.25)
			(keepout
				(tracks allowed)
				(vias not_allowed)
				(pads allowed)
				(copperpour not_allowed)
				(footprints allowed)
			)
			(placement
				(enabled no)
				(sheetname "")
			)
			(fill
				(thermal_gap 0.5)
				(thermal_bridge_width 0.5)
				(island_removal_mode 0)
			)
			(polygon
				(pts
					(xy 351.376234 0.13208) (xy 351.884234 0.13208) (xy 351.884234 0.51308) (xy 351.376234 0.51308)
				)
			)
		)
		(zone
			(layer "F.Cu")
			(hatch none 0.5)
			(connect_pads
				(clearance 0)
			)
			(min_thickness 0.25)
			(keepout
				(tracks not_allowed)
				(vias allowed)
				(pads allowed)
				(copperpour not_allowed)
				(footprints allowed)
			)
			(placement
				(enabled no)
				(sheetname "")
			)
			(fill
				(thermal_gap 0.5)
				(thermal_bridge_width 0.5)
				(island_removal_mode 0)
			)
			(polygon
				(pts
					(xy 351.376234 0.51308) (xy 351.884234 0.51308) (xy 351.884234 0.13208) (xy 351.376234 0.13208)
				)
			)
		)
	)
	(footprint ""
		(layer "F.Cu")
		(at 181.70398 -155.83662 90)
		(property "Reference" "C4W5"
			(at 1.47828 0.78994 0)
			(unlocked yes)
			(layer "F.SilkS")
			(effects
				(font
					(size 0.4064 0.254)
					(thickness 0.1524)
				)
			)
		)
		(property "Value" ""
			(at 0 0 90)
			(layer "F.Fab")
			(effects
				(font
					(size 1.27 1.27)
				)
			)
		)
		(duplicate_pad_numbers_are_jumpers no)
		(fp_poly
			(pts
				(xy -0.7239 -0.2159) (xy 0.7239 -0.2159) (xy 0.7239 1.9939) (xy -0.7239 1.9939)
			)
			(stroke
				(width 0)
				(type default)
			)
			(fill no)
			(layer "F.CrtYd")
		)
		(fp_line
			(start 0.7239 -0.2159)
			(end -0.7239 -0.2159)
			(stroke
				(width 0.1)
				(type default)
			)
			(layer "F.Fab")
		)
		(fp_line
			(start -0.7239 -0.2159)
			(end -0.7239 1.9939)
			(stroke
				(width 0.1)
				(type default)
			)
			(layer "F.Fab")
		)
		(fp_line
			(start 0.7239 1.9939)
			(end 0.7239 -0.2159)
			(stroke
				(width 0.1)
				(type default)
			)
			(layer "F.Fab")
		)
		(fp_line
			(start -0.7239 1.9939)
			(end 0.7239 1.9939)
			(stroke
				(width 0.1)
				(type default)
			)
			(layer "F.Fab")
		)
		(pad "1" smd rect
			(at 0 0 90)
			(size 1.27 1.016)
			(layers "F.Cu" "F.Mask" "F.Paste")
			(net "PVTT_DEF")
		)
		(pad "2" smd rect
			(at 0 1.778 90)
			(size 1.27 1.016)
			(layers "F.Cu" "F.Mask" "F.Paste")
			(net "GND")
		)
		(zone
			(layer "F.Cu")
			(hatch none 0.5)
			(connect_pads
				(clearance 0)
			)
			(min_thickness 0.25)
			(keepout
				(tracks not_allowed)
				(vias allowed)
				(pads allowed)
				(copperpour not_allowed)
				(footprints allowed)
			)
			(placement
				(enabled no)
				(sheetname "")
			)
			(fill
				(thermal_gap 0.5)
				(thermal_bridge_width 0.5)
				(island_removal_mode 0)
			)
			(polygon
				(pts
					(xy 182.21198 -155.20162) (xy 182.21198 -156.47162) (xy 182.97398 -156.47162) (xy 182.97398 -155.20162)
				)
			)
		)
	)
	(footprint ""
		(layer "F.Cu")
		(at 406.908 -23.0505)
		(property "Reference" "R25W88"
			(at -0.8382 -0.67818 0)
			(unlocked yes)
			(layer "F.SilkS")
			(effects
				(font
					(size 0.4064 0.254)
					(thickness 0.1524)
				)
				(justify left)
			)
		)
		(property "Value" ""
			(at 0 0 0)
			(layer "F.Fab")
			(effects
				(font
					(size 1.27 1.27)
				)
			)
		)
		(duplicate_pad_numbers_are_jumpers no)
		(fp_poly
			(pts
				(xy -0.2794 -0.1016) (xy 0.2794 -0.1016) (xy 0.2794 0.9906) (xy -0.2794 0.9906)
			)
			(stroke
				(width 0)
				(type default)
			)
			(fill no)
			(layer "F.CrtYd")
		)
		(fp_line
			(start -0.2794 -0.1016)
			(end -0.2794 0.9906)
			(stroke
				(width 0.1)
				(type default)
			)
			(layer "F.Fab")
		)
		(fp_line
			(start -0.2794 0.9906)
			(end 0.2794 0.9906)
			(stroke
				(width 0.1)
				(type default)
			)
			(layer "F.Fab")
		)
		(fp_line
			(start 0.2794 -0.1016)
			(end -0.2794 -0.1016)
			(stroke
				(width 0.1)
				(type default)
			)
			(layer "F.Fab")
		)
		(fp_line
			(start 0.2794 0.9906)
			(end 0.2794 -0.1016)
			(stroke
				(width 0.1)
				(type default)
			)
			(layer "F.Fab")
		)
		(pad "1" smd rect
			(at 0 0)
			(size 0.508 0.508)
			(layers "F.Cu" "F.Mask" "F.Paste")
			(net "RMII_BMC_SPRNGVLLE_TXEN_R")
		)
		(pad "2" smd rect
			(at 0 0.889)
			(size 0.508 0.508)
			(layers "F.Cu" "F.Mask" "F.Paste")
			(net "RMII_BMC_PCH_SPRNGVLLE_TXEN")
		)
		(zone
			(layer "F.Cu")
			(hatch none 0.5)
			(connect_pads
				(clearance 0)
			)
			(min_thickness 0.25)
			(keepout
				(tracks allowed)
				(vias not_allowed)
				(pads allowed)
				(copperpour not_allowed)
				(footprints allowed)
			)
			(placement
				(enabled no)
				(sheetname "")
			)
			(fill
				(thermal_gap 0.5)
				(thermal_bridge_width 0.5)
				(island_removal_mode 0)
			)
			(polygon
				(pts
					(xy 406.654 -22.7965) (xy 407.162 -22.7965) (xy 407.162 -22.4155) (xy 406.654 -22.4155)
				)
			)
		)
		(zone
			(layer "F.Cu")
			(hatch none 0.5)
			(connect_pads
				(clearance 0)
			)
			(min_thickness 0.25)
			(keepout
				(tracks not_allowed)
				(vias allowed)
				(pads allowed)
				(copperpour not_allowed)
				(footprints allowed)
			)
			(placement
				(enabled no)
				(sheetname "")
			)
			(fill
				(thermal_gap 0.5)
				(thermal_bridge_width 0.5)
				(island_removal_mode 0)
			)
			(polygon
				(pts
					(xy 406.654 -22.4155) (xy 407.162 -22.4155) (xy 407.162 -22.7965) (xy 406.654 -22.7965)
				)
			)
		)
	)
	(footprint ""
		(layer "F.Cu")
		(at 278.427434 -77.382116)
		(property "Reference" "C6D6"
			(at 0 0 0)
			(layer "F.SilkS")
			(hide yes)
			(effects
				(font
					(size 1.27 1.27)
				)
			)
		)
		(property "Value" ""
			(at 0 0 0)
			(layer "F.Fab")
			(effects
				(font
					(size 1.27 1.27)
				)
			)
		)
		(duplicate_pad_numbers_are_jumpers no)
		(fp_poly
			(pts
				(xy -0.4953 -0.2032) (xy 0.4953 -0.2032) (xy 0.4953 1.6002) (xy -0.4953 1.6002)
			)
			(stroke
				(width 0)
				(type default)
			)
			(fill no)
			(layer "F.CrtYd")
		)
		(fp_line
			(start -0.4953 -0.2032)
			(end 0.4953 -0.2032)
			(stroke
				(width 0.1)
				(type default)
			)
			(layer "F.Fab")
		)
		(fp_line
			(start -0.4953 1.6002)
			(end -0.4953 -0.2032)
			(stroke
				(width 0.1)
				(type default)
			)
			(layer "F.Fab")
		)
		(fp_line
			(start 0.4953 -0.2032)
			(end 0.4953 1.6002)
			(stroke
				(width 0.1)
				(type default)
			)
			(layer "F.Fab")
		)
		(fp_line
			(start 0.4953 1.6002)
			(end -0.4953 1.6002)
			(stroke
				(width 0.1)
				(type default)
			)
			(layer "F.Fab")
		)
		(pad "1" smd rect
			(at 0 0)
			(size 0.762 0.889)
			(layers "F.Cu" "F.Mask" "F.Paste")
			(net "PVCCIO_CPU0")
		)
		(pad "2" smd rect
			(at 0 1.397)
			(size 0.762 0.889)
			(layers "F.Cu" "F.Mask" "F.Paste")
			(net "GND")
		)
		(zone
			(layer "F.Cu")
			(hatch none 0.5)
			(connect_pads
				(clearance 0)
			)
			(min_thickness 0.25)
			(keepout
				(tracks not_allowed)
				(vias allowed)
				(pads allowed)
				(copperpour not_allowed)
				(footprints allowed)
			)
			(placement
				(enabled no)
				(sheetname "")
			)
			(fill
				(thermal_gap 0.5)
				(thermal_bridge_width 0.5)
				(island_removal_mode 0)
			)
			(polygon
				(pts
					(xy 278.046434 -76.937616) (xy 278.808434 -76.937616) (xy 278.808434 -76.429616) (xy 278.046434 -76.429616)
				)
			)
		)
	)
	(footprint ""
		(layer "F.Cu")
		(at 343.67216 -21.78812 -90)
		(property "Reference" "R7F21"
			(at -0.8382 -0.67818 270)
			(unlocked yes)
			(layer "F.SilkS")
			(effects
				(font
					(size 0.4064 0.254)
					(thickness 0.1524)
				)
				(justify left)
			)
		)
		(property "Value" ""
			(at 0 0 270)
			(layer "F.Fab")
			(effects
				(font
					(size 1.27 1.27)
				)
			)
		)
		(duplicate_pad_numbers_are_jumpers no)
		(fp_poly
			(pts
				(xy -0.2794 -0.1016) (xy 0.2794 -0.1016) (xy 0.2794 0.9906) (xy -0.2794 0.9906)
			)
			(stroke
				(width 0)
				(type default)
			)
			(fill no)
			(layer "F.CrtYd")
		)
		(fp_line
			(start -0.2794 0.9906)
			(end 0.2794 0.9906)
			(stroke
				(width 0.1)
				(type default)
			)
			(layer "F.Fab")
		)
		(fp_line
			(start 0.2794 0.9906)
			(end 0.2794 -0.1016)
			(stroke
				(width 0.1)
				(type default)
			)
			(layer "F.Fab")
		)
		(fp_line
			(start -0.2794 -0.1016)
			(end -0.2794 0.9906)
			(stroke
				(width 0.1)
				(type default)
			)
			(layer "F.Fab")
		)
		(fp_line
			(start 0.2794 -0.1016)
			(end -0.2794 -0.1016)
			(stroke
				(width 0.1)
				(type default)
			)
			(layer "F.Fab")
		)
		(pad "1" smd rect
			(at 0 0 270)
			(size 0.508 0.508)
			(layers "F.Cu" "F.Mask" "F.Paste")
			(net "FM_PVDDQ_ABC_EN")
		)
		(pad "2" smd rect
			(at 0 0.889 270)
			(size 0.508 0.508)
			(layers "F.Cu" "F.Mask" "F.Paste")
			(net "VR_PVDDQ_ABC_VREN")
		)
		(zone
			(layer "F.Cu")
			(hatch none 0.5)
			(connect_pads
				(clearance 0)
			)
			(min_thickness 0.25)
			(keepout
				(tracks not_allowed)
				(vias allowed)
				(pads allowed)
				(copperpour not_allowed)
				(footprints allowed)
			)
			(placement
				(enabled no)
				(sheetname "")
			)
			(fill
				(thermal_gap 0.5)
				(thermal_bridge_width 0.5)
				(island_removal_mode 0)
			)
			(polygon
				(pts
					(xy 343.03716 -22.04212) (xy 343.03716 -21.53412) (xy 343.41816 -21.53412) (xy 343.41816 -22.04212)
				)
			)
		)
		(zone
			(layer "F.Cu")
			(hatch none 0.5)
			(connect_pads
				(clearance 0)
			)
			(min_thickness 0.25)
			(keepout
				(tracks allowed)
				(vias not_allowed)
				(pads allowed)
				(copperpour not_allowed)
				(footprints allowed)
			)
			(placement
				(enabled no)
				(sheetname "")
			)
			(fill
				(thermal_gap 0.5)
				(thermal_bridge_width 0.5)
				(island_removal_mode 0)
			)
			(polygon
				(pts
					(xy 343.41816 -22.04212) (xy 343.41816 -21.53412) (xy 343.03716 -21.53412) (xy 343.03716 -22.04212)
				)
			)
		)
	)
	(footprint ""
		(layer "F.Cu")
		(at 323.0245 -117.222016 90)
		(property "Reference" "C6B14"
			(at -0.8382 -0.67818 90)
			(unlocked yes)
			(layer "F.SilkS")
			(effects
				(font
					(size 0.4064 0.254)
					(thickness 0.1524)
				)
				(justify left)
			)
		)
		(property "Value" ""
			(at 0 0 90)
			(layer "F.Fab")
			(effects
				(font
					(size 1.27 1.27)
				)
			)
		)
		(duplicate_pad_numbers_are_jumpers no)
		(fp_poly
			(pts
				(xy 0.3048 -0.1016) (xy 0.3048 0.9906) (xy -0.3048 0.9906) (xy -0.3048 -0.1016)
			)
			(stroke
				(width 0)
				(type default)
			)
			(fill no)
			(layer "F.CrtYd")
		)
		(fp_line
			(start 0.3048 -0.1016)
			(end -0.3048 -0.1016)
			(stroke
				(width 0.1)
				(type default)
			)
			(layer "F.Fab")
		)
		(fp_line
			(start -0.3048 -0.1016)
			(end -0.3048 0.9906)
			(stroke
				(width 0.1)
				(type default)
			)
			(layer "F.Fab")
		)
		(fp_line
			(start 0.3048 0.9906)
			(end 0.3048 -0.1016)
			(stroke
				(width 0.1)
				(type default)
			)
			(layer "F.Fab")
		)
		(fp_line
			(start -0.3048 0.9906)
			(end 0.3048 0.9906)
			(stroke
				(width 0.1)
				(type default)
			)
			(layer "F.Fab")
		)
		(pad "1" smd rect
			(at 0 0 90)
			(size 0.508 0.508)
			(layers "F.Cu" "F.Mask" "F.Paste")
			(net "P3E_CPU0_PE1_PCH_TXN<11>")
		)
		(pad "2" smd rect
			(at 0 0.889 90)
			(size 0.508 0.508)
			(layers "F.Cu" "F.Mask" "F.Paste")
			(net "P3E_CPU0_PE1_PCH_C_TXN<11>")
		)
		(zone
			(layer "F.Cu")
			(hatch none 0.5)
			(connect_pads
				(clearance 0)
			)
			(min_thickness 0.25)
			(keepout
				(tracks allowed)
				(vias not_allowed)
				(pads allowed)
				(copperpour not_allowed)
				(footprints allowed)
			)
			(placement
				(enabled no)
				(sheetname "")
			)
			(fill
				(thermal_gap 0.5)
				(thermal_bridge_width 0.5)
				(island_removal_mode 0)
			)
			(polygon
				(pts
					(xy 323.2785 -116.968016) (xy 323.2785 -117.476016) (xy 323.6595 -117.476016) (xy 323.6595 -116.968016)
				)
			)
		)
		(zone
			(layer "F.Cu")
			(hatch none 0.5)
			(connect_pads
				(clearance 0)
			)
			(min_thickness 0.25)
			(keepout
				(tracks not_allowed)
				(vias allowed)
				(pads allowed)
				(copperpour not_allowed)
				(footprints allowed)
			)
			(placement
				(enabled no)
				(sheetname "")
			)
			(fill
				(thermal_gap 0.5)
				(thermal_bridge_width 0.5)
				(island_removal_mode 0)
			)
			(polygon
				(pts
					(xy 323.6595 -116.968016) (xy 323.6595 -117.476016) (xy 323.2785 -117.476016) (xy 323.2785 -116.968016)
				)
			)
		)
	)
	(footprint ""
		(layer "F.Cu")
		(at 27.451558 -22.952456)
		(property "Reference" "C1F19"
			(at 0 0 0)
			(layer "F.SilkS")
			(hide yes)
			(effects
				(font
					(size 1.27 1.27)
				)
			)
		)
		(property "Value" ""
			(at 0 0 0)
			(layer "F.Fab")
			(effects
				(font
					(size 1.27 1.27)
				)
			)
		)
		(duplicate_pad_numbers_are_jumpers no)
		(fp_poly
			(pts
				(xy 0.3048 -0.1016) (xy 0.3048 0.9906) (xy -0.3048 0.9906) (xy -0.3048 -0.1016)
			)
			(stroke
				(width 0)
				(type default)
			)
			(fill no)
			(layer "F.CrtYd")
		)
		(fp_line
			(start -0.3048 -0.1016)
			(end -0.3048 0.9906)
			(stroke
				(width 0.1)
				(type default)
			)
			(layer "F.Fab")
		)
		(fp_line
			(start -0.3048 0.9906)
			(end 0.3048 0.9906)
			(stroke
				(width 0.1)
				(type default)
			)
			(layer "F.Fab")
		)
		(fp_line
			(start 0.3048 -0.1016)
			(end -0.3048 -0.1016)
			(stroke
				(width 0.1)
				(type default)
			)
			(layer "F.Fab")
		)
		(fp_line
			(start 0.3048 0.9906)
			(end 0.3048 -0.1016)
			(stroke
				(width 0.1)
				(type default)
			)
			(layer "F.Fab")
		)
		(pad "1" smd rect
			(at 0 0)
			(size 0.508 0.508)
			(layers "F.Cu" "F.Mask" "F.Paste")
			(net "M_G_CPU_VREF")
		)
		(pad "2" smd rect
			(at 0 0.889)
			(size 0.508 0.508)
			(layers "F.Cu" "F.Mask" "F.Paste")
			(net "GND")
		)
		(zone
			(layer "F.Cu")
			(hatch none 0.5)
			(connect_pads
				(clearance 0)
			)
			(min_thickness 0.25)
			(keepout
				(tracks allowed)
				(vias not_allowed)
				(pads allowed)
				(copperpour not_allowed)
				(footprints allowed)
			)
			(placement
				(enabled no)
				(sheetname "")
			)
			(fill
				(thermal_gap 0.5)
				(thermal_bridge_width 0.5)
				(island_removal_mode 0)
			)
			(polygon
				(pts
					(xy 27.197558 -22.698456) (xy 27.705558 -22.698456) (xy 27.705558 -22.317456) (xy 27.197558 -22.317456)
				)
			)
		)
		(zone
			(layer "F.Cu")
			(hatch none 0.5)
			(connect_pads
				(clearance 0)
			)
			(min_thickness 0.25)
			(keepout
				(tracks not_allowed)
				(vias allowed)
				(pads allowed)
				(copperpour not_allowed)
				(footprints allowed)
			)
			(placement
				(enabled no)
				(sheetname "")
			)
			(fill
				(thermal_gap 0.5)
				(thermal_bridge_width 0.5)
				(island_removal_mode 0)
			)
			(polygon
				(pts
					(xy 27.197558 -22.317456) (xy 27.705558 -22.317456) (xy 27.705558 -22.698456) (xy 27.197558 -22.698456)
				)
			)
		)
	)
	(footprint ""
		(layer "F.Cu")
		(at 7.333234 4.307332)
		(property "Reference" "C1G24"
			(at 0 0 0)
			(layer "F.SilkS")
			(hide yes)
			(effects
				(font
					(size 1.27 1.27)
				)
			)
		)
		(property "Value" ""
			(at 0 0 0)
			(layer "F.Fab")
			(effects
				(font
					(size 1.27 1.27)
				)
			)
		)
		(duplicate_pad_numbers_are_jumpers no)
		(fp_rect
			(start -0.3048 -0.1016)
			(end 0.3048 0.9906)
			(stroke
				(width 0)
				(type default)
			)
			(fill no)
			(layer "F.CrtYd")
		)
		(fp_line
			(start -0.3048 -0.1016)
			(end -0.3048 0.9906)
			(stroke
				(width 0.1)
				(type default)
			)
			(layer "F.Fab")
		)
		(fp_line
			(start -0.3048 0.9906)
			(end 0.3048 0.9906)
			(stroke
				(width 0.1)
				(type default)
			)
			(layer "F.Fab")
		)
		(fp_line
			(start 0.3048 -0.1016)
			(end -0.3048 -0.1016)
			(stroke
				(width 0.1)
				(type default)
			)
			(layer "F.Fab")
		)
		(fp_line
			(start 0.3048 0.9906)
			(end 0.3048 -0.1016)
			(stroke
				(width 0.1)
				(type default)
			)
			(layer "F.Fab")
		)
		(pad "1" smd rect
			(at 0 0)
			(size 0.508 0.508)
			(layers "F.Cu" "F.Mask" "F.Paste")
			(net "A_TSENSE_PVDDQ_GHJ")
		)
		(pad "2" smd rect
			(at 0 0.889)
			(size 0.508 0.508)
			(layers "F.Cu" "F.Mask" "F.Paste")
			(net "GND")
		)
		(zone
			(layer "F.Cu")
			(hatch none 0.5)
			(connect_pads
				(clearance 0)
			)
			(min_thickness 0.25)
			(keepout
				(tracks allowed)
				(vias not_allowed)
				(pads allowed)
				(copperpour not_allowed)
				(footprints allowed)
			)
			(placement
				(enabled no)
				(sheetname "")
			)
			(fill
				(thermal_gap 0.5)
				(thermal_bridge_width 0.5)
				(island_removal_mode 0)
			)
			(polygon
				(pts
					(xy 7.079234 4.561332) (xy 7.079234 4.942332) (xy 7.587234 4.942332) (xy 7.587234 4.561332)
				)
			)
		)
		(zone
			(layer "F.Cu")
			(hatch none 0.5)
			(connect_pads
				(clearance 0)
			)
			(min_thickness 0.25)
			(keepout
				(tracks not_allowed)
				(vias allowed)
				(pads allowed)
				(copperpour not_allowed)
				(footprints allowed)
			)
			(placement
				(enabled no)
				(sheetname "")
			)
			(fill
				(thermal_gap 0.5)
				(thermal_bridge_width 0.5)
				(island_removal_mode 0)
			)
			(polygon
				(pts
					(xy 7.079234 4.561332) (xy 7.079234 4.942332) (xy 7.587234 4.942332) (xy 7.587234 4.561332)
				)
			)
		)
	)
	(footprint ""
		(layer "F.Cu")
		(at 172.466 -131.5085)
		(property "Reference" "C4B5"
			(at 0 0 0)
			(layer "F.SilkS")
			(hide yes)
			(effects
				(font
					(size 1.27 1.27)
				)
			)
		)
		(property "Value" ""
			(at 0 0 0)
			(layer "F.Fab")
			(effects
				(font
					(size 1.27 1.27)
				)
			)
		)
		(duplicate_pad_numbers_are_jumpers no)
		(fp_poly
			(pts
				(xy 0.3048 -0.1016) (xy 0.3048 0.9906) (xy -0.3048 0.9906) (xy -0.3048 -0.1016)
			)
			(stroke
				(width 0)
				(type default)
			)
			(fill no)
			(layer "F.CrtYd")
		)
		(fp_line
			(start -0.3048 -0.1016)
			(end -0.3048 0.9906)
			(stroke
				(width 0.1)
				(type default)
			)
			(layer "F.Fab")
		)
		(fp_line
			(start -0.3048 0.9906)
			(end 0.3048 0.9906)
			(stroke
				(width 0.1)
				(type default)
			)
			(layer "F.Fab")
		)
		(fp_line
			(start 0.3048 -0.1016)
			(end -0.3048 -0.1016)
			(stroke
				(width 0.1)
				(type default)
			)
			(layer "F.Fab")
		)
		(fp_line
			(start 0.3048 0.9906)
			(end 0.3048 -0.1016)
			(stroke
				(width 0.1)
				(type default)
			)
			(layer "F.Fab")
		)
		(pad "1" smd rect
			(at 0 0)
			(size 0.508 0.508)
			(layers "F.Cu" "F.Mask" "F.Paste")
			(net "FM_PVPP_CPU1_EN")
		)
		(pad "2" smd rect
			(at 0 0.889)
			(size 0.508 0.508)
			(layers "F.Cu" "F.Mask" "F.Paste")
			(net "AGND_PVPP_KLM")
		)
		(zone
			(layer "F.Cu")
			(hatch none 0.5)
			(connect_pads
				(clearance 0)
			)
			(min_thickness 0.25)
			(keepout
				(tracks allowed)
				(vias not_allowed)
				(pads allowed)
				(copperpour not_allowed)
				(footprints allowed)
			)
			(placement
				(enabled no)
				(sheetname "")
			)
			(fill
				(thermal_gap 0.5)
				(thermal_bridge_width 0.5)
				(island_removal_mode 0)
			)
			(polygon
				(pts
					(xy 172.212 -131.2545) (xy 172.72 -131.2545) (xy 172.72 -130.8735) (xy 172.212 -130.8735)
				)
			)
		)
		(zone
			(layer "F.Cu")
			(hatch none 0.5)
			(connect_pads
				(clearance 0)
			)
			(min_thickness 0.25)
			(keepout
				(tracks not_allowed)
				(vias allowed)
				(pads allowed)
				(copperpour not_allowed)
				(footprints allowed)
			)
			(placement
				(enabled no)
				(sheetname "")
			)
			(fill
				(thermal_gap 0.5)
				(thermal_bridge_width 0.5)
				(island_removal_mode 0)
			)
			(polygon
				(pts
					(xy 172.212 -130.8735) (xy 172.72 -130.8735) (xy 172.72 -131.2545) (xy 172.212 -131.2545)
				)
			)
		)
	)
	(footprint ""
		(layer "F.Cu")
		(at 264.4394 -79.6036 180)
		(property "Reference" "C5D16"
			(at 0 0 180)
			(layer "F.SilkS")
			(hide yes)
			(effects
				(font
					(size 1.27 1.27)
				)
			)
		)
		(property "Value" ""
			(at 0 0 180)
			(layer "F.Fab")
			(effects
				(font
					(size 1.27 1.27)
				)
			)
		)
		(duplicate_pad_numbers_are_jumpers no)
		(fp_poly
			(pts
				(xy -0.4953 -0.2032) (xy 0.4953 -0.2032) (xy 0.4953 1.6002) (xy -0.4953 1.6002)
			)
			(stroke
				(width 0)
				(type default)
			)
			(fill no)
			(layer "F.CrtYd")
		)
		(fp_line
			(start 0.4953 1.6002)
			(end -0.4953 1.6002)
			(stroke
				(width 0.1)
				(type default)
			)
			(layer "F.Fab")
		)
		(fp_line
			(start 0.4953 -0.2032)
			(end 0.4953 1.6002)
			(stroke
				(width 0.1)
				(type default)
			)
			(layer "F.Fab")
		)
		(fp_line
			(start -0.4953 1.6002)
			(end -0.4953 -0.2032)
			(stroke
				(width 0.1)
				(type default)
			)
			(layer "F.Fab")
		)
		(fp_line
			(start -0.4953 -0.2032)
			(end 0.4953 -0.2032)
			(stroke
				(width 0.1)
				(type default)
			)
			(layer "F.Fab")
		)
		(pad "1" smd rect
			(at 0 0 180)
			(size 0.762 0.889)
			(layers "F.Cu" "F.Mask" "F.Paste")
			(net "PVCCIN_CPU0")
		)
		(pad "2" smd rect
			(at 0 1.397 180)
			(size 0.762 0.889)
			(layers "F.Cu" "F.Mask" "F.Paste")
			(net "GND")
		)
		(zone
			(layer "F.Cu")
			(hatch none 0.5)
			(connect_pads
				(clearance 0)
			)
			(min_thickness 0.25)
			(keepout
				(tracks not_allowed)
				(vias allowed)
				(pads allowed)
				(copperpour not_allowed)
				(footprints allowed)
			)
			(placement
				(enabled no)
				(sheetname "")
			)
			(fill
				(thermal_gap 0.5)
				(thermal_bridge_width 0.5)
				(island_removal_mode 0)
			)
			(polygon
				(pts
					(xy 264.8204 -80.0481) (xy 264.0584 -80.0481) (xy 264.0584 -80.5561) (xy 264.8204 -80.5561)
				)
			)
		)
	)
	(footprint ""
		(layer "F.Cu")
		(at 426.5295 -128.1557 -90)
		(property "Reference" "R8B8"
			(at 0 0 270)
			(layer "F.SilkS")
			(hide yes)
			(effects
				(font
					(size 1.27 1.27)
				)
			)
		)
		(property "Value" ""
			(at 0 0 270)
			(layer "F.Fab")
			(effects
				(font
					(size 1.27 1.27)
				)
			)
		)
		(duplicate_pad_numbers_are_jumpers no)
		(fp_poly
			(pts
				(xy -0.2794 -0.1016) (xy 0.2794 -0.1016) (xy 0.2794 0.9906) (xy -0.2794 0.9906)
			)
			(stroke
				(width 0)
				(type default)
			)
			(fill no)
			(layer "F.CrtYd")
		)
		(fp_line
			(start -0.2794 0.9906)
			(end 0.2794 0.9906)
			(stroke
				(width 0.1)
				(type default)
			)
			(layer "F.Fab")
		)
		(fp_line
			(start 0.2794 0.9906)
			(end 0.2794 -0.1016)
			(stroke
				(width 0.1)
				(type default)
			)
			(layer "F.Fab")
		)
		(fp_line
			(start -0.2794 -0.1016)
			(end -0.2794 0.9906)
			(stroke
				(width 0.1)
				(type default)
			)
			(layer "F.Fab")
		)
		(fp_line
			(start 0.2794 -0.1016)
			(end -0.2794 -0.1016)
			(stroke
				(width 0.1)
				(type default)
			)
			(layer "F.Fab")
		)
		(pad "1" smd rect
			(at 0 0 270)
			(size 0.508 0.508)
			(layers "F.Cu" "F.Mask" "F.Paste")
			(net "PVPP_ABC")
		)
		(pad "2" smd rect
			(at 0 0.889 270)
			(size 0.508 0.508)
			(layers "F.Cu" "F.Mask" "F.Paste")
			(net "RST_HFI0_CPU0_LVT2_N")
		)
		(zone
			(layer "F.Cu")
			(hatch none 0.5)
			(connect_pads
				(clearance 0)
			)
			(min_thickness 0.25)
			(keepout
				(tracks not_allowed)
				(vias allowed)
				(pads allowed)
				(copperpour not_allowed)
				(footprints allowed)
			)
			(placement
				(enabled no)
				(sheetname "")
			)
			(fill
				(thermal_gap 0.5)
				(thermal_bridge_width 0.5)
				(island_removal_mode 0)
			)
			(polygon
				(pts
					(xy 425.8945 -128.4097) (xy 425.8945 -127.9017) (xy 426.2755 -127.9017) (xy 426.2755 -128.4097)
				)
			)
		)
		(zone
			(layer "F.Cu")
			(hatch none 0.5)
			(connect_pads
				(clearance 0)
			)
			(min_thickness 0.25)
			(keepout
				(tracks allowed)
				(vias not_allowed)
				(pads allowed)
				(copperpour not_allowed)
				(footprints allowed)
			)
			(placement
				(enabled no)
				(sheetname "")
			)
			(fill
				(thermal_gap 0.5)
				(thermal_bridge_width 0.5)
				(island_removal_mode 0)
			)
			(polygon
				(pts
					(xy 426.2755 -128.4097) (xy 426.2755 -127.9017) (xy 425.8945 -127.9017) (xy 425.8945 -128.4097)
				)
			)
		)
	)
	(footprint ""
		(layer "F.Cu")
		(at 164.615114 -43.80103 90)
		(property "Reference" "J4E1"
			(at -3.59283 -5.018024 90)
			(unlocked yes)
			(layer "F.SilkS")
			(effects
				(font
					(size 0.7874 0.5842)
					(thickness 0.1524)
				)
			)
		)
		(property "Value" ""
			(at 0 0 90)
			(layer "F.Fab")
			(effects
				(font
					(size 1.27 1.27)
				)
			)
		)
		(duplicate_pad_numbers_are_jumpers no)
		(fp_line
			(start -0.381 -3.81)
			(end -5.969 -3.81)
			(stroke
				(width 0.1524)
				(type default)
			)
			(layer "F.SilkS")
		)
		(fp_line
			(start -5.969 -3.81)
			(end -5.969 -3.048)
			(stroke
				(width 0.1524)
				(type default)
			)
			(layer "F.SilkS")
		)
		(fp_line
			(start -5.969 -3.048)
			(end -7.2771 -3.048)
			(stroke
				(width 0.1524)
				(type default)
			)
			(layer "F.SilkS")
		)
		(fp_line
			(start -7.2771 -3.048)
			(end -7.2771 28.194)
			(stroke
				(width 0.1524)
				(type default)
			)
			(layer "F.SilkS")
		)
		(fp_line
			(start 0.9271 28.194)
			(end 0.9271 -1.703832)
			(stroke
				(width 0.1524)
				(type default)
			)
			(layer "F.SilkS")
		)
		(fp_line
			(start -7.2771 28.194)
			(end 0.9271 28.194)
			(stroke
				(width 0.1524)
				(type default)
			)
			(layer "F.SilkS")
		)
		(fp_poly
			(pts
				(xy 0.424688 -3.343656) (xy 0.932688 -4.613656) (xy -0.083312 -4.613656)
			)
			(stroke
				(width 0)
				(type default)
			)
			(fill yes)
			(layer "F.SilkS")
		)
		(fp_poly
			(pts
				(xy -7.2771 28.194) (xy -7.2771 -3.048) (xy -5.969 -3.048) (xy -5.969 -3.81) (xy -0.381 -3.81) (xy -0.381 -3.048)
				(xy 0.9271 -3.048) (xy 0.9271 28.194)
			)
			(stroke
				(width 0)
				(type default)
			)
			(fill no)
			(layer "F.CrtYd")
		)
		(fp_line
			(start -0.381 -3.81)
			(end -0.381 -3.048)
			(stroke
				(width 0.1)
				(type default)
			)
			(layer "F.Fab")
		)
		(fp_line
			(start -5.969 -3.81)
			(end -0.381 -3.81)
			(stroke
				(width 0.1)
				(type default)
			)
			(layer "F.Fab")
		)
		(fp_line
			(start 0.9271 -3.048)
			(end 0.9271 28.194)
			(stroke
				(width 0.1)
				(type default)
			)
			(layer "F.Fab")
		)
		(fp_line
			(start -0.381 -3.048)
			(end 0.9271 -3.048)
			(stroke
				(width 0.1)
				(type default)
			)
			(layer "F.Fab")
		)
		(fp_line
			(start -5.969 -3.048)
			(end -5.969 -3.81)
			(stroke
				(width 0.1)
				(type default)
			)
			(layer "F.Fab")
		)
		(fp_line
			(start -7.2771 -3.048)
			(end -5.969 -3.048)
			(stroke
				(width 0.1)
				(type default)
			)
			(layer "F.Fab")
		)
		(fp_line
			(start -7.2771 28.1686)
			(end -7.2771 -3.048)
			(stroke
				(width 0.1)
				(type default)
			)
			(layer "F.Fab")
		)
		(fp_line
			(start 0.9271 28.194)
			(end -7.2771 28.194)
			(stroke
				(width 0.1)
				(type default)
			)
			(layer "F.Fab")
		)
		(fp_line
			(start -7.2771 28.194)
			(end -7.2771 28.1686)
			(stroke
				(width 0.1)
				(type default)
			)
			(layer "F.Fab")
		)
		(fp_poly
			(pts
				(xy 1.661668 0.048006) (xy 2.931668 -0.459994) (xy 2.931668 0.556006)
			)
			(stroke
				(width 0)
				(type default)
			)
			(fill yes)
			(layer "F.Fab")
		)
		(fp_text user "F1"
			(at -7.133082 -4.518914 0)
			(unlocked yes)
			(layer "F.SilkS")
			(effects
				(font
					(size 0.7874 0.5842)
					(thickness 0.1524)
				)
				(justify left)
			)
		)
		(fp_text user "F20"
			(at 0.93472 -3.708654 90)
			(unlocked yes)
			(layer "F.SilkS")
			(effects
				(font
					(size 0.7874 0.5842)
					(thickness 0.1524)
				)
				(justify left)
			)
		)
		(fp_text user "A20"
			(at 1.64465 24.3078 0)
			(unlocked yes)
			(layer "F.SilkS")
			(effects
				(font
					(size 0.7874 0.5842)
					(thickness 0.1524)
				)
				(justify left)
			)
		)
		(fp_text user "F1"
			(at 1.502918 -3.502914 0)
			(unlocked yes)
			(layer "F.Fab")
			(effects
				(font
					(size 0.7874 0.5842)
					(thickness 0.1524)
				)
				(justify left)
			)
		)
		(fp_text user "F20"
			(at -7.84987 23.7998 0)
			(unlocked yes)
			(layer "F.Fab")
			(effects
				(font
					(size 0.7874 0.5842)
					(thickness 0.1524)
				)
				(justify left)
			)
		)
		(fp_text user "A20"
			(at 1.34747 27.825192 90)
			(unlocked yes)
			(layer "F.Fab")
			(effects
				(font
					(size 0.7874 0.5842)
					(thickness 0.1524)
				)
				(justify left)
			)
		)
		(pad "" np_thru_hole circle
			(at -3.175 26.5557 90)
			(size 0.254 0.254)
			(drill 1.27)
			(layers "*.Cu" "*.Mask")
			(clearance 0.8255)
			(thermal_gap 0.8255)
		)
		(pad "" np_thru_hole circle
			(at -0.127 -2.4257 90)
			(size 0.254 0.254)
			(drill 1.27)
			(layers "*.Cu" "*.Mask")
			(clearance 0.8255)
			(thermal_gap 0.8255)
		)
		(pad "A1" smd circle
			(at 0 0 90)
			(size 0.635 0.635)
			(layers "F.Cu" "F.Mask" "F.Paste")
			(net "PVCCMCP_CPU1")
		)
		(pad "A2" smd circle
			(at 0 1.27 90)
			(size 0.635 0.635)
			(layers "F.Cu" "F.Mask" "F.Paste")
			(net "PVCCMCP_CPU1")
		)
		(pad "A3" smd circle
			(at 0 2.54 90)
			(size 0.635 0.635)
			(layers "F.Cu" "F.Mask" "F.Paste")
			(net "PVCCMCP_CPU1")
		)
		(pad "A4" smd circle
			(at 0 3.81 90)
			(size 0.635 0.635)
			(layers "F.Cu" "F.Mask" "F.Paste")
			(net "VSENSE_PVCCMCP_CPU1_SKT_VSEN")
		)
		(pad "A5" smd circle
			(at 0 5.08 90)
			(size 0.635 0.635)
			(layers "F.Cu" "F.Mask" "F.Paste")
			(net "PVCCMCP_CPU1")
		)
		(pad "A6" smd circle
			(at 0 6.35 90)
			(size 0.635 0.635)
			(layers "F.Cu" "F.Mask" "F.Paste")
			(net "PVCCMCP_CPU1")
		)
		(pad "A7" smd circle
			(at 0 7.62 90)
			(size 0.635 0.635)
			(layers "F.Cu" "F.Mask" "F.Paste")
			(net "PVCCMCP_CPU1")
		)
		(pad "A8" smd circle
			(at 0 8.89 90)
			(size 0.635 0.635)
			(layers "F.Cu" "F.Mask" "F.Paste")
			(net "PVCCMCP_CPU1")
		)
		(pad "A9" smd circle
			(at 0 10.16 90)
			(size 0.635 0.635)
			(layers "F.Cu" "F.Mask" "F.Paste")
			(net "PVCCMCP_CPU1")
		)
		(pad "A10" smd circle
			(at 0 11.43 90)
			(size 0.635 0.635)
			(layers "F.Cu" "F.Mask" "F.Paste")
			(net "PVCCMCP_CPU1")
		)
		(pad "A11" smd circle
			(at 0 12.7 90)
			(size 0.635 0.635)
			(layers "F.Cu" "F.Mask" "F.Paste")
			(net "PVCCMCP_CPU1")
		)
		(pad "A12" smd circle
			(at 0 13.97 90)
			(size 0.635 0.635)
			(layers "F.Cu" "F.Mask" "F.Paste")
			(net "PVCCMCP_CPU1")
		)
		(pad "A13" smd circle
			(at 0 15.24 90)
			(size 0.635 0.635)
			(layers "F.Cu" "F.Mask" "F.Paste")
			(net "PVCCMCP_CPU1")
		)
		(pad "A14" smd circle
			(at 0 16.51 90)
			(size 0.635 0.635)
			(layers "F.Cu" "F.Mask" "F.Paste")
			(net "PVCCMCP_CPU1")
		)
		(pad "A15" smd circle
			(at 0 17.78 90)
			(size 0.635 0.635)
			(layers "F.Cu" "F.Mask" "F.Paste")
			(net "PVCCMCP_CPU1")
		)
		(pad "A16" smd circle
			(at 0 19.05 90)
			(size 0.635 0.635)
			(layers "F.Cu" "F.Mask" "F.Paste")
			(net "PVCCMCP_CPU1")
		)
		(pad "A17" smd circle
			(at 0 20.32 90)
			(size 0.635 0.635)
			(layers "F.Cu" "F.Mask" "F.Paste")
			(net "PVCCMCP_CPU1")
		)
		(pad "A18" smd circle
			(at 0 21.59 90)
			(size 0.635 0.635)
			(layers "F.Cu" "F.Mask" "F.Paste")
			(net "PVCCMCP_CPU1")
		)
		(pad "A19" smd circle
			(at 0 22.86 90)
			(size 0.635 0.635)
			(layers "F.Cu" "F.Mask" "F.Paste")
			(net "GND")
		)
		(pad "A20" smd circle
			(at 0 24.13 90)
			(size 0.635 0.635)
			(layers "F.Cu" "F.Mask" "F.Paste")
			(net "GND")
		)
		(pad "B1" smd circle
			(at -1.27 0 90)
			(size 0.635 0.635)
			(layers "F.Cu" "F.Mask" "F.Paste")
			(net "PVCCMCP_CPU1")
		)
		(pad "B2" smd circle
			(at -1.27 1.27 90)
			(size 0.635 0.635)
			(layers "F.Cu" "F.Mask" "F.Paste")
			(net "PVCCMCP_CPU1")
		)
		(pad "B3" smd circle
			(at -1.27 2.54 90)
			(size 0.635 0.635)
			(layers "F.Cu" "F.Mask" "F.Paste")
			(net "PVCCMCP_CPU1")
		)
		(pad "B4" smd circle
			(at -1.27 3.81 90)
			(size 0.635 0.635)
			(layers "F.Cu" "F.Mask" "F.Paste")
			(net "VSENSE_PVCCMCP_CPU1_SKT_VRTN")
		)
		(pad "B5" smd circle
			(at -1.27 5.08 90)
			(size 0.635 0.635)
			(layers "F.Cu" "F.Mask" "F.Paste")
			(net "PVCCMCP_CPU1")
		)
		(pad "B6" smd circle
			(at -1.27 6.35 90)
			(size 0.635 0.635)
			(layers "F.Cu" "F.Mask" "F.Paste")
			(net "PVCCMCP_CPU1")
		)
		(pad "B7" smd circle
			(at -1.27 7.62 90)
			(size 0.635 0.635)
			(layers "F.Cu" "F.Mask" "F.Paste")
			(net "PVCCMCP_CPU1")
		)
		(pad "B8" smd circle
			(at -1.27 8.89 90)
			(size 0.635 0.635)
			(layers "F.Cu" "F.Mask" "F.Paste")
			(net "PVCCMCP_CPU1")
		)
		(pad "B9" smd circle
			(at -1.27 10.16 90)
			(size 0.635 0.635)
			(layers "F.Cu" "F.Mask" "F.Paste")
			(net "PVCCMCP_CPU1")
		)
		(pad "B10" smd circle
			(at -1.27 11.43 90)
			(size 0.635 0.635)
			(layers "F.Cu" "F.Mask" "F.Paste")
			(net "PVCCMCP_CPU1")
		)
		(pad "B11" smd circle
			(at -1.27 12.7 90)
			(size 0.635 0.635)
			(layers "F.Cu" "F.Mask" "F.Paste")
			(net "PVCCMCP_CPU1")
		)
		(pad "B12" smd circle
			(at -1.27 13.97 90)
			(size 0.635 0.635)
			(layers "F.Cu" "F.Mask" "F.Paste")
			(net "PVCCMCP_CPU1")
		)
		(pad "B13" smd circle
			(at -1.27 15.24 90)
			(size 0.635 0.635)
			(layers "F.Cu" "F.Mask" "F.Paste")
			(net "PVCCMCP_CPU1")
		)
		(pad "B14" smd circle
			(at -1.27 16.51 90)
			(size 0.635 0.635)
			(layers "F.Cu" "F.Mask" "F.Paste")
			(net "PVCCMCP_CPU1")
		)
		(pad "B15" smd circle
			(at -1.27 17.78 90)
			(size 0.635 0.635)
			(layers "F.Cu" "F.Mask" "F.Paste")
			(net "PVCCMCP_CPU1")
		)
		(pad "B16" smd circle
			(at -1.27 19.05 90)
			(size 0.635 0.635)
			(layers "F.Cu" "F.Mask" "F.Paste")
			(net "PVCCMCP_CPU1")
		)
		(pad "B17" smd circle
			(at -1.27 20.32 90)
			(size 0.635 0.635)
			(layers "F.Cu" "F.Mask" "F.Paste")
			(net "PVCCMCP_CPU1")
		)
		(pad "B18" smd circle
			(at -1.27 21.59 90)
			(size 0.635 0.635)
			(layers "F.Cu" "F.Mask" "F.Paste")
			(net "PVCCMCP_CPU1")
		)
		(pad "B19" smd circle
			(at -1.27 22.86 90)
			(size 0.635 0.635)
			(layers "F.Cu" "F.Mask" "F.Paste")
			(net "GND")
		)
		(pad "B20" smd circle
			(at -1.27 24.13 90)
			(size 0.635 0.635)
			(layers "F.Cu" "F.Mask" "F.Paste")
			(net "GND")
		)
		(pad "C1" smd circle
			(at -2.54 0 90)
			(size 0.635 0.635)
			(layers "F.Cu" "F.Mask" "F.Paste")
			(net "PVCCMCP_CPU1")
		)
		(pad "C2" smd circle
			(at -2.54 1.27 90)
			(size 0.635 0.635)
			(layers "F.Cu" "F.Mask" "F.Paste")
			(net "PVCCMCP_CPU1")
		)
		(pad "C3" smd circle
			(at -2.54 2.54 90)
			(size 0.635 0.635)
			(layers "F.Cu" "F.Mask" "F.Paste")
			(net "PVCCMCP_CPU1")
		)
		(pad "C4" smd circle
			(at -2.54 3.81 90)
			(size 0.635 0.635)
			(layers "F.Cu" "F.Mask" "F.Paste")
			(net "PVCCMCP_CPU1")
		)
		(pad "C5" smd circle
			(at -2.54 5.08 90)
			(size 0.635 0.635)
			(layers "F.Cu" "F.Mask" "F.Paste")
			(net "PVCCMCP_CPU1")
		)
		(pad "C6" smd circle
			(at -2.54 6.35 90)
			(size 0.635 0.635)
			(layers "F.Cu" "F.Mask" "F.Paste")
			(net "PVCCMCP_CPU1")
		)
		(pad "C7" smd circle
			(at -2.54 7.62 90)
			(size 0.635 0.635)
			(layers "F.Cu" "F.Mask" "F.Paste")
			(net "PVCCMCP_CPU1")
		)
		(pad "C8" smd circle
			(at -2.54 8.89 90)
			(size 0.635 0.635)
			(layers "F.Cu" "F.Mask" "F.Paste")
			(net "PVCCMCP_CPU1")
		)
		(pad "C9" smd circle
			(at -2.54 10.16 90)
			(size 0.635 0.635)
			(layers "F.Cu" "F.Mask" "F.Paste")
			(net "PVCCMCP_CPU1")
		)
		(pad "C10" smd circle
			(at -2.54 11.43 90)
			(size 0.635 0.635)
			(layers "F.Cu" "F.Mask" "F.Paste")
			(net "PVCCMCP_CPU1")
		)
		(pad "C11" smd circle
			(at -2.54 12.7 90)
			(size 0.635 0.635)
			(layers "F.Cu" "F.Mask" "F.Paste")
			(net "PVCCMCP_CPU1")
		)
		(pad "C12" smd circle
			(at -2.54 13.97 90)
			(size 0.635 0.635)
			(layers "F.Cu" "F.Mask" "F.Paste")
			(net "PVCCMCP_CPU1")
		)
		(pad "C13" smd circle
			(at -2.54 15.24 90)
			(size 0.635 0.635)
			(layers "F.Cu" "F.Mask" "F.Paste")
			(net "PVCCMCP_CPU1")
		)
		(pad "C14" smd circle
			(at -2.54 16.51 90)
			(size 0.635 0.635)
			(layers "F.Cu" "F.Mask" "F.Paste")
			(net "PVCCMCP_CPU1")
		)
		(pad "C15" smd circle
			(at -2.54 17.78 90)
			(size 0.635 0.635)
			(layers "F.Cu" "F.Mask" "F.Paste")
			(net "PVCCMCP_CPU1")
		)
		(pad "C16" smd circle
			(at -2.54 19.05 90)
			(size 0.635 0.635)
			(layers "F.Cu" "F.Mask" "F.Paste")
			(net "PVCCMCP_CPU1")
		)
		(pad "C17" smd circle
			(at -2.54 20.32 90)
			(size 0.635 0.635)
			(layers "F.Cu" "F.Mask" "F.Paste")
			(net "PVCCMCP_CPU1")
		)
		(pad "C18" smd circle
			(at -2.54 21.59 90)
			(size 0.635 0.635)
			(layers "F.Cu" "F.Mask" "F.Paste")
			(net "PVCCMCP_CPU1")
		)
		(pad "C19" smd circle
			(at -2.54 22.86 90)
			(size 0.635 0.635)
			(layers "F.Cu" "F.Mask" "F.Paste")
			(net "GND")
		)
		(pad "C20" smd circle
			(at -2.54 24.13 90)
			(size 0.635 0.635)
			(layers "F.Cu" "F.Mask" "F.Paste")
			(net "GND")
		)
		(pad "D1" smd circle
			(at -3.81 0 90)
			(size 0.635 0.635)
			(layers "F.Cu" "F.Mask" "F.Paste")
			(net "VSENSE_P1V8MCP_CPU1_SKT_VSEN")
		)
		(pad "D2" smd circle
			(at -3.81 1.27 90)
			(size 0.635 0.635)
			(layers "F.Cu" "F.Mask" "F.Paste")
			(net "VSENSE_P1V8MCP_CPU1_SKT_VRTN")
		)
		(pad "D3" smd circle
			(at -3.81 2.54 90)
			(size 0.635 0.635)
			(layers "F.Cu" "F.Mask" "F.Paste")
			(net "P1V8_MCP_CPU1")
		)
		(pad "D4" smd circle
			(at -3.81 3.81 90)
			(size 0.635 0.635)
			(layers "F.Cu" "F.Mask" "F.Paste")
			(net "GND")
		)
		(pad "D5" smd circle
			(at -3.81 5.08 90)
			(size 0.635 0.635)
			(layers "F.Cu" "F.Mask" "F.Paste")
			(net "GND")
		)
		(pad "D6" smd circle
			(at -3.81 6.35 90)
			(size 0.635 0.635)
			(layers "F.Cu" "F.Mask" "F.Paste")
			(net "GND")
		)
		(pad "D7" smd circle
			(at -3.81 7.62 90)
			(size 0.635 0.635)
			(layers "F.Cu" "F.Mask" "F.Paste")
			(net "GND")
		)
		(pad "D8" smd circle
			(at -3.81 8.89 90)
			(size 0.635 0.635)
			(layers "F.Cu" "F.Mask" "F.Paste")
			(net "GND")
		)
		(pad "D9" smd circle
			(at -3.81 10.16 90)
			(size 0.635 0.635)
			(layers "F.Cu" "F.Mask" "F.Paste")
			(net "GND")
		)
		(pad "D10" smd circle
			(at -3.81 11.43 90)
			(size 0.635 0.635)
			(layers "F.Cu" "F.Mask" "F.Paste")
			(net "GND")
		)
		(pad "D11" smd circle
			(at -3.81 12.7 90)
			(size 0.635 0.635)
			(layers "F.Cu" "F.Mask" "F.Paste")
			(net "GND")
		)
		(pad "D12" smd circle
			(at -3.81 13.97 90)
			(size 0.635 0.635)
			(layers "F.Cu" "F.Mask" "F.Paste")
			(net "GND")
		)
		(pad "D13" smd circle
			(at -3.81 15.24 90)
			(size 0.635 0.635)
			(layers "F.Cu" "F.Mask" "F.Paste")
			(net "GND")
		)
		(pad "D14" smd circle
			(at -3.81 16.51 90)
			(size 0.635 0.635)
			(layers "F.Cu" "F.Mask" "F.Paste")
			(net "GND")
		)
		(pad "D15" smd circle
			(at -3.81 17.78 90)
			(size 0.635 0.635)
			(layers "F.Cu" "F.Mask" "F.Paste")
			(net "GND")
		)
		(pad "D16" smd circle
			(at -3.81 19.05 90)
			(size 0.635 0.635)
			(layers "F.Cu" "F.Mask" "F.Paste")
			(net "GND")
		)
		(pad "D17" smd circle
			(at -3.81 20.32 90)
			(size 0.635 0.635)
			(layers "F.Cu" "F.Mask" "F.Paste")
			(net "GND")
		)
		(pad "D18" smd circle
			(at -3.81 21.59 90)
			(size 0.635 0.635)
			(layers "F.Cu" "F.Mask" "F.Paste")
			(net "GND")
		)
		(pad "D19" smd circle
			(at -3.81 22.86 90)
			(size 0.635 0.635)
			(layers "F.Cu" "F.Mask" "F.Paste")
			(net "GND")
		)
		(pad "D20" smd circle
			(at -3.81 24.13 90)
			(size 0.635 0.635)
			(layers "F.Cu" "F.Mask" "F.Paste")
			(net "GND")
		)
		(pad "E1" smd circle
			(at -5.08 0 90)
			(size 0.635 0.635)
			(layers "F.Cu" "F.Mask" "F.Paste")
			(net "P1V8_MCP_CPU1")
		)
		(pad "E2" smd circle
			(at -5.08 1.27 90)
			(size 0.635 0.635)
			(layers "F.Cu" "F.Mask" "F.Paste")
			(net "P1V8_MCP_CPU1")
		)
		(pad "E3" smd circle
			(at -5.08 2.54 90)
			(size 0.635 0.635)
			(layers "F.Cu" "F.Mask" "F.Paste")
			(net "P1V8_MCP_CPU1")
		)
		(pad "E4" smd circle
			(at -5.08 3.81 90)
			(size 0.635 0.635)
			(layers "F.Cu" "F.Mask" "F.Paste")
			(net "GND")
		)
		(pad "E5" smd circle
			(at -5.08 5.08 90)
			(size 0.635 0.635)
			(layers "F.Cu" "F.Mask" "F.Paste")
			(net "CLK_322M_156M_CPU1_OSC_VRM_DP")
		)
		(pad "E6" smd circle
			(at -5.08 6.35 90)
			(size 0.635 0.635)
			(layers "F.Cu" "F.Mask" "F.Paste")
			(net "GND")
		)
		(pad "E7" smd circle
			(at -5.08 7.62 90)
			(size 0.635 0.635)
			(layers "F.Cu" "F.Mask" "F.Paste")
			(net "GND")
		)
		(pad "E8" smd circle
			(at -5.08 8.89 90)
			(size 0.635 0.635)
			(layers "F.Cu" "F.Mask" "F.Paste")
			(net "GND")
		)
		(pad "E9" smd circle
			(at -5.08 10.16 90)
			(size 0.635 0.635)
			(layers "F.Cu" "F.Mask" "F.Paste")
			(net "GND")
		)
		(pad "E10" smd circle
			(at -5.08 11.43 90)
			(size 0.635 0.635)
			(layers "F.Cu" "F.Mask" "F.Paste")
			(net "GND")
		)
		(pad "E11" smd circle
			(at -5.08 12.7 90)
			(size 0.635 0.635)
			(layers "F.Cu" "F.Mask" "F.Paste")
			(net "GND")
		)
		(pad "E12" smd circle
			(at -5.08 13.97 90)
			(size 0.635 0.635)
			(layers "F.Cu" "F.Mask" "F.Paste")
			(net "GND")
		)
		(pad "E13" smd circle
			(at -5.08 15.24 90)
			(size 0.635 0.635)
			(layers "F.Cu" "F.Mask" "F.Paste")
			(net "GND")
		)
		(pad "E14" smd circle
			(at -5.08 16.51 90)
			(size 0.635 0.635)
			(layers "F.Cu" "F.Mask" "F.Paste")
			(net "GND")
		)
		(pad "E15" smd circle
			(at -5.08 17.78 90)
			(size 0.635 0.635)
			(layers "F.Cu" "F.Mask" "F.Paste")
			(net "GND")
		)
		(pad "E16" smd circle
			(at -5.08 19.05 90)
			(size 0.635 0.635)
			(layers "F.Cu" "F.Mask" "F.Paste")
			(net "GND")
		)
		(pad "E17" smd circle
			(at -5.08 20.32 90)
			(size 0.635 0.635)
			(layers "F.Cu" "F.Mask" "F.Paste")
			(net "GND")
		)
		(pad "E18" smd circle
			(at -5.08 21.59 90)
			(size 0.635 0.635)
			(layers "F.Cu" "F.Mask" "F.Paste")
			(net "GND")
		)
		(pad "E19" smd circle
			(at -5.08 22.86 90)
			(size 0.635 0.635)
			(layers "F.Cu" "F.Mask" "F.Paste")
			(net "GND")
		)
		(pad "E20" smd circle
			(at -5.08 24.13 90)
			(size 0.635 0.635)
			(layers "F.Cu" "F.Mask" "F.Paste")
			(net "GND")
		)
		(pad "F1" smd circle
			(at -6.35 0 90)
			(size 0.635 0.635)
			(layers "F.Cu" "F.Mask" "F.Paste")
			(net "P1V8_MCP_CPU1")
		)
		(pad "F2" smd circle
			(at -6.35 1.27 90)
			(size 0.635 0.635)
			(layers "F.Cu" "F.Mask" "F.Paste")
			(net "P1V8_MCP_CPU1")
		)
		(pad "F3" smd circle
			(at -6.35 2.54 90)
			(size 0.635 0.635)
			(layers "F.Cu" "F.Mask" "F.Paste")
			(net "P1V8_MCP_CPU1")
		)
		(pad "F4" smd circle
			(at -6.35 3.81 90)
			(size 0.635 0.635)
			(layers "F.Cu" "F.Mask" "F.Paste")
			(net "GND")
		)
		(pad "F5" smd circle
			(at -6.35 5.08 90)
			(size 0.635 0.635)
			(layers "F.Cu" "F.Mask" "F.Paste")
			(net "CLK_322M_156M_CPU1_OSC_VRM_DN")
		)
		(pad "F6" smd circle
			(at -6.35 6.35 90)
			(size 0.635 0.635)
			(layers "F.Cu" "F.Mask" "F.Paste")
			(net "GND")
		)
		(pad "F7" smd circle
			(at -6.35 7.62 90)
			(size 0.635 0.635)
			(layers "F.Cu" "F.Mask" "F.Paste")
			(net "GND")
		)
		(pad "F8" smd circle
			(at -6.35 8.89 90)
			(size 0.635 0.635)
			(layers "F.Cu" "F.Mask" "F.Paste")
			(net "GND")
		)
		(pad "F9" smd circle
			(at -6.35 10.16 90)
			(size 0.635 0.635)
			(layers "F.Cu" "F.Mask" "F.Paste")
			(net "GND")
		)
		(pad "F10" smd circle
			(at -6.35 11.43 90)
			(size 0.635 0.635)
			(layers "F.Cu" "F.Mask" "F.Paste")
			(net "GND")
		)
		(pad "F11" smd circle
			(at -6.35 12.7 90)
			(size 0.635 0.635)
			(layers "F.Cu" "F.Mask" "F.Paste")
			(net "GND")
		)
		(pad "F12" smd circle
			(at -6.35 13.97 90)
			(size 0.635 0.635)
			(layers "F.Cu" "F.Mask" "F.Paste")
			(net "GND")
		)
		(pad "F13" smd circle
			(at -6.35 15.24 90)
			(size 0.635 0.635)
			(layers "F.Cu" "F.Mask" "F.Paste")
			(net "GND")
		)
		(pad "F14" smd circle
			(at -6.35 16.51 90)
			(size 0.635 0.635)
			(layers "F.Cu" "F.Mask" "F.Paste")
			(net "GND")
		)
		(pad "F15" smd circle
			(at -6.35 17.78 90)
			(size 0.635 0.635)
			(layers "F.Cu" "F.Mask" "F.Paste")
			(net "GND")
		)
		(pad "F16" smd circle
			(at -6.35 19.05 90)
			(size 0.635 0.635)
			(layers "F.Cu" "F.Mask" "F.Paste")
			(net "GND")
		)
		(pad "F17" smd circle
			(at -6.35 20.32 90)
			(size 0.635 0.635)
			(layers "F.Cu" "F.Mask" "F.Paste")
			(net "GND")
		)
		(pad "F18" smd circle
			(at -6.35 21.59 90)
			(size 0.635 0.635)
			(layers "F.Cu" "F.Mask" "F.Paste")
			(net "GND")
		)
		(pad "F19" smd circle
			(at -6.35 22.86 90)
			(size 0.635 0.635)
			(layers "F.Cu" "F.Mask" "F.Paste")
			(net "GND")
		)
		(pad "F20" smd circle
			(at -6.35 24.13 90)
			(size 0.635 0.635)
			(layers "F.Cu" "F.Mask" "F.Paste")
			(net "GND")
		)
		(zone
			(layers "F.Cu" "B.Cu" "In1.Cu" "In2.Cu" "In3.Cu" "In4.Cu" "In5.Cu" "In6.Cu"
				"In7.Cu" "In8.Cu" "In9.Cu" "In10.Cu" "In11.Cu" "In12.Cu"
			)
			(hatch none 0.5)
			(connect_pads
				(clearance 0)
			)
			(min_thickness 0.25)
			(keepout
				(tracks not_allowed)
				(vias allowed)
				(pads allowed)
				(copperpour not_allowed)
				(footprints allowed)
			)
			(placement
				(enabled no)
				(sheetname "")
			)
			(fill
				(thermal_gap 0.5)
				(thermal_bridge_width 0.5)
				(island_removal_mode 0)
			)
			(polygon
				(pts
					(arc
						(start 163.141914 -43.67403)
						(mid 161.236914 -43.67403)
						(end 163.141914 -43.67403)
					)
				)
			)
		)
		(zone
			(layers "F.Cu" "B.Cu" "In1.Cu" "In2.Cu" "In3.Cu" "In4.Cu" "In5.Cu" "In6.Cu"
				"In7.Cu" "In8.Cu" "In9.Cu" "In10.Cu" "In11.Cu" "In12.Cu"
			)
			(hatch none 0.5)
			(connect_pads
				(clearance 0)
			)
			(min_thickness 0.25)
			(keepout
				(tracks not_allowed)
				(vias allowed)
				(pads allowed)
				(copperpour not_allowed)
				(footprints allowed)
			)
			(placement
				(enabled no)
				(sheetname "")
			)
			(fill
				(thermal_gap 0.5)
				(thermal_bridge_width 0.5)
				(island_removal_mode 0)
			)
			(polygon
				(pts
					(arc
						(start 192.123314 -40.62603)
						(mid 190.218314 -40.62603)
						(end 192.123314 -40.62603)
					)
				)
			)
		)
	)
	(footprint ""
		(layer "F.Cu")
		(at 28.851352 -64.089788 -90)
		(property "Reference" "R1E13"
			(at 0 0 270)
			(layer "F.SilkS")
			(hide yes)
			(effects
				(font
					(size 1.27 1.27)
				)
			)
		)
		(property "Value" ""
			(at 0 0 270)
			(layer "F.Fab")
			(effects
				(font
					(size 1.27 1.27)
				)
			)
		)
		(duplicate_pad_numbers_are_jumpers no)
		(fp_poly
			(pts
				(xy -0.2794 -0.1016) (xy 0.2794 -0.1016) (xy 0.2794 0.9906) (xy -0.2794 0.9906)
			)
			(stroke
				(width 0)
				(type default)
			)
			(fill no)
			(layer "F.CrtYd")
		)
		(fp_line
			(start -0.2794 0.9906)
			(end 0.2794 0.9906)
			(stroke
				(width 0.1)
				(type default)
			)
			(layer "F.Fab")
		)
		(fp_line
			(start 0.2794 0.9906)
			(end 0.2794 -0.1016)
			(stroke
				(width 0.1)
				(type default)
			)
			(layer "F.Fab")
		)
		(fp_line
			(start -0.2794 -0.1016)
			(end -0.2794 0.9906)
			(stroke
				(width 0.1)
				(type default)
			)
			(layer "F.Fab")
		)
		(fp_line
			(start 0.2794 -0.1016)
			(end -0.2794 -0.1016)
			(stroke
				(width 0.1)
				(type default)
			)
			(layer "F.Fab")
		)
		(pad "1" smd rect
			(at 0 0 270)
			(size 0.508 0.508)
			(layers "F.Cu" "F.Mask" "F.Paste")
			(net "VR_PVCCIN_CPU1_PH2_OCSET")
		)
		(pad "2" smd rect
			(at 0 0.889 270)
			(size 0.508 0.508)
			(layers "F.Cu" "F.Mask" "F.Paste")
			(net "GND")
		)
		(zone
			(layer "F.Cu")
			(hatch none 0.5)
			(connect_pads
				(clearance 0)
			)
			(min_thickness 0.25)
			(keepout
				(tracks not_allowed)
				(vias allowed)
				(pads allowed)
				(copperpour not_allowed)
				(footprints allowed)
			)
			(placement
				(enabled no)
				(sheetname "")
			)
			(fill
				(thermal_gap 0.5)
				(thermal_bridge_width 0.5)
				(island_removal_mode 0)
			)
			(polygon
				(pts
					(xy 28.216352 -64.343788) (xy 28.216352 -63.835788) (xy 28.597352 -63.835788) (xy 28.597352 -64.343788)
				)
			)
		)
		(zone
			(layer "F.Cu")
			(hatch none 0.5)
			(connect_pads
				(clearance 0)
			)
			(min_thickness 0.25)
			(keepout
				(tracks allowed)
				(vias not_allowed)
				(pads allowed)
				(copperpour not_allowed)
				(footprints allowed)
			)
			(placement
				(enabled no)
				(sheetname "")
			)
			(fill
				(thermal_gap 0.5)
				(thermal_bridge_width 0.5)
				(island_removal_mode 0)
			)
			(polygon
				(pts
					(xy 28.597352 -64.343788) (xy 28.597352 -63.835788) (xy 28.216352 -63.835788) (xy 28.216352 -64.343788)
				)
			)
		)
	)
	(footprint ""
		(layer "F.Cu")
		(at 347.113606 -2.127504 -90)
		(property "Reference" "C7G41"
			(at 0 0 270)
			(layer "F.SilkS")
			(hide yes)
			(effects
				(font
					(size 1.27 1.27)
				)
			)
		)
		(property "Value" ""
			(at 0 0 270)
			(layer "F.Fab")
			(effects
				(font
					(size 1.27 1.27)
				)
			)
		)
		(duplicate_pad_numbers_are_jumpers no)
		(fp_rect
			(start -0.3048 -0.1016)
			(end 0.3048 0.9906)
			(stroke
				(width 0)
				(type default)
			)
			(fill no)
			(layer "F.CrtYd")
		)
		(fp_line
			(start -0.3048 0.9906)
			(end 0.3048 0.9906)
			(stroke
				(width 0.1)
				(type default)
			)
			(layer "F.Fab")
		)
		(fp_line
			(start 0.3048 0.9906)
			(end 0.3048 -0.1016)
			(stroke
				(width 0.1)
				(type default)
			)
			(layer "F.Fab")
		)
		(fp_line
			(start -0.3048 -0.1016)
			(end -0.3048 0.9906)
			(stroke
				(width 0.1)
				(type default)
			)
			(layer "F.Fab")
		)
		(fp_line
			(start 0.3048 -0.1016)
			(end -0.3048 -0.1016)
			(stroke
				(width 0.1)
				(type default)
			)
			(layer "F.Fab")
		)
		(pad "1" smd rect
			(at 0 0 270)
			(size 0.508 0.508)
			(layers "F.Cu" "F.Mask" "F.Paste")
			(net "P5V_STBY")
		)
		(pad "2" smd rect
			(at 0 0.889 270)
			(size 0.508 0.508)
			(layers "F.Cu" "F.Mask" "F.Paste")
			(net "GND")
		)
		(zone
			(layer "F.Cu")
			(hatch none 0.5)
			(connect_pads
				(clearance 0)
			)
			(min_thickness 0.25)
			(keepout
				(tracks allowed)
				(vias not_allowed)
				(pads allowed)
				(copperpour not_allowed)
				(footprints allowed)
			)
			(placement
				(enabled no)
				(sheetname "")
			)
			(fill
				(thermal_gap 0.5)
				(thermal_bridge_width 0.5)
				(island_removal_mode 0)
			)
			(polygon
				(pts
					(xy 346.859606 -2.381504) (xy 346.478606 -2.381504) (xy 346.478606 -1.873504) (xy 346.859606 -1.873504)
				)
			)
		)
		(zone
			(layer "F.Cu")
			(hatch none 0.5)
			(connect_pads
				(clearance 0)
			)
			(min_thickness 0.25)
			(keepout
				(tracks not_allowed)
				(vias allowed)
				(pads allowed)
				(copperpour not_allowed)
				(footprints allowed)
			)
			(placement
				(enabled no)
				(sheetname "")
			)
			(fill
				(thermal_gap 0.5)
				(thermal_bridge_width 0.5)
				(island_removal_mode 0)
			)
			(polygon
				(pts
					(xy 346.859606 -2.381504) (xy 346.478606 -2.381504) (xy 346.478606 -1.873504) (xy 346.859606 -1.873504)
				)
			)
		)
	)
	(footprint ""
		(layer "F.Cu")
		(at 337.7311 -134.493 -90)
		(property "Reference" "L7B1"
			(at 5.08 6.99643 90)
			(unlocked yes)
			(layer "F.SilkS")
			(effects
				(font
					(size 0.7874 0.5842)
					(thickness 0.1524)
				)
				(justify left)
			)
		)
		(property "Value" ""
			(at 0 0 270)
			(layer "F.Fab")
			(effects
				(font
					(size 1.27 1.27)
				)
			)
		)
		(duplicate_pad_numbers_are_jumpers no)
		(fp_line
			(start -3.4036 6.1341)
			(end -3.4036 -0.6731)
			(stroke
				(width 0.1524)
				(type default)
			)
			(layer "F.SilkS")
		)
		(fp_line
			(start -2.5654 6.1341)
			(end -3.4036 6.1341)
			(stroke
				(width 0.1524)
				(type default)
			)
			(layer "F.SilkS")
		)
		(fp_line
			(start 3.4036 6.1341)
			(end 2.5654 6.1341)
			(stroke
				(width 0.1524)
				(type default)
			)
			(layer "F.SilkS")
		)
		(fp_line
			(start -3.4036 -0.6731)
			(end -2.5654 -0.6731)
			(stroke
				(width 0.1524)
				(type default)
			)
			(layer "F.SilkS")
		)
		(fp_line
			(start 2.5654 -0.6731)
			(end 3.4036 -0.6731)
			(stroke
				(width 0.1524)
				(type default)
			)
			(layer "F.SilkS")
		)
		(fp_line
			(start 3.4036 -0.6731)
			(end 3.4036 6.1341)
			(stroke
				(width 0.1524)
				(type default)
			)
			(layer "F.SilkS")
		)
		(fp_poly
			(pts
				(xy -3.4036 -0.6731) (xy -3.4036 6.1341) (xy 3.4036 6.1341) (xy 3.4036 -0.6731)
			)
			(stroke
				(width 0)
				(type default)
			)
			(fill no)
			(layer "F.CrtYd")
		)
		(fp_line
			(start -3.4036 6.1341)
			(end -3.4036 -0.6731)
			(stroke
				(width 0.1)
				(type default)
			)
			(layer "F.Fab")
		)
		(fp_line
			(start 3.4036 6.1341)
			(end -3.4036 6.1341)
			(stroke
				(width 0.1)
				(type default)
			)
			(layer "F.Fab")
		)
		(fp_line
			(start -3.4036 -0.6731)
			(end 3.4036 -0.6731)
			(stroke
				(width 0.1)
				(type default)
			)
			(layer "F.Fab")
		)
		(fp_line
			(start 3.4036 -0.6731)
			(end 3.4036 6.1341)
			(stroke
				(width 0.1)
				(type default)
			)
			(layer "F.Fab")
		)
		(pad "1" smd rect
			(at 0 0 270)
			(size 3.556 3.175)
			(layers "F.Cu" "F.Mask" "F.Paste")
			(net "VR_PVPP_DEF_PHASE")
		)
		(pad "2" smd rect
			(at 0 5.461 270)
			(size 3.556 3.175)
			(layers "F.Cu" "F.Mask" "F.Paste")
			(net "PVPP_DEF")
		)
	)
	(footprint ""
		(layer "F.Cu")
		(at 252.1585 -149.8092 -90)
		(property "Reference" "C5A3"
			(at 1.848866 0.752348 270)
			(unlocked yes)
			(layer "F.SilkS")
			(effects
				(font
					(size 1.27 0.9652)
					(thickness 0.1524)
				)
			)
		)
		(property "Value" ""
			(at 0 0 270)
			(layer "F.Fab")
			(effects
				(font
					(size 1.27 1.27)
				)
			)
		)
		(duplicate_pad_numbers_are_jumpers no)
		(fp_rect
			(start -0.500126 1.598422)
			(end 0.500126 -0.201422)
			(stroke
				(width 0)
				(type default)
			)
			(fill no)
			(layer "F.CrtYd")
		)
		(fp_line
			(start -0.500126 1.598422)
			(end -0.500126 -0.201422)
			(stroke
				(width 0.1)
				(type default)
			)
			(layer "F.Fab")
		)
		(fp_line
			(start 0.500126 1.598422)
			(end -0.500126 1.598422)
			(stroke
				(width 0.1)
				(type default)
			)
			(layer "F.Fab")
		)
		(fp_line
			(start -0.500126 -0.201422)
			(end 0.500126 -0.201422)
			(stroke
				(width 0.1)
				(type default)
			)
			(layer "F.Fab")
		)
		(fp_line
			(start 0.500126 -0.201422)
			(end 0.500126 1.598422)
			(stroke
				(width 0.1)
				(type default)
			)
			(layer "F.Fab")
		)
		(pad "1" smd rect
			(at 0 0 180)
			(size 0.889 0.9906)
			(layers "F.Cu" "F.Mask" "F.Paste")
			(net "PVDDQ_DEF")
		)
		(pad "2" smd rect
			(at 0 1.397 180)
			(size 0.889 0.9906)
			(layers "F.Cu" "F.Mask" "F.Paste")
			(net "GND")
		)
		(zone
			(layer "F.Cu")
			(hatch none 0.5)
			(connect_pads
				(clearance 0)
			)
			(min_thickness 0.25)
			(keepout
				(tracks allowed)
				(vias not_allowed)
				(pads allowed)
				(copperpour not_allowed)
				(footprints allowed)
			)
			(placement
				(enabled no)
				(sheetname "")
			)
			(fill
				(thermal_gap 0.5)
				(thermal_bridge_width 0.5)
				(island_removal_mode 0)
			)
			(polygon
				(pts
					(xy 251.206 -150.3045) (xy 251.206 -149.3139) (xy 251.714 -149.3139) (xy 251.714 -150.3045)
				)
			)
		)
		(zone
			(layer "F.Cu")
			(hatch none 0.5)
			(connect_pads
				(clearance 0)
			)
			(min_thickness 0.25)
			(keepout
				(tracks not_allowed)
				(vias allowed)
				(pads allowed)
				(copperpour not_allowed)
				(footprints allowed)
			)
			(placement
				(enabled no)
				(sheetname "")
			)
			(fill
				(thermal_gap 0.5)
				(thermal_bridge_width 0.5)
				(island_removal_mode 0)
			)
			(polygon
				(pts
					(xy 251.206 -150.3045) (xy 251.206 -149.3139) (xy 251.714 -149.3139) (xy 251.714 -150.3045)
				)
			)
		)
	)
	(footprint ""
		(layer "F.Cu")
		(at 367.088928 -45.23232)
		(property "Reference" "U8F2"
			(at 10.3505 -2.88671 180)
			(unlocked yes)
			(layer "F.SilkS")
			(effects
				(font
					(size 0.7874 0.5842)
					(thickness 0.1524)
				)
				(justify left)
			)
		)
		(property "Value" ""
			(at 0 0 0)
			(layer "F.Fab")
			(effects
				(font
					(size 1.27 1.27)
				)
			)
		)
		(duplicate_pad_numbers_are_jumpers no)
		(fp_line
			(start -2.094738 -1.929892)
			(end 11.645392 -1.929892)
			(stroke
				(width 0.1524)
				(type default)
			)
			(layer "F.SilkS")
		)
		(fp_line
			(start -2.094738 10.819892)
			(end -2.094738 -1.929892)
			(stroke
				(width 0.1524)
				(type default)
			)
			(layer "F.SilkS")
		)
		(fp_line
			(start 11.645392 -1.929892)
			(end 11.645392 10.819892)
			(stroke
				(width 0.1524)
				(type default)
			)
			(layer "F.SilkS")
		)
		(fp_line
			(start 11.645392 10.819892)
			(end -2.094738 10.819892)
			(stroke
				(width 0.1524)
				(type default)
			)
			(layer "F.SilkS")
		)
		(fp_circle
			(center -2.568194 -2.286)
			(end -2.441194 -2.286)
			(stroke
				(width 0.762)
				(type default)
			)
			(fill no)
			(layer "F.SilkS")
		)
		(fp_rect
			(start -5.600954 12.260326)
			(end -2.094738 -3.284474)
			(stroke
				(width 0)
				(type default)
			)
			(fill no)
			(layer "F.CrtYd")
		)
		(fp_rect
			(start 11.645392 12.260326)
			(end 15.404846 -3.284474)
			(stroke
				(width 0)
				(type default)
			)
			(fill no)
			(layer "F.CrtYd")
		)
		(fp_poly
			(pts
				(xy -2.094738 10.819892) (xy 11.645392 10.819892) (xy 11.645392 -1.929892) (xy -2.094738 -1.929892)
			)
			(stroke
				(width 0)
				(type default)
			)
			(fill no)
			(layer "F.CrtYd")
		)
		(fp_poly
			(pts
				(xy 2.029968 -1.929892) (xy 2.629916 -3.32994) (xy 6.970014 -3.32994) (xy 7.569962 -1.929892)
			)
			(stroke
				(width 0)
				(type default)
			)
			(fill no)
			(layer "F.CrtYd")
		)
		(fp_poly
			(pts
				(xy 7.569962 10.819892) (xy 6.970014 12.21994) (xy 2.629916 12.21994) (xy 2.029968 10.819892)
			)
			(stroke
				(width 0)
				(type default)
			)
			(fill no)
			(layer "F.CrtYd")
		)
		(fp_line
			(start -2.094738 -1.929892)
			(end 11.645392 -1.929892)
			(stroke
				(width 0.1)
				(type default)
			)
			(layer "F.Fab")
		)
		(fp_line
			(start -2.094738 10.819892)
			(end -2.094738 -1.929892)
			(stroke
				(width 0.1)
				(type default)
			)
			(layer "F.Fab")
		)
		(fp_line
			(start 2.029968 -1.929892)
			(end 2.629916 -3.32994)
			(stroke
				(width 0.1)
				(type default)
			)
			(layer "F.Fab")
		)
		(fp_line
			(start 2.629916 -3.32994)
			(end 6.970014 -3.32994)
			(stroke
				(width 0.1)
				(type default)
			)
			(layer "F.Fab")
		)
		(fp_line
			(start 2.629916 12.21994)
			(end 2.029968 10.819892)
			(stroke
				(width 0.1)
				(type default)
			)
			(layer "F.Fab")
		)
		(fp_line
			(start 6.970014 -3.32994)
			(end 7.569962 -1.929892)
			(stroke
				(width 0.1)
				(type default)
			)
			(layer "F.Fab")
		)
		(fp_line
			(start 6.970014 12.21994)
			(end 2.629916 12.21994)
			(stroke
				(width 0.1)
				(type default)
			)
			(layer "F.Fab")
		)
		(fp_line
			(start 7.569962 10.819892)
			(end 6.970014 12.21994)
			(stroke
				(width 0.1)
				(type default)
			)
			(layer "F.Fab")
		)
		(fp_line
			(start 11.645392 -1.929892)
			(end 11.645392 10.819892)
			(stroke
				(width 0.1)
				(type default)
			)
			(layer "F.Fab")
		)
		(fp_line
			(start 11.645392 10.819892)
			(end -2.094738 10.819892)
			(stroke
				(width 0.1)
				(type default)
			)
			(layer "F.Fab")
		)
		(fp_circle
			(center -2.645918 -0.940054)
			(end -2.518918 -0.940054)
			(stroke
				(width 0.254)
				(type default)
			)
			(fill no)
			(layer "F.Fab")
		)
		(fp_text user "8"
			(at -1.498854 11.547348 90)
			(unlocked yes)
			(layer "F.SilkS")
			(effects
				(font
					(size 0.7874 0.5842)
					(thickness 0.1524)
				)
				(justify left)
			)
		)
		(fp_text user "9"
			(at 9.397746 11.529822 90)
			(unlocked yes)
			(layer "F.SilkS")
			(effects
				(font
					(size 0.7874 0.5842)
					(thickness 0.1524)
				)
				(justify left)
			)
		)
		(fp_text user "16"
			(at 12.40917 0.31496 90)
			(unlocked yes)
			(layer "F.SilkS")
			(effects
				(font
					(size 0.7874 0.5842)
					(thickness 0.1524)
				)
				(justify left)
			)
		)
		(fp_text user "8"
			(at -2.4257 9.04621 0)
			(unlocked yes)
			(layer "F.Fab")
			(effects
				(font
					(size 0.635 0.635)
					(thickness 0.1524)
				)
				(justify left)
			)
		)
		(fp_text user "16"
			(at 11.646916 0.367792 0)
			(unlocked yes)
			(layer "F.Fab")
			(effects
				(font
					(size 0.254 0.254)
					(thickness 0.000001)
				)
				(justify left)
			)
		)
		(fp_text user "9"
			(at 11.862054 9.20369 0)
			(unlocked yes)
			(layer "F.Fab")
			(effects
				(font
					(size 0.254 0.254)
					(thickness 0.000001)
				)
				(justify left)
			)
		)
		(pad "1" smd rect
			(at 0 0)
			(size 1.9304 0.635)
			(layers "F.Cu" "F.Mask" "F.Paste")
			(net "PU_SPI_BMC_BT_HOLD_N")
		)
		(pad "2" smd rect
			(at 0 1.27)
			(size 1.9304 0.635)
			(layers "F.Cu" "F.Mask" "F.Paste")
			(net "P3V3_STBY")
		)
		(pad "3" smd rect
			(at 0 2.54)
			(size 1.9304 0.635)
			(layers "F.Cu" "F.Mask" "F.Paste")
			(net "PU_SPI_FLASH_RESET_2_N")
		)
		(pad "4" smd rect
			(at 0 3.81)
			(size 1.9304 0.635)
			(layers "F.Cu" "F.Mask" "F.Paste")
			(net "TP_SPI_2_0")
		)
		(pad "5" smd rect
			(at 0 5.08)
			(size 1.9304 0.635)
			(layers "F.Cu" "F.Mask" "F.Paste")
			(net "TP_SPI_2_1")
		)
		(pad "6" smd rect
			(at 0 6.35)
			(size 1.9304 0.635)
			(layers "F.Cu" "F.Mask" "F.Paste")
			(net "TP_SPI_2_2")
		)
		(pad "7" smd rect
			(at 0 7.62)
			(size 1.9304 0.635)
			(layers "F.Cu" "F.Mask" "F.Paste")
			(net "SPI_BMC_BT_CS_N")
		)
		(pad "8" smd rect
			(at 0 8.89)
			(size 1.9304 0.635)
			(layers "F.Cu" "F.Mask" "F.Paste")
			(net "SPI_BMC_BT_DI_R")
		)
		(pad "9" smd rect
			(at 9.5504 8.89)
			(size 1.9304 0.635)
			(layers "F.Cu" "F.Mask" "F.Paste")
			(net "PU_SPI_BMC_BT_WP_N")
		)
		(pad "10" smd rect
			(at 9.5504 7.62)
			(size 1.9304 0.635)
			(layers "F.Cu" "F.Mask" "F.Paste")
			(net "GND")
		)
		(pad "11" smd rect
			(at 9.5504 6.35)
			(size 1.9304 0.635)
			(layers "F.Cu" "F.Mask" "F.Paste")
			(net "TP_SPI_2_3")
		)
		(pad "12" smd rect
			(at 9.5504 5.08)
			(size 1.9304 0.635)
			(layers "F.Cu" "F.Mask" "F.Paste")
			(net "TP_SPI_2_4")
		)
		(pad "13" smd rect
			(at 9.5504 3.81)
			(size 1.9304 0.635)
			(layers "F.Cu" "F.Mask" "F.Paste")
			(net "TP_SPI_2_5")
		)
		(pad "14" smd rect
			(at 9.5504 2.54)
			(size 1.9304 0.635)
			(layers "F.Cu" "F.Mask" "F.Paste")
			(net "TP_SPI_2_6")
		)
		(pad "15" smd rect
			(at 9.5504 1.27)
			(size 1.9304 0.635)
			(layers "F.Cu" "F.Mask" "F.Paste")
			(net "SPI_BMC_BT_DO")
		)
		(pad "16" smd rect
			(at 9.5504 0)
			(size 1.9304 0.635)
			(layers "F.Cu" "F.Mask" "F.Paste")
			(net "SPI_BMC_BT_CLK")
		)
	)
	(footprint ""
		(layer "F.Cu")
		(at 421.63619 -52.795932 -90)
		(property "Reference" "Q8E2"
			(at -1.98247 1.9685 0)
			(unlocked yes)
			(layer "F.SilkS")
			(effects
				(font
					(size 0.7874 0.5842)
					(thickness 0.1524)
				)
				(justify left)
			)
		)
		(property "Value" ""
			(at 0 0 270)
			(layer "F.Fab")
			(effects
				(font
					(size 1.27 1.27)
				)
			)
		)
		(duplicate_pad_numbers_are_jumpers no)
		(fp_line
			(start 0.9525 2.4765)
			(end 1.778 2.4765)
			(stroke
				(width 0.1524)
				(type default)
			)
			(layer "F.SilkS")
		)
		(fp_line
			(start 1.778 2.4765)
			(end 1.778 1.5875)
			(stroke
				(width 0.1524)
				(type default)
			)
			(layer "F.SilkS")
		)
		(fp_line
			(start 0.381 0.635)
			(end 0.381 1.27)
			(stroke
				(width 0.1524)
				(type default)
			)
			(layer "F.SilkS")
		)
		(fp_line
			(start 0.9525 -0.5715)
			(end 1.778 -0.5715)
			(stroke
				(width 0.1524)
				(type default)
			)
			(layer "F.SilkS")
		)
		(fp_line
			(start 1.778 -0.5715)
			(end 1.778 0.3175)
			(stroke
				(width 0.1524)
				(type default)
			)
			(layer "F.SilkS")
		)
		(fp_circle
			(center -0.636524 -0.863854)
			(end -0.636524 -0.990854)
			(stroke
				(width 0.254)
				(type default)
			)
			(fill no)
			(layer "F.SilkS")
		)
		(fp_poly
			(pts
				(xy 1.778 2.4765) (xy 0.381 2.4765) (xy 0.381 -0.5715) (xy 1.778 -0.5715)
			)
			(stroke
				(width 0)
				(type default)
			)
			(fill no)
			(layer "F.CrtYd")
		)
		(fp_line
			(start 0.381 2.4765)
			(end 1.778 2.4765)
			(stroke
				(width 0.1)
				(type default)
			)
			(layer "F.Fab")
		)
		(fp_line
			(start 1.778 2.4765)
			(end 1.778 -0.5715)
			(stroke
				(width 0.1)
				(type default)
			)
			(layer "F.Fab")
		)
		(fp_line
			(start 0.381 -0.5715)
			(end 0.381 2.4765)
			(stroke
				(width 0.1)
				(type default)
			)
			(layer "F.Fab")
		)
		(fp_line
			(start 1.778 -0.5715)
			(end 0.381 -0.5715)
			(stroke
				(width 0.1)
				(type default)
			)
			(layer "F.Fab")
		)
		(fp_circle
			(center -0.9525 -0.9271)
			(end -0.9525 -1.0541)
			(stroke
				(width 0.254)
				(type default)
			)
			(fill no)
			(layer "F.Fab")
		)
		(pad "1" smd rect
			(at 0 0 270)
			(size 1.143 0.508)
			(layers "F.Cu" "F.Mask" "F.Paste")
			(net "RST_RSMRST_DLY")
		)
		(pad "2" smd rect
			(at 0 1.905 270)
			(size 1.143 0.508)
			(layers "F.Cu" "F.Mask" "F.Paste")
			(net "GND")
		)
		(pad "3" smd rect
			(at 2.159 0.9525 270)
			(size 1.143 0.508)
			(layers "F.Cu" "F.Mask" "F.Paste")
			(net "IRQ_SML0_ALERT_N")
		)
	)
	(footprint ""
		(layer "F.Cu")
		(at 402.66874 -32.902652 -90)
		(property "Reference" "R2U33"
			(at 0 0 270)
			(layer "F.SilkS")
			(hide yes)
			(effects
				(font
					(size 1.27 1.27)
				)
			)
		)
		(property "Value" ""
			(at 0 0 270)
			(layer "F.Fab")
			(effects
				(font
					(size 1.27 1.27)
				)
			)
		)
		(duplicate_pad_numbers_are_jumpers no)
		(fp_poly
			(pts
				(xy -0.2794 -0.1016) (xy 0.2794 -0.1016) (xy 0.2794 0.9906) (xy -0.2794 0.9906)
			)
			(stroke
				(width 0)
				(type default)
			)
			(fill no)
			(layer "F.CrtYd")
		)
		(fp_line
			(start -0.2794 0.9906)
			(end 0.2794 0.9906)
			(stroke
				(width 0.1)
				(type default)
			)
			(layer "F.Fab")
		)
		(fp_line
			(start 0.2794 0.9906)
			(end 0.2794 -0.1016)
			(stroke
				(width 0.1)
				(type default)
			)
			(layer "F.Fab")
		)
		(fp_line
			(start -0.2794 -0.1016)
			(end -0.2794 0.9906)
			(stroke
				(width 0.1)
				(type default)
			)
			(layer "F.Fab")
		)
		(fp_line
			(start 0.2794 -0.1016)
			(end -0.2794 -0.1016)
			(stroke
				(width 0.1)
				(type default)
			)
			(layer "F.Fab")
		)
		(pad "1" smd rect
			(at 0 0 270)
			(size 0.508 0.508)
			(layers "F.Cu" "F.Mask" "F.Paste")
			(net "SMB_HOST_STBY_LVC3_SDA_R")
		)
		(pad "2" smd rect
			(at 0 0.889 270)
			(size 0.508 0.508)
			(layers "F.Cu" "F.Mask" "F.Paste")
			(net "SMB_HOST_STBY_LVC3_SDA")
		)
		(zone
			(layer "F.Cu")
			(hatch none 0.5)
			(connect_pads
				(clearance 0)
			)
			(min_thickness 0.25)
			(keepout
				(tracks not_allowed)
				(vias allowed)
				(pads allowed)
				(copperpour not_allowed)
				(footprints allowed)
			)
			(placement
				(enabled no)
				(sheetname "")
			)
			(fill
				(thermal_gap 0.5)
				(thermal_bridge_width 0.5)
				(island_removal_mode 0)
			)
			(polygon
				(pts
					(xy 402.03374 -33.156652) (xy 402.03374 -32.648652) (xy 402.41474 -32.648652) (xy 402.41474 -33.156652)
				)
			)
		)
		(zone
			(layer "F.Cu")
			(hatch none 0.5)
			(connect_pads
				(clearance 0)
			)
			(min_thickness 0.25)
			(keepout
				(tracks allowed)
				(vias not_allowed)
				(pads allowed)
				(copperpour not_allowed)
				(footprints allowed)
			)
			(placement
				(enabled no)
				(sheetname "")
			)
			(fill
				(thermal_gap 0.5)
				(thermal_bridge_width 0.5)
				(island_removal_mode 0)
			)
			(polygon
				(pts
					(xy 402.41474 -33.156652) (xy 402.41474 -32.648652) (xy 402.03374 -32.648652) (xy 402.03374 -33.156652)
				)
			)
		)
	)
	(footprint ""
		(layer "F.Cu")
		(at 432.51882 -129.2987 180)
		(property "Reference" "C8B5"
			(at 0 0 180)
			(layer "F.SilkS")
			(hide yes)
			(effects
				(font
					(size 1.27 1.27)
				)
			)
		)
		(property "Value" ""
			(at 0 0 180)
			(layer "F.Fab")
			(effects
				(font
					(size 1.27 1.27)
				)
			)
		)
		(duplicate_pad_numbers_are_jumpers no)
		(fp_poly
			(pts
				(xy 0.3048 -0.1016) (xy 0.3048 0.9906) (xy -0.3048 0.9906) (xy -0.3048 -0.1016)
			)
			(stroke
				(width 0)
				(type default)
			)
			(fill no)
			(layer "F.CrtYd")
		)
		(fp_line
			(start 0.3048 0.9906)
			(end 0.3048 -0.1016)
			(stroke
				(width 0.1)
				(type default)
			)
			(layer "F.Fab")
		)
		(fp_line
			(start 0.3048 -0.1016)
			(end -0.3048 -0.1016)
			(stroke
				(width 0.1)
				(type default)
			)
			(layer "F.Fab")
		)
		(fp_line
			(start -0.3048 0.9906)
			(end 0.3048 0.9906)
			(stroke
				(width 0.1)
				(type default)
			)
			(layer "F.Fab")
		)
		(fp_line
			(start -0.3048 -0.1016)
			(end -0.3048 0.9906)
			(stroke
				(width 0.1)
				(type default)
			)
			(layer "F.Fab")
		)
		(pad "1" smd rect
			(at 0 0 180)
			(size 0.508 0.508)
			(layers "F.Cu" "F.Mask" "F.Paste")
			(net "P5V_STBY")
		)
		(pad "2" smd rect
			(at 0 0.889 180)
			(size 0.508 0.508)
			(layers "F.Cu" "F.Mask" "F.Paste")
			(net "GND")
		)
		(zone
			(layer "F.Cu")
			(hatch none 0.5)
			(connect_pads
				(clearance 0)
			)
			(min_thickness 0.25)
			(keepout
				(tracks not_allowed)
				(vias allowed)
				(pads allowed)
				(copperpour not_allowed)
				(footprints allowed)
			)
			(placement
				(enabled no)
				(sheetname "")
			)
			(fill
				(thermal_gap 0.5)
				(thermal_bridge_width 0.5)
				(island_removal_mode 0)
			)
			(polygon
				(pts
					(xy 432.77282 -129.9337) (xy 432.26482 -129.9337) (xy 432.26482 -129.5527) (xy 432.77282 -129.5527)
				)
			)
		)
		(zone
			(layer "F.Cu")
			(hatch none 0.5)
			(connect_pads
				(clearance 0)
			)
			(min_thickness 0.25)
			(keepout
				(tracks allowed)
				(vias not_allowed)
				(pads allowed)
				(copperpour not_allowed)
				(footprints allowed)
			)
			(placement
				(enabled no)
				(sheetname "")
			)
			(fill
				(thermal_gap 0.5)
				(thermal_bridge_width 0.5)
				(island_removal_mode 0)
			)
			(polygon
				(pts
					(xy 432.77282 -129.5527) (xy 432.26482 -129.5527) (xy 432.26482 -129.9337) (xy 432.77282 -129.9337)
				)
			)
		)
	)
	(footprint ""
		(layer "F.Cu")
		(at 344.42654 -10.686796 180)
		(property "Reference" "RF16"
			(at -0.8382 -0.67818 180)
			(unlocked yes)
			(layer "F.SilkS")
			(effects
				(font
					(size 0.4064 0.254)
					(thickness 0.1524)
				)
				(justify left)
			)
		)
		(property "Value" ""
			(at 0 0 180)
			(layer "F.Fab")
			(effects
				(font
					(size 1.27 1.27)
				)
			)
		)
		(duplicate_pad_numbers_are_jumpers no)
		(fp_poly
			(pts
				(xy -0.2794 -0.1016) (xy 0.2794 -0.1016) (xy 0.2794 0.9906) (xy -0.2794 0.9906)
			)
			(stroke
				(width 0)
				(type default)
			)
			(fill no)
			(layer "F.CrtYd")
		)
		(fp_line
			(start 0.2794 0.9906)
			(end 0.2794 -0.1016)
			(stroke
				(width 0.1)
				(type default)
			)
			(layer "F.Fab")
		)
		(fp_line
			(start 0.2794 -0.1016)
			(end -0.2794 -0.1016)
			(stroke
				(width 0.1)
				(type default)
			)
			(layer "F.Fab")
		)
		(fp_line
			(start -0.2794 0.9906)
			(end 0.2794 0.9906)
			(stroke
				(width 0.1)
				(type default)
			)
			(layer "F.Fab")
		)
		(fp_line
			(start -0.2794 -0.1016)
			(end -0.2794 0.9906)
			(stroke
				(width 0.1)
				(type default)
			)
			(layer "F.Fab")
		)
		(pad "1" smd rect
			(at 0 0 180)
			(size 0.508 0.508)
			(layers "F.Cu" "F.Mask" "F.Paste")
			(net "VR_PVDDQ_ABC_AIREF2")
		)
		(pad "2" smd rect
			(at 0 0.889 180)
			(size 0.508 0.508)
			(layers "F.Cu" "F.Mask" "F.Paste")
			(net "ISENSE_PVDDQ_ABC_PH2_IMON")
		)
		(zone
			(layer "F.Cu")
			(hatch none 0.5)
			(connect_pads
				(clearance 0)
			)
			(min_thickness 0.25)
			(keepout
				(tracks not_allowed)
				(vias allowed)
				(pads allowed)
				(copperpour not_allowed)
				(footprints allowed)
			)
			(placement
				(enabled no)
				(sheetname "")
			)
			(fill
				(thermal_gap 0.5)
				(thermal_bridge_width 0.5)
				(island_removal_mode 0)
			)
			(polygon
				(pts
					(xy 344.68054 -11.321796) (xy 344.17254 -11.321796) (xy 344.17254 -10.940796) (xy 344.68054 -10.940796)
				)
			)
		)
		(zone
			(layer "F.Cu")
			(hatch none 0.5)
			(connect_pads
				(clearance 0)
			)
			(min_thickness 0.25)
			(keepout
				(tracks allowed)
				(vias not_allowed)
				(pads allowed)
				(copperpour not_allowed)
				(footprints allowed)
			)
			(placement
				(enabled no)
				(sheetname "")
			)
			(fill
				(thermal_gap 0.5)
				(thermal_bridge_width 0.5)
				(island_removal_mode 0)
			)
			(polygon
				(pts
					(xy 344.68054 -10.940796) (xy 344.17254 -10.940796) (xy 344.17254 -11.321796) (xy 344.68054 -11.321796)
				)
			)
		)
	)
	(footprint ""
		(layer "F.Cu")
		(at 189.3316 -71.1454 180)
		(property "Reference" "CF5"
			(at 0 0 180)
			(layer "F.SilkS")
			(hide yes)
			(effects
				(font
					(size 1.27 1.27)
				)
			)
		)
		(property "Value" "*"
			(at 1.1811 -2.8194 180)
			(unlocked yes)
			(layer "F.Fab")
			(hide yes)
			(effects
				(font
					(size 1.27 1.016)
					(thickness 0.1524)
				)
			)
		)
		(property "Device Type" "SC22P50V2JN-4GP_SMD-BCG-SC22P5A"
			(at 1.1811 -4.3434 180)
			(unlocked yes)
			(layer "F.Fab")
			(hide yes)
			(effects
				(font
					(size 1.27 1.016)
					(thickness 0.1524)
				)
			)
		)
		(duplicate_pad_numbers_are_jumpers no)
		(fp_rect
			(start -0.4318 0.9525)
			(end 0.4318 -0.9525)
			(stroke
				(width 0)
				(type default)
			)
			(fill no)
			(layer "F.CrtYd")
		)
		(fp_rect
			(start -0.4318 0.9525)
			(end 0.4318 -0.9525)
			(stroke
				(width 0)
				(type default)
			)
			(fill no)
			(layer "F.Fab")
		)
		(pad "1" smd custom
			(at 0 -0.4445 180)
			(size 0.1524 0.1524)
			(layers "F.Cu" "F.Mask" "F.Paste")
			(net "VR_PVCCIN_CPU0_AIREF5")
			(options
				(clearance outline)
				(anchor circle)
			)
			(primitives
				(gr_poly
					(pts
						(arc
							(start 0.3048 -0.2032)
							(mid 0.275042 -0.275042)
							(end 0.2032 -0.3048)
						)
						(arc
							(start -0.2032 -0.3048)
							(mid -0.275042 -0.275042)
							(end -0.3048 -0.2032)
						)
						(arc
							(start -0.3048 0.2032)
							(mid -0.275042 0.275042)
							(end -0.2032 0.3048)
						)
						(arc
							(start 0.2032 0.3048)
							(mid 0.275042 0.275042)
							(end 0.3048 0.2032)
						)
					)
					(width 0)
					(fill yes)
				)
			)
		)
		(pad "2" smd custom
			(at 0 0.4445 180)
			(size 0.1524 0.1524)
			(layers "F.Cu" "F.Mask" "F.Paste")
			(net "ISENSE_PVCCIN_CPU0_PH5_IMON")
			(options
				(clearance outline)
				(anchor circle)
			)
			(primitives
				(gr_poly
					(pts
						(arc
							(start 0.3048 -0.2032)
							(mid 0.275042 -0.275042)
							(end 0.2032 -0.3048)
						)
						(arc
							(start -0.2032 -0.3048)
							(mid -0.275042 -0.275042)
							(end -0.3048 -0.2032)
						)
						(arc
							(start -0.3048 0.2032)
							(mid -0.275042 0.275042)
							(end -0.2032 0.3048)
						)
						(arc
							(start 0.2032 0.3048)
							(mid 0.275042 0.275042)
							(end 0.3048 0.2032)
						)
					)
					(width 0)
					(fill yes)
				)
			)
		)
	)
	(footprint ""
		(layer "F.Cu")
		(at 29.83865 -41.8592 180)
		(property "Reference" "C1E20"
			(at 0 0 180)
			(layer "F.SilkS")
			(hide yes)
			(effects
				(font
					(size 1.27 1.27)
				)
			)
		)
		(property "Value" ""
			(at 0 0 180)
			(layer "F.Fab")
			(effects
				(font
					(size 1.27 1.27)
				)
			)
		)
		(duplicate_pad_numbers_are_jumpers no)
		(fp_rect
			(start 0.3048 -0.1016)
			(end -0.3048 0.9906)
			(stroke
				(width 0)
				(type default)
			)
			(fill no)
			(layer "F.CrtYd")
		)
		(fp_line
			(start 0.3048 0.9906)
			(end 0.3048 -0.1016)
			(stroke
				(width 0.1)
				(type default)
			)
			(layer "F.Fab")
		)
		(fp_line
			(start 0.3048 -0.1016)
			(end -0.3048 -0.1016)
			(stroke
				(width 0.1)
				(type default)
			)
			(layer "F.Fab")
		)
		(fp_line
			(start -0.3048 0.9906)
			(end 0.3048 0.9906)
			(stroke
				(width 0.1)
				(type default)
			)
			(layer "F.Fab")
		)
		(fp_line
			(start -0.3048 -0.1016)
			(end -0.3048 0.9906)
			(stroke
				(width 0.1)
				(type default)
			)
			(layer "F.Fab")
		)
		(pad "1" smd rect
			(at 0 0 180)
			(size 0.508 0.508)
			(layers "F.Cu" "F.Mask" "F.Paste")
			(net "P12V_FAN")
		)
		(pad "2" smd rect
			(at 0 0.889 180)
			(size 0.508 0.508)
			(layers "F.Cu" "F.Mask" "F.Paste")
			(net "GND")
		)
		(zone
			(layer "F.Cu")
			(hatch none 0.5)
			(connect_pads
				(clearance 0)
			)
			(min_thickness 0.25)
			(keepout
				(tracks allowed)
				(vias not_allowed)
				(pads allowed)
				(copperpour not_allowed)
				(footprints allowed)
			)
			(placement
				(enabled no)
				(sheetname "")
			)
			(fill
				(thermal_gap 0.5)
				(thermal_bridge_width 0.5)
				(island_removal_mode 0)
			)
			(polygon
				(pts
					(xy 29.58465 -42.1132) (xy 30.09265 -42.1132) (xy 30.09265 -42.4942) (xy 29.58465 -42.4942)
				)
			)
		)
		(zone
			(layer "F.Cu")
			(hatch none 0.5)
			(connect_pads
				(clearance 0)
			)
			(min_thickness 0.25)
			(keepout
				(tracks not_allowed)
				(vias allowed)
				(pads allowed)
				(copperpour not_allowed)
				(footprints allowed)
			)
			(placement
				(enabled no)
				(sheetname "")
			)
			(fill
				(thermal_gap 0.5)
				(thermal_bridge_width 0.5)
				(island_removal_mode 0)
			)
			(polygon
				(pts
					(xy 29.58465 -42.1132) (xy 30.09265 -42.1132) (xy 30.09265 -42.4942) (xy 29.58465 -42.4942)
				)
			)
		)
	)
	(footprint ""
		(layer "F.Cu")
		(at 451.739 -131.2418 -90)
		(property "Reference" "C9B2"
			(at 0 0 270)
			(layer "F.SilkS")
			(hide yes)
			(effects
				(font
					(size 1.27 1.27)
				)
			)
		)
		(property "Value" ""
			(at 0 0 270)
			(layer "F.Fab")
			(effects
				(font
					(size 1.27 1.27)
				)
			)
		)
		(duplicate_pad_numbers_are_jumpers no)
		(fp_poly
			(pts
				(xy -0.7239 -0.2159) (xy 0.7239 -0.2159) (xy 0.7239 1.9939) (xy -0.7239 1.9939)
			)
			(stroke
				(width 0)
				(type default)
			)
			(fill no)
			(layer "F.CrtYd")
		)
		(fp_line
			(start -0.7239 1.9939)
			(end 0.7239 1.9939)
			(stroke
				(width 0.1)
				(type default)
			)
			(layer "F.Fab")
		)
		(fp_line
			(start 0.7239 1.9939)
			(end 0.7239 -0.2159)
			(stroke
				(width 0.1)
				(type default)
			)
			(layer "F.Fab")
		)
		(fp_line
			(start -0.7239 -0.2159)
			(end -0.7239 1.9939)
			(stroke
				(width 0.1)
				(type default)
			)
			(layer "F.Fab")
		)
		(fp_line
			(start 0.7239 -0.2159)
			(end -0.7239 -0.2159)
			(stroke
				(width 0.1)
				(type default)
			)
			(layer "F.Fab")
		)
		(pad "1" smd rect
			(at 0 0 270)
			(size 1.27 1.016)
			(layers "F.Cu" "F.Mask" "F.Paste")
			(net "P12V_HDD_SATA")
		)
		(pad "2" smd rect
			(at 0 1.778 270)
			(size 1.27 1.016)
			(layers "F.Cu" "F.Mask" "F.Paste")
			(net "GND")
		)
		(zone
			(layer "F.Cu")
			(hatch none 0.5)
			(connect_pads
				(clearance 0)
			)
			(min_thickness 0.25)
			(keepout
				(tracks not_allowed)
				(vias allowed)
				(pads allowed)
				(copperpour not_allowed)
				(footprints allowed)
			)
			(placement
				(enabled no)
				(sheetname "")
			)
			(fill
				(thermal_gap 0.5)
				(thermal_bridge_width 0.5)
				(island_removal_mode 0)
			)
			(polygon
				(pts
					(xy 451.231 -131.8768) (xy 451.231 -130.6068) (xy 450.469 -130.6068) (xy 450.469 -131.8768)
				)
			)
		)
	)
	(footprint ""
		(layer "F.Cu")
		(at 169.247058 -105.4354)
		(property "Reference" "C4C1"
			(at -3.104388 3.8354 90)
			(unlocked yes)
			(layer "F.SilkS")
			(effects
				(font
					(size 0.7874 0.5842)
					(thickness 0.1524)
				)
			)
		)
		(property "Value" ""
			(at 0 0 0)
			(layer "F.Fab")
			(effects
				(font
					(size 1.27 1.27)
				)
			)
		)
		(duplicate_pad_numbers_are_jumpers no)
		(fp_line
			(start -2.563114 -1.616456)
			(end -2.563114 1.633728)
			(stroke
				(width 0.1524)
				(type default)
			)
			(layer "F.SilkS")
		)
		(fp_line
			(start -2.563114 1.633728)
			(end -1.6002 1.633728)
			(stroke
				(width 0.1524)
				(type default)
			)
			(layer "F.SilkS")
		)
		(fp_line
			(start -2.286 7.366)
			(end -2.286 1.632712)
			(stroke
				(width 0.1524)
				(type default)
			)
			(layer "F.SilkS")
		)
		(fp_line
			(start -2.286 7.366)
			(end -1.60147 7.366)
			(stroke
				(width 0.1524)
				(type default)
			)
			(layer "F.SilkS")
		)
		(fp_line
			(start -1.6002 -1.616456)
			(end -2.563114 -1.616456)
			(stroke
				(width 0.1524)
				(type default)
			)
			(layer "F.SilkS")
		)
		(fp_line
			(start 1.6002 -1.616456)
			(end 2.504948 -1.616456)
			(stroke
				(width 0.1524)
				(type default)
			)
			(layer "F.SilkS")
		)
		(fp_line
			(start 2.286 7.366)
			(end 1.600708 7.366)
			(stroke
				(width 0.1524)
				(type default)
			)
			(layer "F.SilkS")
		)
		(fp_line
			(start 2.286 7.366)
			(end 2.286 1.63195)
			(stroke
				(width 0.1524)
				(type default)
			)
			(layer "F.SilkS")
		)
		(fp_line
			(start 2.504948 -1.616456)
			(end 2.504948 1.633728)
			(stroke
				(width 0.1524)
				(type default)
			)
			(layer "F.SilkS")
		)
		(fp_line
			(start 2.504948 1.633728)
			(end 1.6002 1.633728)
			(stroke
				(width 0.1524)
				(type default)
			)
			(layer "F.SilkS")
		)
		(fp_rect
			(start -2.286 7.366)
			(end 2.286 -0.254)
			(stroke
				(width 0)
				(type default)
			)
			(fill no)
			(layer "F.CrtYd")
		)
		(fp_line
			(start -2.286 -0.254)
			(end 2.286 -0.254)
			(stroke
				(width 0.1)
				(type default)
			)
			(layer "F.Fab")
		)
		(fp_line
			(start -2.286 7.366)
			(end -2.286 -0.254)
			(stroke
				(width 0.1)
				(type default)
			)
			(layer "F.Fab")
		)
		(fp_line
			(start 2.286 -0.254)
			(end 2.286 7.366)
			(stroke
				(width 0.1)
				(type default)
			)
			(layer "F.Fab")
		)
		(fp_line
			(start 2.286 7.366)
			(end -2.286 7.366)
			(stroke
				(width 0.1)
				(type default)
			)
			(layer "F.Fab")
		)
		(pad "1" smd rect
			(at 0 0)
			(size 2.54 3.048)
			(layers "F.Cu" "F.Mask" "F.Paste")
			(net "PVCCIOMCP_CPU1")
		)
		(pad "2" smd rect
			(at 0 7.112)
			(size 2.54 3.048)
			(layers "F.Cu" "F.Mask" "F.Paste")
			(net "GND")
		)
	)
	(footprint ""
		(layer "F.Cu")
		(at 392.557 -88.2015)
		(property "Reference" "R3P62"
			(at 0 0 0)
			(layer "F.SilkS")
			(hide yes)
			(effects
				(font
					(size 1.27 1.27)
				)
			)
		)
		(property "Value" ""
			(at 0 0 0)
			(layer "F.Fab")
			(effects
				(font
					(size 1.27 1.27)
				)
			)
		)
		(duplicate_pad_numbers_are_jumpers no)
		(fp_poly
			(pts
				(xy -0.2794 -0.1016) (xy 0.2794 -0.1016) (xy 0.2794 0.9906) (xy -0.2794 0.9906)
			)
			(stroke
				(width 0)
				(type default)
			)
			(fill no)
			(layer "F.CrtYd")
		)
		(fp_line
			(start -0.2794 -0.1016)
			(end -0.2794 0.9906)
			(stroke
				(width 0.1)
				(type default)
			)
			(layer "F.Fab")
		)
		(fp_line
			(start -0.2794 0.9906)
			(end 0.2794 0.9906)
			(stroke
				(width 0.1)
				(type default)
			)
			(layer "F.Fab")
		)
		(fp_line
			(start 0.2794 -0.1016)
			(end -0.2794 -0.1016)
			(stroke
				(width 0.1)
				(type default)
			)
			(layer "F.Fab")
		)
		(fp_line
			(start 0.2794 0.9906)
			(end 0.2794 -0.1016)
			(stroke
				(width 0.1)
				(type default)
			)
			(layer "F.Fab")
		)
		(pad "1" smd rect
			(at 0 0)
			(size 0.508 0.508)
			(layers "F.Cu" "F.Mask" "F.Paste")
			(net "P3V3_STBY")
		)
		(pad "2" smd rect
			(at 0 0.889)
			(size 0.508 0.508)
			(layers "F.Cu" "F.Mask" "F.Paste")
			(net "FM_FLASH_ATTACH_CFG_STRAP")
		)
		(zone
			(layer "F.Cu")
			(hatch none 0.5)
			(connect_pads
				(clearance 0)
			)
			(min_thickness 0.25)
			(keepout
				(tracks allowed)
				(vias not_allowed)
				(pads allowed)
				(copperpour not_allowed)
				(footprints allowed)
			)
			(placement
				(enabled no)
				(sheetname "")
			)
			(fill
				(thermal_gap 0.5)
				(thermal_bridge_width 0.5)
				(island_removal_mode 0)
			)
			(polygon
				(pts
					(xy 392.303 -87.9475) (xy 392.811 -87.9475) (xy 392.811 -87.5665) (xy 392.303 -87.5665)
				)
			)
		)
		(zone
			(layer "F.Cu")
			(hatch none 0.5)
			(connect_pads
				(clearance 0)
			)
			(min_thickness 0.25)
			(keepout
				(tracks not_allowed)
				(vias allowed)
				(pads allowed)
				(copperpour not_allowed)
				(footprints allowed)
			)
			(placement
				(enabled no)
				(sheetname "")
			)
			(fill
				(thermal_gap 0.5)
				(thermal_bridge_width 0.5)
				(island_removal_mode 0)
			)
			(polygon
				(pts
					(xy 392.303 -87.5665) (xy 392.811 -87.5665) (xy 392.811 -87.9475) (xy 392.303 -87.9475)
				)
			)
		)
	)
	(footprint ""
		(layer "F.Cu")
		(at 29.028136 -22.994366)
		(property "Reference" "R1F5"
			(at 0 0 0)
			(layer "F.SilkS")
			(hide yes)
			(effects
				(font
					(size 1.27 1.27)
				)
			)
		)
		(property "Value" ""
			(at 0 0 0)
			(layer "F.Fab")
			(effects
				(font
					(size 1.27 1.27)
				)
			)
		)
		(duplicate_pad_numbers_are_jumpers no)
		(fp_poly
			(pts
				(xy -0.2794 -0.1016) (xy 0.2794 -0.1016) (xy 0.2794 0.9906) (xy -0.2794 0.9906)
			)
			(stroke
				(width 0)
				(type default)
			)
			(fill no)
			(layer "F.CrtYd")
		)
		(fp_line
			(start -0.2794 -0.1016)
			(end -0.2794 0.9906)
			(stroke
				(width 0.1)
				(type default)
			)
			(layer "F.Fab")
		)
		(fp_line
			(start -0.2794 0.9906)
			(end 0.2794 0.9906)
			(stroke
				(width 0.1)
				(type default)
			)
			(layer "F.Fab")
		)
		(fp_line
			(start 0.2794 -0.1016)
			(end -0.2794 -0.1016)
			(stroke
				(width 0.1)
				(type default)
			)
			(layer "F.Fab")
		)
		(fp_line
			(start 0.2794 0.9906)
			(end 0.2794 -0.1016)
			(stroke
				(width 0.1)
				(type default)
			)
			(layer "F.Fab")
		)
		(pad "1" smd rect
			(at 0 0)
			(size 0.508 0.508)
			(layers "F.Cu" "F.Mask" "F.Paste")
			(net "PVDDQ_GHJ")
		)
		(pad "2" smd rect
			(at 0 0.889)
			(size 0.508 0.508)
			(layers "F.Cu" "F.Mask" "F.Paste")
			(net "M_G_VREF")
		)
		(zone
			(layer "F.Cu")
			(hatch none 0.5)
			(connect_pads
				(clearance 0)
			)
			(min_thickness 0.25)
			(keepout
				(tracks allowed)
				(vias not_allowed)
				(pads allowed)
				(copperpour not_allowed)
				(footprints allowed)
			)
			(placement
				(enabled no)
				(sheetname "")
			)
			(fill
				(thermal_gap 0.5)
				(thermal_bridge_width 0.5)
				(island_removal_mode 0)
			)
			(polygon
				(pts
					(xy 28.774136 -22.740366) (xy 29.282136 -22.740366) (xy 29.282136 -22.359366) (xy 28.774136 -22.359366)
				)
			)
		)
		(zone
			(layer "F.Cu")
			(hatch none 0.5)
			(connect_pads
				(clearance 0)
			)
			(min_thickness 0.25)
			(keepout
				(tracks not_allowed)
				(vias allowed)
				(pads allowed)
				(copperpour not_allowed)
				(footprints allowed)
			)
			(placement
				(enabled no)
				(sheetname "")
			)
			(fill
				(thermal_gap 0.5)
				(thermal_bridge_width 0.5)
				(island_removal_mode 0)
			)
			(polygon
				(pts
					(xy 28.774136 -22.359366) (xy 29.282136 -22.359366) (xy 29.282136 -22.740366) (xy 28.774136 -22.740366)
				)
			)
		)
	)
	(footprint ""
		(layer "F.Cu")
		(at 8.991346 3.786124 -90)
		(property "Reference" "R1G22"
			(at 0 0 270)
			(layer "F.SilkS")
			(hide yes)
			(effects
				(font
					(size 1.27 1.27)
				)
			)
		)
		(property "Value" ""
			(at 0 0 270)
			(layer "F.Fab")
			(effects
				(font
					(size 1.27 1.27)
				)
			)
		)
		(duplicate_pad_numbers_are_jumpers no)
		(fp_poly
			(pts
				(xy -0.2794 -0.1016) (xy 0.2794 -0.1016) (xy 0.2794 0.9906) (xy -0.2794 0.9906)
			)
			(stroke
				(width 0)
				(type default)
			)
			(fill no)
			(layer "F.CrtYd")
		)
		(fp_line
			(start -0.2794 0.9906)
			(end 0.2794 0.9906)
			(stroke
				(width 0.1)
				(type default)
			)
			(layer "F.Fab")
		)
		(fp_line
			(start 0.2794 0.9906)
			(end 0.2794 -0.1016)
			(stroke
				(width 0.1)
				(type default)
			)
			(layer "F.Fab")
		)
		(fp_line
			(start -0.2794 -0.1016)
			(end -0.2794 0.9906)
			(stroke
				(width 0.1)
				(type default)
			)
			(layer "F.Fab")
		)
		(fp_line
			(start 0.2794 -0.1016)
			(end -0.2794 -0.1016)
			(stroke
				(width 0.1)
				(type default)
			)
			(layer "F.Fab")
		)
		(pad "1" smd rect
			(at 0 0 270)
			(size 0.508 0.508)
			(layers "F.Cu" "F.Mask" "F.Paste")
			(net "VR_PVDDQ_GHJ_XADDR2")
		)
		(pad "2" smd rect
			(at 0 0.889 270)
			(size 0.508 0.508)
			(layers "F.Cu" "F.Mask" "F.Paste")
			(net "GND")
		)
		(zone
			(layer "F.Cu")
			(hatch none 0.5)
			(connect_pads
				(clearance 0)
			)
			(min_thickness 0.25)
			(keepout
				(tracks not_allowed)
				(vias allowed)
				(pads allowed)
				(copperpour not_allowed)
				(footprints allowed)
			)
			(placement
				(enabled no)
				(sheetname "")
			)
			(fill
				(thermal_gap 0.5)
				(thermal_bridge_width 0.5)
				(island_removal_mode 0)
			)
			(polygon
				(pts
					(xy 8.356346 3.532124) (xy 8.356346 4.040124) (xy 8.737346 4.040124) (xy 8.737346 3.532124)
				)
			)
		)
		(zone
			(layer "F.Cu")
			(hatch none 0.5)
			(connect_pads
				(clearance 0)
			)
			(min_thickness 0.25)
			(keepout
				(tracks allowed)
				(vias not_allowed)
				(pads allowed)
				(copperpour not_allowed)
				(footprints allowed)
			)
			(placement
				(enabled no)
				(sheetname "")
			)
			(fill
				(thermal_gap 0.5)
				(thermal_bridge_width 0.5)
				(island_removal_mode 0)
			)
			(polygon
				(pts
					(xy 8.737346 3.532124) (xy 8.737346 4.040124) (xy 8.356346 4.040124) (xy 8.356346 3.532124)
				)
			)
		)
	)
	(footprint ""
		(layer "F.Cu")
		(at 477.3041 -41.3004 90)
		(property "Reference" "R9E20"
			(at 0 0 90)
			(layer "F.SilkS")
			(hide yes)
			(effects
				(font
					(size 1.27 1.27)
				)
			)
		)
		(property "Value" ""
			(at 0 0 90)
			(layer "F.Fab")
			(effects
				(font
					(size 1.27 1.27)
				)
			)
		)
		(duplicate_pad_numbers_are_jumpers no)
		(fp_poly
			(pts
				(xy -0.2794 -0.1016) (xy 0.2794 -0.1016) (xy 0.2794 0.9906) (xy -0.2794 0.9906)
			)
			(stroke
				(width 0)
				(type default)
			)
			(fill no)
			(layer "F.CrtYd")
		)
		(fp_line
			(start 0.2794 -0.1016)
			(end -0.2794 -0.1016)
			(stroke
				(width 0.1)
				(type default)
			)
			(layer "F.Fab")
		)
		(fp_line
			(start -0.2794 -0.1016)
			(end -0.2794 0.9906)
			(stroke
				(width 0.1)
				(type default)
			)
			(layer "F.Fab")
		)
		(fp_line
			(start 0.2794 0.9906)
			(end 0.2794 -0.1016)
			(stroke
				(width 0.1)
				(type default)
			)
			(layer "F.Fab")
		)
		(fp_line
			(start -0.2794 0.9906)
			(end 0.2794 0.9906)
			(stroke
				(width 0.1)
				(type default)
			)
			(layer "F.Fab")
		)
		(pad "1" smd rect
			(at 0 0 90)
			(size 0.508 0.508)
			(layers "F.Cu" "F.Mask" "F.Paste")
			(net "XTAL_25MHZ_IN")
		)
		(pad "2" smd rect
			(at 0 0.889 90)
			(size 0.508 0.508)
			(layers "F.Cu" "F.Mask" "F.Paste")
			(net "XTAL_25MHZ_IN_R")
		)
		(zone
			(layer "F.Cu")
			(hatch none 0.5)
			(connect_pads
				(clearance 0)
			)
			(min_thickness 0.25)
			(keepout
				(tracks allowed)
				(vias not_allowed)
				(pads allowed)
				(copperpour not_allowed)
				(footprints allowed)
			)
			(placement
				(enabled no)
				(sheetname "")
			)
			(fill
				(thermal_gap 0.5)
				(thermal_bridge_width 0.5)
				(island_removal_mode 0)
			)
			(polygon
				(pts
					(xy 477.5581 -41.0464) (xy 477.5581 -41.5544) (xy 477.9391 -41.5544) (xy 477.9391 -41.0464)
				)
			)
		)
		(zone
			(layer "F.Cu")
			(hatch none 0.5)
			(connect_pads
				(clearance 0)
			)
			(min_thickness 0.25)
			(keepout
				(tracks not_allowed)
				(vias allowed)
				(pads allowed)
				(copperpour not_allowed)
				(footprints allowed)
			)
			(placement
				(enabled no)
				(sheetname "")
			)
			(fill
				(thermal_gap 0.5)
				(thermal_bridge_width 0.5)
				(island_removal_mode 0)
			)
			(polygon
				(pts
					(xy 477.9391 -41.0464) (xy 477.9391 -41.5544) (xy 477.5581 -41.5544) (xy 477.5581 -41.0464)
				)
			)
		)
	)
	(footprint ""
		(layer "F.Cu")
		(at 333.6798 -25.2603 90)
		(property "Reference" "R7F10"
			(at 0 0 90)
			(layer "F.SilkS")
			(hide yes)
			(effects
				(font
					(size 1.27 1.27)
				)
			)
		)
		(property "Value" ""
			(at 0 0 90)
			(layer "F.Fab")
			(effects
				(font
					(size 1.27 1.27)
				)
			)
		)
		(duplicate_pad_numbers_are_jumpers no)
		(fp_poly
			(pts
				(xy -0.4953 -0.2032) (xy 0.4953 -0.2032) (xy 0.4953 1.6002) (xy -0.4953 1.6002)
			)
			(stroke
				(width 0)
				(type default)
			)
			(fill no)
			(layer "F.CrtYd")
		)
		(fp_line
			(start 0.4953 -0.2032)
			(end 0.4953 1.6002)
			(stroke
				(width 0.1)
				(type default)
			)
			(layer "F.Fab")
		)
		(fp_line
			(start -0.4953 -0.2032)
			(end 0.4953 -0.2032)
			(stroke
				(width 0.1)
				(type default)
			)
			(layer "F.Fab")
		)
		(fp_line
			(start 0.4953 1.6002)
			(end -0.4953 1.6002)
			(stroke
				(width 0.1)
				(type default)
			)
			(layer "F.Fab")
		)
		(fp_line
			(start -0.4953 1.6002)
			(end -0.4953 -0.2032)
			(stroke
				(width 0.1)
				(type default)
			)
			(layer "F.Fab")
		)
		(pad "1" smd rect
			(at 0 0 90)
			(size 0.762 0.889)
			(layers "F.Cu" "F.Mask" "F.Paste")
			(net "PVPP_ABC")
		)
		(pad "2" smd rect
			(at 0 1.397 90)
			(size 0.762 0.889)
			(layers "F.Cu" "F.Mask" "F.Paste")
			(net "GND")
		)
		(zone
			(layer "F.Cu")
			(hatch none 0.5)
			(connect_pads
				(clearance 0)
			)
			(min_thickness 0.25)
			(keepout
				(tracks allowed)
				(vias not_allowed)
				(pads allowed)
				(copperpour not_allowed)
				(footprints allowed)
			)
			(placement
				(enabled no)
				(sheetname "")
			)
			(fill
				(thermal_gap 0.5)
				(thermal_bridge_width 0.5)
				(island_removal_mode 0)
			)
			(polygon
				(pts
					(xy 334.6323 -25.6413) (xy 334.1243 -25.6413) (xy 334.1243 -24.8793) (xy 334.6323 -24.8793)
				)
			)
		)
		(zone
			(layer "F.Cu")
			(hatch none 0.5)
			(connect_pads
				(clearance 0)
			)
			(min_thickness 0.25)
			(keepout
				(tracks not_allowed)
				(vias allowed)
				(pads allowed)
				(copperpour not_allowed)
				(footprints allowed)
			)
			(placement
				(enabled no)
				(sheetname "")
			)
			(fill
				(thermal_gap 0.5)
				(thermal_bridge_width 0.5)
				(island_removal_mode 0)
			)
			(polygon
				(pts
					(xy 334.6323 -24.8793) (xy 334.6323 -25.6413) (xy 334.1243 -25.6413) (xy 334.1243 -24.8793)
				)
			)
		)
	)
	(footprint ""
		(layer "F.Cu")
		(at 272.24101 -84.890102)
		(property "Reference" "C5D4"
			(at 0 0 0)
			(layer "F.SilkS")
			(hide yes)
			(effects
				(font
					(size 1.27 1.27)
				)
			)
		)
		(property "Value" ""
			(at 0 0 0)
			(layer "F.Fab")
			(effects
				(font
					(size 1.27 1.27)
				)
			)
		)
		(duplicate_pad_numbers_are_jumpers no)
		(fp_poly
			(pts
				(xy -0.4953 -0.2032) (xy 0.4953 -0.2032) (xy 0.4953 1.6002) (xy -0.4953 1.6002)
			)
			(stroke
				(width 0)
				(type default)
			)
			(fill no)
			(layer "F.CrtYd")
		)
		(fp_line
			(start -0.4953 -0.2032)
			(end 0.4953 -0.2032)
			(stroke
				(width 0.1)
				(type default)
			)
			(layer "F.Fab")
		)
		(fp_line
			(start -0.4953 1.6002)
			(end -0.4953 -0.2032)
			(stroke
				(width 0.1)
				(type default)
			)
			(layer "F.Fab")
		)
		(fp_line
			(start 0.4953 -0.2032)
			(end 0.4953 1.6002)
			(stroke
				(width 0.1)
				(type default)
			)
			(layer "F.Fab")
		)
		(fp_line
			(start 0.4953 1.6002)
			(end -0.4953 1.6002)
			(stroke
				(width 0.1)
				(type default)
			)
			(layer "F.Fab")
		)
		(pad "1" smd rect
			(at 0 0)
			(size 0.762 0.889)
			(layers "F.Cu" "F.Mask" "F.Paste")
			(net "PVDDQ_DEF")
		)
		(pad "2" smd rect
			(at 0 1.397)
			(size 0.762 0.889)
			(layers "F.Cu" "F.Mask" "F.Paste")
			(net "GND")
		)
		(zone
			(layer "F.Cu")
			(hatch none 0.5)
			(connect_pads
				(clearance 0)
			)
			(min_thickness 0.25)
			(keepout
				(tracks not_allowed)
				(vias allowed)
				(pads allowed)
				(copperpour not_allowed)
				(footprints allowed)
			)
			(placement
				(enabled no)
				(sheetname "")
			)
			(fill
				(thermal_gap 0.5)
				(thermal_bridge_width 0.5)
				(island_removal_mode 0)
			)
			(polygon
				(pts
					(xy 271.86001 -84.445602) (xy 272.62201 -84.445602) (xy 272.62201 -83.937602) (xy 271.86001 -83.937602)
				)
			)
		)
	)
	(footprint ""
		(layer "F.Cu")
		(at 8.818626 -3.357118 180)
		(property "Reference" "R12W33"
			(at -0.8382 -0.67818 180)
			(unlocked yes)
			(layer "F.SilkS")
			(effects
				(font
					(size 0.4064 0.254)
					(thickness 0.1524)
				)
				(justify left)
			)
		)
		(property "Value" ""
			(at 0 0 180)
			(layer "F.Fab")
			(effects
				(font
					(size 1.27 1.27)
				)
			)
		)
		(duplicate_pad_numbers_are_jumpers no)
		(fp_poly
			(pts
				(xy -0.2794 -0.1016) (xy 0.2794 -0.1016) (xy 0.2794 0.9906) (xy -0.2794 0.9906)
			)
			(stroke
				(width 0)
				(type default)
			)
			(fill no)
			(layer "F.CrtYd")
		)
		(fp_line
			(start 0.2794 0.9906)
			(end 0.2794 -0.1016)
			(stroke
				(width 0.1)
				(type default)
			)
			(layer "F.Fab")
		)
		(fp_line
			(start 0.2794 -0.1016)
			(end -0.2794 -0.1016)
			(stroke
				(width 0.1)
				(type default)
			)
			(layer "F.Fab")
		)
		(fp_line
			(start -0.2794 0.9906)
			(end 0.2794 0.9906)
			(stroke
				(width 0.1)
				(type default)
			)
			(layer "F.Fab")
		)
		(fp_line
			(start -0.2794 -0.1016)
			(end -0.2794 0.9906)
			(stroke
				(width 0.1)
				(type default)
			)
			(layer "F.Fab")
		)
		(pad "1" smd rect
			(at 0 0 180)
			(size 0.508 0.508)
			(layers "F.Cu" "F.Mask" "F.Paste")
			(net "TP_PVDDQ_GHJ_MP2")
		)
		(pad "2" smd rect
			(at 0 0.889 180)
			(size 0.508 0.508)
			(layers "F.Cu" "F.Mask" "F.Paste")
			(net "PWRGD_PVDDQ_GHJ")
		)
		(zone
			(layer "F.Cu")
			(hatch none 0.5)
			(connect_pads
				(clearance 0)
			)
			(min_thickness 0.25)
			(keepout
				(tracks not_allowed)
				(vias allowed)
				(pads allowed)
				(copperpour not_allowed)
				(footprints allowed)
			)
			(placement
				(enabled no)
				(sheetname "")
			)
			(fill
				(thermal_gap 0.5)
				(thermal_bridge_width 0.5)
				(island_removal_mode 0)
			)
			(polygon
				(pts
					(xy 9.072626 -3.992118) (xy 8.564626 -3.992118) (xy 8.564626 -3.611118) (xy 9.072626 -3.611118)
				)
			)
		)
		(zone
			(layer "F.Cu")
			(hatch none 0.5)
			(connect_pads
				(clearance 0)
			)
			(min_thickness 0.25)
			(keepout
				(tracks allowed)
				(vias not_allowed)
				(pads allowed)
				(copperpour not_allowed)
				(footprints allowed)
			)
			(placement
				(enabled no)
				(sheetname "")
			)
			(fill
				(thermal_gap 0.5)
				(thermal_bridge_width 0.5)
				(island_removal_mode 0)
			)
			(polygon
				(pts
					(xy 9.072626 -3.611118) (xy 8.564626 -3.611118) (xy 8.564626 -3.992118) (xy 9.072626 -3.992118)
				)
			)
		)
	)
	(footprint ""
		(layer "F.Cu")
		(at -0.3302 -19.2151 90)
		(property "Reference" "C1F26"
			(at 0 0 90)
			(layer "F.SilkS")
			(hide yes)
			(effects
				(font
					(size 1.27 1.27)
				)
			)
		)
		(property "Value" ""
			(at 0 0 90)
			(layer "F.Fab")
			(effects
				(font
					(size 1.27 1.27)
				)
			)
		)
		(duplicate_pad_numbers_are_jumpers no)
		(fp_poly
			(pts
				(xy 0.3048 -0.1016) (xy 0.3048 0.9906) (xy -0.3048 0.9906) (xy -0.3048 -0.1016)
			)
			(stroke
				(width 0)
				(type default)
			)
			(fill no)
			(layer "F.CrtYd")
		)
		(fp_line
			(start 0.3048 -0.1016)
			(end -0.3048 -0.1016)
			(stroke
				(width 0.1)
				(type default)
			)
			(layer "F.Fab")
		)
		(fp_line
			(start -0.3048 -0.1016)
			(end -0.3048 0.9906)
			(stroke
				(width 0.1)
				(type default)
			)
			(layer "F.Fab")
		)
		(fp_line
			(start 0.3048 0.9906)
			(end 0.3048 -0.1016)
			(stroke
				(width 0.1)
				(type default)
			)
			(layer "F.Fab")
		)
		(fp_line
			(start -0.3048 0.9906)
			(end 0.3048 0.9906)
			(stroke
				(width 0.1)
				(type default)
			)
			(layer "F.Fab")
		)
		(pad "1" smd rect
			(at 0 0 90)
			(size 0.508 0.508)
			(layers "F.Cu" "F.Mask" "F.Paste")
			(net "VR_PVDDQ_GHJ_PH2_BOOT")
		)
		(pad "2" smd rect
			(at 0 0.889 90)
			(size 0.508 0.508)
			(layers "F.Cu" "F.Mask" "F.Paste")
			(net "VR_PVDDQ_GHJ_PH2_PHASE")
		)
		(zone
			(layer "F.Cu")
			(hatch none 0.5)
			(connect_pads
				(clearance 0)
			)
			(min_thickness 0.25)
			(keepout
				(tracks allowed)
				(vias not_allowed)
				(pads allowed)
				(copperpour not_allowed)
				(footprints allowed)
			)
			(placement
				(enabled no)
				(sheetname "")
			)
			(fill
				(thermal_gap 0.5)
				(thermal_bridge_width 0.5)
				(island_removal_mode 0)
			)
			(polygon
				(pts
					(xy -0.0762 -18.9611) (xy -0.0762 -19.4691) (xy 0.3048 -19.4691) (xy 0.3048 -18.9611)
				)
			)
		)
		(zone
			(layer "F.Cu")
			(hatch none 0.5)
			(connect_pads
				(clearance 0)
			)
			(min_thickness 0.25)
			(keepout
				(tracks not_allowed)
				(vias allowed)
				(pads allowed)
				(copperpour not_allowed)
				(footprints allowed)
			)
			(placement
				(enabled no)
				(sheetname "")
			)
			(fill
				(thermal_gap 0.5)
				(thermal_bridge_width 0.5)
				(island_removal_mode 0)
			)
			(polygon
				(pts
					(xy 0.3048 -18.9611) (xy 0.3048 -19.4691) (xy -0.0762 -19.4691) (xy -0.0762 -18.9611)
				)
			)
		)
	)
	(footprint ""
		(layer "F.Cu")
		(at 173.609 -3.683 90)
		(property "Reference" "C4G18"
			(at 0 0 90)
			(layer "F.SilkS")
			(hide yes)
			(effects
				(font
					(size 1.27 1.27)
				)
			)
		)
		(property "Value" ""
			(at 0 0 90)
			(layer "F.Fab")
			(effects
				(font
					(size 1.27 1.27)
				)
			)
		)
		(duplicate_pad_numbers_are_jumpers no)
		(fp_rect
			(start 0.3048 0.9906)
			(end -0.3048 -0.1016)
			(stroke
				(width 0)
				(type default)
			)
			(fill no)
			(layer "F.CrtYd")
		)
		(fp_line
			(start 0.3048 -0.1016)
			(end -0.3048 -0.1016)
			(stroke
				(width 0.1)
				(type default)
			)
			(layer "F.Fab")
		)
		(fp_line
			(start -0.3048 -0.1016)
			(end -0.3048 0.9906)
			(stroke
				(width 0.1)
				(type default)
			)
			(layer "F.Fab")
		)
		(fp_line
			(start 0.3048 0.9906)
			(end 0.3048 -0.1016)
			(stroke
				(width 0.1)
				(type default)
			)
			(layer "F.Fab")
		)
		(fp_line
			(start -0.3048 0.9906)
			(end 0.3048 0.9906)
			(stroke
				(width 0.1)
				(type default)
			)
			(layer "F.Fab")
		)
		(pad "1" smd rect
			(at 0 0 90)
			(size 0.508 0.508)
			(layers "F.Cu" "F.Mask" "F.Paste")
			(net "VR_PVTT_GHJ_BIAS")
		)
		(pad "2" smd rect
			(at 0 0.889 90)
			(size 0.508 0.508)
			(layers "F.Cu" "F.Mask" "F.Paste")
			(net "GND")
		)
		(zone
			(layer "F.Cu")
			(hatch none 0.5)
			(connect_pads
				(clearance 0)
			)
			(min_thickness 0.25)
			(keepout
				(tracks allowed)
				(vias not_allowed)
				(pads allowed)
				(copperpour not_allowed)
				(footprints allowed)
			)
			(placement
				(enabled no)
				(sheetname "")
			)
			(fill
				(thermal_gap 0.5)
				(thermal_bridge_width 0.5)
				(island_removal_mode 0)
			)
			(polygon
				(pts
					(xy 174.244 -3.937) (xy 173.863 -3.937) (xy 173.863 -3.429) (xy 174.244 -3.429)
				)
			)
		)
		(zone
			(layer "F.Cu")
			(hatch none 0.5)
			(connect_pads
				(clearance 0)
			)
			(min_thickness 0.25)
			(keepout
				(tracks not_allowed)
				(vias allowed)
				(pads allowed)
				(copperpour not_allowed)
				(footprints allowed)
			)
			(placement
				(enabled no)
				(sheetname "")
			)
			(fill
				(thermal_gap 0.5)
				(thermal_bridge_width 0.5)
				(island_removal_mode 0)
			)
			(polygon
				(pts
					(xy 174.244 -3.937) (xy 173.863 -3.937) (xy 173.863 -3.429) (xy 174.244 -3.429)
				)
			)
		)
	)
	(footprint ""
		(layer "F.Cu")
		(at 478.1931 -40.4114 -90)
		(property "Reference" "R9E23"
			(at 0 0 270)
			(layer "F.SilkS")
			(hide yes)
			(effects
				(font
					(size 1.27 1.27)
				)
			)
		)
		(property "Value" ""
			(at 0 0 270)
			(layer "F.Fab")
			(effects
				(font
					(size 1.27 1.27)
				)
			)
		)
		(duplicate_pad_numbers_are_jumpers no)
		(fp_poly
			(pts
				(xy -0.2794 -0.1016) (xy 0.2794 -0.1016) (xy 0.2794 0.9906) (xy -0.2794 0.9906)
			)
			(stroke
				(width 0)
				(type default)
			)
			(fill no)
			(layer "F.CrtYd")
		)
		(fp_line
			(start -0.2794 0.9906)
			(end 0.2794 0.9906)
			(stroke
				(width 0.1)
				(type default)
			)
			(layer "F.Fab")
		)
		(fp_line
			(start 0.2794 0.9906)
			(end 0.2794 -0.1016)
			(stroke
				(width 0.1)
				(type default)
			)
			(layer "F.Fab")
		)
		(fp_line
			(start -0.2794 -0.1016)
			(end -0.2794 0.9906)
			(stroke
				(width 0.1)
				(type default)
			)
			(layer "F.Fab")
		)
		(fp_line
			(start 0.2794 -0.1016)
			(end -0.2794 -0.1016)
			(stroke
				(width 0.1)
				(type default)
			)
			(layer "F.Fab")
		)
		(pad "1" smd rect
			(at 0 0 270)
			(size 0.508 0.508)
			(layers "F.Cu" "F.Mask" "F.Paste")
			(net "PD_SPRV_RSET")
		)
		(pad "2" smd rect
			(at 0 0.889 270)
			(size 0.508 0.508)
			(layers "F.Cu" "F.Mask" "F.Paste")
			(net "GND")
		)
		(zone
			(layer "F.Cu")
			(hatch none 0.5)
			(connect_pads
				(clearance 0)
			)
			(min_thickness 0.25)
			(keepout
				(tracks not_allowed)
				(vias allowed)
				(pads allowed)
				(copperpour not_allowed)
				(footprints allowed)
			)
			(placement
				(enabled no)
				(sheetname "")
			)
			(fill
				(thermal_gap 0.5)
				(thermal_bridge_width 0.5)
				(island_removal_mode 0)
			)
			(polygon
				(pts
					(xy 477.5581 -40.6654) (xy 477.5581 -40.1574) (xy 477.9391 -40.1574) (xy 477.9391 -40.6654)
				)
			)
		)
		(zone
			(layer "F.Cu")
			(hatch none 0.5)
			(connect_pads
				(clearance 0)
			)
			(min_thickness 0.25)
			(keepout
				(tracks allowed)
				(vias not_allowed)
				(pads allowed)
				(copperpour not_allowed)
				(footprints allowed)
			)
			(placement
				(enabled no)
				(sheetname "")
			)
			(fill
				(thermal_gap 0.5)
				(thermal_bridge_width 0.5)
				(island_removal_mode 0)
			)
			(polygon
				(pts
					(xy 477.9391 -40.6654) (xy 477.9391 -40.1574) (xy 477.5581 -40.1574) (xy 477.5581 -40.6654)
				)
			)
		)
	)
	(footprint ""
		(layer "F.Cu")
		(at 395.7828 -153.797 90)
		(property "Reference" "EU8A1"
			(at 3.40233 -2.7178 0)
			(unlocked yes)
			(layer "F.SilkS")
			(effects
				(font
					(size 0.7874 0.5842)
					(thickness 0.1524)
				)
				(justify left)
			)
		)
		(property "Value" ""
			(at 0 0 90)
			(layer "F.Fab")
			(effects
				(font
					(size 1.27 1.27)
				)
			)
		)
		(duplicate_pad_numbers_are_jumpers no)
		(fp_line
			(start 3.0607 -3.0607)
			(end 3.0607 3.0607)
			(stroke
				(width 0.1524)
				(type default)
			)
			(layer "F.SilkS")
		)
		(fp_line
			(start -3.0607 -3.0607)
			(end 3.0607 -3.0607)
			(stroke
				(width 0.1524)
				(type default)
			)
			(layer "F.SilkS")
		)
		(fp_line
			(start 2.549906 -2.549906)
			(end 2.549906 -2.258314)
			(stroke
				(width 0.1524)
				(type default)
			)
			(layer "F.SilkS")
		)
		(fp_line
			(start 2.245614 -2.549906)
			(end 2.549906 -2.549906)
			(stroke
				(width 0.1524)
				(type default)
			)
			(layer "F.SilkS")
		)
		(fp_line
			(start -2.549906 -2.549906)
			(end -2.249678 -2.549906)
			(stroke
				(width 0.1524)
				(type default)
			)
			(layer "F.SilkS")
		)
		(fp_line
			(start -2.549906 -2.29362)
			(end -2.549906 -2.549906)
			(stroke
				(width 0.1524)
				(type default)
			)
			(layer "F.SilkS")
		)
		(fp_line
			(start 2.549906 2.233422)
			(end 2.549906 2.549906)
			(stroke
				(width 0.1524)
				(type default)
			)
			(layer "F.SilkS")
		)
		(fp_line
			(start 2.549906 2.549906)
			(end 2.249678 2.549906)
			(stroke
				(width 0.1524)
				(type default)
			)
			(layer "F.SilkS")
		)
		(fp_line
			(start -2.277618 2.549906)
			(end -2.549906 2.549906)
			(stroke
				(width 0.1524)
				(type default)
			)
			(layer "F.SilkS")
		)
		(fp_line
			(start -2.549906 2.549906)
			(end -2.549906 2.267204)
			(stroke
				(width 0.1524)
				(type default)
			)
			(layer "F.SilkS")
		)
		(fp_line
			(start 3.0607 3.0607)
			(end -3.0607 3.0607)
			(stroke
				(width 0.1524)
				(type default)
			)
			(layer "F.SilkS")
		)
		(fp_line
			(start -3.0607 3.0607)
			(end -3.0607 -3.0607)
			(stroke
				(width 0.1524)
				(type default)
			)
			(layer "F.SilkS")
		)
		(fp_circle
			(center -3.237738 -2.256536)
			(end -3.237738 -2.129536)
			(stroke
				(width 0.254)
				(type default)
			)
			(fill no)
			(layer "F.SilkS")
		)
		(fp_poly
			(pts
				(xy -3.0607 -3.0607) (xy -3.0607 -2.0193) (xy -2.0193 -3.0607)
			)
			(stroke
				(width 0)
				(type default)
			)
			(fill yes)
			(layer "F.SilkS")
		)
		(fp_rect
			(start -1.8415 1.8415)
			(end 1.8415 -1.8415)
			(stroke
				(width 0)
				(type default)
			)
			(fill yes)
			(layer "F.Paste")
		)
		(fp_rect
			(start -2.549906 2.549906)
			(end 2.549906 -2.549906)
			(stroke
				(width 0)
				(type default)
			)
			(fill no)
			(layer "F.CrtYd")
		)
		(fp_line
			(start 2.549906 -2.549906)
			(end 2.549906 2.549906)
			(stroke
				(width 0.1)
				(type default)
			)
			(layer "F.Fab")
		)
		(fp_line
			(start -2.549906 -2.549906)
			(end 2.549906 -2.549906)
			(stroke
				(width 0.1)
				(type default)
			)
			(layer "F.Fab")
		)
		(fp_line
			(start 2.549906 2.549906)
			(end -2.549906 2.549906)
			(stroke
				(width 0.1)
				(type default)
			)
			(layer "F.Fab")
		)
		(fp_line
			(start -2.549906 2.549906)
			(end -2.549906 -2.549906)
			(stroke
				(width 0.1)
				(type default)
			)
			(layer "F.Fab")
		)
		(fp_circle
			(center -3.237738 -2.256536)
			(end -3.237738 -2.129536)
			(stroke
				(width 0.254)
				(type default)
			)
			(fill no)
			(layer "F.Fab")
		)
		(pad "1" smd custom
			(at -2.4511 -1.800098 90)
			(size 0.0508 0.0508)
			(layers "F.Cu" "F.Mask" "F.Paste")
			(net "Net_351")
			(options
				(clearance outline)
				(anchor circle)
			)
			(primitives
				(gr_poly
					(pts
						(arc
							(start 0.254 -0.1016)
							(mid 0.3556 0)
							(end 0.254 0.1016)
						)
						(xy -0.3556 0.1016) (xy -0.3556 -0.1016)
					)
					(width 0)
					(fill yes)
				)
			)
		)
		(pad "2" smd custom
			(at -2.4511 -1.400048 90)
			(size 0.0508 0.0508)
			(layers "F.Cu" "F.Mask" "F.Paste")
			(net "Net_352")
			(options
				(clearance outline)
				(anchor circle)
			)
			(primitives
				(gr_poly
					(pts
						(arc
							(start 0.254 -0.1016)
							(mid 0.3556 0)
							(end 0.254 0.1016)
						)
						(xy -0.3556 0.1016) (xy -0.3556 -0.1016)
					)
					(width 0)
					(fill yes)
				)
			)
		)
		(pad "3" smd custom
			(at -2.4511 -0.999998 90)
			(size 0.0508 0.0508)
			(layers "F.Cu" "F.Mask" "F.Paste")
			(net "VR_P1V05_PCH_STBY_PWM1")
			(options
				(clearance outline)
				(anchor circle)
			)
			(primitives
				(gr_poly
					(pts
						(arc
							(start 0.254 -0.1016)
							(mid 0.3556 0)
							(end 0.254 0.1016)
						)
						(xy -0.3556 0.1016) (xy -0.3556 -0.1016)
					)
					(width 0)
					(fill yes)
				)
			)
		)
		(pad "4" smd custom
			(at -2.4511 -0.599948 90)
			(size 0.0508 0.0508)
			(layers "F.Cu" "F.Mask" "F.Paste")
			(net "Net_353")
			(options
				(clearance outline)
				(anchor circle)
			)
			(primitives
				(gr_poly
					(pts
						(arc
							(start 0.254 -0.1016)
							(mid 0.3556 0)
							(end 0.254 0.1016)
						)
						(xy -0.3556 0.1016) (xy -0.3556 -0.1016)
					)
					(width 0)
					(fill yes)
				)
			)
		)
		(pad "5" smd custom
			(at -2.4511 -0.199898 90)
			(size 0.0508 0.0508)
			(layers "F.Cu" "F.Mask" "F.Paste")
			(net "VR_PVNN_PCH_PWM1")
			(options
				(clearance outline)
				(anchor circle)
			)
			(primitives
				(gr_poly
					(pts
						(arc
							(start 0.254 -0.1016)
							(mid 0.3556 0)
							(end 0.254 0.1016)
						)
						(xy -0.3556 0.1016) (xy -0.3556 -0.1016)
					)
					(width 0)
					(fill yes)
				)
			)
		)
		(pad "6" smd custom
			(at -2.4511 0.199898 90)
			(size 0.0508 0.0508)
			(layers "F.Cu" "F.Mask" "F.Paste")
			(net "SMB_VR_STBY_LVC3_SDA")
			(options
				(clearance outline)
				(anchor circle)
			)
			(primitives
				(gr_poly
					(pts
						(arc
							(start 0.254 -0.1016)
							(mid 0.3556 0)
							(end 0.254 0.1016)
						)
						(xy -0.3556 0.1016) (xy -0.3556 -0.1016)
					)
					(width 0)
					(fill yes)
				)
			)
		)
		(pad "7" smd custom
			(at -2.4511 0.599948 90)
			(size 0.0508 0.0508)
			(layers "F.Cu" "F.Mask" "F.Paste")
			(net "SMB_VR_STBY_LVC3_SCL")
			(options
				(clearance outline)
				(anchor circle)
			)
			(primitives
				(gr_poly
					(pts
						(arc
							(start 0.254 -0.1016)
							(mid 0.3556 0)
							(end 0.254 0.1016)
						)
						(xy -0.3556 0.1016) (xy -0.3556 -0.1016)
					)
					(width 0)
					(fill yes)
				)
			)
		)
		(pad "8" smd custom
			(at -2.4511 0.999998 90)
			(size 0.0508 0.0508)
			(layers "F.Cu" "F.Mask" "F.Paste")
			(net "Net_289")
			(options
				(clearance outline)
				(anchor circle)
			)
			(primitives
				(gr_poly
					(pts
						(arc
							(start 0.254 -0.1016)
							(mid 0.3556 0)
							(end 0.254 0.1016)
						)
						(xy -0.3556 0.1016) (xy -0.3556 -0.1016)
					)
					(width 0)
					(fill yes)
				)
			)
		)
		(pad "9" smd custom
			(at -2.4511 1.400048 90)
			(size 0.0508 0.0508)
			(layers "F.Cu" "F.Mask" "F.Paste")
			(net "PWRGD_PVNN_PCH_R")
			(options
				(clearance outline)
				(anchor circle)
			)
			(primitives
				(gr_poly
					(pts
						(arc
							(start 0.254 -0.1016)
							(mid 0.3556 0)
							(end 0.254 0.1016)
						)
						(xy -0.3556 0.1016) (xy -0.3556 -0.1016)
					)
					(width 0)
					(fill yes)
				)
			)
		)
		(pad "10" smd custom
			(at -2.4511 1.800098 90)
			(size 0.0508 0.0508)
			(layers "F.Cu" "F.Mask" "F.Paste")
			(net "VR_PVNN_PCH_VREN")
			(options
				(clearance outline)
				(anchor circle)
			)
			(primitives
				(gr_poly
					(pts
						(arc
							(start 0.254 -0.1016)
							(mid 0.3556 0)
							(end 0.254 0.1016)
						)
						(xy -0.3556 0.1016) (xy -0.3556 -0.1016)
					)
					(width 0)
					(fill yes)
				)
			)
		)
		(pad "11" smd custom
			(at -1.800098 2.4511 90)
			(size 0.0508 0.0508)
			(layers "F.Cu" "F.Mask" "F.Paste")
			(net "IRQ_PVNN_PCH_VRHOT_N")
			(options
				(clearance outline)
				(anchor circle)
			)
			(primitives
				(gr_poly
					(pts
						(arc
							(start -0.1016 -0.254)
							(mid 0 -0.3556)
							(end 0.1016 -0.254)
						)
						(xy 0.1016 0.3556) (xy -0.1016 0.3556)
					)
					(width 0)
					(fill yes)
				)
			)
		)
		(pad "12" smd custom
			(at -1.400048 2.4511 90)
			(size 0.0508 0.0508)
			(layers "F.Cu" "F.Mask" "F.Paste")
			(net "PU_PVNN_PCH_PINALRT_N")
			(options
				(clearance outline)
				(anchor circle)
			)
			(primitives
				(gr_poly
					(pts
						(arc
							(start -0.1016 -0.254)
							(mid 0 -0.3556)
							(end 0.1016 -0.254)
						)
						(xy 0.1016 0.3556) (xy -0.1016 0.3556)
					)
					(width 0)
					(fill yes)
				)
			)
		)
		(pad "13" smd custom
			(at -0.999998 2.4511 90)
			(size 0.0508 0.0508)
			(layers "F.Cu" "F.Mask" "F.Paste")
			(net "VID_PCH_CORE_PVNN_AUX_VID_0")
			(options
				(clearance outline)
				(anchor circle)
			)
			(primitives
				(gr_poly
					(pts
						(arc
							(start -0.1016 -0.254)
							(mid 0 -0.3556)
							(end 0.1016 -0.254)
						)
						(xy 0.1016 0.3556) (xy -0.1016 0.3556)
					)
					(width 0)
					(fill yes)
				)
			)
		)
		(pad "14" smd custom
			(at -0.599948 2.4511 90)
			(size 0.0508 0.0508)
			(layers "F.Cu" "F.Mask" "F.Paste")
			(net "VID_PCH_CORE_PVNN_AUX_VID_1")
			(options
				(clearance outline)
				(anchor circle)
			)
			(primitives
				(gr_poly
					(pts
						(arc
							(start -0.1016 -0.254)
							(mid 0 -0.3556)
							(end 0.1016 -0.254)
						)
						(xy 0.1016 0.3556) (xy -0.1016 0.3556)
					)
					(width 0)
					(fill yes)
				)
			)
		)
		(pad "15" smd custom
			(at -0.199898 2.4511 90)
			(size 0.0508 0.0508)
			(layers "F.Cu" "F.Mask" "F.Paste")
			(net "PU_PVNN_PCH_VCLK")
			(options
				(clearance outline)
				(anchor circle)
			)
			(primitives
				(gr_poly
					(pts
						(arc
							(start -0.1016 -0.254)
							(mid 0 -0.3556)
							(end 0.1016 -0.254)
						)
						(xy 0.1016 0.3556) (xy -0.1016 0.3556)
					)
					(width 0)
					(fill yes)
				)
			)
		)
		(pad "16" smd custom
			(at 0.199898 2.4511 90)
			(size 0.0508 0.0508)
			(layers "F.Cu" "F.Mask" "F.Paste")
			(net "PU_PVNN_PCH_VDIO")
			(options
				(clearance outline)
				(anchor circle)
			)
			(primitives
				(gr_poly
					(pts
						(arc
							(start -0.1016 -0.254)
							(mid 0 -0.3556)
							(end 0.1016 -0.254)
						)
						(xy 0.1016 0.3556) (xy -0.1016 0.3556)
					)
					(width 0)
					(fill yes)
				)
			)
		)
		(pad "17" smd custom
			(at 0.599948 2.4511 90)
			(size 0.0508 0.0508)
			(layers "F.Cu" "F.Mask" "F.Paste")
			(net "Net_267")
			(options
				(clearance outline)
				(anchor circle)
			)
			(primitives
				(gr_poly
					(pts
						(arc
							(start -0.1016 -0.254)
							(mid 0 -0.3556)
							(end 0.1016 -0.254)
						)
						(xy 0.1016 0.3556) (xy -0.1016 0.3556)
					)
					(width 0)
					(fill yes)
				)
			)
		)
		(pad "18" smd custom
			(at 0.999998 2.4511 90)
			(size 0.0508 0.0508)
			(layers "F.Cu" "F.Mask" "F.Paste")
			(net "Net_298")
			(options
				(clearance outline)
				(anchor circle)
			)
			(primitives
				(gr_poly
					(pts
						(arc
							(start -0.1016 -0.254)
							(mid 0 -0.3556)
							(end 0.1016 -0.254)
						)
						(xy 0.1016 0.3556) (xy -0.1016 0.3556)
					)
					(width 0)
					(fill yes)
				)
			)
		)
		(pad "19" smd custom
			(at 1.400048 2.4511 90)
			(size 0.0508 0.0508)
			(layers "F.Cu" "F.Mask" "F.Paste")
			(net "VR_PVNN_PCH_AVSP")
			(options
				(clearance outline)
				(anchor circle)
			)
			(primitives
				(gr_poly
					(pts
						(arc
							(start -0.1016 -0.254)
							(mid 0 -0.3556)
							(end 0.1016 -0.254)
						)
						(xy 0.1016 0.3556) (xy -0.1016 0.3556)
					)
					(width 0)
					(fill yes)
				)
			)
		)
		(pad "20" smd custom
			(at 1.800098 2.4511 90)
			(size 0.0508 0.0508)
			(layers "F.Cu" "F.Mask" "F.Paste")
			(net "VSENSE_PVNN_PCH_STBY_AVSN")
			(options
				(clearance outline)
				(anchor circle)
			)
			(primitives
				(gr_poly
					(pts
						(arc
							(start -0.1016 -0.254)
							(mid 0 -0.3556)
							(end 0.1016 -0.254)
						)
						(xy 0.1016 0.3556) (xy -0.1016 0.3556)
					)
					(width 0)
					(fill yes)
				)
			)
		)
		(pad "21" smd custom
			(at 2.4511 1.800098 90)
			(size 0.0508 0.0508)
			(layers "F.Cu" "F.Mask" "F.Paste")
			(net "VR_PVNN_PCH_AIREF1")
			(options
				(clearance outline)
				(anchor circle)
			)
			(primitives
				(gr_poly
					(pts
						(arc
							(start -0.254 0.1016)
							(mid -0.3556 0)
							(end -0.254 -0.1016)
						)
						(xy 0.3556 -0.1016) (xy 0.3556 0.1016)
					)
					(width 0)
					(fill yes)
				)
			)
		)
		(pad "22" smd custom
			(at 2.4511 1.400048 90)
			(size 0.0508 0.0508)
			(layers "F.Cu" "F.Mask" "F.Paste")
			(net "ISENSE_PVNN_PCH_PH1_IMON")
			(options
				(clearance outline)
				(anchor circle)
			)
			(primitives
				(gr_poly
					(pts
						(arc
							(start -0.254 0.1016)
							(mid -0.3556 0)
							(end -0.254 -0.1016)
						)
						(xy 0.3556 -0.1016) (xy 0.3556 0.1016)
					)
					(width 0)
					(fill yes)
				)
			)
		)
		(pad "23" smd custom
			(at 2.4511 0.999998 90)
			(size 0.0508 0.0508)
			(layers "F.Cu" "F.Mask" "F.Paste")
			(net "GND")
			(options
				(clearance outline)
				(anchor circle)
			)
			(primitives
				(gr_poly
					(pts
						(arc
							(start -0.254 0.1016)
							(mid -0.3556 0)
							(end -0.254 -0.1016)
						)
						(xy 0.3556 -0.1016) (xy 0.3556 0.1016)
					)
					(width 0)
					(fill yes)
				)
			)
		)
		(pad "24" smd custom
			(at 2.4511 0.599948 90)
			(size 0.0508 0.0508)
			(layers "F.Cu" "F.Mask" "F.Paste")
			(net "Net_354")
			(options
				(clearance outline)
				(anchor circle)
			)
			(primitives
				(gr_poly
					(pts
						(arc
							(start -0.254 0.1016)
							(mid -0.3556 0)
							(end -0.254 -0.1016)
						)
						(xy 0.3556 -0.1016) (xy 0.3556 0.1016)
					)
					(width 0)
					(fill yes)
				)
			)
		)
		(pad "25" smd custom
			(at 2.4511 0.199898 90)
			(size 0.0508 0.0508)
			(layers "F.Cu" "F.Mask" "F.Paste")
			(net "VR_P1V05_PCH_BIREF1")
			(options
				(clearance outline)
				(anchor circle)
			)
			(primitives
				(gr_poly
					(pts
						(arc
							(start -0.254 0.1016)
							(mid -0.3556 0)
							(end -0.254 -0.1016)
						)
						(xy 0.3556 -0.1016) (xy 0.3556 0.1016)
					)
					(width 0)
					(fill yes)
				)
			)
		)
		(pad "26" smd custom
			(at 2.4511 -0.199898 90)
			(size 0.0508 0.0508)
			(layers "F.Cu" "F.Mask" "F.Paste")
			(net "ISENSE_P1V05_PCH_STBY_PH1_IMON")
			(options
				(clearance outline)
				(anchor circle)
			)
			(primitives
				(gr_poly
					(pts
						(arc
							(start -0.254 0.1016)
							(mid -0.3556 0)
							(end -0.254 -0.1016)
						)
						(xy 0.3556 -0.1016) (xy 0.3556 0.1016)
					)
					(width 0)
					(fill yes)
				)
			)
		)
		(pad "27" smd custom
			(at 2.4511 -0.599948 90)
			(size 0.0508 0.0508)
			(layers "F.Cu" "F.Mask" "F.Paste")
			(net "GND")
			(options
				(clearance outline)
				(anchor circle)
			)
			(primitives
				(gr_poly
					(pts
						(arc
							(start -0.254 0.1016)
							(mid -0.3556 0)
							(end -0.254 -0.1016)
						)
						(xy 0.3556 -0.1016) (xy 0.3556 0.1016)
					)
					(width 0)
					(fill yes)
				)
			)
		)
		(pad "28" smd custom
			(at 2.4511 -0.999998 90)
			(size 0.0508 0.0508)
			(layers "F.Cu" "F.Mask" "F.Paste")
			(net "Net_355")
			(options
				(clearance outline)
				(anchor circle)
			)
			(primitives
				(gr_poly
					(pts
						(arc
							(start -0.254 0.1016)
							(mid -0.3556 0)
							(end -0.254 -0.1016)
						)
						(xy 0.3556 -0.1016) (xy 0.3556 0.1016)
					)
					(width 0)
					(fill yes)
				)
			)
		)
		(pad "29" smd custom
			(at 2.4511 -1.400048 90)
			(size 0.0508 0.0508)
			(layers "F.Cu" "F.Mask" "F.Paste")
			(net "VR_P1V05_PCH_STBY_AVSP")
			(options
				(clearance outline)
				(anchor circle)
			)
			(primitives
				(gr_poly
					(pts
						(arc
							(start -0.254 0.1016)
							(mid -0.3556 0)
							(end -0.254 -0.1016)
						)
						(xy 0.3556 -0.1016) (xy 0.3556 0.1016)
					)
					(width 0)
					(fill yes)
				)
			)
		)
		(pad "30" smd custom
			(at 2.4511 -1.800098 90)
			(size 0.0508 0.0508)
			(layers "F.Cu" "F.Mask" "F.Paste")
			(net "VSENSE_P1V05_PCH_STBY_AVSN")
			(options
				(clearance outline)
				(anchor circle)
			)
			(primitives
				(gr_poly
					(pts
						(arc
							(start -0.254 0.1016)
							(mid -0.3556 0)
							(end -0.254 -0.1016)
						)
						(xy 0.3556 -0.1016) (xy 0.3556 0.1016)
					)
					(width 0)
					(fill yes)
				)
			)
		)
		(pad "31" smd custom
			(at 1.800098 -2.4511 90)
			(size 0.0508 0.0508)
			(layers "F.Cu" "F.Mask" "F.Paste")
			(net "Net_299")
			(options
				(clearance outline)
				(anchor circle)
			)
			(primitives
				(gr_poly
					(pts
						(arc
							(start 0.1016 0.254)
							(mid 0 0.3556)
							(end -0.1016 0.254)
						)
						(xy -0.1016 -0.3556) (xy 0.1016 -0.3556)
					)
					(width 0)
					(fill yes)
				)
			)
		)
		(pad "32" smd custom
			(at 1.400048 -2.4511 90)
			(size 0.0508 0.0508)
			(layers "F.Cu" "F.Mask" "F.Paste")
			(net "PU_VR_PVNN_PCH_FAULT1")
			(options
				(clearance outline)
				(anchor circle)
			)
			(primitives
				(gr_poly
					(pts
						(arc
							(start 0.1016 0.254)
							(mid 0 0.3556)
							(end -0.1016 0.254)
						)
						(xy -0.1016 -0.3556) (xy 0.1016 -0.3556)
					)
					(width 0)
					(fill yes)
				)
			)
		)
		(pad "33" smd custom
			(at 0.999998 -2.4511 90)
			(size 0.0508 0.0508)
			(layers "F.Cu" "F.Mask" "F.Paste")
			(net "VR_PVNN_PCH_XADDR2")
			(options
				(clearance outline)
				(anchor circle)
			)
			(primitives
				(gr_poly
					(pts
						(arc
							(start 0.1016 0.254)
							(mid 0 0.3556)
							(end -0.1016 0.254)
						)
						(xy -0.1016 -0.3556) (xy 0.1016 -0.3556)
					)
					(width 0)
					(fill yes)
				)
			)
		)
		(pad "34" smd custom
			(at 0.599948 -2.4511 90)
			(size 0.0508 0.0508)
			(layers "F.Cu" "F.Mask" "F.Paste")
			(net "A_TSENSE_P1V05_PCH_STBY_TMON")
			(options
				(clearance outline)
				(anchor circle)
			)
			(primitives
				(gr_poly
					(pts
						(arc
							(start 0.1016 0.254)
							(mid 0 0.3556)
							(end -0.1016 0.254)
						)
						(xy -0.1016 -0.3556) (xy 0.1016 -0.3556)
					)
					(width 0)
					(fill yes)
				)
			)
		)
		(pad "35" smd custom
			(at 0.199898 -2.4511 90)
			(size 0.0508 0.0508)
			(layers "F.Cu" "F.Mask" "F.Paste")
			(net "A_TSENSE_PVNN_PCH_TMON")
			(options
				(clearance outline)
				(anchor circle)
			)
			(primitives
				(gr_poly
					(pts
						(arc
							(start 0.1016 0.254)
							(mid 0 0.3556)
							(end -0.1016 0.254)
						)
						(xy -0.1016 -0.3556) (xy 0.1016 -0.3556)
					)
					(width 0)
					(fill yes)
				)
			)
		)
		(pad "36" smd custom
			(at -0.199898 -2.4511 90)
			(size 0.0508 0.0508)
			(layers "F.Cu" "F.Mask" "F.Paste")
			(net "VR_PVNN_PCH_XADDR1")
			(options
				(clearance outline)
				(anchor circle)
			)
			(primitives
				(gr_poly
					(pts
						(arc
							(start 0.1016 0.254)
							(mid 0 0.3556)
							(end -0.1016 0.254)
						)
						(xy -0.1016 -0.3556) (xy 0.1016 -0.3556)
					)
					(width 0)
					(fill yes)
				)
			)
		)
		(pad "37" smd custom
			(at -0.599948 -2.4511 90)
			(size 0.0508 0.0508)
			(layers "F.Cu" "F.Mask" "F.Paste")
			(net "VR_PVNN_PCH_VINSEN")
			(options
				(clearance outline)
				(anchor circle)
			)
			(primitives
				(gr_poly
					(pts
						(arc
							(start 0.1016 0.254)
							(mid 0 0.3556)
							(end -0.1016 0.254)
						)
						(xy -0.1016 -0.3556) (xy 0.1016 -0.3556)
					)
					(width 0)
					(fill yes)
				)
			)
		)
		(pad "38" smd custom
			(at -0.999998 -2.4511 90)
			(size 0.0508 0.0508)
			(layers "F.Cu" "F.Mask" "F.Paste")
			(net "Net_268")
			(options
				(clearance outline)
				(anchor circle)
			)
			(primitives
				(gr_poly
					(pts
						(arc
							(start 0.1016 0.254)
							(mid 0 0.3556)
							(end -0.1016 0.254)
						)
						(xy -0.1016 -0.3556) (xy 0.1016 -0.3556)
					)
					(width 0)
					(fill yes)
				)
			)
		)
		(pad "39" smd custom
			(at -1.400048 -2.4511 90)
			(size 0.0508 0.0508)
			(layers "F.Cu" "F.Mask" "F.Paste")
			(net "VR_PVNN_PCH_VDD")
			(options
				(clearance outline)
				(anchor circle)
			)
			(primitives
				(gr_poly
					(pts
						(arc
							(start 0.1016 0.254)
							(mid 0 0.3556)
							(end -0.1016 0.254)
						)
						(xy -0.1016 -0.3556) (xy 0.1016 -0.3556)
					)
					(width 0)
					(fill yes)
				)
			)
		)
		(pad "40" smd custom
			(at -1.800098 -2.4511 90)
			(size 0.0508 0.0508)
			(layers "F.Cu" "F.Mask" "F.Paste")
			(net "VR_PVNN_P1V05_PCH_VD12")
			(options
				(clearance outline)
				(anchor circle)
			)
			(primitives
				(gr_poly
					(pts
						(arc
							(start 0.1016 0.254)
							(mid 0 0.3556)
							(end -0.1016 0.254)
						)
						(xy -0.1016 -0.3556) (xy 0.1016 -0.3556)
					)
					(width 0)
					(fill yes)
				)
			)
		)
		(pad "41" smd rect
			(at 0 0 90)
			(size 3.683 3.683)
			(layers "F.Cu" "F.Mask" "F.Paste")
			(net "GND")
		)
		(zone
			(layer "F.Cu")
			(hatch none 0.5)
			(connect_pads
				(clearance 0)
			)
			(min_thickness 0.25)
			(keepout
				(tracks allowed)
				(vias not_allowed)
				(pads allowed)
				(copperpour not_allowed)
				(footprints allowed)
			)
			(placement
				(enabled no)
				(sheetname "")
			)
			(fill
				(thermal_gap 0.5)
				(thermal_bridge_width 0.5)
				(island_removal_mode 0)
			)
			(polygon
				(pts
					(xy 397.8783 -151.7015) (xy 397.41729 -151.7015) (xy 397.41729 -151.9555) (xy 397.6243 -151.9555)
					(xy 397.6243 -155.6385) (xy 393.9413 -155.6385) (xy 393.9413 -151.9555) (xy 397.415258 -151.9555)
					(xy 397.415258 -151.7015) (xy 393.6873 -151.7015) (xy 393.6873 -155.8925) (xy 397.8783 -155.8925)
				)
			)
		)
		(zone
			(layer "F.Cu")
			(hatch none 0.5)
			(connect_pads
				(clearance 0)
			)
			(min_thickness 0.25)
			(keepout
				(tracks not_allowed)
				(vias allowed)
				(pads allowed)
				(copperpour not_allowed)
				(footprints allowed)
			)
			(placement
				(enabled no)
				(sheetname "")
			)
			(fill
				(thermal_gap 0.5)
				(thermal_bridge_width 0.5)
				(island_removal_mode 0)
			)
			(polygon
				(pts
					(xy 397.8783 -151.7015) (xy 397.41729 -151.7015) (xy 397.41729 -151.9555) (xy 397.6243 -151.9555)
					(xy 397.6243 -155.6385) (xy 393.9413 -155.6385) (xy 393.9413 -151.9555) (xy 397.415258 -151.9555)
					(xy 397.415258 -151.7015) (xy 393.6873 -151.7015) (xy 393.6873 -155.8925) (xy 397.8783 -155.8925)
				)
			)
		)
	)
	(footprint ""
		(layer "F.Cu")
		(at 429.895 -22.86 -90)
		(property "Reference" "R10W4"
			(at -0.8382 -0.67818 270)
			(unlocked yes)
			(layer "F.SilkS")
			(effects
				(font
					(size 0.4064 0.254)
					(thickness 0.1524)
				)
				(justify left)
			)
		)
		(property "Value" ""
			(at 0 0 270)
			(layer "F.Fab")
			(effects
				(font
					(size 1.27 1.27)
				)
			)
		)
		(duplicate_pad_numbers_are_jumpers no)
		(fp_poly
			(pts
				(xy -0.2794 -0.1016) (xy 0.2794 -0.1016) (xy 0.2794 0.9906) (xy -0.2794 0.9906)
			)
			(stroke
				(width 0)
				(type default)
			)
			(fill no)
			(layer "F.CrtYd")
		)
		(fp_line
			(start -0.2794 0.9906)
			(end 0.2794 0.9906)
			(stroke
				(width 0.1)
				(type default)
			)
			(layer "F.Fab")
		)
		(fp_line
			(start 0.2794 0.9906)
			(end 0.2794 -0.1016)
			(stroke
				(width 0.1)
				(type default)
			)
			(layer "F.Fab")
		)
		(fp_line
			(start -0.2794 -0.1016)
			(end -0.2794 0.9906)
			(stroke
				(width 0.1)
				(type default)
			)
			(layer "F.Fab")
		)
		(fp_line
			(start 0.2794 -0.1016)
			(end -0.2794 -0.1016)
			(stroke
				(width 0.1)
				(type default)
			)
			(layer "F.Fab")
		)
		(pad "1" smd rect
			(at 0 0 270)
			(size 0.508 0.508)
			(layers "F.Cu" "F.Mask" "F.Paste")
			(net "PUMP_PWM_OUT_BUF")
		)
		(pad "2" smd rect
			(at 0 0.889 270)
			(size 0.508 0.508)
			(layers "F.Cu" "F.Mask" "F.Paste")
			(net "PUMP_PWM_OUT_R")
		)
		(zone
			(layer "F.Cu")
			(hatch none 0.5)
			(connect_pads
				(clearance 0)
			)
			(min_thickness 0.25)
			(keepout
				(tracks not_allowed)
				(vias allowed)
				(pads allowed)
				(copperpour not_allowed)
				(footprints allowed)
			)
			(placement
				(enabled no)
				(sheetname "")
			)
			(fill
				(thermal_gap 0.5)
				(thermal_bridge_width 0.5)
				(island_removal_mode 0)
			)
			(polygon
				(pts
					(xy 429.26 -23.114) (xy 429.26 -22.606) (xy 429.641 -22.606) (xy 429.641 -23.114)
				)
			)
		)
		(zone
			(layer "F.Cu")
			(hatch none 0.5)
			(connect_pads
				(clearance 0)
			)
			(min_thickness 0.25)
			(keepout
				(tracks allowed)
				(vias not_allowed)
				(pads allowed)
				(copperpour not_allowed)
				(footprints allowed)
			)
			(placement
				(enabled no)
				(sheetname "")
			)
			(fill
				(thermal_gap 0.5)
				(thermal_bridge_width 0.5)
				(island_removal_mode 0)
			)
			(polygon
				(pts
					(xy 429.641 -23.114) (xy 429.641 -22.606) (xy 429.26 -22.606) (xy 429.26 -23.114)
				)
			)
		)
	)
	(footprint ""
		(layer "F.Cu")
		(at 341.6046 -127.4445 180)
		(property "Reference" "R7B16"
			(at 0 0 180)
			(layer "F.SilkS")
			(hide yes)
			(effects
				(font
					(size 1.27 1.27)
				)
			)
		)
		(property "Value" ""
			(at 0 0 180)
			(layer "F.Fab")
			(effects
				(font
					(size 1.27 1.27)
				)
			)
		)
		(duplicate_pad_numbers_are_jumpers no)
		(fp_poly
			(pts
				(xy -0.2794 -0.1016) (xy 0.2794 -0.1016) (xy 0.2794 0.9906) (xy -0.2794 0.9906)
			)
			(stroke
				(width 0)
				(type default)
			)
			(fill no)
			(layer "F.CrtYd")
		)
		(fp_line
			(start 0.2794 0.9906)
			(end 0.2794 -0.1016)
			(stroke
				(width 0.1)
				(type default)
			)
			(layer "F.Fab")
		)
		(fp_line
			(start 0.2794 -0.1016)
			(end -0.2794 -0.1016)
			(stroke
				(width 0.1)
				(type default)
			)
			(layer "F.Fab")
		)
		(fp_line
			(start -0.2794 0.9906)
			(end 0.2794 0.9906)
			(stroke
				(width 0.1)
				(type default)
			)
			(layer "F.Fab")
		)
		(fp_line
			(start -0.2794 -0.1016)
			(end -0.2794 0.9906)
			(stroke
				(width 0.1)
				(type default)
			)
			(layer "F.Fab")
		)
		(pad "1" smd rect
			(at 0 0 180)
			(size 0.508 0.508)
			(layers "F.Cu" "F.Mask" "F.Paste")
			(net "VR_COMP_RC_PVPP_DEF")
		)
		(pad "2" smd rect
			(at 0 0.889 180)
			(size 0.508 0.508)
			(layers "F.Cu" "F.Mask" "F.Paste")
			(net "VR_FB_PVPP_DEF")
		)
		(zone
			(layer "F.Cu")
			(hatch none 0.5)
			(connect_pads
				(clearance 0)
			)
			(min_thickness 0.25)
			(keepout
				(tracks not_allowed)
				(vias allowed)
				(pads allowed)
				(copperpour not_allowed)
				(footprints allowed)
			)
			(placement
				(enabled no)
				(sheetname "")
			)
			(fill
				(thermal_gap 0.5)
				(thermal_bridge_width 0.5)
				(island_removal_mode 0)
			)
			(polygon
				(pts
					(xy 341.8586 -128.0795) (xy 341.3506 -128.0795) (xy 341.3506 -127.6985) (xy 341.8586 -127.6985)
				)
			)
		)
		(zone
			(layer "F.Cu")
			(hatch none 0.5)
			(connect_pads
				(clearance 0)
			)
			(min_thickness 0.25)
			(keepout
				(tracks allowed)
				(vias not_allowed)
				(pads allowed)
				(copperpour not_allowed)
				(footprints allowed)
			)
			(placement
				(enabled no)
				(sheetname "")
			)
			(fill
				(thermal_gap 0.5)
				(thermal_bridge_width 0.5)
				(island_removal_mode 0)
			)
			(polygon
				(pts
					(xy 341.8586 -127.6985) (xy 341.3506 -127.6985) (xy 341.3506 -128.0795) (xy 341.8586 -128.0795)
				)
			)
		)
	)
	(footprint ""
		(layer "F.Cu")
		(at -2.856484 -149.29231 90)
		(property "Reference" "C1A8"
			(at 0 0 90)
			(layer "F.SilkS")
			(hide yes)
			(effects
				(font
					(size 1.27 1.27)
				)
			)
		)
		(property "Value" ""
			(at 0 0 90)
			(layer "F.Fab")
			(effects
				(font
					(size 1.27 1.27)
				)
			)
		)
		(duplicate_pad_numbers_are_jumpers no)
		(fp_poly
			(pts
				(xy 0.3048 -0.1016) (xy 0.3048 0.9906) (xy -0.3048 0.9906) (xy -0.3048 -0.1016)
			)
			(stroke
				(width 0)
				(type default)
			)
			(fill no)
			(layer "F.CrtYd")
		)
		(fp_line
			(start 0.3048 -0.1016)
			(end -0.3048 -0.1016)
			(stroke
				(width 0.1)
				(type default)
			)
			(layer "F.Fab")
		)
		(fp_line
			(start -0.3048 -0.1016)
			(end -0.3048 0.9906)
			(stroke
				(width 0.1)
				(type default)
			)
			(layer "F.Fab")
		)
		(fp_line
			(start 0.3048 0.9906)
			(end 0.3048 -0.1016)
			(stroke
				(width 0.1)
				(type default)
			)
			(layer "F.Fab")
		)
		(fp_line
			(start -0.3048 0.9906)
			(end 0.3048 0.9906)
			(stroke
				(width 0.1)
				(type default)
			)
			(layer "F.Fab")
		)
		(pad "1" smd rect
			(at 0 0 90)
			(size 0.508 0.508)
			(layers "F.Cu" "F.Mask" "F.Paste")
			(net "VR_PVDDQ_KLM_PH2_BOOT")
		)
		(pad "2" smd rect
			(at 0 0.889 90)
			(size 0.508 0.508)
			(layers "F.Cu" "F.Mask" "F.Paste")
			(net "VR_PVDDQ_KLM_PH2_PHASE")
		)
		(zone
			(layer "F.Cu")
			(hatch none 0.5)
			(connect_pads
				(clearance 0)
			)
			(min_thickness 0.25)
			(keepout
				(tracks allowed)
				(vias not_allowed)
				(pads allowed)
				(copperpour not_allowed)
				(footprints allowed)
			)
			(placement
				(enabled no)
				(sheetname "")
			)
			(fill
				(thermal_gap 0.5)
				(thermal_bridge_width 0.5)
				(island_removal_mode 0)
			)
			(polygon
				(pts
					(xy -2.602484 -149.03831) (xy -2.602484 -149.54631) (xy -2.221484 -149.54631) (xy -2.221484 -149.03831)
				)
			)
		)
		(zone
			(layer "F.Cu")
			(hatch none 0.5)
			(connect_pads
				(clearance 0)
			)
			(min_thickness 0.25)
			(keepout
				(tracks not_allowed)
				(vias allowed)
				(pads allowed)
				(copperpour not_allowed)
				(footprints allowed)
			)
			(placement
				(enabled no)
				(sheetname "")
			)
			(fill
				(thermal_gap 0.5)
				(thermal_bridge_width 0.5)
				(island_removal_mode 0)
			)
			(polygon
				(pts
					(xy -2.221484 -149.03831) (xy -2.221484 -149.54631) (xy -2.602484 -149.54631) (xy -2.602484 -149.03831)
				)
			)
		)
	)
	(footprint ""
		(layer "F.Cu")
		(at 324.612 -35.052 -90)
		(property "Reference" "R6F3"
			(at 0 0 270)
			(layer "F.SilkS")
			(hide yes)
			(effects
				(font
					(size 1.27 1.27)
				)
			)
		)
		(property "Value" ""
			(at 0 0 270)
			(layer "F.Fab")
			(effects
				(font
					(size 1.27 1.27)
				)
			)
		)
		(duplicate_pad_numbers_are_jumpers no)
		(fp_poly
			(pts
				(xy -0.2794 -0.1016) (xy 0.2794 -0.1016) (xy 0.2794 0.9906) (xy -0.2794 0.9906)
			)
			(stroke
				(width 0)
				(type default)
			)
			(fill no)
			(layer "F.CrtYd")
		)
		(fp_line
			(start -0.2794 0.9906)
			(end 0.2794 0.9906)
			(stroke
				(width 0.1)
				(type default)
			)
			(layer "F.Fab")
		)
		(fp_line
			(start 0.2794 0.9906)
			(end 0.2794 -0.1016)
			(stroke
				(width 0.1)
				(type default)
			)
			(layer "F.Fab")
		)
		(fp_line
			(start -0.2794 -0.1016)
			(end -0.2794 0.9906)
			(stroke
				(width 0.1)
				(type default)
			)
			(layer "F.Fab")
		)
		(fp_line
			(start 0.2794 -0.1016)
			(end -0.2794 -0.1016)
			(stroke
				(width 0.1)
				(type default)
			)
			(layer "F.Fab")
		)
		(pad "1" smd rect
			(at 0 0 270)
			(size 0.508 0.508)
			(layers "F.Cu" "F.Mask" "F.Paste")
			(net "PVPP_ABC")
		)
		(pad "2" smd rect
			(at 0 0.889 270)
			(size 0.508 0.508)
			(layers "F.Cu" "F.Mask" "F.Paste")
			(net "IRQ_DIMM_SAVE_N")
		)
		(zone
			(layer "F.Cu")
			(hatch none 0.5)
			(connect_pads
				(clearance 0)
			)
			(min_thickness 0.25)
			(keepout
				(tracks not_allowed)
				(vias allowed)
				(pads allowed)
				(copperpour not_allowed)
				(footprints allowed)
			)
			(placement
				(enabled no)
				(sheetname "")
			)
			(fill
				(thermal_gap 0.5)
				(thermal_bridge_width 0.5)
				(island_removal_mode 0)
			)
			(polygon
				(pts
					(xy 323.977 -35.306) (xy 323.977 -34.798) (xy 324.358 -34.798) (xy 324.358 -35.306)
				)
			)
		)
		(zone
			(layer "F.Cu")
			(hatch none 0.5)
			(connect_pads
				(clearance 0)
			)
			(min_thickness 0.25)
			(keepout
				(tracks allowed)
				(vias not_allowed)
				(pads allowed)
				(copperpour not_allowed)
				(footprints allowed)
			)
			(placement
				(enabled no)
				(sheetname "")
			)
			(fill
				(thermal_gap 0.5)
				(thermal_bridge_width 0.5)
				(island_removal_mode 0)
			)
			(polygon
				(pts
					(xy 324.358 -35.306) (xy 324.358 -34.798) (xy 323.977 -34.798) (xy 323.977 -35.306)
				)
			)
		)
	)
	(footprint ""
		(layer "F.Cu")
		(at 21.336 -70.866)
		(property "Reference" "C1D27"
			(at 0 0 0)
			(layer "F.SilkS")
			(hide yes)
			(effects
				(font
					(size 1.27 1.27)
				)
			)
		)
		(property "Value" ""
			(at 0 0 0)
			(layer "F.Fab")
			(effects
				(font
					(size 1.27 1.27)
				)
			)
		)
		(duplicate_pad_numbers_are_jumpers no)
		(fp_rect
			(start 0.3048 0.9906)
			(end -0.3048 -0.1016)
			(stroke
				(width 0)
				(type default)
			)
			(fill no)
			(layer "F.CrtYd")
		)
		(fp_line
			(start -0.3048 -0.1016)
			(end -0.3048 0.9906)
			(stroke
				(width 0.1)
				(type default)
			)
			(layer "F.Fab")
		)
		(fp_line
			(start -0.3048 0.9906)
			(end 0.3048 0.9906)
			(stroke
				(width 0.1)
				(type default)
			)
			(layer "F.Fab")
		)
		(fp_line
			(start 0.3048 -0.1016)
			(end -0.3048 -0.1016)
			(stroke
				(width 0.1)
				(type default)
			)
			(layer "F.Fab")
		)
		(fp_line
			(start 0.3048 0.9906)
			(end 0.3048 -0.1016)
			(stroke
				(width 0.1)
				(type default)
			)
			(layer "F.Fab")
		)
		(pad "1" smd rect
			(at 0 0)
			(size 0.508 0.508)
			(layers "F.Cu" "F.Mask" "F.Paste")
			(net "A_HSC_OV")
		)
		(pad "2" smd rect
			(at 0 0.889)
			(size 0.508 0.508)
			(layers "F.Cu" "F.Mask" "F.Paste")
			(net "AGND_HSC")
		)
		(zone
			(layer "F.Cu")
			(hatch none 0.5)
			(connect_pads
				(clearance 0)
			)
			(min_thickness 0.25)
			(keepout
				(tracks not_allowed)
				(vias allowed)
				(pads allowed)
				(copperpour not_allowed)
				(footprints allowed)
			)
			(placement
				(enabled no)
				(sheetname "")
			)
			(fill
				(thermal_gap 0.5)
				(thermal_bridge_width 0.5)
				(island_removal_mode 0)
			)
			(polygon
				(pts
					(xy 21.59 -70.231) (xy 21.59 -70.612) (xy 21.082 -70.612) (xy 21.082 -70.231)
				)
			)
		)
		(zone
			(layer "F.Cu")
			(hatch none 0.5)
			(connect_pads
				(clearance 0)
			)
			(min_thickness 0.25)
			(keepout
				(tracks allowed)
				(vias not_allowed)
				(pads allowed)
				(copperpour not_allowed)
				(footprints allowed)
			)
			(placement
				(enabled no)
				(sheetname "")
			)
			(fill
				(thermal_gap 0.5)
				(thermal_bridge_width 0.5)
				(island_removal_mode 0)
			)
			(polygon
				(pts
					(xy 21.59 -70.231) (xy 21.59 -70.612) (xy 21.082 -70.612) (xy 21.082 -70.231)
				)
			)
		)
	)
	(footprint ""
		(layer "F.Cu")
		(at 30.3276 -69.8754)
		(property "Reference" "CT16"
			(at -0.88773 0.6858 90)
			(unlocked yes)
			(layer "F.SilkS")
			(effects
				(font
					(size 0.7874 0.5842)
					(thickness 0.1524)
				)
				(justify left)
			)
		)
		(property "Value" ""
			(at 0 0 0)
			(layer "F.Fab")
			(effects
				(font
					(size 1.27 1.27)
				)
			)
		)
		(duplicate_pad_numbers_are_jumpers no)
		(fp_poly
			(pts
				(xy 0.3048 -0.1016) (xy 0.3048 0.9906) (xy -0.3048 0.9906) (xy -0.3048 -0.1016)
			)
			(stroke
				(width 0)
				(type default)
			)
			(fill no)
			(layer "F.CrtYd")
		)
		(fp_line
			(start -0.3048 -0.1016)
			(end -0.3048 0.9906)
			(stroke
				(width 0.1)
				(type default)
			)
			(layer "F.Fab")
		)
		(fp_line
			(start -0.3048 0.9906)
			(end 0.3048 0.9906)
			(stroke
				(width 0.1)
				(type default)
			)
			(layer "F.Fab")
		)
		(fp_line
			(start 0.3048 -0.1016)
			(end -0.3048 -0.1016)
			(stroke
				(width 0.1)
				(type default)
			)
			(layer "F.Fab")
		)
		(fp_line
			(start 0.3048 0.9906)
			(end 0.3048 -0.1016)
			(stroke
				(width 0.1)
				(type default)
			)
			(layer "F.Fab")
		)
		(pad "1" smd rect
			(at 0 0)
			(size 0.508 0.508)
			(layers "F.Cu" "F.Mask" "F.Paste")
			(net "VR_PVCCIN_CPU1_AIREF3")
		)
		(pad "2" smd rect
			(at 0 0.889)
			(size 0.508 0.508)
			(layers "F.Cu" "F.Mask" "F.Paste")
			(net "GND")
		)
		(zone
			(layer "F.Cu")
			(hatch none 0.5)
			(connect_pads
				(clearance 0)
			)
			(min_thickness 0.25)
			(keepout
				(tracks allowed)
				(vias not_allowed)
				(pads allowed)
				(copperpour not_allowed)
				(footprints allowed)
			)
			(placement
				(enabled no)
				(sheetname "")
			)
			(fill
				(thermal_gap 0.5)
				(thermal_bridge_width 0.5)
				(island_removal_mode 0)
			)
			(polygon
				(pts
					(xy 30.0736 -69.6214) (xy 30.5816 -69.6214) (xy 30.5816 -69.2404) (xy 30.0736 -69.2404)
				)
			)
		)
		(zone
			(layer "F.Cu")
			(hatch none 0.5)
			(connect_pads
				(clearance 0)
			)
			(min_thickness 0.25)
			(keepout
				(tracks not_allowed)
				(vias allowed)
				(pads allowed)
				(copperpour not_allowed)
				(footprints allowed)
			)
			(placement
				(enabled no)
				(sheetname "")
			)
			(fill
				(thermal_gap 0.5)
				(thermal_bridge_width 0.5)
				(island_removal_mode 0)
			)
			(polygon
				(pts
					(xy 30.0736 -69.2404) (xy 30.5816 -69.2404) (xy 30.5816 -69.6214) (xy 30.0736 -69.6214)
				)
			)
		)
	)
	(footprint ""
		(layer "F.Cu")
		(at 381.508 -88.2015)
		(property "Reference" "R3N26"
			(at 0 0 0)
			(layer "F.SilkS")
			(hide yes)
			(effects
				(font
					(size 1.27 1.27)
				)
			)
		)
		(property "Value" ""
			(at 0 0 0)
			(layer "F.Fab")
			(effects
				(font
					(size 1.27 1.27)
				)
			)
		)
		(duplicate_pad_numbers_are_jumpers no)
		(fp_poly
			(pts
				(xy -0.2794 -0.1016) (xy 0.2794 -0.1016) (xy 0.2794 0.9906) (xy -0.2794 0.9906)
			)
			(stroke
				(width 0)
				(type default)
			)
			(fill no)
			(layer "F.CrtYd")
		)
		(fp_line
			(start -0.2794 -0.1016)
			(end -0.2794 0.9906)
			(stroke
				(width 0.1)
				(type default)
			)
			(layer "F.Fab")
		)
		(fp_line
			(start -0.2794 0.9906)
			(end 0.2794 0.9906)
			(stroke
				(width 0.1)
				(type default)
			)
			(layer "F.Fab")
		)
		(fp_line
			(start 0.2794 -0.1016)
			(end -0.2794 -0.1016)
			(stroke
				(width 0.1)
				(type default)
			)
			(layer "F.Fab")
		)
		(fp_line
			(start 0.2794 0.9906)
			(end 0.2794 -0.1016)
			(stroke
				(width 0.1)
				(type default)
			)
			(layer "F.Fab")
		)
		(pad "1" smd rect
			(at 0 0)
			(size 0.508 0.508)
			(layers "F.Cu" "F.Mask" "F.Paste")
			(net "LPC_LAD0_IO0")
		)
		(pad "2" smd rect
			(at 0 0.889)
			(size 0.508 0.508)
			(layers "F.Cu" "F.Mask" "F.Paste")
			(net "LPC_LAD0_IO0_R")
		)
		(zone
			(layer "F.Cu")
			(hatch none 0.5)
			(connect_pads
				(clearance 0)
			)
			(min_thickness 0.25)
			(keepout
				(tracks allowed)
				(vias not_allowed)
				(pads allowed)
				(copperpour not_allowed)
				(footprints allowed)
			)
			(placement
				(enabled no)
				(sheetname "")
			)
			(fill
				(thermal_gap 0.5)
				(thermal_bridge_width 0.5)
				(island_removal_mode 0)
			)
			(polygon
				(pts
					(xy 381.254 -87.9475) (xy 381.762 -87.9475) (xy 381.762 -87.5665) (xy 381.254 -87.5665)
				)
			)
		)
		(zone
			(layer "F.Cu")
			(hatch none 0.5)
			(connect_pads
				(clearance 0)
			)
			(min_thickness 0.25)
			(keepout
				(tracks not_allowed)
				(vias allowed)
				(pads allowed)
				(copperpour not_allowed)
				(footprints allowed)
			)
			(placement
				(enabled no)
				(sheetname "")
			)
			(fill
				(thermal_gap 0.5)
				(thermal_bridge_width 0.5)
				(island_removal_mode 0)
			)
			(polygon
				(pts
					(xy 381.254 -87.5665) (xy 381.762 -87.5665) (xy 381.762 -87.9475) (xy 381.254 -87.9475)
				)
			)
		)
	)
	(footprint ""
		(layer "F.Cu")
		(at 2.0574 -127.9652 -90)
		(property "Reference" "EU1B1"
			(at 3.76047 4.0132 0)
			(unlocked yes)
			(layer "F.SilkS")
			(effects
				(font
					(size 0.7874 0.5842)
					(thickness 0.1524)
				)
				(justify left)
			)
		)
		(property "Value" ""
			(at 0 0 270)
			(layer "F.Fab")
			(effects
				(font
					(size 1.27 1.27)
				)
			)
		)
		(duplicate_pad_numbers_are_jumpers no)
		(fp_line
			(start -3.0607 3.0607)
			(end -3.0607 -3.0607)
			(stroke
				(width 0.1524)
				(type default)
			)
			(layer "F.SilkS")
		)
		(fp_line
			(start 3.0607 3.0607)
			(end -3.0607 3.0607)
			(stroke
				(width 0.1524)
				(type default)
			)
			(layer "F.SilkS")
		)
		(fp_line
			(start -2.549906 2.549906)
			(end -2.549906 2.267204)
			(stroke
				(width 0.1524)
				(type default)
			)
			(layer "F.SilkS")
		)
		(fp_line
			(start -2.277618 2.549906)
			(end -2.549906 2.549906)
			(stroke
				(width 0.1524)
				(type default)
			)
			(layer "F.SilkS")
		)
		(fp_line
			(start 2.549906 2.549906)
			(end 2.249678 2.549906)
			(stroke
				(width 0.1524)
				(type default)
			)
			(layer "F.SilkS")
		)
		(fp_line
			(start 2.549906 2.233422)
			(end 2.549906 2.549906)
			(stroke
				(width 0.1524)
				(type default)
			)
			(layer "F.SilkS")
		)
		(fp_line
			(start -2.549906 -2.29362)
			(end -2.549906 -2.549906)
			(stroke
				(width 0.1524)
				(type default)
			)
			(layer "F.SilkS")
		)
		(fp_line
			(start -2.549906 -2.549906)
			(end -2.249678 -2.549906)
			(stroke
				(width 0.1524)
				(type default)
			)
			(layer "F.SilkS")
		)
		(fp_line
			(start 2.245614 -2.549906)
			(end 2.549906 -2.549906)
			(stroke
				(width 0.1524)
				(type default)
			)
			(layer "F.SilkS")
		)
		(fp_line
			(start 2.549906 -2.549906)
			(end 2.549906 -2.258314)
			(stroke
				(width 0.1524)
				(type default)
			)
			(layer "F.SilkS")
		)
		(fp_line
			(start -3.0607 -3.0607)
			(end 3.0607 -3.0607)
			(stroke
				(width 0.1524)
				(type default)
			)
			(layer "F.SilkS")
		)
		(fp_line
			(start 3.0607 -3.0607)
			(end 3.0607 3.0607)
			(stroke
				(width 0.1524)
				(type default)
			)
			(layer "F.SilkS")
		)
		(fp_circle
			(center -3.237738 -2.256536)
			(end -3.237738 -2.383536)
			(stroke
				(width 0.254)
				(type default)
			)
			(fill no)
			(layer "F.SilkS")
		)
		(fp_poly
			(pts
				(xy -3.0607 -3.0607) (xy -3.0607 -2.0193) (xy -2.0193 -3.0607)
			)
			(stroke
				(width 0)
				(type default)
			)
			(fill yes)
			(layer "F.SilkS")
		)
		(fp_rect
			(start -1.8415 1.8415)
			(end 1.8415 -1.8415)
			(stroke
				(width 0)
				(type default)
			)
			(fill yes)
			(layer "F.Paste")
		)
		(fp_rect
			(start -2.549906 2.549906)
			(end 2.549906 -2.549906)
			(stroke
				(width 0)
				(type default)
			)
			(fill no)
			(layer "F.CrtYd")
		)
		(fp_line
			(start -2.549906 2.549906)
			(end -2.549906 -2.549906)
			(stroke
				(width 0.1)
				(type default)
			)
			(layer "F.Fab")
		)
		(fp_line
			(start 2.549906 2.549906)
			(end -2.549906 2.549906)
			(stroke
				(width 0.1)
				(type default)
			)
			(layer "F.Fab")
		)
		(fp_line
			(start -2.549906 -2.549906)
			(end 2.549906 -2.549906)
			(stroke
				(width 0.1)
				(type default)
			)
			(layer "F.Fab")
		)
		(fp_line
			(start 2.549906 -2.549906)
			(end 2.549906 2.549906)
			(stroke
				(width 0.1)
				(type default)
			)
			(layer "F.Fab")
		)
		(fp_circle
			(center -3.237738 -2.256536)
			(end -3.237738 -2.383536)
			(stroke
				(width 0.254)
				(type default)
			)
			(fill no)
			(layer "F.Fab")
		)
		(pad "1" smd custom
			(at -2.4511 -1.800098 270)
			(size 0.0508 0.0508)
			(layers "F.Cu" "F.Mask" "F.Paste")
			(net "Net_287")
			(options
				(clearance outline)
				(anchor circle)
			)
			(primitives
				(gr_poly
					(pts
						(arc
							(start 0.254 -0.1016)
							(mid 0.3556 0)
							(end 0.254 0.1016)
						)
						(xy -0.3556 0.1016) (xy -0.3556 -0.1016)
					)
					(width 0)
					(fill yes)
				)
			)
		)
		(pad "2" smd custom
			(at -2.4511 -1.400048 270)
			(size 0.0508 0.0508)
			(layers "F.Cu" "F.Mask" "F.Paste")
			(net "Net_271")
			(options
				(clearance outline)
				(anchor circle)
			)
			(primitives
				(gr_poly
					(pts
						(arc
							(start 0.254 -0.1016)
							(mid 0.3556 0)
							(end 0.254 0.1016)
						)
						(xy -0.3556 0.1016) (xy -0.3556 -0.1016)
					)
					(width 0)
					(fill yes)
				)
			)
		)
		(pad "3" smd custom
			(at -2.4511 -0.999998 270)
			(size 0.0508 0.0508)
			(layers "F.Cu" "F.Mask" "F.Paste")
			(net "Net_250")
			(options
				(clearance outline)
				(anchor circle)
			)
			(primitives
				(gr_poly
					(pts
						(arc
							(start 0.254 -0.1016)
							(mid 0.3556 0)
							(end 0.254 0.1016)
						)
						(xy -0.3556 0.1016) (xy -0.3556 -0.1016)
					)
					(width 0)
					(fill yes)
				)
			)
		)
		(pad "4" smd custom
			(at -2.4511 -0.599948 270)
			(size 0.0508 0.0508)
			(layers "F.Cu" "F.Mask" "F.Paste")
			(net "VR_PVDDQ_KLM_PWM2")
			(options
				(clearance outline)
				(anchor circle)
			)
			(primitives
				(gr_poly
					(pts
						(arc
							(start 0.254 -0.1016)
							(mid 0.3556 0)
							(end 0.254 0.1016)
						)
						(xy -0.3556 0.1016) (xy -0.3556 -0.1016)
					)
					(width 0)
					(fill yes)
				)
			)
		)
		(pad "5" smd custom
			(at -2.4511 -0.199898 270)
			(size 0.0508 0.0508)
			(layers "F.Cu" "F.Mask" "F.Paste")
			(net "VR_PVDDQ_KLM_PWM1")
			(options
				(clearance outline)
				(anchor circle)
			)
			(primitives
				(gr_poly
					(pts
						(arc
							(start 0.254 -0.1016)
							(mid 0.3556 0)
							(end 0.254 0.1016)
						)
						(xy -0.3556 0.1016) (xy -0.3556 -0.1016)
					)
					(width 0)
					(fill yes)
				)
			)
		)
		(pad "6" smd custom
			(at -2.4511 0.199898 270)
			(size 0.0508 0.0508)
			(layers "F.Cu" "F.Mask" "F.Paste")
			(net "SMB_VR_STBY_LVC3_SDA")
			(options
				(clearance outline)
				(anchor circle)
			)
			(primitives
				(gr_poly
					(pts
						(arc
							(start 0.254 -0.1016)
							(mid 0.3556 0)
							(end 0.254 0.1016)
						)
						(xy -0.3556 0.1016) (xy -0.3556 -0.1016)
					)
					(width 0)
					(fill yes)
				)
			)
		)
		(pad "7" smd custom
			(at -2.4511 0.599948 270)
			(size 0.0508 0.0508)
			(layers "F.Cu" "F.Mask" "F.Paste")
			(net "SMB_VR_STBY_LVC3_SCL")
			(options
				(clearance outline)
				(anchor circle)
			)
			(primitives
				(gr_poly
					(pts
						(arc
							(start 0.254 -0.1016)
							(mid 0.3556 0)
							(end 0.254 0.1016)
						)
						(xy -0.3556 0.1016) (xy -0.3556 -0.1016)
					)
					(width 0)
					(fill yes)
				)
			)
		)
		(pad "8" smd custom
			(at -2.4511 0.999998 270)
			(size 0.0508 0.0508)
			(layers "F.Cu" "F.Mask" "F.Paste")
			(net "Net_288")
			(options
				(clearance outline)
				(anchor circle)
			)
			(primitives
				(gr_poly
					(pts
						(arc
							(start 0.254 -0.1016)
							(mid 0.3556 0)
							(end 0.254 0.1016)
						)
						(xy -0.3556 0.1016) (xy -0.3556 -0.1016)
					)
					(width 0)
					(fill yes)
				)
			)
		)
		(pad "9" smd custom
			(at -2.4511 1.400048 270)
			(size 0.0508 0.0508)
			(layers "F.Cu" "F.Mask" "F.Paste")
			(net "PWRGD_PVDDQ_KLM_R")
			(options
				(clearance outline)
				(anchor circle)
			)
			(primitives
				(gr_poly
					(pts
						(arc
							(start 0.254 -0.1016)
							(mid 0.3556 0)
							(end 0.254 0.1016)
						)
						(xy -0.3556 0.1016) (xy -0.3556 -0.1016)
					)
					(width 0)
					(fill yes)
				)
			)
		)
		(pad "10" smd custom
			(at -2.4511 1.800098 270)
			(size 0.0508 0.0508)
			(layers "F.Cu" "F.Mask" "F.Paste")
			(net "VR_PVDDQ_KLM_VREN")
			(options
				(clearance outline)
				(anchor circle)
			)
			(primitives
				(gr_poly
					(pts
						(arc
							(start 0.254 -0.1016)
							(mid 0.3556 0)
							(end 0.254 0.1016)
						)
						(xy -0.3556 0.1016) (xy -0.3556 -0.1016)
					)
					(width 0)
					(fill yes)
				)
			)
		)
		(pad "11" smd custom
			(at -1.800098 2.4511 270)
			(size 0.0508 0.0508)
			(layers "F.Cu" "F.Mask" "F.Paste")
			(net "IRQ_PVDDQ_KLM_VRHOT_LVT3_R_N")
			(options
				(clearance outline)
				(anchor circle)
			)
			(primitives
				(gr_poly
					(pts
						(arc
							(start -0.1016 -0.254)
							(mid 0 -0.3556)
							(end 0.1016 -0.254)
						)
						(xy 0.1016 0.3556) (xy -0.1016 0.3556)
					)
					(width 0)
					(fill yes)
				)
			)
		)
		(pad "12" smd custom
			(at -1.400048 2.4511 270)
			(size 0.0508 0.0508)
			(layers "F.Cu" "F.Mask" "F.Paste")
			(net "Net_239")
			(options
				(clearance outline)
				(anchor circle)
			)
			(primitives
				(gr_poly
					(pts
						(arc
							(start -0.1016 -0.254)
							(mid 0 -0.3556)
							(end 0.1016 -0.254)
						)
						(xy 0.1016 0.3556) (xy -0.1016 0.3556)
					)
					(width 0)
					(fill yes)
				)
			)
		)
		(pad "13" smd custom
			(at -0.999998 2.4511 270)
			(size 0.0508 0.0508)
			(layers "F.Cu" "F.Mask" "F.Paste")
			(net "PU_VR_PVDDQ_KLM_FAULT1")
			(options
				(clearance outline)
				(anchor circle)
			)
			(primitives
				(gr_poly
					(pts
						(arc
							(start -0.1016 -0.254)
							(mid 0 -0.3556)
							(end 0.1016 -0.254)
						)
						(xy 0.1016 0.3556) (xy -0.1016 0.3556)
					)
					(width 0)
					(fill yes)
				)
			)
		)
		(pad "14" smd custom
			(at -0.599948 2.4511 270)
			(size 0.0508 0.0508)
			(layers "F.Cu" "F.Mask" "F.Paste")
			(net "NC_PVDDQ_KLM_GP1")
			(options
				(clearance outline)
				(anchor circle)
			)
			(primitives
				(gr_poly
					(pts
						(arc
							(start -0.1016 -0.254)
							(mid 0 -0.3556)
							(end 0.1016 -0.254)
						)
						(xy 0.1016 0.3556) (xy -0.1016 0.3556)
					)
					(width 0)
					(fill yes)
				)
			)
		)
		(pad "15" smd custom
			(at -0.199898 2.4511 270)
			(size 0.0508 0.0508)
			(layers "F.Cu" "F.Mask" "F.Paste")
			(net "SVID_CLK_PVDDQ_KLM")
			(options
				(clearance outline)
				(anchor circle)
			)
			(primitives
				(gr_poly
					(pts
						(arc
							(start -0.1016 -0.254)
							(mid 0 -0.3556)
							(end 0.1016 -0.254)
						)
						(xy 0.1016 0.3556) (xy -0.1016 0.3556)
					)
					(width 0)
					(fill yes)
				)
			)
		)
		(pad "16" smd custom
			(at 0.199898 2.4511 270)
			(size 0.0508 0.0508)
			(layers "F.Cu" "F.Mask" "F.Paste")
			(net "SVID_VDIO_PVDDQ_KLM")
			(options
				(clearance outline)
				(anchor circle)
			)
			(primitives
				(gr_poly
					(pts
						(arc
							(start -0.1016 -0.254)
							(mid 0 -0.3556)
							(end 0.1016 -0.254)
						)
						(xy 0.1016 0.3556) (xy -0.1016 0.3556)
					)
					(width 0)
					(fill yes)
				)
			)
		)
		(pad "17" smd custom
			(at 0.599948 2.4511 270)
			(size 0.0508 0.0508)
			(layers "F.Cu" "F.Mask" "F.Paste")
			(net "SVID_ALERT_PVDDQ_KLM")
			(options
				(clearance outline)
				(anchor circle)
			)
			(primitives
				(gr_poly
					(pts
						(arc
							(start -0.1016 -0.254)
							(mid 0 -0.3556)
							(end 0.1016 -0.254)
						)
						(xy 0.1016 0.3556) (xy -0.1016 0.3556)
					)
					(width 0)
					(fill yes)
				)
			)
		)
		(pad "18" smd custom
			(at 0.999998 2.4511 270)
			(size 0.0508 0.0508)
			(layers "F.Cu" "F.Mask" "F.Paste")
			(net "NC_PVDDQ_KLM_GP0")
			(options
				(clearance outline)
				(anchor circle)
			)
			(primitives
				(gr_poly
					(pts
						(arc
							(start -0.1016 -0.254)
							(mid 0 -0.3556)
							(end 0.1016 -0.254)
						)
						(xy 0.1016 0.3556) (xy -0.1016 0.3556)
					)
					(width 0)
					(fill yes)
				)
			)
		)
		(pad "19" smd custom
			(at 1.400048 2.4511 270)
			(size 0.0508 0.0508)
			(layers "F.Cu" "F.Mask" "F.Paste")
			(net "VR_PVDDQ_KLM_AVSP")
			(options
				(clearance outline)
				(anchor circle)
			)
			(primitives
				(gr_poly
					(pts
						(arc
							(start -0.1016 -0.254)
							(mid 0 -0.3556)
							(end 0.1016 -0.254)
						)
						(xy 0.1016 0.3556) (xy -0.1016 0.3556)
					)
					(width 0)
					(fill yes)
				)
			)
		)
		(pad "20" smd custom
			(at 1.800098 2.4511 270)
			(size 0.0508 0.0508)
			(layers "F.Cu" "F.Mask" "F.Paste")
			(net "VSENSE_PVDDQ_KLM_N")
			(options
				(clearance outline)
				(anchor circle)
			)
			(primitives
				(gr_poly
					(pts
						(arc
							(start -0.1016 -0.254)
							(mid 0 -0.3556)
							(end 0.1016 -0.254)
						)
						(xy 0.1016 0.3556) (xy -0.1016 0.3556)
					)
					(width 0)
					(fill yes)
				)
			)
		)
		(pad "21" smd custom
			(at 2.4511 1.800098 270)
			(size 0.0508 0.0508)
			(layers "F.Cu" "F.Mask" "F.Paste")
			(net "VR_PVDDQ_KLM_AIREF1")
			(options
				(clearance outline)
				(anchor circle)
			)
			(primitives
				(gr_poly
					(pts
						(arc
							(start -0.254 0.1016)
							(mid -0.3556 0)
							(end -0.254 -0.1016)
						)
						(xy 0.3556 -0.1016) (xy 0.3556 0.1016)
					)
					(width 0)
					(fill yes)
				)
			)
		)
		(pad "22" smd custom
			(at 2.4511 1.400048 270)
			(size 0.0508 0.0508)
			(layers "F.Cu" "F.Mask" "F.Paste")
			(net "ISENSE_PVDDQ_KLM_PH1_IMON")
			(options
				(clearance outline)
				(anchor circle)
			)
			(primitives
				(gr_poly
					(pts
						(arc
							(start -0.254 0.1016)
							(mid -0.3556 0)
							(end -0.254 -0.1016)
						)
						(xy 0.3556 -0.1016) (xy 0.3556 0.1016)
					)
					(width 0)
					(fill yes)
				)
			)
		)
		(pad "23" smd custom
			(at 2.4511 0.999998 270)
			(size 0.0508 0.0508)
			(layers "F.Cu" "F.Mask" "F.Paste")
			(net "VR_PVDDQ_KLM_AIREF2")
			(options
				(clearance outline)
				(anchor circle)
			)
			(primitives
				(gr_poly
					(pts
						(arc
							(start -0.254 0.1016)
							(mid -0.3556 0)
							(end -0.254 -0.1016)
						)
						(xy 0.3556 -0.1016) (xy 0.3556 0.1016)
					)
					(width 0)
					(fill yes)
				)
			)
		)
		(pad "24" smd custom
			(at 2.4511 0.599948 270)
			(size 0.0508 0.0508)
			(layers "F.Cu" "F.Mask" "F.Paste")
			(net "ISENSE_PVDDQ_KLM_PH2_IMON")
			(options
				(clearance outline)
				(anchor circle)
			)
			(primitives
				(gr_poly
					(pts
						(arc
							(start -0.254 0.1016)
							(mid -0.3556 0)
							(end -0.254 -0.1016)
						)
						(xy 0.3556 -0.1016) (xy 0.3556 0.1016)
					)
					(width 0)
					(fill yes)
				)
			)
		)
		(pad "25" smd custom
			(at 2.4511 0.199898 270)
			(size 0.0508 0.0508)
			(layers "F.Cu" "F.Mask" "F.Paste")
			(net "Net_249")
			(options
				(clearance outline)
				(anchor circle)
			)
			(primitives
				(gr_poly
					(pts
						(arc
							(start -0.254 0.1016)
							(mid -0.3556 0)
							(end -0.254 -0.1016)
						)
						(xy 0.3556 -0.1016) (xy 0.3556 0.1016)
					)
					(width 0)
					(fill yes)
				)
			)
		)
		(pad "26" smd custom
			(at 2.4511 -0.199898 270)
			(size 0.0508 0.0508)
			(layers "F.Cu" "F.Mask" "F.Paste")
			(net "Net_248")
			(options
				(clearance outline)
				(anchor circle)
			)
			(primitives
				(gr_poly
					(pts
						(arc
							(start -0.254 0.1016)
							(mid -0.3556 0)
							(end -0.254 -0.1016)
						)
						(xy 0.3556 -0.1016) (xy 0.3556 0.1016)
					)
					(width 0)
					(fill yes)
				)
			)
		)
		(pad "27" smd custom
			(at 2.4511 -0.599948 270)
			(size 0.0508 0.0508)
			(layers "F.Cu" "F.Mask" "F.Paste")
			(net "GND")
			(options
				(clearance outline)
				(anchor circle)
			)
			(primitives
				(gr_poly
					(pts
						(arc
							(start -0.254 0.1016)
							(mid -0.3556 0)
							(end -0.254 -0.1016)
						)
						(xy 0.3556 -0.1016) (xy 0.3556 0.1016)
					)
					(width 0)
					(fill yes)
				)
			)
		)
		(pad "28" smd custom
			(at 2.4511 -0.999998 270)
			(size 0.0508 0.0508)
			(layers "F.Cu" "F.Mask" "F.Paste")
			(net "Net_272")
			(options
				(clearance outline)
				(anchor circle)
			)
			(primitives
				(gr_poly
					(pts
						(arc
							(start -0.254 0.1016)
							(mid -0.3556 0)
							(end -0.254 -0.1016)
						)
						(xy 0.3556 -0.1016) (xy 0.3556 0.1016)
					)
					(width 0)
					(fill yes)
				)
			)
		)
		(pad "29" smd custom
			(at 2.4511 -1.400048 270)
			(size 0.0508 0.0508)
			(layers "F.Cu" "F.Mask" "F.Paste")
			(net "Net_238")
			(options
				(clearance outline)
				(anchor circle)
			)
			(primitives
				(gr_poly
					(pts
						(arc
							(start -0.254 0.1016)
							(mid -0.3556 0)
							(end -0.254 -0.1016)
						)
						(xy 0.3556 -0.1016) (xy 0.3556 0.1016)
					)
					(width 0)
					(fill yes)
				)
			)
		)
		(pad "30" smd custom
			(at 2.4511 -1.800098 270)
			(size 0.0508 0.0508)
			(layers "F.Cu" "F.Mask" "F.Paste")
			(net "Net_237")
			(options
				(clearance outline)
				(anchor circle)
			)
			(primitives
				(gr_poly
					(pts
						(arc
							(start -0.254 0.1016)
							(mid -0.3556 0)
							(end -0.254 -0.1016)
						)
						(xy 0.3556 -0.1016) (xy 0.3556 0.1016)
					)
					(width 0)
					(fill yes)
				)
			)
		)
		(pad "31" smd custom
			(at 1.800098 -2.4511 270)
			(size 0.0508 0.0508)
			(layers "F.Cu" "F.Mask" "F.Paste")
			(net "Net_235")
			(options
				(clearance outline)
				(anchor circle)
			)
			(primitives
				(gr_poly
					(pts
						(arc
							(start 0.1016 0.254)
							(mid 0 0.3556)
							(end -0.1016 0.254)
						)
						(xy -0.1016 -0.3556) (xy 0.1016 -0.3556)
					)
					(width 0)
					(fill yes)
				)
			)
		)
		(pad "32" smd custom
			(at 1.400048 -2.4511 270)
			(size 0.0508 0.0508)
			(layers "F.Cu" "F.Mask" "F.Paste")
			(net "GND")
			(options
				(clearance outline)
				(anchor circle)
			)
			(primitives
				(gr_poly
					(pts
						(arc
							(start 0.1016 0.254)
							(mid 0 0.3556)
							(end -0.1016 0.254)
						)
						(xy -0.1016 -0.3556) (xy 0.1016 -0.3556)
					)
					(width 0)
					(fill yes)
				)
			)
		)
		(pad "33" smd custom
			(at 0.999998 -2.4511 270)
			(size 0.0508 0.0508)
			(layers "F.Cu" "F.Mask" "F.Paste")
			(net "VR_PVDDQ_KLM_XADDR2")
			(options
				(clearance outline)
				(anchor circle)
			)
			(primitives
				(gr_poly
					(pts
						(arc
							(start 0.1016 0.254)
							(mid 0 0.3556)
							(end -0.1016 0.254)
						)
						(xy -0.1016 -0.3556) (xy 0.1016 -0.3556)
					)
					(width 0)
					(fill yes)
				)
			)
		)
		(pad "34" smd custom
			(at 0.599948 -2.4511 270)
			(size 0.0508 0.0508)
			(layers "F.Cu" "F.Mask" "F.Paste")
			(net "Net_236")
			(options
				(clearance outline)
				(anchor circle)
			)
			(primitives
				(gr_poly
					(pts
						(arc
							(start 0.1016 0.254)
							(mid 0 0.3556)
							(end -0.1016 0.254)
						)
						(xy -0.1016 -0.3556) (xy 0.1016 -0.3556)
					)
					(width 0)
					(fill yes)
				)
			)
		)
		(pad "35" smd custom
			(at 0.199898 -2.4511 270)
			(size 0.0508 0.0508)
			(layers "F.Cu" "F.Mask" "F.Paste")
			(net "A_TSENSE_PVDDQ_KLM")
			(options
				(clearance outline)
				(anchor circle)
			)
			(primitives
				(gr_poly
					(pts
						(arc
							(start 0.1016 0.254)
							(mid 0 0.3556)
							(end -0.1016 0.254)
						)
						(xy -0.1016 -0.3556) (xy 0.1016 -0.3556)
					)
					(width 0)
					(fill yes)
				)
			)
		)
		(pad "36" smd custom
			(at -0.199898 -2.4511 270)
			(size 0.0508 0.0508)
			(layers "F.Cu" "F.Mask" "F.Paste")
			(net "VR_PVDDQ_KLM_XADDR1")
			(options
				(clearance outline)
				(anchor circle)
			)
			(primitives
				(gr_poly
					(pts
						(arc
							(start 0.1016 0.254)
							(mid 0 0.3556)
							(end -0.1016 0.254)
						)
						(xy -0.1016 -0.3556) (xy 0.1016 -0.3556)
					)
					(width 0)
					(fill yes)
				)
			)
		)
		(pad "37" smd custom
			(at -0.599948 -2.4511 270)
			(size 0.0508 0.0508)
			(layers "F.Cu" "F.Mask" "F.Paste")
			(net "VR_PVDDQ_KLM_VINSEN")
			(options
				(clearance outline)
				(anchor circle)
			)
			(primitives
				(gr_poly
					(pts
						(arc
							(start 0.1016 0.254)
							(mid 0 0.3556)
							(end -0.1016 0.254)
						)
						(xy -0.1016 -0.3556) (xy 0.1016 -0.3556)
					)
					(width 0)
					(fill yes)
				)
			)
		)
		(pad "38" smd custom
			(at -0.999998 -2.4511 270)
			(size 0.0508 0.0508)
			(layers "F.Cu" "F.Mask" "F.Paste")
			(net "VR_PVDDQ_KLM_AIINSEN")
			(options
				(clearance outline)
				(anchor circle)
			)
			(primitives
				(gr_poly
					(pts
						(arc
							(start 0.1016 0.254)
							(mid 0 0.3556)
							(end -0.1016 0.254)
						)
						(xy -0.1016 -0.3556) (xy 0.1016 -0.3556)
					)
					(width 0)
					(fill yes)
				)
			)
		)
		(pad "39" smd custom
			(at -1.400048 -2.4511 270)
			(size 0.0508 0.0508)
			(layers "F.Cu" "F.Mask" "F.Paste")
			(net "VR_PVDDQ_KLM_VDD")
			(options
				(clearance outline)
				(anchor circle)
			)
			(primitives
				(gr_poly
					(pts
						(arc
							(start 0.1016 0.254)
							(mid 0 0.3556)
							(end -0.1016 0.254)
						)
						(xy -0.1016 -0.3556) (xy 0.1016 -0.3556)
					)
					(width 0)
					(fill yes)
				)
			)
		)
		(pad "40" smd custom
			(at -1.800098 -2.4511 270)
			(size 0.0508 0.0508)
			(layers "F.Cu" "F.Mask" "F.Paste")
			(net "VR_PVDDQ_KLM_VD12")
			(options
				(clearance outline)
				(anchor circle)
			)
			(primitives
				(gr_poly
					(pts
						(arc
							(start 0.1016 0.254)
							(mid 0 0.3556)
							(end -0.1016 0.254)
						)
						(xy -0.1016 -0.3556) (xy 0.1016 -0.3556)
					)
					(width 0)
					(fill yes)
				)
			)
		)
		(pad "41" smd rect
			(at 0 0 270)
			(size 3.683 3.683)
			(layers "F.Cu" "F.Mask" "F.Paste")
			(net "GND")
		)
		(zone
			(layer "F.Cu")
			(hatch none 0.5)
			(connect_pads
				(clearance 0)
			)
			(min_thickness 0.25)
			(keepout
				(tracks allowed)
				(vias not_allowed)
				(pads allowed)
				(copperpour not_allowed)
				(footprints allowed)
			)
			(placement
				(enabled no)
				(sheetname "")
			)
			(fill
				(thermal_gap 0.5)
				(thermal_bridge_width 0.5)
				(island_removal_mode 0)
			)
			(polygon
				(pts
					(xy -0.0381 -130.0607) (xy 0.42291 -130.0607) (xy 0.42291 -129.8067) (xy 0.2159 -129.8067) (xy 0.2159 -126.1237)
					(xy 3.8989 -126.1237) (xy 3.8989 -129.8067) (xy 0.424942 -129.8067) (xy 0.424942 -130.0607) (xy 4.1529 -130.0607)
					(xy 4.1529 -125.8697) (xy -0.0381 -125.8697)
				)
			)
		)
		(zone
			(layer "F.Cu")
			(hatch none 0.5)
			(connect_pads
				(clearance 0)
			)
			(min_thickness 0.25)
			(keepout
				(tracks not_allowed)
				(vias allowed)
				(pads allowed)
				(copperpour not_allowed)
				(footprints allowed)
			)
			(placement
				(enabled no)
				(sheetname "")
			)
			(fill
				(thermal_gap 0.5)
				(thermal_bridge_width 0.5)
				(island_removal_mode 0)
			)
			(polygon
				(pts
					(xy -0.0381 -130.0607) (xy 0.42291 -130.0607) (xy 0.42291 -129.8067) (xy 0.2159 -129.8067) (xy 0.2159 -126.1237)
					(xy 3.8989 -126.1237) (xy 3.8989 -129.8067) (xy 0.424942 -129.8067) (xy 0.424942 -130.0607) (xy 4.1529 -130.0607)
					(xy 4.1529 -125.8697) (xy -0.0381 -125.8697)
				)
			)
		)
	)
	(footprint ""
		(layer "F.Cu")
		(at 344.043 -132.8547 90)
		(property "Reference" "EU7B1"
			(at 5.29463 -1.27 0)
			(unlocked yes)
			(layer "F.SilkS")
			(effects
				(font
					(size 0.7874 0.5842)
					(thickness 0.1524)
				)
				(justify left)
			)
		)
		(property "Value" ""
			(at 0 0 90)
			(layer "F.Fab")
			(effects
				(font
					(size 1.27 1.27)
				)
			)
		)
		(duplicate_pad_numbers_are_jumpers no)
		(fp_line
			(start 3.4671 -3.4671)
			(end 3.4671 3.4671)
			(stroke
				(width 0.1524)
				(type default)
			)
			(layer "F.SilkS")
		)
		(fp_line
			(start -3.4671 -3.4671)
			(end 3.4671 -3.4671)
			(stroke
				(width 0.1524)
				(type default)
			)
			(layer "F.SilkS")
		)
		(fp_line
			(start 3.10007 -3.10007)
			(end 3.10007 -2.900934)
			(stroke
				(width 0.1524)
				(type default)
			)
			(layer "F.SilkS")
		)
		(fp_line
			(start 2.897886 -3.10007)
			(end 3.10007 -3.10007)
			(stroke
				(width 0.1524)
				(type default)
			)
			(layer "F.SilkS")
		)
		(fp_line
			(start -3.10007 -3.10007)
			(end -2.897886 -3.10007)
			(stroke
				(width 0.1524)
				(type default)
			)
			(layer "F.SilkS")
		)
		(fp_line
			(start -3.10007 -2.900934)
			(end -3.10007 -3.10007)
			(stroke
				(width 0.1524)
				(type default)
			)
			(layer "F.SilkS")
		)
		(fp_line
			(start 3.10007 2.897378)
			(end 3.10007 3.10007)
			(stroke
				(width 0.1524)
				(type default)
			)
			(layer "F.SilkS")
		)
		(fp_line
			(start 3.10007 3.10007)
			(end 2.897886 3.10007)
			(stroke
				(width 0.1524)
				(type default)
			)
			(layer "F.SilkS")
		)
		(fp_line
			(start -2.897886 3.10007)
			(end -3.10007 3.10007)
			(stroke
				(width 0.1524)
				(type default)
			)
			(layer "F.SilkS")
		)
		(fp_line
			(start -3.10007 3.10007)
			(end -3.10007 2.897378)
			(stroke
				(width 0.1524)
				(type default)
			)
			(layer "F.SilkS")
		)
		(fp_line
			(start 3.4671 3.4671)
			(end -3.4671 3.4671)
			(stroke
				(width 0.1524)
				(type default)
			)
			(layer "F.SilkS")
		)
		(fp_line
			(start -3.4671 3.4671)
			(end -3.4671 -3.4671)
			(stroke
				(width 0.1524)
				(type default)
			)
			(layer "F.SilkS")
		)
		(fp_circle
			(center -3.917696 -3.100578)
			(end -3.917696 -2.973578)
			(stroke
				(width 0.254)
				(type default)
			)
			(fill no)
			(layer "F.SilkS")
		)
		(fp_poly
			(pts
				(xy -3.4671 -3.4671) (xy -3.4671 -2.5146) (xy -2.5146 -3.4671)
			)
			(stroke
				(width 0)
				(type default)
			)
			(fill yes)
			(layer "F.SilkS")
		)
		(fp_rect
			(start -2.1971 -0.1905)
			(end -0.6985 -2.1971)
			(stroke
				(width 0)
				(type default)
			)
			(fill yes)
			(layer "F.Paste")
		)
		(fp_rect
			(start -0.1905 2.1971)
			(end 2.1971 -2.1971)
			(stroke
				(width 0)
				(type default)
			)
			(fill yes)
			(layer "F.Paste")
		)
		(fp_rect
			(start -2.1971 2.1971)
			(end -0.6985 0.1905)
			(stroke
				(width 0)
				(type default)
			)
			(fill yes)
			(layer "F.Paste")
		)
		(fp_poly
			(pts
				(xy -3.10007 -3.10007) (xy -3.10007 3.10007) (xy 3.10007 3.10007) (xy 3.10007 -3.10007)
			)
			(stroke
				(width 0)
				(type default)
			)
			(fill no)
			(layer "F.CrtYd")
		)
		(fp_line
			(start 3.10007 -3.10007)
			(end 3.10007 3.10007)
			(stroke
				(width 0.1)
				(type default)
			)
			(layer "F.Fab")
		)
		(fp_line
			(start -3.10007 -3.10007)
			(end 3.10007 -3.10007)
			(stroke
				(width 0.1)
				(type default)
			)
			(layer "F.Fab")
		)
		(fp_line
			(start 3.10007 3.10007)
			(end -3.10007 3.10007)
			(stroke
				(width 0.1)
				(type default)
			)
			(layer "F.Fab")
		)
		(fp_line
			(start -3.10007 3.10007)
			(end -3.10007 -3.10007)
			(stroke
				(width 0.1)
				(type default)
			)
			(layer "F.Fab")
		)
		(fp_circle
			(center -3.917696 -3.100578)
			(end -3.917696 -2.973578)
			(stroke
				(width 0.254)
				(type default)
			)
			(fill no)
			(layer "F.Fab")
		)
		(pad "1" smd custom
			(at -2.8321 -2.249932 90)
			(size 0.06985 0.06985)
			(layers "F.Cu" "F.Mask" "F.Paste")
			(net "VR_PVPP_DEF_SS")
			(options
				(clearance outline)
				(anchor circle)
			)
			(primitives
				(gr_poly
					(pts
						(arc
							(start 0.2413 -0.1397)
							(mid 0.381 0)
							(end 0.2413 0.1397)
						)
						(xy -0.381 0.1397) (xy -0.381 -0.1397)
					)
					(width 0)
					(fill yes)
				)
			)
		)
		(pad "2" smd custom
			(at -2.8321 -1.75006 90)
			(size 0.06985 0.06985)
			(layers "F.Cu" "F.Mask" "F.Paste")
			(net "VR_FB_PVPP_DEF")
			(options
				(clearance outline)
				(anchor circle)
			)
			(primitives
				(gr_poly
					(pts
						(arc
							(start 0.2413 -0.1397)
							(mid 0.381 0)
							(end 0.2413 0.1397)
						)
						(xy -0.381 0.1397) (xy -0.381 -0.1397)
					)
					(width 0)
					(fill yes)
				)
			)
		)
		(pad "3" smd custom
			(at -2.8321 -1.249934 90)
			(size 0.06985 0.06985)
			(layers "F.Cu" "F.Mask" "F.Paste")
			(net "VR_COMP_PVPP_DEF_3")
			(options
				(clearance outline)
				(anchor circle)
			)
			(primitives
				(gr_poly
					(pts
						(arc
							(start 0.2413 -0.1397)
							(mid 0.381 0)
							(end 0.2413 0.1397)
						)
						(xy -0.381 0.1397) (xy -0.381 -0.1397)
					)
					(width 0)
					(fill yes)
				)
			)
		)
		(pad "4" smd custom
			(at -2.8321 -0.750062 90)
			(size 0.06985 0.06985)
			(layers "F.Cu" "F.Mask" "F.Paste")
			(net "VR_PVPP_DEF_ISET")
			(options
				(clearance outline)
				(anchor circle)
			)
			(primitives
				(gr_poly
					(pts
						(arc
							(start 0.2413 -0.1397)
							(mid 0.381 0)
							(end 0.2413 0.1397)
						)
						(xy -0.381 0.1397) (xy -0.381 -0.1397)
					)
					(width 0)
					(fill yes)
				)
			)
		)
		(pad "5" smd custom
			(at -2.8321 -0.249936 90)
			(size 0.06985 0.06985)
			(layers "F.Cu" "F.Mask" "F.Paste")
			(net "AGND_PVPP_DEF")
			(options
				(clearance outline)
				(anchor circle)
			)
			(primitives
				(gr_poly
					(pts
						(arc
							(start 0.2413 -0.1397)
							(mid 0.381 0)
							(end 0.2413 0.1397)
						)
						(xy -0.381 0.1397) (xy -0.381 -0.1397)
					)
					(width 0)
					(fill yes)
				)
			)
		)
		(pad "6" smd custom
			(at -2.8321 0.249936 90)
			(size 0.06985 0.06985)
			(layers "F.Cu" "F.Mask" "F.Paste")
			(net "AGND_PVPP_DEF")
			(options
				(clearance outline)
				(anchor circle)
			)
			(primitives
				(gr_poly
					(pts
						(arc
							(start 0.2413 -0.1397)
							(mid 0.381 0)
							(end 0.2413 0.1397)
						)
						(xy -0.381 0.1397) (xy -0.381 -0.1397)
					)
					(width 0)
					(fill yes)
				)
			)
		)
		(pad "7" smd custom
			(at -2.8321 0.750062 90)
			(size 0.06985 0.06985)
			(layers "F.Cu" "F.Mask" "F.Paste")
			(net "PWRGD_PVPP_DEF_R")
			(options
				(clearance outline)
				(anchor circle)
			)
			(primitives
				(gr_poly
					(pts
						(arc
							(start 0.2413 -0.1397)
							(mid 0.381 0)
							(end 0.2413 0.1397)
						)
						(xy -0.381 0.1397) (xy -0.381 -0.1397)
					)
					(width 0)
					(fill yes)
				)
			)
		)
		(pad "8" smd custom
			(at -2.8321 1.249934 90)
			(size 0.06985 0.06985)
			(layers "F.Cu" "F.Mask" "F.Paste")
			(net "VR_FET_SW_P12V_STBY_PVPP_DEF")
			(options
				(clearance outline)
				(anchor circle)
			)
			(primitives
				(gr_poly
					(pts
						(arc
							(start 0.2413 -0.1397)
							(mid 0.381 0)
							(end 0.2413 0.1397)
						)
						(xy -0.381 0.1397) (xy -0.381 -0.1397)
					)
					(width 0)
					(fill yes)
				)
			)
		)
		(pad "9" smd custom
			(at -2.8321 1.75006 90)
			(size 0.06985 0.06985)
			(layers "F.Cu" "F.Mask" "F.Paste")
			(net "VR_FET_SW_P12V_STBY_PVPP_DEF")
			(options
				(clearance outline)
				(anchor circle)
			)
			(primitives
				(gr_poly
					(pts
						(arc
							(start 0.2413 -0.1397)
							(mid 0.381 0)
							(end 0.2413 0.1397)
						)
						(xy -0.381 0.1397) (xy -0.381 -0.1397)
					)
					(width 0)
					(fill yes)
				)
			)
		)
		(pad "10" smd custom
			(at -2.8321 2.249932 90)
			(size 0.06985 0.06985)
			(layers "F.Cu" "F.Mask" "F.Paste")
			(net "VR_FET_SW_P12V_STBY_PVPP_DEF")
			(options
				(clearance outline)
				(anchor circle)
			)
			(primitives
				(gr_poly
					(pts
						(arc
							(start 0.2413 -0.1397)
							(mid 0.381 0)
							(end 0.2413 0.1397)
						)
						(xy -0.381 0.1397) (xy -0.381 -0.1397)
					)
					(width 0)
					(fill yes)
				)
			)
		)
		(pad "11" smd custom
			(at -2.249932 2.8321 90)
			(size 0.06985 0.06985)
			(layers "F.Cu" "F.Mask" "F.Paste")
			(net "VR_FET_SW_P12V_STBY_PVPP_DEF")
			(options
				(clearance outline)
				(anchor circle)
			)
			(primitives
				(gr_poly
					(pts
						(arc
							(start -0.1397 -0.2413)
							(mid 0 -0.381)
							(end 0.1397 -0.2413)
						)
						(xy 0.1397 0.381) (xy -0.1397 0.381)
					)
					(width 0)
					(fill yes)
				)
			)
		)
		(pad "12" smd custom
			(at -1.75006 2.8321 90)
			(size 0.06985 0.06985)
			(layers "F.Cu" "F.Mask" "F.Paste")
			(net "VR_FET_SW_P12V_STBY_PVPP_DEF")
			(options
				(clearance outline)
				(anchor circle)
			)
			(primitives
				(gr_poly
					(pts
						(arc
							(start -0.1397 -0.2413)
							(mid 0 -0.381)
							(end 0.1397 -0.2413)
						)
						(xy 0.1397 0.381) (xy -0.1397 0.381)
					)
					(width 0)
					(fill yes)
				)
			)
		)
		(pad "13" smd custom
			(at -1.249934 2.8321 90)
			(size 0.06985 0.06985)
			(layers "F.Cu" "F.Mask" "F.Paste")
			(net "VR_FET_SW_P12V_STBY_PVPP_DEF")
			(options
				(clearance outline)
				(anchor circle)
			)
			(primitives
				(gr_poly
					(pts
						(arc
							(start -0.1397 -0.2413)
							(mid 0 -0.381)
							(end 0.1397 -0.2413)
						)
						(xy 0.1397 0.381) (xy -0.1397 0.381)
					)
					(width 0)
					(fill yes)
				)
			)
		)
		(pad "14" smd custom
			(at -0.750062 2.8321 90)
			(size 0.06985 0.06985)
			(layers "F.Cu" "F.Mask" "F.Paste")
			(net "VR_FET_SW_P12V_STBY_PVPP_DEF")
			(options
				(clearance outline)
				(anchor circle)
			)
			(primitives
				(gr_poly
					(pts
						(arc
							(start -0.1397 -0.2413)
							(mid 0 -0.381)
							(end 0.1397 -0.2413)
						)
						(xy 0.1397 0.381) (xy -0.1397 0.381)
					)
					(width 0)
					(fill yes)
				)
			)
		)
		(pad "15" smd custom
			(at -0.249936 2.8321 90)
			(size 0.06985 0.06985)
			(layers "F.Cu" "F.Mask" "F.Paste")
			(net "VR_PVPP_DEF_PHASE")
			(options
				(clearance outline)
				(anchor circle)
			)
			(primitives
				(gr_poly
					(pts
						(arc
							(start -0.1397 -0.2413)
							(mid 0 -0.381)
							(end 0.1397 -0.2413)
						)
						(xy 0.1397 0.381) (xy -0.1397 0.381)
					)
					(width 0)
					(fill yes)
				)
			)
		)
		(pad "16" smd custom
			(at 0.249936 2.8321 90)
			(size 0.06985 0.06985)
			(layers "F.Cu" "F.Mask" "F.Paste")
			(net "GND")
			(options
				(clearance outline)
				(anchor circle)
			)
			(primitives
				(gr_poly
					(pts
						(arc
							(start -0.1397 -0.2413)
							(mid 0 -0.381)
							(end 0.1397 -0.2413)
						)
						(xy 0.1397 0.381) (xy -0.1397 0.381)
					)
					(width 0)
					(fill yes)
				)
			)
		)
		(pad "17" smd custom
			(at 0.750062 2.8321 90)
			(size 0.06985 0.06985)
			(layers "F.Cu" "F.Mask" "F.Paste")
			(net "GND")
			(options
				(clearance outline)
				(anchor circle)
			)
			(primitives
				(gr_poly
					(pts
						(arc
							(start -0.1397 -0.2413)
							(mid 0 -0.381)
							(end 0.1397 -0.2413)
						)
						(xy 0.1397 0.381) (xy -0.1397 0.381)
					)
					(width 0)
					(fill yes)
				)
			)
		)
		(pad "18" smd custom
			(at 1.249934 2.8321 90)
			(size 0.06985 0.06985)
			(layers "F.Cu" "F.Mask" "F.Paste")
			(net "GND")
			(options
				(clearance outline)
				(anchor circle)
			)
			(primitives
				(gr_poly
					(pts
						(arc
							(start -0.1397 -0.2413)
							(mid 0 -0.381)
							(end 0.1397 -0.2413)
						)
						(xy 0.1397 0.381) (xy -0.1397 0.381)
					)
					(width 0)
					(fill yes)
				)
			)
		)
		(pad "19" smd custom
			(at 1.75006 2.8321 90)
			(size 0.06985 0.06985)
			(layers "F.Cu" "F.Mask" "F.Paste")
			(net "GND")
			(options
				(clearance outline)
				(anchor circle)
			)
			(primitives
				(gr_poly
					(pts
						(arc
							(start -0.1397 -0.2413)
							(mid 0 -0.381)
							(end 0.1397 -0.2413)
						)
						(xy 0.1397 0.381) (xy -0.1397 0.381)
					)
					(width 0)
					(fill yes)
				)
			)
		)
		(pad "20" smd custom
			(at 2.249932 2.8321 90)
			(size 0.06985 0.06985)
			(layers "F.Cu" "F.Mask" "F.Paste")
			(net "GND")
			(options
				(clearance outline)
				(anchor circle)
			)
			(primitives
				(gr_poly
					(pts
						(arc
							(start -0.1397 -0.2413)
							(mid 0 -0.381)
							(end 0.1397 -0.2413)
						)
						(xy 0.1397 0.381) (xy -0.1397 0.381)
					)
					(width 0)
					(fill yes)
				)
			)
		)
		(pad "21" smd custom
			(at 2.8321 2.249932 90)
			(size 0.06985 0.06985)
			(layers "F.Cu" "F.Mask" "F.Paste")
			(net "GND")
			(options
				(clearance outline)
				(anchor circle)
			)
			(primitives
				(gr_poly
					(pts
						(arc
							(start -0.2413 0.1397)
							(mid -0.381 0)
							(end -0.2413 -0.1397)
						)
						(xy 0.381 -0.1397) (xy 0.381 0.1397)
					)
					(width 0)
					(fill yes)
				)
			)
		)
		(pad "22" smd custom
			(at 2.8321 1.75006 90)
			(size 0.06985 0.06985)
			(layers "F.Cu" "F.Mask" "F.Paste")
			(net "GND")
			(options
				(clearance outline)
				(anchor circle)
			)
			(primitives
				(gr_poly
					(pts
						(arc
							(start -0.2413 0.1397)
							(mid -0.381 0)
							(end -0.2413 -0.1397)
						)
						(xy 0.381 -0.1397) (xy 0.381 0.1397)
					)
					(width 0)
					(fill yes)
				)
			)
		)
		(pad "23" smd custom
			(at 2.8321 1.249934 90)
			(size 0.06985 0.06985)
			(layers "F.Cu" "F.Mask" "F.Paste")
			(net "GND")
			(options
				(clearance outline)
				(anchor circle)
			)
			(primitives
				(gr_poly
					(pts
						(arc
							(start -0.2413 0.1397)
							(mid -0.381 0)
							(end -0.2413 -0.1397)
						)
						(xy 0.381 -0.1397) (xy 0.381 0.1397)
					)
					(width 0)
					(fill yes)
				)
			)
		)
		(pad "24" smd custom
			(at 2.8321 0.750062 90)
			(size 0.06985 0.06985)
			(layers "F.Cu" "F.Mask" "F.Paste")
			(net "GND")
			(options
				(clearance outline)
				(anchor circle)
			)
			(primitives
				(gr_poly
					(pts
						(arc
							(start -0.2413 0.1397)
							(mid -0.381 0)
							(end -0.2413 -0.1397)
						)
						(xy 0.381 -0.1397) (xy 0.381 0.1397)
					)
					(width 0)
					(fill yes)
				)
			)
		)
		(pad "25" smd custom
			(at 2.8321 0.249936 90)
			(size 0.06985 0.06985)
			(layers "F.Cu" "F.Mask" "F.Paste")
			(net "GND")
			(options
				(clearance outline)
				(anchor circle)
			)
			(primitives
				(gr_poly
					(pts
						(arc
							(start -0.2413 0.1397)
							(mid -0.381 0)
							(end -0.2413 -0.1397)
						)
						(xy 0.381 -0.1397) (xy 0.381 0.1397)
					)
					(width 0)
					(fill yes)
				)
			)
		)
		(pad "26" smd custom
			(at 2.8321 -0.249936 90)
			(size 0.06985 0.06985)
			(layers "F.Cu" "F.Mask" "F.Paste")
			(net "GND")
			(options
				(clearance outline)
				(anchor circle)
			)
			(primitives
				(gr_poly
					(pts
						(arc
							(start -0.2413 0.1397)
							(mid -0.381 0)
							(end -0.2413 -0.1397)
						)
						(xy 0.381 -0.1397) (xy 0.381 0.1397)
					)
					(width 0)
					(fill yes)
				)
			)
		)
		(pad "27" smd custom
			(at 2.8321 -0.750062 90)
			(size 0.06985 0.06985)
			(layers "F.Cu" "F.Mask" "F.Paste")
			(net "GND")
			(options
				(clearance outline)
				(anchor circle)
			)
			(primitives
				(gr_poly
					(pts
						(arc
							(start -0.2413 0.1397)
							(mid -0.381 0)
							(end -0.2413 -0.1397)
						)
						(xy 0.381 -0.1397) (xy 0.381 0.1397)
					)
					(width 0)
					(fill yes)
				)
			)
		)
		(pad "28" smd custom
			(at 2.8321 -1.249934 90)
			(size 0.06985 0.06985)
			(layers "F.Cu" "F.Mask" "F.Paste")
			(net "GND")
			(options
				(clearance outline)
				(anchor circle)
			)
			(primitives
				(gr_poly
					(pts
						(arc
							(start -0.2413 0.1397)
							(mid -0.381 0)
							(end -0.2413 -0.1397)
						)
						(xy 0.381 -0.1397) (xy 0.381 0.1397)
					)
					(width 0)
					(fill yes)
				)
			)
		)
		(pad "29" smd custom
			(at 2.8321 -1.75006 90)
			(size 0.06985 0.06985)
			(layers "F.Cu" "F.Mask" "F.Paste")
			(net "VR_PVPP_DEF_PHASE")
			(options
				(clearance outline)
				(anchor circle)
			)
			(primitives
				(gr_poly
					(pts
						(arc
							(start -0.2413 0.1397)
							(mid -0.381 0)
							(end -0.2413 -0.1397)
						)
						(xy 0.381 -0.1397) (xy 0.381 0.1397)
					)
					(width 0)
					(fill yes)
				)
			)
		)
		(pad "30" smd custom
			(at 2.8321 -2.249932 90)
			(size 0.06985 0.06985)
			(layers "F.Cu" "F.Mask" "F.Paste")
			(net "VR_PVPP_DEF_PHASE")
			(options
				(clearance outline)
				(anchor circle)
			)
			(primitives
				(gr_poly
					(pts
						(arc
							(start -0.2413 0.1397)
							(mid -0.381 0)
							(end -0.2413 -0.1397)
						)
						(xy 0.381 -0.1397) (xy 0.381 0.1397)
					)
					(width 0)
					(fill yes)
				)
			)
		)
		(pad "31" smd custom
			(at 2.249932 -2.8321 90)
			(size 0.06985 0.06985)
			(layers "F.Cu" "F.Mask" "F.Paste")
			(net "VR_PVPP_DEF_PHASE")
			(options
				(clearance outline)
				(anchor circle)
			)
			(primitives
				(gr_poly
					(pts
						(arc
							(start 0.1397 0.2413)
							(mid 0 0.381)
							(end -0.1397 0.2413)
						)
						(xy -0.1397 -0.381) (xy 0.1397 -0.381)
					)
					(width 0)
					(fill yes)
				)
			)
		)
		(pad "32" smd custom
			(at 1.75006 -2.8321 90)
			(size 0.06985 0.06985)
			(layers "F.Cu" "F.Mask" "F.Paste")
			(net "VR_PVPP_DEF_PHASE")
			(options
				(clearance outline)
				(anchor circle)
			)
			(primitives
				(gr_poly
					(pts
						(arc
							(start 0.1397 0.2413)
							(mid 0 0.381)
							(end -0.1397 0.2413)
						)
						(xy -0.1397 -0.381) (xy 0.1397 -0.381)
					)
					(width 0)
					(fill yes)
				)
			)
		)
		(pad "33" smd custom
			(at 1.249934 -2.8321 90)
			(size 0.06985 0.06985)
			(layers "F.Cu" "F.Mask" "F.Paste")
			(net "VR_PVPP_DEF_PHASE")
			(options
				(clearance outline)
				(anchor circle)
			)
			(primitives
				(gr_poly
					(pts
						(arc
							(start 0.1397 0.2413)
							(mid 0 0.381)
							(end -0.1397 0.2413)
						)
						(xy -0.1397 -0.381) (xy 0.1397 -0.381)
					)
					(width 0)
					(fill yes)
				)
			)
		)
		(pad "34" smd custom
			(at 0.750062 -2.8321 90)
			(size 0.06985 0.06985)
			(layers "F.Cu" "F.Mask" "F.Paste")
			(net "VR_PVPP_DEF_PHASE")
			(options
				(clearance outline)
				(anchor circle)
			)
			(primitives
				(gr_poly
					(pts
						(arc
							(start 0.1397 0.2413)
							(mid 0 0.381)
							(end -0.1397 0.2413)
						)
						(xy -0.1397 -0.381) (xy 0.1397 -0.381)
					)
					(width 0)
					(fill yes)
				)
			)
		)
		(pad "35" smd custom
			(at 0.249936 -2.8321 90)
			(size 0.06985 0.06985)
			(layers "F.Cu" "F.Mask" "F.Paste")
			(net "VR_PVPP_DEF_PHASE")
			(options
				(clearance outline)
				(anchor circle)
			)
			(primitives
				(gr_poly
					(pts
						(arc
							(start 0.1397 0.2413)
							(mid 0 0.381)
							(end -0.1397 0.2413)
						)
						(xy -0.1397 -0.381) (xy 0.1397 -0.381)
					)
					(width 0)
					(fill yes)
				)
			)
		)
		(pad "36" smd custom
			(at -0.249936 -2.8321 90)
			(size 0.06985 0.06985)
			(layers "F.Cu" "F.Mask" "F.Paste")
			(net "VR_PVPP_DEF_BOOT")
			(options
				(clearance outline)
				(anchor circle)
			)
			(primitives
				(gr_poly
					(pts
						(arc
							(start 0.1397 0.2413)
							(mid 0 0.381)
							(end -0.1397 0.2413)
						)
						(xy -0.1397 -0.381) (xy 0.1397 -0.381)
					)
					(width 0)
					(fill yes)
				)
			)
		)
		(pad "37" smd custom
			(at -0.750062 -2.8321 90)
			(size 0.06985 0.06985)
			(layers "F.Cu" "F.Mask" "F.Paste")
			(net "GND")
			(options
				(clearance outline)
				(anchor circle)
			)
			(primitives
				(gr_poly
					(pts
						(arc
							(start 0.1397 0.2413)
							(mid 0 0.381)
							(end -0.1397 0.2413)
						)
						(xy -0.1397 -0.381) (xy 0.1397 -0.381)
					)
					(width 0)
					(fill yes)
				)
			)
		)
		(pad "38" smd custom
			(at -1.249934 -2.8321 90)
			(size 0.06985 0.06985)
			(layers "F.Cu" "F.Mask" "F.Paste")
			(net "VR_VB_PVPP_DEF")
			(options
				(clearance outline)
				(anchor circle)
			)
			(primitives
				(gr_poly
					(pts
						(arc
							(start 0.1397 0.2413)
							(mid 0 0.381)
							(end -0.1397 0.2413)
						)
						(xy -0.1397 -0.381) (xy 0.1397 -0.381)
					)
					(width 0)
					(fill yes)
				)
			)
		)
		(pad "39" smd custom
			(at -1.75006 -2.8321 90)
			(size 0.06985 0.06985)
			(layers "F.Cu" "F.Mask" "F.Paste")
			(net "VR_FET_SW_P12V_STBY_PVPP_DEF")
			(options
				(clearance outline)
				(anchor circle)
			)
			(primitives
				(gr_poly
					(pts
						(arc
							(start 0.1397 0.2413)
							(mid 0 0.381)
							(end -0.1397 0.2413)
						)
						(xy -0.1397 -0.381) (xy 0.1397 -0.381)
					)
					(width 0)
					(fill yes)
				)
			)
		)
		(pad "40" smd custom
			(at -2.249932 -2.8321 90)
			(size 0.06985 0.06985)
			(layers "F.Cu" "F.Mask" "F.Paste")
			(net "FM_PVPP_PVDDQ_CPU0_EN_DEF")
			(options
				(clearance outline)
				(anchor circle)
			)
			(primitives
				(gr_poly
					(pts
						(arc
							(start 0.1397 0.2413)
							(mid 0 0.381)
							(end -0.1397 0.2413)
						)
						(xy -0.1397 -0.381) (xy 0.1397 -0.381)
					)
					(width 0)
					(fill yes)
				)
			)
		)
		(pad "41" smd rect
			(at -1.4478 -1.1938 90)
			(size 1.4986 2.0066)
			(layers "F.Cu" "F.Mask" "F.Paste")
			(net "GND")
		)
		(pad "42" smd rect
			(at -1.4478 1.1938 90)
			(size 1.4986 2.0066)
			(layers "F.Cu" "F.Mask" "F.Paste")
			(net "VR_FET_SW_P12V_STBY_PVPP_DEF")
		)
		(pad "43" smd rect
			(at 1.0033 0 90)
			(size 2.3876 4.3942)
			(layers "F.Cu" "F.Mask" "F.Paste")
			(net "VR_PVPP_DEF_PHASE")
		)
	)
	(footprint ""
		(layer "F.Cu")
		(at 205.0288 -50.5714 90)
		(property "Reference" "R4E16"
			(at 0 0 90)
			(layer "F.SilkS")
			(hide yes)
			(effects
				(font
					(size 1.27 1.27)
				)
			)
		)
		(property "Value" ""
			(at 0 0 90)
			(layer "F.Fab")
			(effects
				(font
					(size 1.27 1.27)
				)
			)
		)
		(duplicate_pad_numbers_are_jumpers no)
		(fp_poly
			(pts
				(xy -0.2794 -0.1016) (xy 0.2794 -0.1016) (xy 0.2794 0.9906) (xy -0.2794 0.9906)
			)
			(stroke
				(width 0)
				(type default)
			)
			(fill no)
			(layer "F.CrtYd")
		)
		(fp_line
			(start 0.2794 -0.1016)
			(end -0.2794 -0.1016)
			(stroke
				(width 0.1)
				(type default)
			)
			(layer "F.Fab")
		)
		(fp_line
			(start -0.2794 -0.1016)
			(end -0.2794 0.9906)
			(stroke
				(width 0.1)
				(type default)
			)
			(layer "F.Fab")
		)
		(fp_line
			(start 0.2794 0.9906)
			(end 0.2794 -0.1016)
			(stroke
				(width 0.1)
				(type default)
			)
			(layer "F.Fab")
		)
		(fp_line
			(start -0.2794 0.9906)
			(end 0.2794 0.9906)
			(stroke
				(width 0.1)
				(type default)
			)
			(layer "F.Fab")
		)
		(pad "1" smd rect
			(at 0 0 90)
			(size 0.508 0.508)
			(layers "F.Cu" "F.Mask" "F.Paste")
			(net "VSENSE_PVCCIN_CPU0_P")
		)
		(pad "2" smd rect
			(at 0 0.889 90)
			(size 0.508 0.508)
			(layers "F.Cu" "F.Mask" "F.Paste")
			(net "VSENSE_PVCCIN_CPU0_SKT_VSEN")
		)
		(zone
			(layer "F.Cu")
			(hatch none 0.5)
			(connect_pads
				(clearance 0)
			)
			(min_thickness 0.25)
			(keepout
				(tracks allowed)
				(vias not_allowed)
				(pads allowed)
				(copperpour not_allowed)
				(footprints allowed)
			)
			(placement
				(enabled no)
				(sheetname "")
			)
			(fill
				(thermal_gap 0.5)
				(thermal_bridge_width 0.5)
				(island_removal_mode 0)
			)
			(polygon
				(pts
					(xy 205.2828 -50.3174) (xy 205.2828 -50.8254) (xy 205.6638 -50.8254) (xy 205.6638 -50.3174)
				)
			)
		)
		(zone
			(layer "F.Cu")
			(hatch none 0.5)
			(connect_pads
				(clearance 0)
			)
			(min_thickness 0.25)
			(keepout
				(tracks not_allowed)
				(vias allowed)
				(pads allowed)
				(copperpour not_allowed)
				(footprints allowed)
			)
			(placement
				(enabled no)
				(sheetname "")
			)
			(fill
				(thermal_gap 0.5)
				(thermal_bridge_width 0.5)
				(island_removal_mode 0)
			)
			(polygon
				(pts
					(xy 205.6638 -50.3174) (xy 205.6638 -50.8254) (xy 205.2828 -50.8254) (xy 205.2828 -50.3174)
				)
			)
		)
	)
	(footprint ""
		(layer "F.Cu")
		(at 348.4118 -157.2768 -90)
		(property "Reference" "C7A17"
			(at 0 0 270)
			(layer "F.SilkS")
			(hide yes)
			(effects
				(font
					(size 1.27 1.27)
				)
			)
		)
		(property "Value" ""
			(at 0 0 270)
			(layer "F.Fab")
			(effects
				(font
					(size 1.27 1.27)
				)
			)
		)
		(duplicate_pad_numbers_are_jumpers no)
		(fp_poly
			(pts
				(xy 0.3048 -0.1016) (xy 0.3048 0.9906) (xy -0.3048 0.9906) (xy -0.3048 -0.1016)
			)
			(stroke
				(width 0)
				(type default)
			)
			(fill no)
			(layer "F.CrtYd")
		)
		(fp_line
			(start -0.3048 0.9906)
			(end 0.3048 0.9906)
			(stroke
				(width 0.1)
				(type default)
			)
			(layer "F.Fab")
		)
		(fp_line
			(start 0.3048 0.9906)
			(end 0.3048 -0.1016)
			(stroke
				(width 0.1)
				(type default)
			)
			(layer "F.Fab")
		)
		(fp_line
			(start -0.3048 -0.1016)
			(end -0.3048 0.9906)
			(stroke
				(width 0.1)
				(type default)
			)
			(layer "F.Fab")
		)
		(fp_line
			(start 0.3048 -0.1016)
			(end -0.3048 -0.1016)
			(stroke
				(width 0.1)
				(type default)
			)
			(layer "F.Fab")
		)
		(pad "1" smd rect
			(at 0 0 270)
			(size 0.508 0.508)
			(layers "F.Cu" "F.Mask" "F.Paste")
			(net "P5V_STBY")
		)
		(pad "2" smd rect
			(at 0 0.889 270)
			(size 0.508 0.508)
			(layers "F.Cu" "F.Mask" "F.Paste")
			(net "GND")
		)
		(zone
			(layer "F.Cu")
			(hatch none 0.5)
			(connect_pads
				(clearance 0)
			)
			(min_thickness 0.25)
			(keepout
				(tracks not_allowed)
				(vias allowed)
				(pads allowed)
				(copperpour not_allowed)
				(footprints allowed)
			)
			(placement
				(enabled no)
				(sheetname "")
			)
			(fill
				(thermal_gap 0.5)
				(thermal_bridge_width 0.5)
				(island_removal_mode 0)
			)
			(polygon
				(pts
					(xy 347.7768 -157.5308) (xy 347.7768 -157.0228) (xy 348.1578 -157.0228) (xy 348.1578 -157.5308)
				)
			)
		)
		(zone
			(layer "F.Cu")
			(hatch none 0.5)
			(connect_pads
				(clearance 0)
			)
			(min_thickness 0.25)
			(keepout
				(tracks allowed)
				(vias not_allowed)
				(pads allowed)
				(copperpour not_allowed)
				(footprints allowed)
			)
			(placement
				(enabled no)
				(sheetname "")
			)
			(fill
				(thermal_gap 0.5)
				(thermal_bridge_width 0.5)
				(island_removal_mode 0)
			)
			(polygon
				(pts
					(xy 348.1578 -157.5308) (xy 348.1578 -157.0228) (xy 347.7768 -157.0228) (xy 347.7768 -157.5308)
				)
			)
		)
	)
	(footprint ""
		(layer "F.Cu")
		(at 412.877 -22.9235)
		(property "Reference" "R25W57"
			(at -0.8382 -0.67818 0)
			(unlocked yes)
			(layer "F.SilkS")
			(effects
				(font
					(size 0.4064 0.254)
					(thickness 0.1524)
				)
				(justify left)
			)
		)
		(property "Value" ""
			(at 0 0 0)
			(layer "F.Fab")
			(effects
				(font
					(size 1.27 1.27)
				)
			)
		)
		(duplicate_pad_numbers_are_jumpers no)
		(fp_poly
			(pts
				(xy -0.2794 -0.1016) (xy 0.2794 -0.1016) (xy 0.2794 0.9906) (xy -0.2794 0.9906)
			)
			(stroke
				(width 0)
				(type default)
			)
			(fill no)
			(layer "F.CrtYd")
		)
		(fp_line
			(start -0.2794 -0.1016)
			(end -0.2794 0.9906)
			(stroke
				(width 0.1)
				(type default)
			)
			(layer "F.Fab")
		)
		(fp_line
			(start -0.2794 0.9906)
			(end 0.2794 0.9906)
			(stroke
				(width 0.1)
				(type default)
			)
			(layer "F.Fab")
		)
		(fp_line
			(start 0.2794 -0.1016)
			(end -0.2794 -0.1016)
			(stroke
				(width 0.1)
				(type default)
			)
			(layer "F.Fab")
		)
		(fp_line
			(start 0.2794 0.9906)
			(end 0.2794 -0.1016)
			(stroke
				(width 0.1)
				(type default)
			)
			(layer "F.Fab")
		)
		(pad "1" smd rect
			(at 0 0)
			(size 0.508 0.508)
			(layers "F.Cu" "F.Mask" "F.Paste")
			(net "PD_ADCREXT")
		)
		(pad "2" smd rect
			(at 0 0.889)
			(size 0.508 0.508)
			(layers "F.Cu" "F.Mask" "F.Paste")
			(net "GND")
		)
		(zone
			(layer "F.Cu")
			(hatch none 0.5)
			(connect_pads
				(clearance 0)
			)
			(min_thickness 0.25)
			(keepout
				(tracks allowed)
				(vias not_allowed)
				(pads allowed)
				(copperpour not_allowed)
				(footprints allowed)
			)
			(placement
				(enabled no)
				(sheetname "")
			)
			(fill
				(thermal_gap 0.5)
				(thermal_bridge_width 0.5)
				(island_removal_mode 0)
			)
			(polygon
				(pts
					(xy 412.623 -22.6695) (xy 413.131 -22.6695) (xy 413.131 -22.2885) (xy 412.623 -22.2885)
				)
			)
		)
		(zone
			(layer "F.Cu")
			(hatch none 0.5)
			(connect_pads
				(clearance 0)
			)
			(min_thickness 0.25)
			(keepout
				(tracks not_allowed)
				(vias allowed)
				(pads allowed)
				(copperpour not_allowed)
				(footprints allowed)
			)
			(placement
				(enabled no)
				(sheetname "")
			)
			(fill
				(thermal_gap 0.5)
				(thermal_bridge_width 0.5)
				(island_removal_mode 0)
			)
			(polygon
				(pts
					(xy 412.623 -22.2885) (xy 413.131 -22.2885) (xy 413.131 -22.6695) (xy 412.623 -22.6695)
				)
			)
		)
	)
	(footprint ""
		(layer "F.Cu")
		(at 453.3265 -32.131 90)
		(property "Reference" "R9F29"
			(at 0 0 90)
			(layer "F.SilkS")
			(hide yes)
			(effects
				(font
					(size 1.27 1.27)
				)
			)
		)
		(property "Value" ""
			(at 0 0 90)
			(layer "F.Fab")
			(effects
				(font
					(size 1.27 1.27)
				)
			)
		)
		(duplicate_pad_numbers_are_jumpers no)
		(fp_poly
			(pts
				(xy -0.2794 -0.1016) (xy 0.2794 -0.1016) (xy 0.2794 0.9906) (xy -0.2794 0.9906)
			)
			(stroke
				(width 0)
				(type default)
			)
			(fill no)
			(layer "F.CrtYd")
		)
		(fp_line
			(start 0.2794 -0.1016)
			(end -0.2794 -0.1016)
			(stroke
				(width 0.1)
				(type default)
			)
			(layer "F.Fab")
		)
		(fp_line
			(start -0.2794 -0.1016)
			(end -0.2794 0.9906)
			(stroke
				(width 0.1)
				(type default)
			)
			(layer "F.Fab")
		)
		(fp_line
			(start 0.2794 0.9906)
			(end 0.2794 -0.1016)
			(stroke
				(width 0.1)
				(type default)
			)
			(layer "F.Fab")
		)
		(fp_line
			(start -0.2794 0.9906)
			(end 0.2794 0.9906)
			(stroke
				(width 0.1)
				(type default)
			)
			(layer "F.Fab")
		)
		(pad "1" smd rect
			(at 0 0 90)
			(size 0.508 0.508)
			(layers "F.Cu" "F.Mask" "F.Paste")
			(net "P1V2_AUX_BMC")
		)
		(pad "2" smd rect
			(at 0 0.889 90)
			(size 0.508 0.508)
			(layers "F.Cu" "F.Mask" "F.Paste")
			(net "RST_BMC_DDR3_R_N")
		)
		(zone
			(layer "F.Cu")
			(hatch none 0.5)
			(connect_pads
				(clearance 0)
			)
			(min_thickness 0.25)
			(keepout
				(tracks allowed)
				(vias not_allowed)
				(pads allowed)
				(copperpour not_allowed)
				(footprints allowed)
			)
			(placement
				(enabled no)
				(sheetname "")
			)
			(fill
				(thermal_gap 0.5)
				(thermal_bridge_width 0.5)
				(island_removal_mode 0)
			)
			(polygon
				(pts
					(xy 453.5805 -31.877) (xy 453.5805 -32.385) (xy 453.9615 -32.385) (xy 453.9615 -31.877)
				)
			)
		)
		(zone
			(layer "F.Cu")
			(hatch none 0.5)
			(connect_pads
				(clearance 0)
			)
			(min_thickness 0.25)
			(keepout
				(tracks not_allowed)
				(vias allowed)
				(pads allowed)
				(copperpour not_allowed)
				(footprints allowed)
			)
			(placement
				(enabled no)
				(sheetname "")
			)
			(fill
				(thermal_gap 0.5)
				(thermal_bridge_width 0.5)
				(island_removal_mode 0)
			)
			(polygon
				(pts
					(xy 453.9615 -31.877) (xy 453.9615 -32.385) (xy 453.5805 -32.385) (xy 453.5805 -31.877)
				)
			)
		)
	)
	(footprint ""
		(layer "F.Cu")
		(at 279.672034 -77.382116)
		(property "Reference" "C6D7"
			(at 0 0 0)
			(layer "F.SilkS")
			(hide yes)
			(effects
				(font
					(size 1.27 1.27)
				)
			)
		)
		(property "Value" ""
			(at 0 0 0)
			(layer "F.Fab")
			(effects
				(font
					(size 1.27 1.27)
				)
			)
		)
		(duplicate_pad_numbers_are_jumpers no)
		(fp_poly
			(pts
				(xy -0.4953 -0.2032) (xy 0.4953 -0.2032) (xy 0.4953 1.6002) (xy -0.4953 1.6002)
			)
			(stroke
				(width 0)
				(type default)
			)
			(fill no)
			(layer "F.CrtYd")
		)
		(fp_line
			(start -0.4953 -0.2032)
			(end 0.4953 -0.2032)
			(stroke
				(width 0.1)
				(type default)
			)
			(layer "F.Fab")
		)
		(fp_line
			(start -0.4953 1.6002)
			(end -0.4953 -0.2032)
			(stroke
				(width 0.1)
				(type default)
			)
			(layer "F.Fab")
		)
		(fp_line
			(start 0.4953 -0.2032)
			(end 0.4953 1.6002)
			(stroke
				(width 0.1)
				(type default)
			)
			(layer "F.Fab")
		)
		(fp_line
			(start 0.4953 1.6002)
			(end -0.4953 1.6002)
			(stroke
				(width 0.1)
				(type default)
			)
			(layer "F.Fab")
		)
		(pad "1" smd rect
			(at 0 0)
			(size 0.762 0.889)
			(layers "F.Cu" "F.Mask" "F.Paste")
			(net "PVCCIO_CPU0")
		)
		(pad "2" smd rect
			(at 0 1.397)
			(size 0.762 0.889)
			(layers "F.Cu" "F.Mask" "F.Paste")
			(net "GND")
		)
		(zone
			(layer "F.Cu")
			(hatch none 0.5)
			(connect_pads
				(clearance 0)
			)
			(min_thickness 0.25)
			(keepout
				(tracks not_allowed)
				(vias allowed)
				(pads allowed)
				(copperpour not_allowed)
				(footprints allowed)
			)
			(placement
				(enabled no)
				(sheetname "")
			)
			(fill
				(thermal_gap 0.5)
				(thermal_bridge_width 0.5)
				(island_removal_mode 0)
			)
			(polygon
				(pts
					(xy 279.291034 -76.937616) (xy 280.053034 -76.937616) (xy 280.053034 -76.429616) (xy 279.291034 -76.429616)
				)
			)
		)
	)
	(footprint ""
		(layer "F.Cu")
		(at 193.7512 -99.9236 90)
		(property "Reference" "C4C8"
			(at 0 0 90)
			(layer "F.SilkS")
			(hide yes)
			(effects
				(font
					(size 1.27 1.27)
				)
			)
		)
		(property "Value" ""
			(at 0 0 90)
			(layer "F.Fab")
			(effects
				(font
					(size 1.27 1.27)
				)
			)
		)
		(duplicate_pad_numbers_are_jumpers no)
		(fp_rect
			(start -0.3048 0.9906)
			(end 0.3048 -0.1016)
			(stroke
				(width 0)
				(type default)
			)
			(fill no)
			(layer "F.CrtYd")
		)
		(fp_line
			(start 0.3048 -0.1016)
			(end -0.3048 -0.1016)
			(stroke
				(width 0.1)
				(type default)
			)
			(layer "F.Fab")
		)
		(fp_line
			(start -0.3048 -0.1016)
			(end -0.3048 0.9906)
			(stroke
				(width 0.1)
				(type default)
			)
			(layer "F.Fab")
		)
		(fp_line
			(start 0.3048 0.9906)
			(end 0.3048 -0.1016)
			(stroke
				(width 0.1)
				(type default)
			)
			(layer "F.Fab")
		)
		(fp_line
			(start -0.3048 0.9906)
			(end 0.3048 0.9906)
			(stroke
				(width 0.1)
				(type default)
			)
			(layer "F.Fab")
		)
		(pad "1" smd rect
			(at 0 0 90)
			(size 0.508 0.508)
			(layers "F.Cu" "F.Mask" "F.Paste")
			(net "VR_PVSA_CPU0_BOOT")
		)
		(pad "2" smd rect
			(at 0 0.889 90)
			(size 0.508 0.508)
			(layers "F.Cu" "F.Mask" "F.Paste")
			(net "VR_PVSA_CPU0_PHASE")
		)
		(zone
			(layer "F.Cu")
			(hatch none 0.5)
			(connect_pads
				(clearance 0)
			)
			(min_thickness 0.25)
			(keepout
				(tracks not_allowed)
				(vias allowed)
				(pads allowed)
				(copperpour not_allowed)
				(footprints allowed)
			)
			(placement
				(enabled no)
				(sheetname "")
			)
			(fill
				(thermal_gap 0.5)
				(thermal_bridge_width 0.5)
				(island_removal_mode 0)
			)
			(polygon
				(pts
					(xy 194.3862 -99.6696) (xy 194.3862 -100.1776) (xy 194.0052 -100.1776) (xy 194.0052 -99.6696)
				)
			)
		)
		(zone
			(layer "F.Cu")
			(hatch none 0.5)
			(connect_pads
				(clearance 0)
			)
			(min_thickness 0.25)
			(keepout
				(tracks allowed)
				(vias not_allowed)
				(pads allowed)
				(copperpour not_allowed)
				(footprints allowed)
			)
			(placement
				(enabled no)
				(sheetname "")
			)
			(fill
				(thermal_gap 0.5)
				(thermal_bridge_width 0.5)
				(island_removal_mode 0)
			)
			(polygon
				(pts
					(xy 194.3862 -99.6696) (xy 194.3862 -100.1776) (xy 194.0052 -100.1776) (xy 194.0052 -99.6696)
				)
			)
		)
	)
	(footprint ""
		(layer "F.Cu")
		(at 180.594 -146.812)
		(property "Reference" "C4A9"
			(at 0 0 0)
			(layer "F.SilkS")
			(hide yes)
			(effects
				(font
					(size 1.27 1.27)
				)
			)
		)
		(property "Value" ""
			(at 0 0 0)
			(layer "F.Fab")
			(effects
				(font
					(size 1.27 1.27)
				)
			)
		)
		(duplicate_pad_numbers_are_jumpers no)
		(fp_rect
			(start 0.3048 -0.1016)
			(end -0.3048 0.9906)
			(stroke
				(width 0)
				(type default)
			)
			(fill no)
			(layer "F.CrtYd")
		)
		(fp_line
			(start -0.3048 -0.1016)
			(end -0.3048 0.9906)
			(stroke
				(width 0.1)
				(type default)
			)
			(layer "F.Fab")
		)
		(fp_line
			(start -0.3048 0.9906)
			(end 0.3048 0.9906)
			(stroke
				(width 0.1)
				(type default)
			)
			(layer "F.Fab")
		)
		(fp_line
			(start 0.3048 -0.1016)
			(end -0.3048 -0.1016)
			(stroke
				(width 0.1)
				(type default)
			)
			(layer "F.Fab")
		)
		(fp_line
			(start 0.3048 0.9906)
			(end 0.3048 -0.1016)
			(stroke
				(width 0.1)
				(type default)
			)
			(layer "F.Fab")
		)
		(pad "1" smd rect
			(at 0 0)
			(size 0.508 0.508)
			(layers "F.Cu" "F.Mask" "F.Paste")
			(net "VR_PVTT_DEF_VREF")
		)
		(pad "2" smd rect
			(at 0 0.889)
			(size 0.508 0.508)
			(layers "F.Cu" "F.Mask" "F.Paste")
			(net "GND")
		)
		(zone
			(layer "F.Cu")
			(hatch none 0.5)
			(connect_pads
				(clearance 0)
			)
			(min_thickness 0.25)
			(keepout
				(tracks not_allowed)
				(vias allowed)
				(pads allowed)
				(copperpour not_allowed)
				(footprints allowed)
			)
			(placement
				(enabled no)
				(sheetname "")
			)
			(fill
				(thermal_gap 0.5)
				(thermal_bridge_width 0.5)
				(island_removal_mode 0)
			)
			(polygon
				(pts
					(xy 180.848 -146.558) (xy 180.34 -146.558) (xy 180.34 -146.177) (xy 180.848 -146.177)
				)
			)
		)
		(zone
			(layer "F.Cu")
			(hatch none 0.5)
			(connect_pads
				(clearance 0)
			)
			(min_thickness 0.25)
			(keepout
				(tracks allowed)
				(vias not_allowed)
				(pads allowed)
				(copperpour not_allowed)
				(footprints allowed)
			)
			(placement
				(enabled no)
				(sheetname "")
			)
			(fill
				(thermal_gap 0.5)
				(thermal_bridge_width 0.5)
				(island_removal_mode 0)
			)
			(polygon
				(pts
					(xy 180.848 -146.558) (xy 180.34 -146.558) (xy 180.34 -146.177) (xy 180.848 -146.177)
				)
			)
		)
	)
	(footprint ""
		(layer "F.Cu")
		(at 24.257 13.2715 -90)
		(property "Reference" "T1P34"
			(at 0 0 270)
			(layer "F.SilkS")
			(hide yes)
			(effects
				(font
					(size 1.27 1.27)
				)
			)
		)
		(property "Value" "*"
			(at 0 -3.44805 270)
			(unlocked yes)
			(layer "F.Fab")
			(hide yes)
			(effects
				(font
					(size 0.889 0.889)
					(thickness 0.1524)
				)
			)
		)
		(property "Device Type" "TPAD-SE-2P-GP_DISCRET-GA1-TPADA"
			(at 0 -4.97205 270)
			(unlocked yes)
			(layer "F.Fab")
			(hide yes)
			(effects
				(font
					(size 0.889 0.889)
					(thickness 0.1524)
				)
			)
		)
		(duplicate_pad_numbers_are_jumpers no)
		(fp_line
			(start -1.016 2.286)
			(end -1.016 -2.286)
			(stroke
				(width 0.1524)
				(type default)
			)
			(layer "F.SilkS")
		)
		(fp_line
			(start 1.016 2.286)
			(end -1.016 2.286)
			(stroke
				(width 0.1524)
				(type default)
			)
			(layer "F.SilkS")
		)
		(fp_line
			(start -1.016 -2.286)
			(end 1.016 -2.286)
			(stroke
				(width 0.1524)
				(type default)
			)
			(layer "F.SilkS")
		)
		(fp_line
			(start 1.016 -2.286)
			(end 1.016 2.286)
			(stroke
				(width 0.1524)
				(type default)
			)
			(layer "F.SilkS")
		)
		(fp_rect
			(start -1.27 2.54)
			(end 1.27 -2.54)
			(stroke
				(width 0)
				(type default)
			)
			(fill no)
			(layer "F.CrtYd")
		)
		(fp_rect
			(start -1.27 2.54)
			(end 1.27 -2.54)
			(stroke
				(width 0)
				(type default)
			)
			(fill no)
			(layer "F.Fab")
		)
		(pad "1" thru_hole circle
			(at 0 -1.27 270)
			(size 1.524 1.524)
			(drill 0.9144)
			(layers "*.Cu" "*.Mask")
			(remove_unused_layers no)
			(net "L10_50OHM_6INCH")
			(clearance -0.0508)
			(thermal_gap 0.127)
			(padstack
				(mode front_inner_back)
				(layer "Inner"
					(shape circle)
					(size 1.1684 1.1684)
					(clearance 0.127)
				)
				(layer "B.Cu"
					(shape circle)
					(size 1.524 1.524)
					(clearance -0.0508)
				)
			)
		)
		(pad "GND1" thru_hole rect
			(at 0 1.27 270)
			(size 1.524 1.524)
			(drill 0.9144)
			(layers "*.Cu" "*.Mask")
			(remove_unused_layers no)
			(net "GND")
			(clearance -0.0508)
			(thermal_gap 0.127)
			(padstack
				(mode front_inner_back)
				(layer "Inner"
					(shape circle)
					(size 1.1684 1.1684)
					(clearance 0.127)
				)
				(layer "B.Cu"
					(shape rect)
					(size 1.524 1.524)
					(clearance -0.0508)
				)
			)
		)
	)
	(footprint ""
		(layer "F.Cu")
		(at 165.608 -6.477 90)
		(property "Reference" "R4G16"
			(at 0 0 90)
			(layer "F.SilkS")
			(hide yes)
			(effects
				(font
					(size 1.27 1.27)
				)
			)
		)
		(property "Value" ""
			(at 0 0 90)
			(layer "F.Fab")
			(effects
				(font
					(size 1.27 1.27)
				)
			)
		)
		(duplicate_pad_numbers_are_jumpers no)
		(fp_poly
			(pts
				(xy -0.2794 -0.1016) (xy 0.2794 -0.1016) (xy 0.2794 0.9906) (xy -0.2794 0.9906)
			)
			(stroke
				(width 0)
				(type default)
			)
			(fill no)
			(layer "F.CrtYd")
		)
		(fp_line
			(start 0.2794 -0.1016)
			(end -0.2794 -0.1016)
			(stroke
				(width 0.1)
				(type default)
			)
			(layer "F.Fab")
		)
		(fp_line
			(start -0.2794 -0.1016)
			(end -0.2794 0.9906)
			(stroke
				(width 0.1)
				(type default)
			)
			(layer "F.Fab")
		)
		(fp_line
			(start 0.2794 0.9906)
			(end 0.2794 -0.1016)
			(stroke
				(width 0.1)
				(type default)
			)
			(layer "F.Fab")
		)
		(fp_line
			(start -0.2794 0.9906)
			(end 0.2794 0.9906)
			(stroke
				(width 0.1)
				(type default)
			)
			(layer "F.Fab")
		)
		(pad "1" smd rect
			(at 0 0 90)
			(size 0.508 0.508)
			(layers "F.Cu" "F.Mask" "F.Paste")
			(net "PWRGD_PVDDQ_GHJ_R")
		)
		(pad "2" smd rect
			(at 0 0.889 90)
			(size 0.508 0.508)
			(layers "F.Cu" "F.Mask" "F.Paste")
			(net "FM_PVTT_GHJ_EN_R")
		)
		(zone
			(layer "F.Cu")
			(hatch none 0.5)
			(connect_pads
				(clearance 0)
			)
			(min_thickness 0.25)
			(keepout
				(tracks allowed)
				(vias not_allowed)
				(pads allowed)
				(copperpour not_allowed)
				(footprints allowed)
			)
			(placement
				(enabled no)
				(sheetname "")
			)
			(fill
				(thermal_gap 0.5)
				(thermal_bridge_width 0.5)
				(island_removal_mode 0)
			)
			(polygon
				(pts
					(xy 165.862 -6.223) (xy 165.862 -6.731) (xy 166.243 -6.731) (xy 166.243 -6.223)
				)
			)
		)
		(zone
			(layer "F.Cu")
			(hatch none 0.5)
			(connect_pads
				(clearance 0)
			)
			(min_thickness 0.25)
			(keepout
				(tracks not_allowed)
				(vias allowed)
				(pads allowed)
				(copperpour not_allowed)
				(footprints allowed)
			)
			(placement
				(enabled no)
				(sheetname "")
			)
			(fill
				(thermal_gap 0.5)
				(thermal_bridge_width 0.5)
				(island_removal_mode 0)
			)
			(polygon
				(pts
					(xy 166.243 -6.223) (xy 166.243 -6.731) (xy 165.862 -6.731) (xy 165.862 -6.223)
				)
			)
		)
	)
	(footprint ""
		(layer "F.Cu")
		(at 117.410484 12.014454 -90)
		(property "Reference" "T1P7"
			(at 0 0 270)
			(layer "F.SilkS")
			(hide yes)
			(effects
				(font
					(size 1.27 1.27)
				)
			)
		)
		(property "Value" "*"
			(at -3.302 1.12395 270)
			(unlocked yes)
			(layer "F.Fab")
			(hide yes)
			(effects
				(font
					(size 0.889 0.889)
					(thickness 0.1524)
				)
			)
		)
		(property "Device Type" "TPAD-DIFF-4P-GP_DISCRET-GB3-TPA"
			(at -3.302 -0.40005 270)
			(unlocked yes)
			(layer "F.Fab")
			(hide yes)
			(effects
				(font
					(size 0.889 0.889)
					(thickness 0.1524)
				)
			)
		)
		(duplicate_pad_numbers_are_jumpers no)
		(fp_line
			(start -2.286 2.286)
			(end 2.286 2.286)
			(stroke
				(width 0.1524)
				(type default)
			)
			(layer "F.SilkS")
		)
		(fp_line
			(start 2.286 2.286)
			(end 2.286 -2.286)
			(stroke
				(width 0.1524)
				(type default)
			)
			(layer "F.SilkS")
		)
		(fp_line
			(start -2.286 -2.286)
			(end -2.286 2.286)
			(stroke
				(width 0.1524)
				(type default)
			)
			(layer "F.SilkS")
		)
		(fp_line
			(start 2.286 -2.286)
			(end -2.286 -2.286)
			(stroke
				(width 0.1524)
				(type default)
			)
			(layer "F.SilkS")
		)
		(fp_line
			(start -2.413 -2.413)
			(end -2.413 -1.143)
			(stroke
				(width 0.4064)
				(type default)
			)
			(layer "F.SilkS")
		)
		(fp_line
			(start -1.143 -2.413)
			(end -2.413 -2.413)
			(stroke
				(width 0.4064)
				(type default)
			)
			(layer "F.SilkS")
		)
		(fp_rect
			(start -2.54 2.54)
			(end 2.54 -2.54)
			(stroke
				(width 0)
				(type default)
			)
			(fill no)
			(layer "F.CrtYd")
		)
		(fp_rect
			(start -2.54 2.54)
			(end 2.54 -2.54)
			(stroke
				(width 0)
				(type default)
			)
			(fill no)
			(layer "F.Fab")
		)
		(pad "1" thru_hole circle
			(at -1.27 -1.27 270)
			(size 1.524 1.524)
			(drill 0.9144)
			(layers "*.Cu" "*.Mask")
			(remove_unused_layers no)
			(net "L1_73OHM_6INCH_DP")
			(clearance -0.0508)
			(thermal_gap 0.127)
			(padstack
				(mode front_inner_back)
				(layer "Inner"
					(shape circle)
					(size 1.1684 1.1684)
					(clearance 0.127)
				)
				(layer "B.Cu"
					(shape circle)
					(size 1.524 1.524)
					(clearance -0.0508)
				)
			)
		)
		(pad "2" thru_hole circle
			(at 1.27 -1.27 270)
			(size 1.524 1.524)
			(drill 0.9144)
			(layers "*.Cu" "*.Mask")
			(remove_unused_layers no)
			(net "L1_73OHM_6INCH_DN")
			(clearance -0.0508)
			(thermal_gap 0.127)
			(padstack
				(mode front_inner_back)
				(layer "Inner"
					(shape circle)
					(size 1.1684 1.1684)
					(clearance 0.127)
				)
				(layer "B.Cu"
					(shape circle)
					(size 1.524 1.524)
					(clearance -0.0508)
				)
			)
		)
		(pad "GND1" thru_hole rect
			(at -1.27 1.27 270)
			(size 1.524 1.524)
			(drill 0.9144)
			(layers "*.Cu" "*.Mask")
			(remove_unused_layers no)
			(net "GND")
			(clearance -0.0508)
			(thermal_gap 0.127)
			(padstack
				(mode front_inner_back)
				(layer "Inner"
					(shape circle)
					(size 1.1684 1.1684)
					(clearance 0.127)
				)
				(layer "B.Cu"
					(shape rect)
					(size 1.524 1.524)
					(clearance -0.0508)
				)
			)
		)
		(pad "GND2" thru_hole rect
			(at 1.27 1.27 270)
			(size 1.524 1.524)
			(drill 0.9144)
			(layers "*.Cu" "*.Mask")
			(remove_unused_layers no)
			(net "GND")
			(clearance -0.0508)
			(thermal_gap 0.127)
			(padstack
				(mode front_inner_back)
				(layer "Inner"
					(shape circle)
					(size 1.1684 1.1684)
					(clearance 0.127)
				)
				(layer "B.Cu"
					(shape rect)
					(size 1.524 1.524)
					(clearance -0.0508)
				)
			)
		)
	)
	(footprint ""
		(layer "F.Cu")
		(at 489.2294 -149.8854 90)
		(property "Reference" "R6W40"
			(at -0.8382 -0.67818 90)
			(unlocked yes)
			(layer "F.SilkS")
			(effects
				(font
					(size 0.4064 0.254)
					(thickness 0.1524)
				)
				(justify left)
			)
		)
		(property "Value" ""
			(at 0 0 90)
			(layer "F.Fab")
			(effects
				(font
					(size 1.27 1.27)
				)
			)
		)
		(duplicate_pad_numbers_are_jumpers no)
		(fp_poly
			(pts
				(xy -0.2794 -0.1016) (xy 0.2794 -0.1016) (xy 0.2794 0.9906) (xy -0.2794 0.9906)
			)
			(stroke
				(width 0)
				(type default)
			)
			(fill no)
			(layer "F.CrtYd")
		)
		(fp_line
			(start 0.2794 -0.1016)
			(end -0.2794 -0.1016)
			(stroke
				(width 0.1)
				(type default)
			)
			(layer "F.Fab")
		)
		(fp_line
			(start -0.2794 -0.1016)
			(end -0.2794 0.9906)
			(stroke
				(width 0.1)
				(type default)
			)
			(layer "F.Fab")
		)
		(fp_line
			(start 0.2794 0.9906)
			(end 0.2794 -0.1016)
			(stroke
				(width 0.1)
				(type default)
			)
			(layer "F.Fab")
		)
		(fp_line
			(start -0.2794 0.9906)
			(end 0.2794 0.9906)
			(stroke
				(width 0.1)
				(type default)
			)
			(layer "F.Fab")
		)
		(pad "1" smd rect
			(at 0 0 90)
			(size 0.508 0.508)
			(layers "F.Cu" "F.Mask" "F.Paste")
			(net "P3V3_STBY")
		)
		(pad "2" smd rect
			(at 0 0.889 90)
			(size 0.508 0.508)
			(layers "F.Cu" "F.Mask" "F.Paste")
			(net "SPA_5V_SIN_SW_D")
		)
		(zone
			(layer "F.Cu")
			(hatch none 0.5)
			(connect_pads
				(clearance 0)
			)
			(min_thickness 0.25)
			(keepout
				(tracks allowed)
				(vias not_allowed)
				(pads allowed)
				(copperpour not_allowed)
				(footprints allowed)
			)
			(placement
				(enabled no)
				(sheetname "")
			)
			(fill
				(thermal_gap 0.5)
				(thermal_bridge_width 0.5)
				(island_removal_mode 0)
			)
			(polygon
				(pts
					(xy 489.4834 -149.6314) (xy 489.4834 -150.1394) (xy 489.8644 -150.1394) (xy 489.8644 -149.6314)
				)
			)
		)
		(zone
			(layer "F.Cu")
			(hatch none 0.5)
			(connect_pads
				(clearance 0)
			)
			(min_thickness 0.25)
			(keepout
				(tracks not_allowed)
				(vias allowed)
				(pads allowed)
				(copperpour not_allowed)
				(footprints allowed)
			)
			(placement
				(enabled no)
				(sheetname "")
			)
			(fill
				(thermal_gap 0.5)
				(thermal_bridge_width 0.5)
				(island_removal_mode 0)
			)
			(polygon
				(pts
					(xy 489.8644 -149.6314) (xy 489.8644 -150.1394) (xy 489.4834 -150.1394) (xy 489.4834 -149.6314)
				)
			)
		)
	)
	(footprint ""
		(layer "F.Cu")
		(at 173.5074 -133.604 -90)
		(property "Reference" "R4B13"
			(at 1.01473 0.656336 180)
			(unlocked yes)
			(layer "F.SilkS")
			(effects
				(font
					(size 0.4064 0.254)
					(thickness 0.1524)
				)
			)
		)
		(property "Value" ""
			(at 0 0 270)
			(layer "F.Fab")
			(effects
				(font
					(size 1.27 1.27)
				)
			)
		)
		(duplicate_pad_numbers_are_jumpers no)
		(fp_poly
			(pts
				(xy -0.4953 -0.2032) (xy 0.4953 -0.2032) (xy 0.4953 1.6002) (xy -0.4953 1.6002)
			)
			(stroke
				(width 0)
				(type default)
			)
			(fill no)
			(layer "F.CrtYd")
		)
		(fp_line
			(start -0.4953 1.6002)
			(end -0.4953 -0.2032)
			(stroke
				(width 0.1)
				(type default)
			)
			(layer "F.Fab")
		)
		(fp_line
			(start 0.4953 1.6002)
			(end -0.4953 1.6002)
			(stroke
				(width 0.1)
				(type default)
			)
			(layer "F.Fab")
		)
		(fp_line
			(start -0.4953 -0.2032)
			(end 0.4953 -0.2032)
			(stroke
				(width 0.1)
				(type default)
			)
			(layer "F.Fab")
		)
		(fp_line
			(start 0.4953 -0.2032)
			(end 0.4953 1.6002)
			(stroke
				(width 0.1)
				(type default)
			)
			(layer "F.Fab")
		)
		(pad "1" smd rect
			(at 0 0 270)
			(size 0.762 0.889)
			(layers "F.Cu" "F.Mask" "F.Paste")
			(net "VR_PVPP_KLM_BOOT")
		)
		(pad "2" smd rect
			(at 0 1.397 270)
			(size 0.762 0.889)
			(layers "F.Cu" "F.Mask" "F.Paste")
			(net "VR_PVPP_KLM_BOOT_R")
		)
		(zone
			(layer "F.Cu")
			(hatch none 0.5)
			(connect_pads
				(clearance 0)
			)
			(min_thickness 0.25)
			(keepout
				(tracks not_allowed)
				(vias allowed)
				(pads allowed)
				(copperpour not_allowed)
				(footprints allowed)
			)
			(placement
				(enabled no)
				(sheetname "")
			)
			(fill
				(thermal_gap 0.5)
				(thermal_bridge_width 0.5)
				(island_removal_mode 0)
			)
			(polygon
				(pts
					(xy 172.5549 -133.985) (xy 172.5549 -133.223) (xy 173.0629 -133.223) (xy 173.0629 -133.985)
				)
			)
		)
		(zone
			(layer "F.Cu")
			(hatch none 0.5)
			(connect_pads
				(clearance 0)
			)
			(min_thickness 0.25)
			(keepout
				(tracks allowed)
				(vias not_allowed)
				(pads allowed)
				(copperpour not_allowed)
				(footprints allowed)
			)
			(placement
				(enabled no)
				(sheetname "")
			)
			(fill
				(thermal_gap 0.5)
				(thermal_bridge_width 0.5)
				(island_removal_mode 0)
			)
			(polygon
				(pts
					(xy 172.5549 -133.223) (xy 173.0629 -133.223) (xy 173.0629 -133.985) (xy 172.5549 -133.985)
				)
			)
		)
	)
	(footprint ""
		(layer "F.Cu")
		(at 379.2982 -30.629352 -90)
		(property "Reference" "R8F21"
			(at 0 0 270)
			(layer "F.SilkS")
			(hide yes)
			(effects
				(font
					(size 1.27 1.27)
				)
			)
		)
		(property "Value" ""
			(at 0 0 270)
			(layer "F.Fab")
			(effects
				(font
					(size 1.27 1.27)
				)
			)
		)
		(duplicate_pad_numbers_are_jumpers no)
		(fp_poly
			(pts
				(xy -0.2794 -0.1016) (xy 0.2794 -0.1016) (xy 0.2794 0.9906) (xy -0.2794 0.9906)
			)
			(stroke
				(width 0)
				(type default)
			)
			(fill no)
			(layer "F.CrtYd")
		)
		(fp_line
			(start -0.2794 0.9906)
			(end 0.2794 0.9906)
			(stroke
				(width 0.1)
				(type default)
			)
			(layer "F.Fab")
		)
		(fp_line
			(start 0.2794 0.9906)
			(end 0.2794 -0.1016)
			(stroke
				(width 0.1)
				(type default)
			)
			(layer "F.Fab")
		)
		(fp_line
			(start -0.2794 -0.1016)
			(end -0.2794 0.9906)
			(stroke
				(width 0.1)
				(type default)
			)
			(layer "F.Fab")
		)
		(fp_line
			(start 0.2794 -0.1016)
			(end -0.2794 -0.1016)
			(stroke
				(width 0.1)
				(type default)
			)
			(layer "F.Fab")
		)
		(pad "1" smd rect
			(at 0 0 270)
			(size 0.508 0.508)
			(layers "F.Cu" "F.Mask" "F.Paste")
			(net "P3E_PCH_RX_0_DN")
		)
		(pad "2" smd rect
			(at 0 0.889 270)
			(size 0.508 0.508)
			(layers "F.Cu" "F.Mask" "F.Paste")
			(net "P3E_PCH_M2_SATA6G_RX_R_DN")
		)
		(zone
			(layer "F.Cu")
			(hatch none 0.5)
			(connect_pads
				(clearance 0)
			)
			(min_thickness 0.25)
			(keepout
				(tracks not_allowed)
				(vias allowed)
				(pads allowed)
				(copperpour not_allowed)
				(footprints allowed)
			)
			(placement
				(enabled no)
				(sheetname "")
			)
			(fill
				(thermal_gap 0.5)
				(thermal_bridge_width 0.5)
				(island_removal_mode 0)
			)
			(polygon
				(pts
					(xy 378.6632 -30.883352) (xy 378.6632 -30.375352) (xy 379.0442 -30.375352) (xy 379.0442 -30.883352)
				)
			)
		)
		(zone
			(layer "F.Cu")
			(hatch none 0.5)
			(connect_pads
				(clearance 0)
			)
			(min_thickness 0.25)
			(keepout
				(tracks allowed)
				(vias not_allowed)
				(pads allowed)
				(copperpour not_allowed)
				(footprints allowed)
			)
			(placement
				(enabled no)
				(sheetname "")
			)
			(fill
				(thermal_gap 0.5)
				(thermal_bridge_width 0.5)
				(island_removal_mode 0)
			)
			(polygon
				(pts
					(xy 379.0442 -30.883352) (xy 379.0442 -30.375352) (xy 378.6632 -30.375352) (xy 378.6632 -30.883352)
				)
			)
		)
	)
	(footprint ""
		(layer "F.Cu")
		(at 176.0855 -132.334 90)
		(property "Reference" "C4B4"
			(at 0 0 90)
			(layer "F.SilkS")
			(hide yes)
			(effects
				(font
					(size 1.27 1.27)
				)
			)
		)
		(property "Value" ""
			(at 0 0 90)
			(layer "F.Fab")
			(effects
				(font
					(size 1.27 1.27)
				)
			)
		)
		(duplicate_pad_numbers_are_jumpers no)
		(fp_poly
			(pts
				(xy 0.3048 -0.1016) (xy 0.3048 0.9906) (xy -0.3048 0.9906) (xy -0.3048 -0.1016)
			)
			(stroke
				(width 0)
				(type default)
			)
			(fill no)
			(layer "F.CrtYd")
		)
		(fp_line
			(start 0.3048 -0.1016)
			(end -0.3048 -0.1016)
			(stroke
				(width 0.1)
				(type default)
			)
			(layer "F.Fab")
		)
		(fp_line
			(start -0.3048 -0.1016)
			(end -0.3048 0.9906)
			(stroke
				(width 0.1)
				(type default)
			)
			(layer "F.Fab")
		)
		(fp_line
			(start 0.3048 0.9906)
			(end 0.3048 -0.1016)
			(stroke
				(width 0.1)
				(type default)
			)
			(layer "F.Fab")
		)
		(fp_line
			(start -0.3048 0.9906)
			(end 0.3048 0.9906)
			(stroke
				(width 0.1)
				(type default)
			)
			(layer "F.Fab")
		)
		(pad "1" smd rect
			(at 0 0 90)
			(size 0.508 0.508)
			(layers "F.Cu" "F.Mask" "F.Paste")
			(net "VR_FB_PVPP_KLM")
		)
		(pad "2" smd rect
			(at 0 0.889 90)
			(size 0.508 0.508)
			(layers "F.Cu" "F.Mask" "F.Paste")
			(net "VR_COMP_PVPP_KLM_3")
		)
		(zone
			(layer "F.Cu")
			(hatch none 0.5)
			(connect_pads
				(clearance 0)
			)
			(min_thickness 0.25)
			(keepout
				(tracks allowed)
				(vias not_allowed)
				(pads allowed)
				(copperpour not_allowed)
				(footprints allowed)
			)
			(placement
				(enabled no)
				(sheetname "")
			)
			(fill
				(thermal_gap 0.5)
				(thermal_bridge_width 0.5)
				(island_removal_mode 0)
			)
			(polygon
				(pts
					(xy 176.3395 -132.08) (xy 176.3395 -132.588) (xy 176.7205 -132.588) (xy 176.7205 -132.08)
				)
			)
		)
		(zone
			(layer "F.Cu")
			(hatch none 0.5)
			(connect_pads
				(clearance 0)
			)
			(min_thickness 0.25)
			(keepout
				(tracks not_allowed)
				(vias allowed)
				(pads allowed)
				(copperpour not_allowed)
				(footprints allowed)
			)
			(placement
				(enabled no)
				(sheetname "")
			)
			(fill
				(thermal_gap 0.5)
				(thermal_bridge_width 0.5)
				(island_removal_mode 0)
			)
			(polygon
				(pts
					(xy 176.7205 -132.08) (xy 176.7205 -132.588) (xy 176.3395 -132.588) (xy 176.3395 -132.08)
				)
			)
		)
	)
	(footprint ""
		(layer "F.Cu")
		(at 114.671602 -77.382116)
		(property "Reference" "C3D16"
			(at 0 0 0)
			(layer "F.SilkS")
			(hide yes)
			(effects
				(font
					(size 1.27 1.27)
				)
			)
		)
		(property "Value" ""
			(at 0 0 0)
			(layer "F.Fab")
			(effects
				(font
					(size 1.27 1.27)
				)
			)
		)
		(duplicate_pad_numbers_are_jumpers no)
		(fp_poly
			(pts
				(xy -0.4953 -0.2032) (xy 0.4953 -0.2032) (xy 0.4953 1.6002) (xy -0.4953 1.6002)
			)
			(stroke
				(width 0)
				(type default)
			)
			(fill no)
			(layer "F.CrtYd")
		)
		(fp_line
			(start -0.4953 -0.2032)
			(end 0.4953 -0.2032)
			(stroke
				(width 0.1)
				(type default)
			)
			(layer "F.Fab")
		)
		(fp_line
			(start -0.4953 1.6002)
			(end -0.4953 -0.2032)
			(stroke
				(width 0.1)
				(type default)
			)
			(layer "F.Fab")
		)
		(fp_line
			(start 0.4953 -0.2032)
			(end 0.4953 1.6002)
			(stroke
				(width 0.1)
				(type default)
			)
			(layer "F.Fab")
		)
		(fp_line
			(start 0.4953 1.6002)
			(end -0.4953 1.6002)
			(stroke
				(width 0.1)
				(type default)
			)
			(layer "F.Fab")
		)
		(pad "1" smd rect
			(at 0 0)
			(size 0.762 0.889)
			(layers "F.Cu" "F.Mask" "F.Paste")
			(net "PVCCIO_CPU1")
		)
		(pad "2" smd rect
			(at 0 1.397)
			(size 0.762 0.889)
			(layers "F.Cu" "F.Mask" "F.Paste")
			(net "GND")
		)
		(zone
			(layer "F.Cu")
			(hatch none 0.5)
			(connect_pads
				(clearance 0)
			)
			(min_thickness 0.25)
			(keepout
				(tracks not_allowed)
				(vias allowed)
				(pads allowed)
				(copperpour not_allowed)
				(footprints allowed)
			)
			(placement
				(enabled no)
				(sheetname "")
			)
			(fill
				(thermal_gap 0.5)
				(thermal_bridge_width 0.5)
				(island_removal_mode 0)
			)
			(polygon
				(pts
					(xy 114.290602 -76.937616) (xy 115.052602 -76.937616) (xy 115.052602 -76.429616) (xy 114.290602 -76.429616)
				)
			)
		)
	)
	(footprint ""
		(layer "F.Cu")
		(at 457.83119 -35.569906)
		(property "Reference" "R8B25"
			(at 0 0 0)
			(layer "F.SilkS")
			(hide yes)
			(effects
				(font
					(size 1.27 1.27)
				)
			)
		)
		(property "Value" ""
			(at 0 0 0)
			(layer "F.Fab")
			(effects
				(font
					(size 1.27 1.27)
				)
			)
		)
		(duplicate_pad_numbers_are_jumpers no)
		(fp_poly
			(pts
				(xy -0.2794 -0.1016) (xy 0.2794 -0.1016) (xy 0.2794 0.9906) (xy -0.2794 0.9906)
			)
			(stroke
				(width 0)
				(type default)
			)
			(fill no)
			(layer "F.CrtYd")
		)
		(fp_line
			(start -0.2794 -0.1016)
			(end -0.2794 0.9906)
			(stroke
				(width 0.1)
				(type default)
			)
			(layer "F.Fab")
		)
		(fp_line
			(start -0.2794 0.9906)
			(end 0.2794 0.9906)
			(stroke
				(width 0.1)
				(type default)
			)
			(layer "F.Fab")
		)
		(fp_line
			(start 0.2794 -0.1016)
			(end -0.2794 -0.1016)
			(stroke
				(width 0.1)
				(type default)
			)
			(layer "F.Fab")
		)
		(fp_line
			(start 0.2794 0.9906)
			(end 0.2794 -0.1016)
			(stroke
				(width 0.1)
				(type default)
			)
			(layer "F.Fab")
		)
		(pad "1" smd rect
			(at 0 0)
			(size 0.508 0.508)
			(layers "F.Cu" "F.Mask" "F.Paste")
			(net "P3V3_STBY")
		)
		(pad "2" smd rect
			(at 0 0.889)
			(size 0.508 0.508)
			(layers "F.Cu" "F.Mask" "F.Paste")
			(net "FM_BMC_HEARTBEAT_N")
		)
		(zone
			(layer "F.Cu")
			(hatch none 0.5)
			(connect_pads
				(clearance 0)
			)
			(min_thickness 0.25)
			(keepout
				(tracks allowed)
				(vias not_allowed)
				(pads allowed)
				(copperpour not_allowed)
				(footprints allowed)
			)
			(placement
				(enabled no)
				(sheetname "")
			)
			(fill
				(thermal_gap 0.5)
				(thermal_bridge_width 0.5)
				(island_removal_mode 0)
			)
			(polygon
				(pts
					(xy 457.57719 -35.315906) (xy 458.08519 -35.315906) (xy 458.08519 -34.934906) (xy 457.57719 -34.934906)
				)
			)
		)
		(zone
			(layer "F.Cu")
			(hatch none 0.5)
			(connect_pads
				(clearance 0)
			)
			(min_thickness 0.25)
			(keepout
				(tracks not_allowed)
				(vias allowed)
				(pads allowed)
				(copperpour not_allowed)
				(footprints allowed)
			)
			(placement
				(enabled no)
				(sheetname "")
			)
			(fill
				(thermal_gap 0.5)
				(thermal_bridge_width 0.5)
				(island_removal_mode 0)
			)
			(polygon
				(pts
					(xy 457.57719 -34.934906) (xy 458.08519 -34.934906) (xy 458.08519 -35.315906) (xy 457.57719 -35.315906)
				)
			)
		)
	)
	(footprint ""
		(layer "F.Cu")
		(at 347.975936 -140.575538 -90)
		(property "Reference" "C7A21"
			(at 0 0 270)
			(layer "F.SilkS")
			(hide yes)
			(effects
				(font
					(size 1.27 1.27)
				)
			)
		)
		(property "Value" ""
			(at 0 0 270)
			(layer "F.Fab")
			(effects
				(font
					(size 1.27 1.27)
				)
			)
		)
		(duplicate_pad_numbers_are_jumpers no)
		(fp_poly
			(pts
				(xy 0.3048 -0.1016) (xy 0.3048 0.9906) (xy -0.3048 0.9906) (xy -0.3048 -0.1016)
			)
			(stroke
				(width 0)
				(type default)
			)
			(fill no)
			(layer "F.CrtYd")
		)
		(fp_line
			(start -0.3048 0.9906)
			(end 0.3048 0.9906)
			(stroke
				(width 0.1)
				(type default)
			)
			(layer "F.Fab")
		)
		(fp_line
			(start 0.3048 0.9906)
			(end 0.3048 -0.1016)
			(stroke
				(width 0.1)
				(type default)
			)
			(layer "F.Fab")
		)
		(fp_line
			(start -0.3048 -0.1016)
			(end -0.3048 0.9906)
			(stroke
				(width 0.1)
				(type default)
			)
			(layer "F.Fab")
		)
		(fp_line
			(start 0.3048 -0.1016)
			(end -0.3048 -0.1016)
			(stroke
				(width 0.1)
				(type default)
			)
			(layer "F.Fab")
		)
		(pad "1" smd rect
			(at 0 0 270)
			(size 0.508 0.508)
			(layers "F.Cu" "F.Mask" "F.Paste")
			(net "VR_FET_SW_P12V_STBY_PVDDQ_DEF")
		)
		(pad "2" smd rect
			(at 0 0.889 270)
			(size 0.508 0.508)
			(layers "F.Cu" "F.Mask" "F.Paste")
			(net "GND")
		)
		(zone
			(layer "F.Cu")
			(hatch none 0.5)
			(connect_pads
				(clearance 0)
			)
			(min_thickness 0.25)
			(keepout
				(tracks not_allowed)
				(vias allowed)
				(pads allowed)
				(copperpour not_allowed)
				(footprints allowed)
			)
			(placement
				(enabled no)
				(sheetname "")
			)
			(fill
				(thermal_gap 0.5)
				(thermal_bridge_width 0.5)
				(island_removal_mode 0)
			)
			(polygon
				(pts
					(xy 347.340936 -140.829538) (xy 347.340936 -140.321538) (xy 347.721936 -140.321538) (xy 347.721936 -140.829538)
				)
			)
		)
		(zone
			(layer "F.Cu")
			(hatch none 0.5)
			(connect_pads
				(clearance 0)
			)
			(min_thickness 0.25)
			(keepout
				(tracks allowed)
				(vias not_allowed)
				(pads allowed)
				(copperpour not_allowed)
				(footprints allowed)
			)
			(placement
				(enabled no)
				(sheetname "")
			)
			(fill
				(thermal_gap 0.5)
				(thermal_bridge_width 0.5)
				(island_removal_mode 0)
			)
			(polygon
				(pts
					(xy 347.721936 -140.829538) (xy 347.721936 -140.321538) (xy 347.340936 -140.321538) (xy 347.340936 -140.829538)
				)
			)
		)
	)
	(footprint ""
		(layer "F.Cu")
		(at 182.6514 -146.685)
		(property "Reference" "C4A11"
			(at 0 0 0)
			(layer "F.SilkS")
			(hide yes)
			(effects
				(font
					(size 1.27 1.27)
				)
			)
		)
		(property "Value" ""
			(at 0 0 0)
			(layer "F.Fab")
			(effects
				(font
					(size 1.27 1.27)
				)
			)
		)
		(duplicate_pad_numbers_are_jumpers no)
		(fp_poly
			(pts
				(xy -0.4953 -0.2032) (xy 0.4953 -0.2032) (xy 0.4953 1.6002) (xy -0.4953 1.6002)
			)
			(stroke
				(width 0)
				(type default)
			)
			(fill no)
			(layer "F.CrtYd")
		)
		(fp_line
			(start -0.4953 -0.2032)
			(end 0.4953 -0.2032)
			(stroke
				(width 0.1)
				(type default)
			)
			(layer "F.Fab")
		)
		(fp_line
			(start -0.4953 1.6002)
			(end -0.4953 -0.2032)
			(stroke
				(width 0.1)
				(type default)
			)
			(layer "F.Fab")
		)
		(fp_line
			(start 0.4953 -0.2032)
			(end 0.4953 1.6002)
			(stroke
				(width 0.1)
				(type default)
			)
			(layer "F.Fab")
		)
		(fp_line
			(start 0.4953 1.6002)
			(end -0.4953 1.6002)
			(stroke
				(width 0.1)
				(type default)
			)
			(layer "F.Fab")
		)
		(pad "1" smd rect
			(at 0 0)
			(size 0.762 0.889)
			(layers "F.Cu" "F.Mask" "F.Paste")
			(net "VSENSE_PVDDQ_DEF_VTT")
		)
		(pad "2" smd rect
			(at 0 1.397)
			(size 0.762 0.889)
			(layers "F.Cu" "F.Mask" "F.Paste")
			(net "GND")
		)
		(zone
			(layer "F.Cu")
			(hatch none 0.5)
			(connect_pads
				(clearance 0)
			)
			(min_thickness 0.25)
			(keepout
				(tracks not_allowed)
				(vias allowed)
				(pads allowed)
				(copperpour not_allowed)
				(footprints allowed)
			)
			(placement
				(enabled no)
				(sheetname "")
			)
			(fill
				(thermal_gap 0.5)
				(thermal_bridge_width 0.5)
				(island_removal_mode 0)
			)
			(polygon
				(pts
					(xy 182.2704 -146.2405) (xy 183.0324 -146.2405) (xy 183.0324 -145.7325) (xy 182.2704 -145.7325)
				)
			)
		)
	)
	(footprint ""
		(layer "F.Cu")
		(at 278.868124 -71.714614 180)
		(property "Reference" "C6D9"
			(at 0 0 180)
			(layer "F.SilkS")
			(hide yes)
			(effects
				(font
					(size 1.27 1.27)
				)
			)
		)
		(property "Value" ""
			(at 0 0 180)
			(layer "F.Fab")
			(effects
				(font
					(size 1.27 1.27)
				)
			)
		)
		(duplicate_pad_numbers_are_jumpers no)
		(fp_poly
			(pts
				(xy -0.4953 -0.2032) (xy 0.4953 -0.2032) (xy 0.4953 1.6002) (xy -0.4953 1.6002)
			)
			(stroke
				(width 0)
				(type default)
			)
			(fill no)
			(layer "F.CrtYd")
		)
		(fp_line
			(start 0.4953 1.6002)
			(end -0.4953 1.6002)
			(stroke
				(width 0.1)
				(type default)
			)
			(layer "F.Fab")
		)
		(fp_line
			(start 0.4953 -0.2032)
			(end 0.4953 1.6002)
			(stroke
				(width 0.1)
				(type default)
			)
			(layer "F.Fab")
		)
		(fp_line
			(start -0.4953 1.6002)
			(end -0.4953 -0.2032)
			(stroke
				(width 0.1)
				(type default)
			)
			(layer "F.Fab")
		)
		(fp_line
			(start -0.4953 -0.2032)
			(end 0.4953 -0.2032)
			(stroke
				(width 0.1)
				(type default)
			)
			(layer "F.Fab")
		)
		(pad "1" smd rect
			(at 0 0 180)
			(size 0.762 0.889)
			(layers "F.Cu" "F.Mask" "F.Paste")
			(net "PVCCIO_CPU0")
		)
		(pad "2" smd rect
			(at 0 1.397 180)
			(size 0.762 0.889)
			(layers "F.Cu" "F.Mask" "F.Paste")
			(net "GND")
		)
		(zone
			(layer "F.Cu")
			(hatch none 0.5)
			(connect_pads
				(clearance 0)
			)
			(min_thickness 0.25)
			(keepout
				(tracks not_allowed)
				(vias allowed)
				(pads allowed)
				(copperpour not_allowed)
				(footprints allowed)
			)
			(placement
				(enabled no)
				(sheetname "")
			)
			(fill
				(thermal_gap 0.5)
				(thermal_bridge_width 0.5)
				(island_removal_mode 0)
			)
			(polygon
				(pts
					(xy 279.249124 -72.159114) (xy 278.487124 -72.159114) (xy 278.487124 -72.667114) (xy 279.249124 -72.667114)
				)
			)
		)
	)
	(footprint ""
		(layer "F.Cu")
		(at 268.1732 -79.6036 180)
		(property "Reference" "C5D19"
			(at 0 0 180)
			(layer "F.SilkS")
			(hide yes)
			(effects
				(font
					(size 1.27 1.27)
				)
			)
		)
		(property "Value" ""
			(at 0 0 180)
			(layer "F.Fab")
			(effects
				(font
					(size 1.27 1.27)
				)
			)
		)
		(duplicate_pad_numbers_are_jumpers no)
		(fp_poly
			(pts
				(xy -0.4953 -0.2032) (xy 0.4953 -0.2032) (xy 0.4953 1.6002) (xy -0.4953 1.6002)
			)
			(stroke
				(width 0)
				(type default)
			)
			(fill no)
			(layer "F.CrtYd")
		)
		(fp_line
			(start 0.4953 1.6002)
			(end -0.4953 1.6002)
			(stroke
				(width 0.1)
				(type default)
			)
			(layer "F.Fab")
		)
		(fp_line
			(start 0.4953 -0.2032)
			(end 0.4953 1.6002)
			(stroke
				(width 0.1)
				(type default)
			)
			(layer "F.Fab")
		)
		(fp_line
			(start -0.4953 1.6002)
			(end -0.4953 -0.2032)
			(stroke
				(width 0.1)
				(type default)
			)
			(layer "F.Fab")
		)
		(fp_line
			(start -0.4953 -0.2032)
			(end 0.4953 -0.2032)
			(stroke
				(width 0.1)
				(type default)
			)
			(layer "F.Fab")
		)
		(pad "1" smd rect
			(at 0 0 180)
			(size 0.762 0.889)
			(layers "F.Cu" "F.Mask" "F.Paste")
			(net "PVCCIN_CPU0")
		)
		(pad "2" smd rect
			(at 0 1.397 180)
			(size 0.762 0.889)
			(layers "F.Cu" "F.Mask" "F.Paste")
			(net "GND")
		)
		(zone
			(layer "F.Cu")
			(hatch none 0.5)
			(connect_pads
				(clearance 0)
			)
			(min_thickness 0.25)
			(keepout
				(tracks not_allowed)
				(vias allowed)
				(pads allowed)
				(copperpour not_allowed)
				(footprints allowed)
			)
			(placement
				(enabled no)
				(sheetname "")
			)
			(fill
				(thermal_gap 0.5)
				(thermal_bridge_width 0.5)
				(island_removal_mode 0)
			)
			(polygon
				(pts
					(xy 268.5542 -80.0481) (xy 267.7922 -80.0481) (xy 267.7922 -80.5561) (xy 268.5542 -80.5561)
				)
			)
		)
	)
	(footprint ""
		(layer "F.Cu")
		(at 449.454016 3.81 90)
		(property "Reference" "J9G1"
			(at 1.524 -2.13233 90)
			(unlocked yes)
			(layer "B.SilkS")
			(effects
				(font
					(size 0.7874 0.5842)
					(thickness 0.1524)
				)
				(justify mirror)
			)
		)
		(property "Value" ""
			(at 0 0 90)
			(layer "F.Fab")
			(effects
				(font
					(size 1.27 1.27)
				)
			)
		)
		(duplicate_pad_numbers_are_jumpers no)
		(fp_line
			(start 3.8227 -1.27)
			(end 3.8227 13.97)
			(stroke
				(width 0.1524)
				(type default)
			)
			(layer "F.SilkS")
		)
		(fp_line
			(start -1.2827 -1.27)
			(end 3.8227 -1.27)
			(stroke
				(width 0.1524)
				(type default)
			)
			(layer "F.SilkS")
		)
		(fp_line
			(start 3.7592 -1.143)
			(end 3.758184 -1.143)
			(stroke
				(width 0.1)
				(type default)
			)
			(layer "F.SilkS")
		)
		(fp_line
			(start -1.2192 -1.143)
			(end -1.218946 -1.143)
			(stroke
				(width 0.1)
				(type default)
			)
			(layer "F.SilkS")
		)
		(fp_line
			(start 3.7592 13.843)
			(end 3.758946 13.843)
			(stroke
				(width 0.1524)
				(type default)
			)
			(layer "F.SilkS")
		)
		(fp_line
			(start -1.2192 13.843)
			(end -1.218946 13.843)
			(stroke
				(width 0.1524)
				(type default)
			)
			(layer "F.SilkS")
		)
		(fp_line
			(start 3.8227 13.97)
			(end -1.2827 13.97)
			(stroke
				(width 0.1524)
				(type default)
			)
			(layer "F.SilkS")
		)
		(fp_line
			(start -1.2827 13.97)
			(end -1.2827 -1.27)
			(stroke
				(width 0.1524)
				(type default)
			)
			(layer "F.SilkS")
		)
		(fp_poly
			(pts
				(xy -1.7145 -0.005588) (xy -2.9845 0.502412) (xy -2.9845 -0.513588)
			)
			(stroke
				(width 0)
				(type default)
			)
			(fill yes)
			(layer "F.SilkS")
		)
		(fp_poly
			(pts
				(xy -1.7145 -0.005588) (xy -2.9845 0.502412) (xy -2.9845 -0.513588)
			)
			(stroke
				(width 0)
				(type default)
			)
			(fill yes)
			(layer "B.SilkS")
		)
		(fp_poly
			(pts
				(xy -1.2827 -1.27) (xy -1.2827 13.97) (xy 3.8227 13.97) (xy 3.8227 -1.27)
			)
			(stroke
				(width 0)
				(type default)
			)
			(fill no)
			(layer "F.CrtYd")
		)
		(fp_poly
			(pts
				(xy -1.7145 -0.005588) (xy -2.9845 0.502412) (xy -2.9845 -0.513588)
			)
			(stroke
				(width 0)
				(type default)
			)
			(fill yes)
			(layer "B.Fab")
		)
		(fp_line
			(start 3.8227 -1.27)
			(end -1.2827 -1.27)
			(stroke
				(width 0.1)
				(type default)
			)
			(layer "F.Fab")
		)
		(fp_line
			(start -1.2827 -1.27)
			(end -1.2827 13.97)
			(stroke
				(width 0.1)
				(type default)
			)
			(layer "F.Fab")
		)
		(fp_line
			(start 3.8227 13.97)
			(end 3.8227 -1.27)
			(stroke
				(width 0.1)
				(type default)
			)
			(layer "F.Fab")
		)
		(fp_line
			(start -1.2827 13.97)
			(end 3.8227 13.97)
			(stroke
				(width 0.1)
				(type default)
			)
			(layer "F.Fab")
		)
		(fp_poly
			(pts
				(xy -1.7145 -0.005588) (xy -2.9845 0.502412) (xy -2.9845 -0.513588)
			)
			(stroke
				(width 0)
				(type default)
			)
			(fill yes)
			(layer "F.Fab")
		)
		(fp_text user "2"
			(at 2.832354 -1.784096 0)
			(unlocked yes)
			(layer "F.SilkS")
			(effects
				(font
					(size 0.7874 0.5842)
					(thickness 0.1524)
				)
			)
		)
		(fp_text user "12"
			(at 4.391914 12.930124 0)
			(unlocked yes)
			(layer "F.SilkS")
			(effects
				(font
					(size 0.7874 0.5842)
					(thickness 0.1524)
				)
			)
		)
		(fp_text user "11"
			(at -0.980186 14.880336 0)
			(unlocked yes)
			(layer "F.SilkS")
			(effects
				(font
					(size 0.7874 0.5842)
					(thickness 0.1524)
				)
			)
		)
		(fp_text user "2"
			(at 4.5466 0.02667 90)
			(unlocked yes)
			(layer "B.SilkS")
			(effects
				(font
					(size 0.7874 0.5842)
					(thickness 0.1524)
				)
				(justify mirror)
			)
		)
		(fp_text user "11"
			(at -2.2606 12.72667 90)
			(unlocked yes)
			(layer "B.SilkS")
			(effects
				(font
					(size 0.7874 0.5842)
					(thickness 0.1524)
				)
				(justify mirror)
			)
		)
		(fp_text user "12"
			(at 2.6797 14.37767 90)
			(unlocked yes)
			(layer "B.SilkS")
			(effects
				(font
					(size 0.7874 0.5842)
					(thickness 0.1524)
				)
				(justify mirror)
			)
		)
		(fp_text user "2"
			(at 4.5466 0.02667 90)
			(unlocked yes)
			(layer "B.Fab")
			(effects
				(font
					(size 0.7874 0.5842)
					(thickness 0.1524)
				)
				(justify mirror)
			)
		)
		(fp_text user "11"
			(at -2.2606 12.72667 90)
			(unlocked yes)
			(layer "B.Fab")
			(effects
				(font
					(size 0.7874 0.5842)
					(thickness 0.1524)
				)
				(justify mirror)
			)
		)
		(fp_text user "12"
			(at 2.6797 14.37767 90)
			(unlocked yes)
			(layer "B.Fab")
			(effects
				(font
					(size 0.7874 0.5842)
					(thickness 0.1524)
				)
				(justify mirror)
			)
		)
		(fp_text user "2"
			(at 4.572 -1.36271 90)
			(unlocked yes)
			(layer "F.Fab")
			(effects
				(font
					(size 0.7874 0.5842)
					(thickness 0.1524)
				)
			)
		)
		(fp_text user "11"
			(at -2.02692 13.66139 90)
			(unlocked yes)
			(layer "F.Fab")
			(effects
				(font
					(size 0.7874 0.5842)
					(thickness 0.1524)
				)
			)
		)
		(fp_text user "12"
			(at 5.334 14.13129 90)
			(unlocked yes)
			(layer "F.Fab")
			(effects
				(font
					(size 0.7874 0.5842)
					(thickness 0.1524)
				)
			)
		)
		(pad "1" thru_hole rect
			(at 0 0 90)
			(size 1.6256 1.6256)
			(drill 1.2446)
			(layers "*.Cu" "*.Mask")
			(remove_unused_layers no)
			(net "PU_UV_HIGH_SET")
			(clearance 0.127)
			(thermal_gap 0.127)
			(padstack
				(mode front_inner_back)
				(layer "Inner"
					(shape circle)
					(size 1.6256 1.6256)
					(clearance 0.127)
				)
				(layer "B.Cu"
					(shape rect)
					(size 1.6256 1.6256)
					(clearance 0.127)
				)
			)
		)
		(pad "2" thru_hole circle
			(at 2.54 0 90)
			(size 1.6256 1.6256)
			(drill 1.2446)
			(layers "*.Cu" "*.Mask")
			(remove_unused_layers no)
			(net "TP_RST_RTCRST_N")
			(clearance 0.127)
			(thermal_gap 0.127)
		)
		(pad "3" thru_hole circle
			(at 0 2.54 90)
			(size 1.6256 1.6256)
			(drill 1.2446)
			(layers "*.Cu" "*.Mask")
			(remove_unused_layers no)
			(net "UV_HIGH_SET")
			(clearance 0.127)
			(thermal_gap 0.127)
		)
		(pad "4" thru_hole circle
			(at 2.54 2.54 90)
			(size 1.6256 1.6256)
			(drill 1.2446)
			(layers "*.Cu" "*.Mask")
			(remove_unused_layers no)
			(net "RST_RTCRST_N")
			(clearance 0.127)
			(thermal_gap 0.127)
		)
		(pad "5" thru_hole circle
			(at 0 5.08 90)
			(size 1.6256 1.6256)
			(drill 1.2446)
			(layers "*.Cu" "*.Mask")
			(remove_unused_layers no)
			(net "PD_UV_HIGH_SET")
			(clearance 0.127)
			(thermal_gap 0.127)
		)
		(pad "6" thru_hole circle
			(at 2.54 5.08 90)
			(size 1.6256 1.6256)
			(drill 1.2446)
			(layers "*.Cu" "*.Mask")
			(remove_unused_layers no)
			(net "PD_RST_RTCRST_N")
			(clearance 0.127)
			(thermal_gap 0.127)
		)
		(pad "7" thru_hole circle
			(at 0 7.62 90)
			(size 1.6256 1.6256)
			(drill 1.2446)
			(layers "*.Cu" "*.Mask")
			(remove_unused_layers no)
			(net "TP_IE_DEBUG_MODE")
			(clearance 0.127)
			(thermal_gap 0.127)
		)
		(pad "8" thru_hole circle
			(at 2.54 7.62 90)
			(size 1.6256 1.6256)
			(drill 1.2446)
			(layers "*.Cu" "*.Mask")
			(remove_unused_layers no)
			(net "PU_SPI_BMC_BT_CS0_N")
			(clearance 0.127)
			(thermal_gap 0.127)
		)
		(pad "9" thru_hole circle
			(at 0 10.16 90)
			(size 1.6256 1.6256)
			(drill 1.2446)
			(layers "*.Cu" "*.Mask")
			(remove_unused_layers no)
			(net "FM_UART_PRES_N")
			(clearance 0.127)
			(thermal_gap 0.127)
		)
		(pad "10" thru_hole circle
			(at 2.54 10.16 90)
			(size 1.6256 1.6256)
			(drill 1.2446)
			(layers "*.Cu" "*.Mask")
			(remove_unused_layers no)
			(net "SPI_BMC_BT_CS0_N")
			(clearance 0.127)
			(thermal_gap 0.127)
		)
		(pad "11" thru_hole circle
			(at 0 12.7 90)
			(size 1.6256 1.6256)
			(drill 1.2446)
			(layers "*.Cu" "*.Mask")
			(remove_unused_layers no)
			(net "PD_IE_DEBUG_MODE")
			(clearance 0.127)
			(thermal_gap 0.127)
		)
		(pad "12" thru_hole circle
			(at 2.54 12.7 90)
			(size 1.6256 1.6256)
			(drill 1.2446)
			(layers "*.Cu" "*.Mask")
			(remove_unused_layers no)
			(net "PD_SPI_BMC_BT_CS0_N")
			(clearance 0.127)
			(thermal_gap 0.127)
		)
	)
	(footprint ""
		(layer "F.Cu")
		(at 14.224 -101.981)
		(property "Reference" "R1C10"
			(at 0 0 0)
			(layer "F.SilkS")
			(hide yes)
			(effects
				(font
					(size 1.27 1.27)
				)
			)
		)
		(property "Value" ""
			(at 0 0 0)
			(layer "F.Fab")
			(effects
				(font
					(size 1.27 1.27)
				)
			)
		)
		(duplicate_pad_numbers_are_jumpers no)
		(fp_poly
			(pts
				(xy -0.2794 -0.1016) (xy 0.2794 -0.1016) (xy 0.2794 0.9906) (xy -0.2794 0.9906)
			)
			(stroke
				(width 0)
				(type default)
			)
			(fill no)
			(layer "F.CrtYd")
		)
		(fp_line
			(start -0.2794 -0.1016)
			(end -0.2794 0.9906)
			(stroke
				(width 0.1)
				(type default)
			)
			(layer "F.Fab")
		)
		(fp_line
			(start -0.2794 0.9906)
			(end 0.2794 0.9906)
			(stroke
				(width 0.1)
				(type default)
			)
			(layer "F.Fab")
		)
		(fp_line
			(start 0.2794 -0.1016)
			(end -0.2794 -0.1016)
			(stroke
				(width 0.1)
				(type default)
			)
			(layer "F.Fab")
		)
		(fp_line
			(start 0.2794 0.9906)
			(end 0.2794 -0.1016)
			(stroke
				(width 0.1)
				(type default)
			)
			(layer "F.Fab")
		)
		(pad "1" smd rect
			(at 0 0)
			(size 0.508 0.508)
			(layers "F.Cu" "F.Mask" "F.Paste")
			(net "SMB_LAN_STBY_LVC3_SDA")
		)
		(pad "2" smd rect
			(at 0 0.889)
			(size 0.508 0.508)
			(layers "F.Cu" "F.Mask" "F.Paste")
			(net "FAN_TACH3_R")
		)
		(zone
			(layer "F.Cu")
			(hatch none 0.5)
			(connect_pads
				(clearance 0)
			)
			(min_thickness 0.25)
			(keepout
				(tracks allowed)
				(vias not_allowed)
				(pads allowed)
				(copperpour not_allowed)
				(footprints allowed)
			)
			(placement
				(enabled no)
				(sheetname "")
			)
			(fill
				(thermal_gap 0.5)
				(thermal_bridge_width 0.5)
				(island_removal_mode 0)
			)
			(polygon
				(pts
					(xy 13.97 -101.727) (xy 14.478 -101.727) (xy 14.478 -101.346) (xy 13.97 -101.346)
				)
			)
		)
		(zone
			(layer "F.Cu")
			(hatch none 0.5)
			(connect_pads
				(clearance 0)
			)
			(min_thickness 0.25)
			(keepout
				(tracks not_allowed)
				(vias allowed)
				(pads allowed)
				(copperpour not_allowed)
				(footprints allowed)
			)
			(placement
				(enabled no)
				(sheetname "")
			)
			(fill
				(thermal_gap 0.5)
				(thermal_bridge_width 0.5)
				(island_removal_mode 0)
			)
			(polygon
				(pts
					(xy 13.97 -101.346) (xy 14.478 -101.346) (xy 14.478 -101.727) (xy 13.97 -101.727)
				)
			)
		)
	)
	(footprint ""
		(layer "F.Cu")
		(at 356.98684 -134.22757)
		(property "Reference" "C7B2"
			(at 0 0 0)
			(layer "F.SilkS")
			(hide yes)
			(effects
				(font
					(size 1.27 1.27)
				)
			)
		)
		(property "Value" ""
			(at 0 0 0)
			(layer "F.Fab")
			(effects
				(font
					(size 1.27 1.27)
				)
			)
		)
		(duplicate_pad_numbers_are_jumpers no)
		(fp_rect
			(start -0.3048 0.9906)
			(end 0.3048 -0.1016)
			(stroke
				(width 0)
				(type default)
			)
			(fill no)
			(layer "F.CrtYd")
		)
		(fp_line
			(start -0.3048 -0.1016)
			(end -0.3048 0.9906)
			(stroke
				(width 0.1)
				(type default)
			)
			(layer "F.Fab")
		)
		(fp_line
			(start -0.3048 0.9906)
			(end 0.3048 0.9906)
			(stroke
				(width 0.1)
				(type default)
			)
			(layer "F.Fab")
		)
		(fp_line
			(start 0.3048 -0.1016)
			(end -0.3048 -0.1016)
			(stroke
				(width 0.1)
				(type default)
			)
			(layer "F.Fab")
		)
		(fp_line
			(start 0.3048 0.9906)
			(end 0.3048 -0.1016)
			(stroke
				(width 0.1)
				(type default)
			)
			(layer "F.Fab")
		)
		(pad "1" smd rect
			(at 0 0)
			(size 0.508 0.508)
			(layers "F.Cu" "F.Mask" "F.Paste")
			(net "VR_PVDDQ_DEF_VD12")
		)
		(pad "2" smd rect
			(at 0 0.889)
			(size 0.508 0.508)
			(layers "F.Cu" "F.Mask" "F.Paste")
			(net "GND")
		)
		(zone
			(layer "F.Cu")
			(hatch none 0.5)
			(connect_pads
				(clearance 0)
			)
			(min_thickness 0.25)
			(keepout
				(tracks allowed)
				(vias not_allowed)
				(pads allowed)
				(copperpour not_allowed)
				(footprints allowed)
			)
			(placement
				(enabled no)
				(sheetname "")
			)
			(fill
				(thermal_gap 0.5)
				(thermal_bridge_width 0.5)
				(island_removal_mode 0)
			)
			(polygon
				(pts
					(xy 356.73284 -133.59257) (xy 357.24084 -133.59257) (xy 357.24084 -133.97357) (xy 356.73284 -133.97357)
				)
			)
		)
		(zone
			(layer "F.Cu")
			(hatch none 0.5)
			(connect_pads
				(clearance 0)
			)
			(min_thickness 0.25)
			(keepout
				(tracks not_allowed)
				(vias allowed)
				(pads allowed)
				(copperpour not_allowed)
				(footprints allowed)
			)
			(placement
				(enabled no)
				(sheetname "")
			)
			(fill
				(thermal_gap 0.5)
				(thermal_bridge_width 0.5)
				(island_removal_mode 0)
			)
			(polygon
				(pts
					(xy 356.73284 -133.59257) (xy 357.24084 -133.59257) (xy 357.24084 -133.97357) (xy 356.73284 -133.97357)
				)
			)
		)
	)
	(footprint ""
		(layer "F.Cu")
		(at 353.216464 -144.502378 -90)
		(property "Reference" "RT31"
			(at 1.01473 0.656336 180)
			(unlocked yes)
			(layer "F.SilkS")
			(effects
				(font
					(size 0.4064 0.254)
					(thickness 0.1524)
				)
			)
		)
		(property "Value" ""
			(at 0 0 270)
			(layer "F.Fab")
			(effects
				(font
					(size 1.27 1.27)
				)
			)
		)
		(duplicate_pad_numbers_are_jumpers no)
		(fp_poly
			(pts
				(xy -0.4953 -0.2032) (xy 0.4953 -0.2032) (xy 0.4953 1.6002) (xy -0.4953 1.6002)
			)
			(stroke
				(width 0)
				(type default)
			)
			(fill no)
			(layer "F.CrtYd")
		)
		(fp_line
			(start -0.4953 1.6002)
			(end -0.4953 -0.2032)
			(stroke
				(width 0.1)
				(type default)
			)
			(layer "F.Fab")
		)
		(fp_line
			(start 0.4953 1.6002)
			(end -0.4953 1.6002)
			(stroke
				(width 0.1)
				(type default)
			)
			(layer "F.Fab")
		)
		(fp_line
			(start -0.4953 -0.2032)
			(end 0.4953 -0.2032)
			(stroke
				(width 0.1)
				(type default)
			)
			(layer "F.Fab")
		)
		(fp_line
			(start 0.4953 -0.2032)
			(end 0.4953 1.6002)
			(stroke
				(width 0.1)
				(type default)
			)
			(layer "F.Fab")
		)
		(pad "1" smd rect
			(at 0 0 270)
			(size 0.762 0.889)
			(layers "F.Cu" "F.Mask" "F.Paste")
			(net "VR_PVDDQ_DEF_PH2_BOOT")
		)
		(pad "2" smd rect
			(at 0 1.397 270)
			(size 0.762 0.889)
			(layers "F.Cu" "F.Mask" "F.Paste")
			(net "VR_PVDDQ_DEF_PH2_BOOT_R")
		)
		(zone
			(layer "F.Cu")
			(hatch none 0.5)
			(connect_pads
				(clearance 0)
			)
			(min_thickness 0.25)
			(keepout
				(tracks not_allowed)
				(vias allowed)
				(pads allowed)
				(copperpour not_allowed)
				(footprints allowed)
			)
			(placement
				(enabled no)
				(sheetname "")
			)
			(fill
				(thermal_gap 0.5)
				(thermal_bridge_width 0.5)
				(island_removal_mode 0)
			)
			(polygon
				(pts
					(xy 352.263964 -144.883378) (xy 352.263964 -144.121378) (xy 352.771964 -144.121378) (xy 352.771964 -144.883378)
				)
			)
		)
		(zone
			(layer "F.Cu")
			(hatch none 0.5)
			(connect_pads
				(clearance 0)
			)
			(min_thickness 0.25)
			(keepout
				(tracks allowed)
				(vias not_allowed)
				(pads allowed)
				(copperpour not_allowed)
				(footprints allowed)
			)
			(placement
				(enabled no)
				(sheetname "")
			)
			(fill
				(thermal_gap 0.5)
				(thermal_bridge_width 0.5)
				(island_removal_mode 0)
			)
			(polygon
				(pts
					(xy 352.263964 -144.121378) (xy 352.771964 -144.121378) (xy 352.771964 -144.883378) (xy 352.263964 -144.883378)
				)
			)
		)
	)
	(footprint ""
		(layer "F.Cu")
		(at 83.856068 -3.3528 -90)
		(property "Reference" "C2G10"
			(at 1.848866 0.752348 270)
			(unlocked yes)
			(layer "F.SilkS")
			(effects
				(font
					(size 1.27 0.9652)
					(thickness 0.1524)
				)
			)
		)
		(property "Value" ""
			(at 0 0 270)
			(layer "F.Fab")
			(effects
				(font
					(size 1.27 1.27)
				)
			)
		)
		(duplicate_pad_numbers_are_jumpers no)
		(fp_rect
			(start -0.500126 1.598422)
			(end 0.500126 -0.201422)
			(stroke
				(width 0)
				(type default)
			)
			(fill no)
			(layer "F.CrtYd")
		)
		(fp_line
			(start -0.500126 1.598422)
			(end -0.500126 -0.201422)
			(stroke
				(width 0.1)
				(type default)
			)
			(layer "F.Fab")
		)
		(fp_line
			(start 0.500126 1.598422)
			(end -0.500126 1.598422)
			(stroke
				(width 0.1)
				(type default)
			)
			(layer "F.Fab")
		)
		(fp_line
			(start -0.500126 -0.201422)
			(end 0.500126 -0.201422)
			(stroke
				(width 0.1)
				(type default)
			)
			(layer "F.Fab")
		)
		(fp_line
			(start 0.500126 -0.201422)
			(end 0.500126 1.598422)
			(stroke
				(width 0.1)
				(type default)
			)
			(layer "F.Fab")
		)
		(pad "1" smd rect
			(at 0 0 180)
			(size 0.889 0.9906)
			(layers "F.Cu" "F.Mask" "F.Paste")
			(net "PVDDQ_GHJ")
		)
		(pad "2" smd rect
			(at 0 1.397 180)
			(size 0.889 0.9906)
			(layers "F.Cu" "F.Mask" "F.Paste")
			(net "GND")
		)
		(zone
			(layer "F.Cu")
			(hatch none 0.5)
			(connect_pads
				(clearance 0)
			)
			(min_thickness 0.25)
			(keepout
				(tracks not_allowed)
				(vias allowed)
				(pads allowed)
				(copperpour not_allowed)
				(footprints allowed)
			)
			(placement
				(enabled no)
				(sheetname "")
			)
			(fill
				(thermal_gap 0.5)
				(thermal_bridge_width 0.5)
				(island_removal_mode 0)
			)
			(polygon
				(pts
					(xy 82.903568 -3.8481) (xy 82.903568 -2.8575) (xy 83.411568 -2.8575) (xy 83.411568 -3.8481)
				)
			)
		)
		(zone
			(layer "F.Cu")
			(hatch none 0.5)
			(connect_pads
				(clearance 0)
			)
			(min_thickness 0.25)
			(keepout
				(tracks allowed)
				(vias not_allowed)
				(pads allowed)
				(copperpour not_allowed)
				(footprints allowed)
			)
			(placement
				(enabled no)
				(sheetname "")
			)
			(fill
				(thermal_gap 0.5)
				(thermal_bridge_width 0.5)
				(island_removal_mode 0)
			)
			(polygon
				(pts
					(xy 82.903568 -3.8481) (xy 82.903568 -2.8575) (xy 83.411568 -2.8575) (xy 83.411568 -3.8481)
				)
			)
		)
	)
	(footprint ""
		(layer "F.Cu")
		(at 465.328 -41.275)
		(property "Reference" "C9F3"
			(at 0 0 0)
			(layer "F.SilkS")
			(hide yes)
			(effects
				(font
					(size 1.27 1.27)
				)
			)
		)
		(property "Value" ""
			(at 0 0 0)
			(layer "F.Fab")
			(effects
				(font
					(size 1.27 1.27)
				)
			)
		)
		(duplicate_pad_numbers_are_jumpers no)
		(fp_poly
			(pts
				(xy -0.4953 -0.2032) (xy 0.4953 -0.2032) (xy 0.4953 1.6002) (xy -0.4953 1.6002)
			)
			(stroke
				(width 0)
				(type default)
			)
			(fill no)
			(layer "F.CrtYd")
		)
		(fp_line
			(start -0.4953 -0.2032)
			(end 0.4953 -0.2032)
			(stroke
				(width 0.1)
				(type default)
			)
			(layer "F.Fab")
		)
		(fp_line
			(start -0.4953 1.6002)
			(end -0.4953 -0.2032)
			(stroke
				(width 0.1)
				(type default)
			)
			(layer "F.Fab")
		)
		(fp_line
			(start 0.4953 -0.2032)
			(end 0.4953 1.6002)
			(stroke
				(width 0.1)
				(type default)
			)
			(layer "F.Fab")
		)
		(fp_line
			(start 0.4953 1.6002)
			(end -0.4953 1.6002)
			(stroke
				(width 0.1)
				(type default)
			)
			(layer "F.Fab")
		)
		(pad "1" smd rect
			(at 0 0)
			(size 0.762 0.889)
			(layers "F.Cu" "F.Mask" "F.Paste")
			(net "P3V3_STBY")
		)
		(pad "2" smd rect
			(at 0 1.397)
			(size 0.762 0.889)
			(layers "F.Cu" "F.Mask" "F.Paste")
			(net "GND")
		)
		(zone
			(layer "F.Cu")
			(hatch none 0.5)
			(connect_pads
				(clearance 0)
			)
			(min_thickness 0.25)
			(keepout
				(tracks not_allowed)
				(vias allowed)
				(pads allowed)
				(copperpour not_allowed)
				(footprints allowed)
			)
			(placement
				(enabled no)
				(sheetname "")
			)
			(fill
				(thermal_gap 0.5)
				(thermal_bridge_width 0.5)
				(island_removal_mode 0)
			)
			(polygon
				(pts
					(xy 464.947 -40.8305) (xy 465.709 -40.8305) (xy 465.709 -40.3225) (xy 464.947 -40.3225)
				)
			)
		)
	)
	(footprint ""
		(layer "F.Cu")
		(at 337.82 -128.2065 180)
		(property "Reference" "C7B13"
			(at 0 0 180)
			(layer "F.SilkS")
			(hide yes)
			(effects
				(font
					(size 1.27 1.27)
				)
			)
		)
		(property "Value" ""
			(at 0 0 180)
			(layer "F.Fab")
			(effects
				(font
					(size 1.27 1.27)
				)
			)
		)
		(duplicate_pad_numbers_are_jumpers no)
		(fp_poly
			(pts
				(xy 0.3048 -0.1016) (xy 0.3048 0.9906) (xy -0.3048 0.9906) (xy -0.3048 -0.1016)
			)
			(stroke
				(width 0)
				(type default)
			)
			(fill no)
			(layer "F.CrtYd")
		)
		(fp_line
			(start 0.3048 0.9906)
			(end 0.3048 -0.1016)
			(stroke
				(width 0.1)
				(type default)
			)
			(layer "F.Fab")
		)
		(fp_line
			(start 0.3048 -0.1016)
			(end -0.3048 -0.1016)
			(stroke
				(width 0.1)
				(type default)
			)
			(layer "F.Fab")
		)
		(fp_line
			(start -0.3048 0.9906)
			(end 0.3048 0.9906)
			(stroke
				(width 0.1)
				(type default)
			)
			(layer "F.Fab")
		)
		(fp_line
			(start -0.3048 -0.1016)
			(end -0.3048 0.9906)
			(stroke
				(width 0.1)
				(type default)
			)
			(layer "F.Fab")
		)
		(pad "1" smd rect
			(at 0 0 180)
			(size 0.508 0.508)
			(layers "F.Cu" "F.Mask" "F.Paste")
			(net "VR_COMP_PVPP_DEF")
		)
		(pad "2" smd rect
			(at 0 0.889 180)
			(size 0.508 0.508)
			(layers "F.Cu" "F.Mask" "F.Paste")
			(net "VR_FB_PVPP_DEF")
		)
		(zone
			(layer "F.Cu")
			(hatch none 0.5)
			(connect_pads
				(clearance 0)
			)
			(min_thickness 0.25)
			(keepout
				(tracks not_allowed)
				(vias allowed)
				(pads allowed)
				(copperpour not_allowed)
				(footprints allowed)
			)
			(placement
				(enabled no)
				(sheetname "")
			)
			(fill
				(thermal_gap 0.5)
				(thermal_bridge_width 0.5)
				(island_removal_mode 0)
			)
			(polygon
				(pts
					(xy 338.074 -128.8415) (xy 337.566 -128.8415) (xy 337.566 -128.4605) (xy 338.074 -128.4605)
				)
			)
		)
		(zone
			(layer "F.Cu")
			(hatch none 0.5)
			(connect_pads
				(clearance 0)
			)
			(min_thickness 0.25)
			(keepout
				(tracks allowed)
				(vias not_allowed)
				(pads allowed)
				(copperpour not_allowed)
				(footprints allowed)
			)
			(placement
				(enabled no)
				(sheetname "")
			)
			(fill
				(thermal_gap 0.5)
				(thermal_bridge_width 0.5)
				(island_removal_mode 0)
			)
			(polygon
				(pts
					(xy 338.074 -128.4605) (xy 337.566 -128.4605) (xy 337.566 -128.8415) (xy 338.074 -128.8415)
				)
			)
		)
	)
	(footprint ""
		(layer "F.Cu")
		(at 173.7487 -69.723 90)
		(property "Reference" "C4D36"
			(at 0 0 90)
			(layer "F.SilkS")
			(hide yes)
			(effects
				(font
					(size 1.27 1.27)
				)
			)
		)
		(property "Value" ""
			(at 0 0 90)
			(layer "F.Fab")
			(effects
				(font
					(size 1.27 1.27)
				)
			)
		)
		(duplicate_pad_numbers_are_jumpers no)
		(fp_poly
			(pts
				(xy 0.3048 -0.1016) (xy 0.3048 0.9906) (xy -0.3048 0.9906) (xy -0.3048 -0.1016)
			)
			(stroke
				(width 0)
				(type default)
			)
			(fill no)
			(layer "F.CrtYd")
		)
		(fp_line
			(start 0.3048 -0.1016)
			(end -0.3048 -0.1016)
			(stroke
				(width 0.1)
				(type default)
			)
			(layer "F.Fab")
		)
		(fp_line
			(start -0.3048 -0.1016)
			(end -0.3048 0.9906)
			(stroke
				(width 0.1)
				(type default)
			)
			(layer "F.Fab")
		)
		(fp_line
			(start 0.3048 0.9906)
			(end 0.3048 -0.1016)
			(stroke
				(width 0.1)
				(type default)
			)
			(layer "F.Fab")
		)
		(fp_line
			(start -0.3048 0.9906)
			(end 0.3048 0.9906)
			(stroke
				(width 0.1)
				(type default)
			)
			(layer "F.Fab")
		)
		(pad "1" smd rect
			(at 0 0 90)
			(size 0.508 0.508)
			(layers "F.Cu" "F.Mask" "F.Paste")
			(net "VR_PVCCIO_CPU1_VDD")
		)
		(pad "2" smd rect
			(at 0 0.889 90)
			(size 0.508 0.508)
			(layers "F.Cu" "F.Mask" "F.Paste")
			(net "GND")
		)
		(zone
			(layer "F.Cu")
			(hatch none 0.5)
			(connect_pads
				(clearance 0)
			)
			(min_thickness 0.25)
			(keepout
				(tracks allowed)
				(vias not_allowed)
				(pads allowed)
				(copperpour not_allowed)
				(footprints allowed)
			)
			(placement
				(enabled no)
				(sheetname "")
			)
			(fill
				(thermal_gap 0.5)
				(thermal_bridge_width 0.5)
				(island_removal_mode 0)
			)
			(polygon
				(pts
					(xy 174.0027 -69.469) (xy 174.0027 -69.977) (xy 174.3837 -69.977) (xy 174.3837 -69.469)
				)
			)
		)
		(zone
			(layer "F.Cu")
			(hatch none 0.5)
			(connect_pads
				(clearance 0)
			)
			(min_thickness 0.25)
			(keepout
				(tracks not_allowed)
				(vias allowed)
				(pads allowed)
				(copperpour not_allowed)
				(footprints allowed)
			)
			(placement
				(enabled no)
				(sheetname "")
			)
			(fill
				(thermal_gap 0.5)
				(thermal_bridge_width 0.5)
				(island_removal_mode 0)
			)
			(polygon
				(pts
					(xy 174.3837 -69.469) (xy 174.3837 -69.977) (xy 174.0027 -69.977) (xy 174.0027 -69.469)
				)
			)
		)
	)
	(footprint ""
		(layer "F.Cu")
		(at 116.332 -76.327 90)
		(property "Reference" "R3D12"
			(at 0 0 90)
			(layer "F.SilkS")
			(hide yes)
			(effects
				(font
					(size 1.27 1.27)
				)
			)
		)
		(property "Value" ""
			(at 0 0 90)
			(layer "F.Fab")
			(effects
				(font
					(size 1.27 1.27)
				)
			)
		)
		(duplicate_pad_numbers_are_jumpers no)
		(fp_poly
			(pts
				(xy -0.2794 -0.1016) (xy 0.2794 -0.1016) (xy 0.2794 0.9906) (xy -0.2794 0.9906)
			)
			(stroke
				(width 0)
				(type default)
			)
			(fill no)
			(layer "F.CrtYd")
		)
		(fp_line
			(start 0.2794 -0.1016)
			(end -0.2794 -0.1016)
			(stroke
				(width 0.1)
				(type default)
			)
			(layer "F.Fab")
		)
		(fp_line
			(start -0.2794 -0.1016)
			(end -0.2794 0.9906)
			(stroke
				(width 0.1)
				(type default)
			)
			(layer "F.Fab")
		)
		(fp_line
			(start 0.2794 0.9906)
			(end 0.2794 -0.1016)
			(stroke
				(width 0.1)
				(type default)
			)
			(layer "F.Fab")
		)
		(fp_line
			(start -0.2794 0.9906)
			(end 0.2794 0.9906)
			(stroke
				(width 0.1)
				(type default)
			)
			(layer "F.Fab")
		)
		(pad "1" smd rect
			(at 0 0 90)
			(size 0.508 0.508)
			(layers "F.Cu" "F.Mask" "F.Paste")
			(net "GND")
		)
		(pad "2" smd rect
			(at 0 0.889 90)
			(size 0.508 0.508)
			(layers "F.Cu" "F.Mask" "F.Paste")
			(net "PD_CPU1_TXT_PLTEN")
		)
		(zone
			(layer "F.Cu")
			(hatch none 0.5)
			(connect_pads
				(clearance 0)
			)
			(min_thickness 0.25)
			(keepout
				(tracks allowed)
				(vias not_allowed)
				(pads allowed)
				(copperpour not_allowed)
				(footprints allowed)
			)
			(placement
				(enabled no)
				(sheetname "")
			)
			(fill
				(thermal_gap 0.5)
				(thermal_bridge_width 0.5)
				(island_removal_mode 0)
			)
			(polygon
				(pts
					(xy 116.586 -76.073) (xy 116.586 -76.581) (xy 116.967 -76.581) (xy 116.967 -76.073)
				)
			)
		)
		(zone
			(layer "F.Cu")
			(hatch none 0.5)
			(connect_pads
				(clearance 0)
			)
			(min_thickness 0.25)
			(keepout
				(tracks not_allowed)
				(vias allowed)
				(pads allowed)
				(copperpour not_allowed)
				(footprints allowed)
			)
			(placement
				(enabled no)
				(sheetname "")
			)
			(fill
				(thermal_gap 0.5)
				(thermal_bridge_width 0.5)
				(island_removal_mode 0)
			)
			(polygon
				(pts
					(xy 116.967 -76.073) (xy 116.967 -76.581) (xy 116.586 -76.581) (xy 116.586 -76.073)
				)
			)
		)
	)
	(footprint ""
		(layer "F.Cu")
		(at -1.999996 -82.63001 -90)
		(property "Reference" "J1D1"
			(at 0 0 270)
			(layer "F.SilkS")
			(hide yes)
			(effects
				(font
					(size 1.27 1.27)
				)
			)
		)
		(property "Value" "*"
			(at -18.3388 15.2273 270)
			(unlocked yes)
			(layer "F.Fab")
			(hide yes)
			(effects
				(font
					(size 1.27 1.016)
					(thickness 0.1524)
				)
			)
		)
		(property "Device Type" "FCI-CONN12-2R-GP_CONN-G5-FCI-CA"
			(at -18.3388 13.7033 270)
			(unlocked yes)
			(layer "F.Fab")
			(hide yes)
			(effects
				(font
					(size 1.27 1.016)
					(thickness 0.1524)
				)
			)
		)
		(duplicate_pad_numbers_are_jumpers no)
		(fp_line
			(start -6.1849 3.999992)
			(end 6.1849 3.999992)
			(stroke
				(width 0.1524)
				(type default)
			)
			(layer "F.SilkS")
		)
		(fp_line
			(start 6.1849 3.999992)
			(end 6.1849 -14.8971)
			(stroke
				(width 0.1524)
				(type default)
			)
			(layer "F.SilkS")
		)
		(fp_line
			(start -6.1849 -14.8971)
			(end -6.1849 3.999992)
			(stroke
				(width 0.1524)
				(type default)
			)
			(layer "F.SilkS")
		)
		(fp_line
			(start 6.1849 -14.8971)
			(end -6.1849 -14.8971)
			(stroke
				(width 0.1524)
				(type default)
			)
			(layer "F.SilkS")
		)
		(fp_poly
			(pts
				(xy -6.1849 3.999992) (xy 6.1849 3.999992) (xy 6.1849 -14.8971) (xy -6.1849 -14.8971)
			)
			(stroke
				(width 0)
				(type default)
			)
			(fill yes)
			(layer "F.SilkS")
		)
		(fp_poly
			(pts
				(arc
					(start -4.064 1.331976)
					(mid -4.318 1.585976)
					(end -4.572 1.331976)
				)
				(arc
					(start -4.572 0.569976)
					(mid -4.318 0.315976)
					(end -4.064 0.569976)
				)
			)
			(stroke
				(width 0)
				(type default)
			)
			(fill yes)
			(layer "F.SilkS")
		)
		(fp_poly
			(pts
				(arc
					(start -4.064 -0.66802)
					(mid -4.318 -0.41402)
					(end -4.572 -0.66802)
				)
				(arc
					(start -4.572 -1.43002)
					(mid -4.318 -1.68402)
					(end -4.064 -1.43002)
				)
			)
			(stroke
				(width 0)
				(type default)
			)
			(fill yes)
			(layer "F.SilkS")
		)
		(fp_poly
			(pts
				(arc
					(start -4.064 -2.668016)
					(mid -4.318 -2.414016)
					(end -4.572 -2.668016)
				)
				(arc
					(start -4.572 -3.430016)
					(mid -4.318 -3.684016)
					(end -4.064 -3.430016)
				)
			)
			(stroke
				(width 0)
				(type default)
			)
			(fill yes)
			(layer "F.SilkS")
		)
		(fp_poly
			(pts
				(arc
					(start -4.064 -6.668008)
					(mid -4.318 -6.414008)
					(end -4.572 -6.668008)
				)
				(arc
					(start -4.572 -7.430008)
					(mid -4.318 -7.684008)
					(end -4.064 -7.430008)
				)
			)
			(stroke
				(width 0)
				(type default)
			)
			(fill yes)
			(layer "F.SilkS")
		)
		(fp_poly
			(pts
				(arc
					(start -4.064 -8.668004)
					(mid -4.318 -8.414004)
					(end -4.572 -8.668004)
				)
				(arc
					(start -4.572 -9.430004)
					(mid -4.318 -9.684004)
					(end -4.064 -9.430004)
				)
			)
			(stroke
				(width 0)
				(type default)
			)
			(fill yes)
			(layer "F.SilkS")
		)
		(fp_poly
			(pts
				(arc
					(start -4.064 -10.668)
					(mid -4.318 -10.414)
					(end -4.572 -10.668)
				)
				(arc
					(start -4.572 -11.43)
					(mid -4.318 -11.684)
					(end -4.064 -11.43)
				)
			)
			(stroke
				(width 0)
				(type default)
			)
			(fill yes)
			(layer "F.SilkS")
		)
		(fp_rect
			(start -8.5598 6.5532)
			(end 8.5598 -16.5608)
			(stroke
				(width 0)
				(type default)
			)
			(fill no)
			(layer "B.CrtYd")
		)
		(fp_rect
			(start -5.9309 16.3449)
			(end 5.9309 -14.6431)
			(stroke
				(width 0)
				(type default)
			)
			(fill no)
			(layer "F.CrtYd")
		)
		(fp_poly
			(pts
				(xy -10.9347 21.3487) (xy -10.9347 -19.6469) (xy 10.9347 -19.6469) (xy 10.9347 -0.00635) (xy 6.4389 -0.00635)
				(xy 6.4389 -15.1511) (xy -6.4389 -15.1511) (xy -6.4389 16.8529) (xy 6.4389 16.8529) (xy 6.4389 0.00635)
				(xy 10.9347 0.00635) (xy 10.9347 21.3487)
			)
			(stroke
				(width 0)
				(type default)
			)
			(fill no)
			(layer "F.CrtYd")
		)
		(fp_poly
			(pts
				(xy -6.4389 16.8529) (xy -6.4389 -15.1511) (xy 6.4389 -15.1511) (xy 6.4389 -0.00635) (xy 5.9309 -0.00635)
				(xy 5.9309 -14.6431) (xy -5.9309 -14.6431) (xy -5.9309 16.3449) (xy 5.9309 16.3449) (xy 5.9309 0.00635)
				(xy 6.4389 0.00635) (xy 6.4389 16.8529)
			)
			(stroke
				(width 0)
				(type default)
			)
			(fill no)
			(layer "F.CrtYd")
		)
		(fp_rect
			(start -13.5636 11.557)
			(end 13.5636 -21.5646)
			(stroke
				(width 0)
				(type default)
			)
			(fill no)
			(layer "B.Fab")
		)
		(fp_rect
			(start -8.5598 6.5532)
			(end 8.5598 -16.5608)
			(stroke
				(width 0)
				(type default)
			)
			(fill no)
			(layer "B.Fab")
		)
		(fp_rect
			(start -15.9385 26.3525)
			(end 15.9385 -24.6507)
			(stroke
				(width 0)
				(type default)
			)
			(fill no)
			(layer "F.Fab")
		)
		(fp_rect
			(start -10.9347 21.3487)
			(end 10.9347 -19.6469)
			(stroke
				(width 0)
				(type default)
			)
			(fill no)
			(layer "F.Fab")
		)
		(fp_rect
			(start -6.4389 16.8529)
			(end 6.4389 -15.1511)
			(stroke
				(width 0)
				(type default)
			)
			(fill no)
			(layer "F.Fab")
		)
		(fp_text user "Slit"
			(at -2.31521 6.78307 270)
			(unlocked yes)
			(layer "F.SilkS")
			(effects
				(font
					(size 1.27 1.016)
					(thickness 0.1524)
				)
				(justify left)
			)
		)
		(fp_text user "Press Fit"
			(at -5.1054 -12.6111 270)
			(unlocked yes)
			(layer "F.SilkS")
			(effects
				(font
					(size 1.27 1.016)
					(thickness 0.1524)
				)
				(justify left)
			)
		)
		(fp_text user "Can not place BGA,CSP,Wave Solder Component"
			(at -25.73655 8.95604 270)
			(unlocked yes)
			(layer "B.Fab")
			(effects
				(font
					(size 1.27 1.016)
					(thickness 0.1524)
				)
				(justify left)
			)
		)
		(fp_text user "Can not place BGA,CSP,Wave Solder Component"
			(at -25.82926 18.53946 270)
			(unlocked yes)
			(layer "F.Fab")
			(effects
				(font
					(size 1.27 1.016)
					(thickness 0.1524)
				)
				(justify left)
			)
		)
		(fp_text user "High Limit 2mm"
			(at -8.4963 13.35786 270)
			(unlocked yes)
			(layer "F.Fab")
			(effects
				(font
					(size 1.27 1.016)
					(thickness 0.1524)
				)
				(justify left)
			)
		)
		(pad "" np_thru_hole circle
			(at 0 0 270)
			(size 0.254 0.254)
			(drill 2.1336)
			(layers "*.Cu" "*.Mask")
			(clearance 1.2954)
			(thermal_gap 1.2954)
		)
		(pad "1_1" thru_hole circle
			(at 2.999994 -6.999986 270)
			(size 1.1176 1.1176)
			(drill 0.749808)
			(layers "*.Cu" "*.Mask")
			(remove_unused_layers no)
			(net "P12V_PSU")
			(clearance 0.1778)
			(thermal_gap 0.1778)
		)
		(pad "1_2" thru_hole circle
			(at 2.999994 -8.999982 270)
			(size 1.1176 1.1176)
			(drill 0.749808)
			(layers "*.Cu" "*.Mask")
			(remove_unused_layers no)
			(net "P12V_PSU")
			(clearance 0.1778)
			(thermal_gap 0.1778)
		)
		(pad "1_3" thru_hole circle
			(at 2.999994 -10.999978 270)
			(size 1.1176 1.1176)
			(drill 0.749808)
			(layers "*.Cu" "*.Mask")
			(remove_unused_layers no)
			(net "P12V_PSU")
			(clearance 0.1778)
			(thermal_gap 0.1778)
		)
		(pad "2_1" thru_hole circle
			(at -2.999994 -6.999986 270)
			(size 1.1176 1.1176)
			(drill 0.749808)
			(layers "*.Cu" "*.Mask")
			(remove_unused_layers no)
			(net "P12V_PSU")
			(clearance 0.1778)
			(thermal_gap 0.1778)
		)
		(pad "2_2" thru_hole circle
			(at -2.999994 -8.999982 270)
			(size 1.1176 1.1176)
			(drill 0.749808)
			(layers "*.Cu" "*.Mask")
			(remove_unused_layers no)
			(net "P12V_PSU")
			(clearance 0.1778)
			(thermal_gap 0.1778)
		)
		(pad "2_3" thru_hole circle
			(at -2.999994 -10.999978 270)
			(size 1.1176 1.1176)
			(drill 0.749808)
			(layers "*.Cu" "*.Mask")
			(remove_unused_layers no)
			(net "P12V_PSU")
			(clearance 0.1778)
			(thermal_gap 0.1778)
		)
		(pad "3_1" thru_hole circle
			(at -2.999994 0.999998 270)
			(size 1.1176 1.1176)
			(drill 0.749808)
			(layers "*.Cu" "*.Mask")
			(remove_unused_layers no)
			(net "GND")
			(clearance 0.1778)
			(thermal_gap 0.1778)
		)
		(pad "3_2" thru_hole circle
			(at -2.999994 -0.999998 270)
			(size 1.1176 1.1176)
			(drill 0.749808)
			(layers "*.Cu" "*.Mask")
			(remove_unused_layers no)
			(net "GND")
			(clearance 0.1778)
			(thermal_gap 0.1778)
		)
		(pad "3_3" thru_hole circle
			(at -2.999994 -2.999994 270)
			(size 1.1176 1.1176)
			(drill 0.749808)
			(layers "*.Cu" "*.Mask")
			(remove_unused_layers no)
			(net "GND")
			(clearance 0.1778)
			(thermal_gap 0.1778)
		)
		(pad "4_1" thru_hole circle
			(at 2.999994 0.999998 270)
			(size 1.1176 1.1176)
			(drill 0.749808)
			(layers "*.Cu" "*.Mask")
			(remove_unused_layers no)
			(net "GND")
			(clearance 0.1778)
			(thermal_gap 0.1778)
		)
		(pad "4_2" thru_hole circle
			(at 2.999994 -0.999998 270)
			(size 1.1176 1.1176)
			(drill 0.749808)
			(layers "*.Cu" "*.Mask")
			(remove_unused_layers no)
			(net "GND")
			(clearance 0.1778)
			(thermal_gap 0.1778)
		)
		(pad "4_3" thru_hole circle
			(at 2.999994 -2.999994 270)
			(size 1.1176 1.1176)
			(drill 0.749808)
			(layers "*.Cu" "*.Mask")
			(remove_unused_layers no)
			(net "GND")
			(clearance 0.1778)
			(thermal_gap 0.1778)
		)
		(zone
			(layers "F.Cu" "B.Cu" "In1.Cu" "In2.Cu" "In3.Cu" "In4.Cu" "In5.Cu" "In6.Cu"
				"In7.Cu" "In8.Cu" "In9.Cu" "In10.Cu" "In11.Cu" "In12.Cu"
			)
			(hatch none 0.5)
			(connect_pads
				(clearance 0)
			)
			(min_thickness 0.25)
			(keepout
				(tracks not_allowed)
				(vias allowed)
				(pads allowed)
				(copperpour not_allowed)
				(footprints allowed)
			)
			(placement
				(enabled no)
				(sheetname "")
			)
			(fill
				(thermal_gap 0.5)
				(thermal_bridge_width 0.5)
				(island_removal_mode 0)
			)
			(polygon
				(pts
					(arc
						(start -0.628396 -82.63001)
						(mid -3.371596 -82.63001)
						(end -0.628396 -82.63001)
					)
				)
			)
		)
	)
	(footprint ""
		(layer "F.Cu")
		(at 340.995 -106.426 90)
		(property "Reference" "R7C24"
			(at 0 0 90)
			(layer "F.SilkS")
			(hide yes)
			(effects
				(font
					(size 1.27 1.27)
				)
			)
		)
		(property "Value" ""
			(at 0 0 90)
			(layer "F.Fab")
			(effects
				(font
					(size 1.27 1.27)
				)
			)
		)
		(duplicate_pad_numbers_are_jumpers no)
		(fp_poly
			(pts
				(xy -0.2794 -0.1016) (xy 0.2794 -0.1016) (xy 0.2794 0.9906) (xy -0.2794 0.9906)
			)
			(stroke
				(width 0)
				(type default)
			)
			(fill no)
			(layer "F.CrtYd")
		)
		(fp_line
			(start 0.2794 -0.1016)
			(end -0.2794 -0.1016)
			(stroke
				(width 0.1)
				(type default)
			)
			(layer "F.Fab")
		)
		(fp_line
			(start -0.2794 -0.1016)
			(end -0.2794 0.9906)
			(stroke
				(width 0.1)
				(type default)
			)
			(layer "F.Fab")
		)
		(fp_line
			(start 0.2794 0.9906)
			(end 0.2794 -0.1016)
			(stroke
				(width 0.1)
				(type default)
			)
			(layer "F.Fab")
		)
		(fp_line
			(start -0.2794 0.9906)
			(end 0.2794 0.9906)
			(stroke
				(width 0.1)
				(type default)
			)
			(layer "F.Fab")
		)
		(pad "1" smd rect
			(at 0 0 90)
			(size 0.508 0.508)
			(layers "F.Cu" "F.Mask" "F.Paste")
			(net "VR_PVCCMCP_CPU0_XADDR2")
		)
		(pad "2" smd rect
			(at 0 0.889 90)
			(size 0.508 0.508)
			(layers "F.Cu" "F.Mask" "F.Paste")
			(net "GND")
		)
		(zone
			(layer "F.Cu")
			(hatch none 0.5)
			(connect_pads
				(clearance 0)
			)
			(min_thickness 0.25)
			(keepout
				(tracks allowed)
				(vias not_allowed)
				(pads allowed)
				(copperpour not_allowed)
				(footprints allowed)
			)
			(placement
				(enabled no)
				(sheetname "")
			)
			(fill
				(thermal_gap 0.5)
				(thermal_bridge_width 0.5)
				(island_removal_mode 0)
			)
			(polygon
				(pts
					(xy 341.249 -106.172) (xy 341.249 -106.68) (xy 341.63 -106.68) (xy 341.63 -106.172)
				)
			)
		)
		(zone
			(layer "F.Cu")
			(hatch none 0.5)
			(connect_pads
				(clearance 0)
			)
			(min_thickness 0.25)
			(keepout
				(tracks not_allowed)
				(vias allowed)
				(pads allowed)
				(copperpour not_allowed)
				(footprints allowed)
			)
			(placement
				(enabled no)
				(sheetname "")
			)
			(fill
				(thermal_gap 0.5)
				(thermal_bridge_width 0.5)
				(island_removal_mode 0)
			)
			(polygon
				(pts
					(xy 341.63 -106.172) (xy 341.63 -106.68) (xy 341.249 -106.68) (xy 341.249 -106.172)
				)
			)
		)
	)
	(footprint ""
		(layer "F.Cu")
		(at 348.2086 -10.2108 90)
		(property "Reference" "C7G33"
			(at 0 0 90)
			(layer "F.SilkS")
			(hide yes)
			(effects
				(font
					(size 1.27 1.27)
				)
			)
		)
		(property "Value" ""
			(at 0 0 90)
			(layer "F.Fab")
			(effects
				(font
					(size 1.27 1.27)
				)
			)
		)
		(duplicate_pad_numbers_are_jumpers no)
		(fp_poly
			(pts
				(xy 0.3048 -0.1016) (xy 0.3048 0.9906) (xy -0.3048 0.9906) (xy -0.3048 -0.1016)
			)
			(stroke
				(width 0)
				(type default)
			)
			(fill no)
			(layer "F.CrtYd")
		)
		(fp_line
			(start 0.3048 -0.1016)
			(end -0.3048 -0.1016)
			(stroke
				(width 0.1)
				(type default)
			)
			(layer "F.Fab")
		)
		(fp_line
			(start -0.3048 -0.1016)
			(end -0.3048 0.9906)
			(stroke
				(width 0.1)
				(type default)
			)
			(layer "F.Fab")
		)
		(fp_line
			(start 0.3048 0.9906)
			(end 0.3048 -0.1016)
			(stroke
				(width 0.1)
				(type default)
			)
			(layer "F.Fab")
		)
		(fp_line
			(start -0.3048 0.9906)
			(end 0.3048 0.9906)
			(stroke
				(width 0.1)
				(type default)
			)
			(layer "F.Fab")
		)
		(pad "1" smd rect
			(at 0 0 90)
			(size 0.508 0.508)
			(layers "F.Cu" "F.Mask" "F.Paste")
			(net "VR_PVDDQ_ABC_PH1_VCIN")
		)
		(pad "2" smd rect
			(at 0 0.889 90)
			(size 0.508 0.508)
			(layers "F.Cu" "F.Mask" "F.Paste")
			(net "GND")
		)
		(zone
			(layer "F.Cu")
			(hatch none 0.5)
			(connect_pads
				(clearance 0)
			)
			(min_thickness 0.25)
			(keepout
				(tracks allowed)
				(vias not_allowed)
				(pads allowed)
				(copperpour not_allowed)
				(footprints allowed)
			)
			(placement
				(enabled no)
				(sheetname "")
			)
			(fill
				(thermal_gap 0.5)
				(thermal_bridge_width 0.5)
				(island_removal_mode 0)
			)
			(polygon
				(pts
					(xy 348.4626 -9.9568) (xy 348.4626 -10.4648) (xy 348.8436 -10.4648) (xy 348.8436 -9.9568)
				)
			)
		)
		(zone
			(layer "F.Cu")
			(hatch none 0.5)
			(connect_pads
				(clearance 0)
			)
			(min_thickness 0.25)
			(keepout
				(tracks not_allowed)
				(vias allowed)
				(pads allowed)
				(copperpour not_allowed)
				(footprints allowed)
			)
			(placement
				(enabled no)
				(sheetname "")
			)
			(fill
				(thermal_gap 0.5)
				(thermal_bridge_width 0.5)
				(island_removal_mode 0)
			)
			(polygon
				(pts
					(xy 348.8436 -9.9568) (xy 348.8436 -10.4648) (xy 348.4626 -10.4648) (xy 348.4626 -9.9568)
				)
			)
		)
	)
	(footprint ""
		(layer "F.Cu")
		(at 342.2142 -94.107 90)
		(property "Reference" "CT72"
			(at -0.8382 -0.67818 90)
			(unlocked yes)
			(layer "F.SilkS")
			(effects
				(font
					(size 0.4064 0.254)
					(thickness 0.1524)
				)
				(justify left)
			)
		)
		(property "Value" ""
			(at 0 0 90)
			(layer "F.Fab")
			(effects
				(font
					(size 1.27 1.27)
				)
			)
		)
		(duplicate_pad_numbers_are_jumpers no)
		(fp_poly
			(pts
				(xy 0.3048 -0.1016) (xy 0.3048 0.9906) (xy -0.3048 0.9906) (xy -0.3048 -0.1016)
			)
			(stroke
				(width 0)
				(type default)
			)
			(fill no)
			(layer "F.CrtYd")
		)
		(fp_line
			(start 0.3048 -0.1016)
			(end -0.3048 -0.1016)
			(stroke
				(width 0.1)
				(type default)
			)
			(layer "F.Fab")
		)
		(fp_line
			(start -0.3048 -0.1016)
			(end -0.3048 0.9906)
			(stroke
				(width 0.1)
				(type default)
			)
			(layer "F.Fab")
		)
		(fp_line
			(start 0.3048 0.9906)
			(end 0.3048 -0.1016)
			(stroke
				(width 0.1)
				(type default)
			)
			(layer "F.Fab")
		)
		(fp_line
			(start -0.3048 0.9906)
			(end 0.3048 0.9906)
			(stroke
				(width 0.1)
				(type default)
			)
			(layer "F.Fab")
		)
		(pad "1" smd rect
			(at 0 0 90)
			(size 0.508 0.508)
			(layers "F.Cu" "F.Mask" "F.Paste")
			(net "VR_PVCCIO_CPU0_PH1_SW")
		)
		(pad "2" smd rect
			(at 0 0.889 90)
			(size 0.508 0.508)
			(layers "F.Cu" "F.Mask" "F.Paste")
			(net "VR_PVCCIO_CPU0_PH1_SW_RC")
		)
		(zone
			(layer "F.Cu")
			(hatch none 0.5)
			(connect_pads
				(clearance 0)
			)
			(min_thickness 0.25)
			(keepout
				(tracks allowed)
				(vias not_allowed)
				(pads allowed)
				(copperpour not_allowed)
				(footprints allowed)
			)
			(placement
				(enabled no)
				(sheetname "")
			)
			(fill
				(thermal_gap 0.5)
				(thermal_bridge_width 0.5)
				(island_removal_mode 0)
			)
			(polygon
				(pts
					(xy 342.4682 -93.853) (xy 342.4682 -94.361) (xy 342.8492 -94.361) (xy 342.8492 -93.853)
				)
			)
		)
		(zone
			(layer "F.Cu")
			(hatch none 0.5)
			(connect_pads
				(clearance 0)
			)
			(min_thickness 0.25)
			(keepout
				(tracks not_allowed)
				(vias allowed)
				(pads allowed)
				(copperpour not_allowed)
				(footprints allowed)
			)
			(placement
				(enabled no)
				(sheetname "")
			)
			(fill
				(thermal_gap 0.5)
				(thermal_bridge_width 0.5)
				(island_removal_mode 0)
			)
			(polygon
				(pts
					(xy 342.8492 -93.853) (xy 342.8492 -94.361) (xy 342.4682 -94.361) (xy 342.4682 -93.853)
				)
			)
		)
	)
	(footprint ""
		(layer "F.Cu")
		(at 435.388766 -43.086274 180)
		(property "Reference" "R25W30"
			(at -0.8382 -0.67818 180)
			(unlocked yes)
			(layer "F.SilkS")
			(effects
				(font
					(size 0.4064 0.254)
					(thickness 0.1524)
				)
				(justify left)
			)
		)
		(property "Value" ""
			(at 0 0 180)
			(layer "F.Fab")
			(effects
				(font
					(size 1.27 1.27)
				)
			)
		)
		(duplicate_pad_numbers_are_jumpers no)
		(fp_poly
			(pts
				(xy -0.2794 -0.1016) (xy 0.2794 -0.1016) (xy 0.2794 0.9906) (xy -0.2794 0.9906)
			)
			(stroke
				(width 0)
				(type default)
			)
			(fill no)
			(layer "F.CrtYd")
		)
		(fp_line
			(start 0.2794 0.9906)
			(end 0.2794 -0.1016)
			(stroke
				(width 0.1)
				(type default)
			)
			(layer "F.Fab")
		)
		(fp_line
			(start 0.2794 -0.1016)
			(end -0.2794 -0.1016)
			(stroke
				(width 0.1)
				(type default)
			)
			(layer "F.Fab")
		)
		(fp_line
			(start -0.2794 0.9906)
			(end 0.2794 0.9906)
			(stroke
				(width 0.1)
				(type default)
			)
			(layer "F.Fab")
		)
		(fp_line
			(start -0.2794 -0.1016)
			(end -0.2794 0.9906)
			(stroke
				(width 0.1)
				(type default)
			)
			(layer "F.Fab")
		)
		(pad "1" smd rect
			(at 0 0 180)
			(size 0.508 0.508)
			(layers "F.Cu" "F.Mask" "F.Paste")
			(net "BMC_M_MALERT_N")
		)
		(pad "2" smd rect
			(at 0 0.889 180)
			(size 0.508 0.508)
			(layers "F.Cu" "F.Mask" "F.Paste")
			(net "P1V2_AUX_BMC")
		)
		(zone
			(layer "F.Cu")
			(hatch none 0.5)
			(connect_pads
				(clearance 0)
			)
			(min_thickness 0.25)
			(keepout
				(tracks not_allowed)
				(vias allowed)
				(pads allowed)
				(copperpour not_allowed)
				(footprints allowed)
			)
			(placement
				(enabled no)
				(sheetname "")
			)
			(fill
				(thermal_gap 0.5)
				(thermal_bridge_width 0.5)
				(island_removal_mode 0)
			)
			(polygon
				(pts
					(xy 435.642766 -43.721274) (xy 435.134766 -43.721274) (xy 435.134766 -43.340274) (xy 435.642766 -43.340274)
				)
			)
		)
		(zone
			(layer "F.Cu")
			(hatch none 0.5)
			(connect_pads
				(clearance 0)
			)
			(min_thickness 0.25)
			(keepout
				(tracks allowed)
				(vias not_allowed)
				(pads allowed)
				(copperpour not_allowed)
				(footprints allowed)
			)
			(placement
				(enabled no)
				(sheetname "")
			)
			(fill
				(thermal_gap 0.5)
				(thermal_bridge_width 0.5)
				(island_removal_mode 0)
			)
			(polygon
				(pts
					(xy 435.642766 -43.340274) (xy 435.134766 -43.340274) (xy 435.134766 -43.721274) (xy 435.642766 -43.721274)
				)
			)
		)
	)
	(footprint ""
		(layer "F.Cu")
		(at 18.669 -70.866)
		(property "Reference" "C1D25"
			(at 0 0 0)
			(layer "F.SilkS")
			(hide yes)
			(effects
				(font
					(size 1.27 1.27)
				)
			)
		)
		(property "Value" ""
			(at 0 0 0)
			(layer "F.Fab")
			(effects
				(font
					(size 1.27 1.27)
				)
			)
		)
		(duplicate_pad_numbers_are_jumpers no)
		(fp_poly
			(pts
				(xy 0.3048 -0.1016) (xy 0.3048 0.9906) (xy -0.3048 0.9906) (xy -0.3048 -0.1016)
			)
			(stroke
				(width 0)
				(type default)
			)
			(fill no)
			(layer "F.CrtYd")
		)
		(fp_line
			(start -0.3048 -0.1016)
			(end -0.3048 0.9906)
			(stroke
				(width 0.1)
				(type default)
			)
			(layer "F.Fab")
		)
		(fp_line
			(start -0.3048 0.9906)
			(end 0.3048 0.9906)
			(stroke
				(width 0.1)
				(type default)
			)
			(layer "F.Fab")
		)
		(fp_line
			(start 0.3048 -0.1016)
			(end -0.3048 -0.1016)
			(stroke
				(width 0.1)
				(type default)
			)
			(layer "F.Fab")
		)
		(fp_line
			(start 0.3048 0.9906)
			(end 0.3048 -0.1016)
			(stroke
				(width 0.1)
				(type default)
			)
			(layer "F.Fab")
		)
		(pad "1" smd rect
			(at 0 0)
			(size 0.508 0.508)
			(layers "F.Cu" "F.Mask" "F.Paste")
			(net "P12V_HSC_VCC")
		)
		(pad "2" smd rect
			(at 0 0.889)
			(size 0.508 0.508)
			(layers "F.Cu" "F.Mask" "F.Paste")
			(net "AGND_HSC")
		)
		(zone
			(layer "F.Cu")
			(hatch none 0.5)
			(connect_pads
				(clearance 0)
			)
			(min_thickness 0.25)
			(keepout
				(tracks allowed)
				(vias not_allowed)
				(pads allowed)
				(copperpour not_allowed)
				(footprints allowed)
			)
			(placement
				(enabled no)
				(sheetname "")
			)
			(fill
				(thermal_gap 0.5)
				(thermal_bridge_width 0.5)
				(island_removal_mode 0)
			)
			(polygon
				(pts
					(xy 18.415 -70.612) (xy 18.923 -70.612) (xy 18.923 -70.231) (xy 18.415 -70.231)
				)
			)
		)
		(zone
			(layer "F.Cu")
			(hatch none 0.5)
			(connect_pads
				(clearance 0)
			)
			(min_thickness 0.25)
			(keepout
				(tracks not_allowed)
				(vias allowed)
				(pads allowed)
				(copperpour not_allowed)
				(footprints allowed)
			)
			(placement
				(enabled no)
				(sheetname "")
			)
			(fill
				(thermal_gap 0.5)
				(thermal_bridge_width 0.5)
				(island_removal_mode 0)
			)
			(polygon
				(pts
					(xy 18.415 -70.231) (xy 18.923 -70.231) (xy 18.923 -70.612) (xy 18.415 -70.612)
				)
			)
		)
	)
	(footprint ""
		(layer "F.Cu")
		(at 205.036928 -81.415382)
		(property "Reference" "L4D1"
			(at 3.378708 -4.251706 0)
			(unlocked yes)
			(layer "F.SilkS")
			(effects
				(font
					(size 0.4064 0.254)
					(thickness 0.1524)
				)
			)
		)
		(property "Value" ""
			(at 0 0 0)
			(layer "F.Fab")
			(effects
				(font
					(size 1.27 1.27)
				)
			)
		)
		(duplicate_pad_numbers_are_jumpers no)
		(fp_line
			(start -1.1303 -3.199892)
			(end 8.3693 -3.199892)
			(stroke
				(width 0.1524)
				(type default)
			)
			(layer "F.SilkS")
		)
		(fp_line
			(start -1.1303 -1.6637)
			(end -1.1303 -3.199892)
			(stroke
				(width 0.1524)
				(type default)
			)
			(layer "F.SilkS")
		)
		(fp_line
			(start -1.1303 3.199892)
			(end -1.1303 1.6637)
			(stroke
				(width 0.1524)
				(type default)
			)
			(layer "F.SilkS")
		)
		(fp_line
			(start 8.3693 -3.199892)
			(end 8.3693 -1.6637)
			(stroke
				(width 0.1524)
				(type default)
			)
			(layer "F.SilkS")
		)
		(fp_line
			(start 8.3693 1.6637)
			(end 8.3693 3.199892)
			(stroke
				(width 0.1524)
				(type default)
			)
			(layer "F.SilkS")
		)
		(fp_line
			(start 8.3693 3.199892)
			(end -1.1303 3.199892)
			(stroke
				(width 0.1524)
				(type default)
			)
			(layer "F.SilkS")
		)
		(fp_rect
			(start -1.1303 3.199892)
			(end 8.3693 -3.199892)
			(stroke
				(width 0)
				(type default)
			)
			(fill no)
			(layer "F.CrtYd")
		)
		(fp_line
			(start -1.1303 -3.199892)
			(end 8.3693 -3.199892)
			(stroke
				(width 0.1)
				(type default)
			)
			(layer "F.Fab")
		)
		(fp_line
			(start -1.1303 3.199892)
			(end -1.1303 -3.199892)
			(stroke
				(width 0.1)
				(type default)
			)
			(layer "F.Fab")
		)
		(fp_line
			(start 8.3693 -3.199892)
			(end 8.3693 3.199892)
			(stroke
				(width 0.1)
				(type default)
			)
			(layer "F.Fab")
		)
		(fp_line
			(start 8.3693 3.199892)
			(end -1.1303 3.199892)
			(stroke
				(width 0.1)
				(type default)
			)
			(layer "F.Fab")
		)
		(pad "1" smd rect
			(at 0 0)
			(size 3.683 2.667)
			(layers "F.Cu" "F.Mask" "F.Paste")
			(net "VR_PVCCIN_CPU0_PHASE4")
		)
		(pad "2" smd rect
			(at 7.239 0)
			(size 3.683 2.667)
			(layers "F.Cu" "F.Mask" "F.Paste")
			(net "PVCCIN_CPU0")
		)
	)
	(footprint ""
		(layer "F.Cu")
		(at 343.789 -22.64156 90)
		(property "Reference" "C7F12"
			(at 0 0 90)
			(layer "F.SilkS")
			(hide yes)
			(effects
				(font
					(size 1.27 1.27)
				)
			)
		)
		(property "Value" ""
			(at 0 0 90)
			(layer "F.Fab")
			(effects
				(font
					(size 1.27 1.27)
				)
			)
		)
		(duplicate_pad_numbers_are_jumpers no)
		(fp_poly
			(pts
				(xy 0.3048 -0.1016) (xy 0.3048 0.9906) (xy -0.3048 0.9906) (xy -0.3048 -0.1016)
			)
			(stroke
				(width 0)
				(type default)
			)
			(fill no)
			(layer "F.CrtYd")
		)
		(fp_line
			(start 0.3048 -0.1016)
			(end -0.3048 -0.1016)
			(stroke
				(width 0.1)
				(type default)
			)
			(layer "F.Fab")
		)
		(fp_line
			(start -0.3048 -0.1016)
			(end -0.3048 0.9906)
			(stroke
				(width 0.1)
				(type default)
			)
			(layer "F.Fab")
		)
		(fp_line
			(start 0.3048 0.9906)
			(end 0.3048 -0.1016)
			(stroke
				(width 0.1)
				(type default)
			)
			(layer "F.Fab")
		)
		(fp_line
			(start -0.3048 0.9906)
			(end 0.3048 0.9906)
			(stroke
				(width 0.1)
				(type default)
			)
			(layer "F.Fab")
		)
		(pad "1" smd rect
			(at 0 0 90)
			(size 0.508 0.508)
			(layers "F.Cu" "F.Mask" "F.Paste")
			(net "VR_COMP_RC_PVPP_ABC")
		)
		(pad "2" smd rect
			(at 0 0.889 90)
			(size 0.508 0.508)
			(layers "F.Cu" "F.Mask" "F.Paste")
			(net "VR_COMP_PVPP_ABC_3")
		)
		(zone
			(layer "F.Cu")
			(hatch none 0.5)
			(connect_pads
				(clearance 0)
			)
			(min_thickness 0.25)
			(keepout
				(tracks allowed)
				(vias not_allowed)
				(pads allowed)
				(copperpour not_allowed)
				(footprints allowed)
			)
			(placement
				(enabled no)
				(sheetname "")
			)
			(fill
				(thermal_gap 0.5)
				(thermal_bridge_width 0.5)
				(island_removal_mode 0)
			)
			(polygon
				(pts
					(xy 344.043 -22.38756) (xy 344.043 -22.89556) (xy 344.424 -22.89556) (xy 344.424 -22.38756)
				)
			)
		)
		(zone
			(layer "F.Cu")
			(hatch none 0.5)
			(connect_pads
				(clearance 0)
			)
			(min_thickness 0.25)
			(keepout
				(tracks not_allowed)
				(vias allowed)
				(pads allowed)
				(copperpour not_allowed)
				(footprints allowed)
			)
			(placement
				(enabled no)
				(sheetname "")
			)
			(fill
				(thermal_gap 0.5)
				(thermal_bridge_width 0.5)
				(island_removal_mode 0)
			)
			(polygon
				(pts
					(xy 344.424 -22.38756) (xy 344.424 -22.89556) (xy 344.043 -22.89556) (xy 344.043 -22.38756)
				)
			)
		)
	)
	(footprint ""
		(layer "F.Cu")
		(at 346.906342 5.168646 -90)
		(property "Reference" "C7G36"
			(at 0 0 270)
			(layer "F.SilkS")
			(hide yes)
			(effects
				(font
					(size 1.27 1.27)
				)
			)
		)
		(property "Value" ""
			(at 0 0 270)
			(layer "F.Fab")
			(effects
				(font
					(size 1.27 1.27)
				)
			)
		)
		(duplicate_pad_numbers_are_jumpers no)
		(fp_rect
			(start -0.3048 0.9906)
			(end 0.3048 -0.1016)
			(stroke
				(width 0)
				(type default)
			)
			(fill no)
			(layer "F.CrtYd")
		)
		(fp_line
			(start -0.3048 0.9906)
			(end 0.3048 0.9906)
			(stroke
				(width 0.1)
				(type default)
			)
			(layer "F.Fab")
		)
		(fp_line
			(start 0.3048 0.9906)
			(end 0.3048 -0.1016)
			(stroke
				(width 0.1)
				(type default)
			)
			(layer "F.Fab")
		)
		(fp_line
			(start -0.3048 -0.1016)
			(end -0.3048 0.9906)
			(stroke
				(width 0.1)
				(type default)
			)
			(layer "F.Fab")
		)
		(fp_line
			(start 0.3048 -0.1016)
			(end -0.3048 -0.1016)
			(stroke
				(width 0.1)
				(type default)
			)
			(layer "F.Fab")
		)
		(pad "1" smd rect
			(at 0 0 270)
			(size 0.508 0.508)
			(layers "F.Cu" "F.Mask" "F.Paste")
			(net "VR_FET_SW_P12V_STBY_PVDDQ_ABC")
		)
		(pad "2" smd rect
			(at 0 0.889 270)
			(size 0.508 0.508)
			(layers "F.Cu" "F.Mask" "F.Paste")
			(net "GND")
		)
		(zone
			(layer "F.Cu")
			(hatch none 0.5)
			(connect_pads
				(clearance 0)
			)
			(min_thickness 0.25)
			(keepout
				(tracks not_allowed)
				(vias allowed)
				(pads allowed)
				(copperpour not_allowed)
				(footprints allowed)
			)
			(placement
				(enabled no)
				(sheetname "")
			)
			(fill
				(thermal_gap 0.5)
				(thermal_bridge_width 0.5)
				(island_removal_mode 0)
			)
			(polygon
				(pts
					(xy 346.271342 4.914646) (xy 346.271342 5.422646) (xy 346.652342 5.422646) (xy 346.652342 4.914646)
				)
			)
		)
		(zone
			(layer "F.Cu")
			(hatch none 0.5)
			(connect_pads
				(clearance 0)
			)
			(min_thickness 0.25)
			(keepout
				(tracks allowed)
				(vias not_allowed)
				(pads allowed)
				(copperpour not_allowed)
				(footprints allowed)
			)
			(placement
				(enabled no)
				(sheetname "")
			)
			(fill
				(thermal_gap 0.5)
				(thermal_bridge_width 0.5)
				(island_removal_mode 0)
			)
			(polygon
				(pts
					(xy 346.271342 4.914646) (xy 346.271342 5.422646) (xy 346.652342 5.422646) (xy 346.652342 4.914646)
				)
			)
		)
	)
	(footprint ""
		(layer "F.Cu")
		(at 8.763 -13.843)
		(property "Reference" "CT33"
			(at -0.8382 -0.67818 0)
			(unlocked yes)
			(layer "F.SilkS")
			(effects
				(font
					(size 0.4064 0.254)
					(thickness 0.1524)
				)
				(justify left)
			)
		)
		(property "Value" ""
			(at 0 0 0)
			(layer "F.Fab")
			(effects
				(font
					(size 1.27 1.27)
				)
			)
		)
		(duplicate_pad_numbers_are_jumpers no)
		(fp_poly
			(pts
				(xy 0.3048 -0.1016) (xy 0.3048 0.9906) (xy -0.3048 0.9906) (xy -0.3048 -0.1016)
			)
			(stroke
				(width 0)
				(type default)
			)
			(fill no)
			(layer "F.CrtYd")
		)
		(fp_line
			(start -0.3048 -0.1016)
			(end -0.3048 0.9906)
			(stroke
				(width 0.1)
				(type default)
			)
			(layer "F.Fab")
		)
		(fp_line
			(start -0.3048 0.9906)
			(end 0.3048 0.9906)
			(stroke
				(width 0.1)
				(type default)
			)
			(layer "F.Fab")
		)
		(fp_line
			(start 0.3048 -0.1016)
			(end -0.3048 -0.1016)
			(stroke
				(width 0.1)
				(type default)
			)
			(layer "F.Fab")
		)
		(fp_line
			(start 0.3048 0.9906)
			(end 0.3048 -0.1016)
			(stroke
				(width 0.1)
				(type default)
			)
			(layer "F.Fab")
		)
		(pad "1" smd rect
			(at 0 0)
			(size 0.508 0.508)
			(layers "F.Cu" "F.Mask" "F.Paste")
			(net "VR_PVDDQ_GHJ_PH2_SW")
		)
		(pad "2" smd rect
			(at 0 0.889)
			(size 0.508 0.508)
			(layers "F.Cu" "F.Mask" "F.Paste")
			(net "VR_PVDDQ_GHJ_PH2_SW_RC")
		)
		(zone
			(layer "F.Cu")
			(hatch none 0.5)
			(connect_pads
				(clearance 0)
			)
			(min_thickness 0.25)
			(keepout
				(tracks allowed)
				(vias not_allowed)
				(pads allowed)
				(copperpour not_allowed)
				(footprints allowed)
			)
			(placement
				(enabled no)
				(sheetname "")
			)
			(fill
				(thermal_gap 0.5)
				(thermal_bridge_width 0.5)
				(island_removal_mode 0)
			)
			(polygon
				(pts
					(xy 8.509 -13.589) (xy 9.017 -13.589) (xy 9.017 -13.208) (xy 8.509 -13.208)
				)
			)
		)
		(zone
			(layer "F.Cu")
			(hatch none 0.5)
			(connect_pads
				(clearance 0)
			)
			(min_thickness 0.25)
			(keepout
				(tracks not_allowed)
				(vias allowed)
				(pads allowed)
				(copperpour not_allowed)
				(footprints allowed)
			)
			(placement
				(enabled no)
				(sheetname "")
			)
			(fill
				(thermal_gap 0.5)
				(thermal_bridge_width 0.5)
				(island_removal_mode 0)
			)
			(polygon
				(pts
					(xy 8.509 -13.208) (xy 9.017 -13.208) (xy 9.017 -13.589) (xy 8.509 -13.589)
				)
			)
		)
	)
	(footprint ""
		(layer "F.Cu")
		(at 182.372 -56.1594 180)
		(property "Reference" "R4E21"
			(at 0 0 180)
			(layer "F.SilkS")
			(hide yes)
			(effects
				(font
					(size 1.27 1.27)
				)
			)
		)
		(property "Value" ""
			(at 0 0 180)
			(layer "F.Fab")
			(effects
				(font
					(size 1.27 1.27)
				)
			)
		)
		(duplicate_pad_numbers_are_jumpers no)
		(fp_poly
			(pts
				(xy -0.2794 -0.1016) (xy 0.2794 -0.1016) (xy 0.2794 0.9906) (xy -0.2794 0.9906)
			)
			(stroke
				(width 0)
				(type default)
			)
			(fill no)
			(layer "F.CrtYd")
		)
		(fp_line
			(start 0.2794 0.9906)
			(end 0.2794 -0.1016)
			(stroke
				(width 0.1)
				(type default)
			)
			(layer "F.Fab")
		)
		(fp_line
			(start 0.2794 -0.1016)
			(end -0.2794 -0.1016)
			(stroke
				(width 0.1)
				(type default)
			)
			(layer "F.Fab")
		)
		(fp_line
			(start -0.2794 0.9906)
			(end 0.2794 0.9906)
			(stroke
				(width 0.1)
				(type default)
			)
			(layer "F.Fab")
		)
		(fp_line
			(start -0.2794 -0.1016)
			(end -0.2794 0.9906)
			(stroke
				(width 0.1)
				(type default)
			)
			(layer "F.Fab")
		)
		(pad "1" smd rect
			(at 0 0 180)
			(size 0.508 0.508)
			(layers "F.Cu" "F.Mask" "F.Paste")
			(net "VR_PVCCIO_CPU1_OCSET")
		)
		(pad "2" smd rect
			(at 0 0.889 180)
			(size 0.508 0.508)
			(layers "F.Cu" "F.Mask" "F.Paste")
			(net "GND")
		)
		(zone
			(layer "F.Cu")
			(hatch none 0.5)
			(connect_pads
				(clearance 0)
			)
			(min_thickness 0.25)
			(keepout
				(tracks not_allowed)
				(vias allowed)
				(pads allowed)
				(copperpour not_allowed)
				(footprints allowed)
			)
			(placement
				(enabled no)
				(sheetname "")
			)
			(fill
				(thermal_gap 0.5)
				(thermal_bridge_width 0.5)
				(island_removal_mode 0)
			)
			(polygon
				(pts
					(xy 182.626 -56.7944) (xy 182.118 -56.7944) (xy 182.118 -56.4134) (xy 182.626 -56.4134)
				)
			)
		)
		(zone
			(layer "F.Cu")
			(hatch none 0.5)
			(connect_pads
				(clearance 0)
			)
			(min_thickness 0.25)
			(keepout
				(tracks allowed)
				(vias not_allowed)
				(pads allowed)
				(copperpour not_allowed)
				(footprints allowed)
			)
			(placement
				(enabled no)
				(sheetname "")
			)
			(fill
				(thermal_gap 0.5)
				(thermal_bridge_width 0.5)
				(island_removal_mode 0)
			)
			(polygon
				(pts
					(xy 182.626 -56.4134) (xy 182.118 -56.4134) (xy 182.118 -56.7944) (xy 182.626 -56.7944)
				)
			)
		)
	)
	(footprint ""
		(layer "F.Cu")
		(at 29.6164 -83.963002 -90)
		(property "Reference" "C1D12"
			(at 0 0 270)
			(layer "F.SilkS")
			(hide yes)
			(effects
				(font
					(size 1.27 1.27)
				)
			)
		)
		(property "Value" ""
			(at 0 0 270)
			(layer "F.Fab")
			(effects
				(font
					(size 1.27 1.27)
				)
			)
		)
		(duplicate_pad_numbers_are_jumpers no)
		(fp_rect
			(start 0.3048 -0.1016)
			(end -0.3048 0.9906)
			(stroke
				(width 0)
				(type default)
			)
			(fill no)
			(layer "F.CrtYd")
		)
		(fp_line
			(start -0.3048 0.9906)
			(end 0.3048 0.9906)
			(stroke
				(width 0.1)
				(type default)
			)
			(layer "F.Fab")
		)
		(fp_line
			(start 0.3048 0.9906)
			(end 0.3048 -0.1016)
			(stroke
				(width 0.1)
				(type default)
			)
			(layer "F.Fab")
		)
		(fp_line
			(start -0.3048 -0.1016)
			(end -0.3048 0.9906)
			(stroke
				(width 0.1)
				(type default)
			)
			(layer "F.Fab")
		)
		(fp_line
			(start 0.3048 -0.1016)
			(end -0.3048 -0.1016)
			(stroke
				(width 0.1)
				(type default)
			)
			(layer "F.Fab")
		)
		(pad "1" smd rect
			(at 0 0 270)
			(size 0.508 0.508)
			(layers "F.Cu" "F.Mask" "F.Paste")
			(net "VR_FET_SW_P12V_STBY_PVCCIN_CPU1")
		)
		(pad "2" smd rect
			(at 0 0.889 270)
			(size 0.508 0.508)
			(layers "F.Cu" "F.Mask" "F.Paste")
			(net "GND")
		)
		(zone
			(layer "F.Cu")
			(hatch none 0.5)
			(connect_pads
				(clearance 0)
			)
			(min_thickness 0.25)
			(keepout
				(tracks allowed)
				(vias not_allowed)
				(pads allowed)
				(copperpour not_allowed)
				(footprints allowed)
			)
			(placement
				(enabled no)
				(sheetname "")
			)
			(fill
				(thermal_gap 0.5)
				(thermal_bridge_width 0.5)
				(island_removal_mode 0)
			)
			(polygon
				(pts
					(xy 29.3624 -83.709002) (xy 29.3624 -84.217002) (xy 28.9814 -84.217002) (xy 28.9814 -83.709002)
				)
			)
		)
		(zone
			(layer "F.Cu")
			(hatch none 0.5)
			(connect_pads
				(clearance 0)
			)
			(min_thickness 0.25)
			(keepout
				(tracks not_allowed)
				(vias allowed)
				(pads allowed)
				(copperpour not_allowed)
				(footprints allowed)
			)
			(placement
				(enabled no)
				(sheetname "")
			)
			(fill
				(thermal_gap 0.5)
				(thermal_bridge_width 0.5)
				(island_removal_mode 0)
			)
			(polygon
				(pts
					(xy 29.3624 -83.709002) (xy 29.3624 -84.217002) (xy 28.9814 -84.217002) (xy 28.9814 -83.709002)
				)
			)
		)
	)
	(footprint ""
		(layer "F.Cu")
		(at 417.43122 -111.19612)
		(property "Reference" "R2N1"
			(at 0 0 0)
			(layer "F.SilkS")
			(hide yes)
			(effects
				(font
					(size 1.27 1.27)
				)
			)
		)
		(property "Value" ""
			(at 0 0 0)
			(layer "F.Fab")
			(effects
				(font
					(size 1.27 1.27)
				)
			)
		)
		(duplicate_pad_numbers_are_jumpers no)
		(fp_poly
			(pts
				(xy -0.2794 -0.1016) (xy 0.2794 -0.1016) (xy 0.2794 0.9906) (xy -0.2794 0.9906)
			)
			(stroke
				(width 0)
				(type default)
			)
			(fill no)
			(layer "F.CrtYd")
		)
		(fp_line
			(start -0.2794 -0.1016)
			(end -0.2794 0.9906)
			(stroke
				(width 0.1)
				(type default)
			)
			(layer "F.Fab")
		)
		(fp_line
			(start -0.2794 0.9906)
			(end 0.2794 0.9906)
			(stroke
				(width 0.1)
				(type default)
			)
			(layer "F.Fab")
		)
		(fp_line
			(start 0.2794 -0.1016)
			(end -0.2794 -0.1016)
			(stroke
				(width 0.1)
				(type default)
			)
			(layer "F.Fab")
		)
		(fp_line
			(start 0.2794 0.9906)
			(end 0.2794 -0.1016)
			(stroke
				(width 0.1)
				(type default)
			)
			(layer "F.Fab")
		)
		(pad "1" smd rect
			(at 0 0)
			(size 0.508 0.508)
			(layers "F.Cu" "F.Mask" "F.Paste")
			(net "FM_CPU_CATERR_DLY_LVT3_R_N")
		)
		(pad "2" smd rect
			(at 0 0.889)
			(size 0.508 0.508)
			(layers "F.Cu" "F.Mask" "F.Paste")
			(net "FM_CPU_CATERR_DLY_LVT3_N")
		)
		(zone
			(layer "F.Cu")
			(hatch none 0.5)
			(connect_pads
				(clearance 0)
			)
			(min_thickness 0.25)
			(keepout
				(tracks allowed)
				(vias not_allowed)
				(pads allowed)
				(copperpour not_allowed)
				(footprints allowed)
			)
			(placement
				(enabled no)
				(sheetname "")
			)
			(fill
				(thermal_gap 0.5)
				(thermal_bridge_width 0.5)
				(island_removal_mode 0)
			)
			(polygon
				(pts
					(xy 417.17722 -110.94212) (xy 417.68522 -110.94212) (xy 417.68522 -110.56112) (xy 417.17722 -110.56112)
				)
			)
		)
		(zone
			(layer "F.Cu")
			(hatch none 0.5)
			(connect_pads
				(clearance 0)
			)
			(min_thickness 0.25)
			(keepout
				(tracks not_allowed)
				(vias allowed)
				(pads allowed)
				(copperpour not_allowed)
				(footprints allowed)
			)
			(placement
				(enabled no)
				(sheetname "")
			)
			(fill
				(thermal_gap 0.5)
				(thermal_bridge_width 0.5)
				(island_removal_mode 0)
			)
			(polygon
				(pts
					(xy 417.17722 -110.56112) (xy 417.68522 -110.56112) (xy 417.68522 -110.94212) (xy 417.17722 -110.94212)
				)
			)
		)
	)
	(footprint ""
		(layer "F.Cu")
		(at 192.786 -23.396194)
		(property "Reference" "R4F3"
			(at 0 0 0)
			(layer "F.SilkS")
			(hide yes)
			(effects
				(font
					(size 1.27 1.27)
				)
			)
		)
		(property "Value" ""
			(at 0 0 0)
			(layer "F.Fab")
			(effects
				(font
					(size 1.27 1.27)
				)
			)
		)
		(duplicate_pad_numbers_are_jumpers no)
		(fp_poly
			(pts
				(xy -0.2794 -0.1016) (xy 0.2794 -0.1016) (xy 0.2794 0.9906) (xy -0.2794 0.9906)
			)
			(stroke
				(width 0)
				(type default)
			)
			(fill no)
			(layer "F.CrtYd")
		)
		(fp_line
			(start -0.2794 -0.1016)
			(end -0.2794 0.9906)
			(stroke
				(width 0.1)
				(type default)
			)
			(layer "F.Fab")
		)
		(fp_line
			(start -0.2794 0.9906)
			(end 0.2794 0.9906)
			(stroke
				(width 0.1)
				(type default)
			)
			(layer "F.Fab")
		)
		(fp_line
			(start 0.2794 -0.1016)
			(end -0.2794 -0.1016)
			(stroke
				(width 0.1)
				(type default)
			)
			(layer "F.Fab")
		)
		(fp_line
			(start 0.2794 0.9906)
			(end 0.2794 -0.1016)
			(stroke
				(width 0.1)
				(type default)
			)
			(layer "F.Fab")
		)
		(pad "1" smd rect
			(at 0 0)
			(size 0.508 0.508)
			(layers "F.Cu" "F.Mask" "F.Paste")
			(net "M_A_CPU_VREF")
		)
		(pad "2" smd rect
			(at 0 0.889)
			(size 0.508 0.508)
			(layers "F.Cu" "F.Mask" "F.Paste")
			(net "M_A_VREF")
		)
		(zone
			(layer "F.Cu")
			(hatch none 0.5)
			(connect_pads
				(clearance 0)
			)
			(min_thickness 0.25)
			(keepout
				(tracks allowed)
				(vias not_allowed)
				(pads allowed)
				(copperpour not_allowed)
				(footprints allowed)
			)
			(placement
				(enabled no)
				(sheetname "")
			)
			(fill
				(thermal_gap 0.5)
				(thermal_bridge_width 0.5)
				(island_removal_mode 0)
			)
			(polygon
				(pts
					(xy 192.532 -23.142194) (xy 193.04 -23.142194) (xy 193.04 -22.761194) (xy 192.532 -22.761194)
				)
			)
		)
		(zone
			(layer "F.Cu")
			(hatch none 0.5)
			(connect_pads
				(clearance 0)
			)
			(min_thickness 0.25)
			(keepout
				(tracks not_allowed)
				(vias allowed)
				(pads allowed)
				(copperpour not_allowed)
				(footprints allowed)
			)
			(placement
				(enabled no)
				(sheetname "")
			)
			(fill
				(thermal_gap 0.5)
				(thermal_bridge_width 0.5)
				(island_removal_mode 0)
			)
			(polygon
				(pts
					(xy 192.532 -22.761194) (xy 193.04 -22.761194) (xy 193.04 -23.142194) (xy 192.532 -23.142194)
				)
			)
		)
	)
	(footprint ""
		(layer "F.Cu")
		(at 398.879568 -34.279586 90)
		(property "Reference" "R8G6"
			(at 0 0 90)
			(layer "F.SilkS")
			(hide yes)
			(effects
				(font
					(size 1.27 1.27)
				)
			)
		)
		(property "Value" ""
			(at 0 0 90)
			(layer "F.Fab")
			(effects
				(font
					(size 1.27 1.27)
				)
			)
		)
		(duplicate_pad_numbers_are_jumpers no)
		(fp_poly
			(pts
				(xy -0.2794 -0.1016) (xy 0.2794 -0.1016) (xy 0.2794 0.9906) (xy -0.2794 0.9906)
			)
			(stroke
				(width 0)
				(type default)
			)
			(fill no)
			(layer "F.CrtYd")
		)
		(fp_line
			(start 0.2794 -0.1016)
			(end -0.2794 -0.1016)
			(stroke
				(width 0.1)
				(type default)
			)
			(layer "F.Fab")
		)
		(fp_line
			(start -0.2794 -0.1016)
			(end -0.2794 0.9906)
			(stroke
				(width 0.1)
				(type default)
			)
			(layer "F.Fab")
		)
		(fp_line
			(start 0.2794 0.9906)
			(end 0.2794 -0.1016)
			(stroke
				(width 0.1)
				(type default)
			)
			(layer "F.Fab")
		)
		(fp_line
			(start -0.2794 0.9906)
			(end 0.2794 0.9906)
			(stroke
				(width 0.1)
				(type default)
			)
			(layer "F.Fab")
		)
		(pad "1" smd rect
			(at 0 0 90)
			(size 0.508 0.508)
			(layers "F.Cu" "F.Mask" "F.Paste")
			(net "P3V3_STBY")
		)
		(pad "2" smd rect
			(at 0 0.889 90)
			(size 0.508 0.508)
			(layers "F.Cu" "F.Mask" "F.Paste")
			(net "SMB_OCP_LAN_STBY_LVC3_SDA_R")
		)
		(zone
			(layer "F.Cu")
			(hatch none 0.5)
			(connect_pads
				(clearance 0)
			)
			(min_thickness 0.25)
			(keepout
				(tracks allowed)
				(vias not_allowed)
				(pads allowed)
				(copperpour not_allowed)
				(footprints allowed)
			)
			(placement
				(enabled no)
				(sheetname "")
			)
			(fill
				(thermal_gap 0.5)
				(thermal_bridge_width 0.5)
				(island_removal_mode 0)
			)
			(polygon
				(pts
					(xy 399.133568 -34.025586) (xy 399.133568 -34.533586) (xy 399.514568 -34.533586) (xy 399.514568 -34.025586)
				)
			)
		)
		(zone
			(layer "F.Cu")
			(hatch none 0.5)
			(connect_pads
				(clearance 0)
			)
			(min_thickness 0.25)
			(keepout
				(tracks not_allowed)
				(vias allowed)
				(pads allowed)
				(copperpour not_allowed)
				(footprints allowed)
			)
			(placement
				(enabled no)
				(sheetname "")
			)
			(fill
				(thermal_gap 0.5)
				(thermal_bridge_width 0.5)
				(island_removal_mode 0)
			)
			(polygon
				(pts
					(xy 399.514568 -34.025586) (xy 399.514568 -34.533586) (xy 399.133568 -34.533586) (xy 399.133568 -34.025586)
				)
			)
		)
	)
	(footprint ""
		(layer "F.Cu")
		(at 30.554168 -128.8542 90)
		(property "Reference" "C1B9"
			(at 0 0 90)
			(layer "F.SilkS")
			(hide yes)
			(effects
				(font
					(size 1.27 1.27)
				)
			)
		)
		(property "Value" ""
			(at 0 0 90)
			(layer "F.Fab")
			(effects
				(font
					(size 1.27 1.27)
				)
			)
		)
		(duplicate_pad_numbers_are_jumpers no)
		(fp_poly
			(pts
				(xy 0.3048 -0.1016) (xy 0.3048 0.9906) (xy -0.3048 0.9906) (xy -0.3048 -0.1016)
			)
			(stroke
				(width 0)
				(type default)
			)
			(fill no)
			(layer "F.CrtYd")
		)
		(fp_line
			(start 0.3048 -0.1016)
			(end -0.3048 -0.1016)
			(stroke
				(width 0.1)
				(type default)
			)
			(layer "F.Fab")
		)
		(fp_line
			(start -0.3048 -0.1016)
			(end -0.3048 0.9906)
			(stroke
				(width 0.1)
				(type default)
			)
			(layer "F.Fab")
		)
		(fp_line
			(start 0.3048 0.9906)
			(end 0.3048 -0.1016)
			(stroke
				(width 0.1)
				(type default)
			)
			(layer "F.Fab")
		)
		(fp_line
			(start -0.3048 0.9906)
			(end 0.3048 0.9906)
			(stroke
				(width 0.1)
				(type default)
			)
			(layer "F.Fab")
		)
		(pad "1" smd rect
			(at 0 0 90)
			(size 0.508 0.508)
			(layers "F.Cu" "F.Mask" "F.Paste")
			(net "M_K_VREF")
		)
		(pad "2" smd rect
			(at 0 0.889 90)
			(size 0.508 0.508)
			(layers "F.Cu" "F.Mask" "F.Paste")
			(net "GND")
		)
		(zone
			(layer "F.Cu")
			(hatch none 0.5)
			(connect_pads
				(clearance 0)
			)
			(min_thickness 0.25)
			(keepout
				(tracks allowed)
				(vias not_allowed)
				(pads allowed)
				(copperpour not_allowed)
				(footprints allowed)
			)
			(placement
				(enabled no)
				(sheetname "")
			)
			(fill
				(thermal_gap 0.5)
				(thermal_bridge_width 0.5)
				(island_removal_mode 0)
			)
			(polygon
				(pts
					(xy 30.808168 -128.6002) (xy 30.808168 -129.1082) (xy 31.189168 -129.1082) (xy 31.189168 -128.6002)
				)
			)
		)
		(zone
			(layer "F.Cu")
			(hatch none 0.5)
			(connect_pads
				(clearance 0)
			)
			(min_thickness 0.25)
			(keepout
				(tracks not_allowed)
				(vias allowed)
				(pads allowed)
				(copperpour not_allowed)
				(footprints allowed)
			)
			(placement
				(enabled no)
				(sheetname "")
			)
			(fill
				(thermal_gap 0.5)
				(thermal_bridge_width 0.5)
				(island_removal_mode 0)
			)
			(polygon
				(pts
					(xy 31.189168 -128.6002) (xy 31.189168 -129.1082) (xy 30.808168 -129.1082) (xy 30.808168 -128.6002)
				)
			)
		)
	)
	(footprint ""
		(layer "F.Cu")
		(at 32.6263 -32.9438)
		(property "Reference" "R1F3"
			(at -0.90297 -2.159 270)
			(unlocked yes)
			(layer "F.SilkS")
			(effects
				(font
					(size 0.7874 0.5842)
					(thickness 0.1524)
				)
			)
		)
		(property "Value" ""
			(at 0 0 0)
			(layer "F.Fab")
			(effects
				(font
					(size 1.27 1.27)
				)
			)
		)
		(duplicate_pad_numbers_are_jumpers no)
		(fp_line
			(start -0.9017 1.951736)
			(end -0.9017 0.823468)
			(stroke
				(width 0.1524)
				(type default)
			)
			(layer "F.SilkS")
		)
		(fp_line
			(start 0.9017 1.952498)
			(end 0.9017 0.853948)
			(stroke
				(width 0.1524)
				(type default)
			)
			(layer "F.SilkS")
		)
		(fp_rect
			(start 0.9017 -0.3048)
			(end -0.9017 3.0988)
			(stroke
				(width 0)
				(type default)
			)
			(fill no)
			(layer "F.CrtYd")
		)
		(fp_line
			(start -0.9017 -0.3048)
			(end -0.9017 3.0988)
			(stroke
				(width 0.1)
				(type default)
			)
			(layer "F.Fab")
		)
		(fp_line
			(start -0.9017 3.0988)
			(end 0.9017 3.0988)
			(stroke
				(width 0.1)
				(type default)
			)
			(layer "F.Fab")
		)
		(fp_line
			(start 0.9017 -0.3048)
			(end -0.9017 -0.3048)
			(stroke
				(width 0.1)
				(type default)
			)
			(layer "F.Fab")
		)
		(fp_line
			(start 0.9017 3.0988)
			(end 0.9017 -0.3048)
			(stroke
				(width 0.1)
				(type default)
			)
			(layer "F.Fab")
		)
		(pad "1" smd rect
			(at 0 0)
			(size 1.524 1.016)
			(layers "F.Cu" "F.Mask" "F.Paste")
			(net "P12V_STBY")
		)
		(pad "2" smd rect
			(at 0 2.794)
			(size 1.524 1.016)
			(layers "F.Cu" "F.Mask" "F.Paste")
			(net "P12V_NVDIMM_GHJ")
		)
		(zone
			(layer "F.Cu")
			(hatch none 0.5)
			(connect_pads
				(clearance 0)
			)
			(min_thickness 0.25)
			(keepout
				(tracks allowed)
				(vias not_allowed)
				(pads allowed)
				(copperpour not_allowed)
				(footprints allowed)
			)
			(placement
				(enabled no)
				(sheetname "")
			)
			(fill
				(thermal_gap 0.5)
				(thermal_bridge_width 0.5)
				(island_removal_mode 0)
			)
			(polygon
				(pts
					(xy 33.3883 -32.4358) (xy 31.8643 -32.4358) (xy 31.8643 -30.6578) (xy 33.3883 -30.6578)
				)
			)
		)
	)
	(footprint ""
		(layer "F.Cu")
		(at 435.5338 -15.748)
		(property "Reference" "R6W46"
			(at -0.8382 -0.67818 0)
			(unlocked yes)
			(layer "F.SilkS")
			(effects
				(font
					(size 0.4064 0.254)
					(thickness 0.1524)
				)
				(justify left)
			)
		)
		(property "Value" ""
			(at 0 0 0)
			(layer "F.Fab")
			(effects
				(font
					(size 1.27 1.27)
				)
			)
		)
		(duplicate_pad_numbers_are_jumpers no)
		(fp_poly
			(pts
				(xy -0.2794 -0.1016) (xy 0.2794 -0.1016) (xy 0.2794 0.9906) (xy -0.2794 0.9906)
			)
			(stroke
				(width 0)
				(type default)
			)
			(fill no)
			(layer "F.CrtYd")
		)
		(fp_line
			(start -0.2794 -0.1016)
			(end -0.2794 0.9906)
			(stroke
				(width 0.1)
				(type default)
			)
			(layer "F.Fab")
		)
		(fp_line
			(start -0.2794 0.9906)
			(end 0.2794 0.9906)
			(stroke
				(width 0.1)
				(type default)
			)
			(layer "F.Fab")
		)
		(fp_line
			(start 0.2794 -0.1016)
			(end -0.2794 -0.1016)
			(stroke
				(width 0.1)
				(type default)
			)
			(layer "F.Fab")
		)
		(fp_line
			(start 0.2794 0.9906)
			(end 0.2794 -0.1016)
			(stroke
				(width 0.1)
				(type default)
			)
			(layer "F.Fab")
		)
		(pad "1" smd rect
			(at 0 0)
			(size 0.508 0.508)
			(layers "F.Cu" "F.Mask" "F.Paste")
			(net "PCA9554_A1")
		)
		(pad "2" smd rect
			(at 0 0.889)
			(size 0.508 0.508)
			(layers "F.Cu" "F.Mask" "F.Paste")
			(net "GND")
		)
		(zone
			(layer "F.Cu")
			(hatch none 0.5)
			(connect_pads
				(clearance 0)
			)
			(min_thickness 0.25)
			(keepout
				(tracks allowed)
				(vias not_allowed)
				(pads allowed)
				(copperpour not_allowed)
				(footprints allowed)
			)
			(placement
				(enabled no)
				(sheetname "")
			)
			(fill
				(thermal_gap 0.5)
				(thermal_bridge_width 0.5)
				(island_removal_mode 0)
			)
			(polygon
				(pts
					(xy 435.2798 -15.494) (xy 435.7878 -15.494) (xy 435.7878 -15.113) (xy 435.2798 -15.113)
				)
			)
		)
		(zone
			(layer "F.Cu")
			(hatch none 0.5)
			(connect_pads
				(clearance 0)
			)
			(min_thickness 0.25)
			(keepout
				(tracks not_allowed)
				(vias allowed)
				(pads allowed)
				(copperpour not_allowed)
				(footprints allowed)
			)
			(placement
				(enabled no)
				(sheetname "")
			)
			(fill
				(thermal_gap 0.5)
				(thermal_bridge_width 0.5)
				(island_removal_mode 0)
			)
			(polygon
				(pts
					(xy 435.2798 -15.113) (xy 435.7878 -15.113) (xy 435.7878 -15.494) (xy 435.2798 -15.494)
				)
			)
		)
	)
	(footprint ""
		(layer "F.Cu")
		(at 499.872 -149.86)
		(property "Reference" "DS9A2"
			(at -1.31953 -0.28448 90)
			(unlocked yes)
			(layer "F.SilkS")
			(effects
				(font
					(size 0.7874 0.5842)
					(thickness 0.1524)
				)
			)
		)
		(property "Value" ""
			(at 0 0 0)
			(layer "F.Fab")
			(effects
				(font
					(size 1.27 1.27)
				)
			)
		)
		(duplicate_pad_numbers_are_jumpers no)
		(fp_line
			(start -1.842262 1.00711)
			(end -1.36144 0.174244)
			(stroke
				(width 0.1524)
				(type default)
			)
			(layer "F.SilkS")
		)
		(fp_line
			(start -1.36144 -0.949198)
			(end -1.36144 0.174244)
			(stroke
				(width 0.1524)
				(type default)
			)
			(layer "F.SilkS")
		)
		(fp_line
			(start -1.36144 0.174244)
			(end -0.880618 1.00711)
			(stroke
				(width 0.1524)
				(type default)
			)
			(layer "F.SilkS")
		)
		(fp_line
			(start -1.36144 1.00711)
			(end -1.842262 1.00711)
			(stroke
				(width 0.1524)
				(type default)
			)
			(layer "F.SilkS")
		)
		(fp_line
			(start -1.36144 1.918716)
			(end -1.36144 1.00711)
			(stroke
				(width 0.1524)
				(type default)
			)
			(layer "F.SilkS")
		)
		(fp_line
			(start -0.880618 0.174244)
			(end -1.842262 0.174244)
			(stroke
				(width 0.1524)
				(type default)
			)
			(layer "F.SilkS")
		)
		(fp_line
			(start -0.880618 1.00711)
			(end -1.36144 1.00711)
			(stroke
				(width 0.1524)
				(type default)
			)
			(layer "F.SilkS")
		)
		(fp_poly
			(pts
				(xy -0.5715 2.2098) (xy -0.5715 0.2032) (xy 0.5715 0.2032) (xy 0.5715 0.6985)
				(arc
					(start 0.726948 0.6985)
					(mid 1.29058 0.932279)
					(end 1.524 1.49606)
				)
				(arc
					(start 1.524 2.05994)
					(mid 1.2904 2.6239)
					(end 0.72644 2.8575)
				)
				(xy 0.5715 2.8575) (xy 0.5715 3.3528) (xy -0.5715 3.3528)
			)
			(stroke
				(width 0)
				(type default)
			)
			(fill no)
			(layer "F.CrtYd")
		)
		(fp_line
			(start -1.848612 0.973328)
			(end -1.36779 0.140462)
			(stroke
				(width 0.1)
				(type default)
			)
			(layer "F.Fab")
		)
		(fp_line
			(start -1.36779 0.140462)
			(end -1.36779 -0.98298)
			(stroke
				(width 0.1)
				(type default)
			)
			(layer "F.Fab")
		)
		(fp_line
			(start -1.36779 0.140462)
			(end -0.886968 0.973328)
			(stroke
				(width 0.1)
				(type default)
			)
			(layer "F.Fab")
		)
		(fp_line
			(start -1.36779 0.973328)
			(end -1.36779 1.884934)
			(stroke
				(width 0.1)
				(type default)
			)
			(layer "F.Fab")
		)
		(fp_line
			(start -0.886968 0.140462)
			(end -1.848612 0.140462)
			(stroke
				(width 0.1)
				(type default)
			)
			(layer "F.Fab")
		)
		(fp_line
			(start -0.886968 0.973328)
			(end -1.848612 0.973328)
			(stroke
				(width 0.1)
				(type default)
			)
			(layer "F.Fab")
		)
		(fp_line
			(start -0.5715 0.2032)
			(end 0.5715 0.2032)
			(stroke
				(width 0.1)
				(type default)
			)
			(layer "F.Fab")
		)
		(fp_line
			(start -0.5715 0.7112)
			(end 0.5715 0.7112)
			(stroke
				(width 0.1)
				(type default)
			)
			(layer "F.Fab")
		)
		(fp_line
			(start -0.5715 2.8448)
			(end 0.5715 2.8448)
			(stroke
				(width 0.1)
				(type default)
			)
			(layer "F.Fab")
		)
		(fp_line
			(start -0.5715 3.3528)
			(end -0.5715 0.2032)
			(stroke
				(width 0.1)
				(type default)
			)
			(layer "F.Fab")
		)
		(fp_line
			(start 0.5715 0.2032)
			(end 0.5715 3.3528)
			(stroke
				(width 0.1)
				(type default)
			)
			(layer "F.Fab")
		)
		(fp_line
			(start 0.5715 2.8575)
			(end 0.72644 2.8575)
			(stroke
				(width 0.1)
				(type default)
			)
			(layer "F.Fab")
		)
		(fp_line
			(start 0.5715 3.3528)
			(end -0.5715 3.3528)
			(stroke
				(width 0.1)
				(type default)
			)
			(layer "F.Fab")
		)
		(fp_line
			(start 0.72644 0.6985)
			(end 0.5715 0.6985)
			(stroke
				(width 0.1)
				(type default)
			)
			(layer "F.Fab")
		)
		(fp_line
			(start 1.524 2.05994)
			(end 1.524 1.49606)
			(stroke
				(width 0.1)
				(type default)
			)
			(layer "F.Fab")
		)
		(fp_arc
			(start 0.72644 0.6985)
			(mid 1.290388 0.932112)
			(end 1.524 1.49606)
			(stroke
				(width 0.1)
				(type default)
			)
			(layer "F.Fab")
		)
		(fp_arc
			(start 1.524 2.05994)
			(mid 1.290388 2.623888)
			(end 0.72644 2.8575)
			(stroke
				(width 0.1)
				(type default)
			)
			(layer "F.Fab")
		)
		(pad "1" smd rect
			(at 0 0)
			(size 1.524 1.524)
			(layers "F.Cu" "F.Mask" "F.Paste")
			(net "FP_LED_HDD_ACTIVITY_AND_N")
		)
		(pad "2" smd rect
			(at 0 3.556)
			(size 1.524 1.524)
			(layers "F.Cu" "F.Mask" "F.Paste")
			(net "FP_LED_HDD_ACTIVITY_AND_R_N")
		)
		(pad "3" smd rect
			(at -0.762 1.778)
			(size 0.889 0.889)
			(layers "F.Cu" "F.Mask" "F.Paste")
			(net "Net_6478")
		)
		(zone
			(layer "F.Cu")
			(hatch none 0.5)
			(connect_pads
				(clearance 0)
			)
			(min_thickness 0.25)
			(keepout
				(tracks allowed)
				(vias not_allowed)
				(pads allowed)
				(copperpour not_allowed)
				(footprints allowed)
			)
			(placement
				(enabled no)
				(sheetname "")
			)
			(fill
				(thermal_gap 0.5)
				(thermal_bridge_width 0.5)
				(island_removal_mode 0)
			)
			(polygon
				(pts
					(xy 500.4435 -149.0472) (xy 500.4435 -147.1168) (xy 499.3005 -147.1168) (xy 499.3005 -149.0472)
				)
			)
		)
	)
	(footprint ""
		(layer "F.Cu")
		(at 413.639 -21.971 180)
		(property "Reference" "R25W116"
			(at -0.8382 -0.67818 180)
			(unlocked yes)
			(layer "F.SilkS")
			(effects
				(font
					(size 0.4064 0.254)
					(thickness 0.1524)
				)
				(justify left)
			)
		)
		(property "Value" ""
			(at 0 0 180)
			(layer "F.Fab")
			(effects
				(font
					(size 1.27 1.27)
				)
			)
		)
		(duplicate_pad_numbers_are_jumpers no)
		(fp_poly
			(pts
				(xy -0.2794 -0.1016) (xy 0.2794 -0.1016) (xy 0.2794 0.9906) (xy -0.2794 0.9906)
			)
			(stroke
				(width 0)
				(type default)
			)
			(fill no)
			(layer "F.CrtYd")
		)
		(fp_line
			(start 0.2794 0.9906)
			(end 0.2794 -0.1016)
			(stroke
				(width 0.1)
				(type default)
			)
			(layer "F.Fab")
		)
		(fp_line
			(start 0.2794 -0.1016)
			(end -0.2794 -0.1016)
			(stroke
				(width 0.1)
				(type default)
			)
			(layer "F.Fab")
		)
		(fp_line
			(start -0.2794 0.9906)
			(end 0.2794 0.9906)
			(stroke
				(width 0.1)
				(type default)
			)
			(layer "F.Fab")
		)
		(fp_line
			(start -0.2794 -0.1016)
			(end -0.2794 0.9906)
			(stroke
				(width 0.1)
				(type default)
			)
			(layer "F.Fab")
		)
		(pad "1" smd rect
			(at 0 0 180)
			(size 0.508 0.508)
			(layers "F.Cu" "F.Mask" "F.Paste")
			(net "GND")
		)
		(pad "2" smd rect
			(at 0 0.889 180)
			(size 0.508 0.508)
			(layers "F.Cu" "F.Mask" "F.Paste")
			(net "UART_BMC_TXD5")
		)
		(zone
			(layer "F.Cu")
			(hatch none 0.5)
			(connect_pads
				(clearance 0)
			)
			(min_thickness 0.25)
			(keepout
				(tracks not_allowed)
				(vias allowed)
				(pads allowed)
				(copperpour not_allowed)
				(footprints allowed)
			)
			(placement
				(enabled no)
				(sheetname "")
			)
			(fill
				(thermal_gap 0.5)
				(thermal_bridge_width 0.5)
				(island_removal_mode 0)
			)
			(polygon
				(pts
					(xy 413.893 -22.606) (xy 413.385 -22.606) (xy 413.385 -22.225) (xy 413.893 -22.225)
				)
			)
		)
		(zone
			(layer "F.Cu")
			(hatch none 0.5)
			(connect_pads
				(clearance 0)
			)
			(min_thickness 0.25)
			(keepout
				(tracks allowed)
				(vias not_allowed)
				(pads allowed)
				(copperpour not_allowed)
				(footprints allowed)
			)
			(placement
				(enabled no)
				(sheetname "")
			)
			(fill
				(thermal_gap 0.5)
				(thermal_bridge_width 0.5)
				(island_removal_mode 0)
			)
			(polygon
				(pts
					(xy 413.893 -22.225) (xy 413.385 -22.225) (xy 413.385 -22.606) (xy 413.893 -22.606)
				)
			)
		)
	)
	(footprint ""
		(layer "F.Cu")
		(at 347.462094 -153.218642 -90)
		(property "Reference" "EU7A1"
			(at 3.410712 2.733294 0)
			(unlocked yes)
			(layer "F.SilkS")
			(effects
				(font
					(size 0.7874 0.5842)
					(thickness 0.1524)
				)
			)
		)
		(property "Value" ""
			(at 0 0 270)
			(layer "F.Fab")
			(effects
				(font
					(size 1.27 1.27)
				)
			)
		)
		(duplicate_pad_numbers_are_jumpers no)
		(fp_line
			(start -3.0099 3.429)
			(end -3.0099 -3.5052)
			(stroke
				(width 0.1524)
				(type default)
			)
			(layer "F.SilkS")
		)
		(fp_line
			(start 2.9718 3.429)
			(end -3.0099 3.429)
			(stroke
				(width 0.1524)
				(type default)
			)
			(layer "F.SilkS")
		)
		(fp_line
			(start -3.0099 -3.5052)
			(end 2.9718 -3.5052)
			(stroke
				(width 0.1524)
				(type default)
			)
			(layer "F.SilkS")
		)
		(fp_line
			(start 2.9718 -3.5052)
			(end 2.9718 3.429)
			(stroke
				(width 0.1524)
				(type default)
			)
			(layer "F.SilkS")
		)
		(fp_circle
			(center -3.057398 -2.678684)
			(end -3.057398 -2.805684)
			(stroke
				(width 0.254)
				(type default)
			)
			(fill no)
			(layer "F.SilkS")
		)
		(fp_poly
			(pts
				(xy -2.9972 -3.4925) (xy -2.9972 -2.6924) (xy -2.1971 -3.4925)
			)
			(stroke
				(width 0)
				(type default)
			)
			(fill yes)
			(layer "F.SilkS")
		)
		(fp_poly
			(pts
				(xy -2.549906 -3.050032) (xy -2.549906 3.050032) (xy 2.549906 3.050032) (xy 2.549906 -3.050032)
			)
			(stroke
				(width 0)
				(type default)
			)
			(fill no)
			(layer "F.CrtYd")
		)
		(fp_line
			(start -2.549906 3.050032)
			(end -2.549906 -3.050032)
			(stroke
				(width 0.1)
				(type default)
			)
			(layer "F.Fab")
		)
		(fp_line
			(start 2.549906 3.050032)
			(end -2.549906 3.050032)
			(stroke
				(width 0.1)
				(type default)
			)
			(layer "F.Fab")
		)
		(fp_line
			(start -2.549906 -3.050032)
			(end 2.549906 -3.050032)
			(stroke
				(width 0.1)
				(type default)
			)
			(layer "F.Fab")
		)
		(fp_line
			(start 2.549906 -3.050032)
			(end 2.549906 3.050032)
			(stroke
				(width 0.1)
				(type default)
			)
			(layer "F.Fab")
		)
		(fp_circle
			(center -3.057398 -2.678684)
			(end -3.057398 -2.805684)
			(stroke
				(width 0.254)
				(type default)
			)
			(fill no)
			(layer "F.Fab")
		)
		(pad "1" smd rect
			(at -2.39522 -2.279904 270)
			(size 0.7112 0.254)
			(layers "F.Cu" "F.Mask" "F.Paste")
			(net "PVDDQ_DEF")
		)
		(pad "2" smd rect
			(at -2.39522 -1.83007 270)
			(size 0.7112 0.254)
			(layers "F.Cu" "F.Mask" "F.Paste")
			(net "GND")
		)
		(pad "3" smd rect
			(at -2.39522 -1.379982 270)
			(size 0.7112 0.254)
			(layers "F.Cu" "F.Mask" "F.Paste")
			(net "VR_PVDDQ_DEF_PH1_VCIN")
		)
		(pad "4" smd rect
			(at -2.39522 -0.929894 270)
			(size 0.7112 0.254)
			(layers "F.Cu" "F.Mask" "F.Paste")
			(net "P5V_STBY")
		)
		(pad "5" smd rect
			(at -2.39522 -0.48006 270)
			(size 0.7112 0.254)
			(layers "F.Cu" "F.Mask" "F.Paste")
			(net "GND")
		)
		(pad "6" smd rect
			(at -2.39522 -0.029972 270)
			(size 0.7112 0.254)
			(layers "F.Cu" "F.Mask" "F.Paste")
			(net "TP_PVDDQ_DEF_PH1_GL_0")
		)
		(pad "7" smd custom
			(at 0.016764 1.145032 270)
			(size 0.53975 0.53975)
			(layers "F.Cu" "F.Mask" "F.Paste")
			(net "GND")
			(options
				(clearance outline)
				(anchor circle)
			)
			(primitives
				(gr_poly
					(pts
						(xy -2.7051 1.0795) (xy -2.7051 -0.3683) (xy -0.9271 -0.3683) (xy -0.9271 -1.0795) (xy 2.7051 -1.0795)
						(xy 2.7051 1.0795)
					)
					(width 0)
					(fill yes)
				)
			)
		)
		(pad "10" smd rect
			(at -0.008382 2.874772 270)
			(size 4.3434 0.6096)
			(layers "F.Cu" "F.Mask" "F.Paste")
			(net "VR_PVDDQ_DEF_PH1_SW")
		)
		(pad "25" smd rect
			(at 1.548384 -1.283208 270)
			(size 2.3368 2.0066)
			(layers "F.Cu" "F.Mask" "F.Paste")
			(net "VR_FET_SW_P12V_STBY_PVDDQ_DEF")
		)
		(pad "30" smd rect
			(at 2.050034 -2.895092 270)
			(size 0.254 0.7112)
			(layers "F.Cu" "F.Mask" "F.Paste")
			(net "VR_FET_SW_P12V_STBY_PVDDQ_DEF")
		)
		(pad "31" smd rect
			(at 1.599946 -2.895092 270)
			(size 0.254 0.7112)
			(layers "F.Cu" "F.Mask" "F.Paste")
			(net "Net_370")
		)
		(pad "32" smd rect
			(at 1.150112 -2.895092 270)
			(size 0.254 0.7112)
			(layers "F.Cu" "F.Mask" "F.Paste")
			(net "VR_PVDDQ_DEF_PH1_PHASE")
		)
		(pad "33" smd rect
			(at 0.700024 -2.895092 270)
			(size 0.254 0.7112)
			(layers "F.Cu" "F.Mask" "F.Paste")
			(net "VR_PVDDQ_DEF_PH1_BOOT_R")
		)
		(pad "34" smd rect
			(at 0.249936 -2.895092 270)
			(size 0.254 0.7112)
			(layers "F.Cu" "F.Mask" "F.Paste")
			(net "VR_PVDDQ_DEF_PWM1")
		)
		(pad "35" smd rect
			(at -0.199898 -2.895092 270)
			(size 0.254 0.7112)
			(layers "F.Cu" "F.Mask" "F.Paste")
			(net "P5V_STBY")
		)
		(pad "36" smd rect
			(at -0.649986 -2.895092 270)
			(size 0.254 0.7112)
			(layers "F.Cu" "F.Mask" "F.Paste")
			(net "A_TSENSE_PVDDQ_DEF")
		)
		(pad "37" smd rect
			(at -1.100074 -2.895092 270)
			(size 0.254 0.7112)
			(layers "F.Cu" "F.Mask" "F.Paste")
			(net "VR_PVDDQ_DEF_PH1_OCSET")
		)
		(pad "38" smd rect
			(at -1.549908 -2.895092 270)
			(size 0.254 0.7112)
			(layers "F.Cu" "F.Mask" "F.Paste")
			(net "ISENSE_PVDDQ_DEF_PH1_IMON")
		)
		(pad "39" smd rect
			(at -1.999996 -2.895092 270)
			(size 0.254 0.7112)
			(layers "F.Cu" "F.Mask" "F.Paste")
			(net "VR_PVDDQ_DEF_AIREF1")
		)
		(pad "40" smd rect
			(at -0.871728 -1.283208 270)
			(size 1.8034 2.0066)
			(layers "F.Cu" "F.Mask" "F.Paste")
			(net "GND")
		)
		(pad "41" smd rect
			(at -1.533906 0.247904 270)
			(size 0.508 0.3556)
			(layers "F.Cu" "F.Mask" "F.Paste")
			(net "TP_PVDDQ_DEF_PH1_GL_1")
		)
	)
	(footprint ""
		(layer "F.Cu")
		(at 490.2835 -145.527268 -90)
		(property "Reference" "C1T56"
			(at 0 0 270)
			(layer "F.SilkS")
			(hide yes)
			(effects
				(font
					(size 1.27 1.27)
				)
			)
		)
		(property "Value" ""
			(at 0 0 270)
			(layer "F.Fab")
			(effects
				(font
					(size 1.27 1.27)
				)
			)
		)
		(duplicate_pad_numbers_are_jumpers no)
		(fp_poly
			(pts
				(xy 0.3048 -0.1016) (xy 0.3048 0.9906) (xy -0.3048 0.9906) (xy -0.3048 -0.1016)
			)
			(stroke
				(width 0)
				(type default)
			)
			(fill no)
			(layer "F.CrtYd")
		)
		(fp_line
			(start -0.3048 0.9906)
			(end 0.3048 0.9906)
			(stroke
				(width 0.1)
				(type default)
			)
			(layer "F.Fab")
		)
		(fp_line
			(start 0.3048 0.9906)
			(end 0.3048 -0.1016)
			(stroke
				(width 0.1)
				(type default)
			)
			(layer "F.Fab")
		)
		(fp_line
			(start -0.3048 -0.1016)
			(end -0.3048 0.9906)
			(stroke
				(width 0.1)
				(type default)
			)
			(layer "F.Fab")
		)
		(fp_line
			(start 0.3048 -0.1016)
			(end -0.3048 -0.1016)
			(stroke
				(width 0.1)
				(type default)
			)
			(layer "F.Fab")
		)
		(pad "1" smd rect
			(at 0 0 270)
			(size 0.508 0.508)
			(layers "F.Cu" "F.Mask" "F.Paste")
			(net "P3V3_STBY")
		)
		(pad "2" smd rect
			(at 0 0.889 270)
			(size 0.508 0.508)
			(layers "F.Cu" "F.Mask" "F.Paste")
			(net "GND")
		)
		(zone
			(layer "F.Cu")
			(hatch none 0.5)
			(connect_pads
				(clearance 0)
			)
			(min_thickness 0.25)
			(keepout
				(tracks not_allowed)
				(vias allowed)
				(pads allowed)
				(copperpour not_allowed)
				(footprints allowed)
			)
			(placement
				(enabled no)
				(sheetname "")
			)
			(fill
				(thermal_gap 0.5)
				(thermal_bridge_width 0.5)
				(island_removal_mode 0)
			)
			(polygon
				(pts
					(xy 489.6485 -145.781268) (xy 489.6485 -145.273268) (xy 490.0295 -145.273268) (xy 490.0295 -145.781268)
				)
			)
		)
		(zone
			(layer "F.Cu")
			(hatch none 0.5)
			(connect_pads
				(clearance 0)
			)
			(min_thickness 0.25)
			(keepout
				(tracks allowed)
				(vias not_allowed)
				(pads allowed)
				(copperpour not_allowed)
				(footprints allowed)
			)
			(placement
				(enabled no)
				(sheetname "")
			)
			(fill
				(thermal_gap 0.5)
				(thermal_bridge_width 0.5)
				(island_removal_mode 0)
			)
			(polygon
				(pts
					(xy 490.0295 -145.781268) (xy 490.0295 -145.273268) (xy 489.6485 -145.273268) (xy 489.6485 -145.781268)
				)
			)
		)
	)
	(footprint ""
		(layer "F.Cu")
		(at 275.463 -69.977)
		(property "Reference" "R5D4"
			(at 0 0 0)
			(layer "F.SilkS")
			(hide yes)
			(effects
				(font
					(size 1.27 1.27)
				)
			)
		)
		(property "Value" ""
			(at 0 0 0)
			(layer "F.Fab")
			(effects
				(font
					(size 1.27 1.27)
				)
			)
		)
		(duplicate_pad_numbers_are_jumpers no)
		(fp_poly
			(pts
				(xy -0.2794 -0.1016) (xy 0.2794 -0.1016) (xy 0.2794 0.9906) (xy -0.2794 0.9906)
			)
			(stroke
				(width 0)
				(type default)
			)
			(fill no)
			(layer "F.CrtYd")
		)
		(fp_line
			(start -0.2794 -0.1016)
			(end -0.2794 0.9906)
			(stroke
				(width 0.1)
				(type default)
			)
			(layer "F.Fab")
		)
		(fp_line
			(start -0.2794 0.9906)
			(end 0.2794 0.9906)
			(stroke
				(width 0.1)
				(type default)
			)
			(layer "F.Fab")
		)
		(fp_line
			(start 0.2794 -0.1016)
			(end -0.2794 -0.1016)
			(stroke
				(width 0.1)
				(type default)
			)
			(layer "F.Fab")
		)
		(fp_line
			(start 0.2794 0.9906)
			(end 0.2794 -0.1016)
			(stroke
				(width 0.1)
				(type default)
			)
			(layer "F.Fab")
		)
		(pad "1" smd rect
			(at 0 0)
			(size 0.508 0.508)
			(layers "F.Cu" "F.Mask" "F.Paste")
			(net "PVCCIO_CPU0")
		)
		(pad "2" smd rect
			(at 0 0.889)
			(size 0.508 0.508)
			(layers "F.Cu" "F.Mask" "F.Paste")
			(net "PU_CPU0_TXT_AGENT")
		)
		(zone
			(layer "F.Cu")
			(hatch none 0.5)
			(connect_pads
				(clearance 0)
			)
			(min_thickness 0.25)
			(keepout
				(tracks allowed)
				(vias not_allowed)
				(pads allowed)
				(copperpour not_allowed)
				(footprints allowed)
			)
			(placement
				(enabled no)
				(sheetname "")
			)
			(fill
				(thermal_gap 0.5)
				(thermal_bridge_width 0.5)
				(island_removal_mode 0)
			)
			(polygon
				(pts
					(xy 275.209 -69.723) (xy 275.717 -69.723) (xy 275.717 -69.342) (xy 275.209 -69.342)
				)
			)
		)
		(zone
			(layer "F.Cu")
			(hatch none 0.5)
			(connect_pads
				(clearance 0)
			)
			(min_thickness 0.25)
			(keepout
				(tracks not_allowed)
				(vias allowed)
				(pads allowed)
				(copperpour not_allowed)
				(footprints allowed)
			)
			(placement
				(enabled no)
				(sheetname "")
			)
			(fill
				(thermal_gap 0.5)
				(thermal_bridge_width 0.5)
				(island_removal_mode 0)
			)
			(polygon
				(pts
					(xy 275.209 -69.342) (xy 275.717 -69.342) (xy 275.717 -69.723) (xy 275.209 -69.723)
				)
			)
		)
	)
	(footprint ""
		(layer "F.Cu")
		(at 399.372074 -84.309204 -90)
		(property "Reference" "Q8D2"
			(at 1.42748 3.45567 90)
			(unlocked yes)
			(layer "F.SilkS")
			(effects
				(font
					(size 0.7874 0.5842)
					(thickness 0.1524)
				)
				(justify left)
			)
		)
		(property "Value" ""
			(at 0 0 270)
			(layer "F.Fab")
			(effects
				(font
					(size 1.27 1.27)
				)
			)
		)
		(duplicate_pad_numbers_are_jumpers no)
		(fp_line
			(start 0.9525 2.4765)
			(end 1.778 2.4765)
			(stroke
				(width 0.1524)
				(type default)
			)
			(layer "F.SilkS")
		)
		(fp_line
			(start 1.778 2.4765)
			(end 1.778 1.5875)
			(stroke
				(width 0.1524)
				(type default)
			)
			(layer "F.SilkS")
		)
		(fp_line
			(start 0.381 0.635)
			(end 0.381 1.27)
			(stroke
				(width 0.1524)
				(type default)
			)
			(layer "F.SilkS")
		)
		(fp_line
			(start 0.9525 -0.5715)
			(end 1.778 -0.5715)
			(stroke
				(width 0.1524)
				(type default)
			)
			(layer "F.SilkS")
		)
		(fp_line
			(start 1.778 -0.5715)
			(end 1.778 0.3175)
			(stroke
				(width 0.1524)
				(type default)
			)
			(layer "F.SilkS")
		)
		(fp_circle
			(center -1.039368 -0.721614)
			(end -1.039368 -0.848614)
			(stroke
				(width 0.254)
				(type default)
			)
			(fill no)
			(layer "F.SilkS")
		)
		(fp_poly
			(pts
				(xy 1.778 2.4765) (xy 0.381 2.4765) (xy 0.381 -0.5715) (xy 1.778 -0.5715)
			)
			(stroke
				(width 0)
				(type default)
			)
			(fill no)
			(layer "F.CrtYd")
		)
		(fp_line
			(start 0.381 2.4765)
			(end 1.778 2.4765)
			(stroke
				(width 0.1)
				(type default)
			)
			(layer "F.Fab")
		)
		(fp_line
			(start 1.778 2.4765)
			(end 1.778 -0.5715)
			(stroke
				(width 0.1)
				(type default)
			)
			(layer "F.Fab")
		)
		(fp_line
			(start 0.381 -0.5715)
			(end 0.381 2.4765)
			(stroke
				(width 0.1)
				(type default)
			)
			(layer "F.Fab")
		)
		(fp_line
			(start 1.778 -0.5715)
			(end 0.381 -0.5715)
			(stroke
				(width 0.1)
				(type default)
			)
			(layer "F.Fab")
		)
		(fp_circle
			(center -0.9525 -0.9271)
			(end -0.9525 -1.0541)
			(stroke
				(width 0.254)
				(type default)
			)
			(fill no)
			(layer "F.Fab")
		)
		(pad "1" smd rect
			(at 0 0 270)
			(size 1.143 0.508)
			(layers "F.Cu" "F.Mask" "F.Paste")
			(net "RST_PLTRST_BUF_N")
		)
		(pad "2" smd rect
			(at 0 1.905 270)
			(size 1.143 0.508)
			(layers "F.Cu" "F.Mask" "F.Paste")
			(net "FM_PCH_BMC_THERMTRIP_EXI_STRAP_")
		)
		(pad "3" smd rect
			(at 2.159 0.9525 270)
			(size 1.143 0.508)
			(layers "F.Cu" "F.Mask" "F.Paste")
			(net "FM_PCH_BMC_THERMTRIP_N")
		)
	)
	(footprint ""
		(layer "F.Cu")
		(at 167.259 -71.5264)
		(property "Reference" "R4D42"
			(at 0 0 0)
			(layer "F.SilkS")
			(hide yes)
			(effects
				(font
					(size 1.27 1.27)
				)
			)
		)
		(property "Value" ""
			(at 0 0 0)
			(layer "F.Fab")
			(effects
				(font
					(size 1.27 1.27)
				)
			)
		)
		(duplicate_pad_numbers_are_jumpers no)
		(fp_poly
			(pts
				(xy -0.2794 -0.1016) (xy 0.2794 -0.1016) (xy 0.2794 0.9906) (xy -0.2794 0.9906)
			)
			(stroke
				(width 0)
				(type default)
			)
			(fill no)
			(layer "F.CrtYd")
		)
		(fp_line
			(start -0.2794 -0.1016)
			(end -0.2794 0.9906)
			(stroke
				(width 0.1)
				(type default)
			)
			(layer "F.Fab")
		)
		(fp_line
			(start -0.2794 0.9906)
			(end 0.2794 0.9906)
			(stroke
				(width 0.1)
				(type default)
			)
			(layer "F.Fab")
		)
		(fp_line
			(start 0.2794 -0.1016)
			(end -0.2794 -0.1016)
			(stroke
				(width 0.1)
				(type default)
			)
			(layer "F.Fab")
		)
		(fp_line
			(start 0.2794 0.9906)
			(end 0.2794 -0.1016)
			(stroke
				(width 0.1)
				(type default)
			)
			(layer "F.Fab")
		)
		(pad "1" smd rect
			(at 0 0)
			(size 0.508 0.508)
			(layers "F.Cu" "F.Mask" "F.Paste")
			(net "P3V3_STBY")
		)
		(pad "2" smd rect
			(at 0 0.889)
			(size 0.508 0.508)
			(layers "F.Cu" "F.Mask" "F.Paste")
			(net "PWRGD_PVCCIO_CPU1_R")
		)
		(zone
			(layer "F.Cu")
			(hatch none 0.5)
			(connect_pads
				(clearance 0)
			)
			(min_thickness 0.25)
			(keepout
				(tracks allowed)
				(vias not_allowed)
				(pads allowed)
				(copperpour not_allowed)
				(footprints allowed)
			)
			(placement
				(enabled no)
				(sheetname "")
			)
			(fill
				(thermal_gap 0.5)
				(thermal_bridge_width 0.5)
				(island_removal_mode 0)
			)
			(polygon
				(pts
					(xy 167.005 -71.2724) (xy 167.513 -71.2724) (xy 167.513 -70.8914) (xy 167.005 -70.8914)
				)
			)
		)
		(zone
			(layer "F.Cu")
			(hatch none 0.5)
			(connect_pads
				(clearance 0)
			)
			(min_thickness 0.25)
			(keepout
				(tracks not_allowed)
				(vias allowed)
				(pads allowed)
				(copperpour not_allowed)
				(footprints allowed)
			)
			(placement
				(enabled no)
				(sheetname "")
			)
			(fill
				(thermal_gap 0.5)
				(thermal_bridge_width 0.5)
				(island_removal_mode 0)
			)
			(polygon
				(pts
					(xy 167.005 -70.8914) (xy 167.513 -70.8914) (xy 167.513 -71.2724) (xy 167.005 -71.2724)
				)
			)
		)
	)
	(footprint ""
		(layer "F.Cu")
		(at 379.3109 -137.4648)
		(property "Reference" "C7A30"
			(at 0 0 0)
			(layer "F.SilkS")
			(hide yes)
			(effects
				(font
					(size 1.27 1.27)
				)
			)
		)
		(property "Value" ""
			(at 0 0 0)
			(layer "F.Fab")
			(effects
				(font
					(size 1.27 1.27)
				)
			)
		)
		(duplicate_pad_numbers_are_jumpers no)
		(fp_rect
			(start -0.7239 1.9939)
			(end 0.7239 -0.2159)
			(stroke
				(width 0)
				(type default)
			)
			(fill no)
			(layer "F.CrtYd")
		)
		(fp_line
			(start -0.7239 -0.2159)
			(end -0.7239 1.9939)
			(stroke
				(width 0.1)
				(type default)
			)
			(layer "F.Fab")
		)
		(fp_line
			(start -0.7239 1.9939)
			(end 0.7239 1.9939)
			(stroke
				(width 0.1)
				(type default)
			)
			(layer "F.Fab")
		)
		(fp_line
			(start 0.7239 -0.2159)
			(end -0.7239 -0.2159)
			(stroke
				(width 0.1)
				(type default)
			)
			(layer "F.Fab")
		)
		(fp_line
			(start 0.7239 1.9939)
			(end 0.7239 -0.2159)
			(stroke
				(width 0.1)
				(type default)
			)
			(layer "F.Fab")
		)
		(pad "1" smd rect
			(at 0 0)
			(size 1.27 1.016)
			(layers "F.Cu" "F.Mask" "F.Paste")
			(net "PVNN_PCH_STBY")
		)
		(pad "2" smd rect
			(at 0 1.778)
			(size 1.27 1.016)
			(layers "F.Cu" "F.Mask" "F.Paste")
			(net "GND")
		)
		(zone
			(layer "F.Cu")
			(hatch none 0.5)
			(connect_pads
				(clearance 0)
			)
			(min_thickness 0.25)
			(keepout
				(tracks not_allowed)
				(vias allowed)
				(pads allowed)
				(copperpour not_allowed)
				(footprints allowed)
			)
			(placement
				(enabled no)
				(sheetname "")
			)
			(fill
				(thermal_gap 0.5)
				(thermal_bridge_width 0.5)
				(island_removal_mode 0)
			)
			(polygon
				(pts
					(xy 378.6759 -136.1948) (xy 379.9459 -136.1948) (xy 379.9459 -136.9568) (xy 378.6759 -136.9568)
				)
			)
		)
	)
	(footprint ""
		(layer "F.Cu")
		(at 173.355 -131.5085)
		(property "Reference" "C4B6"
			(at 0 0 0)
			(layer "F.SilkS")
			(hide yes)
			(effects
				(font
					(size 1.27 1.27)
				)
			)
		)
		(property "Value" ""
			(at 0 0 0)
			(layer "F.Fab")
			(effects
				(font
					(size 1.27 1.27)
				)
			)
		)
		(duplicate_pad_numbers_are_jumpers no)
		(fp_poly
			(pts
				(xy 0.3048 -0.1016) (xy 0.3048 0.9906) (xy -0.3048 0.9906) (xy -0.3048 -0.1016)
			)
			(stroke
				(width 0)
				(type default)
			)
			(fill no)
			(layer "F.CrtYd")
		)
		(fp_line
			(start -0.3048 -0.1016)
			(end -0.3048 0.9906)
			(stroke
				(width 0.1)
				(type default)
			)
			(layer "F.Fab")
		)
		(fp_line
			(start -0.3048 0.9906)
			(end 0.3048 0.9906)
			(stroke
				(width 0.1)
				(type default)
			)
			(layer "F.Fab")
		)
		(fp_line
			(start 0.3048 -0.1016)
			(end -0.3048 -0.1016)
			(stroke
				(width 0.1)
				(type default)
			)
			(layer "F.Fab")
		)
		(fp_line
			(start 0.3048 0.9906)
			(end 0.3048 -0.1016)
			(stroke
				(width 0.1)
				(type default)
			)
			(layer "F.Fab")
		)
		(pad "1" smd rect
			(at 0 0)
			(size 0.508 0.508)
			(layers "F.Cu" "F.Mask" "F.Paste")
			(net "VR_PVPP_KLM_SS")
		)
		(pad "2" smd rect
			(at 0 0.889)
			(size 0.508 0.508)
			(layers "F.Cu" "F.Mask" "F.Paste")
			(net "AGND_PVPP_KLM")
		)
		(zone
			(layer "F.Cu")
			(hatch none 0.5)
			(connect_pads
				(clearance 0)
			)
			(min_thickness 0.25)
			(keepout
				(tracks allowed)
				(vias not_allowed)
				(pads allowed)
				(copperpour not_allowed)
				(footprints allowed)
			)
			(placement
				(enabled no)
				(sheetname "")
			)
			(fill
				(thermal_gap 0.5)
				(thermal_bridge_width 0.5)
				(island_removal_mode 0)
			)
			(polygon
				(pts
					(xy 173.101 -131.2545) (xy 173.609 -131.2545) (xy 173.609 -130.8735) (xy 173.101 -130.8735)
				)
			)
		)
		(zone
			(layer "F.Cu")
			(hatch none 0.5)
			(connect_pads
				(clearance 0)
			)
			(min_thickness 0.25)
			(keepout
				(tracks not_allowed)
				(vias allowed)
				(pads allowed)
				(copperpour not_allowed)
				(footprints allowed)
			)
			(placement
				(enabled no)
				(sheetname "")
			)
			(fill
				(thermal_gap 0.5)
				(thermal_bridge_width 0.5)
				(island_removal_mode 0)
			)
			(polygon
				(pts
					(xy 173.101 -130.8735) (xy 173.609 -130.8735) (xy 173.609 -131.2545) (xy 173.101 -131.2545)
				)
			)
		)
	)
	(footprint ""
		(layer "F.Cu")
		(at 434.7718 -14.859 180)
		(property "Reference" "R6W43"
			(at -0.8382 -0.67818 180)
			(unlocked yes)
			(layer "F.SilkS")
			(effects
				(font
					(size 0.4064 0.254)
					(thickness 0.1524)
				)
				(justify left)
			)
		)
		(property "Value" ""
			(at 0 0 180)
			(layer "F.Fab")
			(effects
				(font
					(size 1.27 1.27)
				)
			)
		)
		(duplicate_pad_numbers_are_jumpers no)
		(fp_poly
			(pts
				(xy -0.2794 -0.1016) (xy 0.2794 -0.1016) (xy 0.2794 0.9906) (xy -0.2794 0.9906)
			)
			(stroke
				(width 0)
				(type default)
			)
			(fill no)
			(layer "F.CrtYd")
		)
		(fp_line
			(start 0.2794 0.9906)
			(end 0.2794 -0.1016)
			(stroke
				(width 0.1)
				(type default)
			)
			(layer "F.Fab")
		)
		(fp_line
			(start 0.2794 -0.1016)
			(end -0.2794 -0.1016)
			(stroke
				(width 0.1)
				(type default)
			)
			(layer "F.Fab")
		)
		(fp_line
			(start -0.2794 0.9906)
			(end 0.2794 0.9906)
			(stroke
				(width 0.1)
				(type default)
			)
			(layer "F.Fab")
		)
		(fp_line
			(start -0.2794 -0.1016)
			(end -0.2794 0.9906)
			(stroke
				(width 0.1)
				(type default)
			)
			(layer "F.Fab")
		)
		(pad "1" smd rect
			(at 0 0 180)
			(size 0.508 0.508)
			(layers "F.Cu" "F.Mask" "F.Paste")
			(net "P3V3_STBY")
		)
		(pad "2" smd rect
			(at 0 0.889 180)
			(size 0.508 0.508)
			(layers "F.Cu" "F.Mask" "F.Paste")
			(net "PCA9554_A1")
		)
		(zone
			(layer "F.Cu")
			(hatch none 0.5)
			(connect_pads
				(clearance 0)
			)
			(min_thickness 0.25)
			(keepout
				(tracks not_allowed)
				(vias allowed)
				(pads allowed)
				(copperpour not_allowed)
				(footprints allowed)
			)
			(placement
				(enabled no)
				(sheetname "")
			)
			(fill
				(thermal_gap 0.5)
				(thermal_bridge_width 0.5)
				(island_removal_mode 0)
			)
			(polygon
				(pts
					(xy 435.0258 -15.494) (xy 434.5178 -15.494) (xy 434.5178 -15.113) (xy 435.0258 -15.113)
				)
			)
		)
		(zone
			(layer "F.Cu")
			(hatch none 0.5)
			(connect_pads
				(clearance 0)
			)
			(min_thickness 0.25)
			(keepout
				(tracks allowed)
				(vias not_allowed)
				(pads allowed)
				(copperpour not_allowed)
				(footprints allowed)
			)
			(placement
				(enabled no)
				(sheetname "")
			)
			(fill
				(thermal_gap 0.5)
				(thermal_bridge_width 0.5)
				(island_removal_mode 0)
			)
			(polygon
				(pts
					(xy 435.0258 -15.113) (xy 434.5178 -15.113) (xy 434.5178 -15.494) (xy 435.0258 -15.494)
				)
			)
		)
	)
	(footprint ""
		(layer "F.Cu")
		(at 352.714814 -103.103934 -90)
		(property "Reference" "L7C1"
			(at 0 0 270)
			(layer "F.SilkS")
			(hide yes)
			(effects
				(font
					(size 1.27 1.27)
				)
			)
		)
		(property "Value" "*"
			(at -3.5941 0.3429 270)
			(unlocked yes)
			(layer "F.Fab")
			(hide yes)
			(effects
				(font
					(size 1.27 1.016)
					(thickness 0.1524)
				)
			)
		)
		(property "Device Type" "IND-100NH-35-GP_DISCRET-G8-INDA"
			(at -3.5941 -1.1811 270)
			(unlocked yes)
			(layer "F.Fab")
			(hide yes)
			(effects
				(font
					(size 1.27 1.016)
					(thickness 0.1524)
				)
			)
		)
		(duplicate_pad_numbers_are_jumpers no)
		(fp_line
			(start -2.2479 2.794)
			(end -2.2479 -2.794)
			(stroke
				(width 0.1524)
				(type default)
			)
			(layer "F.SilkS")
		)
		(fp_line
			(start 2.2479 2.794)
			(end -2.2479 2.794)
			(stroke
				(width 0.1524)
				(type default)
			)
			(layer "F.SilkS")
		)
		(fp_line
			(start -2.2479 -2.794)
			(end 2.2479 -2.794)
			(stroke
				(width 0.1524)
				(type default)
			)
			(layer "F.SilkS")
		)
		(fp_line
			(start 2.2479 -2.794)
			(end 2.2479 2.794)
			(stroke
				(width 0.1524)
				(type default)
			)
			(layer "F.SilkS")
		)
		(fp_poly
			(pts
				(xy -1.9939 1.9939) (xy 1.9939 1.9939) (xy 1.9939 -1.9939) (xy -1.9939 -1.9939)
			)
			(stroke
				(width 0)
				(type default)
			)
			(fill no)
			(layer "F.CrtYd")
		)
		(fp_poly
			(pts
				(xy -2.5019 2.8702) (xy -2.5019 1.9939) (xy 1.9939 1.9939) (xy 1.9939 -1.9939) (xy -1.9939 -1.9939)
				(xy -1.9939 1.9812) (xy -2.5019 1.9812) (xy -2.5019 -2.8702) (xy 2.5019 -2.8702) (xy 2.5019 2.8702)
			)
			(stroke
				(width 0)
				(type default)
			)
			(fill no)
			(layer "F.CrtYd")
		)
		(fp_rect
			(start -2.5019 2.8702)
			(end 2.5019 -2.8702)
			(stroke
				(width 0)
				(type default)
			)
			(fill no)
			(layer "F.Fab")
		)
		(pad "1" smd rect
			(at 0 -1.745996 270)
			(size 1.5494 1.6002)
			(layers "F.Cu" "F.Mask" "F.Paste")
			(net "P12V_STBY")
		)
		(pad "2" smd rect
			(at 0 1.745996 270)
			(size 1.5494 1.6002)
			(layers "F.Cu" "F.Mask" "F.Paste")
			(net "VR_FET_SW_P12V_STBY_PVCCIO_CPU0")
		)
	)
	(footprint ""
		(layer "F.Cu")
		(at 263.186672 -77.636116)
		(property "Reference" "C5D28"
			(at 0 0 0)
			(layer "F.SilkS")
			(hide yes)
			(effects
				(font
					(size 1.27 1.27)
				)
			)
		)
		(property "Value" ""
			(at 0 0 0)
			(layer "F.Fab")
			(effects
				(font
					(size 1.27 1.27)
				)
			)
		)
		(duplicate_pad_numbers_are_jumpers no)
		(fp_poly
			(pts
				(xy -0.4953 -0.2032) (xy 0.4953 -0.2032) (xy 0.4953 1.6002) (xy -0.4953 1.6002)
			)
			(stroke
				(width 0)
				(type default)
			)
			(fill no)
			(layer "F.CrtYd")
		)
		(fp_line
			(start -0.4953 -0.2032)
			(end 0.4953 -0.2032)
			(stroke
				(width 0.1)
				(type default)
			)
			(layer "F.Fab")
		)
		(fp_line
			(start -0.4953 1.6002)
			(end -0.4953 -0.2032)
			(stroke
				(width 0.1)
				(type default)
			)
			(layer "F.Fab")
		)
		(fp_line
			(start 0.4953 -0.2032)
			(end 0.4953 1.6002)
			(stroke
				(width 0.1)
				(type default)
			)
			(layer "F.Fab")
		)
		(fp_line
			(start 0.4953 1.6002)
			(end -0.4953 1.6002)
			(stroke
				(width 0.1)
				(type default)
			)
			(layer "F.Fab")
		)
		(pad "1" smd rect
			(at 0 0)
			(size 0.762 0.889)
			(layers "F.Cu" "F.Mask" "F.Paste")
			(net "PVCCIN_CPU0")
		)
		(pad "2" smd rect
			(at 0 1.397)
			(size 0.762 0.889)
			(layers "F.Cu" "F.Mask" "F.Paste")
			(net "GND")
		)
		(zone
			(layer "F.Cu")
			(hatch none 0.5)
			(connect_pads
				(clearance 0)
			)
			(min_thickness 0.25)
			(keepout
				(tracks not_allowed)
				(vias allowed)
				(pads allowed)
				(copperpour not_allowed)
				(footprints allowed)
			)
			(placement
				(enabled no)
				(sheetname "")
			)
			(fill
				(thermal_gap 0.5)
				(thermal_bridge_width 0.5)
				(island_removal_mode 0)
			)
			(polygon
				(pts
					(xy 262.805672 -77.191616) (xy 263.567672 -77.191616) (xy 263.567672 -76.683616) (xy 262.805672 -76.683616)
				)
			)
		)
	)
	(footprint ""
		(layer "F.Cu")
		(at 24.384 -73.9648)
		(property "Reference" "C1D19"
			(at 0 0 0)
			(layer "F.SilkS")
			(hide yes)
			(effects
				(font
					(size 1.27 1.27)
				)
			)
		)
		(property "Value" ""
			(at 0 0 0)
			(layer "F.Fab")
			(effects
				(font
					(size 1.27 1.27)
				)
			)
		)
		(duplicate_pad_numbers_are_jumpers no)
		(fp_poly
			(pts
				(xy 0.3048 -0.1016) (xy 0.3048 0.9906) (xy -0.3048 0.9906) (xy -0.3048 -0.1016)
			)
			(stroke
				(width 0)
				(type default)
			)
			(fill no)
			(layer "F.CrtYd")
		)
		(fp_line
			(start -0.3048 -0.1016)
			(end -0.3048 0.9906)
			(stroke
				(width 0.1)
				(type default)
			)
			(layer "F.Fab")
		)
		(fp_line
			(start -0.3048 0.9906)
			(end 0.3048 0.9906)
			(stroke
				(width 0.1)
				(type default)
			)
			(layer "F.Fab")
		)
		(fp_line
			(start 0.3048 -0.1016)
			(end -0.3048 -0.1016)
			(stroke
				(width 0.1)
				(type default)
			)
			(layer "F.Fab")
		)
		(fp_line
			(start 0.3048 0.9906)
			(end 0.3048 -0.1016)
			(stroke
				(width 0.1)
				(type default)
			)
			(layer "F.Fab")
		)
		(pad "1" smd rect
			(at 0 0)
			(size 0.508 0.508)
			(layers "F.Cu" "F.Mask" "F.Paste")
			(net "A_HSC_VCAP")
		)
		(pad "2" smd rect
			(at 0 0.889)
			(size 0.508 0.508)
			(layers "F.Cu" "F.Mask" "F.Paste")
			(net "AGND_HSC")
		)
		(zone
			(layer "F.Cu")
			(hatch none 0.5)
			(connect_pads
				(clearance 0)
			)
			(min_thickness 0.25)
			(keepout
				(tracks allowed)
				(vias not_allowed)
				(pads allowed)
				(copperpour not_allowed)
				(footprints allowed)
			)
			(placement
				(enabled no)
				(sheetname "")
			)
			(fill
				(thermal_gap 0.5)
				(thermal_bridge_width 0.5)
				(island_removal_mode 0)
			)
			(polygon
				(pts
					(xy 24.13 -73.7108) (xy 24.638 -73.7108) (xy 24.638 -73.3298) (xy 24.13 -73.3298)
				)
			)
		)
		(zone
			(layer "F.Cu")
			(hatch none 0.5)
			(connect_pads
				(clearance 0)
			)
			(min_thickness 0.25)
			(keepout
				(tracks not_allowed)
				(vias allowed)
				(pads allowed)
				(copperpour not_allowed)
				(footprints allowed)
			)
			(placement
				(enabled no)
				(sheetname "")
			)
			(fill
				(thermal_gap 0.5)
				(thermal_bridge_width 0.5)
				(island_removal_mode 0)
			)
			(polygon
				(pts
					(xy 24.13 -73.3298) (xy 24.638 -73.3298) (xy 24.638 -73.7108) (xy 24.13 -73.7108)
				)
			)
		)
	)
	(footprint ""
		(layer "F.Cu")
		(at 163.277042 -34.671)
		(property "Reference" "C3F1"
			(at 0 0 0)
			(layer "F.SilkS")
			(hide yes)
			(effects
				(font
					(size 1.27 1.27)
				)
			)
		)
		(property "Value" ""
			(at 0 0 0)
			(layer "F.Fab")
			(effects
				(font
					(size 1.27 1.27)
				)
			)
		)
		(duplicate_pad_numbers_are_jumpers no)
		(fp_rect
			(start -0.500126 1.598422)
			(end 0.500126 -0.201422)
			(stroke
				(width 0)
				(type default)
			)
			(fill no)
			(layer "F.CrtYd")
		)
		(fp_line
			(start -0.500126 -0.201422)
			(end 0.500126 -0.201422)
			(stroke
				(width 0.1)
				(type default)
			)
			(layer "F.Fab")
		)
		(fp_line
			(start -0.500126 1.598422)
			(end -0.500126 -0.201422)
			(stroke
				(width 0.1)
				(type default)
			)
			(layer "F.Fab")
		)
		(fp_line
			(start 0.500126 -0.201422)
			(end 0.500126 1.598422)
			(stroke
				(width 0.1)
				(type default)
			)
			(layer "F.Fab")
		)
		(fp_line
			(start 0.500126 1.598422)
			(end -0.500126 1.598422)
			(stroke
				(width 0.1)
				(type default)
			)
			(layer "F.Fab")
		)
		(pad "1" smd rect
			(at 0 0 270)
			(size 0.889 0.9906)
			(layers "F.Cu" "F.Mask" "F.Paste")
			(net "P1V8_MCP_CPU1")
		)
		(pad "2" smd rect
			(at 0 1.397 270)
			(size 0.889 0.9906)
			(layers "F.Cu" "F.Mask" "F.Paste")
			(net "GND")
		)
		(zone
			(layer "F.Cu")
			(hatch none 0.5)
			(connect_pads
				(clearance 0)
			)
			(min_thickness 0.25)
			(keepout
				(tracks not_allowed)
				(vias allowed)
				(pads allowed)
				(copperpour not_allowed)
				(footprints allowed)
			)
			(placement
				(enabled no)
				(sheetname "")
			)
			(fill
				(thermal_gap 0.5)
				(thermal_bridge_width 0.5)
				(island_removal_mode 0)
			)
			(polygon
				(pts
					(xy 162.781742 -33.7185) (xy 163.772342 -33.7185) (xy 163.772342 -34.2265) (xy 162.781742 -34.2265)
				)
			)
		)
		(zone
			(layer "F.Cu")
			(hatch none 0.5)
			(connect_pads
				(clearance 0)
			)
			(min_thickness 0.25)
			(keepout
				(tracks allowed)
				(vias not_allowed)
				(pads allowed)
				(copperpour not_allowed)
				(footprints allowed)
			)
			(placement
				(enabled no)
				(sheetname "")
			)
			(fill
				(thermal_gap 0.5)
				(thermal_bridge_width 0.5)
				(island_removal_mode 0)
			)
			(polygon
				(pts
					(xy 162.781742 -33.7185) (xy 163.772342 -33.7185) (xy 163.772342 -34.2265) (xy 162.781742 -34.2265)
				)
			)
		)
	)
	(footprint ""
		(layer "F.Cu")
		(at 185.1406 -75.4253 180)
		(property "Reference" "C4D18"
			(at 0 0 180)
			(layer "F.SilkS")
			(hide yes)
			(effects
				(font
					(size 1.27 1.27)
				)
			)
		)
		(property "Value" ""
			(at 0 0 180)
			(layer "F.Fab")
			(effects
				(font
					(size 1.27 1.27)
				)
			)
		)
		(duplicate_pad_numbers_are_jumpers no)
		(fp_rect
			(start 0.3048 -0.1016)
			(end -0.3048 0.9906)
			(stroke
				(width 0)
				(type default)
			)
			(fill no)
			(layer "F.CrtYd")
		)
		(fp_line
			(start 0.3048 0.9906)
			(end 0.3048 -0.1016)
			(stroke
				(width 0.1)
				(type default)
			)
			(layer "F.Fab")
		)
		(fp_line
			(start 0.3048 -0.1016)
			(end -0.3048 -0.1016)
			(stroke
				(width 0.1)
				(type default)
			)
			(layer "F.Fab")
		)
		(fp_line
			(start -0.3048 0.9906)
			(end 0.3048 0.9906)
			(stroke
				(width 0.1)
				(type default)
			)
			(layer "F.Fab")
		)
		(fp_line
			(start -0.3048 -0.1016)
			(end -0.3048 0.9906)
			(stroke
				(width 0.1)
				(type default)
			)
			(layer "F.Fab")
		)
		(pad "1" smd rect
			(at 0 0 180)
			(size 0.508 0.508)
			(layers "F.Cu" "F.Mask" "F.Paste")
			(net "A_TSENSE_PVSA_CPU0")
		)
		(pad "2" smd rect
			(at 0 0.889 180)
			(size 0.508 0.508)
			(layers "F.Cu" "F.Mask" "F.Paste")
			(net "GND")
		)
		(zone
			(layer "F.Cu")
			(hatch none 0.5)
			(connect_pads
				(clearance 0)
			)
			(min_thickness 0.25)
			(keepout
				(tracks allowed)
				(vias not_allowed)
				(pads allowed)
				(copperpour not_allowed)
				(footprints allowed)
			)
			(placement
				(enabled no)
				(sheetname "")
			)
			(fill
				(thermal_gap 0.5)
				(thermal_bridge_width 0.5)
				(island_removal_mode 0)
			)
			(polygon
				(pts
					(xy 184.8866 -75.6793) (xy 185.3946 -75.6793) (xy 185.3946 -76.0603) (xy 184.8866 -76.0603)
				)
			)
		)
		(zone
			(layer "F.Cu")
			(hatch none 0.5)
			(connect_pads
				(clearance 0)
			)
			(min_thickness 0.25)
			(keepout
				(tracks not_allowed)
				(vias allowed)
				(pads allowed)
				(copperpour not_allowed)
				(footprints allowed)
			)
			(placement
				(enabled no)
				(sheetname "")
			)
			(fill
				(thermal_gap 0.5)
				(thermal_bridge_width 0.5)
				(island_removal_mode 0)
			)
			(polygon
				(pts
					(xy 184.8866 -75.6793) (xy 185.3946 -75.6793) (xy 185.3946 -76.0603) (xy 184.8866 -76.0603)
				)
			)
		)
	)
	(footprint ""
		(layer "F.Cu")
		(at 28.09748 -98.59772 90)
		(property "Reference" "RT37"
			(at 1.01473 0.656336 0)
			(unlocked yes)
			(layer "F.SilkS")
			(effects
				(font
					(size 0.4064 0.254)
					(thickness 0.1524)
				)
			)
		)
		(property "Value" ""
			(at 0 0 90)
			(layer "F.Fab")
			(effects
				(font
					(size 1.27 1.27)
				)
			)
		)
		(duplicate_pad_numbers_are_jumpers no)
		(fp_poly
			(pts
				(xy -0.4953 -0.2032) (xy 0.4953 -0.2032) (xy 0.4953 1.6002) (xy -0.4953 1.6002)
			)
			(stroke
				(width 0)
				(type default)
			)
			(fill no)
			(layer "F.CrtYd")
		)
		(fp_line
			(start 0.4953 -0.2032)
			(end 0.4953 1.6002)
			(stroke
				(width 0.1)
				(type default)
			)
			(layer "F.Fab")
		)
		(fp_line
			(start -0.4953 -0.2032)
			(end 0.4953 -0.2032)
			(stroke
				(width 0.1)
				(type default)
			)
			(layer "F.Fab")
		)
		(fp_line
			(start 0.4953 1.6002)
			(end -0.4953 1.6002)
			(stroke
				(width 0.1)
				(type default)
			)
			(layer "F.Fab")
		)
		(fp_line
			(start -0.4953 1.6002)
			(end -0.4953 -0.2032)
			(stroke
				(width 0.1)
				(type default)
			)
			(layer "F.Fab")
		)
		(pad "1" smd rect
			(at 0 0 90)
			(size 0.762 0.889)
			(layers "F.Cu" "F.Mask" "F.Paste")
			(net "VR_PVSA_CPU1_BOOT")
		)
		(pad "2" smd rect
			(at 0 1.397 90)
			(size 0.762 0.889)
			(layers "F.Cu" "F.Mask" "F.Paste")
			(net "VR_PVSA_CPU1_BOOT_R")
		)
		(zone
			(layer "F.Cu")
			(hatch none 0.5)
			(connect_pads
				(clearance 0)
			)
			(min_thickness 0.25)
			(keepout
				(tracks allowed)
				(vias not_allowed)
				(pads allowed)
				(copperpour not_allowed)
				(footprints allowed)
			)
			(placement
				(enabled no)
				(sheetname "")
			)
			(fill
				(thermal_gap 0.5)
				(thermal_bridge_width 0.5)
				(island_removal_mode 0)
			)
			(polygon
				(pts
					(xy 29.04998 -98.97872) (xy 28.54198 -98.97872) (xy 28.54198 -98.21672) (xy 29.04998 -98.21672)
				)
			)
		)
		(zone
			(layer "F.Cu")
			(hatch none 0.5)
			(connect_pads
				(clearance 0)
			)
			(min_thickness 0.25)
			(keepout
				(tracks not_allowed)
				(vias allowed)
				(pads allowed)
				(copperpour not_allowed)
				(footprints allowed)
			)
			(placement
				(enabled no)
				(sheetname "")
			)
			(fill
				(thermal_gap 0.5)
				(thermal_bridge_width 0.5)
				(island_removal_mode 0)
			)
			(polygon
				(pts
					(xy 29.04998 -98.21672) (xy 29.04998 -98.97872) (xy 28.54198 -98.97872) (xy 28.54198 -98.21672)
				)
			)
		)
	)
	(footprint ""
		(layer "F.Cu")
		(at 10.414 -131.826 90)
		(property "Reference" "L1B1"
			(at 0 0 90)
			(layer "F.SilkS")
			(hide yes)
			(effects
				(font
					(size 1.27 1.27)
				)
			)
		)
		(property "Value" "*"
			(at -3.5941 0.3429 90)
			(unlocked yes)
			(layer "F.Fab")
			(hide yes)
			(effects
				(font
					(size 1.27 1.016)
					(thickness 0.1524)
				)
			)
		)
		(property "Device Type" "IND-100NH-35-GP_DISCRET-G8-INDA"
			(at -3.5941 -1.1811 90)
			(unlocked yes)
			(layer "F.Fab")
			(hide yes)
			(effects
				(font
					(size 1.27 1.016)
					(thickness 0.1524)
				)
			)
		)
		(duplicate_pad_numbers_are_jumpers no)
		(fp_line
			(start 2.2479 -2.794)
			(end 2.2479 2.794)
			(stroke
				(width 0.1524)
				(type default)
			)
			(layer "F.SilkS")
		)
		(fp_line
			(start -2.2479 -2.794)
			(end 2.2479 -2.794)
			(stroke
				(width 0.1524)
				(type default)
			)
			(layer "F.SilkS")
		)
		(fp_line
			(start 2.2479 2.794)
			(end -2.2479 2.794)
			(stroke
				(width 0.1524)
				(type default)
			)
			(layer "F.SilkS")
		)
		(fp_line
			(start -2.2479 2.794)
			(end -2.2479 -2.794)
			(stroke
				(width 0.1524)
				(type default)
			)
			(layer "F.SilkS")
		)
		(fp_rect
			(start -1.9939 1.9939)
			(end 1.9939 -1.9939)
			(stroke
				(width 0)
				(type default)
			)
			(fill no)
			(layer "F.CrtYd")
		)
		(fp_poly
			(pts
				(xy -2.5019 2.8702) (xy -2.5019 1.9939) (xy 1.9939 1.9939) (xy 1.9939 -1.9939) (xy -1.9939 -1.9939)
				(xy -1.9939 1.9812) (xy -2.5019 1.9812) (xy -2.5019 -2.8702) (xy 2.5019 -2.8702) (xy 2.5019 2.8702)
			)
			(stroke
				(width 0)
				(type default)
			)
			(fill no)
			(layer "F.CrtYd")
		)
		(fp_rect
			(start -2.5019 2.8702)
			(end 2.5019 -2.8702)
			(stroke
				(width 0)
				(type default)
			)
			(fill no)
			(layer "F.Fab")
		)
		(pad "1" smd rect
			(at 0 -1.745996 90)
			(size 1.5494 1.6002)
			(layers "F.Cu" "F.Mask" "F.Paste")
			(net "P12V_STBY")
		)
		(pad "2" smd rect
			(at 0 1.745996 90)
			(size 1.5494 1.6002)
			(layers "F.Cu" "F.Mask" "F.Paste")
			(net "VR_FET_SW_P12V_STBY_PVDDQ_KLM")
		)
	)
	(footprint ""
		(layer "F.Cu")
		(at 32.672274 -101.472492 90)
		(property "Reference" "C1C17"
			(at 0 0 90)
			(layer "F.SilkS")
			(hide yes)
			(effects
				(font
					(size 1.27 1.27)
				)
			)
		)
		(property "Value" ""
			(at 0 0 90)
			(layer "F.Fab")
			(effects
				(font
					(size 1.27 1.27)
				)
			)
		)
		(duplicate_pad_numbers_are_jumpers no)
		(fp_rect
			(start 0.3048 0.9906)
			(end -0.3048 -0.1016)
			(stroke
				(width 0)
				(type default)
			)
			(fill no)
			(layer "F.CrtYd")
		)
		(fp_line
			(start 0.3048 -0.1016)
			(end -0.3048 -0.1016)
			(stroke
				(width 0.1)
				(type default)
			)
			(layer "F.Fab")
		)
		(fp_line
			(start -0.3048 -0.1016)
			(end -0.3048 0.9906)
			(stroke
				(width 0.1)
				(type default)
			)
			(layer "F.Fab")
		)
		(fp_line
			(start 0.3048 0.9906)
			(end 0.3048 -0.1016)
			(stroke
				(width 0.1)
				(type default)
			)
			(layer "F.Fab")
		)
		(fp_line
			(start -0.3048 0.9906)
			(end 0.3048 0.9906)
			(stroke
				(width 0.1)
				(type default)
			)
			(layer "F.Fab")
		)
		(pad "1" smd rect
			(at 0 0 90)
			(size 0.508 0.508)
			(layers "F.Cu" "F.Mask" "F.Paste")
			(net "VR_FET_SW_P12V_STBY_PVCCIN_CPU1")
		)
		(pad "2" smd rect
			(at 0 0.889 90)
			(size 0.508 0.508)
			(layers "F.Cu" "F.Mask" "F.Paste")
			(net "GND")
		)
		(zone
			(layer "F.Cu")
			(hatch none 0.5)
			(connect_pads
				(clearance 0)
			)
			(min_thickness 0.25)
			(keepout
				(tracks allowed)
				(vias not_allowed)
				(pads allowed)
				(copperpour not_allowed)
				(footprints allowed)
			)
			(placement
				(enabled no)
				(sheetname "")
			)
			(fill
				(thermal_gap 0.5)
				(thermal_bridge_width 0.5)
				(island_removal_mode 0)
			)
			(polygon
				(pts
					(xy 33.307274 -101.726492) (xy 32.926274 -101.726492) (xy 32.926274 -101.218492) (xy 33.307274 -101.218492)
				)
			)
		)
		(zone
			(layer "F.Cu")
			(hatch none 0.5)
			(connect_pads
				(clearance 0)
			)
			(min_thickness 0.25)
			(keepout
				(tracks not_allowed)
				(vias allowed)
				(pads allowed)
				(copperpour not_allowed)
				(footprints allowed)
			)
			(placement
				(enabled no)
				(sheetname "")
			)
			(fill
				(thermal_gap 0.5)
				(thermal_bridge_width 0.5)
				(island_removal_mode 0)
			)
			(polygon
				(pts
					(xy 33.307274 -101.726492) (xy 32.926274 -101.726492) (xy 32.926274 -101.218492) (xy 33.307274 -101.218492)
				)
			)
		)
	)
	(footprint ""
		(layer "F.Cu")
		(at 7.137146 -4.548886 90)
		(property "Reference" "R1G5"
			(at 0 0 90)
			(layer "F.SilkS")
			(hide yes)
			(effects
				(font
					(size 1.27 1.27)
				)
			)
		)
		(property "Value" ""
			(at 0 0 90)
			(layer "F.Fab")
			(effects
				(font
					(size 1.27 1.27)
				)
			)
		)
		(duplicate_pad_numbers_are_jumpers no)
		(fp_rect
			(start 0.2794 -0.1016)
			(end -0.2794 0.9906)
			(stroke
				(width 0)
				(type default)
			)
			(fill no)
			(layer "F.CrtYd")
		)
		(fp_line
			(start 0.2794 -0.1016)
			(end -0.2794 -0.1016)
			(stroke
				(width 0.1)
				(type default)
			)
			(layer "F.Fab")
		)
		(fp_line
			(start -0.2794 -0.1016)
			(end -0.2794 0.9906)
			(stroke
				(width 0.1)
				(type default)
			)
			(layer "F.Fab")
		)
		(fp_line
			(start 0.2794 0.9906)
			(end 0.2794 -0.1016)
			(stroke
				(width 0.1)
				(type default)
			)
			(layer "F.Fab")
		)
		(fp_line
			(start -0.2794 0.9906)
			(end 0.2794 0.9906)
			(stroke
				(width 0.1)
				(type default)
			)
			(layer "F.Fab")
		)
		(pad "1" smd rect
			(at 0 0 90)
			(size 0.508 0.508)
			(layers "F.Cu" "F.Mask" "F.Paste")
			(net "VSENSE_PVDDQ_GHJ_P")
		)
		(pad "2" smd rect
			(at 0 0.889 90)
			(size 0.508 0.508)
			(layers "F.Cu" "F.Mask" "F.Paste")
			(net "VR_PVDDQ_GHJ_AVSP")
		)
		(zone
			(layer "F.Cu")
			(hatch none 0.5)
			(connect_pads
				(clearance 0)
			)
			(min_thickness 0.25)
			(keepout
				(tracks allowed)
				(vias not_allowed)
				(pads allowed)
				(copperpour not_allowed)
				(footprints allowed)
			)
			(placement
				(enabled no)
				(sheetname "")
			)
			(fill
				(thermal_gap 0.5)
				(thermal_bridge_width 0.5)
				(island_removal_mode 0)
			)
			(polygon
				(pts
					(xy 7.391146 -4.802886) (xy 7.391146 -4.294886) (xy 7.772146 -4.294886) (xy 7.772146 -4.802886)
				)
			)
		)
		(zone
			(layer "F.Cu")
			(hatch none 0.5)
			(connect_pads
				(clearance 0)
			)
			(min_thickness 0.25)
			(keepout
				(tracks not_allowed)
				(vias allowed)
				(pads allowed)
				(copperpour not_allowed)
				(footprints allowed)
			)
			(placement
				(enabled no)
				(sheetname "")
			)
			(fill
				(thermal_gap 0.5)
				(thermal_bridge_width 0.5)
				(island_removal_mode 0)
			)
			(polygon
				(pts
					(xy 7.391146 -4.802886) (xy 7.391146 -4.294886) (xy 7.772146 -4.294886) (xy 7.772146 -4.802886)
				)
			)
		)
	)
	(footprint ""
		(layer "F.Cu")
		(at 401.8915 -49.403 90)
		(property "Reference" "C7F1"
			(at 0 0 90)
			(layer "F.SilkS")
			(hide yes)
			(effects
				(font
					(size 1.27 1.27)
				)
			)
		)
		(property "Value" ""
			(at 0 0 90)
			(layer "F.Fab")
			(effects
				(font
					(size 1.27 1.27)
				)
			)
		)
		(duplicate_pad_numbers_are_jumpers no)
		(fp_poly
			(pts
				(xy 0.3048 -0.1016) (xy 0.3048 0.9906) (xy -0.3048 0.9906) (xy -0.3048 -0.1016)
			)
			(stroke
				(width 0)
				(type default)
			)
			(fill no)
			(layer "F.CrtYd")
		)
		(fp_line
			(start 0.3048 -0.1016)
			(end -0.3048 -0.1016)
			(stroke
				(width 0.1)
				(type default)
			)
			(layer "F.Fab")
		)
		(fp_line
			(start -0.3048 -0.1016)
			(end -0.3048 0.9906)
			(stroke
				(width 0.1)
				(type default)
			)
			(layer "F.Fab")
		)
		(fp_line
			(start 0.3048 0.9906)
			(end 0.3048 -0.1016)
			(stroke
				(width 0.1)
				(type default)
			)
			(layer "F.Fab")
		)
		(fp_line
			(start -0.3048 0.9906)
			(end 0.3048 0.9906)
			(stroke
				(width 0.1)
				(type default)
			)
			(layer "F.Fab")
		)
		(pad "1" smd rect
			(at 0 0 90)
			(size 0.508 0.508)
			(layers "F.Cu" "F.Mask" "F.Paste")
			(net "P3V3_STBY")
		)
		(pad "2" smd rect
			(at 0 0.889 90)
			(size 0.508 0.508)
			(layers "F.Cu" "F.Mask" "F.Paste")
			(net "GND")
		)
		(zone
			(layer "F.Cu")
			(hatch none 0.5)
			(connect_pads
				(clearance 0)
			)
			(min_thickness 0.25)
			(keepout
				(tracks allowed)
				(vias not_allowed)
				(pads allowed)
				(copperpour not_allowed)
				(footprints allowed)
			)
			(placement
				(enabled no)
				(sheetname "")
			)
			(fill
				(thermal_gap 0.5)
				(thermal_bridge_width 0.5)
				(island_removal_mode 0)
			)
			(polygon
				(pts
					(xy 402.1455 -49.149) (xy 402.1455 -49.657) (xy 402.5265 -49.657) (xy 402.5265 -49.149)
				)
			)
		)
		(zone
			(layer "F.Cu")
			(hatch none 0.5)
			(connect_pads
				(clearance 0)
			)
			(min_thickness 0.25)
			(keepout
				(tracks not_allowed)
				(vias allowed)
				(pads allowed)
				(copperpour not_allowed)
				(footprints allowed)
			)
			(placement
				(enabled no)
				(sheetname "")
			)
			(fill
				(thermal_gap 0.5)
				(thermal_bridge_width 0.5)
				(island_removal_mode 0)
			)
			(polygon
				(pts
					(xy 402.5265 -49.149) (xy 402.5265 -49.657) (xy 402.1455 -49.657) (xy 402.1455 -49.149)
				)
			)
		)
	)
	(footprint ""
		(layer "F.Cu")
		(at 375.539 -132.08 180)
		(property "Reference" "C7B20"
			(at 0 0 180)
			(layer "F.SilkS")
			(hide yes)
			(effects
				(font
					(size 1.27 1.27)
				)
			)
		)
		(property "Value" ""
			(at 0 0 180)
			(layer "F.Fab")
			(effects
				(font
					(size 1.27 1.27)
				)
			)
		)
		(duplicate_pad_numbers_are_jumpers no)
		(fp_poly
			(pts
				(xy -0.4953 -0.2032) (xy 0.4953 -0.2032) (xy 0.4953 1.6002) (xy -0.4953 1.6002)
			)
			(stroke
				(width 0)
				(type default)
			)
			(fill no)
			(layer "F.CrtYd")
		)
		(fp_line
			(start 0.4953 1.6002)
			(end -0.4953 1.6002)
			(stroke
				(width 0.1)
				(type default)
			)
			(layer "F.Fab")
		)
		(fp_line
			(start 0.4953 -0.2032)
			(end 0.4953 1.6002)
			(stroke
				(width 0.1)
				(type default)
			)
			(layer "F.Fab")
		)
		(fp_line
			(start -0.4953 1.6002)
			(end -0.4953 -0.2032)
			(stroke
				(width 0.1)
				(type default)
			)
			(layer "F.Fab")
		)
		(fp_line
			(start -0.4953 -0.2032)
			(end 0.4953 -0.2032)
			(stroke
				(width 0.1)
				(type default)
			)
			(layer "F.Fab")
		)
		(pad "1" smd rect
			(at 0 0 180)
			(size 0.762 0.889)
			(layers "F.Cu" "F.Mask" "F.Paste")
			(net "P1V05_PCH_STBY")
		)
		(pad "2" smd rect
			(at 0 1.397 180)
			(size 0.762 0.889)
			(layers "F.Cu" "F.Mask" "F.Paste")
			(net "GND")
		)
		(zone
			(layer "F.Cu")
			(hatch none 0.5)
			(connect_pads
				(clearance 0)
			)
			(min_thickness 0.25)
			(keepout
				(tracks not_allowed)
				(vias allowed)
				(pads allowed)
				(copperpour not_allowed)
				(footprints allowed)
			)
			(placement
				(enabled no)
				(sheetname "")
			)
			(fill
				(thermal_gap 0.5)
				(thermal_bridge_width 0.5)
				(island_removal_mode 0)
			)
			(polygon
				(pts
					(xy 375.92 -132.5245) (xy 375.158 -132.5245) (xy 375.158 -133.0325) (xy 375.92 -133.0325)
				)
			)
		)
	)
	(footprint ""
		(layer "F.Cu")
		(at 341.049864 1.898904 180)
		(property "Reference" "L7G2"
			(at 3.378708 -4.251706 180)
			(unlocked yes)
			(layer "F.SilkS")
			(effects
				(font
					(size 0.4064 0.254)
					(thickness 0.1524)
				)
			)
		)
		(property "Value" ""
			(at 0 0 180)
			(layer "F.Fab")
			(effects
				(font
					(size 1.27 1.27)
				)
			)
		)
		(duplicate_pad_numbers_are_jumpers no)
		(fp_line
			(start 8.3693 3.199892)
			(end -1.1303 3.199892)
			(stroke
				(width 0.1524)
				(type default)
			)
			(layer "F.SilkS")
		)
		(fp_line
			(start 8.3693 1.6637)
			(end 8.3693 3.199892)
			(stroke
				(width 0.1524)
				(type default)
			)
			(layer "F.SilkS")
		)
		(fp_line
			(start 8.3693 -3.199892)
			(end 8.3693 -1.6637)
			(stroke
				(width 0.1524)
				(type default)
			)
			(layer "F.SilkS")
		)
		(fp_line
			(start -1.1303 3.199892)
			(end -1.1303 1.6637)
			(stroke
				(width 0.1524)
				(type default)
			)
			(layer "F.SilkS")
		)
		(fp_line
			(start -1.1303 -1.6637)
			(end -1.1303 -3.199892)
			(stroke
				(width 0.1524)
				(type default)
			)
			(layer "F.SilkS")
		)
		(fp_line
			(start -1.1303 -3.199892)
			(end 8.3693 -3.199892)
			(stroke
				(width 0.1524)
				(type default)
			)
			(layer "F.SilkS")
		)
		(fp_rect
			(start -1.1303 3.199892)
			(end 8.3693 -3.199892)
			(stroke
				(width 0)
				(type default)
			)
			(fill no)
			(layer "F.CrtYd")
		)
		(fp_line
			(start 8.3693 3.199892)
			(end -1.1303 3.199892)
			(stroke
				(width 0.1)
				(type default)
			)
			(layer "F.Fab")
		)
		(fp_line
			(start 8.3693 -3.199892)
			(end 8.3693 3.199892)
			(stroke
				(width 0.1)
				(type default)
			)
			(layer "F.Fab")
		)
		(fp_line
			(start -1.1303 3.199892)
			(end -1.1303 -3.199892)
			(stroke
				(width 0.1)
				(type default)
			)
			(layer "F.Fab")
		)
		(fp_line
			(start -1.1303 -3.199892)
			(end 8.3693 -3.199892)
			(stroke
				(width 0.1)
				(type default)
			)
			(layer "F.Fab")
		)
		(pad "1" smd rect
			(at 0 0 180)
			(size 3.683 2.667)
			(layers "F.Cu" "F.Mask" "F.Paste")
			(net "VR_PVDDQ_ABC_PH2_SW")
		)
		(pad "2" smd rect
			(at 7.239 0 180)
			(size 3.683 2.667)
			(layers "F.Cu" "F.Mask" "F.Paste")
			(net "PVDDQ_ABC")
		)
	)
	(footprint ""
		(layer "F.Cu")
		(at 6.843522 -13.302996 -90)
		(property "Reference" "RT22"
			(at 0 0 270)
			(layer "F.SilkS")
			(hide yes)
			(effects
				(font
					(size 1.27 1.27)
				)
			)
		)
		(property "Value" "*"
			(at -0.0254 -2.6289 270)
			(unlocked yes)
			(layer "F.Fab")
			(hide yes)
			(effects
				(font
					(size 1.27 1.016)
					(thickness 0.1524)
				)
			)
		)
		(property "Device Type" "1R3F-GP_RCL_GP-1R3F-GP,64.1R00A"
			(at -0.0254 -4.1529 270)
			(unlocked yes)
			(layer "F.Fab")
			(hide yes)
			(effects
				(font
					(size 1.27 1.016)
					(thickness 0.1524)
				)
			)
		)
		(duplicate_pad_numbers_are_jumpers no)
		(fp_line
			(start -0.4826 0)
			(end -0.2032 0)
			(stroke
				(width 0.2032)
				(type default)
			)
			(layer "F.SilkS")
		)
		(fp_line
			(start 0.2032 0)
			(end 0.4826 0)
			(stroke
				(width 0.2032)
				(type default)
			)
			(layer "F.SilkS")
		)
		(fp_rect
			(start -0.5842 1.3335)
			(end 0.5842 -1.3335)
			(stroke
				(width 0)
				(type default)
			)
			(fill no)
			(layer "F.CrtYd")
		)
		(fp_rect
			(start -0.5842 1.3335)
			(end 0.5842 -1.3335)
			(stroke
				(width 0)
				(type default)
			)
			(fill no)
			(layer "F.Fab")
		)
		(pad "1" smd custom
			(at 0 -0.762 270)
			(size 0.2159 0.2159)
			(layers "F.Cu" "F.Mask" "F.Paste")
			(net "VR_PVDDQ_GHJ_PH2_SW_RC")
			(options
				(clearance outline)
				(anchor circle)
			)
			(primitives
				(gr_poly
					(pts
						(arc
							(start -0.3302 -0.4318)
							(mid -0.402042 -0.402042)
							(end -0.4318 -0.3302)
						)
						(arc
							(start -0.4318 0.3302)
							(mid -0.402042 0.402042)
							(end -0.3302 0.4318)
						)
						(arc
							(start 0.3302 0.4318)
							(mid 0.402042 0.402042)
							(end 0.4318 0.3302)
						)
						(arc
							(start 0.4318 -0.3302)
							(mid 0.402042 -0.402042)
							(end 0.3302 -0.4318)
						)
					)
					(width 0)
					(fill yes)
				)
			)
		)
		(pad "2" smd custom
			(at 0 0.762 270)
			(size 0.2159 0.2159)
			(layers "F.Cu" "F.Mask" "F.Paste")
			(net "GND")
			(options
				(clearance outline)
				(anchor circle)
			)
			(primitives
				(gr_poly
					(pts
						(arc
							(start -0.3302 -0.4318)
							(mid -0.402042 -0.402042)
							(end -0.4318 -0.3302)
						)
						(arc
							(start -0.4318 0.3302)
							(mid -0.402042 0.402042)
							(end -0.3302 0.4318)
						)
						(arc
							(start 0.3302 0.4318)
							(mid 0.402042 0.402042)
							(end 0.4318 0.3302)
						)
						(arc
							(start 0.4318 -0.3302)
							(mid 0.402042 -0.402042)
							(end 0.3302 -0.4318)
						)
					)
					(width 0)
					(fill yes)
				)
			)
		)
	)
	(footprint ""
		(layer "F.Cu")
		(at 190.754 -94.107 -90)
		(property "Reference" "C4C12"
			(at 1.905 7.84733 90)
			(unlocked yes)
			(layer "F.SilkS")
			(effects
				(font
					(size 0.7874 0.5842)
					(thickness 0.1524)
				)
				(justify left)
			)
		)
		(property "Value" ""
			(at 0 0 270)
			(layer "F.Fab")
			(effects
				(font
					(size 1.27 1.27)
				)
			)
		)
		(duplicate_pad_numbers_are_jumpers no)
		(fp_line
			(start -3.400044 6.067044)
			(end -0.9017 6.067044)
			(stroke
				(width 0.1524)
				(type default)
			)
			(layer "F.SilkS")
		)
		(fp_line
			(start 0.9017 6.067044)
			(end 3.400044 6.067044)
			(stroke
				(width 0.1524)
				(type default)
			)
			(layer "F.SilkS")
		)
		(fp_line
			(start 3.400044 6.067044)
			(end 3.400044 0.028956)
			(stroke
				(width 0.1524)
				(type default)
			)
			(layer "F.SilkS")
		)
		(fp_line
			(start -0.9017 1.587754)
			(end -0.7239 1.587754)
			(stroke
				(width 0.1524)
				(type default)
			)
			(layer "F.SilkS")
		)
		(fp_line
			(start 0.7239 1.587754)
			(end 0.9017 1.587754)
			(stroke
				(width 0.1524)
				(type default)
			)
			(layer "F.SilkS")
		)
		(fp_line
			(start 0.9017 1.587754)
			(end 0.9017 -1.714246)
			(stroke
				(width 0.1524)
				(type default)
			)
			(layer "F.SilkS")
		)
		(fp_line
			(start -3.400044 0.028956)
			(end -3.400044 6.067044)
			(stroke
				(width 0.1524)
				(type default)
			)
			(layer "F.SilkS")
		)
		(fp_line
			(start 3.400044 0.028956)
			(end 2.638044 -0.733044)
			(stroke
				(width 0.1524)
				(type default)
			)
			(layer "F.SilkS")
		)
		(fp_line
			(start -2.638044 -0.733044)
			(end -3.400044 0.028956)
			(stroke
				(width 0.1524)
				(type default)
			)
			(layer "F.SilkS")
		)
		(fp_line
			(start -0.9017 -0.733044)
			(end -2.638044 -0.733044)
			(stroke
				(width 0.1524)
				(type default)
			)
			(layer "F.SilkS")
		)
		(fp_line
			(start 2.638044 -0.733044)
			(end 0.9017 -0.733044)
			(stroke
				(width 0.1524)
				(type default)
			)
			(layer "F.SilkS")
		)
		(fp_line
			(start -0.9017 -1.714246)
			(end -0.9017 1.587754)
			(stroke
				(width 0.1524)
				(type default)
			)
			(layer "F.SilkS")
		)
		(fp_line
			(start -0.7239 -1.714246)
			(end -0.9017 -1.714246)
			(stroke
				(width 0.1524)
				(type default)
			)
			(layer "F.SilkS")
		)
		(fp_line
			(start 0.9017 -1.714246)
			(end 0.7239 -1.714246)
			(stroke
				(width 0.1524)
				(type default)
			)
			(layer "F.SilkS")
		)
		(fp_poly
			(pts
				(xy -3.400044 6.067044) (xy 3.400044 6.067044) (xy 3.400044 0.028956) (xy 2.638044 -0.733044) (xy -2.638044 -0.733044)
				(xy -3.400044 0.028956)
			)
			(stroke
				(width 0)
				(type default)
			)
			(fill no)
			(layer "F.CrtYd")
		)
		(fp_line
			(start -3.400044 6.067044)
			(end 3.400044 6.067044)
			(stroke
				(width 0.1)
				(type default)
			)
			(layer "F.Fab")
		)
		(fp_line
			(start 3.400044 6.067044)
			(end 3.400044 0.028956)
			(stroke
				(width 0.1)
				(type default)
			)
			(layer "F.Fab")
		)
		(fp_line
			(start -3.400044 0.028956)
			(end -3.400044 6.067044)
			(stroke
				(width 0.1)
				(type default)
			)
			(layer "F.Fab")
		)
		(fp_line
			(start 3.400044 0.028956)
			(end 2.638044 -0.733044)
			(stroke
				(width 0.1)
				(type default)
			)
			(layer "F.Fab")
		)
		(fp_line
			(start -2.638044 -0.733044)
			(end -3.400044 0.028956)
			(stroke
				(width 0.1)
				(type default)
			)
			(layer "F.Fab")
		)
		(fp_line
			(start 2.638044 -0.733044)
			(end -2.638044 -0.733044)
			(stroke
				(width 0.1)
				(type default)
			)
			(layer "F.Fab")
		)
		(fp_circle
			(center 0 2.667)
			(end 0 -0.733044)
			(stroke
				(width 0.1)
				(type default)
			)
			(fill no)
			(layer "F.Fab")
		)
		(pad "1" smd rect
			(at 0 0 270)
			(size 0.7874 3.429)
			(layers "F.Cu" "F.Mask" "F.Paste")
			(net "VR_FET_SW_P12V_STBY_PVCCIN_CPU0")
		)
		(pad "2" smd rect
			(at 0 5.334 270)
			(size 0.7874 3.429)
			(layers "F.Cu" "F.Mask" "F.Paste")
			(net "GND")
		)
	)
	(footprint ""
		(layer "F.Cu")
		(at 480.845876 3.820668 90)
		(property "Reference" "C9G13"
			(at 0 0 90)
			(layer "F.SilkS")
			(hide yes)
			(effects
				(font
					(size 1.27 1.27)
				)
			)
		)
		(property "Value" ""
			(at 0 0 90)
			(layer "F.Fab")
			(effects
				(font
					(size 1.27 1.27)
				)
			)
		)
		(duplicate_pad_numbers_are_jumpers no)
		(fp_poly
			(pts
				(xy 0.3048 -0.1016) (xy 0.3048 0.9906) (xy -0.3048 0.9906) (xy -0.3048 -0.1016)
			)
			(stroke
				(width 0)
				(type default)
			)
			(fill no)
			(layer "F.CrtYd")
		)
		(fp_line
			(start 0.3048 -0.1016)
			(end -0.3048 -0.1016)
			(stroke
				(width 0.1)
				(type default)
			)
			(layer "F.Fab")
		)
		(fp_line
			(start -0.3048 -0.1016)
			(end -0.3048 0.9906)
			(stroke
				(width 0.1)
				(type default)
			)
			(layer "F.Fab")
		)
		(fp_line
			(start 0.3048 0.9906)
			(end 0.3048 -0.1016)
			(stroke
				(width 0.1)
				(type default)
			)
			(layer "F.Fab")
		)
		(fp_line
			(start -0.3048 0.9906)
			(end 0.3048 0.9906)
			(stroke
				(width 0.1)
				(type default)
			)
			(layer "F.Fab")
		)
		(pad "1" smd rect
			(at 0 0 90)
			(size 0.508 0.508)
			(layers "F.Cu" "F.Mask" "F.Paste")
			(net "NIC_SET_N_MDI_2_DN")
		)
		(pad "2" smd rect
			(at 0 0.889 90)
			(size 0.508 0.508)
			(layers "F.Cu" "F.Mask" "F.Paste")
			(net "NIC_MDI_MNG_TX_DN")
		)
		(zone
			(layer "F.Cu")
			(hatch none 0.5)
			(connect_pads
				(clearance 0)
			)
			(min_thickness 0.25)
			(keepout
				(tracks allowed)
				(vias not_allowed)
				(pads allowed)
				(copperpour not_allowed)
				(footprints allowed)
			)
			(placement
				(enabled no)
				(sheetname "")
			)
			(fill
				(thermal_gap 0.5)
				(thermal_bridge_width 0.5)
				(island_removal_mode 0)
			)
			(polygon
				(pts
					(xy 481.099876 4.074668) (xy 481.099876 3.566668) (xy 481.480876 3.566668) (xy 481.480876 4.074668)
				)
			)
		)
		(zone
			(layer "F.Cu")
			(hatch none 0.5)
			(connect_pads
				(clearance 0)
			)
			(min_thickness 0.25)
			(keepout
				(tracks not_allowed)
				(vias allowed)
				(pads allowed)
				(copperpour not_allowed)
				(footprints allowed)
			)
			(placement
				(enabled no)
				(sheetname "")
			)
			(fill
				(thermal_gap 0.5)
				(thermal_bridge_width 0.5)
				(island_removal_mode 0)
			)
			(polygon
				(pts
					(xy 481.480876 4.074668) (xy 481.480876 3.566668) (xy 481.099876 3.566668) (xy 481.099876 4.074668)
				)
			)
		)
	)
	(footprint ""
		(layer "F.Cu")
		(at 15.293848 -0.733552 90)
		(property "Reference" "R1G12"
			(at 0 0 90)
			(layer "F.SilkS")
			(hide yes)
			(effects
				(font
					(size 1.27 1.27)
				)
			)
		)
		(property "Value" ""
			(at 0 0 90)
			(layer "F.Fab")
			(effects
				(font
					(size 1.27 1.27)
				)
			)
		)
		(duplicate_pad_numbers_are_jumpers no)
		(fp_rect
			(start 0.2794 -0.1016)
			(end -0.2794 0.9906)
			(stroke
				(width 0)
				(type default)
			)
			(fill no)
			(layer "F.CrtYd")
		)
		(fp_line
			(start 0.2794 -0.1016)
			(end -0.2794 -0.1016)
			(stroke
				(width 0.1)
				(type default)
			)
			(layer "F.Fab")
		)
		(fp_line
			(start -0.2794 -0.1016)
			(end -0.2794 0.9906)
			(stroke
				(width 0.1)
				(type default)
			)
			(layer "F.Fab")
		)
		(fp_line
			(start 0.2794 0.9906)
			(end 0.2794 -0.1016)
			(stroke
				(width 0.1)
				(type default)
			)
			(layer "F.Fab")
		)
		(fp_line
			(start -0.2794 0.9906)
			(end 0.2794 0.9906)
			(stroke
				(width 0.1)
				(type default)
			)
			(layer "F.Fab")
		)
		(pad "1" smd rect
			(at 0 0 90)
			(size 0.508 0.508)
			(layers "F.Cu" "F.Mask" "F.Paste")
			(net "PWRGD_PVDDQ_GHJ_R")
		)
		(pad "2" smd rect
			(at 0 0.889 90)
			(size 0.508 0.508)
			(layers "F.Cu" "F.Mask" "F.Paste")
			(net "PWRGD_PVDDQ_GHJ")
		)
		(zone
			(layer "F.Cu")
			(hatch none 0.5)
			(connect_pads
				(clearance 0)
			)
			(min_thickness 0.25)
			(keepout
				(tracks allowed)
				(vias not_allowed)
				(pads allowed)
				(copperpour not_allowed)
				(footprints allowed)
			)
			(placement
				(enabled no)
				(sheetname "")
			)
			(fill
				(thermal_gap 0.5)
				(thermal_bridge_width 0.5)
				(island_removal_mode 0)
			)
			(polygon
				(pts
					(xy 15.547848 -0.987552) (xy 15.547848 -0.479552) (xy 15.928848 -0.479552) (xy 15.928848 -0.987552)
				)
			)
		)
		(zone
			(layer "F.Cu")
			(hatch none 0.5)
			(connect_pads
				(clearance 0)
			)
			(min_thickness 0.25)
			(keepout
				(tracks not_allowed)
				(vias allowed)
				(pads allowed)
				(copperpour not_allowed)
				(footprints allowed)
			)
			(placement
				(enabled no)
				(sheetname "")
			)
			(fill
				(thermal_gap 0.5)
				(thermal_bridge_width 0.5)
				(island_removal_mode 0)
			)
			(polygon
				(pts
					(xy 15.547848 -0.987552) (xy 15.547848 -0.479552) (xy 15.928848 -0.479552) (xy 15.928848 -0.987552)
				)
			)
		)
	)
	(footprint ""
		(layer "F.Cu")
		(at 411.444694 -132.567172 90)
		(property "Reference" "R8B3"
			(at 0 0 90)
			(layer "F.SilkS")
			(hide yes)
			(effects
				(font
					(size 1.27 1.27)
				)
			)
		)
		(property "Value" ""
			(at 0 0 90)
			(layer "F.Fab")
			(effects
				(font
					(size 1.27 1.27)
				)
			)
		)
		(duplicate_pad_numbers_are_jumpers no)
		(fp_poly
			(pts
				(xy -0.2794 -0.1016) (xy 0.2794 -0.1016) (xy 0.2794 0.9906) (xy -0.2794 0.9906)
			)
			(stroke
				(width 0)
				(type default)
			)
			(fill no)
			(layer "F.CrtYd")
		)
		(fp_line
			(start 0.2794 -0.1016)
			(end -0.2794 -0.1016)
			(stroke
				(width 0.1)
				(type default)
			)
			(layer "F.Fab")
		)
		(fp_line
			(start -0.2794 -0.1016)
			(end -0.2794 0.9906)
			(stroke
				(width 0.1)
				(type default)
			)
			(layer "F.Fab")
		)
		(fp_line
			(start 0.2794 0.9906)
			(end 0.2794 -0.1016)
			(stroke
				(width 0.1)
				(type default)
			)
			(layer "F.Fab")
		)
		(fp_line
			(start -0.2794 0.9906)
			(end 0.2794 0.9906)
			(stroke
				(width 0.1)
				(type default)
			)
			(layer "F.Fab")
		)
		(pad "1" smd rect
			(at 0 0 90)
			(size 0.508 0.508)
			(layers "F.Cu" "F.Mask" "F.Paste")
			(net "PVPP_ABC")
		)
		(pad "2" smd rect
			(at 0 0.889 90)
			(size 0.508 0.508)
			(layers "F.Cu" "F.Mask" "F.Paste")
			(net "FM_MODPRST_HFI0_CPU0_LVT2_N")
		)
		(zone
			(layer "F.Cu")
			(hatch none 0.5)
			(connect_pads
				(clearance 0)
			)
			(min_thickness 0.25)
			(keepout
				(tracks allowed)
				(vias not_allowed)
				(pads allowed)
				(copperpour not_allowed)
				(footprints allowed)
			)
			(placement
				(enabled no)
				(sheetname "")
			)
			(fill
				(thermal_gap 0.5)
				(thermal_bridge_width 0.5)
				(island_removal_mode 0)
			)
			(polygon
				(pts
					(xy 411.698694 -132.313172) (xy 411.698694 -132.821172) (xy 412.079694 -132.821172) (xy 412.079694 -132.313172)
				)
			)
		)
		(zone
			(layer "F.Cu")
			(hatch none 0.5)
			(connect_pads
				(clearance 0)
			)
			(min_thickness 0.25)
			(keepout
				(tracks not_allowed)
				(vias allowed)
				(pads allowed)
				(copperpour not_allowed)
				(footprints allowed)
			)
			(placement
				(enabled no)
				(sheetname "")
			)
			(fill
				(thermal_gap 0.5)
				(thermal_bridge_width 0.5)
				(island_removal_mode 0)
			)
			(polygon
				(pts
					(xy 412.079694 -132.313172) (xy 412.079694 -132.821172) (xy 411.698694 -132.821172) (xy 411.698694 -132.313172)
				)
			)
		)
	)
	(footprint ""
		(layer "F.Cu")
		(at 405.1935 -116.967 90)
		(property "Reference" "C8B13"
			(at 0 0 90)
			(layer "F.SilkS")
			(hide yes)
			(effects
				(font
					(size 1.27 1.27)
				)
			)
		)
		(property "Value" ""
			(at 0 0 90)
			(layer "F.Fab")
			(effects
				(font
					(size 1.27 1.27)
				)
			)
		)
		(duplicate_pad_numbers_are_jumpers no)
		(fp_poly
			(pts
				(xy -0.4953 -0.2032) (xy 0.4953 -0.2032) (xy 0.4953 1.6002) (xy -0.4953 1.6002)
			)
			(stroke
				(width 0)
				(type default)
			)
			(fill no)
			(layer "F.CrtYd")
		)
		(fp_line
			(start 0.4953 -0.2032)
			(end 0.4953 1.6002)
			(stroke
				(width 0.1)
				(type default)
			)
			(layer "F.Fab")
		)
		(fp_line
			(start -0.4953 -0.2032)
			(end 0.4953 -0.2032)
			(stroke
				(width 0.1)
				(type default)
			)
			(layer "F.Fab")
		)
		(fp_line
			(start 0.4953 1.6002)
			(end -0.4953 1.6002)
			(stroke
				(width 0.1)
				(type default)
			)
			(layer "F.Fab")
		)
		(fp_line
			(start -0.4953 1.6002)
			(end -0.4953 -0.2032)
			(stroke
				(width 0.1)
				(type default)
			)
			(layer "F.Fab")
		)
		(pad "1" smd rect
			(at 0 0 90)
			(size 0.762 0.889)
			(layers "F.Cu" "F.Mask" "F.Paste")
			(net "P1V05_PCH_STBY")
		)
		(pad "2" smd rect
			(at 0 1.397 90)
			(size 0.762 0.889)
			(layers "F.Cu" "F.Mask" "F.Paste")
			(net "GND")
		)
		(zone
			(layer "F.Cu")
			(hatch none 0.5)
			(connect_pads
				(clearance 0)
			)
			(min_thickness 0.25)
			(keepout
				(tracks not_allowed)
				(vias allowed)
				(pads allowed)
				(copperpour not_allowed)
				(footprints allowed)
			)
			(placement
				(enabled no)
				(sheetname "")
			)
			(fill
				(thermal_gap 0.5)
				(thermal_bridge_width 0.5)
				(island_removal_mode 0)
			)
			(polygon
				(pts
					(xy 405.638 -116.586) (xy 405.638 -117.348) (xy 406.146 -117.348) (xy 406.146 -116.586)
				)
			)
		)
	)
	(footprint ""
		(layer "F.Cu")
		(at 268.165072 -73.318116)
		(property "Reference" "C5D47"
			(at 0 0 0)
			(layer "F.SilkS")
			(hide yes)
			(effects
				(font
					(size 1.27 1.27)
				)
			)
		)
		(property "Value" ""
			(at 0 0 0)
			(layer "F.Fab")
			(effects
				(font
					(size 1.27 1.27)
				)
			)
		)
		(duplicate_pad_numbers_are_jumpers no)
		(fp_poly
			(pts
				(xy -0.4953 -0.2032) (xy 0.4953 -0.2032) (xy 0.4953 1.6002) (xy -0.4953 1.6002)
			)
			(stroke
				(width 0)
				(type default)
			)
			(fill no)
			(layer "F.CrtYd")
		)
		(fp_line
			(start -0.4953 -0.2032)
			(end 0.4953 -0.2032)
			(stroke
				(width 0.1)
				(type default)
			)
			(layer "F.Fab")
		)
		(fp_line
			(start -0.4953 1.6002)
			(end -0.4953 -0.2032)
			(stroke
				(width 0.1)
				(type default)
			)
			(layer "F.Fab")
		)
		(fp_line
			(start 0.4953 -0.2032)
			(end 0.4953 1.6002)
			(stroke
				(width 0.1)
				(type default)
			)
			(layer "F.Fab")
		)
		(fp_line
			(start 0.4953 1.6002)
			(end -0.4953 1.6002)
			(stroke
				(width 0.1)
				(type default)
			)
			(layer "F.Fab")
		)
		(pad "1" smd rect
			(at 0 0)
			(size 0.762 0.889)
			(layers "F.Cu" "F.Mask" "F.Paste")
			(net "PVCCIN_CPU0")
		)
		(pad "2" smd rect
			(at 0 1.397)
			(size 0.762 0.889)
			(layers "F.Cu" "F.Mask" "F.Paste")
			(net "GND")
		)
		(zone
			(layer "F.Cu")
			(hatch none 0.5)
			(connect_pads
				(clearance 0)
			)
			(min_thickness 0.25)
			(keepout
				(tracks not_allowed)
				(vias allowed)
				(pads allowed)
				(copperpour not_allowed)
				(footprints allowed)
			)
			(placement
				(enabled no)
				(sheetname "")
			)
			(fill
				(thermal_gap 0.5)
				(thermal_bridge_width 0.5)
				(island_removal_mode 0)
			)
			(polygon
				(pts
					(xy 267.784072 -72.873616) (xy 268.546072 -72.873616) (xy 268.546072 -72.365616) (xy 267.784072 -72.365616)
				)
			)
		)
	)
	(footprint ""
		(layer "F.Cu")
		(at 258.208272 -73.318116)
		(property "Reference" "C5D39"
			(at 0 0 0)
			(layer "F.SilkS")
			(hide yes)
			(effects
				(font
					(size 1.27 1.27)
				)
			)
		)
		(property "Value" ""
			(at 0 0 0)
			(layer "F.Fab")
			(effects
				(font
					(size 1.27 1.27)
				)
			)
		)
		(duplicate_pad_numbers_are_jumpers no)
		(fp_poly
			(pts
				(xy -0.4953 -0.2032) (xy 0.4953 -0.2032) (xy 0.4953 1.6002) (xy -0.4953 1.6002)
			)
			(stroke
				(width 0)
				(type default)
			)
			(fill no)
			(layer "F.CrtYd")
		)
		(fp_line
			(start -0.4953 -0.2032)
			(end 0.4953 -0.2032)
			(stroke
				(width 0.1)
				(type default)
			)
			(layer "F.Fab")
		)
		(fp_line
			(start -0.4953 1.6002)
			(end -0.4953 -0.2032)
			(stroke
				(width 0.1)
				(type default)
			)
			(layer "F.Fab")
		)
		(fp_line
			(start 0.4953 -0.2032)
			(end 0.4953 1.6002)
			(stroke
				(width 0.1)
				(type default)
			)
			(layer "F.Fab")
		)
		(fp_line
			(start 0.4953 1.6002)
			(end -0.4953 1.6002)
			(stroke
				(width 0.1)
				(type default)
			)
			(layer "F.Fab")
		)
		(pad "1" smd rect
			(at 0 0)
			(size 0.762 0.889)
			(layers "F.Cu" "F.Mask" "F.Paste")
			(net "PVCCIN_CPU0")
		)
		(pad "2" smd rect
			(at 0 1.397)
			(size 0.762 0.889)
			(layers "F.Cu" "F.Mask" "F.Paste")
			(net "GND")
		)
		(zone
			(layer "F.Cu")
			(hatch none 0.5)
			(connect_pads
				(clearance 0)
			)
			(min_thickness 0.25)
			(keepout
				(tracks not_allowed)
				(vias allowed)
				(pads allowed)
				(copperpour not_allowed)
				(footprints allowed)
			)
			(placement
				(enabled no)
				(sheetname "")
			)
			(fill
				(thermal_gap 0.5)
				(thermal_bridge_width 0.5)
				(island_removal_mode 0)
			)
			(polygon
				(pts
					(xy 257.827272 -72.873616) (xy 258.589272 -72.873616) (xy 258.589272 -72.365616) (xy 257.827272 -72.365616)
				)
			)
		)
	)
	(footprint ""
		(layer "F.Cu")
		(at 21.29028 -121.43232 -90)
		(property "Reference" "CR1B1"
			(at 3.22199 1.60528 0)
			(unlocked yes)
			(layer "F.SilkS")
			(effects
				(font
					(size 0.7874 0.5842)
					(thickness 0.1524)
				)
				(justify left)
			)
		)
		(property "Value" ""
			(at 0 0 270)
			(layer "F.Fab")
			(effects
				(font
					(size 1.27 1.27)
				)
			)
		)
		(duplicate_pad_numbers_are_jumpers no)
		(fp_line
			(start -1.335278 2.576068)
			(end -1.335278 1.664462)
			(stroke
				(width 0.1524)
				(type default)
			)
			(layer "F.SilkS")
		)
		(fp_line
			(start -1.8161 1.664462)
			(end -1.335278 0.831596)
			(stroke
				(width 0.1524)
				(type default)
			)
			(layer "F.SilkS")
		)
		(fp_line
			(start -1.335278 1.664462)
			(end -1.8161 1.664462)
			(stroke
				(width 0.1524)
				(type default)
			)
			(layer "F.SilkS")
		)
		(fp_line
			(start -0.854456 1.664462)
			(end -1.335278 1.664462)
			(stroke
				(width 0.1524)
				(type default)
			)
			(layer "F.SilkS")
		)
		(fp_line
			(start -1.335278 0.831596)
			(end -0.854456 1.664462)
			(stroke
				(width 0.1524)
				(type default)
			)
			(layer "F.SilkS")
		)
		(fp_line
			(start -0.854456 0.831596)
			(end -1.8161 0.831596)
			(stroke
				(width 0.1524)
				(type default)
			)
			(layer "F.SilkS")
		)
		(fp_line
			(start -1.335278 -0.291846)
			(end -1.335278 0.831596)
			(stroke
				(width 0.1524)
				(type default)
			)
			(layer "F.SilkS")
		)
		(fp_rect
			(start 0.67437 2.04216)
			(end -0.67437 0.24384)
			(stroke
				(width 0)
				(type default)
			)
			(fill no)
			(layer "F.CrtYd")
		)
		(fp_line
			(start -0.67437 2.04216)
			(end 0.67437 2.04216)
			(stroke
				(width 0.1)
				(type default)
			)
			(layer "F.Fab")
		)
		(fp_line
			(start 0.67437 2.04216)
			(end 0.67437 0.24384)
			(stroke
				(width 0.1)
				(type default)
			)
			(layer "F.Fab")
		)
		(fp_line
			(start -1.8161 1.664462)
			(end -1.335278 0.831596)
			(stroke
				(width 0.1)
				(type default)
			)
			(layer "F.Fab")
		)
		(fp_line
			(start -1.335278 1.664462)
			(end -1.335278 2.576068)
			(stroke
				(width 0.1)
				(type default)
			)
			(layer "F.Fab")
		)
		(fp_line
			(start -0.854456 1.664462)
			(end -1.8161 1.664462)
			(stroke
				(width 0.1)
				(type default)
			)
			(layer "F.Fab")
		)
		(fp_line
			(start -1.335278 0.831596)
			(end -0.854456 1.664462)
			(stroke
				(width 0.1)
				(type default)
			)
			(layer "F.Fab")
		)
		(fp_line
			(start -1.335278 0.831596)
			(end -1.335278 -0.291846)
			(stroke
				(width 0.1)
				(type default)
			)
			(layer "F.Fab")
		)
		(fp_line
			(start -0.854456 0.831596)
			(end -1.8161 0.831596)
			(stroke
				(width 0.1)
				(type default)
			)
			(layer "F.Fab")
		)
		(fp_line
			(start -0.67437 0.24384)
			(end -0.67437 2.04216)
			(stroke
				(width 0.1)
				(type default)
			)
			(layer "F.Fab")
		)
		(fp_line
			(start 0.67437 0.24384)
			(end -0.67437 0.24384)
			(stroke
				(width 0.1)
				(type default)
			)
			(layer "F.Fab")
		)
		(pad "1" smd rect
			(at 0 0 270)
			(size 0.4064 1.016)
			(layers "F.Cu" "F.Mask" "F.Paste")
			(net "P5V_STBY")
		)
		(pad "2" smd rect
			(at 0 2.286 270)
			(size 0.4064 1.016)
			(layers "F.Cu" "F.Mask" "F.Paste")
			(net "FAN_PWM_OUT_SYS1_R")
		)
	)
	(footprint ""
		(layer "F.Cu")
		(at 442.368686 -43.254676)
		(property "Reference" "C25W18"
			(at 0 0 0)
			(layer "F.SilkS")
			(hide yes)
			(effects
				(font
					(size 1.27 1.27)
				)
			)
		)
		(property "Value" "*"
			(at 0 -2.9337 0)
			(unlocked yes)
			(layer "F.Fab")
			(hide yes)
			(effects
				(font
					(size 1.27 1.016)
					(thickness 0.1524)
				)
			)
		)
		(property "Device Type" "SC1U16V3KX-2GP_SMD-BCG-SC1U16VA"
			(at 0 -4.4577 0)
			(unlocked yes)
			(layer "F.Fab")
			(hide yes)
			(effects
				(font
					(size 1.27 1.016)
					(thickness 0.1524)
				)
			)
		)
		(duplicate_pad_numbers_are_jumpers no)
		(fp_line
			(start 0.508 0)
			(end -0.508 0)
			(stroke
				(width 0.2032)
				(type default)
			)
			(layer "F.SilkS")
		)
		(fp_rect
			(start -0.5842 1.3335)
			(end 0.5842 -1.3335)
			(stroke
				(width 0)
				(type default)
			)
			(fill no)
			(layer "F.CrtYd")
		)
		(fp_rect
			(start -0.5842 1.3335)
			(end 0.5842 -1.3335)
			(stroke
				(width 0)
				(type default)
			)
			(fill no)
			(layer "F.Fab")
		)
		(pad "1" smd custom
			(at 0 -0.762)
			(size 0.2159 0.2159)
			(layers "F.Cu" "F.Mask" "F.Paste")
			(net "P1V2_AUX_BMC")
			(options
				(clearance outline)
				(anchor circle)
			)
			(primitives
				(gr_poly
					(pts
						(arc
							(start -0.3302 -0.4318)
							(mid -0.402042 -0.402042)
							(end -0.4318 -0.3302)
						)
						(arc
							(start -0.4318 0.3302)
							(mid -0.402042 0.402042)
							(end -0.3302 0.4318)
						)
						(arc
							(start 0.3302 0.4318)
							(mid 0.402042 0.402042)
							(end 0.4318 0.3302)
						)
						(arc
							(start 0.4318 -0.3302)
							(mid 0.402042 -0.402042)
							(end 0.3302 -0.4318)
						)
					)
					(width 0)
					(fill yes)
				)
			)
		)
		(pad "2" smd custom
			(at 0 0.762)
			(size 0.2159 0.2159)
			(layers "F.Cu" "F.Mask" "F.Paste")
			(net "GND")
			(options
				(clearance outline)
				(anchor circle)
			)
			(primitives
				(gr_poly
					(pts
						(arc
							(start -0.3302 -0.4318)
							(mid -0.402042 -0.402042)
							(end -0.4318 -0.3302)
						)
						(arc
							(start -0.4318 0.3302)
							(mid -0.402042 0.402042)
							(end -0.3302 0.4318)
						)
						(arc
							(start 0.3302 0.4318)
							(mid 0.402042 0.402042)
							(end 0.4318 0.3302)
						)
						(arc
							(start 0.4318 -0.3302)
							(mid 0.402042 -0.402042)
							(end 0.3302 -0.4318)
						)
					)
					(width 0)
					(fill yes)
				)
			)
		)
	)
	(footprint ""
		(layer "F.Cu")
		(at -0.277622 -118.636034 90)
		(property "Reference" "C10W5"
			(at -0.8382 -0.67818 90)
			(unlocked yes)
			(layer "F.SilkS")
			(effects
				(font
					(size 0.4064 0.254)
					(thickness 0.1524)
				)
				(justify left)
			)
		)
		(property "Value" ""
			(at 0 0 90)
			(layer "F.Fab")
			(effects
				(font
					(size 1.27 1.27)
				)
			)
		)
		(duplicate_pad_numbers_are_jumpers no)
		(fp_poly
			(pts
				(xy 0.3048 -0.1016) (xy 0.3048 0.9906) (xy -0.3048 0.9906) (xy -0.3048 -0.1016)
			)
			(stroke
				(width 0)
				(type default)
			)
			(fill no)
			(layer "F.CrtYd")
		)
		(fp_line
			(start 0.3048 -0.1016)
			(end -0.3048 -0.1016)
			(stroke
				(width 0.1)
				(type default)
			)
			(layer "F.Fab")
		)
		(fp_line
			(start -0.3048 -0.1016)
			(end -0.3048 0.9906)
			(stroke
				(width 0.1)
				(type default)
			)
			(layer "F.Fab")
		)
		(fp_line
			(start 0.3048 0.9906)
			(end 0.3048 -0.1016)
			(stroke
				(width 0.1)
				(type default)
			)
			(layer "F.Fab")
		)
		(fp_line
			(start -0.3048 0.9906)
			(end 0.3048 0.9906)
			(stroke
				(width 0.1)
				(type default)
			)
			(layer "F.Fab")
		)
		(pad "1" smd rect
			(at 0 0 90)
			(size 0.508 0.508)
			(layers "F.Cu" "F.Mask" "F.Paste")
			(net "PUMP_TACH1")
		)
		(pad "2" smd rect
			(at 0 0.889 90)
			(size 0.508 0.508)
			(layers "F.Cu" "F.Mask" "F.Paste")
			(net "GND")
		)
		(zone
			(layer "F.Cu")
			(hatch none 0.5)
			(connect_pads
				(clearance 0)
			)
			(min_thickness 0.25)
			(keepout
				(tracks allowed)
				(vias not_allowed)
				(pads allowed)
				(copperpour not_allowed)
				(footprints allowed)
			)
			(placement
				(enabled no)
				(sheetname "")
			)
			(fill
				(thermal_gap 0.5)
				(thermal_bridge_width 0.5)
				(island_removal_mode 0)
			)
			(polygon
				(pts
					(xy -0.023622 -118.382034) (xy -0.023622 -118.890034) (xy 0.357378 -118.890034) (xy 0.357378 -118.382034)
				)
			)
		)
		(zone
			(layer "F.Cu")
			(hatch none 0.5)
			(connect_pads
				(clearance 0)
			)
			(min_thickness 0.25)
			(keepout
				(tracks not_allowed)
				(vias allowed)
				(pads allowed)
				(copperpour not_allowed)
				(footprints allowed)
			)
			(placement
				(enabled no)
				(sheetname "")
			)
			(fill
				(thermal_gap 0.5)
				(thermal_bridge_width 0.5)
				(island_removal_mode 0)
			)
			(polygon
				(pts
					(xy 0.357378 -118.382034) (xy 0.357378 -118.890034) (xy -0.023622 -118.890034) (xy -0.023622 -118.382034)
				)
			)
		)
	)
	(footprint ""
		(layer "F.Cu")
		(at 116.3066 -73.787 90)
		(property "Reference" "R3D15"
			(at 0 0 90)
			(layer "F.SilkS")
			(hide yes)
			(effects
				(font
					(size 1.27 1.27)
				)
			)
		)
		(property "Value" ""
			(at 0 0 90)
			(layer "F.Fab")
			(effects
				(font
					(size 1.27 1.27)
				)
			)
		)
		(duplicate_pad_numbers_are_jumpers no)
		(fp_poly
			(pts
				(xy -0.2794 -0.1016) (xy 0.2794 -0.1016) (xy 0.2794 0.9906) (xy -0.2794 0.9906)
			)
			(stroke
				(width 0)
				(type default)
			)
			(fill no)
			(layer "F.CrtYd")
		)
		(fp_line
			(start 0.2794 -0.1016)
			(end -0.2794 -0.1016)
			(stroke
				(width 0.1)
				(type default)
			)
			(layer "F.Fab")
		)
		(fp_line
			(start -0.2794 -0.1016)
			(end -0.2794 0.9906)
			(stroke
				(width 0.1)
				(type default)
			)
			(layer "F.Fab")
		)
		(fp_line
			(start 0.2794 0.9906)
			(end 0.2794 -0.1016)
			(stroke
				(width 0.1)
				(type default)
			)
			(layer "F.Fab")
		)
		(fp_line
			(start -0.2794 0.9906)
			(end 0.2794 0.9906)
			(stroke
				(width 0.1)
				(type default)
			)
			(layer "F.Fab")
		)
		(pad "1" smd rect
			(at 0 0 90)
			(size 0.508 0.508)
			(layers "F.Cu" "F.Mask" "F.Paste")
			(net "PVCCIO_CPU1")
		)
		(pad "2" smd rect
			(at 0 0.889 90)
			(size 0.508 0.508)
			(layers "F.Cu" "F.Mask" "F.Paste")
			(net "PWRGD_CPU1_G")
		)
		(zone
			(layer "F.Cu")
			(hatch none 0.5)
			(connect_pads
				(clearance 0)
			)
			(min_thickness 0.25)
			(keepout
				(tracks allowed)
				(vias not_allowed)
				(pads allowed)
				(copperpour not_allowed)
				(footprints allowed)
			)
			(placement
				(enabled no)
				(sheetname "")
			)
			(fill
				(thermal_gap 0.5)
				(thermal_bridge_width 0.5)
				(island_removal_mode 0)
			)
			(polygon
				(pts
					(xy 116.5606 -73.533) (xy 116.5606 -74.041) (xy 116.9416 -74.041) (xy 116.9416 -73.533)
				)
			)
		)
		(zone
			(layer "F.Cu")
			(hatch none 0.5)
			(connect_pads
				(clearance 0)
			)
			(min_thickness 0.25)
			(keepout
				(tracks not_allowed)
				(vias allowed)
				(pads allowed)
				(copperpour not_allowed)
				(footprints allowed)
			)
			(placement
				(enabled no)
				(sheetname "")
			)
			(fill
				(thermal_gap 0.5)
				(thermal_bridge_width 0.5)
				(island_removal_mode 0)
			)
			(polygon
				(pts
					(xy 116.9416 -73.533) (xy 116.9416 -74.041) (xy 116.5606 -74.041) (xy 116.5606 -73.533)
				)
			)
		)
	)
	(footprint ""
		(layer "F.Cu")
		(at 406.6286 -61.6204 90)
		(property "Reference" "R8D35"
			(at 0 0 90)
			(layer "F.SilkS")
			(hide yes)
			(effects
				(font
					(size 1.27 1.27)
				)
			)
		)
		(property "Value" ""
			(at 0 0 90)
			(layer "F.Fab")
			(effects
				(font
					(size 1.27 1.27)
				)
			)
		)
		(duplicate_pad_numbers_are_jumpers no)
		(fp_poly
			(pts
				(xy -0.2794 -0.1016) (xy 0.2794 -0.1016) (xy 0.2794 0.9906) (xy -0.2794 0.9906)
			)
			(stroke
				(width 0)
				(type default)
			)
			(fill no)
			(layer "F.CrtYd")
		)
		(pad "1" smd rect
			(at 0 0 90)
			(size 0.508 0.508)
			(layers "F.Cu" "F.Mask" "F.Paste")
			(net "SPI_PCH_TPM_CS_N")
		)
		(pad "2" smd rect
			(at 0 0.889 90)
			(size 0.508 0.508)
			(layers "F.Cu" "F.Mask" "F.Paste")
			(net "SPI_PCH_TPM_CS_R_N")
		)
		(zone
			(layer "F.Cu")
			(hatch none 0.5)
			(connect_pads
				(clearance 0)
			)
			(min_thickness 0.25)
			(keepout
				(tracks allowed)
				(vias not_allowed)
				(pads allowed)
				(copperpour not_allowed)
				(footprints allowed)
			)
			(placement
				(enabled no)
				(sheetname "")
			)
			(fill
				(thermal_gap 0.5)
				(thermal_bridge_width 0.5)
				(island_removal_mode 0)
			)
			(polygon
				(pts
					(xy 406.8826 -61.3664) (xy 406.8826 -61.8744) (xy 407.2636 -61.8744) (xy 407.2636 -61.3664)
				)
			)
		)
		(zone
			(layer "F.Cu")
			(hatch none 0.5)
			(connect_pads
				(clearance 0)
			)
			(min_thickness 0.25)
			(keepout
				(tracks not_allowed)
				(vias allowed)
				(pads allowed)
				(copperpour not_allowed)
				(footprints allowed)
			)
			(placement
				(enabled no)
				(sheetname "")
			)
			(fill
				(thermal_gap 0.5)
				(thermal_bridge_width 0.5)
				(island_removal_mode 0)
			)
			(polygon
				(pts
					(xy 407.2636 -61.3664) (xy 407.2636 -61.8744) (xy 406.8826 -61.8744) (xy 406.8826 -61.3664)
				)
			)
		)
	)
	(footprint ""
		(layer "F.Cu")
		(at 83.856068 -149.8092 -90)
		(property "Reference" "C2A2"
			(at 1.848866 0.752348 270)
			(unlocked yes)
			(layer "F.SilkS")
			(effects
				(font
					(size 1.27 0.9652)
					(thickness 0.1524)
				)
			)
		)
		(property "Value" ""
			(at 0 0 270)
			(layer "F.Fab")
			(effects
				(font
					(size 1.27 1.27)
				)
			)
		)
		(duplicate_pad_numbers_are_jumpers no)
		(fp_rect
			(start -0.500126 1.598422)
			(end 0.500126 -0.201422)
			(stroke
				(width 0)
				(type default)
			)
			(fill no)
			(layer "F.CrtYd")
		)
		(fp_line
			(start -0.500126 1.598422)
			(end -0.500126 -0.201422)
			(stroke
				(width 0.1)
				(type default)
			)
			(layer "F.Fab")
		)
		(fp_line
			(start 0.500126 1.598422)
			(end -0.500126 1.598422)
			(stroke
				(width 0.1)
				(type default)
			)
			(layer "F.Fab")
		)
		(fp_line
			(start -0.500126 -0.201422)
			(end 0.500126 -0.201422)
			(stroke
				(width 0.1)
				(type default)
			)
			(layer "F.Fab")
		)
		(fp_line
			(start 0.500126 -0.201422)
			(end 0.500126 1.598422)
			(stroke
				(width 0.1)
				(type default)
			)
			(layer "F.Fab")
		)
		(pad "1" smd rect
			(at 0 0 180)
			(size 0.889 0.9906)
			(layers "F.Cu" "F.Mask" "F.Paste")
			(net "PVDDQ_KLM")
		)
		(pad "2" smd rect
			(at 0 1.397 180)
			(size 0.889 0.9906)
			(layers "F.Cu" "F.Mask" "F.Paste")
			(net "GND")
		)
		(zone
			(layer "F.Cu")
			(hatch none 0.5)
			(connect_pads
				(clearance 0)
			)
			(min_thickness 0.25)
			(keepout
				(tracks not_allowed)
				(vias allowed)
				(pads allowed)
				(copperpour not_allowed)
				(footprints allowed)
			)
			(placement
				(enabled no)
				(sheetname "")
			)
			(fill
				(thermal_gap 0.5)
				(thermal_bridge_width 0.5)
				(island_removal_mode 0)
			)
			(polygon
				(pts
					(xy 82.903568 -150.3045) (xy 82.903568 -149.3139) (xy 83.411568 -149.3139) (xy 83.411568 -150.3045)
				)
			)
		)
		(zone
			(layer "F.Cu")
			(hatch none 0.5)
			(connect_pads
				(clearance 0)
			)
			(min_thickness 0.25)
			(keepout
				(tracks allowed)
				(vias not_allowed)
				(pads allowed)
				(copperpour not_allowed)
				(footprints allowed)
			)
			(placement
				(enabled no)
				(sheetname "")
			)
			(fill
				(thermal_gap 0.5)
				(thermal_bridge_width 0.5)
				(island_removal_mode 0)
			)
			(polygon
				(pts
					(xy 82.903568 -150.3045) (xy 82.903568 -149.3139) (xy 83.411568 -149.3139) (xy 83.411568 -150.3045)
				)
			)
		)
	)
	(footprint ""
		(layer "F.Cu")
		(at 268.401038 -68.365116 180)
		(property "Reference" "C5D58"
			(at 0 0 180)
			(layer "F.SilkS")
			(hide yes)
			(effects
				(font
					(size 1.27 1.27)
				)
			)
		)
		(property "Value" ""
			(at 0 0 180)
			(layer "F.Fab")
			(effects
				(font
					(size 1.27 1.27)
				)
			)
		)
		(duplicate_pad_numbers_are_jumpers no)
		(fp_poly
			(pts
				(xy -0.4953 -0.2032) (xy 0.4953 -0.2032) (xy 0.4953 1.6002) (xy -0.4953 1.6002)
			)
			(stroke
				(width 0)
				(type default)
			)
			(fill no)
			(layer "F.CrtYd")
		)
		(fp_line
			(start 0.4953 1.6002)
			(end -0.4953 1.6002)
			(stroke
				(width 0.1)
				(type default)
			)
			(layer "F.Fab")
		)
		(fp_line
			(start 0.4953 -0.2032)
			(end 0.4953 1.6002)
			(stroke
				(width 0.1)
				(type default)
			)
			(layer "F.Fab")
		)
		(fp_line
			(start -0.4953 1.6002)
			(end -0.4953 -0.2032)
			(stroke
				(width 0.1)
				(type default)
			)
			(layer "F.Fab")
		)
		(fp_line
			(start -0.4953 -0.2032)
			(end 0.4953 -0.2032)
			(stroke
				(width 0.1)
				(type default)
			)
			(layer "F.Fab")
		)
		(pad "1" smd rect
			(at 0 0 180)
			(size 0.762 0.889)
			(layers "F.Cu" "F.Mask" "F.Paste")
			(net "PVDDQ_ABC")
		)
		(pad "2" smd rect
			(at 0 1.397 180)
			(size 0.762 0.889)
			(layers "F.Cu" "F.Mask" "F.Paste")
			(net "GND")
		)
		(zone
			(layer "F.Cu")
			(hatch none 0.5)
			(connect_pads
				(clearance 0)
			)
			(min_thickness 0.25)
			(keepout
				(tracks not_allowed)
				(vias allowed)
				(pads allowed)
				(copperpour not_allowed)
				(footprints allowed)
			)
			(placement
				(enabled no)
				(sheetname "")
			)
			(fill
				(thermal_gap 0.5)
				(thermal_bridge_width 0.5)
				(island_removal_mode 0)
			)
			(polygon
				(pts
					(xy 268.782038 -68.809616) (xy 268.020038 -68.809616) (xy 268.020038 -69.317616) (xy 268.782038 -69.317616)
				)
			)
		)
	)
	(footprint ""
		(layer "F.Cu")
		(at 96.746568 -23.241 180)
		(property "Reference" "C2F2"
			(at 0 0 180)
			(layer "F.SilkS")
			(hide yes)
			(effects
				(font
					(size 1.27 1.27)
				)
			)
		)
		(property "Value" ""
			(at 0 0 180)
			(layer "F.Fab")
			(effects
				(font
					(size 1.27 1.27)
				)
			)
		)
		(duplicate_pad_numbers_are_jumpers no)
		(fp_rect
			(start -0.500126 1.598422)
			(end 0.500126 -0.201422)
			(stroke
				(width 0)
				(type default)
			)
			(fill no)
			(layer "F.CrtYd")
		)
		(fp_line
			(start 0.500126 1.598422)
			(end -0.500126 1.598422)
			(stroke
				(width 0.1)
				(type default)
			)
			(layer "F.Fab")
		)
		(fp_line
			(start 0.500126 -0.201422)
			(end 0.500126 1.598422)
			(stroke
				(width 0.1)
				(type default)
			)
			(layer "F.Fab")
		)
		(fp_line
			(start -0.500126 1.598422)
			(end -0.500126 -0.201422)
			(stroke
				(width 0.1)
				(type default)
			)
			(layer "F.Fab")
		)
		(fp_line
			(start -0.500126 -0.201422)
			(end 0.500126 -0.201422)
			(stroke
				(width 0.1)
				(type default)
			)
			(layer "F.Fab")
		)
		(pad "1" smd rect
			(at 0 0 90)
			(size 0.889 0.9906)
			(layers "F.Cu" "F.Mask" "F.Paste")
			(net "PVTT_GHJ")
		)
		(pad "2" smd rect
			(at 0 1.397 90)
			(size 0.889 0.9906)
			(layers "F.Cu" "F.Mask" "F.Paste")
			(net "GND")
		)
		(zone
			(layer "F.Cu")
			(hatch none 0.5)
			(connect_pads
				(clearance 0)
			)
			(min_thickness 0.25)
			(keepout
				(tracks not_allowed)
				(vias allowed)
				(pads allowed)
				(copperpour not_allowed)
				(footprints allowed)
			)
			(placement
				(enabled no)
				(sheetname "")
			)
			(fill
				(thermal_gap 0.5)
				(thermal_bridge_width 0.5)
				(island_removal_mode 0)
			)
			(polygon
				(pts
					(xy 97.241868 -24.1935) (xy 96.251268 -24.1935) (xy 96.251268 -23.6855) (xy 97.241868 -23.6855)
				)
			)
		)
		(zone
			(layer "F.Cu")
			(hatch none 0.5)
			(connect_pads
				(clearance 0)
			)
			(min_thickness 0.25)
			(keepout
				(tracks allowed)
				(vias not_allowed)
				(pads allowed)
				(copperpour not_allowed)
				(footprints allowed)
			)
			(placement
				(enabled no)
				(sheetname "")
			)
			(fill
				(thermal_gap 0.5)
				(thermal_bridge_width 0.5)
				(island_removal_mode 0)
			)
			(polygon
				(pts
					(xy 97.241868 -24.1935) (xy 96.251268 -24.1935) (xy 96.251268 -23.6855) (xy 97.241868 -23.6855)
				)
			)
		)
	)
	(footprint ""
		(layer "F.Cu")
		(at 445.1985 -1.143 90)
		(property "Reference" "R7D30"
			(at 0 0 90)
			(layer "F.SilkS")
			(hide yes)
			(effects
				(font
					(size 1.27 1.27)
				)
			)
		)
		(property "Value" ""
			(at 0 0 90)
			(layer "F.Fab")
			(effects
				(font
					(size 1.27 1.27)
				)
			)
		)
		(duplicate_pad_numbers_are_jumpers no)
		(fp_poly
			(pts
				(xy -0.2794 -0.1016) (xy 0.2794 -0.1016) (xy 0.2794 0.9906) (xy -0.2794 0.9906)
			)
			(stroke
				(width 0)
				(type default)
			)
			(fill no)
			(layer "F.CrtYd")
		)
		(fp_line
			(start 0.2794 -0.1016)
			(end -0.2794 -0.1016)
			(stroke
				(width 0.1)
				(type default)
			)
			(layer "F.Fab")
		)
		(fp_line
			(start -0.2794 -0.1016)
			(end -0.2794 0.9906)
			(stroke
				(width 0.1)
				(type default)
			)
			(layer "F.Fab")
		)
		(fp_line
			(start 0.2794 0.9906)
			(end 0.2794 -0.1016)
			(stroke
				(width 0.1)
				(type default)
			)
			(layer "F.Fab")
		)
		(fp_line
			(start -0.2794 0.9906)
			(end 0.2794 0.9906)
			(stroke
				(width 0.1)
				(type default)
			)
			(layer "F.Fab")
		)
		(pad "1" smd rect
			(at 0 0 90)
			(size 0.508 0.508)
			(layers "F.Cu" "F.Mask" "F.Paste")
			(net "P3V3_STBY")
		)
		(pad "2" smd rect
			(at 0 0.889 90)
			(size 0.508 0.508)
			(layers "F.Cu" "F.Mask" "F.Paste")
			(net "FM_CPLD_UART_CH_LOCK_N")
		)
		(zone
			(layer "F.Cu")
			(hatch none 0.5)
			(connect_pads
				(clearance 0)
			)
			(min_thickness 0.25)
			(keepout
				(tracks allowed)
				(vias not_allowed)
				(pads allowed)
				(copperpour not_allowed)
				(footprints allowed)
			)
			(placement
				(enabled no)
				(sheetname "")
			)
			(fill
				(thermal_gap 0.5)
				(thermal_bridge_width 0.5)
				(island_removal_mode 0)
			)
			(polygon
				(pts
					(xy 445.4525 -0.889) (xy 445.4525 -1.397) (xy 445.8335 -1.397) (xy 445.8335 -0.889)
				)
			)
		)
		(zone
			(layer "F.Cu")
			(hatch none 0.5)
			(connect_pads
				(clearance 0)
			)
			(min_thickness 0.25)
			(keepout
				(tracks not_allowed)
				(vias allowed)
				(pads allowed)
				(copperpour not_allowed)
				(footprints allowed)
			)
			(placement
				(enabled no)
				(sheetname "")
			)
			(fill
				(thermal_gap 0.5)
				(thermal_bridge_width 0.5)
				(island_removal_mode 0)
			)
			(polygon
				(pts
					(xy 445.8335 -0.889) (xy 445.8335 -1.397) (xy 445.4525 -1.397) (xy 445.4525 -0.889)
				)
			)
		)
	)
	(footprint ""
		(layer "F.Cu")
		(at 40.036496 -89.416382)
		(property "Reference" "L1C2"
			(at 3.378708 -4.251706 0)
			(unlocked yes)
			(layer "F.SilkS")
			(effects
				(font
					(size 0.4064 0.254)
					(thickness 0.1524)
				)
			)
		)
		(property "Value" ""
			(at 0 0 0)
			(layer "F.Fab")
			(effects
				(font
					(size 1.27 1.27)
				)
			)
		)
		(duplicate_pad_numbers_are_jumpers no)
		(fp_line
			(start -1.1303 -3.199892)
			(end 8.3693 -3.199892)
			(stroke
				(width 0.1524)
				(type default)
			)
			(layer "F.SilkS")
		)
		(fp_line
			(start -1.1303 -1.6637)
			(end -1.1303 -3.199892)
			(stroke
				(width 0.1524)
				(type default)
			)
			(layer "F.SilkS")
		)
		(fp_line
			(start -1.1303 3.199892)
			(end -1.1303 1.6637)
			(stroke
				(width 0.1524)
				(type default)
			)
			(layer "F.SilkS")
		)
		(fp_line
			(start 8.3693 -3.199892)
			(end 8.3693 -1.6637)
			(stroke
				(width 0.1524)
				(type default)
			)
			(layer "F.SilkS")
		)
		(fp_line
			(start 8.3693 1.6637)
			(end 8.3693 3.199892)
			(stroke
				(width 0.1524)
				(type default)
			)
			(layer "F.SilkS")
		)
		(fp_line
			(start 8.3693 3.199892)
			(end -1.1303 3.199892)
			(stroke
				(width 0.1524)
				(type default)
			)
			(layer "F.SilkS")
		)
		(fp_rect
			(start -1.1303 3.199892)
			(end 8.3693 -3.199892)
			(stroke
				(width 0)
				(type default)
			)
			(fill no)
			(layer "F.CrtYd")
		)
		(fp_line
			(start -1.1303 -3.199892)
			(end 8.3693 -3.199892)
			(stroke
				(width 0.1)
				(type default)
			)
			(layer "F.Fab")
		)
		(fp_line
			(start -1.1303 3.199892)
			(end -1.1303 -3.199892)
			(stroke
				(width 0.1)
				(type default)
			)
			(layer "F.Fab")
		)
		(fp_line
			(start 8.3693 -3.199892)
			(end 8.3693 3.199892)
			(stroke
				(width 0.1)
				(type default)
			)
			(layer "F.Fab")
		)
		(fp_line
			(start 8.3693 3.199892)
			(end -1.1303 3.199892)
			(stroke
				(width 0.1)
				(type default)
			)
			(layer "F.Fab")
		)
		(pad "1" smd rect
			(at 0 0)
			(size 3.683 2.667)
			(layers "F.Cu" "F.Mask" "F.Paste")
			(net "VR_PVCCIN_CPU1_PHASE5")
		)
		(pad "2" smd rect
			(at 7.239 0)
			(size 3.683 2.667)
			(layers "F.Cu" "F.Mask" "F.Paste")
			(net "PVCCIN_CPU1")
		)
	)
	(footprint ""
		(layer "F.Cu")
		(at 168.9608 -144.6276 90)
		(property "Reference" "C4A15"
			(at 0 0 90)
			(layer "F.SilkS")
			(hide yes)
			(effects
				(font
					(size 1.27 1.27)
				)
			)
		)
		(property "Value" ""
			(at 0 0 90)
			(layer "F.Fab")
			(effects
				(font
					(size 1.27 1.27)
				)
			)
		)
		(duplicate_pad_numbers_are_jumpers no)
		(fp_rect
			(start 0.4953 1.6002)
			(end -0.4953 -0.2032)
			(stroke
				(width 0)
				(type default)
			)
			(fill no)
			(layer "F.CrtYd")
		)
		(fp_line
			(start 0.4953 -0.2032)
			(end 0.4953 1.6002)
			(stroke
				(width 0.1)
				(type default)
			)
			(layer "F.Fab")
		)
		(fp_line
			(start -0.4953 -0.2032)
			(end 0.4953 -0.2032)
			(stroke
				(width 0.1)
				(type default)
			)
			(layer "F.Fab")
		)
		(fp_line
			(start 0.4953 1.6002)
			(end -0.4953 1.6002)
			(stroke
				(width 0.1)
				(type default)
			)
			(layer "F.Fab")
		)
		(fp_line
			(start -0.4953 1.6002)
			(end -0.4953 -0.2032)
			(stroke
				(width 0.1)
				(type default)
			)
			(layer "F.Fab")
		)
		(pad "1" smd rect
			(at 0 0 90)
			(size 0.762 0.889)
			(layers "F.Cu" "F.Mask" "F.Paste")
			(net "PVDDQ_KLM")
		)
		(pad "2" smd rect
			(at 0 1.397 90)
			(size 0.762 0.889)
			(layers "F.Cu" "F.Mask" "F.Paste")
			(net "GND")
		)
		(zone
			(layer "F.Cu")
			(hatch none 0.5)
			(connect_pads
				(clearance 0)
			)
			(min_thickness 0.25)
			(keepout
				(tracks not_allowed)
				(vias allowed)
				(pads allowed)
				(copperpour not_allowed)
				(footprints allowed)
			)
			(placement
				(enabled no)
				(sheetname "")
			)
			(fill
				(thermal_gap 0.5)
				(thermal_bridge_width 0.5)
				(island_removal_mode 0)
			)
			(polygon
				(pts
					(xy 169.9133 -145.0086) (xy 169.4053 -145.0086) (xy 169.4053 -144.2466) (xy 169.9133 -144.2466)
				)
			)
		)
	)
	(footprint ""
		(layer "F.Cu")
		(at 418.465 -18.7452)
		(property "Reference" "R1U8"
			(at 0 0 0)
			(layer "F.SilkS")
			(hide yes)
			(effects
				(font
					(size 1.27 1.27)
				)
			)
		)
		(property "Value" ""
			(at 0 0 0)
			(layer "F.Fab")
			(effects
				(font
					(size 1.27 1.27)
				)
			)
		)
		(duplicate_pad_numbers_are_jumpers no)
		(fp_poly
			(pts
				(xy -0.2794 -0.1016) (xy 0.2794 -0.1016) (xy 0.2794 0.9906) (xy -0.2794 0.9906)
			)
			(stroke
				(width 0)
				(type default)
			)
			(fill no)
			(layer "F.CrtYd")
		)
		(fp_line
			(start -0.2794 -0.1016)
			(end -0.2794 0.9906)
			(stroke
				(width 0.1)
				(type default)
			)
			(layer "F.Fab")
		)
		(fp_line
			(start -0.2794 0.9906)
			(end 0.2794 0.9906)
			(stroke
				(width 0.1)
				(type default)
			)
			(layer "F.Fab")
		)
		(fp_line
			(start 0.2794 -0.1016)
			(end -0.2794 -0.1016)
			(stroke
				(width 0.1)
				(type default)
			)
			(layer "F.Fab")
		)
		(fp_line
			(start 0.2794 0.9906)
			(end 0.2794 -0.1016)
			(stroke
				(width 0.1)
				(type default)
			)
			(layer "F.Fab")
		)
		(pad "1" smd rect
			(at 0 0)
			(size 0.508 0.508)
			(layers "F.Cu" "F.Mask" "F.Paste")
			(net "SMB_VR_STBY_LVC3_SDA_R")
		)
		(pad "2" smd rect
			(at 0 0.889)
			(size 0.508 0.508)
			(layers "F.Cu" "F.Mask" "F.Paste")
			(net "SMB_VR_STBY_LVC3_SDA")
		)
		(zone
			(layer "F.Cu")
			(hatch none 0.5)
			(connect_pads
				(clearance 0)
			)
			(min_thickness 0.25)
			(keepout
				(tracks allowed)
				(vias not_allowed)
				(pads allowed)
				(copperpour not_allowed)
				(footprints allowed)
			)
			(placement
				(enabled no)
				(sheetname "")
			)
			(fill
				(thermal_gap 0.5)
				(thermal_bridge_width 0.5)
				(island_removal_mode 0)
			)
			(polygon
				(pts
					(xy 418.211 -18.4912) (xy 418.719 -18.4912) (xy 418.719 -18.1102) (xy 418.211 -18.1102)
				)
			)
		)
		(zone
			(layer "F.Cu")
			(hatch none 0.5)
			(connect_pads
				(clearance 0)
			)
			(min_thickness 0.25)
			(keepout
				(tracks not_allowed)
				(vias allowed)
				(pads allowed)
				(copperpour not_allowed)
				(footprints allowed)
			)
			(placement
				(enabled no)
				(sheetname "")
			)
			(fill
				(thermal_gap 0.5)
				(thermal_bridge_width 0.5)
				(island_removal_mode 0)
			)
			(polygon
				(pts
					(xy 418.211 -18.1102) (xy 418.719 -18.1102) (xy 418.719 -18.4912) (xy 418.211 -18.4912)
				)
			)
		)
	)
	(footprint ""
		(layer "F.Cu")
		(at -3.556 -128.6002 90)
		(property "Reference" "R1B8"
			(at 0 0 90)
			(layer "F.SilkS")
			(hide yes)
			(effects
				(font
					(size 1.27 1.27)
				)
			)
		)
		(property "Value" ""
			(at 0 0 90)
			(layer "F.Fab")
			(effects
				(font
					(size 1.27 1.27)
				)
			)
		)
		(duplicate_pad_numbers_are_jumpers no)
		(fp_rect
			(start -0.2794 -0.1016)
			(end 0.2794 0.9906)
			(stroke
				(width 0)
				(type default)
			)
			(fill no)
			(layer "F.CrtYd")
		)
		(fp_line
			(start 0.2794 -0.1016)
			(end -0.2794 -0.1016)
			(stroke
				(width 0.1)
				(type default)
			)
			(layer "F.Fab")
		)
		(fp_line
			(start -0.2794 -0.1016)
			(end -0.2794 0.9906)
			(stroke
				(width 0.1)
				(type default)
			)
			(layer "F.Fab")
		)
		(fp_line
			(start 0.2794 0.9906)
			(end 0.2794 -0.1016)
			(stroke
				(width 0.1)
				(type default)
			)
			(layer "F.Fab")
		)
		(fp_line
			(start -0.2794 0.9906)
			(end 0.2794 0.9906)
			(stroke
				(width 0.1)
				(type default)
			)
			(layer "F.Fab")
		)
		(pad "1" smd rect
			(at 0 0 90)
			(size 0.508 0.508)
			(layers "F.Cu" "F.Mask" "F.Paste")
			(net "SVID_CLK1_CPU1_R")
		)
		(pad "2" smd rect
			(at 0 0.889 90)
			(size 0.508 0.508)
			(layers "F.Cu" "F.Mask" "F.Paste")
			(net "SVID_CLK_PVDDQ_KLM")
		)
		(zone
			(layer "F.Cu")
			(hatch none 0.5)
			(connect_pads
				(clearance 0)
			)
			(min_thickness 0.25)
			(keepout
				(tracks not_allowed)
				(vias allowed)
				(pads allowed)
				(copperpour not_allowed)
				(footprints allowed)
			)
			(placement
				(enabled no)
				(sheetname "")
			)
			(fill
				(thermal_gap 0.5)
				(thermal_bridge_width 0.5)
				(island_removal_mode 0)
			)
			(polygon
				(pts
					(xy -3.302 -128.3462) (xy -2.921 -128.3462) (xy -2.921 -128.8542) (xy -3.302 -128.8542)
				)
			)
		)
		(zone
			(layer "F.Cu")
			(hatch none 0.5)
			(connect_pads
				(clearance 0)
			)
			(min_thickness 0.25)
			(keepout
				(tracks allowed)
				(vias not_allowed)
				(pads allowed)
				(copperpour not_allowed)
				(footprints allowed)
			)
			(placement
				(enabled no)
				(sheetname "")
			)
			(fill
				(thermal_gap 0.5)
				(thermal_bridge_width 0.5)
				(island_removal_mode 0)
			)
			(polygon
				(pts
					(xy -3.302 -128.3462) (xy -2.921 -128.3462) (xy -2.921 -128.8542) (xy -3.302 -128.8542)
				)
			)
		)
	)
	(footprint ""
		(layer "F.Cu")
		(at 390.525 -71.0565 180)
		(property "Reference" "R7E14"
			(at 0 0 180)
			(layer "F.SilkS")
			(hide yes)
			(effects
				(font
					(size 1.27 1.27)
				)
			)
		)
		(property "Value" ""
			(at 0 0 180)
			(layer "F.Fab")
			(effects
				(font
					(size 1.27 1.27)
				)
			)
		)
		(duplicate_pad_numbers_are_jumpers no)
		(fp_poly
			(pts
				(xy -0.2794 -0.1016) (xy 0.2794 -0.1016) (xy 0.2794 0.9906) (xy -0.2794 0.9906)
			)
			(stroke
				(width 0)
				(type default)
			)
			(fill no)
			(layer "F.CrtYd")
		)
		(fp_line
			(start 0.2794 0.9906)
			(end 0.2794 -0.1016)
			(stroke
				(width 0.1)
				(type default)
			)
			(layer "F.Fab")
		)
		(fp_line
			(start 0.2794 -0.1016)
			(end -0.2794 -0.1016)
			(stroke
				(width 0.1)
				(type default)
			)
			(layer "F.Fab")
		)
		(fp_line
			(start -0.2794 0.9906)
			(end 0.2794 0.9906)
			(stroke
				(width 0.1)
				(type default)
			)
			(layer "F.Fab")
		)
		(fp_line
			(start -0.2794 -0.1016)
			(end -0.2794 0.9906)
			(stroke
				(width 0.1)
				(type default)
			)
			(layer "F.Fab")
		)
		(pad "1" smd rect
			(at 0 0 180)
			(size 0.508 0.508)
			(layers "F.Cu" "F.Mask" "F.Paste")
			(net "VR_P5V_STBY_RT")
		)
		(pad "2" smd rect
			(at 0 0.889 180)
			(size 0.508 0.508)
			(layers "F.Cu" "F.Mask" "F.Paste")
			(net "AGND_P5V_STBY")
		)
		(zone
			(layer "F.Cu")
			(hatch none 0.5)
			(connect_pads
				(clearance 0)
			)
			(min_thickness 0.25)
			(keepout
				(tracks not_allowed)
				(vias allowed)
				(pads allowed)
				(copperpour not_allowed)
				(footprints allowed)
			)
			(placement
				(enabled no)
				(sheetname "")
			)
			(fill
				(thermal_gap 0.5)
				(thermal_bridge_width 0.5)
				(island_removal_mode 0)
			)
			(polygon
				(pts
					(xy 390.779 -71.6915) (xy 390.271 -71.6915) (xy 390.271 -71.3105) (xy 390.779 -71.3105)
				)
			)
		)
		(zone
			(layer "F.Cu")
			(hatch none 0.5)
			(connect_pads
				(clearance 0)
			)
			(min_thickness 0.25)
			(keepout
				(tracks allowed)
				(vias not_allowed)
				(pads allowed)
				(copperpour not_allowed)
				(footprints allowed)
			)
			(placement
				(enabled no)
				(sheetname "")
			)
			(fill
				(thermal_gap 0.5)
				(thermal_bridge_width 0.5)
				(island_removal_mode 0)
			)
			(polygon
				(pts
					(xy 390.779 -71.3105) (xy 390.271 -71.3105) (xy 390.271 -71.6915) (xy 390.779 -71.6915)
				)
			)
		)
	)
	(footprint ""
		(layer "F.Cu")
		(at 426.681646 -48.968152)
		(property "Reference" "R25W83"
			(at -0.8382 -0.67818 0)
			(unlocked yes)
			(layer "F.SilkS")
			(effects
				(font
					(size 0.4064 0.254)
					(thickness 0.1524)
				)
				(justify left)
			)
		)
		(property "Value" ""
			(at 0 0 0)
			(layer "F.Fab")
			(effects
				(font
					(size 1.27 1.27)
				)
			)
		)
		(duplicate_pad_numbers_are_jumpers no)
		(fp_poly
			(pts
				(xy -0.2794 -0.1016) (xy 0.2794 -0.1016) (xy 0.2794 0.9906) (xy -0.2794 0.9906)
			)
			(stroke
				(width 0)
				(type default)
			)
			(fill no)
			(layer "F.CrtYd")
		)
		(fp_line
			(start -0.2794 -0.1016)
			(end -0.2794 0.9906)
			(stroke
				(width 0.1)
				(type default)
			)
			(layer "F.Fab")
		)
		(fp_line
			(start -0.2794 0.9906)
			(end 0.2794 0.9906)
			(stroke
				(width 0.1)
				(type default)
			)
			(layer "F.Fab")
		)
		(fp_line
			(start 0.2794 -0.1016)
			(end -0.2794 -0.1016)
			(stroke
				(width 0.1)
				(type default)
			)
			(layer "F.Fab")
		)
		(fp_line
			(start 0.2794 0.9906)
			(end 0.2794 -0.1016)
			(stroke
				(width 0.1)
				(type default)
			)
			(layer "F.Fab")
		)
		(pad "1" smd rect
			(at 0 0)
			(size 0.508 0.508)
			(layers "F.Cu" "F.Mask" "F.Paste")
			(net "FM_BMC_NMI_N")
		)
		(pad "2" smd rect
			(at 0 0.889)
			(size 0.508 0.508)
			(layers "F.Cu" "F.Mask" "F.Paste")
			(net "FM_BMC_NMI_N_R")
		)
		(zone
			(layer "F.Cu")
			(hatch none 0.5)
			(connect_pads
				(clearance 0)
			)
			(min_thickness 0.25)
			(keepout
				(tracks allowed)
				(vias not_allowed)
				(pads allowed)
				(copperpour not_allowed)
				(footprints allowed)
			)
			(placement
				(enabled no)
				(sheetname "")
			)
			(fill
				(thermal_gap 0.5)
				(thermal_bridge_width 0.5)
				(island_removal_mode 0)
			)
			(polygon
				(pts
					(xy 426.427646 -48.714152) (xy 426.935646 -48.714152) (xy 426.935646 -48.333152) (xy 426.427646 -48.333152)
				)
			)
		)
		(zone
			(layer "F.Cu")
			(hatch none 0.5)
			(connect_pads
				(clearance 0)
			)
			(min_thickness 0.25)
			(keepout
				(tracks not_allowed)
				(vias allowed)
				(pads allowed)
				(copperpour not_allowed)
				(footprints allowed)
			)
			(placement
				(enabled no)
				(sheetname "")
			)
			(fill
				(thermal_gap 0.5)
				(thermal_bridge_width 0.5)
				(island_removal_mode 0)
			)
			(polygon
				(pts
					(xy 426.427646 -48.333152) (xy 426.935646 -48.333152) (xy 426.935646 -48.714152) (xy 426.427646 -48.714152)
				)
			)
		)
	)
	(footprint ""
		(layer "F.Cu")
		(at 113.427002 -77.382116)
		(property "Reference" "C3D15"
			(at 0 0 0)
			(layer "F.SilkS")
			(hide yes)
			(effects
				(font
					(size 1.27 1.27)
				)
			)
		)
		(property "Value" ""
			(at 0 0 0)
			(layer "F.Fab")
			(effects
				(font
					(size 1.27 1.27)
				)
			)
		)
		(duplicate_pad_numbers_are_jumpers no)
		(fp_poly
			(pts
				(xy -0.4953 -0.2032) (xy 0.4953 -0.2032) (xy 0.4953 1.6002) (xy -0.4953 1.6002)
			)
			(stroke
				(width 0)
				(type default)
			)
			(fill no)
			(layer "F.CrtYd")
		)
		(fp_line
			(start -0.4953 -0.2032)
			(end 0.4953 -0.2032)
			(stroke
				(width 0.1)
				(type default)
			)
			(layer "F.Fab")
		)
		(fp_line
			(start -0.4953 1.6002)
			(end -0.4953 -0.2032)
			(stroke
				(width 0.1)
				(type default)
			)
			(layer "F.Fab")
		)
		(fp_line
			(start 0.4953 -0.2032)
			(end 0.4953 1.6002)
			(stroke
				(width 0.1)
				(type default)
			)
			(layer "F.Fab")
		)
		(fp_line
			(start 0.4953 1.6002)
			(end -0.4953 1.6002)
			(stroke
				(width 0.1)
				(type default)
			)
			(layer "F.Fab")
		)
		(pad "1" smd rect
			(at 0 0)
			(size 0.762 0.889)
			(layers "F.Cu" "F.Mask" "F.Paste")
			(net "PVCCIO_CPU1")
		)
		(pad "2" smd rect
			(at 0 1.397)
			(size 0.762 0.889)
			(layers "F.Cu" "F.Mask" "F.Paste")
			(net "GND")
		)
		(zone
			(layer "F.Cu")
			(hatch none 0.5)
			(connect_pads
				(clearance 0)
			)
			(min_thickness 0.25)
			(keepout
				(tracks not_allowed)
				(vias allowed)
				(pads allowed)
				(copperpour not_allowed)
				(footprints allowed)
			)
			(placement
				(enabled no)
				(sheetname "")
			)
			(fill
				(thermal_gap 0.5)
				(thermal_bridge_width 0.5)
				(island_removal_mode 0)
			)
			(polygon
				(pts
					(xy 113.046002 -76.937616) (xy 113.808002 -76.937616) (xy 113.808002 -76.429616) (xy 113.046002 -76.429616)
				)
			)
		)
	)
	(footprint ""
		(layer "F.Cu")
		(at 153.5303 -22.7457 -90)
		(property "Reference" "C3F3"
			(at 0 0 270)
			(layer "F.SilkS")
			(hide yes)
			(effects
				(font
					(size 1.27 1.27)
				)
			)
		)
		(property "Value" ""
			(at 0 0 270)
			(layer "F.Fab")
			(effects
				(font
					(size 1.27 1.27)
				)
			)
		)
		(duplicate_pad_numbers_are_jumpers no)
		(fp_poly
			(pts
				(xy -0.4953 -0.2032) (xy 0.4953 -0.2032) (xy 0.4953 1.6002) (xy -0.4953 1.6002)
			)
			(stroke
				(width 0)
				(type default)
			)
			(fill no)
			(layer "F.CrtYd")
		)
		(fp_line
			(start -0.4953 1.6002)
			(end -0.4953 -0.2032)
			(stroke
				(width 0.1)
				(type default)
			)
			(layer "F.Fab")
		)
		(fp_line
			(start 0.4953 1.6002)
			(end -0.4953 1.6002)
			(stroke
				(width 0.1)
				(type default)
			)
			(layer "F.Fab")
		)
		(fp_line
			(start -0.4953 -0.2032)
			(end 0.4953 -0.2032)
			(stroke
				(width 0.1)
				(type default)
			)
			(layer "F.Fab")
		)
		(fp_line
			(start 0.4953 -0.2032)
			(end 0.4953 1.6002)
			(stroke
				(width 0.1)
				(type default)
			)
			(layer "F.Fab")
		)
		(pad "1" smd rect
			(at 0 0 270)
			(size 0.762 0.889)
			(layers "F.Cu" "F.Mask" "F.Paste")
			(net "PVPP_GHJ")
		)
		(pad "2" smd rect
			(at 0 1.397 270)
			(size 0.762 0.889)
			(layers "F.Cu" "F.Mask" "F.Paste")
			(net "GND")
		)
		(zone
			(layer "F.Cu")
			(hatch none 0.5)
			(connect_pads
				(clearance 0)
			)
			(min_thickness 0.25)
			(keepout
				(tracks not_allowed)
				(vias allowed)
				(pads allowed)
				(copperpour not_allowed)
				(footprints allowed)
			)
			(placement
				(enabled no)
				(sheetname "")
			)
			(fill
				(thermal_gap 0.5)
				(thermal_bridge_width 0.5)
				(island_removal_mode 0)
			)
			(polygon
				(pts
					(xy 153.0858 -23.1267) (xy 153.0858 -22.3647) (xy 152.5778 -22.3647) (xy 152.5778 -23.1267)
				)
			)
		)
	)
	(footprint ""
		(layer "F.Cu")
		(at 29.591 -2.877312 180)
		(property "Reference" "R1G17"
			(at 0 0 180)
			(layer "F.SilkS")
			(hide yes)
			(effects
				(font
					(size 1.27 1.27)
				)
			)
		)
		(property "Value" ""
			(at 0 0 180)
			(layer "F.Fab")
			(effects
				(font
					(size 1.27 1.27)
				)
			)
		)
		(duplicate_pad_numbers_are_jumpers no)
		(fp_poly
			(pts
				(xy -0.2794 -0.1016) (xy 0.2794 -0.1016) (xy 0.2794 0.9906) (xy -0.2794 0.9906)
			)
			(stroke
				(width 0)
				(type default)
			)
			(fill no)
			(layer "F.CrtYd")
		)
		(fp_line
			(start 0.2794 0.9906)
			(end 0.2794 -0.1016)
			(stroke
				(width 0.1)
				(type default)
			)
			(layer "F.Fab")
		)
		(fp_line
			(start 0.2794 -0.1016)
			(end -0.2794 -0.1016)
			(stroke
				(width 0.1)
				(type default)
			)
			(layer "F.Fab")
		)
		(fp_line
			(start -0.2794 0.9906)
			(end 0.2794 0.9906)
			(stroke
				(width 0.1)
				(type default)
			)
			(layer "F.Fab")
		)
		(fp_line
			(start -0.2794 -0.1016)
			(end -0.2794 0.9906)
			(stroke
				(width 0.1)
				(type default)
			)
			(layer "F.Fab")
		)
		(pad "1" smd rect
			(at 0 0 180)
			(size 0.508 0.508)
			(layers "F.Cu" "F.Mask" "F.Paste")
			(net "M_J_VREF")
		)
		(pad "2" smd rect
			(at 0 0.889 180)
			(size 0.508 0.508)
			(layers "F.Cu" "F.Mask" "F.Paste")
			(net "GND")
		)
		(zone
			(layer "F.Cu")
			(hatch none 0.5)
			(connect_pads
				(clearance 0)
			)
			(min_thickness 0.25)
			(keepout
				(tracks not_allowed)
				(vias allowed)
				(pads allowed)
				(copperpour not_allowed)
				(footprints allowed)
			)
			(placement
				(enabled no)
				(sheetname "")
			)
			(fill
				(thermal_gap 0.5)
				(thermal_bridge_width 0.5)
				(island_removal_mode 0)
			)
			(polygon
				(pts
					(xy 29.845 -3.512312) (xy 29.337 -3.512312) (xy 29.337 -3.131312) (xy 29.845 -3.131312)
				)
			)
		)
		(zone
			(layer "F.Cu")
			(hatch none 0.5)
			(connect_pads
				(clearance 0)
			)
			(min_thickness 0.25)
			(keepout
				(tracks allowed)
				(vias not_allowed)
				(pads allowed)
				(copperpour not_allowed)
				(footprints allowed)
			)
			(placement
				(enabled no)
				(sheetname "")
			)
			(fill
				(thermal_gap 0.5)
				(thermal_bridge_width 0.5)
				(island_removal_mode 0)
			)
			(polygon
				(pts
					(xy 29.845 -3.131312) (xy 29.337 -3.131312) (xy 29.337 -3.512312) (xy 29.845 -3.512312)
				)
			)
		)
	)
	(footprint ""
		(layer "F.Cu")
		(at 490.6137 -35.687)
		(property "Reference" "CR25W1"
			(at -1.495806 -1.067816 0)
			(unlocked yes)
			(layer "F.SilkS")
			(effects
				(font
					(size 0.4064 0.254)
					(thickness 0.1524)
				)
				(justify left)
			)
		)
		(property "Value" ""
			(at 0 0 0)
			(layer "F.Fab")
			(effects
				(font
					(size 1.27 1.27)
				)
			)
		)
		(duplicate_pad_numbers_are_jumpers no)
		(fp_circle
			(center -0.589026 -0.5334)
			(end -0.462026 -0.5334)
			(stroke
				(width 0.254)
				(type default)
			)
			(fill no)
			(layer "F.SilkS")
		)
		(fp_rect
			(start -0.225552 2.167382)
			(end 0.809498 -0.167386)
			(stroke
				(width 0)
				(type default)
			)
			(fill no)
			(layer "F.CrtYd")
		)
		(fp_line
			(start -0.225552 -0.167386)
			(end 0.809498 -0.167386)
			(stroke
				(width 0.1)
				(type default)
			)
			(layer "F.Fab")
		)
		(fp_line
			(start -0.225552 2.167382)
			(end -0.225552 -0.167386)
			(stroke
				(width 0.1)
				(type default)
			)
			(layer "F.Fab")
		)
		(fp_line
			(start 0.809498 -0.167386)
			(end 0.809498 2.167382)
			(stroke
				(width 0.1)
				(type default)
			)
			(layer "F.Fab")
		)
		(fp_line
			(start 0.809498 2.167382)
			(end -0.225552 2.167382)
			(stroke
				(width 0.1)
				(type default)
			)
			(layer "F.Fab")
		)
		(fp_circle
			(center -0.589026 -0.5334)
			(end -0.462026 -0.5334)
			(stroke
				(width 0.254)
				(type default)
			)
			(fill no)
			(layer "F.Fab")
		)
		(pad "1" smd rect
			(at 0 0)
			(size 0.3556 0.2032)
			(layers "F.Cu" "F.Mask" "F.Paste")
			(net "V_IO_B_J")
		)
		(pad "2" smd rect
			(at 0 0.500126)
			(size 0.3556 0.2032)
			(layers "F.Cu" "F.Mask" "F.Paste")
			(net "V_IO_G_J")
		)
		(pad "3" smd rect
			(at 0.2921 0.999998)
			(size 0.9398 0.4064)
			(layers "F.Cu" "F.Mask" "F.Paste")
			(net "GND")
		)
		(pad "4" smd rect
			(at 0 1.500124)
			(size 0.3556 0.2032)
			(layers "F.Cu" "F.Mask" "F.Paste")
			(net "V_IO_R_J")
		)
		(pad "5" smd rect
			(at 0 1.999996)
			(size 0.3556 0.2032)
			(layers "F.Cu" "F.Mask" "F.Paste")
			(net "Net_6484")
		)
		(pad "6" smd rect
			(at 0.583946 1.999996)
			(size 0.3556 0.2032)
			(layers "F.Cu" "F.Mask" "F.Paste")
			(net "Net_6483")
		)
		(pad "7" smd rect
			(at 0.583946 1.500124)
			(size 0.3556 0.2032)
			(layers "F.Cu" "F.Mask" "F.Paste")
			(net "V_IO_R_J")
		)
		(pad "8" smd rect
			(at 0.583946 0.500126)
			(size 0.3556 0.2032)
			(layers "F.Cu" "F.Mask" "F.Paste")
			(net "V_IO_G_J")
		)
		(pad "9" smd rect
			(at 0.583946 0)
			(size 0.3556 0.2032)
			(layers "F.Cu" "F.Mask" "F.Paste")
			(net "V_IO_B_J")
		)
	)
	(footprint ""
		(layer "F.Cu")
		(at 465.593938 -26.557224 90)
		(property "Reference" "R8E25"
			(at 0 0 90)
			(layer "F.SilkS")
			(hide yes)
			(effects
				(font
					(size 1.27 1.27)
				)
			)
		)
		(property "Value" ""
			(at 0 0 90)
			(layer "F.Fab")
			(effects
				(font
					(size 1.27 1.27)
				)
			)
		)
		(duplicate_pad_numbers_are_jumpers no)
		(fp_rect
			(start -0.2794 -0.1016)
			(end 0.2794 0.9906)
			(stroke
				(width 0)
				(type default)
			)
			(fill no)
			(layer "F.CrtYd")
		)
		(fp_line
			(start 0.2794 -0.1016)
			(end -0.2794 -0.1016)
			(stroke
				(width 0.1)
				(type default)
			)
			(layer "F.Fab")
		)
		(fp_line
			(start -0.2794 -0.1016)
			(end -0.2794 0.9906)
			(stroke
				(width 0.1)
				(type default)
			)
			(layer "F.Fab")
		)
		(fp_line
			(start 0.2794 0.9906)
			(end 0.2794 -0.1016)
			(stroke
				(width 0.1)
				(type default)
			)
			(layer "F.Fab")
		)
		(fp_line
			(start -0.2794 0.9906)
			(end 0.2794 0.9906)
			(stroke
				(width 0.1)
				(type default)
			)
			(layer "F.Fab")
		)
		(pad "1" smd rect
			(at 0 0 90)
			(size 0.508 0.508)
			(layers "F.Cu" "F.Mask" "F.Paste")
			(net "P3V3_STBY")
		)
		(pad "2" smd rect
			(at 0 0.889 90)
			(size 0.508 0.508)
			(layers "F.Cu" "F.Mask" "F.Paste")
			(net "VSENSE_P3V3_STBY")
		)
		(zone
			(layer "F.Cu")
			(hatch none 0.5)
			(connect_pads
				(clearance 0)
			)
			(min_thickness 0.25)
			(keepout
				(tracks not_allowed)
				(vias allowed)
				(pads allowed)
				(copperpour not_allowed)
				(footprints allowed)
			)
			(placement
				(enabled no)
				(sheetname "")
			)
			(fill
				(thermal_gap 0.5)
				(thermal_bridge_width 0.5)
				(island_removal_mode 0)
			)
			(polygon
				(pts
					(xy 465.847938 -26.303224) (xy 466.228938 -26.303224) (xy 466.228938 -26.811224) (xy 465.847938 -26.811224)
				)
			)
		)
		(zone
			(layer "F.Cu")
			(hatch none 0.5)
			(connect_pads
				(clearance 0)
			)
			(min_thickness 0.25)
			(keepout
				(tracks allowed)
				(vias not_allowed)
				(pads allowed)
				(copperpour not_allowed)
				(footprints allowed)
			)
			(placement
				(enabled no)
				(sheetname "")
			)
			(fill
				(thermal_gap 0.5)
				(thermal_bridge_width 0.5)
				(island_removal_mode 0)
			)
			(polygon
				(pts
					(xy 465.847938 -26.303224) (xy 466.228938 -26.303224) (xy 466.228938 -26.811224) (xy 465.847938 -26.811224)
				)
			)
		)
	)
	(footprint ""
		(layer "F.Cu")
		(at 354.36048 -135.742934)
		(property "Reference" "C7A37"
			(at 0 0 0)
			(layer "F.SilkS")
			(hide yes)
			(effects
				(font
					(size 1.27 1.27)
				)
			)
		)
		(property "Value" ""
			(at 0 0 0)
			(layer "F.Fab")
			(effects
				(font
					(size 1.27 1.27)
				)
			)
		)
		(duplicate_pad_numbers_are_jumpers no)
		(fp_poly
			(pts
				(xy 0.3048 -0.1016) (xy 0.3048 0.9906) (xy -0.3048 0.9906) (xy -0.3048 -0.1016)
			)
			(stroke
				(width 0)
				(type default)
			)
			(fill no)
			(layer "F.CrtYd")
		)
		(fp_line
			(start -0.3048 -0.1016)
			(end -0.3048 0.9906)
			(stroke
				(width 0.1)
				(type default)
			)
			(layer "F.Fab")
		)
		(fp_line
			(start -0.3048 0.9906)
			(end 0.3048 0.9906)
			(stroke
				(width 0.1)
				(type default)
			)
			(layer "F.Fab")
		)
		(fp_line
			(start 0.3048 -0.1016)
			(end -0.3048 -0.1016)
			(stroke
				(width 0.1)
				(type default)
			)
			(layer "F.Fab")
		)
		(fp_line
			(start 0.3048 0.9906)
			(end 0.3048 -0.1016)
			(stroke
				(width 0.1)
				(type default)
			)
			(layer "F.Fab")
		)
		(pad "1" smd rect
			(at 0 0)
			(size 0.508 0.508)
			(layers "F.Cu" "F.Mask" "F.Paste")
			(net "VR_PVDDQ_DEF_VDD")
		)
		(pad "2" smd rect
			(at 0 0.889)
			(size 0.508 0.508)
			(layers "F.Cu" "F.Mask" "F.Paste")
			(net "GND")
		)
		(zone
			(layer "F.Cu")
			(hatch none 0.5)
			(connect_pads
				(clearance 0)
			)
			(min_thickness 0.25)
			(keepout
				(tracks allowed)
				(vias not_allowed)
				(pads allowed)
				(copperpour not_allowed)
				(footprints allowed)
			)
			(placement
				(enabled no)
				(sheetname "")
			)
			(fill
				(thermal_gap 0.5)
				(thermal_bridge_width 0.5)
				(island_removal_mode 0)
			)
			(polygon
				(pts
					(xy 354.10648 -135.488934) (xy 354.61448 -135.488934) (xy 354.61448 -135.107934) (xy 354.10648 -135.107934)
				)
			)
		)
		(zone
			(layer "F.Cu")
			(hatch none 0.5)
			(connect_pads
				(clearance 0)
			)
			(min_thickness 0.25)
			(keepout
				(tracks not_allowed)
				(vias allowed)
				(pads allowed)
				(copperpour not_allowed)
				(footprints allowed)
			)
			(placement
				(enabled no)
				(sheetname "")
			)
			(fill
				(thermal_gap 0.5)
				(thermal_bridge_width 0.5)
				(island_removal_mode 0)
			)
			(polygon
				(pts
					(xy 354.10648 -135.107934) (xy 354.61448 -135.107934) (xy 354.61448 -135.488934) (xy 354.10648 -135.488934)
				)
			)
		)
	)
	(footprint ""
		(layer "F.Cu")
		(at 28.794964 -88.540844 -90)
		(property "Reference" "R1D52"
			(at 0 0 270)
			(layer "F.SilkS")
			(hide yes)
			(effects
				(font
					(size 1.27 1.27)
				)
			)
		)
		(property "Value" ""
			(at 0 0 270)
			(layer "F.Fab")
			(effects
				(font
					(size 1.27 1.27)
				)
			)
		)
		(duplicate_pad_numbers_are_jumpers no)
		(fp_poly
			(pts
				(xy -0.2794 -0.1016) (xy 0.2794 -0.1016) (xy 0.2794 0.9906) (xy -0.2794 0.9906)
			)
			(stroke
				(width 0)
				(type default)
			)
			(fill no)
			(layer "F.CrtYd")
		)
		(fp_line
			(start -0.2794 0.9906)
			(end 0.2794 0.9906)
			(stroke
				(width 0.1)
				(type default)
			)
			(layer "F.Fab")
		)
		(fp_line
			(start 0.2794 0.9906)
			(end 0.2794 -0.1016)
			(stroke
				(width 0.1)
				(type default)
			)
			(layer "F.Fab")
		)
		(fp_line
			(start -0.2794 -0.1016)
			(end -0.2794 0.9906)
			(stroke
				(width 0.1)
				(type default)
			)
			(layer "F.Fab")
		)
		(fp_line
			(start 0.2794 -0.1016)
			(end -0.2794 -0.1016)
			(stroke
				(width 0.1)
				(type default)
			)
			(layer "F.Fab")
		)
		(pad "1" smd rect
			(at 0 0 270)
			(size 0.508 0.508)
			(layers "F.Cu" "F.Mask" "F.Paste")
			(net "VR_PVCCIN_CPU1_PH5_OCSET")
		)
		(pad "2" smd rect
			(at 0 0.889 270)
			(size 0.508 0.508)
			(layers "F.Cu" "F.Mask" "F.Paste")
			(net "GND")
		)
		(zone
			(layer "F.Cu")
			(hatch none 0.5)
			(connect_pads
				(clearance 0)
			)
			(min_thickness 0.25)
			(keepout
				(tracks not_allowed)
				(vias allowed)
				(pads allowed)
				(copperpour not_allowed)
				(footprints allowed)
			)
			(placement
				(enabled no)
				(sheetname "")
			)
			(fill
				(thermal_gap 0.5)
				(thermal_bridge_width 0.5)
				(island_removal_mode 0)
			)
			(polygon
				(pts
					(xy 28.159964 -88.794844) (xy 28.159964 -88.286844) (xy 28.540964 -88.286844) (xy 28.540964 -88.794844)
				)
			)
		)
		(zone
			(layer "F.Cu")
			(hatch none 0.5)
			(connect_pads
				(clearance 0)
			)
			(min_thickness 0.25)
			(keepout
				(tracks allowed)
				(vias not_allowed)
				(pads allowed)
				(copperpour not_allowed)
				(footprints allowed)
			)
			(placement
				(enabled no)
				(sheetname "")
			)
			(fill
				(thermal_gap 0.5)
				(thermal_bridge_width 0.5)
				(island_removal_mode 0)
			)
			(polygon
				(pts
					(xy 28.540964 -88.794844) (xy 28.540964 -88.286844) (xy 28.159964 -88.286844) (xy 28.159964 -88.794844)
				)
			)
		)
	)
	(footprint ""
		(layer "F.Cu")
		(at 29.636466 -53.42763 90)
		(property "Reference" "CT24"
			(at 1.67513 -6.1976 0)
			(unlocked yes)
			(layer "F.SilkS")
			(effects
				(font
					(size 0.7874 0.5842)
					(thickness 0.1524)
				)
				(justify left)
			)
		)
		(property "Value" ""
			(at 0 0 90)
			(layer "F.Fab")
			(effects
				(font
					(size 1.27 1.27)
				)
			)
		)
		(duplicate_pad_numbers_are_jumpers no)
		(fp_poly
			(pts
				(xy 0.3048 -0.1016) (xy 0.3048 0.9906) (xy -0.3048 0.9906) (xy -0.3048 -0.1016)
			)
			(stroke
				(width 0)
				(type default)
			)
			(fill no)
			(layer "F.CrtYd")
		)
		(fp_line
			(start 0.3048 -0.1016)
			(end -0.3048 -0.1016)
			(stroke
				(width 0.1)
				(type default)
			)
			(layer "F.Fab")
		)
		(fp_line
			(start -0.3048 -0.1016)
			(end -0.3048 0.9906)
			(stroke
				(width 0.1)
				(type default)
			)
			(layer "F.Fab")
		)
		(fp_line
			(start 0.3048 0.9906)
			(end 0.3048 -0.1016)
			(stroke
				(width 0.1)
				(type default)
			)
			(layer "F.Fab")
		)
		(fp_line
			(start -0.3048 0.9906)
			(end 0.3048 0.9906)
			(stroke
				(width 0.1)
				(type default)
			)
			(layer "F.Fab")
		)
		(pad "1" smd rect
			(at 0 0 90)
			(size 0.508 0.508)
			(layers "F.Cu" "F.Mask" "F.Paste")
			(net "VR_PVCCIN_CPU1_AIREF1")
		)
		(pad "2" smd rect
			(at 0 0.889 90)
			(size 0.508 0.508)
			(layers "F.Cu" "F.Mask" "F.Paste")
			(net "GND")
		)
		(zone
			(layer "F.Cu")
			(hatch none 0.5)
			(connect_pads
				(clearance 0)
			)
			(min_thickness 0.25)
			(keepout
				(tracks allowed)
				(vias not_allowed)
				(pads allowed)
				(copperpour not_allowed)
				(footprints allowed)
			)
			(placement
				(enabled no)
				(sheetname "")
			)
			(fill
				(thermal_gap 0.5)
				(thermal_bridge_width 0.5)
				(island_removal_mode 0)
			)
			(polygon
				(pts
					(xy 29.890466 -53.17363) (xy 29.890466 -53.68163) (xy 30.271466 -53.68163) (xy 30.271466 -53.17363)
				)
			)
		)
		(zone
			(layer "F.Cu")
			(hatch none 0.5)
			(connect_pads
				(clearance 0)
			)
			(min_thickness 0.25)
			(keepout
				(tracks not_allowed)
				(vias allowed)
				(pads allowed)
				(copperpour not_allowed)
				(footprints allowed)
			)
			(placement
				(enabled no)
				(sheetname "")
			)
			(fill
				(thermal_gap 0.5)
				(thermal_bridge_width 0.5)
				(island_removal_mode 0)
			)
			(polygon
				(pts
					(xy 30.271466 -53.17363) (xy 30.271466 -53.68163) (xy 29.890466 -53.68163) (xy 29.890466 -53.17363)
				)
			)
		)
	)
	(footprint ""
		(layer "F.Cu")
		(at 323.0245 -118.415816 -90)
		(property "Reference" "C833"
			(at -0.8382 -0.67818 270)
			(unlocked yes)
			(layer "F.SilkS")
			(effects
				(font
					(size 0.4064 0.254)
					(thickness 0.1524)
				)
				(justify left)
			)
		)
		(property "Value" ""
			(at 0 0 270)
			(layer "F.Fab")
			(effects
				(font
					(size 1.27 1.27)
				)
			)
		)
		(duplicate_pad_numbers_are_jumpers no)
		(fp_poly
			(pts
				(xy 0.3048 -0.1016) (xy 0.3048 0.9906) (xy -0.3048 0.9906) (xy -0.3048 -0.1016)
			)
			(stroke
				(width 0)
				(type default)
			)
			(fill no)
			(layer "F.CrtYd")
		)
		(fp_line
			(start -0.3048 0.9906)
			(end 0.3048 0.9906)
			(stroke
				(width 0.1)
				(type default)
			)
			(layer "F.Fab")
		)
		(fp_line
			(start 0.3048 0.9906)
			(end 0.3048 -0.1016)
			(stroke
				(width 0.1)
				(type default)
			)
			(layer "F.Fab")
		)
		(fp_line
			(start -0.3048 -0.1016)
			(end -0.3048 0.9906)
			(stroke
				(width 0.1)
				(type default)
			)
			(layer "F.Fab")
		)
		(fp_line
			(start 0.3048 -0.1016)
			(end -0.3048 -0.1016)
			(stroke
				(width 0.1)
				(type default)
			)
			(layer "F.Fab")
		)
		(pad "1" smd rect
			(at 0 0 270)
			(size 0.508 0.508)
			(layers "F.Cu" "F.Mask" "F.Paste")
			(net "P3E_CPU0_PE1_PCH_TXP<11>")
		)
		(pad "2" smd rect
			(at 0 0.889 270)
			(size 0.508 0.508)
			(layers "F.Cu" "F.Mask" "F.Paste")
			(net "P3E_CPU0_PE1_PCH_CON_TXP<11>")
		)
		(zone
			(layer "F.Cu")
			(hatch none 0.5)
			(connect_pads
				(clearance 0)
			)
			(min_thickness 0.25)
			(keepout
				(tracks not_allowed)
				(vias allowed)
				(pads allowed)
				(copperpour not_allowed)
				(footprints allowed)
			)
			(placement
				(enabled no)
				(sheetname "")
			)
			(fill
				(thermal_gap 0.5)
				(thermal_bridge_width 0.5)
				(island_removal_mode 0)
			)
			(polygon
				(pts
					(xy 322.3895 -118.669816) (xy 322.3895 -118.161816) (xy 322.7705 -118.161816) (xy 322.7705 -118.669816)
				)
			)
		)
		(zone
			(layer "F.Cu")
			(hatch none 0.5)
			(connect_pads
				(clearance 0)
			)
			(min_thickness 0.25)
			(keepout
				(tracks allowed)
				(vias not_allowed)
				(pads allowed)
				(copperpour not_allowed)
				(footprints allowed)
			)
			(placement
				(enabled no)
				(sheetname "")
			)
			(fill
				(thermal_gap 0.5)
				(thermal_bridge_width 0.5)
				(island_removal_mode 0)
			)
			(polygon
				(pts
					(xy 322.7705 -118.669816) (xy 322.7705 -118.161816) (xy 322.3895 -118.161816) (xy 322.3895 -118.669816)
				)
			)
		)
	)
	(footprint ""
		(layer "F.Cu")
		(at 360.622088 -142.03172 -90)
		(property "Reference" "RF18"
			(at -0.8382 -0.67818 270)
			(unlocked yes)
			(layer "F.SilkS")
			(effects
				(font
					(size 0.4064 0.254)
					(thickness 0.1524)
				)
				(justify left)
			)
		)
		(property "Value" ""
			(at 0 0 270)
			(layer "F.Fab")
			(effects
				(font
					(size 1.27 1.27)
				)
			)
		)
		(duplicate_pad_numbers_are_jumpers no)
		(fp_poly
			(pts
				(xy -0.2794 -0.1016) (xy 0.2794 -0.1016) (xy 0.2794 0.9906) (xy -0.2794 0.9906)
			)
			(stroke
				(width 0)
				(type default)
			)
			(fill no)
			(layer "F.CrtYd")
		)
		(fp_line
			(start -0.2794 0.9906)
			(end 0.2794 0.9906)
			(stroke
				(width 0.1)
				(type default)
			)
			(layer "F.Fab")
		)
		(fp_line
			(start 0.2794 0.9906)
			(end 0.2794 -0.1016)
			(stroke
				(width 0.1)
				(type default)
			)
			(layer "F.Fab")
		)
		(fp_line
			(start -0.2794 -0.1016)
			(end -0.2794 0.9906)
			(stroke
				(width 0.1)
				(type default)
			)
			(layer "F.Fab")
		)
		(fp_line
			(start 0.2794 -0.1016)
			(end -0.2794 -0.1016)
			(stroke
				(width 0.1)
				(type default)
			)
			(layer "F.Fab")
		)
		(pad "1" smd rect
			(at 0 0 270)
			(size 0.508 0.508)
			(layers "F.Cu" "F.Mask" "F.Paste")
			(net "VR_PVDDQ_DEF_AIREF2")
		)
		(pad "2" smd rect
			(at 0 0.889 270)
			(size 0.508 0.508)
			(layers "F.Cu" "F.Mask" "F.Paste")
			(net "ISENSE_PVDDQ_DEF_PH2_IMON")
		)
		(zone
			(layer "F.Cu")
			(hatch none 0.5)
			(connect_pads
				(clearance 0)
			)
			(min_thickness 0.25)
			(keepout
				(tracks not_allowed)
				(vias allowed)
				(pads allowed)
				(copperpour not_allowed)
				(footprints allowed)
			)
			(placement
				(enabled no)
				(sheetname "")
			)
			(fill
				(thermal_gap 0.5)
				(thermal_bridge_width 0.5)
				(island_removal_mode 0)
			)
			(polygon
				(pts
					(xy 359.987088 -142.28572) (xy 359.987088 -141.77772) (xy 360.368088 -141.77772) (xy 360.368088 -142.28572)
				)
			)
		)
		(zone
			(layer "F.Cu")
			(hatch none 0.5)
			(connect_pads
				(clearance 0)
			)
			(min_thickness 0.25)
			(keepout
				(tracks allowed)
				(vias not_allowed)
				(pads allowed)
				(copperpour not_allowed)
				(footprints allowed)
			)
			(placement
				(enabled no)
				(sheetname "")
			)
			(fill
				(thermal_gap 0.5)
				(thermal_bridge_width 0.5)
				(island_removal_mode 0)
			)
			(polygon
				(pts
					(xy 360.368088 -142.28572) (xy 360.368088 -141.77772) (xy 359.987088 -141.77772) (xy 359.987088 -142.28572)
				)
			)
		)
	)
	(footprint ""
		(layer "F.Cu")
		(at 28.380182 -149.7838 -90)
		(property "Reference" "C1A4"
			(at 0 0 270)
			(layer "F.SilkS")
			(hide yes)
			(effects
				(font
					(size 1.27 1.27)
				)
			)
		)
		(property "Value" ""
			(at 0 0 270)
			(layer "F.Fab")
			(effects
				(font
					(size 1.27 1.27)
				)
			)
		)
		(duplicate_pad_numbers_are_jumpers no)
		(fp_poly
			(pts
				(xy -0.7239 -0.2159) (xy 0.7239 -0.2159) (xy 0.7239 1.9939) (xy -0.7239 1.9939)
			)
			(stroke
				(width 0)
				(type default)
			)
			(fill no)
			(layer "F.CrtYd")
		)
		(fp_line
			(start -0.7239 1.9939)
			(end 0.7239 1.9939)
			(stroke
				(width 0.1)
				(type default)
			)
			(layer "F.Fab")
		)
		(fp_line
			(start 0.7239 1.9939)
			(end 0.7239 -0.2159)
			(stroke
				(width 0.1)
				(type default)
			)
			(layer "F.Fab")
		)
		(fp_line
			(start -0.7239 -0.2159)
			(end -0.7239 1.9939)
			(stroke
				(width 0.1)
				(type default)
			)
			(layer "F.Fab")
		)
		(fp_line
			(start 0.7239 -0.2159)
			(end -0.7239 -0.2159)
			(stroke
				(width 0.1)
				(type default)
			)
			(layer "F.Fab")
		)
		(pad "1" smd rect
			(at 0 0 270)
			(size 1.27 1.016)
			(layers "F.Cu" "F.Mask" "F.Paste")
			(net "P12V_NVDIMM_KLM")
		)
		(pad "2" smd rect
			(at 0 1.778 270)
			(size 1.27 1.016)
			(layers "F.Cu" "F.Mask" "F.Paste")
			(net "GND")
		)
		(zone
			(layer "F.Cu")
			(hatch none 0.5)
			(connect_pads
				(clearance 0)
			)
			(min_thickness 0.25)
			(keepout
				(tracks not_allowed)
				(vias allowed)
				(pads allowed)
				(copperpour not_allowed)
				(footprints allowed)
			)
			(placement
				(enabled no)
				(sheetname "")
			)
			(fill
				(thermal_gap 0.5)
				(thermal_bridge_width 0.5)
				(island_removal_mode 0)
			)
			(polygon
				(pts
					(xy 27.872182 -150.4188) (xy 27.872182 -149.1488) (xy 27.110182 -149.1488) (xy 27.110182 -150.4188)
				)
			)
		)
	)
	(footprint ""
		(layer "F.Cu")
		(at 5.909056 2.91846 90)
		(property "Reference" "CF20"
			(at 0 0 90)
			(layer "F.SilkS")
			(hide yes)
			(effects
				(font
					(size 1.27 1.27)
				)
			)
		)
		(property "Value" "*"
			(at 1.1811 -2.8194 90)
			(unlocked yes)
			(layer "F.Fab")
			(hide yes)
			(effects
				(font
					(size 1.27 1.016)
					(thickness 0.1524)
				)
			)
		)
		(property "Device Type" "SC22P50V2JN-4GP_SMD-BCG-SC22P5A"
			(at 1.1811 -4.3434 90)
			(unlocked yes)
			(layer "F.Fab")
			(hide yes)
			(effects
				(font
					(size 1.27 1.016)
					(thickness 0.1524)
				)
			)
		)
		(duplicate_pad_numbers_are_jumpers no)
		(fp_rect
			(start -0.4318 0.9525)
			(end 0.4318 -0.9525)
			(stroke
				(width 0)
				(type default)
			)
			(fill no)
			(layer "F.CrtYd")
		)
		(fp_rect
			(start -0.4318 0.9525)
			(end 0.4318 -0.9525)
			(stroke
				(width 0)
				(type default)
			)
			(fill no)
			(layer "F.Fab")
		)
		(pad "1" smd custom
			(at 0 -0.4445 90)
			(size 0.1524 0.1524)
			(layers "F.Cu" "F.Mask" "F.Paste")
			(net "VR_PVDDQ_GHJ_AIREF2")
			(options
				(clearance outline)
				(anchor circle)
			)
			(primitives
				(gr_poly
					(pts
						(arc
							(start 0.3048 -0.2032)
							(mid 0.275042 -0.275042)
							(end 0.2032 -0.3048)
						)
						(arc
							(start -0.2032 -0.3048)
							(mid -0.275042 -0.275042)
							(end -0.3048 -0.2032)
						)
						(arc
							(start -0.3048 0.2032)
							(mid -0.275042 0.275042)
							(end -0.2032 0.3048)
						)
						(arc
							(start 0.2032 0.3048)
							(mid 0.275042 0.275042)
							(end 0.3048 0.2032)
						)
					)
					(width 0)
					(fill yes)
				)
			)
		)
		(pad "2" smd custom
			(at 0 0.4445 90)
			(size 0.1524 0.1524)
			(layers "F.Cu" "F.Mask" "F.Paste")
			(net "ISENSE_PVDDQ_GHJ_PH2_IMON")
			(options
				(clearance outline)
				(anchor circle)
			)
			(primitives
				(gr_poly
					(pts
						(arc
							(start 0.3048 -0.2032)
							(mid 0.275042 -0.275042)
							(end 0.2032 -0.3048)
						)
						(arc
							(start -0.2032 -0.3048)
							(mid -0.275042 -0.275042)
							(end -0.3048 -0.2032)
						)
						(arc
							(start -0.3048 0.2032)
							(mid -0.275042 0.275042)
							(end -0.2032 0.3048)
						)
						(arc
							(start 0.2032 0.3048)
							(mid 0.275042 0.275042)
							(end 0.3048 0.2032)
						)
					)
					(width 0)
					(fill yes)
				)
			)
		)
	)
	(footprint ""
		(layer "F.Cu")
		(at 364.617 -110.998 90)
		(property "Reference" "C7C1"
			(at 0 0 90)
			(layer "F.SilkS")
			(hide yes)
			(effects
				(font
					(size 1.27 1.27)
				)
			)
		)
		(property "Value" ""
			(at 0 0 90)
			(layer "F.Fab")
			(effects
				(font
					(size 1.27 1.27)
				)
			)
		)
		(duplicate_pad_numbers_are_jumpers no)
		(fp_poly
			(pts
				(xy 0.3048 -0.1016) (xy 0.3048 0.9906) (xy -0.3048 0.9906) (xy -0.3048 -0.1016)
			)
			(stroke
				(width 0)
				(type default)
			)
			(fill no)
			(layer "F.CrtYd")
		)
		(fp_line
			(start 0.3048 -0.1016)
			(end -0.3048 -0.1016)
			(stroke
				(width 0.1)
				(type default)
			)
			(layer "F.Fab")
		)
		(fp_line
			(start -0.3048 -0.1016)
			(end -0.3048 0.9906)
			(stroke
				(width 0.1)
				(type default)
			)
			(layer "F.Fab")
		)
		(fp_line
			(start 0.3048 0.9906)
			(end 0.3048 -0.1016)
			(stroke
				(width 0.1)
				(type default)
			)
			(layer "F.Fab")
		)
		(fp_line
			(start -0.3048 0.9906)
			(end 0.3048 0.9906)
			(stroke
				(width 0.1)
				(type default)
			)
			(layer "F.Fab")
		)
		(pad "1" smd rect
			(at 0 0 90)
			(size 0.508 0.508)
			(layers "F.Cu" "F.Mask" "F.Paste")
			(net "DMI_CPU0_PCH_TX_DN<1>")
		)
		(pad "2" smd rect
			(at 0 0.889 90)
			(size 0.508 0.508)
			(layers "F.Cu" "F.Mask" "F.Paste")
			(net "DMI_CPU0_PCH_TX_C_DN<1>")
		)
		(zone
			(layer "F.Cu")
			(hatch none 0.5)
			(connect_pads
				(clearance 0)
			)
			(min_thickness 0.25)
			(keepout
				(tracks allowed)
				(vias not_allowed)
				(pads allowed)
				(copperpour not_allowed)
				(footprints allowed)
			)
			(placement
				(enabled no)
				(sheetname "")
			)
			(fill
				(thermal_gap 0.5)
				(thermal_bridge_width 0.5)
				(island_removal_mode 0)
			)
			(polygon
				(pts
					(xy 364.871 -110.744) (xy 364.871 -111.252) (xy 365.252 -111.252) (xy 365.252 -110.744)
				)
			)
		)
		(zone
			(layer "F.Cu")
			(hatch none 0.5)
			(connect_pads
				(clearance 0)
			)
			(min_thickness 0.25)
			(keepout
				(tracks not_allowed)
				(vias allowed)
				(pads allowed)
				(copperpour not_allowed)
				(footprints allowed)
			)
			(placement
				(enabled no)
				(sheetname "")
			)
			(fill
				(thermal_gap 0.5)
				(thermal_bridge_width 0.5)
				(island_removal_mode 0)
			)
			(polygon
				(pts
					(xy 365.252 -110.744) (xy 365.252 -111.252) (xy 364.871 -111.252) (xy 364.871 -110.744)
				)
			)
		)
	)
	(footprint ""
		(layer "F.Cu")
		(at 347.599 -93.761306 -90)
		(property "Reference" "C7C11"
			(at 0 0 270)
			(layer "F.SilkS")
			(hide yes)
			(effects
				(font
					(size 1.27 1.27)
				)
			)
		)
		(property "Value" ""
			(at 0 0 270)
			(layer "F.Fab")
			(effects
				(font
					(size 1.27 1.27)
				)
			)
		)
		(duplicate_pad_numbers_are_jumpers no)
		(fp_poly
			(pts
				(xy 0.3048 -0.1016) (xy 0.3048 0.9906) (xy -0.3048 0.9906) (xy -0.3048 -0.1016)
			)
			(stroke
				(width 0)
				(type default)
			)
			(fill no)
			(layer "F.CrtYd")
		)
		(fp_line
			(start -0.3048 0.9906)
			(end 0.3048 0.9906)
			(stroke
				(width 0.1)
				(type default)
			)
			(layer "F.Fab")
		)
		(fp_line
			(start 0.3048 0.9906)
			(end 0.3048 -0.1016)
			(stroke
				(width 0.1)
				(type default)
			)
			(layer "F.Fab")
		)
		(fp_line
			(start -0.3048 -0.1016)
			(end -0.3048 0.9906)
			(stroke
				(width 0.1)
				(type default)
			)
			(layer "F.Fab")
		)
		(fp_line
			(start 0.3048 -0.1016)
			(end -0.3048 -0.1016)
			(stroke
				(width 0.1)
				(type default)
			)
			(layer "F.Fab")
		)
		(pad "1" smd rect
			(at 0 0 270)
			(size 0.508 0.508)
			(layers "F.Cu" "F.Mask" "F.Paste")
			(net "VR_FET_SW_P12V_STBY_PVCCIO_CPU0")
		)
		(pad "2" smd rect
			(at 0 0.889 270)
			(size 0.508 0.508)
			(layers "F.Cu" "F.Mask" "F.Paste")
			(net "GND")
		)
		(zone
			(layer "F.Cu")
			(hatch none 0.5)
			(connect_pads
				(clearance 0)
			)
			(min_thickness 0.25)
			(keepout
				(tracks not_allowed)
				(vias allowed)
				(pads allowed)
				(copperpour not_allowed)
				(footprints allowed)
			)
			(placement
				(enabled no)
				(sheetname "")
			)
			(fill
				(thermal_gap 0.5)
				(thermal_bridge_width 0.5)
				(island_removal_mode 0)
			)
			(polygon
				(pts
					(xy 346.964 -94.015306) (xy 346.964 -93.507306) (xy 347.345 -93.507306) (xy 347.345 -94.015306)
				)
			)
		)
		(zone
			(layer "F.Cu")
			(hatch none 0.5)
			(connect_pads
				(clearance 0)
			)
			(min_thickness 0.25)
			(keepout
				(tracks allowed)
				(vias not_allowed)
				(pads allowed)
				(copperpour not_allowed)
				(footprints allowed)
			)
			(placement
				(enabled no)
				(sheetname "")
			)
			(fill
				(thermal_gap 0.5)
				(thermal_bridge_width 0.5)
				(island_removal_mode 0)
			)
			(polygon
				(pts
					(xy 347.345 -94.015306) (xy 347.345 -93.507306) (xy 346.964 -93.507306) (xy 346.964 -94.015306)
				)
			)
		)
	)
	(footprint ""
		(layer "F.Cu")
		(at 408.8765 -105.664 -90)
		(property "Reference" "R8C17"
			(at 0 0 270)
			(layer "F.SilkS")
			(hide yes)
			(effects
				(font
					(size 1.27 1.27)
				)
			)
		)
		(property "Value" ""
			(at 0 0 270)
			(layer "F.Fab")
			(effects
				(font
					(size 1.27 1.27)
				)
			)
		)
		(duplicate_pad_numbers_are_jumpers no)
		(fp_poly
			(pts
				(xy -0.2794 -0.1016) (xy 0.2794 -0.1016) (xy 0.2794 0.9906) (xy -0.2794 0.9906)
			)
			(stroke
				(width 0)
				(type default)
			)
			(fill no)
			(layer "F.CrtYd")
		)
		(fp_line
			(start -0.2794 0.9906)
			(end 0.2794 0.9906)
			(stroke
				(width 0.1)
				(type default)
			)
			(layer "F.Fab")
		)
		(fp_line
			(start 0.2794 0.9906)
			(end 0.2794 -0.1016)
			(stroke
				(width 0.1)
				(type default)
			)
			(layer "F.Fab")
		)
		(fp_line
			(start -0.2794 -0.1016)
			(end -0.2794 0.9906)
			(stroke
				(width 0.1)
				(type default)
			)
			(layer "F.Fab")
		)
		(fp_line
			(start 0.2794 -0.1016)
			(end -0.2794 -0.1016)
			(stroke
				(width 0.1)
				(type default)
			)
			(layer "F.Fab")
		)
		(pad "1" smd rect
			(at 0 0 270)
			(size 0.508 0.508)
			(layers "F.Cu" "F.Mask" "F.Paste")
			(net "PU_PCH_TLS_ENABLE_STRAP")
		)
		(pad "2" smd rect
			(at 0 0.889 270)
			(size 0.508 0.508)
			(layers "F.Cu" "F.Mask" "F.Paste")
			(net "GND")
		)
		(zone
			(layer "F.Cu")
			(hatch none 0.5)
			(connect_pads
				(clearance 0)
			)
			(min_thickness 0.25)
			(keepout
				(tracks not_allowed)
				(vias allowed)
				(pads allowed)
				(copperpour not_allowed)
				(footprints allowed)
			)
			(placement
				(enabled no)
				(sheetname "")
			)
			(fill
				(thermal_gap 0.5)
				(thermal_bridge_width 0.5)
				(island_removal_mode 0)
			)
			(polygon
				(pts
					(xy 408.2415 -105.918) (xy 408.2415 -105.41) (xy 408.6225 -105.41) (xy 408.6225 -105.918)
				)
			)
		)
		(zone
			(layer "F.Cu")
			(hatch none 0.5)
			(connect_pads
				(clearance 0)
			)
			(min_thickness 0.25)
			(keepout
				(tracks allowed)
				(vias not_allowed)
				(pads allowed)
				(copperpour not_allowed)
				(footprints allowed)
			)
			(placement
				(enabled no)
				(sheetname "")
			)
			(fill
				(thermal_gap 0.5)
				(thermal_bridge_width 0.5)
				(island_removal_mode 0)
			)
			(polygon
				(pts
					(xy 408.6225 -105.918) (xy 408.6225 -105.41) (xy 408.2415 -105.41) (xy 408.2415 -105.918)
				)
			)
		)
	)
	(footprint ""
		(layer "F.Cu")
		(at 259.1054 -149.7838 90)
		(property "Reference" "C5A10"
			(at 0 0 90)
			(layer "F.SilkS")
			(hide yes)
			(effects
				(font
					(size 1.27 1.27)
				)
			)
		)
		(property "Value" ""
			(at 0 0 90)
			(layer "F.Fab")
			(effects
				(font
					(size 1.27 1.27)
				)
			)
		)
		(duplicate_pad_numbers_are_jumpers no)
		(fp_rect
			(start -0.7239 -0.2159)
			(end 0.7239 1.9939)
			(stroke
				(width 0)
				(type default)
			)
			(fill no)
			(layer "F.CrtYd")
		)
		(fp_line
			(start 0.7239 -0.2159)
			(end -0.7239 -0.2159)
			(stroke
				(width 0.1)
				(type default)
			)
			(layer "F.Fab")
		)
		(fp_line
			(start -0.7239 -0.2159)
			(end -0.7239 1.9939)
			(stroke
				(width 0.1)
				(type default)
			)
			(layer "F.Fab")
		)
		(fp_line
			(start 0.7239 1.9939)
			(end 0.7239 -0.2159)
			(stroke
				(width 0.1)
				(type default)
			)
			(layer "F.Fab")
		)
		(fp_line
			(start -0.7239 1.9939)
			(end 0.7239 1.9939)
			(stroke
				(width 0.1)
				(type default)
			)
			(layer "F.Fab")
		)
		(pad "1" smd rect
			(at 0 0 90)
			(size 1.27 1.016)
			(layers "F.Cu" "F.Mask" "F.Paste")
			(net "PVDDQ_DEF")
		)
		(pad "2" smd rect
			(at 0 1.778 90)
			(size 1.27 1.016)
			(layers "F.Cu" "F.Mask" "F.Paste")
			(net "GND")
		)
		(zone
			(layer "F.Cu")
			(hatch none 0.5)
			(connect_pads
				(clearance 0)
			)
			(min_thickness 0.25)
			(keepout
				(tracks not_allowed)
				(vias allowed)
				(pads allowed)
				(copperpour not_allowed)
				(footprints allowed)
			)
			(placement
				(enabled no)
				(sheetname "")
			)
			(fill
				(thermal_gap 0.5)
				(thermal_bridge_width 0.5)
				(island_removal_mode 0)
			)
			(polygon
				(pts
					(xy 259.6134 -149.1488) (xy 260.3754 -149.1488) (xy 260.3754 -150.4188) (xy 259.6134 -150.4188)
				)
			)
		)
	)
	(footprint ""
		(layer "F.Cu")
		(at 30.528768 -149.6568 90)
		(property "Reference" "C1A5"
			(at 0 0 90)
			(layer "F.SilkS")
			(hide yes)
			(effects
				(font
					(size 1.27 1.27)
				)
			)
		)
		(property "Value" ""
			(at 0 0 90)
			(layer "F.Fab")
			(effects
				(font
					(size 1.27 1.27)
				)
			)
		)
		(duplicate_pad_numbers_are_jumpers no)
		(fp_poly
			(pts
				(xy 0.3048 -0.1016) (xy 0.3048 0.9906) (xy -0.3048 0.9906) (xy -0.3048 -0.1016)
			)
			(stroke
				(width 0)
				(type default)
			)
			(fill no)
			(layer "F.CrtYd")
		)
		(fp_line
			(start 0.3048 -0.1016)
			(end -0.3048 -0.1016)
			(stroke
				(width 0.1)
				(type default)
			)
			(layer "F.Fab")
		)
		(fp_line
			(start -0.3048 -0.1016)
			(end -0.3048 0.9906)
			(stroke
				(width 0.1)
				(type default)
			)
			(layer "F.Fab")
		)
		(fp_line
			(start 0.3048 0.9906)
			(end 0.3048 -0.1016)
			(stroke
				(width 0.1)
				(type default)
			)
			(layer "F.Fab")
		)
		(fp_line
			(start -0.3048 0.9906)
			(end 0.3048 0.9906)
			(stroke
				(width 0.1)
				(type default)
			)
			(layer "F.Fab")
		)
		(pad "1" smd rect
			(at 0 0 90)
			(size 0.508 0.508)
			(layers "F.Cu" "F.Mask" "F.Paste")
			(net "M_M_VREF")
		)
		(pad "2" smd rect
			(at 0 0.889 90)
			(size 0.508 0.508)
			(layers "F.Cu" "F.Mask" "F.Paste")
			(net "GND")
		)
		(zone
			(layer "F.Cu")
			(hatch none 0.5)
			(connect_pads
				(clearance 0)
			)
			(min_thickness 0.25)
			(keepout
				(tracks allowed)
				(vias not_allowed)
				(pads allowed)
				(copperpour not_allowed)
				(footprints allowed)
			)
			(placement
				(enabled no)
				(sheetname "")
			)
			(fill
				(thermal_gap 0.5)
				(thermal_bridge_width 0.5)
				(island_removal_mode 0)
			)
			(polygon
				(pts
					(xy 30.782768 -149.4028) (xy 30.782768 -149.9108) (xy 31.163768 -149.9108) (xy 31.163768 -149.4028)
				)
			)
		)
		(zone
			(layer "F.Cu")
			(hatch none 0.5)
			(connect_pads
				(clearance 0)
			)
			(min_thickness 0.25)
			(keepout
				(tracks not_allowed)
				(vias allowed)
				(pads allowed)
				(copperpour not_allowed)
				(footprints allowed)
			)
			(placement
				(enabled no)
				(sheetname "")
			)
			(fill
				(thermal_gap 0.5)
				(thermal_bridge_width 0.5)
				(island_removal_mode 0)
			)
			(polygon
				(pts
					(xy 31.163768 -149.4028) (xy 31.163768 -149.9108) (xy 30.782768 -149.9108) (xy 30.782768 -149.4028)
				)
			)
		)
	)
	(footprint ""
		(layer "F.Cu")
		(at 414.528 -16.383)
		(property "Reference" "S8E1"
			(at -2.31267 3.3274 270)
			(unlocked yes)
			(layer "F.SilkS")
			(effects
				(font
					(size 0.7874 0.5842)
					(thickness 0.1524)
				)
			)
		)
		(property "Value" ""
			(at 0 0 0)
			(layer "F.Fab")
			(effects
				(font
					(size 1.27 1.27)
				)
			)
		)
		(duplicate_pad_numbers_are_jumpers no)
		(fp_line
			(start -1.6256 0.0381)
			(end -0.954278 0.0381)
			(stroke
				(width 0.1524)
				(type default)
			)
			(layer "F.SilkS")
		)
		(fp_line
			(start -1.6256 4.2799)
			(end -1.6256 0.0381)
			(stroke
				(width 0.1524)
				(type default)
			)
			(layer "F.SilkS")
		)
		(fp_line
			(start -1.6256 4.2799)
			(end -0.954024 4.2799)
			(stroke
				(width 0.1524)
				(type default)
			)
			(layer "F.SilkS")
		)
		(fp_line
			(start 1.6256 0.0381)
			(end 0.953262 0.0381)
			(stroke
				(width 0.1524)
				(type default)
			)
			(layer "F.SilkS")
		)
		(fp_line
			(start 1.6256 0.0381)
			(end 1.6256 4.2799)
			(stroke
				(width 0.1524)
				(type default)
			)
			(layer "F.SilkS")
		)
		(fp_line
			(start 1.6256 4.2799)
			(end 0.954024 4.2799)
			(stroke
				(width 0.1524)
				(type default)
			)
			(layer "F.SilkS")
		)
		(fp_circle
			(center -1.177036 -0.999998)
			(end -1.050036 -0.999998)
			(stroke
				(width 0.254)
				(type default)
			)
			(fill no)
			(layer "F.SilkS")
		)
		(fp_poly
			(pts
				(xy -1.6256 0.0381) (xy -1.6256 4.2799) (xy 1.6256 4.2799) (xy 1.6256 0.0381)
			)
			(stroke
				(width 0)
				(type default)
			)
			(fill no)
			(layer "F.CrtYd")
		)
		(fp_line
			(start -1.6256 0.0381)
			(end 1.6256 0.0381)
			(stroke
				(width 0.1)
				(type default)
			)
			(layer "F.Fab")
		)
		(fp_line
			(start -1.6256 4.2799)
			(end -1.6256 0.0381)
			(stroke
				(width 0.1)
				(type default)
			)
			(layer "F.Fab")
		)
		(fp_line
			(start 1.6256 0.0381)
			(end 1.6256 4.2799)
			(stroke
				(width 0.1)
				(type default)
			)
			(layer "F.Fab")
		)
		(fp_line
			(start 1.6256 4.2799)
			(end -1.6256 4.2799)
			(stroke
				(width 0.1)
				(type default)
			)
			(layer "F.Fab")
		)
		(fp_circle
			(center -1.208786 -1.23698)
			(end -1.081786 -1.23698)
			(stroke
				(width 0.254)
				(type default)
			)
			(fill no)
			(layer "F.Fab")
		)
		(pad "1" smd rect
			(at 0 0)
			(size 1.2446 1.7272)
			(layers "F.Cu" "F.Mask" "F.Paste")
			(net "GND")
		)
		(pad "2" smd rect
			(at 0 4.318)
			(size 1.2446 1.7272)
			(layers "F.Cu" "F.Mask" "F.Paste")
			(net "FP_NMI_BTN_OUT_R_N")
		)
	)
	(footprint ""
		(layer "F.Cu")
		(at 17.9832 -79.6417 180)
		(property "Reference" "R1D26"
			(at 0 0 180)
			(layer "F.SilkS")
			(hide yes)
			(effects
				(font
					(size 1.27 1.27)
				)
			)
		)
		(property "Value" ""
			(at 0 0 180)
			(layer "F.Fab")
			(effects
				(font
					(size 1.27 1.27)
				)
			)
		)
		(duplicate_pad_numbers_are_jumpers no)
		(fp_poly
			(pts
				(xy -0.2794 -0.1016) (xy 0.2794 -0.1016) (xy 0.2794 0.9906) (xy -0.2794 0.9906)
			)
			(stroke
				(width 0)
				(type default)
			)
			(fill no)
			(layer "F.CrtYd")
		)
		(fp_line
			(start 0.2794 0.9906)
			(end 0.2794 -0.1016)
			(stroke
				(width 0.1)
				(type default)
			)
			(layer "F.Fab")
		)
		(fp_line
			(start 0.2794 -0.1016)
			(end -0.2794 -0.1016)
			(stroke
				(width 0.1)
				(type default)
			)
			(layer "F.Fab")
		)
		(fp_line
			(start -0.2794 0.9906)
			(end 0.2794 0.9906)
			(stroke
				(width 0.1)
				(type default)
			)
			(layer "F.Fab")
		)
		(fp_line
			(start -0.2794 -0.1016)
			(end -0.2794 0.9906)
			(stroke
				(width 0.1)
				(type default)
			)
			(layer "F.Fab")
		)
		(pad "1" smd rect
			(at 0 0 180)
			(size 0.508 0.508)
			(layers "F.Cu" "F.Mask" "F.Paste")
			(net "IRQ_SML1_PMBUS_ALERT_R_N")
		)
		(pad "2" smd rect
			(at 0 0.889 180)
			(size 0.508 0.508)
			(layers "F.Cu" "F.Mask" "F.Paste")
			(net "IRQ_SML1_PMBUS_ALERT_N")
		)
		(zone
			(layer "F.Cu")
			(hatch none 0.5)
			(connect_pads
				(clearance 0)
			)
			(min_thickness 0.25)
			(keepout
				(tracks not_allowed)
				(vias allowed)
				(pads allowed)
				(copperpour not_allowed)
				(footprints allowed)
			)
			(placement
				(enabled no)
				(sheetname "")
			)
			(fill
				(thermal_gap 0.5)
				(thermal_bridge_width 0.5)
				(island_removal_mode 0)
			)
			(polygon
				(pts
					(xy 18.2372 -80.2767) (xy 17.7292 -80.2767) (xy 17.7292 -79.8957) (xy 18.2372 -79.8957)
				)
			)
		)
		(zone
			(layer "F.Cu")
			(hatch none 0.5)
			(connect_pads
				(clearance 0)
			)
			(min_thickness 0.25)
			(keepout
				(tracks allowed)
				(vias not_allowed)
				(pads allowed)
				(copperpour not_allowed)
				(footprints allowed)
			)
			(placement
				(enabled no)
				(sheetname "")
			)
			(fill
				(thermal_gap 0.5)
				(thermal_bridge_width 0.5)
				(island_removal_mode 0)
			)
			(polygon
				(pts
					(xy 18.2372 -79.8957) (xy 17.7292 -79.8957) (xy 17.7292 -80.2767) (xy 18.2372 -80.2767)
				)
			)
		)
	)
	(footprint ""
		(layer "F.Cu")
		(at 418.554408 -48.953166)
		(property "Reference" "R1T15"
			(at -0.8382 -0.67818 0)
			(unlocked yes)
			(layer "F.SilkS")
			(effects
				(font
					(size 0.4064 0.254)
					(thickness 0.1524)
				)
				(justify left)
			)
		)
		(property "Value" ""
			(at 0 0 0)
			(layer "F.Fab")
			(effects
				(font
					(size 1.27 1.27)
				)
			)
		)
		(duplicate_pad_numbers_are_jumpers no)
		(fp_poly
			(pts
				(xy -0.2794 -0.1016) (xy 0.2794 -0.1016) (xy 0.2794 0.9906) (xy -0.2794 0.9906)
			)
			(stroke
				(width 0)
				(type default)
			)
			(fill no)
			(layer "F.CrtYd")
		)
		(fp_line
			(start -0.2794 -0.1016)
			(end -0.2794 0.9906)
			(stroke
				(width 0.1)
				(type default)
			)
			(layer "F.Fab")
		)
		(fp_line
			(start -0.2794 0.9906)
			(end 0.2794 0.9906)
			(stroke
				(width 0.1)
				(type default)
			)
			(layer "F.Fab")
		)
		(fp_line
			(start 0.2794 -0.1016)
			(end -0.2794 -0.1016)
			(stroke
				(width 0.1)
				(type default)
			)
			(layer "F.Fab")
		)
		(fp_line
			(start 0.2794 0.9906)
			(end 0.2794 -0.1016)
			(stroke
				(width 0.1)
				(type default)
			)
			(layer "F.Fab")
		)
		(pad "1" smd rect
			(at 0 0)
			(size 0.508 0.508)
			(layers "F.Cu" "F.Mask" "F.Paste")
			(net "FM_BMC_ONCTL_N")
		)
		(pad "2" smd rect
			(at 0 0.889)
			(size 0.508 0.508)
			(layers "F.Cu" "F.Mask" "F.Paste")
			(net "FM_BMC_ONCTL_R_N")
		)
		(zone
			(layer "F.Cu")
			(hatch none 0.5)
			(connect_pads
				(clearance 0)
			)
			(min_thickness 0.25)
			(keepout
				(tracks allowed)
				(vias not_allowed)
				(pads allowed)
				(copperpour not_allowed)
				(footprints allowed)
			)
			(placement
				(enabled no)
				(sheetname "")
			)
			(fill
				(thermal_gap 0.5)
				(thermal_bridge_width 0.5)
				(island_removal_mode 0)
			)
			(polygon
				(pts
					(xy 418.300408 -48.699166) (xy 418.808408 -48.699166) (xy 418.808408 -48.318166) (xy 418.300408 -48.318166)
				)
			)
		)
		(zone
			(layer "F.Cu")
			(hatch none 0.5)
			(connect_pads
				(clearance 0)
			)
			(min_thickness 0.25)
			(keepout
				(tracks not_allowed)
				(vias allowed)
				(pads allowed)
				(copperpour not_allowed)
				(footprints allowed)
			)
			(placement
				(enabled no)
				(sheetname "")
			)
			(fill
				(thermal_gap 0.5)
				(thermal_bridge_width 0.5)
				(island_removal_mode 0)
			)
			(polygon
				(pts
					(xy 418.300408 -48.318166) (xy 418.808408 -48.318166) (xy 418.808408 -48.699166) (xy 418.300408 -48.699166)
				)
			)
		)
	)
	(footprint ""
		(layer "F.Cu")
		(at 320.6115 -123.317 90)
		(property "Reference" "C6B5"
			(at -0.8382 -0.67818 90)
			(unlocked yes)
			(layer "F.SilkS")
			(effects
				(font
					(size 0.4064 0.254)
					(thickness 0.1524)
				)
				(justify left)
			)
		)
		(property "Value" ""
			(at 0 0 90)
			(layer "F.Fab")
			(effects
				(font
					(size 1.27 1.27)
				)
			)
		)
		(duplicate_pad_numbers_are_jumpers no)
		(fp_poly
			(pts
				(xy 0.3048 -0.1016) (xy 0.3048 0.9906) (xy -0.3048 0.9906) (xy -0.3048 -0.1016)
			)
			(stroke
				(width 0)
				(type default)
			)
			(fill no)
			(layer "F.CrtYd")
		)
		(fp_line
			(start 0.3048 -0.1016)
			(end -0.3048 -0.1016)
			(stroke
				(width 0.1)
				(type default)
			)
			(layer "F.Fab")
		)
		(fp_line
			(start -0.3048 -0.1016)
			(end -0.3048 0.9906)
			(stroke
				(width 0.1)
				(type default)
			)
			(layer "F.Fab")
		)
		(fp_line
			(start 0.3048 0.9906)
			(end 0.3048 -0.1016)
			(stroke
				(width 0.1)
				(type default)
			)
			(layer "F.Fab")
		)
		(fp_line
			(start -0.3048 0.9906)
			(end 0.3048 0.9906)
			(stroke
				(width 0.1)
				(type default)
			)
			(layer "F.Fab")
		)
		(pad "1" smd rect
			(at 0 0 90)
			(size 0.508 0.508)
			(layers "F.Cu" "F.Mask" "F.Paste")
			(net "P3E_CPU0_PE1_PCH_TXP<15>")
		)
		(pad "2" smd rect
			(at 0 0.889 90)
			(size 0.508 0.508)
			(layers "F.Cu" "F.Mask" "F.Paste")
			(net "P3E_CPU0_PE1_PCH_C_TXP<15>")
		)
		(zone
			(layer "F.Cu")
			(hatch none 0.5)
			(connect_pads
				(clearance 0)
			)
			(min_thickness 0.25)
			(keepout
				(tracks allowed)
				(vias not_allowed)
				(pads allowed)
				(copperpour not_allowed)
				(footprints allowed)
			)
			(placement
				(enabled no)
				(sheetname "")
			)
			(fill
				(thermal_gap 0.5)
				(thermal_bridge_width 0.5)
				(island_removal_mode 0)
			)
			(polygon
				(pts
					(xy 320.8655 -123.063) (xy 320.8655 -123.571) (xy 321.2465 -123.571) (xy 321.2465 -123.063)
				)
			)
		)
		(zone
			(layer "F.Cu")
			(hatch none 0.5)
			(connect_pads
				(clearance 0)
			)
			(min_thickness 0.25)
			(keepout
				(tracks not_allowed)
				(vias allowed)
				(pads allowed)
				(copperpour not_allowed)
				(footprints allowed)
			)
			(placement
				(enabled no)
				(sheetname "")
			)
			(fill
				(thermal_gap 0.5)
				(thermal_bridge_width 0.5)
				(island_removal_mode 0)
			)
			(polygon
				(pts
					(xy 321.2465 -123.063) (xy 321.2465 -123.571) (xy 320.8655 -123.571) (xy 320.8655 -123.063)
				)
			)
		)
	)
	(footprint ""
		(layer "F.Cu")
		(at 394.6525 -76.581 90)
		(property "Reference" "R7D31"
			(at 0 0 90)
			(layer "F.SilkS")
			(hide yes)
			(effects
				(font
					(size 1.27 1.27)
				)
			)
		)
		(property "Value" ""
			(at 0 0 90)
			(layer "F.Fab")
			(effects
				(font
					(size 1.27 1.27)
				)
			)
		)
		(duplicate_pad_numbers_are_jumpers no)
		(fp_poly
			(pts
				(xy -0.2794 -0.1016) (xy 0.2794 -0.1016) (xy 0.2794 0.9906) (xy -0.2794 0.9906)
			)
			(stroke
				(width 0)
				(type default)
			)
			(fill no)
			(layer "F.CrtYd")
		)
		(fp_line
			(start 0.2794 -0.1016)
			(end -0.2794 -0.1016)
			(stroke
				(width 0.1)
				(type default)
			)
			(layer "F.Fab")
		)
		(fp_line
			(start -0.2794 -0.1016)
			(end -0.2794 0.9906)
			(stroke
				(width 0.1)
				(type default)
			)
			(layer "F.Fab")
		)
		(fp_line
			(start 0.2794 0.9906)
			(end 0.2794 -0.1016)
			(stroke
				(width 0.1)
				(type default)
			)
			(layer "F.Fab")
		)
		(fp_line
			(start -0.2794 0.9906)
			(end 0.2794 0.9906)
			(stroke
				(width 0.1)
				(type default)
			)
			(layer "F.Fab")
		)
		(pad "1" smd rect
			(at 0 0 90)
			(size 0.508 0.508)
			(layers "F.Cu" "F.Mask" "F.Paste")
			(net "FM_CPU_ERR2_LVT3_R_N")
		)
		(pad "2" smd rect
			(at 0 0.889 90)
			(size 0.508 0.508)
			(layers "F.Cu" "F.Mask" "F.Paste")
			(net "FM_CPU_ERR2_LVT3_N")
		)
		(zone
			(layer "F.Cu")
			(hatch none 0.5)
			(connect_pads
				(clearance 0)
			)
			(min_thickness 0.25)
			(keepout
				(tracks allowed)
				(vias not_allowed)
				(pads allowed)
				(copperpour not_allowed)
				(footprints allowed)
			)
			(placement
				(enabled no)
				(sheetname "")
			)
			(fill
				(thermal_gap 0.5)
				(thermal_bridge_width 0.5)
				(island_removal_mode 0)
			)
			(polygon
				(pts
					(xy 394.9065 -76.327) (xy 394.9065 -76.835) (xy 395.2875 -76.835) (xy 395.2875 -76.327)
				)
			)
		)
		(zone
			(layer "F.Cu")
			(hatch none 0.5)
			(connect_pads
				(clearance 0)
			)
			(min_thickness 0.25)
			(keepout
				(tracks not_allowed)
				(vias allowed)
				(pads allowed)
				(copperpour not_allowed)
				(footprints allowed)
			)
			(placement
				(enabled no)
				(sheetname "")
			)
			(fill
				(thermal_gap 0.5)
				(thermal_bridge_width 0.5)
				(island_removal_mode 0)
			)
			(polygon
				(pts
					(xy 395.2875 -76.327) (xy 395.2875 -76.835) (xy 394.9065 -76.835) (xy 394.9065 -76.327)
				)
			)
		)
	)
	(footprint ""
		(layer "F.Cu")
		(at 253.392432 -12.954 90)
		(property "Reference" "C5G4"
			(at 1.848866 0.752348 90)
			(unlocked yes)
			(layer "F.SilkS")
			(effects
				(font
					(size 1.27 0.9652)
					(thickness 0.1524)
				)
			)
		)
		(property "Value" ""
			(at 0 0 90)
			(layer "F.Fab")
			(effects
				(font
					(size 1.27 1.27)
				)
			)
		)
		(duplicate_pad_numbers_are_jumpers no)
		(fp_rect
			(start -0.500126 1.598422)
			(end 0.500126 -0.201422)
			(stroke
				(width 0)
				(type default)
			)
			(fill no)
			(layer "F.CrtYd")
		)
		(fp_line
			(start 0.500126 -0.201422)
			(end 0.500126 1.598422)
			(stroke
				(width 0.1)
				(type default)
			)
			(layer "F.Fab")
		)
		(fp_line
			(start -0.500126 -0.201422)
			(end 0.500126 -0.201422)
			(stroke
				(width 0.1)
				(type default)
			)
			(layer "F.Fab")
		)
		(fp_line
			(start 0.500126 1.598422)
			(end -0.500126 1.598422)
			(stroke
				(width 0.1)
				(type default)
			)
			(layer "F.Fab")
		)
		(fp_line
			(start -0.500126 1.598422)
			(end -0.500126 -0.201422)
			(stroke
				(width 0.1)
				(type default)
			)
			(layer "F.Fab")
		)
		(pad "1" smd rect
			(at 0 0)
			(size 0.889 0.9906)
			(layers "F.Cu" "F.Mask" "F.Paste")
			(net "PVDDQ_ABC")
		)
		(pad "2" smd rect
			(at 0 1.397)
			(size 0.889 0.9906)
			(layers "F.Cu" "F.Mask" "F.Paste")
			(net "GND")
		)
		(zone
			(layer "F.Cu")
			(hatch none 0.5)
			(connect_pads
				(clearance 0)
			)
			(min_thickness 0.25)
			(keepout
				(tracks allowed)
				(vias not_allowed)
				(pads allowed)
				(copperpour not_allowed)
				(footprints allowed)
			)
			(placement
				(enabled no)
				(sheetname "")
			)
			(fill
				(thermal_gap 0.5)
				(thermal_bridge_width 0.5)
				(island_removal_mode 0)
			)
			(polygon
				(pts
					(xy 254.344932 -12.4587) (xy 254.344932 -13.4493) (xy 253.836932 -13.4493) (xy 253.836932 -12.4587)
				)
			)
		)
		(zone
			(layer "F.Cu")
			(hatch none 0.5)
			(connect_pads
				(clearance 0)
			)
			(min_thickness 0.25)
			(keepout
				(tracks not_allowed)
				(vias allowed)
				(pads allowed)
				(copperpour not_allowed)
				(footprints allowed)
			)
			(placement
				(enabled no)
				(sheetname "")
			)
			(fill
				(thermal_gap 0.5)
				(thermal_bridge_width 0.5)
				(island_removal_mode 0)
			)
			(polygon
				(pts
					(xy 254.344932 -12.4587) (xy 254.344932 -13.4493) (xy 253.836932 -13.4493) (xy 253.836932 -12.4587)
				)
			)
		)
	)
	(footprint ""
		(layer "F.Cu")
		(at 407.753566 -95.687642 -90)
		(property "Reference" "C8C13"
			(at -0.8382 -0.67818 270)
			(unlocked yes)
			(layer "F.SilkS")
			(effects
				(font
					(size 0.4064 0.254)
					(thickness 0.1524)
				)
				(justify left)
			)
		)
		(property "Value" ""
			(at 0 0 270)
			(layer "F.Fab")
			(effects
				(font
					(size 1.27 1.27)
				)
			)
		)
		(duplicate_pad_numbers_are_jumpers no)
		(fp_poly
			(pts
				(xy 0.3048 -0.1016) (xy 0.3048 0.9906) (xy -0.3048 0.9906) (xy -0.3048 -0.1016)
			)
			(stroke
				(width 0)
				(type default)
			)
			(fill no)
			(layer "F.CrtYd")
		)
		(fp_line
			(start -0.3048 0.9906)
			(end 0.3048 0.9906)
			(stroke
				(width 0.1)
				(type default)
			)
			(layer "F.Fab")
		)
		(fp_line
			(start 0.3048 0.9906)
			(end 0.3048 -0.1016)
			(stroke
				(width 0.1)
				(type default)
			)
			(layer "F.Fab")
		)
		(fp_line
			(start -0.3048 -0.1016)
			(end -0.3048 0.9906)
			(stroke
				(width 0.1)
				(type default)
			)
			(layer "F.Fab")
		)
		(fp_line
			(start 0.3048 -0.1016)
			(end -0.3048 -0.1016)
			(stroke
				(width 0.1)
				(type default)
			)
			(layer "F.Fab")
		)
		(pad "1" smd rect
			(at 0 0 270)
			(size 0.508 0.508)
			(layers "F.Cu" "F.Mask" "F.Paste")
			(net "KR_P1_OCP_RX_DN")
		)
		(pad "2" smd rect
			(at 0 0.889 270)
			(size 0.508 0.508)
			(layers "F.Cu" "F.Mask" "F.Paste")
			(net "KR_P1_OCP_RX_C_DN")
		)
		(zone
			(layer "F.Cu")
			(hatch none 0.5)
			(connect_pads
				(clearance 0)
			)
			(min_thickness 0.25)
			(keepout
				(tracks not_allowed)
				(vias allowed)
				(pads allowed)
				(copperpour not_allowed)
				(footprints allowed)
			)
			(placement
				(enabled no)
				(sheetname "")
			)
			(fill
				(thermal_gap 0.5)
				(thermal_bridge_width 0.5)
				(island_removal_mode 0)
			)
			(polygon
				(pts
					(xy 407.118566 -95.941642) (xy 407.118566 -95.433642) (xy 407.499566 -95.433642) (xy 407.499566 -95.941642)
				)
			)
		)
		(zone
			(layer "F.Cu")
			(hatch none 0.5)
			(connect_pads
				(clearance 0)
			)
			(min_thickness 0.25)
			(keepout
				(tracks allowed)
				(vias not_allowed)
				(pads allowed)
				(copperpour not_allowed)
				(footprints allowed)
			)
			(placement
				(enabled no)
				(sheetname "")
			)
			(fill
				(thermal_gap 0.5)
				(thermal_bridge_width 0.5)
				(island_removal_mode 0)
			)
			(polygon
				(pts
					(xy 407.499566 -95.941642) (xy 407.499566 -95.433642) (xy 407.118566 -95.433642) (xy 407.118566 -95.941642)
				)
			)
		)
	)
	(footprint ""
		(layer "F.Cu")
		(at 33.240726 -93.787214 90)
		(property "Reference" "C1C4"
			(at 0 0 90)
			(layer "F.SilkS")
			(hide yes)
			(effects
				(font
					(size 1.27 1.27)
				)
			)
		)
		(property "Value" ""
			(at 0 0 90)
			(layer "F.Fab")
			(effects
				(font
					(size 1.27 1.27)
				)
			)
		)
		(duplicate_pad_numbers_are_jumpers no)
		(fp_rect
			(start 0.3048 0.9906)
			(end -0.3048 -0.1016)
			(stroke
				(width 0)
				(type default)
			)
			(fill no)
			(layer "F.CrtYd")
		)
		(fp_line
			(start 0.3048 -0.1016)
			(end -0.3048 -0.1016)
			(stroke
				(width 0.1)
				(type default)
			)
			(layer "F.Fab")
		)
		(fp_line
			(start -0.3048 -0.1016)
			(end -0.3048 0.9906)
			(stroke
				(width 0.1)
				(type default)
			)
			(layer "F.Fab")
		)
		(fp_line
			(start 0.3048 0.9906)
			(end 0.3048 -0.1016)
			(stroke
				(width 0.1)
				(type default)
			)
			(layer "F.Fab")
		)
		(fp_line
			(start -0.3048 0.9906)
			(end 0.3048 0.9906)
			(stroke
				(width 0.1)
				(type default)
			)
			(layer "F.Fab")
		)
		(pad "1" smd rect
			(at 0 0 90)
			(size 0.508 0.508)
			(layers "F.Cu" "F.Mask" "F.Paste")
			(net "P5V_STBY")
		)
		(pad "2" smd rect
			(at 0 0.889 90)
			(size 0.508 0.508)
			(layers "F.Cu" "F.Mask" "F.Paste")
			(net "GND")
		)
		(zone
			(layer "F.Cu")
			(hatch none 0.5)
			(connect_pads
				(clearance 0)
			)
			(min_thickness 0.25)
			(keepout
				(tracks allowed)
				(vias not_allowed)
				(pads allowed)
				(copperpour not_allowed)
				(footprints allowed)
			)
			(placement
				(enabled no)
				(sheetname "")
			)
			(fill
				(thermal_gap 0.5)
				(thermal_bridge_width 0.5)
				(island_removal_mode 0)
			)
			(polygon
				(pts
					(xy 33.875726 -94.041214) (xy 33.494726 -94.041214) (xy 33.494726 -93.533214) (xy 33.875726 -93.533214)
				)
			)
		)
		(zone
			(layer "F.Cu")
			(hatch none 0.5)
			(connect_pads
				(clearance 0)
			)
			(min_thickness 0.25)
			(keepout
				(tracks not_allowed)
				(vias allowed)
				(pads allowed)
				(copperpour not_allowed)
				(footprints allowed)
			)
			(placement
				(enabled no)
				(sheetname "")
			)
			(fill
				(thermal_gap 0.5)
				(thermal_bridge_width 0.5)
				(island_removal_mode 0)
			)
			(polygon
				(pts
					(xy 33.875726 -94.041214) (xy 33.494726 -94.041214) (xy 33.494726 -93.533214) (xy 33.875726 -93.533214)
				)
			)
		)
	)
	(footprint ""
		(layer "F.Cu")
		(at 35.7886 -52.9082 -90)
		(property "Reference" "RT16"
			(at 0 0 270)
			(layer "F.SilkS")
			(hide yes)
			(effects
				(font
					(size 1.27 1.27)
				)
			)
		)
		(property "Value" "*"
			(at -0.0254 -2.6289 270)
			(unlocked yes)
			(layer "F.Fab")
			(hide yes)
			(effects
				(font
					(size 1.27 1.016)
					(thickness 0.1524)
				)
			)
		)
		(property "Device Type" "1R3F-GP_RCL_GP-1R3F-GP,64.1R00A"
			(at -0.0254 -4.1529 270)
			(unlocked yes)
			(layer "F.Fab")
			(hide yes)
			(effects
				(font
					(size 1.27 1.016)
					(thickness 0.1524)
				)
			)
		)
		(duplicate_pad_numbers_are_jumpers no)
		(fp_line
			(start -0.4826 0)
			(end -0.2032 0)
			(stroke
				(width 0.2032)
				(type default)
			)
			(layer "F.SilkS")
		)
		(fp_line
			(start 0.2032 0)
			(end 0.4826 0)
			(stroke
				(width 0.2032)
				(type default)
			)
			(layer "F.SilkS")
		)
		(fp_rect
			(start -0.5842 1.3335)
			(end 0.5842 -1.3335)
			(stroke
				(width 0)
				(type default)
			)
			(fill no)
			(layer "F.CrtYd")
		)
		(fp_rect
			(start -0.5842 1.3335)
			(end 0.5842 -1.3335)
			(stroke
				(width 0)
				(type default)
			)
			(fill no)
			(layer "F.Fab")
		)
		(pad "1" smd custom
			(at 0 -0.762 270)
			(size 0.2159 0.2159)
			(layers "F.Cu" "F.Mask" "F.Paste")
			(net "VR_PVCCIN_CPU1_PHASE1_RC")
			(options
				(clearance outline)
				(anchor circle)
			)
			(primitives
				(gr_poly
					(pts
						(arc
							(start -0.3302 -0.4318)
							(mid -0.402042 -0.402042)
							(end -0.4318 -0.3302)
						)
						(arc
							(start -0.4318 0.3302)
							(mid -0.402042 0.402042)
							(end -0.3302 0.4318)
						)
						(arc
							(start 0.3302 0.4318)
							(mid 0.402042 0.402042)
							(end 0.4318 0.3302)
						)
						(arc
							(start 0.4318 -0.3302)
							(mid 0.402042 -0.402042)
							(end 0.3302 -0.4318)
						)
					)
					(width 0)
					(fill yes)
				)
			)
		)
		(pad "2" smd custom
			(at 0 0.762 270)
			(size 0.2159 0.2159)
			(layers "F.Cu" "F.Mask" "F.Paste")
			(net "GND")
			(options
				(clearance outline)
				(anchor circle)
			)
			(primitives
				(gr_poly
					(pts
						(arc
							(start -0.3302 -0.4318)
							(mid -0.402042 -0.402042)
							(end -0.4318 -0.3302)
						)
						(arc
							(start -0.4318 0.3302)
							(mid -0.402042 0.402042)
							(end -0.3302 0.4318)
						)
						(arc
							(start 0.3302 0.4318)
							(mid 0.402042 0.402042)
							(end 0.4318 0.3302)
						)
						(arc
							(start 0.4318 -0.3302)
							(mid 0.402042 -0.402042)
							(end 0.3302 -0.4318)
						)
					)
					(width 0)
					(fill yes)
				)
			)
		)
	)
	(footprint ""
		(layer "F.Cu")
		(at 145.415 -26.67)
		(property "Reference" ""
			(at 0 0 0)
			(layer "F.SilkS")
			(hide yes)
			(effects
				(font
					(size 1.27 1.27)
				)
			)
		)
		(property "Value" ""
			(at 0 0 0)
			(layer "F.Fab")
			(effects
				(font
					(size 1.27 1.27)
				)
			)
		)
		(duplicate_pad_numbers_are_jumpers no)
		(fp_poly
			(pts
				(arc
					(start 2.032 0)
					(mid -2.032 0)
					(end 2.032 0)
				)
			)
			(stroke
				(width 0)
				(type default)
			)
			(fill no)
			(layer "F.CrtYd")
		)
		(pad "1" smd circle
			(at 0 0)
			(size 1.016 1.016)
			(layers "F.Cu" "F.Mask" "F.Paste")
			(net "Net_389")
		)
		(zone
			(layer "F.Cu")
			(hatch none 0.5)
			(connect_pads
				(clearance 0)
			)
			(min_thickness 0.25)
			(keepout
				(tracks not_allowed)
				(vias allowed)
				(pads allowed)
				(copperpour not_allowed)
				(footprints allowed)
			)
			(placement
				(enabled no)
				(sheetname "")
			)
			(fill
				(thermal_gap 0.5)
				(thermal_bridge_width 0.5)
				(island_removal_mode 0)
			)
			(polygon
				(pts
					(arc
						(start 146.939 -26.67)
						(mid 143.891 -26.67)
						(end 146.939 -26.67)
					)
				)
			)
		)
		(zone
			(layers "F.Cu" "B.Cu" "In1.Cu" "In2.Cu" "In3.Cu" "In4.Cu" "In5.Cu" "In6.Cu"
				"In7.Cu" "In8.Cu" "In9.Cu" "In10.Cu" "In11.Cu" "In12.Cu"
			)
			(hatch none 0.5)
			(connect_pads
				(clearance 0)
			)
			(min_thickness 0.25)
			(keepout
				(tracks allowed)
				(vias not_allowed)
				(pads allowed)
				(copperpour not_allowed)
				(footprints allowed)
			)
			(placement
				(enabled no)
				(sheetname "")
			)
			(fill
				(thermal_gap 0.5)
				(thermal_bridge_width 0.5)
				(island_removal_mode 0)
			)
			(polygon
				(pts
					(arc
						(start 146.939 -26.67)
						(mid 143.891 -26.67)
						(end 146.939 -26.67)
					)
				)
			)
		)
	)
	(footprint ""
		(layer "F.Cu")
		(at 88.392 -12.954 90)
		(property "Reference" "C2G4"
			(at 1.848866 0.752348 90)
			(unlocked yes)
			(layer "F.SilkS")
			(effects
				(font
					(size 1.27 0.9652)
					(thickness 0.1524)
				)
			)
		)
		(property "Value" ""
			(at 0 0 90)
			(layer "F.Fab")
			(effects
				(font
					(size 1.27 1.27)
				)
			)
		)
		(duplicate_pad_numbers_are_jumpers no)
		(fp_rect
			(start -0.500126 1.598422)
			(end 0.500126 -0.201422)
			(stroke
				(width 0)
				(type default)
			)
			(fill no)
			(layer "F.CrtYd")
		)
		(fp_line
			(start 0.500126 -0.201422)
			(end 0.500126 1.598422)
			(stroke
				(width 0.1)
				(type default)
			)
			(layer "F.Fab")
		)
		(fp_line
			(start -0.500126 -0.201422)
			(end 0.500126 -0.201422)
			(stroke
				(width 0.1)
				(type default)
			)
			(layer "F.Fab")
		)
		(fp_line
			(start 0.500126 1.598422)
			(end -0.500126 1.598422)
			(stroke
				(width 0.1)
				(type default)
			)
			(layer "F.Fab")
		)
		(fp_line
			(start -0.500126 1.598422)
			(end -0.500126 -0.201422)
			(stroke
				(width 0.1)
				(type default)
			)
			(layer "F.Fab")
		)
		(pad "1" smd rect
			(at 0 0)
			(size 0.889 0.9906)
			(layers "F.Cu" "F.Mask" "F.Paste")
			(net "PVDDQ_GHJ")
		)
		(pad "2" smd rect
			(at 0 1.397)
			(size 0.889 0.9906)
			(layers "F.Cu" "F.Mask" "F.Paste")
			(net "GND")
		)
		(zone
			(layer "F.Cu")
			(hatch none 0.5)
			(connect_pads
				(clearance 0)
			)
			(min_thickness 0.25)
			(keepout
				(tracks allowed)
				(vias not_allowed)
				(pads allowed)
				(copperpour not_allowed)
				(footprints allowed)
			)
			(placement
				(enabled no)
				(sheetname "")
			)
			(fill
				(thermal_gap 0.5)
				(thermal_bridge_width 0.5)
				(island_removal_mode 0)
			)
			(polygon
				(pts
					(xy 89.3445 -12.4587) (xy 89.3445 -13.4493) (xy 88.8365 -13.4493) (xy 88.8365 -12.4587)
				)
			)
		)
		(zone
			(layer "F.Cu")
			(hatch none 0.5)
			(connect_pads
				(clearance 0)
			)
			(min_thickness 0.25)
			(keepout
				(tracks not_allowed)
				(vias allowed)
				(pads allowed)
				(copperpour not_allowed)
				(footprints allowed)
			)
			(placement
				(enabled no)
				(sheetname "")
			)
			(fill
				(thermal_gap 0.5)
				(thermal_bridge_width 0.5)
				(island_removal_mode 0)
			)
			(polygon
				(pts
					(xy 89.3445 -12.4587) (xy 89.3445 -13.4493) (xy 88.8365 -13.4493) (xy 88.8365 -12.4587)
				)
			)
		)
	)
	(footprint ""
		(layer "F.Cu")
		(at 414.5788 -112.2426 90)
		(property "Reference" "R2M4"
			(at 0 0 90)
			(layer "F.SilkS")
			(hide yes)
			(effects
				(font
					(size 1.27 1.27)
				)
			)
		)
		(property "Value" ""
			(at 0 0 90)
			(layer "F.Fab")
			(effects
				(font
					(size 1.27 1.27)
				)
			)
		)
		(duplicate_pad_numbers_are_jumpers no)
		(fp_poly
			(pts
				(xy -0.2794 -0.1016) (xy 0.2794 -0.1016) (xy 0.2794 0.9906) (xy -0.2794 0.9906)
			)
			(stroke
				(width 0)
				(type default)
			)
			(fill no)
			(layer "F.CrtYd")
		)
		(fp_line
			(start 0.2794 -0.1016)
			(end -0.2794 -0.1016)
			(stroke
				(width 0.1)
				(type default)
			)
			(layer "F.Fab")
		)
		(fp_line
			(start -0.2794 -0.1016)
			(end -0.2794 0.9906)
			(stroke
				(width 0.1)
				(type default)
			)
			(layer "F.Fab")
		)
		(fp_line
			(start 0.2794 0.9906)
			(end 0.2794 -0.1016)
			(stroke
				(width 0.1)
				(type default)
			)
			(layer "F.Fab")
		)
		(fp_line
			(start -0.2794 0.9906)
			(end 0.2794 0.9906)
			(stroke
				(width 0.1)
				(type default)
			)
			(layer "F.Fab")
		)
		(pad "1" smd rect
			(at 0 0 90)
			(size 0.508 0.508)
			(layers "F.Cu" "F.Mask" "F.Paste")
			(net "P3V3_STBY")
		)
		(pad "2" smd rect
			(at 0 0.889 90)
			(size 0.508 0.508)
			(layers "F.Cu" "F.Mask" "F.Paste")
			(net "IRQ_HSC_FAULT_N")
		)
		(zone
			(layer "F.Cu")
			(hatch none 0.5)
			(connect_pads
				(clearance 0)
			)
			(min_thickness 0.25)
			(keepout
				(tracks allowed)
				(vias not_allowed)
				(pads allowed)
				(copperpour not_allowed)
				(footprints allowed)
			)
			(placement
				(enabled no)
				(sheetname "")
			)
			(fill
				(thermal_gap 0.5)
				(thermal_bridge_width 0.5)
				(island_removal_mode 0)
			)
			(polygon
				(pts
					(xy 414.8328 -111.9886) (xy 414.8328 -112.4966) (xy 415.2138 -112.4966) (xy 415.2138 -111.9886)
				)
			)
		)
		(zone
			(layer "F.Cu")
			(hatch none 0.5)
			(connect_pads
				(clearance 0)
			)
			(min_thickness 0.25)
			(keepout
				(tracks not_allowed)
				(vias allowed)
				(pads allowed)
				(copperpour not_allowed)
				(footprints allowed)
			)
			(placement
				(enabled no)
				(sheetname "")
			)
			(fill
				(thermal_gap 0.5)
				(thermal_bridge_width 0.5)
				(island_removal_mode 0)
			)
			(polygon
				(pts
					(xy 415.2138 -111.9886) (xy 415.2138 -112.4966) (xy 414.8328 -112.4966) (xy 414.8328 -111.9886)
				)
			)
		)
	)
	(footprint ""
		(layer "F.Cu")
		(at 173.9265 -68.834 90)
		(property "Reference" "C4D38"
			(at 0 0 90)
			(layer "F.SilkS")
			(hide yes)
			(effects
				(font
					(size 1.27 1.27)
				)
			)
		)
		(property "Value" ""
			(at 0 0 90)
			(layer "F.Fab")
			(effects
				(font
					(size 1.27 1.27)
				)
			)
		)
		(duplicate_pad_numbers_are_jumpers no)
		(fp_poly
			(pts
				(xy 0.3048 -0.1016) (xy 0.3048 0.9906) (xy -0.3048 0.9906) (xy -0.3048 -0.1016)
			)
			(stroke
				(width 0)
				(type default)
			)
			(fill no)
			(layer "F.CrtYd")
		)
		(fp_line
			(start 0.3048 -0.1016)
			(end -0.3048 -0.1016)
			(stroke
				(width 0.1)
				(type default)
			)
			(layer "F.Fab")
		)
		(fp_line
			(start -0.3048 -0.1016)
			(end -0.3048 0.9906)
			(stroke
				(width 0.1)
				(type default)
			)
			(layer "F.Fab")
		)
		(fp_line
			(start 0.3048 0.9906)
			(end 0.3048 -0.1016)
			(stroke
				(width 0.1)
				(type default)
			)
			(layer "F.Fab")
		)
		(fp_line
			(start -0.3048 0.9906)
			(end 0.3048 0.9906)
			(stroke
				(width 0.1)
				(type default)
			)
			(layer "F.Fab")
		)
		(pad "1" smd rect
			(at 0 0 90)
			(size 0.508 0.508)
			(layers "F.Cu" "F.Mask" "F.Paste")
			(net "VR_PVCCIO_CPU1_VDD")
		)
		(pad "2" smd rect
			(at 0 0.889 90)
			(size 0.508 0.508)
			(layers "F.Cu" "F.Mask" "F.Paste")
			(net "GND")
		)
		(zone
			(layer "F.Cu")
			(hatch none 0.5)
			(connect_pads
				(clearance 0)
			)
			(min_thickness 0.25)
			(keepout
				(tracks allowed)
				(vias not_allowed)
				(pads allowed)
				(copperpour not_allowed)
				(footprints allowed)
			)
			(placement
				(enabled no)
				(sheetname "")
			)
			(fill
				(thermal_gap 0.5)
				(thermal_bridge_width 0.5)
				(island_removal_mode 0)
			)
			(polygon
				(pts
					(xy 174.1805 -68.58) (xy 174.1805 -69.088) (xy 174.5615 -69.088) (xy 174.5615 -68.58)
				)
			)
		)
		(zone
			(layer "F.Cu")
			(hatch none 0.5)
			(connect_pads
				(clearance 0)
			)
			(min_thickness 0.25)
			(keepout
				(tracks not_allowed)
				(vias allowed)
				(pads allowed)
				(copperpour not_allowed)
				(footprints allowed)
			)
			(placement
				(enabled no)
				(sheetname "")
			)
			(fill
				(thermal_gap 0.5)
				(thermal_bridge_width 0.5)
				(island_removal_mode 0)
			)
			(polygon
				(pts
					(xy 174.5615 -68.58) (xy 174.5615 -69.088) (xy 174.1805 -69.088) (xy 174.1805 -68.58)
				)
			)
		)
	)
	(footprint ""
		(layer "F.Cu")
		(at 421.894 -117.4877 180)
		(property "Reference" "R8B19"
			(at 0 0 180)
			(layer "F.SilkS")
			(hide yes)
			(effects
				(font
					(size 1.27 1.27)
				)
			)
		)
		(property "Value" ""
			(at 0 0 180)
			(layer "F.Fab")
			(effects
				(font
					(size 1.27 1.27)
				)
			)
		)
		(duplicate_pad_numbers_are_jumpers no)
		(fp_poly
			(pts
				(xy -0.2794 -0.1016) (xy 0.2794 -0.1016) (xy 0.2794 0.9906) (xy -0.2794 0.9906)
			)
			(stroke
				(width 0)
				(type default)
			)
			(fill no)
			(layer "F.CrtYd")
		)
		(fp_line
			(start 0.2794 0.9906)
			(end 0.2794 -0.1016)
			(stroke
				(width 0.1)
				(type default)
			)
			(layer "F.Fab")
		)
		(fp_line
			(start 0.2794 -0.1016)
			(end -0.2794 -0.1016)
			(stroke
				(width 0.1)
				(type default)
			)
			(layer "F.Fab")
		)
		(fp_line
			(start -0.2794 0.9906)
			(end 0.2794 0.9906)
			(stroke
				(width 0.1)
				(type default)
			)
			(layer "F.Fab")
		)
		(fp_line
			(start -0.2794 -0.1016)
			(end -0.2794 0.9906)
			(stroke
				(width 0.1)
				(type default)
			)
			(layer "F.Fab")
		)
		(pad "1" smd rect
			(at 0 0 180)
			(size 0.508 0.508)
			(layers "F.Cu" "F.Mask" "F.Paste")
			(net "PVPP_ABC")
		)
		(pad "2" smd rect
			(at 0 0.889 180)
			(size 0.508 0.508)
			(layers "F.Cu" "F.Mask" "F.Paste")
			(net "FM_MODPRST_HFI1_CPU0_LVT2_N")
		)
		(zone
			(layer "F.Cu")
			(hatch none 0.5)
			(connect_pads
				(clearance 0)
			)
			(min_thickness 0.25)
			(keepout
				(tracks not_allowed)
				(vias allowed)
				(pads allowed)
				(copperpour not_allowed)
				(footprints allowed)
			)
			(placement
				(enabled no)
				(sheetname "")
			)
			(fill
				(thermal_gap 0.5)
				(thermal_bridge_width 0.5)
				(island_removal_mode 0)
			)
			(polygon
				(pts
					(xy 422.148 -118.1227) (xy 421.64 -118.1227) (xy 421.64 -117.7417) (xy 422.148 -117.7417)
				)
			)
		)
		(zone
			(layer "F.Cu")
			(hatch none 0.5)
			(connect_pads
				(clearance 0)
			)
			(min_thickness 0.25)
			(keepout
				(tracks allowed)
				(vias not_allowed)
				(pads allowed)
				(copperpour not_allowed)
				(footprints allowed)
			)
			(placement
				(enabled no)
				(sheetname "")
			)
			(fill
				(thermal_gap 0.5)
				(thermal_bridge_width 0.5)
				(island_removal_mode 0)
			)
			(polygon
				(pts
					(xy 422.148 -117.7417) (xy 421.64 -117.7417) (xy 421.64 -118.1227) (xy 422.148 -118.1227)
				)
			)
		)
	)
	(footprint ""
		(layer "F.Cu")
		(at 337.947 -19.7612 90)
		(property "Reference" "R7F27"
			(at 0 0 90)
			(layer "F.SilkS")
			(hide yes)
			(effects
				(font
					(size 1.27 1.27)
				)
			)
		)
		(property "Value" ""
			(at 0 0 90)
			(layer "F.Fab")
			(effects
				(font
					(size 1.27 1.27)
				)
			)
		)
		(duplicate_pad_numbers_are_jumpers no)
		(fp_poly
			(pts
				(xy -0.2794 -0.1016) (xy 0.2794 -0.1016) (xy 0.2794 0.9906) (xy -0.2794 0.9906)
			)
			(stroke
				(width 0)
				(type default)
			)
			(fill no)
			(layer "F.CrtYd")
		)
		(fp_line
			(start 0.2794 -0.1016)
			(end -0.2794 -0.1016)
			(stroke
				(width 0.1)
				(type default)
			)
			(layer "F.Fab")
		)
		(fp_line
			(start -0.2794 -0.1016)
			(end -0.2794 0.9906)
			(stroke
				(width 0.1)
				(type default)
			)
			(layer "F.Fab")
		)
		(fp_line
			(start 0.2794 0.9906)
			(end 0.2794 -0.1016)
			(stroke
				(width 0.1)
				(type default)
			)
			(layer "F.Fab")
		)
		(fp_line
			(start -0.2794 0.9906)
			(end 0.2794 0.9906)
			(stroke
				(width 0.1)
				(type default)
			)
			(layer "F.Fab")
		)
		(pad "1" smd rect
			(at 0 0 90)
			(size 0.508 0.508)
			(layers "F.Cu" "F.Mask" "F.Paste")
			(net "P3V3_STBY")
		)
		(pad "2" smd rect
			(at 0 0.889 90)
			(size 0.508 0.508)
			(layers "F.Cu" "F.Mask" "F.Paste")
			(net "IRQ_PVDDQ_ABC_VRHOT_LVT3_R_N")
		)
		(zone
			(layer "F.Cu")
			(hatch none 0.5)
			(connect_pads
				(clearance 0)
			)
			(min_thickness 0.25)
			(keepout
				(tracks allowed)
				(vias not_allowed)
				(pads allowed)
				(copperpour not_allowed)
				(footprints allowed)
			)
			(placement
				(enabled no)
				(sheetname "")
			)
			(fill
				(thermal_gap 0.5)
				(thermal_bridge_width 0.5)
				(island_removal_mode 0)
			)
			(polygon
				(pts
					(xy 338.201 -19.5072) (xy 338.201 -20.0152) (xy 338.582 -20.0152) (xy 338.582 -19.5072)
				)
			)
		)
		(zone
			(layer "F.Cu")
			(hatch none 0.5)
			(connect_pads
				(clearance 0)
			)
			(min_thickness 0.25)
			(keepout
				(tracks not_allowed)
				(vias allowed)
				(pads allowed)
				(copperpour not_allowed)
				(footprints allowed)
			)
			(placement
				(enabled no)
				(sheetname "")
			)
			(fill
				(thermal_gap 0.5)
				(thermal_bridge_width 0.5)
				(island_removal_mode 0)
			)
			(polygon
				(pts
					(xy 338.582 -19.5072) (xy 338.582 -20.0152) (xy 338.201 -20.0152) (xy 338.201 -19.5072)
				)
			)
		)
	)
	(footprint ""
		(layer "F.Cu")
		(at 411.892242 -47.682404 180)
		(property "Reference" "R25W60"
			(at -0.8382 -0.67818 180)
			(unlocked yes)
			(layer "F.SilkS")
			(effects
				(font
					(size 0.4064 0.254)
					(thickness 0.1524)
				)
				(justify left)
			)
		)
		(property "Value" ""
			(at 0 0 180)
			(layer "F.Fab")
			(effects
				(font
					(size 1.27 1.27)
				)
			)
		)
		(duplicate_pad_numbers_are_jumpers no)
		(fp_poly
			(pts
				(xy -0.2794 -0.1016) (xy 0.2794 -0.1016) (xy 0.2794 0.9906) (xy -0.2794 0.9906)
			)
			(stroke
				(width 0)
				(type default)
			)
			(fill no)
			(layer "F.CrtYd")
		)
		(fp_line
			(start 0.2794 0.9906)
			(end 0.2794 -0.1016)
			(stroke
				(width 0.1)
				(type default)
			)
			(layer "F.Fab")
		)
		(fp_line
			(start 0.2794 -0.1016)
			(end -0.2794 -0.1016)
			(stroke
				(width 0.1)
				(type default)
			)
			(layer "F.Fab")
		)
		(fp_line
			(start -0.2794 0.9906)
			(end 0.2794 0.9906)
			(stroke
				(width 0.1)
				(type default)
			)
			(layer "F.Fab")
		)
		(fp_line
			(start -0.2794 -0.1016)
			(end -0.2794 0.9906)
			(stroke
				(width 0.1)
				(type default)
			)
			(layer "F.Fab")
		)
		(pad "1" smd rect
			(at 0 0 180)
			(size 0.508 0.508)
			(layers "F.Cu" "F.Mask" "F.Paste")
			(net "CLK_100M_BMC_PE_R_DN")
		)
		(pad "2" smd rect
			(at 0 0.889 180)
			(size 0.508 0.508)
			(layers "F.Cu" "F.Mask" "F.Paste")
			(net "GND")
		)
		(zone
			(layer "F.Cu")
			(hatch none 0.5)
			(connect_pads
				(clearance 0)
			)
			(min_thickness 0.25)
			(keepout
				(tracks not_allowed)
				(vias allowed)
				(pads allowed)
				(copperpour not_allowed)
				(footprints allowed)
			)
			(placement
				(enabled no)
				(sheetname "")
			)
			(fill
				(thermal_gap 0.5)
				(thermal_bridge_width 0.5)
				(island_removal_mode 0)
			)
			(polygon
				(pts
					(xy 412.146242 -48.317404) (xy 411.638242 -48.317404) (xy 411.638242 -47.936404) (xy 412.146242 -47.936404)
				)
			)
		)
		(zone
			(layer "F.Cu")
			(hatch none 0.5)
			(connect_pads
				(clearance 0)
			)
			(min_thickness 0.25)
			(keepout
				(tracks allowed)
				(vias not_allowed)
				(pads allowed)
				(copperpour not_allowed)
				(footprints allowed)
			)
			(placement
				(enabled no)
				(sheetname "")
			)
			(fill
				(thermal_gap 0.5)
				(thermal_bridge_width 0.5)
				(island_removal_mode 0)
			)
			(polygon
				(pts
					(xy 412.146242 -47.936404) (xy 411.638242 -47.936404) (xy 411.638242 -48.317404) (xy 412.146242 -48.317404)
				)
			)
		)
	)
	(footprint ""
		(layer "F.Cu")
		(at 487.2228 -138.4554 180)
		(property "Reference" "C6W10"
			(at -0.8382 -0.67818 180)
			(unlocked yes)
			(layer "F.SilkS")
			(effects
				(font
					(size 0.4064 0.254)
					(thickness 0.1524)
				)
				(justify left)
			)
		)
		(property "Value" ""
			(at 0 0 180)
			(layer "F.Fab")
			(effects
				(font
					(size 1.27 1.27)
				)
			)
		)
		(duplicate_pad_numbers_are_jumpers no)
		(fp_poly
			(pts
				(xy 0.3048 -0.1016) (xy 0.3048 0.9906) (xy -0.3048 0.9906) (xy -0.3048 -0.1016)
			)
			(stroke
				(width 0)
				(type default)
			)
			(fill no)
			(layer "F.CrtYd")
		)
		(fp_line
			(start 0.3048 0.9906)
			(end 0.3048 -0.1016)
			(stroke
				(width 0.1)
				(type default)
			)
			(layer "F.Fab")
		)
		(fp_line
			(start 0.3048 -0.1016)
			(end -0.3048 -0.1016)
			(stroke
				(width 0.1)
				(type default)
			)
			(layer "F.Fab")
		)
		(fp_line
			(start -0.3048 0.9906)
			(end 0.3048 0.9906)
			(stroke
				(width 0.1)
				(type default)
			)
			(layer "F.Fab")
		)
		(fp_line
			(start -0.3048 -0.1016)
			(end -0.3048 0.9906)
			(stroke
				(width 0.1)
				(type default)
			)
			(layer "F.Fab")
		)
		(pad "1" smd rect
			(at 0 0 180)
			(size 0.508 0.508)
			(layers "F.Cu" "F.Mask" "F.Paste")
			(net "P3V3_STBY")
		)
		(pad "2" smd rect
			(at 0 0.889 180)
			(size 0.508 0.508)
			(layers "F.Cu" "F.Mask" "F.Paste")
			(net "GND")
		)
		(zone
			(layer "F.Cu")
			(hatch none 0.5)
			(connect_pads
				(clearance 0)
			)
			(min_thickness 0.25)
			(keepout
				(tracks not_allowed)
				(vias allowed)
				(pads allowed)
				(copperpour not_allowed)
				(footprints allowed)
			)
			(placement
				(enabled no)
				(sheetname "")
			)
			(fill
				(thermal_gap 0.5)
				(thermal_bridge_width 0.5)
				(island_removal_mode 0)
			)
			(polygon
				(pts
					(xy 487.4768 -139.0904) (xy 486.9688 -139.0904) (xy 486.9688 -138.7094) (xy 487.4768 -138.7094)
				)
			)
		)
		(zone
			(layer "F.Cu")
			(hatch none 0.5)
			(connect_pads
				(clearance 0)
			)
			(min_thickness 0.25)
			(keepout
				(tracks allowed)
				(vias not_allowed)
				(pads allowed)
				(copperpour not_allowed)
				(footprints allowed)
			)
			(placement
				(enabled no)
				(sheetname "")
			)
			(fill
				(thermal_gap 0.5)
				(thermal_bridge_width 0.5)
				(island_removal_mode 0)
			)
			(polygon
				(pts
					(xy 487.4768 -138.7094) (xy 486.9688 -138.7094) (xy 486.9688 -139.0904) (xy 487.4768 -139.0904)
				)
			)
		)
	)
	(footprint ""
		(layer "F.Cu")
		(at 162.6362 -66.675 -90)
		(property "Reference" "R3D28"
			(at 0 0 270)
			(layer "F.SilkS")
			(hide yes)
			(effects
				(font
					(size 1.27 1.27)
				)
			)
		)
		(property "Value" ""
			(at 0 0 270)
			(layer "F.Fab")
			(effects
				(font
					(size 1.27 1.27)
				)
			)
		)
		(duplicate_pad_numbers_are_jumpers no)
		(fp_poly
			(pts
				(xy -0.2794 -0.1016) (xy 0.2794 -0.1016) (xy 0.2794 0.9906) (xy -0.2794 0.9906)
			)
			(stroke
				(width 0)
				(type default)
			)
			(fill no)
			(layer "F.CrtYd")
		)
		(fp_line
			(start -0.2794 0.9906)
			(end 0.2794 0.9906)
			(stroke
				(width 0.1)
				(type default)
			)
			(layer "F.Fab")
		)
		(fp_line
			(start 0.2794 0.9906)
			(end 0.2794 -0.1016)
			(stroke
				(width 0.1)
				(type default)
			)
			(layer "F.Fab")
		)
		(fp_line
			(start -0.2794 -0.1016)
			(end -0.2794 0.9906)
			(stroke
				(width 0.1)
				(type default)
			)
			(layer "F.Fab")
		)
		(fp_line
			(start 0.2794 -0.1016)
			(end -0.2794 -0.1016)
			(stroke
				(width 0.1)
				(type default)
			)
			(layer "F.Fab")
		)
		(pad "1" smd rect
			(at 0 0 270)
			(size 0.508 0.508)
			(layers "F.Cu" "F.Mask" "F.Paste")
			(net "VSENSE_PVCCIO_CPU1_AVSN")
		)
		(pad "2" smd rect
			(at 0 0.889 270)
			(size 0.508 0.508)
			(layers "F.Cu" "F.Mask" "F.Paste")
			(net "GND")
		)
		(zone
			(layer "F.Cu")
			(hatch none 0.5)
			(connect_pads
				(clearance 0)
			)
			(min_thickness 0.25)
			(keepout
				(tracks not_allowed)
				(vias allowed)
				(pads allowed)
				(copperpour not_allowed)
				(footprints allowed)
			)
			(placement
				(enabled no)
				(sheetname "")
			)
			(fill
				(thermal_gap 0.5)
				(thermal_bridge_width 0.5)
				(island_removal_mode 0)
			)
			(polygon
				(pts
					(xy 162.0012 -66.929) (xy 162.0012 -66.421) (xy 162.3822 -66.421) (xy 162.3822 -66.929)
				)
			)
		)
		(zone
			(layer "F.Cu")
			(hatch none 0.5)
			(connect_pads
				(clearance 0)
			)
			(min_thickness 0.25)
			(keepout
				(tracks allowed)
				(vias not_allowed)
				(pads allowed)
				(copperpour not_allowed)
				(footprints allowed)
			)
			(placement
				(enabled no)
				(sheetname "")
			)
			(fill
				(thermal_gap 0.5)
				(thermal_bridge_width 0.5)
				(island_removal_mode 0)
			)
			(polygon
				(pts
					(xy 162.3822 -66.929) (xy 162.3822 -66.421) (xy 162.0012 -66.421) (xy 162.0012 -66.929)
				)
			)
		)
	)
	(footprint ""
		(layer "F.Cu")
		(at 412.4325 -110.617 90)
		(property "Reference" "R2R5"
			(at 0 0 90)
			(layer "F.SilkS")
			(hide yes)
			(effects
				(font
					(size 1.27 1.27)
				)
			)
		)
		(property "Value" ""
			(at 0 0 90)
			(layer "F.Fab")
			(effects
				(font
					(size 1.27 1.27)
				)
			)
		)
		(duplicate_pad_numbers_are_jumpers no)
		(fp_poly
			(pts
				(xy -0.2794 -0.1016) (xy 0.2794 -0.1016) (xy 0.2794 0.9906) (xy -0.2794 0.9906)
			)
			(stroke
				(width 0)
				(type default)
			)
			(fill no)
			(layer "F.CrtYd")
		)
		(fp_line
			(start 0.2794 -0.1016)
			(end -0.2794 -0.1016)
			(stroke
				(width 0.1)
				(type default)
			)
			(layer "F.Fab")
		)
		(fp_line
			(start -0.2794 -0.1016)
			(end -0.2794 0.9906)
			(stroke
				(width 0.1)
				(type default)
			)
			(layer "F.Fab")
		)
		(fp_line
			(start 0.2794 0.9906)
			(end 0.2794 -0.1016)
			(stroke
				(width 0.1)
				(type default)
			)
			(layer "F.Fab")
		)
		(fp_line
			(start -0.2794 0.9906)
			(end 0.2794 0.9906)
			(stroke
				(width 0.1)
				(type default)
			)
			(layer "F.Fab")
		)
		(pad "1" smd rect
			(at 0 0 90)
			(size 0.508 0.508)
			(layers "F.Cu" "F.Mask" "F.Paste")
			(net "P3V3_STBY")
		)
		(pad "2" smd rect
			(at 0 0.889 90)
			(size 0.508 0.508)
			(layers "F.Cu" "F.Mask" "F.Paste")
			(net "FM_PCH_PLD_DATA")
		)
		(zone
			(layer "F.Cu")
			(hatch none 0.5)
			(connect_pads
				(clearance 0)
			)
			(min_thickness 0.25)
			(keepout
				(tracks allowed)
				(vias not_allowed)
				(pads allowed)
				(copperpour not_allowed)
				(footprints allowed)
			)
			(placement
				(enabled no)
				(sheetname "")
			)
			(fill
				(thermal_gap 0.5)
				(thermal_bridge_width 0.5)
				(island_removal_mode 0)
			)
			(polygon
				(pts
					(xy 412.6865 -110.363) (xy 412.6865 -110.871) (xy 413.0675 -110.871) (xy 413.0675 -110.363)
				)
			)
		)
		(zone
			(layer "F.Cu")
			(hatch none 0.5)
			(connect_pads
				(clearance 0)
			)
			(min_thickness 0.25)
			(keepout
				(tracks not_allowed)
				(vias allowed)
				(pads allowed)
				(copperpour not_allowed)
				(footprints allowed)
			)
			(placement
				(enabled no)
				(sheetname "")
			)
			(fill
				(thermal_gap 0.5)
				(thermal_bridge_width 0.5)
				(island_removal_mode 0)
			)
			(polygon
				(pts
					(xy 413.0675 -110.363) (xy 413.0675 -110.871) (xy 412.6865 -110.871) (xy 412.6865 -110.363)
				)
			)
		)
	)
	(footprint ""
		(layer "F.Cu")
		(at 1.84912 -142.002256 90)
		(property "Reference" "C1A10"
			(at 0 0 90)
			(layer "F.SilkS")
			(hide yes)
			(effects
				(font
					(size 1.27 1.27)
				)
			)
		)
		(property "Value" ""
			(at 0 0 90)
			(layer "F.Fab")
			(effects
				(font
					(size 1.27 1.27)
				)
			)
		)
		(duplicate_pad_numbers_are_jumpers no)
		(fp_rect
			(start 0.3048 -0.1016)
			(end -0.3048 0.9906)
			(stroke
				(width 0)
				(type default)
			)
			(fill no)
			(layer "F.CrtYd")
		)
		(fp_line
			(start 0.3048 -0.1016)
			(end -0.3048 -0.1016)
			(stroke
				(width 0.1)
				(type default)
			)
			(layer "F.Fab")
		)
		(fp_line
			(start -0.3048 -0.1016)
			(end -0.3048 0.9906)
			(stroke
				(width 0.1)
				(type default)
			)
			(layer "F.Fab")
		)
		(fp_line
			(start 0.3048 0.9906)
			(end 0.3048 -0.1016)
			(stroke
				(width 0.1)
				(type default)
			)
			(layer "F.Fab")
		)
		(fp_line
			(start -0.3048 0.9906)
			(end 0.3048 0.9906)
			(stroke
				(width 0.1)
				(type default)
			)
			(layer "F.Fab")
		)
		(pad "1" smd rect
			(at 0 0 90)
			(size 0.508 0.508)
			(layers "F.Cu" "F.Mask" "F.Paste")
			(net "VR_FET_SW_P12V_STBY_PVDDQ_KLM")
		)
		(pad "2" smd rect
			(at 0 0.889 90)
			(size 0.508 0.508)
			(layers "F.Cu" "F.Mask" "F.Paste")
			(net "GND")
		)
		(zone
			(layer "F.Cu")
			(hatch none 0.5)
			(connect_pads
				(clearance 0)
			)
			(min_thickness 0.25)
			(keepout
				(tracks not_allowed)
				(vias allowed)
				(pads allowed)
				(copperpour not_allowed)
				(footprints allowed)
			)
			(placement
				(enabled no)
				(sheetname "")
			)
			(fill
				(thermal_gap 0.5)
				(thermal_bridge_width 0.5)
				(island_removal_mode 0)
			)
			(polygon
				(pts
					(xy 2.10312 -142.256256) (xy 2.10312 -141.748256) (xy 2.48412 -141.748256) (xy 2.48412 -142.256256)
				)
			)
		)
		(zone
			(layer "F.Cu")
			(hatch none 0.5)
			(connect_pads
				(clearance 0)
			)
			(min_thickness 0.25)
			(keepout
				(tracks allowed)
				(vias not_allowed)
				(pads allowed)
				(copperpour not_allowed)
				(footprints allowed)
			)
			(placement
				(enabled no)
				(sheetname "")
			)
			(fill
				(thermal_gap 0.5)
				(thermal_bridge_width 0.5)
				(island_removal_mode 0)
			)
			(polygon
				(pts
					(xy 2.10312 -142.256256) (xy 2.10312 -141.748256) (xy 2.48412 -141.748256) (xy 2.48412 -142.256256)
				)
			)
		)
	)
	(footprint ""
		(layer "F.Cu")
		(at 432.689762 3.81 90)
		(property "Reference" "J8G2"
			(at 3.96621 6.19506 0)
			(unlocked yes)
			(layer "B.SilkS")
			(effects
				(font
					(size 0.7874 0.5842)
					(thickness 0.1524)
				)
				(justify mirror)
			)
		)
		(property "Value" ""
			(at 0 0 90)
			(layer "F.Fab")
			(effects
				(font
					(size 1.27 1.27)
				)
			)
		)
		(duplicate_pad_numbers_are_jumpers no)
		(fp_line
			(start 3.8227 -1.27)
			(end 3.8227 13.97)
			(stroke
				(width 0.1524)
				(type default)
			)
			(layer "F.SilkS")
		)
		(fp_line
			(start -1.2827 -1.27)
			(end 3.8227 -1.27)
			(stroke
				(width 0.1524)
				(type default)
			)
			(layer "F.SilkS")
		)
		(fp_line
			(start 3.7592 -1.143)
			(end 3.758184 -1.143)
			(stroke
				(width 0.1)
				(type default)
			)
			(layer "F.SilkS")
		)
		(fp_line
			(start -1.2192 -1.143)
			(end -1.218946 -1.143)
			(stroke
				(width 0.1)
				(type default)
			)
			(layer "F.SilkS")
		)
		(fp_line
			(start 3.7592 13.843)
			(end 3.758946 13.843)
			(stroke
				(width 0.1524)
				(type default)
			)
			(layer "F.SilkS")
		)
		(fp_line
			(start -1.2192 13.843)
			(end -1.218946 13.843)
			(stroke
				(width 0.1524)
				(type default)
			)
			(layer "F.SilkS")
		)
		(fp_line
			(start 3.8227 13.97)
			(end -1.2827 13.97)
			(stroke
				(width 0.1524)
				(type default)
			)
			(layer "F.SilkS")
		)
		(fp_line
			(start -1.2827 13.97)
			(end -1.2827 -1.27)
			(stroke
				(width 0.1524)
				(type default)
			)
			(layer "F.SilkS")
		)
		(fp_poly
			(pts
				(xy -1.7145 -0.005588) (xy -2.9845 0.502412) (xy -2.9845 -0.513588)
			)
			(stroke
				(width 0)
				(type default)
			)
			(fill yes)
			(layer "F.SilkS")
		)
		(fp_poly
			(pts
				(xy -1.7145 -0.005588) (xy -2.9845 0.502412) (xy -2.9845 -0.513588)
			)
			(stroke
				(width 0)
				(type default)
			)
			(fill yes)
			(layer "B.SilkS")
		)
		(fp_poly
			(pts
				(xy -1.2827 -1.27) (xy -1.2827 13.97) (xy 3.8227 13.97) (xy 3.8227 -1.27)
			)
			(stroke
				(width 0)
				(type default)
			)
			(fill no)
			(layer "F.CrtYd")
		)
		(fp_poly
			(pts
				(xy -1.7145 -0.005588) (xy -2.9845 0.502412) (xy -2.9845 -0.513588)
			)
			(stroke
				(width 0)
				(type default)
			)
			(fill yes)
			(layer "B.Fab")
		)
		(fp_line
			(start 3.8227 -1.27)
			(end -1.2827 -1.27)
			(stroke
				(width 0.1)
				(type default)
			)
			(layer "F.Fab")
		)
		(fp_line
			(start -1.2827 -1.27)
			(end -1.2827 13.97)
			(stroke
				(width 0.1)
				(type default)
			)
			(layer "F.Fab")
		)
		(fp_line
			(start 3.8227 13.97)
			(end 3.8227 -1.27)
			(stroke
				(width 0.1)
				(type default)
			)
			(layer "F.Fab")
		)
		(fp_line
			(start -1.2827 13.97)
			(end 3.8227 13.97)
			(stroke
				(width 0.1)
				(type default)
			)
			(layer "F.Fab")
		)
		(fp_poly
			(pts
				(xy -1.7145 -0.005588) (xy -2.9845 0.502412) (xy -2.9845 -0.513588)
			)
			(stroke
				(width 0)
				(type default)
			)
			(fill yes)
			(layer "F.Fab")
		)
		(fp_text user "2"
			(at 4.470908 -0.198882 0)
			(unlocked yes)
			(layer "F.SilkS")
			(effects
				(font
					(size 0.7874 0.5842)
					(thickness 0.1524)
				)
			)
		)
		(fp_text user "12"
			(at 4.1402 14.630908 90)
			(unlocked yes)
			(layer "F.SilkS")
			(effects
				(font
					(size 0.7874 0.5842)
					(thickness 0.1524)
				)
			)
		)
		(fp_text user "11"
			(at -0.870204 14.70787 0)
			(unlocked yes)
			(layer "F.SilkS")
			(effects
				(font
					(size 0.7874 0.5842)
					(thickness 0.1524)
				)
			)
		)
		(fp_text user "2"
			(at 4.5466 0.02667 90)
			(unlocked yes)
			(layer "B.SilkS")
			(effects
				(font
					(size 0.7874 0.5842)
					(thickness 0.1524)
				)
				(justify mirror)
			)
		)
		(fp_text user "12"
			(at 4.9403 12.72667 90)
			(unlocked yes)
			(layer "B.SilkS")
			(effects
				(font
					(size 0.7874 0.5842)
					(thickness 0.1524)
				)
				(justify mirror)
			)
		)
		(fp_text user "11"
			(at -2.2606 12.72667 90)
			(unlocked yes)
			(layer "B.SilkS")
			(effects
				(font
					(size 0.7874 0.5842)
					(thickness 0.1524)
				)
				(justify mirror)
			)
		)
		(fp_text user "2"
			(at 4.5466 0.02667 90)
			(unlocked yes)
			(layer "B.Fab")
			(effects
				(font
					(size 0.7874 0.5842)
					(thickness 0.1524)
				)
				(justify mirror)
			)
		)
		(fp_text user "12"
			(at 4.9403 12.72667 90)
			(unlocked yes)
			(layer "B.Fab")
			(effects
				(font
					(size 0.7874 0.5842)
					(thickness 0.1524)
				)
				(justify mirror)
			)
		)
		(fp_text user "11"
			(at -2.2606 12.72667 90)
			(unlocked yes)
			(layer "B.Fab")
			(effects
				(font
					(size 0.7874 0.5842)
					(thickness 0.1524)
				)
				(justify mirror)
			)
		)
		(fp_text user "2"
			(at 4.445 0.669544 90)
			(unlocked yes)
			(layer "F.Fab")
			(effects
				(font
					(size 0.7874 0.5842)
					(thickness 0.1524)
				)
			)
		)
		(fp_text user "11"
			(at -1.4478 13.66647 90)
			(unlocked yes)
			(layer "F.Fab")
			(effects
				(font
					(size 0.7874 0.5842)
					(thickness 0.1524)
				)
			)
		)
		(fp_text user "12"
			(at 0.889 14.639544 90)
			(unlocked yes)
			(layer "F.Fab")
			(effects
				(font
					(size 0.7874 0.5842)
					(thickness 0.1524)
				)
			)
		)
		(pad "1" thru_hole rect
			(at 0 0 90)
			(size 1.6256 1.6256)
			(drill 1.2446)
			(layers "*.Cu" "*.Mask")
			(remove_unused_layers no)
			(net "TP_JUMPER_BLOCK_1_1")
			(clearance 0.127)
			(thermal_gap 0.127)
			(padstack
				(mode front_inner_back)
				(layer "Inner"
					(shape circle)
					(size 1.6256 1.6256)
					(clearance 0.127)
				)
				(layer "B.Cu"
					(shape rect)
					(size 1.6256 1.6256)
					(clearance 0.127)
				)
			)
		)
		(pad "2" thru_hole circle
			(at 2.54 0 90)
			(size 1.6256 1.6256)
			(drill 1.2446)
			(layers "*.Cu" "*.Mask")
			(remove_unused_layers no)
			(net "TP_JUMPER_BLOCK_1_2")
			(clearance 0.127)
			(thermal_gap 0.127)
		)
		(pad "3" thru_hole circle
			(at 0 2.54 90)
			(size 1.6256 1.6256)
			(drill 1.2446)
			(layers "*.Cu" "*.Mask")
			(remove_unused_layers no)
			(net "RST_BMC_SRST_N")
			(clearance 0.127)
			(thermal_gap 0.127)
		)
		(pad "4" thru_hole circle
			(at 2.54 2.54 90)
			(size 1.6256 1.6256)
			(drill 1.2446)
			(layers "*.Cu" "*.Mask")
			(remove_unused_layers no)
			(net "FM_IE_DISABLE_N")
			(clearance 0.127)
			(thermal_gap 0.127)
		)
		(pad "5" thru_hole circle
			(at 0 5.08 90)
			(size 1.6256 1.6256)
			(drill 1.2446)
			(layers "*.Cu" "*.Mask")
			(remove_unused_layers no)
			(net "GND")
			(clearance 0.127)
			(thermal_gap 0.127)
		)
		(pad "6" thru_hole circle
			(at 2.54 5.08 90)
			(size 1.6256 1.6256)
			(drill 1.2446)
			(layers "*.Cu" "*.Mask")
			(remove_unused_layers no)
			(net "GND")
			(clearance 0.127)
			(thermal_gap 0.127)
		)
		(pad "7" thru_hole circle
			(at 0 7.62 90)
			(size 1.6256 1.6256)
			(drill 1.2446)
			(layers "*.Cu" "*.Mask")
			(remove_unused_layers no)
			(net "TP_JUMPER_BLOCK_1_7")
			(clearance 0.127)
			(thermal_gap 0.127)
		)
		(pad "8" thru_hole circle
			(at 2.54 7.62 90)
			(size 1.6256 1.6256)
			(drill 1.2446)
			(layers "*.Cu" "*.Mask")
			(remove_unused_layers no)
			(net "TP_JUMPER_BLOCK_1_8")
			(clearance 0.127)
			(thermal_gap 0.127)
		)
		(pad "9" thru_hole circle
			(at 0 10.16 90)
			(size 1.6256 1.6256)
			(drill 1.2446)
			(layers "*.Cu" "*.Mask")
			(remove_unused_layers no)
			(net "FM_CPLD_UART_CH_LOCK_N")
			(clearance 0.127)
			(thermal_gap 0.127)
		)
		(pad "10" thru_hole circle
			(at 2.54 10.16 90)
			(size 1.6256 1.6256)
			(drill 1.2446)
			(layers "*.Cu" "*.Mask")
			(remove_unused_layers no)
			(net "FM_DIS_ADR_DLY")
			(clearance 0.127)
			(thermal_gap 0.127)
		)
		(pad "11" thru_hole circle
			(at 0 12.7 90)
			(size 1.6256 1.6256)
			(drill 1.2446)
			(layers "*.Cu" "*.Mask")
			(remove_unused_layers no)
			(net "GND")
			(clearance 0.127)
			(thermal_gap 0.127)
		)
		(pad "12" thru_hole circle
			(at 2.54 12.7 90)
			(size 1.6256 1.6256)
			(drill 1.2446)
			(layers "*.Cu" "*.Mask")
			(remove_unused_layers no)
			(net "GND")
			(clearance 0.127)
			(thermal_gap 0.127)
		)
	)
	(footprint ""
		(layer "F.Cu")
		(at 83.856068 -140.208 -90)
		(property "Reference" "C2A10"
			(at 1.848866 0.752348 270)
			(unlocked yes)
			(layer "F.SilkS")
			(effects
				(font
					(size 1.27 0.9652)
					(thickness 0.1524)
				)
			)
		)
		(property "Value" ""
			(at 0 0 270)
			(layer "F.Fab")
			(effects
				(font
					(size 1.27 1.27)
				)
			)
		)
		(duplicate_pad_numbers_are_jumpers no)
		(fp_rect
			(start -0.500126 1.598422)
			(end 0.500126 -0.201422)
			(stroke
				(width 0)
				(type default)
			)
			(fill no)
			(layer "F.CrtYd")
		)
		(fp_line
			(start -0.500126 1.598422)
			(end -0.500126 -0.201422)
			(stroke
				(width 0.1)
				(type default)
			)
			(layer "F.Fab")
		)
		(fp_line
			(start 0.500126 1.598422)
			(end -0.500126 1.598422)
			(stroke
				(width 0.1)
				(type default)
			)
			(layer "F.Fab")
		)
		(fp_line
			(start -0.500126 -0.201422)
			(end 0.500126 -0.201422)
			(stroke
				(width 0.1)
				(type default)
			)
			(layer "F.Fab")
		)
		(fp_line
			(start 0.500126 -0.201422)
			(end 0.500126 1.598422)
			(stroke
				(width 0.1)
				(type default)
			)
			(layer "F.Fab")
		)
		(pad "1" smd rect
			(at 0 0 180)
			(size 0.889 0.9906)
			(layers "F.Cu" "F.Mask" "F.Paste")
			(net "PVDDQ_KLM")
		)
		(pad "2" smd rect
			(at 0 1.397 180)
			(size 0.889 0.9906)
			(layers "F.Cu" "F.Mask" "F.Paste")
			(net "GND")
		)
		(zone
			(layer "F.Cu")
			(hatch none 0.5)
			(connect_pads
				(clearance 0)
			)
			(min_thickness 0.25)
			(keepout
				(tracks not_allowed)
				(vias allowed)
				(pads allowed)
				(copperpour not_allowed)
				(footprints allowed)
			)
			(placement
				(enabled no)
				(sheetname "")
			)
			(fill
				(thermal_gap 0.5)
				(thermal_bridge_width 0.5)
				(island_removal_mode 0)
			)
			(polygon
				(pts
					(xy 82.903568 -140.7033) (xy 82.903568 -139.7127) (xy 83.411568 -139.7127) (xy 83.411568 -140.7033)
				)
			)
		)
		(zone
			(layer "F.Cu")
			(hatch none 0.5)
			(connect_pads
				(clearance 0)
			)
			(min_thickness 0.25)
			(keepout
				(tracks allowed)
				(vias not_allowed)
				(pads allowed)
				(copperpour not_allowed)
				(footprints allowed)
			)
			(placement
				(enabled no)
				(sheetname "")
			)
			(fill
				(thermal_gap 0.5)
				(thermal_bridge_width 0.5)
				(island_removal_mode 0)
			)
			(polygon
				(pts
					(xy 82.903568 -140.7033) (xy 82.903568 -139.7127) (xy 83.411568 -139.7127) (xy 83.411568 -140.7033)
				)
			)
		)
	)
	(footprint ""
		(layer "F.Cu")
		(at 191.897 -23.396194)
		(property "Reference" "C4F9"
			(at 0 0 0)
			(layer "F.SilkS")
			(hide yes)
			(effects
				(font
					(size 1.27 1.27)
				)
			)
		)
		(property "Value" ""
			(at 0 0 0)
			(layer "F.Fab")
			(effects
				(font
					(size 1.27 1.27)
				)
			)
		)
		(duplicate_pad_numbers_are_jumpers no)
		(fp_poly
			(pts
				(xy 0.3048 -0.1016) (xy 0.3048 0.9906) (xy -0.3048 0.9906) (xy -0.3048 -0.1016)
			)
			(stroke
				(width 0)
				(type default)
			)
			(fill no)
			(layer "F.CrtYd")
		)
		(fp_line
			(start -0.3048 -0.1016)
			(end -0.3048 0.9906)
			(stroke
				(width 0.1)
				(type default)
			)
			(layer "F.Fab")
		)
		(fp_line
			(start -0.3048 0.9906)
			(end 0.3048 0.9906)
			(stroke
				(width 0.1)
				(type default)
			)
			(layer "F.Fab")
		)
		(fp_line
			(start 0.3048 -0.1016)
			(end -0.3048 -0.1016)
			(stroke
				(width 0.1)
				(type default)
			)
			(layer "F.Fab")
		)
		(fp_line
			(start 0.3048 0.9906)
			(end 0.3048 -0.1016)
			(stroke
				(width 0.1)
				(type default)
			)
			(layer "F.Fab")
		)
		(pad "1" smd rect
			(at 0 0)
			(size 0.508 0.508)
			(layers "F.Cu" "F.Mask" "F.Paste")
			(net "M_A_CPU_VREF")
		)
		(pad "2" smd rect
			(at 0 0.889)
			(size 0.508 0.508)
			(layers "F.Cu" "F.Mask" "F.Paste")
			(net "GND")
		)
		(zone
			(layer "F.Cu")
			(hatch none 0.5)
			(connect_pads
				(clearance 0)
			)
			(min_thickness 0.25)
			(keepout
				(tracks allowed)
				(vias not_allowed)
				(pads allowed)
				(copperpour not_allowed)
				(footprints allowed)
			)
			(placement
				(enabled no)
				(sheetname "")
			)
			(fill
				(thermal_gap 0.5)
				(thermal_bridge_width 0.5)
				(island_removal_mode 0)
			)
			(polygon
				(pts
					(xy 191.643 -23.142194) (xy 192.151 -23.142194) (xy 192.151 -22.761194) (xy 191.643 -22.761194)
				)
			)
		)
		(zone
			(layer "F.Cu")
			(hatch none 0.5)
			(connect_pads
				(clearance 0)
			)
			(min_thickness 0.25)
			(keepout
				(tracks not_allowed)
				(vias allowed)
				(pads allowed)
				(copperpour not_allowed)
				(footprints allowed)
			)
			(placement
				(enabled no)
				(sheetname "")
			)
			(fill
				(thermal_gap 0.5)
				(thermal_bridge_width 0.5)
				(island_removal_mode 0)
			)
			(polygon
				(pts
					(xy 191.643 -22.761194) (xy 192.151 -22.761194) (xy 192.151 -23.142194) (xy 191.643 -23.142194)
				)
			)
		)
	)
	(footprint ""
		(layer "F.Cu")
		(at 399.542 -77.089 180)
		(property "Reference" "CR8E1"
			(at 1.49733 1.4478 90)
			(unlocked yes)
			(layer "F.SilkS")
			(effects
				(font
					(size 0.7874 0.5842)
					(thickness 0.1524)
				)
				(justify left)
			)
		)
		(property "Value" ""
			(at 0 0 180)
			(layer "F.Fab")
			(effects
				(font
					(size 1.27 1.27)
				)
			)
		)
		(duplicate_pad_numbers_are_jumpers no)
		(fp_line
			(start -0.798576 1.649222)
			(end -1.279398 1.649222)
			(stroke
				(width 0.1524)
				(type default)
			)
			(layer "F.SilkS")
		)
		(fp_line
			(start -0.798576 0.816356)
			(end -1.76022 0.816356)
			(stroke
				(width 0.1524)
				(type default)
			)
			(layer "F.SilkS")
		)
		(fp_line
			(start -1.279398 2.560828)
			(end -1.279398 1.649222)
			(stroke
				(width 0.1524)
				(type default)
			)
			(layer "F.SilkS")
		)
		(fp_line
			(start -1.279398 1.649222)
			(end -1.76022 1.649222)
			(stroke
				(width 0.1524)
				(type default)
			)
			(layer "F.SilkS")
		)
		(fp_line
			(start -1.279398 0.816356)
			(end -0.798576 1.649222)
			(stroke
				(width 0.1524)
				(type default)
			)
			(layer "F.SilkS")
		)
		(fp_line
			(start -1.279398 -0.307086)
			(end -1.279398 0.816356)
			(stroke
				(width 0.1524)
				(type default)
			)
			(layer "F.SilkS")
		)
		(fp_line
			(start -1.76022 1.649222)
			(end -1.279398 0.816356)
			(stroke
				(width 0.1524)
				(type default)
			)
			(layer "F.SilkS")
		)
		(fp_poly
			(pts
				(xy -0.67437 0.24384) (xy -0.67437 2.04216) (xy 0.67437 2.04216) (xy 0.67437 0.24384)
			)
			(stroke
				(width 0)
				(type default)
			)
			(fill no)
			(layer "F.CrtYd")
		)
		(fp_line
			(start 0.67437 2.04216)
			(end 0.67437 0.24384)
			(stroke
				(width 0.1)
				(type default)
			)
			(layer "F.Fab")
		)
		(fp_line
			(start 0.67437 0.24384)
			(end -0.67437 0.24384)
			(stroke
				(width 0.1)
				(type default)
			)
			(layer "F.Fab")
		)
		(fp_line
			(start -0.67437 2.04216)
			(end 0.67437 2.04216)
			(stroke
				(width 0.1)
				(type default)
			)
			(layer "F.Fab")
		)
		(fp_line
			(start -0.67437 0.24384)
			(end -0.67437 2.04216)
			(stroke
				(width 0.1)
				(type default)
			)
			(layer "F.Fab")
		)
		(fp_line
			(start -0.803656 1.664462)
			(end -1.7653 1.664462)
			(stroke
				(width 0.1)
				(type default)
			)
			(layer "F.Fab")
		)
		(fp_line
			(start -0.854456 0.831596)
			(end -1.8161 0.831596)
			(stroke
				(width 0.1)
				(type default)
			)
			(layer "F.Fab")
		)
		(fp_line
			(start -1.284478 1.664462)
			(end -1.284478 2.576068)
			(stroke
				(width 0.1)
				(type default)
			)
			(layer "F.Fab")
		)
		(fp_line
			(start -1.284478 0.831596)
			(end -0.803656 1.664462)
			(stroke
				(width 0.1)
				(type default)
			)
			(layer "F.Fab")
		)
		(fp_line
			(start -1.335278 0.831596)
			(end -1.335278 -0.291846)
			(stroke
				(width 0.1)
				(type default)
			)
			(layer "F.Fab")
		)
		(fp_line
			(start -1.7653 1.664462)
			(end -1.284478 0.831596)
			(stroke
				(width 0.1)
				(type default)
			)
			(layer "F.Fab")
		)
		(pad "1" smd rect
			(at 0 0 180)
			(size 0.4064 1.016)
			(layers "F.Cu" "F.Mask" "F.Paste")
			(net "PWRGD_P12V_HSC")
		)
		(pad "2" smd rect
			(at 0 2.286 180)
			(size 0.4064 1.016)
			(layers "F.Cu" "F.Mask" "F.Paste")
			(net "PWRGD_P12V_HSC_DLY")
		)
	)
	(footprint ""
		(layer "F.Cu")
		(at 354.244656 -137.833608 180)
		(property "Reference" "R12W10"
			(at 0 0 180)
			(layer "F.SilkS")
			(hide yes)
			(effects
				(font
					(size 1.27 1.27)
				)
			)
		)
		(property "Value" "*"
			(at 0.064008 -4.108196 180)
			(unlocked yes)
			(layer "F.Fab")
			(hide yes)
			(effects
				(font
					(size 1.27 1.016)
					(thickness 0.1524)
				)
			)
		)
		(property "Device Type" "665KR2B-GP_SMD-RG2-665KR2B-GP,A"
			(at 0.064008 -5.632196 180)
			(unlocked yes)
			(layer "F.Fab")
			(hide yes)
			(effects
				(font
					(size 1.27 1.016)
					(thickness 0.1524)
				)
			)
		)
		(duplicate_pad_numbers_are_jumpers no)
		(fp_line
			(start 0.508 -0.9398)
			(end -0.508 -0.9398)
			(stroke
				(width 0.1524)
				(type default)
			)
			(layer "F.SilkS")
		)
		(fp_line
			(start -0.508 -0.9398)
			(end -0.508 0.9398)
			(stroke
				(width 0.1524)
				(type default)
			)
			(layer "F.SilkS")
		)
		(fp_rect
			(start -0.508 0.9398)
			(end 0.508 -0.9398)
			(stroke
				(width 0)
				(type default)
			)
			(fill no)
			(layer "F.CrtYd")
		)
		(fp_rect
			(start -0.508 0.9398)
			(end 0.508 -0.9398)
			(stroke
				(width 0)
				(type default)
			)
			(fill no)
			(layer "F.Fab")
		)
		(pad "1" smd custom
			(at 0 -0.4445 180)
			(size 0.1397 0.1397)
			(layers "F.Cu" "F.Mask" "F.Paste")
			(net "VR_PVDDQ_DEF_AIINSEN")
			(options
				(clearance outline)
				(anchor circle)
			)
			(primitives
				(gr_poly
					(pts
						(arc
							(start -0.1778 -0.2794)
							(mid -0.249642 -0.249642)
							(end -0.2794 -0.1778)
						)
						(arc
							(start -0.2794 0.1778)
							(mid -0.249642 0.249642)
							(end -0.1778 0.2794)
						)
						(arc
							(start 0.1778 0.2794)
							(mid 0.249642 0.249642)
							(end 0.2794 0.1778)
						)
						(arc
							(start 0.2794 -0.1778)
							(mid 0.249642 -0.249642)
							(end 0.1778 -0.2794)
						)
					)
					(width 0)
					(fill yes)
				)
			)
		)
		(pad "2" smd custom
			(at 0 0.4445 180)
			(size 0.1397 0.1397)
			(layers "F.Cu" "F.Mask" "F.Paste")
			(net "VR_PVDDQ_DEF_VINSEN")
			(options
				(clearance outline)
				(anchor circle)
			)
			(primitives
				(gr_poly
					(pts
						(arc
							(start -0.1778 -0.2794)
							(mid -0.249642 -0.249642)
							(end -0.2794 -0.1778)
						)
						(arc
							(start -0.2794 0.1778)
							(mid -0.249642 0.249642)
							(end -0.1778 0.2794)
						)
						(arc
							(start 0.1778 0.2794)
							(mid 0.249642 0.249642)
							(end 0.2794 0.1778)
						)
						(arc
							(start 0.2794 -0.1778)
							(mid 0.249642 -0.249642)
							(end 0.1778 -0.2794)
						)
					)
					(width 0)
					(fill yes)
				)
			)
		)
	)
	(footprint ""
		(layer "F.Cu")
		(at 339.092032 -129.587498 90)
		(property "Reference" "R7B9"
			(at 0 0 90)
			(layer "F.SilkS")
			(hide yes)
			(effects
				(font
					(size 1.27 1.27)
				)
			)
		)
		(property "Value" ""
			(at 0 0 90)
			(layer "F.Fab")
			(effects
				(font
					(size 1.27 1.27)
				)
			)
		)
		(duplicate_pad_numbers_are_jumpers no)
		(fp_poly
			(pts
				(xy -0.2794 -0.1016) (xy 0.2794 -0.1016) (xy 0.2794 0.9906) (xy -0.2794 0.9906)
			)
			(stroke
				(width 0)
				(type default)
			)
			(fill no)
			(layer "F.CrtYd")
		)
		(fp_line
			(start 0.2794 -0.1016)
			(end -0.2794 -0.1016)
			(stroke
				(width 0.1)
				(type default)
			)
			(layer "F.Fab")
		)
		(fp_line
			(start -0.2794 -0.1016)
			(end -0.2794 0.9906)
			(stroke
				(width 0.1)
				(type default)
			)
			(layer "F.Fab")
		)
		(fp_line
			(start 0.2794 0.9906)
			(end 0.2794 -0.1016)
			(stroke
				(width 0.1)
				(type default)
			)
			(layer "F.Fab")
		)
		(fp_line
			(start -0.2794 0.9906)
			(end 0.2794 0.9906)
			(stroke
				(width 0.1)
				(type default)
			)
			(layer "F.Fab")
		)
		(pad "1" smd rect
			(at 0 0 90)
			(size 0.508 0.508)
			(layers "F.Cu" "F.Mask" "F.Paste")
			(net "FM_PVPP_CPU0_EN")
		)
		(pad "2" smd rect
			(at 0 0.889 90)
			(size 0.508 0.508)
			(layers "F.Cu" "F.Mask" "F.Paste")
			(net "FM_PVPP_PVDDQ_CPU0_EN_DEF")
		)
		(zone
			(layer "F.Cu")
			(hatch none 0.5)
			(connect_pads
				(clearance 0)
			)
			(min_thickness 0.25)
			(keepout
				(tracks allowed)
				(vias not_allowed)
				(pads allowed)
				(copperpour not_allowed)
				(footprints allowed)
			)
			(placement
				(enabled no)
				(sheetname "")
			)
			(fill
				(thermal_gap 0.5)
				(thermal_bridge_width 0.5)
				(island_removal_mode 0)
			)
			(polygon
				(pts
					(xy 339.346032 -129.333498) (xy 339.346032 -129.841498) (xy 339.727032 -129.841498) (xy 339.727032 -129.333498)
				)
			)
		)
		(zone
			(layer "F.Cu")
			(hatch none 0.5)
			(connect_pads
				(clearance 0)
			)
			(min_thickness 0.25)
			(keepout
				(tracks not_allowed)
				(vias allowed)
				(pads allowed)
				(copperpour not_allowed)
				(footprints allowed)
			)
			(placement
				(enabled no)
				(sheetname "")
			)
			(fill
				(thermal_gap 0.5)
				(thermal_bridge_width 0.5)
				(island_removal_mode 0)
			)
			(polygon
				(pts
					(xy 339.727032 -129.333498) (xy 339.727032 -129.841498) (xy 339.346032 -129.841498) (xy 339.346032 -129.333498)
				)
			)
		)
	)
	(footprint ""
		(layer "F.Cu")
		(at 456.1713 -27.432 90)
		(property "Reference" "Q9F1"
			(at 0.92202 -1.23317 90)
			(unlocked yes)
			(layer "F.SilkS")
			(effects
				(font
					(size 0.7874 0.5842)
					(thickness 0.1524)
				)
				(justify left)
			)
		)
		(property "Value" ""
			(at 0 0 90)
			(layer "F.Fab")
			(effects
				(font
					(size 1.27 1.27)
				)
			)
		)
		(duplicate_pad_numbers_are_jumpers no)
		(fp_circle
			(center -0.788416 -0.597662)
			(end -0.788416 -0.470662)
			(stroke
				(width 0.254)
				(type default)
			)
			(fill no)
			(layer "F.SilkS")
		)
		(fp_poly
			(pts
				(xy 0.2159 1.7526) (xy 1.5621 1.7526) (xy 1.5621 -0.4572) (xy 0.2159 -0.4572)
			)
			(stroke
				(width 0)
				(type default)
			)
			(fill no)
			(layer "F.CrtYd")
		)
		(fp_line
			(start 1.5621 -0.45466)
			(end 0.2159 -0.45466)
			(stroke
				(width 0.1)
				(type default)
			)
			(layer "F.Fab")
		)
		(fp_line
			(start 0.2159 -0.45466)
			(end 0.2159 1.75514)
			(stroke
				(width 0.1)
				(type default)
			)
			(layer "F.Fab")
		)
		(fp_line
			(start 1.5621 1.75514)
			(end 1.5621 -0.45466)
			(stroke
				(width 0.1)
				(type default)
			)
			(layer "F.Fab")
		)
		(fp_line
			(start 0.2159 1.75514)
			(end 1.5621 1.75514)
			(stroke
				(width 0.1)
				(type default)
			)
			(layer "F.Fab")
		)
		(fp_circle
			(center -0.508 -0.7874)
			(end -0.508 -0.6604)
			(stroke
				(width 0.254)
				(type default)
			)
			(fill no)
			(layer "F.Fab")
		)
		(pad "1" smd rect
			(at 0 0 90)
			(size 1.016 0.381)
			(layers "F.Cu" "F.Mask" "F.Paste")
			(net "GND")
		)
		(pad "2" smd rect
			(at 0 0.65024 90)
			(size 1.016 0.381)
			(layers "F.Cu" "F.Mask" "F.Paste")
			(net "FM_BMC_FAULT_LED_N")
		)
		(pad "3" smd rect
			(at 0 1.30048 90)
			(size 1.016 0.381)
			(layers "F.Cu" "F.Mask" "F.Paste")
			(net "FM_RED_LED_CATHODE")
		)
		(pad "4" smd rect
			(at 1.778 1.30048 90)
			(size 1.016 0.381)
			(layers "F.Cu" "F.Mask" "F.Paste")
			(net "GND")
		)
		(pad "5" smd rect
			(at 1.778 0.65024 90)
			(size 1.016 0.381)
			(layers "F.Cu" "F.Mask" "F.Paste")
			(net "FM_BMC_FAULT_LED")
		)
		(pad "6" smd rect
			(at 1.778 0 90)
			(size 1.016 0.381)
			(layers "F.Cu" "F.Mask" "F.Paste")
			(net "FM_BMC_FAULT_LED")
		)
		(zone
			(layer "F.Cu")
			(hatch none 0.5)
			(connect_pads
				(clearance 0)
			)
			(min_thickness 0.25)
			(keepout
				(tracks allowed)
				(vias not_allowed)
				(pads allowed)
				(copperpour not_allowed)
				(footprints allowed)
			)
			(placement
				(enabled no)
				(sheetname "")
			)
			(fill
				(thermal_gap 0.5)
				(thermal_bridge_width 0.5)
				(island_removal_mode 0)
			)
			(polygon
				(pts
					(xy 455.9808 -28.702) (xy 455.9808 -29.718) (xy 457.6699 -29.718) (xy 457.6699 -28.702)
				)
			)
		)
		(zone
			(layer "F.Cu")
			(hatch none 0.5)
			(connect_pads
				(clearance 0)
			)
			(min_thickness 0.25)
			(keepout
				(tracks allowed)
				(vias not_allowed)
				(pads allowed)
				(copperpour not_allowed)
				(footprints allowed)
			)
			(placement
				(enabled no)
				(sheetname "")
			)
			(fill
				(thermal_gap 0.5)
				(thermal_bridge_width 0.5)
				(island_removal_mode 0)
			)
			(polygon
				(pts
					(xy 455.9808 -26.924) (xy 455.9808 -27.94) (xy 457.6699 -27.94) (xy 457.6699 -26.924)
				)
			)
		)
	)
	(footprint ""
		(layer "F.Cu")
		(at 0.130048 -110.259876)
		(property "Reference" "J10W1"
			(at 0 0 0)
			(layer "F.SilkS")
			(hide yes)
			(effects
				(font
					(size 1.27 1.27)
				)
			)
		)
		(property "Value" "*"
			(at -6.3881 -0.97155 0)
			(unlocked yes)
			(layer "F.Fab")
			(hide yes)
			(effects
				(font
					(size 0.889 0.889)
					(thickness 0.1524)
				)
			)
		)
		(property "Device Type" "LOTES-CON4-S1-GP_CONN-G7-LOTESA"
			(at -6.3881 -2.49555 0)
			(unlocked yes)
			(layer "F.Fab")
			(hide yes)
			(effects
				(font
					(size 0.889 0.889)
					(thickness 0.1524)
				)
			)
		)
		(duplicate_pad_numbers_are_jumpers no)
		(fp_line
			(start -5.334 -3.302)
			(end 5.334 -3.302)
			(stroke
				(width 0.508)
				(type default)
			)
			(layer "F.SilkS")
		)
		(fp_line
			(start -5.334 -3.1242)
			(end 5.334 -3.1242)
			(stroke
				(width 0.1524)
				(type default)
			)
			(layer "F.SilkS")
		)
		(fp_line
			(start -5.334 3.0226)
			(end -5.334 -3.1242)
			(stroke
				(width 0.1524)
				(type default)
			)
			(layer "F.SilkS")
		)
		(fp_line
			(start 4.191 3.16484)
			(end 5.461 3.16484)
			(stroke
				(width 0.4064)
				(type default)
			)
			(layer "F.SilkS")
		)
		(fp_line
			(start 5.334 -3.1242)
			(end 5.334 3.0226)
			(stroke
				(width 0.1524)
				(type default)
			)
			(layer "F.SilkS")
		)
		(fp_line
			(start 5.334 3.0226)
			(end -5.334 3.0226)
			(stroke
				(width 0.1524)
				(type default)
			)
			(layer "F.SilkS")
		)
		(fp_line
			(start 5.461 3.16484)
			(end 5.461 1.89484)
			(stroke
				(width 0.4064)
				(type default)
			)
			(layer "F.SilkS")
		)
		(fp_circle
			(center -3.81 0)
			(end -2.5527 0)
			(stroke
				(width 0.3048)
				(type default)
			)
			(fill no)
			(layer "F.SilkS")
		)
		(fp_circle
			(center -1.27 0)
			(end -0.0127 0)
			(stroke
				(width 0.3048)
				(type default)
			)
			(fill no)
			(layer "F.SilkS")
		)
		(fp_circle
			(center 1.27 0)
			(end 2.5273 0)
			(stroke
				(width 0.3048)
				(type default)
			)
			(fill no)
			(layer "F.SilkS")
		)
		(fp_circle
			(center 3.81 0)
			(end 5.0673 0)
			(stroke
				(width 0.3048)
				(type default)
			)
			(fill no)
			(layer "F.SilkS")
		)
		(fp_rect
			(start -5.08 2.54)
			(end 5.08 -2.8702)
			(stroke
				(width 0)
				(type default)
			)
			(fill no)
			(layer "F.CrtYd")
		)
		(fp_poly
			(pts
				(xy -5.588 3.2766) (xy -5.588 -3.3782) (xy 5.588 -3.3782) (xy 5.588 -0.00635) (xy 5.08 -0.00635)
				(xy 5.08 -2.8702) (xy -5.08 -2.8702) (xy -5.08 2.54) (xy 5.08 2.54) (xy 5.08 0.00635) (xy 5.588 0.00635)
				(xy 5.588 3.2766)
			)
			(stroke
				(width 0)
				(type default)
			)
			(fill no)
			(layer "F.CrtYd")
		)
		(fp_rect
			(start -5.588 3.2766)
			(end 5.588 -3.3782)
			(stroke
				(width 0)
				(type default)
			)
			(fill no)
			(layer "F.Fab")
		)
		(pad "" np_thru_hole circle
			(at -1.27 2.189988)
			(size 0.254 0.254)
			(drill 1.1684)
			(layers "*.Cu" "*.Mask")
			(clearance 0.8128)
			(thermal_gap 0.8128)
		)
		(pad "1" thru_hole circle
			(at 3.81 0)
			(size 1.8034 1.8034)
			(drill 1.1684)
			(layers "*.Cu" "*.Mask")
			(remove_unused_layers no)
			(net "GND")
			(clearance 0.1905)
			(thermal_gap 0.1905)
		)
		(pad "2" thru_hole circle
			(at 1.27 0)
			(size 1.8034 1.8034)
			(drill 1.1684)
			(layers "*.Cu" "*.Mask")
			(remove_unused_layers no)
			(net "P12V_FAN")
			(clearance 0.1905)
			(thermal_gap 0.1905)
		)
		(pad "3" thru_hole circle
			(at -1.27 0)
			(size 1.8034 1.8034)
			(drill 1.1684)
			(layers "*.Cu" "*.Mask")
			(remove_unused_layers no)
			(net "FAN_TACH2_CPU1_D1")
			(clearance 0.1905)
			(thermal_gap 0.1905)
		)
		(pad "4" thru_hole circle
			(at -3.81 0)
			(size 1.8034 1.8034)
			(drill 1.1684)
			(layers "*.Cu" "*.Mask")
			(remove_unused_layers no)
			(net "FAN_PWM_OUT_SYS1_R")
			(clearance 0.1905)
			(thermal_gap 0.1905)
		)
		(zone
			(layers "F.Cu" "B.Cu" "In1.Cu" "In2.Cu" "In3.Cu" "In4.Cu" "In5.Cu" "In6.Cu"
				"In7.Cu" "In8.Cu" "In9.Cu" "In10.Cu" "In11.Cu" "In12.Cu"
			)
			(hatch none 0.5)
			(connect_pads
				(clearance 0)
			)
			(min_thickness 0.25)
			(keepout
				(tracks not_allowed)
				(vias allowed)
				(pads allowed)
				(copperpour not_allowed)
				(footprints allowed)
			)
			(placement
				(enabled no)
				(sheetname "")
			)
			(fill
				(thermal_gap 0.5)
				(thermal_bridge_width 0.5)
				(island_removal_mode 0)
			)
			(polygon
				(pts
					(arc
						(start -0.250952 -108.069888)
						(mid -2.028952 -108.069888)
						(end -0.250952 -108.069888)
					)
				)
			)
		)
	)
	(footprint ""
		(layer "F.Cu")
		(at 202.079098 -69.316092 -90)
		(property "Reference" "RT26"
			(at 0 0 270)
			(layer "F.SilkS")
			(hide yes)
			(effects
				(font
					(size 1.27 1.27)
				)
			)
		)
		(property "Value" "*"
			(at -0.0254 -2.6289 270)
			(unlocked yes)
			(layer "F.Fab")
			(hide yes)
			(effects
				(font
					(size 1.27 1.016)
					(thickness 0.1524)
				)
			)
		)
		(property "Device Type" "1R3F-GP_RCL_GP-1R3F-GP,64.1R00A"
			(at -0.0254 -4.1529 270)
			(unlocked yes)
			(layer "F.Fab")
			(hide yes)
			(effects
				(font
					(size 1.27 1.016)
					(thickness 0.1524)
				)
			)
		)
		(duplicate_pad_numbers_are_jumpers no)
		(fp_line
			(start -0.4826 0)
			(end -0.2032 0)
			(stroke
				(width 0.2032)
				(type default)
			)
			(layer "F.SilkS")
		)
		(fp_line
			(start 0.2032 0)
			(end 0.4826 0)
			(stroke
				(width 0.2032)
				(type default)
			)
			(layer "F.SilkS")
		)
		(fp_rect
			(start -0.5842 1.3335)
			(end 0.5842 -1.3335)
			(stroke
				(width 0)
				(type default)
			)
			(fill no)
			(layer "F.CrtYd")
		)
		(fp_rect
			(start -0.5842 1.3335)
			(end 0.5842 -1.3335)
			(stroke
				(width 0)
				(type default)
			)
			(fill no)
			(layer "F.Fab")
		)
		(pad "1" smd custom
			(at 0 -0.762 270)
			(size 0.2159 0.2159)
			(layers "F.Cu" "F.Mask" "F.Paste")
			(net "VR_PVCCIN_CPU0_PHASE3_RC")
			(options
				(clearance outline)
				(anchor circle)
			)
			(primitives
				(gr_poly
					(pts
						(arc
							(start -0.3302 -0.4318)
							(mid -0.402042 -0.402042)
							(end -0.4318 -0.3302)
						)
						(arc
							(start -0.4318 0.3302)
							(mid -0.402042 0.402042)
							(end -0.3302 0.4318)
						)
						(arc
							(start 0.3302 0.4318)
							(mid 0.402042 0.402042)
							(end 0.4318 0.3302)
						)
						(arc
							(start 0.4318 -0.3302)
							(mid 0.402042 -0.402042)
							(end 0.3302 -0.4318)
						)
					)
					(width 0)
					(fill yes)
				)
			)
		)
		(pad "2" smd custom
			(at 0 0.762 270)
			(size 0.2159 0.2159)
			(layers "F.Cu" "F.Mask" "F.Paste")
			(net "GND")
			(options
				(clearance outline)
				(anchor circle)
			)
			(primitives
				(gr_poly
					(pts
						(arc
							(start -0.3302 -0.4318)
							(mid -0.402042 -0.402042)
							(end -0.4318 -0.3302)
						)
						(arc
							(start -0.4318 0.3302)
							(mid -0.402042 0.402042)
							(end -0.3302 0.4318)
						)
						(arc
							(start 0.3302 0.4318)
							(mid 0.402042 0.402042)
							(end 0.4318 0.3302)
						)
						(arc
							(start 0.4318 -0.3302)
							(mid 0.402042 -0.402042)
							(end 0.3302 -0.4318)
						)
					)
					(width 0)
					(fill yes)
				)
			)
		)
	)
	(footprint ""
		(layer "F.Cu")
		(at 409.928822 -11.436858)
		(property "Reference" "C8G9"
			(at 0 0 0)
			(layer "F.SilkS")
			(hide yes)
			(effects
				(font
					(size 1.27 1.27)
				)
			)
		)
		(property "Value" ""
			(at 0 0 0)
			(layer "F.Fab")
			(effects
				(font
					(size 1.27 1.27)
				)
			)
		)
		(duplicate_pad_numbers_are_jumpers no)
		(fp_rect
			(start -0.3048 0.9906)
			(end 0.3048 -0.1016)
			(stroke
				(width 0)
				(type default)
			)
			(fill no)
			(layer "F.CrtYd")
		)
		(fp_line
			(start -0.3048 -0.1016)
			(end -0.3048 0.9906)
			(stroke
				(width 0.1)
				(type default)
			)
			(layer "F.Fab")
		)
		(fp_line
			(start -0.3048 0.9906)
			(end 0.3048 0.9906)
			(stroke
				(width 0.1)
				(type default)
			)
			(layer "F.Fab")
		)
		(fp_line
			(start 0.3048 -0.1016)
			(end -0.3048 -0.1016)
			(stroke
				(width 0.1)
				(type default)
			)
			(layer "F.Fab")
		)
		(fp_line
			(start 0.3048 0.9906)
			(end 0.3048 -0.1016)
			(stroke
				(width 0.1)
				(type default)
			)
			(layer "F.Fab")
		)
		(pad "1" smd rect
			(at 0 0)
			(size 0.508 0.508)
			(layers "F.Cu" "F.Mask" "F.Paste")
			(net "P3E_CPU0_PE2_SS_TXP<0>")
		)
		(pad "2" smd rect
			(at 0 0.889)
			(size 0.508 0.508)
			(layers "F.Cu" "F.Mask" "F.Paste")
			(net "P3E_CPU0_PE2_SS_C_TXP<0>")
		)
		(zone
			(layer "F.Cu")
			(hatch none 0.5)
			(connect_pads
				(clearance 0)
			)
			(min_thickness 0.25)
			(keepout
				(tracks allowed)
				(vias not_allowed)
				(pads allowed)
				(copperpour not_allowed)
				(footprints allowed)
			)
			(placement
				(enabled no)
				(sheetname "")
			)
			(fill
				(thermal_gap 0.5)
				(thermal_bridge_width 0.5)
				(island_removal_mode 0)
			)
			(polygon
				(pts
					(xy 409.674822 -10.801858) (xy 410.182822 -10.801858) (xy 410.182822 -11.182858) (xy 409.674822 -11.182858)
				)
			)
		)
	)
	(footprint ""
		(layer "F.Cu")
		(at 467.90102 -35.052 -90)
		(property "Reference" "C9W19"
			(at 0.97536 0.76708 180)
			(unlocked yes)
			(layer "F.SilkS")
			(effects
				(font
					(size 0.4064 0.254)
					(thickness 0.1524)
				)
			)
		)
		(property "Value" ""
			(at 0 0 270)
			(layer "F.Fab")
			(effects
				(font
					(size 1.27 1.27)
				)
			)
		)
		(duplicate_pad_numbers_are_jumpers no)
		(fp_poly
			(pts
				(xy -0.4953 -0.2032) (xy 0.4953 -0.2032) (xy 0.4953 1.6002) (xy -0.4953 1.6002)
			)
			(stroke
				(width 0)
				(type default)
			)
			(fill no)
			(layer "F.CrtYd")
		)
		(fp_line
			(start -0.4953 1.6002)
			(end -0.4953 -0.2032)
			(stroke
				(width 0.1)
				(type default)
			)
			(layer "F.Fab")
		)
		(fp_line
			(start 0.4953 1.6002)
			(end -0.4953 1.6002)
			(stroke
				(width 0.1)
				(type default)
			)
			(layer "F.Fab")
		)
		(fp_line
			(start -0.4953 -0.2032)
			(end 0.4953 -0.2032)
			(stroke
				(width 0.1)
				(type default)
			)
			(layer "F.Fab")
		)
		(fp_line
			(start 0.4953 -0.2032)
			(end 0.4953 1.6002)
			(stroke
				(width 0.1)
				(type default)
			)
			(layer "F.Fab")
		)
		(pad "1" smd rect
			(at 0 0 270)
			(size 0.762 0.889)
			(layers "F.Cu" "F.Mask" "F.Paste")
			(net "P1V2_AUX_BMC")
		)
		(pad "2" smd rect
			(at 0 1.397 270)
			(size 0.762 0.889)
			(layers "F.Cu" "F.Mask" "F.Paste")
			(net "GND")
		)
		(zone
			(layer "F.Cu")
			(hatch none 0.5)
			(connect_pads
				(clearance 0)
			)
			(min_thickness 0.25)
			(keepout
				(tracks not_allowed)
				(vias allowed)
				(pads allowed)
				(copperpour not_allowed)
				(footprints allowed)
			)
			(placement
				(enabled no)
				(sheetname "")
			)
			(fill
				(thermal_gap 0.5)
				(thermal_bridge_width 0.5)
				(island_removal_mode 0)
			)
			(polygon
				(pts
					(xy 467.45652 -35.433) (xy 467.45652 -34.671) (xy 466.94852 -34.671) (xy 466.94852 -35.433)
				)
			)
		)
	)
	(footprint ""
		(layer "F.Cu")
		(at 259.4356 -3.321812 90)
		(property "Reference" "C5G20"
			(at 0 0 90)
			(layer "F.SilkS")
			(hide yes)
			(effects
				(font
					(size 1.27 1.27)
				)
			)
		)
		(property "Value" ""
			(at 0 0 90)
			(layer "F.Fab")
			(effects
				(font
					(size 1.27 1.27)
				)
			)
		)
		(duplicate_pad_numbers_are_jumpers no)
		(fp_rect
			(start -0.7239 -0.2159)
			(end 0.7239 1.9939)
			(stroke
				(width 0)
				(type default)
			)
			(fill no)
			(layer "F.CrtYd")
		)
		(fp_line
			(start 0.7239 -0.2159)
			(end -0.7239 -0.2159)
			(stroke
				(width 0.1)
				(type default)
			)
			(layer "F.Fab")
		)
		(fp_line
			(start -0.7239 -0.2159)
			(end -0.7239 1.9939)
			(stroke
				(width 0.1)
				(type default)
			)
			(layer "F.Fab")
		)
		(fp_line
			(start 0.7239 1.9939)
			(end 0.7239 -0.2159)
			(stroke
				(width 0.1)
				(type default)
			)
			(layer "F.Fab")
		)
		(fp_line
			(start -0.7239 1.9939)
			(end 0.7239 1.9939)
			(stroke
				(width 0.1)
				(type default)
			)
			(layer "F.Fab")
		)
		(pad "1" smd rect
			(at 0 0 90)
			(size 1.27 1.016)
			(layers "F.Cu" "F.Mask" "F.Paste")
			(net "PVDDQ_ABC")
		)
		(pad "2" smd rect
			(at 0 1.778 90)
			(size 1.27 1.016)
			(layers "F.Cu" "F.Mask" "F.Paste")
			(net "GND")
		)
		(zone
			(layer "F.Cu")
			(hatch none 0.5)
			(connect_pads
				(clearance 0)
			)
			(min_thickness 0.25)
			(keepout
				(tracks not_allowed)
				(vias allowed)
				(pads allowed)
				(copperpour not_allowed)
				(footprints allowed)
			)
			(placement
				(enabled no)
				(sheetname "")
			)
			(fill
				(thermal_gap 0.5)
				(thermal_bridge_width 0.5)
				(island_removal_mode 0)
			)
			(polygon
				(pts
					(xy 259.9436 -2.686812) (xy 260.7056 -2.686812) (xy 260.7056 -3.956812) (xy 259.9436 -3.956812)
				)
			)
		)
	)
	(footprint ""
		(layer "F.Cu")
		(at 193.675 -3.7465)
		(property "Reference" "R4G21"
			(at 0 0 0)
			(layer "F.SilkS")
			(hide yes)
			(effects
				(font
					(size 1.27 1.27)
				)
			)
		)
		(property "Value" ""
			(at 0 0 0)
			(layer "F.Fab")
			(effects
				(font
					(size 1.27 1.27)
				)
			)
		)
		(duplicate_pad_numbers_are_jumpers no)
		(fp_poly
			(pts
				(xy -0.2794 -0.1016) (xy 0.2794 -0.1016) (xy 0.2794 0.9906) (xy -0.2794 0.9906)
			)
			(stroke
				(width 0)
				(type default)
			)
			(fill no)
			(layer "F.CrtYd")
		)
		(fp_line
			(start -0.2794 -0.1016)
			(end -0.2794 0.9906)
			(stroke
				(width 0.1)
				(type default)
			)
			(layer "F.Fab")
		)
		(fp_line
			(start -0.2794 0.9906)
			(end 0.2794 0.9906)
			(stroke
				(width 0.1)
				(type default)
			)
			(layer "F.Fab")
		)
		(fp_line
			(start 0.2794 -0.1016)
			(end -0.2794 -0.1016)
			(stroke
				(width 0.1)
				(type default)
			)
			(layer "F.Fab")
		)
		(fp_line
			(start 0.2794 0.9906)
			(end 0.2794 -0.1016)
			(stroke
				(width 0.1)
				(type default)
			)
			(layer "F.Fab")
		)
		(pad "1" smd rect
			(at 0 0)
			(size 0.508 0.508)
			(layers "F.Cu" "F.Mask" "F.Paste")
			(net "PVDDQ_ABC")
		)
		(pad "2" smd rect
			(at 0 0.889)
			(size 0.508 0.508)
			(layers "F.Cu" "F.Mask" "F.Paste")
			(net "M_C_VREF")
		)
		(zone
			(layer "F.Cu")
			(hatch none 0.5)
			(connect_pads
				(clearance 0)
			)
			(min_thickness 0.25)
			(keepout
				(tracks allowed)
				(vias not_allowed)
				(pads allowed)
				(copperpour not_allowed)
				(footprints allowed)
			)
			(placement
				(enabled no)
				(sheetname "")
			)
			(fill
				(thermal_gap 0.5)
				(thermal_bridge_width 0.5)
				(island_removal_mode 0)
			)
			(polygon
				(pts
					(xy 193.421 -3.4925) (xy 193.929 -3.4925) (xy 193.929 -3.1115) (xy 193.421 -3.1115)
				)
			)
		)
		(zone
			(layer "F.Cu")
			(hatch none 0.5)
			(connect_pads
				(clearance 0)
			)
			(min_thickness 0.25)
			(keepout
				(tracks not_allowed)
				(vias allowed)
				(pads allowed)
				(copperpour not_allowed)
				(footprints allowed)
			)
			(placement
				(enabled no)
				(sheetname "")
			)
			(fill
				(thermal_gap 0.5)
				(thermal_bridge_width 0.5)
				(island_removal_mode 0)
			)
			(polygon
				(pts
					(xy 193.421 -3.1115) (xy 193.929 -3.1115) (xy 193.929 -3.4925) (xy 193.421 -3.4925)
				)
			)
		)
	)
	(footprint ""
		(layer "F.Cu")
		(at 214.8586 -94.4372)
		(property "Reference" "C4C11"
			(at 0.97536 0.76708 270)
			(unlocked yes)
			(layer "F.SilkS")
			(effects
				(font
					(size 0.4064 0.254)
					(thickness 0.1524)
				)
			)
		)
		(property "Value" ""
			(at 0 0 0)
			(layer "F.Fab")
			(effects
				(font
					(size 1.27 1.27)
				)
			)
		)
		(duplicate_pad_numbers_are_jumpers no)
		(fp_poly
			(pts
				(xy -0.4953 -0.2032) (xy 0.4953 -0.2032) (xy 0.4953 1.6002) (xy -0.4953 1.6002)
			)
			(stroke
				(width 0)
				(type default)
			)
			(fill no)
			(layer "F.CrtYd")
		)
		(fp_line
			(start -0.4953 -0.2032)
			(end 0.4953 -0.2032)
			(stroke
				(width 0.1)
				(type default)
			)
			(layer "F.Fab")
		)
		(fp_line
			(start -0.4953 1.6002)
			(end -0.4953 -0.2032)
			(stroke
				(width 0.1)
				(type default)
			)
			(layer "F.Fab")
		)
		(fp_line
			(start 0.4953 -0.2032)
			(end 0.4953 1.6002)
			(stroke
				(width 0.1)
				(type default)
			)
			(layer "F.Fab")
		)
		(fp_line
			(start 0.4953 1.6002)
			(end -0.4953 1.6002)
			(stroke
				(width 0.1)
				(type default)
			)
			(layer "F.Fab")
		)
		(pad "1" smd rect
			(at 0 0)
			(size 0.762 0.889)
			(layers "F.Cu" "F.Mask" "F.Paste")
			(net "PVSA_CPU0")
		)
		(pad "2" smd rect
			(at 0 1.397)
			(size 0.762 0.889)
			(layers "F.Cu" "F.Mask" "F.Paste")
			(net "GND")
		)
		(zone
			(layer "F.Cu")
			(hatch none 0.5)
			(connect_pads
				(clearance 0)
			)
			(min_thickness 0.25)
			(keepout
				(tracks not_allowed)
				(vias allowed)
				(pads allowed)
				(copperpour not_allowed)
				(footprints allowed)
			)
			(placement
				(enabled no)
				(sheetname "")
			)
			(fill
				(thermal_gap 0.5)
				(thermal_bridge_width 0.5)
				(island_removal_mode 0)
			)
			(polygon
				(pts
					(xy 214.4776 -93.9927) (xy 215.2396 -93.9927) (xy 215.2396 -93.4847) (xy 214.4776 -93.4847)
				)
			)
		)
	)
	(footprint ""
		(layer "F.Cu")
		(at 175.88738 -73.69556 180)
		(property "Reference" "R4D38"
			(at 0 0 180)
			(layer "F.SilkS")
			(hide yes)
			(effects
				(font
					(size 1.27 1.27)
				)
			)
		)
		(property "Value" ""
			(at 0 0 180)
			(layer "F.Fab")
			(effects
				(font
					(size 1.27 1.27)
				)
			)
		)
		(duplicate_pad_numbers_are_jumpers no)
		(fp_poly
			(pts
				(xy -0.2794 -0.1016) (xy 0.2794 -0.1016) (xy 0.2794 0.9906) (xy -0.2794 0.9906)
			)
			(stroke
				(width 0)
				(type default)
			)
			(fill no)
			(layer "F.CrtYd")
		)
		(fp_line
			(start 0.2794 0.9906)
			(end 0.2794 -0.1016)
			(stroke
				(width 0.1)
				(type default)
			)
			(layer "F.Fab")
		)
		(fp_line
			(start 0.2794 -0.1016)
			(end -0.2794 -0.1016)
			(stroke
				(width 0.1)
				(type default)
			)
			(layer "F.Fab")
		)
		(fp_line
			(start -0.2794 0.9906)
			(end 0.2794 0.9906)
			(stroke
				(width 0.1)
				(type default)
			)
			(layer "F.Fab")
		)
		(fp_line
			(start -0.2794 -0.1016)
			(end -0.2794 0.9906)
			(stroke
				(width 0.1)
				(type default)
			)
			(layer "F.Fab")
		)
		(pad "1" smd rect
			(at 0 0 180)
			(size 0.508 0.508)
			(layers "F.Cu" "F.Mask" "F.Paste")
			(net "P3V3_DB1200")
		)
		(pad "2" smd rect
			(at 0 0.889 180)
			(size 0.508 0.508)
			(layers "F.Cu" "F.Mask" "F.Paste")
			(net "FM_DB1200_SMB_SA1")
		)
		(zone
			(layer "F.Cu")
			(hatch none 0.5)
			(connect_pads
				(clearance 0)
			)
			(min_thickness 0.25)
			(keepout
				(tracks not_allowed)
				(vias allowed)
				(pads allowed)
				(copperpour not_allowed)
				(footprints allowed)
			)
			(placement
				(enabled no)
				(sheetname "")
			)
			(fill
				(thermal_gap 0.5)
				(thermal_bridge_width 0.5)
				(island_removal_mode 0)
			)
			(polygon
				(pts
					(xy 176.14138 -74.33056) (xy 175.63338 -74.33056) (xy 175.63338 -73.94956) (xy 176.14138 -73.94956)
				)
			)
		)
		(zone
			(layer "F.Cu")
			(hatch none 0.5)
			(connect_pads
				(clearance 0)
			)
			(min_thickness 0.25)
			(keepout
				(tracks allowed)
				(vias not_allowed)
				(pads allowed)
				(copperpour not_allowed)
				(footprints allowed)
			)
			(placement
				(enabled no)
				(sheetname "")
			)
			(fill
				(thermal_gap 0.5)
				(thermal_bridge_width 0.5)
				(island_removal_mode 0)
			)
			(polygon
				(pts
					(xy 176.14138 -73.94956) (xy 175.63338 -73.94956) (xy 175.63338 -74.33056) (xy 176.14138 -74.33056)
				)
			)
		)
	)
	(footprint ""
		(layer "F.Cu")
		(at 410.69006 -101.49332)
		(property "Reference" "R7W16"
			(at -0.8382 -0.67818 0)
			(unlocked yes)
			(layer "F.SilkS")
			(effects
				(font
					(size 0.4064 0.254)
					(thickness 0.1524)
				)
				(justify left)
			)
		)
		(property "Value" ""
			(at 0 0 0)
			(layer "F.Fab")
			(effects
				(font
					(size 1.27 1.27)
				)
			)
		)
		(duplicate_pad_numbers_are_jumpers no)
		(fp_poly
			(pts
				(xy -0.2794 -0.1016) (xy 0.2794 -0.1016) (xy 0.2794 0.9906) (xy -0.2794 0.9906)
			)
			(stroke
				(width 0)
				(type default)
			)
			(fill no)
			(layer "F.CrtYd")
		)
		(fp_line
			(start -0.2794 -0.1016)
			(end -0.2794 0.9906)
			(stroke
				(width 0.1)
				(type default)
			)
			(layer "F.Fab")
		)
		(fp_line
			(start -0.2794 0.9906)
			(end 0.2794 0.9906)
			(stroke
				(width 0.1)
				(type default)
			)
			(layer "F.Fab")
		)
		(fp_line
			(start 0.2794 -0.1016)
			(end -0.2794 -0.1016)
			(stroke
				(width 0.1)
				(type default)
			)
			(layer "F.Fab")
		)
		(fp_line
			(start 0.2794 0.9906)
			(end 0.2794 -0.1016)
			(stroke
				(width 0.1)
				(type default)
			)
			(layer "F.Fab")
		)
		(pad "1" smd rect
			(at 0 0)
			(size 0.508 0.508)
			(layers "F.Cu" "F.Mask" "F.Paste")
			(net "IRQ_DIMM_SAVE_LVT3_R_N")
		)
		(pad "2" smd rect
			(at 0 0.889)
			(size 0.508 0.508)
			(layers "F.Cu" "F.Mask" "F.Paste")
			(net "IRQ_DIMM_SAVE_LVT3_N")
		)
		(zone
			(layer "F.Cu")
			(hatch none 0.5)
			(connect_pads
				(clearance 0)
			)
			(min_thickness 0.25)
			(keepout
				(tracks allowed)
				(vias not_allowed)
				(pads allowed)
				(copperpour not_allowed)
				(footprints allowed)
			)
			(placement
				(enabled no)
				(sheetname "")
			)
			(fill
				(thermal_gap 0.5)
				(thermal_bridge_width 0.5)
				(island_removal_mode 0)
			)
			(polygon
				(pts
					(xy 410.43606 -101.23932) (xy 410.94406 -101.23932) (xy 410.94406 -100.85832) (xy 410.43606 -100.85832)
				)
			)
		)
		(zone
			(layer "F.Cu")
			(hatch none 0.5)
			(connect_pads
				(clearance 0)
			)
			(min_thickness 0.25)
			(keepout
				(tracks not_allowed)
				(vias allowed)
				(pads allowed)
				(copperpour not_allowed)
				(footprints allowed)
			)
			(placement
				(enabled no)
				(sheetname "")
			)
			(fill
				(thermal_gap 0.5)
				(thermal_bridge_width 0.5)
				(island_removal_mode 0)
			)
			(polygon
				(pts
					(xy 410.43606 -100.85832) (xy 410.94406 -100.85832) (xy 410.94406 -101.23932) (xy 410.43606 -101.23932)
				)
			)
		)
	)
	(footprint ""
		(layer "F.Cu")
		(at 362.276644 -10.916158)
		(property "Reference" "C7G5"
			(at 0 0 0)
			(layer "F.SilkS")
			(hide yes)
			(effects
				(font
					(size 1.27 1.27)
				)
			)
		)
		(property "Value" ""
			(at 0 0 0)
			(layer "F.Fab")
			(effects
				(font
					(size 1.27 1.27)
				)
			)
		)
		(duplicate_pad_numbers_are_jumpers no)
		(fp_rect
			(start -0.3048 0.9906)
			(end 0.3048 -0.1016)
			(stroke
				(width 0)
				(type default)
			)
			(fill no)
			(layer "F.CrtYd")
		)
		(fp_line
			(start -0.3048 -0.1016)
			(end -0.3048 0.9906)
			(stroke
				(width 0.1)
				(type default)
			)
			(layer "F.Fab")
		)
		(fp_line
			(start -0.3048 0.9906)
			(end 0.3048 0.9906)
			(stroke
				(width 0.1)
				(type default)
			)
			(layer "F.Fab")
		)
		(fp_line
			(start 0.3048 -0.1016)
			(end -0.3048 -0.1016)
			(stroke
				(width 0.1)
				(type default)
			)
			(layer "F.Fab")
		)
		(fp_line
			(start 0.3048 0.9906)
			(end 0.3048 -0.1016)
			(stroke
				(width 0.1)
				(type default)
			)
			(layer "F.Fab")
		)
		(pad "1" smd rect
			(at 0 0)
			(size 0.508 0.508)
			(layers "F.Cu" "F.Mask" "F.Paste")
			(net "P3E_CPU0_PE2_SS_TXP<15>")
		)
		(pad "2" smd rect
			(at 0 0.889)
			(size 0.508 0.508)
			(layers "F.Cu" "F.Mask" "F.Paste")
			(net "P3E_CPU0_PE2_SS_C_TXP<15>")
		)
		(zone
			(layer "F.Cu")
			(hatch none 0.5)
			(connect_pads
				(clearance 0)
			)
			(min_thickness 0.25)
			(keepout
				(tracks not_allowed)
				(vias allowed)
				(pads allowed)
				(copperpour not_allowed)
				(footprints allowed)
			)
			(placement
				(enabled no)
				(sheetname "")
			)
			(fill
				(thermal_gap 0.5)
				(thermal_bridge_width 0.5)
				(island_removal_mode 0)
			)
			(polygon
				(pts
					(xy 362.022644 -10.281158) (xy 362.530644 -10.281158) (xy 362.530644 -10.662158) (xy 362.022644 -10.662158)
				)
			)
		)
		(zone
			(layer "F.Cu")
			(hatch none 0.5)
			(connect_pads
				(clearance 0)
			)
			(min_thickness 0.25)
			(keepout
				(tracks allowed)
				(vias not_allowed)
				(pads allowed)
				(copperpour not_allowed)
				(footprints allowed)
			)
			(placement
				(enabled no)
				(sheetname "")
			)
			(fill
				(thermal_gap 0.5)
				(thermal_bridge_width 0.5)
				(island_removal_mode 0)
			)
			(polygon
				(pts
					(xy 362.022644 -10.281158) (xy 362.530644 -10.281158) (xy 362.530644 -10.662158) (xy 362.022644 -10.662158)
				)
			)
		)
	)
	(footprint ""
		(layer "F.Cu")
		(at 94.50324 -81.573116)
		(property "Reference" "C2D10"
			(at 0 0 0)
			(layer "F.SilkS")
			(hide yes)
			(effects
				(font
					(size 1.27 1.27)
				)
			)
		)
		(property "Value" ""
			(at 0 0 0)
			(layer "F.Fab")
			(effects
				(font
					(size 1.27 1.27)
				)
			)
		)
		(duplicate_pad_numbers_are_jumpers no)
		(fp_poly
			(pts
				(xy -0.4953 -0.2032) (xy 0.4953 -0.2032) (xy 0.4953 1.6002) (xy -0.4953 1.6002)
			)
			(stroke
				(width 0)
				(type default)
			)
			(fill no)
			(layer "F.CrtYd")
		)
		(fp_line
			(start -0.4953 -0.2032)
			(end 0.4953 -0.2032)
			(stroke
				(width 0.1)
				(type default)
			)
			(layer "F.Fab")
		)
		(fp_line
			(start -0.4953 1.6002)
			(end -0.4953 -0.2032)
			(stroke
				(width 0.1)
				(type default)
			)
			(layer "F.Fab")
		)
		(fp_line
			(start 0.4953 -0.2032)
			(end 0.4953 1.6002)
			(stroke
				(width 0.1)
				(type default)
			)
			(layer "F.Fab")
		)
		(fp_line
			(start 0.4953 1.6002)
			(end -0.4953 1.6002)
			(stroke
				(width 0.1)
				(type default)
			)
			(layer "F.Fab")
		)
		(pad "1" smd rect
			(at 0 0)
			(size 0.762 0.889)
			(layers "F.Cu" "F.Mask" "F.Paste")
			(net "PVSA_CPU1")
		)
		(pad "2" smd rect
			(at 0 1.397)
			(size 0.762 0.889)
			(layers "F.Cu" "F.Mask" "F.Paste")
			(net "GND")
		)
		(zone
			(layer "F.Cu")
			(hatch none 0.5)
			(connect_pads
				(clearance 0)
			)
			(min_thickness 0.25)
			(keepout
				(tracks not_allowed)
				(vias allowed)
				(pads allowed)
				(copperpour not_allowed)
				(footprints allowed)
			)
			(placement
				(enabled no)
				(sheetname "")
			)
			(fill
				(thermal_gap 0.5)
				(thermal_bridge_width 0.5)
				(island_removal_mode 0)
			)
			(polygon
				(pts
					(xy 94.12224 -81.128616) (xy 94.88424 -81.128616) (xy 94.88424 -80.620616) (xy 94.12224 -80.620616)
				)
			)
		)
	)
	(footprint ""
		(layer "F.Cu")
		(at 192.786 -3.7465)
		(property "Reference" "R4G20"
			(at 0 0 0)
			(layer "F.SilkS")
			(hide yes)
			(effects
				(font
					(size 1.27 1.27)
				)
			)
		)
		(property "Value" ""
			(at 0 0 0)
			(layer "F.Fab")
			(effects
				(font
					(size 1.27 1.27)
				)
			)
		)
		(duplicate_pad_numbers_are_jumpers no)
		(fp_poly
			(pts
				(xy -0.2794 -0.1016) (xy 0.2794 -0.1016) (xy 0.2794 0.9906) (xy -0.2794 0.9906)
			)
			(stroke
				(width 0)
				(type default)
			)
			(fill no)
			(layer "F.CrtYd")
		)
		(fp_line
			(start -0.2794 -0.1016)
			(end -0.2794 0.9906)
			(stroke
				(width 0.1)
				(type default)
			)
			(layer "F.Fab")
		)
		(fp_line
			(start -0.2794 0.9906)
			(end 0.2794 0.9906)
			(stroke
				(width 0.1)
				(type default)
			)
			(layer "F.Fab")
		)
		(fp_line
			(start 0.2794 -0.1016)
			(end -0.2794 -0.1016)
			(stroke
				(width 0.1)
				(type default)
			)
			(layer "F.Fab")
		)
		(fp_line
			(start 0.2794 0.9906)
			(end 0.2794 -0.1016)
			(stroke
				(width 0.1)
				(type default)
			)
			(layer "F.Fab")
		)
		(pad "1" smd rect
			(at 0 0)
			(size 0.508 0.508)
			(layers "F.Cu" "F.Mask" "F.Paste")
			(net "M_C_CPU_VREF")
		)
		(pad "2" smd rect
			(at 0 0.889)
			(size 0.508 0.508)
			(layers "F.Cu" "F.Mask" "F.Paste")
			(net "M_C_VREF")
		)
		(zone
			(layer "F.Cu")
			(hatch none 0.5)
			(connect_pads
				(clearance 0)
			)
			(min_thickness 0.25)
			(keepout
				(tracks allowed)
				(vias not_allowed)
				(pads allowed)
				(copperpour not_allowed)
				(footprints allowed)
			)
			(placement
				(enabled no)
				(sheetname "")
			)
			(fill
				(thermal_gap 0.5)
				(thermal_bridge_width 0.5)
				(island_removal_mode 0)
			)
			(polygon
				(pts
					(xy 192.532 -3.4925) (xy 193.04 -3.4925) (xy 193.04 -3.1115) (xy 192.532 -3.1115)
				)
			)
		)
		(zone
			(layer "F.Cu")
			(hatch none 0.5)
			(connect_pads
				(clearance 0)
			)
			(min_thickness 0.25)
			(keepout
				(tracks not_allowed)
				(vias allowed)
				(pads allowed)
				(copperpour not_allowed)
				(footprints allowed)
			)
			(placement
				(enabled no)
				(sheetname "")
			)
			(fill
				(thermal_gap 0.5)
				(thermal_bridge_width 0.5)
				(island_removal_mode 0)
			)
			(polygon
				(pts
					(xy 192.532 -3.1115) (xy 193.04 -3.1115) (xy 193.04 -3.4925) (xy 192.532 -3.4925)
				)
			)
		)
	)
	(footprint ""
		(layer "F.Cu")
		(at 362.09224 -133.08457 180)
		(property "Reference" "R7B5"
			(at 0 0 180)
			(layer "F.SilkS")
			(hide yes)
			(effects
				(font
					(size 1.27 1.27)
				)
			)
		)
		(property "Value" ""
			(at 0 0 180)
			(layer "F.Fab")
			(effects
				(font
					(size 1.27 1.27)
				)
			)
		)
		(duplicate_pad_numbers_are_jumpers no)
		(fp_rect
			(start 0.2794 -0.1016)
			(end -0.2794 0.9906)
			(stroke
				(width 0)
				(type default)
			)
			(fill no)
			(layer "F.CrtYd")
		)
		(fp_line
			(start 0.2794 0.9906)
			(end 0.2794 -0.1016)
			(stroke
				(width 0.1)
				(type default)
			)
			(layer "F.Fab")
		)
		(fp_line
			(start 0.2794 -0.1016)
			(end -0.2794 -0.1016)
			(stroke
				(width 0.1)
				(type default)
			)
			(layer "F.Fab")
		)
		(fp_line
			(start -0.2794 0.9906)
			(end 0.2794 0.9906)
			(stroke
				(width 0.1)
				(type default)
			)
			(layer "F.Fab")
		)
		(fp_line
			(start -0.2794 -0.1016)
			(end -0.2794 0.9906)
			(stroke
				(width 0.1)
				(type default)
			)
			(layer "F.Fab")
		)
		(pad "1" smd rect
			(at 0 0 180)
			(size 0.508 0.508)
			(layers "F.Cu" "F.Mask" "F.Paste")
			(net "P3V3_STBY")
		)
		(pad "2" smd rect
			(at 0 0.889 180)
			(size 0.508 0.508)
			(layers "F.Cu" "F.Mask" "F.Paste")
			(net "PWRGD_PVDDQ_DEF_R")
		)
		(zone
			(layer "F.Cu")
			(hatch none 0.5)
			(connect_pads
				(clearance 0)
			)
			(min_thickness 0.25)
			(keepout
				(tracks allowed)
				(vias not_allowed)
				(pads allowed)
				(copperpour not_allowed)
				(footprints allowed)
			)
			(placement
				(enabled no)
				(sheetname "")
			)
			(fill
				(thermal_gap 0.5)
				(thermal_bridge_width 0.5)
				(island_removal_mode 0)
			)
			(polygon
				(pts
					(xy 361.83824 -133.33857) (xy 362.34624 -133.33857) (xy 362.34624 -133.71957) (xy 361.83824 -133.71957)
				)
			)
		)
		(zone
			(layer "F.Cu")
			(hatch none 0.5)
			(connect_pads
				(clearance 0)
			)
			(min_thickness 0.25)
			(keepout
				(tracks not_allowed)
				(vias allowed)
				(pads allowed)
				(copperpour not_allowed)
				(footprints allowed)
			)
			(placement
				(enabled no)
				(sheetname "")
			)
			(fill
				(thermal_gap 0.5)
				(thermal_bridge_width 0.5)
				(island_removal_mode 0)
			)
			(polygon
				(pts
					(xy 361.83824 -133.33857) (xy 362.34624 -133.33857) (xy 362.34624 -133.71957) (xy 361.83824 -133.71957)
				)
			)
		)
	)
	(footprint ""
		(layer "F.Cu")
		(at 155.1051 -22.7457 90)
		(property "Reference" "C3F4"
			(at 0 0 90)
			(layer "F.SilkS")
			(hide yes)
			(effects
				(font
					(size 1.27 1.27)
				)
			)
		)
		(property "Value" ""
			(at 0 0 90)
			(layer "F.Fab")
			(effects
				(font
					(size 1.27 1.27)
				)
			)
		)
		(duplicate_pad_numbers_are_jumpers no)
		(fp_poly
			(pts
				(xy -0.4953 -0.2032) (xy 0.4953 -0.2032) (xy 0.4953 1.6002) (xy -0.4953 1.6002)
			)
			(stroke
				(width 0)
				(type default)
			)
			(fill no)
			(layer "F.CrtYd")
		)
		(fp_line
			(start 0.4953 -0.2032)
			(end 0.4953 1.6002)
			(stroke
				(width 0.1)
				(type default)
			)
			(layer "F.Fab")
		)
		(fp_line
			(start -0.4953 -0.2032)
			(end 0.4953 -0.2032)
			(stroke
				(width 0.1)
				(type default)
			)
			(layer "F.Fab")
		)
		(fp_line
			(start 0.4953 1.6002)
			(end -0.4953 1.6002)
			(stroke
				(width 0.1)
				(type default)
			)
			(layer "F.Fab")
		)
		(fp_line
			(start -0.4953 1.6002)
			(end -0.4953 -0.2032)
			(stroke
				(width 0.1)
				(type default)
			)
			(layer "F.Fab")
		)
		(pad "1" smd rect
			(at 0 0 90)
			(size 0.762 0.889)
			(layers "F.Cu" "F.Mask" "F.Paste")
			(net "PVPP_GHJ")
		)
		(pad "2" smd rect
			(at 0 1.397 90)
			(size 0.762 0.889)
			(layers "F.Cu" "F.Mask" "F.Paste")
			(net "GND")
		)
		(zone
			(layer "F.Cu")
			(hatch none 0.5)
			(connect_pads
				(clearance 0)
			)
			(min_thickness 0.25)
			(keepout
				(tracks not_allowed)
				(vias allowed)
				(pads allowed)
				(copperpour not_allowed)
				(footprints allowed)
			)
			(placement
				(enabled no)
				(sheetname "")
			)
			(fill
				(thermal_gap 0.5)
				(thermal_bridge_width 0.5)
				(island_removal_mode 0)
			)
			(polygon
				(pts
					(xy 155.5496 -22.3647) (xy 155.5496 -23.1267) (xy 156.0576 -23.1267) (xy 156.0576 -22.3647)
				)
			)
		)
	)
	(footprint ""
		(layer "F.Cu")
		(at 173.736 -63.831978 90)
		(property "Reference" "R4E2"
			(at 0 0 90)
			(layer "F.SilkS")
			(hide yes)
			(effects
				(font
					(size 1.27 1.27)
				)
			)
		)
		(property "Value" ""
			(at 0 0 90)
			(layer "F.Fab")
			(effects
				(font
					(size 1.27 1.27)
				)
			)
		)
		(duplicate_pad_numbers_are_jumpers no)
		(fp_poly
			(pts
				(xy -0.2794 -0.1016) (xy 0.2794 -0.1016) (xy 0.2794 0.9906) (xy -0.2794 0.9906)
			)
			(stroke
				(width 0)
				(type default)
			)
			(fill no)
			(layer "F.CrtYd")
		)
		(fp_line
			(start 0.2794 -0.1016)
			(end -0.2794 -0.1016)
			(stroke
				(width 0.1)
				(type default)
			)
			(layer "F.Fab")
		)
		(fp_line
			(start -0.2794 -0.1016)
			(end -0.2794 0.9906)
			(stroke
				(width 0.1)
				(type default)
			)
			(layer "F.Fab")
		)
		(fp_line
			(start 0.2794 0.9906)
			(end 0.2794 -0.1016)
			(stroke
				(width 0.1)
				(type default)
			)
			(layer "F.Fab")
		)
		(fp_line
			(start -0.2794 0.9906)
			(end 0.2794 0.9906)
			(stroke
				(width 0.1)
				(type default)
			)
			(layer "F.Fab")
		)
		(pad "1" smd rect
			(at 0 0 90)
			(size 0.508 0.508)
			(layers "F.Cu" "F.Mask" "F.Paste")
			(net "VR_PVCCIO_CPU1_XADDR2")
		)
		(pad "2" smd rect
			(at 0 0.889 90)
			(size 0.508 0.508)
			(layers "F.Cu" "F.Mask" "F.Paste")
			(net "GND")
		)
		(zone
			(layer "F.Cu")
			(hatch none 0.5)
			(connect_pads
				(clearance 0)
			)
			(min_thickness 0.25)
			(keepout
				(tracks allowed)
				(vias not_allowed)
				(pads allowed)
				(copperpour not_allowed)
				(footprints allowed)
			)
			(placement
				(enabled no)
				(sheetname "")
			)
			(fill
				(thermal_gap 0.5)
				(thermal_bridge_width 0.5)
				(island_removal_mode 0)
			)
			(polygon
				(pts
					(xy 173.99 -63.577978) (xy 173.99 -64.085978) (xy 174.371 -64.085978) (xy 174.371 -63.577978)
				)
			)
		)
		(zone
			(layer "F.Cu")
			(hatch none 0.5)
			(connect_pads
				(clearance 0)
			)
			(min_thickness 0.25)
			(keepout
				(tracks not_allowed)
				(vias allowed)
				(pads allowed)
				(copperpour not_allowed)
				(footprints allowed)
			)
			(placement
				(enabled no)
				(sheetname "")
			)
			(fill
				(thermal_gap 0.5)
				(thermal_bridge_width 0.5)
				(island_removal_mode 0)
			)
			(polygon
				(pts
					(xy 174.371 -63.577978) (xy 174.371 -64.085978) (xy 173.99 -64.085978) (xy 173.99 -63.577978)
				)
			)
		)
	)
	(footprint ""
		(layer "F.Cu")
		(at 94.308168 -3.321812 90)
		(property "Reference" "C2G16"
			(at 0 0 90)
			(layer "F.SilkS")
			(hide yes)
			(effects
				(font
					(size 1.27 1.27)
				)
			)
		)
		(property "Value" ""
			(at 0 0 90)
			(layer "F.Fab")
			(effects
				(font
					(size 1.27 1.27)
				)
			)
		)
		(duplicate_pad_numbers_are_jumpers no)
		(fp_poly
			(pts
				(xy -0.7239 -0.2159) (xy 0.7239 -0.2159) (xy 0.7239 1.9939) (xy -0.7239 1.9939)
			)
			(stroke
				(width 0)
				(type default)
			)
			(fill no)
			(layer "F.CrtYd")
		)
		(fp_line
			(start 0.7239 -0.2159)
			(end -0.7239 -0.2159)
			(stroke
				(width 0.1)
				(type default)
			)
			(layer "F.Fab")
		)
		(fp_line
			(start -0.7239 -0.2159)
			(end -0.7239 1.9939)
			(stroke
				(width 0.1)
				(type default)
			)
			(layer "F.Fab")
		)
		(fp_line
			(start 0.7239 1.9939)
			(end 0.7239 -0.2159)
			(stroke
				(width 0.1)
				(type default)
			)
			(layer "F.Fab")
		)
		(fp_line
			(start -0.7239 1.9939)
			(end 0.7239 1.9939)
			(stroke
				(width 0.1)
				(type default)
			)
			(layer "F.Fab")
		)
		(pad "1" smd rect
			(at 0 0 90)
			(size 1.27 1.016)
			(layers "F.Cu" "F.Mask" "F.Paste")
			(net "PVDDQ_GHJ")
		)
		(pad "2" smd rect
			(at 0 1.778 90)
			(size 1.27 1.016)
			(layers "F.Cu" "F.Mask" "F.Paste")
			(net "GND")
		)
		(zone
			(layer "F.Cu")
			(hatch none 0.5)
			(connect_pads
				(clearance 0)
			)
			(min_thickness 0.25)
			(keepout
				(tracks not_allowed)
				(vias allowed)
				(pads allowed)
				(copperpour not_allowed)
				(footprints allowed)
			)
			(placement
				(enabled no)
				(sheetname "")
			)
			(fill
				(thermal_gap 0.5)
				(thermal_bridge_width 0.5)
				(island_removal_mode 0)
			)
			(polygon
				(pts
					(xy 94.816168 -2.686812) (xy 94.816168 -3.956812) (xy 95.578168 -3.956812) (xy 95.578168 -2.686812)
				)
			)
		)
	)
	(footprint ""
		(layer "F.Cu")
		(at 0.762 -71.247 90)
		(property "Reference" "U1E1"
			(at 2.0066 -2.13233 90)
			(unlocked yes)
			(layer "F.SilkS")
			(effects
				(font
					(size 0.7874 0.5842)
					(thickness 0.1524)
				)
			)
		)
		(property "Value" ""
			(at 0 0 90)
			(layer "F.Fab")
			(effects
				(font
					(size 1.27 1.27)
				)
			)
		)
		(duplicate_pad_numbers_are_jumpers no)
		(fp_line
			(start 1.566672 -0.52324)
			(end 0.985774 -0.52324)
			(stroke
				(width 0.1524)
				(type default)
			)
			(layer "F.SilkS")
		)
		(fp_line
			(start 1.583436 2.47396)
			(end 0.965454 2.47396)
			(stroke
				(width 0.1524)
				(type default)
			)
			(layer "F.SilkS")
		)
		(fp_circle
			(center -0.635 -0.889)
			(end -0.635 -0.762)
			(stroke
				(width 0.254)
				(type default)
			)
			(fill no)
			(layer "F.SilkS")
		)
		(fp_rect
			(start 0.3937 2.47396)
			(end 2.1463 -0.52324)
			(stroke
				(width 0)
				(type default)
			)
			(fill no)
			(layer "F.CrtYd")
		)
		(fp_line
			(start 2.1463 -0.52324)
			(end 2.1463 2.47396)
			(stroke
				(width 0.1)
				(type default)
			)
			(layer "F.Fab")
		)
		(fp_line
			(start 0.3937 -0.52324)
			(end 2.1463 -0.52324)
			(stroke
				(width 0.1)
				(type default)
			)
			(layer "F.Fab")
		)
		(fp_line
			(start 2.1463 2.47396)
			(end 0.3937 2.47396)
			(stroke
				(width 0.1)
				(type default)
			)
			(layer "F.Fab")
		)
		(fp_line
			(start 0.3937 2.47396)
			(end 0.3937 -0.52324)
			(stroke
				(width 0.1)
				(type default)
			)
			(layer "F.Fab")
		)
		(fp_circle
			(center -0.635 -0.889)
			(end -0.635 -0.762)
			(stroke
				(width 0.254)
				(type default)
			)
			(fill no)
			(layer "F.Fab")
		)
		(pad "1" smd rect
			(at 0 0 90)
			(size 1.27 0.381)
			(layers "F.Cu" "F.Mask" "F.Paste")
			(net "ISENSE_TMP421_2_DXP")
		)
		(pad "2" smd rect
			(at 0 0.65024 90)
			(size 1.27 0.381)
			(layers "F.Cu" "F.Mask" "F.Paste")
			(net "ISENSE_TMP421_2_DXN")
		)
		(pad "3" smd rect
			(at 0 1.30048 90)
			(size 1.27 0.381)
			(layers "F.Cu" "F.Mask" "F.Paste")
			(net "PD_TMP421_2_A1")
		)
		(pad "4" smd rect
			(at 0 1.95072 90)
			(size 1.27 0.381)
			(layers "F.Cu" "F.Mask" "F.Paste")
			(net "PU_TMP421_2_A0")
		)
		(pad "5" smd rect
			(at 2.54 1.95072 90)
			(size 1.27 0.381)
			(layers "F.Cu" "F.Mask" "F.Paste")
			(net "GND")
		)
		(pad "6" smd rect
			(at 2.54 1.30048 90)
			(size 1.27 0.381)
			(layers "F.Cu" "F.Mask" "F.Paste")
			(net "SMB_SENSOR_TMP421_2_SDA")
		)
		(pad "7" smd rect
			(at 2.54 0.65024 90)
			(size 1.27 0.381)
			(layers "F.Cu" "F.Mask" "F.Paste")
			(net "SMB_SENSOR_TMP421_2_SCL")
		)
		(pad "8" smd rect
			(at 2.54 0 90)
			(size 1.27 0.381)
			(layers "F.Cu" "F.Mask" "F.Paste")
			(net "P3V3_STBY")
		)
	)
	(footprint ""
		(layer "F.Cu")
		(at 166.977822 -9.013952 90)
		(property "Reference" "R4G8"
			(at 0 0 90)
			(layer "F.SilkS")
			(hide yes)
			(effects
				(font
					(size 1.27 1.27)
				)
			)
		)
		(property "Value" ""
			(at 0 0 90)
			(layer "F.Fab")
			(effects
				(font
					(size 1.27 1.27)
				)
			)
		)
		(duplicate_pad_numbers_are_jumpers no)
		(fp_rect
			(start 0.2794 0.9906)
			(end -0.2794 -0.1016)
			(stroke
				(width 0)
				(type default)
			)
			(fill no)
			(layer "F.CrtYd")
		)
		(fp_line
			(start 0.2794 -0.1016)
			(end -0.2794 -0.1016)
			(stroke
				(width 0.1)
				(type default)
			)
			(layer "F.Fab")
		)
		(fp_line
			(start -0.2794 -0.1016)
			(end -0.2794 0.9906)
			(stroke
				(width 0.1)
				(type default)
			)
			(layer "F.Fab")
		)
		(fp_line
			(start 0.2794 0.9906)
			(end 0.2794 -0.1016)
			(stroke
				(width 0.1)
				(type default)
			)
			(layer "F.Fab")
		)
		(fp_line
			(start -0.2794 0.9906)
			(end 0.2794 0.9906)
			(stroke
				(width 0.1)
				(type default)
			)
			(layer "F.Fab")
		)
		(pad "1" smd rect
			(at 0 0 90)
			(size 0.508 0.508)
			(layers "F.Cu" "F.Mask" "F.Paste")
			(net "PVPP_GHJ")
		)
		(pad "2" smd rect
			(at 0 0.889 90)
			(size 0.508 0.508)
			(layers "F.Cu" "F.Mask" "F.Paste")
			(net "VSENSE_PVPP_GHJ")
		)
		(zone
			(layer "F.Cu")
			(hatch none 0.5)
			(connect_pads
				(clearance 0)
			)
			(min_thickness 0.25)
			(keepout
				(tracks allowed)
				(vias not_allowed)
				(pads allowed)
				(copperpour not_allowed)
				(footprints allowed)
			)
			(placement
				(enabled no)
				(sheetname "")
			)
			(fill
				(thermal_gap 0.5)
				(thermal_bridge_width 0.5)
				(island_removal_mode 0)
			)
			(polygon
				(pts
					(xy 167.612822 -9.267952) (xy 167.231822 -9.267952) (xy 167.231822 -8.759952) (xy 167.612822 -8.759952)
				)
			)
		)
		(zone
			(layer "F.Cu")
			(hatch none 0.5)
			(connect_pads
				(clearance 0)
			)
			(min_thickness 0.25)
			(keepout
				(tracks not_allowed)
				(vias allowed)
				(pads allowed)
				(copperpour not_allowed)
				(footprints allowed)
			)
			(placement
				(enabled no)
				(sheetname "")
			)
			(fill
				(thermal_gap 0.5)
				(thermal_bridge_width 0.5)
				(island_removal_mode 0)
			)
			(polygon
				(pts
					(xy 167.612822 -9.267952) (xy 167.231822 -9.267952) (xy 167.231822 -8.759952) (xy 167.612822 -8.759952)
				)
			)
		)
	)
	(footprint ""
		(layer "F.Cu")
		(at 250.77801 -75.65009 180)
		(property "Reference" "XLU1"
			(at 19.38401 33.79724 0)
			(unlocked yes)
			(layer "F.SilkS")
			(effects
				(font
					(size 0.7874 0.5842)
					(thickness 0.1524)
				)
				(justify left)
			)
		)
		(property "Value" ""
			(at 0 0 180)
			(layer "F.Fab")
			(effects
				(font
					(size 1.27 1.27)
				)
			)
		)
		(duplicate_pad_numbers_are_jumpers no)
		(fp_line
			(start 21.77796 31.949898)
			(end 21.77796 8.899906)
			(stroke
				(width 0.1524)
				(type default)
			)
			(layer "F.SilkS")
		)
		(fp_line
			(start 21.77796 8.899906)
			(end 18.278094 5.40004)
			(stroke
				(width 0.1524)
				(type default)
			)
			(layer "F.SilkS")
		)
		(fp_line
			(start 21.77796 -7.100062)
			(end 21.77796 -30.150054)
			(stroke
				(width 0.1524)
				(type default)
			)
			(layer "F.SilkS")
		)
		(fp_line
			(start 21.77796 -30.150054)
			(end 14.777974 -30.150054)
			(stroke
				(width 0.1524)
				(type default)
			)
			(layer "F.SilkS")
		)
		(fp_line
			(start 18.278094 5.40004)
			(end 18.278094 3.899916)
			(stroke
				(width 0.1524)
				(type default)
			)
			(layer "F.SilkS")
		)
		(fp_line
			(start 18.278094 3.899916)
			(end 17.777968 3.899916)
			(stroke
				(width 0.1524)
				(type default)
			)
			(layer "F.SilkS")
		)
		(fp_line
			(start 18.278094 -2.100072)
			(end 18.278094 -3.599942)
			(stroke
				(width 0.1524)
				(type default)
			)
			(layer "F.SilkS")
		)
		(fp_line
			(start 18.278094 -3.599942)
			(end 21.77796 -7.100062)
			(stroke
				(width 0.1524)
				(type default)
			)
			(layer "F.SilkS")
		)
		(fp_line
			(start 17.777968 3.899916)
			(end 17.777968 -2.100072)
			(stroke
				(width 0.1524)
				(type default)
			)
			(layer "F.SilkS")
		)
		(fp_line
			(start 17.777968 -2.100072)
			(end 18.278094 -2.100072)
			(stroke
				(width 0.1524)
				(type default)
			)
			(layer "F.SilkS")
		)
		(fp_line
			(start 14.777974 31.949898)
			(end 21.77796 31.949898)
			(stroke
				(width 0.1524)
				(type default)
			)
			(layer "F.SilkS")
		)
		(fp_line
			(start 14.777974 29.399992)
			(end 14.777974 31.949898)
			(stroke
				(width 0.1524)
				(type default)
			)
			(layer "F.SilkS")
		)
		(fp_line
			(start 14.777974 -27.599894)
			(end -17.622012 -27.599894)
			(stroke
				(width 0.1524)
				(type default)
			)
			(layer "F.SilkS")
		)
		(fp_line
			(start 14.777974 -30.150054)
			(end 14.777974 -27.599894)
			(stroke
				(width 0.1524)
				(type default)
			)
			(layer "F.SilkS")
		)
		(fp_line
			(start -6.171946 6.690106)
			(end -12.761976 10.649966)
			(stroke
				(width 0.1524)
				(type default)
			)
			(layer "F.SilkS")
		)
		(fp_line
			(start -6.171946 -4.890008)
			(end -6.171946 6.690106)
			(stroke
				(width 0.1524)
				(type default)
			)
			(layer "F.SilkS")
		)
		(fp_line
			(start -12.761976 10.649966)
			(end -19.221958 10.649966)
			(stroke
				(width 0.1524)
				(type default)
			)
			(layer "F.SilkS")
		)
		(fp_line
			(start -12.761976 -8.850122)
			(end -6.171946 -4.890008)
			(stroke
				(width 0.1524)
				(type default)
			)
			(layer "F.SilkS")
		)
		(fp_line
			(start -17.622012 30.39999)
			(end -17.622012 29.399992)
			(stroke
				(width 0.1524)
				(type default)
			)
			(layer "F.SilkS")
		)
		(fp_line
			(start -17.622012 29.399992)
			(end 14.777974 29.399992)
			(stroke
				(width 0.1524)
				(type default)
			)
			(layer "F.SilkS")
		)
		(fp_line
			(start -17.622012 -27.599894)
			(end -17.622012 -28.599892)
			(stroke
				(width 0.1524)
				(type default)
			)
			(layer "F.SilkS")
		)
		(fp_line
			(start -17.622012 -28.599892)
			(end -18.62201 -28.599892)
			(stroke
				(width 0.1524)
				(type default)
			)
			(layer "F.SilkS")
		)
		(fp_line
			(start -18.62201 30.39999)
			(end -17.622012 30.39999)
			(stroke
				(width 0.1524)
				(type default)
			)
			(layer "F.SilkS")
		)
		(fp_line
			(start -18.62201 29.399992)
			(end -18.62201 30.39999)
			(stroke
				(width 0.1524)
				(type default)
			)
			(layer "F.SilkS")
		)
		(fp_line
			(start -18.62201 -8.850122)
			(end -12.761976 -8.850122)
			(stroke
				(width 0.1524)
				(type default)
			)
			(layer "F.SilkS")
		)
		(fp_line
			(start -18.62201 -28.599892)
			(end -18.62201 -8.850122)
			(stroke
				(width 0.1524)
				(type default)
			)
			(layer "F.SilkS")
		)
		(fp_line
			(start -19.221958 29.399992)
			(end -18.62201 29.399992)
			(stroke
				(width 0.1524)
				(type default)
			)
			(layer "F.SilkS")
		)
		(fp_line
			(start -19.221958 10.649966)
			(end -19.221958 29.399992)
			(stroke
				(width 0.1524)
				(type default)
			)
			(layer "F.SilkS")
		)
		(fp_poly
			(pts
				(xy 19.777964 -5.100066) (xy 19.777964 -22.649942) (xy 18.839434 -22.649942) (xy 18.839434 -27.410918)
				(xy 14.777974 -27.410918) (xy 14.777974 -30.150054) (xy 21.77796 -30.150054) (xy 21.77796 -7.100062)
			)
			(stroke
				(width 0)
				(type default)
			)
			(fill no)
			(layer "F.CrtYd")
		)
		(fp_poly
			(pts
				(arc
					(start 19.777964 17.616678)
					(mid 20.051978 16.900049)
					(end 19.777964 16.183356)
				)
				(xy 19.777964 6.89991) (xy 21.77796 8.899906) (xy 21.77796 31.949898) (xy 14.777974 31.949898) (xy 14.777974 29.211016)
				(xy 18.839434 29.211016) (xy 18.839434 24.449786) (xy 19.777964 24.449786)
			)
			(stroke
				(width 0)
				(type default)
			)
			(fill no)
			(layer "F.CrtYd")
		)
		(fp_line
			(start 21.77796 31.949898)
			(end 14.777974 31.949898)
			(stroke
				(width 0.1)
				(type default)
			)
			(layer "F.Fab")
		)
		(fp_line
			(start 21.77796 8.899906)
			(end 21.77796 31.949898)
			(stroke
				(width 0.1)
				(type default)
			)
			(layer "F.Fab")
		)
		(fp_line
			(start 21.77796 -7.100062)
			(end 19.777964 -5.100066)
			(stroke
				(width 0.1)
				(type default)
			)
			(layer "F.Fab")
		)
		(fp_line
			(start 21.77796 -30.150054)
			(end 21.77796 -7.100062)
			(stroke
				(width 0.1)
				(type default)
			)
			(layer "F.Fab")
		)
		(fp_line
			(start 19.777964 24.449786)
			(end 19.777964 22.078696)
			(stroke
				(width 0.1)
				(type default)
			)
			(layer "F.Fab")
		)
		(fp_line
			(start 19.777964 21.179028)
			(end 19.777964 17.616678)
			(stroke
				(width 0.1)
				(type default)
			)
			(layer "F.Fab")
		)
		(fp_line
			(start 19.777964 16.183356)
			(end 19.777964 6.89991)
			(stroke
				(width 0.1)
				(type default)
			)
			(layer "F.Fab")
		)
		(fp_line
			(start 19.777964 6.89991)
			(end 21.77796 8.899906)
			(stroke
				(width 0.1)
				(type default)
			)
			(layer "F.Fab")
		)
		(fp_line
			(start 19.777964 -5.100066)
			(end 19.777964 -22.649942)
			(stroke
				(width 0.1)
				(type default)
			)
			(layer "F.Fab")
		)
		(fp_line
			(start 19.777964 -22.649942)
			(end 18.839434 -22.649942)
			(stroke
				(width 0.1)
				(type default)
			)
			(layer "F.Fab")
		)
		(fp_line
			(start 18.839434 29.211016)
			(end 18.839434 24.449786)
			(stroke
				(width 0.1)
				(type default)
			)
			(layer "F.Fab")
		)
		(fp_line
			(start 18.839434 24.449786)
			(end 19.777964 24.449786)
			(stroke
				(width 0.1)
				(type default)
			)
			(layer "F.Fab")
		)
		(fp_line
			(start 18.839434 -22.649942)
			(end 18.839434 -27.410918)
			(stroke
				(width 0.1)
				(type default)
			)
			(layer "F.Fab")
		)
		(fp_line
			(start 18.839434 -27.410918)
			(end 14.777974 -27.410918)
			(stroke
				(width 0.1)
				(type default)
			)
			(layer "F.Fab")
		)
		(fp_line
			(start 14.777974 31.949898)
			(end 14.777974 29.211016)
			(stroke
				(width 0.1)
				(type default)
			)
			(layer "F.Fab")
		)
		(fp_line
			(start 14.777974 29.211016)
			(end 18.839434 29.211016)
			(stroke
				(width 0.1)
				(type default)
			)
			(layer "F.Fab")
		)
		(fp_line
			(start 14.777974 -27.410918)
			(end 14.777974 -30.150054)
			(stroke
				(width 0.1)
				(type default)
			)
			(layer "F.Fab")
		)
		(fp_line
			(start 14.777974 -30.150054)
			(end 21.77796 -30.150054)
			(stroke
				(width 0.1)
				(type default)
			)
			(layer "F.Fab")
		)
		(fp_arc
			(start 19.777964 22.078696)
			(mid 19.777668 21.628862)
			(end 19.777964 21.179028)
			(stroke
				(width 0.1)
				(type default)
			)
			(layer "F.Fab")
		)
		(fp_arc
			(start 19.777964 16.183356)
			(mid 20.051979 16.900015)
			(end 19.777964 17.616678)
			(stroke
				(width 0.1)
				(type default)
			)
			(layer "F.Fab")
		)
	)
	(footprint ""
		(layer "F.Cu")
		(at 421.005 -117.4877 180)
		(property "Reference" "R8B18"
			(at 0 0 180)
			(layer "F.SilkS")
			(hide yes)
			(effects
				(font
					(size 1.27 1.27)
				)
			)
		)
		(property "Value" ""
			(at 0 0 180)
			(layer "F.Fab")
			(effects
				(font
					(size 1.27 1.27)
				)
			)
		)
		(duplicate_pad_numbers_are_jumpers no)
		(fp_poly
			(pts
				(xy -0.2794 -0.1016) (xy 0.2794 -0.1016) (xy 0.2794 0.9906) (xy -0.2794 0.9906)
			)
			(stroke
				(width 0)
				(type default)
			)
			(fill no)
			(layer "F.CrtYd")
		)
		(fp_line
			(start 0.2794 0.9906)
			(end 0.2794 -0.1016)
			(stroke
				(width 0.1)
				(type default)
			)
			(layer "F.Fab")
		)
		(fp_line
			(start 0.2794 -0.1016)
			(end -0.2794 -0.1016)
			(stroke
				(width 0.1)
				(type default)
			)
			(layer "F.Fab")
		)
		(fp_line
			(start -0.2794 0.9906)
			(end 0.2794 0.9906)
			(stroke
				(width 0.1)
				(type default)
			)
			(layer "F.Fab")
		)
		(fp_line
			(start -0.2794 -0.1016)
			(end -0.2794 0.9906)
			(stroke
				(width 0.1)
				(type default)
			)
			(layer "F.Fab")
		)
		(pad "1" smd rect
			(at 0 0 180)
			(size 0.508 0.508)
			(layers "F.Cu" "F.Mask" "F.Paste")
			(net "PVPP_ABC")
		)
		(pad "2" smd rect
			(at 0 0.889 180)
			(size 0.508 0.508)
			(layers "F.Cu" "F.Mask" "F.Paste")
			(net "LED_HFI1_CPU0_N")
		)
		(zone
			(layer "F.Cu")
			(hatch none 0.5)
			(connect_pads
				(clearance 0)
			)
			(min_thickness 0.25)
			(keepout
				(tracks allowed)
				(vias not_allowed)
				(pads allowed)
				(copperpour not_allowed)
				(footprints allowed)
			)
			(placement
				(enabled no)
				(sheetname "")
			)
			(fill
				(thermal_gap 0.5)
				(thermal_bridge_width 0.5)
				(island_removal_mode 0)
			)
			(polygon
				(pts
					(xy 421.259 -117.7417) (xy 420.751 -117.7417) (xy 420.750746 -118.1227) (xy 421.259254 -118.1227)
				)
			)
		)
		(zone
			(layer "F.Cu")
			(hatch none 0.5)
			(connect_pads
				(clearance 0)
			)
			(min_thickness 0.25)
			(keepout
				(tracks not_allowed)
				(vias allowed)
				(pads allowed)
				(copperpour not_allowed)
				(footprints allowed)
			)
			(placement
				(enabled no)
				(sheetname "")
			)
			(fill
				(thermal_gap 0.5)
				(thermal_bridge_width 0.5)
				(island_removal_mode 0)
			)
			(polygon
				(pts
					(xy 421.259254 -118.1227) (xy 420.750746 -118.1227) (xy 420.751 -117.7417) (xy 421.259 -117.7417)
				)
			)
		)
	)
	(footprint ""
		(layer "F.Cu")
		(at 403.154388 -28.490926 180)
		(property "Reference" "R25W108"
			(at -0.8382 -0.67818 180)
			(unlocked yes)
			(layer "F.SilkS")
			(effects
				(font
					(size 0.4064 0.254)
					(thickness 0.1524)
				)
				(justify left)
			)
		)
		(property "Value" ""
			(at 0 0 180)
			(layer "F.Fab")
			(effects
				(font
					(size 1.27 1.27)
				)
			)
		)
		(duplicate_pad_numbers_are_jumpers no)
		(fp_poly
			(pts
				(xy -0.2794 -0.1016) (xy 0.2794 -0.1016) (xy 0.2794 0.9906) (xy -0.2794 0.9906)
			)
			(stroke
				(width 0)
				(type default)
			)
			(fill no)
			(layer "F.CrtYd")
		)
		(fp_line
			(start 0.2794 0.9906)
			(end 0.2794 -0.1016)
			(stroke
				(width 0.1)
				(type default)
			)
			(layer "F.Fab")
		)
		(fp_line
			(start 0.2794 -0.1016)
			(end -0.2794 -0.1016)
			(stroke
				(width 0.1)
				(type default)
			)
			(layer "F.Fab")
		)
		(fp_line
			(start -0.2794 0.9906)
			(end 0.2794 0.9906)
			(stroke
				(width 0.1)
				(type default)
			)
			(layer "F.Fab")
		)
		(fp_line
			(start -0.2794 -0.1016)
			(end -0.2794 0.9906)
			(stroke
				(width 0.1)
				(type default)
			)
			(layer "F.Fab")
		)
		(pad "1" smd rect
			(at 0 0 180)
			(size 0.508 0.508)
			(layers "F.Cu" "F.Mask" "F.Paste")
			(net "P3V3_STBY")
		)
		(pad "2" smd rect
			(at 0 0.889 180)
			(size 0.508 0.508)
			(layers "F.Cu" "F.Mask" "F.Paste")
			(net "RMII_BMC_OCP_TXD1_R")
		)
		(zone
			(layer "F.Cu")
			(hatch none 0.5)
			(connect_pads
				(clearance 0)
			)
			(min_thickness 0.25)
			(keepout
				(tracks not_allowed)
				(vias allowed)
				(pads allowed)
				(copperpour not_allowed)
				(footprints allowed)
			)
			(placement
				(enabled no)
				(sheetname "")
			)
			(fill
				(thermal_gap 0.5)
				(thermal_bridge_width 0.5)
				(island_removal_mode 0)
			)
			(polygon
				(pts
					(xy 403.408388 -29.125926) (xy 402.900388 -29.125926) (xy 402.900388 -28.744926) (xy 403.408388 -28.744926)
				)
			)
		)
		(zone
			(layer "F.Cu")
			(hatch none 0.5)
			(connect_pads
				(clearance 0)
			)
			(min_thickness 0.25)
			(keepout
				(tracks allowed)
				(vias not_allowed)
				(pads allowed)
				(copperpour not_allowed)
				(footprints allowed)
			)
			(placement
				(enabled no)
				(sheetname "")
			)
			(fill
				(thermal_gap 0.5)
				(thermal_bridge_width 0.5)
				(island_removal_mode 0)
			)
			(polygon
				(pts
					(xy 403.408388 -28.744926) (xy 402.900388 -28.744926) (xy 402.900388 -29.125926) (xy 403.408388 -29.125926)
				)
			)
		)
	)
	(footprint ""
		(layer "F.Cu")
		(at 404.43658 -143.561816 -90)
		(property "Reference" "C8A12"
			(at 0 0 270)
			(layer "F.SilkS")
			(hide yes)
			(effects
				(font
					(size 1.27 1.27)
				)
			)
		)
		(property "Value" ""
			(at 0 0 270)
			(layer "F.Fab")
			(effects
				(font
					(size 1.27 1.27)
				)
			)
		)
		(duplicate_pad_numbers_are_jumpers no)
		(fp_poly
			(pts
				(xy -0.7239 -0.2159) (xy 0.7239 -0.2159) (xy 0.7239 1.9939) (xy -0.7239 1.9939)
			)
			(stroke
				(width 0)
				(type default)
			)
			(fill no)
			(layer "F.CrtYd")
		)
		(fp_line
			(start -0.7239 1.9939)
			(end 0.7239 1.9939)
			(stroke
				(width 0.1)
				(type default)
			)
			(layer "F.Fab")
		)
		(fp_line
			(start 0.7239 1.9939)
			(end 0.7239 -0.2159)
			(stroke
				(width 0.1)
				(type default)
			)
			(layer "F.Fab")
		)
		(fp_line
			(start -0.7239 -0.2159)
			(end -0.7239 1.9939)
			(stroke
				(width 0.1)
				(type default)
			)
			(layer "F.Fab")
		)
		(fp_line
			(start 0.7239 -0.2159)
			(end -0.7239 -0.2159)
			(stroke
				(width 0.1)
				(type default)
			)
			(layer "F.Fab")
		)
		(pad "1" smd rect
			(at 0 0 270)
			(size 1.27 1.016)
			(layers "F.Cu" "F.Mask" "F.Paste")
			(net "P1V8_PCH_STBY")
		)
		(pad "2" smd rect
			(at 0 1.778 270)
			(size 1.27 1.016)
			(layers "F.Cu" "F.Mask" "F.Paste")
			(net "GND")
		)
		(zone
			(layer "F.Cu")
			(hatch none 0.5)
			(connect_pads
				(clearance 0)
			)
			(min_thickness 0.25)
			(keepout
				(tracks not_allowed)
				(vias allowed)
				(pads allowed)
				(copperpour not_allowed)
				(footprints allowed)
			)
			(placement
				(enabled no)
				(sheetname "")
			)
			(fill
				(thermal_gap 0.5)
				(thermal_bridge_width 0.5)
				(island_removal_mode 0)
			)
			(polygon
				(pts
					(xy 403.92858 -144.196816) (xy 403.92858 -142.926816) (xy 403.16658 -142.926816) (xy 403.16658 -144.196816)
				)
			)
		)
	)
	(footprint ""
		(layer "F.Cu")
		(at 433.3494 -31.7373 180)
		(property "Reference" "R25W117"
			(at -0.8382 -0.67818 180)
			(unlocked yes)
			(layer "F.SilkS")
			(effects
				(font
					(size 0.4064 0.254)
					(thickness 0.1524)
				)
				(justify left)
			)
		)
		(property "Value" ""
			(at 0 0 180)
			(layer "F.Fab")
			(effects
				(font
					(size 1.27 1.27)
				)
			)
		)
		(duplicate_pad_numbers_are_jumpers no)
		(fp_poly
			(pts
				(xy -0.2794 -0.1016) (xy 0.2794 -0.1016) (xy 0.2794 0.9906) (xy -0.2794 0.9906)
			)
			(stroke
				(width 0)
				(type default)
			)
			(fill no)
			(layer "F.CrtYd")
		)
		(fp_line
			(start 0.2794 0.9906)
			(end 0.2794 -0.1016)
			(stroke
				(width 0.1)
				(type default)
			)
			(layer "F.Fab")
		)
		(fp_line
			(start 0.2794 -0.1016)
			(end -0.2794 -0.1016)
			(stroke
				(width 0.1)
				(type default)
			)
			(layer "F.Fab")
		)
		(fp_line
			(start -0.2794 0.9906)
			(end 0.2794 0.9906)
			(stroke
				(width 0.1)
				(type default)
			)
			(layer "F.Fab")
		)
		(fp_line
			(start -0.2794 -0.1016)
			(end -0.2794 0.9906)
			(stroke
				(width 0.1)
				(type default)
			)
			(layer "F.Fab")
		)
		(pad "1" smd rect
			(at 0 0 180)
			(size 0.508 0.508)
			(layers "F.Cu" "F.Mask" "F.Paste")
			(net "BMC_ZQ")
		)
		(pad "2" smd rect
			(at 0 0.889 180)
			(size 0.508 0.508)
			(layers "F.Cu" "F.Mask" "F.Paste")
			(net "GND")
		)
		(zone
			(layer "F.Cu")
			(hatch none 0.5)
			(connect_pads
				(clearance 0)
			)
			(min_thickness 0.25)
			(keepout
				(tracks not_allowed)
				(vias allowed)
				(pads allowed)
				(copperpour not_allowed)
				(footprints allowed)
			)
			(placement
				(enabled no)
				(sheetname "")
			)
			(fill
				(thermal_gap 0.5)
				(thermal_bridge_width 0.5)
				(island_removal_mode 0)
			)
			(polygon
				(pts
					(xy 433.6034 -32.3723) (xy 433.0954 -32.3723) (xy 433.0954 -31.9913) (xy 433.6034 -31.9913)
				)
			)
		)
		(zone
			(layer "F.Cu")
			(hatch none 0.5)
			(connect_pads
				(clearance 0)
			)
			(min_thickness 0.25)
			(keepout
				(tracks allowed)
				(vias not_allowed)
				(pads allowed)
				(copperpour not_allowed)
				(footprints allowed)
			)
			(placement
				(enabled no)
				(sheetname "")
			)
			(fill
				(thermal_gap 0.5)
				(thermal_bridge_width 0.5)
				(island_removal_mode 0)
			)
			(polygon
				(pts
					(xy 433.6034 -31.9913) (xy 433.0954 -31.9913) (xy 433.0954 -32.3723) (xy 433.6034 -32.3723)
				)
			)
		)
	)
	(footprint ""
		(layer "F.Cu")
		(at 154.305 -28.8798 90)
		(property "Reference" "R3F4"
			(at 0 0 90)
			(layer "F.SilkS")
			(hide yes)
			(effects
				(font
					(size 1.27 1.27)
				)
			)
		)
		(property "Value" ""
			(at 0 0 90)
			(layer "F.Fab")
			(effects
				(font
					(size 1.27 1.27)
				)
			)
		)
		(duplicate_pad_numbers_are_jumpers no)
		(fp_poly
			(pts
				(xy -0.2794 -0.1016) (xy 0.2794 -0.1016) (xy 0.2794 0.9906) (xy -0.2794 0.9906)
			)
			(stroke
				(width 0)
				(type default)
			)
			(fill no)
			(layer "F.CrtYd")
		)
		(fp_line
			(start 0.2794 -0.1016)
			(end -0.2794 -0.1016)
			(stroke
				(width 0.1)
				(type default)
			)
			(layer "F.Fab")
		)
		(fp_line
			(start -0.2794 -0.1016)
			(end -0.2794 0.9906)
			(stroke
				(width 0.1)
				(type default)
			)
			(layer "F.Fab")
		)
		(fp_line
			(start 0.2794 0.9906)
			(end 0.2794 -0.1016)
			(stroke
				(width 0.1)
				(type default)
			)
			(layer "F.Fab")
		)
		(fp_line
			(start -0.2794 0.9906)
			(end 0.2794 0.9906)
			(stroke
				(width 0.1)
				(type default)
			)
			(layer "F.Fab")
		)
		(pad "1" smd rect
			(at 0 0 90)
			(size 0.508 0.508)
			(layers "F.Cu" "F.Mask" "F.Paste")
			(net "CLK_156M_OSC_BRD_CPU1_DP")
		)
		(pad "2" smd rect
			(at 0 0.889 90)
			(size 0.508 0.508)
			(layers "F.Cu" "F.Mask" "F.Paste")
			(net "CLK_156M_OSC_CPU1_HFI_DP")
		)
		(zone
			(layer "F.Cu")
			(hatch none 0.5)
			(connect_pads
				(clearance 0)
			)
			(min_thickness 0.25)
			(keepout
				(tracks allowed)
				(vias not_allowed)
				(pads allowed)
				(copperpour not_allowed)
				(footprints allowed)
			)
			(placement
				(enabled no)
				(sheetname "")
			)
			(fill
				(thermal_gap 0.5)
				(thermal_bridge_width 0.5)
				(island_removal_mode 0)
			)
			(polygon
				(pts
					(xy 154.559 -28.6258) (xy 154.559 -29.1338) (xy 154.94 -29.1338) (xy 154.94 -28.6258)
				)
			)
		)
		(zone
			(layer "F.Cu")
			(hatch none 0.5)
			(connect_pads
				(clearance 0)
			)
			(min_thickness 0.25)
			(keepout
				(tracks not_allowed)
				(vias allowed)
				(pads allowed)
				(copperpour not_allowed)
				(footprints allowed)
			)
			(placement
				(enabled no)
				(sheetname "")
			)
			(fill
				(thermal_gap 0.5)
				(thermal_bridge_width 0.5)
				(island_removal_mode 0)
			)
			(polygon
				(pts
					(xy 154.94 -28.6258) (xy 154.94 -29.1338) (xy 154.559 -29.1338) (xy 154.559 -28.6258)
				)
			)
		)
	)
	(footprint ""
		(layer "F.Cu")
		(at 342.4428 -126.746 90)
		(property "Reference" "C7B14"
			(at 0 0 90)
			(layer "F.SilkS")
			(hide yes)
			(effects
				(font
					(size 1.27 1.27)
				)
			)
		)
		(property "Value" ""
			(at 0 0 90)
			(layer "F.Fab")
			(effects
				(font
					(size 1.27 1.27)
				)
			)
		)
		(duplicate_pad_numbers_are_jumpers no)
		(fp_poly
			(pts
				(xy 0.3048 -0.1016) (xy 0.3048 0.9906) (xy -0.3048 0.9906) (xy -0.3048 -0.1016)
			)
			(stroke
				(width 0)
				(type default)
			)
			(fill no)
			(layer "F.CrtYd")
		)
		(fp_line
			(start 0.3048 -0.1016)
			(end -0.3048 -0.1016)
			(stroke
				(width 0.1)
				(type default)
			)
			(layer "F.Fab")
		)
		(fp_line
			(start -0.3048 -0.1016)
			(end -0.3048 0.9906)
			(stroke
				(width 0.1)
				(type default)
			)
			(layer "F.Fab")
		)
		(fp_line
			(start 0.3048 0.9906)
			(end 0.3048 -0.1016)
			(stroke
				(width 0.1)
				(type default)
			)
			(layer "F.Fab")
		)
		(fp_line
			(start -0.3048 0.9906)
			(end 0.3048 0.9906)
			(stroke
				(width 0.1)
				(type default)
			)
			(layer "F.Fab")
		)
		(pad "1" smd rect
			(at 0 0 90)
			(size 0.508 0.508)
			(layers "F.Cu" "F.Mask" "F.Paste")
			(net "VR_COMP_RC_PVPP_DEF")
		)
		(pad "2" smd rect
			(at 0 0.889 90)
			(size 0.508 0.508)
			(layers "F.Cu" "F.Mask" "F.Paste")
			(net "VR_COMP_PVPP_DEF_3")
		)
		(zone
			(layer "F.Cu")
			(hatch none 0.5)
			(connect_pads
				(clearance 0)
			)
			(min_thickness 0.25)
			(keepout
				(tracks allowed)
				(vias not_allowed)
				(pads allowed)
				(copperpour not_allowed)
				(footprints allowed)
			)
			(placement
				(enabled no)
				(sheetname "")
			)
			(fill
				(thermal_gap 0.5)
				(thermal_bridge_width 0.5)
				(island_removal_mode 0)
			)
			(polygon
				(pts
					(xy 342.6968 -126.492) (xy 342.6968 -127) (xy 343.0778 -127) (xy 343.0778 -126.492)
				)
			)
		)
		(zone
			(layer "F.Cu")
			(hatch none 0.5)
			(connect_pads
				(clearance 0)
			)
			(min_thickness 0.25)
			(keepout
				(tracks not_allowed)
				(vias allowed)
				(pads allowed)
				(copperpour not_allowed)
				(footprints allowed)
			)
			(placement
				(enabled no)
				(sheetname "")
			)
			(fill
				(thermal_gap 0.5)
				(thermal_bridge_width 0.5)
				(island_removal_mode 0)
			)
			(polygon
				(pts
					(xy 343.0778 -126.492) (xy 343.0778 -127) (xy 342.6968 -127) (xy 342.6968 -126.492)
				)
			)
		)
	)
	(footprint ""
		(layer "F.Cu")
		(at 205.025498 -97.454974)
		(property "Reference" "L4C2"
			(at 3.378708 -4.251706 0)
			(unlocked yes)
			(layer "F.SilkS")
			(effects
				(font
					(size 0.4064 0.254)
					(thickness 0.1524)
				)
			)
		)
		(property "Value" ""
			(at 0 0 0)
			(layer "F.Fab")
			(effects
				(font
					(size 1.27 1.27)
				)
			)
		)
		(duplicate_pad_numbers_are_jumpers no)
		(fp_line
			(start -1.1303 -3.199892)
			(end 8.3693 -3.199892)
			(stroke
				(width 0.1524)
				(type default)
			)
			(layer "F.SilkS")
		)
		(fp_line
			(start -1.1303 -1.6637)
			(end -1.1303 -3.199892)
			(stroke
				(width 0.1524)
				(type default)
			)
			(layer "F.SilkS")
		)
		(fp_line
			(start -1.1303 3.199892)
			(end -1.1303 1.6637)
			(stroke
				(width 0.1524)
				(type default)
			)
			(layer "F.SilkS")
		)
		(fp_line
			(start 8.3693 -3.199892)
			(end 8.3693 -1.6637)
			(stroke
				(width 0.1524)
				(type default)
			)
			(layer "F.SilkS")
		)
		(fp_line
			(start 8.3693 1.6637)
			(end 8.3693 3.199892)
			(stroke
				(width 0.1524)
				(type default)
			)
			(layer "F.SilkS")
		)
		(fp_line
			(start 8.3693 3.199892)
			(end -1.1303 3.199892)
			(stroke
				(width 0.1524)
				(type default)
			)
			(layer "F.SilkS")
		)
		(fp_rect
			(start -1.1303 3.199892)
			(end 8.3693 -3.199892)
			(stroke
				(width 0)
				(type default)
			)
			(fill no)
			(layer "F.CrtYd")
		)
		(fp_line
			(start -1.1303 -3.199892)
			(end 8.3693 -3.199892)
			(stroke
				(width 0.1)
				(type default)
			)
			(layer "F.Fab")
		)
		(fp_line
			(start -1.1303 3.199892)
			(end -1.1303 -3.199892)
			(stroke
				(width 0.1)
				(type default)
			)
			(layer "F.Fab")
		)
		(fp_line
			(start 8.3693 -3.199892)
			(end 8.3693 3.199892)
			(stroke
				(width 0.1)
				(type default)
			)
			(layer "F.Fab")
		)
		(fp_line
			(start 8.3693 3.199892)
			(end -1.1303 3.199892)
			(stroke
				(width 0.1)
				(type default)
			)
			(layer "F.Fab")
		)
		(pad "1" smd rect
			(at 0 0)
			(size 3.683 2.667)
			(layers "F.Cu" "F.Mask" "F.Paste")
			(net "VR_PVSA_CPU0_PHASE_SW")
		)
		(pad "2" smd rect
			(at 7.239 0)
			(size 3.683 2.667)
			(layers "F.Cu" "F.Mask" "F.Paste")
			(net "PVSA_CPU0")
		)
	)
	(footprint ""
		(layer "F.Cu")
		(at 269.559532 -12.954 90)
		(property "Reference" "C5G6"
			(at 1.848866 0.752348 90)
			(unlocked yes)
			(layer "F.SilkS")
			(effects
				(font
					(size 1.27 0.9652)
					(thickness 0.1524)
				)
			)
		)
		(property "Value" ""
			(at 0 0 90)
			(layer "F.Fab")
			(effects
				(font
					(size 1.27 1.27)
				)
			)
		)
		(duplicate_pad_numbers_are_jumpers no)
		(fp_rect
			(start -0.500126 1.598422)
			(end 0.500126 -0.201422)
			(stroke
				(width 0)
				(type default)
			)
			(fill no)
			(layer "F.CrtYd")
		)
		(fp_line
			(start 0.500126 -0.201422)
			(end 0.500126 1.598422)
			(stroke
				(width 0.1)
				(type default)
			)
			(layer "F.Fab")
		)
		(fp_line
			(start -0.500126 -0.201422)
			(end 0.500126 -0.201422)
			(stroke
				(width 0.1)
				(type default)
			)
			(layer "F.Fab")
		)
		(fp_line
			(start 0.500126 1.598422)
			(end -0.500126 1.598422)
			(stroke
				(width 0.1)
				(type default)
			)
			(layer "F.Fab")
		)
		(fp_line
			(start -0.500126 1.598422)
			(end -0.500126 -0.201422)
			(stroke
				(width 0.1)
				(type default)
			)
			(layer "F.Fab")
		)
		(pad "1" smd rect
			(at 0 0)
			(size 0.889 0.9906)
			(layers "F.Cu" "F.Mask" "F.Paste")
			(net "PVDDQ_ABC")
		)
		(pad "2" smd rect
			(at 0 1.397)
			(size 0.889 0.9906)
			(layers "F.Cu" "F.Mask" "F.Paste")
			(net "GND")
		)
		(zone
			(layer "F.Cu")
			(hatch none 0.5)
			(connect_pads
				(clearance 0)
			)
			(min_thickness 0.25)
			(keepout
				(tracks not_allowed)
				(vias allowed)
				(pads allowed)
				(copperpour not_allowed)
				(footprints allowed)
			)
			(placement
				(enabled no)
				(sheetname "")
			)
			(fill
				(thermal_gap 0.5)
				(thermal_bridge_width 0.5)
				(island_removal_mode 0)
			)
			(polygon
				(pts
					(xy 270.512032 -12.4587) (xy 270.512032 -13.4493) (xy 270.004032 -13.4493) (xy 270.004032 -12.4587)
				)
			)
		)
		(zone
			(layer "F.Cu")
			(hatch none 0.5)
			(connect_pads
				(clearance 0)
			)
			(min_thickness 0.25)
			(keepout
				(tracks allowed)
				(vias not_allowed)
				(pads allowed)
				(copperpour not_allowed)
				(footprints allowed)
			)
			(placement
				(enabled no)
				(sheetname "")
			)
			(fill
				(thermal_gap 0.5)
				(thermal_bridge_width 0.5)
				(island_removal_mode 0)
			)
			(polygon
				(pts
					(xy 270.512032 -12.4587) (xy 270.512032 -13.4493) (xy 270.004032 -13.4493) (xy 270.004032 -12.4587)
				)
			)
		)
	)
	(footprint ""
		(layer "F.Cu")
		(at 155.702 -140.0048 90)
		(property "Reference" "C3A8"
			(at 0 0 90)
			(layer "F.SilkS")
			(hide yes)
			(effects
				(font
					(size 1.27 1.27)
				)
			)
		)
		(property "Value" ""
			(at 0 0 90)
			(layer "F.Fab")
			(effects
				(font
					(size 1.27 1.27)
				)
			)
		)
		(duplicate_pad_numbers_are_jumpers no)
		(fp_rect
			(start -0.4953 1.6002)
			(end 0.4953 -0.2032)
			(stroke
				(width 0)
				(type default)
			)
			(fill no)
			(layer "F.CrtYd")
		)
		(fp_line
			(start 0.4953 -0.2032)
			(end 0.4953 1.6002)
			(stroke
				(width 0.1)
				(type default)
			)
			(layer "F.Fab")
		)
		(fp_line
			(start -0.4953 -0.2032)
			(end 0.4953 -0.2032)
			(stroke
				(width 0.1)
				(type default)
			)
			(layer "F.Fab")
		)
		(fp_line
			(start 0.4953 1.6002)
			(end -0.4953 1.6002)
			(stroke
				(width 0.1)
				(type default)
			)
			(layer "F.Fab")
		)
		(fp_line
			(start -0.4953 1.6002)
			(end -0.4953 -0.2032)
			(stroke
				(width 0.1)
				(type default)
			)
			(layer "F.Fab")
		)
		(pad "1" smd rect
			(at 0 0 90)
			(size 0.762 0.889)
			(layers "F.Cu" "F.Mask" "F.Paste")
			(net "PVPP_KLM")
		)
		(pad "2" smd rect
			(at 0 1.397 90)
			(size 0.762 0.889)
			(layers "F.Cu" "F.Mask" "F.Paste")
			(net "GND")
		)
		(zone
			(layer "F.Cu")
			(hatch none 0.5)
			(connect_pads
				(clearance 0)
			)
			(min_thickness 0.25)
			(keepout
				(tracks not_allowed)
				(vias allowed)
				(pads allowed)
				(copperpour not_allowed)
				(footprints allowed)
			)
			(placement
				(enabled no)
				(sheetname "")
			)
			(fill
				(thermal_gap 0.5)
				(thermal_bridge_width 0.5)
				(island_removal_mode 0)
			)
			(polygon
				(pts
					(xy 156.6545 -139.6238) (xy 156.6545 -140.3858) (xy 156.1465 -140.3858) (xy 156.1465 -139.6238)
				)
			)
		)
	)
	(footprint ""
		(layer "F.Cu")
		(at 184.277 -69.85)
		(property "Reference" "EU4D4"
			(at -7.4422 -3.32613 0)
			(unlocked yes)
			(layer "F.SilkS")
			(effects
				(font
					(size 0.7874 0.5842)
					(thickness 0.1524)
				)
				(justify left)
			)
		)
		(property "Value" ""
			(at 0 0 0)
			(layer "F.Fab")
			(effects
				(font
					(size 1.27 1.27)
				)
			)
		)
		(duplicate_pad_numbers_are_jumpers no)
		(fp_line
			(start -3.5052 -3.5052)
			(end 3.5052 -3.5052)
			(stroke
				(width 0.1524)
				(type default)
			)
			(layer "F.SilkS")
		)
		(fp_line
			(start -3.5052 3.5052)
			(end -3.5052 -3.5052)
			(stroke
				(width 0.1524)
				(type default)
			)
			(layer "F.SilkS")
		)
		(fp_line
			(start -2.999994 -2.999994)
			(end -2.750058 -2.999994)
			(stroke
				(width 0.1524)
				(type default)
			)
			(layer "F.SilkS")
		)
		(fp_line
			(start -2.999994 -2.750058)
			(end -2.999994 -2.999994)
			(stroke
				(width 0.1524)
				(type default)
			)
			(layer "F.SilkS")
		)
		(fp_line
			(start -2.999994 2.999994)
			(end -2.999994 2.750058)
			(stroke
				(width 0.1524)
				(type default)
			)
			(layer "F.SilkS")
		)
		(fp_line
			(start -2.750058 2.999994)
			(end -2.999994 2.999994)
			(stroke
				(width 0.1524)
				(type default)
			)
			(layer "F.SilkS")
		)
		(fp_line
			(start 2.750058 -2.999994)
			(end 2.999994 -2.999994)
			(stroke
				(width 0.1524)
				(type default)
			)
			(layer "F.SilkS")
		)
		(fp_line
			(start 2.999994 -2.999994)
			(end 2.999994 -2.750058)
			(stroke
				(width 0.1524)
				(type default)
			)
			(layer "F.SilkS")
		)
		(fp_line
			(start 2.999994 2.750058)
			(end 2.999994 2.999994)
			(stroke
				(width 0.1524)
				(type default)
			)
			(layer "F.SilkS")
		)
		(fp_line
			(start 2.999994 2.999994)
			(end 2.750058 2.999994)
			(stroke
				(width 0.1524)
				(type default)
			)
			(layer "F.SilkS")
		)
		(fp_line
			(start 3.5052 -3.5052)
			(end 3.5052 3.5052)
			(stroke
				(width 0.1524)
				(type default)
			)
			(layer "F.SilkS")
		)
		(fp_line
			(start 3.5052 3.5052)
			(end -3.5052 3.5052)
			(stroke
				(width 0.1524)
				(type default)
			)
			(layer "F.SilkS")
		)
		(fp_circle
			(center -3.752088 -2.214626)
			(end -3.625088 -2.214626)
			(stroke
				(width 0.254)
				(type default)
			)
			(fill no)
			(layer "F.SilkS")
		)
		(fp_poly
			(pts
				(xy -3.5052 -3.5052) (xy -3.5052 -2.3368) (xy -2.3368 -3.5052)
			)
			(stroke
				(width 0)
				(type default)
			)
			(fill yes)
			(layer "F.SilkS")
		)
		(fp_rect
			(start -1.8034 1.8034)
			(end 1.8034 -1.8034)
			(stroke
				(width 0)
				(type default)
			)
			(fill yes)
			(layer "F.Paste")
		)
		(fp_rect
			(start -2.999994 2.999994)
			(end 2.999994 -2.999994)
			(stroke
				(width 0)
				(type default)
			)
			(fill no)
			(layer "F.CrtYd")
		)
		(fp_line
			(start -2.999994 -2.999994)
			(end 2.999994 -2.999994)
			(stroke
				(width 0.1)
				(type default)
			)
			(layer "F.Fab")
		)
		(fp_line
			(start -2.999994 2.999994)
			(end -2.999994 -2.999994)
			(stroke
				(width 0.1)
				(type default)
			)
			(layer "F.Fab")
		)
		(fp_line
			(start 2.999994 -2.999994)
			(end 2.999994 2.999994)
			(stroke
				(width 0.1)
				(type default)
			)
			(layer "F.Fab")
		)
		(fp_line
			(start 2.999994 2.999994)
			(end -2.999994 2.999994)
			(stroke
				(width 0.1)
				(type default)
			)
			(layer "F.Fab")
		)
		(fp_circle
			(center -3.752088 -2.214626)
			(end -3.625088 -2.214626)
			(stroke
				(width 0.254)
				(type default)
			)
			(fill no)
			(layer "F.Fab")
		)
		(pad "1" smd custom
			(at -2.8956 -2.199894)
			(size 0.0508 0.0508)
			(layers "F.Cu" "F.Mask" "F.Paste")
			(net "VR_PVSA_CPU0_PWM")
			(options
				(clearance outline)
				(anchor circle)
			)
			(primitives
				(gr_poly
					(pts
						(arc
							(start 0.254 -0.1016)
							(mid 0.3556 0)
							(end 0.254 0.1016)
						)
						(xy -0.3556 0.1016) (xy -0.3556 -0.1016)
					)
					(width 0)
					(fill yes)
				)
			)
		)
		(pad "2" smd custom
			(at -2.8956 -1.800098)
			(size 0.0508 0.0508)
			(layers "F.Cu" "F.Mask" "F.Paste")
			(net "Net_274")
			(options
				(clearance outline)
				(anchor circle)
			)
			(primitives
				(gr_poly
					(pts
						(arc
							(start 0.254 -0.1016)
							(mid 0.3556 0)
							(end 0.254 0.1016)
						)
						(xy -0.3556 0.1016) (xy -0.3556 -0.1016)
					)
					(width 0)
					(fill yes)
				)
			)
		)
		(pad "3" smd custom
			(at -2.8956 -1.400048)
			(size 0.0508 0.0508)
			(layers "F.Cu" "F.Mask" "F.Paste")
			(net "VR_PVCCIN_CPU0_PWM5")
			(options
				(clearance outline)
				(anchor circle)
			)
			(primitives
				(gr_poly
					(pts
						(arc
							(start 0.254 -0.1016)
							(mid 0.3556 0)
							(end 0.254 0.1016)
						)
						(xy -0.3556 0.1016) (xy -0.3556 -0.1016)
					)
					(width 0)
					(fill yes)
				)
			)
		)
		(pad "4" smd custom
			(at -2.8956 -0.999998)
			(size 0.0508 0.0508)
			(layers "F.Cu" "F.Mask" "F.Paste")
			(net "VR_PVCCIN_CPU0_PWM4")
			(options
				(clearance outline)
				(anchor circle)
			)
			(primitives
				(gr_poly
					(pts
						(arc
							(start 0.254 -0.1016)
							(mid 0.3556 0)
							(end 0.254 0.1016)
						)
						(xy -0.3556 0.1016) (xy -0.3556 -0.1016)
					)
					(width 0)
					(fill yes)
				)
			)
		)
		(pad "5" smd custom
			(at -2.8956 -0.599948)
			(size 0.0508 0.0508)
			(layers "F.Cu" "F.Mask" "F.Paste")
			(net "VR_PVCCIN_CPU0_PWM3")
			(options
				(clearance outline)
				(anchor circle)
			)
			(primitives
				(gr_poly
					(pts
						(arc
							(start 0.254 -0.1016)
							(mid 0.3556 0)
							(end 0.254 0.1016)
						)
						(xy -0.3556 0.1016) (xy -0.3556 -0.1016)
					)
					(width 0)
					(fill yes)
				)
			)
		)
		(pad "6" smd custom
			(at -2.8956 -0.199898)
			(size 0.0508 0.0508)
			(layers "F.Cu" "F.Mask" "F.Paste")
			(net "VR_PVCCIN_CPU0_PWM2")
			(options
				(clearance outline)
				(anchor circle)
			)
			(primitives
				(gr_poly
					(pts
						(arc
							(start 0.254 -0.1016)
							(mid 0.3556 0)
							(end 0.254 0.1016)
						)
						(xy -0.3556 0.1016) (xy -0.3556 -0.1016)
					)
					(width 0)
					(fill yes)
				)
			)
		)
		(pad "7" smd custom
			(at -2.8956 0.199898)
			(size 0.0508 0.0508)
			(layers "F.Cu" "F.Mask" "F.Paste")
			(net "VR_PVCCIN_CPU0_PWM1")
			(options
				(clearance outline)
				(anchor circle)
			)
			(primitives
				(gr_poly
					(pts
						(arc
							(start 0.254 -0.1016)
							(mid 0.3556 0)
							(end 0.254 0.1016)
						)
						(xy -0.3556 0.1016) (xy -0.3556 -0.1016)
					)
					(width 0)
					(fill yes)
				)
			)
		)
		(pad "8" smd custom
			(at -2.8956 0.599948)
			(size 0.0508 0.0508)
			(layers "F.Cu" "F.Mask" "F.Paste")
			(net "SMB_VR_STBY_LVC3_SDA")
			(options
				(clearance outline)
				(anchor circle)
			)
			(primitives
				(gr_poly
					(pts
						(arc
							(start 0.254 -0.1016)
							(mid 0.3556 0)
							(end 0.254 0.1016)
						)
						(xy -0.3556 0.1016) (xy -0.3556 -0.1016)
					)
					(width 0)
					(fill yes)
				)
			)
		)
		(pad "9" smd custom
			(at -2.8956 0.999998)
			(size 0.0508 0.0508)
			(layers "F.Cu" "F.Mask" "F.Paste")
			(net "SMB_VR_STBY_LVC3_SCL")
			(options
				(clearance outline)
				(anchor circle)
			)
			(primitives
				(gr_poly
					(pts
						(arc
							(start 0.254 -0.1016)
							(mid 0.3556 0)
							(end 0.254 0.1016)
						)
						(xy -0.3556 0.1016) (xy -0.3556 -0.1016)
					)
					(width 0)
					(fill yes)
				)
			)
		)
		(pad "10" smd custom
			(at -2.8956 1.400048)
			(size 0.0508 0.0508)
			(layers "F.Cu" "F.Mask" "F.Paste")
			(net "Net_275")
			(options
				(clearance outline)
				(anchor circle)
			)
			(primitives
				(gr_poly
					(pts
						(arc
							(start 0.254 -0.1016)
							(mid 0.3556 0)
							(end 0.254 0.1016)
						)
						(xy -0.3556 0.1016) (xy -0.3556 -0.1016)
					)
					(width 0)
					(fill yes)
				)
			)
		)
		(pad "11" smd custom
			(at -2.8956 1.800098)
			(size 0.0508 0.0508)
			(layers "F.Cu" "F.Mask" "F.Paste")
			(net "VR_VRRDY_PVCCIN_CPU0")
			(options
				(clearance outline)
				(anchor circle)
			)
			(primitives
				(gr_poly
					(pts
						(arc
							(start 0.254 -0.1016)
							(mid 0.3556 0)
							(end 0.254 0.1016)
						)
						(xy -0.3556 0.1016) (xy -0.3556 -0.1016)
					)
					(width 0)
					(fill yes)
				)
			)
		)
		(pad "12" smd custom
			(at -2.8956 2.199894)
			(size 0.0508 0.0508)
			(layers "F.Cu" "F.Mask" "F.Paste")
			(net "VR_PVCCIN_CPU0_VREN")
			(options
				(clearance outline)
				(anchor circle)
			)
			(primitives
				(gr_poly
					(pts
						(arc
							(start 0.254 -0.1016)
							(mid 0.3556 0)
							(end 0.254 0.1016)
						)
						(xy -0.3556 0.1016) (xy -0.3556 -0.1016)
					)
					(width 0)
					(fill yes)
				)
			)
		)
		(pad "13" smd custom
			(at -2.199894 2.8956)
			(size 0.0508 0.0508)
			(layers "F.Cu" "F.Mask" "F.Paste")
			(net "IRQ_PVCCIN_CPU0_VRHOT_LVC3_R_N")
			(options
				(clearance outline)
				(anchor circle)
			)
			(primitives
				(gr_poly
					(pts
						(arc
							(start -0.1016 -0.254)
							(mid 0 -0.3556)
							(end 0.1016 -0.254)
						)
						(xy 0.1016 0.3556) (xy -0.1016 0.3556)
					)
					(width 0)
					(fill yes)
				)
			)
		)
		(pad "14" smd custom
			(at -1.800098 2.8956)
			(size 0.0508 0.0508)
			(layers "F.Cu" "F.Mask" "F.Paste")
			(net "FM_PVCCIN_CPU0_PWR_IN_ALERT_N")
			(options
				(clearance outline)
				(anchor circle)
			)
			(primitives
				(gr_poly
					(pts
						(arc
							(start -0.1016 -0.254)
							(mid 0 -0.3556)
							(end 0.1016 -0.254)
						)
						(xy 0.1016 0.3556) (xy -0.1016 0.3556)
					)
					(width 0)
					(fill yes)
				)
			)
		)
		(pad "15" smd custom
			(at -1.400048 2.8956)
			(size 0.0508 0.0508)
			(layers "F.Cu" "F.Mask" "F.Paste")
			(net "PWRGD_PVSA_CPU0_R")
			(options
				(clearance outline)
				(anchor circle)
			)
			(primitives
				(gr_poly
					(pts
						(arc
							(start -0.1016 -0.254)
							(mid 0 -0.3556)
							(end 0.1016 -0.254)
						)
						(xy 0.1016 0.3556) (xy -0.1016 0.3556)
					)
					(width 0)
					(fill yes)
				)
			)
		)
		(pad "16" smd custom
			(at -0.999998 2.8956)
			(size 0.0508 0.0508)
			(layers "F.Cu" "F.Mask" "F.Paste")
			(net "Net_219")
			(options
				(clearance outline)
				(anchor circle)
			)
			(primitives
				(gr_poly
					(pts
						(arc
							(start -0.1016 -0.254)
							(mid 0 -0.3556)
							(end 0.1016 -0.254)
						)
						(xy 0.1016 0.3556) (xy -0.1016 0.3556)
					)
					(width 0)
					(fill yes)
				)
			)
		)
		(pad "17" smd custom
			(at -0.599948 2.8956)
			(size 0.0508 0.0508)
			(layers "F.Cu" "F.Mask" "F.Paste")
			(net "SVID_VCLK_PVCCIN_CPU0")
			(options
				(clearance outline)
				(anchor circle)
			)
			(primitives
				(gr_poly
					(pts
						(arc
							(start -0.1016 -0.254)
							(mid 0 -0.3556)
							(end 0.1016 -0.254)
						)
						(xy 0.1016 0.3556) (xy -0.1016 0.3556)
					)
					(width 0)
					(fill yes)
				)
			)
		)
		(pad "18" smd custom
			(at -0.199898 2.8956)
			(size 0.0508 0.0508)
			(layers "F.Cu" "F.Mask" "F.Paste")
			(net "SVID_VDIO_PVCCIN_CPU0")
			(options
				(clearance outline)
				(anchor circle)
			)
			(primitives
				(gr_poly
					(pts
						(arc
							(start -0.1016 -0.254)
							(mid 0 -0.3556)
							(end 0.1016 -0.254)
						)
						(xy 0.1016 0.3556) (xy -0.1016 0.3556)
					)
					(width 0)
					(fill yes)
				)
			)
		)
		(pad "19" smd custom
			(at 0.199898 2.8956)
			(size 0.0508 0.0508)
			(layers "F.Cu" "F.Mask" "F.Paste")
			(net "SVID_VALERT_VCCIN_CPU0")
			(options
				(clearance outline)
				(anchor circle)
			)
			(primitives
				(gr_poly
					(pts
						(arc
							(start -0.1016 -0.254)
							(mid 0 -0.3556)
							(end 0.1016 -0.254)
						)
						(xy 0.1016 0.3556) (xy -0.1016 0.3556)
					)
					(width 0)
					(fill yes)
				)
			)
		)
		(pad "20" smd custom
			(at 0.599948 2.8956)
			(size 0.0508 0.0508)
			(layers "F.Cu" "F.Mask" "F.Paste")
			(net "PU_VR_PVCCIN_CPU0_FLT1_SMBALT_N")
			(options
				(clearance outline)
				(anchor circle)
			)
			(primitives
				(gr_poly
					(pts
						(arc
							(start -0.1016 -0.254)
							(mid 0 -0.3556)
							(end 0.1016 -0.254)
						)
						(xy 0.1016 0.3556) (xy -0.1016 0.3556)
					)
					(width 0)
					(fill yes)
				)
			)
		)
		(pad "21" smd custom
			(at 0.999998 2.8956)
			(size 0.0508 0.0508)
			(layers "F.Cu" "F.Mask" "F.Paste")
			(net "VSENSE_PVCCIN_CPU0_AVSP")
			(options
				(clearance outline)
				(anchor circle)
			)
			(primitives
				(gr_poly
					(pts
						(arc
							(start -0.1016 -0.254)
							(mid 0 -0.3556)
							(end 0.1016 -0.254)
						)
						(xy 0.1016 0.3556) (xy -0.1016 0.3556)
					)
					(width 0)
					(fill yes)
				)
			)
		)
		(pad "22" smd custom
			(at 1.400048 2.8956)
			(size 0.0508 0.0508)
			(layers "F.Cu" "F.Mask" "F.Paste")
			(net "VSENSE_PVCCIN_CPU0_N")
			(options
				(clearance outline)
				(anchor circle)
			)
			(primitives
				(gr_poly
					(pts
						(arc
							(start -0.1016 -0.254)
							(mid 0 -0.3556)
							(end 0.1016 -0.254)
						)
						(xy 0.1016 0.3556) (xy -0.1016 0.3556)
					)
					(width 0)
					(fill yes)
				)
			)
		)
		(pad "23" smd custom
			(at 1.800098 2.8956)
			(size 0.0508 0.0508)
			(layers "F.Cu" "F.Mask" "F.Paste")
			(net "VR_PVCCIN_CPU0_AIREF1")
			(options
				(clearance outline)
				(anchor circle)
			)
			(primitives
				(gr_poly
					(pts
						(arc
							(start -0.1016 -0.254)
							(mid 0 -0.3556)
							(end 0.1016 -0.254)
						)
						(xy 0.1016 0.3556) (xy -0.1016 0.3556)
					)
					(width 0)
					(fill yes)
				)
			)
		)
		(pad "24" smd custom
			(at 2.199894 2.8956)
			(size 0.0508 0.0508)
			(layers "F.Cu" "F.Mask" "F.Paste")
			(net "ISENSE_PVCCIN_CPU0_PH1_IMON")
			(options
				(clearance outline)
				(anchor circle)
			)
			(primitives
				(gr_poly
					(pts
						(arc
							(start -0.1016 -0.254)
							(mid 0 -0.3556)
							(end 0.1016 -0.254)
						)
						(xy 0.1016 0.3556) (xy -0.1016 0.3556)
					)
					(width 0)
					(fill yes)
				)
			)
		)
		(pad "25" smd custom
			(at 2.8956 2.199894)
			(size 0.0508 0.0508)
			(layers "F.Cu" "F.Mask" "F.Paste")
			(net "VR_PVCCIN_CPU0_AIREF2")
			(options
				(clearance outline)
				(anchor circle)
			)
			(primitives
				(gr_poly
					(pts
						(arc
							(start -0.254 0.1016)
							(mid -0.3556 0)
							(end -0.254 -0.1016)
						)
						(xy 0.3556 -0.1016) (xy 0.3556 0.1016)
					)
					(width 0)
					(fill yes)
				)
			)
		)
		(pad "26" smd custom
			(at 2.8956 1.800098)
			(size 0.0508 0.0508)
			(layers "F.Cu" "F.Mask" "F.Paste")
			(net "ISENSE_PVCCIN_CPU0_PH2_IMON")
			(options
				(clearance outline)
				(anchor circle)
			)
			(primitives
				(gr_poly
					(pts
						(arc
							(start -0.254 0.1016)
							(mid -0.3556 0)
							(end -0.254 -0.1016)
						)
						(xy 0.3556 -0.1016) (xy 0.3556 0.1016)
					)
					(width 0)
					(fill yes)
				)
			)
		)
		(pad "27" smd custom
			(at 2.8956 1.400048)
			(size 0.0508 0.0508)
			(layers "F.Cu" "F.Mask" "F.Paste")
			(net "VR_PVCCIN_CPU0_AIREF3")
			(options
				(clearance outline)
				(anchor circle)
			)
			(primitives
				(gr_poly
					(pts
						(arc
							(start -0.254 0.1016)
							(mid -0.3556 0)
							(end -0.254 -0.1016)
						)
						(xy 0.3556 -0.1016) (xy 0.3556 0.1016)
					)
					(width 0)
					(fill yes)
				)
			)
		)
		(pad "28" smd custom
			(at 2.8956 0.999998)
			(size 0.0508 0.0508)
			(layers "F.Cu" "F.Mask" "F.Paste")
			(net "ISENSE_PVCCIN_CPU0_PH3_IMON")
			(options
				(clearance outline)
				(anchor circle)
			)
			(primitives
				(gr_poly
					(pts
						(arc
							(start -0.254 0.1016)
							(mid -0.3556 0)
							(end -0.254 -0.1016)
						)
						(xy 0.3556 -0.1016) (xy 0.3556 0.1016)
					)
					(width 0)
					(fill yes)
				)
			)
		)
		(pad "29" smd custom
			(at 2.8956 0.599948)
			(size 0.0508 0.0508)
			(layers "F.Cu" "F.Mask" "F.Paste")
			(net "VR_PVCCIN_CPU0_AIREF4")
			(options
				(clearance outline)
				(anchor circle)
			)
			(primitives
				(gr_poly
					(pts
						(arc
							(start -0.254 0.1016)
							(mid -0.3556 0)
							(end -0.254 -0.1016)
						)
						(xy 0.3556 -0.1016) (xy 0.3556 0.1016)
					)
					(width 0)
					(fill yes)
				)
			)
		)
		(pad "30" smd custom
			(at 2.8956 0.199898)
			(size 0.0508 0.0508)
			(layers "F.Cu" "F.Mask" "F.Paste")
			(net "ISENSE_PVCCIN_CPU0_PH4_IMON")
			(options
				(clearance outline)
				(anchor circle)
			)
			(primitives
				(gr_poly
					(pts
						(arc
							(start -0.254 0.1016)
							(mid -0.3556 0)
							(end -0.254 -0.1016)
						)
						(xy 0.3556 -0.1016) (xy 0.3556 0.1016)
					)
					(width 0)
					(fill yes)
				)
			)
		)
		(pad "31" smd custom
			(at 2.8956 -0.199898)
			(size 0.0508 0.0508)
			(layers "F.Cu" "F.Mask" "F.Paste")
			(net "VR_PVCCIN_CPU0_AIREF5")
			(options
				(clearance outline)
				(anchor circle)
			)
			(primitives
				(gr_poly
					(pts
						(arc
							(start -0.254 0.1016)
							(mid -0.3556 0)
							(end -0.254 -0.1016)
						)
						(xy 0.3556 -0.1016) (xy 0.3556 0.1016)
					)
					(width 0)
					(fill yes)
				)
			)
		)
		(pad "32" smd custom
			(at 2.8956 -0.599948)
			(size 0.0508 0.0508)
			(layers "F.Cu" "F.Mask" "F.Paste")
			(net "ISENSE_PVCCIN_CPU0_PH5_IMON")
			(options
				(clearance outline)
				(anchor circle)
			)
			(primitives
				(gr_poly
					(pts
						(arc
							(start -0.254 0.1016)
							(mid -0.3556 0)
							(end -0.254 -0.1016)
						)
						(xy 0.3556 -0.1016) (xy 0.3556 0.1016)
					)
					(width 0)
					(fill yes)
				)
			)
		)
		(pad "33" smd custom
			(at 2.8956 -0.999998)
			(size 0.0508 0.0508)
			(layers "F.Cu" "F.Mask" "F.Paste")
			(net "Net_273")
			(options
				(clearance outline)
				(anchor circle)
			)
			(primitives
				(gr_poly
					(pts
						(arc
							(start -0.254 0.1016)
							(mid -0.3556 0)
							(end -0.254 -0.1016)
						)
						(xy 0.3556 -0.1016) (xy 0.3556 0.1016)
					)
					(width 0)
					(fill yes)
				)
			)
		)
		(pad "34" smd custom
			(at 2.8956 -1.400048)
			(size 0.0508 0.0508)
			(layers "F.Cu" "F.Mask" "F.Paste")
			(net "Net_290")
			(options
				(clearance outline)
				(anchor circle)
			)
			(primitives
				(gr_poly
					(pts
						(arc
							(start -0.254 0.1016)
							(mid -0.3556 0)
							(end -0.254 -0.1016)
						)
						(xy 0.3556 -0.1016) (xy 0.3556 0.1016)
					)
					(width 0)
					(fill yes)
				)
			)
		)
		(pad "35" smd custom
			(at 2.8956 -1.800098)
			(size 0.0508 0.0508)
			(layers "F.Cu" "F.Mask" "F.Paste")
			(net "VSENSE_PVSA_CPU0_BVSP")
			(options
				(clearance outline)
				(anchor circle)
			)
			(primitives
				(gr_poly
					(pts
						(arc
							(start -0.254 0.1016)
							(mid -0.3556 0)
							(end -0.254 -0.1016)
						)
						(xy 0.3556 -0.1016) (xy 0.3556 0.1016)
					)
					(width 0)
					(fill yes)
				)
			)
		)
		(pad "36" smd custom
			(at 2.8956 -2.199894)
			(size 0.0508 0.0508)
			(layers "F.Cu" "F.Mask" "F.Paste")
			(net "VSENSE_PVSA_CPU0_N")
			(options
				(clearance outline)
				(anchor circle)
			)
			(primitives
				(gr_poly
					(pts
						(arc
							(start -0.254 0.1016)
							(mid -0.3556 0)
							(end -0.254 -0.1016)
						)
						(xy 0.3556 -0.1016) (xy 0.3556 0.1016)
					)
					(width 0)
					(fill yes)
				)
			)
		)
		(pad "37" smd custom
			(at 2.199894 -2.8956)
			(size 0.0508 0.0508)
			(layers "F.Cu" "F.Mask" "F.Paste")
			(net "VR_PVSA_CPU0_BIREF1")
			(options
				(clearance outline)
				(anchor circle)
			)
			(primitives
				(gr_poly
					(pts
						(arc
							(start 0.1016 0.254)
							(mid 0 0.3556)
							(end -0.1016 0.254)
						)
						(xy -0.1016 -0.3556) (xy 0.1016 -0.3556)
					)
					(width 0)
					(fill yes)
				)
			)
		)
		(pad "38" smd custom
			(at 1.800098 -2.8956)
			(size 0.0508 0.0508)
			(layers "F.Cu" "F.Mask" "F.Paste")
			(net "ISENSE_PVSA_CPU0_IMON")
			(options
				(clearance outline)
				(anchor circle)
			)
			(primitives
				(gr_poly
					(pts
						(arc
							(start 0.1016 0.254)
							(mid 0 0.3556)
							(end -0.1016 0.254)
						)
						(xy -0.1016 -0.3556) (xy 0.1016 -0.3556)
					)
					(width 0)
					(fill yes)
				)
			)
		)
		(pad "39" smd custom
			(at 1.400048 -2.8956)
			(size 0.0508 0.0508)
			(layers "F.Cu" "F.Mask" "F.Paste")
			(net "PU_VR_PVCCIN_CPU0_IMON")
			(options
				(clearance outline)
				(anchor circle)
			)
			(primitives
				(gr_poly
					(pts
						(arc
							(start 0.1016 0.254)
							(mid 0 0.3556)
							(end -0.1016 0.254)
						)
						(xy -0.1016 -0.3556) (xy 0.1016 -0.3556)
					)
					(width 0)
					(fill yes)
				)
			)
		)
		(pad "40" smd custom
			(at 0.999998 -2.8956)
			(size 0.0508 0.0508)
			(layers "F.Cu" "F.Mask" "F.Paste")
			(net "Net_292")
			(options
				(clearance outline)
				(anchor circle)
			)
			(primitives
				(gr_poly
					(pts
						(arc
							(start 0.1016 0.254)
							(mid 0 0.3556)
							(end -0.1016 0.254)
						)
						(xy -0.1016 -0.3556) (xy 0.1016 -0.3556)
					)
					(width 0)
					(fill yes)
				)
			)
		)
		(pad "41" smd custom
			(at 0.599948 -2.8956)
			(size 0.0508 0.0508)
			(layers "F.Cu" "F.Mask" "F.Paste")
			(net "VR_PVCCIN_CPU0_XADDR2")
			(options
				(clearance outline)
				(anchor circle)
			)
			(primitives
				(gr_poly
					(pts
						(arc
							(start 0.1016 0.254)
							(mid 0 0.3556)
							(end -0.1016 0.254)
						)
						(xy -0.1016 -0.3556) (xy 0.1016 -0.3556)
					)
					(width 0)
					(fill yes)
				)
			)
		)
		(pad "42" smd custom
			(at 0.199898 -2.8956)
			(size 0.0508 0.0508)
			(layers "F.Cu" "F.Mask" "F.Paste")
			(net "A_TSENSE_PVSA_CPU0")
			(options
				(clearance outline)
				(anchor circle)
			)
			(primitives
				(gr_poly
					(pts
						(arc
							(start 0.1016 0.254)
							(mid 0 0.3556)
							(end -0.1016 0.254)
						)
						(xy -0.1016 -0.3556) (xy 0.1016 -0.3556)
					)
					(width 0)
					(fill yes)
				)
			)
		)
		(pad "43" smd custom
			(at -0.199898 -2.8956)
			(size 0.0508 0.0508)
			(layers "F.Cu" "F.Mask" "F.Paste")
			(net "A_TSENSE_PVCCIN_CPU0")
			(options
				(clearance outline)
				(anchor circle)
			)
			(primitives
				(gr_poly
					(pts
						(arc
							(start 0.1016 0.254)
							(mid 0 0.3556)
							(end -0.1016 0.254)
						)
						(xy -0.1016 -0.3556) (xy 0.1016 -0.3556)
					)
					(width 0)
					(fill yes)
				)
			)
		)
		(pad "44" smd custom
			(at -0.599948 -2.8956)
			(size 0.0508 0.0508)
			(layers "F.Cu" "F.Mask" "F.Paste")
			(net "VR_PVCCIN_CPU0_XADDR1")
			(options
				(clearance outline)
				(anchor circle)
			)
			(primitives
				(gr_poly
					(pts
						(arc
							(start 0.1016 0.254)
							(mid 0 0.3556)
							(end -0.1016 0.254)
						)
						(xy -0.1016 -0.3556) (xy 0.1016 -0.3556)
					)
					(width 0)
					(fill yes)
				)
			)
		)
		(pad "45" smd custom
			(at -0.999998 -2.8956)
			(size 0.0508 0.0508)
			(layers "F.Cu" "F.Mask" "F.Paste")
			(net "VR_PVCCIN_CPU0_AVINSEN")
			(options
				(clearance outline)
				(anchor circle)
			)
			(primitives
				(gr_poly
					(pts
						(arc
							(start 0.1016 0.254)
							(mid 0 0.3556)
							(end -0.1016 0.254)
						)
						(xy -0.1016 -0.3556) (xy 0.1016 -0.3556)
					)
					(width 0)
					(fill yes)
				)
			)
		)
		(pad "46" smd custom
			(at -1.400048 -2.8956)
			(size 0.0508 0.0508)
			(layers "F.Cu" "F.Mask" "F.Paste")
			(net "Net_217")
			(options
				(clearance outline)
				(anchor circle)
			)
			(primitives
				(gr_poly
					(pts
						(arc
							(start 0.1016 0.254)
							(mid 0 0.3556)
							(end -0.1016 0.254)
						)
						(xy -0.1016 -0.3556) (xy 0.1016 -0.3556)
					)
					(width 0)
					(fill yes)
				)
			)
		)
		(pad "47" smd custom
			(at -1.800098 -2.8956)
			(size 0.0508 0.0508)
			(layers "F.Cu" "F.Mask" "F.Paste")
			(net "VR_PVCCIN_CPU0_VDD")
			(options
				(clearance outline)
				(anchor circle)
			)
			(primitives
				(gr_poly
					(pts
						(arc
							(start 0.1016 0.254)
							(mid 0 0.3556)
							(end -0.1016 0.254)
						)
						(xy -0.1016 -0.3556) (xy 0.1016 -0.3556)
					)
					(width 0)
					(fill yes)
				)
			)
		)
		(pad "48" smd custom
			(at -2.199894 -2.8956)
			(size 0.0508 0.0508)
			(layers "F.Cu" "F.Mask" "F.Paste")
			(net "VR_PVCCIN_CPU0_VD12")
			(options
				(clearance outline)
				(anchor circle)
			)
			(primitives
				(gr_poly
					(pts
						(arc
							(start 0.1016 0.254)
							(mid 0 0.3556)
							(end -0.1016 0.254)
						)
						(xy -0.1016 -0.3556) (xy 0.1016 -0.3556)
					)
					(width 0)
					(fill yes)
				)
			)
		)
		(pad "49" smd rect
			(at 0 0)
			(size 3.6068 3.6068)
			(layers "F.Cu" "F.Mask" "F.Paste")
			(net "GND")
		)
		(zone
			(layer "F.Cu")
			(hatch none 0.5)
			(connect_pads
				(clearance 0)
			)
			(min_thickness 0.25)
			(keepout
				(tracks allowed)
				(vias not_allowed)
				(pads allowed)
				(copperpour not_allowed)
				(footprints allowed)
			)
			(placement
				(enabled no)
				(sheetname "")
			)
			(fill
				(thermal_gap 0.5)
				(thermal_bridge_width 0.5)
				(island_removal_mode 0)
			)
			(polygon
				(pts
					(xy 181.738778 -72.387714) (xy 181.738778 -68.247514) (xy 182.470044 -68.247514) (xy 182.470044 -68.248022)
					(xy 182.4736 -68.248022) (xy 182.4736 -71.6534) (xy 186.0804 -71.6534) (xy 186.0804 -68.0466) (xy 182.4736 -68.0466)
					(xy 182.4736 -68.247768) (xy 182.470298 -68.247768) (xy 182.470298 -68.247006) (xy 181.738778 -68.247006)
					(xy 181.738778 -67.311016) (xy 186.816238 -67.311016) (xy 186.816238 -72.387714)
				)
			)
		)
		(zone
			(layer "F.Cu")
			(hatch none 0.5)
			(connect_pads
				(clearance 0)
			)
			(min_thickness 0.25)
			(keepout
				(tracks not_allowed)
				(vias allowed)
				(pads allowed)
				(copperpour not_allowed)
				(footprints allowed)
			)
			(placement
				(enabled no)
				(sheetname "")
			)
			(fill
				(thermal_gap 0.5)
				(thermal_bridge_width 0.5)
				(island_removal_mode 0)
			)
			(polygon
				(pts
					(xy 181.738778 -72.387714) (xy 181.738778 -68.247514) (xy 182.470044 -68.247514) (xy 182.470044 -68.248022)
					(xy 182.4736 -68.248022) (xy 182.4736 -71.6534) (xy 186.0804 -71.6534) (xy 186.0804 -68.0466) (xy 182.4736 -68.0466)
					(xy 182.4736 -68.247768) (xy 182.470298 -68.247768) (xy 182.470298 -68.247006) (xy 181.738778 -68.247006)
					(xy 181.738778 -67.311016) (xy 186.816238 -67.311016) (xy 186.816238 -72.387714)
				)
			)
		)
	)
	(footprint ""
		(layer "F.Cu")
		(at 400.685 -76.073)
		(property "Reference" "C8E3"
			(at 0 0 0)
			(layer "F.SilkS")
			(hide yes)
			(effects
				(font
					(size 1.27 1.27)
				)
			)
		)
		(property "Value" ""
			(at 0 0 0)
			(layer "F.Fab")
			(effects
				(font
					(size 1.27 1.27)
				)
			)
		)
		(duplicate_pad_numbers_are_jumpers no)
		(fp_poly
			(pts
				(xy 0.3048 -0.1016) (xy 0.3048 0.9906) (xy -0.3048 0.9906) (xy -0.3048 -0.1016)
			)
			(stroke
				(width 0)
				(type default)
			)
			(fill no)
			(layer "F.CrtYd")
		)
		(fp_line
			(start -0.3048 -0.1016)
			(end -0.3048 0.9906)
			(stroke
				(width 0.1)
				(type default)
			)
			(layer "F.Fab")
		)
		(fp_line
			(start -0.3048 0.9906)
			(end 0.3048 0.9906)
			(stroke
				(width 0.1)
				(type default)
			)
			(layer "F.Fab")
		)
		(fp_line
			(start 0.3048 -0.1016)
			(end -0.3048 -0.1016)
			(stroke
				(width 0.1)
				(type default)
			)
			(layer "F.Fab")
		)
		(fp_line
			(start 0.3048 0.9906)
			(end 0.3048 -0.1016)
			(stroke
				(width 0.1)
				(type default)
			)
			(layer "F.Fab")
		)
		(pad "1" smd rect
			(at 0 0)
			(size 0.508 0.508)
			(layers "F.Cu" "F.Mask" "F.Paste")
			(net "PWRGD_P12V_HSC")
		)
		(pad "2" smd rect
			(at 0 0.889)
			(size 0.508 0.508)
			(layers "F.Cu" "F.Mask" "F.Paste")
			(net "GND")
		)
		(zone
			(layer "F.Cu")
			(hatch none 0.5)
			(connect_pads
				(clearance 0)
			)
			(min_thickness 0.25)
			(keepout
				(tracks allowed)
				(vias not_allowed)
				(pads allowed)
				(copperpour not_allowed)
				(footprints allowed)
			)
			(placement
				(enabled no)
				(sheetname "")
			)
			(fill
				(thermal_gap 0.5)
				(thermal_bridge_width 0.5)
				(island_removal_mode 0)
			)
			(polygon
				(pts
					(xy 400.431 -75.819) (xy 400.939 -75.819) (xy 400.939 -75.438) (xy 400.431 -75.438)
				)
			)
		)
		(zone
			(layer "F.Cu")
			(hatch none 0.5)
			(connect_pads
				(clearance 0)
			)
			(min_thickness 0.25)
			(keepout
				(tracks not_allowed)
				(vias allowed)
				(pads allowed)
				(copperpour not_allowed)
				(footprints allowed)
			)
			(placement
				(enabled no)
				(sheetname "")
			)
			(fill
				(thermal_gap 0.5)
				(thermal_bridge_width 0.5)
				(island_removal_mode 0)
			)
			(polygon
				(pts
					(xy 400.431 -75.438) (xy 400.939 -75.438) (xy 400.939 -75.819) (xy 400.431 -75.819)
				)
			)
		)
	)
	(footprint ""
		(layer "F.Cu")
		(at 439.722006 -31.4325 180)
		(property "Reference" "U25W5"
			(at 0 0 180)
			(layer "F.SilkS")
			(hide yes)
			(effects
				(font
					(size 1.27 1.27)
				)
			)
		)
		(property "Value" "*"
			(at -8.423656 -16.0909 180)
			(unlocked yes)
			(layer "F.Fab")
			(hide yes)
			(effects
				(font
					(size 1.27 1.016)
					(thickness 0.1524)
				)
			)
		)
		(property "Device Type" "H5AN4G6NAFR-TFC-GP_MEMORY-G2-HA"
			(at -8.423656 -17.6149 180)
			(unlocked yes)
			(layer "F.Fab")
			(hide yes)
			(effects
				(font
					(size 1.27 1.016)
					(thickness 0.1524)
				)
			)
		)
		(duplicate_pad_numbers_are_jumpers no)
		(fp_line
			(start 3.750056 6.500114)
			(end 3.750056 -6.500114)
			(stroke
				(width 0.1524)
				(type default)
			)
			(layer "F.SilkS")
		)
		(fp_line
			(start 3.750056 -6.500114)
			(end -3.750056 -6.500114)
			(stroke
				(width 0.1524)
				(type default)
			)
			(layer "F.SilkS")
		)
		(fp_line
			(start -3.750056 6.500114)
			(end 3.750056 6.500114)
			(stroke
				(width 0.1524)
				(type default)
			)
			(layer "F.SilkS")
		)
		(fp_line
			(start -3.750056 -6.500114)
			(end -3.750056 6.500114)
			(stroke
				(width 0.1524)
				(type default)
			)
			(layer "F.SilkS")
		)
		(fp_line
			(start -4.080256 -5.230114)
			(end -4.080256 -6.830314)
			(stroke
				(width 0.508)
				(type default)
			)
			(layer "F.SilkS")
		)
		(fp_line
			(start -4.080256 -6.830314)
			(end -2.480056 -6.830314)
			(stroke
				(width 0.508)
				(type default)
			)
			(layer "F.SilkS")
		)
		(fp_rect
			(start -3.750056 6.500114)
			(end 3.750056 -6.500114)
			(stroke
				(width 0)
				(type default)
			)
			(fill no)
			(layer "F.CrtYd")
		)
		(fp_poly
			(pts
				(xy -4.7498 7.5057) (xy -4.7498 -7.5057) (xy 4.7498 -7.5057) (xy 4.7498 -0.54864) (xy 3.750056 -0.54864)
				(xy 3.750056 -6.500114) (xy -3.750056 -6.500114) (xy -3.750056 6.500114) (xy 3.750056 6.500114)
				(xy 3.750056 -0.54356) (xy 4.7498 -0.54356) (xy 4.7498 7.5057)
			)
			(stroke
				(width 0)
				(type default)
			)
			(fill no)
			(layer "F.CrtYd")
		)
		(fp_rect
			(start -5.750052 8.50011)
			(end 5.750052 -8.50011)
			(stroke
				(width 0)
				(type default)
			)
			(fill no)
			(layer "F.Fab")
		)
		(pad "A1" smd circle
			(at -3.199892 -5.999988 180)
			(size 0.3556 0.3556)
			(layers "F.Cu" "F.Mask" "F.Paste")
			(net "P1V2_AUX_BMC")
		)
		(pad "A2" smd circle
			(at -2.400046 -5.999988 180)
			(size 0.3556 0.3556)
			(layers "F.Cu" "F.Mask" "F.Paste")
			(net "GND")
		)
		(pad "A3" smd circle
			(at -1.599946 -5.999988 180)
			(size 0.3556 0.3556)
			(layers "F.Cu" "F.Mask" "F.Paste")
			(net "BMC_M_DQ8")
		)
		(pad "A7" smd circle
			(at 1.599946 -5.999988 180)
			(size 0.3556 0.3556)
			(layers "F.Cu" "F.Mask" "F.Paste")
			(net "BMC_M_DQS1_DN")
		)
		(pad "A8" smd circle
			(at 2.400046 -5.999988 180)
			(size 0.3556 0.3556)
			(layers "F.Cu" "F.Mask" "F.Paste")
			(net "GND")
		)
		(pad "A9" smd circle
			(at 3.199892 -5.999988 180)
			(size 0.3556 0.3556)
			(layers "F.Cu" "F.Mask" "F.Paste")
			(net "P1V2_AUX_BMC")
		)
		(pad "B1" smd circle
			(at -3.199892 -5.199888 180)
			(size 0.3556 0.3556)
			(layers "F.Cu" "F.Mask" "F.Paste")
			(net "P2V5_AUX_BMC")
		)
		(pad "B2" smd circle
			(at -2.400046 -5.199888 180)
			(size 0.3556 0.3556)
			(layers "F.Cu" "F.Mask" "F.Paste")
			(net "GND")
		)
		(pad "B3" smd circle
			(at -1.599946 -5.199888 180)
			(size 0.3556 0.3556)
			(layers "F.Cu" "F.Mask" "F.Paste")
			(net "P1V2_AUX_BMC")
		)
		(pad "B7" smd circle
			(at 1.599946 -5.199888 180)
			(size 0.3556 0.3556)
			(layers "F.Cu" "F.Mask" "F.Paste")
			(net "BMC_M_DQS1_DP")
		)
		(pad "B8" smd circle
			(at 2.400046 -5.199888 180)
			(size 0.3556 0.3556)
			(layers "F.Cu" "F.Mask" "F.Paste")
			(net "BMC_M_DQ9")
		)
		(pad "B9" smd circle
			(at 3.199892 -5.199888 180)
			(size 0.3556 0.3556)
			(layers "F.Cu" "F.Mask" "F.Paste")
			(net "P1V2_AUX_BMC")
		)
		(pad "C1" smd circle
			(at -3.199892 -4.400042 180)
			(size 0.3556 0.3556)
			(layers "F.Cu" "F.Mask" "F.Paste")
			(net "P1V2_AUX_BMC")
		)
		(pad "C2" smd circle
			(at -2.400046 -4.400042 180)
			(size 0.3556 0.3556)
			(layers "F.Cu" "F.Mask" "F.Paste")
			(net "BMC_M_DQ12")
		)
		(pad "C3" smd circle
			(at -1.599946 -4.400042 180)
			(size 0.3556 0.3556)
			(layers "F.Cu" "F.Mask" "F.Paste")
			(net "BMC_M_DQ10")
		)
		(pad "C7" smd circle
			(at 1.599946 -4.400042 180)
			(size 0.3556 0.3556)
			(layers "F.Cu" "F.Mask" "F.Paste")
			(net "BMC_M_DQ11")
		)
		(pad "C8" smd circle
			(at 2.400046 -4.400042 180)
			(size 0.3556 0.3556)
			(layers "F.Cu" "F.Mask" "F.Paste")
			(net "BMC_M_DQ13")
		)
		(pad "C9" smd circle
			(at 3.199892 -4.400042 180)
			(size 0.3556 0.3556)
			(layers "F.Cu" "F.Mask" "F.Paste")
			(net "GND")
		)
		(pad "D1" smd circle
			(at -3.199892 -3.599942 180)
			(size 0.3556 0.3556)
			(layers "F.Cu" "F.Mask" "F.Paste")
			(net "P1V2_AUX_BMC")
		)
		(pad "D2" smd circle
			(at -2.400046 -3.599942 180)
			(size 0.3556 0.3556)
			(layers "F.Cu" "F.Mask" "F.Paste")
			(net "GND")
		)
		(pad "D3" smd circle
			(at -1.599946 -3.599942 180)
			(size 0.3556 0.3556)
			(layers "F.Cu" "F.Mask" "F.Paste")
			(net "BMC_M_DQ14")
		)
		(pad "D7" smd circle
			(at 1.599946 -3.599942 180)
			(size 0.3556 0.3556)
			(layers "F.Cu" "F.Mask" "F.Paste")
			(net "BMC_M_DQ15")
		)
		(pad "D8" smd circle
			(at 2.400046 -3.599942 180)
			(size 0.3556 0.3556)
			(layers "F.Cu" "F.Mask" "F.Paste")
			(net "GND")
		)
		(pad "D9" smd circle
			(at 3.199892 -3.599942 180)
			(size 0.3556 0.3556)
			(layers "F.Cu" "F.Mask" "F.Paste")
			(net "P1V2_AUX_BMC")
		)
		(pad "E1" smd circle
			(at -3.199892 -2.800096 180)
			(size 0.3556 0.3556)
			(layers "F.Cu" "F.Mask" "F.Paste")
			(net "GND")
		)
		(pad "E2" smd circle
			(at -2.400046 -2.800096 180)
			(size 0.3556 0.3556)
			(layers "F.Cu" "F.Mask" "F.Paste")
			(net "BMC_M_DM1")
		)
		(pad "E3" smd circle
			(at -1.599946 -2.800096 180)
			(size 0.3556 0.3556)
			(layers "F.Cu" "F.Mask" "F.Paste")
			(net "GND")
		)
		(pad "E7" smd circle
			(at 1.599946 -2.800096 180)
			(size 0.3556 0.3556)
			(layers "F.Cu" "F.Mask" "F.Paste")
			(net "BMC_M_DM0")
		)
		(pad "E8" smd circle
			(at 2.400046 -2.800096 180)
			(size 0.3556 0.3556)
			(layers "F.Cu" "F.Mask" "F.Paste")
			(net "GND")
		)
		(pad "E9" smd circle
			(at 3.199892 -2.800096 180)
			(size 0.3556 0.3556)
			(layers "F.Cu" "F.Mask" "F.Paste")
			(net "GND")
		)
		(pad "F1" smd circle
			(at -3.199892 -1.999996 180)
			(size 0.3556 0.3556)
			(layers "F.Cu" "F.Mask" "F.Paste")
			(net "GND")
		)
		(pad "F2" smd circle
			(at -2.400046 -1.999996 180)
			(size 0.3556 0.3556)
			(layers "F.Cu" "F.Mask" "F.Paste")
			(net "P1V2_AUX_BMC")
		)
		(pad "F3" smd circle
			(at -1.599946 -1.999996 180)
			(size 0.3556 0.3556)
			(layers "F.Cu" "F.Mask" "F.Paste")
			(net "BMC_M_DQS0_DN")
		)
		(pad "F7" smd circle
			(at 1.599946 -1.999996 180)
			(size 0.3556 0.3556)
			(layers "F.Cu" "F.Mask" "F.Paste")
			(net "BMC_M_DQ1")
		)
		(pad "F8" smd circle
			(at 2.400046 -1.999996 180)
			(size 0.3556 0.3556)
			(layers "F.Cu" "F.Mask" "F.Paste")
			(net "P1V2_AUX_BMC")
		)
		(pad "F9" smd circle
			(at 3.199892 -1.999996 180)
			(size 0.3556 0.3556)
			(layers "F.Cu" "F.Mask" "F.Paste")
			(net "BMC_ZQ")
		)
		(pad "G1" smd circle
			(at -3.199892 -1.199896 180)
			(size 0.3556 0.3556)
			(layers "F.Cu" "F.Mask" "F.Paste")
			(net "P1V2_AUX_BMC")
		)
		(pad "G2" smd circle
			(at -2.400046 -1.199896 180)
			(size 0.3556 0.3556)
			(layers "F.Cu" "F.Mask" "F.Paste")
			(net "BMC_M_DQ0")
		)
		(pad "G3" smd circle
			(at -1.599946 -1.199896 180)
			(size 0.3556 0.3556)
			(layers "F.Cu" "F.Mask" "F.Paste")
			(net "BMC_M_DQS0_DP")
		)
		(pad "G7" smd circle
			(at 1.599946 -1.199896 180)
			(size 0.3556 0.3556)
			(layers "F.Cu" "F.Mask" "F.Paste")
			(net "P1V2_AUX_BMC")
		)
		(pad "G8" smd circle
			(at 2.400046 -1.199896 180)
			(size 0.3556 0.3556)
			(layers "F.Cu" "F.Mask" "F.Paste")
			(net "GND")
		)
		(pad "G9" smd circle
			(at 3.199892 -1.199896 180)
			(size 0.3556 0.3556)
			(layers "F.Cu" "F.Mask" "F.Paste")
			(net "P1V2_AUX_BMC")
		)
		(pad "H1" smd circle
			(at -3.199892 -0.40005 180)
			(size 0.3556 0.3556)
			(layers "F.Cu" "F.Mask" "F.Paste")
			(net "GND")
		)
		(pad "H2" smd circle
			(at -2.400046 -0.40005 180)
			(size 0.3556 0.3556)
			(layers "F.Cu" "F.Mask" "F.Paste")
			(net "BMC_M_DQ4")
		)
		(pad "H3" smd circle
			(at -1.599946 -0.40005 180)
			(size 0.3556 0.3556)
			(layers "F.Cu" "F.Mask" "F.Paste")
			(net "BMC_M_DQ2")
		)
		(pad "H7" smd circle
			(at 1.599946 -0.40005 180)
			(size 0.3556 0.3556)
			(layers "F.Cu" "F.Mask" "F.Paste")
			(net "BMC_M_DQ3")
		)
		(pad "H8" smd circle
			(at 2.400046 -0.40005 180)
			(size 0.3556 0.3556)
			(layers "F.Cu" "F.Mask" "F.Paste")
			(net "BMC_M_DQ5")
		)
		(pad "H9" smd circle
			(at 3.199892 -0.40005 180)
			(size 0.3556 0.3556)
			(layers "F.Cu" "F.Mask" "F.Paste")
			(net "GND")
		)
		(pad "J1" smd circle
			(at -3.199892 0.40005 180)
			(size 0.3556 0.3556)
			(layers "F.Cu" "F.Mask" "F.Paste")
			(net "P1V2_AUX_BMC")
		)
		(pad "J2" smd circle
			(at -2.400046 0.40005 180)
			(size 0.3556 0.3556)
			(layers "F.Cu" "F.Mask" "F.Paste")
			(net "P1V2_AUX_BMC")
		)
		(pad "J3" smd circle
			(at -1.599946 0.40005 180)
			(size 0.3556 0.3556)
			(layers "F.Cu" "F.Mask" "F.Paste")
			(net "BMC_M_DQ6")
		)
		(pad "J7" smd circle
			(at 1.599946 0.40005 180)
			(size 0.3556 0.3556)
			(layers "F.Cu" "F.Mask" "F.Paste")
			(net "BMC_M_DQ7")
		)
		(pad "J8" smd circle
			(at 2.400046 0.40005 180)
			(size 0.3556 0.3556)
			(layers "F.Cu" "F.Mask" "F.Paste")
			(net "P1V2_AUX_BMC")
		)
		(pad "J9" smd circle
			(at 3.199892 0.40005 180)
			(size 0.3556 0.3556)
			(layers "F.Cu" "F.Mask" "F.Paste")
			(net "P1V2_AUX_BMC")
		)
		(pad "K1" smd circle
			(at -3.199892 1.199896 180)
			(size 0.3556 0.3556)
			(layers "F.Cu" "F.Mask" "F.Paste")
			(net "GND")
		)
		(pad "K2" smd circle
			(at -2.400046 1.199896 180)
			(size 0.3556 0.3556)
			(layers "F.Cu" "F.Mask" "F.Paste")
			(net "BMC_M_CKE")
		)
		(pad "K3" smd circle
			(at -1.599946 1.199896 180)
			(size 0.3556 0.3556)
			(layers "F.Cu" "F.Mask" "F.Paste")
			(net "BMC_M_ODT")
		)
		(pad "K7" smd circle
			(at 1.599946 1.199896 180)
			(size 0.3556 0.3556)
			(layers "F.Cu" "F.Mask" "F.Paste")
			(net "BMC_M_CLK_DP")
		)
		(pad "K8" smd circle
			(at 2.400046 1.199896 180)
			(size 0.3556 0.3556)
			(layers "F.Cu" "F.Mask" "F.Paste")
			(net "BMC_M_CLK_DN")
		)
		(pad "K9" smd circle
			(at 3.199892 1.199896 180)
			(size 0.3556 0.3556)
			(layers "F.Cu" "F.Mask" "F.Paste")
			(net "GND")
		)
		(pad "L1" smd circle
			(at -3.199892 1.999996 180)
			(size 0.3556 0.3556)
			(layers "F.Cu" "F.Mask" "F.Paste")
			(net "P1V2_AUX_BMC")
		)
		(pad "L2" smd circle
			(at -2.400046 1.999996 180)
			(size 0.3556 0.3556)
			(layers "F.Cu" "F.Mask" "F.Paste")
			(net "BMC_M_WE_N")
		)
		(pad "L3" smd circle
			(at -1.599946 1.999996 180)
			(size 0.3556 0.3556)
			(layers "F.Cu" "F.Mask" "F.Paste")
			(net "BMC_M_MACT_N")
		)
		(pad "L7" smd circle
			(at 1.599946 1.999996 180)
			(size 0.3556 0.3556)
			(layers "F.Cu" "F.Mask" "F.Paste")
			(net "BMC_M_CS_N")
		)
		(pad "L8" smd circle
			(at 2.400046 1.999996 180)
			(size 0.3556 0.3556)
			(layers "F.Cu" "F.Mask" "F.Paste")
			(net "BMC_M_RAS_N")
		)
		(pad "L9" smd circle
			(at 3.199892 1.999996 180)
			(size 0.3556 0.3556)
			(layers "F.Cu" "F.Mask" "F.Paste")
			(net "P1V2_AUX_BMC")
		)
		(pad "M1" smd circle
			(at -3.199892 2.800096 180)
			(size 0.3556 0.3556)
			(layers "F.Cu" "F.Mask" "F.Paste")
			(net "BMC_M_VREFCA")
		)
		(pad "M2" smd circle
			(at -2.400046 2.800096 180)
			(size 0.3556 0.3556)
			(layers "F.Cu" "F.Mask" "F.Paste")
			(net "BMC_M_BG0")
		)
		(pad "M3" smd circle
			(at -1.599946 2.800096 180)
			(size 0.3556 0.3556)
			(layers "F.Cu" "F.Mask" "F.Paste")
			(net "BMC_M_A10")
		)
		(pad "M7" smd circle
			(at 1.599946 2.800096 180)
			(size 0.3556 0.3556)
			(layers "F.Cu" "F.Mask" "F.Paste")
			(net "BMC_M_A12")
		)
		(pad "M8" smd circle
			(at 2.400046 2.800096 180)
			(size 0.3556 0.3556)
			(layers "F.Cu" "F.Mask" "F.Paste")
			(net "BMC_M_CAS_N")
		)
		(pad "M9" smd circle
			(at 3.199892 2.800096 180)
			(size 0.3556 0.3556)
			(layers "F.Cu" "F.Mask" "F.Paste")
			(net "GND")
		)
		(pad "N1" smd circle
			(at -3.199892 3.599942 180)
			(size 0.3556 0.3556)
			(layers "F.Cu" "F.Mask" "F.Paste")
			(net "GND")
		)
		(pad "N2" smd circle
			(at -2.400046 3.599942 180)
			(size 0.3556 0.3556)
			(layers "F.Cu" "F.Mask" "F.Paste")
			(net "BMC_M_BA0")
		)
		(pad "N3" smd circle
			(at -1.599946 3.599942 180)
			(size 0.3556 0.3556)
			(layers "F.Cu" "F.Mask" "F.Paste")
			(net "BMC_M_A4")
		)
		(pad "N7" smd circle
			(at 1.599946 3.599942 180)
			(size 0.3556 0.3556)
			(layers "F.Cu" "F.Mask" "F.Paste")
			(net "BMC_M_A3")
		)
		(pad "N8" smd circle
			(at 2.400046 3.599942 180)
			(size 0.3556 0.3556)
			(layers "F.Cu" "F.Mask" "F.Paste")
			(net "BMC_M_BA1")
		)
		(pad "N9" smd circle
			(at 3.199892 3.599942 180)
			(size 0.3556 0.3556)
			(layers "F.Cu" "F.Mask" "F.Paste")
			(net "GND")
		)
		(pad "P1" smd circle
			(at -3.199892 4.400042 180)
			(size 0.3556 0.3556)
			(layers "F.Cu" "F.Mask" "F.Paste")
			(net "BMC_M_RST_N")
		)
		(pad "P2" smd circle
			(at -2.400046 4.400042 180)
			(size 0.3556 0.3556)
			(layers "F.Cu" "F.Mask" "F.Paste")
			(net "BMC_M_A6")
		)
		(pad "P3" smd circle
			(at -1.599946 4.400042 180)
			(size 0.3556 0.3556)
			(layers "F.Cu" "F.Mask" "F.Paste")
			(net "BMC_M_A0")
		)
		(pad "P7" smd circle
			(at 1.599946 4.400042 180)
			(size 0.3556 0.3556)
			(layers "F.Cu" "F.Mask" "F.Paste")
			(net "BMC_M_A1")
		)
		(pad "P8" smd circle
			(at 2.400046 4.400042 180)
			(size 0.3556 0.3556)
			(layers "F.Cu" "F.Mask" "F.Paste")
			(net "BMC_M_A5")
		)
		(pad "P9" smd circle
			(at 3.199892 4.400042 180)
			(size 0.3556 0.3556)
			(layers "F.Cu" "F.Mask" "F.Paste")
			(net "BMC_M_MALERT_N")
		)
		(pad "R1" smd circle
			(at -3.199892 5.199888 180)
			(size 0.3556 0.3556)
			(layers "F.Cu" "F.Mask" "F.Paste")
			(net "P1V2_AUX_BMC")
		)
		(pad "R2" smd circle
			(at -2.400046 5.199888 180)
			(size 0.3556 0.3556)
			(layers "F.Cu" "F.Mask" "F.Paste")
			(net "BMC_M_A8")
		)
		(pad "R3" smd circle
			(at -1.599946 5.199888 180)
			(size 0.3556 0.3556)
			(layers "F.Cu" "F.Mask" "F.Paste")
			(net "BMC_M_A2")
		)
		(pad "R7" smd circle
			(at 1.599946 5.199888 180)
			(size 0.3556 0.3556)
			(layers "F.Cu" "F.Mask" "F.Paste")
			(net "BMC_M_A9")
		)
		(pad "R8" smd circle
			(at 2.400046 5.199888 180)
			(size 0.3556 0.3556)
			(layers "F.Cu" "F.Mask" "F.Paste")
			(net "BMC_M_A7")
		)
		(pad "R9" smd circle
			(at 3.199892 5.199888 180)
			(size 0.3556 0.3556)
			(layers "F.Cu" "F.Mask" "F.Paste")
			(net "P2V5_AUX_BMC")
		)
		(pad "T1" smd circle
			(at -3.199892 5.999988 180)
			(size 0.3556 0.3556)
			(layers "F.Cu" "F.Mask" "F.Paste")
			(net "GND")
		)
		(pad "T2" smd circle
			(at -2.400046 5.999988 180)
			(size 0.3556 0.3556)
			(layers "F.Cu" "F.Mask" "F.Paste")
			(net "BMC_M_A11")
		)
		(pad "T3" smd circle
			(at -1.599946 5.999988 180)
			(size 0.3556 0.3556)
			(layers "F.Cu" "F.Mask" "F.Paste")
			(net "BMC_M_PAR")
		)
		(pad "T7" smd circle
			(at 1.599946 5.999988 180)
			(size 0.3556 0.3556)
			(layers "F.Cu" "F.Mask" "F.Paste")
			(net "Net_6479")
		)
		(pad "T8" smd circle
			(at 2.400046 5.999988 180)
			(size 0.3556 0.3556)
			(layers "F.Cu" "F.Mask" "F.Paste")
			(net "BMC_M_A13")
		)
		(pad "T9" smd circle
			(at 3.199892 5.999988 180)
			(size 0.3556 0.3556)
			(layers "F.Cu" "F.Mask" "F.Paste")
			(net "P1V2_AUX_BMC")
		)
	)
	(footprint ""
		(layer "F.Cu")
		(at 394.6525 -75.819 90)
		(property "Reference" "R7D34"
			(at 0 0 90)
			(layer "F.SilkS")
			(hide yes)
			(effects
				(font
					(size 1.27 1.27)
				)
			)
		)
		(property "Value" ""
			(at 0 0 90)
			(layer "F.Fab")
			(effects
				(font
					(size 1.27 1.27)
				)
			)
		)
		(duplicate_pad_numbers_are_jumpers no)
		(fp_poly
			(pts
				(xy -0.2794 -0.1016) (xy 0.2794 -0.1016) (xy 0.2794 0.9906) (xy -0.2794 0.9906)
			)
			(stroke
				(width 0)
				(type default)
			)
			(fill no)
			(layer "F.CrtYd")
		)
		(fp_line
			(start 0.2794 -0.1016)
			(end -0.2794 -0.1016)
			(stroke
				(width 0.1)
				(type default)
			)
			(layer "F.Fab")
		)
		(fp_line
			(start -0.2794 -0.1016)
			(end -0.2794 0.9906)
			(stroke
				(width 0.1)
				(type default)
			)
			(layer "F.Fab")
		)
		(fp_line
			(start 0.2794 0.9906)
			(end 0.2794 -0.1016)
			(stroke
				(width 0.1)
				(type default)
			)
			(layer "F.Fab")
		)
		(fp_line
			(start -0.2794 0.9906)
			(end 0.2794 0.9906)
			(stroke
				(width 0.1)
				(type default)
			)
			(layer "F.Fab")
		)
		(pad "1" smd rect
			(at 0 0 90)
			(size 0.508 0.508)
			(layers "F.Cu" "F.Mask" "F.Paste")
			(net "FM_CPU0_THERMTRIP_LVT3_R_N")
		)
		(pad "2" smd rect
			(at 0 0.889 90)
			(size 0.508 0.508)
			(layers "F.Cu" "F.Mask" "F.Paste")
			(net "FM_CPU0_THERMTRIP_LVT3_N")
		)
		(zone
			(layer "F.Cu")
			(hatch none 0.5)
			(connect_pads
				(clearance 0)
			)
			(min_thickness 0.25)
			(keepout
				(tracks allowed)
				(vias not_allowed)
				(pads allowed)
				(copperpour not_allowed)
				(footprints allowed)
			)
			(placement
				(enabled no)
				(sheetname "")
			)
			(fill
				(thermal_gap 0.5)
				(thermal_bridge_width 0.5)
				(island_removal_mode 0)
			)
			(polygon
				(pts
					(xy 394.9065 -75.565) (xy 394.9065 -76.073) (xy 395.2875 -76.073) (xy 395.2875 -75.565)
				)
			)
		)
		(zone
			(layer "F.Cu")
			(hatch none 0.5)
			(connect_pads
				(clearance 0)
			)
			(min_thickness 0.25)
			(keepout
				(tracks not_allowed)
				(vias allowed)
				(pads allowed)
				(copperpour not_allowed)
				(footprints allowed)
			)
			(placement
				(enabled no)
				(sheetname "")
			)
			(fill
				(thermal_gap 0.5)
				(thermal_bridge_width 0.5)
				(island_removal_mode 0)
			)
			(polygon
				(pts
					(xy 395.2875 -75.565) (xy 395.2875 -76.073) (xy 394.9065 -76.073) (xy 394.9065 -75.565)
				)
			)
		)
	)
	(footprint ""
		(layer "F.Cu")
		(at 180.381148 -72.96785 -90)
		(property "Reference" "C4D25"
			(at 0 0 270)
			(layer "F.SilkS")
			(hide yes)
			(effects
				(font
					(size 1.27 1.27)
				)
			)
		)
		(property "Value" ""
			(at 0 0 270)
			(layer "F.Fab")
			(effects
				(font
					(size 1.27 1.27)
				)
			)
		)
		(duplicate_pad_numbers_are_jumpers no)
		(fp_poly
			(pts
				(xy 0.3048 -0.1016) (xy 0.3048 0.9906) (xy -0.3048 0.9906) (xy -0.3048 -0.1016)
			)
			(stroke
				(width 0)
				(type default)
			)
			(fill no)
			(layer "F.CrtYd")
		)
		(fp_line
			(start -0.3048 0.9906)
			(end 0.3048 0.9906)
			(stroke
				(width 0.1)
				(type default)
			)
			(layer "F.Fab")
		)
		(fp_line
			(start 0.3048 0.9906)
			(end 0.3048 -0.1016)
			(stroke
				(width 0.1)
				(type default)
			)
			(layer "F.Fab")
		)
		(fp_line
			(start -0.3048 -0.1016)
			(end -0.3048 0.9906)
			(stroke
				(width 0.1)
				(type default)
			)
			(layer "F.Fab")
		)
		(fp_line
			(start 0.3048 -0.1016)
			(end -0.3048 -0.1016)
			(stroke
				(width 0.1)
				(type default)
			)
			(layer "F.Fab")
		)
		(pad "1" smd rect
			(at 0 0 270)
			(size 0.508 0.508)
			(layers "F.Cu" "F.Mask" "F.Paste")
			(net "VR_PVCCIN_CPU0_VD12")
		)
		(pad "2" smd rect
			(at 0 0.889 270)
			(size 0.508 0.508)
			(layers "F.Cu" "F.Mask" "F.Paste")
			(net "GND")
		)
		(zone
			(layer "F.Cu")
			(hatch none 0.5)
			(connect_pads
				(clearance 0)
			)
			(min_thickness 0.25)
			(keepout
				(tracks not_allowed)
				(vias allowed)
				(pads allowed)
				(copperpour not_allowed)
				(footprints allowed)
			)
			(placement
				(enabled no)
				(sheetname "")
			)
			(fill
				(thermal_gap 0.5)
				(thermal_bridge_width 0.5)
				(island_removal_mode 0)
			)
			(polygon
				(pts
					(xy 179.746148 -73.22185) (xy 179.746148 -72.71385) (xy 180.127148 -72.71385) (xy 180.127148 -73.22185)
				)
			)
		)
		(zone
			(layer "F.Cu")
			(hatch none 0.5)
			(connect_pads
				(clearance 0)
			)
			(min_thickness 0.25)
			(keepout
				(tracks allowed)
				(vias not_allowed)
				(pads allowed)
				(copperpour not_allowed)
				(footprints allowed)
			)
			(placement
				(enabled no)
				(sheetname "")
			)
			(fill
				(thermal_gap 0.5)
				(thermal_bridge_width 0.5)
				(island_removal_mode 0)
			)
			(polygon
				(pts
					(xy 180.127148 -73.22185) (xy 180.127148 -72.71385) (xy 179.746148 -72.71385) (xy 179.746148 -73.22185)
				)
			)
		)
	)
	(footprint ""
		(layer "F.Cu")
		(at 28.82773 -85.983318 90)
		(property "Reference" "CT13"
			(at 2.28473 -5.9182 0)
			(unlocked yes)
			(layer "F.SilkS")
			(effects
				(font
					(size 0.7874 0.5842)
					(thickness 0.1524)
				)
				(justify left)
			)
		)
		(property "Value" ""
			(at 0 0 90)
			(layer "F.Fab")
			(effects
				(font
					(size 1.27 1.27)
				)
			)
		)
		(duplicate_pad_numbers_are_jumpers no)
		(fp_poly
			(pts
				(xy 0.3048 -0.1016) (xy 0.3048 0.9906) (xy -0.3048 0.9906) (xy -0.3048 -0.1016)
			)
			(stroke
				(width 0)
				(type default)
			)
			(fill no)
			(layer "F.CrtYd")
		)
		(fp_line
			(start 0.3048 -0.1016)
			(end -0.3048 -0.1016)
			(stroke
				(width 0.1)
				(type default)
			)
			(layer "F.Fab")
		)
		(fp_line
			(start -0.3048 -0.1016)
			(end -0.3048 0.9906)
			(stroke
				(width 0.1)
				(type default)
			)
			(layer "F.Fab")
		)
		(fp_line
			(start 0.3048 0.9906)
			(end 0.3048 -0.1016)
			(stroke
				(width 0.1)
				(type default)
			)
			(layer "F.Fab")
		)
		(fp_line
			(start -0.3048 0.9906)
			(end 0.3048 0.9906)
			(stroke
				(width 0.1)
				(type default)
			)
			(layer "F.Fab")
		)
		(pad "1" smd rect
			(at 0 0 90)
			(size 0.508 0.508)
			(layers "F.Cu" "F.Mask" "F.Paste")
			(net "VR_PVCCIN_CPU1_AIREF5")
		)
		(pad "2" smd rect
			(at 0 0.889 90)
			(size 0.508 0.508)
			(layers "F.Cu" "F.Mask" "F.Paste")
			(net "GND")
		)
		(zone
			(layer "F.Cu")
			(hatch none 0.5)
			(connect_pads
				(clearance 0)
			)
			(min_thickness 0.25)
			(keepout
				(tracks allowed)
				(vias not_allowed)
				(pads allowed)
				(copperpour not_allowed)
				(footprints allowed)
			)
			(placement
				(enabled no)
				(sheetname "")
			)
			(fill
				(thermal_gap 0.5)
				(thermal_bridge_width 0.5)
				(island_removal_mode 0)
			)
			(polygon
				(pts
					(xy 29.08173 -85.729318) (xy 29.08173 -86.237318) (xy 29.46273 -86.237318) (xy 29.46273 -85.729318)
				)
			)
		)
		(zone
			(layer "F.Cu")
			(hatch none 0.5)
			(connect_pads
				(clearance 0)
			)
			(min_thickness 0.25)
			(keepout
				(tracks not_allowed)
				(vias allowed)
				(pads allowed)
				(copperpour not_allowed)
				(footprints allowed)
			)
			(placement
				(enabled no)
				(sheetname "")
			)
			(fill
				(thermal_gap 0.5)
				(thermal_bridge_width 0.5)
				(island_removal_mode 0)
			)
			(polygon
				(pts
					(xy 29.46273 -85.729318) (xy 29.46273 -86.237318) (xy 29.08173 -86.237318) (xy 29.08173 -85.729318)
				)
			)
		)
	)
	(footprint ""
		(layer "F.Cu")
		(at 194.700398 -5.822442 90)
		(property "Reference" "J4G2"
			(at 6.596888 37.58311 0)
			(unlocked yes)
			(layer "F.SilkS")
			(effects
				(font
					(size 0.7874 0.5842)
					(thickness 0.1524)
				)
				(justify left)
			)
		)
		(property "Value" ""
			(at 0 0 90)
			(layer "F.Fab")
			(effects
				(font
					(size 1.27 1.27)
				)
			)
		)
		(duplicate_pad_numbers_are_jumpers no)
		(fp_line
			(start 5.5499 -7.675118)
			(end 5.5499 -1.480058)
			(stroke
				(width 0.1524)
				(type default)
			)
			(layer "F.SilkS")
		)
		(fp_line
			(start -0.94996 -7.675118)
			(end 5.5499 -7.675118)
			(stroke
				(width 0.1524)
				(type default)
			)
			(layer "F.SilkS")
		)
		(fp_line
			(start -0.94996 -1.480058)
			(end -0.94996 -7.675118)
			(stroke
				(width 0.1524)
				(type default)
			)
			(layer "F.SilkS")
		)
		(fp_line
			(start 5.5499 128.130046)
			(end 5.5499 134.325106)
			(stroke
				(width 0.1524)
				(type default)
			)
			(layer "F.SilkS")
		)
		(fp_line
			(start 5.5499 134.325106)
			(end -0.94996 134.325106)
			(stroke
				(width 0.1524)
				(type default)
			)
			(layer "F.SilkS")
		)
		(fp_line
			(start -0.94996 134.325106)
			(end -0.94996 128.130046)
			(stroke
				(width 0.1524)
				(type default)
			)
			(layer "F.SilkS")
		)
		(fp_poly
			(pts
				(xy -3.036824 -4.192778) (xy -3.036824 -3.176778) (xy -1.766824 -3.684778)
			)
			(stroke
				(width 0)
				(type default)
			)
			(fill yes)
			(layer "F.SilkS")
		)
		(fp_poly
			(pts
				(xy -0.94996 -7.675118) (xy -0.94996 134.325106) (xy 5.5499 134.325106) (xy 5.5499 -7.675118)
			)
			(stroke
				(width 0)
				(type default)
			)
			(fill no)
			(layer "F.CrtYd")
		)
		(fp_line
			(start 5.5499 -7.675118)
			(end 5.5499 134.325106)
			(stroke
				(width 0.1)
				(type default)
			)
			(layer "F.Fab")
		)
		(fp_line
			(start -0.94996 -7.675118)
			(end 5.5499 -7.675118)
			(stroke
				(width 0.1)
				(type default)
			)
			(layer "F.Fab")
		)
		(fp_line
			(start 5.5499 134.325106)
			(end -0.94996 134.325106)
			(stroke
				(width 0.1)
				(type default)
			)
			(layer "F.Fab")
		)
		(fp_line
			(start -0.94996 134.325106)
			(end -0.94996 -7.675118)
			(stroke
				(width 0.1)
				(type default)
			)
			(layer "F.Fab")
		)
		(fp_poly
			(pts
				(xy -2.984246 -0.461264) (xy -2.984246 0.554736) (xy -1.714246 0.046736)
			)
			(stroke
				(width 0)
				(type default)
			)
			(fill yes)
			(layer "F.Fab")
		)
		(fp_text user "145"
			(at -1.948942 -8.483092 90)
			(unlocked yes)
			(layer "F.SilkS")
			(effects
				(font
					(size 0.7874 0.5842)
					(thickness 0.1524)
				)
				(justify left)
			)
		)
		(fp_text user "221"
			(at 5.834888 65.14211 0)
			(unlocked yes)
			(layer "F.SilkS")
			(effects
				(font
					(size 0.7874 0.5842)
					(thickness 0.1524)
				)
				(justify left)
			)
		)
		(fp_text user "77"
			(at -1.277112 65.14211 0)
			(unlocked yes)
			(layer "F.SilkS")
			(effects
				(font
					(size 0.7874 0.5842)
					(thickness 0.1524)
				)
				(justify left)
			)
		)
		(fp_text user "222"
			(at 6.088888 69.71411 0)
			(unlocked yes)
			(layer "F.SilkS")
			(effects
				(font
					(size 0.7874 0.5842)
					(thickness 0.1524)
				)
				(justify left)
			)
		)
		(fp_text user "78"
			(at -1.658112 69.71411 0)
			(unlocked yes)
			(layer "F.SilkS")
			(effects
				(font
					(size 0.7874 0.5842)
					(thickness 0.1524)
				)
				(justify left)
			)
		)
		(fp_text user "144"
			(at -1.658112 127.62611 0)
			(unlocked yes)
			(layer "F.SilkS")
			(effects
				(font
					(size 0.7874 0.5842)
					(thickness 0.1524)
				)
				(justify left)
			)
		)
		(fp_text user "288"
			(at 6.215888 128.38811 0)
			(unlocked yes)
			(layer "F.SilkS")
			(effects
				(font
					(size 0.7874 0.5842)
					(thickness 0.1524)
				)
				(justify left)
			)
		)
		(fp_text user "145"
			(at 3.702558 -0.74422 90)
			(unlocked yes)
			(layer "F.Fab")
			(effects
				(font
					(size 0.7874 0.5842)
					(thickness 0.1524)
				)
				(justify left)
			)
		)
		(fp_text user "221"
			(at 3.702558 65.93078 90)
			(unlocked yes)
			(layer "F.Fab")
			(effects
				(font
					(size 0.7874 0.5842)
					(thickness 0.1524)
				)
				(justify left)
			)
		)
		(fp_text user "77"
			(at -0.742442 65.93078 90)
			(unlocked yes)
			(layer "F.Fab")
			(effects
				(font
					(size 0.7874 0.5842)
					(thickness 0.1524)
				)
				(justify left)
			)
		)
		(fp_text user "222"
			(at 4.058158 69.20738 90)
			(unlocked yes)
			(layer "F.Fab")
			(effects
				(font
					(size 0.7874 0.5842)
					(thickness 0.1524)
				)
				(justify left)
			)
		)
		(fp_text user "78"
			(at -0.742442 69.74078 90)
			(unlocked yes)
			(layer "F.Fab")
			(effects
				(font
					(size 0.7874 0.5842)
					(thickness 0.1524)
				)
				(justify left)
			)
		)
		(fp_text user "288"
			(at 3.067558 128.16078 90)
			(unlocked yes)
			(layer "F.Fab")
			(effects
				(font
					(size 0.7874 0.5842)
					(thickness 0.1524)
				)
				(justify left)
			)
		)
		(fp_text user "144"
			(at -0.742442 128.16078 90)
			(unlocked yes)
			(layer "F.Fab")
			(effects
				(font
					(size 0.7874 0.5842)
					(thickness 0.1524)
				)
				(justify left)
			)
		)
		(pad "" thru_hole circle
			(at 2.29997 -5.649976 90)
			(size 2.8194 2.8194)
			(drill 2.4384)
			(layers "*.Cu" "*.Mask")
			(remove_unused_layers no)
			(clearance 0.127)
			(thermal_gap 0.127)
		)
		(pad "" thru_hole oval
			(at 2.29997 68.90004 90)
			(size 2.8194 1.5748)
			(drill oval 2.4384 1.1938)
			(layers "*.Cu" "*.Mask")
			(remove_unused_layers no)
			(clearance 0.127)
			(thermal_gap 0.127)
		)
		(pad "" thru_hole circle
			(at 2.29997 132.299964 90)
			(size 2.8194 2.8194)
			(drill 2.4384)
			(layers "*.Cu" "*.Mask")
			(remove_unused_layers no)
			(clearance 0.127)
			(thermal_gap 0.127)
		)
		(pad "1" smd rect
			(at 0 0 90)
			(size 1.8034 0.508)
			(layers "F.Cu" "F.Mask" "F.Paste")
			(net "P12V_NVDIMM_ABC")
		)
		(pad "2" smd rect
			(at 0 0.849884 90)
			(size 1.8034 0.508)
			(layers "F.Cu" "F.Mask" "F.Paste")
			(net "GND")
		)
		(pad "3" smd rect
			(at 0 1.700022 90)
			(size 1.8034 0.508)
			(layers "F.Cu" "F.Mask" "F.Paste")
			(net "M_B_DQ<5>")
		)
		(pad "4" smd rect
			(at 0 2.549906 90)
			(size 1.8034 0.508)
			(layers "F.Cu" "F.Mask" "F.Paste")
			(net "GND")
		)
		(pad "5" smd rect
			(at 0 3.400044 90)
			(size 1.8034 0.508)
			(layers "F.Cu" "F.Mask" "F.Paste")
			(net "M_B_DQ<1>")
		)
		(pad "6" smd rect
			(at 0 4.249928 90)
			(size 1.8034 0.508)
			(layers "F.Cu" "F.Mask" "F.Paste")
			(net "GND")
		)
		(pad "7" smd rect
			(at 0 5.100066 90)
			(size 1.8034 0.508)
			(layers "F.Cu" "F.Mask" "F.Paste")
			(net "M_B_DQS_DP<9>")
		)
		(pad "8" smd rect
			(at 0 5.94995 90)
			(size 1.8034 0.508)
			(layers "F.Cu" "F.Mask" "F.Paste")
			(net "M_B_DQS_DN<9>")
		)
		(pad "9" smd rect
			(at 0 6.800088 90)
			(size 1.8034 0.508)
			(layers "F.Cu" "F.Mask" "F.Paste")
			(net "GND")
		)
		(pad "10" smd rect
			(at 0 7.649972 90)
			(size 1.8034 0.508)
			(layers "F.Cu" "F.Mask" "F.Paste")
			(net "M_B_DQ<7>")
		)
		(pad "11" smd rect
			(at 0 8.50011 90)
			(size 1.8034 0.508)
			(layers "F.Cu" "F.Mask" "F.Paste")
			(net "GND")
		)
		(pad "12" smd rect
			(at 0 9.349994 90)
			(size 1.8034 0.508)
			(layers "F.Cu" "F.Mask" "F.Paste")
			(net "M_B_DQ<3>")
		)
		(pad "13" smd rect
			(at 0 10.199878 90)
			(size 1.8034 0.508)
			(layers "F.Cu" "F.Mask" "F.Paste")
			(net "GND")
		)
		(pad "14" smd rect
			(at 0 11.050016 90)
			(size 1.8034 0.508)
			(layers "F.Cu" "F.Mask" "F.Paste")
			(net "M_B_DQ<13>")
		)
		(pad "15" smd rect
			(at 0 11.8999 90)
			(size 1.8034 0.508)
			(layers "F.Cu" "F.Mask" "F.Paste")
			(net "GND")
		)
		(pad "16" smd rect
			(at 0 12.750038 90)
			(size 1.8034 0.508)
			(layers "F.Cu" "F.Mask" "F.Paste")
			(net "M_B_DQ<9>")
		)
		(pad "17" smd rect
			(at 0 13.599922 90)
			(size 1.8034 0.508)
			(layers "F.Cu" "F.Mask" "F.Paste")
			(net "GND")
		)
		(pad "18" smd rect
			(at 0 14.45006 90)
			(size 1.8034 0.508)
			(layers "F.Cu" "F.Mask" "F.Paste")
			(net "M_B_DQS_DP<10>")
		)
		(pad "19" smd rect
			(at 0 15.299944 90)
			(size 1.8034 0.508)
			(layers "F.Cu" "F.Mask" "F.Paste")
			(net "M_B_DQS_DN<10>")
		)
		(pad "20" smd rect
			(at 0 16.150082 90)
			(size 1.8034 0.508)
			(layers "F.Cu" "F.Mask" "F.Paste")
			(net "GND")
		)
		(pad "21" smd rect
			(at 0 16.999966 90)
			(size 1.8034 0.508)
			(layers "F.Cu" "F.Mask" "F.Paste")
			(net "M_B_DQ<15>")
		)
		(pad "22" smd rect
			(at 0 17.850104 90)
			(size 1.8034 0.508)
			(layers "F.Cu" "F.Mask" "F.Paste")
			(net "GND")
		)
		(pad "23" smd rect
			(at 0 18.699988 90)
			(size 1.8034 0.508)
			(layers "F.Cu" "F.Mask" "F.Paste")
			(net "M_B_DQ<11>")
		)
		(pad "24" smd rect
			(at 0 19.550126 90)
			(size 1.8034 0.508)
			(layers "F.Cu" "F.Mask" "F.Paste")
			(net "GND")
		)
		(pad "25" smd rect
			(at 0 20.40001 90)
			(size 1.8034 0.508)
			(layers "F.Cu" "F.Mask" "F.Paste")
			(net "M_B_DQ<21>")
		)
		(pad "26" smd rect
			(at 0 21.249894 90)
			(size 1.8034 0.508)
			(layers "F.Cu" "F.Mask" "F.Paste")
			(net "GND")
		)
		(pad "27" smd rect
			(at 0 22.100032 90)
			(size 1.8034 0.508)
			(layers "F.Cu" "F.Mask" "F.Paste")
			(net "M_B_DQ<17>")
		)
		(pad "28" smd rect
			(at 0 22.949916 90)
			(size 1.8034 0.508)
			(layers "F.Cu" "F.Mask" "F.Paste")
			(net "GND")
		)
		(pad "29" smd rect
			(at 0 23.800054 90)
			(size 1.8034 0.508)
			(layers "F.Cu" "F.Mask" "F.Paste")
			(net "M_B_DQS_DP<11>")
		)
		(pad "30" smd rect
			(at 0 24.649938 90)
			(size 1.8034 0.508)
			(layers "F.Cu" "F.Mask" "F.Paste")
			(net "M_B_DQS_DN<11>")
		)
		(pad "31" smd rect
			(at 0 25.500076 90)
			(size 1.8034 0.508)
			(layers "F.Cu" "F.Mask" "F.Paste")
			(net "GND")
		)
		(pad "32" smd rect
			(at 0 26.34996 90)
			(size 1.8034 0.508)
			(layers "F.Cu" "F.Mask" "F.Paste")
			(net "M_B_DQ<23>")
		)
		(pad "33" smd rect
			(at 0 27.200098 90)
			(size 1.8034 0.508)
			(layers "F.Cu" "F.Mask" "F.Paste")
			(net "GND")
		)
		(pad "34" smd rect
			(at 0 28.049982 90)
			(size 1.8034 0.508)
			(layers "F.Cu" "F.Mask" "F.Paste")
			(net "M_B_DQ<19>")
		)
		(pad "35" smd rect
			(at 0 28.90012 90)
			(size 1.8034 0.508)
			(layers "F.Cu" "F.Mask" "F.Paste")
			(net "GND")
		)
		(pad "36" smd rect
			(at 0 29.750004 90)
			(size 1.8034 0.508)
			(layers "F.Cu" "F.Mask" "F.Paste")
			(net "M_B_DQ<29>")
		)
		(pad "37" smd rect
			(at 0 30.599888 90)
			(size 1.8034 0.508)
			(layers "F.Cu" "F.Mask" "F.Paste")
			(net "GND")
		)
		(pad "38" smd rect
			(at 0 31.450026 90)
			(size 1.8034 0.508)
			(layers "F.Cu" "F.Mask" "F.Paste")
			(net "M_B_DQ<25>")
		)
		(pad "39" smd rect
			(at 0 32.29991 90)
			(size 1.8034 0.508)
			(layers "F.Cu" "F.Mask" "F.Paste")
			(net "GND")
		)
		(pad "40" smd rect
			(at 0 33.150048 90)
			(size 1.8034 0.508)
			(layers "F.Cu" "F.Mask" "F.Paste")
			(net "M_B_DQS_DP<12>")
		)
		(pad "41" smd rect
			(at 0 33.999932 90)
			(size 1.8034 0.508)
			(layers "F.Cu" "F.Mask" "F.Paste")
			(net "M_B_DQS_DN<12>")
		)
		(pad "42" smd rect
			(at 0 34.85007 90)
			(size 1.8034 0.508)
			(layers "F.Cu" "F.Mask" "F.Paste")
			(net "GND")
		)
		(pad "43" smd rect
			(at 0 35.699954 90)
			(size 1.8034 0.508)
			(layers "F.Cu" "F.Mask" "F.Paste")
			(net "M_B_DQ<31>")
		)
		(pad "44" smd rect
			(at 0 36.550092 90)
			(size 1.8034 0.508)
			(layers "F.Cu" "F.Mask" "F.Paste")
			(net "GND")
		)
		(pad "45" smd rect
			(at 0 37.399976 90)
			(size 1.8034 0.508)
			(layers "F.Cu" "F.Mask" "F.Paste")
			(net "M_B_DQ<27>")
		)
		(pad "46" smd rect
			(at 0 38.250114 90)
			(size 1.8034 0.508)
			(layers "F.Cu" "F.Mask" "F.Paste")
			(net "GND")
		)
		(pad "47" smd rect
			(at 0 39.099998 90)
			(size 1.8034 0.508)
			(layers "F.Cu" "F.Mask" "F.Paste")
			(net "M_B_ECC<5>")
		)
		(pad "48" smd rect
			(at 0 39.949882 90)
			(size 1.8034 0.508)
			(layers "F.Cu" "F.Mask" "F.Paste")
			(net "GND")
		)
		(pad "49" smd rect
			(at 0 40.80002 90)
			(size 1.8034 0.508)
			(layers "F.Cu" "F.Mask" "F.Paste")
			(net "M_B_ECC<1>")
		)
		(pad "50" smd rect
			(at 0 41.649904 90)
			(size 1.8034 0.508)
			(layers "F.Cu" "F.Mask" "F.Paste")
			(net "GND")
		)
		(pad "51" smd rect
			(at 0 42.500042 90)
			(size 1.8034 0.508)
			(layers "F.Cu" "F.Mask" "F.Paste")
			(net "M_B_DQS_DP<17>")
		)
		(pad "52" smd rect
			(at 0 43.349926 90)
			(size 1.8034 0.508)
			(layers "F.Cu" "F.Mask" "F.Paste")
			(net "M_B_DQS_DN<17>")
		)
		(pad "53" smd rect
			(at 0 44.200064 90)
			(size 1.8034 0.508)
			(layers "F.Cu" "F.Mask" "F.Paste")
			(net "GND")
		)
		(pad "54" smd rect
			(at 0 45.049948 90)
			(size 1.8034 0.508)
			(layers "F.Cu" "F.Mask" "F.Paste")
			(net "M_B_ECC<7>")
		)
		(pad "55" smd rect
			(at 0 45.900086 90)
			(size 1.8034 0.508)
			(layers "F.Cu" "F.Mask" "F.Paste")
			(net "GND")
		)
		(pad "56" smd rect
			(at 0 46.74997 90)
			(size 1.8034 0.508)
			(layers "F.Cu" "F.Mask" "F.Paste")
			(net "M_B_ECC<3>")
		)
		(pad "57" smd rect
			(at 0 47.600108 90)
			(size 1.8034 0.508)
			(layers "F.Cu" "F.Mask" "F.Paste")
			(net "GND")
		)
		(pad "58" smd rect
			(at 0 48.449992 90)
			(size 1.8034 0.508)
			(layers "F.Cu" "F.Mask" "F.Paste")
			(net "M_ABC_RST_N")
		)
		(pad "59" smd rect
			(at 0 49.299876 90)
			(size 1.8034 0.508)
			(layers "F.Cu" "F.Mask" "F.Paste")
			(net "PVDDQ_ABC")
		)
		(pad "60" smd rect
			(at 0 50.150014 90)
			(size 1.8034 0.508)
			(layers "F.Cu" "F.Mask" "F.Paste")
			(net "M_B_CKE<0>")
		)
		(pad "61" smd rect
			(at 0 50.999898 90)
			(size 1.8034 0.508)
			(layers "F.Cu" "F.Mask" "F.Paste")
			(net "PVDDQ_ABC")
		)
		(pad "62" smd rect
			(at 0 51.850036 90)
			(size 1.8034 0.508)
			(layers "F.Cu" "F.Mask" "F.Paste")
			(net "M_B_ACT_N")
		)
		(pad "63" smd rect
			(at 0 52.69992 90)
			(size 1.8034 0.508)
			(layers "F.Cu" "F.Mask" "F.Paste")
			(net "M_B_BG<0>")
		)
		(pad "64" smd rect
			(at 0 53.550058 90)
			(size 1.8034 0.508)
			(layers "F.Cu" "F.Mask" "F.Paste")
			(net "PVDDQ_ABC")
		)
		(pad "65" smd rect
			(at 0 54.399942 90)
			(size 1.8034 0.508)
			(layers "F.Cu" "F.Mask" "F.Paste")
			(net "M_B_MA<12>")
		)
		(pad "66" smd rect
			(at 0 55.25008 90)
			(size 1.8034 0.508)
			(layers "F.Cu" "F.Mask" "F.Paste")
			(net "M_B_MA<9>")
		)
		(pad "67" smd rect
			(at 0 56.099964 90)
			(size 1.8034 0.508)
			(layers "F.Cu" "F.Mask" "F.Paste")
			(net "PVDDQ_ABC")
		)
		(pad "68" smd rect
			(at 0 56.950102 90)
			(size 1.8034 0.508)
			(layers "F.Cu" "F.Mask" "F.Paste")
			(net "M_B_MA<8>")
		)
		(pad "69" smd rect
			(at 0 57.799986 90)
			(size 1.8034 0.508)
			(layers "F.Cu" "F.Mask" "F.Paste")
			(net "M_B_MA<6>")
		)
		(pad "70" smd rect
			(at 0 58.650124 90)
			(size 1.8034 0.508)
			(layers "F.Cu" "F.Mask" "F.Paste")
			(net "PVDDQ_ABC")
		)
		(pad "71" smd rect
			(at 0 59.500008 90)
			(size 1.8034 0.508)
			(layers "F.Cu" "F.Mask" "F.Paste")
			(net "M_B_MA<3>")
		)
		(pad "72" smd rect
			(at 0 60.349892 90)
			(size 1.8034 0.508)
			(layers "F.Cu" "F.Mask" "F.Paste")
			(net "M_B_MA<1>")
		)
		(pad "73" smd rect
			(at 0 61.20003 90)
			(size 1.8034 0.508)
			(layers "F.Cu" "F.Mask" "F.Paste")
			(net "PVDDQ_ABC")
		)
		(pad "74" smd rect
			(at 0 62.049914 90)
			(size 1.8034 0.508)
			(layers "F.Cu" "F.Mask" "F.Paste")
			(net "M_B_CLK_DP<0>")
		)
		(pad "75" smd rect
			(at 0 62.900052 90)
			(size 1.8034 0.508)
			(layers "F.Cu" "F.Mask" "F.Paste")
			(net "M_B_CLK_DN<0>")
		)
		(pad "76" smd rect
			(at 0 63.749936 90)
			(size 1.8034 0.508)
			(layers "F.Cu" "F.Mask" "F.Paste")
			(net "PVDDQ_ABC")
		)
		(pad "77" smd rect
			(at 0 64.600074 90)
			(size 1.8034 0.508)
			(layers "F.Cu" "F.Mask" "F.Paste")
			(net "PVTT_ABC")
		)
		(pad "78" smd rect
			(at 0 70.550024 90)
			(size 1.8034 0.508)
			(layers "F.Cu" "F.Mask" "F.Paste")
			(net "FM_DIMM_EVENT_COD_N")
		)
		(pad "79" smd rect
			(at 0 71.399908 90)
			(size 1.8034 0.508)
			(layers "F.Cu" "F.Mask" "F.Paste")
			(net "M_B_MA<0>")
		)
		(pad "80" smd rect
			(at 0 72.250046 90)
			(size 1.8034 0.508)
			(layers "F.Cu" "F.Mask" "F.Paste")
			(net "PVDDQ_ABC")
		)
		(pad "81" smd rect
			(at 0 73.09993 90)
			(size 1.8034 0.508)
			(layers "F.Cu" "F.Mask" "F.Paste")
			(net "M_B_BA<0>")
		)
		(pad "82" smd rect
			(at 0 73.950068 90)
			(size 1.8034 0.508)
			(layers "F.Cu" "F.Mask" "F.Paste")
			(net "M_B_MA<16>")
		)
		(pad "83" smd rect
			(at 0 74.799952 90)
			(size 1.8034 0.508)
			(layers "F.Cu" "F.Mask" "F.Paste")
			(net "PVDDQ_ABC")
		)
		(pad "84" smd rect
			(at 0 75.65009 90)
			(size 1.8034 0.508)
			(layers "F.Cu" "F.Mask" "F.Paste")
			(net "M_B_CS_N<0>")
		)
		(pad "85" smd rect
			(at 0 76.499974 90)
			(size 1.8034 0.508)
			(layers "F.Cu" "F.Mask" "F.Paste")
			(net "PVDDQ_ABC")
		)
		(pad "86" smd rect
			(at 0 77.350112 90)
			(size 1.8034 0.508)
			(layers "F.Cu" "F.Mask" "F.Paste")
			(net "M_B_MA<15>")
		)
		(pad "87" smd rect
			(at 0 78.199996 90)
			(size 1.8034 0.508)
			(layers "F.Cu" "F.Mask" "F.Paste")
			(net "M_B_ODT<0>")
		)
		(pad "88" smd rect
			(at 0 79.04988 90)
			(size 1.8034 0.508)
			(layers "F.Cu" "F.Mask" "F.Paste")
			(net "PVDDQ_ABC")
		)
		(pad "89" smd rect
			(at 0 79.900018 90)
			(size 1.8034 0.508)
			(layers "F.Cu" "F.Mask" "F.Paste")
			(net "M_B_CS_N<1>")
		)
		(pad "90" smd rect
			(at 0 80.749902 90)
			(size 1.8034 0.508)
			(layers "F.Cu" "F.Mask" "F.Paste")
			(net "PVDDQ_ABC")
		)
		(pad "91" smd rect
			(at 0 81.60004 90)
			(size 1.8034 0.508)
			(layers "F.Cu" "F.Mask" "F.Paste")
			(net "M_B_ODT<1>")
		)
		(pad "92" smd rect
			(at 0 82.449924 90)
			(size 1.8034 0.508)
			(layers "F.Cu" "F.Mask" "F.Paste")
			(net "PVDDQ_ABC")
		)
		(pad "93" smd rect
			(at 0 83.300062 90)
			(size 1.8034 0.508)
			(layers "F.Cu" "F.Mask" "F.Paste")
			(net "M_B_CS_N<2>")
		)
		(pad "94" smd rect
			(at 0 84.149946 90)
			(size 1.8034 0.508)
			(layers "F.Cu" "F.Mask" "F.Paste")
			(net "GND")
		)
		(pad "95" smd rect
			(at 0 85.000084 90)
			(size 1.8034 0.508)
			(layers "F.Cu" "F.Mask" "F.Paste")
			(net "M_B_DQ<37>")
		)
		(pad "96" smd rect
			(at 0 85.849968 90)
			(size 1.8034 0.508)
			(layers "F.Cu" "F.Mask" "F.Paste")
			(net "GND")
		)
		(pad "97" smd rect
			(at 0 86.700106 90)
			(size 1.8034 0.508)
			(layers "F.Cu" "F.Mask" "F.Paste")
			(net "M_B_DQ<33>")
		)
		(pad "98" smd rect
			(at 0 87.54999 90)
			(size 1.8034 0.508)
			(layers "F.Cu" "F.Mask" "F.Paste")
			(net "GND")
		)
		(pad "99" smd rect
			(at 0 88.399874 90)
			(size 1.8034 0.508)
			(layers "F.Cu" "F.Mask" "F.Paste")
			(net "M_B_DQS_DP<13>")
		)
		(pad "100" smd rect
			(at 0 89.250012 90)
			(size 1.8034 0.508)
			(layers "F.Cu" "F.Mask" "F.Paste")
			(net "M_B_DQS_DN<13>")
		)
		(pad "101" smd rect
			(at 0 90.099896 90)
			(size 1.8034 0.508)
			(layers "F.Cu" "F.Mask" "F.Paste")
			(net "GND")
		)
		(pad "102" smd rect
			(at 0 90.950034 90)
			(size 1.8034 0.508)
			(layers "F.Cu" "F.Mask" "F.Paste")
			(net "M_B_DQ<39>")
		)
		(pad "103" smd rect
			(at 0 91.799918 90)
			(size 1.8034 0.508)
			(layers "F.Cu" "F.Mask" "F.Paste")
			(net "GND")
		)
		(pad "104" smd rect
			(at 0 92.650056 90)
			(size 1.8034 0.508)
			(layers "F.Cu" "F.Mask" "F.Paste")
			(net "M_B_DQ<35>")
		)
		(pad "105" smd rect
			(at 0 93.49994 90)
			(size 1.8034 0.508)
			(layers "F.Cu" "F.Mask" "F.Paste")
			(net "GND")
		)
		(pad "106" smd rect
			(at 0 94.350078 90)
			(size 1.8034 0.508)
			(layers "F.Cu" "F.Mask" "F.Paste")
			(net "M_B_DQ<45>")
		)
		(pad "107" smd rect
			(at 0 95.199962 90)
			(size 1.8034 0.508)
			(layers "F.Cu" "F.Mask" "F.Paste")
			(net "GND")
		)
		(pad "108" smd rect
			(at 0 96.0501 90)
			(size 1.8034 0.508)
			(layers "F.Cu" "F.Mask" "F.Paste")
			(net "M_B_DQ<41>")
		)
		(pad "109" smd rect
			(at 0 96.899984 90)
			(size 1.8034 0.508)
			(layers "F.Cu" "F.Mask" "F.Paste")
			(net "GND")
		)
		(pad "110" smd rect
			(at 0 97.750122 90)
			(size 1.8034 0.508)
			(layers "F.Cu" "F.Mask" "F.Paste")
			(net "M_B_DQS_DP<14>")
		)
		(pad "111" smd rect
			(at 0 98.600006 90)
			(size 1.8034 0.508)
			(layers "F.Cu" "F.Mask" "F.Paste")
			(net "M_B_DQS_DN<14>")
		)
		(pad "112" smd rect
			(at 0 99.44989 90)
			(size 1.8034 0.508)
			(layers "F.Cu" "F.Mask" "F.Paste")
			(net "GND")
		)
		(pad "113" smd rect
			(at 0 100.300028 90)
			(size 1.8034 0.508)
			(layers "F.Cu" "F.Mask" "F.Paste")
			(net "M_B_DQ<47>")
		)
		(pad "114" smd rect
			(at 0 101.149912 90)
			(size 1.8034 0.508)
			(layers "F.Cu" "F.Mask" "F.Paste")
			(net "GND")
		)
		(pad "115" smd rect
			(at 0 102.00005 90)
			(size 1.8034 0.508)
			(layers "F.Cu" "F.Mask" "F.Paste")
			(net "M_B_DQ<43>")
		)
		(pad "116" smd rect
			(at 0 102.849934 90)
			(size 1.8034 0.508)
			(layers "F.Cu" "F.Mask" "F.Paste")
			(net "GND")
		)
		(pad "117" smd rect
			(at 0 103.700072 90)
			(size 1.8034 0.508)
			(layers "F.Cu" "F.Mask" "F.Paste")
			(net "M_B_DQ<53>")
		)
		(pad "118" smd rect
			(at 0 104.549956 90)
			(size 1.8034 0.508)
			(layers "F.Cu" "F.Mask" "F.Paste")
			(net "GND")
		)
		(pad "119" smd rect
			(at 0 105.400094 90)
			(size 1.8034 0.508)
			(layers "F.Cu" "F.Mask" "F.Paste")
			(net "M_B_DQ<49>")
		)
		(pad "120" smd rect
			(at 0 106.249978 90)
			(size 1.8034 0.508)
			(layers "F.Cu" "F.Mask" "F.Paste")
			(net "GND")
		)
		(pad "121" smd rect
			(at 0 107.100116 90)
			(size 1.8034 0.508)
			(layers "F.Cu" "F.Mask" "F.Paste")
			(net "M_B_DQS_DP<15>")
		)
		(pad "122" smd rect
			(at 0 107.95 90)
			(size 1.8034 0.508)
			(layers "F.Cu" "F.Mask" "F.Paste")
			(net "M_B_DQS_DN<15>")
		)
		(pad "123" smd rect
			(at 0 108.799884 90)
			(size 1.8034 0.508)
			(layers "F.Cu" "F.Mask" "F.Paste")
			(net "GND")
		)
		(pad "124" smd rect
			(at 0 109.650022 90)
			(size 1.8034 0.508)
			(layers "F.Cu" "F.Mask" "F.Paste")
			(net "M_B_DQ<55>")
		)
		(pad "125" smd rect
			(at 0 110.499906 90)
			(size 1.8034 0.508)
			(layers "F.Cu" "F.Mask" "F.Paste")
			(net "GND")
		)
		(pad "126" smd rect
			(at 0 111.350044 90)
			(size 1.8034 0.508)
			(layers "F.Cu" "F.Mask" "F.Paste")
			(net "M_B_DQ<51>")
		)
		(pad "127" smd rect
			(at 0 112.199928 90)
			(size 1.8034 0.508)
			(layers "F.Cu" "F.Mask" "F.Paste")
			(net "GND")
		)
		(pad "128" smd rect
			(at 0 113.050066 90)
			(size 1.8034 0.508)
			(layers "F.Cu" "F.Mask" "F.Paste")
			(net "M_B_DQ<61>")
		)
		(pad "129" smd rect
			(at 0 113.89995 90)
			(size 1.8034 0.508)
			(layers "F.Cu" "F.Mask" "F.Paste")
			(net "GND")
		)
		(pad "130" smd rect
			(at 0 114.750088 90)
			(size 1.8034 0.508)
			(layers "F.Cu" "F.Mask" "F.Paste")
			(net "M_B_DQ<57>")
		)
		(pad "131" smd rect
			(at 0 115.599972 90)
			(size 1.8034 0.508)
			(layers "F.Cu" "F.Mask" "F.Paste")
			(net "GND")
		)
		(pad "132" smd rect
			(at 0 116.45011 90)
			(size 1.8034 0.508)
			(layers "F.Cu" "F.Mask" "F.Paste")
			(net "M_B_DQS_DP<16>")
		)
		(pad "133" smd rect
			(at 0 117.299994 90)
			(size 1.8034 0.508)
			(layers "F.Cu" "F.Mask" "F.Paste")
			(net "M_B_DQS_DN<16>")
		)
		(pad "134" smd rect
			(at 0 118.149878 90)
			(size 1.8034 0.508)
			(layers "F.Cu" "F.Mask" "F.Paste")
			(net "GND")
		)
		(pad "135" smd rect
			(at 0 119.000016 90)
			(size 1.8034 0.508)
			(layers "F.Cu" "F.Mask" "F.Paste")
			(net "M_B_DQ<63>")
		)
		(pad "136" smd rect
			(at 0 119.8499 90)
			(size 1.8034 0.508)
			(layers "F.Cu" "F.Mask" "F.Paste")
			(net "GND")
		)
		(pad "137" smd rect
			(at 0 120.700038 90)
			(size 1.8034 0.508)
			(layers "F.Cu" "F.Mask" "F.Paste")
			(net "M_B_DQ<59>")
		)
		(pad "138" smd rect
			(at 0 121.549922 90)
			(size 1.8034 0.508)
			(layers "F.Cu" "F.Mask" "F.Paste")
			(net "GND")
		)
		(pad "139" smd rect
			(at 0 122.40006 90)
			(size 1.8034 0.508)
			(layers "F.Cu" "F.Mask" "F.Paste")
			(net "GND")
		)
		(pad "140" smd rect
			(at 0 123.249944 90)
			(size 1.8034 0.508)
			(layers "F.Cu" "F.Mask" "F.Paste")
			(net "PVPP_ABC")
		)
		(pad "141" smd rect
			(at 0 124.100082 90)
			(size 1.8034 0.508)
			(layers "F.Cu" "F.Mask" "F.Paste")
			(net "SMB_DDR_ABC_VPP_SCL")
		)
		(pad "142" smd rect
			(at 0 124.949966 90)
			(size 1.8034 0.508)
			(layers "F.Cu" "F.Mask" "F.Paste")
			(net "PVPP_ABC")
		)
		(pad "143" smd rect
			(at 0 125.800104 90)
			(size 1.8034 0.508)
			(layers "F.Cu" "F.Mask" "F.Paste")
			(net "PVPP_ABC")
		)
		(pad "144" smd rect
			(at 0 126.649988 90)
			(size 1.8034 0.508)
			(layers "F.Cu" "F.Mask" "F.Paste")
			(net "TP_CH_B_DIMM_B0_RFU_2")
		)
		(pad "145" smd rect
			(at 4.59994 0 90)
			(size 1.8034 0.508)
			(layers "F.Cu" "F.Mask" "F.Paste")
			(net "P12V_NVDIMM_ABC")
		)
		(pad "146" smd rect
			(at 4.59994 0.849884 90)
			(size 1.8034 0.508)
			(layers "F.Cu" "F.Mask" "F.Paste")
			(net "M_B_VREF")
		)
		(pad "147" smd rect
			(at 4.59994 1.700022 90)
			(size 1.8034 0.508)
			(layers "F.Cu" "F.Mask" "F.Paste")
			(net "GND")
		)
		(pad "148" smd rect
			(at 4.59994 2.549906 90)
			(size 1.8034 0.508)
			(layers "F.Cu" "F.Mask" "F.Paste")
			(net "M_B_DQ<4>")
		)
		(pad "149" smd rect
			(at 4.59994 3.400044 90)
			(size 1.8034 0.508)
			(layers "F.Cu" "F.Mask" "F.Paste")
			(net "GND")
		)
		(pad "150" smd rect
			(at 4.59994 4.249928 90)
			(size 1.8034 0.508)
			(layers "F.Cu" "F.Mask" "F.Paste")
			(net "M_B_DQ<0>")
		)
		(pad "151" smd rect
			(at 4.59994 5.100066 90)
			(size 1.8034 0.508)
			(layers "F.Cu" "F.Mask" "F.Paste")
			(net "GND")
		)
		(pad "152" smd rect
			(at 4.59994 5.94995 90)
			(size 1.8034 0.508)
			(layers "F.Cu" "F.Mask" "F.Paste")
			(net "M_B_DQS_DN<0>")
		)
		(pad "153" smd rect
			(at 4.59994 6.800088 90)
			(size 1.8034 0.508)
			(layers "F.Cu" "F.Mask" "F.Paste")
			(net "M_B_DQS_DP<0>")
		)
		(pad "154" smd rect
			(at 4.59994 7.649972 90)
			(size 1.8034 0.508)
			(layers "F.Cu" "F.Mask" "F.Paste")
			(net "GND")
		)
		(pad "155" smd rect
			(at 4.59994 8.50011 90)
			(size 1.8034 0.508)
			(layers "F.Cu" "F.Mask" "F.Paste")
			(net "M_B_DQ<6>")
		)
		(pad "156" smd rect
			(at 4.59994 9.349994 90)
			(size 1.8034 0.508)
			(layers "F.Cu" "F.Mask" "F.Paste")
			(net "GND")
		)
		(pad "157" smd rect
			(at 4.59994 10.199878 90)
			(size 1.8034 0.508)
			(layers "F.Cu" "F.Mask" "F.Paste")
			(net "M_B_DQ<2>")
		)
		(pad "158" smd rect
			(at 4.59994 11.050016 90)
			(size 1.8034 0.508)
			(layers "F.Cu" "F.Mask" "F.Paste")
			(net "GND")
		)
		(pad "159" smd rect
			(at 4.59994 11.8999 90)
			(size 1.8034 0.508)
			(layers "F.Cu" "F.Mask" "F.Paste")
			(net "M_B_DQ<12>")
		)
		(pad "160" smd rect
			(at 4.59994 12.750038 90)
			(size 1.8034 0.508)
			(layers "F.Cu" "F.Mask" "F.Paste")
			(net "GND")
		)
		(pad "161" smd rect
			(at 4.59994 13.599922 90)
			(size 1.8034 0.508)
			(layers "F.Cu" "F.Mask" "F.Paste")
			(net "M_B_DQ<8>")
		)
		(pad "162" smd rect
			(at 4.59994 14.45006 90)
			(size 1.8034 0.508)
			(layers "F.Cu" "F.Mask" "F.Paste")
			(net "GND")
		)
		(pad "163" smd rect
			(at 4.59994 15.299944 90)
			(size 1.8034 0.508)
			(layers "F.Cu" "F.Mask" "F.Paste")
			(net "M_B_DQS_DN<1>")
		)
		(pad "164" smd rect
			(at 4.59994 16.150082 90)
			(size 1.8034 0.508)
			(layers "F.Cu" "F.Mask" "F.Paste")
			(net "M_B_DQS_DP<1>")
		)
		(pad "165" smd rect
			(at 4.59994 16.999966 90)
			(size 1.8034 0.508)
			(layers "F.Cu" "F.Mask" "F.Paste")
			(net "GND")
		)
		(pad "166" smd rect
			(at 4.59994 17.850104 90)
			(size 1.8034 0.508)
			(layers "F.Cu" "F.Mask" "F.Paste")
			(net "M_B_DQ<14>")
		)
		(pad "167" smd rect
			(at 4.59994 18.699988 90)
			(size 1.8034 0.508)
			(layers "F.Cu" "F.Mask" "F.Paste")
			(net "GND")
		)
		(pad "168" smd rect
			(at 4.59994 19.550126 90)
			(size 1.8034 0.508)
			(layers "F.Cu" "F.Mask" "F.Paste")
			(net "M_B_DQ<10>")
		)
		(pad "169" smd rect
			(at 4.59994 20.40001 90)
			(size 1.8034 0.508)
			(layers "F.Cu" "F.Mask" "F.Paste")
			(net "GND")
		)
		(pad "170" smd rect
			(at 4.59994 21.249894 90)
			(size 1.8034 0.508)
			(layers "F.Cu" "F.Mask" "F.Paste")
			(net "M_B_DQ<20>")
		)
		(pad "171" smd rect
			(at 4.59994 22.100032 90)
			(size 1.8034 0.508)
			(layers "F.Cu" "F.Mask" "F.Paste")
			(net "GND")
		)
		(pad "172" smd rect
			(at 4.59994 22.949916 90)
			(size 1.8034 0.508)
			(layers "F.Cu" "F.Mask" "F.Paste")
			(net "M_B_DQ<16>")
		)
		(pad "173" smd rect
			(at 4.59994 23.800054 90)
			(size 1.8034 0.508)
			(layers "F.Cu" "F.Mask" "F.Paste")
			(net "GND")
		)
		(pad "174" smd rect
			(at 4.59994 24.649938 90)
			(size 1.8034 0.508)
			(layers "F.Cu" "F.Mask" "F.Paste")
			(net "M_B_DQS_DN<2>")
		)
		(pad "175" smd rect
			(at 4.59994 25.500076 90)
			(size 1.8034 0.508)
			(layers "F.Cu" "F.Mask" "F.Paste")
			(net "M_B_DQS_DP<2>")
		)
		(pad "176" smd rect
			(at 4.59994 26.34996 90)
			(size 1.8034 0.508)
			(layers "F.Cu" "F.Mask" "F.Paste")
			(net "GND")
		)
		(pad "177" smd rect
			(at 4.59994 27.200098 90)
			(size 1.8034 0.508)
			(layers "F.Cu" "F.Mask" "F.Paste")
			(net "M_B_DQ<22>")
		)
		(pad "178" smd rect
			(at 4.59994 28.049982 90)
			(size 1.8034 0.508)
			(layers "F.Cu" "F.Mask" "F.Paste")
			(net "GND")
		)
		(pad "179" smd rect
			(at 4.59994 28.90012 90)
			(size 1.8034 0.508)
			(layers "F.Cu" "F.Mask" "F.Paste")
			(net "M_B_DQ<18>")
		)
		(pad "180" smd rect
			(at 4.59994 29.750004 90)
			(size 1.8034 0.508)
			(layers "F.Cu" "F.Mask" "F.Paste")
			(net "GND")
		)
		(pad "181" smd rect
			(at 4.59994 30.599888 90)
			(size 1.8034 0.508)
			(layers "F.Cu" "F.Mask" "F.Paste")
			(net "M_B_DQ<28>")
		)
		(pad "182" smd rect
			(at 4.59994 31.450026 90)
			(size 1.8034 0.508)
			(layers "F.Cu" "F.Mask" "F.Paste")
			(net "GND")
		)
		(pad "183" smd rect
			(at 4.59994 32.29991 90)
			(size 1.8034 0.508)
			(layers "F.Cu" "F.Mask" "F.Paste")
			(net "M_B_DQ<24>")
		)
		(pad "184" smd rect
			(at 4.59994 33.150048 90)
			(size 1.8034 0.508)
			(layers "F.Cu" "F.Mask" "F.Paste")
			(net "GND")
		)
		(pad "185" smd rect
			(at 4.59994 33.999932 90)
			(size 1.8034 0.508)
			(layers "F.Cu" "F.Mask" "F.Paste")
			(net "M_B_DQS_DN<3>")
		)
		(pad "186" smd rect
			(at 4.59994 34.85007 90)
			(size 1.8034 0.508)
			(layers "F.Cu" "F.Mask" "F.Paste")
			(net "M_B_DQS_DP<3>")
		)
		(pad "187" smd rect
			(at 4.59994 35.699954 90)
			(size 1.8034 0.508)
			(layers "F.Cu" "F.Mask" "F.Paste")
			(net "GND")
		)
		(pad "188" smd rect
			(at 4.59994 36.550092 90)
			(size 1.8034 0.508)
			(layers "F.Cu" "F.Mask" "F.Paste")
			(net "M_B_DQ<30>")
		)
		(pad "189" smd rect
			(at 4.59994 37.399976 90)
			(size 1.8034 0.508)
			(layers "F.Cu" "F.Mask" "F.Paste")
			(net "GND")
		)
		(pad "190" smd rect
			(at 4.59994 38.250114 90)
			(size 1.8034 0.508)
			(layers "F.Cu" "F.Mask" "F.Paste")
			(net "M_B_DQ<26>")
		)
		(pad "191" smd rect
			(at 4.59994 39.099998 90)
			(size 1.8034 0.508)
			(layers "F.Cu" "F.Mask" "F.Paste")
			(net "GND")
		)
		(pad "192" smd rect
			(at 4.59994 39.949882 90)
			(size 1.8034 0.508)
			(layers "F.Cu" "F.Mask" "F.Paste")
			(net "M_B_ECC<4>")
		)
		(pad "193" smd rect
			(at 4.59994 40.80002 90)
			(size 1.8034 0.508)
			(layers "F.Cu" "F.Mask" "F.Paste")
			(net "GND")
		)
		(pad "194" smd rect
			(at 4.59994 41.649904 90)
			(size 1.8034 0.508)
			(layers "F.Cu" "F.Mask" "F.Paste")
			(net "M_B_ECC<0>")
		)
		(pad "195" smd rect
			(at 4.59994 42.500042 90)
			(size 1.8034 0.508)
			(layers "F.Cu" "F.Mask" "F.Paste")
			(net "GND")
		)
		(pad "196" smd rect
			(at 4.59994 43.349926 90)
			(size 1.8034 0.508)
			(layers "F.Cu" "F.Mask" "F.Paste")
			(net "M_B_DQS_DN<8>")
		)
		(pad "197" smd rect
			(at 4.59994 44.200064 90)
			(size 1.8034 0.508)
			(layers "F.Cu" "F.Mask" "F.Paste")
			(net "M_B_DQS_DP<8>")
		)
		(pad "198" smd rect
			(at 4.59994 45.049948 90)
			(size 1.8034 0.508)
			(layers "F.Cu" "F.Mask" "F.Paste")
			(net "GND")
		)
		(pad "199" smd rect
			(at 4.59994 45.900086 90)
			(size 1.8034 0.508)
			(layers "F.Cu" "F.Mask" "F.Paste")
			(net "M_B_ECC<6>")
		)
		(pad "200" smd rect
			(at 4.59994 46.74997 90)
			(size 1.8034 0.508)
			(layers "F.Cu" "F.Mask" "F.Paste")
			(net "GND")
		)
		(pad "201" smd rect
			(at 4.59994 47.600108 90)
			(size 1.8034 0.508)
			(layers "F.Cu" "F.Mask" "F.Paste")
			(net "M_B_ECC<2>")
		)
		(pad "202" smd rect
			(at 4.59994 48.449992 90)
			(size 1.8034 0.508)
			(layers "F.Cu" "F.Mask" "F.Paste")
			(net "GND")
		)
		(pad "203" smd rect
			(at 4.59994 49.299876 90)
			(size 1.8034 0.508)
			(layers "F.Cu" "F.Mask" "F.Paste")
			(net "M_B_CKE<1>")
		)
		(pad "204" smd rect
			(at 4.59994 50.150014 90)
			(size 1.8034 0.508)
			(layers "F.Cu" "F.Mask" "F.Paste")
			(net "PVDDQ_ABC")
		)
		(pad "205" smd rect
			(at 4.59994 50.999898 90)
			(size 1.8034 0.508)
			(layers "F.Cu" "F.Mask" "F.Paste")
			(net "TP_CH_B_DIMM_B0_RFU_0")
		)
		(pad "206" smd rect
			(at 4.59994 51.850036 90)
			(size 1.8034 0.508)
			(layers "F.Cu" "F.Mask" "F.Paste")
			(net "PVDDQ_ABC")
		)
		(pad "207" smd rect
			(at 4.59994 52.69992 90)
			(size 1.8034 0.508)
			(layers "F.Cu" "F.Mask" "F.Paste")
			(net "M_B_BG<1>")
		)
		(pad "208" smd rect
			(at 4.59994 53.550058 90)
			(size 1.8034 0.508)
			(layers "F.Cu" "F.Mask" "F.Paste")
			(net "M_B_ALERT_N")
		)
		(pad "209" smd rect
			(at 4.59994 54.399942 90)
			(size 1.8034 0.508)
			(layers "F.Cu" "F.Mask" "F.Paste")
			(net "PVDDQ_ABC")
		)
		(pad "210" smd rect
			(at 4.59994 55.25008 90)
			(size 1.8034 0.508)
			(layers "F.Cu" "F.Mask" "F.Paste")
			(net "M_B_MA<11>")
		)
		(pad "211" smd rect
			(at 4.59994 56.099964 90)
			(size 1.8034 0.508)
			(layers "F.Cu" "F.Mask" "F.Paste")
			(net "M_B_MA<7>")
		)
		(pad "212" smd rect
			(at 4.59994 56.950102 90)
			(size 1.8034 0.508)
			(layers "F.Cu" "F.Mask" "F.Paste")
			(net "PVDDQ_ABC")
		)
		(pad "213" smd rect
			(at 4.59994 57.799986 90)
			(size 1.8034 0.508)
			(layers "F.Cu" "F.Mask" "F.Paste")
			(net "M_B_MA<5>")
		)
		(pad "214" smd rect
			(at 4.59994 58.650124 90)
			(size 1.8034 0.508)
			(layers "F.Cu" "F.Mask" "F.Paste")
			(net "M_B_MA<4>")
		)
		(pad "215" smd rect
			(at 4.59994 59.500008 90)
			(size 1.8034 0.508)
			(layers "F.Cu" "F.Mask" "F.Paste")
			(net "PVDDQ_ABC")
		)
		(pad "216" smd rect
			(at 4.59994 60.349892 90)
			(size 1.8034 0.508)
			(layers "F.Cu" "F.Mask" "F.Paste")
			(net "M_B_MA<2>")
		)
		(pad "217" smd rect
			(at 4.59994 61.20003 90)
			(size 1.8034 0.508)
			(layers "F.Cu" "F.Mask" "F.Paste")
			(net "PVDDQ_ABC")
		)
		(pad "218" smd rect
			(at 4.59994 62.049914 90)
			(size 1.8034 0.508)
			(layers "F.Cu" "F.Mask" "F.Paste")
			(net "M_B_CLK_DP<1>")
		)
		(pad "219" smd rect
			(at 4.59994 62.900052 90)
			(size 1.8034 0.508)
			(layers "F.Cu" "F.Mask" "F.Paste")
			(net "M_B_CLK_DN<1>")
		)
		(pad "220" smd rect
			(at 4.59994 63.749936 90)
			(size 1.8034 0.508)
			(layers "F.Cu" "F.Mask" "F.Paste")
			(net "PVDDQ_ABC")
		)
		(pad "221" smd rect
			(at 4.59994 64.600074 90)
			(size 1.8034 0.508)
			(layers "F.Cu" "F.Mask" "F.Paste")
			(net "PVTT_ABC")
		)
		(pad "222" smd rect
			(at 4.59994 70.550024 90)
			(size 1.8034 0.508)
			(layers "F.Cu" "F.Mask" "F.Paste")
			(net "M_B_PAR")
		)
		(pad "223" smd rect
			(at 4.59994 71.399908 90)
			(size 1.8034 0.508)
			(layers "F.Cu" "F.Mask" "F.Paste")
			(net "PVDDQ_ABC")
		)
		(pad "224" smd rect
			(at 4.59994 72.250046 90)
			(size 1.8034 0.508)
			(layers "F.Cu" "F.Mask" "F.Paste")
			(net "M_B_BA<1>")
		)
		(pad "225" smd rect
			(at 4.59994 73.09993 90)
			(size 1.8034 0.508)
			(layers "F.Cu" "F.Mask" "F.Paste")
			(net "M_B_MA<10>")
		)
		(pad "226" smd rect
			(at 4.59994 73.950068 90)
			(size 1.8034 0.508)
			(layers "F.Cu" "F.Mask" "F.Paste")
			(net "PVDDQ_ABC")
		)
		(pad "227" smd rect
			(at 4.59994 74.799952 90)
			(size 1.8034 0.508)
			(layers "F.Cu" "F.Mask" "F.Paste")
			(net "TP_CH_B_DIMM_B0_RFU_1")
		)
		(pad "228" smd rect
			(at 4.59994 75.65009 90)
			(size 1.8034 0.508)
			(layers "F.Cu" "F.Mask" "F.Paste")
			(net "M_B_MA<14>")
		)
		(pad "229" smd rect
			(at 4.59994 76.499974 90)
			(size 1.8034 0.508)
			(layers "F.Cu" "F.Mask" "F.Paste")
			(net "PVDDQ_ABC")
		)
		(pad "230" smd rect
			(at 4.59994 77.350112 90)
			(size 1.8034 0.508)
			(layers "F.Cu" "F.Mask" "F.Paste")
			(net "FM_ADR_COMPLETE_ABC_N")
		)
		(pad "231" smd rect
			(at 4.59994 78.199996 90)
			(size 1.8034 0.508)
			(layers "F.Cu" "F.Mask" "F.Paste")
			(net "PVDDQ_ABC")
		)
		(pad "232" smd rect
			(at 4.59994 79.04988 90)
			(size 1.8034 0.508)
			(layers "F.Cu" "F.Mask" "F.Paste")
			(net "M_B_MA<13>")
		)
		(pad "233" smd rect
			(at 4.59994 79.900018 90)
			(size 1.8034 0.508)
			(layers "F.Cu" "F.Mask" "F.Paste")
			(net "PVDDQ_ABC")
		)
		(pad "234" smd rect
			(at 4.59994 80.749902 90)
			(size 1.8034 0.508)
			(layers "F.Cu" "F.Mask" "F.Paste")
			(net "M_B_MA<17>")
		)
		(pad "235" smd rect
			(at 4.59994 81.60004 90)
			(size 1.8034 0.508)
			(layers "F.Cu" "F.Mask" "F.Paste")
			(net "M_B_C<2>")
		)
		(pad "236" smd rect
			(at 4.59994 82.449924 90)
			(size 1.8034 0.508)
			(layers "F.Cu" "F.Mask" "F.Paste")
			(net "PVDDQ_ABC")
		)
		(pad "237" smd rect
			(at 4.59994 83.300062 90)
			(size 1.8034 0.508)
			(layers "F.Cu" "F.Mask" "F.Paste")
			(net "M_B_CS_N<3>")
		)
		(pad "238" smd rect
			(at 4.59994 84.149946 90)
			(size 1.8034 0.508)
			(layers "F.Cu" "F.Mask" "F.Paste")
			(net "GND")
		)
		(pad "239" smd rect
			(at 4.59994 85.000084 90)
			(size 1.8034 0.508)
			(layers "F.Cu" "F.Mask" "F.Paste")
			(net "GND")
		)
		(pad "240" smd rect
			(at 4.59994 85.849968 90)
			(size 1.8034 0.508)
			(layers "F.Cu" "F.Mask" "F.Paste")
			(net "M_B_DQ<36>")
		)
		(pad "241" smd rect
			(at 4.59994 86.700106 90)
			(size 1.8034 0.508)
			(layers "F.Cu" "F.Mask" "F.Paste")
			(net "GND")
		)
		(pad "242" smd rect
			(at 4.59994 87.54999 90)
			(size 1.8034 0.508)
			(layers "F.Cu" "F.Mask" "F.Paste")
			(net "M_B_DQ<32>")
		)
		(pad "243" smd rect
			(at 4.59994 88.399874 90)
			(size 1.8034 0.508)
			(layers "F.Cu" "F.Mask" "F.Paste")
			(net "GND")
		)
		(pad "244" smd rect
			(at 4.59994 89.250012 90)
			(size 1.8034 0.508)
			(layers "F.Cu" "F.Mask" "F.Paste")
			(net "M_B_DQS_DN<4>")
		)
		(pad "245" smd rect
			(at 4.59994 90.099896 90)
			(size 1.8034 0.508)
			(layers "F.Cu" "F.Mask" "F.Paste")
			(net "M_B_DQS_DP<4>")
		)
		(pad "246" smd rect
			(at 4.59994 90.950034 90)
			(size 1.8034 0.508)
			(layers "F.Cu" "F.Mask" "F.Paste")
			(net "GND")
		)
		(pad "247" smd rect
			(at 4.59994 91.799918 90)
			(size 1.8034 0.508)
			(layers "F.Cu" "F.Mask" "F.Paste")
			(net "M_B_DQ<38>")
		)
		(pad "248" smd rect
			(at 4.59994 92.650056 90)
			(size 1.8034 0.508)
			(layers "F.Cu" "F.Mask" "F.Paste")
			(net "GND")
		)
		(pad "249" smd rect
			(at 4.59994 93.49994 90)
			(size 1.8034 0.508)
			(layers "F.Cu" "F.Mask" "F.Paste")
			(net "M_B_DQ<34>")
		)
		(pad "250" smd rect
			(at 4.59994 94.350078 90)
			(size 1.8034 0.508)
			(layers "F.Cu" "F.Mask" "F.Paste")
			(net "GND")
		)
		(pad "251" smd rect
			(at 4.59994 95.199962 90)
			(size 1.8034 0.508)
			(layers "F.Cu" "F.Mask" "F.Paste")
			(net "M_B_DQ<44>")
		)
		(pad "252" smd rect
			(at 4.59994 96.0501 90)
			(size 1.8034 0.508)
			(layers "F.Cu" "F.Mask" "F.Paste")
			(net "GND")
		)
		(pad "253" smd rect
			(at 4.59994 96.899984 90)
			(size 1.8034 0.508)
			(layers "F.Cu" "F.Mask" "F.Paste")
			(net "M_B_DQ<40>")
		)
		(pad "254" smd rect
			(at 4.59994 97.750122 90)
			(size 1.8034 0.508)
			(layers "F.Cu" "F.Mask" "F.Paste")
			(net "GND")
		)
		(pad "255" smd rect
			(at 4.59994 98.600006 90)
			(size 1.8034 0.508)
			(layers "F.Cu" "F.Mask" "F.Paste")
			(net "M_B_DQS_DN<5>")
		)
		(pad "256" smd rect
			(at 4.59994 99.44989 90)
			(size 1.8034 0.508)
			(layers "F.Cu" "F.Mask" "F.Paste")
			(net "M_B_DQS_DP<5>")
		)
		(pad "257" smd rect
			(at 4.59994 100.300028 90)
			(size 1.8034 0.508)
			(layers "F.Cu" "F.Mask" "F.Paste")
			(net "GND")
		)
		(pad "258" smd rect
			(at 4.59994 101.149912 90)
			(size 1.8034 0.508)
			(layers "F.Cu" "F.Mask" "F.Paste")
			(net "M_B_DQ<46>")
		)
		(pad "259" smd rect
			(at 4.59994 102.00005 90)
			(size 1.8034 0.508)
			(layers "F.Cu" "F.Mask" "F.Paste")
			(net "GND")
		)
		(pad "260" smd rect
			(at 4.59994 102.849934 90)
			(size 1.8034 0.508)
			(layers "F.Cu" "F.Mask" "F.Paste")
			(net "M_B_DQ<42>")
		)
		(pad "261" smd rect
			(at 4.59994 103.700072 90)
			(size 1.8034 0.508)
			(layers "F.Cu" "F.Mask" "F.Paste")
			(net "GND")
		)
		(pad "262" smd rect
			(at 4.59994 104.549956 90)
			(size 1.8034 0.508)
			(layers "F.Cu" "F.Mask" "F.Paste")
			(net "M_B_DQ<52>")
		)
		(pad "263" smd rect
			(at 4.59994 105.400094 90)
			(size 1.8034 0.508)
			(layers "F.Cu" "F.Mask" "F.Paste")
			(net "GND")
		)
		(pad "264" smd rect
			(at 4.59994 106.249978 90)
			(size 1.8034 0.508)
			(layers "F.Cu" "F.Mask" "F.Paste")
			(net "M_B_DQ<48>")
		)
		(pad "265" smd rect
			(at 4.59994 107.100116 90)
			(size 1.8034 0.508)
			(layers "F.Cu" "F.Mask" "F.Paste")
			(net "GND")
		)
		(pad "266" smd rect
			(at 4.59994 107.95 90)
			(size 1.8034 0.508)
			(layers "F.Cu" "F.Mask" "F.Paste")
			(net "M_B_DQS_DN<6>")
		)
		(pad "267" smd rect
			(at 4.59994 108.799884 90)
			(size 1.8034 0.508)
			(layers "F.Cu" "F.Mask" "F.Paste")
			(net "M_B_DQS_DP<6>")
		)
		(pad "268" smd rect
			(at 4.59994 109.650022 90)
			(size 1.8034 0.508)
			(layers "F.Cu" "F.Mask" "F.Paste")
			(net "GND")
		)
		(pad "269" smd rect
			(at 4.59994 110.499906 90)
			(size 1.8034 0.508)
			(layers "F.Cu" "F.Mask" "F.Paste")
			(net "M_B_DQ<54>")
		)
		(pad "270" smd rect
			(at 4.59994 111.350044 90)
			(size 1.8034 0.508)
			(layers "F.Cu" "F.Mask" "F.Paste")
			(net "GND")
		)
		(pad "271" smd rect
			(at 4.59994 112.199928 90)
			(size 1.8034 0.508)
			(layers "F.Cu" "F.Mask" "F.Paste")
			(net "M_B_DQ<50>")
		)
		(pad "272" smd rect
			(at 4.59994 113.050066 90)
			(size 1.8034 0.508)
			(layers "F.Cu" "F.Mask" "F.Paste")
			(net "GND")
		)
		(pad "273" smd rect
			(at 4.59994 113.89995 90)
			(size 1.8034 0.508)
			(layers "F.Cu" "F.Mask" "F.Paste")
			(net "M_B_DQ<60>")
		)
		(pad "274" smd rect
			(at 4.59994 114.750088 90)
			(size 1.8034 0.508)
			(layers "F.Cu" "F.Mask" "F.Paste")
			(net "GND")
		)
		(pad "275" smd rect
			(at 4.59994 115.599972 90)
			(size 1.8034 0.508)
			(layers "F.Cu" "F.Mask" "F.Paste")
			(net "M_B_DQ<56>")
		)
		(pad "276" smd rect
			(at 4.59994 116.45011 90)
			(size 1.8034 0.508)
			(layers "F.Cu" "F.Mask" "F.Paste")
			(net "GND")
		)
		(pad "277" smd rect
			(at 4.59994 117.299994 90)
			(size 1.8034 0.508)
			(layers "F.Cu" "F.Mask" "F.Paste")
			(net "M_B_DQS_DN<7>")
		)
		(pad "278" smd rect
			(at 4.59994 118.149878 90)
			(size 1.8034 0.508)
			(layers "F.Cu" "F.Mask" "F.Paste")
			(net "M_B_DQS_DP<7>")
		)
		(pad "279" smd rect
			(at 4.59994 119.000016 90)
			(size 1.8034 0.508)
			(layers "F.Cu" "F.Mask" "F.Paste")
			(net "GND")
		)
		(pad "280" smd rect
			(at 4.59994 119.8499 90)
			(size 1.8034 0.508)
			(layers "F.Cu" "F.Mask" "F.Paste")
			(net "M_B_DQ<62>")
		)
		(pad "281" smd rect
			(at 4.59994 120.700038 90)
			(size 1.8034 0.508)
			(layers "F.Cu" "F.Mask" "F.Paste")
			(net "GND")
		)
		(pad "282" smd rect
			(at 4.59994 121.549922 90)
			(size 1.8034 0.508)
			(layers "F.Cu" "F.Mask" "F.Paste")
			(net "M_B_DQ<58>")
		)
		(pad "283" smd rect
			(at 4.59994 122.40006 90)
			(size 1.8034 0.508)
			(layers "F.Cu" "F.Mask" "F.Paste")
			(net "GND")
		)
		(pad "284" smd rect
			(at 4.59994 123.249944 90)
			(size 1.8034 0.508)
			(layers "F.Cu" "F.Mask" "F.Paste")
			(net "PVPP_ABC")
		)
		(pad "285" smd rect
			(at 4.59994 124.100082 90)
			(size 1.8034 0.508)
			(layers "F.Cu" "F.Mask" "F.Paste")
			(net "SMB_DDR_ABC_VPP_SDA")
		)
		(pad "286" smd rect
			(at 4.59994 124.949966 90)
			(size 1.8034 0.508)
			(layers "F.Cu" "F.Mask" "F.Paste")
			(net "PVPP_ABC")
		)
		(pad "287" smd rect
			(at 4.59994 125.800104 90)
			(size 1.8034 0.508)
			(layers "F.Cu" "F.Mask" "F.Paste")
			(net "PVPP_ABC")
		)
		(pad "288" smd rect
			(at 4.59994 126.649988 90)
			(size 1.8034 0.508)
			(layers "F.Cu" "F.Mask" "F.Paste")
			(net "PVPP_ABC")
		)
	)
	(footprint ""
		(layer "F.Cu")
		(at 476.2246 -145.8849 -90)
		(property "Reference" "U1L3"
			(at 4.98094 2.76733 90)
			(unlocked yes)
			(layer "F.SilkS")
			(effects
				(font
					(size 0.7874 0.5842)
					(thickness 0.1524)
				)
				(justify left)
			)
		)
		(property "Value" ""
			(at 0 0 270)
			(layer "F.Fab")
			(effects
				(font
					(size 1.27 1.27)
				)
			)
		)
		(duplicate_pad_numbers_are_jumpers no)
		(fp_line
			(start 0.9525 2.4765)
			(end 1.778 2.4765)
			(stroke
				(width 0.1524)
				(type default)
			)
			(layer "F.SilkS")
		)
		(fp_line
			(start 1.778 2.4765)
			(end 1.778 1.5875)
			(stroke
				(width 0.1524)
				(type default)
			)
			(layer "F.SilkS")
		)
		(fp_line
			(start 0.381 0.635)
			(end 0.381 1.27)
			(stroke
				(width 0.1524)
				(type default)
			)
			(layer "F.SilkS")
		)
		(fp_line
			(start 0.9525 -0.5715)
			(end 1.778 -0.5715)
			(stroke
				(width 0.1524)
				(type default)
			)
			(layer "F.SilkS")
		)
		(fp_line
			(start 1.778 -0.5715)
			(end 1.778 0.3175)
			(stroke
				(width 0.1524)
				(type default)
			)
			(layer "F.SilkS")
		)
		(fp_circle
			(center -0.9525 -0.9271)
			(end -0.9525 -1.0541)
			(stroke
				(width 0.254)
				(type default)
			)
			(fill no)
			(layer "F.SilkS")
		)
		(fp_poly
			(pts
				(xy 1.778 2.4765) (xy 0.381 2.4765) (xy 0.381 -0.5715) (xy 1.778 -0.5715)
			)
			(stroke
				(width 0)
				(type default)
			)
			(fill no)
			(layer "F.CrtYd")
		)
		(fp_line
			(start 0.381 2.4765)
			(end 1.778 2.4765)
			(stroke
				(width 0.1)
				(type default)
			)
			(layer "F.Fab")
		)
		(fp_line
			(start 1.778 2.4765)
			(end 1.778 -0.5715)
			(stroke
				(width 0.1)
				(type default)
			)
			(layer "F.Fab")
		)
		(fp_line
			(start 0.381 -0.5715)
			(end 0.381 2.4765)
			(stroke
				(width 0.1)
				(type default)
			)
			(layer "F.Fab")
		)
		(fp_line
			(start 1.778 -0.5715)
			(end 0.381 -0.5715)
			(stroke
				(width 0.1)
				(type default)
			)
			(layer "F.Fab")
		)
		(fp_circle
			(center -0.9525 -0.9271)
			(end -0.9525 -1.0541)
			(stroke
				(width 0.254)
				(type default)
			)
			(fill no)
			(layer "F.Fab")
		)
		(pad "1" smd rect
			(at 0 0 270)
			(size 1.143 0.508)
			(layers "F.Cu" "F.Mask" "F.Paste")
			(net "GND")
		)
		(pad "2" smd rect
			(at 0 1.905 270)
			(size 1.143 0.508)
			(layers "F.Cu" "F.Mask" "F.Paste")
			(net "PWRGD_P3V3_R1")
		)
		(pad "3" smd rect
			(at 2.159 0.9525 270)
			(size 1.143 0.508)
			(layers "F.Cu" "F.Mask" "F.Paste")
			(net "P3V3")
		)
	)
	(footprint ""
		(layer "F.Cu")
		(at 227.071936 11.952478 -90)
		(property "Reference" "T1P6"
			(at 0 0 270)
			(layer "F.SilkS")
			(hide yes)
			(effects
				(font
					(size 1.27 1.27)
				)
			)
		)
		(property "Value" "*"
			(at -3.302 1.12395 270)
			(unlocked yes)
			(layer "F.Fab")
			(hide yes)
			(effects
				(font
					(size 0.889 0.889)
					(thickness 0.1524)
				)
			)
		)
		(property "Device Type" "TPAD-DIFF-4P-GP_DISCRET-GB3-TPA"
			(at -3.302 -0.40005 270)
			(unlocked yes)
			(layer "F.Fab")
			(hide yes)
			(effects
				(font
					(size 0.889 0.889)
					(thickness 0.1524)
				)
			)
		)
		(duplicate_pad_numbers_are_jumpers no)
		(fp_line
			(start -2.286 2.286)
			(end 2.286 2.286)
			(stroke
				(width 0.1524)
				(type default)
			)
			(layer "F.SilkS")
		)
		(fp_line
			(start 2.286 2.286)
			(end 2.286 -2.286)
			(stroke
				(width 0.1524)
				(type default)
			)
			(layer "F.SilkS")
		)
		(fp_line
			(start -2.286 -2.286)
			(end -2.286 2.286)
			(stroke
				(width 0.1524)
				(type default)
			)
			(layer "F.SilkS")
		)
		(fp_line
			(start 2.286 -2.286)
			(end -2.286 -2.286)
			(stroke
				(width 0.1524)
				(type default)
			)
			(layer "F.SilkS")
		)
		(fp_line
			(start -2.413 -2.413)
			(end -2.413 -1.143)
			(stroke
				(width 0.4064)
				(type default)
			)
			(layer "F.SilkS")
		)
		(fp_line
			(start -1.143 -2.413)
			(end -2.413 -2.413)
			(stroke
				(width 0.4064)
				(type default)
			)
			(layer "F.SilkS")
		)
		(fp_rect
			(start -2.54 2.54)
			(end 2.54 -2.54)
			(stroke
				(width 0)
				(type default)
			)
			(fill no)
			(layer "F.CrtYd")
		)
		(fp_rect
			(start -2.54 2.54)
			(end 2.54 -2.54)
			(stroke
				(width 0)
				(type default)
			)
			(fill no)
			(layer "F.Fab")
		)
		(pad "1" thru_hole circle
			(at -1.27 -1.27 270)
			(size 1.524 1.524)
			(drill 0.9144)
			(layers "*.Cu" "*.Mask")
			(remove_unused_layers no)
			(net "L14_85OHM_6INCH_DP")
			(clearance -0.0508)
			(thermal_gap 0.127)
			(padstack
				(mode front_inner_back)
				(layer "Inner"
					(shape circle)
					(size 1.1684 1.1684)
					(clearance 0.127)
				)
				(layer "B.Cu"
					(shape circle)
					(size 1.524 1.524)
					(clearance -0.0508)
				)
			)
		)
		(pad "2" thru_hole circle
			(at 1.27 -1.27 270)
			(size 1.524 1.524)
			(drill 0.9144)
			(layers "*.Cu" "*.Mask")
			(remove_unused_layers no)
			(net "L14_85OHM_6INCH_DN")
			(clearance -0.0508)
			(thermal_gap 0.127)
			(padstack
				(mode front_inner_back)
				(layer "Inner"
					(shape circle)
					(size 1.1684 1.1684)
					(clearance 0.127)
				)
				(layer "B.Cu"
					(shape circle)
					(size 1.524 1.524)
					(clearance -0.0508)
				)
			)
		)
		(pad "GND1" thru_hole rect
			(at -1.27 1.27 270)
			(size 1.524 1.524)
			(drill 0.9144)
			(layers "*.Cu" "*.Mask")
			(remove_unused_layers no)
			(net "GND")
			(clearance -0.0508)
			(thermal_gap 0.127)
			(padstack
				(mode front_inner_back)
				(layer "Inner"
					(shape circle)
					(size 1.1684 1.1684)
					(clearance 0.127)
				)
				(layer "B.Cu"
					(shape rect)
					(size 1.524 1.524)
					(clearance -0.0508)
				)
			)
		)
		(pad "GND2" thru_hole rect
			(at 1.27 1.27 270)
			(size 1.524 1.524)
			(drill 0.9144)
			(layers "*.Cu" "*.Mask")
			(remove_unused_layers no)
			(net "GND")
			(clearance -0.0508)
			(thermal_gap 0.127)
			(padstack
				(mode front_inner_back)
				(layer "Inner"
					(shape circle)
					(size 1.1684 1.1684)
					(clearance 0.127)
				)
				(layer "B.Cu"
					(shape rect)
					(size 1.524 1.524)
					(clearance -0.0508)
				)
			)
		)
	)
	(footprint ""
		(layer "F.Cu")
		(at 474.9927 -40.631364 180)
		(property "Reference" "Y9E1"
			(at 2.77749 0.5842 90)
			(unlocked yes)
			(layer "F.SilkS")
			(effects
				(font
					(size 0.7874 0.5842)
					(thickness 0.1524)
				)
				(justify left)
			)
		)
		(property "Value" ""
			(at 0 0 180)
			(layer "F.Fab")
			(effects
				(font
					(size 1.27 1.27)
				)
			)
		)
		(duplicate_pad_numbers_are_jumpers no)
		(fp_circle
			(center -0.668782 -1.07823)
			(end -0.795782 -1.07823)
			(stroke
				(width 0.254)
				(type default)
			)
			(fill no)
			(layer "F.SilkS")
		)
		(fp_rect
			(start -0.499872 2.70002)
			(end 2.100072 -0.599948)
			(stroke
				(width 0)
				(type default)
			)
			(fill no)
			(layer "F.CrtYd")
		)
		(fp_line
			(start 2.100072 2.70002)
			(end -0.499872 2.70002)
			(stroke
				(width 0.1)
				(type default)
			)
			(layer "F.Fab")
		)
		(fp_line
			(start 2.100072 -0.599948)
			(end 2.100072 2.70002)
			(stroke
				(width 0.1)
				(type default)
			)
			(layer "F.Fab")
		)
		(fp_line
			(start -0.499872 2.70002)
			(end -0.499872 -0.599948)
			(stroke
				(width 0.1)
				(type default)
			)
			(layer "F.Fab")
		)
		(fp_line
			(start -0.499872 -0.599948)
			(end 2.100072 -0.599948)
			(stroke
				(width 0.1)
				(type default)
			)
			(layer "F.Fab")
		)
		(fp_circle
			(center -1.049782 -0.44323)
			(end -1.176782 -0.44323)
			(stroke
				(width 0.254)
				(type default)
			)
			(fill no)
			(layer "F.Fab")
		)
		(pad "1" smd rect
			(at 0 0 180)
			(size 1.0414 1.143)
			(layers "F.Cu" "F.Mask" "F.Paste")
			(net "XTAL_25MHZ_IN")
		)
		(pad "2" smd rect
			(at 0 2.100072 180)
			(size 1.0414 1.143)
			(layers "F.Cu" "F.Mask" "F.Paste")
			(net "GND")
		)
		(pad "3" smd rect
			(at 1.6002 2.100072 180)
			(size 1.0414 1.143)
			(layers "F.Cu" "F.Mask" "F.Paste")
			(net "XTAL_25MHZ_OUT_R")
		)
		(pad "4" smd rect
			(at 1.6002 0 180)
			(size 1.0414 1.143)
			(layers "F.Cu" "F.Mask" "F.Paste")
			(net "GND")
		)
	)
	(footprint ""
		(layer "F.Cu")
		(at 417.8935 -64.897 -90)
		(property "Reference" "R8W1"
			(at -0.8382 -0.67818 270)
			(unlocked yes)
			(layer "F.SilkS")
			(effects
				(font
					(size 0.4064 0.254)
					(thickness 0.1524)
				)
				(justify left)
			)
		)
		(property "Value" ""
			(at 0 0 270)
			(layer "F.Fab")
			(effects
				(font
					(size 1.27 1.27)
				)
			)
		)
		(duplicate_pad_numbers_are_jumpers no)
		(fp_poly
			(pts
				(xy -0.2794 -0.1016) (xy 0.2794 -0.1016) (xy 0.2794 0.9906) (xy -0.2794 0.9906)
			)
			(stroke
				(width 0)
				(type default)
			)
			(fill no)
			(layer "F.CrtYd")
		)
		(fp_line
			(start -0.2794 0.9906)
			(end 0.2794 0.9906)
			(stroke
				(width 0.1)
				(type default)
			)
			(layer "F.Fab")
		)
		(fp_line
			(start 0.2794 0.9906)
			(end 0.2794 -0.1016)
			(stroke
				(width 0.1)
				(type default)
			)
			(layer "F.Fab")
		)
		(fp_line
			(start -0.2794 -0.1016)
			(end -0.2794 0.9906)
			(stroke
				(width 0.1)
				(type default)
			)
			(layer "F.Fab")
		)
		(fp_line
			(start 0.2794 -0.1016)
			(end -0.2794 -0.1016)
			(stroke
				(width 0.1)
				(type default)
			)
			(layer "F.Fab")
		)
		(pad "1" smd rect
			(at 0 0 270)
			(size 0.508 0.508)
			(layers "F.Cu" "F.Mask" "F.Paste")
			(net "BMC_SELF_HW_D_RST")
		)
		(pad "2" smd rect
			(at 0 0.889 270)
			(size 0.508 0.508)
			(layers "F.Cu" "F.Mask" "F.Paste")
			(net "FM_TPM_PRES_RST_N")
		)
		(zone
			(layer "F.Cu")
			(hatch none 0.5)
			(connect_pads
				(clearance 0)
			)
			(min_thickness 0.25)
			(keepout
				(tracks not_allowed)
				(vias allowed)
				(pads allowed)
				(copperpour not_allowed)
				(footprints allowed)
			)
			(placement
				(enabled no)
				(sheetname "")
			)
			(fill
				(thermal_gap 0.5)
				(thermal_bridge_width 0.5)
				(island_removal_mode 0)
			)
			(polygon
				(pts
					(xy 417.2585 -65.151) (xy 417.2585 -64.643) (xy 417.6395 -64.643) (xy 417.6395 -65.151)
				)
			)
		)
		(zone
			(layer "F.Cu")
			(hatch none 0.5)
			(connect_pads
				(clearance 0)
			)
			(min_thickness 0.25)
			(keepout
				(tracks allowed)
				(vias not_allowed)
				(pads allowed)
				(copperpour not_allowed)
				(footprints allowed)
			)
			(placement
				(enabled no)
				(sheetname "")
			)
			(fill
				(thermal_gap 0.5)
				(thermal_bridge_width 0.5)
				(island_removal_mode 0)
			)
			(polygon
				(pts
					(xy 417.6395 -65.151) (xy 417.6395 -64.643) (xy 417.2585 -64.643) (xy 417.2585 -65.151)
				)
			)
		)
	)
	(footprint ""
		(layer "F.Cu")
		(at 269.4432 -79.6036 180)
		(property "Reference" "C5W1"
			(at 0.97536 0.76708 90)
			(unlocked yes)
			(layer "F.SilkS")
			(effects
				(font
					(size 0.4064 0.254)
					(thickness 0.1524)
				)
			)
		)
		(property "Value" ""
			(at 0 0 180)
			(layer "F.Fab")
			(effects
				(font
					(size 1.27 1.27)
				)
			)
		)
		(duplicate_pad_numbers_are_jumpers no)
		(fp_poly
			(pts
				(xy -0.4953 -0.2032) (xy 0.4953 -0.2032) (xy 0.4953 1.6002) (xy -0.4953 1.6002)
			)
			(stroke
				(width 0)
				(type default)
			)
			(fill no)
			(layer "F.CrtYd")
		)
		(fp_line
			(start 0.4953 1.6002)
			(end -0.4953 1.6002)
			(stroke
				(width 0.1)
				(type default)
			)
			(layer "F.Fab")
		)
		(fp_line
			(start 0.4953 -0.2032)
			(end 0.4953 1.6002)
			(stroke
				(width 0.1)
				(type default)
			)
			(layer "F.Fab")
		)
		(fp_line
			(start -0.4953 1.6002)
			(end -0.4953 -0.2032)
			(stroke
				(width 0.1)
				(type default)
			)
			(layer "F.Fab")
		)
		(fp_line
			(start -0.4953 -0.2032)
			(end 0.4953 -0.2032)
			(stroke
				(width 0.1)
				(type default)
			)
			(layer "F.Fab")
		)
		(pad "1" smd rect
			(at 0 0 180)
			(size 0.762 0.889)
			(layers "F.Cu" "F.Mask" "F.Paste")
			(net "PVCCMCP_CPU0")
		)
		(pad "2" smd rect
			(at 0 1.397 180)
			(size 0.762 0.889)
			(layers "F.Cu" "F.Mask" "F.Paste")
			(net "GND")
		)
		(zone
			(layer "F.Cu")
			(hatch none 0.5)
			(connect_pads
				(clearance 0)
			)
			(min_thickness 0.25)
			(keepout
				(tracks not_allowed)
				(vias allowed)
				(pads allowed)
				(copperpour not_allowed)
				(footprints allowed)
			)
			(placement
				(enabled no)
				(sheetname "")
			)
			(fill
				(thermal_gap 0.5)
				(thermal_bridge_width 0.5)
				(island_removal_mode 0)
			)
			(polygon
				(pts
					(xy 269.8242 -80.0481) (xy 269.0622 -80.0481) (xy 269.0622 -80.5561) (xy 269.8242 -80.5561)
				)
			)
		)
	)
	(footprint ""
		(layer "F.Cu")
		(at 28.8036 -58.7883 90)
		(property "Reference" "C1E11"
			(at 0 0 90)
			(layer "F.SilkS")
			(hide yes)
			(effects
				(font
					(size 1.27 1.27)
				)
			)
		)
		(property "Value" ""
			(at 0 0 90)
			(layer "F.Fab")
			(effects
				(font
					(size 1.27 1.27)
				)
			)
		)
		(duplicate_pad_numbers_are_jumpers no)
		(fp_rect
			(start -0.3048 0.9906)
			(end 0.3048 -0.1016)
			(stroke
				(width 0)
				(type default)
			)
			(fill no)
			(layer "F.CrtYd")
		)
		(fp_line
			(start 0.3048 -0.1016)
			(end -0.3048 -0.1016)
			(stroke
				(width 0.1)
				(type default)
			)
			(layer "F.Fab")
		)
		(fp_line
			(start -0.3048 -0.1016)
			(end -0.3048 0.9906)
			(stroke
				(width 0.1)
				(type default)
			)
			(layer "F.Fab")
		)
		(fp_line
			(start 0.3048 0.9906)
			(end 0.3048 -0.1016)
			(stroke
				(width 0.1)
				(type default)
			)
			(layer "F.Fab")
		)
		(fp_line
			(start -0.3048 0.9906)
			(end 0.3048 0.9906)
			(stroke
				(width 0.1)
				(type default)
			)
			(layer "F.Fab")
		)
		(pad "1" smd rect
			(at 0 0 90)
			(size 0.508 0.508)
			(layers "F.Cu" "F.Mask" "F.Paste")
			(net "VR_PVCCIN_CPU1_PH1_BOOT")
		)
		(pad "2" smd rect
			(at 0 0.889 90)
			(size 0.508 0.508)
			(layers "F.Cu" "F.Mask" "F.Paste")
			(net "VR_PVCCIN_CPU1_PH1_PHASE")
		)
		(zone
			(layer "F.Cu")
			(hatch none 0.5)
			(connect_pads
				(clearance 0)
			)
			(min_thickness 0.25)
			(keepout
				(tracks not_allowed)
				(vias allowed)
				(pads allowed)
				(copperpour not_allowed)
				(footprints allowed)
			)
			(placement
				(enabled no)
				(sheetname "")
			)
			(fill
				(thermal_gap 0.5)
				(thermal_bridge_width 0.5)
				(island_removal_mode 0)
			)
			(polygon
				(pts
					(xy 29.4386 -58.5343) (xy 29.4386 -59.0423) (xy 29.0576 -59.0423) (xy 29.0576 -58.5343)
				)
			)
		)
		(zone
			(layer "F.Cu")
			(hatch none 0.5)
			(connect_pads
				(clearance 0)
			)
			(min_thickness 0.25)
			(keepout
				(tracks allowed)
				(vias not_allowed)
				(pads allowed)
				(copperpour not_allowed)
				(footprints allowed)
			)
			(placement
				(enabled no)
				(sheetname "")
			)
			(fill
				(thermal_gap 0.5)
				(thermal_bridge_width 0.5)
				(island_removal_mode 0)
			)
			(polygon
				(pts
					(xy 29.4386 -58.5343) (xy 29.4386 -59.0423) (xy 29.0576 -59.0423) (xy 29.0576 -58.5343)
				)
			)
		)
	)
	(footprint ""
		(layer "F.Cu")
		(at 318.643 -130.3528 -90)
		(property "Reference" "C6B1"
			(at 0 0 270)
			(layer "F.SilkS")
			(hide yes)
			(effects
				(font
					(size 1.27 1.27)
				)
			)
		)
		(property "Value" ""
			(at 0 0 270)
			(layer "F.Fab")
			(effects
				(font
					(size 1.27 1.27)
				)
			)
		)
		(duplicate_pad_numbers_are_jumpers no)
		(fp_poly
			(pts
				(xy -0.4953 -0.2032) (xy 0.4953 -0.2032) (xy 0.4953 1.6002) (xy -0.4953 1.6002)
			)
			(stroke
				(width 0)
				(type default)
			)
			(fill no)
			(layer "F.CrtYd")
		)
		(fp_line
			(start -0.4953 1.6002)
			(end -0.4953 -0.2032)
			(stroke
				(width 0.1)
				(type default)
			)
			(layer "F.Fab")
		)
		(fp_line
			(start 0.4953 1.6002)
			(end -0.4953 1.6002)
			(stroke
				(width 0.1)
				(type default)
			)
			(layer "F.Fab")
		)
		(fp_line
			(start -0.4953 -0.2032)
			(end 0.4953 -0.2032)
			(stroke
				(width 0.1)
				(type default)
			)
			(layer "F.Fab")
		)
		(fp_line
			(start 0.4953 -0.2032)
			(end 0.4953 1.6002)
			(stroke
				(width 0.1)
				(type default)
			)
			(layer "F.Fab")
		)
		(pad "1" smd rect
			(at 0 0 270)
			(size 0.762 0.889)
			(layers "F.Cu" "F.Mask" "F.Paste")
			(net "PVPP_DEF")
		)
		(pad "2" smd rect
			(at 0 1.397 270)
			(size 0.762 0.889)
			(layers "F.Cu" "F.Mask" "F.Paste")
			(net "GND")
		)
		(zone
			(layer "F.Cu")
			(hatch none 0.5)
			(connect_pads
				(clearance 0)
			)
			(min_thickness 0.25)
			(keepout
				(tracks not_allowed)
				(vias allowed)
				(pads allowed)
				(copperpour not_allowed)
				(footprints allowed)
			)
			(placement
				(enabled no)
				(sheetname "")
			)
			(fill
				(thermal_gap 0.5)
				(thermal_bridge_width 0.5)
				(island_removal_mode 0)
			)
			(polygon
				(pts
					(xy 318.1985 -130.7338) (xy 318.1985 -129.9718) (xy 317.6905 -129.9718) (xy 317.6905 -130.7338)
				)
			)
		)
	)
	(footprint ""
		(layer "F.Cu")
		(at 401.319492 -10.917936)
		(property "Reference" "C8G2"
			(at 0 0 0)
			(layer "F.SilkS")
			(hide yes)
			(effects
				(font
					(size 1.27 1.27)
				)
			)
		)
		(property "Value" ""
			(at 0 0 0)
			(layer "F.Fab")
			(effects
				(font
					(size 1.27 1.27)
				)
			)
		)
		(duplicate_pad_numbers_are_jumpers no)
		(fp_rect
			(start -0.3048 0.9906)
			(end 0.3048 -0.1016)
			(stroke
				(width 0)
				(type default)
			)
			(fill no)
			(layer "F.CrtYd")
		)
		(fp_line
			(start -0.3048 -0.1016)
			(end -0.3048 0.9906)
			(stroke
				(width 0.1)
				(type default)
			)
			(layer "F.Fab")
		)
		(fp_line
			(start -0.3048 0.9906)
			(end 0.3048 0.9906)
			(stroke
				(width 0.1)
				(type default)
			)
			(layer "F.Fab")
		)
		(fp_line
			(start 0.3048 -0.1016)
			(end -0.3048 -0.1016)
			(stroke
				(width 0.1)
				(type default)
			)
			(layer "F.Fab")
		)
		(fp_line
			(start 0.3048 0.9906)
			(end 0.3048 -0.1016)
			(stroke
				(width 0.1)
				(type default)
			)
			(layer "F.Fab")
		)
		(pad "1" smd rect
			(at 0 0)
			(size 0.508 0.508)
			(layers "F.Cu" "F.Mask" "F.Paste")
			(net "P3E_CPU0_PE2_SS_TXN<4>")
		)
		(pad "2" smd rect
			(at 0 0.889)
			(size 0.508 0.508)
			(layers "F.Cu" "F.Mask" "F.Paste")
			(net "P3E_CPU0_PE2_SS_C_TXN<4>")
		)
		(zone
			(layer "F.Cu")
			(hatch none 0.5)
			(connect_pads
				(clearance 0)
			)
			(min_thickness 0.25)
			(keepout
				(tracks not_allowed)
				(vias allowed)
				(pads allowed)
				(copperpour not_allowed)
				(footprints allowed)
			)
			(placement
				(enabled no)
				(sheetname "")
			)
			(fill
				(thermal_gap 0.5)
				(thermal_bridge_width 0.5)
				(island_removal_mode 0)
			)
			(polygon
				(pts
					(xy 401.065492 -10.282936) (xy 401.573492 -10.282936) (xy 401.573492 -10.663936) (xy 401.065492 -10.663936)
				)
			)
		)
		(zone
			(layer "F.Cu")
			(hatch none 0.5)
			(connect_pads
				(clearance 0)
			)
			(min_thickness 0.25)
			(keepout
				(tracks allowed)
				(vias not_allowed)
				(pads allowed)
				(copperpour not_allowed)
				(footprints allowed)
			)
			(placement
				(enabled no)
				(sheetname "")
			)
			(fill
				(thermal_gap 0.5)
				(thermal_bridge_width 0.5)
				(island_removal_mode 0)
			)
			(polygon
				(pts
					(xy 401.065492 -10.282936) (xy 401.573492 -10.282936) (xy 401.573492 -10.663936) (xy 401.065492 -10.663936)
				)
			)
		)
	)
	(footprint ""
		(layer "F.Cu")
		(at 360.765598 -10.916158)
		(property "Reference" "R8W13"
			(at -0.8382 -0.67818 0)
			(unlocked yes)
			(layer "F.SilkS")
			(effects
				(font
					(size 0.4064 0.254)
					(thickness 0.1524)
				)
				(justify left)
			)
		)
		(property "Value" ""
			(at 0 0 0)
			(layer "F.Fab")
			(effects
				(font
					(size 1.27 1.27)
				)
			)
		)
		(duplicate_pad_numbers_are_jumpers no)
		(fp_poly
			(pts
				(xy -0.2794 -0.1016) (xy 0.2794 -0.1016) (xy 0.2794 0.9906) (xy -0.2794 0.9906)
			)
			(stroke
				(width 0)
				(type default)
			)
			(fill no)
			(layer "F.CrtYd")
		)
		(fp_line
			(start -0.2794 -0.1016)
			(end -0.2794 0.9906)
			(stroke
				(width 0.1)
				(type default)
			)
			(layer "F.Fab")
		)
		(fp_line
			(start -0.2794 0.9906)
			(end 0.2794 0.9906)
			(stroke
				(width 0.1)
				(type default)
			)
			(layer "F.Fab")
		)
		(fp_line
			(start 0.2794 -0.1016)
			(end -0.2794 -0.1016)
			(stroke
				(width 0.1)
				(type default)
			)
			(layer "F.Fab")
		)
		(fp_line
			(start 0.2794 0.9906)
			(end 0.2794 -0.1016)
			(stroke
				(width 0.1)
				(type default)
			)
			(layer "F.Fab")
		)
		(pad "1" smd rect
			(at 0 0)
			(size 0.508 0.508)
			(layers "F.Cu" "F.Mask" "F.Paste")
			(net "JTAG_RISER_TDI_R")
		)
		(pad "2" smd rect
			(at 0 0.889)
			(size 0.508 0.508)
			(layers "F.Cu" "F.Mask" "F.Paste")
			(net "JTAG_RISER_TDI")
		)
		(zone
			(layer "F.Cu")
			(hatch none 0.5)
			(connect_pads
				(clearance 0)
			)
			(min_thickness 0.25)
			(keepout
				(tracks allowed)
				(vias not_allowed)
				(pads allowed)
				(copperpour not_allowed)
				(footprints allowed)
			)
			(placement
				(enabled no)
				(sheetname "")
			)
			(fill
				(thermal_gap 0.5)
				(thermal_bridge_width 0.5)
				(island_removal_mode 0)
			)
			(polygon
				(pts
					(xy 360.511598 -10.662158) (xy 361.019598 -10.662158) (xy 361.019598 -10.281158) (xy 360.511598 -10.281158)
				)
			)
		)
		(zone
			(layer "F.Cu")
			(hatch none 0.5)
			(connect_pads
				(clearance 0)
			)
			(min_thickness 0.25)
			(keepout
				(tracks not_allowed)
				(vias allowed)
				(pads allowed)
				(copperpour not_allowed)
				(footprints allowed)
			)
			(placement
				(enabled no)
				(sheetname "")
			)
			(fill
				(thermal_gap 0.5)
				(thermal_bridge_width 0.5)
				(island_removal_mode 0)
			)
			(polygon
				(pts
					(xy 360.511598 -10.281158) (xy 361.019598 -10.281158) (xy 361.019598 -10.662158) (xy 360.511598 -10.662158)
				)
			)
		)
	)
	(footprint ""
		(layer "F.Cu")
		(at 276.000464 -140.208 90)
		(property "Reference" "C5A19"
			(at 1.848866 0.752348 90)
			(unlocked yes)
			(layer "F.SilkS")
			(effects
				(font
					(size 1.27 0.9652)
					(thickness 0.1524)
				)
			)
		)
		(property "Value" ""
			(at 0 0 90)
			(layer "F.Fab")
			(effects
				(font
					(size 1.27 1.27)
				)
			)
		)
		(duplicate_pad_numbers_are_jumpers no)
		(fp_rect
			(start -0.500126 1.598422)
			(end 0.500126 -0.201422)
			(stroke
				(width 0)
				(type default)
			)
			(fill no)
			(layer "F.CrtYd")
		)
		(fp_line
			(start 0.500126 -0.201422)
			(end 0.500126 1.598422)
			(stroke
				(width 0.1)
				(type default)
			)
			(layer "F.Fab")
		)
		(fp_line
			(start -0.500126 -0.201422)
			(end 0.500126 -0.201422)
			(stroke
				(width 0.1)
				(type default)
			)
			(layer "F.Fab")
		)
		(fp_line
			(start 0.500126 1.598422)
			(end -0.500126 1.598422)
			(stroke
				(width 0.1)
				(type default)
			)
			(layer "F.Fab")
		)
		(fp_line
			(start -0.500126 1.598422)
			(end -0.500126 -0.201422)
			(stroke
				(width 0.1)
				(type default)
			)
			(layer "F.Fab")
		)
		(pad "1" smd rect
			(at 0 0)
			(size 0.889 0.9906)
			(layers "F.Cu" "F.Mask" "F.Paste")
			(net "PVDDQ_DEF")
		)
		(pad "2" smd rect
			(at 0 1.397)
			(size 0.889 0.9906)
			(layers "F.Cu" "F.Mask" "F.Paste")
			(net "GND")
		)
		(zone
			(layer "F.Cu")
			(hatch none 0.5)
			(connect_pads
				(clearance 0)
			)
			(min_thickness 0.25)
			(keepout
				(tracks allowed)
				(vias not_allowed)
				(pads allowed)
				(copperpour not_allowed)
				(footprints allowed)
			)
			(placement
				(enabled no)
				(sheetname "")
			)
			(fill
				(thermal_gap 0.5)
				(thermal_bridge_width 0.5)
				(island_removal_mode 0)
			)
			(polygon
				(pts
					(xy 276.952964 -139.7127) (xy 276.952964 -140.7033) (xy 276.444964 -140.7033) (xy 276.444964 -139.7127)
				)
			)
		)
		(zone
			(layer "F.Cu")
			(hatch none 0.5)
			(connect_pads
				(clearance 0)
			)
			(min_thickness 0.25)
			(keepout
				(tracks not_allowed)
				(vias allowed)
				(pads allowed)
				(copperpour not_allowed)
				(footprints allowed)
			)
			(placement
				(enabled no)
				(sheetname "")
			)
			(fill
				(thermal_gap 0.5)
				(thermal_bridge_width 0.5)
				(island_removal_mode 0)
			)
			(polygon
				(pts
					(xy 276.952964 -139.7127) (xy 276.952964 -140.7033) (xy 276.444964 -140.7033) (xy 276.444964 -139.7127)
				)
			)
		)
	)
	(footprint ""
		(layer "F.Cu")
		(at 265.675872 -77.636116)
		(property "Reference" "C5D30"
			(at 0 0 0)
			(layer "F.SilkS")
			(hide yes)
			(effects
				(font
					(size 1.27 1.27)
				)
			)
		)
		(property "Value" ""
			(at 0 0 0)
			(layer "F.Fab")
			(effects
				(font
					(size 1.27 1.27)
				)
			)
		)
		(duplicate_pad_numbers_are_jumpers no)
		(fp_poly
			(pts
				(xy -0.4953 -0.2032) (xy 0.4953 -0.2032) (xy 0.4953 1.6002) (xy -0.4953 1.6002)
			)
			(stroke
				(width 0)
				(type default)
			)
			(fill no)
			(layer "F.CrtYd")
		)
		(fp_line
			(start -0.4953 -0.2032)
			(end 0.4953 -0.2032)
			(stroke
				(width 0.1)
				(type default)
			)
			(layer "F.Fab")
		)
		(fp_line
			(start -0.4953 1.6002)
			(end -0.4953 -0.2032)
			(stroke
				(width 0.1)
				(type default)
			)
			(layer "F.Fab")
		)
		(fp_line
			(start 0.4953 -0.2032)
			(end 0.4953 1.6002)
			(stroke
				(width 0.1)
				(type default)
			)
			(layer "F.Fab")
		)
		(fp_line
			(start 0.4953 1.6002)
			(end -0.4953 1.6002)
			(stroke
				(width 0.1)
				(type default)
			)
			(layer "F.Fab")
		)
		(pad "1" smd rect
			(at 0 0)
			(size 0.762 0.889)
			(layers "F.Cu" "F.Mask" "F.Paste")
			(net "PVCCIN_CPU0")
		)
		(pad "2" smd rect
			(at 0 1.397)
			(size 0.762 0.889)
			(layers "F.Cu" "F.Mask" "F.Paste")
			(net "GND")
		)
		(zone
			(layer "F.Cu")
			(hatch none 0.5)
			(connect_pads
				(clearance 0)
			)
			(min_thickness 0.25)
			(keepout
				(tracks not_allowed)
				(vias allowed)
				(pads allowed)
				(copperpour not_allowed)
				(footprints allowed)
			)
			(placement
				(enabled no)
				(sheetname "")
			)
			(fill
				(thermal_gap 0.5)
				(thermal_bridge_width 0.5)
				(island_removal_mode 0)
			)
			(polygon
				(pts
					(xy 265.294872 -77.191616) (xy 266.056872 -77.191616) (xy 266.056872 -76.683616) (xy 265.294872 -76.683616)
				)
			)
		)
	)
	(footprint ""
		(layer "F.Cu")
		(at 272.861532 -140.208 90)
		(property "Reference" "C5A18"
			(at 1.848866 0.752348 90)
			(unlocked yes)
			(layer "F.SilkS")
			(effects
				(font
					(size 1.27 0.9652)
					(thickness 0.1524)
				)
			)
		)
		(property "Value" ""
			(at 0 0 90)
			(layer "F.Fab")
			(effects
				(font
					(size 1.27 1.27)
				)
			)
		)
		(duplicate_pad_numbers_are_jumpers no)
		(fp_rect
			(start -0.500126 1.598422)
			(end 0.500126 -0.201422)
			(stroke
				(width 0)
				(type default)
			)
			(fill no)
			(layer "F.CrtYd")
		)
		(fp_line
			(start 0.500126 -0.201422)
			(end 0.500126 1.598422)
			(stroke
				(width 0.1)
				(type default)
			)
			(layer "F.Fab")
		)
		(fp_line
			(start -0.500126 -0.201422)
			(end 0.500126 -0.201422)
			(stroke
				(width 0.1)
				(type default)
			)
			(layer "F.Fab")
		)
		(fp_line
			(start 0.500126 1.598422)
			(end -0.500126 1.598422)
			(stroke
				(width 0.1)
				(type default)
			)
			(layer "F.Fab")
		)
		(fp_line
			(start -0.500126 1.598422)
			(end -0.500126 -0.201422)
			(stroke
				(width 0.1)
				(type default)
			)
			(layer "F.Fab")
		)
		(pad "1" smd rect
			(at 0 0)
			(size 0.889 0.9906)
			(layers "F.Cu" "F.Mask" "F.Paste")
			(net "PVDDQ_DEF")
		)
		(pad "2" smd rect
			(at 0 1.397)
			(size 0.889 0.9906)
			(layers "F.Cu" "F.Mask" "F.Paste")
			(net "GND")
		)
		(zone
			(layer "F.Cu")
			(hatch none 0.5)
			(connect_pads
				(clearance 0)
			)
			(min_thickness 0.25)
			(keepout
				(tracks allowed)
				(vias not_allowed)
				(pads allowed)
				(copperpour not_allowed)
				(footprints allowed)
			)
			(placement
				(enabled no)
				(sheetname "")
			)
			(fill
				(thermal_gap 0.5)
				(thermal_bridge_width 0.5)
				(island_removal_mode 0)
			)
			(polygon
				(pts
					(xy 273.814032 -139.7127) (xy 273.814032 -140.7033) (xy 273.306032 -140.7033) (xy 273.306032 -139.7127)
				)
			)
		)
		(zone
			(layer "F.Cu")
			(hatch none 0.5)
			(connect_pads
				(clearance 0)
			)
			(min_thickness 0.25)
			(keepout
				(tracks not_allowed)
				(vias allowed)
				(pads allowed)
				(copperpour not_allowed)
				(footprints allowed)
			)
			(placement
				(enabled no)
				(sheetname "")
			)
			(fill
				(thermal_gap 0.5)
				(thermal_bridge_width 0.5)
				(island_removal_mode 0)
			)
			(polygon
				(pts
					(xy 273.814032 -139.7127) (xy 273.814032 -140.7033) (xy 273.306032 -140.7033) (xy 273.306032 -139.7127)
				)
			)
		)
	)
	(footprint ""
		(layer "F.Cu")
		(at 414.059116 -53.707792 180)
		(property "Reference" "R8E20"
			(at 0 0 180)
			(layer "F.SilkS")
			(hide yes)
			(effects
				(font
					(size 1.27 1.27)
				)
			)
		)
		(property "Value" ""
			(at 0 0 180)
			(layer "F.Fab")
			(effects
				(font
					(size 1.27 1.27)
				)
			)
		)
		(duplicate_pad_numbers_are_jumpers no)
		(fp_poly
			(pts
				(xy -0.2794 -0.1016) (xy 0.2794 -0.1016) (xy 0.2794 0.9906) (xy -0.2794 0.9906)
			)
			(stroke
				(width 0)
				(type default)
			)
			(fill no)
			(layer "F.CrtYd")
		)
		(fp_line
			(start 0.2794 0.9906)
			(end 0.2794 -0.1016)
			(stroke
				(width 0.1)
				(type default)
			)
			(layer "F.Fab")
		)
		(fp_line
			(start 0.2794 -0.1016)
			(end -0.2794 -0.1016)
			(stroke
				(width 0.1)
				(type default)
			)
			(layer "F.Fab")
		)
		(fp_line
			(start -0.2794 0.9906)
			(end 0.2794 0.9906)
			(stroke
				(width 0.1)
				(type default)
			)
			(layer "F.Fab")
		)
		(fp_line
			(start -0.2794 -0.1016)
			(end -0.2794 0.9906)
			(stroke
				(width 0.1)
				(type default)
			)
			(layer "F.Fab")
		)
		(pad "1" smd rect
			(at 0 0 180)
			(size 0.508 0.508)
			(layers "F.Cu" "F.Mask" "F.Paste")
			(net "FM_BIOS_TOP_SWAP_SPKR_R")
		)
		(pad "2" smd rect
			(at 0 0.889 180)
			(size 0.508 0.508)
			(layers "F.Cu" "F.Mask" "F.Paste")
			(net "FM_BIOS_TOP_SWAP_SPKR")
		)
		(zone
			(layer "F.Cu")
			(hatch none 0.5)
			(connect_pads
				(clearance 0)
			)
			(min_thickness 0.25)
			(keepout
				(tracks not_allowed)
				(vias allowed)
				(pads allowed)
				(copperpour not_allowed)
				(footprints allowed)
			)
			(placement
				(enabled no)
				(sheetname "")
			)
			(fill
				(thermal_gap 0.5)
				(thermal_bridge_width 0.5)
				(island_removal_mode 0)
			)
			(polygon
				(pts
					(xy 414.313116 -54.342792) (xy 413.805116 -54.342792) (xy 413.805116 -53.961792) (xy 414.313116 -53.961792)
				)
			)
		)
		(zone
			(layer "F.Cu")
			(hatch none 0.5)
			(connect_pads
				(clearance 0)
			)
			(min_thickness 0.25)
			(keepout
				(tracks allowed)
				(vias not_allowed)
				(pads allowed)
				(copperpour not_allowed)
				(footprints allowed)
			)
			(placement
				(enabled no)
				(sheetname "")
			)
			(fill
				(thermal_gap 0.5)
				(thermal_bridge_width 0.5)
				(island_removal_mode 0)
			)
			(polygon
				(pts
					(xy 414.313116 -53.961792) (xy 413.805116 -53.961792) (xy 413.805116 -54.342792) (xy 414.313116 -54.342792)
				)
			)
		)
	)
	(footprint ""
		(layer "F.Cu")
		(at 263.525 -84.709)
		(property "Reference" "C5D9"
			(at 0 0 0)
			(layer "F.SilkS")
			(hide yes)
			(effects
				(font
					(size 1.27 1.27)
				)
			)
		)
		(property "Value" ""
			(at 0 0 0)
			(layer "F.Fab")
			(effects
				(font
					(size 1.27 1.27)
				)
			)
		)
		(duplicate_pad_numbers_are_jumpers no)
		(fp_poly
			(pts
				(xy -0.4953 -0.2032) (xy 0.4953 -0.2032) (xy 0.4953 1.6002) (xy -0.4953 1.6002)
			)
			(stroke
				(width 0)
				(type default)
			)
			(fill no)
			(layer "F.CrtYd")
		)
		(fp_line
			(start -0.4953 -0.2032)
			(end 0.4953 -0.2032)
			(stroke
				(width 0.1)
				(type default)
			)
			(layer "F.Fab")
		)
		(fp_line
			(start -0.4953 1.6002)
			(end -0.4953 -0.2032)
			(stroke
				(width 0.1)
				(type default)
			)
			(layer "F.Fab")
		)
		(fp_line
			(start 0.4953 -0.2032)
			(end 0.4953 1.6002)
			(stroke
				(width 0.1)
				(type default)
			)
			(layer "F.Fab")
		)
		(fp_line
			(start 0.4953 1.6002)
			(end -0.4953 1.6002)
			(stroke
				(width 0.1)
				(type default)
			)
			(layer "F.Fab")
		)
		(pad "1" smd rect
			(at 0 0)
			(size 0.762 0.889)
			(layers "F.Cu" "F.Mask" "F.Paste")
			(net "PVDDQ_DEF")
		)
		(pad "2" smd rect
			(at 0 1.397)
			(size 0.762 0.889)
			(layers "F.Cu" "F.Mask" "F.Paste")
			(net "GND")
		)
		(zone
			(layer "F.Cu")
			(hatch none 0.5)
			(connect_pads
				(clearance 0)
			)
			(min_thickness 0.25)
			(keepout
				(tracks not_allowed)
				(vias allowed)
				(pads allowed)
				(copperpour not_allowed)
				(footprints allowed)
			)
			(placement
				(enabled no)
				(sheetname "")
			)
			(fill
				(thermal_gap 0.5)
				(thermal_bridge_width 0.5)
				(island_removal_mode 0)
			)
			(polygon
				(pts
					(xy 263.144 -84.2645) (xy 263.906 -84.2645) (xy 263.906 -83.7565) (xy 263.144 -83.7565)
				)
			)
		)
	)
	(footprint ""
		(layer "F.Cu")
		(at 260.697472 -73.318116)
		(property "Reference" "C5D41"
			(at 0 0 0)
			(layer "F.SilkS")
			(hide yes)
			(effects
				(font
					(size 1.27 1.27)
				)
			)
		)
		(property "Value" ""
			(at 0 0 0)
			(layer "F.Fab")
			(effects
				(font
					(size 1.27 1.27)
				)
			)
		)
		(duplicate_pad_numbers_are_jumpers no)
		(fp_poly
			(pts
				(xy -0.4953 -0.2032) (xy 0.4953 -0.2032) (xy 0.4953 1.6002) (xy -0.4953 1.6002)
			)
			(stroke
				(width 0)
				(type default)
			)
			(fill no)
			(layer "F.CrtYd")
		)
		(fp_line
			(start -0.4953 -0.2032)
			(end 0.4953 -0.2032)
			(stroke
				(width 0.1)
				(type default)
			)
			(layer "F.Fab")
		)
		(fp_line
			(start -0.4953 1.6002)
			(end -0.4953 -0.2032)
			(stroke
				(width 0.1)
				(type default)
			)
			(layer "F.Fab")
		)
		(fp_line
			(start 0.4953 -0.2032)
			(end 0.4953 1.6002)
			(stroke
				(width 0.1)
				(type default)
			)
			(layer "F.Fab")
		)
		(fp_line
			(start 0.4953 1.6002)
			(end -0.4953 1.6002)
			(stroke
				(width 0.1)
				(type default)
			)
			(layer "F.Fab")
		)
		(pad "1" smd rect
			(at 0 0)
			(size 0.762 0.889)
			(layers "F.Cu" "F.Mask" "F.Paste")
			(net "PVCCIN_CPU0")
		)
		(pad "2" smd rect
			(at 0 1.397)
			(size 0.762 0.889)
			(layers "F.Cu" "F.Mask" "F.Paste")
			(net "GND")
		)
		(zone
			(layer "F.Cu")
			(hatch none 0.5)
			(connect_pads
				(clearance 0)
			)
			(min_thickness 0.25)
			(keepout
				(tracks not_allowed)
				(vias allowed)
				(pads allowed)
				(copperpour not_allowed)
				(footprints allowed)
			)
			(placement
				(enabled no)
				(sheetname "")
			)
			(fill
				(thermal_gap 0.5)
				(thermal_bridge_width 0.5)
				(island_removal_mode 0)
			)
			(polygon
				(pts
					(xy 260.316472 -72.873616) (xy 261.078472 -72.873616) (xy 261.078472 -72.365616) (xy 260.316472 -72.365616)
				)
			)
		)
	)
	(footprint ""
		(layer "F.Cu")
		(at 204.2668 -50.5714)
		(property "Reference" "R4E15"
			(at 0 0 0)
			(layer "F.SilkS")
			(hide yes)
			(effects
				(font
					(size 1.27 1.27)
				)
			)
		)
		(property "Value" ""
			(at 0 0 0)
			(layer "F.Fab")
			(effects
				(font
					(size 1.27 1.27)
				)
			)
		)
		(duplicate_pad_numbers_are_jumpers no)
		(fp_poly
			(pts
				(xy -0.2794 -0.1016) (xy 0.2794 -0.1016) (xy 0.2794 0.9906) (xy -0.2794 0.9906)
			)
			(stroke
				(width 0)
				(type default)
			)
			(fill no)
			(layer "F.CrtYd")
		)
		(fp_line
			(start -0.2794 -0.1016)
			(end -0.2794 0.9906)
			(stroke
				(width 0.1)
				(type default)
			)
			(layer "F.Fab")
		)
		(fp_line
			(start -0.2794 0.9906)
			(end 0.2794 0.9906)
			(stroke
				(width 0.1)
				(type default)
			)
			(layer "F.Fab")
		)
		(fp_line
			(start 0.2794 -0.1016)
			(end -0.2794 -0.1016)
			(stroke
				(width 0.1)
				(type default)
			)
			(layer "F.Fab")
		)
		(fp_line
			(start 0.2794 0.9906)
			(end 0.2794 -0.1016)
			(stroke
				(width 0.1)
				(type default)
			)
			(layer "F.Fab")
		)
		(pad "1" smd rect
			(at 0 0)
			(size 0.508 0.508)
			(layers "F.Cu" "F.Mask" "F.Paste")
			(net "VSENSE_PVCCIN_CPU0_P")
		)
		(pad "2" smd rect
			(at 0 0.889)
			(size 0.508 0.508)
			(layers "F.Cu" "F.Mask" "F.Paste")
			(net "VSENSE_PVCCIN_CPU0_N")
		)
		(zone
			(layer "F.Cu")
			(hatch none 0.5)
			(connect_pads
				(clearance 0)
			)
			(min_thickness 0.25)
			(keepout
				(tracks allowed)
				(vias not_allowed)
				(pads allowed)
				(copperpour not_allowed)
				(footprints allowed)
			)
			(placement
				(enabled no)
				(sheetname "")
			)
			(fill
				(thermal_gap 0.5)
				(thermal_bridge_width 0.5)
				(island_removal_mode 0)
			)
			(polygon
				(pts
					(xy 204.0128 -50.3174) (xy 204.5208 -50.3174) (xy 204.5208 -49.9364) (xy 204.0128 -49.9364)
				)
			)
		)
		(zone
			(layer "F.Cu")
			(hatch none 0.5)
			(connect_pads
				(clearance 0)
			)
			(min_thickness 0.25)
			(keepout
				(tracks not_allowed)
				(vias allowed)
				(pads allowed)
				(copperpour not_allowed)
				(footprints allowed)
			)
			(placement
				(enabled no)
				(sheetname "")
			)
			(fill
				(thermal_gap 0.5)
				(thermal_bridge_width 0.5)
				(island_removal_mode 0)
			)
			(polygon
				(pts
					(xy 204.0128 -49.9364) (xy 204.5208 -49.9364) (xy 204.5208 -50.3174) (xy 204.0128 -50.3174)
				)
			)
		)
	)
	(footprint ""
		(layer "F.Cu")
		(at 436.499 -19.3675)
		(property "Reference" "C10W3"
			(at -0.8382 -0.67818 0)
			(unlocked yes)
			(layer "F.SilkS")
			(effects
				(font
					(size 0.4064 0.254)
					(thickness 0.1524)
				)
				(justify left)
			)
		)
		(property "Value" ""
			(at 0 0 0)
			(layer "F.Fab")
			(effects
				(font
					(size 1.27 1.27)
				)
			)
		)
		(duplicate_pad_numbers_are_jumpers no)
		(fp_poly
			(pts
				(xy 0.3048 -0.1016) (xy 0.3048 0.9906) (xy -0.3048 0.9906) (xy -0.3048 -0.1016)
			)
			(stroke
				(width 0)
				(type default)
			)
			(fill no)
			(layer "F.CrtYd")
		)
		(fp_line
			(start -0.3048 -0.1016)
			(end -0.3048 0.9906)
			(stroke
				(width 0.1)
				(type default)
			)
			(layer "F.Fab")
		)
		(fp_line
			(start -0.3048 0.9906)
			(end 0.3048 0.9906)
			(stroke
				(width 0.1)
				(type default)
			)
			(layer "F.Fab")
		)
		(fp_line
			(start 0.3048 -0.1016)
			(end -0.3048 -0.1016)
			(stroke
				(width 0.1)
				(type default)
			)
			(layer "F.Fab")
		)
		(fp_line
			(start 0.3048 0.9906)
			(end 0.3048 -0.1016)
			(stroke
				(width 0.1)
				(type default)
			)
			(layer "F.Fab")
		)
		(pad "1" smd rect
			(at 0 0)
			(size 0.508 0.508)
			(layers "F.Cu" "F.Mask" "F.Paste")
			(net "PUMP_TACH0")
		)
		(pad "2" smd rect
			(at 0 0.889)
			(size 0.508 0.508)
			(layers "F.Cu" "F.Mask" "F.Paste")
			(net "GND")
		)
		(zone
			(layer "F.Cu")
			(hatch none 0.5)
			(connect_pads
				(clearance 0)
			)
			(min_thickness 0.25)
			(keepout
				(tracks allowed)
				(vias not_allowed)
				(pads allowed)
				(copperpour not_allowed)
				(footprints allowed)
			)
			(placement
				(enabled no)
				(sheetname "")
			)
			(fill
				(thermal_gap 0.5)
				(thermal_bridge_width 0.5)
				(island_removal_mode 0)
			)
			(polygon
				(pts
					(xy 436.245 -19.1135) (xy 436.753 -19.1135) (xy 436.753 -18.7325) (xy 436.245 -18.7325)
				)
			)
		)
		(zone
			(layer "F.Cu")
			(hatch none 0.5)
			(connect_pads
				(clearance 0)
			)
			(min_thickness 0.25)
			(keepout
				(tracks not_allowed)
				(vias allowed)
				(pads allowed)
				(copperpour not_allowed)
				(footprints allowed)
			)
			(placement
				(enabled no)
				(sheetname "")
			)
			(fill
				(thermal_gap 0.5)
				(thermal_bridge_width 0.5)
				(island_removal_mode 0)
			)
			(polygon
				(pts
					(xy 436.245 -18.7325) (xy 436.753 -18.7325) (xy 436.753 -19.1135) (xy 436.245 -19.1135)
				)
			)
		)
	)
	(footprint ""
		(layer "F.Cu")
		(at 173.8757 -126.99238 -90)
		(property "Reference" "Q4B1"
			(at 2.27838 2.98323 90)
			(unlocked yes)
			(layer "F.SilkS")
			(effects
				(font
					(size 0.7874 0.5842)
					(thickness 0.1524)
				)
				(justify left)
			)
		)
		(property "Value" ""
			(at 0 0 270)
			(layer "F.Fab")
			(effects
				(font
					(size 1.27 1.27)
				)
			)
		)
		(duplicate_pad_numbers_are_jumpers no)
		(fp_circle
			(center -0.508 -0.7874)
			(end -0.508 -0.9144)
			(stroke
				(width 0.254)
				(type default)
			)
			(fill no)
			(layer "F.SilkS")
		)
		(fp_poly
			(pts
				(xy 0.2159 1.7526) (xy 1.5621 1.7526) (xy 1.5621 -0.4572) (xy 0.2159 -0.4572)
			)
			(stroke
				(width 0)
				(type default)
			)
			(fill no)
			(layer "F.CrtYd")
		)
		(fp_line
			(start 0.2159 1.75514)
			(end 1.5621 1.75514)
			(stroke
				(width 0.1)
				(type default)
			)
			(layer "F.Fab")
		)
		(fp_line
			(start 1.5621 1.75514)
			(end 1.5621 -0.45466)
			(stroke
				(width 0.1)
				(type default)
			)
			(layer "F.Fab")
		)
		(fp_line
			(start 0.2159 -0.45466)
			(end 0.2159 1.75514)
			(stroke
				(width 0.1)
				(type default)
			)
			(layer "F.Fab")
		)
		(fp_line
			(start 1.5621 -0.45466)
			(end 0.2159 -0.45466)
			(stroke
				(width 0.1)
				(type default)
			)
			(layer "F.Fab")
		)
		(fp_circle
			(center -0.508 -0.7874)
			(end -0.508 -0.9144)
			(stroke
				(width 0.254)
				(type default)
			)
			(fill no)
			(layer "F.Fab")
		)
		(pad "1" smd rect
			(at 0 0 270)
			(size 1.016 0.381)
			(layers "F.Cu" "F.Mask" "F.Paste")
			(net "GND")
		)
		(pad "2" smd rect
			(at 0 0.65024 270)
			(size 1.016 0.381)
			(layers "F.Cu" "F.Mask" "F.Paste")
			(net "IRQ_PVDDQ_KLM_VRHOT_LVT3_N")
		)
		(pad "3" smd rect
			(at 0 1.30048 270)
			(size 1.016 0.381)
			(layers "F.Cu" "F.Mask" "F.Paste")
			(net "H_CPU1_MEMKLM_MEMHOT_G_N")
		)
		(pad "4" smd rect
			(at 1.778 1.30048 270)
			(size 1.016 0.381)
			(layers "F.Cu" "F.Mask" "F.Paste")
			(net "GND")
		)
		(pad "5" smd rect
			(at 1.778 0.65024 270)
			(size 1.016 0.381)
			(layers "F.Cu" "F.Mask" "F.Paste")
			(net "H_CPU1_MEMKLM_MEMHOT")
		)
		(pad "6" smd rect
			(at 1.778 0 270)
			(size 1.016 0.381)
			(layers "F.Cu" "F.Mask" "F.Paste")
			(net "H_CPU1_MEMKLM_MEMHOT")
		)
		(zone
			(layer "F.Cu")
			(hatch none 0.5)
			(connect_pads
				(clearance 0)
			)
			(min_thickness 0.25)
			(keepout
				(tracks allowed)
				(vias not_allowed)
				(pads allowed)
				(copperpour not_allowed)
				(footprints allowed)
			)
			(placement
				(enabled no)
				(sheetname "")
			)
			(fill
				(thermal_gap 0.5)
				(thermal_bridge_width 0.5)
				(island_removal_mode 0)
			)
			(polygon
				(pts
					(xy 174.0662 -127.50038) (xy 174.0662 -126.48438) (xy 172.3771 -126.48438) (xy 172.3771 -127.50038)
				)
			)
		)
		(zone
			(layer "F.Cu")
			(hatch none 0.5)
			(connect_pads
				(clearance 0)
			)
			(min_thickness 0.25)
			(keepout
				(tracks allowed)
				(vias not_allowed)
				(pads allowed)
				(copperpour not_allowed)
				(footprints allowed)
			)
			(placement
				(enabled no)
				(sheetname "")
			)
			(fill
				(thermal_gap 0.5)
				(thermal_bridge_width 0.5)
				(island_removal_mode 0)
			)
			(polygon
				(pts
					(xy 174.0662 -125.72238) (xy 174.0662 -124.70638) (xy 172.3771 -124.70638) (xy 172.3771 -125.72238)
				)
			)
		)
	)
	(footprint ""
		(layer "F.Cu")
		(at 479.77298 -35.5854 90)
		(property "Reference" "R1W25"
			(at -0.8382 -0.67818 90)
			(unlocked yes)
			(layer "F.SilkS")
			(effects
				(font
					(size 0.4064 0.254)
					(thickness 0.1524)
				)
				(justify left)
			)
		)
		(property "Value" ""
			(at 0 0 90)
			(layer "F.Fab")
			(effects
				(font
					(size 1.27 1.27)
				)
			)
		)
		(duplicate_pad_numbers_are_jumpers no)
		(fp_poly
			(pts
				(xy -0.2794 -0.1016) (xy 0.2794 -0.1016) (xy 0.2794 0.9906) (xy -0.2794 0.9906)
			)
			(stroke
				(width 0)
				(type default)
			)
			(fill no)
			(layer "F.CrtYd")
		)
		(fp_line
			(start 0.2794 -0.1016)
			(end -0.2794 -0.1016)
			(stroke
				(width 0.1)
				(type default)
			)
			(layer "F.Fab")
		)
		(fp_line
			(start -0.2794 -0.1016)
			(end -0.2794 0.9906)
			(stroke
				(width 0.1)
				(type default)
			)
			(layer "F.Fab")
		)
		(fp_line
			(start 0.2794 0.9906)
			(end 0.2794 -0.1016)
			(stroke
				(width 0.1)
				(type default)
			)
			(layer "F.Fab")
		)
		(fp_line
			(start -0.2794 0.9906)
			(end 0.2794 0.9906)
			(stroke
				(width 0.1)
				(type default)
			)
			(layer "F.Fab")
		)
		(pad "1" smd rect
			(at 0 0 90)
			(size 0.508 0.508)
			(layers "F.Cu" "F.Mask" "F.Paste")
			(net "PU_33P_33M_SMBADR")
		)
		(pad "2" smd rect
			(at 0 0.889 90)
			(size 0.508 0.508)
			(layers "F.Cu" "F.Mask" "F.Paste")
			(net "GND")
		)
		(zone
			(layer "F.Cu")
			(hatch none 0.5)
			(connect_pads
				(clearance 0)
			)
			(min_thickness 0.25)
			(keepout
				(tracks allowed)
				(vias not_allowed)
				(pads allowed)
				(copperpour not_allowed)
				(footprints allowed)
			)
			(placement
				(enabled no)
				(sheetname "")
			)
			(fill
				(thermal_gap 0.5)
				(thermal_bridge_width 0.5)
				(island_removal_mode 0)
			)
			(polygon
				(pts
					(xy 480.02698 -35.3314) (xy 480.02698 -35.8394) (xy 480.40798 -35.8394) (xy 480.40798 -35.3314)
				)
			)
		)
		(zone
			(layer "F.Cu")
			(hatch none 0.5)
			(connect_pads
				(clearance 0)
			)
			(min_thickness 0.25)
			(keepout
				(tracks not_allowed)
				(vias allowed)
				(pads allowed)
				(copperpour not_allowed)
				(footprints allowed)
			)
			(placement
				(enabled no)
				(sheetname "")
			)
			(fill
				(thermal_gap 0.5)
				(thermal_bridge_width 0.5)
				(island_removal_mode 0)
			)
			(polygon
				(pts
					(xy 480.40798 -35.3314) (xy 480.40798 -35.8394) (xy 480.02698 -35.8394) (xy 480.02698 -35.3314)
				)
			)
		)
	)
	(footprint ""
		(layer "F.Cu")
		(at 352.363532 12.003278 -90)
		(property "Reference" "T1P19"
			(at 0 0 270)
			(layer "F.SilkS")
			(hide yes)
			(effects
				(font
					(size 1.27 1.27)
				)
			)
		)
		(property "Value" "*"
			(at -3.302 1.12395 270)
			(unlocked yes)
			(layer "F.Fab")
			(hide yes)
			(effects
				(font
					(size 0.889 0.889)
					(thickness 0.1524)
				)
			)
		)
		(property "Device Type" "TPAD-DIFF-4P-GP_DISCRET-GB3-TPA"
			(at -3.302 -0.40005 270)
			(unlocked yes)
			(layer "F.Fab")
			(hide yes)
			(effects
				(font
					(size 0.889 0.889)
					(thickness 0.1524)
				)
			)
		)
		(duplicate_pad_numbers_are_jumpers no)
		(fp_line
			(start -2.286 2.286)
			(end 2.286 2.286)
			(stroke
				(width 0.1524)
				(type default)
			)
			(layer "F.SilkS")
		)
		(fp_line
			(start 2.286 2.286)
			(end 2.286 -2.286)
			(stroke
				(width 0.1524)
				(type default)
			)
			(layer "F.SilkS")
		)
		(fp_line
			(start -2.286 -2.286)
			(end -2.286 2.286)
			(stroke
				(width 0.1524)
				(type default)
			)
			(layer "F.SilkS")
		)
		(fp_line
			(start 2.286 -2.286)
			(end -2.286 -2.286)
			(stroke
				(width 0.1524)
				(type default)
			)
			(layer "F.SilkS")
		)
		(fp_line
			(start -2.413 -2.413)
			(end -2.413 -1.143)
			(stroke
				(width 0.4064)
				(type default)
			)
			(layer "F.SilkS")
		)
		(fp_line
			(start -1.143 -2.413)
			(end -2.413 -2.413)
			(stroke
				(width 0.4064)
				(type default)
			)
			(layer "F.SilkS")
		)
		(fp_rect
			(start -2.54 2.54)
			(end 2.54 -2.54)
			(stroke
				(width 0)
				(type default)
			)
			(fill no)
			(layer "F.CrtYd")
		)
		(fp_rect
			(start -2.54 2.54)
			(end 2.54 -2.54)
			(stroke
				(width 0)
				(type default)
			)
			(fill no)
			(layer "F.Fab")
		)
		(pad "1" thru_hole circle
			(at -1.27 -1.27 270)
			(size 1.524 1.524)
			(drill 0.9144)
			(layers "*.Cu" "*.Mask")
			(remove_unused_layers no)
			(net "L1_100OHM_6INCH_DP")
			(clearance -0.0508)
			(thermal_gap 0.127)
			(padstack
				(mode front_inner_back)
				(layer "Inner"
					(shape circle)
					(size 1.1684 1.1684)
					(clearance 0.127)
				)
				(layer "B.Cu"
					(shape circle)
					(size 1.524 1.524)
					(clearance -0.0508)
				)
			)
		)
		(pad "2" thru_hole circle
			(at 1.27 -1.27 270)
			(size 1.524 1.524)
			(drill 0.9144)
			(layers "*.Cu" "*.Mask")
			(remove_unused_layers no)
			(net "L1_100OHM_6INCH_DN")
			(clearance -0.0508)
			(thermal_gap 0.127)
			(padstack
				(mode front_inner_back)
				(layer "Inner"
					(shape circle)
					(size 1.1684 1.1684)
					(clearance 0.127)
				)
				(layer "B.Cu"
					(shape circle)
					(size 1.524 1.524)
					(clearance -0.0508)
				)
			)
		)
		(pad "GND1" thru_hole rect
			(at -1.27 1.27 270)
			(size 1.524 1.524)
			(drill 0.9144)
			(layers "*.Cu" "*.Mask")
			(remove_unused_layers no)
			(net "GND")
			(clearance -0.0508)
			(thermal_gap 0.127)
			(padstack
				(mode front_inner_back)
				(layer "Inner"
					(shape circle)
					(size 1.1684 1.1684)
					(clearance 0.127)
				)
				(layer "B.Cu"
					(shape rect)
					(size 1.524 1.524)
					(clearance -0.0508)
				)
			)
		)
		(pad "GND2" thru_hole rect
			(at 1.27 1.27 270)
			(size 1.524 1.524)
			(drill 0.9144)
			(layers "*.Cu" "*.Mask")
			(remove_unused_layers no)
			(net "GND")
			(clearance -0.0508)
			(thermal_gap 0.127)
			(padstack
				(mode front_inner_back)
				(layer "Inner"
					(shape circle)
					(size 1.1684 1.1684)
					(clearance 0.127)
				)
				(layer "B.Cu"
					(shape rect)
					(size 1.524 1.524)
					(clearance -0.0508)
				)
			)
		)
	)
	(footprint ""
		(layer "F.Cu")
		(at 411.0355 -108.966 -90)
		(property "Reference" "R2N8"
			(at 0 0 270)
			(layer "F.SilkS")
			(hide yes)
			(effects
				(font
					(size 1.27 1.27)
				)
			)
		)
		(property "Value" ""
			(at 0 0 270)
			(layer "F.Fab")
			(effects
				(font
					(size 1.27 1.27)
				)
			)
		)
		(duplicate_pad_numbers_are_jumpers no)
		(fp_poly
			(pts
				(xy -0.2794 -0.1016) (xy 0.2794 -0.1016) (xy 0.2794 0.9906) (xy -0.2794 0.9906)
			)
			(stroke
				(width 0)
				(type default)
			)
			(fill no)
			(layer "F.CrtYd")
		)
		(fp_line
			(start -0.2794 0.9906)
			(end 0.2794 0.9906)
			(stroke
				(width 0.1)
				(type default)
			)
			(layer "F.Fab")
		)
		(fp_line
			(start 0.2794 0.9906)
			(end 0.2794 -0.1016)
			(stroke
				(width 0.1)
				(type default)
			)
			(layer "F.Fab")
		)
		(fp_line
			(start -0.2794 -0.1016)
			(end -0.2794 0.9906)
			(stroke
				(width 0.1)
				(type default)
			)
			(layer "F.Fab")
		)
		(fp_line
			(start 0.2794 -0.1016)
			(end -0.2794 -0.1016)
			(stroke
				(width 0.1)
				(type default)
			)
			(layer "F.Fab")
		)
		(pad "1" smd rect
			(at 0 0 270)
			(size 0.508 0.508)
			(layers "F.Cu" "F.Mask" "F.Paste")
			(net "P3V3_STBY")
		)
		(pad "2" smd rect
			(at 0 0.889 270)
			(size 0.508 0.508)
			(layers "F.Cu" "F.Mask" "F.Paste")
			(net "SMB_SMLINK0_STBY_LVC3_SDA")
		)
		(zone
			(layer "F.Cu")
			(hatch none 0.5)
			(connect_pads
				(clearance 0)
			)
			(min_thickness 0.25)
			(keepout
				(tracks not_allowed)
				(vias allowed)
				(pads allowed)
				(copperpour not_allowed)
				(footprints allowed)
			)
			(placement
				(enabled no)
				(sheetname "")
			)
			(fill
				(thermal_gap 0.5)
				(thermal_bridge_width 0.5)
				(island_removal_mode 0)
			)
			(polygon
				(pts
					(xy 410.4005 -109.22) (xy 410.4005 -108.712) (xy 410.7815 -108.712) (xy 410.7815 -109.22)
				)
			)
		)
		(zone
			(layer "F.Cu")
			(hatch none 0.5)
			(connect_pads
				(clearance 0)
			)
			(min_thickness 0.25)
			(keepout
				(tracks allowed)
				(vias not_allowed)
				(pads allowed)
				(copperpour not_allowed)
				(footprints allowed)
			)
			(placement
				(enabled no)
				(sheetname "")
			)
			(fill
				(thermal_gap 0.5)
				(thermal_bridge_width 0.5)
				(island_removal_mode 0)
			)
			(polygon
				(pts
					(xy 410.7815 -109.22) (xy 410.7815 -108.712) (xy 410.4005 -108.712) (xy 410.4005 -109.22)
				)
			)
		)
	)
	(footprint ""
		(layer "F.Cu")
		(at 466.09 -147.1295)
		(property "Reference" "C9A4"
			(at 0 0 0)
			(layer "F.SilkS")
			(hide yes)
			(effects
				(font
					(size 1.27 1.27)
				)
			)
		)
		(property "Value" ""
			(at 0 0 0)
			(layer "F.Fab")
			(effects
				(font
					(size 1.27 1.27)
				)
			)
		)
		(duplicate_pad_numbers_are_jumpers no)
		(fp_poly
			(pts
				(xy 0.3048 -0.1016) (xy 0.3048 0.9906) (xy -0.3048 0.9906) (xy -0.3048 -0.1016)
			)
			(stroke
				(width 0)
				(type default)
			)
			(fill no)
			(layer "F.CrtYd")
		)
		(fp_line
			(start -0.3048 -0.1016)
			(end -0.3048 0.9906)
			(stroke
				(width 0.1)
				(type default)
			)
			(layer "F.Fab")
		)
		(fp_line
			(start -0.3048 0.9906)
			(end 0.3048 0.9906)
			(stroke
				(width 0.1)
				(type default)
			)
			(layer "F.Fab")
		)
		(fp_line
			(start 0.3048 -0.1016)
			(end -0.3048 -0.1016)
			(stroke
				(width 0.1)
				(type default)
			)
			(layer "F.Fab")
		)
		(fp_line
			(start 0.3048 0.9906)
			(end 0.3048 -0.1016)
			(stroke
				(width 0.1)
				(type default)
			)
			(layer "F.Fab")
		)
		(pad "1" smd rect
			(at 0 0)
			(size 0.508 0.508)
			(layers "F.Cu" "F.Mask" "F.Paste")
			(net "XDP_CPU_PWR_DEBUG_N")
		)
		(pad "2" smd rect
			(at 0 0.889)
			(size 0.508 0.508)
			(layers "F.Cu" "F.Mask" "F.Paste")
			(net "GND")
		)
		(zone
			(layer "F.Cu")
			(hatch none 0.5)
			(connect_pads
				(clearance 0)
			)
			(min_thickness 0.25)
			(keepout
				(tracks allowed)
				(vias not_allowed)
				(pads allowed)
				(copperpour not_allowed)
				(footprints allowed)
			)
			(placement
				(enabled no)
				(sheetname "")
			)
			(fill
				(thermal_gap 0.5)
				(thermal_bridge_width 0.5)
				(island_removal_mode 0)
			)
			(polygon
				(pts
					(xy 465.836 -146.8755) (xy 466.344 -146.8755) (xy 466.344 -146.4945) (xy 465.836 -146.4945)
				)
			)
		)
		(zone
			(layer "F.Cu")
			(hatch none 0.5)
			(connect_pads
				(clearance 0)
			)
			(min_thickness 0.25)
			(keepout
				(tracks not_allowed)
				(vias allowed)
				(pads allowed)
				(copperpour not_allowed)
				(footprints allowed)
			)
			(placement
				(enabled no)
				(sheetname "")
			)
			(fill
				(thermal_gap 0.5)
				(thermal_bridge_width 0.5)
				(island_removal_mode 0)
			)
			(polygon
				(pts
					(xy 465.836 -146.4945) (xy 466.344 -146.4945) (xy 466.344 -146.8755) (xy 465.836 -146.8755)
				)
			)
		)
	)
	(footprint ""
		(layer "F.Cu")
		(at 78.735174 -26.591006 -45)
		(property "Reference" "C2F1"
			(at 0 0 315)
			(layer "F.SilkS")
			(hide yes)
			(effects
				(font
					(size 1.27 1.27)
				)
			)
		)
		(property "Value" ""
			(at 0 0 315)
			(layer "F.Fab")
			(effects
				(font
					(size 1.27 1.27)
				)
			)
		)
		(duplicate_pad_numbers_are_jumpers no)
		(fp_poly
			(pts
				(xy -0.500021 -0.201359) (xy 0.500231 -0.201359) (xy 0.500231 1.598486) (xy -0.500021 1.598486)
			)
			(stroke
				(width 0)
				(type default)
			)
			(fill no)
			(layer "F.CrtYd")
		)
		(fp_line
			(start -0.500021 1.598486)
			(end -0.5002 -0.201337)
			(stroke
				(width 0.1)
				(type default)
			)
			(layer "F.Fab")
		)
		(fp_line
			(start 0.500021 1.598486)
			(end -0.500021 1.598486)
			(stroke
				(width 0.1)
				(type default)
			)
			(layer "F.Fab")
		)
		(fp_line
			(start -0.5002 -0.201337)
			(end 0.5002 -0.201337)
			(stroke
				(width 0.1)
				(type default)
			)
			(layer "F.Fab")
		)
		(fp_line
			(start 0.5002 -0.201337)
			(end 0.500021 1.598486)
			(stroke
				(width 0.1)
				(type default)
			)
			(layer "F.Fab")
		)
		(pad "1" smd rect
			(at 0 0 225)
			(size 0.889 0.9906)
			(layers "F.Cu" "F.Mask" "F.Paste")
			(net "PVDDQ_GHJ")
		)
		(pad "2" smd rect
			(at 0 1.397 225)
			(size 0.889 0.9906)
			(layers "F.Cu" "F.Mask" "F.Paste")
			(net "GND")
		)
		(zone
			(layer "F.Cu")
			(hatch none 0.5)
			(connect_pads
				(clearance 0)
			)
			(min_thickness 0.25)
			(keepout
				(tracks allowed)
				(vias not_allowed)
				(pads allowed)
				(copperpour not_allowed)
				(footprints allowed)
			)
			(placement
				(enabled no)
				(sheetname "")
			)
			(fill
				(thermal_gap 0.5)
				(thermal_bridge_width 0.5)
				(island_removal_mode 0)
			)
			(polygon
				(pts
					(xy 77.7113 -26.267664) (xy 78.41176 -25.567204) (xy 78.77097 -25.926414) (xy 78.07051 -26.626874)
				)
			)
		)
		(zone
			(layer "F.Cu")
			(hatch none 0.5)
			(connect_pads
				(clearance 0)
			)
			(min_thickness 0.25)
			(keepout
				(tracks not_allowed)
				(vias allowed)
				(pads allowed)
				(copperpour not_allowed)
				(footprints allowed)
			)
			(placement
				(enabled no)
				(sheetname "")
			)
			(fill
				(thermal_gap 0.5)
				(thermal_bridge_width 0.5)
				(island_removal_mode 0)
			)
			(polygon
				(pts
					(xy 77.7113 -26.267664) (xy 78.41176 -25.567204) (xy 78.77097 -25.926414) (xy 78.07051 -26.626874)
				)
			)
		)
	)
	(footprint ""
		(layer "F.Cu")
		(at 324.5485 -122.555 90)
		(property "Reference" "C6B8"
			(at -0.8382 -0.67818 90)
			(unlocked yes)
			(layer "F.SilkS")
			(effects
				(font
					(size 0.4064 0.254)
					(thickness 0.1524)
				)
				(justify left)
			)
		)
		(property "Value" ""
			(at 0 0 90)
			(layer "F.Fab")
			(effects
				(font
					(size 1.27 1.27)
				)
			)
		)
		(duplicate_pad_numbers_are_jumpers no)
		(fp_poly
			(pts
				(xy 0.3048 -0.1016) (xy 0.3048 0.9906) (xy -0.3048 0.9906) (xy -0.3048 -0.1016)
			)
			(stroke
				(width 0)
				(type default)
			)
			(fill no)
			(layer "F.CrtYd")
		)
		(fp_line
			(start 0.3048 -0.1016)
			(end -0.3048 -0.1016)
			(stroke
				(width 0.1)
				(type default)
			)
			(layer "F.Fab")
		)
		(fp_line
			(start -0.3048 -0.1016)
			(end -0.3048 0.9906)
			(stroke
				(width 0.1)
				(type default)
			)
			(layer "F.Fab")
		)
		(fp_line
			(start 0.3048 0.9906)
			(end 0.3048 -0.1016)
			(stroke
				(width 0.1)
				(type default)
			)
			(layer "F.Fab")
		)
		(fp_line
			(start -0.3048 0.9906)
			(end 0.3048 0.9906)
			(stroke
				(width 0.1)
				(type default)
			)
			(layer "F.Fab")
		)
		(pad "1" smd rect
			(at 0 0 90)
			(size 0.508 0.508)
			(layers "F.Cu" "F.Mask" "F.Paste")
			(net "P3E_CPU0_PE1_PCH_TXP<14>")
		)
		(pad "2" smd rect
			(at 0 0.889 90)
			(size 0.508 0.508)
			(layers "F.Cu" "F.Mask" "F.Paste")
			(net "P3E_CPU0_PE1_PCH_C_TXP<14>")
		)
		(zone
			(layer "F.Cu")
			(hatch none 0.5)
			(connect_pads
				(clearance 0)
			)
			(min_thickness 0.25)
			(keepout
				(tracks allowed)
				(vias not_allowed)
				(pads allowed)
				(copperpour not_allowed)
				(footprints allowed)
			)
			(placement
				(enabled no)
				(sheetname "")
			)
			(fill
				(thermal_gap 0.5)
				(thermal_bridge_width 0.5)
				(island_removal_mode 0)
			)
			(polygon
				(pts
					(xy 324.8025 -122.301) (xy 324.8025 -122.809) (xy 325.1835 -122.809) (xy 325.1835 -122.301)
				)
			)
		)
		(zone
			(layer "F.Cu")
			(hatch none 0.5)
			(connect_pads
				(clearance 0)
			)
			(min_thickness 0.25)
			(keepout
				(tracks not_allowed)
				(vias allowed)
				(pads allowed)
				(copperpour not_allowed)
				(footprints allowed)
			)
			(placement
				(enabled no)
				(sheetname "")
			)
			(fill
				(thermal_gap 0.5)
				(thermal_bridge_width 0.5)
				(island_removal_mode 0)
			)
			(polygon
				(pts
					(xy 325.1835 -122.301) (xy 325.1835 -122.809) (xy 324.8025 -122.809) (xy 324.8025 -122.301)
				)
			)
		)
	)
	(footprint ""
		(layer "F.Cu")
		(at 387.35 1.651 90)
		(property "Reference" "R7G23"
			(at 0 0 90)
			(layer "F.SilkS")
			(hide yes)
			(effects
				(font
					(size 1.27 1.27)
				)
			)
		)
		(property "Value" ""
			(at 0 0 90)
			(layer "F.Fab")
			(effects
				(font
					(size 1.27 1.27)
				)
			)
		)
		(duplicate_pad_numbers_are_jumpers no)
		(fp_poly
			(pts
				(xy -0.2794 -0.1016) (xy 0.2794 -0.1016) (xy 0.2794 0.9906) (xy -0.2794 0.9906)
			)
			(stroke
				(width 0)
				(type default)
			)
			(fill no)
			(layer "F.CrtYd")
		)
		(fp_line
			(start 0.2794 -0.1016)
			(end -0.2794 -0.1016)
			(stroke
				(width 0.1)
				(type default)
			)
			(layer "F.Fab")
		)
		(fp_line
			(start -0.2794 -0.1016)
			(end -0.2794 0.9906)
			(stroke
				(width 0.1)
				(type default)
			)
			(layer "F.Fab")
		)
		(fp_line
			(start 0.2794 0.9906)
			(end 0.2794 -0.1016)
			(stroke
				(width 0.1)
				(type default)
			)
			(layer "F.Fab")
		)
		(fp_line
			(start -0.2794 0.9906)
			(end 0.2794 0.9906)
			(stroke
				(width 0.1)
				(type default)
			)
			(layer "F.Fab")
		)
		(pad "1" smd rect
			(at 0 0 90)
			(size 0.508 0.508)
			(layers "F.Cu" "F.Mask" "F.Paste")
			(net "P3V3_STBY")
		)
		(pad "2" smd rect
			(at 0 0.889 90)
			(size 0.508 0.508)
			(layers "F.Cu" "F.Mask" "F.Paste")
			(net "JTAG_TDI_R")
		)
		(zone
			(layer "F.Cu")
			(hatch none 0.5)
			(connect_pads
				(clearance 0)
			)
			(min_thickness 0.25)
			(keepout
				(tracks allowed)
				(vias not_allowed)
				(pads allowed)
				(copperpour not_allowed)
				(footprints allowed)
			)
			(placement
				(enabled no)
				(sheetname "")
			)
			(fill
				(thermal_gap 0.5)
				(thermal_bridge_width 0.5)
				(island_removal_mode 0)
			)
			(polygon
				(pts
					(xy 387.604 1.905) (xy 387.604 1.397) (xy 387.985 1.397) (xy 387.985 1.905)
				)
			)
		)
		(zone
			(layer "F.Cu")
			(hatch none 0.5)
			(connect_pads
				(clearance 0)
			)
			(min_thickness 0.25)
			(keepout
				(tracks not_allowed)
				(vias allowed)
				(pads allowed)
				(copperpour not_allowed)
				(footprints allowed)
			)
			(placement
				(enabled no)
				(sheetname "")
			)
			(fill
				(thermal_gap 0.5)
				(thermal_bridge_width 0.5)
				(island_removal_mode 0)
			)
			(polygon
				(pts
					(xy 387.985 1.905) (xy 387.985 1.397) (xy 387.604 1.397) (xy 387.604 1.905)
				)
			)
		)
	)
	(footprint ""
		(layer "F.Cu")
		(at 198.877936 -122.301)
		(property "Reference" "C4B13"
			(at 3.2512 10.18667 0)
			(unlocked yes)
			(layer "F.SilkS")
			(effects
				(font
					(size 0.7874 0.5842)
					(thickness 0.1524)
				)
			)
		)
		(property "Value" ""
			(at 0 0 0)
			(layer "F.Fab")
			(effects
				(font
					(size 1.27 1.27)
				)
			)
		)
		(duplicate_pad_numbers_are_jumpers no)
		(fp_line
			(start -5.1435 -0.127)
			(end -4.3815 -1.016)
			(stroke
				(width 0.1524)
				(type default)
			)
			(layer "F.SilkS")
		)
		(fp_line
			(start -5.1435 9.271)
			(end -5.1435 -0.127)
			(stroke
				(width 0.1524)
				(type default)
			)
			(layer "F.SilkS")
		)
		(fp_line
			(start -4.3815 -1.016)
			(end -1.8415 -1.016)
			(stroke
				(width 0.1524)
				(type default)
			)
			(layer "F.SilkS")
		)
		(fp_line
			(start -1.8415 -2.0955)
			(end -1.8415 2.0955)
			(stroke
				(width 0.1524)
				(type default)
			)
			(layer "F.SilkS")
		)
		(fp_line
			(start -1.8415 2.0955)
			(end -1.4097 2.0955)
			(stroke
				(width 0.1524)
				(type default)
			)
			(layer "F.SilkS")
		)
		(fp_line
			(start -1.4097 -2.0955)
			(end -1.8415 -2.0955)
			(stroke
				(width 0.1524)
				(type default)
			)
			(layer "F.SilkS")
		)
		(fp_line
			(start -1.4097 9.271)
			(end -5.1435 9.271)
			(stroke
				(width 0.1524)
				(type default)
			)
			(layer "F.SilkS")
		)
		(fp_line
			(start 1.4097 -2.0955)
			(end 1.8415 -2.0955)
			(stroke
				(width 0.1524)
				(type default)
			)
			(layer "F.SilkS")
		)
		(fp_line
			(start 1.8415 -2.0955)
			(end 1.8415 2.0955)
			(stroke
				(width 0.1524)
				(type default)
			)
			(layer "F.SilkS")
		)
		(fp_line
			(start 1.8415 -1.016)
			(end 4.3815 -1.016)
			(stroke
				(width 0.1524)
				(type default)
			)
			(layer "F.SilkS")
		)
		(fp_line
			(start 1.8415 2.0955)
			(end 1.4097 2.0955)
			(stroke
				(width 0.1524)
				(type default)
			)
			(layer "F.SilkS")
		)
		(fp_line
			(start 4.3815 -1.016)
			(end 5.1435 -0.127)
			(stroke
				(width 0.1524)
				(type default)
			)
			(layer "F.SilkS")
		)
		(fp_line
			(start 5.1435 -0.127)
			(end 5.1435 9.271)
			(stroke
				(width 0.1524)
				(type default)
			)
			(layer "F.SilkS")
		)
		(fp_line
			(start 5.1435 9.271)
			(end 1.4097 9.271)
			(stroke
				(width 0.1524)
				(type default)
			)
			(layer "F.SilkS")
		)
		(fp_poly
			(pts
				(xy -5.14604 -0.12954) (xy -4.38404 -1.01346) (xy 4.37896 -1.016) (xy 5.1435 -0.12954) (xy 5.14096 9.271)
				(xy -5.14604 9.27354)
			)
			(stroke
				(width 0)
				(type default)
			)
			(fill no)
			(layer "F.CrtYd")
		)
		(fp_line
			(start -5.1435 -0.127)
			(end -4.3815 -1.016)
			(stroke
				(width 0.1)
				(type default)
			)
			(layer "F.Fab")
		)
		(fp_line
			(start -5.1435 9.271)
			(end -5.1435 -0.127)
			(stroke
				(width 0.1)
				(type default)
			)
			(layer "F.Fab")
		)
		(fp_line
			(start -4.3815 -1.016)
			(end 4.3815 -1.016)
			(stroke
				(width 0.1)
				(type default)
			)
			(layer "F.Fab")
		)
		(fp_line
			(start 4.3815 -1.016)
			(end 5.1435 -0.127)
			(stroke
				(width 0.1)
				(type default)
			)
			(layer "F.Fab")
		)
		(fp_line
			(start 5.1435 -0.127)
			(end 5.1435 9.271)
			(stroke
				(width 0.1)
				(type default)
			)
			(layer "F.Fab")
		)
		(fp_line
			(start 5.1435 9.271)
			(end -5.1435 9.271)
			(stroke
				(width 0.1)
				(type default)
			)
			(layer "F.Fab")
		)
		(fp_circle
			(center 0 4.1275)
			(end 4.9911 4.1275)
			(stroke
				(width 0.1)
				(type default)
			)
			(fill no)
			(layer "F.Fab")
		)
		(pad "1" smd rect
			(at 0 0)
			(size 1.905 4.191)
			(layers "F.Cu" "F.Mask" "F.Paste")
			(net "P12V_STBY")
		)
		(pad "2" smd rect
			(at 0 8.255)
			(size 1.905 4.191)
			(layers "F.Cu" "F.Mask" "F.Paste")
			(net "GND")
		)
		(zone
			(layer "F.Cu")
			(hatch none 0.5)
			(connect_pads
				(clearance 0)
			)
			(min_thickness 0.25)
			(keepout
				(tracks allowed)
				(vias not_allowed)
				(pads allowed)
				(copperpour not_allowed)
				(footprints allowed)
			)
			(placement
				(enabled no)
				(sheetname "")
			)
			(fill
				(thermal_gap 0.5)
				(thermal_bridge_width 0.5)
				(island_removal_mode 0)
			)
			(polygon
				(pts
					(xy 193.734436 -113.03) (xy 204.021436 -113.03) (xy 204.021436 -122.428) (xy 203.259436 -123.317)
					(xy 194.496436 -123.317) (xy 193.734436 -122.428)
				)
			)
		)
	)
	(footprint ""
		(layer "F.Cu")
		(at 110.70844 -73.318116)
		(property "Reference" "C3D19"
			(at 0 0 0)
			(layer "F.SilkS")
			(hide yes)
			(effects
				(font
					(size 1.27 1.27)
				)
			)
		)
		(property "Value" ""
			(at 0 0 0)
			(layer "F.Fab")
			(effects
				(font
					(size 1.27 1.27)
				)
			)
		)
		(duplicate_pad_numbers_are_jumpers no)
		(fp_poly
			(pts
				(xy -0.4953 -0.2032) (xy 0.4953 -0.2032) (xy 0.4953 1.6002) (xy -0.4953 1.6002)
			)
			(stroke
				(width 0)
				(type default)
			)
			(fill no)
			(layer "F.CrtYd")
		)
		(fp_line
			(start -0.4953 -0.2032)
			(end 0.4953 -0.2032)
			(stroke
				(width 0.1)
				(type default)
			)
			(layer "F.Fab")
		)
		(fp_line
			(start -0.4953 1.6002)
			(end -0.4953 -0.2032)
			(stroke
				(width 0.1)
				(type default)
			)
			(layer "F.Fab")
		)
		(fp_line
			(start 0.4953 -0.2032)
			(end 0.4953 1.6002)
			(stroke
				(width 0.1)
				(type default)
			)
			(layer "F.Fab")
		)
		(fp_line
			(start 0.4953 1.6002)
			(end -0.4953 1.6002)
			(stroke
				(width 0.1)
				(type default)
			)
			(layer "F.Fab")
		)
		(pad "1" smd rect
			(at 0 0)
			(size 0.762 0.889)
			(layers "F.Cu" "F.Mask" "F.Paste")
			(net "PVCCMCP_CPU1")
		)
		(pad "2" smd rect
			(at 0 1.397)
			(size 0.762 0.889)
			(layers "F.Cu" "F.Mask" "F.Paste")
			(net "GND")
		)
		(zone
			(layer "F.Cu")
			(hatch none 0.5)
			(connect_pads
				(clearance 0)
			)
			(min_thickness 0.25)
			(keepout
				(tracks not_allowed)
				(vias allowed)
				(pads allowed)
				(copperpour not_allowed)
				(footprints allowed)
			)
			(placement
				(enabled no)
				(sheetname "")
			)
			(fill
				(thermal_gap 0.5)
				(thermal_bridge_width 0.5)
				(island_removal_mode 0)
			)
			(polygon
				(pts
					(xy 110.32744 -72.873616) (xy 111.08944 -72.873616) (xy 111.08944 -72.365616) (xy 110.32744 -72.365616)
				)
			)
		)
	)
	(footprint ""
		(layer "F.Cu")
		(at 201.671936 11.952478 -90)
		(property "Reference" "T1P1"
			(at 0 0 270)
			(layer "F.SilkS")
			(hide yes)
			(effects
				(font
					(size 1.27 1.27)
				)
			)
		)
		(property "Value" "*"
			(at -3.302 1.12395 270)
			(unlocked yes)
			(layer "F.Fab")
			(hide yes)
			(effects
				(font
					(size 0.889 0.889)
					(thickness 0.1524)
				)
			)
		)
		(property "Device Type" "TPAD-DIFF-4P-GP_DISCRET-GB3-TPA"
			(at -3.302 -0.40005 270)
			(unlocked yes)
			(layer "F.Fab")
			(hide yes)
			(effects
				(font
					(size 0.889 0.889)
					(thickness 0.1524)
				)
			)
		)
		(duplicate_pad_numbers_are_jumpers no)
		(fp_line
			(start -2.286 2.286)
			(end 2.286 2.286)
			(stroke
				(width 0.1524)
				(type default)
			)
			(layer "F.SilkS")
		)
		(fp_line
			(start 2.286 2.286)
			(end 2.286 -2.286)
			(stroke
				(width 0.1524)
				(type default)
			)
			(layer "F.SilkS")
		)
		(fp_line
			(start -2.286 -2.286)
			(end -2.286 2.286)
			(stroke
				(width 0.1524)
				(type default)
			)
			(layer "F.SilkS")
		)
		(fp_line
			(start 2.286 -2.286)
			(end -2.286 -2.286)
			(stroke
				(width 0.1524)
				(type default)
			)
			(layer "F.SilkS")
		)
		(fp_line
			(start -2.413 -2.413)
			(end -2.413 -1.143)
			(stroke
				(width 0.4064)
				(type default)
			)
			(layer "F.SilkS")
		)
		(fp_line
			(start -1.143 -2.413)
			(end -2.413 -2.413)
			(stroke
				(width 0.4064)
				(type default)
			)
			(layer "F.SilkS")
		)
		(fp_rect
			(start -2.54 2.54)
			(end 2.54 -2.54)
			(stroke
				(width 0)
				(type default)
			)
			(fill no)
			(layer "F.CrtYd")
		)
		(fp_rect
			(start -2.54 2.54)
			(end 2.54 -2.54)
			(stroke
				(width 0)
				(type default)
			)
			(fill no)
			(layer "F.Fab")
		)
		(pad "1" thru_hole circle
			(at -1.27 -1.27 270)
			(size 1.524 1.524)
			(drill 0.9144)
			(layers "*.Cu" "*.Mask")
			(remove_unused_layers no)
			(net "L1_85OHM_6INCH_DP")
			(clearance -0.0508)
			(thermal_gap 0.127)
			(padstack
				(mode front_inner_back)
				(layer "Inner"
					(shape circle)
					(size 1.1684 1.1684)
					(clearance 0.127)
				)
				(layer "B.Cu"
					(shape circle)
					(size 1.524 1.524)
					(clearance -0.0508)
				)
			)
		)
		(pad "2" thru_hole circle
			(at 1.27 -1.27 270)
			(size 1.524 1.524)
			(drill 0.9144)
			(layers "*.Cu" "*.Mask")
			(remove_unused_layers no)
			(net "L1_85OHM_6INCH_DN")
			(clearance -0.0508)
			(thermal_gap 0.127)
			(padstack
				(mode front_inner_back)
				(layer "Inner"
					(shape circle)
					(size 1.1684 1.1684)
					(clearance 0.127)
				)
				(layer "B.Cu"
					(shape circle)
					(size 1.524 1.524)
					(clearance -0.0508)
				)
			)
		)
		(pad "GND1" thru_hole rect
			(at -1.27 1.27 270)
			(size 1.524 1.524)
			(drill 0.9144)
			(layers "*.Cu" "*.Mask")
			(remove_unused_layers no)
			(net "GND")
			(clearance -0.0508)
			(thermal_gap 0.127)
			(padstack
				(mode front_inner_back)
				(layer "Inner"
					(shape circle)
					(size 1.1684 1.1684)
					(clearance 0.127)
				)
				(layer "B.Cu"
					(shape rect)
					(size 1.524 1.524)
					(clearance -0.0508)
				)
			)
		)
		(pad "GND2" thru_hole rect
			(at 1.27 1.27 270)
			(size 1.524 1.524)
			(drill 0.9144)
			(layers "*.Cu" "*.Mask")
			(remove_unused_layers no)
			(net "GND")
			(clearance -0.0508)
			(thermal_gap 0.127)
			(padstack
				(mode front_inner_back)
				(layer "Inner"
					(shape circle)
					(size 1.1684 1.1684)
					(clearance 0.127)
				)
				(layer "B.Cu"
					(shape rect)
					(size 1.524 1.524)
					(clearance -0.0508)
				)
			)
		)
	)
	(footprint ""
		(layer "F.Cu")
		(at 171.9834 -138.1125 -90)
		(property "Reference" "L4A1"
			(at -4.43103 4.191 0)
			(unlocked yes)
			(layer "F.SilkS")
			(effects
				(font
					(size 0.7874 0.5842)
					(thickness 0.1524)
				)
				(justify left)
			)
		)
		(property "Value" ""
			(at 0 0 270)
			(layer "F.Fab")
			(effects
				(font
					(size 1.27 1.27)
				)
			)
		)
		(duplicate_pad_numbers_are_jumpers no)
		(fp_line
			(start -3.4036 6.1341)
			(end -3.4036 -0.6731)
			(stroke
				(width 0.1524)
				(type default)
			)
			(layer "F.SilkS")
		)
		(fp_line
			(start -2.5654 6.1341)
			(end -3.4036 6.1341)
			(stroke
				(width 0.1524)
				(type default)
			)
			(layer "F.SilkS")
		)
		(fp_line
			(start 3.4036 6.1341)
			(end 2.5654 6.1341)
			(stroke
				(width 0.1524)
				(type default)
			)
			(layer "F.SilkS")
		)
		(fp_line
			(start -3.4036 -0.6731)
			(end -2.5654 -0.6731)
			(stroke
				(width 0.1524)
				(type default)
			)
			(layer "F.SilkS")
		)
		(fp_line
			(start 2.5654 -0.6731)
			(end 3.4036 -0.6731)
			(stroke
				(width 0.1524)
				(type default)
			)
			(layer "F.SilkS")
		)
		(fp_line
			(start 3.4036 -0.6731)
			(end 3.4036 6.1341)
			(stroke
				(width 0.1524)
				(type default)
			)
			(layer "F.SilkS")
		)
		(fp_poly
			(pts
				(xy -3.4036 -0.6731) (xy -3.4036 6.1341) (xy 3.4036 6.1341) (xy 3.4036 -0.6731)
			)
			(stroke
				(width 0)
				(type default)
			)
			(fill no)
			(layer "F.CrtYd")
		)
		(fp_line
			(start -3.4036 6.1341)
			(end -3.4036 -0.6731)
			(stroke
				(width 0.1)
				(type default)
			)
			(layer "F.Fab")
		)
		(fp_line
			(start 3.4036 6.1341)
			(end -3.4036 6.1341)
			(stroke
				(width 0.1)
				(type default)
			)
			(layer "F.Fab")
		)
		(fp_line
			(start -3.4036 -0.6731)
			(end 3.4036 -0.6731)
			(stroke
				(width 0.1)
				(type default)
			)
			(layer "F.Fab")
		)
		(fp_line
			(start 3.4036 -0.6731)
			(end 3.4036 6.1341)
			(stroke
				(width 0.1)
				(type default)
			)
			(layer "F.Fab")
		)
		(pad "1" smd rect
			(at 0 0 270)
			(size 3.556 3.175)
			(layers "F.Cu" "F.Mask" "F.Paste")
			(net "VR_PVPP_KLM_PHASE")
		)
		(pad "2" smd rect
			(at 0 5.461 270)
			(size 3.556 3.175)
			(layers "F.Cu" "F.Mask" "F.Paste")
			(net "PVPP_KLM")
		)
	)
	(footprint ""
		(layer "F.Cu")
		(at 347.778578 -101.363272 -90)
		(property "Reference" "C7C18"
			(at 0 0 270)
			(layer "F.SilkS")
			(hide yes)
			(effects
				(font
					(size 1.27 1.27)
				)
			)
		)
		(property "Value" ""
			(at 0 0 270)
			(layer "F.Fab")
			(effects
				(font
					(size 1.27 1.27)
				)
			)
		)
		(duplicate_pad_numbers_are_jumpers no)
		(fp_poly
			(pts
				(xy 0.3048 -0.1016) (xy 0.3048 0.9906) (xy -0.3048 0.9906) (xy -0.3048 -0.1016)
			)
			(stroke
				(width 0)
				(type default)
			)
			(fill no)
			(layer "F.CrtYd")
		)
		(fp_line
			(start -0.3048 0.9906)
			(end 0.3048 0.9906)
			(stroke
				(width 0.1)
				(type default)
			)
			(layer "F.Fab")
		)
		(fp_line
			(start 0.3048 0.9906)
			(end 0.3048 -0.1016)
			(stroke
				(width 0.1)
				(type default)
			)
			(layer "F.Fab")
		)
		(fp_line
			(start -0.3048 -0.1016)
			(end -0.3048 0.9906)
			(stroke
				(width 0.1)
				(type default)
			)
			(layer "F.Fab")
		)
		(fp_line
			(start 0.3048 -0.1016)
			(end -0.3048 -0.1016)
			(stroke
				(width 0.1)
				(type default)
			)
			(layer "F.Fab")
		)
		(pad "1" smd rect
			(at 0 0 270)
			(size 0.508 0.508)
			(layers "F.Cu" "F.Mask" "F.Paste")
			(net "P5V_STBY")
		)
		(pad "2" smd rect
			(at 0 0.889 270)
			(size 0.508 0.508)
			(layers "F.Cu" "F.Mask" "F.Paste")
			(net "GND")
		)
		(zone
			(layer "F.Cu")
			(hatch none 0.5)
			(connect_pads
				(clearance 0)
			)
			(min_thickness 0.25)
			(keepout
				(tracks not_allowed)
				(vias allowed)
				(pads allowed)
				(copperpour not_allowed)
				(footprints allowed)
			)
			(placement
				(enabled no)
				(sheetname "")
			)
			(fill
				(thermal_gap 0.5)
				(thermal_bridge_width 0.5)
				(island_removal_mode 0)
			)
			(polygon
				(pts
					(xy 347.143578 -101.617272) (xy 347.143578 -101.109272) (xy 347.524578 -101.109272) (xy 347.524578 -101.617272)
				)
			)
		)
		(zone
			(layer "F.Cu")
			(hatch none 0.5)
			(connect_pads
				(clearance 0)
			)
			(min_thickness 0.25)
			(keepout
				(tracks allowed)
				(vias not_allowed)
				(pads allowed)
				(copperpour not_allowed)
				(footprints allowed)
			)
			(placement
				(enabled no)
				(sheetname "")
			)
			(fill
				(thermal_gap 0.5)
				(thermal_bridge_width 0.5)
				(island_removal_mode 0)
			)
			(polygon
				(pts
					(xy 347.524578 -101.617272) (xy 347.524578 -101.109272) (xy 347.143578 -101.109272) (xy 347.143578 -101.617272)
				)
			)
		)
	)
	(footprint ""
		(layer "F.Cu")
		(at 95.69704 -77.636116)
		(property "Reference" "C2D21"
			(at 0 0 0)
			(layer "F.SilkS")
			(hide yes)
			(effects
				(font
					(size 1.27 1.27)
				)
			)
		)
		(property "Value" ""
			(at 0 0 0)
			(layer "F.Fab")
			(effects
				(font
					(size 1.27 1.27)
				)
			)
		)
		(duplicate_pad_numbers_are_jumpers no)
		(fp_poly
			(pts
				(xy -0.4953 -0.2032) (xy 0.4953 -0.2032) (xy 0.4953 1.6002) (xy -0.4953 1.6002)
			)
			(stroke
				(width 0)
				(type default)
			)
			(fill no)
			(layer "F.CrtYd")
		)
		(fp_line
			(start -0.4953 -0.2032)
			(end 0.4953 -0.2032)
			(stroke
				(width 0.1)
				(type default)
			)
			(layer "F.Fab")
		)
		(fp_line
			(start -0.4953 1.6002)
			(end -0.4953 -0.2032)
			(stroke
				(width 0.1)
				(type default)
			)
			(layer "F.Fab")
		)
		(fp_line
			(start 0.4953 -0.2032)
			(end 0.4953 1.6002)
			(stroke
				(width 0.1)
				(type default)
			)
			(layer "F.Fab")
		)
		(fp_line
			(start 0.4953 1.6002)
			(end -0.4953 1.6002)
			(stroke
				(width 0.1)
				(type default)
			)
			(layer "F.Fab")
		)
		(pad "1" smd rect
			(at 0 0)
			(size 0.762 0.889)
			(layers "F.Cu" "F.Mask" "F.Paste")
			(net "PVCCIN_CPU1")
		)
		(pad "2" smd rect
			(at 0 1.397)
			(size 0.762 0.889)
			(layers "F.Cu" "F.Mask" "F.Paste")
			(net "GND")
		)
		(zone
			(layer "F.Cu")
			(hatch none 0.5)
			(connect_pads
				(clearance 0)
			)
			(min_thickness 0.25)
			(keepout
				(tracks not_allowed)
				(vias allowed)
				(pads allowed)
				(copperpour not_allowed)
				(footprints allowed)
			)
			(placement
				(enabled no)
				(sheetname "")
			)
			(fill
				(thermal_gap 0.5)
				(thermal_bridge_width 0.5)
				(island_removal_mode 0)
			)
			(polygon
				(pts
					(xy 95.31604 -77.191616) (xy 96.07804 -77.191616) (xy 96.07804 -76.683616) (xy 95.31604 -76.683616)
				)
			)
		)
	)
	(footprint ""
		(layer "F.Cu")
		(at 389.439912 -81.906364 90)
		(property "Reference" "C14W2"
			(at -0.8382 -0.67818 90)
			(unlocked yes)
			(layer "F.SilkS")
			(effects
				(font
					(size 0.4064 0.254)
					(thickness 0.1524)
				)
				(justify left)
			)
		)
		(property "Value" ""
			(at 0 0 90)
			(layer "F.Fab")
			(effects
				(font
					(size 1.27 1.27)
				)
			)
		)
		(duplicate_pad_numbers_are_jumpers no)
		(fp_poly
			(pts
				(xy 0.3048 -0.1016) (xy 0.3048 0.9906) (xy -0.3048 0.9906) (xy -0.3048 -0.1016)
			)
			(stroke
				(width 0)
				(type default)
			)
			(fill no)
			(layer "F.CrtYd")
		)
		(fp_line
			(start 0.3048 -0.1016)
			(end -0.3048 -0.1016)
			(stroke
				(width 0.1)
				(type default)
			)
			(layer "F.Fab")
		)
		(fp_line
			(start -0.3048 -0.1016)
			(end -0.3048 0.9906)
			(stroke
				(width 0.1)
				(type default)
			)
			(layer "F.Fab")
		)
		(fp_line
			(start 0.3048 0.9906)
			(end 0.3048 -0.1016)
			(stroke
				(width 0.1)
				(type default)
			)
			(layer "F.Fab")
		)
		(fp_line
			(start -0.3048 0.9906)
			(end 0.3048 0.9906)
			(stroke
				(width 0.1)
				(type default)
			)
			(layer "F.Fab")
		)
		(pad "1" smd rect
			(at 0 0 90)
			(size 0.508 0.508)
			(layers "F.Cu" "F.Mask" "F.Paste")
			(net "P3V3")
		)
		(pad "2" smd rect
			(at 0 0.889 90)
			(size 0.508 0.508)
			(layers "F.Cu" "F.Mask" "F.Paste")
			(net "GND")
		)
		(zone
			(layer "F.Cu")
			(hatch none 0.5)
			(connect_pads
				(clearance 0)
			)
			(min_thickness 0.25)
			(keepout
				(tracks allowed)
				(vias not_allowed)
				(pads allowed)
				(copperpour not_allowed)
				(footprints allowed)
			)
			(placement
				(enabled no)
				(sheetname "")
			)
			(fill
				(thermal_gap 0.5)
				(thermal_bridge_width 0.5)
				(island_removal_mode 0)
			)
			(polygon
				(pts
					(xy 389.693912 -81.652364) (xy 389.693912 -82.160364) (xy 390.074912 -82.160364) (xy 390.074912 -81.652364)
				)
			)
		)
		(zone
			(layer "F.Cu")
			(hatch none 0.5)
			(connect_pads
				(clearance 0)
			)
			(min_thickness 0.25)
			(keepout
				(tracks not_allowed)
				(vias allowed)
				(pads allowed)
				(copperpour not_allowed)
				(footprints allowed)
			)
			(placement
				(enabled no)
				(sheetname "")
			)
			(fill
				(thermal_gap 0.5)
				(thermal_bridge_width 0.5)
				(island_removal_mode 0)
			)
			(polygon
				(pts
					(xy 390.074912 -81.652364) (xy 390.074912 -82.160364) (xy 389.693912 -82.160364) (xy 389.693912 -81.652364)
				)
			)
		)
	)
	(footprint ""
		(layer "F.Cu")
		(at 99.455224 -68.641214 -90)
		(property "Reference" "C2D42"
			(at 0 0 270)
			(layer "F.SilkS")
			(hide yes)
			(effects
				(font
					(size 1.27 1.27)
				)
			)
		)
		(property "Value" ""
			(at 0 0 270)
			(layer "F.Fab")
			(effects
				(font
					(size 1.27 1.27)
				)
			)
		)
		(duplicate_pad_numbers_are_jumpers no)
		(fp_poly
			(pts
				(xy -0.4953 -0.2032) (xy 0.4953 -0.2032) (xy 0.4953 1.6002) (xy -0.4953 1.6002)
			)
			(stroke
				(width 0)
				(type default)
			)
			(fill no)
			(layer "F.CrtYd")
		)
		(fp_line
			(start -0.4953 1.6002)
			(end -0.4953 -0.2032)
			(stroke
				(width 0.1)
				(type default)
			)
			(layer "F.Fab")
		)
		(fp_line
			(start 0.4953 1.6002)
			(end -0.4953 1.6002)
			(stroke
				(width 0.1)
				(type default)
			)
			(layer "F.Fab")
		)
		(fp_line
			(start -0.4953 -0.2032)
			(end 0.4953 -0.2032)
			(stroke
				(width 0.1)
				(type default)
			)
			(layer "F.Fab")
		)
		(fp_line
			(start 0.4953 -0.2032)
			(end 0.4953 1.6002)
			(stroke
				(width 0.1)
				(type default)
			)
			(layer "F.Fab")
		)
		(pad "1" smd rect
			(at 0 0 270)
			(size 0.762 0.889)
			(layers "F.Cu" "F.Mask" "F.Paste")
			(net "PVDDQ_GHJ")
		)
		(pad "2" smd rect
			(at 0 1.397 270)
			(size 0.762 0.889)
			(layers "F.Cu" "F.Mask" "F.Paste")
			(net "GND")
		)
		(zone
			(layer "F.Cu")
			(hatch none 0.5)
			(connect_pads
				(clearance 0)
			)
			(min_thickness 0.25)
			(keepout
				(tracks not_allowed)
				(vias allowed)
				(pads allowed)
				(copperpour not_allowed)
				(footprints allowed)
			)
			(placement
				(enabled no)
				(sheetname "")
			)
			(fill
				(thermal_gap 0.5)
				(thermal_bridge_width 0.5)
				(island_removal_mode 0)
			)
			(polygon
				(pts
					(xy 99.010724 -69.022214) (xy 99.010724 -68.260214) (xy 98.502724 -68.260214) (xy 98.502724 -69.022214)
				)
			)
		)
	)
	(footprint ""
		(layer "F.Cu")
		(at 259.452872 -73.318116)
		(property "Reference" "C5D40"
			(at 0 0 0)
			(layer "F.SilkS")
			(hide yes)
			(effects
				(font
					(size 1.27 1.27)
				)
			)
		)
		(property "Value" ""
			(at 0 0 0)
			(layer "F.Fab")
			(effects
				(font
					(size 1.27 1.27)
				)
			)
		)
		(duplicate_pad_numbers_are_jumpers no)
		(fp_poly
			(pts
				(xy -0.4953 -0.2032) (xy 0.4953 -0.2032) (xy 0.4953 1.6002) (xy -0.4953 1.6002)
			)
			(stroke
				(width 0)
				(type default)
			)
			(fill no)
			(layer "F.CrtYd")
		)
		(fp_line
			(start -0.4953 -0.2032)
			(end 0.4953 -0.2032)
			(stroke
				(width 0.1)
				(type default)
			)
			(layer "F.Fab")
		)
		(fp_line
			(start -0.4953 1.6002)
			(end -0.4953 -0.2032)
			(stroke
				(width 0.1)
				(type default)
			)
			(layer "F.Fab")
		)
		(fp_line
			(start 0.4953 -0.2032)
			(end 0.4953 1.6002)
			(stroke
				(width 0.1)
				(type default)
			)
			(layer "F.Fab")
		)
		(fp_line
			(start 0.4953 1.6002)
			(end -0.4953 1.6002)
			(stroke
				(width 0.1)
				(type default)
			)
			(layer "F.Fab")
		)
		(pad "1" smd rect
			(at 0 0)
			(size 0.762 0.889)
			(layers "F.Cu" "F.Mask" "F.Paste")
			(net "PVCCIN_CPU0")
		)
		(pad "2" smd rect
			(at 0 1.397)
			(size 0.762 0.889)
			(layers "F.Cu" "F.Mask" "F.Paste")
			(net "GND")
		)
		(zone
			(layer "F.Cu")
			(hatch none 0.5)
			(connect_pads
				(clearance 0)
			)
			(min_thickness 0.25)
			(keepout
				(tracks not_allowed)
				(vias allowed)
				(pads allowed)
				(copperpour not_allowed)
				(footprints allowed)
			)
			(placement
				(enabled no)
				(sheetname "")
			)
			(fill
				(thermal_gap 0.5)
				(thermal_bridge_width 0.5)
				(island_removal_mode 0)
			)
			(polygon
				(pts
					(xy 259.071872 -72.873616) (xy 259.833872 -72.873616) (xy 259.833872 -72.365616) (xy 259.071872 -72.365616)
				)
			)
		)
	)
	(footprint ""
		(layer "F.Cu")
		(at 272.861532 -3.3528 90)
		(property "Reference" "C5G17"
			(at 1.848866 0.752348 90)
			(unlocked yes)
			(layer "F.SilkS")
			(effects
				(font
					(size 1.27 0.9652)
					(thickness 0.1524)
				)
			)
		)
		(property "Value" ""
			(at 0 0 90)
			(layer "F.Fab")
			(effects
				(font
					(size 1.27 1.27)
				)
			)
		)
		(duplicate_pad_numbers_are_jumpers no)
		(fp_rect
			(start -0.500126 1.598422)
			(end 0.500126 -0.201422)
			(stroke
				(width 0)
				(type default)
			)
			(fill no)
			(layer "F.CrtYd")
		)
		(fp_line
			(start 0.500126 -0.201422)
			(end 0.500126 1.598422)
			(stroke
				(width 0.1)
				(type default)
			)
			(layer "F.Fab")
		)
		(fp_line
			(start -0.500126 -0.201422)
			(end 0.500126 -0.201422)
			(stroke
				(width 0.1)
				(type default)
			)
			(layer "F.Fab")
		)
		(fp_line
			(start 0.500126 1.598422)
			(end -0.500126 1.598422)
			(stroke
				(width 0.1)
				(type default)
			)
			(layer "F.Fab")
		)
		(fp_line
			(start -0.500126 1.598422)
			(end -0.500126 -0.201422)
			(stroke
				(width 0.1)
				(type default)
			)
			(layer "F.Fab")
		)
		(pad "1" smd rect
			(at 0 0)
			(size 0.889 0.9906)
			(layers "F.Cu" "F.Mask" "F.Paste")
			(net "PVDDQ_ABC")
		)
		(pad "2" smd rect
			(at 0 1.397)
			(size 0.889 0.9906)
			(layers "F.Cu" "F.Mask" "F.Paste")
			(net "GND")
		)
		(zone
			(layer "F.Cu")
			(hatch none 0.5)
			(connect_pads
				(clearance 0)
			)
			(min_thickness 0.25)
			(keepout
				(tracks allowed)
				(vias not_allowed)
				(pads allowed)
				(copperpour not_allowed)
				(footprints allowed)
			)
			(placement
				(enabled no)
				(sheetname "")
			)
			(fill
				(thermal_gap 0.5)
				(thermal_bridge_width 0.5)
				(island_removal_mode 0)
			)
			(polygon
				(pts
					(xy 273.814032 -2.8575) (xy 273.814032 -3.8481) (xy 273.306032 -3.8481) (xy 273.306032 -2.8575)
				)
			)
		)
		(zone
			(layer "F.Cu")
			(hatch none 0.5)
			(connect_pads
				(clearance 0)
			)
			(min_thickness 0.25)
			(keepout
				(tracks not_allowed)
				(vias allowed)
				(pads allowed)
				(copperpour not_allowed)
				(footprints allowed)
			)
			(placement
				(enabled no)
				(sheetname "")
			)
			(fill
				(thermal_gap 0.5)
				(thermal_bridge_width 0.5)
				(island_removal_mode 0)
			)
			(polygon
				(pts
					(xy 273.814032 -2.8575) (xy 273.814032 -3.8481) (xy 273.306032 -3.8481) (xy 273.306032 -2.8575)
				)
			)
		)
	)
	(footprint ""
		(layer "F.Cu")
		(at 412.496 -18.415 90)
		(property "Reference" "C9G18"
			(at 0 0 90)
			(layer "F.SilkS")
			(hide yes)
			(effects
				(font
					(size 1.27 1.27)
				)
			)
		)
		(property "Value" ""
			(at 0 0 90)
			(layer "F.Fab")
			(effects
				(font
					(size 1.27 1.27)
				)
			)
		)
		(duplicate_pad_numbers_are_jumpers no)
		(fp_poly
			(pts
				(xy 0.3048 -0.1016) (xy 0.3048 0.9906) (xy -0.3048 0.9906) (xy -0.3048 -0.1016)
			)
			(stroke
				(width 0)
				(type default)
			)
			(fill no)
			(layer "F.CrtYd")
		)
		(fp_line
			(start 0.3048 -0.1016)
			(end -0.3048 -0.1016)
			(stroke
				(width 0.1)
				(type default)
			)
			(layer "F.Fab")
		)
		(fp_line
			(start -0.3048 -0.1016)
			(end -0.3048 0.9906)
			(stroke
				(width 0.1)
				(type default)
			)
			(layer "F.Fab")
		)
		(fp_line
			(start 0.3048 0.9906)
			(end 0.3048 -0.1016)
			(stroke
				(width 0.1)
				(type default)
			)
			(layer "F.Fab")
		)
		(fp_line
			(start -0.3048 0.9906)
			(end 0.3048 0.9906)
			(stroke
				(width 0.1)
				(type default)
			)
			(layer "F.Fab")
		)
		(pad "1" smd rect
			(at 0 0 90)
			(size 0.508 0.508)
			(layers "F.Cu" "F.Mask" "F.Paste")
			(net "A_PVNN_STBY_PCH_SENSOR")
		)
		(pad "2" smd rect
			(at 0 0.889 90)
			(size 0.508 0.508)
			(layers "F.Cu" "F.Mask" "F.Paste")
			(net "GND")
		)
		(zone
			(layer "F.Cu")
			(hatch none 0.5)
			(connect_pads
				(clearance 0)
			)
			(min_thickness 0.25)
			(keepout
				(tracks allowed)
				(vias not_allowed)
				(pads allowed)
				(copperpour not_allowed)
				(footprints allowed)
			)
			(placement
				(enabled no)
				(sheetname "")
			)
			(fill
				(thermal_gap 0.5)
				(thermal_bridge_width 0.5)
				(island_removal_mode 0)
			)
			(polygon
				(pts
					(xy 412.75 -18.161) (xy 412.75 -18.669) (xy 413.131 -18.669) (xy 413.131 -18.161)
				)
			)
		)
		(zone
			(layer "F.Cu")
			(hatch none 0.5)
			(connect_pads
				(clearance 0)
			)
			(min_thickness 0.25)
			(keepout
				(tracks not_allowed)
				(vias allowed)
				(pads allowed)
				(copperpour not_allowed)
				(footprints allowed)
			)
			(placement
				(enabled no)
				(sheetname "")
			)
			(fill
				(thermal_gap 0.5)
				(thermal_bridge_width 0.5)
				(island_removal_mode 0)
			)
			(polygon
				(pts
					(xy 413.131 -18.161) (xy 413.131 -18.669) (xy 412.75 -18.669) (xy 412.75 -18.161)
				)
			)
		)
	)
	(footprint ""
		(layer "F.Cu")
		(at 419.0492 -113.9952 180)
		(property "Reference" "R2M5"
			(at 0 0 180)
			(layer "F.SilkS")
			(hide yes)
			(effects
				(font
					(size 1.27 1.27)
				)
			)
		)
		(property "Value" ""
			(at 0 0 180)
			(layer "F.Fab")
			(effects
				(font
					(size 1.27 1.27)
				)
			)
		)
		(duplicate_pad_numbers_are_jumpers no)
		(fp_poly
			(pts
				(xy -0.2794 -0.1016) (xy 0.2794 -0.1016) (xy 0.2794 0.9906) (xy -0.2794 0.9906)
			)
			(stroke
				(width 0)
				(type default)
			)
			(fill no)
			(layer "F.CrtYd")
		)
		(fp_line
			(start 0.2794 0.9906)
			(end 0.2794 -0.1016)
			(stroke
				(width 0.1)
				(type default)
			)
			(layer "F.Fab")
		)
		(fp_line
			(start 0.2794 -0.1016)
			(end -0.2794 -0.1016)
			(stroke
				(width 0.1)
				(type default)
			)
			(layer "F.Fab")
		)
		(fp_line
			(start -0.2794 0.9906)
			(end 0.2794 0.9906)
			(stroke
				(width 0.1)
				(type default)
			)
			(layer "F.Fab")
		)
		(fp_line
			(start -0.2794 -0.1016)
			(end -0.2794 0.9906)
			(stroke
				(width 0.1)
				(type default)
			)
			(layer "F.Fab")
		)
		(pad "1" smd rect
			(at 0 0 180)
			(size 0.508 0.508)
			(layers "F.Cu" "F.Mask" "F.Paste")
			(net "P3V3_STBY")
		)
		(pad "2" smd rect
			(at 0 0.889 180)
			(size 0.508 0.508)
			(layers "F.Cu" "F.Mask" "F.Paste")
			(net "FM_BMC_CPLD_GPO")
		)
		(zone
			(layer "F.Cu")
			(hatch none 0.5)
			(connect_pads
				(clearance 0)
			)
			(min_thickness 0.25)
			(keepout
				(tracks not_allowed)
				(vias allowed)
				(pads allowed)
				(copperpour not_allowed)
				(footprints allowed)
			)
			(placement
				(enabled no)
				(sheetname "")
			)
			(fill
				(thermal_gap 0.5)
				(thermal_bridge_width 0.5)
				(island_removal_mode 0)
			)
			(polygon
				(pts
					(xy 419.3032 -114.6302) (xy 418.7952 -114.6302) (xy 418.7952 -114.2492) (xy 419.3032 -114.2492)
				)
			)
		)
		(zone
			(layer "F.Cu")
			(hatch none 0.5)
			(connect_pads
				(clearance 0)
			)
			(min_thickness 0.25)
			(keepout
				(tracks allowed)
				(vias not_allowed)
				(pads allowed)
				(copperpour not_allowed)
				(footprints allowed)
			)
			(placement
				(enabled no)
				(sheetname "")
			)
			(fill
				(thermal_gap 0.5)
				(thermal_bridge_width 0.5)
				(island_removal_mode 0)
			)
			(polygon
				(pts
					(xy 419.3032 -114.2492) (xy 418.7952 -114.2492) (xy 418.7952 -114.6302) (xy 419.3032 -114.6302)
				)
			)
		)
	)
	(footprint ""
		(layer "F.Cu")
		(at 323.516498 -128.013714 180)
		(property "Reference" "R6B4"
			(at 0 0 180)
			(layer "F.SilkS")
			(hide yes)
			(effects
				(font
					(size 1.27 1.27)
				)
			)
		)
		(property "Value" ""
			(at 0 0 180)
			(layer "F.Fab")
			(effects
				(font
					(size 1.27 1.27)
				)
			)
		)
		(duplicate_pad_numbers_are_jumpers no)
		(fp_poly
			(pts
				(xy -0.2794 -0.1016) (xy 0.2794 -0.1016) (xy 0.2794 0.9906) (xy -0.2794 0.9906)
			)
			(stroke
				(width 0)
				(type default)
			)
			(fill no)
			(layer "F.CrtYd")
		)
		(fp_line
			(start 0.2794 0.9906)
			(end 0.2794 -0.1016)
			(stroke
				(width 0.1)
				(type default)
			)
			(layer "F.Fab")
		)
		(fp_line
			(start 0.2794 -0.1016)
			(end -0.2794 -0.1016)
			(stroke
				(width 0.1)
				(type default)
			)
			(layer "F.Fab")
		)
		(fp_line
			(start -0.2794 0.9906)
			(end 0.2794 0.9906)
			(stroke
				(width 0.1)
				(type default)
			)
			(layer "F.Fab")
		)
		(fp_line
			(start -0.2794 -0.1016)
			(end -0.2794 0.9906)
			(stroke
				(width 0.1)
				(type default)
			)
			(layer "F.Fab")
		)
		(pad "1" smd rect
			(at 0 0 180)
			(size 0.508 0.508)
			(layers "F.Cu" "F.Mask" "F.Paste")
			(net "SVID_DIO1_CPU0")
		)
		(pad "2" smd rect
			(at 0 0.889 180)
			(size 0.508 0.508)
			(layers "F.Cu" "F.Mask" "F.Paste")
			(net "SVID_DIO1_CPU0_R")
		)
		(zone
			(layer "F.Cu")
			(hatch none 0.5)
			(connect_pads
				(clearance 0)
			)
			(min_thickness 0.25)
			(keepout
				(tracks not_allowed)
				(vias allowed)
				(pads allowed)
				(copperpour not_allowed)
				(footprints allowed)
			)
			(placement
				(enabled no)
				(sheetname "")
			)
			(fill
				(thermal_gap 0.5)
				(thermal_bridge_width 0.5)
				(island_removal_mode 0)
			)
			(polygon
				(pts
					(xy 323.770498 -128.648714) (xy 323.262498 -128.648714) (xy 323.262498 -128.267714) (xy 323.770498 -128.267714)
				)
			)
		)
		(zone
			(layer "F.Cu")
			(hatch none 0.5)
			(connect_pads
				(clearance 0)
			)
			(min_thickness 0.25)
			(keepout
				(tracks allowed)
				(vias not_allowed)
				(pads allowed)
				(copperpour not_allowed)
				(footprints allowed)
			)
			(placement
				(enabled no)
				(sheetname "")
			)
			(fill
				(thermal_gap 0.5)
				(thermal_bridge_width 0.5)
				(island_removal_mode 0)
			)
			(polygon
				(pts
					(xy 323.770498 -128.267714) (xy 323.262498 -128.267714) (xy 323.262498 -128.648714) (xy 323.770498 -128.648714)
				)
			)
		)
	)
	(footprint ""
		(layer "F.Cu")
		(at 469.3412 -14.317472 -90)
		(property "Reference" "L8F1"
			(at 0 0 270)
			(layer "F.SilkS")
			(hide yes)
			(effects
				(font
					(size 1.27 1.27)
				)
			)
		)
		(property "Value" "*"
			(at 5.9436 -5.842 270)
			(unlocked yes)
			(layer "F.Fab")
			(hide yes)
			(effects
				(font
					(size 1.27 1.016)
					(thickness 0.1524)
				)
			)
		)
		(property "Device Type" "IND-1UH-361-GP_DISCRET-GC1-INDA"
			(at 5.9436 -7.366 270)
			(unlocked yes)
			(layer "F.Fab")
			(hide yes)
			(effects
				(font
					(size 1.27 1.016)
					(thickness 0.1524)
				)
			)
		)
		(duplicate_pad_numbers_are_jumpers no)
		(fp_line
			(start -4.0005 4.6101)
			(end -4.0005 -4.6101)
			(stroke
				(width 0.1524)
				(type default)
			)
			(layer "F.SilkS")
		)
		(fp_line
			(start 4.0005 4.6101)
			(end -4.0005 4.6101)
			(stroke
				(width 0.1524)
				(type default)
			)
			(layer "F.SilkS")
		)
		(fp_line
			(start -4.0005 -4.6101)
			(end 4.0005 -4.6101)
			(stroke
				(width 0.1524)
				(type default)
			)
			(layer "F.SilkS")
		)
		(fp_line
			(start 4.0005 -4.6101)
			(end 4.0005 4.6101)
			(stroke
				(width 0.1524)
				(type default)
			)
			(layer "F.SilkS")
		)
		(fp_rect
			(start -3.7465 3.5941)
			(end 3.7465 -3.5941)
			(stroke
				(width 0)
				(type default)
			)
			(fill no)
			(layer "F.CrtYd")
		)
		(fp_poly
			(pts
				(xy -4.2545 4.6863) (xy -4.2545 3.5941) (xy 3.7465 3.5941) (xy 3.7465 -3.5941) (xy -3.7465 -3.5941)
				(xy -3.7465 3.5814) (xy -4.2545 3.5814) (xy -4.2545 -4.6863) (xy 4.2545 -4.6863) (xy 4.2545 4.6863)
			)
			(stroke
				(width 0)
				(type default)
			)
			(fill no)
			(layer "F.CrtYd")
		)
		(fp_rect
			(start -4.2545 4.6863)
			(end 4.2545 -4.6863)
			(stroke
				(width 0)
				(type default)
			)
			(fill no)
			(layer "F.Fab")
		)
		(pad "1" smd rect
			(at 0 -3.039872 270)
			(size 5.5118 2.6416)
			(layers "F.Cu" "F.Mask" "F.Paste")
			(net "VR_P3V3_STBY_PHASE")
		)
		(pad "2" smd rect
			(at 0 3.039872 270)
			(size 5.5118 2.6416)
			(layers "F.Cu" "F.Mask" "F.Paste")
			(net "P3V3_STBY")
		)
	)
	(footprint ""
		(layer "F.Cu")
		(at 483.6414 -125.222 -90)
		(property "Reference" "J9B2"
			(at 2.69367 0.889 0)
			(unlocked yes)
			(layer "B.SilkS")
			(effects
				(font
					(size 0.7874 0.5842)
					(thickness 0.1524)
				)
				(justify left mirror)
			)
		)
		(property "Value" ""
			(at 0 0 270)
			(layer "F.Fab")
			(effects
				(font
					(size 1.27 1.27)
				)
			)
		)
		(duplicate_pad_numbers_are_jumpers no)
		(fp_line
			(start -1.27 6.54939)
			(end -1.27 -1.46939)
			(stroke
				(width 0.1524)
				(type default)
			)
			(layer "F.SilkS")
		)
		(fp_line
			(start 1.27 6.54939)
			(end -1.27 6.54939)
			(stroke
				(width 0.1524)
				(type default)
			)
			(layer "F.SilkS")
		)
		(fp_line
			(start -1.27 -1.46939)
			(end 1.27 -1.46939)
			(stroke
				(width 0.1524)
				(type default)
			)
			(layer "F.SilkS")
		)
		(fp_line
			(start 1.27 -1.46939)
			(end 1.27 6.54939)
			(stroke
				(width 0.1524)
				(type default)
			)
			(layer "F.SilkS")
		)
		(fp_poly
			(pts
				(xy -3.17246 0.38862) (xy -3.17246 -0.62738) (xy -1.90246 -0.11938)
			)
			(stroke
				(width 0)
				(type default)
			)
			(fill yes)
			(layer "F.SilkS")
		)
		(fp_poly
			(pts
				(xy -3.17246 0.38862) (xy -3.17246 -0.62738) (xy -1.90246 -0.11938)
			)
			(stroke
				(width 0)
				(type default)
			)
			(fill yes)
			(layer "B.SilkS")
		)
		(fp_poly
			(pts
				(xy 1.27 6.54939) (xy 1.27 -1.46939) (xy -1.27 -1.46939) (xy -1.27 6.54939)
			)
			(stroke
				(width 0)
				(type default)
			)
			(fill no)
			(layer "F.CrtYd")
		)
		(fp_poly
			(pts
				(xy -3.17246 0.38862) (xy -3.17246 -0.62738) (xy -1.90246 -0.11938)
			)
			(stroke
				(width 0)
				(type default)
			)
			(fill yes)
			(layer "B.Fab")
		)
		(fp_line
			(start -1.27 6.54939)
			(end -1.27 -1.46939)
			(stroke
				(width 0.1)
				(type default)
			)
			(layer "F.Fab")
		)
		(fp_line
			(start 1.27 6.54939)
			(end -1.27 6.54939)
			(stroke
				(width 0.1)
				(type default)
			)
			(layer "F.Fab")
		)
		(fp_line
			(start -1.27 -1.46939)
			(end 1.27 -1.46939)
			(stroke
				(width 0.1)
				(type default)
			)
			(layer "F.Fab")
		)
		(fp_line
			(start 1.27 -1.46939)
			(end 1.27 6.54939)
			(stroke
				(width 0.1)
				(type default)
			)
			(layer "F.Fab")
		)
		(fp_poly
			(pts
				(xy -3.17246 0.38862) (xy -3.17246 -0.62738) (xy -1.90246 -0.11938)
			)
			(stroke
				(width 0)
				(type default)
			)
			(fill yes)
			(layer "F.Fab")
		)
		(fp_text user "3"
			(at 0.188976 7.44728 0)
			(unlocked yes)
			(layer "F.SilkS")
			(effects
				(font
					(size 0.7874 0.5842)
					(thickness 0.1524)
				)
				(justify left)
			)
		)
		(fp_text user "3"
			(at -1.60655 3.38582 0)
			(unlocked yes)
			(layer "B.SilkS")
			(effects
				(font
					(size 0.7874 0.5842)
					(thickness 0.1524)
				)
				(justify left mirror)
			)
		)
		(fp_text user "3"
			(at -1.82626 5.08127 270)
			(unlocked yes)
			(layer "B.Fab")
			(effects
				(font
					(size 0.7874 0.5842)
					(thickness 0.1524)
				)
				(justify left mirror)
			)
		)
		(fp_text user "3"
			(at 0.187706 7.4422 0)
			(unlocked yes)
			(layer "F.Fab")
			(effects
				(font
					(size 0.7874 0.5842)
					(thickness 0.1524)
				)
				(justify left)
			)
		)
		(pad "1" thru_hole rect
			(at 0 0 270)
			(size 1.524 1.524)
			(drill 1.143)
			(layers "*.Cu" "*.Mask")
			(remove_unused_layers no)
			(net "SMB_SMLINK0_STBY_LVC3_SDA")
			(clearance 0.127)
			(thermal_gap 0.127)
			(padstack
				(mode front_inner_back)
				(layer "Inner"
					(shape circle)
					(size 1.524 1.524)
					(clearance 0.127)
				)
				(layer "B.Cu"
					(shape rect)
					(size 1.524 1.524)
					(clearance 0.127)
				)
			)
		)
		(pad "2" thru_hole circle
			(at 0 2.54 270)
			(size 1.524 1.524)
			(drill 1.143)
			(layers "*.Cu" "*.Mask")
			(remove_unused_layers no)
			(net "GND")
			(clearance 0.127)
			(thermal_gap 0.127)
		)
		(pad "3" thru_hole circle
			(at 0 5.08 270)
			(size 1.524 1.524)
			(drill 1.143)
			(layers "*.Cu" "*.Mask")
			(remove_unused_layers no)
			(net "SMB_SMLINK0_STBY_LVC3_SCL")
			(clearance 0.127)
			(thermal_gap 0.127)
		)
	)
	(footprint ""
		(layer "F.Cu")
		(at 374.015 -89.0905 180)
		(property "Reference" "R2P2"
			(at 0 0 180)
			(layer "F.SilkS")
			(hide yes)
			(effects
				(font
					(size 1.27 1.27)
				)
			)
		)
		(property "Value" ""
			(at 0 0 180)
			(layer "F.Fab")
			(effects
				(font
					(size 1.27 1.27)
				)
			)
		)
		(duplicate_pad_numbers_are_jumpers no)
		(fp_rect
			(start 0.2794 -0.1016)
			(end -0.2794 0.9906)
			(stroke
				(width 0)
				(type default)
			)
			(fill no)
			(layer "F.CrtYd")
		)
		(fp_line
			(start 0.2794 0.9906)
			(end 0.2794 -0.1016)
			(stroke
				(width 0.1)
				(type default)
			)
			(layer "F.Fab")
		)
		(fp_line
			(start 0.2794 -0.1016)
			(end -0.2794 -0.1016)
			(stroke
				(width 0.1)
				(type default)
			)
			(layer "F.Fab")
		)
		(fp_line
			(start -0.2794 0.9906)
			(end 0.2794 0.9906)
			(stroke
				(width 0.1)
				(type default)
			)
			(layer "F.Fab")
		)
		(fp_line
			(start -0.2794 -0.1016)
			(end -0.2794 0.9906)
			(stroke
				(width 0.1)
				(type default)
			)
			(layer "F.Fab")
		)
		(pad "1" smd rect
			(at 0 0 180)
			(size 0.508 0.508)
			(layers "F.Cu" "F.Mask" "F.Paste")
			(net "SPI_PCH_IO2")
		)
		(pad "2" smd rect
			(at 0 0.889 180)
			(size 0.508 0.508)
			(layers "F.Cu" "F.Mask" "F.Paste")
			(net "XDP_DEBUG_CONSENT_N")
		)
		(zone
			(layer "F.Cu")
			(hatch none 0.5)
			(connect_pads
				(clearance 0)
			)
			(min_thickness 0.25)
			(keepout
				(tracks allowed)
				(vias not_allowed)
				(pads allowed)
				(copperpour not_allowed)
				(footprints allowed)
			)
			(placement
				(enabled no)
				(sheetname "")
			)
			(fill
				(thermal_gap 0.5)
				(thermal_bridge_width 0.5)
				(island_removal_mode 0)
			)
			(polygon
				(pts
					(xy 373.761 -89.3445) (xy 374.269 -89.3445) (xy 374.269 -89.7255) (xy 373.761 -89.7255)
				)
			)
		)
		(zone
			(layer "F.Cu")
			(hatch none 0.5)
			(connect_pads
				(clearance 0)
			)
			(min_thickness 0.25)
			(keepout
				(tracks not_allowed)
				(vias allowed)
				(pads allowed)
				(copperpour not_allowed)
				(footprints allowed)
			)
			(placement
				(enabled no)
				(sheetname "")
			)
			(fill
				(thermal_gap 0.5)
				(thermal_bridge_width 0.5)
				(island_removal_mode 0)
			)
			(polygon
				(pts
					(xy 373.761 -89.3445) (xy 374.269 -89.3445) (xy 374.269 -89.7255) (xy 373.761 -89.7255)
				)
			)
		)
	)
	(footprint ""
		(layer "F.Cu")
		(at -3.429 -124.333 180)
		(property "Reference" "R1B16"
			(at 0 0 180)
			(layer "F.SilkS")
			(hide yes)
			(effects
				(font
					(size 1.27 1.27)
				)
			)
		)
		(property "Value" ""
			(at 0 0 180)
			(layer "F.Fab")
			(effects
				(font
					(size 1.27 1.27)
				)
			)
		)
		(duplicate_pad_numbers_are_jumpers no)
		(fp_rect
			(start 0.2794 -0.1016)
			(end -0.2794 0.9906)
			(stroke
				(width 0)
				(type default)
			)
			(fill no)
			(layer "F.CrtYd")
		)
		(fp_line
			(start 0.2794 0.9906)
			(end 0.2794 -0.1016)
			(stroke
				(width 0.1)
				(type default)
			)
			(layer "F.Fab")
		)
		(fp_line
			(start 0.2794 -0.1016)
			(end -0.2794 -0.1016)
			(stroke
				(width 0.1)
				(type default)
			)
			(layer "F.Fab")
		)
		(fp_line
			(start -0.2794 0.9906)
			(end 0.2794 0.9906)
			(stroke
				(width 0.1)
				(type default)
			)
			(layer "F.Fab")
		)
		(fp_line
			(start -0.2794 -0.1016)
			(end -0.2794 0.9906)
			(stroke
				(width 0.1)
				(type default)
			)
			(layer "F.Fab")
		)
		(pad "1" smd rect
			(at 0 0 180)
			(size 0.508 0.508)
			(layers "F.Cu" "F.Mask" "F.Paste")
			(net "VSENSE_PVDDQ_KLM_P")
		)
		(pad "2" smd rect
			(at 0 0.889 180)
			(size 0.508 0.508)
			(layers "F.Cu" "F.Mask" "F.Paste")
			(net "VR_PVDDQ_KLM_AVSP")
		)
		(zone
			(layer "F.Cu")
			(hatch none 0.5)
			(connect_pads
				(clearance 0)
			)
			(min_thickness 0.25)
			(keepout
				(tracks allowed)
				(vias not_allowed)
				(pads allowed)
				(copperpour not_allowed)
				(footprints allowed)
			)
			(placement
				(enabled no)
				(sheetname "")
			)
			(fill
				(thermal_gap 0.5)
				(thermal_bridge_width 0.5)
				(island_removal_mode 0)
			)
			(polygon
				(pts
					(xy -3.683 -124.587) (xy -3.175 -124.587) (xy -3.175 -124.968) (xy -3.683 -124.968)
				)
			)
		)
		(zone
			(layer "F.Cu")
			(hatch none 0.5)
			(connect_pads
				(clearance 0)
			)
			(min_thickness 0.25)
			(keepout
				(tracks not_allowed)
				(vias allowed)
				(pads allowed)
				(copperpour not_allowed)
				(footprints allowed)
			)
			(placement
				(enabled no)
				(sheetname "")
			)
			(fill
				(thermal_gap 0.5)
				(thermal_bridge_width 0.5)
				(island_removal_mode 0)
			)
			(polygon
				(pts
					(xy -3.683 -124.587) (xy -3.175 -124.587) (xy -3.175 -124.968) (xy -3.683 -124.968)
				)
			)
		)
	)
	(footprint ""
		(layer "F.Cu")
		(at 155.194 -3.302 90)
		(property "Reference" "C3G8"
			(at 0 0 90)
			(layer "F.SilkS")
			(hide yes)
			(effects
				(font
					(size 1.27 1.27)
				)
			)
		)
		(property "Value" ""
			(at 0 0 90)
			(layer "F.Fab")
			(effects
				(font
					(size 1.27 1.27)
				)
			)
		)
		(duplicate_pad_numbers_are_jumpers no)
		(fp_poly
			(pts
				(xy -0.4953 -0.2032) (xy 0.4953 -0.2032) (xy 0.4953 1.6002) (xy -0.4953 1.6002)
			)
			(stroke
				(width 0)
				(type default)
			)
			(fill no)
			(layer "F.CrtYd")
		)
		(fp_line
			(start 0.4953 -0.2032)
			(end 0.4953 1.6002)
			(stroke
				(width 0.1)
				(type default)
			)
			(layer "F.Fab")
		)
		(fp_line
			(start -0.4953 -0.2032)
			(end 0.4953 -0.2032)
			(stroke
				(width 0.1)
				(type default)
			)
			(layer "F.Fab")
		)
		(fp_line
			(start 0.4953 1.6002)
			(end -0.4953 1.6002)
			(stroke
				(width 0.1)
				(type default)
			)
			(layer "F.Fab")
		)
		(fp_line
			(start -0.4953 1.6002)
			(end -0.4953 -0.2032)
			(stroke
				(width 0.1)
				(type default)
			)
			(layer "F.Fab")
		)
		(pad "1" smd rect
			(at 0 0 90)
			(size 0.762 0.889)
			(layers "F.Cu" "F.Mask" "F.Paste")
			(net "PVPP_GHJ")
		)
		(pad "2" smd rect
			(at 0 1.397 90)
			(size 0.762 0.889)
			(layers "F.Cu" "F.Mask" "F.Paste")
			(net "GND")
		)
		(zone
			(layer "F.Cu")
			(hatch none 0.5)
			(connect_pads
				(clearance 0)
			)
			(min_thickness 0.25)
			(keepout
				(tracks not_allowed)
				(vias allowed)
				(pads allowed)
				(copperpour not_allowed)
				(footprints allowed)
			)
			(placement
				(enabled no)
				(sheetname "")
			)
			(fill
				(thermal_gap 0.5)
				(thermal_bridge_width 0.5)
				(island_removal_mode 0)
			)
			(polygon
				(pts
					(xy 155.6385 -2.921) (xy 155.6385 -3.683) (xy 156.1465 -3.683) (xy 156.1465 -2.921)
				)
			)
		)
	)
	(footprint ""
		(layer "F.Cu")
		(at 471.338402 -36.562792 180)
		(property "Reference" "R9F31"
			(at 0 0 180)
			(layer "F.SilkS")
			(hide yes)
			(effects
				(font
					(size 1.27 1.27)
				)
			)
		)
		(property "Value" "*"
			(at 0.064008 -4.108196 180)
			(unlocked yes)
			(layer "F.Fab")
			(hide yes)
			(effects
				(font
					(size 1.27 1.016)
					(thickness 0.1524)
				)
			)
		)
		(property "Device Type" "5K1R2F-2-GP_SMD-RG-5K1R2F-2-GPA"
			(at 0.064008 -5.632196 180)
			(unlocked yes)
			(layer "F.Fab")
			(hide yes)
			(effects
				(font
					(size 1.27 1.016)
					(thickness 0.1524)
				)
			)
		)
		(duplicate_pad_numbers_are_jumpers no)
		(fp_line
			(start 0.508 -0.9398)
			(end -0.508 -0.9398)
			(stroke
				(width 0.1524)
				(type default)
			)
			(layer "F.SilkS")
		)
		(fp_line
			(start -0.508 -0.9398)
			(end -0.508 0.9398)
			(stroke
				(width 0.1524)
				(type default)
			)
			(layer "F.SilkS")
		)
		(fp_rect
			(start -0.508 0.9398)
			(end 0.508 -0.9398)
			(stroke
				(width 0)
				(type default)
			)
			(fill no)
			(layer "F.CrtYd")
		)
		(fp_rect
			(start -0.508 0.9398)
			(end 0.508 -0.9398)
			(stroke
				(width 0)
				(type default)
			)
			(fill no)
			(layer "F.Fab")
		)
		(pad "1" smd custom
			(at 0 -0.4445 180)
			(size 0.1397 0.1397)
			(layers "F.Cu" "F.Mask" "F.Paste")
			(net "P1V2_AUX_BMC")
			(options
				(clearance outline)
				(anchor circle)
			)
			(primitives
				(gr_poly
					(pts
						(arc
							(start -0.1778 -0.2794)
							(mid -0.249642 -0.249642)
							(end -0.2794 -0.1778)
						)
						(arc
							(start -0.2794 0.1778)
							(mid -0.249642 0.249642)
							(end -0.1778 0.2794)
						)
						(arc
							(start 0.1778 0.2794)
							(mid 0.249642 0.249642)
							(end 0.2794 0.1778)
						)
						(arc
							(start 0.2794 -0.1778)
							(mid 0.249642 -0.249642)
							(end 0.1778 -0.2794)
						)
					)
					(width 0)
					(fill yes)
				)
			)
		)
		(pad "2" smd custom
			(at 0 0.4445 180)
			(size 0.1397 0.1397)
			(layers "F.Cu" "F.Mask" "F.Paste")
			(net "VR_P1V2_BMC_STBY_FB")
			(options
				(clearance outline)
				(anchor circle)
			)
			(primitives
				(gr_poly
					(pts
						(arc
							(start -0.1778 -0.2794)
							(mid -0.249642 -0.249642)
							(end -0.2794 -0.1778)
						)
						(arc
							(start -0.2794 0.1778)
							(mid -0.249642 0.249642)
							(end -0.1778 0.2794)
						)
						(arc
							(start 0.1778 0.2794)
							(mid 0.249642 0.249642)
							(end 0.2794 0.1778)
						)
						(arc
							(start 0.2794 -0.1778)
							(mid 0.249642 -0.249642)
							(end 0.1778 -0.2794)
						)
					)
					(width 0)
					(fill yes)
				)
			)
		)
	)
	(footprint ""
		(layer "F.Cu")
		(at 0.18034 -131.67106 180)
		(property "Reference" "C1B4"
			(at 0 0 180)
			(layer "F.SilkS")
			(hide yes)
			(effects
				(font
					(size 1.27 1.27)
				)
			)
		)
		(property "Value" ""
			(at 0 0 180)
			(layer "F.Fab")
			(effects
				(font
					(size 1.27 1.27)
				)
			)
		)
		(duplicate_pad_numbers_are_jumpers no)
		(fp_poly
			(pts
				(xy 0.3048 -0.1016) (xy 0.3048 0.9906) (xy -0.3048 0.9906) (xy -0.3048 -0.1016)
			)
			(stroke
				(width 0)
				(type default)
			)
			(fill no)
			(layer "F.CrtYd")
		)
		(fp_line
			(start 0.3048 0.9906)
			(end 0.3048 -0.1016)
			(stroke
				(width 0.1)
				(type default)
			)
			(layer "F.Fab")
		)
		(fp_line
			(start 0.3048 -0.1016)
			(end -0.3048 -0.1016)
			(stroke
				(width 0.1)
				(type default)
			)
			(layer "F.Fab")
		)
		(fp_line
			(start -0.3048 0.9906)
			(end 0.3048 0.9906)
			(stroke
				(width 0.1)
				(type default)
			)
			(layer "F.Fab")
		)
		(fp_line
			(start -0.3048 -0.1016)
			(end -0.3048 0.9906)
			(stroke
				(width 0.1)
				(type default)
			)
			(layer "F.Fab")
		)
		(pad "1" smd rect
			(at 0 0 180)
			(size 0.508 0.508)
			(layers "F.Cu" "F.Mask" "F.Paste")
			(net "PWRGD_PVDDQ_KLM_R")
		)
		(pad "2" smd rect
			(at 0 0.889 180)
			(size 0.508 0.508)
			(layers "F.Cu" "F.Mask" "F.Paste")
			(net "GND")
		)
		(zone
			(layer "F.Cu")
			(hatch none 0.5)
			(connect_pads
				(clearance 0)
			)
			(min_thickness 0.25)
			(keepout
				(tracks not_allowed)
				(vias allowed)
				(pads allowed)
				(copperpour not_allowed)
				(footprints allowed)
			)
			(placement
				(enabled no)
				(sheetname "")
			)
			(fill
				(thermal_gap 0.5)
				(thermal_bridge_width 0.5)
				(island_removal_mode 0)
			)
			(polygon
				(pts
					(xy 0.43434 -132.30606) (xy -0.07366 -132.30606) (xy -0.07366 -131.92506) (xy 0.43434 -131.92506)
				)
			)
		)
		(zone
			(layer "F.Cu")
			(hatch none 0.5)
			(connect_pads
				(clearance 0)
			)
			(min_thickness 0.25)
			(keepout
				(tracks allowed)
				(vias not_allowed)
				(pads allowed)
				(copperpour not_allowed)
				(footprints allowed)
			)
			(placement
				(enabled no)
				(sheetname "")
			)
			(fill
				(thermal_gap 0.5)
				(thermal_bridge_width 0.5)
				(island_removal_mode 0)
			)
			(polygon
				(pts
					(xy 0.43434 -131.92506) (xy -0.07366 -131.92506) (xy -0.07366 -132.30606) (xy 0.43434 -132.30606)
				)
			)
		)
	)
	(footprint ""
		(layer "F.Cu")
		(at 472.86418 -27.0764 180)
		(property "Reference" "C22W11"
			(at 0 0 180)
			(layer "F.SilkS")
			(hide yes)
			(effects
				(font
					(size 1.27 1.27)
				)
			)
		)
		(property "Value" "*"
			(at -0.0762 -6.2357 180)
			(unlocked yes)
			(layer "F.Fab")
			(hide yes)
			(effects
				(font
					(size 1.27 1.016)
					(thickness 0.1524)
				)
			)
		)
		(property "Device Type" "SC22U16V5MX-4-GP_SMD-BCG5-SC22A"
			(at -0.0762 -8.2677 180)
			(unlocked yes)
			(layer "F.Fab")
			(hide yes)
			(effects
				(font
					(size 1.27 1.016)
					(thickness 0.1524)
				)
			)
		)
		(duplicate_pad_numbers_are_jumpers no)
		(fp_line
			(start 0.635 0)
			(end -0.635 0)
			(stroke
				(width 0.508)
				(type default)
			)
			(layer "F.SilkS")
		)
		(fp_rect
			(start -0.9652 1.778)
			(end 0.9652 -1.778)
			(stroke
				(width 0)
				(type default)
			)
			(fill no)
			(layer "F.CrtYd")
		)
		(fp_poly
			(pts
				(xy -0.9652 -1.778) (xy 0.9652 -1.778) (xy 0.9652 1.778) (xy -0.9652 1.778)
			)
			(stroke
				(width 0)
				(type default)
			)
			(fill no)
			(layer "F.Fab")
		)
		(pad "1" smd rect
			(at 0 -0.9652 180)
			(size 1.397 1.143)
			(layers "F.Cu" "F.Mask" "F.Paste")
			(net "VR_FET_SW_P12V_STBY_P3V3_STBY")
		)
		(pad "2" smd rect
			(at 0 0.9652 180)
			(size 1.397 1.143)
			(layers "F.Cu" "F.Mask" "F.Paste")
			(net "GND")
		)
	)
	(footprint ""
		(layer "F.Cu")
		(at 177.927 -32.766 -90)
		(property "Reference" "C4F5"
			(at 3.32867 1.524 0)
			(unlocked yes)
			(layer "F.SilkS")
			(effects
				(font
					(size 0.7874 0.5842)
					(thickness 0.1524)
				)
			)
		)
		(property "Value" ""
			(at 0 0 270)
			(layer "F.Fab")
			(effects
				(font
					(size 1.27 1.27)
				)
			)
		)
		(duplicate_pad_numbers_are_jumpers no)
		(fp_line
			(start -2.286 7.366)
			(end -1.60147 7.366)
			(stroke
				(width 0.1524)
				(type default)
			)
			(layer "F.SilkS")
		)
		(fp_line
			(start -2.286 7.366)
			(end -2.286 1.632712)
			(stroke
				(width 0.1524)
				(type default)
			)
			(layer "F.SilkS")
		)
		(fp_line
			(start 2.286 7.366)
			(end 1.600708 7.366)
			(stroke
				(width 0.1524)
				(type default)
			)
			(layer "F.SilkS")
		)
		(fp_line
			(start 2.286 7.366)
			(end 2.286 1.63195)
			(stroke
				(width 0.1524)
				(type default)
			)
			(layer "F.SilkS")
		)
		(fp_line
			(start -2.563114 1.633982)
			(end -1.6002 1.633728)
			(stroke
				(width 0.1524)
				(type default)
			)
			(layer "F.SilkS")
		)
		(fp_line
			(start 2.504948 1.633982)
			(end 1.6002 1.633728)
			(stroke
				(width 0.1524)
				(type default)
			)
			(layer "F.SilkS")
		)
		(fp_line
			(start -2.56286 -1.616456)
			(end -2.563114 1.633982)
			(stroke
				(width 0.1524)
				(type default)
			)
			(layer "F.SilkS")
		)
		(fp_line
			(start -1.6002 -1.616456)
			(end -2.56286 -1.616456)
			(stroke
				(width 0.1524)
				(type default)
			)
			(layer "F.SilkS")
		)
		(fp_line
			(start 1.6002 -1.616456)
			(end 2.504948 -1.61671)
			(stroke
				(width 0.1524)
				(type default)
			)
			(layer "F.SilkS")
		)
		(fp_line
			(start 2.504948 -1.61671)
			(end 2.504948 1.633982)
			(stroke
				(width 0.1524)
				(type default)
			)
			(layer "F.SilkS")
		)
		(fp_rect
			(start -2.286 7.366)
			(end 2.286 -0.254)
			(stroke
				(width 0)
				(type default)
			)
			(fill no)
			(layer "F.CrtYd")
		)
		(fp_line
			(start -2.286 7.366)
			(end -2.286 -0.254)
			(stroke
				(width 0.1)
				(type default)
			)
			(layer "F.Fab")
		)
		(fp_line
			(start 2.286 7.366)
			(end -2.286 7.366)
			(stroke
				(width 0.1)
				(type default)
			)
			(layer "F.Fab")
		)
		(fp_line
			(start -2.286 -0.254)
			(end 2.286 -0.254)
			(stroke
				(width 0.1)
				(type default)
			)
			(layer "F.Fab")
		)
		(fp_line
			(start 2.286 -0.254)
			(end 2.286 7.366)
			(stroke
				(width 0.1)
				(type default)
			)
			(layer "F.Fab")
		)
		(pad "1" smd rect
			(at 0 0 270)
			(size 2.54 3.048)
			(layers "F.Cu" "F.Mask" "F.Paste")
			(net "P12V_STBY")
		)
		(pad "2" smd rect
			(at 0 7.112 270)
			(size 2.54 3.048)
			(layers "F.Cu" "F.Mask" "F.Paste")
			(net "GND")
		)
	)
	(footprint ""
		(layer "F.Cu")
		(at 390.578594 -153.47569 90)
		(property "Reference" "R8A4"
			(at 0 0 90)
			(layer "F.SilkS")
			(hide yes)
			(effects
				(font
					(size 1.27 1.27)
				)
			)
		)
		(property "Value" ""
			(at 0 0 90)
			(layer "F.Fab")
			(effects
				(font
					(size 1.27 1.27)
				)
			)
		)
		(duplicate_pad_numbers_are_jumpers no)
		(fp_poly
			(pts
				(xy -0.2794 -0.1016) (xy 0.2794 -0.1016) (xy 0.2794 0.9906) (xy -0.2794 0.9906)
			)
			(stroke
				(width 0)
				(type default)
			)
			(fill no)
			(layer "F.CrtYd")
		)
		(fp_line
			(start 0.2794 -0.1016)
			(end -0.2794 -0.1016)
			(stroke
				(width 0.1)
				(type default)
			)
			(layer "F.Fab")
		)
		(fp_line
			(start -0.2794 -0.1016)
			(end -0.2794 0.9906)
			(stroke
				(width 0.1)
				(type default)
			)
			(layer "F.Fab")
		)
		(fp_line
			(start 0.2794 0.9906)
			(end 0.2794 -0.1016)
			(stroke
				(width 0.1)
				(type default)
			)
			(layer "F.Fab")
		)
		(fp_line
			(start -0.2794 0.9906)
			(end 0.2794 0.9906)
			(stroke
				(width 0.1)
				(type default)
			)
			(layer "F.Fab")
		)
		(pad "1" smd rect
			(at 0 0 90)
			(size 0.508 0.508)
			(layers "F.Cu" "F.Mask" "F.Paste")
			(net "VR_FET_SW_P12V_STBY_PVDDQ_DEF")
		)
		(pad "2" smd rect
			(at 0 0.889 90)
			(size 0.508 0.508)
			(layers "F.Cu" "F.Mask" "F.Paste")
			(net "VR_PVNN_PCH_VINSEN")
		)
		(zone
			(layer "F.Cu")
			(hatch none 0.5)
			(connect_pads
				(clearance 0)
			)
			(min_thickness 0.25)
			(keepout
				(tracks allowed)
				(vias not_allowed)
				(pads allowed)
				(copperpour not_allowed)
				(footprints allowed)
			)
			(placement
				(enabled no)
				(sheetname "")
			)
			(fill
				(thermal_gap 0.5)
				(thermal_bridge_width 0.5)
				(island_removal_mode 0)
			)
			(polygon
				(pts
					(xy 390.832594 -153.22169) (xy 390.832594 -153.72969) (xy 391.213594 -153.72969) (xy 391.213594 -153.22169)
				)
			)
		)
		(zone
			(layer "F.Cu")
			(hatch none 0.5)
			(connect_pads
				(clearance 0)
			)
			(min_thickness 0.25)
			(keepout
				(tracks not_allowed)
				(vias allowed)
				(pads allowed)
				(copperpour not_allowed)
				(footprints allowed)
			)
			(placement
				(enabled no)
				(sheetname "")
			)
			(fill
				(thermal_gap 0.5)
				(thermal_bridge_width 0.5)
				(island_removal_mode 0)
			)
			(polygon
				(pts
					(xy 391.213594 -153.22169) (xy 391.213594 -153.72969) (xy 390.832594 -153.72969) (xy 390.832594 -153.22169)
				)
			)
		)
	)
	(footprint ""
		(layer "F.Cu")
		(at 497.781834 -23.657052 90)
		(property "Reference" "C7E5"
			(at 0 0 90)
			(layer "F.SilkS")
			(hide yes)
			(effects
				(font
					(size 1.27 1.27)
				)
			)
		)
		(property "Value" ""
			(at 0 0 90)
			(layer "F.Fab")
			(effects
				(font
					(size 1.27 1.27)
				)
			)
		)
		(duplicate_pad_numbers_are_jumpers no)
		(fp_rect
			(start 0.3048 0.9906)
			(end -0.3048 -0.1016)
			(stroke
				(width 0)
				(type default)
			)
			(fill no)
			(layer "F.CrtYd")
		)
		(fp_line
			(start 0.3048 -0.1016)
			(end -0.3048 -0.1016)
			(stroke
				(width 0.1)
				(type default)
			)
			(layer "F.Fab")
		)
		(fp_line
			(start -0.3048 -0.1016)
			(end -0.3048 0.9906)
			(stroke
				(width 0.1)
				(type default)
			)
			(layer "F.Fab")
		)
		(fp_line
			(start 0.3048 0.9906)
			(end 0.3048 -0.1016)
			(stroke
				(width 0.1)
				(type default)
			)
			(layer "F.Fab")
		)
		(fp_line
			(start -0.3048 0.9906)
			(end 0.3048 0.9906)
			(stroke
				(width 0.1)
				(type default)
			)
			(layer "F.Fab")
		)
		(pad "1" smd rect
			(at 0 0 90)
			(size 0.508 0.508)
			(layers "F.Cu" "F.Mask" "F.Paste")
			(net "P12V_STBY")
		)
		(pad "2" smd rect
			(at 0 0.889 90)
			(size 0.508 0.508)
			(layers "F.Cu" "F.Mask" "F.Paste")
			(net "GND")
		)
		(zone
			(layer "F.Cu")
			(hatch none 0.5)
			(connect_pads
				(clearance 0)
			)
			(min_thickness 0.25)
			(keepout
				(tracks allowed)
				(vias not_allowed)
				(pads allowed)
				(copperpour not_allowed)
				(footprints allowed)
			)
			(placement
				(enabled no)
				(sheetname "")
			)
			(fill
				(thermal_gap 0.5)
				(thermal_bridge_width 0.5)
				(island_removal_mode 0)
			)
			(polygon
				(pts
					(xy 498.416834 -23.911052) (xy 498.035834 -23.911052) (xy 498.035834 -23.403052) (xy 498.416834 -23.403052)
				)
			)
		)
		(zone
			(layer "F.Cu")
			(hatch none 0.5)
			(connect_pads
				(clearance 0)
			)
			(min_thickness 0.25)
			(keepout
				(tracks not_allowed)
				(vias allowed)
				(pads allowed)
				(copperpour not_allowed)
				(footprints allowed)
			)
			(placement
				(enabled no)
				(sheetname "")
			)
			(fill
				(thermal_gap 0.5)
				(thermal_bridge_width 0.5)
				(island_removal_mode 0)
			)
			(polygon
				(pts
					(xy 498.416834 -23.911052) (xy 498.035834 -23.911052) (xy 498.035834 -23.403052) (xy 498.416834 -23.403052)
				)
			)
		)
	)
	(footprint ""
		(layer "F.Cu")
		(at 19.431 -82.423 -90)
		(property "Reference" "R1D16"
			(at 0 0 270)
			(layer "F.SilkS")
			(hide yes)
			(effects
				(font
					(size 1.27 1.27)
				)
			)
		)
		(property "Value" ""
			(at 0 0 270)
			(layer "F.Fab")
			(effects
				(font
					(size 1.27 1.27)
				)
			)
		)
		(duplicate_pad_numbers_are_jumpers no)
		(fp_poly
			(pts
				(xy -0.2794 -0.1016) (xy 0.2794 -0.1016) (xy 0.2794 0.9906) (xy -0.2794 0.9906)
			)
			(stroke
				(width 0)
				(type default)
			)
			(fill no)
			(layer "F.CrtYd")
		)
		(fp_line
			(start -0.2794 0.9906)
			(end 0.2794 0.9906)
			(stroke
				(width 0.1)
				(type default)
			)
			(layer "F.Fab")
		)
		(fp_line
			(start 0.2794 0.9906)
			(end 0.2794 -0.1016)
			(stroke
				(width 0.1)
				(type default)
			)
			(layer "F.Fab")
		)
		(fp_line
			(start -0.2794 -0.1016)
			(end -0.2794 0.9906)
			(stroke
				(width 0.1)
				(type default)
			)
			(layer "F.Fab")
		)
		(fp_line
			(start 0.2794 -0.1016)
			(end -0.2794 -0.1016)
			(stroke
				(width 0.1)
				(type default)
			)
			(layer "F.Fab")
		)
		(pad "1" smd rect
			(at 0 0 270)
			(size 0.508 0.508)
			(layers "F.Cu" "F.Mask" "F.Paste")
			(net "A_HSC_ISET")
		)
		(pad "2" smd rect
			(at 0 0.889 270)
			(size 0.508 0.508)
			(layers "F.Cu" "F.Mask" "F.Paste")
			(net "A_HSC_ISET_S2")
		)
		(zone
			(layer "F.Cu")
			(hatch none 0.5)
			(connect_pads
				(clearance 0)
			)
			(min_thickness 0.25)
			(keepout
				(tracks not_allowed)
				(vias allowed)
				(pads allowed)
				(copperpour not_allowed)
				(footprints allowed)
			)
			(placement
				(enabled no)
				(sheetname "")
			)
			(fill
				(thermal_gap 0.5)
				(thermal_bridge_width 0.5)
				(island_removal_mode 0)
			)
			(polygon
				(pts
					(xy 18.796 -82.677) (xy 18.796 -82.169) (xy 19.177 -82.169) (xy 19.177 -82.677)
				)
			)
		)
		(zone
			(layer "F.Cu")
			(hatch none 0.5)
			(connect_pads
				(clearance 0)
			)
			(min_thickness 0.25)
			(keepout
				(tracks allowed)
				(vias not_allowed)
				(pads allowed)
				(copperpour not_allowed)
				(footprints allowed)
			)
			(placement
				(enabled no)
				(sheetname "")
			)
			(fill
				(thermal_gap 0.5)
				(thermal_bridge_width 0.5)
				(island_removal_mode 0)
			)
			(polygon
				(pts
					(xy 19.177 -82.677) (xy 19.177 -82.169) (xy 18.796 -82.169) (xy 18.796 -82.677)
				)
			)
		)
	)
	(footprint ""
		(layer "F.Cu")
		(at 5.045456 -17.460976 90)
		(property "Reference" "EU1F1"
			(at 3.789172 1.463294 0)
			(unlocked yes)
			(layer "F.SilkS")
			(effects
				(font
					(size 0.7874 0.5842)
					(thickness 0.1524)
				)
			)
		)
		(property "Value" ""
			(at 0 0 90)
			(layer "F.Fab")
			(effects
				(font
					(size 1.27 1.27)
				)
			)
		)
		(duplicate_pad_numbers_are_jumpers no)
		(fp_line
			(start 2.9718 -3.5052)
			(end 2.9718 3.429)
			(stroke
				(width 0.1524)
				(type default)
			)
			(layer "F.SilkS")
		)
		(fp_line
			(start -3.0099 -3.5052)
			(end 2.9718 -3.5052)
			(stroke
				(width 0.1524)
				(type default)
			)
			(layer "F.SilkS")
		)
		(fp_line
			(start 2.9718 3.429)
			(end -3.0099 3.429)
			(stroke
				(width 0.1524)
				(type default)
			)
			(layer "F.SilkS")
		)
		(fp_line
			(start -3.0099 3.429)
			(end -3.0099 -3.5052)
			(stroke
				(width 0.1524)
				(type default)
			)
			(layer "F.SilkS")
		)
		(fp_circle
			(center -3.057398 -2.678684)
			(end -3.057398 -2.551684)
			(stroke
				(width 0.254)
				(type default)
			)
			(fill no)
			(layer "F.SilkS")
		)
		(fp_poly
			(pts
				(xy -2.9972 -3.4925) (xy -2.9972 -2.6924) (xy -2.1971 -3.4925)
			)
			(stroke
				(width 0)
				(type default)
			)
			(fill yes)
			(layer "F.SilkS")
		)
		(fp_poly
			(pts
				(xy -2.549906 -3.050032) (xy -2.549906 3.050032) (xy 2.549906 3.050032) (xy 2.549906 -3.050032)
			)
			(stroke
				(width 0)
				(type default)
			)
			(fill no)
			(layer "F.CrtYd")
		)
		(fp_line
			(start 2.549906 -3.050032)
			(end 2.549906 3.050032)
			(stroke
				(width 0.1)
				(type default)
			)
			(layer "F.Fab")
		)
		(fp_line
			(start -2.549906 -3.050032)
			(end 2.549906 -3.050032)
			(stroke
				(width 0.1)
				(type default)
			)
			(layer "F.Fab")
		)
		(fp_line
			(start 2.549906 3.050032)
			(end -2.549906 3.050032)
			(stroke
				(width 0.1)
				(type default)
			)
			(layer "F.Fab")
		)
		(fp_line
			(start -2.549906 3.050032)
			(end -2.549906 -3.050032)
			(stroke
				(width 0.1)
				(type default)
			)
			(layer "F.Fab")
		)
		(fp_circle
			(center -3.057398 -2.678684)
			(end -3.057398 -2.551684)
			(stroke
				(width 0.254)
				(type default)
			)
			(fill no)
			(layer "F.Fab")
		)
		(pad "1" smd rect
			(at -2.39522 -2.279904 90)
			(size 0.7112 0.254)
			(layers "F.Cu" "F.Mask" "F.Paste")
			(net "PVDDQ_GHJ")
		)
		(pad "2" smd rect
			(at -2.39522 -1.83007 90)
			(size 0.7112 0.254)
			(layers "F.Cu" "F.Mask" "F.Paste")
			(net "GND")
		)
		(pad "3" smd rect
			(at -2.39522 -1.379982 90)
			(size 0.7112 0.254)
			(layers "F.Cu" "F.Mask" "F.Paste")
			(net "VR_PVDDQ_GHJ_PH2_VCIN")
		)
		(pad "4" smd rect
			(at -2.39522 -0.929894 90)
			(size 0.7112 0.254)
			(layers "F.Cu" "F.Mask" "F.Paste")
			(net "P5V_STBY")
		)
		(pad "5" smd rect
			(at -2.39522 -0.48006 90)
			(size 0.7112 0.254)
			(layers "F.Cu" "F.Mask" "F.Paste")
			(net "GND")
		)
		(pad "6" smd rect
			(at -2.39522 -0.029972 90)
			(size 0.7112 0.254)
			(layers "F.Cu" "F.Mask" "F.Paste")
			(net "TP_PVDDQ_GHJ_PH2_GL_0")
		)
		(pad "7" smd custom
			(at 0.016764 1.145032 90)
			(size 0.53975 0.53975)
			(layers "F.Cu" "F.Mask" "F.Paste")
			(net "GND")
			(options
				(clearance outline)
				(anchor circle)
			)
			(primitives
				(gr_poly
					(pts
						(xy -2.7051 1.0795) (xy -2.7051 -0.3683) (xy -0.9271 -0.3683) (xy -0.9271 -1.0795) (xy 2.7051 -1.0795)
						(xy 2.7051 1.0795)
					)
					(width 0)
					(fill yes)
				)
			)
		)
		(pad "10" smd rect
			(at -0.008382 2.874772 90)
			(size 4.3434 0.6096)
			(layers "F.Cu" "F.Mask" "F.Paste")
			(net "VR_PVDDQ_GHJ_PH2_SW")
		)
		(pad "25" smd rect
			(at 1.548384 -1.283208 90)
			(size 2.3368 2.0066)
			(layers "F.Cu" "F.Mask" "F.Paste")
			(net "VR_FET_SW_P12V_STBY_PVDDQ_GHJ")
		)
		(pad "30" smd rect
			(at 2.050034 -2.895092 90)
			(size 0.254 0.7112)
			(layers "F.Cu" "F.Mask" "F.Paste")
			(net "VR_FET_SW_P12V_STBY_PVDDQ_GHJ")
		)
		(pad "31" smd rect
			(at 1.599946 -2.895092 90)
			(size 0.254 0.7112)
			(layers "F.Cu" "F.Mask" "F.Paste")
			(net "Net_297")
		)
		(pad "32" smd rect
			(at 1.150112 -2.895092 90)
			(size 0.254 0.7112)
			(layers "F.Cu" "F.Mask" "F.Paste")
			(net "VR_PVDDQ_GHJ_PH2_PHASE")
		)
		(pad "33" smd rect
			(at 0.700024 -2.895092 90)
			(size 0.254 0.7112)
			(layers "F.Cu" "F.Mask" "F.Paste")
			(net "VR_PVDDQ_GHJ_PH2_BOOT_R")
		)
		(pad "34" smd rect
			(at 0.249936 -2.895092 90)
			(size 0.254 0.7112)
			(layers "F.Cu" "F.Mask" "F.Paste")
			(net "VR_PVDDQ_GHJ_PWM2")
		)
		(pad "35" smd rect
			(at -0.199898 -2.895092 90)
			(size 0.254 0.7112)
			(layers "F.Cu" "F.Mask" "F.Paste")
			(net "P5V_STBY")
		)
		(pad "36" smd rect
			(at -0.649986 -2.895092 90)
			(size 0.254 0.7112)
			(layers "F.Cu" "F.Mask" "F.Paste")
			(net "A_TSENSE_PVDDQ_GHJ")
		)
		(pad "37" smd rect
			(at -1.100074 -2.895092 90)
			(size 0.254 0.7112)
			(layers "F.Cu" "F.Mask" "F.Paste")
			(net "VR_PVDDQ_GHJ_PH2_OCSET")
		)
		(pad "38" smd rect
			(at -1.549908 -2.895092 90)
			(size 0.254 0.7112)
			(layers "F.Cu" "F.Mask" "F.Paste")
			(net "ISENSE_PVDDQ_GHJ_PH2_IMON")
		)
		(pad "39" smd rect
			(at -1.999996 -2.895092 90)
			(size 0.254 0.7112)
			(layers "F.Cu" "F.Mask" "F.Paste")
			(net "VR_PVDDQ_GHJ_AIREF2")
		)
		(pad "40" smd rect
			(at -0.871728 -1.283208 90)
			(size 1.8034 2.0066)
			(layers "F.Cu" "F.Mask" "F.Paste")
			(net "GND")
		)
		(pad "41" smd rect
			(at -1.533906 0.247904 90)
			(size 0.508 0.3556)
			(layers "F.Cu" "F.Mask" "F.Paste")
			(net "TP_PVDDQ_GHJ_PH2_GL_1")
		)
	)
	(footprint ""
		(layer "F.Cu")
		(at 21.336 -81.79308)
		(property "Reference" "C1D9"
			(at 0 0 0)
			(layer "F.SilkS")
			(hide yes)
			(effects
				(font
					(size 1.27 1.27)
				)
			)
		)
		(property "Value" ""
			(at 0 0 0)
			(layer "F.Fab")
			(effects
				(font
					(size 1.27 1.27)
				)
			)
		)
		(duplicate_pad_numbers_are_jumpers no)
		(fp_poly
			(pts
				(xy 0.3048 -0.1016) (xy 0.3048 0.9906) (xy -0.3048 0.9906) (xy -0.3048 -0.1016)
			)
			(stroke
				(width 0)
				(type default)
			)
			(fill no)
			(layer "F.CrtYd")
		)
		(fp_line
			(start -0.3048 -0.1016)
			(end -0.3048 0.9906)
			(stroke
				(width 0.1)
				(type default)
			)
			(layer "F.Fab")
		)
		(fp_line
			(start -0.3048 0.9906)
			(end 0.3048 0.9906)
			(stroke
				(width 0.1)
				(type default)
			)
			(layer "F.Fab")
		)
		(fp_line
			(start 0.3048 -0.1016)
			(end -0.3048 -0.1016)
			(stroke
				(width 0.1)
				(type default)
			)
			(layer "F.Fab")
		)
		(fp_line
			(start 0.3048 0.9906)
			(end 0.3048 -0.1016)
			(stroke
				(width 0.1)
				(type default)
			)
			(layer "F.Fab")
		)
		(pad "1" smd rect
			(at 0 0)
			(size 0.508 0.508)
			(layers "F.Cu" "F.Mask" "F.Paste")
			(net "P12V_STBY")
		)
		(pad "2" smd rect
			(at 0 0.889)
			(size 0.508 0.508)
			(layers "F.Cu" "F.Mask" "F.Paste")
			(net "AGND_HSC")
		)
		(zone
			(layer "F.Cu")
			(hatch none 0.5)
			(connect_pads
				(clearance 0)
			)
			(min_thickness 0.25)
			(keepout
				(tracks allowed)
				(vias not_allowed)
				(pads allowed)
				(copperpour not_allowed)
				(footprints allowed)
			)
			(placement
				(enabled no)
				(sheetname "")
			)
			(fill
				(thermal_gap 0.5)
				(thermal_bridge_width 0.5)
				(island_removal_mode 0)
			)
			(polygon
				(pts
					(xy 21.082 -81.53908) (xy 21.59 -81.53908) (xy 21.59 -81.15808) (xy 21.082 -81.15808)
				)
			)
		)
		(zone
			(layer "F.Cu")
			(hatch none 0.5)
			(connect_pads
				(clearance 0)
			)
			(min_thickness 0.25)
			(keepout
				(tracks not_allowed)
				(vias allowed)
				(pads allowed)
				(copperpour not_allowed)
				(footprints allowed)
			)
			(placement
				(enabled no)
				(sheetname "")
			)
			(fill
				(thermal_gap 0.5)
				(thermal_bridge_width 0.5)
				(island_removal_mode 0)
			)
			(polygon
				(pts
					(xy 21.082 -81.15808) (xy 21.59 -81.15808) (xy 21.59 -81.53908) (xy 21.082 -81.53908)
				)
			)
		)
	)
	(footprint ""
		(layer "F.Cu")
		(at 198.039228 -93.861382 90)
		(property "Reference" "C4C5"
			(at 0 0 90)
			(layer "F.SilkS")
			(hide yes)
			(effects
				(font
					(size 1.27 1.27)
				)
			)
		)
		(property "Value" ""
			(at 0 0 90)
			(layer "F.Fab")
			(effects
				(font
					(size 1.27 1.27)
				)
			)
		)
		(duplicate_pad_numbers_are_jumpers no)
		(fp_rect
			(start 0.3048 0.9906)
			(end -0.3048 -0.1016)
			(stroke
				(width 0)
				(type default)
			)
			(fill no)
			(layer "F.CrtYd")
		)
		(fp_line
			(start 0.3048 -0.1016)
			(end -0.3048 -0.1016)
			(stroke
				(width 0.1)
				(type default)
			)
			(layer "F.Fab")
		)
		(fp_line
			(start -0.3048 -0.1016)
			(end -0.3048 0.9906)
			(stroke
				(width 0.1)
				(type default)
			)
			(layer "F.Fab")
		)
		(fp_line
			(start 0.3048 0.9906)
			(end 0.3048 -0.1016)
			(stroke
				(width 0.1)
				(type default)
			)
			(layer "F.Fab")
		)
		(fp_line
			(start -0.3048 0.9906)
			(end 0.3048 0.9906)
			(stroke
				(width 0.1)
				(type default)
			)
			(layer "F.Fab")
		)
		(pad "1" smd rect
			(at 0 0 90)
			(size 0.508 0.508)
			(layers "F.Cu" "F.Mask" "F.Paste")
			(net "P5V_STBY")
		)
		(pad "2" smd rect
			(at 0 0.889 90)
			(size 0.508 0.508)
			(layers "F.Cu" "F.Mask" "F.Paste")
			(net "GND")
		)
		(zone
			(layer "F.Cu")
			(hatch none 0.5)
			(connect_pads
				(clearance 0)
			)
			(min_thickness 0.25)
			(keepout
				(tracks not_allowed)
				(vias allowed)
				(pads allowed)
				(copperpour not_allowed)
				(footprints allowed)
			)
			(placement
				(enabled no)
				(sheetname "")
			)
			(fill
				(thermal_gap 0.5)
				(thermal_bridge_width 0.5)
				(island_removal_mode 0)
			)
			(polygon
				(pts
					(xy 198.674228 -94.115382) (xy 198.293228 -94.115382) (xy 198.293228 -93.607382) (xy 198.674228 -93.607382)
				)
			)
		)
		(zone
			(layer "F.Cu")
			(hatch none 0.5)
			(connect_pads
				(clearance 0)
			)
			(min_thickness 0.25)
			(keepout
				(tracks allowed)
				(vias not_allowed)
				(pads allowed)
				(copperpour not_allowed)
				(footprints allowed)
			)
			(placement
				(enabled no)
				(sheetname "")
			)
			(fill
				(thermal_gap 0.5)
				(thermal_bridge_width 0.5)
				(island_removal_mode 0)
			)
			(polygon
				(pts
					(xy 198.674228 -94.115382) (xy 198.293228 -94.115382) (xy 198.293228 -93.607382) (xy 198.674228 -93.607382)
				)
			)
		)
	)
	(footprint ""
		(layer "F.Cu")
		(at 406.197054 -64.298068)
		(property "Reference" "R8E2"
			(at 0 0 0)
			(layer "F.SilkS")
			(hide yes)
			(effects
				(font
					(size 1.27 1.27)
				)
			)
		)
		(property "Value" ""
			(at 0 0 0)
			(layer "F.Fab")
			(effects
				(font
					(size 1.27 1.27)
				)
			)
		)
		(duplicate_pad_numbers_are_jumpers no)
		(fp_poly
			(pts
				(xy -0.2794 -0.1016) (xy 0.2794 -0.1016) (xy 0.2794 0.9906) (xy -0.2794 0.9906)
			)
			(stroke
				(width 0)
				(type default)
			)
			(fill no)
			(layer "F.CrtYd")
		)
		(fp_line
			(start -0.2794 -0.1016)
			(end -0.2794 0.9906)
			(stroke
				(width 0.1)
				(type default)
			)
			(layer "F.Fab")
		)
		(fp_line
			(start -0.2794 0.9906)
			(end 0.2794 0.9906)
			(stroke
				(width 0.1)
				(type default)
			)
			(layer "F.Fab")
		)
		(fp_line
			(start 0.2794 -0.1016)
			(end -0.2794 -0.1016)
			(stroke
				(width 0.1)
				(type default)
			)
			(layer "F.Fab")
		)
		(fp_line
			(start 0.2794 0.9906)
			(end 0.2794 -0.1016)
			(stroke
				(width 0.1)
				(type default)
			)
			(layer "F.Fab")
		)
		(pad "1" smd rect
			(at 0 0)
			(size 0.508 0.508)
			(layers "F.Cu" "F.Mask" "F.Paste")
			(net "XDP_SPI_PCH_MOSI_BOOT_HALT_N")
		)
		(pad "2" smd rect
			(at 0 0.889)
			(size 0.508 0.508)
			(layers "F.Cu" "F.Mask" "F.Paste")
			(net "SPI_PCH_MOSI")
		)
		(zone
			(layer "F.Cu")
			(hatch none 0.5)
			(connect_pads
				(clearance 0)
			)
			(min_thickness 0.25)
			(keepout
				(tracks allowed)
				(vias not_allowed)
				(pads allowed)
				(copperpour not_allowed)
				(footprints allowed)
			)
			(placement
				(enabled no)
				(sheetname "")
			)
			(fill
				(thermal_gap 0.5)
				(thermal_bridge_width 0.5)
				(island_removal_mode 0)
			)
			(polygon
				(pts
					(xy 405.943054 -64.044068) (xy 406.451054 -64.044068) (xy 406.451054 -63.663068) (xy 405.943054 -63.663068)
				)
			)
		)
		(zone
			(layer "F.Cu")
			(hatch none 0.5)
			(connect_pads
				(clearance 0)
			)
			(min_thickness 0.25)
			(keepout
				(tracks not_allowed)
				(vias allowed)
				(pads allowed)
				(copperpour not_allowed)
				(footprints allowed)
			)
			(placement
				(enabled no)
				(sheetname "")
			)
			(fill
				(thermal_gap 0.5)
				(thermal_bridge_width 0.5)
				(island_removal_mode 0)
			)
			(polygon
				(pts
					(xy 405.943054 -63.663068) (xy 406.451054 -63.663068) (xy 406.451054 -64.044068) (xy 405.943054 -64.044068)
				)
			)
		)
	)
	(footprint ""
		(layer "F.Cu")
		(at 28.380182 -130.5814 -90)
		(property "Reference" "C1B7"
			(at 0 0 270)
			(layer "F.SilkS")
			(hide yes)
			(effects
				(font
					(size 1.27 1.27)
				)
			)
		)
		(property "Value" ""
			(at 0 0 270)
			(layer "F.Fab")
			(effects
				(font
					(size 1.27 1.27)
				)
			)
		)
		(duplicate_pad_numbers_are_jumpers no)
		(fp_poly
			(pts
				(xy -0.7239 -0.2159) (xy 0.7239 -0.2159) (xy 0.7239 1.9939) (xy -0.7239 1.9939)
			)
			(stroke
				(width 0)
				(type default)
			)
			(fill no)
			(layer "F.CrtYd")
		)
		(fp_line
			(start -0.7239 1.9939)
			(end 0.7239 1.9939)
			(stroke
				(width 0.1)
				(type default)
			)
			(layer "F.Fab")
		)
		(fp_line
			(start 0.7239 1.9939)
			(end 0.7239 -0.2159)
			(stroke
				(width 0.1)
				(type default)
			)
			(layer "F.Fab")
		)
		(fp_line
			(start -0.7239 -0.2159)
			(end -0.7239 1.9939)
			(stroke
				(width 0.1)
				(type default)
			)
			(layer "F.Fab")
		)
		(fp_line
			(start 0.7239 -0.2159)
			(end -0.7239 -0.2159)
			(stroke
				(width 0.1)
				(type default)
			)
			(layer "F.Fab")
		)
		(pad "1" smd rect
			(at 0 0 270)
			(size 1.27 1.016)
			(layers "F.Cu" "F.Mask" "F.Paste")
			(net "P12V_NVDIMM_KLM")
		)
		(pad "2" smd rect
			(at 0 1.778 270)
			(size 1.27 1.016)
			(layers "F.Cu" "F.Mask" "F.Paste")
			(net "GND")
		)
		(zone
			(layer "F.Cu")
			(hatch none 0.5)
			(connect_pads
				(clearance 0)
			)
			(min_thickness 0.25)
			(keepout
				(tracks not_allowed)
				(vias allowed)
				(pads allowed)
				(copperpour not_allowed)
				(footprints allowed)
			)
			(placement
				(enabled no)
				(sheetname "")
			)
			(fill
				(thermal_gap 0.5)
				(thermal_bridge_width 0.5)
				(island_removal_mode 0)
			)
			(polygon
				(pts
					(xy 27.872182 -131.2164) (xy 27.872182 -129.9464) (xy 27.110182 -129.9464) (xy 27.110182 -131.2164)
				)
			)
		)
	)
	(footprint ""
		(layer "F.Cu")
		(at 338.836 -16.383 -90)
		(property "Reference" "R7G2"
			(at 0 0 270)
			(layer "F.SilkS")
			(hide yes)
			(effects
				(font
					(size 1.27 1.27)
				)
			)
		)
		(property "Value" ""
			(at 0 0 270)
			(layer "F.Fab")
			(effects
				(font
					(size 1.27 1.27)
				)
			)
		)
		(duplicate_pad_numbers_are_jumpers no)
		(fp_rect
			(start 0.2794 0.9906)
			(end -0.2794 -0.1016)
			(stroke
				(width 0)
				(type default)
			)
			(fill no)
			(layer "F.CrtYd")
		)
		(fp_line
			(start -0.2794 0.9906)
			(end 0.2794 0.9906)
			(stroke
				(width 0.1)
				(type default)
			)
			(layer "F.Fab")
		)
		(fp_line
			(start 0.2794 0.9906)
			(end 0.2794 -0.1016)
			(stroke
				(width 0.1)
				(type default)
			)
			(layer "F.Fab")
		)
		(fp_line
			(start -0.2794 -0.1016)
			(end -0.2794 0.9906)
			(stroke
				(width 0.1)
				(type default)
			)
			(layer "F.Fab")
		)
		(fp_line
			(start 0.2794 -0.1016)
			(end -0.2794 -0.1016)
			(stroke
				(width 0.1)
				(type default)
			)
			(layer "F.Fab")
		)
		(pad "1" smd rect
			(at 0 0 270)
			(size 0.508 0.508)
			(layers "F.Cu" "F.Mask" "F.Paste")
			(net "SVID_VDIO_PVDDQ_ABC")
		)
		(pad "2" smd rect
			(at 0 0.889 270)
			(size 0.508 0.508)
			(layers "F.Cu" "F.Mask" "F.Paste")
			(net "SVID_DIO1_CPU0_R")
		)
		(zone
			(layer "F.Cu")
			(hatch none 0.5)
			(connect_pads
				(clearance 0)
			)
			(min_thickness 0.25)
			(keepout
				(tracks not_allowed)
				(vias allowed)
				(pads allowed)
				(copperpour not_allowed)
				(footprints allowed)
			)
			(placement
				(enabled no)
				(sheetname "")
			)
			(fill
				(thermal_gap 0.5)
				(thermal_bridge_width 0.5)
				(island_removal_mode 0)
			)
			(polygon
				(pts
					(xy 338.201 -16.129) (xy 338.582 -16.129) (xy 338.582 -16.637) (xy 338.201 -16.637)
				)
			)
		)
		(zone
			(layer "F.Cu")
			(hatch none 0.5)
			(connect_pads
				(clearance 0)
			)
			(min_thickness 0.25)
			(keepout
				(tracks allowed)
				(vias not_allowed)
				(pads allowed)
				(copperpour not_allowed)
				(footprints allowed)
			)
			(placement
				(enabled no)
				(sheetname "")
			)
			(fill
				(thermal_gap 0.5)
				(thermal_bridge_width 0.5)
				(island_removal_mode 0)
			)
			(polygon
				(pts
					(xy 338.201 -16.129) (xy 338.582 -16.129) (xy 338.582 -16.637) (xy 338.201 -16.637)
				)
			)
		)
	)
	(footprint ""
		(layer "F.Cu")
		(at 113.332768 -79.6036 180)
		(property "Reference" "C3D8"
			(at 0 0 180)
			(layer "F.SilkS")
			(hide yes)
			(effects
				(font
					(size 1.27 1.27)
				)
			)
		)
		(property "Value" ""
			(at 0 0 180)
			(layer "F.Fab")
			(effects
				(font
					(size 1.27 1.27)
				)
			)
		)
		(duplicate_pad_numbers_are_jumpers no)
		(fp_poly
			(pts
				(xy -0.4953 -0.2032) (xy 0.4953 -0.2032) (xy 0.4953 1.6002) (xy -0.4953 1.6002)
			)
			(stroke
				(width 0)
				(type default)
			)
			(fill no)
			(layer "F.CrtYd")
		)
		(fp_line
			(start 0.4953 1.6002)
			(end -0.4953 1.6002)
			(stroke
				(width 0.1)
				(type default)
			)
			(layer "F.Fab")
		)
		(fp_line
			(start 0.4953 -0.2032)
			(end 0.4953 1.6002)
			(stroke
				(width 0.1)
				(type default)
			)
			(layer "F.Fab")
		)
		(fp_line
			(start -0.4953 1.6002)
			(end -0.4953 -0.2032)
			(stroke
				(width 0.1)
				(type default)
			)
			(layer "F.Fab")
		)
		(fp_line
			(start -0.4953 -0.2032)
			(end 0.4953 -0.2032)
			(stroke
				(width 0.1)
				(type default)
			)
			(layer "F.Fab")
		)
		(pad "1" smd rect
			(at 0 0 180)
			(size 0.762 0.889)
			(layers "F.Cu" "F.Mask" "F.Paste")
			(net "PVCCIO_CPU1")
		)
		(pad "2" smd rect
			(at 0 1.397 180)
			(size 0.762 0.889)
			(layers "F.Cu" "F.Mask" "F.Paste")
			(net "GND")
		)
		(zone
			(layer "F.Cu")
			(hatch none 0.5)
			(connect_pads
				(clearance 0)
			)
			(min_thickness 0.25)
			(keepout
				(tracks not_allowed)
				(vias allowed)
				(pads allowed)
				(copperpour not_allowed)
				(footprints allowed)
			)
			(placement
				(enabled no)
				(sheetname "")
			)
			(fill
				(thermal_gap 0.5)
				(thermal_bridge_width 0.5)
				(island_removal_mode 0)
			)
			(polygon
				(pts
					(xy 113.713768 -80.0481) (xy 112.951768 -80.0481) (xy 112.951768 -80.5561) (xy 113.713768 -80.5561)
				)
			)
		)
	)
	(footprint ""
		(layer "F.Cu")
		(at 19.2024 -84.3534)
		(property "Reference" "R1D13"
			(at 0 0 0)
			(layer "F.SilkS")
			(hide yes)
			(effects
				(font
					(size 1.27 1.27)
				)
			)
		)
		(property "Value" ""
			(at 0 0 0)
			(layer "F.Fab")
			(effects
				(font
					(size 1.27 1.27)
				)
			)
		)
		(duplicate_pad_numbers_are_jumpers no)
		(fp_poly
			(pts
				(xy -0.2794 -0.1016) (xy 0.2794 -0.1016) (xy 0.2794 0.9906) (xy -0.2794 0.9906)
			)
			(stroke
				(width 0)
				(type default)
			)
			(fill no)
			(layer "F.CrtYd")
		)
		(fp_line
			(start -0.2794 -0.1016)
			(end -0.2794 0.9906)
			(stroke
				(width 0.1)
				(type default)
			)
			(layer "F.Fab")
		)
		(fp_line
			(start -0.2794 0.9906)
			(end 0.2794 0.9906)
			(stroke
				(width 0.1)
				(type default)
			)
			(layer "F.Fab")
		)
		(fp_line
			(start 0.2794 -0.1016)
			(end -0.2794 -0.1016)
			(stroke
				(width 0.1)
				(type default)
			)
			(layer "F.Fab")
		)
		(fp_line
			(start 0.2794 0.9906)
			(end 0.2794 -0.1016)
			(stroke
				(width 0.1)
				(type default)
			)
			(layer "F.Fab")
		)
		(pad "1" smd rect
			(at 0 0)
			(size 0.508 0.508)
			(layers "F.Cu" "F.Mask" "F.Paste")
			(net "A_HSC_ISET_S")
		)
		(pad "2" smd rect
			(at 0 0.889)
			(size 0.508 0.508)
			(layers "F.Cu" "F.Mask" "F.Paste")
			(net "A_HSC_ISET")
		)
		(zone
			(layer "F.Cu")
			(hatch none 0.5)
			(connect_pads
				(clearance 0)
			)
			(min_thickness 0.25)
			(keepout
				(tracks allowed)
				(vias not_allowed)
				(pads allowed)
				(copperpour not_allowed)
				(footprints allowed)
			)
			(placement
				(enabled no)
				(sheetname "")
			)
			(fill
				(thermal_gap 0.5)
				(thermal_bridge_width 0.5)
				(island_removal_mode 0)
			)
			(polygon
				(pts
					(xy 18.9484 -84.0994) (xy 19.4564 -84.0994) (xy 19.4564 -83.7184) (xy 18.9484 -83.7184)
				)
			)
		)
		(zone
			(layer "F.Cu")
			(hatch none 0.5)
			(connect_pads
				(clearance 0)
			)
			(min_thickness 0.25)
			(keepout
				(tracks not_allowed)
				(vias allowed)
				(pads allowed)
				(copperpour not_allowed)
				(footprints allowed)
			)
			(placement
				(enabled no)
				(sheetname "")
			)
			(fill
				(thermal_gap 0.5)
				(thermal_bridge_width 0.5)
				(island_removal_mode 0)
			)
			(polygon
				(pts
					(xy 18.9484 -83.7184) (xy 19.4564 -83.7184) (xy 19.4564 -84.0994) (xy 18.9484 -84.0994)
				)
			)
		)
	)
	(footprint ""
		(layer "F.Cu")
		(at 105.62844 -73.279)
		(property "Reference" "C2D40"
			(at 0 0 0)
			(layer "F.SilkS")
			(hide yes)
			(effects
				(font
					(size 1.27 1.27)
				)
			)
		)
		(property "Value" ""
			(at 0 0 0)
			(layer "F.Fab")
			(effects
				(font
					(size 1.27 1.27)
				)
			)
		)
		(duplicate_pad_numbers_are_jumpers no)
		(fp_poly
			(pts
				(xy -0.4953 -0.2032) (xy 0.4953 -0.2032) (xy 0.4953 1.6002) (xy -0.4953 1.6002)
			)
			(stroke
				(width 0)
				(type default)
			)
			(fill no)
			(layer "F.CrtYd")
		)
		(fp_line
			(start -0.4953 -0.2032)
			(end 0.4953 -0.2032)
			(stroke
				(width 0.1)
				(type default)
			)
			(layer "F.Fab")
		)
		(fp_line
			(start -0.4953 1.6002)
			(end -0.4953 -0.2032)
			(stroke
				(width 0.1)
				(type default)
			)
			(layer "F.Fab")
		)
		(fp_line
			(start 0.4953 -0.2032)
			(end 0.4953 1.6002)
			(stroke
				(width 0.1)
				(type default)
			)
			(layer "F.Fab")
		)
		(fp_line
			(start 0.4953 1.6002)
			(end -0.4953 1.6002)
			(stroke
				(width 0.1)
				(type default)
			)
			(layer "F.Fab")
		)
		(pad "1" smd rect
			(at 0 0)
			(size 0.762 0.889)
			(layers "F.Cu" "F.Mask" "F.Paste")
			(net "PVCCMCP_CPU1")
		)
		(pad "2" smd rect
			(at 0 1.397)
			(size 0.762 0.889)
			(layers "F.Cu" "F.Mask" "F.Paste")
			(net "GND")
		)
		(zone
			(layer "F.Cu")
			(hatch none 0.5)
			(connect_pads
				(clearance 0)
			)
			(min_thickness 0.25)
			(keepout
				(tracks not_allowed)
				(vias allowed)
				(pads allowed)
				(copperpour not_allowed)
				(footprints allowed)
			)
			(placement
				(enabled no)
				(sheetname "")
			)
			(fill
				(thermal_gap 0.5)
				(thermal_bridge_width 0.5)
				(island_removal_mode 0)
			)
			(polygon
				(pts
					(xy 105.24744 -72.8345) (xy 106.00944 -72.8345) (xy 106.00944 -72.3265) (xy 105.24744 -72.3265)
				)
			)
		)
	)
	(footprint ""
		(layer "F.Cu")
		(at 270.654272 -77.636116)
		(property "Reference" "C5D34"
			(at 0 0 0)
			(layer "F.SilkS")
			(hide yes)
			(effects
				(font
					(size 1.27 1.27)
				)
			)
		)
		(property "Value" ""
			(at 0 0 0)
			(layer "F.Fab")
			(effects
				(font
					(size 1.27 1.27)
				)
			)
		)
		(duplicate_pad_numbers_are_jumpers no)
		(fp_poly
			(pts
				(xy -0.4953 -0.2032) (xy 0.4953 -0.2032) (xy 0.4953 1.6002) (xy -0.4953 1.6002)
			)
			(stroke
				(width 0)
				(type default)
			)
			(fill no)
			(layer "F.CrtYd")
		)
		(fp_line
			(start -0.4953 -0.2032)
			(end 0.4953 -0.2032)
			(stroke
				(width 0.1)
				(type default)
			)
			(layer "F.Fab")
		)
		(fp_line
			(start -0.4953 1.6002)
			(end -0.4953 -0.2032)
			(stroke
				(width 0.1)
				(type default)
			)
			(layer "F.Fab")
		)
		(fp_line
			(start 0.4953 -0.2032)
			(end 0.4953 1.6002)
			(stroke
				(width 0.1)
				(type default)
			)
			(layer "F.Fab")
		)
		(fp_line
			(start 0.4953 1.6002)
			(end -0.4953 1.6002)
			(stroke
				(width 0.1)
				(type default)
			)
			(layer "F.Fab")
		)
		(pad "1" smd rect
			(at 0 0)
			(size 0.762 0.889)
			(layers "F.Cu" "F.Mask" "F.Paste")
			(net "PVCCMCP_CPU0")
		)
		(pad "2" smd rect
			(at 0 1.397)
			(size 0.762 0.889)
			(layers "F.Cu" "F.Mask" "F.Paste")
			(net "GND")
		)
		(zone
			(layer "F.Cu")
			(hatch none 0.5)
			(connect_pads
				(clearance 0)
			)
			(min_thickness 0.25)
			(keepout
				(tracks not_allowed)
				(vias allowed)
				(pads allowed)
				(copperpour not_allowed)
				(footprints allowed)
			)
			(placement
				(enabled no)
				(sheetname "")
			)
			(fill
				(thermal_gap 0.5)
				(thermal_bridge_width 0.5)
				(island_removal_mode 0)
			)
			(polygon
				(pts
					(xy 270.273272 -77.191616) (xy 271.035272 -77.191616) (xy 271.035272 -76.683616) (xy 270.273272 -76.683616)
				)
			)
		)
	)
	(footprint ""
		(layer "F.Cu")
		(at 450.521832 -28.772104)
		(property "Reference" "C25W4"
			(at -0.8382 -0.67818 0)
			(unlocked yes)
			(layer "F.SilkS")
			(effects
				(font
					(size 0.4064 0.254)
					(thickness 0.1524)
				)
				(justify left)
			)
		)
		(property "Value" ""
			(at 0 0 0)
			(layer "F.Fab")
			(effects
				(font
					(size 1.27 1.27)
				)
			)
		)
		(duplicate_pad_numbers_are_jumpers no)
		(fp_poly
			(pts
				(xy 0.3048 -0.1016) (xy 0.3048 0.9906) (xy -0.3048 0.9906) (xy -0.3048 -0.1016)
			)
			(stroke
				(width 0)
				(type default)
			)
			(fill no)
			(layer "F.CrtYd")
		)
		(fp_line
			(start -0.3048 -0.1016)
			(end -0.3048 0.9906)
			(stroke
				(width 0.1)
				(type default)
			)
			(layer "F.Fab")
		)
		(fp_line
			(start -0.3048 0.9906)
			(end 0.3048 0.9906)
			(stroke
				(width 0.1)
				(type default)
			)
			(layer "F.Fab")
		)
		(fp_line
			(start 0.3048 -0.1016)
			(end -0.3048 -0.1016)
			(stroke
				(width 0.1)
				(type default)
			)
			(layer "F.Fab")
		)
		(fp_line
			(start 0.3048 0.9906)
			(end 0.3048 -0.1016)
			(stroke
				(width 0.1)
				(type default)
			)
			(layer "F.Fab")
		)
		(pad "1" smd rect
			(at 0 0)
			(size 0.508 0.508)
			(layers "F.Cu" "F.Mask" "F.Paste")
			(net "P1V2_AUX_BMC")
		)
		(pad "2" smd rect
			(at 0 0.889)
			(size 0.508 0.508)
			(layers "F.Cu" "F.Mask" "F.Paste")
			(net "GND")
		)
		(zone
			(layer "F.Cu")
			(hatch none 0.5)
			(connect_pads
				(clearance 0)
			)
			(min_thickness 0.25)
			(keepout
				(tracks allowed)
				(vias not_allowed)
				(pads allowed)
				(copperpour not_allowed)
				(footprints allowed)
			)
			(placement
				(enabled no)
				(sheetname "")
			)
			(fill
				(thermal_gap 0.5)
				(thermal_bridge_width 0.5)
				(island_removal_mode 0)
			)
			(polygon
				(pts
					(xy 450.267832 -28.518104) (xy 450.775832 -28.518104) (xy 450.775832 -28.137104) (xy 450.267832 -28.137104)
				)
			)
		)
		(zone
			(layer "F.Cu")
			(hatch none 0.5)
			(connect_pads
				(clearance 0)
			)
			(min_thickness 0.25)
			(keepout
				(tracks not_allowed)
				(vias allowed)
				(pads allowed)
				(copperpour not_allowed)
				(footprints allowed)
			)
			(placement
				(enabled no)
				(sheetname "")
			)
			(fill
				(thermal_gap 0.5)
				(thermal_bridge_width 0.5)
				(island_removal_mode 0)
			)
			(polygon
				(pts
					(xy 450.267832 -28.137104) (xy 450.775832 -28.137104) (xy 450.775832 -28.518104) (xy 450.267832 -28.518104)
				)
			)
		)
	)
	(footprint ""
		(layer "F.Cu")
		(at 174.639224 -75.004168 -90)
		(property "Reference" "R4W4"
			(at -0.8382 -0.67818 270)
			(unlocked yes)
			(layer "F.SilkS")
			(effects
				(font
					(size 0.4064 0.254)
					(thickness 0.1524)
				)
				(justify left)
			)
		)
		(property "Value" ""
			(at 0 0 270)
			(layer "F.Fab")
			(effects
				(font
					(size 1.27 1.27)
				)
			)
		)
		(duplicate_pad_numbers_are_jumpers no)
		(fp_poly
			(pts
				(xy -0.2794 -0.1016) (xy 0.2794 -0.1016) (xy 0.2794 0.9906) (xy -0.2794 0.9906)
			)
			(stroke
				(width 0)
				(type default)
			)
			(fill no)
			(layer "F.CrtYd")
		)
		(fp_line
			(start -0.2794 0.9906)
			(end 0.2794 0.9906)
			(stroke
				(width 0.1)
				(type default)
			)
			(layer "F.Fab")
		)
		(fp_line
			(start 0.2794 0.9906)
			(end 0.2794 -0.1016)
			(stroke
				(width 0.1)
				(type default)
			)
			(layer "F.Fab")
		)
		(fp_line
			(start -0.2794 -0.1016)
			(end -0.2794 0.9906)
			(stroke
				(width 0.1)
				(type default)
			)
			(layer "F.Fab")
		)
		(fp_line
			(start 0.2794 -0.1016)
			(end -0.2794 -0.1016)
			(stroke
				(width 0.1)
				(type default)
			)
			(layer "F.Fab")
		)
		(pad "1" smd rect
			(at 0 0 270)
			(size 0.508 0.508)
			(layers "F.Cu" "F.Mask" "F.Paste")
			(net "P3V3_DB1200")
		)
		(pad "2" smd rect
			(at 0 0.889 270)
			(size 0.508 0.508)
			(layers "F.Cu" "F.Mask" "F.Paste")
			(net "SMB_HOST_STBY_LVC3_SCL_R2")
		)
		(zone
			(layer "F.Cu")
			(hatch none 0.5)
			(connect_pads
				(clearance 0)
			)
			(min_thickness 0.25)
			(keepout
				(tracks not_allowed)
				(vias allowed)
				(pads allowed)
				(copperpour not_allowed)
				(footprints allowed)
			)
			(placement
				(enabled no)
				(sheetname "")
			)
			(fill
				(thermal_gap 0.5)
				(thermal_bridge_width 0.5)
				(island_removal_mode 0)
			)
			(polygon
				(pts
					(xy 174.004224 -75.258168) (xy 174.004224 -74.750168) (xy 174.385224 -74.750168) (xy 174.385224 -75.258168)
				)
			)
		)
		(zone
			(layer "F.Cu")
			(hatch none 0.5)
			(connect_pads
				(clearance 0)
			)
			(min_thickness 0.25)
			(keepout
				(tracks allowed)
				(vias not_allowed)
				(pads allowed)
				(copperpour not_allowed)
				(footprints allowed)
			)
			(placement
				(enabled no)
				(sheetname "")
			)
			(fill
				(thermal_gap 0.5)
				(thermal_bridge_width 0.5)
				(island_removal_mode 0)
			)
			(polygon
				(pts
					(xy 174.385224 -75.258168) (xy 174.385224 -74.750168) (xy 174.004224 -74.750168) (xy 174.004224 -75.258168)
				)
			)
		)
	)
	(footprint ""
		(layer "F.Cu")
		(at 19.812 -86.6267 180)
		(property "Reference" "R1D53"
			(at 0 0 180)
			(layer "F.SilkS")
			(hide yes)
			(effects
				(font
					(size 1.27 1.27)
				)
			)
		)
		(property "Value" ""
			(at 0 0 180)
			(layer "F.Fab")
			(effects
				(font
					(size 1.27 1.27)
				)
			)
		)
		(duplicate_pad_numbers_are_jumpers no)
		(fp_rect
			(start -0.2794 0.9906)
			(end 0.2794 -0.1016)
			(stroke
				(width 0)
				(type default)
			)
			(fill no)
			(layer "F.CrtYd")
		)
		(fp_line
			(start 0.2794 0.9906)
			(end 0.2794 -0.1016)
			(stroke
				(width 0.1)
				(type default)
			)
			(layer "F.Fab")
		)
		(fp_line
			(start 0.2794 -0.1016)
			(end -0.2794 -0.1016)
			(stroke
				(width 0.1)
				(type default)
			)
			(layer "F.Fab")
		)
		(fp_line
			(start -0.2794 0.9906)
			(end 0.2794 0.9906)
			(stroke
				(width 0.1)
				(type default)
			)
			(layer "F.Fab")
		)
		(fp_line
			(start -0.2794 -0.1016)
			(end -0.2794 0.9906)
			(stroke
				(width 0.1)
				(type default)
			)
			(layer "F.Fab")
		)
		(pad "1" smd rect
			(at 0 0 180)
			(size 0.508 0.508)
			(layers "F.Cu" "F.Mask" "F.Paste")
			(net "P3V3_STBY")
		)
		(pad "2" smd rect
			(at 0 0.889 180)
			(size 0.508 0.508)
			(layers "F.Cu" "F.Mask" "F.Paste")
			(net "PU_VR_PVCCIN_CPU1_FLT1_SMBALT_N")
		)
		(zone
			(layer "F.Cu")
			(hatch none 0.5)
			(connect_pads
				(clearance 0)
			)
			(min_thickness 0.25)
			(keepout
				(tracks allowed)
				(vias not_allowed)
				(pads allowed)
				(copperpour not_allowed)
				(footprints allowed)
			)
			(placement
				(enabled no)
				(sheetname "")
			)
			(fill
				(thermal_gap 0.5)
				(thermal_bridge_width 0.5)
				(island_removal_mode 0)
			)
			(polygon
				(pts
					(xy 20.066 -87.2617) (xy 19.558 -87.2617) (xy 19.558 -86.8807) (xy 20.066 -86.8807)
				)
			)
		)
		(zone
			(layer "F.Cu")
			(hatch none 0.5)
			(connect_pads
				(clearance 0)
			)
			(min_thickness 0.25)
			(keepout
				(tracks not_allowed)
				(vias allowed)
				(pads allowed)
				(copperpour not_allowed)
				(footprints allowed)
			)
			(placement
				(enabled no)
				(sheetname "")
			)
			(fill
				(thermal_gap 0.5)
				(thermal_bridge_width 0.5)
				(island_removal_mode 0)
			)
			(polygon
				(pts
					(xy 20.066 -87.2617) (xy 19.558 -87.2617) (xy 19.558 -86.8807) (xy 20.066 -86.8807)
				)
			)
		)
	)
	(footprint ""
		(layer "F.Cu")
		(at 330.835 -12.8016 180)
		(property "Reference" "C6G3"
			(at 0 0 180)
			(layer "F.SilkS")
			(hide yes)
			(effects
				(font
					(size 1.27 1.27)
				)
			)
		)
		(property "Value" ""
			(at 0 0 180)
			(layer "F.Fab")
			(effects
				(font
					(size 1.27 1.27)
				)
			)
		)
		(duplicate_pad_numbers_are_jumpers no)
		(fp_rect
			(start 0.7239 -0.2159)
			(end -0.7239 1.9939)
			(stroke
				(width 0)
				(type default)
			)
			(fill no)
			(layer "F.CrtYd")
		)
		(fp_line
			(start 0.7239 1.9939)
			(end 0.7239 -0.2159)
			(stroke
				(width 0.1)
				(type default)
			)
			(layer "F.Fab")
		)
		(fp_line
			(start 0.7239 -0.2159)
			(end -0.7239 -0.2159)
			(stroke
				(width 0.1)
				(type default)
			)
			(layer "F.Fab")
		)
		(fp_line
			(start -0.7239 1.9939)
			(end 0.7239 1.9939)
			(stroke
				(width 0.1)
				(type default)
			)
			(layer "F.Fab")
		)
		(fp_line
			(start -0.7239 -0.2159)
			(end -0.7239 1.9939)
			(stroke
				(width 0.1)
				(type default)
			)
			(layer "F.Fab")
		)
		(pad "1" smd rect
			(at 0 0 180)
			(size 1.27 1.016)
			(layers "F.Cu" "F.Mask" "F.Paste")
			(net "PVDDQ_ABC")
		)
		(pad "2" smd rect
			(at 0 1.778 180)
			(size 1.27 1.016)
			(layers "F.Cu" "F.Mask" "F.Paste")
			(net "GND")
		)
		(zone
			(layer "F.Cu")
			(hatch none 0.5)
			(connect_pads
				(clearance 0)
			)
			(min_thickness 0.25)
			(keepout
				(tracks not_allowed)
				(vias allowed)
				(pads allowed)
				(copperpour not_allowed)
				(footprints allowed)
			)
			(placement
				(enabled no)
				(sheetname "")
			)
			(fill
				(thermal_gap 0.5)
				(thermal_bridge_width 0.5)
				(island_removal_mode 0)
			)
			(polygon
				(pts
					(xy 330.2 -13.3096) (xy 331.47 -13.3096) (xy 331.47 -14.0716) (xy 330.2 -14.0716)
				)
			)
		)
	)
	(footprint ""
		(layer "F.Cu")
		(at 343.492328 -156.591 180)
		(property "Reference" "CT44"
			(at -0.8382 -0.67818 180)
			(unlocked yes)
			(layer "F.SilkS")
			(effects
				(font
					(size 0.4064 0.254)
					(thickness 0.1524)
				)
				(justify left)
			)
		)
		(property "Value" ""
			(at 0 0 180)
			(layer "F.Fab")
			(effects
				(font
					(size 1.27 1.27)
				)
			)
		)
		(duplicate_pad_numbers_are_jumpers no)
		(fp_poly
			(pts
				(xy 0.3048 -0.1016) (xy 0.3048 0.9906) (xy -0.3048 0.9906) (xy -0.3048 -0.1016)
			)
			(stroke
				(width 0)
				(type default)
			)
			(fill no)
			(layer "F.CrtYd")
		)
		(fp_line
			(start 0.3048 0.9906)
			(end 0.3048 -0.1016)
			(stroke
				(width 0.1)
				(type default)
			)
			(layer "F.Fab")
		)
		(fp_line
			(start 0.3048 -0.1016)
			(end -0.3048 -0.1016)
			(stroke
				(width 0.1)
				(type default)
			)
			(layer "F.Fab")
		)
		(fp_line
			(start -0.3048 0.9906)
			(end 0.3048 0.9906)
			(stroke
				(width 0.1)
				(type default)
			)
			(layer "F.Fab")
		)
		(fp_line
			(start -0.3048 -0.1016)
			(end -0.3048 0.9906)
			(stroke
				(width 0.1)
				(type default)
			)
			(layer "F.Fab")
		)
		(pad "1" smd rect
			(at 0 0 180)
			(size 0.508 0.508)
			(layers "F.Cu" "F.Mask" "F.Paste")
			(net "VR_PVDDQ_DEF_PH1_SW")
		)
		(pad "2" smd rect
			(at 0 0.889 180)
			(size 0.508 0.508)
			(layers "F.Cu" "F.Mask" "F.Paste")
			(net "VR_PVDDQ_DEF_PH1_SW_RC")
		)
		(zone
			(layer "F.Cu")
			(hatch none 0.5)
			(connect_pads
				(clearance 0)
			)
			(min_thickness 0.25)
			(keepout
				(tracks not_allowed)
				(vias allowed)
				(pads allowed)
				(copperpour not_allowed)
				(footprints allowed)
			)
			(placement
				(enabled no)
				(sheetname "")
			)
			(fill
				(thermal_gap 0.5)
				(thermal_bridge_width 0.5)
				(island_removal_mode 0)
			)
			(polygon
				(pts
					(xy 343.746328 -157.226) (xy 343.238328 -157.226) (xy 343.238328 -156.845) (xy 343.746328 -156.845)
				)
			)
		)
		(zone
			(layer "F.Cu")
			(hatch none 0.5)
			(connect_pads
				(clearance 0)
			)
			(min_thickness 0.25)
			(keepout
				(tracks allowed)
				(vias not_allowed)
				(pads allowed)
				(copperpour not_allowed)
				(footprints allowed)
			)
			(placement
				(enabled no)
				(sheetname "")
			)
			(fill
				(thermal_gap 0.5)
				(thermal_bridge_width 0.5)
				(island_removal_mode 0)
			)
			(polygon
				(pts
					(xy 343.746328 -156.845) (xy 343.238328 -156.845) (xy 343.238328 -157.226) (xy 343.746328 -157.226)
				)
			)
		)
	)
	(footprint ""
		(layer "F.Cu")
		(at 193.5099 -70.88124)
		(property "Reference" "R4D72"
			(at 0 0 0)
			(layer "F.SilkS")
			(hide yes)
			(effects
				(font
					(size 1.27 1.27)
				)
			)
		)
		(property "Value" ""
			(at 0 0 0)
			(layer "F.Fab")
			(effects
				(font
					(size 1.27 1.27)
				)
			)
		)
		(duplicate_pad_numbers_are_jumpers no)
		(fp_poly
			(pts
				(xy -0.2794 -0.1016) (xy 0.2794 -0.1016) (xy 0.2794 0.9906) (xy -0.2794 0.9906)
			)
			(stroke
				(width 0)
				(type default)
			)
			(fill no)
			(layer "F.CrtYd")
		)
		(fp_line
			(start -0.2794 -0.1016)
			(end -0.2794 0.9906)
			(stroke
				(width 0.1)
				(type default)
			)
			(layer "F.Fab")
		)
		(fp_line
			(start -0.2794 0.9906)
			(end 0.2794 0.9906)
			(stroke
				(width 0.1)
				(type default)
			)
			(layer "F.Fab")
		)
		(fp_line
			(start 0.2794 -0.1016)
			(end -0.2794 -0.1016)
			(stroke
				(width 0.1)
				(type default)
			)
			(layer "F.Fab")
		)
		(fp_line
			(start 0.2794 0.9906)
			(end 0.2794 -0.1016)
			(stroke
				(width 0.1)
				(type default)
			)
			(layer "F.Fab")
		)
		(pad "1" smd rect
			(at 0 0)
			(size 0.508 0.508)
			(layers "F.Cu" "F.Mask" "F.Paste")
			(net "VR_PVCCIN_CPU0_PH3_OCSET")
		)
		(pad "2" smd rect
			(at 0 0.889)
			(size 0.508 0.508)
			(layers "F.Cu" "F.Mask" "F.Paste")
			(net "GND")
		)
		(zone
			(layer "F.Cu")
			(hatch none 0.5)
			(connect_pads
				(clearance 0)
			)
			(min_thickness 0.25)
			(keepout
				(tracks allowed)
				(vias not_allowed)
				(pads allowed)
				(copperpour not_allowed)
				(footprints allowed)
			)
			(placement
				(enabled no)
				(sheetname "")
			)
			(fill
				(thermal_gap 0.5)
				(thermal_bridge_width 0.5)
				(island_removal_mode 0)
			)
			(polygon
				(pts
					(xy 193.2559 -70.62724) (xy 193.7639 -70.62724) (xy 193.7639 -70.24624) (xy 193.2559 -70.24624)
				)
			)
		)
		(zone
			(layer "F.Cu")
			(hatch none 0.5)
			(connect_pads
				(clearance 0)
			)
			(min_thickness 0.25)
			(keepout
				(tracks not_allowed)
				(vias allowed)
				(pads allowed)
				(copperpour not_allowed)
				(footprints allowed)
			)
			(placement
				(enabled no)
				(sheetname "")
			)
			(fill
				(thermal_gap 0.5)
				(thermal_bridge_width 0.5)
				(island_removal_mode 0)
			)
			(polygon
				(pts
					(xy 193.2559 -70.24624) (xy 193.7639 -70.24624) (xy 193.7639 -70.62724) (xy 193.2559 -70.62724)
				)
			)
		)
	)
	(footprint ""
		(layer "F.Cu")
		(at 353.810062 -128.493266 180)
		(property "Reference" "R7B12"
			(at 0 0 180)
			(layer "F.SilkS")
			(hide yes)
			(effects
				(font
					(size 1.27 1.27)
				)
			)
		)
		(property "Value" ""
			(at 0 0 180)
			(layer "F.Fab")
			(effects
				(font
					(size 1.27 1.27)
				)
			)
		)
		(duplicate_pad_numbers_are_jumpers no)
		(fp_poly
			(pts
				(xy -0.2794 -0.1016) (xy 0.2794 -0.1016) (xy 0.2794 0.9906) (xy -0.2794 0.9906)
			)
			(stroke
				(width 0)
				(type default)
			)
			(fill no)
			(layer "F.CrtYd")
		)
		(fp_line
			(start 0.2794 0.9906)
			(end 0.2794 -0.1016)
			(stroke
				(width 0.1)
				(type default)
			)
			(layer "F.Fab")
		)
		(fp_line
			(start 0.2794 -0.1016)
			(end -0.2794 -0.1016)
			(stroke
				(width 0.1)
				(type default)
			)
			(layer "F.Fab")
		)
		(fp_line
			(start -0.2794 0.9906)
			(end 0.2794 0.9906)
			(stroke
				(width 0.1)
				(type default)
			)
			(layer "F.Fab")
		)
		(fp_line
			(start -0.2794 -0.1016)
			(end -0.2794 0.9906)
			(stroke
				(width 0.1)
				(type default)
			)
			(layer "F.Fab")
		)
		(pad "1" smd rect
			(at 0 0 180)
			(size 0.508 0.508)
			(layers "F.Cu" "F.Mask" "F.Paste")
			(net "PWRGD_PVPP_DEF_R")
		)
		(pad "2" smd rect
			(at 0 0.889 180)
			(size 0.508 0.508)
			(layers "F.Cu" "F.Mask" "F.Paste")
			(net "PWRGD_PVPP_DEF")
		)
		(zone
			(layer "F.Cu")
			(hatch none 0.5)
			(connect_pads
				(clearance 0)
			)
			(min_thickness 0.25)
			(keepout
				(tracks not_allowed)
				(vias allowed)
				(pads allowed)
				(copperpour not_allowed)
				(footprints allowed)
			)
			(placement
				(enabled no)
				(sheetname "")
			)
			(fill
				(thermal_gap 0.5)
				(thermal_bridge_width 0.5)
				(island_removal_mode 0)
			)
			(polygon
				(pts
					(xy 354.064062 -129.128266) (xy 353.556062 -129.128266) (xy 353.556062 -128.747266) (xy 354.064062 -128.747266)
				)
			)
		)
		(zone
			(layer "F.Cu")
			(hatch none 0.5)
			(connect_pads
				(clearance 0)
			)
			(min_thickness 0.25)
			(keepout
				(tracks allowed)
				(vias not_allowed)
				(pads allowed)
				(copperpour not_allowed)
				(footprints allowed)
			)
			(placement
				(enabled no)
				(sheetname "")
			)
			(fill
				(thermal_gap 0.5)
				(thermal_bridge_width 0.5)
				(island_removal_mode 0)
			)
			(polygon
				(pts
					(xy 354.064062 -128.747266) (xy 353.556062 -128.747266) (xy 353.556062 -129.128266) (xy 354.064062 -129.128266)
				)
			)
		)
	)
	(footprint ""
		(layer "F.Cu")
		(at 183.215026 -125.6157 180)
		(property "Reference" "R12W8"
			(at 0 0 180)
			(layer "F.SilkS")
			(hide yes)
			(effects
				(font
					(size 1.27 1.27)
				)
			)
		)
		(property "Value" "*"
			(at 0.064008 -4.108196 180)
			(unlocked yes)
			(layer "F.Fab")
			(hide yes)
			(effects
				(font
					(size 1.27 1.016)
					(thickness 0.1524)
				)
			)
		)
		(property "Device Type" "4D02R2F-GP_SMD-RG2-4D02R2F-GP,A"
			(at 0.064008 -5.632196 180)
			(unlocked yes)
			(layer "F.Fab")
			(hide yes)
			(effects
				(font
					(size 1.27 1.016)
					(thickness 0.1524)
				)
			)
		)
		(duplicate_pad_numbers_are_jumpers no)
		(fp_line
			(start 0.508 -0.9398)
			(end -0.508 -0.9398)
			(stroke
				(width 0.1524)
				(type default)
			)
			(layer "F.SilkS")
		)
		(fp_line
			(start -0.508 -0.9398)
			(end -0.508 0.9398)
			(stroke
				(width 0.1524)
				(type default)
			)
			(layer "F.SilkS")
		)
		(fp_rect
			(start -0.508 0.9398)
			(end 0.508 -0.9398)
			(stroke
				(width 0)
				(type default)
			)
			(fill no)
			(layer "F.CrtYd")
		)
		(fp_rect
			(start -0.508 0.9398)
			(end 0.508 -0.9398)
			(stroke
				(width 0)
				(type default)
			)
			(fill no)
			(layer "F.Fab")
		)
		(pad "1" smd custom
			(at 0 -0.4445 180)
			(size 0.1397 0.1397)
			(layers "F.Cu" "F.Mask" "F.Paste")
			(net "P12V_STBY")
			(options
				(clearance outline)
				(anchor circle)
			)
			(primitives
				(gr_poly
					(pts
						(arc
							(start -0.1778 -0.2794)
							(mid -0.249642 -0.249642)
							(end -0.2794 -0.1778)
						)
						(arc
							(start -0.2794 0.1778)
							(mid -0.249642 0.249642)
							(end -0.1778 0.2794)
						)
						(arc
							(start 0.1778 0.2794)
							(mid 0.249642 0.249642)
							(end 0.2794 0.1778)
						)
						(arc
							(start 0.2794 -0.1778)
							(mid 0.249642 -0.249642)
							(end 0.1778 -0.2794)
						)
					)
					(width 0)
					(fill yes)
				)
			)
		)
		(pad "2" smd custom
			(at 0 0.4445 180)
			(size 0.1397 0.1397)
			(layers "F.Cu" "F.Mask" "F.Paste")
			(net "P12V_NVDIMM_DEF_D")
			(options
				(clearance outline)
				(anchor circle)
			)
			(primitives
				(gr_poly
					(pts
						(arc
							(start -0.1778 -0.2794)
							(mid -0.249642 -0.249642)
							(end -0.2794 -0.1778)
						)
						(arc
							(start -0.2794 0.1778)
							(mid -0.249642 0.249642)
							(end -0.1778 0.2794)
						)
						(arc
							(start 0.1778 0.2794)
							(mid 0.249642 0.249642)
							(end 0.2794 0.1778)
						)
						(arc
							(start 0.2794 -0.1778)
							(mid 0.249642 -0.249642)
							(end 0.1778 -0.2794)
						)
					)
					(width 0)
					(fill yes)
				)
			)
		)
	)
	(footprint ""
		(layer "F.Cu")
		(at 467.0806 -126.6952 180)
		(property "Reference" "R9B14"
			(at 0 0 180)
			(layer "F.SilkS")
			(hide yes)
			(effects
				(font
					(size 1.27 1.27)
				)
			)
		)
		(property "Value" ""
			(at 0 0 180)
			(layer "F.Fab")
			(effects
				(font
					(size 1.27 1.27)
				)
			)
		)
		(duplicate_pad_numbers_are_jumpers no)
		(fp_poly
			(pts
				(xy -0.2794 -0.1016) (xy 0.2794 -0.1016) (xy 0.2794 0.9906) (xy -0.2794 0.9906)
			)
			(stroke
				(width 0)
				(type default)
			)
			(fill no)
			(layer "F.CrtYd")
		)
		(fp_line
			(start 0.2794 0.9906)
			(end 0.2794 -0.1016)
			(stroke
				(width 0.1)
				(type default)
			)
			(layer "F.Fab")
		)
		(fp_line
			(start 0.2794 -0.1016)
			(end -0.2794 -0.1016)
			(stroke
				(width 0.1)
				(type default)
			)
			(layer "F.Fab")
		)
		(fp_line
			(start -0.2794 0.9906)
			(end 0.2794 0.9906)
			(stroke
				(width 0.1)
				(type default)
			)
			(layer "F.Fab")
		)
		(fp_line
			(start -0.2794 -0.1016)
			(end -0.2794 0.9906)
			(stroke
				(width 0.1)
				(type default)
			)
			(layer "F.Fab")
		)
		(pad "1" smd rect
			(at 0 0 180)
			(size 0.508 0.508)
			(layers "F.Cu" "F.Mask" "F.Paste")
			(net "PWRGD_CPU0_G")
		)
		(pad "2" smd rect
			(at 0 0.889 180)
			(size 0.508 0.508)
			(layers "F.Cu" "F.Mask" "F.Paste")
			(net "PWRGD_CPU0_G_R")
		)
		(zone
			(layer "F.Cu")
			(hatch none 0.5)
			(connect_pads
				(clearance 0)
			)
			(min_thickness 0.25)
			(keepout
				(tracks not_allowed)
				(vias allowed)
				(pads allowed)
				(copperpour not_allowed)
				(footprints allowed)
			)
			(placement
				(enabled no)
				(sheetname "")
			)
			(fill
				(thermal_gap 0.5)
				(thermal_bridge_width 0.5)
				(island_removal_mode 0)
			)
			(polygon
				(pts
					(xy 467.3346 -127.3302) (xy 466.8266 -127.3302) (xy 466.8266 -126.9492) (xy 467.3346 -126.9492)
				)
			)
		)
		(zone
			(layer "F.Cu")
			(hatch none 0.5)
			(connect_pads
				(clearance 0)
			)
			(min_thickness 0.25)
			(keepout
				(tracks allowed)
				(vias not_allowed)
				(pads allowed)
				(copperpour not_allowed)
				(footprints allowed)
			)
			(placement
				(enabled no)
				(sheetname "")
			)
			(fill
				(thermal_gap 0.5)
				(thermal_bridge_width 0.5)
				(island_removal_mode 0)
			)
			(polygon
				(pts
					(xy 467.3346 -126.9492) (xy 466.8266 -126.9492) (xy 466.8266 -127.3302) (xy 467.3346 -127.3302)
				)
			)
		)
	)
	(footprint ""
		(layer "F.Cu")
		(at 28.85948 -96.19234 -90)
		(property "Reference" "R1C37"
			(at 0 0 270)
			(layer "F.SilkS")
			(hide yes)
			(effects
				(font
					(size 1.27 1.27)
				)
			)
		)
		(property "Value" ""
			(at 0 0 270)
			(layer "F.Fab")
			(effects
				(font
					(size 1.27 1.27)
				)
			)
		)
		(duplicate_pad_numbers_are_jumpers no)
		(fp_poly
			(pts
				(xy -0.2794 -0.1016) (xy 0.2794 -0.1016) (xy 0.2794 0.9906) (xy -0.2794 0.9906)
			)
			(stroke
				(width 0)
				(type default)
			)
			(fill no)
			(layer "F.CrtYd")
		)
		(fp_line
			(start -0.2794 0.9906)
			(end 0.2794 0.9906)
			(stroke
				(width 0.1)
				(type default)
			)
			(layer "F.Fab")
		)
		(fp_line
			(start 0.2794 0.9906)
			(end 0.2794 -0.1016)
			(stroke
				(width 0.1)
				(type default)
			)
			(layer "F.Fab")
		)
		(fp_line
			(start -0.2794 -0.1016)
			(end -0.2794 0.9906)
			(stroke
				(width 0.1)
				(type default)
			)
			(layer "F.Fab")
		)
		(fp_line
			(start 0.2794 -0.1016)
			(end -0.2794 -0.1016)
			(stroke
				(width 0.1)
				(type default)
			)
			(layer "F.Fab")
		)
		(pad "1" smd rect
			(at 0 0 270)
			(size 0.508 0.508)
			(layers "F.Cu" "F.Mask" "F.Paste")
			(net "VR_PVSA_CPU1_OCSET")
		)
		(pad "2" smd rect
			(at 0 0.889 270)
			(size 0.508 0.508)
			(layers "F.Cu" "F.Mask" "F.Paste")
			(net "GND")
		)
		(zone
			(layer "F.Cu")
			(hatch none 0.5)
			(connect_pads
				(clearance 0)
			)
			(min_thickness 0.25)
			(keepout
				(tracks not_allowed)
				(vias allowed)
				(pads allowed)
				(copperpour not_allowed)
				(footprints allowed)
			)
			(placement
				(enabled no)
				(sheetname "")
			)
			(fill
				(thermal_gap 0.5)
				(thermal_bridge_width 0.5)
				(island_removal_mode 0)
			)
			(polygon
				(pts
					(xy 28.22448 -96.44634) (xy 28.22448 -95.93834) (xy 28.60548 -95.93834) (xy 28.60548 -96.44634)
				)
			)
		)
		(zone
			(layer "F.Cu")
			(hatch none 0.5)
			(connect_pads
				(clearance 0)
			)
			(min_thickness 0.25)
			(keepout
				(tracks allowed)
				(vias not_allowed)
				(pads allowed)
				(copperpour not_allowed)
				(footprints allowed)
			)
			(placement
				(enabled no)
				(sheetname "")
			)
			(fill
				(thermal_gap 0.5)
				(thermal_bridge_width 0.5)
				(island_removal_mode 0)
			)
			(polygon
				(pts
					(xy 28.60548 -96.44634) (xy 28.60548 -95.93834) (xy 28.22448 -95.93834) (xy 28.22448 -96.44634)
				)
			)
		)
	)
	(footprint ""
		(layer "F.Cu")
		(at 107.240578 -84.890102)
		(property "Reference" "C3D1"
			(at 0 0 0)
			(layer "F.SilkS")
			(hide yes)
			(effects
				(font
					(size 1.27 1.27)
				)
			)
		)
		(property "Value" ""
			(at 0 0 0)
			(layer "F.Fab")
			(effects
				(font
					(size 1.27 1.27)
				)
			)
		)
		(duplicate_pad_numbers_are_jumpers no)
		(fp_poly
			(pts
				(xy -0.4953 -0.2032) (xy 0.4953 -0.2032) (xy 0.4953 1.6002) (xy -0.4953 1.6002)
			)
			(stroke
				(width 0)
				(type default)
			)
			(fill no)
			(layer "F.CrtYd")
		)
		(fp_line
			(start -0.4953 -0.2032)
			(end 0.4953 -0.2032)
			(stroke
				(width 0.1)
				(type default)
			)
			(layer "F.Fab")
		)
		(fp_line
			(start -0.4953 1.6002)
			(end -0.4953 -0.2032)
			(stroke
				(width 0.1)
				(type default)
			)
			(layer "F.Fab")
		)
		(fp_line
			(start 0.4953 -0.2032)
			(end 0.4953 1.6002)
			(stroke
				(width 0.1)
				(type default)
			)
			(layer "F.Fab")
		)
		(fp_line
			(start 0.4953 1.6002)
			(end -0.4953 1.6002)
			(stroke
				(width 0.1)
				(type default)
			)
			(layer "F.Fab")
		)
		(pad "1" smd rect
			(at 0 0)
			(size 0.762 0.889)
			(layers "F.Cu" "F.Mask" "F.Paste")
			(net "PVDDQ_KLM")
		)
		(pad "2" smd rect
			(at 0 1.397)
			(size 0.762 0.889)
			(layers "F.Cu" "F.Mask" "F.Paste")
			(net "GND")
		)
		(zone
			(layer "F.Cu")
			(hatch none 0.5)
			(connect_pads
				(clearance 0)
			)
			(min_thickness 0.25)
			(keepout
				(tracks not_allowed)
				(vias allowed)
				(pads allowed)
				(copperpour not_allowed)
				(footprints allowed)
			)
			(placement
				(enabled no)
				(sheetname "")
			)
			(fill
				(thermal_gap 0.5)
				(thermal_bridge_width 0.5)
				(island_removal_mode 0)
			)
			(polygon
				(pts
					(xy 106.859578 -84.445602) (xy 107.621578 -84.445602) (xy 107.621578 -83.937602) (xy 106.859578 -83.937602)
				)
			)
		)
	)
	(footprint ""
		(layer "F.Cu")
		(at 174.6377 -70.612 -90)
		(property "Reference" "R4D47"
			(at 0 0 270)
			(layer "F.SilkS")
			(hide yes)
			(effects
				(font
					(size 1.27 1.27)
				)
			)
		)
		(property "Value" ""
			(at 0 0 270)
			(layer "F.Fab")
			(effects
				(font
					(size 1.27 1.27)
				)
			)
		)
		(duplicate_pad_numbers_are_jumpers no)
		(fp_poly
			(pts
				(xy -0.2794 -0.1016) (xy 0.2794 -0.1016) (xy 0.2794 0.9906) (xy -0.2794 0.9906)
			)
			(stroke
				(width 0)
				(type default)
			)
			(fill no)
			(layer "F.CrtYd")
		)
		(fp_line
			(start -0.2794 0.9906)
			(end 0.2794 0.9906)
			(stroke
				(width 0.1)
				(type default)
			)
			(layer "F.Fab")
		)
		(fp_line
			(start 0.2794 0.9906)
			(end 0.2794 -0.1016)
			(stroke
				(width 0.1)
				(type default)
			)
			(layer "F.Fab")
		)
		(fp_line
			(start -0.2794 -0.1016)
			(end -0.2794 0.9906)
			(stroke
				(width 0.1)
				(type default)
			)
			(layer "F.Fab")
		)
		(fp_line
			(start 0.2794 -0.1016)
			(end -0.2794 -0.1016)
			(stroke
				(width 0.1)
				(type default)
			)
			(layer "F.Fab")
		)
		(pad "1" smd rect
			(at 0 0 270)
			(size 0.508 0.508)
			(layers "F.Cu" "F.Mask" "F.Paste")
			(net "P3V3_STBY")
		)
		(pad "2" smd rect
			(at 0 0.889 270)
			(size 0.508 0.508)
			(layers "F.Cu" "F.Mask" "F.Paste")
			(net "VR_PVCCIO_CPU1_VDD")
		)
		(zone
			(layer "F.Cu")
			(hatch none 0.5)
			(connect_pads
				(clearance 0)
			)
			(min_thickness 0.25)
			(keepout
				(tracks not_allowed)
				(vias allowed)
				(pads allowed)
				(copperpour not_allowed)
				(footprints allowed)
			)
			(placement
				(enabled no)
				(sheetname "")
			)
			(fill
				(thermal_gap 0.5)
				(thermal_bridge_width 0.5)
				(island_removal_mode 0)
			)
			(polygon
				(pts
					(xy 174.0027 -70.866) (xy 174.0027 -70.358) (xy 174.3837 -70.358) (xy 174.3837 -70.866)
				)
			)
		)
		(zone
			(layer "F.Cu")
			(hatch none 0.5)
			(connect_pads
				(clearance 0)
			)
			(min_thickness 0.25)
			(keepout
				(tracks allowed)
				(vias not_allowed)
				(pads allowed)
				(copperpour not_allowed)
				(footprints allowed)
			)
			(placement
				(enabled no)
				(sheetname "")
			)
			(fill
				(thermal_gap 0.5)
				(thermal_bridge_width 0.5)
				(island_removal_mode 0)
			)
			(polygon
				(pts
					(xy 174.3837 -70.866) (xy 174.3837 -70.358) (xy 174.0027 -70.358) (xy 174.0027 -70.866)
				)
			)
		)
	)
	(footprint ""
		(layer "F.Cu")
		(at 117.221 -77.089 -90)
		(property "Reference" "R3D9"
			(at 0 0 270)
			(layer "F.SilkS")
			(hide yes)
			(effects
				(font
					(size 1.27 1.27)
				)
			)
		)
		(property "Value" ""
			(at 0 0 270)
			(layer "F.Fab")
			(effects
				(font
					(size 1.27 1.27)
				)
			)
		)
		(duplicate_pad_numbers_are_jumpers no)
		(fp_poly
			(pts
				(xy -0.2794 -0.1016) (xy 0.2794 -0.1016) (xy 0.2794 0.9906) (xy -0.2794 0.9906)
			)
			(stroke
				(width 0)
				(type default)
			)
			(fill no)
			(layer "F.CrtYd")
		)
		(fp_line
			(start -0.2794 0.9906)
			(end 0.2794 0.9906)
			(stroke
				(width 0.1)
				(type default)
			)
			(layer "F.Fab")
		)
		(fp_line
			(start 0.2794 0.9906)
			(end 0.2794 -0.1016)
			(stroke
				(width 0.1)
				(type default)
			)
			(layer "F.Fab")
		)
		(fp_line
			(start -0.2794 -0.1016)
			(end -0.2794 0.9906)
			(stroke
				(width 0.1)
				(type default)
			)
			(layer "F.Fab")
		)
		(fp_line
			(start 0.2794 -0.1016)
			(end -0.2794 -0.1016)
			(stroke
				(width 0.1)
				(type default)
			)
			(layer "F.Fab")
		)
		(pad "1" smd rect
			(at 0 0 270)
			(size 0.508 0.508)
			(layers "F.Cu" "F.Mask" "F.Paste")
			(net "PD_CPU1_TEST12")
		)
		(pad "2" smd rect
			(at 0 0.889 270)
			(size 0.508 0.508)
			(layers "F.Cu" "F.Mask" "F.Paste")
			(net "GND")
		)
		(zone
			(layer "F.Cu")
			(hatch none 0.5)
			(connect_pads
				(clearance 0)
			)
			(min_thickness 0.25)
			(keepout
				(tracks not_allowed)
				(vias allowed)
				(pads allowed)
				(copperpour not_allowed)
				(footprints allowed)
			)
			(placement
				(enabled no)
				(sheetname "")
			)
			(fill
				(thermal_gap 0.5)
				(thermal_bridge_width 0.5)
				(island_removal_mode 0)
			)
			(polygon
				(pts
					(xy 116.586 -77.343) (xy 116.586 -76.835) (xy 116.967 -76.835) (xy 116.967 -77.343)
				)
			)
		)
		(zone
			(layer "F.Cu")
			(hatch none 0.5)
			(connect_pads
				(clearance 0)
			)
			(min_thickness 0.25)
			(keepout
				(tracks allowed)
				(vias not_allowed)
				(pads allowed)
				(copperpour not_allowed)
				(footprints allowed)
			)
			(placement
				(enabled no)
				(sheetname "")
			)
			(fill
				(thermal_gap 0.5)
				(thermal_bridge_width 0.5)
				(island_removal_mode 0)
			)
			(polygon
				(pts
					(xy 116.967 -77.343) (xy 116.967 -76.835) (xy 116.586 -76.835) (xy 116.586 -77.343)
				)
			)
		)
	)
	(footprint ""
		(layer "F.Cu")
		(at 494.1697 -125.03912 90)
		(property "Reference" "R1M8"
			(at 0 0 90)
			(layer "F.SilkS")
			(hide yes)
			(effects
				(font
					(size 1.27 1.27)
				)
			)
		)
		(property "Value" ""
			(at 0 0 90)
			(layer "F.Fab")
			(effects
				(font
					(size 1.27 1.27)
				)
			)
		)
		(duplicate_pad_numbers_are_jumpers no)
		(fp_rect
			(start 0.2794 -0.1016)
			(end -0.2794 0.9906)
			(stroke
				(width 0)
				(type default)
			)
			(fill no)
			(layer "F.CrtYd")
		)
		(fp_line
			(start 0.2794 -0.1016)
			(end -0.2794 -0.1016)
			(stroke
				(width 0.1)
				(type default)
			)
			(layer "F.Fab")
		)
		(fp_line
			(start -0.2794 -0.1016)
			(end -0.2794 0.9906)
			(stroke
				(width 0.1)
				(type default)
			)
			(layer "F.Fab")
		)
		(fp_line
			(start 0.2794 0.9906)
			(end 0.2794 -0.1016)
			(stroke
				(width 0.1)
				(type default)
			)
			(layer "F.Fab")
		)
		(fp_line
			(start -0.2794 0.9906)
			(end 0.2794 0.9906)
			(stroke
				(width 0.1)
				(type default)
			)
			(layer "F.Fab")
		)
		(pad "1" smd rect
			(at 0 0 90)
			(size 0.508 0.508)
			(layers "F.Cu" "F.Mask" "F.Paste")
			(net "SMB_SENSOR_TMP421_1_SCL")
		)
		(pad "2" smd rect
			(at 0 0.889 90)
			(size 0.508 0.508)
			(layers "F.Cu" "F.Mask" "F.Paste")
			(net "SMB_SENSOR_STBY_LVC3_SCL")
		)
		(zone
			(layer "F.Cu")
			(hatch none 0.5)
			(connect_pads
				(clearance 0)
			)
			(min_thickness 0.25)
			(keepout
				(tracks not_allowed)
				(vias allowed)
				(pads allowed)
				(copperpour not_allowed)
				(footprints allowed)
			)
			(placement
				(enabled no)
				(sheetname "")
			)
			(fill
				(thermal_gap 0.5)
				(thermal_bridge_width 0.5)
				(island_removal_mode 0)
			)
			(polygon
				(pts
					(xy 494.4237 -125.29312) (xy 494.4237 -124.78512) (xy 494.8047 -124.78512) (xy 494.8047 -125.29312)
				)
			)
		)
		(zone
			(layer "F.Cu")
			(hatch none 0.5)
			(connect_pads
				(clearance 0)
			)
			(min_thickness 0.25)
			(keepout
				(tracks allowed)
				(vias not_allowed)
				(pads allowed)
				(copperpour not_allowed)
				(footprints allowed)
			)
			(placement
				(enabled no)
				(sheetname "")
			)
			(fill
				(thermal_gap 0.5)
				(thermal_bridge_width 0.5)
				(island_removal_mode 0)
			)
			(polygon
				(pts
					(xy 494.4237 -125.29312) (xy 494.4237 -124.78512) (xy 494.8047 -124.78512) (xy 494.8047 -125.29312)
				)
			)
		)
	)
	(footprint ""
		(layer "F.Cu")
		(at 411.327092 -125.850904 -90)
		(property "Reference" "R8B14"
			(at 0 0 270)
			(layer "F.SilkS")
			(hide yes)
			(effects
				(font
					(size 1.27 1.27)
				)
			)
		)
		(property "Value" ""
			(at 0 0 270)
			(layer "F.Fab")
			(effects
				(font
					(size 1.27 1.27)
				)
			)
		)
		(duplicate_pad_numbers_are_jumpers no)
		(fp_poly
			(pts
				(xy -0.2794 -0.1016) (xy 0.2794 -0.1016) (xy 0.2794 0.9906) (xy -0.2794 0.9906)
			)
			(stroke
				(width 0)
				(type default)
			)
			(fill no)
			(layer "F.CrtYd")
		)
		(fp_line
			(start -0.2794 0.9906)
			(end 0.2794 0.9906)
			(stroke
				(width 0.1)
				(type default)
			)
			(layer "F.Fab")
		)
		(fp_line
			(start 0.2794 0.9906)
			(end 0.2794 -0.1016)
			(stroke
				(width 0.1)
				(type default)
			)
			(layer "F.Fab")
		)
		(fp_line
			(start -0.2794 -0.1016)
			(end -0.2794 0.9906)
			(stroke
				(width 0.1)
				(type default)
			)
			(layer "F.Fab")
		)
		(fp_line
			(start 0.2794 -0.1016)
			(end -0.2794 -0.1016)
			(stroke
				(width 0.1)
				(type default)
			)
			(layer "F.Fab")
		)
		(pad "1" smd rect
			(at 0 0 270)
			(size 0.508 0.508)
			(layers "F.Cu" "F.Mask" "F.Paste")
			(net "VSENSE_P1V05_PCH_STBY_AVSP")
		)
		(pad "2" smd rect
			(at 0 0.889 270)
			(size 0.508 0.508)
			(layers "F.Cu" "F.Mask" "F.Paste")
			(net "P1V05_PCH_STBY")
		)
		(zone
			(layer "F.Cu")
			(hatch none 0.5)
			(connect_pads
				(clearance 0)
			)
			(min_thickness 0.25)
			(keepout
				(tracks not_allowed)
				(vias allowed)
				(pads allowed)
				(copperpour not_allowed)
				(footprints allowed)
			)
			(placement
				(enabled no)
				(sheetname "")
			)
			(fill
				(thermal_gap 0.5)
				(thermal_bridge_width 0.5)
				(island_removal_mode 0)
			)
			(polygon
				(pts
					(xy 410.692092 -126.104904) (xy 410.692092 -125.596904) (xy 411.073092 -125.596904) (xy 411.073092 -126.104904)
				)
			)
		)
		(zone
			(layer "F.Cu")
			(hatch none 0.5)
			(connect_pads
				(clearance 0)
			)
			(min_thickness 0.25)
			(keepout
				(tracks allowed)
				(vias not_allowed)
				(pads allowed)
				(copperpour not_allowed)
				(footprints allowed)
			)
			(placement
				(enabled no)
				(sheetname "")
			)
			(fill
				(thermal_gap 0.5)
				(thermal_bridge_width 0.5)
				(island_removal_mode 0)
			)
			(polygon
				(pts
					(xy 411.073092 -126.104904) (xy 411.073092 -125.596904) (xy 410.692092 -125.596904) (xy 410.692092 -126.104904)
				)
			)
		)
	)
	(footprint ""
		(layer "F.Cu")
		(at 195.4784 -140.0556 90)
		(property "Reference" "C4A18"
			(at 0 0 90)
			(layer "F.SilkS")
			(hide yes)
			(effects
				(font
					(size 1.27 1.27)
				)
			)
		)
		(property "Value" ""
			(at 0 0 90)
			(layer "F.Fab")
			(effects
				(font
					(size 1.27 1.27)
				)
			)
		)
		(duplicate_pad_numbers_are_jumpers no)
		(fp_poly
			(pts
				(xy 0.3048 -0.1016) (xy 0.3048 0.9906) (xy -0.3048 0.9906) (xy -0.3048 -0.1016)
			)
			(stroke
				(width 0)
				(type default)
			)
			(fill no)
			(layer "F.CrtYd")
		)
		(fp_line
			(start 0.3048 -0.1016)
			(end -0.3048 -0.1016)
			(stroke
				(width 0.1)
				(type default)
			)
			(layer "F.Fab")
		)
		(fp_line
			(start -0.3048 -0.1016)
			(end -0.3048 0.9906)
			(stroke
				(width 0.1)
				(type default)
			)
			(layer "F.Fab")
		)
		(fp_line
			(start 0.3048 0.9906)
			(end 0.3048 -0.1016)
			(stroke
				(width 0.1)
				(type default)
			)
			(layer "F.Fab")
		)
		(fp_line
			(start -0.3048 0.9906)
			(end 0.3048 0.9906)
			(stroke
				(width 0.1)
				(type default)
			)
			(layer "F.Fab")
		)
		(pad "1" smd rect
			(at 0 0 90)
			(size 0.508 0.508)
			(layers "F.Cu" "F.Mask" "F.Paste")
			(net "M_E_VREF")
		)
		(pad "2" smd rect
			(at 0 0.889 90)
			(size 0.508 0.508)
			(layers "F.Cu" "F.Mask" "F.Paste")
			(net "GND")
		)
		(zone
			(layer "F.Cu")
			(hatch none 0.5)
			(connect_pads
				(clearance 0)
			)
			(min_thickness 0.25)
			(keepout
				(tracks allowed)
				(vias not_allowed)
				(pads allowed)
				(copperpour not_allowed)
				(footprints allowed)
			)
			(placement
				(enabled no)
				(sheetname "")
			)
			(fill
				(thermal_gap 0.5)
				(thermal_bridge_width 0.5)
				(island_removal_mode 0)
			)
			(polygon
				(pts
					(xy 195.7324 -139.8016) (xy 195.7324 -140.3096) (xy 196.1134 -140.3096) (xy 196.1134 -139.8016)
				)
			)
		)
		(zone
			(layer "F.Cu")
			(hatch none 0.5)
			(connect_pads
				(clearance 0)
			)
			(min_thickness 0.25)
			(keepout
				(tracks not_allowed)
				(vias allowed)
				(pads allowed)
				(copperpour not_allowed)
				(footprints allowed)
			)
			(placement
				(enabled no)
				(sheetname "")
			)
			(fill
				(thermal_gap 0.5)
				(thermal_bridge_width 0.5)
				(island_removal_mode 0)
			)
			(polygon
				(pts
					(xy 196.1134 -139.8016) (xy 196.1134 -140.3096) (xy 195.7324 -140.3096) (xy 195.7324 -139.8016)
				)
			)
		)
	)
	(footprint ""
		(layer "F.Cu")
		(at 1.27 -75.057 180)
		(property "Reference" "R9R7"
			(at 0 0 180)
			(layer "F.SilkS")
			(hide yes)
			(effects
				(font
					(size 1.27 1.27)
				)
			)
		)
		(property "Value" ""
			(at 0 0 180)
			(layer "F.Fab")
			(effects
				(font
					(size 1.27 1.27)
				)
			)
		)
		(duplicate_pad_numbers_are_jumpers no)
		(fp_poly
			(pts
				(xy -0.2794 -0.1016) (xy 0.2794 -0.1016) (xy 0.2794 0.9906) (xy -0.2794 0.9906)
			)
			(stroke
				(width 0)
				(type default)
			)
			(fill no)
			(layer "F.CrtYd")
		)
		(fp_line
			(start 0.2794 0.9906)
			(end 0.2794 -0.1016)
			(stroke
				(width 0.1)
				(type default)
			)
			(layer "F.Fab")
		)
		(fp_line
			(start 0.2794 -0.1016)
			(end -0.2794 -0.1016)
			(stroke
				(width 0.1)
				(type default)
			)
			(layer "F.Fab")
		)
		(fp_line
			(start -0.2794 0.9906)
			(end 0.2794 0.9906)
			(stroke
				(width 0.1)
				(type default)
			)
			(layer "F.Fab")
		)
		(fp_line
			(start -0.2794 -0.1016)
			(end -0.2794 0.9906)
			(stroke
				(width 0.1)
				(type default)
			)
			(layer "F.Fab")
		)
		(pad "1" smd rect
			(at 0 0 180)
			(size 0.508 0.508)
			(layers "F.Cu" "F.Mask" "F.Paste")
			(net "SMB_SENSOR_TMP421_2_SCL")
		)
		(pad "2" smd rect
			(at 0 0.889 180)
			(size 0.508 0.508)
			(layers "F.Cu" "F.Mask" "F.Paste")
			(net "SMB_SENSOR_STBY_LVC3_SCL")
		)
		(zone
			(layer "F.Cu")
			(hatch none 0.5)
			(connect_pads
				(clearance 0)
			)
			(min_thickness 0.25)
			(keepout
				(tracks not_allowed)
				(vias allowed)
				(pads allowed)
				(copperpour not_allowed)
				(footprints allowed)
			)
			(placement
				(enabled no)
				(sheetname "")
			)
			(fill
				(thermal_gap 0.5)
				(thermal_bridge_width 0.5)
				(island_removal_mode 0)
			)
			(polygon
				(pts
					(xy 1.524 -75.692) (xy 1.016 -75.692) (xy 1.016 -75.311) (xy 1.524 -75.311)
				)
			)
		)
		(zone
			(layer "F.Cu")
			(hatch none 0.5)
			(connect_pads
				(clearance 0)
			)
			(min_thickness 0.25)
			(keepout
				(tracks allowed)
				(vias not_allowed)
				(pads allowed)
				(copperpour not_allowed)
				(footprints allowed)
			)
			(placement
				(enabled no)
				(sheetname "")
			)
			(fill
				(thermal_gap 0.5)
				(thermal_bridge_width 0.5)
				(island_removal_mode 0)
			)
			(polygon
				(pts
					(xy 1.524 -75.311) (xy 1.016 -75.311) (xy 1.016 -75.692) (xy 1.524 -75.692)
				)
			)
		)
	)
	(footprint ""
		(layer "F.Cu")
		(at 377.698 -87.3125 180)
		(property "Reference" "R3N17"
			(at -0.8382 -0.67818 180)
			(unlocked yes)
			(layer "F.SilkS")
			(effects
				(font
					(size 0.4064 0.254)
					(thickness 0.1524)
				)
				(justify left)
			)
		)
		(property "Value" ""
			(at 0 0 180)
			(layer "F.Fab")
			(effects
				(font
					(size 1.27 1.27)
				)
			)
		)
		(duplicate_pad_numbers_are_jumpers no)
		(fp_poly
			(pts
				(xy -0.2794 -0.1016) (xy 0.2794 -0.1016) (xy 0.2794 0.9906) (xy -0.2794 0.9906)
			)
			(stroke
				(width 0)
				(type default)
			)
			(fill no)
			(layer "F.CrtYd")
		)
		(fp_line
			(start 0.2794 0.9906)
			(end 0.2794 -0.1016)
			(stroke
				(width 0.1)
				(type default)
			)
			(layer "F.Fab")
		)
		(fp_line
			(start 0.2794 -0.1016)
			(end -0.2794 -0.1016)
			(stroke
				(width 0.1)
				(type default)
			)
			(layer "F.Fab")
		)
		(fp_line
			(start -0.2794 0.9906)
			(end 0.2794 0.9906)
			(stroke
				(width 0.1)
				(type default)
			)
			(layer "F.Fab")
		)
		(fp_line
			(start -0.2794 -0.1016)
			(end -0.2794 0.9906)
			(stroke
				(width 0.1)
				(type default)
			)
			(layer "F.Fab")
		)
		(pad "1" smd rect
			(at 0 0 180)
			(size 0.508 0.508)
			(layers "F.Cu" "F.Mask" "F.Paste")
			(net "P3V3_STBY")
		)
		(pad "2" smd rect
			(at 0 0.889 180)
			(size 0.508 0.508)
			(layers "F.Cu" "F.Mask" "F.Paste")
			(net "SPI_PCH_IO3")
		)
		(zone
			(layer "F.Cu")
			(hatch none 0.5)
			(connect_pads
				(clearance 0)
			)
			(min_thickness 0.25)
			(keepout
				(tracks not_allowed)
				(vias allowed)
				(pads allowed)
				(copperpour not_allowed)
				(footprints allowed)
			)
			(placement
				(enabled no)
				(sheetname "")
			)
			(fill
				(thermal_gap 0.5)
				(thermal_bridge_width 0.5)
				(island_removal_mode 0)
			)
			(polygon
				(pts
					(xy 377.952 -87.9475) (xy 377.444 -87.9475) (xy 377.444 -87.5665) (xy 377.952 -87.5665)
				)
			)
		)
		(zone
			(layer "F.Cu")
			(hatch none 0.5)
			(connect_pads
				(clearance 0)
			)
			(min_thickness 0.25)
			(keepout
				(tracks allowed)
				(vias not_allowed)
				(pads allowed)
				(copperpour not_allowed)
				(footprints allowed)
			)
			(placement
				(enabled no)
				(sheetname "")
			)
			(fill
				(thermal_gap 0.5)
				(thermal_bridge_width 0.5)
				(island_removal_mode 0)
			)
			(polygon
				(pts
					(xy 377.952 -87.5665) (xy 377.444 -87.5665) (xy 377.444 -87.9475) (xy 377.952 -87.9475)
				)
			)
		)
	)
	(footprint ""
		(layer "F.Cu")
		(at 38.9128 -50.5714)
		(property "Reference" "R1E5"
			(at 0 0 0)
			(layer "F.SilkS")
			(hide yes)
			(effects
				(font
					(size 1.27 1.27)
				)
			)
		)
		(property "Value" ""
			(at 0 0 0)
			(layer "F.Fab")
			(effects
				(font
					(size 1.27 1.27)
				)
			)
		)
		(duplicate_pad_numbers_are_jumpers no)
		(fp_poly
			(pts
				(xy -0.2794 -0.1016) (xy 0.2794 -0.1016) (xy 0.2794 0.9906) (xy -0.2794 0.9906)
			)
			(stroke
				(width 0)
				(type default)
			)
			(fill no)
			(layer "F.CrtYd")
		)
		(fp_line
			(start -0.2794 -0.1016)
			(end -0.2794 0.9906)
			(stroke
				(width 0.1)
				(type default)
			)
			(layer "F.Fab")
		)
		(fp_line
			(start -0.2794 0.9906)
			(end 0.2794 0.9906)
			(stroke
				(width 0.1)
				(type default)
			)
			(layer "F.Fab")
		)
		(fp_line
			(start 0.2794 -0.1016)
			(end -0.2794 -0.1016)
			(stroke
				(width 0.1)
				(type default)
			)
			(layer "F.Fab")
		)
		(fp_line
			(start 0.2794 0.9906)
			(end 0.2794 -0.1016)
			(stroke
				(width 0.1)
				(type default)
			)
			(layer "F.Fab")
		)
		(pad "1" smd rect
			(at 0 0)
			(size 0.508 0.508)
			(layers "F.Cu" "F.Mask" "F.Paste")
			(net "VSENSE_PVCCIN_CPU1_P")
		)
		(pad "2" smd rect
			(at 0 0.889)
			(size 0.508 0.508)
			(layers "F.Cu" "F.Mask" "F.Paste")
			(net "VSENSE_PVCCIN_CPU1_N")
		)
		(zone
			(layer "F.Cu")
			(hatch none 0.5)
			(connect_pads
				(clearance 0)
			)
			(min_thickness 0.25)
			(keepout
				(tracks allowed)
				(vias not_allowed)
				(pads allowed)
				(copperpour not_allowed)
				(footprints allowed)
			)
			(placement
				(enabled no)
				(sheetname "")
			)
			(fill
				(thermal_gap 0.5)
				(thermal_bridge_width 0.5)
				(island_removal_mode 0)
			)
			(polygon
				(pts
					(xy 38.6588 -50.3174) (xy 39.1668 -50.3174) (xy 39.1668 -49.9364) (xy 38.6588 -49.9364)
				)
			)
		)
		(zone
			(layer "F.Cu")
			(hatch none 0.5)
			(connect_pads
				(clearance 0)
			)
			(min_thickness 0.25)
			(keepout
				(tracks not_allowed)
				(vias allowed)
				(pads allowed)
				(copperpour not_allowed)
				(footprints allowed)
			)
			(placement
				(enabled no)
				(sheetname "")
			)
			(fill
				(thermal_gap 0.5)
				(thermal_bridge_width 0.5)
				(island_removal_mode 0)
			)
			(polygon
				(pts
					(xy 38.6588 -49.9364) (xy 39.1668 -49.9364) (xy 39.1668 -50.3174) (xy 38.6588 -50.3174)
				)
			)
		)
	)
	(footprint ""
		(layer "F.Cu")
		(at 265.684 -79.6036 180)
		(property "Reference" "C5D17"
			(at 0 0 180)
			(layer "F.SilkS")
			(hide yes)
			(effects
				(font
					(size 1.27 1.27)
				)
			)
		)
		(property "Value" ""
			(at 0 0 180)
			(layer "F.Fab")
			(effects
				(font
					(size 1.27 1.27)
				)
			)
		)
		(duplicate_pad_numbers_are_jumpers no)
		(fp_poly
			(pts
				(xy -0.4953 -0.2032) (xy 0.4953 -0.2032) (xy 0.4953 1.6002) (xy -0.4953 1.6002)
			)
			(stroke
				(width 0)
				(type default)
			)
			(fill no)
			(layer "F.CrtYd")
		)
		(fp_line
			(start 0.4953 1.6002)
			(end -0.4953 1.6002)
			(stroke
				(width 0.1)
				(type default)
			)
			(layer "F.Fab")
		)
		(fp_line
			(start 0.4953 -0.2032)
			(end 0.4953 1.6002)
			(stroke
				(width 0.1)
				(type default)
			)
			(layer "F.Fab")
		)
		(fp_line
			(start -0.4953 1.6002)
			(end -0.4953 -0.2032)
			(stroke
				(width 0.1)
				(type default)
			)
			(layer "F.Fab")
		)
		(fp_line
			(start -0.4953 -0.2032)
			(end 0.4953 -0.2032)
			(stroke
				(width 0.1)
				(type default)
			)
			(layer "F.Fab")
		)
		(pad "1" smd rect
			(at 0 0 180)
			(size 0.762 0.889)
			(layers "F.Cu" "F.Mask" "F.Paste")
			(net "PVCCIN_CPU0")
		)
		(pad "2" smd rect
			(at 0 1.397 180)
			(size 0.762 0.889)
			(layers "F.Cu" "F.Mask" "F.Paste")
			(net "GND")
		)
		(zone
			(layer "F.Cu")
			(hatch none 0.5)
			(connect_pads
				(clearance 0)
			)
			(min_thickness 0.25)
			(keepout
				(tracks not_allowed)
				(vias allowed)
				(pads allowed)
				(copperpour not_allowed)
				(footprints allowed)
			)
			(placement
				(enabled no)
				(sheetname "")
			)
			(fill
				(thermal_gap 0.5)
				(thermal_bridge_width 0.5)
				(island_removal_mode 0)
			)
			(polygon
				(pts
					(xy 266.065 -80.0481) (xy 265.303 -80.0481) (xy 265.303 -80.5561) (xy 266.065 -80.5561)
				)
			)
		)
	)
	(footprint ""
		(layer "F.Cu")
		(at 409.3972 -116.6114 90)
		(property "Reference" "R8B20"
			(at 0 0 90)
			(layer "F.SilkS")
			(hide yes)
			(effects
				(font
					(size 1.27 1.27)
				)
			)
		)
		(property "Value" ""
			(at 0 0 90)
			(layer "F.Fab")
			(effects
				(font
					(size 1.27 1.27)
				)
			)
		)
		(duplicate_pad_numbers_are_jumpers no)
		(fp_poly
			(pts
				(xy -0.2794 -0.1016) (xy 0.2794 -0.1016) (xy 0.2794 0.9906) (xy -0.2794 0.9906)
			)
			(stroke
				(width 0)
				(type default)
			)
			(fill no)
			(layer "F.CrtYd")
		)
		(fp_line
			(start 0.2794 -0.1016)
			(end -0.2794 -0.1016)
			(stroke
				(width 0.1)
				(type default)
			)
			(layer "F.Fab")
		)
		(fp_line
			(start -0.2794 -0.1016)
			(end -0.2794 0.9906)
			(stroke
				(width 0.1)
				(type default)
			)
			(layer "F.Fab")
		)
		(fp_line
			(start 0.2794 0.9906)
			(end 0.2794 -0.1016)
			(stroke
				(width 0.1)
				(type default)
			)
			(layer "F.Fab")
		)
		(fp_line
			(start -0.2794 0.9906)
			(end 0.2794 0.9906)
			(stroke
				(width 0.1)
				(type default)
			)
			(layer "F.Fab")
		)
		(pad "1" smd rect
			(at 0 0 90)
			(size 0.508 0.508)
			(layers "F.Cu" "F.Mask" "F.Paste")
			(net "H_PMSYNC_CLK_24M_R")
		)
		(pad "2" smd rect
			(at 0 0.889 90)
			(size 0.508 0.508)
			(layers "F.Cu" "F.Mask" "F.Paste")
			(net "H_PMSYNC_CLK_24M")
		)
		(zone
			(layer "F.Cu")
			(hatch none 0.5)
			(connect_pads
				(clearance 0)
			)
			(min_thickness 0.25)
			(keepout
				(tracks allowed)
				(vias not_allowed)
				(pads allowed)
				(copperpour not_allowed)
				(footprints allowed)
			)
			(placement
				(enabled no)
				(sheetname "")
			)
			(fill
				(thermal_gap 0.5)
				(thermal_bridge_width 0.5)
				(island_removal_mode 0)
			)
			(polygon
				(pts
					(xy 409.6512 -116.3574) (xy 409.6512 -116.8654) (xy 410.0322 -116.8654) (xy 410.0322 -116.3574)
				)
			)
		)
		(zone
			(layer "F.Cu")
			(hatch none 0.5)
			(connect_pads
				(clearance 0)
			)
			(min_thickness 0.25)
			(keepout
				(tracks not_allowed)
				(vias allowed)
				(pads allowed)
				(copperpour not_allowed)
				(footprints allowed)
			)
			(placement
				(enabled no)
				(sheetname "")
			)
			(fill
				(thermal_gap 0.5)
				(thermal_bridge_width 0.5)
				(island_removal_mode 0)
			)
			(polygon
				(pts
					(xy 410.0322 -116.3574) (xy 410.0322 -116.8654) (xy 409.6512 -116.8654) (xy 409.6512 -116.3574)
				)
			)
		)
	)
	(footprint ""
		(layer "F.Cu")
		(at 367.116106 -64.81064 90)
		(property "Reference" "R7E5"
			(at 0 0 90)
			(layer "F.SilkS")
			(hide yes)
			(effects
				(font
					(size 1.27 1.27)
				)
			)
		)
		(property "Value" ""
			(at 0 0 90)
			(layer "F.Fab")
			(effects
				(font
					(size 1.27 1.27)
				)
			)
		)
		(duplicate_pad_numbers_are_jumpers no)
		(fp_poly
			(pts
				(xy -0.2794 -0.1016) (xy 0.2794 -0.1016) (xy 0.2794 0.9906) (xy -0.2794 0.9906)
			)
			(stroke
				(width 0)
				(type default)
			)
			(fill no)
			(layer "F.CrtYd")
		)
		(fp_line
			(start 0.2794 -0.1016)
			(end -0.2794 -0.1016)
			(stroke
				(width 0.1)
				(type default)
			)
			(layer "F.Fab")
		)
		(fp_line
			(start -0.2794 -0.1016)
			(end -0.2794 0.9906)
			(stroke
				(width 0.1)
				(type default)
			)
			(layer "F.Fab")
		)
		(fp_line
			(start 0.2794 0.9906)
			(end 0.2794 -0.1016)
			(stroke
				(width 0.1)
				(type default)
			)
			(layer "F.Fab")
		)
		(fp_line
			(start -0.2794 0.9906)
			(end 0.2794 0.9906)
			(stroke
				(width 0.1)
				(type default)
			)
			(layer "F.Fab")
		)
		(pad "1" smd rect
			(at 0 0 90)
			(size 0.508 0.508)
			(layers "F.Cu" "F.Mask" "F.Paste")
			(net "P3V3_STBY")
		)
		(pad "2" smd rect
			(at 0 0.889 90)
			(size 0.508 0.508)
			(layers "F.Cu" "F.Mask" "F.Paste")
			(net "PU_THERMTRIP_FORCE_N")
		)
		(zone
			(layer "F.Cu")
			(hatch none 0.5)
			(connect_pads
				(clearance 0)
			)
			(min_thickness 0.25)
			(keepout
				(tracks allowed)
				(vias not_allowed)
				(pads allowed)
				(copperpour not_allowed)
				(footprints allowed)
			)
			(placement
				(enabled no)
				(sheetname "")
			)
			(fill
				(thermal_gap 0.5)
				(thermal_bridge_width 0.5)
				(island_removal_mode 0)
			)
			(polygon
				(pts
					(xy 367.370106 -64.55664) (xy 367.370106 -65.06464) (xy 367.751106 -65.06464) (xy 367.751106 -64.55664)
				)
			)
		)
		(zone
			(layer "F.Cu")
			(hatch none 0.5)
			(connect_pads
				(clearance 0)
			)
			(min_thickness 0.25)
			(keepout
				(tracks not_allowed)
				(vias allowed)
				(pads allowed)
				(copperpour not_allowed)
				(footprints allowed)
			)
			(placement
				(enabled no)
				(sheetname "")
			)
			(fill
				(thermal_gap 0.5)
				(thermal_bridge_width 0.5)
				(island_removal_mode 0)
			)
			(polygon
				(pts
					(xy 367.751106 -64.55664) (xy 367.751106 -65.06464) (xy 367.370106 -65.06464) (xy 367.370106 -64.55664)
				)
			)
		)
	)
	(footprint ""
		(layer "F.Cu")
		(at 417.9316 -57.1119 180)
		(property "Reference" "R8E14"
			(at 0 0 180)
			(layer "F.SilkS")
			(hide yes)
			(effects
				(font
					(size 1.27 1.27)
				)
			)
		)
		(property "Value" ""
			(at 0 0 180)
			(layer "F.Fab")
			(effects
				(font
					(size 1.27 1.27)
				)
			)
		)
		(duplicate_pad_numbers_are_jumpers no)
		(fp_poly
			(pts
				(xy -0.2794 -0.1016) (xy 0.2794 -0.1016) (xy 0.2794 0.9906) (xy -0.2794 0.9906)
			)
			(stroke
				(width 0)
				(type default)
			)
			(fill no)
			(layer "F.CrtYd")
		)
		(fp_line
			(start 0.2794 0.9906)
			(end 0.2794 -0.1016)
			(stroke
				(width 0.1)
				(type default)
			)
			(layer "F.Fab")
		)
		(fp_line
			(start 0.2794 -0.1016)
			(end -0.2794 -0.1016)
			(stroke
				(width 0.1)
				(type default)
			)
			(layer "F.Fab")
		)
		(fp_line
			(start -0.2794 0.9906)
			(end 0.2794 0.9906)
			(stroke
				(width 0.1)
				(type default)
			)
			(layer "F.Fab")
		)
		(fp_line
			(start -0.2794 -0.1016)
			(end -0.2794 0.9906)
			(stroke
				(width 0.1)
				(type default)
			)
			(layer "F.Fab")
		)
		(pad "1" smd rect
			(at 0 0 180)
			(size 0.508 0.508)
			(layers "F.Cu" "F.Mask" "F.Paste")
			(net "P3V3_STBY")
		)
		(pad "2" smd rect
			(at 0 0.889 180)
			(size 0.508 0.508)
			(layers "F.Cu" "F.Mask" "F.Paste")
			(net "RST_PLTRST_TOP_SWAP")
		)
		(zone
			(layer "F.Cu")
			(hatch none 0.5)
			(connect_pads
				(clearance 0)
			)
			(min_thickness 0.25)
			(keepout
				(tracks not_allowed)
				(vias allowed)
				(pads allowed)
				(copperpour not_allowed)
				(footprints allowed)
			)
			(placement
				(enabled no)
				(sheetname "")
			)
			(fill
				(thermal_gap 0.5)
				(thermal_bridge_width 0.5)
				(island_removal_mode 0)
			)
			(polygon
				(pts
					(xy 418.1856 -57.7469) (xy 417.6776 -57.7469) (xy 417.6776 -57.3659) (xy 418.1856 -57.3659)
				)
			)
		)
		(zone
			(layer "F.Cu")
			(hatch none 0.5)
			(connect_pads
				(clearance 0)
			)
			(min_thickness 0.25)
			(keepout
				(tracks allowed)
				(vias not_allowed)
				(pads allowed)
				(copperpour not_allowed)
				(footprints allowed)
			)
			(placement
				(enabled no)
				(sheetname "")
			)
			(fill
				(thermal_gap 0.5)
				(thermal_bridge_width 0.5)
				(island_removal_mode 0)
			)
			(polygon
				(pts
					(xy 418.1856 -57.3659) (xy 417.6776 -57.3659) (xy 417.6776 -57.7469) (xy 418.1856 -57.7469)
				)
			)
		)
	)
	(footprint ""
		(layer "F.Cu")
		(at 368.184938 -102.30739 -90)
		(property "Reference" "C7C9"
			(at 0 0 270)
			(layer "F.SilkS")
			(hide yes)
			(effects
				(font
					(size 1.27 1.27)
				)
			)
		)
		(property "Value" ""
			(at 0 0 270)
			(layer "F.Fab")
			(effects
				(font
					(size 1.27 1.27)
				)
			)
		)
		(duplicate_pad_numbers_are_jumpers no)
		(fp_poly
			(pts
				(xy -0.4953 -0.2032) (xy 0.4953 -0.2032) (xy 0.4953 1.6002) (xy -0.4953 1.6002)
			)
			(stroke
				(width 0)
				(type default)
			)
			(fill no)
			(layer "F.CrtYd")
		)
		(fp_line
			(start -0.4953 1.6002)
			(end -0.4953 -0.2032)
			(stroke
				(width 0.1)
				(type default)
			)
			(layer "F.Fab")
		)
		(fp_line
			(start 0.4953 1.6002)
			(end -0.4953 1.6002)
			(stroke
				(width 0.1)
				(type default)
			)
			(layer "F.Fab")
		)
		(fp_line
			(start -0.4953 -0.2032)
			(end 0.4953 -0.2032)
			(stroke
				(width 0.1)
				(type default)
			)
			(layer "F.Fab")
		)
		(fp_line
			(start 0.4953 -0.2032)
			(end 0.4953 1.6002)
			(stroke
				(width 0.1)
				(type default)
			)
			(layer "F.Fab")
		)
		(pad "1" smd rect
			(at 0 0 270)
			(size 0.762 0.889)
			(layers "F.Cu" "F.Mask" "F.Paste")
			(net "PVNN_PCH_STBY")
		)
		(pad "2" smd rect
			(at 0 1.397 270)
			(size 0.762 0.889)
			(layers "F.Cu" "F.Mask" "F.Paste")
			(net "GND")
		)
		(zone
			(layer "F.Cu")
			(hatch none 0.5)
			(connect_pads
				(clearance 0)
			)
			(min_thickness 0.25)
			(keepout
				(tracks not_allowed)
				(vias allowed)
				(pads allowed)
				(copperpour not_allowed)
				(footprints allowed)
			)
			(placement
				(enabled no)
				(sheetname "")
			)
			(fill
				(thermal_gap 0.5)
				(thermal_bridge_width 0.5)
				(island_removal_mode 0)
			)
			(polygon
				(pts
					(xy 367.740438 -102.68839) (xy 367.740438 -101.92639) (xy 367.232438 -101.92639) (xy 367.232438 -102.68839)
				)
			)
		)
	)
	(footprint ""
		(layer "F.Cu")
		(at 155.194 -27.9908 -90)
		(property "Reference" "R3F6"
			(at 0 0 270)
			(layer "F.SilkS")
			(hide yes)
			(effects
				(font
					(size 1.27 1.27)
				)
			)
		)
		(property "Value" ""
			(at 0 0 270)
			(layer "F.Fab")
			(effects
				(font
					(size 1.27 1.27)
				)
			)
		)
		(duplicate_pad_numbers_are_jumpers no)
		(fp_poly
			(pts
				(xy -0.2794 -0.1016) (xy 0.2794 -0.1016) (xy 0.2794 0.9906) (xy -0.2794 0.9906)
			)
			(stroke
				(width 0)
				(type default)
			)
			(fill no)
			(layer "F.CrtYd")
		)
		(fp_line
			(start -0.2794 0.9906)
			(end 0.2794 0.9906)
			(stroke
				(width 0.1)
				(type default)
			)
			(layer "F.Fab")
		)
		(fp_line
			(start 0.2794 0.9906)
			(end 0.2794 -0.1016)
			(stroke
				(width 0.1)
				(type default)
			)
			(layer "F.Fab")
		)
		(fp_line
			(start -0.2794 -0.1016)
			(end -0.2794 0.9906)
			(stroke
				(width 0.1)
				(type default)
			)
			(layer "F.Fab")
		)
		(fp_line
			(start 0.2794 -0.1016)
			(end -0.2794 -0.1016)
			(stroke
				(width 0.1)
				(type default)
			)
			(layer "F.Fab")
		)
		(pad "1" smd rect
			(at 0 0 270)
			(size 0.508 0.508)
			(layers "F.Cu" "F.Mask" "F.Paste")
			(net "CLK_322M_156M_CPU1_OSC_VRM_DP")
		)
		(pad "2" smd rect
			(at 0 0.889 270)
			(size 0.508 0.508)
			(layers "F.Cu" "F.Mask" "F.Paste")
			(net "CLK_322M_OSC_CPU1_RC_DP")
		)
		(zone
			(layer "F.Cu")
			(hatch none 0.5)
			(connect_pads
				(clearance 0)
			)
			(min_thickness 0.25)
			(keepout
				(tracks not_allowed)
				(vias allowed)
				(pads allowed)
				(copperpour not_allowed)
				(footprints allowed)
			)
			(placement
				(enabled no)
				(sheetname "")
			)
			(fill
				(thermal_gap 0.5)
				(thermal_bridge_width 0.5)
				(island_removal_mode 0)
			)
			(polygon
				(pts
					(xy 154.559 -28.2448) (xy 154.559 -27.7368) (xy 154.94 -27.7368) (xy 154.94 -28.2448)
				)
			)
		)
		(zone
			(layer "F.Cu")
			(hatch none 0.5)
			(connect_pads
				(clearance 0)
			)
			(min_thickness 0.25)
			(keepout
				(tracks allowed)
				(vias not_allowed)
				(pads allowed)
				(copperpour not_allowed)
				(footprints allowed)
			)
			(placement
				(enabled no)
				(sheetname "")
			)
			(fill
				(thermal_gap 0.5)
				(thermal_bridge_width 0.5)
				(island_removal_mode 0)
			)
			(polygon
				(pts
					(xy 154.94 -28.2448) (xy 154.94 -27.7368) (xy 154.559 -27.7368) (xy 154.559 -28.2448)
				)
			)
		)
	)
	(footprint ""
		(layer "F.Cu")
		(at 275.48332 -83.88604)
		(property "Reference" "R5D1"
			(at 0 0 0)
			(layer "F.SilkS")
			(hide yes)
			(effects
				(font
					(size 1.27 1.27)
				)
			)
		)
		(property "Value" ""
			(at 0 0 0)
			(layer "F.Fab")
			(effects
				(font
					(size 1.27 1.27)
				)
			)
		)
		(duplicate_pad_numbers_are_jumpers no)
		(fp_poly
			(pts
				(xy -0.2794 -0.1016) (xy 0.2794 -0.1016) (xy 0.2794 0.9906) (xy -0.2794 0.9906)
			)
			(stroke
				(width 0)
				(type default)
			)
			(fill no)
			(layer "F.CrtYd")
		)
		(fp_line
			(start -0.2794 -0.1016)
			(end -0.2794 0.9906)
			(stroke
				(width 0.1)
				(type default)
			)
			(layer "F.Fab")
		)
		(fp_line
			(start -0.2794 0.9906)
			(end 0.2794 0.9906)
			(stroke
				(width 0.1)
				(type default)
			)
			(layer "F.Fab")
		)
		(fp_line
			(start 0.2794 -0.1016)
			(end -0.2794 -0.1016)
			(stroke
				(width 0.1)
				(type default)
			)
			(layer "F.Fab")
		)
		(fp_line
			(start 0.2794 0.9906)
			(end 0.2794 -0.1016)
			(stroke
				(width 0.1)
				(type default)
			)
			(layer "F.Fab")
		)
		(pad "1" smd rect
			(at 0 0)
			(size 0.508 0.508)
			(layers "F.Cu" "F.Mask" "F.Paste")
			(net "A_CPU0_DEF_RCOMP0")
		)
		(pad "2" smd rect
			(at 0 0.889)
			(size 0.508 0.508)
			(layers "F.Cu" "F.Mask" "F.Paste")
			(net "GND")
		)
		(zone
			(layer "F.Cu")
			(hatch none 0.5)
			(connect_pads
				(clearance 0)
			)
			(min_thickness 0.25)
			(keepout
				(tracks allowed)
				(vias not_allowed)
				(pads allowed)
				(copperpour not_allowed)
				(footprints allowed)
			)
			(placement
				(enabled no)
				(sheetname "")
			)
			(fill
				(thermal_gap 0.5)
				(thermal_bridge_width 0.5)
				(island_removal_mode 0)
			)
			(polygon
				(pts
					(xy 275.22932 -83.63204) (xy 275.73732 -83.63204) (xy 275.73732 -83.25104) (xy 275.22932 -83.25104)
				)
			)
		)
		(zone
			(layer "F.Cu")
			(hatch none 0.5)
			(connect_pads
				(clearance 0)
			)
			(min_thickness 0.25)
			(keepout
				(tracks not_allowed)
				(vias allowed)
				(pads allowed)
				(copperpour not_allowed)
				(footprints allowed)
			)
			(placement
				(enabled no)
				(sheetname "")
			)
			(fill
				(thermal_gap 0.5)
				(thermal_bridge_width 0.5)
				(island_removal_mode 0)
			)
			(polygon
				(pts
					(xy 275.22932 -83.25104) (xy 275.73732 -83.25104) (xy 275.73732 -83.63204) (xy 275.22932 -83.63204)
				)
			)
		)
	)
	(footprint ""
		(layer "F.Cu")
		(at 351.410524 -4.296918 180)
		(property "Reference" "RT33"
			(at 1.01473 0.656336 90)
			(unlocked yes)
			(layer "F.SilkS")
			(effects
				(font
					(size 0.4064 0.254)
					(thickness 0.1524)
				)
			)
		)
		(property "Value" ""
			(at 0 0 180)
			(layer "F.Fab")
			(effects
				(font
					(size 1.27 1.27)
				)
			)
		)
		(duplicate_pad_numbers_are_jumpers no)
		(fp_poly
			(pts
				(xy -0.4953 -0.2032) (xy 0.4953 -0.2032) (xy 0.4953 1.6002) (xy -0.4953 1.6002)
			)
			(stroke
				(width 0)
				(type default)
			)
			(fill no)
			(layer "F.CrtYd")
		)
		(fp_line
			(start 0.4953 1.6002)
			(end -0.4953 1.6002)
			(stroke
				(width 0.1)
				(type default)
			)
			(layer "F.Fab")
		)
		(fp_line
			(start 0.4953 -0.2032)
			(end 0.4953 1.6002)
			(stroke
				(width 0.1)
				(type default)
			)
			(layer "F.Fab")
		)
		(fp_line
			(start -0.4953 1.6002)
			(end -0.4953 -0.2032)
			(stroke
				(width 0.1)
				(type default)
			)
			(layer "F.Fab")
		)
		(fp_line
			(start -0.4953 -0.2032)
			(end 0.4953 -0.2032)
			(stroke
				(width 0.1)
				(type default)
			)
			(layer "F.Fab")
		)
		(pad "1" smd rect
			(at 0 0 180)
			(size 0.762 0.889)
			(layers "F.Cu" "F.Mask" "F.Paste")
			(net "VR_PVDDQ_ABC_PH1_BOOT")
		)
		(pad "2" smd rect
			(at 0 1.397 180)
			(size 0.762 0.889)
			(layers "F.Cu" "F.Mask" "F.Paste")
			(net "VR_PVDDQ_ABC_PH1_BOOT_R")
		)
		(zone
			(layer "F.Cu")
			(hatch none 0.5)
			(connect_pads
				(clearance 0)
			)
			(min_thickness 0.25)
			(keepout
				(tracks allowed)
				(vias not_allowed)
				(pads allowed)
				(copperpour not_allowed)
				(footprints allowed)
			)
			(placement
				(enabled no)
				(sheetname "")
			)
			(fill
				(thermal_gap 0.5)
				(thermal_bridge_width 0.5)
				(island_removal_mode 0)
			)
			(polygon
				(pts
					(xy 351.029524 -5.249418) (xy 351.029524 -4.741418) (xy 351.791524 -4.741418) (xy 351.791524 -5.249418)
				)
			)
		)
		(zone
			(layer "F.Cu")
			(hatch none 0.5)
			(connect_pads
				(clearance 0)
			)
			(min_thickness 0.25)
			(keepout
				(tracks not_allowed)
				(vias allowed)
				(pads allowed)
				(copperpour not_allowed)
				(footprints allowed)
			)
			(placement
				(enabled no)
				(sheetname "")
			)
			(fill
				(thermal_gap 0.5)
				(thermal_bridge_width 0.5)
				(island_removal_mode 0)
			)
			(polygon
				(pts
					(xy 351.791524 -5.249418) (xy 351.029524 -5.249418) (xy 351.029524 -4.741418) (xy 351.791524 -4.741418)
				)
			)
		)
	)
	(footprint ""
		(layer "F.Cu")
		(at 411.6832 -51.308 180)
		(property "Reference" "U8D4"
			(at 1.778 5.09143 0)
			(unlocked yes)
			(layer "F.SilkS")
			(effects
				(font
					(size 0.7874 0.5842)
					(thickness 0.1524)
				)
				(justify left)
			)
		)
		(property "Value" ""
			(at 0 0 180)
			(layer "F.Fab")
			(effects
				(font
					(size 1.27 1.27)
				)
			)
		)
		(duplicate_pad_numbers_are_jumpers no)
		(fp_line
			(start 4.191 4.4069)
			(end 1.2954 4.4069)
			(stroke
				(width 0.1524)
				(type default)
			)
			(layer "F.SilkS")
		)
		(fp_line
			(start 4.191 -0.5969)
			(end 4.191 4.4069)
			(stroke
				(width 0.1524)
				(type default)
			)
			(layer "F.SilkS")
		)
		(fp_line
			(start 3.3782 0.6731)
			(end 3.3782 -0.5842)
			(stroke
				(width 0.1524)
				(type default)
			)
			(layer "F.SilkS")
		)
		(fp_line
			(start 2.1082 0.6731)
			(end 3.3782 0.6731)
			(stroke
				(width 0.1524)
				(type default)
			)
			(layer "F.SilkS")
		)
		(fp_line
			(start 2.1082 -0.5842)
			(end 2.1082 0.6731)
			(stroke
				(width 0.1524)
				(type default)
			)
			(layer "F.SilkS")
		)
		(fp_line
			(start 1.2954 4.4069)
			(end 1.2954 -0.5969)
			(stroke
				(width 0.1524)
				(type default)
			)
			(layer "F.SilkS")
		)
		(fp_line
			(start 1.2954 -0.5969)
			(end 4.191 -0.5969)
			(stroke
				(width 0.1524)
				(type default)
			)
			(layer "F.SilkS")
		)
		(fp_circle
			(center -1.37414 -0.541528)
			(end -1.50114 -0.541528)
			(stroke
				(width 0.254)
				(type default)
			)
			(fill no)
			(layer "F.SilkS")
		)
		(fp_poly
			(pts
				(xy 0.7493 -0.5969) (xy 4.7371 -0.5969) (xy 4.7371 4.4069) (xy 0.7493 4.4069)
			)
			(stroke
				(width 0)
				(type default)
			)
			(fill no)
			(layer "F.CrtYd")
		)
		(fp_line
			(start 4.7371 4.4069)
			(end 0.7493 4.4069)
			(stroke
				(width 0.1)
				(type default)
			)
			(layer "F.Fab")
		)
		(fp_line
			(start 4.7371 -0.5969)
			(end 4.7371 4.4069)
			(stroke
				(width 0.1)
				(type default)
			)
			(layer "F.Fab")
		)
		(fp_line
			(start 3.3782 0.6731)
			(end 3.3782 -0.5842)
			(stroke
				(width 0.1)
				(type default)
			)
			(layer "F.Fab")
		)
		(fp_line
			(start 2.1082 0.6731)
			(end 3.3782 0.6731)
			(stroke
				(width 0.1)
				(type default)
			)
			(layer "F.Fab")
		)
		(fp_line
			(start 2.1082 -0.5842)
			(end 2.1082 0.6731)
			(stroke
				(width 0.1)
				(type default)
			)
			(layer "F.Fab")
		)
		(fp_line
			(start 0.7493 4.4069)
			(end 0.7493 -0.5969)
			(stroke
				(width 0.1)
				(type default)
			)
			(layer "F.Fab")
		)
		(fp_line
			(start 0.7493 -0.5969)
			(end 4.7371 -0.5969)
			(stroke
				(width 0.1)
				(type default)
			)
			(layer "F.Fab")
		)
		(fp_circle
			(center -1.382014 -0.7112)
			(end -1.509014 -0.7112)
			(stroke
				(width 0.254)
				(type default)
			)
			(fill no)
			(layer "F.Fab")
		)
		(pad "1" smd rect
			(at 0 0 180)
			(size 1.9304 0.635)
			(layers "F.Cu" "F.Mask" "F.Paste")
			(net "GND")
		)
		(pad "2" smd rect
			(at 0 1.27 180)
			(size 1.9304 0.635)
			(layers "F.Cu" "F.Mask" "F.Paste")
			(net "GND")
		)
		(pad "3" smd rect
			(at 0 2.54 180)
			(size 1.9304 0.635)
			(layers "F.Cu" "F.Mask" "F.Paste")
			(net "PU_AT24C64_A2")
		)
		(pad "4" smd rect
			(at 0 3.81 180)
			(size 1.9304 0.635)
			(layers "F.Cu" "F.Mask" "F.Paste")
			(net "GND")
		)
		(pad "5" smd rect
			(at 5.4864 3.81 180)
			(size 1.9304 0.635)
			(layers "F.Cu" "F.Mask" "F.Paste")
			(net "SMB_SENSOR_STBY_LVC3_SDA_R2")
		)
		(pad "6" smd rect
			(at 5.4864 2.54 180)
			(size 1.9304 0.635)
			(layers "F.Cu" "F.Mask" "F.Paste")
			(net "SMB_SENSOR_STBY_LVC3_SCL_R2")
		)
		(pad "7" smd rect
			(at 5.4864 1.27 180)
			(size 1.9304 0.635)
			(layers "F.Cu" "F.Mask" "F.Paste")
			(net "PD_FRU_WP")
		)
		(pad "8" smd rect
			(at 5.4864 0 180)
			(size 1.9304 0.635)
			(layers "F.Cu" "F.Mask" "F.Paste")
			(net "P3V3_STBY")
		)
	)
	(footprint ""
		(layer "F.Cu")
		(at 367.411 -100.076)
		(property "Reference" "Y7C2"
			(at -0.127 -1.49733 0)
			(unlocked yes)
			(layer "F.SilkS")
			(effects
				(font
					(size 0.7874 0.5842)
					(thickness 0.1524)
				)
			)
		)
		(property "Value" ""
			(at 0 0 0)
			(layer "F.Fab")
			(effects
				(font
					(size 1.27 1.27)
				)
			)
		)
		(duplicate_pad_numbers_are_jumpers no)
		(fp_line
			(start -0.8001 1.9558)
			(end -0.8001 1.0922)
			(stroke
				(width 0.1524)
				(type default)
			)
			(layer "F.SilkS")
		)
		(fp_line
			(start 0.8001 1.9558)
			(end 0.8001 1.0922)
			(stroke
				(width 0.1524)
				(type default)
			)
			(layer "F.SilkS")
		)
		(fp_rect
			(start -0.8001 3.173984)
			(end 0.8001 -0.125984)
			(stroke
				(width 0)
				(type default)
			)
			(fill no)
			(layer "F.CrtYd")
		)
		(fp_line
			(start -0.8001 -0.125984)
			(end -0.8001 3.173984)
			(stroke
				(width 0.1)
				(type default)
			)
			(layer "F.Fab")
		)
		(fp_line
			(start -0.8001 3.173984)
			(end 0.8001 3.173984)
			(stroke
				(width 0.1)
				(type default)
			)
			(layer "F.Fab")
		)
		(fp_line
			(start 0.8001 -0.125984)
			(end -0.8001 -0.125984)
			(stroke
				(width 0.1)
				(type default)
			)
			(layer "F.Fab")
		)
		(fp_line
			(start 0.8001 3.173984)
			(end 0.8001 -0.125984)
			(stroke
				(width 0.1)
				(type default)
			)
			(layer "F.Fab")
		)
		(pad "1" smd rect
			(at 0 0)
			(size 1.6002 1.524)
			(layers "F.Cu" "F.Mask" "F.Paste")
			(net "XTAL_33K_RTC1")
		)
		(pad "2" smd rect
			(at 0 3.048)
			(size 1.6002 1.524)
			(layers "F.Cu" "F.Mask" "F.Paste")
			(net "XTAL_33K_RTC2")
		)
	)
	(footprint ""
		(layer "F.Cu")
		(at 355.656388 -139.87399 180)
		(property "Reference" "R7A8"
			(at 0 0 180)
			(layer "F.SilkS")
			(hide yes)
			(effects
				(font
					(size 1.27 1.27)
				)
			)
		)
		(property "Value" ""
			(at 0 0 180)
			(layer "F.Fab")
			(effects
				(font
					(size 1.27 1.27)
				)
			)
		)
		(duplicate_pad_numbers_are_jumpers no)
		(fp_poly
			(pts
				(xy -0.2794 -0.1016) (xy 0.2794 -0.1016) (xy 0.2794 0.9906) (xy -0.2794 0.9906)
			)
			(stroke
				(width 0)
				(type default)
			)
			(fill no)
			(layer "F.CrtYd")
		)
		(fp_line
			(start 0.2794 0.9906)
			(end 0.2794 -0.1016)
			(stroke
				(width 0.1)
				(type default)
			)
			(layer "F.Fab")
		)
		(fp_line
			(start 0.2794 -0.1016)
			(end -0.2794 -0.1016)
			(stroke
				(width 0.1)
				(type default)
			)
			(layer "F.Fab")
		)
		(fp_line
			(start -0.2794 0.9906)
			(end 0.2794 0.9906)
			(stroke
				(width 0.1)
				(type default)
			)
			(layer "F.Fab")
		)
		(fp_line
			(start -0.2794 -0.1016)
			(end -0.2794 0.9906)
			(stroke
				(width 0.1)
				(type default)
			)
			(layer "F.Fab")
		)
		(pad "1" smd rect
			(at 0 0 180)
			(size 0.508 0.508)
			(layers "F.Cu" "F.Mask" "F.Paste")
			(net "VR_PVDDQ_DEF_XADDR2")
		)
		(pad "2" smd rect
			(at 0 0.889 180)
			(size 0.508 0.508)
			(layers "F.Cu" "F.Mask" "F.Paste")
			(net "GND")
		)
		(zone
			(layer "F.Cu")
			(hatch none 0.5)
			(connect_pads
				(clearance 0)
			)
			(min_thickness 0.25)
			(keepout
				(tracks not_allowed)
				(vias allowed)
				(pads allowed)
				(copperpour not_allowed)
				(footprints allowed)
			)
			(placement
				(enabled no)
				(sheetname "")
			)
			(fill
				(thermal_gap 0.5)
				(thermal_bridge_width 0.5)
				(island_removal_mode 0)
			)
			(polygon
				(pts
					(xy 355.910388 -140.50899) (xy 355.402388 -140.50899) (xy 355.402388 -140.12799) (xy 355.910388 -140.12799)
				)
			)
		)
		(zone
			(layer "F.Cu")
			(hatch none 0.5)
			(connect_pads
				(clearance 0)
			)
			(min_thickness 0.25)
			(keepout
				(tracks allowed)
				(vias not_allowed)
				(pads allowed)
				(copperpour not_allowed)
				(footprints allowed)
			)
			(placement
				(enabled no)
				(sheetname "")
			)
			(fill
				(thermal_gap 0.5)
				(thermal_bridge_width 0.5)
				(island_removal_mode 0)
			)
			(polygon
				(pts
					(xy 355.910388 -140.12799) (xy 355.402388 -140.12799) (xy 355.402388 -140.50899) (xy 355.910388 -140.50899)
				)
			)
		)
	)
	(footprint ""
		(layer "F.Cu")
		(at 418.7571 -87.6935 180)
		(property "Reference" "R2P3"
			(at 0 0 180)
			(layer "F.SilkS")
			(hide yes)
			(effects
				(font
					(size 1.27 1.27)
				)
			)
		)
		(property "Value" ""
			(at 0 0 180)
			(layer "F.Fab")
			(effects
				(font
					(size 1.27 1.27)
				)
			)
		)
		(duplicate_pad_numbers_are_jumpers no)
		(fp_poly
			(pts
				(xy -0.2794 -0.1016) (xy 0.2794 -0.1016) (xy 0.2794 0.9906) (xy -0.2794 0.9906)
			)
			(stroke
				(width 0)
				(type default)
			)
			(fill no)
			(layer "F.CrtYd")
		)
		(fp_line
			(start 0.2794 0.9906)
			(end 0.2794 -0.1016)
			(stroke
				(width 0.1)
				(type default)
			)
			(layer "F.Fab")
		)
		(fp_line
			(start 0.2794 -0.1016)
			(end -0.2794 -0.1016)
			(stroke
				(width 0.1)
				(type default)
			)
			(layer "F.Fab")
		)
		(fp_line
			(start -0.2794 0.9906)
			(end 0.2794 0.9906)
			(stroke
				(width 0.1)
				(type default)
			)
			(layer "F.Fab")
		)
		(fp_line
			(start -0.2794 -0.1016)
			(end -0.2794 0.9906)
			(stroke
				(width 0.1)
				(type default)
			)
			(layer "F.Fab")
		)
		(pad "1" smd rect
			(at 0 0 180)
			(size 0.508 0.508)
			(layers "F.Cu" "F.Mask" "F.Paste")
			(net "P3V3_STBY")
		)
		(pad "2" smd rect
			(at 0 0.889 180)
			(size 0.508 0.508)
			(layers "F.Cu" "F.Mask" "F.Paste")
			(net "IRQ_FORCE_NM_THROTTLE_R_N")
		)
		(zone
			(layer "F.Cu")
			(hatch none 0.5)
			(connect_pads
				(clearance 0)
			)
			(min_thickness 0.25)
			(keepout
				(tracks not_allowed)
				(vias allowed)
				(pads allowed)
				(copperpour not_allowed)
				(footprints allowed)
			)
			(placement
				(enabled no)
				(sheetname "")
			)
			(fill
				(thermal_gap 0.5)
				(thermal_bridge_width 0.5)
				(island_removal_mode 0)
			)
			(polygon
				(pts
					(xy 419.0111 -88.3285) (xy 418.5031 -88.3285) (xy 418.5031 -87.9475) (xy 419.0111 -87.9475)
				)
			)
		)
		(zone
			(layer "F.Cu")
			(hatch none 0.5)
			(connect_pads
				(clearance 0)
			)
			(min_thickness 0.25)
			(keepout
				(tracks allowed)
				(vias not_allowed)
				(pads allowed)
				(copperpour not_allowed)
				(footprints allowed)
			)
			(placement
				(enabled no)
				(sheetname "")
			)
			(fill
				(thermal_gap 0.5)
				(thermal_bridge_width 0.5)
				(island_removal_mode 0)
			)
			(polygon
				(pts
					(xy 419.0111 -87.9475) (xy 418.5031 -87.9475) (xy 418.5031 -88.3285) (xy 419.0111 -88.3285)
				)
			)
		)
	)
	(footprint ""
		(layer "F.Cu")
		(at 104.442768 -79.6036 180)
		(property "Reference" "C3W3"
			(at 0.97536 0.76708 90)
			(unlocked yes)
			(layer "F.SilkS")
			(effects
				(font
					(size 0.4064 0.254)
					(thickness 0.1524)
				)
			)
		)
		(property "Value" ""
			(at 0 0 180)
			(layer "F.Fab")
			(effects
				(font
					(size 1.27 1.27)
				)
			)
		)
		(duplicate_pad_numbers_are_jumpers no)
		(fp_poly
			(pts
				(xy -0.4953 -0.2032) (xy 0.4953 -0.2032) (xy 0.4953 1.6002) (xy -0.4953 1.6002)
			)
			(stroke
				(width 0)
				(type default)
			)
			(fill no)
			(layer "F.CrtYd")
		)
		(fp_line
			(start 0.4953 1.6002)
			(end -0.4953 1.6002)
			(stroke
				(width 0.1)
				(type default)
			)
			(layer "F.Fab")
		)
		(fp_line
			(start 0.4953 -0.2032)
			(end 0.4953 1.6002)
			(stroke
				(width 0.1)
				(type default)
			)
			(layer "F.Fab")
		)
		(fp_line
			(start -0.4953 1.6002)
			(end -0.4953 -0.2032)
			(stroke
				(width 0.1)
				(type default)
			)
			(layer "F.Fab")
		)
		(fp_line
			(start -0.4953 -0.2032)
			(end 0.4953 -0.2032)
			(stroke
				(width 0.1)
				(type default)
			)
			(layer "F.Fab")
		)
		(pad "1" smd rect
			(at 0 0 180)
			(size 0.762 0.889)
			(layers "F.Cu" "F.Mask" "F.Paste")
			(net "PVCCMCP_CPU1")
		)
		(pad "2" smd rect
			(at 0 1.397 180)
			(size 0.762 0.889)
			(layers "F.Cu" "F.Mask" "F.Paste")
			(net "GND")
		)
		(zone
			(layer "F.Cu")
			(hatch none 0.5)
			(connect_pads
				(clearance 0)
			)
			(min_thickness 0.25)
			(keepout
				(tracks not_allowed)
				(vias allowed)
				(pads allowed)
				(copperpour not_allowed)
				(footprints allowed)
			)
			(placement
				(enabled no)
				(sheetname "")
			)
			(fill
				(thermal_gap 0.5)
				(thermal_bridge_width 0.5)
				(island_removal_mode 0)
			)
			(polygon
				(pts
					(xy 104.823768 -80.0481) (xy 104.061768 -80.0481) (xy 104.061768 -80.5561) (xy 104.823768 -80.5561)
				)
			)
		)
	)
	(footprint ""
		(layer "F.Cu")
		(at 181.483 -51.5874 90)
		(property "Reference" "C4E15"
			(at 0 0 90)
			(layer "F.SilkS")
			(hide yes)
			(effects
				(font
					(size 1.27 1.27)
				)
			)
		)
		(property "Value" ""
			(at 0 0 90)
			(layer "F.Fab")
			(effects
				(font
					(size 1.27 1.27)
				)
			)
		)
		(duplicate_pad_numbers_are_jumpers no)
		(fp_poly
			(pts
				(xy 0.3048 -0.1016) (xy 0.3048 0.9906) (xy -0.3048 0.9906) (xy -0.3048 -0.1016)
			)
			(stroke
				(width 0)
				(type default)
			)
			(fill no)
			(layer "F.CrtYd")
		)
		(fp_line
			(start 0.3048 -0.1016)
			(end -0.3048 -0.1016)
			(stroke
				(width 0.1)
				(type default)
			)
			(layer "F.Fab")
		)
		(fp_line
			(start -0.3048 -0.1016)
			(end -0.3048 0.9906)
			(stroke
				(width 0.1)
				(type default)
			)
			(layer "F.Fab")
		)
		(fp_line
			(start 0.3048 0.9906)
			(end 0.3048 -0.1016)
			(stroke
				(width 0.1)
				(type default)
			)
			(layer "F.Fab")
		)
		(fp_line
			(start -0.3048 0.9906)
			(end 0.3048 0.9906)
			(stroke
				(width 0.1)
				(type default)
			)
			(layer "F.Fab")
		)
		(pad "1" smd rect
			(at 0 0 90)
			(size 0.508 0.508)
			(layers "F.Cu" "F.Mask" "F.Paste")
			(net "VR_FET_SW_P12V_STBY_PVCCIN_CPU0")
		)
		(pad "2" smd rect
			(at 0 0.889 90)
			(size 0.508 0.508)
			(layers "F.Cu" "F.Mask" "F.Paste")
			(net "GND")
		)
		(zone
			(layer "F.Cu")
			(hatch none 0.5)
			(connect_pads
				(clearance 0)
			)
			(min_thickness 0.25)
			(keepout
				(tracks allowed)
				(vias not_allowed)
				(pads allowed)
				(copperpour not_allowed)
				(footprints allowed)
			)
			(placement
				(enabled no)
				(sheetname "")
			)
			(fill
				(thermal_gap 0.5)
				(thermal_bridge_width 0.5)
				(island_removal_mode 0)
			)
			(polygon
				(pts
					(xy 181.737 -51.3334) (xy 181.737 -51.8414) (xy 182.118 -51.8414) (xy 182.118 -51.3334)
				)
			)
		)
		(zone
			(layer "F.Cu")
			(hatch none 0.5)
			(connect_pads
				(clearance 0)
			)
			(min_thickness 0.25)
			(keepout
				(tracks not_allowed)
				(vias allowed)
				(pads allowed)
				(copperpour not_allowed)
				(footprints allowed)
			)
			(placement
				(enabled no)
				(sheetname "")
			)
			(fill
				(thermal_gap 0.5)
				(thermal_bridge_width 0.5)
				(island_removal_mode 0)
			)
			(polygon
				(pts
					(xy 182.118 -51.3334) (xy 182.118 -51.8414) (xy 181.737 -51.8414) (xy 181.737 -51.3334)
				)
			)
		)
	)
	(footprint ""
		(layer "F.Cu")
		(at 173.74108 -65.42278 90)
		(property "Reference" "R4D64"
			(at 0 0 90)
			(layer "F.SilkS")
			(hide yes)
			(effects
				(font
					(size 1.27 1.27)
				)
			)
		)
		(property "Value" ""
			(at 0 0 90)
			(layer "F.Fab")
			(effects
				(font
					(size 1.27 1.27)
				)
			)
		)
		(duplicate_pad_numbers_are_jumpers no)
		(fp_poly
			(pts
				(xy -0.2794 -0.1016) (xy 0.2794 -0.1016) (xy 0.2794 0.9906) (xy -0.2794 0.9906)
			)
			(stroke
				(width 0)
				(type default)
			)
			(fill no)
			(layer "F.CrtYd")
		)
		(fp_line
			(start 0.2794 -0.1016)
			(end -0.2794 -0.1016)
			(stroke
				(width 0.1)
				(type default)
			)
			(layer "F.Fab")
		)
		(fp_line
			(start -0.2794 -0.1016)
			(end -0.2794 0.9906)
			(stroke
				(width 0.1)
				(type default)
			)
			(layer "F.Fab")
		)
		(fp_line
			(start 0.2794 0.9906)
			(end 0.2794 -0.1016)
			(stroke
				(width 0.1)
				(type default)
			)
			(layer "F.Fab")
		)
		(fp_line
			(start -0.2794 0.9906)
			(end 0.2794 0.9906)
			(stroke
				(width 0.1)
				(type default)
			)
			(layer "F.Fab")
		)
		(pad "1" smd rect
			(at 0 0 90)
			(size 0.508 0.508)
			(layers "F.Cu" "F.Mask" "F.Paste")
			(net "VR_PVCCIO_CPU1_XADDR1")
		)
		(pad "2" smd rect
			(at 0 0.889 90)
			(size 0.508 0.508)
			(layers "F.Cu" "F.Mask" "F.Paste")
			(net "GND")
		)
		(zone
			(layer "F.Cu")
			(hatch none 0.5)
			(connect_pads
				(clearance 0)
			)
			(min_thickness 0.25)
			(keepout
				(tracks allowed)
				(vias not_allowed)
				(pads allowed)
				(copperpour not_allowed)
				(footprints allowed)
			)
			(placement
				(enabled no)
				(sheetname "")
			)
			(fill
				(thermal_gap 0.5)
				(thermal_bridge_width 0.5)
				(island_removal_mode 0)
			)
			(polygon
				(pts
					(xy 173.99508 -65.16878) (xy 173.99508 -65.67678) (xy 174.37608 -65.67678) (xy 174.37608 -65.16878)
				)
			)
		)
		(zone
			(layer "F.Cu")
			(hatch none 0.5)
			(connect_pads
				(clearance 0)
			)
			(min_thickness 0.25)
			(keepout
				(tracks not_allowed)
				(vias allowed)
				(pads allowed)
				(copperpour not_allowed)
				(footprints allowed)
			)
			(placement
				(enabled no)
				(sheetname "")
			)
			(fill
				(thermal_gap 0.5)
				(thermal_bridge_width 0.5)
				(island_removal_mode 0)
			)
			(polygon
				(pts
					(xy 174.37608 -65.16878) (xy 174.37608 -65.67678) (xy 173.99508 -65.67678) (xy 173.99508 -65.16878)
				)
			)
		)
	)
	(footprint ""
		(layer "F.Cu")
		(at 23.114 -76.327 -90)
		(property "Reference" "R1D32"
			(at 0 0 270)
			(layer "F.SilkS")
			(hide yes)
			(effects
				(font
					(size 1.27 1.27)
				)
			)
		)
		(property "Value" ""
			(at 0 0 270)
			(layer "F.Fab")
			(effects
				(font
					(size 1.27 1.27)
				)
			)
		)
		(duplicate_pad_numbers_are_jumpers no)
		(fp_poly
			(pts
				(xy -0.2794 -0.1016) (xy 0.2794 -0.1016) (xy 0.2794 0.9906) (xy -0.2794 0.9906)
			)
			(stroke
				(width 0)
				(type default)
			)
			(fill no)
			(layer "F.CrtYd")
		)
		(fp_line
			(start -0.2794 0.9906)
			(end 0.2794 0.9906)
			(stroke
				(width 0.1)
				(type default)
			)
			(layer "F.Fab")
		)
		(fp_line
			(start 0.2794 0.9906)
			(end 0.2794 -0.1016)
			(stroke
				(width 0.1)
				(type default)
			)
			(layer "F.Fab")
		)
		(fp_line
			(start -0.2794 -0.1016)
			(end -0.2794 0.9906)
			(stroke
				(width 0.1)
				(type default)
			)
			(layer "F.Fab")
		)
		(fp_line
			(start 0.2794 -0.1016)
			(end -0.2794 -0.1016)
			(stroke
				(width 0.1)
				(type default)
			)
			(layer "F.Fab")
		)
		(pad "1" smd rect
			(at 0 0 270)
			(size 0.508 0.508)
			(layers "F.Cu" "F.Mask" "F.Paste")
			(net "A_HSC_VCAP")
		)
		(pad "2" smd rect
			(at 0 0.889 270)
			(size 0.508 0.508)
			(layers "F.Cu" "F.Mask" "F.Paste")
			(net "A_HSC_ISTART")
		)
		(zone
			(layer "F.Cu")
			(hatch none 0.5)
			(connect_pads
				(clearance 0)
			)
			(min_thickness 0.25)
			(keepout
				(tracks not_allowed)
				(vias allowed)
				(pads allowed)
				(copperpour not_allowed)
				(footprints allowed)
			)
			(placement
				(enabled no)
				(sheetname "")
			)
			(fill
				(thermal_gap 0.5)
				(thermal_bridge_width 0.5)
				(island_removal_mode 0)
			)
			(polygon
				(pts
					(xy 22.479 -76.581) (xy 22.479 -76.073) (xy 22.86 -76.073) (xy 22.86 -76.581)
				)
			)
		)
		(zone
			(layer "F.Cu")
			(hatch none 0.5)
			(connect_pads
				(clearance 0)
			)
			(min_thickness 0.25)
			(keepout
				(tracks allowed)
				(vias not_allowed)
				(pads allowed)
				(copperpour not_allowed)
				(footprints allowed)
			)
			(placement
				(enabled no)
				(sheetname "")
			)
			(fill
				(thermal_gap 0.5)
				(thermal_bridge_width 0.5)
				(island_removal_mode 0)
			)
			(polygon
				(pts
					(xy 22.86 -76.581) (xy 22.86 -76.073) (xy 22.479 -76.073) (xy 22.479 -76.581)
				)
			)
		)
	)
	(footprint ""
		(layer "F.Cu")
		(at 101.448616 -164.9857 90)
		(property "Reference" "T1D9"
			(at 0 0 90)
			(layer "F.SilkS")
			(hide yes)
			(effects
				(font
					(size 1.27 1.27)
				)
			)
		)
		(property "Value" "*"
			(at -3.4036 -4.46405 90)
			(unlocked yes)
			(layer "F.Fab")
			(hide yes)
			(effects
				(font
					(size 0.889 0.889)
					(thickness 0.1524)
				)
			)
		)
		(property "Device Type" "TEST-PAD-12P-1-GP-U_DISCRET-GBA"
			(at -3.4036 -5.98805 90)
			(unlocked yes)
			(layer "F.Fab")
			(hide yes)
			(effects
				(font
					(size 0.889 0.889)
					(thickness 0.1524)
				)
			)
		)
		(duplicate_pad_numbers_are_jumpers no)
		(fp_line
			(start 2.3622 -4.826)
			(end 2.3622 3.4798)
			(stroke
				(width 0.1524)
				(type default)
			)
			(layer "F.SilkS")
		)
		(fp_line
			(start -2.3876 -4.826)
			(end 2.3622 -4.826)
			(stroke
				(width 0.1524)
				(type default)
			)
			(layer "F.SilkS")
		)
		(fp_line
			(start 2.3622 3.4798)
			(end -2.3876 3.4798)
			(stroke
				(width 0.1524)
				(type default)
			)
			(layer "F.SilkS")
		)
		(fp_line
			(start -2.3876 3.4798)
			(end -2.3876 -4.826)
			(stroke
				(width 0.1524)
				(type default)
			)
			(layer "F.SilkS")
		)
		(fp_rect
			(start -2.6416 3.7338)
			(end 2.6162 -5.08)
			(stroke
				(width 0)
				(type default)
			)
			(fill no)
			(layer "F.CrtYd")
		)
		(fp_rect
			(start -2.6416 3.7338)
			(end 2.6162 -5.08)
			(stroke
				(width 0)
				(type default)
			)
			(fill no)
			(layer "F.Fab")
		)
		(pad "1" smd circle
			(at 0.496824 -1.301496 90)
			(size 0.6604 0.6604)
			(layers "F.Cu" "F.Mask" "F.Paste")
			(net "L12_85OHM_5INCH_DP")
		)
		(pad "2" smd circle
			(at -0.503936 -1.301496 90)
			(size 0.6604 0.6604)
			(layers "F.Cu" "F.Mask" "F.Paste")
			(net "L12_85OHM_5INCH_DN")
		)
		(pad "3" smd custom
			(at -0.00889 0.370078 90)
			(size 0.74295 0.74295)
			(layers "F.Cu" "F.Mask" "F.Paste")
			(net "GND")
			(options
				(clearance outline)
				(anchor circle)
			)
			(primitives
				(gr_poly
					(pts
						(xy -2.1209 1.4859) (xy 2.1209 1.4859) (xy 2.1209 -1.4859) (xy 1.08585 -1.4859) (xy 1.08585 -0.4699)
						(xy -1.08585 -0.4699) (xy -1.08585 -1.4859) (xy -2.1209 -1.4859)
					)
					(width 0)
					(fill yes)
				)
			)
		)
		(pad "4" thru_hole circle
			(at 1.266444 -3.851656 90)
			(size 1.4478 1.4478)
			(drill 1.0414)
			(layers "*.Cu" "*.Mask")
			(remove_unused_layers no)
			(net "GND")
			(clearance 0.1524)
			(thermal_gap 0.1524)
		)
		(pad "5" thru_hole circle
			(at -1.273556 -3.851656 90)
			(size 1.4478 1.4478)
			(drill 1.0414)
			(layers "*.Cu" "*.Mask")
			(remove_unused_layers no)
			(net "GND")
			(clearance 0.1524)
			(thermal_gap 0.1524)
		)
		(pad "6" thru_hole circle
			(at 1.266444 2.498344 90)
			(size 1.4478 1.4478)
			(drill 1.0414)
			(layers "*.Cu" "*.Mask")
			(remove_unused_layers no)
			(net "GND")
			(clearance 0.1524)
			(thermal_gap 0.1524)
		)
		(pad "7" thru_hole circle
			(at -1.273556 2.498344 90)
			(size 1.4478 1.4478)
			(drill 1.0414)
			(layers "*.Cu" "*.Mask")
			(remove_unused_layers no)
			(net "GND")
			(clearance 0.1524)
			(thermal_gap 0.1524)
		)
		(pad "8" thru_hole circle
			(at 1.27 -0.4572 90)
			(size 0.7112 0.7112)
			(drill 0.4064)
			(layers "*.Cu" "*.Mask")
			(remove_unused_layers no)
			(net "GND")
			(clearance 0.1016)
			(thermal_gap 0.1016)
		)
		(pad "9" thru_hole circle
			(at 1.27 0.762 90)
			(size 0.7112 0.7112)
			(drill 0.4064)
			(layers "*.Cu" "*.Mask")
			(remove_unused_layers no)
			(net "GND")
			(clearance 0.1016)
			(thermal_gap 0.1016)
		)
		(pad "10" thru_hole circle
			(at -0.0254 0.762 90)
			(size 0.7112 0.7112)
			(drill 0.4064)
			(layers "*.Cu" "*.Mask")
			(remove_unused_layers no)
			(net "GND")
			(clearance 0.1016)
			(thermal_gap 0.1016)
		)
		(pad "11" thru_hole circle
			(at -1.27 0.762 90)
			(size 0.7112 0.7112)
			(drill 0.4064)
			(layers "*.Cu" "*.Mask")
			(remove_unused_layers no)
			(net "GND")
			(clearance 0.1016)
			(thermal_gap 0.1016)
		)
		(pad "12" thru_hole circle
			(at -1.27 -0.4572 90)
			(size 0.7112 0.7112)
			(drill 0.4064)
			(layers "*.Cu" "*.Mask")
			(remove_unused_layers no)
			(net "GND")
			(clearance 0.1016)
			(thermal_gap 0.1016)
		)
	)
	(footprint ""
		(layer "F.Cu")
		(at 393.192 -71.0565 180)
		(property "Reference" "R7E15"
			(at 0 0 180)
			(layer "F.SilkS")
			(hide yes)
			(effects
				(font
					(size 1.27 1.27)
				)
			)
		)
		(property "Value" ""
			(at 0 0 180)
			(layer "F.Fab")
			(effects
				(font
					(size 1.27 1.27)
				)
			)
		)
		(duplicate_pad_numbers_are_jumpers no)
		(fp_poly
			(pts
				(xy -0.2794 -0.1016) (xy 0.2794 -0.1016) (xy 0.2794 0.9906) (xy -0.2794 0.9906)
			)
			(stroke
				(width 0)
				(type default)
			)
			(fill no)
			(layer "F.CrtYd")
		)
		(fp_line
			(start 0.2794 0.9906)
			(end 0.2794 -0.1016)
			(stroke
				(width 0.1)
				(type default)
			)
			(layer "F.Fab")
		)
		(fp_line
			(start 0.2794 -0.1016)
			(end -0.2794 -0.1016)
			(stroke
				(width 0.1)
				(type default)
			)
			(layer "F.Fab")
		)
		(fp_line
			(start -0.2794 0.9906)
			(end 0.2794 0.9906)
			(stroke
				(width 0.1)
				(type default)
			)
			(layer "F.Fab")
		)
		(fp_line
			(start -0.2794 -0.1016)
			(end -0.2794 0.9906)
			(stroke
				(width 0.1)
				(type default)
			)
			(layer "F.Fab")
		)
		(pad "1" smd rect
			(at 0 0 180)
			(size 0.508 0.508)
			(layers "F.Cu" "F.Mask" "F.Paste")
			(net "PWRGD_P5V_STBY_R")
		)
		(pad "2" smd rect
			(at 0 0.889 180)
			(size 0.508 0.508)
			(layers "F.Cu" "F.Mask" "F.Paste")
			(net "PWRGD_P5V_STBY")
		)
		(zone
			(layer "F.Cu")
			(hatch none 0.5)
			(connect_pads
				(clearance 0)
			)
			(min_thickness 0.25)
			(keepout
				(tracks not_allowed)
				(vias allowed)
				(pads allowed)
				(copperpour not_allowed)
				(footprints allowed)
			)
			(placement
				(enabled no)
				(sheetname "")
			)
			(fill
				(thermal_gap 0.5)
				(thermal_bridge_width 0.5)
				(island_removal_mode 0)
			)
			(polygon
				(pts
					(xy 393.446 -71.6915) (xy 392.938 -71.6915) (xy 392.938 -71.3105) (xy 393.446 -71.3105)
				)
			)
		)
		(zone
			(layer "F.Cu")
			(hatch none 0.5)
			(connect_pads
				(clearance 0)
			)
			(min_thickness 0.25)
			(keepout
				(tracks allowed)
				(vias not_allowed)
				(pads allowed)
				(copperpour not_allowed)
				(footprints allowed)
			)
			(placement
				(enabled no)
				(sheetname "")
			)
			(fill
				(thermal_gap 0.5)
				(thermal_bridge_width 0.5)
				(island_removal_mode 0)
			)
			(polygon
				(pts
					(xy 393.446 -71.3105) (xy 392.938 -71.3105) (xy 392.938 -71.6915) (xy 393.446 -71.6915)
				)
			)
		)
	)
	(footprint ""
		(layer "F.Cu")
		(at 269.559532 -149.8092 90)
		(property "Reference" "C5A7"
			(at 1.848866 0.752348 90)
			(unlocked yes)
			(layer "F.SilkS")
			(effects
				(font
					(size 1.27 0.9652)
					(thickness 0.1524)
				)
			)
		)
		(property "Value" ""
			(at 0 0 90)
			(layer "F.Fab")
			(effects
				(font
					(size 1.27 1.27)
				)
			)
		)
		(duplicate_pad_numbers_are_jumpers no)
		(fp_rect
			(start -0.500126 1.598422)
			(end 0.500126 -0.201422)
			(stroke
				(width 0)
				(type default)
			)
			(fill no)
			(layer "F.CrtYd")
		)
		(fp_line
			(start 0.500126 -0.201422)
			(end 0.500126 1.598422)
			(stroke
				(width 0.1)
				(type default)
			)
			(layer "F.Fab")
		)
		(fp_line
			(start -0.500126 -0.201422)
			(end 0.500126 -0.201422)
			(stroke
				(width 0.1)
				(type default)
			)
			(layer "F.Fab")
		)
		(fp_line
			(start 0.500126 1.598422)
			(end -0.500126 1.598422)
			(stroke
				(width 0.1)
				(type default)
			)
			(layer "F.Fab")
		)
		(fp_line
			(start -0.500126 1.598422)
			(end -0.500126 -0.201422)
			(stroke
				(width 0.1)
				(type default)
			)
			(layer "F.Fab")
		)
		(pad "1" smd rect
			(at 0 0)
			(size 0.889 0.9906)
			(layers "F.Cu" "F.Mask" "F.Paste")
			(net "PVDDQ_DEF")
		)
		(pad "2" smd rect
			(at 0 1.397)
			(size 0.889 0.9906)
			(layers "F.Cu" "F.Mask" "F.Paste")
			(net "GND")
		)
		(zone
			(layer "F.Cu")
			(hatch none 0.5)
			(connect_pads
				(clearance 0)
			)
			(min_thickness 0.25)
			(keepout
				(tracks allowed)
				(vias not_allowed)
				(pads allowed)
				(copperpour not_allowed)
				(footprints allowed)
			)
			(placement
				(enabled no)
				(sheetname "")
			)
			(fill
				(thermal_gap 0.5)
				(thermal_bridge_width 0.5)
				(island_removal_mode 0)
			)
			(polygon
				(pts
					(xy 270.512032 -149.3139) (xy 270.512032 -150.3045) (xy 270.004032 -150.3045) (xy 270.004032 -149.3139)
				)
			)
		)
		(zone
			(layer "F.Cu")
			(hatch none 0.5)
			(connect_pads
				(clearance 0)
			)
			(min_thickness 0.25)
			(keepout
				(tracks not_allowed)
				(vias allowed)
				(pads allowed)
				(copperpour not_allowed)
				(footprints allowed)
			)
			(placement
				(enabled no)
				(sheetname "")
			)
			(fill
				(thermal_gap 0.5)
				(thermal_bridge_width 0.5)
				(island_removal_mode 0)
			)
			(polygon
				(pts
					(xy 270.512032 -149.3139) (xy 270.512032 -150.3045) (xy 270.004032 -150.3045) (xy 270.004032 -149.3139)
				)
			)
		)
	)
	(footprint ""
		(layer "F.Cu")
		(at 191.897 -13.3985)
		(property "Reference" "C4G1"
			(at 0 0 0)
			(layer "F.SilkS")
			(hide yes)
			(effects
				(font
					(size 1.27 1.27)
				)
			)
		)
		(property "Value" ""
			(at 0 0 0)
			(layer "F.Fab")
			(effects
				(font
					(size 1.27 1.27)
				)
			)
		)
		(duplicate_pad_numbers_are_jumpers no)
		(fp_poly
			(pts
				(xy 0.3048 -0.1016) (xy 0.3048 0.9906) (xy -0.3048 0.9906) (xy -0.3048 -0.1016)
			)
			(stroke
				(width 0)
				(type default)
			)
			(fill no)
			(layer "F.CrtYd")
		)
		(fp_line
			(start -0.3048 -0.1016)
			(end -0.3048 0.9906)
			(stroke
				(width 0.1)
				(type default)
			)
			(layer "F.Fab")
		)
		(fp_line
			(start -0.3048 0.9906)
			(end 0.3048 0.9906)
			(stroke
				(width 0.1)
				(type default)
			)
			(layer "F.Fab")
		)
		(fp_line
			(start 0.3048 -0.1016)
			(end -0.3048 -0.1016)
			(stroke
				(width 0.1)
				(type default)
			)
			(layer "F.Fab")
		)
		(fp_line
			(start 0.3048 0.9906)
			(end 0.3048 -0.1016)
			(stroke
				(width 0.1)
				(type default)
			)
			(layer "F.Fab")
		)
		(pad "1" smd rect
			(at 0 0)
			(size 0.508 0.508)
			(layers "F.Cu" "F.Mask" "F.Paste")
			(net "M_B_CPU_VREF")
		)
		(pad "2" smd rect
			(at 0 0.889)
			(size 0.508 0.508)
			(layers "F.Cu" "F.Mask" "F.Paste")
			(net "GND")
		)
		(zone
			(layer "F.Cu")
			(hatch none 0.5)
			(connect_pads
				(clearance 0)
			)
			(min_thickness 0.25)
			(keepout
				(tracks allowed)
				(vias not_allowed)
				(pads allowed)
				(copperpour not_allowed)
				(footprints allowed)
			)
			(placement
				(enabled no)
				(sheetname "")
			)
			(fill
				(thermal_gap 0.5)
				(thermal_bridge_width 0.5)
				(island_removal_mode 0)
			)
			(polygon
				(pts
					(xy 191.643 -13.1445) (xy 192.151 -13.1445) (xy 192.151 -12.7635) (xy 191.643 -12.7635)
				)
			)
		)
		(zone
			(layer "F.Cu")
			(hatch none 0.5)
			(connect_pads
				(clearance 0)
			)
			(min_thickness 0.25)
			(keepout
				(tracks not_allowed)
				(vias allowed)
				(pads allowed)
				(copperpour not_allowed)
				(footprints allowed)
			)
			(placement
				(enabled no)
				(sheetname "")
			)
			(fill
				(thermal_gap 0.5)
				(thermal_bridge_width 0.5)
				(island_removal_mode 0)
			)
			(polygon
				(pts
					(xy 191.643 -12.7635) (xy 192.151 -12.7635) (xy 192.151 -13.1445) (xy 191.643 -13.1445)
				)
			)
		)
	)
	(footprint ""
		(layer "F.Cu")
		(at 110.0074 -83.8962)
		(property "Reference" "R3D1"
			(at 0 0 0)
			(layer "F.SilkS")
			(hide yes)
			(effects
				(font
					(size 1.27 1.27)
				)
			)
		)
		(property "Value" ""
			(at 0 0 0)
			(layer "F.Fab")
			(effects
				(font
					(size 1.27 1.27)
				)
			)
		)
		(duplicate_pad_numbers_are_jumpers no)
		(fp_poly
			(pts
				(xy -0.2794 -0.1016) (xy 0.2794 -0.1016) (xy 0.2794 0.9906) (xy -0.2794 0.9906)
			)
			(stroke
				(width 0)
				(type default)
			)
			(fill no)
			(layer "F.CrtYd")
		)
		(fp_line
			(start -0.2794 -0.1016)
			(end -0.2794 0.9906)
			(stroke
				(width 0.1)
				(type default)
			)
			(layer "F.Fab")
		)
		(fp_line
			(start -0.2794 0.9906)
			(end 0.2794 0.9906)
			(stroke
				(width 0.1)
				(type default)
			)
			(layer "F.Fab")
		)
		(fp_line
			(start 0.2794 -0.1016)
			(end -0.2794 -0.1016)
			(stroke
				(width 0.1)
				(type default)
			)
			(layer "F.Fab")
		)
		(fp_line
			(start 0.2794 0.9906)
			(end 0.2794 -0.1016)
			(stroke
				(width 0.1)
				(type default)
			)
			(layer "F.Fab")
		)
		(pad "1" smd rect
			(at 0 0)
			(size 0.508 0.508)
			(layers "F.Cu" "F.Mask" "F.Paste")
			(net "A_CPU1_KLM_RCOMP0")
		)
		(pad "2" smd rect
			(at 0 0.889)
			(size 0.508 0.508)
			(layers "F.Cu" "F.Mask" "F.Paste")
			(net "GND")
		)
		(zone
			(layer "F.Cu")
			(hatch none 0.5)
			(connect_pads
				(clearance 0)
			)
			(min_thickness 0.25)
			(keepout
				(tracks allowed)
				(vias not_allowed)
				(pads allowed)
				(copperpour not_allowed)
				(footprints allowed)
			)
			(placement
				(enabled no)
				(sheetname "")
			)
			(fill
				(thermal_gap 0.5)
				(thermal_bridge_width 0.5)
				(island_removal_mode 0)
			)
			(polygon
				(pts
					(xy 109.7534 -83.6422) (xy 110.2614 -83.6422) (xy 110.2614 -83.2612) (xy 109.7534 -83.2612)
				)
			)
		)
		(zone
			(layer "F.Cu")
			(hatch none 0.5)
			(connect_pads
				(clearance 0)
			)
			(min_thickness 0.25)
			(keepout
				(tracks not_allowed)
				(vias allowed)
				(pads allowed)
				(copperpour not_allowed)
				(footprints allowed)
			)
			(placement
				(enabled no)
				(sheetname "")
			)
			(fill
				(thermal_gap 0.5)
				(thermal_bridge_width 0.5)
				(island_removal_mode 0)
			)
			(polygon
				(pts
					(xy 109.7534 -83.2612) (xy 110.2614 -83.2612) (xy 110.2614 -83.6422) (xy 109.7534 -83.6422)
				)
			)
		)
	)
	(footprint ""
		(layer "F.Cu")
		(at 344.0176 -141.224 90)
		(property "Reference" "RT32"
			(at 0 0 90)
			(layer "F.SilkS")
			(hide yes)
			(effects
				(font
					(size 1.27 1.27)
				)
			)
		)
		(property "Value" "*"
			(at -0.0254 -2.6289 90)
			(unlocked yes)
			(layer "F.Fab")
			(hide yes)
			(effects
				(font
					(size 1.27 1.016)
					(thickness 0.1524)
				)
			)
		)
		(property "Device Type" "1R3F-GP_RCL_GP-1R3F-GP,64.1R00A"
			(at -0.0254 -4.1529 90)
			(unlocked yes)
			(layer "F.Fab")
			(hide yes)
			(effects
				(font
					(size 1.27 1.016)
					(thickness 0.1524)
				)
			)
		)
		(duplicate_pad_numbers_are_jumpers no)
		(fp_line
			(start 0.2032 0)
			(end 0.4826 0)
			(stroke
				(width 0.2032)
				(type default)
			)
			(layer "F.SilkS")
		)
		(fp_line
			(start -0.4826 0)
			(end -0.2032 0)
			(stroke
				(width 0.2032)
				(type default)
			)
			(layer "F.SilkS")
		)
		(fp_rect
			(start -0.5842 1.3335)
			(end 0.5842 -1.3335)
			(stroke
				(width 0)
				(type default)
			)
			(fill no)
			(layer "F.CrtYd")
		)
		(fp_rect
			(start -0.5842 1.3335)
			(end 0.5842 -1.3335)
			(stroke
				(width 0)
				(type default)
			)
			(fill no)
			(layer "F.Fab")
		)
		(pad "1" smd custom
			(at 0 -0.762 90)
			(size 0.2159 0.2159)
			(layers "F.Cu" "F.Mask" "F.Paste")
			(net "VR_PVDDQ_DEF_PH2_SW_RC")
			(options
				(clearance outline)
				(anchor circle)
			)
			(primitives
				(gr_poly
					(pts
						(arc
							(start -0.3302 -0.4318)
							(mid -0.402042 -0.402042)
							(end -0.4318 -0.3302)
						)
						(arc
							(start -0.4318 0.3302)
							(mid -0.402042 0.402042)
							(end -0.3302 0.4318)
						)
						(arc
							(start 0.3302 0.4318)
							(mid 0.402042 0.402042)
							(end 0.4318 0.3302)
						)
						(arc
							(start 0.4318 -0.3302)
							(mid 0.402042 -0.402042)
							(end 0.3302 -0.4318)
						)
					)
					(width 0)
					(fill yes)
				)
			)
		)
		(pad "2" smd custom
			(at 0 0.762 90)
			(size 0.2159 0.2159)
			(layers "F.Cu" "F.Mask" "F.Paste")
			(net "GND")
			(options
				(clearance outline)
				(anchor circle)
			)
			(primitives
				(gr_poly
					(pts
						(arc
							(start -0.3302 -0.4318)
							(mid -0.402042 -0.402042)
							(end -0.4318 -0.3302)
						)
						(arc
							(start -0.4318 0.3302)
							(mid -0.402042 0.402042)
							(end -0.3302 0.4318)
						)
						(arc
							(start 0.3302 0.4318)
							(mid 0.402042 0.402042)
							(end 0.4318 0.3302)
						)
						(arc
							(start 0.4318 -0.3302)
							(mid 0.402042 -0.402042)
							(end 0.3302 -0.4318)
						)
					)
					(width 0)
					(fill yes)
				)
			)
		)
	)
	(footprint ""
		(layer "F.Cu")
		(at 8.4074 -138.2014)
		(property "Reference" "L1A2"
			(at 3.378708 -4.251706 0)
			(unlocked yes)
			(layer "F.SilkS")
			(effects
				(font
					(size 0.4064 0.254)
					(thickness 0.1524)
				)
			)
		)
		(property "Value" ""
			(at 0 0 0)
			(layer "F.Fab")
			(effects
				(font
					(size 1.27 1.27)
				)
			)
		)
		(duplicate_pad_numbers_are_jumpers no)
		(fp_line
			(start -1.1303 -3.199892)
			(end 8.3693 -3.199892)
			(stroke
				(width 0.1524)
				(type default)
			)
			(layer "F.SilkS")
		)
		(fp_line
			(start -1.1303 -1.6637)
			(end -1.1303 -3.199892)
			(stroke
				(width 0.1524)
				(type default)
			)
			(layer "F.SilkS")
		)
		(fp_line
			(start -1.1303 3.199892)
			(end -1.1303 1.6637)
			(stroke
				(width 0.1524)
				(type default)
			)
			(layer "F.SilkS")
		)
		(fp_line
			(start 8.3693 -3.199892)
			(end 8.3693 -1.6637)
			(stroke
				(width 0.1524)
				(type default)
			)
			(layer "F.SilkS")
		)
		(fp_line
			(start 8.3693 1.6637)
			(end 8.3693 3.199892)
			(stroke
				(width 0.1524)
				(type default)
			)
			(layer "F.SilkS")
		)
		(fp_line
			(start 8.3693 3.199892)
			(end -1.1303 3.199892)
			(stroke
				(width 0.1524)
				(type default)
			)
			(layer "F.SilkS")
		)
		(fp_rect
			(start -1.1303 3.199892)
			(end 8.3693 -3.199892)
			(stroke
				(width 0)
				(type default)
			)
			(fill no)
			(layer "F.CrtYd")
		)
		(fp_line
			(start -1.1303 -3.199892)
			(end 8.3693 -3.199892)
			(stroke
				(width 0.1)
				(type default)
			)
			(layer "F.Fab")
		)
		(fp_line
			(start -1.1303 3.199892)
			(end -1.1303 -3.199892)
			(stroke
				(width 0.1)
				(type default)
			)
			(layer "F.Fab")
		)
		(fp_line
			(start 8.3693 -3.199892)
			(end 8.3693 3.199892)
			(stroke
				(width 0.1)
				(type default)
			)
			(layer "F.Fab")
		)
		(fp_line
			(start 8.3693 3.199892)
			(end -1.1303 3.199892)
			(stroke
				(width 0.1)
				(type default)
			)
			(layer "F.Fab")
		)
		(pad "1" smd rect
			(at 0 0)
			(size 3.683 2.667)
			(layers "F.Cu" "F.Mask" "F.Paste")
			(net "VR_PVDDQ_KLM_PH1_SW")
		)
		(pad "2" smd rect
			(at 7.239 0)
			(size 3.683 2.667)
			(layers "F.Cu" "F.Mask" "F.Paste")
			(net "PVDDQ_KLM")
		)
	)
	(footprint ""
		(layer "F.Cu")
		(at 480.842574 4.65709 -90)
		(property "Reference" "R9G18"
			(at 0 0 270)
			(layer "F.SilkS")
			(hide yes)
			(effects
				(font
					(size 1.27 1.27)
				)
			)
		)
		(property "Value" ""
			(at 0 0 270)
			(layer "F.Fab")
			(effects
				(font
					(size 1.27 1.27)
				)
			)
		)
		(duplicate_pad_numbers_are_jumpers no)
		(fp_poly
			(pts
				(xy -0.2794 -0.1016) (xy 0.2794 -0.1016) (xy 0.2794 0.9906) (xy -0.2794 0.9906)
			)
			(stroke
				(width 0)
				(type default)
			)
			(fill no)
			(layer "F.CrtYd")
		)
		(fp_line
			(start -0.2794 0.9906)
			(end 0.2794 0.9906)
			(stroke
				(width 0.1)
				(type default)
			)
			(layer "F.Fab")
		)
		(fp_line
			(start 0.2794 0.9906)
			(end 0.2794 -0.1016)
			(stroke
				(width 0.1)
				(type default)
			)
			(layer "F.Fab")
		)
		(fp_line
			(start -0.2794 -0.1016)
			(end -0.2794 0.9906)
			(stroke
				(width 0.1)
				(type default)
			)
			(layer "F.Fab")
		)
		(fp_line
			(start 0.2794 -0.1016)
			(end -0.2794 -0.1016)
			(stroke
				(width 0.1)
				(type default)
			)
			(layer "F.Fab")
		)
		(pad "1" smd rect
			(at 0 0 270)
			(size 0.508 0.508)
			(layers "F.Cu" "F.Mask" "F.Paste")
			(net "NIC_SET_P_MDI_2_DP")
		)
		(pad "2" smd rect
			(at 0 0.889 270)
			(size 0.508 0.508)
			(layers "F.Cu" "F.Mask" "F.Paste")
			(net "NIC_MDI_SPRV_RJ45_2_R_DP")
		)
		(zone
			(layer "F.Cu")
			(hatch none 0.5)
			(connect_pads
				(clearance 0)
			)
			(min_thickness 0.25)
			(keepout
				(tracks not_allowed)
				(vias allowed)
				(pads allowed)
				(copperpour not_allowed)
				(footprints allowed)
			)
			(placement
				(enabled no)
				(sheetname "")
			)
			(fill
				(thermal_gap 0.5)
				(thermal_bridge_width 0.5)
				(island_removal_mode 0)
			)
			(polygon
				(pts
					(xy 480.207574 4.40309) (xy 480.207574 4.91109) (xy 480.588574 4.91109) (xy 480.588574 4.40309)
				)
			)
		)
		(zone
			(layer "F.Cu")
			(hatch none 0.5)
			(connect_pads
				(clearance 0)
			)
			(min_thickness 0.25)
			(keepout
				(tracks allowed)
				(vias not_allowed)
				(pads allowed)
				(copperpour not_allowed)
				(footprints allowed)
			)
			(placement
				(enabled no)
				(sheetname "")
			)
			(fill
				(thermal_gap 0.5)
				(thermal_bridge_width 0.5)
				(island_removal_mode 0)
			)
			(polygon
				(pts
					(xy 480.588574 4.40309) (xy 480.588574 4.91109) (xy 480.207574 4.91109) (xy 480.207574 4.40309)
				)
			)
		)
	)
	(footprint ""
		(layer "F.Cu")
		(at 391.795 -151.236426)
		(property "Reference" "C8A8"
			(at 0 0 0)
			(layer "F.SilkS")
			(hide yes)
			(effects
				(font
					(size 1.27 1.27)
				)
			)
		)
		(property "Value" ""
			(at 0 0 0)
			(layer "F.Fab")
			(effects
				(font
					(size 1.27 1.27)
				)
			)
		)
		(duplicate_pad_numbers_are_jumpers no)
		(fp_poly
			(pts
				(xy 0.3048 -0.1016) (xy 0.3048 0.9906) (xy -0.3048 0.9906) (xy -0.3048 -0.1016)
			)
			(stroke
				(width 0)
				(type default)
			)
			(fill no)
			(layer "F.CrtYd")
		)
		(fp_line
			(start -0.3048 -0.1016)
			(end -0.3048 0.9906)
			(stroke
				(width 0.1)
				(type default)
			)
			(layer "F.Fab")
		)
		(fp_line
			(start -0.3048 0.9906)
			(end 0.3048 0.9906)
			(stroke
				(width 0.1)
				(type default)
			)
			(layer "F.Fab")
		)
		(fp_line
			(start 0.3048 -0.1016)
			(end -0.3048 -0.1016)
			(stroke
				(width 0.1)
				(type default)
			)
			(layer "F.Fab")
		)
		(fp_line
			(start 0.3048 0.9906)
			(end 0.3048 -0.1016)
			(stroke
				(width 0.1)
				(type default)
			)
			(layer "F.Fab")
		)
		(pad "1" smd rect
			(at 0 0)
			(size 0.508 0.508)
			(layers "F.Cu" "F.Mask" "F.Paste")
			(net "VR_PVNN_P1V05_PCH_VD12")
		)
		(pad "2" smd rect
			(at 0 0.889)
			(size 0.508 0.508)
			(layers "F.Cu" "F.Mask" "F.Paste")
			(net "GND")
		)
		(zone
			(layer "F.Cu")
			(hatch none 0.5)
			(connect_pads
				(clearance 0)
			)
			(min_thickness 0.25)
			(keepout
				(tracks allowed)
				(vias not_allowed)
				(pads allowed)
				(copperpour not_allowed)
				(footprints allowed)
			)
			(placement
				(enabled no)
				(sheetname "")
			)
			(fill
				(thermal_gap 0.5)
				(thermal_bridge_width 0.5)
				(island_removal_mode 0)
			)
			(polygon
				(pts
					(xy 391.541 -150.982426) (xy 392.049 -150.982426) (xy 392.049 -150.601426) (xy 391.541 -150.601426)
				)
			)
		)
		(zone
			(layer "F.Cu")
			(hatch none 0.5)
			(connect_pads
				(clearance 0)
			)
			(min_thickness 0.25)
			(keepout
				(tracks not_allowed)
				(vias allowed)
				(pads allowed)
				(copperpour not_allowed)
				(footprints allowed)
			)
			(placement
				(enabled no)
				(sheetname "")
			)
			(fill
				(thermal_gap 0.5)
				(thermal_bridge_width 0.5)
				(island_removal_mode 0)
			)
			(polygon
				(pts
					(xy 391.541 -150.601426) (xy 392.049 -150.601426) (xy 392.049 -150.982426) (xy 391.541 -150.982426)
				)
			)
		)
	)
	(footprint ""
		(layer "F.Cu")
		(at 351.1804 -94.685104 90)
		(property "Reference" "C7C12"
			(at 0 0 90)
			(layer "F.SilkS")
			(hide yes)
			(effects
				(font
					(size 1.27 1.27)
				)
			)
		)
		(property "Value" ""
			(at 0 0 90)
			(layer "F.Fab")
			(effects
				(font
					(size 1.27 1.27)
				)
			)
		)
		(duplicate_pad_numbers_are_jumpers no)
		(fp_poly
			(pts
				(xy 0.3048 -0.1016) (xy 0.3048 0.9906) (xy -0.3048 0.9906) (xy -0.3048 -0.1016)
			)
			(stroke
				(width 0)
				(type default)
			)
			(fill no)
			(layer "F.CrtYd")
		)
		(fp_line
			(start 0.3048 -0.1016)
			(end -0.3048 -0.1016)
			(stroke
				(width 0.1)
				(type default)
			)
			(layer "F.Fab")
		)
		(fp_line
			(start -0.3048 -0.1016)
			(end -0.3048 0.9906)
			(stroke
				(width 0.1)
				(type default)
			)
			(layer "F.Fab")
		)
		(fp_line
			(start 0.3048 0.9906)
			(end 0.3048 -0.1016)
			(stroke
				(width 0.1)
				(type default)
			)
			(layer "F.Fab")
		)
		(fp_line
			(start -0.3048 0.9906)
			(end 0.3048 0.9906)
			(stroke
				(width 0.1)
				(type default)
			)
			(layer "F.Fab")
		)
		(pad "1" smd rect
			(at 0 0 90)
			(size 0.508 0.508)
			(layers "F.Cu" "F.Mask" "F.Paste")
			(net "VR_FET_SW_P12V_STBY_PVCCIO_CPU0")
		)
		(pad "2" smd rect
			(at 0 0.889 90)
			(size 0.508 0.508)
			(layers "F.Cu" "F.Mask" "F.Paste")
			(net "GND")
		)
		(zone
			(layer "F.Cu")
			(hatch none 0.5)
			(connect_pads
				(clearance 0)
			)
			(min_thickness 0.25)
			(keepout
				(tracks allowed)
				(vias not_allowed)
				(pads allowed)
				(copperpour not_allowed)
				(footprints allowed)
			)
			(placement
				(enabled no)
				(sheetname "")
			)
			(fill
				(thermal_gap 0.5)
				(thermal_bridge_width 0.5)
				(island_removal_mode 0)
			)
			(polygon
				(pts
					(xy 351.4344 -94.431104) (xy 351.4344 -94.939104) (xy 351.8154 -94.939104) (xy 351.8154 -94.431104)
				)
			)
		)
		(zone
			(layer "F.Cu")
			(hatch none 0.5)
			(connect_pads
				(clearance 0)
			)
			(min_thickness 0.25)
			(keepout
				(tracks not_allowed)
				(vias allowed)
				(pads allowed)
				(copperpour not_allowed)
				(footprints allowed)
			)
			(placement
				(enabled no)
				(sheetname "")
			)
			(fill
				(thermal_gap 0.5)
				(thermal_bridge_width 0.5)
				(island_removal_mode 0)
			)
			(polygon
				(pts
					(xy 351.8154 -94.431104) (xy 351.8154 -94.939104) (xy 351.4344 -94.939104) (xy 351.4344 -94.431104)
				)
			)
		)
	)
	(footprint ""
		(layer "F.Cu")
		(at 385.29514 -82.28076 180)
		(property "Reference" "R7W14"
			(at -0.8382 -0.67818 180)
			(unlocked yes)
			(layer "F.SilkS")
			(effects
				(font
					(size 0.4064 0.254)
					(thickness 0.1524)
				)
				(justify left)
			)
		)
		(property "Value" ""
			(at 0 0 180)
			(layer "F.Fab")
			(effects
				(font
					(size 1.27 1.27)
				)
			)
		)
		(duplicate_pad_numbers_are_jumpers no)
		(fp_poly
			(pts
				(xy -0.2794 -0.1016) (xy 0.2794 -0.1016) (xy 0.2794 0.9906) (xy -0.2794 0.9906)
			)
			(stroke
				(width 0)
				(type default)
			)
			(fill no)
			(layer "F.CrtYd")
		)
		(fp_line
			(start 0.2794 0.9906)
			(end 0.2794 -0.1016)
			(stroke
				(width 0.1)
				(type default)
			)
			(layer "F.Fab")
		)
		(fp_line
			(start 0.2794 -0.1016)
			(end -0.2794 -0.1016)
			(stroke
				(width 0.1)
				(type default)
			)
			(layer "F.Fab")
		)
		(fp_line
			(start -0.2794 0.9906)
			(end 0.2794 0.9906)
			(stroke
				(width 0.1)
				(type default)
			)
			(layer "F.Fab")
		)
		(fp_line
			(start -0.2794 -0.1016)
			(end -0.2794 0.9906)
			(stroke
				(width 0.1)
				(type default)
			)
			(layer "F.Fab")
		)
		(pad "1" smd rect
			(at 0 0 180)
			(size 0.508 0.508)
			(layers "F.Cu" "F.Mask" "F.Paste")
			(net "FM_BMC_READY_N")
		)
		(pad "2" smd rect
			(at 0 0.889 180)
			(size 0.508 0.508)
			(layers "F.Cu" "F.Mask" "F.Paste")
			(net "FM_BMC_READY_R1_N")
		)
		(zone
			(layer "F.Cu")
			(hatch none 0.5)
			(connect_pads
				(clearance 0)
			)
			(min_thickness 0.25)
			(keepout
				(tracks not_allowed)
				(vias allowed)
				(pads allowed)
				(copperpour not_allowed)
				(footprints allowed)
			)
			(placement
				(enabled no)
				(sheetname "")
			)
			(fill
				(thermal_gap 0.5)
				(thermal_bridge_width 0.5)
				(island_removal_mode 0)
			)
			(polygon
				(pts
					(xy 385.54914 -82.91576) (xy 385.04114 -82.91576) (xy 385.04114 -82.53476) (xy 385.54914 -82.53476)
				)
			)
		)
		(zone
			(layer "F.Cu")
			(hatch none 0.5)
			(connect_pads
				(clearance 0)
			)
			(min_thickness 0.25)
			(keepout
				(tracks allowed)
				(vias not_allowed)
				(pads allowed)
				(copperpour not_allowed)
				(footprints allowed)
			)
			(placement
				(enabled no)
				(sheetname "")
			)
			(fill
				(thermal_gap 0.5)
				(thermal_bridge_width 0.5)
				(island_removal_mode 0)
			)
			(polygon
				(pts
					(xy 385.54914 -82.53476) (xy 385.04114 -82.53476) (xy 385.04114 -82.91576) (xy 385.54914 -82.91576)
				)
			)
		)
	)
	(footprint ""
		(layer "F.Cu")
		(at 383.794 -87.3125 180)
		(property "Reference" "R7D9"
			(at 0 0 180)
			(layer "F.SilkS")
			(hide yes)
			(effects
				(font
					(size 1.27 1.27)
				)
			)
		)
		(property "Value" ""
			(at 0 0 180)
			(layer "F.Fab")
			(effects
				(font
					(size 1.27 1.27)
				)
			)
		)
		(duplicate_pad_numbers_are_jumpers no)
		(fp_poly
			(pts
				(xy -0.2794 -0.1016) (xy 0.2794 -0.1016) (xy 0.2794 0.9906) (xy -0.2794 0.9906)
			)
			(stroke
				(width 0)
				(type default)
			)
			(fill no)
			(layer "F.CrtYd")
		)
		(fp_line
			(start 0.2794 0.9906)
			(end 0.2794 -0.1016)
			(stroke
				(width 0.1)
				(type default)
			)
			(layer "F.Fab")
		)
		(fp_line
			(start 0.2794 -0.1016)
			(end -0.2794 -0.1016)
			(stroke
				(width 0.1)
				(type default)
			)
			(layer "F.Fab")
		)
		(fp_line
			(start -0.2794 0.9906)
			(end 0.2794 0.9906)
			(stroke
				(width 0.1)
				(type default)
			)
			(layer "F.Fab")
		)
		(fp_line
			(start -0.2794 -0.1016)
			(end -0.2794 0.9906)
			(stroke
				(width 0.1)
				(type default)
			)
			(layer "F.Fab")
		)
		(pad "1" smd rect
			(at 0 0 180)
			(size 0.508 0.508)
			(layers "F.Cu" "F.Mask" "F.Paste")
			(net "P3V3_STBY")
		)
		(pad "2" smd rect
			(at 0 0.889 180)
			(size 0.508 0.508)
			(layers "F.Cu" "F.Mask" "F.Paste")
			(net "FM_MB_SLOT_ID1")
		)
		(zone
			(layer "F.Cu")
			(hatch none 0.5)
			(connect_pads
				(clearance 0)
			)
			(min_thickness 0.25)
			(keepout
				(tracks not_allowed)
				(vias allowed)
				(pads allowed)
				(copperpour not_allowed)
				(footprints allowed)
			)
			(placement
				(enabled no)
				(sheetname "")
			)
			(fill
				(thermal_gap 0.5)
				(thermal_bridge_width 0.5)
				(island_removal_mode 0)
			)
			(polygon
				(pts
					(xy 384.048 -87.9475) (xy 383.54 -87.9475) (xy 383.54 -87.5665) (xy 384.048 -87.5665)
				)
			)
		)
		(zone
			(layer "F.Cu")
			(hatch none 0.5)
			(connect_pads
				(clearance 0)
			)
			(min_thickness 0.25)
			(keepout
				(tracks allowed)
				(vias not_allowed)
				(pads allowed)
				(copperpour not_allowed)
				(footprints allowed)
			)
			(placement
				(enabled no)
				(sheetname "")
			)
			(fill
				(thermal_gap 0.5)
				(thermal_bridge_width 0.5)
				(island_removal_mode 0)
			)
			(polygon
				(pts
					(xy 384.048 -87.5665) (xy 383.54 -87.5665) (xy 383.54 -87.9475) (xy 384.048 -87.9475)
				)
			)
		)
	)
	(footprint ""
		(layer "F.Cu")
		(at 173.78172 -147.95246 90)
		(property "Reference" "C4A7"
			(at 0 0 90)
			(layer "F.SilkS")
			(hide yes)
			(effects
				(font
					(size 1.27 1.27)
				)
			)
		)
		(property "Value" ""
			(at 0 0 90)
			(layer "F.Fab")
			(effects
				(font
					(size 1.27 1.27)
				)
			)
		)
		(duplicate_pad_numbers_are_jumpers no)
		(fp_poly
			(pts
				(xy -0.4953 -0.2032) (xy 0.4953 -0.2032) (xy 0.4953 1.6002) (xy -0.4953 1.6002)
			)
			(stroke
				(width 0)
				(type default)
			)
			(fill no)
			(layer "F.CrtYd")
		)
		(fp_line
			(start 0.4953 -0.2032)
			(end 0.4953 1.6002)
			(stroke
				(width 0.1)
				(type default)
			)
			(layer "F.Fab")
		)
		(fp_line
			(start -0.4953 -0.2032)
			(end 0.4953 -0.2032)
			(stroke
				(width 0.1)
				(type default)
			)
			(layer "F.Fab")
		)
		(fp_line
			(start 0.4953 1.6002)
			(end -0.4953 1.6002)
			(stroke
				(width 0.1)
				(type default)
			)
			(layer "F.Fab")
		)
		(fp_line
			(start -0.4953 1.6002)
			(end -0.4953 -0.2032)
			(stroke
				(width 0.1)
				(type default)
			)
			(layer "F.Fab")
		)
		(pad "1" smd rect
			(at 0 0 90)
			(size 0.762 0.889)
			(layers "F.Cu" "F.Mask" "F.Paste")
			(net "VSENSE_PVDDQ_KLM_VTT")
		)
		(pad "2" smd rect
			(at 0 1.397 90)
			(size 0.762 0.889)
			(layers "F.Cu" "F.Mask" "F.Paste")
			(net "GND")
		)
		(zone
			(layer "F.Cu")
			(hatch none 0.5)
			(connect_pads
				(clearance 0)
			)
			(min_thickness 0.25)
			(keepout
				(tracks not_allowed)
				(vias allowed)
				(pads allowed)
				(copperpour not_allowed)
				(footprints allowed)
			)
			(placement
				(enabled no)
				(sheetname "")
			)
			(fill
				(thermal_gap 0.5)
				(thermal_bridge_width 0.5)
				(island_removal_mode 0)
			)
			(polygon
				(pts
					(xy 174.22622 -147.57146) (xy 174.22622 -148.33346) (xy 174.73422 -148.33346) (xy 174.73422 -147.57146)
				)
			)
		)
	)
	(footprint ""
		(layer "F.Cu")
		(at 177.673 -136.8425 90)
		(property "Reference" "EU4A3"
			(at 5.29463 0.1778 0)
			(unlocked yes)
			(layer "F.SilkS")
			(effects
				(font
					(size 0.7874 0.5842)
					(thickness 0.1524)
				)
				(justify left)
			)
		)
		(property "Value" ""
			(at 0 0 90)
			(layer "F.Fab")
			(effects
				(font
					(size 1.27 1.27)
				)
			)
		)
		(duplicate_pad_numbers_are_jumpers no)
		(fp_line
			(start 3.4671 -3.4671)
			(end 3.4671 3.4671)
			(stroke
				(width 0.1524)
				(type default)
			)
			(layer "F.SilkS")
		)
		(fp_line
			(start -3.4671 -3.4671)
			(end 3.4671 -3.4671)
			(stroke
				(width 0.1524)
				(type default)
			)
			(layer "F.SilkS")
		)
		(fp_line
			(start 3.10007 -3.10007)
			(end 3.10007 -2.900934)
			(stroke
				(width 0.1524)
				(type default)
			)
			(layer "F.SilkS")
		)
		(fp_line
			(start 2.897886 -3.10007)
			(end 3.10007 -3.10007)
			(stroke
				(width 0.1524)
				(type default)
			)
			(layer "F.SilkS")
		)
		(fp_line
			(start -3.10007 -3.10007)
			(end -2.897886 -3.10007)
			(stroke
				(width 0.1524)
				(type default)
			)
			(layer "F.SilkS")
		)
		(fp_line
			(start -3.10007 -2.900934)
			(end -3.10007 -3.10007)
			(stroke
				(width 0.1524)
				(type default)
			)
			(layer "F.SilkS")
		)
		(fp_line
			(start 3.10007 2.897378)
			(end 3.10007 3.10007)
			(stroke
				(width 0.1524)
				(type default)
			)
			(layer "F.SilkS")
		)
		(fp_line
			(start 3.10007 3.10007)
			(end 2.897886 3.10007)
			(stroke
				(width 0.1524)
				(type default)
			)
			(layer "F.SilkS")
		)
		(fp_line
			(start -2.897886 3.10007)
			(end -3.10007 3.10007)
			(stroke
				(width 0.1524)
				(type default)
			)
			(layer "F.SilkS")
		)
		(fp_line
			(start -3.10007 3.10007)
			(end -3.10007 2.897378)
			(stroke
				(width 0.1524)
				(type default)
			)
			(layer "F.SilkS")
		)
		(fp_line
			(start 3.4671 3.4671)
			(end -3.4671 3.4671)
			(stroke
				(width 0.1524)
				(type default)
			)
			(layer "F.SilkS")
		)
		(fp_line
			(start -3.4671 3.4671)
			(end -3.4671 -3.4671)
			(stroke
				(width 0.1524)
				(type default)
			)
			(layer "F.SilkS")
		)
		(fp_circle
			(center -3.917696 -3.100578)
			(end -3.917696 -2.973578)
			(stroke
				(width 0.254)
				(type default)
			)
			(fill no)
			(layer "F.SilkS")
		)
		(fp_poly
			(pts
				(xy -3.4671 -3.4671) (xy -3.4671 -2.5146) (xy -2.5146 -3.4671)
			)
			(stroke
				(width 0)
				(type default)
			)
			(fill yes)
			(layer "F.SilkS")
		)
		(fp_rect
			(start -2.1971 -0.1905)
			(end -0.6985 -2.1971)
			(stroke
				(width 0)
				(type default)
			)
			(fill yes)
			(layer "F.Paste")
		)
		(fp_rect
			(start -0.1905 2.1971)
			(end 2.1971 -2.1971)
			(stroke
				(width 0)
				(type default)
			)
			(fill yes)
			(layer "F.Paste")
		)
		(fp_rect
			(start -2.1971 2.1971)
			(end -0.6985 0.1905)
			(stroke
				(width 0)
				(type default)
			)
			(fill yes)
			(layer "F.Paste")
		)
		(fp_poly
			(pts
				(xy -3.10007 -3.10007) (xy -3.10007 3.10007) (xy 3.10007 3.10007) (xy 3.10007 -3.10007)
			)
			(stroke
				(width 0)
				(type default)
			)
			(fill no)
			(layer "F.CrtYd")
		)
		(fp_line
			(start 3.10007 -3.10007)
			(end 3.10007 3.10007)
			(stroke
				(width 0.1)
				(type default)
			)
			(layer "F.Fab")
		)
		(fp_line
			(start -3.10007 -3.10007)
			(end 3.10007 -3.10007)
			(stroke
				(width 0.1)
				(type default)
			)
			(layer "F.Fab")
		)
		(fp_line
			(start 3.10007 3.10007)
			(end -3.10007 3.10007)
			(stroke
				(width 0.1)
				(type default)
			)
			(layer "F.Fab")
		)
		(fp_line
			(start -3.10007 3.10007)
			(end -3.10007 -3.10007)
			(stroke
				(width 0.1)
				(type default)
			)
			(layer "F.Fab")
		)
		(fp_circle
			(center -3.917696 -3.100578)
			(end -3.917696 -2.973578)
			(stroke
				(width 0.254)
				(type default)
			)
			(fill no)
			(layer "F.Fab")
		)
		(pad "1" smd custom
			(at -2.8321 -2.249932 90)
			(size 0.06985 0.06985)
			(layers "F.Cu" "F.Mask" "F.Paste")
			(net "VR_PVPP_KLM_SS")
			(options
				(clearance outline)
				(anchor circle)
			)
			(primitives
				(gr_poly
					(pts
						(arc
							(start 0.2413 -0.1397)
							(mid 0.381 0)
							(end 0.2413 0.1397)
						)
						(xy -0.381 0.1397) (xy -0.381 -0.1397)
					)
					(width 0)
					(fill yes)
				)
			)
		)
		(pad "2" smd custom
			(at -2.8321 -1.75006 90)
			(size 0.06985 0.06985)
			(layers "F.Cu" "F.Mask" "F.Paste")
			(net "VR_FB_PVPP_KLM")
			(options
				(clearance outline)
				(anchor circle)
			)
			(primitives
				(gr_poly
					(pts
						(arc
							(start 0.2413 -0.1397)
							(mid 0.381 0)
							(end 0.2413 0.1397)
						)
						(xy -0.381 0.1397) (xy -0.381 -0.1397)
					)
					(width 0)
					(fill yes)
				)
			)
		)
		(pad "3" smd custom
			(at -2.8321 -1.249934 90)
			(size 0.06985 0.06985)
			(layers "F.Cu" "F.Mask" "F.Paste")
			(net "VR_COMP_PVPP_KLM_3")
			(options
				(clearance outline)
				(anchor circle)
			)
			(primitives
				(gr_poly
					(pts
						(arc
							(start 0.2413 -0.1397)
							(mid 0.381 0)
							(end 0.2413 0.1397)
						)
						(xy -0.381 0.1397) (xy -0.381 -0.1397)
					)
					(width 0)
					(fill yes)
				)
			)
		)
		(pad "4" smd custom
			(at -2.8321 -0.750062 90)
			(size 0.06985 0.06985)
			(layers "F.Cu" "F.Mask" "F.Paste")
			(net "VR_PVPP_KLM_ISET")
			(options
				(clearance outline)
				(anchor circle)
			)
			(primitives
				(gr_poly
					(pts
						(arc
							(start 0.2413 -0.1397)
							(mid 0.381 0)
							(end 0.2413 0.1397)
						)
						(xy -0.381 0.1397) (xy -0.381 -0.1397)
					)
					(width 0)
					(fill yes)
				)
			)
		)
		(pad "5" smd custom
			(at -2.8321 -0.249936 90)
			(size 0.06985 0.06985)
			(layers "F.Cu" "F.Mask" "F.Paste")
			(net "AGND_PVPP_KLM")
			(options
				(clearance outline)
				(anchor circle)
			)
			(primitives
				(gr_poly
					(pts
						(arc
							(start 0.2413 -0.1397)
							(mid 0.381 0)
							(end 0.2413 0.1397)
						)
						(xy -0.381 0.1397) (xy -0.381 -0.1397)
					)
					(width 0)
					(fill yes)
				)
			)
		)
		(pad "6" smd custom
			(at -2.8321 0.249936 90)
			(size 0.06985 0.06985)
			(layers "F.Cu" "F.Mask" "F.Paste")
			(net "AGND_PVPP_KLM")
			(options
				(clearance outline)
				(anchor circle)
			)
			(primitives
				(gr_poly
					(pts
						(arc
							(start 0.2413 -0.1397)
							(mid 0.381 0)
							(end 0.2413 0.1397)
						)
						(xy -0.381 0.1397) (xy -0.381 -0.1397)
					)
					(width 0)
					(fill yes)
				)
			)
		)
		(pad "7" smd custom
			(at -2.8321 0.750062 90)
			(size 0.06985 0.06985)
			(layers "F.Cu" "F.Mask" "F.Paste")
			(net "PWRGD_PVPP_KLM_R")
			(options
				(clearance outline)
				(anchor circle)
			)
			(primitives
				(gr_poly
					(pts
						(arc
							(start 0.2413 -0.1397)
							(mid 0.381 0)
							(end 0.2413 0.1397)
						)
						(xy -0.381 0.1397) (xy -0.381 -0.1397)
					)
					(width 0)
					(fill yes)
				)
			)
		)
		(pad "8" smd custom
			(at -2.8321 1.249934 90)
			(size 0.06985 0.06985)
			(layers "F.Cu" "F.Mask" "F.Paste")
			(net "VR_FET_SW_P12V_STBY_PVPP_KLM")
			(options
				(clearance outline)
				(anchor circle)
			)
			(primitives
				(gr_poly
					(pts
						(arc
							(start 0.2413 -0.1397)
							(mid 0.381 0)
							(end 0.2413 0.1397)
						)
						(xy -0.381 0.1397) (xy -0.381 -0.1397)
					)
					(width 0)
					(fill yes)
				)
			)
		)
		(pad "9" smd custom
			(at -2.8321 1.75006 90)
			(size 0.06985 0.06985)
			(layers "F.Cu" "F.Mask" "F.Paste")
			(net "VR_FET_SW_P12V_STBY_PVPP_KLM")
			(options
				(clearance outline)
				(anchor circle)
			)
			(primitives
				(gr_poly
					(pts
						(arc
							(start 0.2413 -0.1397)
							(mid 0.381 0)
							(end 0.2413 0.1397)
						)
						(xy -0.381 0.1397) (xy -0.381 -0.1397)
					)
					(width 0)
					(fill yes)
				)
			)
		)
		(pad "10" smd custom
			(at -2.8321 2.249932 90)
			(size 0.06985 0.06985)
			(layers "F.Cu" "F.Mask" "F.Paste")
			(net "VR_FET_SW_P12V_STBY_PVPP_KLM")
			(options
				(clearance outline)
				(anchor circle)
			)
			(primitives
				(gr_poly
					(pts
						(arc
							(start 0.2413 -0.1397)
							(mid 0.381 0)
							(end 0.2413 0.1397)
						)
						(xy -0.381 0.1397) (xy -0.381 -0.1397)
					)
					(width 0)
					(fill yes)
				)
			)
		)
		(pad "11" smd custom
			(at -2.249932 2.8321 90)
			(size 0.06985 0.06985)
			(layers "F.Cu" "F.Mask" "F.Paste")
			(net "VR_FET_SW_P12V_STBY_PVPP_KLM")
			(options
				(clearance outline)
				(anchor circle)
			)
			(primitives
				(gr_poly
					(pts
						(arc
							(start -0.1397 -0.2413)
							(mid 0 -0.381)
							(end 0.1397 -0.2413)
						)
						(xy 0.1397 0.381) (xy -0.1397 0.381)
					)
					(width 0)
					(fill yes)
				)
			)
		)
		(pad "12" smd custom
			(at -1.75006 2.8321 90)
			(size 0.06985 0.06985)
			(layers "F.Cu" "F.Mask" "F.Paste")
			(net "VR_FET_SW_P12V_STBY_PVPP_KLM")
			(options
				(clearance outline)
				(anchor circle)
			)
			(primitives
				(gr_poly
					(pts
						(arc
							(start -0.1397 -0.2413)
							(mid 0 -0.381)
							(end 0.1397 -0.2413)
						)
						(xy 0.1397 0.381) (xy -0.1397 0.381)
					)
					(width 0)
					(fill yes)
				)
			)
		)
		(pad "13" smd custom
			(at -1.249934 2.8321 90)
			(size 0.06985 0.06985)
			(layers "F.Cu" "F.Mask" "F.Paste")
			(net "VR_FET_SW_P12V_STBY_PVPP_KLM")
			(options
				(clearance outline)
				(anchor circle)
			)
			(primitives
				(gr_poly
					(pts
						(arc
							(start -0.1397 -0.2413)
							(mid 0 -0.381)
							(end 0.1397 -0.2413)
						)
						(xy 0.1397 0.381) (xy -0.1397 0.381)
					)
					(width 0)
					(fill yes)
				)
			)
		)
		(pad "14" smd custom
			(at -0.750062 2.8321 90)
			(size 0.06985 0.06985)
			(layers "F.Cu" "F.Mask" "F.Paste")
			(net "VR_FET_SW_P12V_STBY_PVPP_KLM")
			(options
				(clearance outline)
				(anchor circle)
			)
			(primitives
				(gr_poly
					(pts
						(arc
							(start -0.1397 -0.2413)
							(mid 0 -0.381)
							(end 0.1397 -0.2413)
						)
						(xy 0.1397 0.381) (xy -0.1397 0.381)
					)
					(width 0)
					(fill yes)
				)
			)
		)
		(pad "15" smd custom
			(at -0.249936 2.8321 90)
			(size 0.06985 0.06985)
			(layers "F.Cu" "F.Mask" "F.Paste")
			(net "VR_PVPP_KLM_PHASE")
			(options
				(clearance outline)
				(anchor circle)
			)
			(primitives
				(gr_poly
					(pts
						(arc
							(start -0.1397 -0.2413)
							(mid 0 -0.381)
							(end 0.1397 -0.2413)
						)
						(xy 0.1397 0.381) (xy -0.1397 0.381)
					)
					(width 0)
					(fill yes)
				)
			)
		)
		(pad "16" smd custom
			(at 0.249936 2.8321 90)
			(size 0.06985 0.06985)
			(layers "F.Cu" "F.Mask" "F.Paste")
			(net "GND")
			(options
				(clearance outline)
				(anchor circle)
			)
			(primitives
				(gr_poly
					(pts
						(arc
							(start -0.1397 -0.2413)
							(mid 0 -0.381)
							(end 0.1397 -0.2413)
						)
						(xy 0.1397 0.381) (xy -0.1397 0.381)
					)
					(width 0)
					(fill yes)
				)
			)
		)
		(pad "17" smd custom
			(at 0.750062 2.8321 90)
			(size 0.06985 0.06985)
			(layers "F.Cu" "F.Mask" "F.Paste")
			(net "GND")
			(options
				(clearance outline)
				(anchor circle)
			)
			(primitives
				(gr_poly
					(pts
						(arc
							(start -0.1397 -0.2413)
							(mid 0 -0.381)
							(end 0.1397 -0.2413)
						)
						(xy 0.1397 0.381) (xy -0.1397 0.381)
					)
					(width 0)
					(fill yes)
				)
			)
		)
		(pad "18" smd custom
			(at 1.249934 2.8321 90)
			(size 0.06985 0.06985)
			(layers "F.Cu" "F.Mask" "F.Paste")
			(net "GND")
			(options
				(clearance outline)
				(anchor circle)
			)
			(primitives
				(gr_poly
					(pts
						(arc
							(start -0.1397 -0.2413)
							(mid 0 -0.381)
							(end 0.1397 -0.2413)
						)
						(xy 0.1397 0.381) (xy -0.1397 0.381)
					)
					(width 0)
					(fill yes)
				)
			)
		)
		(pad "19" smd custom
			(at 1.75006 2.8321 90)
			(size 0.06985 0.06985)
			(layers "F.Cu" "F.Mask" "F.Paste")
			(net "GND")
			(options
				(clearance outline)
				(anchor circle)
			)
			(primitives
				(gr_poly
					(pts
						(arc
							(start -0.1397 -0.2413)
							(mid 0 -0.381)
							(end 0.1397 -0.2413)
						)
						(xy 0.1397 0.381) (xy -0.1397 0.381)
					)
					(width 0)
					(fill yes)
				)
			)
		)
		(pad "20" smd custom
			(at 2.249932 2.8321 90)
			(size 0.06985 0.06985)
			(layers "F.Cu" "F.Mask" "F.Paste")
			(net "GND")
			(options
				(clearance outline)
				(anchor circle)
			)
			(primitives
				(gr_poly
					(pts
						(arc
							(start -0.1397 -0.2413)
							(mid 0 -0.381)
							(end 0.1397 -0.2413)
						)
						(xy 0.1397 0.381) (xy -0.1397 0.381)
					)
					(width 0)
					(fill yes)
				)
			)
		)
		(pad "21" smd custom
			(at 2.8321 2.249932 90)
			(size 0.06985 0.06985)
			(layers "F.Cu" "F.Mask" "F.Paste")
			(net "GND")
			(options
				(clearance outline)
				(anchor circle)
			)
			(primitives
				(gr_poly
					(pts
						(arc
							(start -0.2413 0.1397)
							(mid -0.381 0)
							(end -0.2413 -0.1397)
						)
						(xy 0.381 -0.1397) (xy 0.381 0.1397)
					)
					(width 0)
					(fill yes)
				)
			)
		)
		(pad "22" smd custom
			(at 2.8321 1.75006 90)
			(size 0.06985 0.06985)
			(layers "F.Cu" "F.Mask" "F.Paste")
			(net "GND")
			(options
				(clearance outline)
				(anchor circle)
			)
			(primitives
				(gr_poly
					(pts
						(arc
							(start -0.2413 0.1397)
							(mid -0.381 0)
							(end -0.2413 -0.1397)
						)
						(xy 0.381 -0.1397) (xy 0.381 0.1397)
					)
					(width 0)
					(fill yes)
				)
			)
		)
		(pad "23" smd custom
			(at 2.8321 1.249934 90)
			(size 0.06985 0.06985)
			(layers "F.Cu" "F.Mask" "F.Paste")
			(net "GND")
			(options
				(clearance outline)
				(anchor circle)
			)
			(primitives
				(gr_poly
					(pts
						(arc
							(start -0.2413 0.1397)
							(mid -0.381 0)
							(end -0.2413 -0.1397)
						)
						(xy 0.381 -0.1397) (xy 0.381 0.1397)
					)
					(width 0)
					(fill yes)
				)
			)
		)
		(pad "24" smd custom
			(at 2.8321 0.750062 90)
			(size 0.06985 0.06985)
			(layers "F.Cu" "F.Mask" "F.Paste")
			(net "GND")
			(options
				(clearance outline)
				(anchor circle)
			)
			(primitives
				(gr_poly
					(pts
						(arc
							(start -0.2413 0.1397)
							(mid -0.381 0)
							(end -0.2413 -0.1397)
						)
						(xy 0.381 -0.1397) (xy 0.381 0.1397)
					)
					(width 0)
					(fill yes)
				)
			)
		)
		(pad "25" smd custom
			(at 2.8321 0.249936 90)
			(size 0.06985 0.06985)
			(layers "F.Cu" "F.Mask" "F.Paste")
			(net "GND")
			(options
				(clearance outline)
				(anchor circle)
			)
			(primitives
				(gr_poly
					(pts
						(arc
							(start -0.2413 0.1397)
							(mid -0.381 0)
							(end -0.2413 -0.1397)
						)
						(xy 0.381 -0.1397) (xy 0.381 0.1397)
					)
					(width 0)
					(fill yes)
				)
			)
		)
		(pad "26" smd custom
			(at 2.8321 -0.249936 90)
			(size 0.06985 0.06985)
			(layers "F.Cu" "F.Mask" "F.Paste")
			(net "GND")
			(options
				(clearance outline)
				(anchor circle)
			)
			(primitives
				(gr_poly
					(pts
						(arc
							(start -0.2413 0.1397)
							(mid -0.381 0)
							(end -0.2413 -0.1397)
						)
						(xy 0.381 -0.1397) (xy 0.381 0.1397)
					)
					(width 0)
					(fill yes)
				)
			)
		)
		(pad "27" smd custom
			(at 2.8321 -0.750062 90)
			(size 0.06985 0.06985)
			(layers "F.Cu" "F.Mask" "F.Paste")
			(net "GND")
			(options
				(clearance outline)
				(anchor circle)
			)
			(primitives
				(gr_poly
					(pts
						(arc
							(start -0.2413 0.1397)
							(mid -0.381 0)
							(end -0.2413 -0.1397)
						)
						(xy 0.381 -0.1397) (xy 0.381 0.1397)
					)
					(width 0)
					(fill yes)
				)
			)
		)
		(pad "28" smd custom
			(at 2.8321 -1.249934 90)
			(size 0.06985 0.06985)
			(layers "F.Cu" "F.Mask" "F.Paste")
			(net "GND")
			(options
				(clearance outline)
				(anchor circle)
			)
			(primitives
				(gr_poly
					(pts
						(arc
							(start -0.2413 0.1397)
							(mid -0.381 0)
							(end -0.2413 -0.1397)
						)
						(xy 0.381 -0.1397) (xy 0.381 0.1397)
					)
					(width 0)
					(fill yes)
				)
			)
		)
		(pad "29" smd custom
			(at 2.8321 -1.75006 90)
			(size 0.06985 0.06985)
			(layers "F.Cu" "F.Mask" "F.Paste")
			(net "VR_PVPP_KLM_PHASE")
			(options
				(clearance outline)
				(anchor circle)
			)
			(primitives
				(gr_poly
					(pts
						(arc
							(start -0.2413 0.1397)
							(mid -0.381 0)
							(end -0.2413 -0.1397)
						)
						(xy 0.381 -0.1397) (xy 0.381 0.1397)
					)
					(width 0)
					(fill yes)
				)
			)
		)
		(pad "30" smd custom
			(at 2.8321 -2.249932 90)
			(size 0.06985 0.06985)
			(layers "F.Cu" "F.Mask" "F.Paste")
			(net "VR_PVPP_KLM_PHASE")
			(options
				(clearance outline)
				(anchor circle)
			)
			(primitives
				(gr_poly
					(pts
						(arc
							(start -0.2413 0.1397)
							(mid -0.381 0)
							(end -0.2413 -0.1397)
						)
						(xy 0.381 -0.1397) (xy 0.381 0.1397)
					)
					(width 0)
					(fill yes)
				)
			)
		)
		(pad "31" smd custom
			(at 2.249932 -2.8321 90)
			(size 0.06985 0.06985)
			(layers "F.Cu" "F.Mask" "F.Paste")
			(net "VR_PVPP_KLM_PHASE")
			(options
				(clearance outline)
				(anchor circle)
			)
			(primitives
				(gr_poly
					(pts
						(arc
							(start 0.1397 0.2413)
							(mid 0 0.381)
							(end -0.1397 0.2413)
						)
						(xy -0.1397 -0.381) (xy 0.1397 -0.381)
					)
					(width 0)
					(fill yes)
				)
			)
		)
		(pad "32" smd custom
			(at 1.75006 -2.8321 90)
			(size 0.06985 0.06985)
			(layers "F.Cu" "F.Mask" "F.Paste")
			(net "VR_PVPP_KLM_PHASE")
			(options
				(clearance outline)
				(anchor circle)
			)
			(primitives
				(gr_poly
					(pts
						(arc
							(start 0.1397 0.2413)
							(mid 0 0.381)
							(end -0.1397 0.2413)
						)
						(xy -0.1397 -0.381) (xy 0.1397 -0.381)
					)
					(width 0)
					(fill yes)
				)
			)
		)
		(pad "33" smd custom
			(at 1.249934 -2.8321 90)
			(size 0.06985 0.06985)
			(layers "F.Cu" "F.Mask" "F.Paste")
			(net "VR_PVPP_KLM_PHASE")
			(options
				(clearance outline)
				(anchor circle)
			)
			(primitives
				(gr_poly
					(pts
						(arc
							(start 0.1397 0.2413)
							(mid 0 0.381)
							(end -0.1397 0.2413)
						)
						(xy -0.1397 -0.381) (xy 0.1397 -0.381)
					)
					(width 0)
					(fill yes)
				)
			)
		)
		(pad "34" smd custom
			(at 0.750062 -2.8321 90)
			(size 0.06985 0.06985)
			(layers "F.Cu" "F.Mask" "F.Paste")
			(net "VR_PVPP_KLM_PHASE")
			(options
				(clearance outline)
				(anchor circle)
			)
			(primitives
				(gr_poly
					(pts
						(arc
							(start 0.1397 0.2413)
							(mid 0 0.381)
							(end -0.1397 0.2413)
						)
						(xy -0.1397 -0.381) (xy 0.1397 -0.381)
					)
					(width 0)
					(fill yes)
				)
			)
		)
		(pad "35" smd custom
			(at 0.249936 -2.8321 90)
			(size 0.06985 0.06985)
			(layers "F.Cu" "F.Mask" "F.Paste")
			(net "VR_PVPP_KLM_PHASE")
			(options
				(clearance outline)
				(anchor circle)
			)
			(primitives
				(gr_poly
					(pts
						(arc
							(start 0.1397 0.2413)
							(mid 0 0.381)
							(end -0.1397 0.2413)
						)
						(xy -0.1397 -0.381) (xy 0.1397 -0.381)
					)
					(width 0)
					(fill yes)
				)
			)
		)
		(pad "36" smd custom
			(at -0.249936 -2.8321 90)
			(size 0.06985 0.06985)
			(layers "F.Cu" "F.Mask" "F.Paste")
			(net "VR_PVPP_KLM_BOOT")
			(options
				(clearance outline)
				(anchor circle)
			)
			(primitives
				(gr_poly
					(pts
						(arc
							(start 0.1397 0.2413)
							(mid 0 0.381)
							(end -0.1397 0.2413)
						)
						(xy -0.1397 -0.381) (xy 0.1397 -0.381)
					)
					(width 0)
					(fill yes)
				)
			)
		)
		(pad "37" smd custom
			(at -0.750062 -2.8321 90)
			(size 0.06985 0.06985)
			(layers "F.Cu" "F.Mask" "F.Paste")
			(net "GND")
			(options
				(clearance outline)
				(anchor circle)
			)
			(primitives
				(gr_poly
					(pts
						(arc
							(start 0.1397 0.2413)
							(mid 0 0.381)
							(end -0.1397 0.2413)
						)
						(xy -0.1397 -0.381) (xy 0.1397 -0.381)
					)
					(width 0)
					(fill yes)
				)
			)
		)
		(pad "38" smd custom
			(at -1.249934 -2.8321 90)
			(size 0.06985 0.06985)
			(layers "F.Cu" "F.Mask" "F.Paste")
			(net "VR_VB_PVPP_KLM")
			(options
				(clearance outline)
				(anchor circle)
			)
			(primitives
				(gr_poly
					(pts
						(arc
							(start 0.1397 0.2413)
							(mid 0 0.381)
							(end -0.1397 0.2413)
						)
						(xy -0.1397 -0.381) (xy 0.1397 -0.381)
					)
					(width 0)
					(fill yes)
				)
			)
		)
		(pad "39" smd custom
			(at -1.75006 -2.8321 90)
			(size 0.06985 0.06985)
			(layers "F.Cu" "F.Mask" "F.Paste")
			(net "VR_FET_SW_P12V_STBY_PVPP_KLM")
			(options
				(clearance outline)
				(anchor circle)
			)
			(primitives
				(gr_poly
					(pts
						(arc
							(start 0.1397 0.2413)
							(mid 0 0.381)
							(end -0.1397 0.2413)
						)
						(xy -0.1397 -0.381) (xy 0.1397 -0.381)
					)
					(width 0)
					(fill yes)
				)
			)
		)
		(pad "40" smd custom
			(at -2.249932 -2.8321 90)
			(size 0.06985 0.06985)
			(layers "F.Cu" "F.Mask" "F.Paste")
			(net "FM_PVPP_PVDDQ_CPU1_EN_KLM")
			(options
				(clearance outline)
				(anchor circle)
			)
			(primitives
				(gr_poly
					(pts
						(arc
							(start 0.1397 0.2413)
							(mid 0 0.381)
							(end -0.1397 0.2413)
						)
						(xy -0.1397 -0.381) (xy 0.1397 -0.381)
					)
					(width 0)
					(fill yes)
				)
			)
		)
		(pad "41" smd rect
			(at -1.4478 -1.1938 90)
			(size 1.4986 2.0066)
			(layers "F.Cu" "F.Mask" "F.Paste")
			(net "GND")
		)
		(pad "42" smd rect
			(at -1.4478 1.1938 90)
			(size 1.4986 2.0066)
			(layers "F.Cu" "F.Mask" "F.Paste")
			(net "VR_FET_SW_P12V_STBY_PVPP_KLM")
		)
		(pad "43" smd rect
			(at 1.0033 0 90)
			(size 2.3876 4.3942)
			(layers "F.Cu" "F.Mask" "F.Paste")
			(net "VR_PVPP_KLM_PHASE")
		)
	)
	(footprint ""
		(layer "F.Cu")
		(at 343.95664 -2.44348 90)
		(property "Reference" "RT35"
			(at 0 0 90)
			(layer "F.SilkS")
			(hide yes)
			(effects
				(font
					(size 1.27 1.27)
				)
			)
		)
		(property "Value" "*"
			(at -0.0254 -2.6289 90)
			(unlocked yes)
			(layer "F.Fab")
			(hide yes)
			(effects
				(font
					(size 1.27 1.016)
					(thickness 0.1524)
				)
			)
		)
		(property "Device Type" "1R3F-GP_RCL_GP-1R3F-GP,64.1R00A"
			(at -0.0254 -4.1529 90)
			(unlocked yes)
			(layer "F.Fab")
			(hide yes)
			(effects
				(font
					(size 1.27 1.016)
					(thickness 0.1524)
				)
			)
		)
		(duplicate_pad_numbers_are_jumpers no)
		(fp_line
			(start 0.2032 0)
			(end 0.4826 0)
			(stroke
				(width 0.2032)
				(type default)
			)
			(layer "F.SilkS")
		)
		(fp_line
			(start -0.4826 0)
			(end -0.2032 0)
			(stroke
				(width 0.2032)
				(type default)
			)
			(layer "F.SilkS")
		)
		(fp_rect
			(start -0.5842 1.3335)
			(end 0.5842 -1.3335)
			(stroke
				(width 0)
				(type default)
			)
			(fill no)
			(layer "F.CrtYd")
		)
		(fp_rect
			(start -0.5842 1.3335)
			(end 0.5842 -1.3335)
			(stroke
				(width 0)
				(type default)
			)
			(fill no)
			(layer "F.Fab")
		)
		(pad "1" smd custom
			(at 0 -0.762 90)
			(size 0.2159 0.2159)
			(layers "F.Cu" "F.Mask" "F.Paste")
			(net "VR_PVDDQ_ABC_PH2_SW_RC")
			(options
				(clearance outline)
				(anchor circle)
			)
			(primitives
				(gr_poly
					(pts
						(arc
							(start -0.3302 -0.4318)
							(mid -0.402042 -0.402042)
							(end -0.4318 -0.3302)
						)
						(arc
							(start -0.4318 0.3302)
							(mid -0.402042 0.402042)
							(end -0.3302 0.4318)
						)
						(arc
							(start 0.3302 0.4318)
							(mid 0.402042 0.402042)
							(end 0.4318 0.3302)
						)
						(arc
							(start 0.4318 -0.3302)
							(mid 0.402042 -0.402042)
							(end 0.3302 -0.4318)
						)
					)
					(width 0)
					(fill yes)
				)
			)
		)
		(pad "2" smd custom
			(at 0 0.762 90)
			(size 0.2159 0.2159)
			(layers "F.Cu" "F.Mask" "F.Paste")
			(net "GND")
			(options
				(clearance outline)
				(anchor circle)
			)
			(primitives
				(gr_poly
					(pts
						(arc
							(start -0.3302 -0.4318)
							(mid -0.402042 -0.402042)
							(end -0.4318 -0.3302)
						)
						(arc
							(start -0.4318 0.3302)
							(mid -0.402042 0.402042)
							(end -0.3302 0.4318)
						)
						(arc
							(start 0.3302 0.4318)
							(mid 0.402042 0.402042)
							(end 0.4318 0.3302)
						)
						(arc
							(start 0.4318 -0.3302)
							(mid 0.402042 -0.402042)
							(end 0.3302 -0.4318)
						)
					)
					(width 0)
					(fill yes)
				)
			)
		)
	)
	(footprint ""
		(layer "F.Cu")
		(at 194.344036 -69.770244)
		(property "Reference" "CT39"
			(at -0.35687 -5.5118 270)
			(unlocked yes)
			(layer "F.SilkS")
			(effects
				(font
					(size 0.7874 0.5842)
					(thickness 0.1524)
				)
				(justify left)
			)
		)
		(property "Value" ""
			(at 0 0 0)
			(layer "F.Fab")
			(effects
				(font
					(size 1.27 1.27)
				)
			)
		)
		(duplicate_pad_numbers_are_jumpers no)
		(fp_poly
			(pts
				(xy 0.3048 -0.1016) (xy 0.3048 0.9906) (xy -0.3048 0.9906) (xy -0.3048 -0.1016)
			)
			(stroke
				(width 0)
				(type default)
			)
			(fill no)
			(layer "F.CrtYd")
		)
		(fp_line
			(start -0.3048 -0.1016)
			(end -0.3048 0.9906)
			(stroke
				(width 0.1)
				(type default)
			)
			(layer "F.Fab")
		)
		(fp_line
			(start -0.3048 0.9906)
			(end 0.3048 0.9906)
			(stroke
				(width 0.1)
				(type default)
			)
			(layer "F.Fab")
		)
		(fp_line
			(start 0.3048 -0.1016)
			(end -0.3048 -0.1016)
			(stroke
				(width 0.1)
				(type default)
			)
			(layer "F.Fab")
		)
		(fp_line
			(start 0.3048 0.9906)
			(end 0.3048 -0.1016)
			(stroke
				(width 0.1)
				(type default)
			)
			(layer "F.Fab")
		)
		(pad "1" smd rect
			(at 0 0)
			(size 0.508 0.508)
			(layers "F.Cu" "F.Mask" "F.Paste")
			(net "VR_PVCCIN_CPU0_AIREF3")
		)
		(pad "2" smd rect
			(at 0 0.889)
			(size 0.508 0.508)
			(layers "F.Cu" "F.Mask" "F.Paste")
			(net "GND")
		)
		(zone
			(layer "F.Cu")
			(hatch none 0.5)
			(connect_pads
				(clearance 0)
			)
			(min_thickness 0.25)
			(keepout
				(tracks allowed)
				(vias not_allowed)
				(pads allowed)
				(copperpour not_allowed)
				(footprints allowed)
			)
			(placement
				(enabled no)
				(sheetname "")
			)
			(fill
				(thermal_gap 0.5)
				(thermal_bridge_width 0.5)
				(island_removal_mode 0)
			)
			(polygon
				(pts
					(xy 194.090036 -69.516244) (xy 194.598036 -69.516244) (xy 194.598036 -69.135244) (xy 194.090036 -69.135244)
				)
			)
		)
		(zone
			(layer "F.Cu")
			(hatch none 0.5)
			(connect_pads
				(clearance 0)
			)
			(min_thickness 0.25)
			(keepout
				(tracks not_allowed)
				(vias allowed)
				(pads allowed)
				(copperpour not_allowed)
				(footprints allowed)
			)
			(placement
				(enabled no)
				(sheetname "")
			)
			(fill
				(thermal_gap 0.5)
				(thermal_bridge_width 0.5)
				(island_removal_mode 0)
			)
			(polygon
				(pts
					(xy 194.090036 -69.135244) (xy 194.598036 -69.135244) (xy 194.598036 -69.516244) (xy 194.090036 -69.516244)
				)
			)
		)
	)
	(footprint ""
		(layer "F.Cu")
		(at 107.8611 -140.208 90)
		(property "Reference" "C3A5"
			(at 1.848866 0.752348 90)
			(unlocked yes)
			(layer "F.SilkS")
			(effects
				(font
					(size 1.27 0.9652)
					(thickness 0.1524)
				)
			)
		)
		(property "Value" ""
			(at 0 0 90)
			(layer "F.Fab")
			(effects
				(font
					(size 1.27 1.27)
				)
			)
		)
		(duplicate_pad_numbers_are_jumpers no)
		(fp_rect
			(start -0.500126 1.598422)
			(end 0.500126 -0.201422)
			(stroke
				(width 0)
				(type default)
			)
			(fill no)
			(layer "F.CrtYd")
		)
		(fp_line
			(start 0.500126 -0.201422)
			(end 0.500126 1.598422)
			(stroke
				(width 0.1)
				(type default)
			)
			(layer "F.Fab")
		)
		(fp_line
			(start -0.500126 -0.201422)
			(end 0.500126 -0.201422)
			(stroke
				(width 0.1)
				(type default)
			)
			(layer "F.Fab")
		)
		(fp_line
			(start 0.500126 1.598422)
			(end -0.500126 1.598422)
			(stroke
				(width 0.1)
				(type default)
			)
			(layer "F.Fab")
		)
		(fp_line
			(start -0.500126 1.598422)
			(end -0.500126 -0.201422)
			(stroke
				(width 0.1)
				(type default)
			)
			(layer "F.Fab")
		)
		(pad "1" smd rect
			(at 0 0)
			(size 0.889 0.9906)
			(layers "F.Cu" "F.Mask" "F.Paste")
			(net "PVDDQ_KLM")
		)
		(pad "2" smd rect
			(at 0 1.397)
			(size 0.889 0.9906)
			(layers "F.Cu" "F.Mask" "F.Paste")
			(net "GND")
		)
		(zone
			(layer "F.Cu")
			(hatch none 0.5)
			(connect_pads
				(clearance 0)
			)
			(min_thickness 0.25)
			(keepout
				(tracks allowed)
				(vias not_allowed)
				(pads allowed)
				(copperpour not_allowed)
				(footprints allowed)
			)
			(placement
				(enabled no)
				(sheetname "")
			)
			(fill
				(thermal_gap 0.5)
				(thermal_bridge_width 0.5)
				(island_removal_mode 0)
			)
			(polygon
				(pts
					(xy 108.8136 -139.7127) (xy 108.8136 -140.7033) (xy 108.3056 -140.7033) (xy 108.3056 -139.7127)
				)
			)
		)
		(zone
			(layer "F.Cu")
			(hatch none 0.5)
			(connect_pads
				(clearance 0)
			)
			(min_thickness 0.25)
			(keepout
				(tracks not_allowed)
				(vias allowed)
				(pads allowed)
				(copperpour not_allowed)
				(footprints allowed)
			)
			(placement
				(enabled no)
				(sheetname "")
			)
			(fill
				(thermal_gap 0.5)
				(thermal_bridge_width 0.5)
				(island_removal_mode 0)
			)
			(polygon
				(pts
					(xy 108.8136 -139.7127) (xy 108.8136 -140.7033) (xy 108.3056 -140.7033) (xy 108.3056 -139.7127)
				)
			)
		)
	)
	(footprint ""
		(layer "F.Cu")
		(at 364.617 -115.189 90)
		(property "Reference" "C7B25"
			(at 0 0 90)
			(layer "F.SilkS")
			(hide yes)
			(effects
				(font
					(size 1.27 1.27)
				)
			)
		)
		(property "Value" ""
			(at 0 0 90)
			(layer "F.Fab")
			(effects
				(font
					(size 1.27 1.27)
				)
			)
		)
		(duplicate_pad_numbers_are_jumpers no)
		(fp_poly
			(pts
				(xy 0.3048 -0.1016) (xy 0.3048 0.9906) (xy -0.3048 0.9906) (xy -0.3048 -0.1016)
			)
			(stroke
				(width 0)
				(type default)
			)
			(fill no)
			(layer "F.CrtYd")
		)
		(fp_line
			(start 0.3048 -0.1016)
			(end -0.3048 -0.1016)
			(stroke
				(width 0.1)
				(type default)
			)
			(layer "F.Fab")
		)
		(fp_line
			(start -0.3048 -0.1016)
			(end -0.3048 0.9906)
			(stroke
				(width 0.1)
				(type default)
			)
			(layer "F.Fab")
		)
		(fp_line
			(start 0.3048 0.9906)
			(end 0.3048 -0.1016)
			(stroke
				(width 0.1)
				(type default)
			)
			(layer "F.Fab")
		)
		(fp_line
			(start -0.3048 0.9906)
			(end 0.3048 0.9906)
			(stroke
				(width 0.1)
				(type default)
			)
			(layer "F.Fab")
		)
		(pad "1" smd rect
			(at 0 0 90)
			(size 0.508 0.508)
			(layers "F.Cu" "F.Mask" "F.Paste")
			(net "DMI_CPU0_PCH_TX_DP<3>")
		)
		(pad "2" smd rect
			(at 0 0.889 90)
			(size 0.508 0.508)
			(layers "F.Cu" "F.Mask" "F.Paste")
			(net "DMI_CPU0_PCH_TX_C_DP<3>")
		)
		(zone
			(layer "F.Cu")
			(hatch none 0.5)
			(connect_pads
				(clearance 0)
			)
			(min_thickness 0.25)
			(keepout
				(tracks allowed)
				(vias not_allowed)
				(pads allowed)
				(copperpour not_allowed)
				(footprints allowed)
			)
			(placement
				(enabled no)
				(sheetname "")
			)
			(fill
				(thermal_gap 0.5)
				(thermal_bridge_width 0.5)
				(island_removal_mode 0)
			)
			(polygon
				(pts
					(xy 364.871 -114.935) (xy 364.871 -115.443) (xy 365.252 -115.443) (xy 365.252 -114.935)
				)
			)
		)
		(zone
			(layer "F.Cu")
			(hatch none 0.5)
			(connect_pads
				(clearance 0)
			)
			(min_thickness 0.25)
			(keepout
				(tracks not_allowed)
				(vias allowed)
				(pads allowed)
				(copperpour not_allowed)
				(footprints allowed)
			)
			(placement
				(enabled no)
				(sheetname "")
			)
			(fill
				(thermal_gap 0.5)
				(thermal_bridge_width 0.5)
				(island_removal_mode 0)
			)
			(polygon
				(pts
					(xy 365.252 -114.935) (xy 365.252 -115.443) (xy 364.871 -115.443) (xy 364.871 -114.935)
				)
			)
		)
	)
	(footprint ""
		(layer "F.Cu")
		(at 181.890924 -148.3487 90)
		(property "Reference" "EU4A1"
			(at -0.2667 3.555746 90)
			(unlocked yes)
			(layer "F.SilkS")
			(effects
				(font
					(size 0.7874 0.5842)
					(thickness 0.1524)
				)
				(justify left)
			)
		)
		(property "Value" ""
			(at 0 0 90)
			(layer "F.Fab")
			(effects
				(font
					(size 1.27 1.27)
				)
			)
		)
		(duplicate_pad_numbers_are_jumpers no)
		(fp_circle
			(center -0.835152 -0.417322)
			(end -0.835152 -0.290576)
			(stroke
				(width 0.254)
				(type default)
			)
			(fill no)
			(layer "F.SilkS")
		)
		(fp_poly
			(pts
				(xy -0.064516 -1.0922) (xy -0.064516 -0.3302) (xy 0.697484 -1.0922)
			)
			(stroke
				(width 0)
				(type default)
			)
			(fill yes)
			(layer "F.SilkS")
		)
		(fp_rect
			(start 0.597408 2.295398)
			(end 2.273808 -0.295402)
			(stroke
				(width 0)
				(type default)
			)
			(fill yes)
			(layer "F.Paste")
		)
		(fp_rect
			(start -0.064516 2.500122)
			(end 2.935478 -0.500126)
			(stroke
				(width 0)
				(type default)
			)
			(fill no)
			(layer "F.CrtYd")
		)
		(fp_line
			(start 2.935478 -0.500126)
			(end 2.935478 2.500122)
			(stroke
				(width 0.1)
				(type default)
			)
			(layer "F.Fab")
		)
		(fp_line
			(start -0.064516 -0.500126)
			(end 2.935478 -0.500126)
			(stroke
				(width 0.1)
				(type default)
			)
			(layer "F.Fab")
		)
		(fp_line
			(start 2.935478 2.500122)
			(end -0.064516 2.500122)
			(stroke
				(width 0.1)
				(type default)
			)
			(layer "F.Fab")
		)
		(fp_line
			(start -0.064516 2.500122)
			(end -0.064516 -0.500126)
			(stroke
				(width 0.1)
				(type default)
			)
			(layer "F.Fab")
		)
		(fp_circle
			(center -0.835152 -0.417322)
			(end -0.835152 -0.290576)
			(stroke
				(width 0.254)
				(type default)
			)
			(fill no)
			(layer "F.Fab")
		)
		(pad "1" smd rect
			(at 0 0 90)
			(size 0.6858 0.3048)
			(layers "F.Cu" "F.Mask" "F.Paste")
			(net "VR_PVTT_DEF_VREF")
		)
		(pad "2" smd rect
			(at 0 0.500126 90)
			(size 0.6858 0.3048)
			(layers "F.Cu" "F.Mask" "F.Paste")
			(net "VR_PVTT_DEF_BIAS")
		)
		(pad "3" smd rect
			(at 0 0.999998 90)
			(size 0.6858 0.3048)
			(layers "F.Cu" "F.Mask" "F.Paste")
			(net "GND")
		)
		(pad "4" smd rect
			(at 0 1.500124 90)
			(size 0.6858 0.3048)
			(layers "F.Cu" "F.Mask" "F.Paste")
			(net "VSENSE_PVDDQ_DEF_VTT")
		)
		(pad "5" smd rect
			(at 0 1.999996 90)
			(size 0.6858 0.3048)
			(layers "F.Cu" "F.Mask" "F.Paste")
			(net "PWRGD_PVTT_DEF_CPU0_R")
		)
		(pad "6" smd rect
			(at 2.871216 1.999996 90)
			(size 0.6858 0.3048)
			(layers "F.Cu" "F.Mask" "F.Paste")
			(net "VR_PVTT_DEF_SNS")
		)
		(pad "7" smd rect
			(at 2.871216 1.500124 90)
			(size 0.6858 0.3048)
			(layers "F.Cu" "F.Mask" "F.Paste")
			(net "FM_PVTT_DEF_EN_R")
		)
		(pad "8" smd rect
			(at 2.871216 0.999998 90)
			(size 0.6858 0.3048)
			(layers "F.Cu" "F.Mask" "F.Paste")
			(net "GND")
		)
		(pad "9" smd rect
			(at 2.871216 0.500126 90)
			(size 0.6858 0.3048)
			(layers "F.Cu" "F.Mask" "F.Paste")
			(net "PVTT_DEF")
		)
		(pad "10" smd rect
			(at 2.871216 0 90)
			(size 0.6858 0.3048)
			(layers "F.Cu" "F.Mask" "F.Paste")
			(net "PVDDQ_DEF")
		)
		(pad "11" smd rect
			(at 1.435608 0.999998 90)
			(size 1.6764 2.5908)
			(layers "F.Cu" "F.Mask" "F.Paste")
			(net "GND")
		)
	)
	(footprint ""
		(layer "F.Cu")
		(at 277.182834 -77.382116)
		(property "Reference" "C6D5"
			(at 0 0 0)
			(layer "F.SilkS")
			(hide yes)
			(effects
				(font
					(size 1.27 1.27)
				)
			)
		)
		(property "Value" ""
			(at 0 0 0)
			(layer "F.Fab")
			(effects
				(font
					(size 1.27 1.27)
				)
			)
		)
		(duplicate_pad_numbers_are_jumpers no)
		(fp_poly
			(pts
				(xy -0.4953 -0.2032) (xy 0.4953 -0.2032) (xy 0.4953 1.6002) (xy -0.4953 1.6002)
			)
			(stroke
				(width 0)
				(type default)
			)
			(fill no)
			(layer "F.CrtYd")
		)
		(fp_line
			(start -0.4953 -0.2032)
			(end 0.4953 -0.2032)
			(stroke
				(width 0.1)
				(type default)
			)
			(layer "F.Fab")
		)
		(fp_line
			(start -0.4953 1.6002)
			(end -0.4953 -0.2032)
			(stroke
				(width 0.1)
				(type default)
			)
			(layer "F.Fab")
		)
		(fp_line
			(start 0.4953 -0.2032)
			(end 0.4953 1.6002)
			(stroke
				(width 0.1)
				(type default)
			)
			(layer "F.Fab")
		)
		(fp_line
			(start 0.4953 1.6002)
			(end -0.4953 1.6002)
			(stroke
				(width 0.1)
				(type default)
			)
			(layer "F.Fab")
		)
		(pad "1" smd rect
			(at 0 0)
			(size 0.762 0.889)
			(layers "F.Cu" "F.Mask" "F.Paste")
			(net "PVCCMCP_CPU0")
		)
		(pad "2" smd rect
			(at 0 1.397)
			(size 0.762 0.889)
			(layers "F.Cu" "F.Mask" "F.Paste")
			(net "GND")
		)
		(zone
			(layer "F.Cu")
			(hatch none 0.5)
			(connect_pads
				(clearance 0)
			)
			(min_thickness 0.25)
			(keepout
				(tracks not_allowed)
				(vias allowed)
				(pads allowed)
				(copperpour not_allowed)
				(footprints allowed)
			)
			(placement
				(enabled no)
				(sheetname "")
			)
			(fill
				(thermal_gap 0.5)
				(thermal_bridge_width 0.5)
				(island_removal_mode 0)
			)
			(polygon
				(pts
					(xy 276.801834 -76.937616) (xy 277.563834 -76.937616) (xy 277.563834 -76.429616) (xy 276.801834 -76.429616)
				)
			)
		)
	)
	(footprint ""
		(layer "F.Cu")
		(at 27.785568 -13.3985)
		(property "Reference" "R1G1"
			(at 0 0 0)
			(layer "F.SilkS")
			(hide yes)
			(effects
				(font
					(size 1.27 1.27)
				)
			)
		)
		(property "Value" ""
			(at 0 0 0)
			(layer "F.Fab")
			(effects
				(font
					(size 1.27 1.27)
				)
			)
		)
		(duplicate_pad_numbers_are_jumpers no)
		(fp_poly
			(pts
				(xy -0.2794 -0.1016) (xy 0.2794 -0.1016) (xy 0.2794 0.9906) (xy -0.2794 0.9906)
			)
			(stroke
				(width 0)
				(type default)
			)
			(fill no)
			(layer "F.CrtYd")
		)
		(fp_line
			(start -0.2794 -0.1016)
			(end -0.2794 0.9906)
			(stroke
				(width 0.1)
				(type default)
			)
			(layer "F.Fab")
		)
		(fp_line
			(start -0.2794 0.9906)
			(end 0.2794 0.9906)
			(stroke
				(width 0.1)
				(type default)
			)
			(layer "F.Fab")
		)
		(fp_line
			(start 0.2794 -0.1016)
			(end -0.2794 -0.1016)
			(stroke
				(width 0.1)
				(type default)
			)
			(layer "F.Fab")
		)
		(fp_line
			(start 0.2794 0.9906)
			(end 0.2794 -0.1016)
			(stroke
				(width 0.1)
				(type default)
			)
			(layer "F.Fab")
		)
		(pad "1" smd rect
			(at 0 0)
			(size 0.508 0.508)
			(layers "F.Cu" "F.Mask" "F.Paste")
			(net "M_H_CPU_VREF")
		)
		(pad "2" smd rect
			(at 0 0.889)
			(size 0.508 0.508)
			(layers "F.Cu" "F.Mask" "F.Paste")
			(net "M_H_VREF")
		)
		(zone
			(layer "F.Cu")
			(hatch none 0.5)
			(connect_pads
				(clearance 0)
			)
			(min_thickness 0.25)
			(keepout
				(tracks allowed)
				(vias not_allowed)
				(pads allowed)
				(copperpour not_allowed)
				(footprints allowed)
			)
			(placement
				(enabled no)
				(sheetname "")
			)
			(fill
				(thermal_gap 0.5)
				(thermal_bridge_width 0.5)
				(island_removal_mode 0)
			)
			(polygon
				(pts
					(xy 27.531568 -13.1445) (xy 28.039568 -13.1445) (xy 28.039568 -12.7635) (xy 27.531568 -12.7635)
				)
			)
		)
		(zone
			(layer "F.Cu")
			(hatch none 0.5)
			(connect_pads
				(clearance 0)
			)
			(min_thickness 0.25)
			(keepout
				(tracks not_allowed)
				(vias allowed)
				(pads allowed)
				(copperpour not_allowed)
				(footprints allowed)
			)
			(placement
				(enabled no)
				(sheetname "")
			)
			(fill
				(thermal_gap 0.5)
				(thermal_bridge_width 0.5)
				(island_removal_mode 0)
			)
			(polygon
				(pts
					(xy 27.531568 -12.7635) (xy 28.039568 -12.7635) (xy 28.039568 -13.1445) (xy 27.531568 -13.1445)
				)
			)
		)
	)
	(footprint ""
		(layer "F.Cu")
		(at 269.645638 -68.365116 180)
		(property "Reference" "C5D59"
			(at 0 0 180)
			(layer "F.SilkS")
			(hide yes)
			(effects
				(font
					(size 1.27 1.27)
				)
			)
		)
		(property "Value" ""
			(at 0 0 180)
			(layer "F.Fab")
			(effects
				(font
					(size 1.27 1.27)
				)
			)
		)
		(duplicate_pad_numbers_are_jumpers no)
		(fp_poly
			(pts
				(xy -0.4953 -0.2032) (xy 0.4953 -0.2032) (xy 0.4953 1.6002) (xy -0.4953 1.6002)
			)
			(stroke
				(width 0)
				(type default)
			)
			(fill no)
			(layer "F.CrtYd")
		)
		(fp_line
			(start 0.4953 1.6002)
			(end -0.4953 1.6002)
			(stroke
				(width 0.1)
				(type default)
			)
			(layer "F.Fab")
		)
		(fp_line
			(start 0.4953 -0.2032)
			(end 0.4953 1.6002)
			(stroke
				(width 0.1)
				(type default)
			)
			(layer "F.Fab")
		)
		(fp_line
			(start -0.4953 1.6002)
			(end -0.4953 -0.2032)
			(stroke
				(width 0.1)
				(type default)
			)
			(layer "F.Fab")
		)
		(fp_line
			(start -0.4953 -0.2032)
			(end 0.4953 -0.2032)
			(stroke
				(width 0.1)
				(type default)
			)
			(layer "F.Fab")
		)
		(pad "1" smd rect
			(at 0 0 180)
			(size 0.762 0.889)
			(layers "F.Cu" "F.Mask" "F.Paste")
			(net "PVDDQ_ABC")
		)
		(pad "2" smd rect
			(at 0 1.397 180)
			(size 0.762 0.889)
			(layers "F.Cu" "F.Mask" "F.Paste")
			(net "GND")
		)
		(zone
			(layer "F.Cu")
			(hatch none 0.5)
			(connect_pads
				(clearance 0)
			)
			(min_thickness 0.25)
			(keepout
				(tracks not_allowed)
				(vias allowed)
				(pads allowed)
				(copperpour not_allowed)
				(footprints allowed)
			)
			(placement
				(enabled no)
				(sheetname "")
			)
			(fill
				(thermal_gap 0.5)
				(thermal_bridge_width 0.5)
				(island_removal_mode 0)
			)
			(polygon
				(pts
					(xy 270.026638 -68.809616) (xy 269.264638 -68.809616) (xy 269.264638 -69.317616) (xy 270.026638 -69.317616)
				)
			)
		)
	)
	(footprint ""
		(layer "F.Cu")
		(at 179.6288 -65.7606 -90)
		(property "Reference" "R4D63"
			(at 0 0 270)
			(layer "F.SilkS")
			(hide yes)
			(effects
				(font
					(size 1.27 1.27)
				)
			)
		)
		(property "Value" ""
			(at 0 0 270)
			(layer "F.Fab")
			(effects
				(font
					(size 1.27 1.27)
				)
			)
		)
		(duplicate_pad_numbers_are_jumpers no)
		(fp_poly
			(pts
				(xy -0.2794 -0.1016) (xy 0.2794 -0.1016) (xy 0.2794 0.9906) (xy -0.2794 0.9906)
			)
			(stroke
				(width 0)
				(type default)
			)
			(fill no)
			(layer "F.CrtYd")
		)
		(fp_line
			(start -0.2794 0.9906)
			(end 0.2794 0.9906)
			(stroke
				(width 0.1)
				(type default)
			)
			(layer "F.Fab")
		)
		(fp_line
			(start 0.2794 0.9906)
			(end 0.2794 -0.1016)
			(stroke
				(width 0.1)
				(type default)
			)
			(layer "F.Fab")
		)
		(fp_line
			(start -0.2794 -0.1016)
			(end -0.2794 0.9906)
			(stroke
				(width 0.1)
				(type default)
			)
			(layer "F.Fab")
		)
		(fp_line
			(start 0.2794 -0.1016)
			(end -0.2794 -0.1016)
			(stroke
				(width 0.1)
				(type default)
			)
			(layer "F.Fab")
		)
		(pad "1" smd rect
			(at 0 0 270)
			(size 0.508 0.508)
			(layers "F.Cu" "F.Mask" "F.Paste")
			(net "VR_VRRDY_PVCCIN_CPU0")
		)
		(pad "2" smd rect
			(at 0 0.889 270)
			(size 0.508 0.508)
			(layers "F.Cu" "F.Mask" "F.Paste")
			(net "PWRGD_PVCCIN_CPU0")
		)
		(zone
			(layer "F.Cu")
			(hatch none 0.5)
			(connect_pads
				(clearance 0)
			)
			(min_thickness 0.25)
			(keepout
				(tracks not_allowed)
				(vias allowed)
				(pads allowed)
				(copperpour not_allowed)
				(footprints allowed)
			)
			(placement
				(enabled no)
				(sheetname "")
			)
			(fill
				(thermal_gap 0.5)
				(thermal_bridge_width 0.5)
				(island_removal_mode 0)
			)
			(polygon
				(pts
					(xy 178.9938 -66.0146) (xy 178.9938 -65.5066) (xy 179.3748 -65.5066) (xy 179.3748 -66.0146)
				)
			)
		)
		(zone
			(layer "F.Cu")
			(hatch none 0.5)
			(connect_pads
				(clearance 0)
			)
			(min_thickness 0.25)
			(keepout
				(tracks allowed)
				(vias not_allowed)
				(pads allowed)
				(copperpour not_allowed)
				(footprints allowed)
			)
			(placement
				(enabled no)
				(sheetname "")
			)
			(fill
				(thermal_gap 0.5)
				(thermal_bridge_width 0.5)
				(island_removal_mode 0)
			)
			(polygon
				(pts
					(xy 179.3748 -66.0146) (xy 179.3748 -65.5066) (xy 178.9938 -65.5066) (xy 178.9938 -66.0146)
				)
			)
		)
	)
	(footprint ""
		(layer "F.Cu")
		(at 29.699458 -15.423642 90)
		(property "Reference" "J1G1"
			(at 9.314688 35.070542 0)
			(unlocked yes)
			(layer "F.SilkS")
			(effects
				(font
					(size 0.7874 0.5842)
					(thickness 0.1524)
				)
				(justify left)
			)
		)
		(property "Value" ""
			(at 0 0 90)
			(layer "F.Fab")
			(effects
				(font
					(size 1.27 1.27)
				)
			)
		)
		(duplicate_pad_numbers_are_jumpers no)
		(fp_line
			(start 5.5499 -7.675118)
			(end 5.5499 -1.480058)
			(stroke
				(width 0.1524)
				(type default)
			)
			(layer "F.SilkS")
		)
		(fp_line
			(start -0.94996 -7.675118)
			(end 5.5499 -7.675118)
			(stroke
				(width 0.1524)
				(type default)
			)
			(layer "F.SilkS")
		)
		(fp_line
			(start -0.94996 -1.480058)
			(end -0.94996 -7.675118)
			(stroke
				(width 0.1524)
				(type default)
			)
			(layer "F.SilkS")
		)
		(fp_line
			(start 5.5499 128.130046)
			(end 5.5499 134.325106)
			(stroke
				(width 0.1524)
				(type default)
			)
			(layer "F.SilkS")
		)
		(fp_line
			(start 5.5499 134.325106)
			(end -0.94996 134.325106)
			(stroke
				(width 0.1524)
				(type default)
			)
			(layer "F.SilkS")
		)
		(fp_line
			(start -0.94996 134.325106)
			(end -0.94996 128.130046)
			(stroke
				(width 0.1524)
				(type default)
			)
			(layer "F.SilkS")
		)
		(fp_poly
			(pts
				(xy -2.999232 -4.170426) (xy -2.999232 -3.154426) (xy -1.729232 -3.662426)
			)
			(stroke
				(width 0)
				(type default)
			)
			(fill yes)
			(layer "F.SilkS")
		)
		(fp_poly
			(pts
				(xy -0.94996 -7.675118) (xy -0.94996 134.325106) (xy 5.5499 134.325106) (xy 5.5499 -7.675118)
			)
			(stroke
				(width 0)
				(type default)
			)
			(fill no)
			(layer "F.CrtYd")
		)
		(fp_line
			(start 5.5499 -7.675118)
			(end 5.5499 134.325106)
			(stroke
				(width 0.1)
				(type default)
			)
			(layer "F.Fab")
		)
		(fp_line
			(start -0.94996 -7.675118)
			(end 5.5499 -7.675118)
			(stroke
				(width 0.1)
				(type default)
			)
			(layer "F.Fab")
		)
		(fp_line
			(start 5.5499 134.325106)
			(end -0.94996 134.325106)
			(stroke
				(width 0.1)
				(type default)
			)
			(layer "F.Fab")
		)
		(fp_line
			(start -0.94996 134.325106)
			(end -0.94996 -7.675118)
			(stroke
				(width 0.1)
				(type default)
			)
			(layer "F.Fab")
		)
		(fp_poly
			(pts
				(xy -2.984246 -0.461264) (xy -2.984246 0.554736) (xy -1.714246 0.046736)
			)
			(stroke
				(width 0)
				(type default)
			)
			(fill yes)
			(layer "F.Fab")
		)
		(fp_text user "145"
			(at -1.632712 0.196342 0)
			(unlocked yes)
			(layer "F.SilkS")
			(effects
				(font
					(size 0.7874 0.5842)
					(thickness 0.1524)
				)
				(justify left)
			)
		)
		(fp_text user "77"
			(at -1.028192 64.928242 0)
			(unlocked yes)
			(layer "F.SilkS")
			(effects
				(font
					(size 0.7874 0.5842)
					(thickness 0.1524)
				)
				(justify left)
			)
		)
		(fp_text user "221"
			(at 6.447028 64.933322 0)
			(unlocked yes)
			(layer "F.SilkS")
			(effects
				(font
					(size 0.7874 0.5842)
					(thickness 0.1524)
				)
				(justify left)
			)
		)
		(fp_text user "78"
			(at -1.607312 69.883782 0)
			(unlocked yes)
			(layer "F.SilkS")
			(effects
				(font
					(size 0.7874 0.5842)
					(thickness 0.1524)
				)
				(justify left)
			)
		)
		(fp_text user "222"
			(at 6.713728 69.921882 0)
			(unlocked yes)
			(layer "F.SilkS")
			(effects
				(font
					(size 0.7874 0.5842)
					(thickness 0.1524)
				)
				(justify left)
			)
		)
		(fp_text user "288"
			(at 6.165088 127.704342 0)
			(unlocked yes)
			(layer "F.SilkS")
			(effects
				(font
					(size 0.7874 0.5842)
					(thickness 0.1524)
				)
				(justify left)
			)
		)
		(fp_text user "144"
			(at -1.912112 128.059942 0)
			(unlocked yes)
			(layer "F.SilkS")
			(effects
				(font
					(size 0.7874 0.5842)
					(thickness 0.1524)
				)
				(justify left)
			)
		)
		(fp_text user "145"
			(at 2.800858 -1.724152 90)
			(unlocked yes)
			(layer "F.Fab")
			(effects
				(font
					(size 0.7874 0.5842)
					(thickness 0.1524)
				)
				(justify left)
			)
		)
		(fp_text user "221"
			(at 3.296158 65.653412 90)
			(unlocked yes)
			(layer "F.Fab")
			(effects
				(font
					(size 0.7874 0.5842)
					(thickness 0.1524)
				)
				(justify left)
			)
		)
		(fp_text user "77"
			(at -0.539242 65.729612 90)
			(unlocked yes)
			(layer "F.Fab")
			(effects
				(font
					(size 0.7874 0.5842)
					(thickness 0.1524)
				)
				(justify left)
			)
		)
		(fp_text user "78"
			(at -0.793242 68.930012 90)
			(unlocked yes)
			(layer "F.Fab")
			(effects
				(font
					(size 0.7874 0.5842)
					(thickness 0.1524)
				)
				(justify left)
			)
		)
		(fp_text user "222"
			(at 3.092958 69.361812 90)
			(unlocked yes)
			(layer "F.Fab")
			(effects
				(font
					(size 0.7874 0.5842)
					(thickness 0.1524)
				)
				(justify left)
			)
		)
		(fp_text user "288"
			(at 3.042158 127.629412 90)
			(unlocked yes)
			(layer "F.Fab")
			(effects
				(font
					(size 0.7874 0.5842)
					(thickness 0.1524)
				)
				(justify left)
			)
		)
		(fp_text user "144"
			(at -0.742442 127.629412 90)
			(unlocked yes)
			(layer "F.Fab")
			(effects
				(font
					(size 0.7874 0.5842)
					(thickness 0.1524)
				)
				(justify left)
			)
		)
		(pad "" thru_hole circle
			(at 2.29997 -5.649976 90)
			(size 2.8194 2.8194)
			(drill 2.4384)
			(layers "*.Cu" "*.Mask")
			(remove_unused_layers no)
			(clearance 0.127)
			(thermal_gap 0.127)
		)
		(pad "" thru_hole oval
			(at 2.29997 68.90004 90)
			(size 2.8194 1.5748)
			(drill oval 2.4384 1.1938)
			(layers "*.Cu" "*.Mask")
			(remove_unused_layers no)
			(clearance 0.127)
			(thermal_gap 0.127)
		)
		(pad "" thru_hole circle
			(at 2.29997 132.299964 90)
			(size 2.8194 2.8194)
			(drill 2.4384)
			(layers "*.Cu" "*.Mask")
			(remove_unused_layers no)
			(clearance 0.127)
			(thermal_gap 0.127)
		)
		(pad "1" smd rect
			(at 0 0 90)
			(size 1.8034 0.508)
			(layers "F.Cu" "F.Mask" "F.Paste")
			(net "P12V_NVDIMM_GHJ")
		)
		(pad "2" smd rect
			(at 0 0.849884 90)
			(size 1.8034 0.508)
			(layers "F.Cu" "F.Mask" "F.Paste")
			(net "GND")
		)
		(pad "3" smd rect
			(at 0 1.700022 90)
			(size 1.8034 0.508)
			(layers "F.Cu" "F.Mask" "F.Paste")
			(net "M_G_DQ<5>")
		)
		(pad "4" smd rect
			(at 0 2.549906 90)
			(size 1.8034 0.508)
			(layers "F.Cu" "F.Mask" "F.Paste")
			(net "GND")
		)
		(pad "5" smd rect
			(at 0 3.400044 90)
			(size 1.8034 0.508)
			(layers "F.Cu" "F.Mask" "F.Paste")
			(net "M_G_DQ<1>")
		)
		(pad "6" smd rect
			(at 0 4.249928 90)
			(size 1.8034 0.508)
			(layers "F.Cu" "F.Mask" "F.Paste")
			(net "GND")
		)
		(pad "7" smd rect
			(at 0 5.100066 90)
			(size 1.8034 0.508)
			(layers "F.Cu" "F.Mask" "F.Paste")
			(net "M_G_DQS_DP<9>")
		)
		(pad "8" smd rect
			(at 0 5.94995 90)
			(size 1.8034 0.508)
			(layers "F.Cu" "F.Mask" "F.Paste")
			(net "M_G_DQS_DN<9>")
		)
		(pad "9" smd rect
			(at 0 6.800088 90)
			(size 1.8034 0.508)
			(layers "F.Cu" "F.Mask" "F.Paste")
			(net "GND")
		)
		(pad "10" smd rect
			(at 0 7.649972 90)
			(size 1.8034 0.508)
			(layers "F.Cu" "F.Mask" "F.Paste")
			(net "M_G_DQ<7>")
		)
		(pad "11" smd rect
			(at 0 8.50011 90)
			(size 1.8034 0.508)
			(layers "F.Cu" "F.Mask" "F.Paste")
			(net "GND")
		)
		(pad "12" smd rect
			(at 0 9.349994 90)
			(size 1.8034 0.508)
			(layers "F.Cu" "F.Mask" "F.Paste")
			(net "M_G_DQ<3>")
		)
		(pad "13" smd rect
			(at 0 10.199878 90)
			(size 1.8034 0.508)
			(layers "F.Cu" "F.Mask" "F.Paste")
			(net "GND")
		)
		(pad "14" smd rect
			(at 0 11.050016 90)
			(size 1.8034 0.508)
			(layers "F.Cu" "F.Mask" "F.Paste")
			(net "M_G_DQ<13>")
		)
		(pad "15" smd rect
			(at 0 11.8999 90)
			(size 1.8034 0.508)
			(layers "F.Cu" "F.Mask" "F.Paste")
			(net "GND")
		)
		(pad "16" smd rect
			(at 0 12.750038 90)
			(size 1.8034 0.508)
			(layers "F.Cu" "F.Mask" "F.Paste")
			(net "M_G_DQ<9>")
		)
		(pad "17" smd rect
			(at 0 13.599922 90)
			(size 1.8034 0.508)
			(layers "F.Cu" "F.Mask" "F.Paste")
			(net "GND")
		)
		(pad "18" smd rect
			(at 0 14.45006 90)
			(size 1.8034 0.508)
			(layers "F.Cu" "F.Mask" "F.Paste")
			(net "M_G_DQS_DP<10>")
		)
		(pad "19" smd rect
			(at 0 15.299944 90)
			(size 1.8034 0.508)
			(layers "F.Cu" "F.Mask" "F.Paste")
			(net "M_G_DQS_DN<10>")
		)
		(pad "20" smd rect
			(at 0 16.150082 90)
			(size 1.8034 0.508)
			(layers "F.Cu" "F.Mask" "F.Paste")
			(net "GND")
		)
		(pad "21" smd rect
			(at 0 16.999966 90)
			(size 1.8034 0.508)
			(layers "F.Cu" "F.Mask" "F.Paste")
			(net "M_G_DQ<15>")
		)
		(pad "22" smd rect
			(at 0 17.850104 90)
			(size 1.8034 0.508)
			(layers "F.Cu" "F.Mask" "F.Paste")
			(net "GND")
		)
		(pad "23" smd rect
			(at 0 18.699988 90)
			(size 1.8034 0.508)
			(layers "F.Cu" "F.Mask" "F.Paste")
			(net "M_G_DQ<11>")
		)
		(pad "24" smd rect
			(at 0 19.550126 90)
			(size 1.8034 0.508)
			(layers "F.Cu" "F.Mask" "F.Paste")
			(net "GND")
		)
		(pad "25" smd rect
			(at 0 20.40001 90)
			(size 1.8034 0.508)
			(layers "F.Cu" "F.Mask" "F.Paste")
			(net "M_G_DQ<21>")
		)
		(pad "26" smd rect
			(at 0 21.249894 90)
			(size 1.8034 0.508)
			(layers "F.Cu" "F.Mask" "F.Paste")
			(net "GND")
		)
		(pad "27" smd rect
			(at 0 22.100032 90)
			(size 1.8034 0.508)
			(layers "F.Cu" "F.Mask" "F.Paste")
			(net "M_G_DQ<17>")
		)
		(pad "28" smd rect
			(at 0 22.949916 90)
			(size 1.8034 0.508)
			(layers "F.Cu" "F.Mask" "F.Paste")
			(net "GND")
		)
		(pad "29" smd rect
			(at 0 23.800054 90)
			(size 1.8034 0.508)
			(layers "F.Cu" "F.Mask" "F.Paste")
			(net "M_G_DQS_DP<11>")
		)
		(pad "30" smd rect
			(at 0 24.649938 90)
			(size 1.8034 0.508)
			(layers "F.Cu" "F.Mask" "F.Paste")
			(net "M_G_DQS_DN<11>")
		)
		(pad "31" smd rect
			(at 0 25.500076 90)
			(size 1.8034 0.508)
			(layers "F.Cu" "F.Mask" "F.Paste")
			(net "GND")
		)
		(pad "32" smd rect
			(at 0 26.34996 90)
			(size 1.8034 0.508)
			(layers "F.Cu" "F.Mask" "F.Paste")
			(net "M_G_DQ<23>")
		)
		(pad "33" smd rect
			(at 0 27.200098 90)
			(size 1.8034 0.508)
			(layers "F.Cu" "F.Mask" "F.Paste")
			(net "GND")
		)
		(pad "34" smd rect
			(at 0 28.049982 90)
			(size 1.8034 0.508)
			(layers "F.Cu" "F.Mask" "F.Paste")
			(net "M_G_DQ<19>")
		)
		(pad "35" smd rect
			(at 0 28.90012 90)
			(size 1.8034 0.508)
			(layers "F.Cu" "F.Mask" "F.Paste")
			(net "GND")
		)
		(pad "36" smd rect
			(at 0 29.750004 90)
			(size 1.8034 0.508)
			(layers "F.Cu" "F.Mask" "F.Paste")
			(net "M_G_DQ<29>")
		)
		(pad "37" smd rect
			(at 0 30.599888 90)
			(size 1.8034 0.508)
			(layers "F.Cu" "F.Mask" "F.Paste")
			(net "GND")
		)
		(pad "38" smd rect
			(at 0 31.450026 90)
			(size 1.8034 0.508)
			(layers "F.Cu" "F.Mask" "F.Paste")
			(net "M_G_DQ<25>")
		)
		(pad "39" smd rect
			(at 0 32.29991 90)
			(size 1.8034 0.508)
			(layers "F.Cu" "F.Mask" "F.Paste")
			(net "GND")
		)
		(pad "40" smd rect
			(at 0 33.150048 90)
			(size 1.8034 0.508)
			(layers "F.Cu" "F.Mask" "F.Paste")
			(net "M_G_DQS_DP<12>")
		)
		(pad "41" smd rect
			(at 0 33.999932 90)
			(size 1.8034 0.508)
			(layers "F.Cu" "F.Mask" "F.Paste")
			(net "M_G_DQS_DN<12>")
		)
		(pad "42" smd rect
			(at 0 34.85007 90)
			(size 1.8034 0.508)
			(layers "F.Cu" "F.Mask" "F.Paste")
			(net "GND")
		)
		(pad "43" smd rect
			(at 0 35.699954 90)
			(size 1.8034 0.508)
			(layers "F.Cu" "F.Mask" "F.Paste")
			(net "M_G_DQ<31>")
		)
		(pad "44" smd rect
			(at 0 36.550092 90)
			(size 1.8034 0.508)
			(layers "F.Cu" "F.Mask" "F.Paste")
			(net "GND")
		)
		(pad "45" smd rect
			(at 0 37.399976 90)
			(size 1.8034 0.508)
			(layers "F.Cu" "F.Mask" "F.Paste")
			(net "M_G_DQ<27>")
		)
		(pad "46" smd rect
			(at 0 38.250114 90)
			(size 1.8034 0.508)
			(layers "F.Cu" "F.Mask" "F.Paste")
			(net "GND")
		)
		(pad "47" smd rect
			(at 0 39.099998 90)
			(size 1.8034 0.508)
			(layers "F.Cu" "F.Mask" "F.Paste")
			(net "M_G_ECC<5>")
		)
		(pad "48" smd rect
			(at 0 39.949882 90)
			(size 1.8034 0.508)
			(layers "F.Cu" "F.Mask" "F.Paste")
			(net "GND")
		)
		(pad "49" smd rect
			(at 0 40.80002 90)
			(size 1.8034 0.508)
			(layers "F.Cu" "F.Mask" "F.Paste")
			(net "M_G_ECC<1>")
		)
		(pad "50" smd rect
			(at 0 41.649904 90)
			(size 1.8034 0.508)
			(layers "F.Cu" "F.Mask" "F.Paste")
			(net "GND")
		)
		(pad "51" smd rect
			(at 0 42.500042 90)
			(size 1.8034 0.508)
			(layers "F.Cu" "F.Mask" "F.Paste")
			(net "M_G_DQS_DP<17>")
		)
		(pad "52" smd rect
			(at 0 43.349926 90)
			(size 1.8034 0.508)
			(layers "F.Cu" "F.Mask" "F.Paste")
			(net "M_G_DQS_DN<17>")
		)
		(pad "53" smd rect
			(at 0 44.200064 90)
			(size 1.8034 0.508)
			(layers "F.Cu" "F.Mask" "F.Paste")
			(net "GND")
		)
		(pad "54" smd rect
			(at 0 45.049948 90)
			(size 1.8034 0.508)
			(layers "F.Cu" "F.Mask" "F.Paste")
			(net "M_G_ECC<7>")
		)
		(pad "55" smd rect
			(at 0 45.900086 90)
			(size 1.8034 0.508)
			(layers "F.Cu" "F.Mask" "F.Paste")
			(net "GND")
		)
		(pad "56" smd rect
			(at 0 46.74997 90)
			(size 1.8034 0.508)
			(layers "F.Cu" "F.Mask" "F.Paste")
			(net "M_G_ECC<3>")
		)
		(pad "57" smd rect
			(at 0 47.600108 90)
			(size 1.8034 0.508)
			(layers "F.Cu" "F.Mask" "F.Paste")
			(net "GND")
		)
		(pad "58" smd rect
			(at 0 48.449992 90)
			(size 1.8034 0.508)
			(layers "F.Cu" "F.Mask" "F.Paste")
			(net "M_GHJ_RST_N")
		)
		(pad "59" smd rect
			(at 0 49.299876 90)
			(size 1.8034 0.508)
			(layers "F.Cu" "F.Mask" "F.Paste")
			(net "PVDDQ_GHJ")
		)
		(pad "60" smd rect
			(at 0 50.150014 90)
			(size 1.8034 0.508)
			(layers "F.Cu" "F.Mask" "F.Paste")
			(net "M_G_CKE<0>")
		)
		(pad "61" smd rect
			(at 0 50.999898 90)
			(size 1.8034 0.508)
			(layers "F.Cu" "F.Mask" "F.Paste")
			(net "PVDDQ_GHJ")
		)
		(pad "62" smd rect
			(at 0 51.850036 90)
			(size 1.8034 0.508)
			(layers "F.Cu" "F.Mask" "F.Paste")
			(net "M_G_ACT_N")
		)
		(pad "63" smd rect
			(at 0 52.69992 90)
			(size 1.8034 0.508)
			(layers "F.Cu" "F.Mask" "F.Paste")
			(net "M_G_BG<0>")
		)
		(pad "64" smd rect
			(at 0 53.550058 90)
			(size 1.8034 0.508)
			(layers "F.Cu" "F.Mask" "F.Paste")
			(net "PVDDQ_GHJ")
		)
		(pad "65" smd rect
			(at 0 54.399942 90)
			(size 1.8034 0.508)
			(layers "F.Cu" "F.Mask" "F.Paste")
			(net "M_G_MA<12>")
		)
		(pad "66" smd rect
			(at 0 55.25008 90)
			(size 1.8034 0.508)
			(layers "F.Cu" "F.Mask" "F.Paste")
			(net "M_G_MA<9>")
		)
		(pad "67" smd rect
			(at 0 56.099964 90)
			(size 1.8034 0.508)
			(layers "F.Cu" "F.Mask" "F.Paste")
			(net "PVDDQ_GHJ")
		)
		(pad "68" smd rect
			(at 0 56.950102 90)
			(size 1.8034 0.508)
			(layers "F.Cu" "F.Mask" "F.Paste")
			(net "M_G_MA<8>")
		)
		(pad "69" smd rect
			(at 0 57.799986 90)
			(size 1.8034 0.508)
			(layers "F.Cu" "F.Mask" "F.Paste")
			(net "M_G_MA<6>")
		)
		(pad "70" smd rect
			(at 0 58.650124 90)
			(size 1.8034 0.508)
			(layers "F.Cu" "F.Mask" "F.Paste")
			(net "PVDDQ_GHJ")
		)
		(pad "71" smd rect
			(at 0 59.500008 90)
			(size 1.8034 0.508)
			(layers "F.Cu" "F.Mask" "F.Paste")
			(net "M_G_MA<3>")
		)
		(pad "72" smd rect
			(at 0 60.349892 90)
			(size 1.8034 0.508)
			(layers "F.Cu" "F.Mask" "F.Paste")
			(net "M_G_MA<1>")
		)
		(pad "73" smd rect
			(at 0 61.20003 90)
			(size 1.8034 0.508)
			(layers "F.Cu" "F.Mask" "F.Paste")
			(net "PVDDQ_GHJ")
		)
		(pad "74" smd rect
			(at 0 62.049914 90)
			(size 1.8034 0.508)
			(layers "F.Cu" "F.Mask" "F.Paste")
			(net "M_G_CLK_DP<0>")
		)
		(pad "75" smd rect
			(at 0 62.900052 90)
			(size 1.8034 0.508)
			(layers "F.Cu" "F.Mask" "F.Paste")
			(net "M_G_CLK_DN<0>")
		)
		(pad "76" smd rect
			(at 0 63.749936 90)
			(size 1.8034 0.508)
			(layers "F.Cu" "F.Mask" "F.Paste")
			(net "PVDDQ_GHJ")
		)
		(pad "77" smd rect
			(at 0 64.600074 90)
			(size 1.8034 0.508)
			(layers "F.Cu" "F.Mask" "F.Paste")
			(net "PVTT_GHJ")
		)
		(pad "78" smd rect
			(at 0 70.550024 90)
			(size 1.8034 0.508)
			(layers "F.Cu" "F.Mask" "F.Paste")
			(net "FM_DIMM_EVENT_COD_N")
		)
		(pad "79" smd rect
			(at 0 71.399908 90)
			(size 1.8034 0.508)
			(layers "F.Cu" "F.Mask" "F.Paste")
			(net "M_G_MA<0>")
		)
		(pad "80" smd rect
			(at 0 72.250046 90)
			(size 1.8034 0.508)
			(layers "F.Cu" "F.Mask" "F.Paste")
			(net "PVDDQ_GHJ")
		)
		(pad "81" smd rect
			(at 0 73.09993 90)
			(size 1.8034 0.508)
			(layers "F.Cu" "F.Mask" "F.Paste")
			(net "M_G_BA<0>")
		)
		(pad "82" smd rect
			(at 0 73.950068 90)
			(size 1.8034 0.508)
			(layers "F.Cu" "F.Mask" "F.Paste")
			(net "M_G_MA<16>")
		)
		(pad "83" smd rect
			(at 0 74.799952 90)
			(size 1.8034 0.508)
			(layers "F.Cu" "F.Mask" "F.Paste")
			(net "PVDDQ_GHJ")
		)
		(pad "84" smd rect
			(at 0 75.65009 90)
			(size 1.8034 0.508)
			(layers "F.Cu" "F.Mask" "F.Paste")
			(net "M_G_CS_N<0>")
		)
		(pad "85" smd rect
			(at 0 76.499974 90)
			(size 1.8034 0.508)
			(layers "F.Cu" "F.Mask" "F.Paste")
			(net "PVDDQ_GHJ")
		)
		(pad "86" smd rect
			(at 0 77.350112 90)
			(size 1.8034 0.508)
			(layers "F.Cu" "F.Mask" "F.Paste")
			(net "M_G_MA<15>")
		)
		(pad "87" smd rect
			(at 0 78.199996 90)
			(size 1.8034 0.508)
			(layers "F.Cu" "F.Mask" "F.Paste")
			(net "M_G_ODT<0>")
		)
		(pad "88" smd rect
			(at 0 79.04988 90)
			(size 1.8034 0.508)
			(layers "F.Cu" "F.Mask" "F.Paste")
			(net "PVDDQ_GHJ")
		)
		(pad "89" smd rect
			(at 0 79.900018 90)
			(size 1.8034 0.508)
			(layers "F.Cu" "F.Mask" "F.Paste")
			(net "M_G_CS_N<1>")
		)
		(pad "90" smd rect
			(at 0 80.749902 90)
			(size 1.8034 0.508)
			(layers "F.Cu" "F.Mask" "F.Paste")
			(net "PVDDQ_GHJ")
		)
		(pad "91" smd rect
			(at 0 81.60004 90)
			(size 1.8034 0.508)
			(layers "F.Cu" "F.Mask" "F.Paste")
			(net "M_G_ODT<1>")
		)
		(pad "92" smd rect
			(at 0 82.449924 90)
			(size 1.8034 0.508)
			(layers "F.Cu" "F.Mask" "F.Paste")
			(net "PVDDQ_GHJ")
		)
		(pad "93" smd rect
			(at 0 83.300062 90)
			(size 1.8034 0.508)
			(layers "F.Cu" "F.Mask" "F.Paste")
			(net "M_G_CS_N<2>")
		)
		(pad "94" smd rect
			(at 0 84.149946 90)
			(size 1.8034 0.508)
			(layers "F.Cu" "F.Mask" "F.Paste")
			(net "GND")
		)
		(pad "95" smd rect
			(at 0 85.000084 90)
			(size 1.8034 0.508)
			(layers "F.Cu" "F.Mask" "F.Paste")
			(net "M_G_DQ<37>")
		)
		(pad "96" smd rect
			(at 0 85.849968 90)
			(size 1.8034 0.508)
			(layers "F.Cu" "F.Mask" "F.Paste")
			(net "GND")
		)
		(pad "97" smd rect
			(at 0 86.700106 90)
			(size 1.8034 0.508)
			(layers "F.Cu" "F.Mask" "F.Paste")
			(net "M_G_DQ<33>")
		)
		(pad "98" smd rect
			(at 0 87.54999 90)
			(size 1.8034 0.508)
			(layers "F.Cu" "F.Mask" "F.Paste")
			(net "GND")
		)
		(pad "99" smd rect
			(at 0 88.399874 90)
			(size 1.8034 0.508)
			(layers "F.Cu" "F.Mask" "F.Paste")
			(net "M_G_DQS_DP<13>")
		)
		(pad "100" smd rect
			(at 0 89.250012 90)
			(size 1.8034 0.508)
			(layers "F.Cu" "F.Mask" "F.Paste")
			(net "M_G_DQS_DN<13>")
		)
		(pad "101" smd rect
			(at 0 90.099896 90)
			(size 1.8034 0.508)
			(layers "F.Cu" "F.Mask" "F.Paste")
			(net "GND")
		)
		(pad "102" smd rect
			(at 0 90.950034 90)
			(size 1.8034 0.508)
			(layers "F.Cu" "F.Mask" "F.Paste")
			(net "M_G_DQ<39>")
		)
		(pad "103" smd rect
			(at 0 91.799918 90)
			(size 1.8034 0.508)
			(layers "F.Cu" "F.Mask" "F.Paste")
			(net "GND")
		)
		(pad "104" smd rect
			(at 0 92.650056 90)
			(size 1.8034 0.508)
			(layers "F.Cu" "F.Mask" "F.Paste")
			(net "M_G_DQ<35>")
		)
		(pad "105" smd rect
			(at 0 93.49994 90)
			(size 1.8034 0.508)
			(layers "F.Cu" "F.Mask" "F.Paste")
			(net "GND")
		)
		(pad "106" smd rect
			(at 0 94.350078 90)
			(size 1.8034 0.508)
			(layers "F.Cu" "F.Mask" "F.Paste")
			(net "M_G_DQ<45>")
		)
		(pad "107" smd rect
			(at 0 95.199962 90)
			(size 1.8034 0.508)
			(layers "F.Cu" "F.Mask" "F.Paste")
			(net "GND")
		)
		(pad "108" smd rect
			(at 0 96.0501 90)
			(size 1.8034 0.508)
			(layers "F.Cu" "F.Mask" "F.Paste")
			(net "M_G_DQ<41>")
		)
		(pad "109" smd rect
			(at 0 96.899984 90)
			(size 1.8034 0.508)
			(layers "F.Cu" "F.Mask" "F.Paste")
			(net "GND")
		)
		(pad "110" smd rect
			(at 0 97.750122 90)
			(size 1.8034 0.508)
			(layers "F.Cu" "F.Mask" "F.Paste")
			(net "M_G_DQS_DP<14>")
		)
		(pad "111" smd rect
			(at 0 98.600006 90)
			(size 1.8034 0.508)
			(layers "F.Cu" "F.Mask" "F.Paste")
			(net "M_G_DQS_DN<14>")
		)
		(pad "112" smd rect
			(at 0 99.44989 90)
			(size 1.8034 0.508)
			(layers "F.Cu" "F.Mask" "F.Paste")
			(net "GND")
		)
		(pad "113" smd rect
			(at 0 100.300028 90)
			(size 1.8034 0.508)
			(layers "F.Cu" "F.Mask" "F.Paste")
			(net "M_G_DQ<47>")
		)
		(pad "114" smd rect
			(at 0 101.149912 90)
			(size 1.8034 0.508)
			(layers "F.Cu" "F.Mask" "F.Paste")
			(net "GND")
		)
		(pad "115" smd rect
			(at 0 102.00005 90)
			(size 1.8034 0.508)
			(layers "F.Cu" "F.Mask" "F.Paste")
			(net "M_G_DQ<43>")
		)
		(pad "116" smd rect
			(at 0 102.849934 90)
			(size 1.8034 0.508)
			(layers "F.Cu" "F.Mask" "F.Paste")
			(net "GND")
		)
		(pad "117" smd rect
			(at 0 103.700072 90)
			(size 1.8034 0.508)
			(layers "F.Cu" "F.Mask" "F.Paste")
			(net "M_G_DQ<53>")
		)
		(pad "118" smd rect
			(at 0 104.549956 90)
			(size 1.8034 0.508)
			(layers "F.Cu" "F.Mask" "F.Paste")
			(net "GND")
		)
		(pad "119" smd rect
			(at 0 105.400094 90)
			(size 1.8034 0.508)
			(layers "F.Cu" "F.Mask" "F.Paste")
			(net "M_G_DQ<49>")
		)
		(pad "120" smd rect
			(at 0 106.249978 90)
			(size 1.8034 0.508)
			(layers "F.Cu" "F.Mask" "F.Paste")
			(net "GND")
		)
		(pad "121" smd rect
			(at 0 107.100116 90)
			(size 1.8034 0.508)
			(layers "F.Cu" "F.Mask" "F.Paste")
			(net "M_G_DQS_DP<15>")
		)
		(pad "122" smd rect
			(at 0 107.95 90)
			(size 1.8034 0.508)
			(layers "F.Cu" "F.Mask" "F.Paste")
			(net "M_G_DQS_DN<15>")
		)
		(pad "123" smd rect
			(at 0 108.799884 90)
			(size 1.8034 0.508)
			(layers "F.Cu" "F.Mask" "F.Paste")
			(net "GND")
		)
		(pad "124" smd rect
			(at 0 109.650022 90)
			(size 1.8034 0.508)
			(layers "F.Cu" "F.Mask" "F.Paste")
			(net "M_G_DQ<55>")
		)
		(pad "125" smd rect
			(at 0 110.499906 90)
			(size 1.8034 0.508)
			(layers "F.Cu" "F.Mask" "F.Paste")
			(net "GND")
		)
		(pad "126" smd rect
			(at 0 111.350044 90)
			(size 1.8034 0.508)
			(layers "F.Cu" "F.Mask" "F.Paste")
			(net "M_G_DQ<51>")
		)
		(pad "127" smd rect
			(at 0 112.199928 90)
			(size 1.8034 0.508)
			(layers "F.Cu" "F.Mask" "F.Paste")
			(net "GND")
		)
		(pad "128" smd rect
			(at 0 113.050066 90)
			(size 1.8034 0.508)
			(layers "F.Cu" "F.Mask" "F.Paste")
			(net "M_G_DQ<61>")
		)
		(pad "129" smd rect
			(at 0 113.89995 90)
			(size 1.8034 0.508)
			(layers "F.Cu" "F.Mask" "F.Paste")
			(net "GND")
		)
		(pad "130" smd rect
			(at 0 114.750088 90)
			(size 1.8034 0.508)
			(layers "F.Cu" "F.Mask" "F.Paste")
			(net "M_G_DQ<57>")
		)
		(pad "131" smd rect
			(at 0 115.599972 90)
			(size 1.8034 0.508)
			(layers "F.Cu" "F.Mask" "F.Paste")
			(net "GND")
		)
		(pad "132" smd rect
			(at 0 116.45011 90)
			(size 1.8034 0.508)
			(layers "F.Cu" "F.Mask" "F.Paste")
			(net "M_G_DQS_DP<16>")
		)
		(pad "133" smd rect
			(at 0 117.299994 90)
			(size 1.8034 0.508)
			(layers "F.Cu" "F.Mask" "F.Paste")
			(net "M_G_DQS_DN<16>")
		)
		(pad "134" smd rect
			(at 0 118.149878 90)
			(size 1.8034 0.508)
			(layers "F.Cu" "F.Mask" "F.Paste")
			(net "GND")
		)
		(pad "135" smd rect
			(at 0 119.000016 90)
			(size 1.8034 0.508)
			(layers "F.Cu" "F.Mask" "F.Paste")
			(net "M_G_DQ<63>")
		)
		(pad "136" smd rect
			(at 0 119.8499 90)
			(size 1.8034 0.508)
			(layers "F.Cu" "F.Mask" "F.Paste")
			(net "GND")
		)
		(pad "137" smd rect
			(at 0 120.700038 90)
			(size 1.8034 0.508)
			(layers "F.Cu" "F.Mask" "F.Paste")
			(net "M_G_DQ<59>")
		)
		(pad "138" smd rect
			(at 0 121.549922 90)
			(size 1.8034 0.508)
			(layers "F.Cu" "F.Mask" "F.Paste")
			(net "GND")
		)
		(pad "139" smd rect
			(at 0 122.40006 90)
			(size 1.8034 0.508)
			(layers "F.Cu" "F.Mask" "F.Paste")
			(net "GND")
		)
		(pad "140" smd rect
			(at 0 123.249944 90)
			(size 1.8034 0.508)
			(layers "F.Cu" "F.Mask" "F.Paste")
			(net "GND")
		)
		(pad "141" smd rect
			(at 0 124.100082 90)
			(size 1.8034 0.508)
			(layers "F.Cu" "F.Mask" "F.Paste")
			(net "SMB_DDR_GHJ_VPP_SCL")
		)
		(pad "142" smd rect
			(at 0 124.949966 90)
			(size 1.8034 0.508)
			(layers "F.Cu" "F.Mask" "F.Paste")
			(net "PVPP_GHJ")
		)
		(pad "143" smd rect
			(at 0 125.800104 90)
			(size 1.8034 0.508)
			(layers "F.Cu" "F.Mask" "F.Paste")
			(net "PVPP_GHJ")
		)
		(pad "144" smd rect
			(at 0 126.649988 90)
			(size 1.8034 0.508)
			(layers "F.Cu" "F.Mask" "F.Paste")
			(net "TP_CH_G_DIMM_G0_RFU_2")
		)
		(pad "145" smd rect
			(at 4.59994 0 90)
			(size 1.8034 0.508)
			(layers "F.Cu" "F.Mask" "F.Paste")
			(net "P12V_NVDIMM_GHJ")
		)
		(pad "146" smd rect
			(at 4.59994 0.849884 90)
			(size 1.8034 0.508)
			(layers "F.Cu" "F.Mask" "F.Paste")
			(net "M_G_VREF")
		)
		(pad "147" smd rect
			(at 4.59994 1.700022 90)
			(size 1.8034 0.508)
			(layers "F.Cu" "F.Mask" "F.Paste")
			(net "GND")
		)
		(pad "148" smd rect
			(at 4.59994 2.549906 90)
			(size 1.8034 0.508)
			(layers "F.Cu" "F.Mask" "F.Paste")
			(net "M_G_DQ<4>")
		)
		(pad "149" smd rect
			(at 4.59994 3.400044 90)
			(size 1.8034 0.508)
			(layers "F.Cu" "F.Mask" "F.Paste")
			(net "GND")
		)
		(pad "150" smd rect
			(at 4.59994 4.249928 90)
			(size 1.8034 0.508)
			(layers "F.Cu" "F.Mask" "F.Paste")
			(net "M_G_DQ<0>")
		)
		(pad "151" smd rect
			(at 4.59994 5.100066 90)
			(size 1.8034 0.508)
			(layers "F.Cu" "F.Mask" "F.Paste")
			(net "GND")
		)
		(pad "152" smd rect
			(at 4.59994 5.94995 90)
			(size 1.8034 0.508)
			(layers "F.Cu" "F.Mask" "F.Paste")
			(net "M_G_DQS_DN<0>")
		)
		(pad "153" smd rect
			(at 4.59994 6.800088 90)
			(size 1.8034 0.508)
			(layers "F.Cu" "F.Mask" "F.Paste")
			(net "M_G_DQS_DP<0>")
		)
		(pad "154" smd rect
			(at 4.59994 7.649972 90)
			(size 1.8034 0.508)
			(layers "F.Cu" "F.Mask" "F.Paste")
			(net "GND")
		)
		(pad "155" smd rect
			(at 4.59994 8.50011 90)
			(size 1.8034 0.508)
			(layers "F.Cu" "F.Mask" "F.Paste")
			(net "M_G_DQ<6>")
		)
		(pad "156" smd rect
			(at 4.59994 9.349994 90)
			(size 1.8034 0.508)
			(layers "F.Cu" "F.Mask" "F.Paste")
			(net "GND")
		)
		(pad "157" smd rect
			(at 4.59994 10.199878 90)
			(size 1.8034 0.508)
			(layers "F.Cu" "F.Mask" "F.Paste")
			(net "M_G_DQ<2>")
		)
		(pad "158" smd rect
			(at 4.59994 11.050016 90)
			(size 1.8034 0.508)
			(layers "F.Cu" "F.Mask" "F.Paste")
			(net "GND")
		)
		(pad "159" smd rect
			(at 4.59994 11.8999 90)
			(size 1.8034 0.508)
			(layers "F.Cu" "F.Mask" "F.Paste")
			(net "M_G_DQ<12>")
		)
		(pad "160" smd rect
			(at 4.59994 12.750038 90)
			(size 1.8034 0.508)
			(layers "F.Cu" "F.Mask" "F.Paste")
			(net "GND")
		)
		(pad "161" smd rect
			(at 4.59994 13.599922 90)
			(size 1.8034 0.508)
			(layers "F.Cu" "F.Mask" "F.Paste")
			(net "M_G_DQ<8>")
		)
		(pad "162" smd rect
			(at 4.59994 14.45006 90)
			(size 1.8034 0.508)
			(layers "F.Cu" "F.Mask" "F.Paste")
			(net "GND")
		)
		(pad "163" smd rect
			(at 4.59994 15.299944 90)
			(size 1.8034 0.508)
			(layers "F.Cu" "F.Mask" "F.Paste")
			(net "M_G_DQS_DN<1>")
		)
		(pad "164" smd rect
			(at 4.59994 16.150082 90)
			(size 1.8034 0.508)
			(layers "F.Cu" "F.Mask" "F.Paste")
			(net "M_G_DQS_DP<1>")
		)
		(pad "165" smd rect
			(at 4.59994 16.999966 90)
			(size 1.8034 0.508)
			(layers "F.Cu" "F.Mask" "F.Paste")
			(net "GND")
		)
		(pad "166" smd rect
			(at 4.59994 17.850104 90)
			(size 1.8034 0.508)
			(layers "F.Cu" "F.Mask" "F.Paste")
			(net "M_G_DQ<14>")
		)
		(pad "167" smd rect
			(at 4.59994 18.699988 90)
			(size 1.8034 0.508)
			(layers "F.Cu" "F.Mask" "F.Paste")
			(net "GND")
		)
		(pad "168" smd rect
			(at 4.59994 19.550126 90)
			(size 1.8034 0.508)
			(layers "F.Cu" "F.Mask" "F.Paste")
			(net "M_G_DQ<10>")
		)
		(pad "169" smd rect
			(at 4.59994 20.40001 90)
			(size 1.8034 0.508)
			(layers "F.Cu" "F.Mask" "F.Paste")
			(net "GND")
		)
		(pad "170" smd rect
			(at 4.59994 21.249894 90)
			(size 1.8034 0.508)
			(layers "F.Cu" "F.Mask" "F.Paste")
			(net "M_G_DQ<20>")
		)
		(pad "171" smd rect
			(at 4.59994 22.100032 90)
			(size 1.8034 0.508)
			(layers "F.Cu" "F.Mask" "F.Paste")
			(net "GND")
		)
		(pad "172" smd rect
			(at 4.59994 22.949916 90)
			(size 1.8034 0.508)
			(layers "F.Cu" "F.Mask" "F.Paste")
			(net "M_G_DQ<16>")
		)
		(pad "173" smd rect
			(at 4.59994 23.800054 90)
			(size 1.8034 0.508)
			(layers "F.Cu" "F.Mask" "F.Paste")
			(net "GND")
		)
		(pad "174" smd rect
			(at 4.59994 24.649938 90)
			(size 1.8034 0.508)
			(layers "F.Cu" "F.Mask" "F.Paste")
			(net "M_G_DQS_DN<2>")
		)
		(pad "175" smd rect
			(at 4.59994 25.500076 90)
			(size 1.8034 0.508)
			(layers "F.Cu" "F.Mask" "F.Paste")
			(net "M_G_DQS_DP<2>")
		)
		(pad "176" smd rect
			(at 4.59994 26.34996 90)
			(size 1.8034 0.508)
			(layers "F.Cu" "F.Mask" "F.Paste")
			(net "GND")
		)
		(pad "177" smd rect
			(at 4.59994 27.200098 90)
			(size 1.8034 0.508)
			(layers "F.Cu" "F.Mask" "F.Paste")
			(net "M_G_DQ<22>")
		)
		(pad "178" smd rect
			(at 4.59994 28.049982 90)
			(size 1.8034 0.508)
			(layers "F.Cu" "F.Mask" "F.Paste")
			(net "GND")
		)
		(pad "179" smd rect
			(at 4.59994 28.90012 90)
			(size 1.8034 0.508)
			(layers "F.Cu" "F.Mask" "F.Paste")
			(net "M_G_DQ<18>")
		)
		(pad "180" smd rect
			(at 4.59994 29.750004 90)
			(size 1.8034 0.508)
			(layers "F.Cu" "F.Mask" "F.Paste")
			(net "GND")
		)
		(pad "181" smd rect
			(at 4.59994 30.599888 90)
			(size 1.8034 0.508)
			(layers "F.Cu" "F.Mask" "F.Paste")
			(net "M_G_DQ<28>")
		)
		(pad "182" smd rect
			(at 4.59994 31.450026 90)
			(size 1.8034 0.508)
			(layers "F.Cu" "F.Mask" "F.Paste")
			(net "GND")
		)
		(pad "183" smd rect
			(at 4.59994 32.29991 90)
			(size 1.8034 0.508)
			(layers "F.Cu" "F.Mask" "F.Paste")
			(net "M_G_DQ<24>")
		)
		(pad "184" smd rect
			(at 4.59994 33.150048 90)
			(size 1.8034 0.508)
			(layers "F.Cu" "F.Mask" "F.Paste")
			(net "GND")
		)
		(pad "185" smd rect
			(at 4.59994 33.999932 90)
			(size 1.8034 0.508)
			(layers "F.Cu" "F.Mask" "F.Paste")
			(net "M_G_DQS_DN<3>")
		)
		(pad "186" smd rect
			(at 4.59994 34.85007 90)
			(size 1.8034 0.508)
			(layers "F.Cu" "F.Mask" "F.Paste")
			(net "M_G_DQS_DP<3>")
		)
		(pad "187" smd rect
			(at 4.59994 35.699954 90)
			(size 1.8034 0.508)
			(layers "F.Cu" "F.Mask" "F.Paste")
			(net "GND")
		)
		(pad "188" smd rect
			(at 4.59994 36.550092 90)
			(size 1.8034 0.508)
			(layers "F.Cu" "F.Mask" "F.Paste")
			(net "M_G_DQ<30>")
		)
		(pad "189" smd rect
			(at 4.59994 37.399976 90)
			(size 1.8034 0.508)
			(layers "F.Cu" "F.Mask" "F.Paste")
			(net "GND")
		)
		(pad "190" smd rect
			(at 4.59994 38.250114 90)
			(size 1.8034 0.508)
			(layers "F.Cu" "F.Mask" "F.Paste")
			(net "M_G_DQ<26>")
		)
		(pad "191" smd rect
			(at 4.59994 39.099998 90)
			(size 1.8034 0.508)
			(layers "F.Cu" "F.Mask" "F.Paste")
			(net "GND")
		)
		(pad "192" smd rect
			(at 4.59994 39.949882 90)
			(size 1.8034 0.508)
			(layers "F.Cu" "F.Mask" "F.Paste")
			(net "M_G_ECC<4>")
		)
		(pad "193" smd rect
			(at 4.59994 40.80002 90)
			(size 1.8034 0.508)
			(layers "F.Cu" "F.Mask" "F.Paste")
			(net "GND")
		)
		(pad "194" smd rect
			(at 4.59994 41.649904 90)
			(size 1.8034 0.508)
			(layers "F.Cu" "F.Mask" "F.Paste")
			(net "M_G_ECC<0>")
		)
		(pad "195" smd rect
			(at 4.59994 42.500042 90)
			(size 1.8034 0.508)
			(layers "F.Cu" "F.Mask" "F.Paste")
			(net "GND")
		)
		(pad "196" smd rect
			(at 4.59994 43.349926 90)
			(size 1.8034 0.508)
			(layers "F.Cu" "F.Mask" "F.Paste")
			(net "M_G_DQS_DN<8>")
		)
		(pad "197" smd rect
			(at 4.59994 44.200064 90)
			(size 1.8034 0.508)
			(layers "F.Cu" "F.Mask" "F.Paste")
			(net "M_G_DQS_DP<8>")
		)
		(pad "198" smd rect
			(at 4.59994 45.049948 90)
			(size 1.8034 0.508)
			(layers "F.Cu" "F.Mask" "F.Paste")
			(net "GND")
		)
		(pad "199" smd rect
			(at 4.59994 45.900086 90)
			(size 1.8034 0.508)
			(layers "F.Cu" "F.Mask" "F.Paste")
			(net "M_G_ECC<6>")
		)
		(pad "200" smd rect
			(at 4.59994 46.74997 90)
			(size 1.8034 0.508)
			(layers "F.Cu" "F.Mask" "F.Paste")
			(net "GND")
		)
		(pad "201" smd rect
			(at 4.59994 47.600108 90)
			(size 1.8034 0.508)
			(layers "F.Cu" "F.Mask" "F.Paste")
			(net "M_G_ECC<2>")
		)
		(pad "202" smd rect
			(at 4.59994 48.449992 90)
			(size 1.8034 0.508)
			(layers "F.Cu" "F.Mask" "F.Paste")
			(net "GND")
		)
		(pad "203" smd rect
			(at 4.59994 49.299876 90)
			(size 1.8034 0.508)
			(layers "F.Cu" "F.Mask" "F.Paste")
			(net "M_G_CKE<1>")
		)
		(pad "204" smd rect
			(at 4.59994 50.150014 90)
			(size 1.8034 0.508)
			(layers "F.Cu" "F.Mask" "F.Paste")
			(net "PVDDQ_GHJ")
		)
		(pad "205" smd rect
			(at 4.59994 50.999898 90)
			(size 1.8034 0.508)
			(layers "F.Cu" "F.Mask" "F.Paste")
			(net "TP_CH_G_DIMM_G0_RFU_0")
		)
		(pad "206" smd rect
			(at 4.59994 51.850036 90)
			(size 1.8034 0.508)
			(layers "F.Cu" "F.Mask" "F.Paste")
			(net "PVDDQ_GHJ")
		)
		(pad "207" smd rect
			(at 4.59994 52.69992 90)
			(size 1.8034 0.508)
			(layers "F.Cu" "F.Mask" "F.Paste")
			(net "M_G_BG<1>")
		)
		(pad "208" smd rect
			(at 4.59994 53.550058 90)
			(size 1.8034 0.508)
			(layers "F.Cu" "F.Mask" "F.Paste")
			(net "M_G_ALERT_N")
		)
		(pad "209" smd rect
			(at 4.59994 54.399942 90)
			(size 1.8034 0.508)
			(layers "F.Cu" "F.Mask" "F.Paste")
			(net "PVDDQ_GHJ")
		)
		(pad "210" smd rect
			(at 4.59994 55.25008 90)
			(size 1.8034 0.508)
			(layers "F.Cu" "F.Mask" "F.Paste")
			(net "M_G_MA<11>")
		)
		(pad "211" smd rect
			(at 4.59994 56.099964 90)
			(size 1.8034 0.508)
			(layers "F.Cu" "F.Mask" "F.Paste")
			(net "M_G_MA<7>")
		)
		(pad "212" smd rect
			(at 4.59994 56.950102 90)
			(size 1.8034 0.508)
			(layers "F.Cu" "F.Mask" "F.Paste")
			(net "PVDDQ_GHJ")
		)
		(pad "213" smd rect
			(at 4.59994 57.799986 90)
			(size 1.8034 0.508)
			(layers "F.Cu" "F.Mask" "F.Paste")
			(net "M_G_MA<5>")
		)
		(pad "214" smd rect
			(at 4.59994 58.650124 90)
			(size 1.8034 0.508)
			(layers "F.Cu" "F.Mask" "F.Paste")
			(net "M_G_MA<4>")
		)
		(pad "215" smd rect
			(at 4.59994 59.500008 90)
			(size 1.8034 0.508)
			(layers "F.Cu" "F.Mask" "F.Paste")
			(net "PVDDQ_GHJ")
		)
		(pad "216" smd rect
			(at 4.59994 60.349892 90)
			(size 1.8034 0.508)
			(layers "F.Cu" "F.Mask" "F.Paste")
			(net "M_G_MA<2>")
		)
		(pad "217" smd rect
			(at 4.59994 61.20003 90)
			(size 1.8034 0.508)
			(layers "F.Cu" "F.Mask" "F.Paste")
			(net "PVDDQ_GHJ")
		)
		(pad "218" smd rect
			(at 4.59994 62.049914 90)
			(size 1.8034 0.508)
			(layers "F.Cu" "F.Mask" "F.Paste")
			(net "M_G_CLK_DP<1>")
		)
		(pad "219" smd rect
			(at 4.59994 62.900052 90)
			(size 1.8034 0.508)
			(layers "F.Cu" "F.Mask" "F.Paste")
			(net "M_G_CLK_DN<1>")
		)
		(pad "220" smd rect
			(at 4.59994 63.749936 90)
			(size 1.8034 0.508)
			(layers "F.Cu" "F.Mask" "F.Paste")
			(net "PVDDQ_GHJ")
		)
		(pad "221" smd rect
			(at 4.59994 64.600074 90)
			(size 1.8034 0.508)
			(layers "F.Cu" "F.Mask" "F.Paste")
			(net "PVTT_GHJ")
		)
		(pad "222" smd rect
			(at 4.59994 70.550024 90)
			(size 1.8034 0.508)
			(layers "F.Cu" "F.Mask" "F.Paste")
			(net "M_G_PAR")
		)
		(pad "223" smd rect
			(at 4.59994 71.399908 90)
			(size 1.8034 0.508)
			(layers "F.Cu" "F.Mask" "F.Paste")
			(net "PVDDQ_GHJ")
		)
		(pad "224" smd rect
			(at 4.59994 72.250046 90)
			(size 1.8034 0.508)
			(layers "F.Cu" "F.Mask" "F.Paste")
			(net "M_G_BA<1>")
		)
		(pad "225" smd rect
			(at 4.59994 73.09993 90)
			(size 1.8034 0.508)
			(layers "F.Cu" "F.Mask" "F.Paste")
			(net "M_G_MA<10>")
		)
		(pad "226" smd rect
			(at 4.59994 73.950068 90)
			(size 1.8034 0.508)
			(layers "F.Cu" "F.Mask" "F.Paste")
			(net "PVDDQ_GHJ")
		)
		(pad "227" smd rect
			(at 4.59994 74.799952 90)
			(size 1.8034 0.508)
			(layers "F.Cu" "F.Mask" "F.Paste")
			(net "TP_CH_G_DIMM_G0_RFU_1")
		)
		(pad "228" smd rect
			(at 4.59994 75.65009 90)
			(size 1.8034 0.508)
			(layers "F.Cu" "F.Mask" "F.Paste")
			(net "M_G_MA<14>")
		)
		(pad "229" smd rect
			(at 4.59994 76.499974 90)
			(size 1.8034 0.508)
			(layers "F.Cu" "F.Mask" "F.Paste")
			(net "PVDDQ_GHJ")
		)
		(pad "230" smd rect
			(at 4.59994 77.350112 90)
			(size 1.8034 0.508)
			(layers "F.Cu" "F.Mask" "F.Paste")
			(net "FM_ADR_COMPLETE_GHJ_N")
		)
		(pad "231" smd rect
			(at 4.59994 78.199996 90)
			(size 1.8034 0.508)
			(layers "F.Cu" "F.Mask" "F.Paste")
			(net "PVDDQ_GHJ")
		)
		(pad "232" smd rect
			(at 4.59994 79.04988 90)
			(size 1.8034 0.508)
			(layers "F.Cu" "F.Mask" "F.Paste")
			(net "M_G_MA<13>")
		)
		(pad "233" smd rect
			(at 4.59994 79.900018 90)
			(size 1.8034 0.508)
			(layers "F.Cu" "F.Mask" "F.Paste")
			(net "PVDDQ_GHJ")
		)
		(pad "234" smd rect
			(at 4.59994 80.749902 90)
			(size 1.8034 0.508)
			(layers "F.Cu" "F.Mask" "F.Paste")
			(net "M_G_MA<17>")
		)
		(pad "235" smd rect
			(at 4.59994 81.60004 90)
			(size 1.8034 0.508)
			(layers "F.Cu" "F.Mask" "F.Paste")
			(net "M_G_C<2>")
		)
		(pad "236" smd rect
			(at 4.59994 82.449924 90)
			(size 1.8034 0.508)
			(layers "F.Cu" "F.Mask" "F.Paste")
			(net "PVDDQ_GHJ")
		)
		(pad "237" smd rect
			(at 4.59994 83.300062 90)
			(size 1.8034 0.508)
			(layers "F.Cu" "F.Mask" "F.Paste")
			(net "M_G_CS_N<3>")
		)
		(pad "238" smd rect
			(at 4.59994 84.149946 90)
			(size 1.8034 0.508)
			(layers "F.Cu" "F.Mask" "F.Paste")
			(net "GND")
		)
		(pad "239" smd rect
			(at 4.59994 85.000084 90)
			(size 1.8034 0.508)
			(layers "F.Cu" "F.Mask" "F.Paste")
			(net "GND")
		)
		(pad "240" smd rect
			(at 4.59994 85.849968 90)
			(size 1.8034 0.508)
			(layers "F.Cu" "F.Mask" "F.Paste")
			(net "M_G_DQ<36>")
		)
		(pad "241" smd rect
			(at 4.59994 86.700106 90)
			(size 1.8034 0.508)
			(layers "F.Cu" "F.Mask" "F.Paste")
			(net "GND")
		)
		(pad "242" smd rect
			(at 4.59994 87.54999 90)
			(size 1.8034 0.508)
			(layers "F.Cu" "F.Mask" "F.Paste")
			(net "M_G_DQ<32>")
		)
		(pad "243" smd rect
			(at 4.59994 88.399874 90)
			(size 1.8034 0.508)
			(layers "F.Cu" "F.Mask" "F.Paste")
			(net "GND")
		)
		(pad "244" smd rect
			(at 4.59994 89.250012 90)
			(size 1.8034 0.508)
			(layers "F.Cu" "F.Mask" "F.Paste")
			(net "M_G_DQS_DN<4>")
		)
		(pad "245" smd rect
			(at 4.59994 90.099896 90)
			(size 1.8034 0.508)
			(layers "F.Cu" "F.Mask" "F.Paste")
			(net "M_G_DQS_DP<4>")
		)
		(pad "246" smd rect
			(at 4.59994 90.950034 90)
			(size 1.8034 0.508)
			(layers "F.Cu" "F.Mask" "F.Paste")
			(net "GND")
		)
		(pad "247" smd rect
			(at 4.59994 91.799918 90)
			(size 1.8034 0.508)
			(layers "F.Cu" "F.Mask" "F.Paste")
			(net "M_G_DQ<38>")
		)
		(pad "248" smd rect
			(at 4.59994 92.650056 90)
			(size 1.8034 0.508)
			(layers "F.Cu" "F.Mask" "F.Paste")
			(net "GND")
		)
		(pad "249" smd rect
			(at 4.59994 93.49994 90)
			(size 1.8034 0.508)
			(layers "F.Cu" "F.Mask" "F.Paste")
			(net "M_G_DQ<34>")
		)
		(pad "250" smd rect
			(at 4.59994 94.350078 90)
			(size 1.8034 0.508)
			(layers "F.Cu" "F.Mask" "F.Paste")
			(net "GND")
		)
		(pad "251" smd rect
			(at 4.59994 95.199962 90)
			(size 1.8034 0.508)
			(layers "F.Cu" "F.Mask" "F.Paste")
			(net "M_G_DQ<44>")
		)
		(pad "252" smd rect
			(at 4.59994 96.0501 90)
			(size 1.8034 0.508)
			(layers "F.Cu" "F.Mask" "F.Paste")
			(net "GND")
		)
		(pad "253" smd rect
			(at 4.59994 96.899984 90)
			(size 1.8034 0.508)
			(layers "F.Cu" "F.Mask" "F.Paste")
			(net "M_G_DQ<40>")
		)
		(pad "254" smd rect
			(at 4.59994 97.750122 90)
			(size 1.8034 0.508)
			(layers "F.Cu" "F.Mask" "F.Paste")
			(net "GND")
		)
		(pad "255" smd rect
			(at 4.59994 98.600006 90)
			(size 1.8034 0.508)
			(layers "F.Cu" "F.Mask" "F.Paste")
			(net "M_G_DQS_DN<5>")
		)
		(pad "256" smd rect
			(at 4.59994 99.44989 90)
			(size 1.8034 0.508)
			(layers "F.Cu" "F.Mask" "F.Paste")
			(net "M_G_DQS_DP<5>")
		)
		(pad "257" smd rect
			(at 4.59994 100.300028 90)
			(size 1.8034 0.508)
			(layers "F.Cu" "F.Mask" "F.Paste")
			(net "GND")
		)
		(pad "258" smd rect
			(at 4.59994 101.149912 90)
			(size 1.8034 0.508)
			(layers "F.Cu" "F.Mask" "F.Paste")
			(net "M_G_DQ<46>")
		)
		(pad "259" smd rect
			(at 4.59994 102.00005 90)
			(size 1.8034 0.508)
			(layers "F.Cu" "F.Mask" "F.Paste")
			(net "GND")
		)
		(pad "260" smd rect
			(at 4.59994 102.849934 90)
			(size 1.8034 0.508)
			(layers "F.Cu" "F.Mask" "F.Paste")
			(net "M_G_DQ<42>")
		)
		(pad "261" smd rect
			(at 4.59994 103.700072 90)
			(size 1.8034 0.508)
			(layers "F.Cu" "F.Mask" "F.Paste")
			(net "GND")
		)
		(pad "262" smd rect
			(at 4.59994 104.549956 90)
			(size 1.8034 0.508)
			(layers "F.Cu" "F.Mask" "F.Paste")
			(net "M_G_DQ<52>")
		)
		(pad "263" smd rect
			(at 4.59994 105.400094 90)
			(size 1.8034 0.508)
			(layers "F.Cu" "F.Mask" "F.Paste")
			(net "GND")
		)
		(pad "264" smd rect
			(at 4.59994 106.249978 90)
			(size 1.8034 0.508)
			(layers "F.Cu" "F.Mask" "F.Paste")
			(net "M_G_DQ<48>")
		)
		(pad "265" smd rect
			(at 4.59994 107.100116 90)
			(size 1.8034 0.508)
			(layers "F.Cu" "F.Mask" "F.Paste")
			(net "GND")
		)
		(pad "266" smd rect
			(at 4.59994 107.95 90)
			(size 1.8034 0.508)
			(layers "F.Cu" "F.Mask" "F.Paste")
			(net "M_G_DQS_DN<6>")
		)
		(pad "267" smd rect
			(at 4.59994 108.799884 90)
			(size 1.8034 0.508)
			(layers "F.Cu" "F.Mask" "F.Paste")
			(net "M_G_DQS_DP<6>")
		)
		(pad "268" smd rect
			(at 4.59994 109.650022 90)
			(size 1.8034 0.508)
			(layers "F.Cu" "F.Mask" "F.Paste")
			(net "GND")
		)
		(pad "269" smd rect
			(at 4.59994 110.499906 90)
			(size 1.8034 0.508)
			(layers "F.Cu" "F.Mask" "F.Paste")
			(net "M_G_DQ<54>")
		)
		(pad "270" smd rect
			(at 4.59994 111.350044 90)
			(size 1.8034 0.508)
			(layers "F.Cu" "F.Mask" "F.Paste")
			(net "GND")
		)
		(pad "271" smd rect
			(at 4.59994 112.199928 90)
			(size 1.8034 0.508)
			(layers "F.Cu" "F.Mask" "F.Paste")
			(net "M_G_DQ<50>")
		)
		(pad "272" smd rect
			(at 4.59994 113.050066 90)
			(size 1.8034 0.508)
			(layers "F.Cu" "F.Mask" "F.Paste")
			(net "GND")
		)
		(pad "273" smd rect
			(at 4.59994 113.89995 90)
			(size 1.8034 0.508)
			(layers "F.Cu" "F.Mask" "F.Paste")
			(net "M_G_DQ<60>")
		)
		(pad "274" smd rect
			(at 4.59994 114.750088 90)
			(size 1.8034 0.508)
			(layers "F.Cu" "F.Mask" "F.Paste")
			(net "GND")
		)
		(pad "275" smd rect
			(at 4.59994 115.599972 90)
			(size 1.8034 0.508)
			(layers "F.Cu" "F.Mask" "F.Paste")
			(net "M_G_DQ<56>")
		)
		(pad "276" smd rect
			(at 4.59994 116.45011 90)
			(size 1.8034 0.508)
			(layers "F.Cu" "F.Mask" "F.Paste")
			(net "GND")
		)
		(pad "277" smd rect
			(at 4.59994 117.299994 90)
			(size 1.8034 0.508)
			(layers "F.Cu" "F.Mask" "F.Paste")
			(net "M_G_DQS_DN<7>")
		)
		(pad "278" smd rect
			(at 4.59994 118.149878 90)
			(size 1.8034 0.508)
			(layers "F.Cu" "F.Mask" "F.Paste")
			(net "M_G_DQS_DP<7>")
		)
		(pad "279" smd rect
			(at 4.59994 119.000016 90)
			(size 1.8034 0.508)
			(layers "F.Cu" "F.Mask" "F.Paste")
			(net "GND")
		)
		(pad "280" smd rect
			(at 4.59994 119.8499 90)
			(size 1.8034 0.508)
			(layers "F.Cu" "F.Mask" "F.Paste")
			(net "M_G_DQ<62>")
		)
		(pad "281" smd rect
			(at 4.59994 120.700038 90)
			(size 1.8034 0.508)
			(layers "F.Cu" "F.Mask" "F.Paste")
			(net "GND")
		)
		(pad "282" smd rect
			(at 4.59994 121.549922 90)
			(size 1.8034 0.508)
			(layers "F.Cu" "F.Mask" "F.Paste")
			(net "M_G_DQ<58>")
		)
		(pad "283" smd rect
			(at 4.59994 122.40006 90)
			(size 1.8034 0.508)
			(layers "F.Cu" "F.Mask" "F.Paste")
			(net "GND")
		)
		(pad "284" smd rect
			(at 4.59994 123.249944 90)
			(size 1.8034 0.508)
			(layers "F.Cu" "F.Mask" "F.Paste")
			(net "PVPP_GHJ")
		)
		(pad "285" smd rect
			(at 4.59994 124.100082 90)
			(size 1.8034 0.508)
			(layers "F.Cu" "F.Mask" "F.Paste")
			(net "SMB_DDR_GHJ_VPP_SDA")
		)
		(pad "286" smd rect
			(at 4.59994 124.949966 90)
			(size 1.8034 0.508)
			(layers "F.Cu" "F.Mask" "F.Paste")
			(net "PVPP_GHJ")
		)
		(pad "287" smd rect
			(at 4.59994 125.800104 90)
			(size 1.8034 0.508)
			(layers "F.Cu" "F.Mask" "F.Paste")
			(net "PVPP_GHJ")
		)
		(pad "288" smd rect
			(at 4.59994 126.649988 90)
			(size 1.8034 0.508)
			(layers "F.Cu" "F.Mask" "F.Paste")
			(net "PVPP_GHJ")
		)
	)
	(footprint ""
		(layer "F.Cu")
		(at 410.226256 -57.26684 90)
		(property "Reference" "R8D23"
			(at 0 0 90)
			(layer "F.SilkS")
			(hide yes)
			(effects
				(font
					(size 1.27 1.27)
				)
			)
		)
		(property "Value" ""
			(at 0 0 90)
			(layer "F.Fab")
			(effects
				(font
					(size 1.27 1.27)
				)
			)
		)
		(duplicate_pad_numbers_are_jumpers no)
		(fp_poly
			(pts
				(xy -0.2794 -0.1016) (xy 0.2794 -0.1016) (xy 0.2794 0.9906) (xy -0.2794 0.9906)
			)
			(stroke
				(width 0)
				(type default)
			)
			(fill no)
			(layer "F.CrtYd")
		)
		(fp_line
			(start 0.2794 -0.1016)
			(end -0.2794 -0.1016)
			(stroke
				(width 0.1)
				(type default)
			)
			(layer "F.Fab")
		)
		(fp_line
			(start -0.2794 -0.1016)
			(end -0.2794 0.9906)
			(stroke
				(width 0.1)
				(type default)
			)
			(layer "F.Fab")
		)
		(fp_line
			(start 0.2794 0.9906)
			(end 0.2794 -0.1016)
			(stroke
				(width 0.1)
				(type default)
			)
			(layer "F.Fab")
		)
		(fp_line
			(start -0.2794 0.9906)
			(end 0.2794 0.9906)
			(stroke
				(width 0.1)
				(type default)
			)
			(layer "F.Fab")
		)
		(pad "1" smd rect
			(at 0 0 90)
			(size 0.508 0.508)
			(layers "F.Cu" "F.Mask" "F.Paste")
			(net "SMB_SENSOR_STBY_LVC3_SDA_R2")
		)
		(pad "2" smd rect
			(at 0 0.889 90)
			(size 0.508 0.508)
			(layers "F.Cu" "F.Mask" "F.Paste")
			(net "SMB_SENSOR_STBY_LVC3_SDA")
		)
		(zone
			(layer "F.Cu")
			(hatch none 0.5)
			(connect_pads
				(clearance 0)
			)
			(min_thickness 0.25)
			(keepout
				(tracks allowed)
				(vias not_allowed)
				(pads allowed)
				(copperpour not_allowed)
				(footprints allowed)
			)
			(placement
				(enabled no)
				(sheetname "")
			)
			(fill
				(thermal_gap 0.5)
				(thermal_bridge_width 0.5)
				(island_removal_mode 0)
			)
			(polygon
				(pts
					(xy 410.480256 -57.01284) (xy 410.480256 -57.52084) (xy 410.861256 -57.52084) (xy 410.861256 -57.01284)
				)
			)
		)
		(zone
			(layer "F.Cu")
			(hatch none 0.5)
			(connect_pads
				(clearance 0)
			)
			(min_thickness 0.25)
			(keepout
				(tracks not_allowed)
				(vias allowed)
				(pads allowed)
				(copperpour not_allowed)
				(footprints allowed)
			)
			(placement
				(enabled no)
				(sheetname "")
			)
			(fill
				(thermal_gap 0.5)
				(thermal_bridge_width 0.5)
				(island_removal_mode 0)
			)
			(polygon
				(pts
					(xy 410.861256 -57.01284) (xy 410.861256 -57.52084) (xy 410.480256 -57.52084) (xy 410.480256 -57.01284)
				)
			)
		)
	)
	(footprint ""
		(layer "F.Cu")
		(at 407.9875 -104.648 90)
		(property "Reference" "R2N7"
			(at 0 0 90)
			(layer "F.SilkS")
			(hide yes)
			(effects
				(font
					(size 1.27 1.27)
				)
			)
		)
		(property "Value" ""
			(at 0 0 90)
			(layer "F.Fab")
			(effects
				(font
					(size 1.27 1.27)
				)
			)
		)
		(duplicate_pad_numbers_are_jumpers no)
		(fp_poly
			(pts
				(xy -0.2794 -0.1016) (xy 0.2794 -0.1016) (xy 0.2794 0.9906) (xy -0.2794 0.9906)
			)
			(stroke
				(width 0)
				(type default)
			)
			(fill no)
			(layer "F.CrtYd")
		)
		(fp_line
			(start 0.2794 -0.1016)
			(end -0.2794 -0.1016)
			(stroke
				(width 0.1)
				(type default)
			)
			(layer "F.Fab")
		)
		(fp_line
			(start -0.2794 -0.1016)
			(end -0.2794 0.9906)
			(stroke
				(width 0.1)
				(type default)
			)
			(layer "F.Fab")
		)
		(fp_line
			(start 0.2794 0.9906)
			(end 0.2794 -0.1016)
			(stroke
				(width 0.1)
				(type default)
			)
			(layer "F.Fab")
		)
		(fp_line
			(start -0.2794 0.9906)
			(end 0.2794 0.9906)
			(stroke
				(width 0.1)
				(type default)
			)
			(layer "F.Fab")
		)
		(pad "1" smd rect
			(at 0 0 90)
			(size 0.508 0.508)
			(layers "F.Cu" "F.Mask" "F.Paste")
			(net "P3V3_STBY")
		)
		(pad "2" smd rect
			(at 0 0.889 90)
			(size 0.508 0.508)
			(layers "F.Cu" "F.Mask" "F.Paste")
			(net "IRQ_BOARD_BMC_ALERT_N")
		)
		(zone
			(layer "F.Cu")
			(hatch none 0.5)
			(connect_pads
				(clearance 0)
			)
			(min_thickness 0.25)
			(keepout
				(tracks allowed)
				(vias not_allowed)
				(pads allowed)
				(copperpour not_allowed)
				(footprints allowed)
			)
			(placement
				(enabled no)
				(sheetname "")
			)
			(fill
				(thermal_gap 0.5)
				(thermal_bridge_width 0.5)
				(island_removal_mode 0)
			)
			(polygon
				(pts
					(xy 408.2415 -104.394) (xy 408.2415 -104.902) (xy 408.6225 -104.902) (xy 408.6225 -104.394)
				)
			)
		)
		(zone
			(layer "F.Cu")
			(hatch none 0.5)
			(connect_pads
				(clearance 0)
			)
			(min_thickness 0.25)
			(keepout
				(tracks not_allowed)
				(vias allowed)
				(pads allowed)
				(copperpour not_allowed)
				(footprints allowed)
			)
			(placement
				(enabled no)
				(sheetname "")
			)
			(fill
				(thermal_gap 0.5)
				(thermal_bridge_width 0.5)
				(island_removal_mode 0)
			)
			(polygon
				(pts
					(xy 408.6225 -104.394) (xy 408.6225 -104.902) (xy 408.2415 -104.902) (xy 408.2415 -104.394)
				)
			)
		)
	)
	(footprint ""
		(layer "F.Cu")
		(at 28.83408 -99.60102 90)
		(property "Reference" "C1C12"
			(at 0 0 90)
			(layer "F.SilkS")
			(hide yes)
			(effects
				(font
					(size 1.27 1.27)
				)
			)
		)
		(property "Value" ""
			(at 0 0 90)
			(layer "F.Fab")
			(effects
				(font
					(size 1.27 1.27)
				)
			)
		)
		(duplicate_pad_numbers_are_jumpers no)
		(fp_rect
			(start -0.3048 0.9906)
			(end 0.3048 -0.1016)
			(stroke
				(width 0)
				(type default)
			)
			(fill no)
			(layer "F.CrtYd")
		)
		(fp_line
			(start 0.3048 -0.1016)
			(end -0.3048 -0.1016)
			(stroke
				(width 0.1)
				(type default)
			)
			(layer "F.Fab")
		)
		(fp_line
			(start -0.3048 -0.1016)
			(end -0.3048 0.9906)
			(stroke
				(width 0.1)
				(type default)
			)
			(layer "F.Fab")
		)
		(fp_line
			(start 0.3048 0.9906)
			(end 0.3048 -0.1016)
			(stroke
				(width 0.1)
				(type default)
			)
			(layer "F.Fab")
		)
		(fp_line
			(start -0.3048 0.9906)
			(end 0.3048 0.9906)
			(stroke
				(width 0.1)
				(type default)
			)
			(layer "F.Fab")
		)
		(pad "1" smd rect
			(at 0 0 90)
			(size 0.508 0.508)
			(layers "F.Cu" "F.Mask" "F.Paste")
			(net "VR_PVSA_CPU1_BOOT")
		)
		(pad "2" smd rect
			(at 0 0.889 90)
			(size 0.508 0.508)
			(layers "F.Cu" "F.Mask" "F.Paste")
			(net "VR_PVSA_CPU1_PHASE")
		)
		(zone
			(layer "F.Cu")
			(hatch none 0.5)
			(connect_pads
				(clearance 0)
			)
			(min_thickness 0.25)
			(keepout
				(tracks not_allowed)
				(vias allowed)
				(pads allowed)
				(copperpour not_allowed)
				(footprints allowed)
			)
			(placement
				(enabled no)
				(sheetname "")
			)
			(fill
				(thermal_gap 0.5)
				(thermal_bridge_width 0.5)
				(island_removal_mode 0)
			)
			(polygon
				(pts
					(xy 29.46908 -99.34702) (xy 29.46908 -99.85502) (xy 29.08808 -99.85502) (xy 29.08808 -99.34702)
				)
			)
		)
		(zone
			(layer "F.Cu")
			(hatch none 0.5)
			(connect_pads
				(clearance 0)
			)
			(min_thickness 0.25)
			(keepout
				(tracks allowed)
				(vias not_allowed)
				(pads allowed)
				(copperpour not_allowed)
				(footprints allowed)
			)
			(placement
				(enabled no)
				(sheetname "")
			)
			(fill
				(thermal_gap 0.5)
				(thermal_bridge_width 0.5)
				(island_removal_mode 0)
			)
			(polygon
				(pts
					(xy 29.46908 -99.34702) (xy 29.46908 -99.85502) (xy 29.08808 -99.85502) (xy 29.08808 -99.34702)
				)
			)
		)
	)
	(footprint ""
		(layer "F.Cu")
		(at 404.495 -22.098 180)
		(property "Reference" "R25W112"
			(at -0.8382 -0.67818 180)
			(unlocked yes)
			(layer "F.SilkS")
			(effects
				(font
					(size 0.4064 0.254)
					(thickness 0.1524)
				)
				(justify left)
			)
		)
		(property "Value" ""
			(at 0 0 180)
			(layer "F.Fab")
			(effects
				(font
					(size 1.27 1.27)
				)
			)
		)
		(duplicate_pad_numbers_are_jumpers no)
		(fp_poly
			(pts
				(xy -0.2794 -0.1016) (xy 0.2794 -0.1016) (xy 0.2794 0.9906) (xy -0.2794 0.9906)
			)
			(stroke
				(width 0)
				(type default)
			)
			(fill no)
			(layer "F.CrtYd")
		)
		(fp_line
			(start 0.2794 0.9906)
			(end 0.2794 -0.1016)
			(stroke
				(width 0.1)
				(type default)
			)
			(layer "F.Fab")
		)
		(fp_line
			(start 0.2794 -0.1016)
			(end -0.2794 -0.1016)
			(stroke
				(width 0.1)
				(type default)
			)
			(layer "F.Fab")
		)
		(fp_line
			(start -0.2794 0.9906)
			(end 0.2794 0.9906)
			(stroke
				(width 0.1)
				(type default)
			)
			(layer "F.Fab")
		)
		(fp_line
			(start -0.2794 -0.1016)
			(end -0.2794 0.9906)
			(stroke
				(width 0.1)
				(type default)
			)
			(layer "F.Fab")
		)
		(pad "1" smd rect
			(at 0 0 180)
			(size 0.508 0.508)
			(layers "F.Cu" "F.Mask" "F.Paste")
			(net "P3V3_STBY")
		)
		(pad "2" smd rect
			(at 0 0.889 180)
			(size 0.508 0.508)
			(layers "F.Cu" "F.Mask" "F.Paste")
			(net "RMII_BMC_PCH_SPRNGVLLE_TXD0_R")
		)
		(zone
			(layer "F.Cu")
			(hatch none 0.5)
			(connect_pads
				(clearance 0)
			)
			(min_thickness 0.25)
			(keepout
				(tracks not_allowed)
				(vias allowed)
				(pads allowed)
				(copperpour not_allowed)
				(footprints allowed)
			)
			(placement
				(enabled no)
				(sheetname "")
			)
			(fill
				(thermal_gap 0.5)
				(thermal_bridge_width 0.5)
				(island_removal_mode 0)
			)
			(polygon
				(pts
					(xy 404.749 -22.733) (xy 404.241 -22.733) (xy 404.241 -22.352) (xy 404.749 -22.352)
				)
			)
		)
		(zone
			(layer "F.Cu")
			(hatch none 0.5)
			(connect_pads
				(clearance 0)
			)
			(min_thickness 0.25)
			(keepout
				(tracks allowed)
				(vias not_allowed)
				(pads allowed)
				(copperpour not_allowed)
				(footprints allowed)
			)
			(placement
				(enabled no)
				(sheetname "")
			)
			(fill
				(thermal_gap 0.5)
				(thermal_bridge_width 0.5)
				(island_removal_mode 0)
			)
			(polygon
				(pts
					(xy 404.749 -22.352) (xy 404.241 -22.352) (xy 404.241 -22.733) (xy 404.749 -22.733)
				)
			)
		)
	)
	(footprint ""
		(layer "F.Cu")
		(at 370.7384 -127.762 -90)
		(property "Reference" "R7B8"
			(at 0 0 270)
			(layer "F.SilkS")
			(hide yes)
			(effects
				(font
					(size 1.27 1.27)
				)
			)
		)
		(property "Value" ""
			(at 0 0 270)
			(layer "F.Fab")
			(effects
				(font
					(size 1.27 1.27)
				)
			)
		)
		(duplicate_pad_numbers_are_jumpers no)
		(fp_poly
			(pts
				(xy -0.2794 -0.1016) (xy 0.2794 -0.1016) (xy 0.2794 0.9906) (xy -0.2794 0.9906)
			)
			(stroke
				(width 0)
				(type default)
			)
			(fill no)
			(layer "F.CrtYd")
		)
		(fp_line
			(start -0.2794 0.9906)
			(end 0.2794 0.9906)
			(stroke
				(width 0.1)
				(type default)
			)
			(layer "F.Fab")
		)
		(fp_line
			(start 0.2794 0.9906)
			(end 0.2794 -0.1016)
			(stroke
				(width 0.1)
				(type default)
			)
			(layer "F.Fab")
		)
		(fp_line
			(start -0.2794 -0.1016)
			(end -0.2794 0.9906)
			(stroke
				(width 0.1)
				(type default)
			)
			(layer "F.Fab")
		)
		(fp_line
			(start 0.2794 -0.1016)
			(end -0.2794 -0.1016)
			(stroke
				(width 0.1)
				(type default)
			)
			(layer "F.Fab")
		)
		(pad "1" smd rect
			(at 0 0 270)
			(size 0.508 0.508)
			(layers "F.Cu" "F.Mask" "F.Paste")
			(net "A_EXTCLKN")
		)
		(pad "2" smd rect
			(at 0 0.889 270)
			(size 0.508 0.508)
			(layers "F.Cu" "F.Mask" "F.Paste")
			(net "GND")
		)
		(zone
			(layer "F.Cu")
			(hatch none 0.5)
			(connect_pads
				(clearance 0)
			)
			(min_thickness 0.25)
			(keepout
				(tracks not_allowed)
				(vias allowed)
				(pads allowed)
				(copperpour not_allowed)
				(footprints allowed)
			)
			(placement
				(enabled no)
				(sheetname "")
			)
			(fill
				(thermal_gap 0.5)
				(thermal_bridge_width 0.5)
				(island_removal_mode 0)
			)
			(polygon
				(pts
					(xy 370.1034 -128.016) (xy 370.1034 -127.508) (xy 370.4844 -127.508) (xy 370.4844 -128.016)
				)
			)
		)
		(zone
			(layer "F.Cu")
			(hatch none 0.5)
			(connect_pads
				(clearance 0)
			)
			(min_thickness 0.25)
			(keepout
				(tracks allowed)
				(vias not_allowed)
				(pads allowed)
				(copperpour not_allowed)
				(footprints allowed)
			)
			(placement
				(enabled no)
				(sheetname "")
			)
			(fill
				(thermal_gap 0.5)
				(thermal_bridge_width 0.5)
				(island_removal_mode 0)
			)
			(polygon
				(pts
					(xy 370.4844 -128.016) (xy 370.4844 -127.508) (xy 370.1034 -127.508) (xy 370.1034 -128.016)
				)
			)
		)
	)
	(footprint ""
		(layer "F.Cu")
		(at 402.615146 -42.935652 90)
		(property "Reference" "R1T36"
			(at 0 0 90)
			(layer "F.SilkS")
			(hide yes)
			(effects
				(font
					(size 1.27 1.27)
				)
			)
		)
		(property "Value" ""
			(at 0 0 90)
			(layer "F.Fab")
			(effects
				(font
					(size 1.27 1.27)
				)
			)
		)
		(duplicate_pad_numbers_are_jumpers no)
		(fp_poly
			(pts
				(xy -0.2794 -0.1016) (xy 0.2794 -0.1016) (xy 0.2794 0.9906) (xy -0.2794 0.9906)
			)
			(stroke
				(width 0)
				(type default)
			)
			(fill no)
			(layer "F.CrtYd")
		)
		(fp_line
			(start 0.2794 -0.1016)
			(end -0.2794 -0.1016)
			(stroke
				(width 0.1)
				(type default)
			)
			(layer "F.Fab")
		)
		(fp_line
			(start -0.2794 -0.1016)
			(end -0.2794 0.9906)
			(stroke
				(width 0.1)
				(type default)
			)
			(layer "F.Fab")
		)
		(fp_line
			(start 0.2794 0.9906)
			(end 0.2794 -0.1016)
			(stroke
				(width 0.1)
				(type default)
			)
			(layer "F.Fab")
		)
		(fp_line
			(start -0.2794 0.9906)
			(end 0.2794 0.9906)
			(stroke
				(width 0.1)
				(type default)
			)
			(layer "F.Fab")
		)
		(pad "1" smd rect
			(at 0 0 90)
			(size 0.508 0.508)
			(layers "F.Cu" "F.Mask" "F.Paste")
			(net "FM_CPU0_PROCHOT_LVT3_N")
		)
		(pad "2" smd rect
			(at 0 0.889 90)
			(size 0.508 0.508)
			(layers "F.Cu" "F.Mask" "F.Paste")
			(net "FM_CPU0_PROCHOT_LVT3_BMC_N")
		)
		(zone
			(layer "F.Cu")
			(hatch none 0.5)
			(connect_pads
				(clearance 0)
			)
			(min_thickness 0.25)
			(keepout
				(tracks allowed)
				(vias not_allowed)
				(pads allowed)
				(copperpour not_allowed)
				(footprints allowed)
			)
			(placement
				(enabled no)
				(sheetname "")
			)
			(fill
				(thermal_gap 0.5)
				(thermal_bridge_width 0.5)
				(island_removal_mode 0)
			)
			(polygon
				(pts
					(xy 402.869146 -42.681652) (xy 402.869146 -43.189652) (xy 403.250146 -43.189652) (xy 403.250146 -42.681652)
				)
			)
		)
		(zone
			(layer "F.Cu")
			(hatch none 0.5)
			(connect_pads
				(clearance 0)
			)
			(min_thickness 0.25)
			(keepout
				(tracks not_allowed)
				(vias allowed)
				(pads allowed)
				(copperpour not_allowed)
				(footprints allowed)
			)
			(placement
				(enabled no)
				(sheetname "")
			)
			(fill
				(thermal_gap 0.5)
				(thermal_bridge_width 0.5)
				(island_removal_mode 0)
			)
			(polygon
				(pts
					(xy 403.250146 -42.681652) (xy 403.250146 -43.189652) (xy 402.869146 -43.189652) (xy 402.869146 -42.681652)
				)
			)
		)
	)
	(footprint ""
		(layer "F.Cu")
		(at 398.8689 -87.4649 -90)
		(property "Reference" "R2P17"
			(at 0 0 270)
			(layer "F.SilkS")
			(hide yes)
			(effects
				(font
					(size 1.27 1.27)
				)
			)
		)
		(property "Value" ""
			(at 0 0 270)
			(layer "F.Fab")
			(effects
				(font
					(size 1.27 1.27)
				)
			)
		)
		(duplicate_pad_numbers_are_jumpers no)
		(fp_poly
			(pts
				(xy -0.2794 -0.1016) (xy 0.2794 -0.1016) (xy 0.2794 0.9906) (xy -0.2794 0.9906)
			)
			(stroke
				(width 0)
				(type default)
			)
			(fill no)
			(layer "F.CrtYd")
		)
		(fp_line
			(start -0.2794 0.9906)
			(end 0.2794 0.9906)
			(stroke
				(width 0.1)
				(type default)
			)
			(layer "F.Fab")
		)
		(fp_line
			(start 0.2794 0.9906)
			(end 0.2794 -0.1016)
			(stroke
				(width 0.1)
				(type default)
			)
			(layer "F.Fab")
		)
		(fp_line
			(start -0.2794 -0.1016)
			(end -0.2794 0.9906)
			(stroke
				(width 0.1)
				(type default)
			)
			(layer "F.Fab")
		)
		(fp_line
			(start 0.2794 -0.1016)
			(end -0.2794 -0.1016)
			(stroke
				(width 0.1)
				(type default)
			)
			(layer "F.Fab")
		)
		(pad "1" smd rect
			(at 0 0 270)
			(size 0.508 0.508)
			(layers "F.Cu" "F.Mask" "F.Paste")
			(net "P3V3_STBY")
		)
		(pad "2" smd rect
			(at 0 0.889 270)
			(size 0.508 0.508)
			(layers "F.Cu" "F.Mask" "F.Paste")
			(net "FM_PCH_BMC_THERMTRIP_N")
		)
		(zone
			(layer "F.Cu")
			(hatch none 0.5)
			(connect_pads
				(clearance 0)
			)
			(min_thickness 0.25)
			(keepout
				(tracks not_allowed)
				(vias allowed)
				(pads allowed)
				(copperpour not_allowed)
				(footprints allowed)
			)
			(placement
				(enabled no)
				(sheetname "")
			)
			(fill
				(thermal_gap 0.5)
				(thermal_bridge_width 0.5)
				(island_removal_mode 0)
			)
			(polygon
				(pts
					(xy 398.2339 -87.7189) (xy 398.2339 -87.2109) (xy 398.6149 -87.2109) (xy 398.6149 -87.7189)
				)
			)
		)
		(zone
			(layer "F.Cu")
			(hatch none 0.5)
			(connect_pads
				(clearance 0)
			)
			(min_thickness 0.25)
			(keepout
				(tracks allowed)
				(vias not_allowed)
				(pads allowed)
				(copperpour not_allowed)
				(footprints allowed)
			)
			(placement
				(enabled no)
				(sheetname "")
			)
			(fill
				(thermal_gap 0.5)
				(thermal_bridge_width 0.5)
				(island_removal_mode 0)
			)
			(polygon
				(pts
					(xy 398.6149 -87.7189) (xy 398.6149 -87.2109) (xy 398.2339 -87.2109) (xy 398.2339 -87.7189)
				)
			)
		)
	)
	(footprint ""
		(layer "F.Cu")
		(at 259.452872 -77.636116)
		(property "Reference" "C5D25"
			(at 0 0 0)
			(layer "F.SilkS")
			(hide yes)
			(effects
				(font
					(size 1.27 1.27)
				)
			)
		)
		(property "Value" ""
			(at 0 0 0)
			(layer "F.Fab")
			(effects
				(font
					(size 1.27 1.27)
				)
			)
		)
		(duplicate_pad_numbers_are_jumpers no)
		(fp_poly
			(pts
				(xy -0.4953 -0.2032) (xy 0.4953 -0.2032) (xy 0.4953 1.6002) (xy -0.4953 1.6002)
			)
			(stroke
				(width 0)
				(type default)
			)
			(fill no)
			(layer "F.CrtYd")
		)
		(fp_line
			(start -0.4953 -0.2032)
			(end 0.4953 -0.2032)
			(stroke
				(width 0.1)
				(type default)
			)
			(layer "F.Fab")
		)
		(fp_line
			(start -0.4953 1.6002)
			(end -0.4953 -0.2032)
			(stroke
				(width 0.1)
				(type default)
			)
			(layer "F.Fab")
		)
		(fp_line
			(start 0.4953 -0.2032)
			(end 0.4953 1.6002)
			(stroke
				(width 0.1)
				(type default)
			)
			(layer "F.Fab")
		)
		(fp_line
			(start 0.4953 1.6002)
			(end -0.4953 1.6002)
			(stroke
				(width 0.1)
				(type default)
			)
			(layer "F.Fab")
		)
		(pad "1" smd rect
			(at 0 0)
			(size 0.762 0.889)
			(layers "F.Cu" "F.Mask" "F.Paste")
			(net "PVCCIN_CPU0")
		)
		(pad "2" smd rect
			(at 0 1.397)
			(size 0.762 0.889)
			(layers "F.Cu" "F.Mask" "F.Paste")
			(net "GND")
		)
		(zone
			(layer "F.Cu")
			(hatch none 0.5)
			(connect_pads
				(clearance 0)
			)
			(min_thickness 0.25)
			(keepout
				(tracks not_allowed)
				(vias allowed)
				(pads allowed)
				(copperpour not_allowed)
				(footprints allowed)
			)
			(placement
				(enabled no)
				(sheetname "")
			)
			(fill
				(thermal_gap 0.5)
				(thermal_bridge_width 0.5)
				(island_removal_mode 0)
			)
			(polygon
				(pts
					(xy 259.071872 -77.191616) (xy 259.833872 -77.191616) (xy 259.833872 -76.683616) (xy 259.071872 -76.683616)
				)
			)
		)
	)
	(footprint ""
		(layer "F.Cu")
		(at 387.8326 -65.3034)
		(property "Reference" "C22W8"
			(at 0 0 0)
			(layer "F.SilkS")
			(hide yes)
			(effects
				(font
					(size 1.27 1.27)
				)
			)
		)
		(property "Value" "*"
			(at -0.0762 -6.2357 0)
			(unlocked yes)
			(layer "F.Fab")
			(hide yes)
			(effects
				(font
					(size 1.27 1.016)
					(thickness 0.1524)
				)
			)
		)
		(property "Device Type" "SC22U16V5MX-4-GP_SMD-BCG5-SC22A"
			(at -0.0762 -8.2677 0)
			(unlocked yes)
			(layer "F.Fab")
			(hide yes)
			(effects
				(font
					(size 1.27 1.016)
					(thickness 0.1524)
				)
			)
		)
		(duplicate_pad_numbers_are_jumpers no)
		(fp_line
			(start 0.635 0)
			(end -0.635 0)
			(stroke
				(width 0.508)
				(type default)
			)
			(layer "F.SilkS")
		)
		(fp_rect
			(start -0.9652 1.778)
			(end 0.9652 -1.778)
			(stroke
				(width 0)
				(type default)
			)
			(fill no)
			(layer "F.CrtYd")
		)
		(fp_poly
			(pts
				(xy -0.9652 -1.778) (xy 0.9652 -1.778) (xy 0.9652 1.778) (xy -0.9652 1.778)
			)
			(stroke
				(width 0)
				(type default)
			)
			(fill no)
			(layer "F.Fab")
		)
		(pad "1" smd rect
			(at 0 -0.9652)
			(size 1.397 1.143)
			(layers "F.Cu" "F.Mask" "F.Paste")
			(net "VR_FET_SW_P5V_STBY_PVIN")
		)
		(pad "2" smd rect
			(at 0 0.9652)
			(size 1.397 1.143)
			(layers "F.Cu" "F.Mask" "F.Paste")
			(net "GND")
		)
	)
	(footprint ""
		(layer "F.Cu")
		(at 178.36261 -24.961088 90)
		(property "Reference" "R12W3"
			(at 0 0 90)
			(layer "F.SilkS")
			(hide yes)
			(effects
				(font
					(size 1.27 1.27)
				)
			)
		)
		(property "Value" "*"
			(at 0.064008 -4.108196 90)
			(unlocked yes)
			(layer "F.Fab")
			(hide yes)
			(effects
				(font
					(size 1.27 1.016)
					(thickness 0.1524)
				)
			)
		)
		(property "Device Type" "4D02R2F-GP_SMD-RG2-4D02R2F-GP,A"
			(at 0.064008 -5.632196 90)
			(unlocked yes)
			(layer "F.Fab")
			(hide yes)
			(effects
				(font
					(size 1.27 1.016)
					(thickness 0.1524)
				)
			)
		)
		(duplicate_pad_numbers_are_jumpers no)
		(fp_line
			(start 0.508 -0.9398)
			(end -0.508 -0.9398)
			(stroke
				(width 0.1524)
				(type default)
			)
			(layer "F.SilkS")
		)
		(fp_line
			(start -0.508 -0.9398)
			(end -0.508 0.9398)
			(stroke
				(width 0.1524)
				(type default)
			)
			(layer "F.SilkS")
		)
		(fp_rect
			(start -0.508 0.9398)
			(end 0.508 -0.9398)
			(stroke
				(width 0)
				(type default)
			)
			(fill no)
			(layer "F.CrtYd")
		)
		(fp_rect
			(start -0.508 0.9398)
			(end 0.508 -0.9398)
			(stroke
				(width 0)
				(type default)
			)
			(fill no)
			(layer "F.Fab")
		)
		(pad "1" smd custom
			(at 0 -0.4445 90)
			(size 0.1397 0.1397)
			(layers "F.Cu" "F.Mask" "F.Paste")
			(net "P12V_STBY")
			(options
				(clearance outline)
				(anchor circle)
			)
			(primitives
				(gr_poly
					(pts
						(arc
							(start -0.1778 -0.2794)
							(mid -0.249642 -0.249642)
							(end -0.2794 -0.1778)
						)
						(arc
							(start -0.2794 0.1778)
							(mid -0.249642 0.249642)
							(end -0.1778 0.2794)
						)
						(arc
							(start 0.1778 0.2794)
							(mid 0.249642 0.249642)
							(end 0.2794 0.1778)
						)
						(arc
							(start 0.2794 -0.1778)
							(mid 0.249642 -0.249642)
							(end 0.1778 -0.2794)
						)
					)
					(width 0)
					(fill yes)
				)
			)
		)
		(pad "2" smd custom
			(at 0 0.4445 90)
			(size 0.1397 0.1397)
			(layers "F.Cu" "F.Mask" "F.Paste")
			(net "P12V_NVDIMM_ABC_D")
			(options
				(clearance outline)
				(anchor circle)
			)
			(primitives
				(gr_poly
					(pts
						(arc
							(start -0.1778 -0.2794)
							(mid -0.249642 -0.249642)
							(end -0.2794 -0.1778)
						)
						(arc
							(start -0.2794 0.1778)
							(mid -0.249642 0.249642)
							(end -0.1778 0.2794)
						)
						(arc
							(start 0.1778 0.2794)
							(mid 0.249642 0.249642)
							(end 0.2794 0.1778)
						)
						(arc
							(start 0.2794 -0.1778)
							(mid 0.249642 -0.249642)
							(end 0.1778 -0.2794)
						)
					)
					(width 0)
					(fill yes)
				)
			)
		)
	)
	(footprint ""
		(layer "F.Cu")
		(at 5.602732 2.141474 90)
		(property "Reference" "RF20"
			(at -0.8382 -0.67818 90)
			(unlocked yes)
			(layer "F.SilkS")
			(effects
				(font
					(size 0.4064 0.254)
					(thickness 0.1524)
				)
				(justify left)
			)
		)
		(property "Value" ""
			(at 0 0 90)
			(layer "F.Fab")
			(effects
				(font
					(size 1.27 1.27)
				)
			)
		)
		(duplicate_pad_numbers_are_jumpers no)
		(fp_poly
			(pts
				(xy -0.2794 -0.1016) (xy 0.2794 -0.1016) (xy 0.2794 0.9906) (xy -0.2794 0.9906)
			)
			(stroke
				(width 0)
				(type default)
			)
			(fill no)
			(layer "F.CrtYd")
		)
		(fp_line
			(start 0.2794 -0.1016)
			(end -0.2794 -0.1016)
			(stroke
				(width 0.1)
				(type default)
			)
			(layer "F.Fab")
		)
		(fp_line
			(start -0.2794 -0.1016)
			(end -0.2794 0.9906)
			(stroke
				(width 0.1)
				(type default)
			)
			(layer "F.Fab")
		)
		(fp_line
			(start 0.2794 0.9906)
			(end 0.2794 -0.1016)
			(stroke
				(width 0.1)
				(type default)
			)
			(layer "F.Fab")
		)
		(fp_line
			(start -0.2794 0.9906)
			(end 0.2794 0.9906)
			(stroke
				(width 0.1)
				(type default)
			)
			(layer "F.Fab")
		)
		(pad "1" smd rect
			(at 0 0 90)
			(size 0.508 0.508)
			(layers "F.Cu" "F.Mask" "F.Paste")
			(net "VR_PVDDQ_GHJ_AIREF2")
		)
		(pad "2" smd rect
			(at 0 0.889 90)
			(size 0.508 0.508)
			(layers "F.Cu" "F.Mask" "F.Paste")
			(net "ISENSE_PVDDQ_GHJ_PH2_IMON")
		)
		(zone
			(layer "F.Cu")
			(hatch none 0.5)
			(connect_pads
				(clearance 0)
			)
			(min_thickness 0.25)
			(keepout
				(tracks allowed)
				(vias not_allowed)
				(pads allowed)
				(copperpour not_allowed)
				(footprints allowed)
			)
			(placement
				(enabled no)
				(sheetname "")
			)
			(fill
				(thermal_gap 0.5)
				(thermal_bridge_width 0.5)
				(island_removal_mode 0)
			)
			(polygon
				(pts
					(xy 5.856732 2.395474) (xy 5.856732 1.887474) (xy 6.237732 1.887474) (xy 6.237732 2.395474)
				)
			)
		)
		(zone
			(layer "F.Cu")
			(hatch none 0.5)
			(connect_pads
				(clearance 0)
			)
			(min_thickness 0.25)
			(keepout
				(tracks not_allowed)
				(vias allowed)
				(pads allowed)
				(copperpour not_allowed)
				(footprints allowed)
			)
			(placement
				(enabled no)
				(sheetname "")
			)
			(fill
				(thermal_gap 0.5)
				(thermal_bridge_width 0.5)
				(island_removal_mode 0)
			)
			(polygon
				(pts
					(xy 6.237732 2.395474) (xy 6.237732 1.887474) (xy 5.856732 1.887474) (xy 5.856732 2.395474)
				)
			)
		)
	)
	(footprint ""
		(layer "F.Cu")
		(at 33.278826 -85.7377 90)
		(property "Reference" "C1D33"
			(at 0 0 90)
			(layer "F.SilkS")
			(hide yes)
			(effects
				(font
					(size 1.27 1.27)
				)
			)
		)
		(property "Value" ""
			(at 0 0 90)
			(layer "F.Fab")
			(effects
				(font
					(size 1.27 1.27)
				)
			)
		)
		(duplicate_pad_numbers_are_jumpers no)
		(fp_rect
			(start 0.3048 0.9906)
			(end -0.3048 -0.1016)
			(stroke
				(width 0)
				(type default)
			)
			(fill no)
			(layer "F.CrtYd")
		)
		(fp_line
			(start 0.3048 -0.1016)
			(end -0.3048 -0.1016)
			(stroke
				(width 0.1)
				(type default)
			)
			(layer "F.Fab")
		)
		(fp_line
			(start -0.3048 -0.1016)
			(end -0.3048 0.9906)
			(stroke
				(width 0.1)
				(type default)
			)
			(layer "F.Fab")
		)
		(fp_line
			(start 0.3048 0.9906)
			(end 0.3048 -0.1016)
			(stroke
				(width 0.1)
				(type default)
			)
			(layer "F.Fab")
		)
		(fp_line
			(start -0.3048 0.9906)
			(end 0.3048 0.9906)
			(stroke
				(width 0.1)
				(type default)
			)
			(layer "F.Fab")
		)
		(pad "1" smd rect
			(at 0 0 90)
			(size 0.508 0.508)
			(layers "F.Cu" "F.Mask" "F.Paste")
			(net "P5V_STBY")
		)
		(pad "2" smd rect
			(at 0 0.889 90)
			(size 0.508 0.508)
			(layers "F.Cu" "F.Mask" "F.Paste")
			(net "GND")
		)
		(zone
			(layer "F.Cu")
			(hatch none 0.5)
			(connect_pads
				(clearance 0)
			)
			(min_thickness 0.25)
			(keepout
				(tracks not_allowed)
				(vias allowed)
				(pads allowed)
				(copperpour not_allowed)
				(footprints allowed)
			)
			(placement
				(enabled no)
				(sheetname "")
			)
			(fill
				(thermal_gap 0.5)
				(thermal_bridge_width 0.5)
				(island_removal_mode 0)
			)
			(polygon
				(pts
					(xy 33.913826 -85.9917) (xy 33.532826 -85.9917) (xy 33.532826 -85.4837) (xy 33.913826 -85.4837)
				)
			)
		)
		(zone
			(layer "F.Cu")
			(hatch none 0.5)
			(connect_pads
				(clearance 0)
			)
			(min_thickness 0.25)
			(keepout
				(tracks allowed)
				(vias not_allowed)
				(pads allowed)
				(copperpour not_allowed)
				(footprints allowed)
			)
			(placement
				(enabled no)
				(sheetname "")
			)
			(fill
				(thermal_gap 0.5)
				(thermal_bridge_width 0.5)
				(island_removal_mode 0)
			)
			(polygon
				(pts
					(xy 33.913826 -85.9917) (xy 33.532826 -85.9917) (xy 33.532826 -85.4837) (xy 33.913826 -85.4837)
				)
			)
		)
	)
	(footprint ""
		(layer "F.Cu")
		(at 29.699458 -142.6718 90)
		(property "Reference" "J1A2"
			(at -2.623312 42.436542 0)
			(unlocked yes)
			(layer "F.SilkS")
			(effects
				(font
					(size 0.7874 0.5842)
					(thickness 0.1524)
				)
				(justify left)
			)
		)
		(property "Value" ""
			(at 0 0 90)
			(layer "F.Fab")
			(effects
				(font
					(size 1.27 1.27)
				)
			)
		)
		(duplicate_pad_numbers_are_jumpers no)
		(fp_line
			(start 5.5499 -7.675118)
			(end 5.5499 -1.480058)
			(stroke
				(width 0.1524)
				(type default)
			)
			(layer "F.SilkS")
		)
		(fp_line
			(start -0.94996 -7.675118)
			(end 5.5499 -7.675118)
			(stroke
				(width 0.1524)
				(type default)
			)
			(layer "F.SilkS")
		)
		(fp_line
			(start -0.94996 -1.480058)
			(end -0.94996 -7.675118)
			(stroke
				(width 0.1524)
				(type default)
			)
			(layer "F.SilkS")
		)
		(fp_line
			(start 5.5499 128.130046)
			(end 5.5499 134.325106)
			(stroke
				(width 0.1524)
				(type default)
			)
			(layer "F.SilkS")
		)
		(fp_line
			(start 5.5499 134.325106)
			(end -0.94996 134.325106)
			(stroke
				(width 0.1524)
				(type default)
			)
			(layer "F.SilkS")
		)
		(fp_line
			(start -0.94996 134.325106)
			(end -0.94996 128.130046)
			(stroke
				(width 0.1524)
				(type default)
			)
			(layer "F.SilkS")
		)
		(fp_poly
			(pts
				(xy -2.939288 -0.536448) (xy -2.939288 0.479552) (xy -1.669288 -0.028448)
			)
			(stroke
				(width 0)
				(type default)
			)
			(fill yes)
			(layer "F.SilkS")
		)
		(fp_poly
			(pts
				(xy -0.94996 -7.675118) (xy -0.94996 134.325106) (xy 5.5499 134.325106) (xy 5.5499 -7.675118)
			)
			(stroke
				(width 0)
				(type default)
			)
			(fill no)
			(layer "F.CrtYd")
		)
		(fp_line
			(start 5.5499 -7.675118)
			(end 5.5499 134.325106)
			(stroke
				(width 0.1)
				(type default)
			)
			(layer "F.Fab")
		)
		(fp_line
			(start -0.94996 -7.675118)
			(end 5.5499 -7.675118)
			(stroke
				(width 0.1)
				(type default)
			)
			(layer "F.Fab")
		)
		(fp_line
			(start 5.5499 134.325106)
			(end -0.94996 134.325106)
			(stroke
				(width 0.1)
				(type default)
			)
			(layer "F.Fab")
		)
		(fp_line
			(start -0.94996 134.325106)
			(end -0.94996 -7.675118)
			(stroke
				(width 0.1)
				(type default)
			)
			(layer "F.Fab")
		)
		(fp_poly
			(pts
				(xy -2.984246 -0.461264) (xy -2.984246 0.554736) (xy -1.714246 0.046736)
			)
			(stroke
				(width 0)
				(type default)
			)
			(fill yes)
			(layer "F.Fab")
		)
		(fp_text user "145"
			(at 6.045708 0.191262 0)
			(unlocked yes)
			(layer "F.SilkS")
			(effects
				(font
					(size 0.7874 0.5842)
					(thickness 0.1524)
				)
				(justify left)
			)
		)
		(fp_text user "221"
			(at 5.86613 64.953642 0)
			(unlocked yes)
			(layer "F.SilkS")
			(effects
				(font
					(size 0.7874 0.5842)
					(thickness 0.1524)
				)
				(justify left)
			)
		)
		(fp_text user "77"
			(at -1.464056 66.433446 0)
			(unlocked yes)
			(layer "F.SilkS")
			(effects
				(font
					(size 0.7874 0.5842)
					(thickness 0.1524)
				)
				(justify left)
			)
		)
		(fp_text user "78"
			(at -1.540256 69.680074 0)
			(unlocked yes)
			(layer "F.SilkS")
			(effects
				(font
					(size 0.7874 0.5842)
					(thickness 0.1524)
				)
				(justify left)
			)
		)
		(fp_text user "222"
			(at 6.068822 70.107556 0)
			(unlocked yes)
			(layer "F.SilkS")
			(effects
				(font
					(size 0.7874 0.5842)
					(thickness 0.1524)
				)
				(justify left)
			)
		)
		(fp_text user "288"
			(at 6.266688 127.958342 0)
			(unlocked yes)
			(layer "F.SilkS")
			(effects
				(font
					(size 0.7874 0.5842)
					(thickness 0.1524)
				)
				(justify left)
			)
		)
		(fp_text user "144"
			(at -1.683512 128.059942 0)
			(unlocked yes)
			(layer "F.SilkS")
			(effects
				(font
					(size 0.7874 0.5842)
					(thickness 0.1524)
				)
				(justify left)
			)
		)
		(fp_text user "145"
			(at -1.736852 6.940042 0)
			(unlocked yes)
			(layer "F.Fab")
			(effects
				(font
					(size 0.7874 0.5842)
					(thickness 0.1524)
				)
				(justify left)
			)
		)
		(fp_text user "221"
			(at 3.372358 65.831212 90)
			(unlocked yes)
			(layer "F.Fab")
			(effects
				(font
					(size 0.7874 0.5842)
					(thickness 0.1524)
				)
				(justify left)
			)
		)
		(fp_text user "77"
			(at -0.437642 65.831212 90)
			(unlocked yes)
			(layer "F.Fab")
			(effects
				(font
					(size 0.7874 0.5842)
					(thickness 0.1524)
				)
				(justify left)
			)
		)
		(fp_text user "78"
			(at -0.767842 69.438012 90)
			(unlocked yes)
			(layer "F.Fab")
			(effects
				(font
					(size 0.7874 0.5842)
					(thickness 0.1524)
				)
				(justify left)
			)
		)
		(fp_text user "222"
			(at 2.961894 70.186042 0)
			(unlocked yes)
			(layer "F.Fab")
			(effects
				(font
					(size 0.7874 0.5842)
					(thickness 0.1524)
				)
				(justify left)
			)
		)
		(fp_text user "288"
			(at 3.372358 128.061212 90)
			(unlocked yes)
			(layer "F.Fab")
			(effects
				(font
					(size 0.7874 0.5842)
					(thickness 0.1524)
				)
				(justify left)
			)
		)
		(fp_text user "144"
			(at -0.437642 128.061212 90)
			(unlocked yes)
			(layer "F.Fab")
			(effects
				(font
					(size 0.7874 0.5842)
					(thickness 0.1524)
				)
				(justify left)
			)
		)
		(pad "" thru_hole circle
			(at 2.29997 -5.649976 90)
			(size 2.8194 2.8194)
			(drill 2.4384)
			(layers "*.Cu" "*.Mask")
			(remove_unused_layers no)
			(clearance 0.127)
			(thermal_gap 0.127)
		)
		(pad "" thru_hole oval
			(at 2.29997 68.90004 90)
			(size 2.8194 1.5748)
			(drill oval 2.4384 1.1938)
			(layers "*.Cu" "*.Mask")
			(remove_unused_layers no)
			(clearance 0.127)
			(thermal_gap 0.127)
		)
		(pad "" thru_hole circle
			(at 2.29997 132.299964 90)
			(size 2.8194 2.8194)
			(drill 2.4384)
			(layers "*.Cu" "*.Mask")
			(remove_unused_layers no)
			(clearance 0.127)
			(thermal_gap 0.127)
		)
		(pad "1" smd rect
			(at 0 0 90)
			(size 1.8034 0.508)
			(layers "F.Cu" "F.Mask" "F.Paste")
			(net "P12V_NVDIMM_KLM")
		)
		(pad "2" smd rect
			(at 0 0.849884 90)
			(size 1.8034 0.508)
			(layers "F.Cu" "F.Mask" "F.Paste")
			(net "GND")
		)
		(pad "3" smd rect
			(at 0 1.700022 90)
			(size 1.8034 0.508)
			(layers "F.Cu" "F.Mask" "F.Paste")
			(net "M_L_DQ<5>")
		)
		(pad "4" smd rect
			(at 0 2.549906 90)
			(size 1.8034 0.508)
			(layers "F.Cu" "F.Mask" "F.Paste")
			(net "GND")
		)
		(pad "5" smd rect
			(at 0 3.400044 90)
			(size 1.8034 0.508)
			(layers "F.Cu" "F.Mask" "F.Paste")
			(net "M_L_DQ<1>")
		)
		(pad "6" smd rect
			(at 0 4.249928 90)
			(size 1.8034 0.508)
			(layers "F.Cu" "F.Mask" "F.Paste")
			(net "GND")
		)
		(pad "7" smd rect
			(at 0 5.100066 90)
			(size 1.8034 0.508)
			(layers "F.Cu" "F.Mask" "F.Paste")
			(net "M_L_DQS_DP<9>")
		)
		(pad "8" smd rect
			(at 0 5.94995 90)
			(size 1.8034 0.508)
			(layers "F.Cu" "F.Mask" "F.Paste")
			(net "M_L_DQS_DN<9>")
		)
		(pad "9" smd rect
			(at 0 6.800088 90)
			(size 1.8034 0.508)
			(layers "F.Cu" "F.Mask" "F.Paste")
			(net "GND")
		)
		(pad "10" smd rect
			(at 0 7.649972 90)
			(size 1.8034 0.508)
			(layers "F.Cu" "F.Mask" "F.Paste")
			(net "M_L_DQ<7>")
		)
		(pad "11" smd rect
			(at 0 8.50011 90)
			(size 1.8034 0.508)
			(layers "F.Cu" "F.Mask" "F.Paste")
			(net "GND")
		)
		(pad "12" smd rect
			(at 0 9.349994 90)
			(size 1.8034 0.508)
			(layers "F.Cu" "F.Mask" "F.Paste")
			(net "M_L_DQ<3>")
		)
		(pad "13" smd rect
			(at 0 10.199878 90)
			(size 1.8034 0.508)
			(layers "F.Cu" "F.Mask" "F.Paste")
			(net "GND")
		)
		(pad "14" smd rect
			(at 0 11.050016 90)
			(size 1.8034 0.508)
			(layers "F.Cu" "F.Mask" "F.Paste")
			(net "M_L_DQ<13>")
		)
		(pad "15" smd rect
			(at 0 11.8999 90)
			(size 1.8034 0.508)
			(layers "F.Cu" "F.Mask" "F.Paste")
			(net "GND")
		)
		(pad "16" smd rect
			(at 0 12.750038 90)
			(size 1.8034 0.508)
			(layers "F.Cu" "F.Mask" "F.Paste")
			(net "M_L_DQ<9>")
		)
		(pad "17" smd rect
			(at 0 13.599922 90)
			(size 1.8034 0.508)
			(layers "F.Cu" "F.Mask" "F.Paste")
			(net "GND")
		)
		(pad "18" smd rect
			(at 0 14.45006 90)
			(size 1.8034 0.508)
			(layers "F.Cu" "F.Mask" "F.Paste")
			(net "M_L_DQS_DP<10>")
		)
		(pad "19" smd rect
			(at 0 15.299944 90)
			(size 1.8034 0.508)
			(layers "F.Cu" "F.Mask" "F.Paste")
			(net "M_L_DQS_DN<10>")
		)
		(pad "20" smd rect
			(at 0 16.150082 90)
			(size 1.8034 0.508)
			(layers "F.Cu" "F.Mask" "F.Paste")
			(net "GND")
		)
		(pad "21" smd rect
			(at 0 16.999966 90)
			(size 1.8034 0.508)
			(layers "F.Cu" "F.Mask" "F.Paste")
			(net "M_L_DQ<15>")
		)
		(pad "22" smd rect
			(at 0 17.850104 90)
			(size 1.8034 0.508)
			(layers "F.Cu" "F.Mask" "F.Paste")
			(net "GND")
		)
		(pad "23" smd rect
			(at 0 18.699988 90)
			(size 1.8034 0.508)
			(layers "F.Cu" "F.Mask" "F.Paste")
			(net "M_L_DQ<11>")
		)
		(pad "24" smd rect
			(at 0 19.550126 90)
			(size 1.8034 0.508)
			(layers "F.Cu" "F.Mask" "F.Paste")
			(net "GND")
		)
		(pad "25" smd rect
			(at 0 20.40001 90)
			(size 1.8034 0.508)
			(layers "F.Cu" "F.Mask" "F.Paste")
			(net "M_L_DQ<21>")
		)
		(pad "26" smd rect
			(at 0 21.249894 90)
			(size 1.8034 0.508)
			(layers "F.Cu" "F.Mask" "F.Paste")
			(net "GND")
		)
		(pad "27" smd rect
			(at 0 22.100032 90)
			(size 1.8034 0.508)
			(layers "F.Cu" "F.Mask" "F.Paste")
			(net "M_L_DQ<17>")
		)
		(pad "28" smd rect
			(at 0 22.949916 90)
			(size 1.8034 0.508)
			(layers "F.Cu" "F.Mask" "F.Paste")
			(net "GND")
		)
		(pad "29" smd rect
			(at 0 23.800054 90)
			(size 1.8034 0.508)
			(layers "F.Cu" "F.Mask" "F.Paste")
			(net "M_L_DQS_DP<11>")
		)
		(pad "30" smd rect
			(at 0 24.649938 90)
			(size 1.8034 0.508)
			(layers "F.Cu" "F.Mask" "F.Paste")
			(net "M_L_DQS_DN<11>")
		)
		(pad "31" smd rect
			(at 0 25.500076 90)
			(size 1.8034 0.508)
			(layers "F.Cu" "F.Mask" "F.Paste")
			(net "GND")
		)
		(pad "32" smd rect
			(at 0 26.34996 90)
			(size 1.8034 0.508)
			(layers "F.Cu" "F.Mask" "F.Paste")
			(net "M_L_DQ<23>")
		)
		(pad "33" smd rect
			(at 0 27.200098 90)
			(size 1.8034 0.508)
			(layers "F.Cu" "F.Mask" "F.Paste")
			(net "GND")
		)
		(pad "34" smd rect
			(at 0 28.049982 90)
			(size 1.8034 0.508)
			(layers "F.Cu" "F.Mask" "F.Paste")
			(net "M_L_DQ<19>")
		)
		(pad "35" smd rect
			(at 0 28.90012 90)
			(size 1.8034 0.508)
			(layers "F.Cu" "F.Mask" "F.Paste")
			(net "GND")
		)
		(pad "36" smd rect
			(at 0 29.750004 90)
			(size 1.8034 0.508)
			(layers "F.Cu" "F.Mask" "F.Paste")
			(net "M_L_DQ<29>")
		)
		(pad "37" smd rect
			(at 0 30.599888 90)
			(size 1.8034 0.508)
			(layers "F.Cu" "F.Mask" "F.Paste")
			(net "GND")
		)
		(pad "38" smd rect
			(at 0 31.450026 90)
			(size 1.8034 0.508)
			(layers "F.Cu" "F.Mask" "F.Paste")
			(net "M_L_DQ<25>")
		)
		(pad "39" smd rect
			(at 0 32.29991 90)
			(size 1.8034 0.508)
			(layers "F.Cu" "F.Mask" "F.Paste")
			(net "GND")
		)
		(pad "40" smd rect
			(at 0 33.150048 90)
			(size 1.8034 0.508)
			(layers "F.Cu" "F.Mask" "F.Paste")
			(net "M_L_DQS_DP<12>")
		)
		(pad "41" smd rect
			(at 0 33.999932 90)
			(size 1.8034 0.508)
			(layers "F.Cu" "F.Mask" "F.Paste")
			(net "M_L_DQS_DN<12>")
		)
		(pad "42" smd rect
			(at 0 34.85007 90)
			(size 1.8034 0.508)
			(layers "F.Cu" "F.Mask" "F.Paste")
			(net "GND")
		)
		(pad "43" smd rect
			(at 0 35.699954 90)
			(size 1.8034 0.508)
			(layers "F.Cu" "F.Mask" "F.Paste")
			(net "M_L_DQ<31>")
		)
		(pad "44" smd rect
			(at 0 36.550092 90)
			(size 1.8034 0.508)
			(layers "F.Cu" "F.Mask" "F.Paste")
			(net "GND")
		)
		(pad "45" smd rect
			(at 0 37.399976 90)
			(size 1.8034 0.508)
			(layers "F.Cu" "F.Mask" "F.Paste")
			(net "M_L_DQ<27>")
		)
		(pad "46" smd rect
			(at 0 38.250114 90)
			(size 1.8034 0.508)
			(layers "F.Cu" "F.Mask" "F.Paste")
			(net "GND")
		)
		(pad "47" smd rect
			(at 0 39.099998 90)
			(size 1.8034 0.508)
			(layers "F.Cu" "F.Mask" "F.Paste")
			(net "M_L_ECC<5>")
		)
		(pad "48" smd rect
			(at 0 39.949882 90)
			(size 1.8034 0.508)
			(layers "F.Cu" "F.Mask" "F.Paste")
			(net "GND")
		)
		(pad "49" smd rect
			(at 0 40.80002 90)
			(size 1.8034 0.508)
			(layers "F.Cu" "F.Mask" "F.Paste")
			(net "M_L_ECC<1>")
		)
		(pad "50" smd rect
			(at 0 41.649904 90)
			(size 1.8034 0.508)
			(layers "F.Cu" "F.Mask" "F.Paste")
			(net "GND")
		)
		(pad "51" smd rect
			(at 0 42.500042 90)
			(size 1.8034 0.508)
			(layers "F.Cu" "F.Mask" "F.Paste")
			(net "M_L_DQS_DP<17>")
		)
		(pad "52" smd rect
			(at 0 43.349926 90)
			(size 1.8034 0.508)
			(layers "F.Cu" "F.Mask" "F.Paste")
			(net "M_L_DQS_DN<17>")
		)
		(pad "53" smd rect
			(at 0 44.200064 90)
			(size 1.8034 0.508)
			(layers "F.Cu" "F.Mask" "F.Paste")
			(net "GND")
		)
		(pad "54" smd rect
			(at 0 45.049948 90)
			(size 1.8034 0.508)
			(layers "F.Cu" "F.Mask" "F.Paste")
			(net "M_L_ECC<7>")
		)
		(pad "55" smd rect
			(at 0 45.900086 90)
			(size 1.8034 0.508)
			(layers "F.Cu" "F.Mask" "F.Paste")
			(net "GND")
		)
		(pad "56" smd rect
			(at 0 46.74997 90)
			(size 1.8034 0.508)
			(layers "F.Cu" "F.Mask" "F.Paste")
			(net "M_L_ECC<3>")
		)
		(pad "57" smd rect
			(at 0 47.600108 90)
			(size 1.8034 0.508)
			(layers "F.Cu" "F.Mask" "F.Paste")
			(net "GND")
		)
		(pad "58" smd rect
			(at 0 48.449992 90)
			(size 1.8034 0.508)
			(layers "F.Cu" "F.Mask" "F.Paste")
			(net "M_KLM_RST_N")
		)
		(pad "59" smd rect
			(at 0 49.299876 90)
			(size 1.8034 0.508)
			(layers "F.Cu" "F.Mask" "F.Paste")
			(net "PVDDQ_KLM")
		)
		(pad "60" smd rect
			(at 0 50.150014 90)
			(size 1.8034 0.508)
			(layers "F.Cu" "F.Mask" "F.Paste")
			(net "M_L_CKE<0>")
		)
		(pad "61" smd rect
			(at 0 50.999898 90)
			(size 1.8034 0.508)
			(layers "F.Cu" "F.Mask" "F.Paste")
			(net "PVDDQ_KLM")
		)
		(pad "62" smd rect
			(at 0 51.850036 90)
			(size 1.8034 0.508)
			(layers "F.Cu" "F.Mask" "F.Paste")
			(net "M_L_ACT_N")
		)
		(pad "63" smd rect
			(at 0 52.69992 90)
			(size 1.8034 0.508)
			(layers "F.Cu" "F.Mask" "F.Paste")
			(net "M_L_BG<0>")
		)
		(pad "64" smd rect
			(at 0 53.550058 90)
			(size 1.8034 0.508)
			(layers "F.Cu" "F.Mask" "F.Paste")
			(net "PVDDQ_KLM")
		)
		(pad "65" smd rect
			(at 0 54.399942 90)
			(size 1.8034 0.508)
			(layers "F.Cu" "F.Mask" "F.Paste")
			(net "M_L_MA<12>")
		)
		(pad "66" smd rect
			(at 0 55.25008 90)
			(size 1.8034 0.508)
			(layers "F.Cu" "F.Mask" "F.Paste")
			(net "M_L_MA<9>")
		)
		(pad "67" smd rect
			(at 0 56.099964 90)
			(size 1.8034 0.508)
			(layers "F.Cu" "F.Mask" "F.Paste")
			(net "PVDDQ_KLM")
		)
		(pad "68" smd rect
			(at 0 56.950102 90)
			(size 1.8034 0.508)
			(layers "F.Cu" "F.Mask" "F.Paste")
			(net "M_L_MA<8>")
		)
		(pad "69" smd rect
			(at 0 57.799986 90)
			(size 1.8034 0.508)
			(layers "F.Cu" "F.Mask" "F.Paste")
			(net "M_L_MA<6>")
		)
		(pad "70" smd rect
			(at 0 58.650124 90)
			(size 1.8034 0.508)
			(layers "F.Cu" "F.Mask" "F.Paste")
			(net "PVDDQ_KLM")
		)
		(pad "71" smd rect
			(at 0 59.500008 90)
			(size 1.8034 0.508)
			(layers "F.Cu" "F.Mask" "F.Paste")
			(net "M_L_MA<3>")
		)
		(pad "72" smd rect
			(at 0 60.349892 90)
			(size 1.8034 0.508)
			(layers "F.Cu" "F.Mask" "F.Paste")
			(net "M_L_MA<1>")
		)
		(pad "73" smd rect
			(at 0 61.20003 90)
			(size 1.8034 0.508)
			(layers "F.Cu" "F.Mask" "F.Paste")
			(net "PVDDQ_KLM")
		)
		(pad "74" smd rect
			(at 0 62.049914 90)
			(size 1.8034 0.508)
			(layers "F.Cu" "F.Mask" "F.Paste")
			(net "M_L_CLK_DP<0>")
		)
		(pad "75" smd rect
			(at 0 62.900052 90)
			(size 1.8034 0.508)
			(layers "F.Cu" "F.Mask" "F.Paste")
			(net "M_L_CLK_DN<0>")
		)
		(pad "76" smd rect
			(at 0 63.749936 90)
			(size 1.8034 0.508)
			(layers "F.Cu" "F.Mask" "F.Paste")
			(net "PVDDQ_KLM")
		)
		(pad "77" smd rect
			(at 0 64.600074 90)
			(size 1.8034 0.508)
			(layers "F.Cu" "F.Mask" "F.Paste")
			(net "PVTT_KLM")
		)
		(pad "78" smd rect
			(at 0 70.550024 90)
			(size 1.8034 0.508)
			(layers "F.Cu" "F.Mask" "F.Paste")
			(net "FM_DIMM_EVENT_COD_N")
		)
		(pad "79" smd rect
			(at 0 71.399908 90)
			(size 1.8034 0.508)
			(layers "F.Cu" "F.Mask" "F.Paste")
			(net "M_L_MA<0>")
		)
		(pad "80" smd rect
			(at 0 72.250046 90)
			(size 1.8034 0.508)
			(layers "F.Cu" "F.Mask" "F.Paste")
			(net "PVDDQ_KLM")
		)
		(pad "81" smd rect
			(at 0 73.09993 90)
			(size 1.8034 0.508)
			(layers "F.Cu" "F.Mask" "F.Paste")
			(net "M_L_BA<0>")
		)
		(pad "82" smd rect
			(at 0 73.950068 90)
			(size 1.8034 0.508)
			(layers "F.Cu" "F.Mask" "F.Paste")
			(net "M_L_MA<16>")
		)
		(pad "83" smd rect
			(at 0 74.799952 90)
			(size 1.8034 0.508)
			(layers "F.Cu" "F.Mask" "F.Paste")
			(net "PVDDQ_KLM")
		)
		(pad "84" smd rect
			(at 0 75.65009 90)
			(size 1.8034 0.508)
			(layers "F.Cu" "F.Mask" "F.Paste")
			(net "M_L_CS_N<0>")
		)
		(pad "85" smd rect
			(at 0 76.499974 90)
			(size 1.8034 0.508)
			(layers "F.Cu" "F.Mask" "F.Paste")
			(net "PVDDQ_KLM")
		)
		(pad "86" smd rect
			(at 0 77.350112 90)
			(size 1.8034 0.508)
			(layers "F.Cu" "F.Mask" "F.Paste")
			(net "M_L_MA<15>")
		)
		(pad "87" smd rect
			(at 0 78.199996 90)
			(size 1.8034 0.508)
			(layers "F.Cu" "F.Mask" "F.Paste")
			(net "M_L_ODT<0>")
		)
		(pad "88" smd rect
			(at 0 79.04988 90)
			(size 1.8034 0.508)
			(layers "F.Cu" "F.Mask" "F.Paste")
			(net "PVDDQ_KLM")
		)
		(pad "89" smd rect
			(at 0 79.900018 90)
			(size 1.8034 0.508)
			(layers "F.Cu" "F.Mask" "F.Paste")
			(net "M_L_CS_N<1>")
		)
		(pad "90" smd rect
			(at 0 80.749902 90)
			(size 1.8034 0.508)
			(layers "F.Cu" "F.Mask" "F.Paste")
			(net "PVDDQ_KLM")
		)
		(pad "91" smd rect
			(at 0 81.60004 90)
			(size 1.8034 0.508)
			(layers "F.Cu" "F.Mask" "F.Paste")
			(net "M_L_ODT<1>")
		)
		(pad "92" smd rect
			(at 0 82.449924 90)
			(size 1.8034 0.508)
			(layers "F.Cu" "F.Mask" "F.Paste")
			(net "PVDDQ_KLM")
		)
		(pad "93" smd rect
			(at 0 83.300062 90)
			(size 1.8034 0.508)
			(layers "F.Cu" "F.Mask" "F.Paste")
			(net "M_L_CS_N<2>")
		)
		(pad "94" smd rect
			(at 0 84.149946 90)
			(size 1.8034 0.508)
			(layers "F.Cu" "F.Mask" "F.Paste")
			(net "GND")
		)
		(pad "95" smd rect
			(at 0 85.000084 90)
			(size 1.8034 0.508)
			(layers "F.Cu" "F.Mask" "F.Paste")
			(net "M_L_DQ<37>")
		)
		(pad "96" smd rect
			(at 0 85.849968 90)
			(size 1.8034 0.508)
			(layers "F.Cu" "F.Mask" "F.Paste")
			(net "GND")
		)
		(pad "97" smd rect
			(at 0 86.700106 90)
			(size 1.8034 0.508)
			(layers "F.Cu" "F.Mask" "F.Paste")
			(net "M_L_DQ<33>")
		)
		(pad "98" smd rect
			(at 0 87.54999 90)
			(size 1.8034 0.508)
			(layers "F.Cu" "F.Mask" "F.Paste")
			(net "GND")
		)
		(pad "99" smd rect
			(at 0 88.399874 90)
			(size 1.8034 0.508)
			(layers "F.Cu" "F.Mask" "F.Paste")
			(net "M_L_DQS_DP<13>")
		)
		(pad "100" smd rect
			(at 0 89.250012 90)
			(size 1.8034 0.508)
			(layers "F.Cu" "F.Mask" "F.Paste")
			(net "M_L_DQS_DN<13>")
		)
		(pad "101" smd rect
			(at 0 90.099896 90)
			(size 1.8034 0.508)
			(layers "F.Cu" "F.Mask" "F.Paste")
			(net "GND")
		)
		(pad "102" smd rect
			(at 0 90.950034 90)
			(size 1.8034 0.508)
			(layers "F.Cu" "F.Mask" "F.Paste")
			(net "M_L_DQ<39>")
		)
		(pad "103" smd rect
			(at 0 91.799918 90)
			(size 1.8034 0.508)
			(layers "F.Cu" "F.Mask" "F.Paste")
			(net "GND")
		)
		(pad "104" smd rect
			(at 0 92.650056 90)
			(size 1.8034 0.508)
			(layers "F.Cu" "F.Mask" "F.Paste")
			(net "M_L_DQ<35>")
		)
		(pad "105" smd rect
			(at 0 93.49994 90)
			(size 1.8034 0.508)
			(layers "F.Cu" "F.Mask" "F.Paste")
			(net "GND")
		)
		(pad "106" smd rect
			(at 0 94.350078 90)
			(size 1.8034 0.508)
			(layers "F.Cu" "F.Mask" "F.Paste")
			(net "M_L_DQ<45>")
		)
		(pad "107" smd rect
			(at 0 95.199962 90)
			(size 1.8034 0.508)
			(layers "F.Cu" "F.Mask" "F.Paste")
			(net "GND")
		)
		(pad "108" smd rect
			(at 0 96.0501 90)
			(size 1.8034 0.508)
			(layers "F.Cu" "F.Mask" "F.Paste")
			(net "M_L_DQ<41>")
		)
		(pad "109" smd rect
			(at 0 96.899984 90)
			(size 1.8034 0.508)
			(layers "F.Cu" "F.Mask" "F.Paste")
			(net "GND")
		)
		(pad "110" smd rect
			(at 0 97.750122 90)
			(size 1.8034 0.508)
			(layers "F.Cu" "F.Mask" "F.Paste")
			(net "M_L_DQS_DP<14>")
		)
		(pad "111" smd rect
			(at 0 98.600006 90)
			(size 1.8034 0.508)
			(layers "F.Cu" "F.Mask" "F.Paste")
			(net "M_L_DQS_DN<14>")
		)
		(pad "112" smd rect
			(at 0 99.44989 90)
			(size 1.8034 0.508)
			(layers "F.Cu" "F.Mask" "F.Paste")
			(net "GND")
		)
		(pad "113" smd rect
			(at 0 100.300028 90)
			(size 1.8034 0.508)
			(layers "F.Cu" "F.Mask" "F.Paste")
			(net "M_L_DQ<47>")
		)
		(pad "114" smd rect
			(at 0 101.149912 90)
			(size 1.8034 0.508)
			(layers "F.Cu" "F.Mask" "F.Paste")
			(net "GND")
		)
		(pad "115" smd rect
			(at 0 102.00005 90)
			(size 1.8034 0.508)
			(layers "F.Cu" "F.Mask" "F.Paste")
			(net "M_L_DQ<43>")
		)
		(pad "116" smd rect
			(at 0 102.849934 90)
			(size 1.8034 0.508)
			(layers "F.Cu" "F.Mask" "F.Paste")
			(net "GND")
		)
		(pad "117" smd rect
			(at 0 103.700072 90)
			(size 1.8034 0.508)
			(layers "F.Cu" "F.Mask" "F.Paste")
			(net "M_L_DQ<53>")
		)
		(pad "118" smd rect
			(at 0 104.549956 90)
			(size 1.8034 0.508)
			(layers "F.Cu" "F.Mask" "F.Paste")
			(net "GND")
		)
		(pad "119" smd rect
			(at 0 105.400094 90)
			(size 1.8034 0.508)
			(layers "F.Cu" "F.Mask" "F.Paste")
			(net "M_L_DQ<49>")
		)
		(pad "120" smd rect
			(at 0 106.249978 90)
			(size 1.8034 0.508)
			(layers "F.Cu" "F.Mask" "F.Paste")
			(net "GND")
		)
		(pad "121" smd rect
			(at 0 107.100116 90)
			(size 1.8034 0.508)
			(layers "F.Cu" "F.Mask" "F.Paste")
			(net "M_L_DQS_DP<15>")
		)
		(pad "122" smd rect
			(at 0 107.95 90)
			(size 1.8034 0.508)
			(layers "F.Cu" "F.Mask" "F.Paste")
			(net "M_L_DQS_DN<15>")
		)
		(pad "123" smd rect
			(at 0 108.799884 90)
			(size 1.8034 0.508)
			(layers "F.Cu" "F.Mask" "F.Paste")
			(net "GND")
		)
		(pad "124" smd rect
			(at 0 109.650022 90)
			(size 1.8034 0.508)
			(layers "F.Cu" "F.Mask" "F.Paste")
			(net "M_L_DQ<55>")
		)
		(pad "125" smd rect
			(at 0 110.499906 90)
			(size 1.8034 0.508)
			(layers "F.Cu" "F.Mask" "F.Paste")
			(net "GND")
		)
		(pad "126" smd rect
			(at 0 111.350044 90)
			(size 1.8034 0.508)
			(layers "F.Cu" "F.Mask" "F.Paste")
			(net "M_L_DQ<51>")
		)
		(pad "127" smd rect
			(at 0 112.199928 90)
			(size 1.8034 0.508)
			(layers "F.Cu" "F.Mask" "F.Paste")
			(net "GND")
		)
		(pad "128" smd rect
			(at 0 113.050066 90)
			(size 1.8034 0.508)
			(layers "F.Cu" "F.Mask" "F.Paste")
			(net "M_L_DQ<61>")
		)
		(pad "129" smd rect
			(at 0 113.89995 90)
			(size 1.8034 0.508)
			(layers "F.Cu" "F.Mask" "F.Paste")
			(net "GND")
		)
		(pad "130" smd rect
			(at 0 114.750088 90)
			(size 1.8034 0.508)
			(layers "F.Cu" "F.Mask" "F.Paste")
			(net "M_L_DQ<57>")
		)
		(pad "131" smd rect
			(at 0 115.599972 90)
			(size 1.8034 0.508)
			(layers "F.Cu" "F.Mask" "F.Paste")
			(net "GND")
		)
		(pad "132" smd rect
			(at 0 116.45011 90)
			(size 1.8034 0.508)
			(layers "F.Cu" "F.Mask" "F.Paste")
			(net "M_L_DQS_DP<16>")
		)
		(pad "133" smd rect
			(at 0 117.299994 90)
			(size 1.8034 0.508)
			(layers "F.Cu" "F.Mask" "F.Paste")
			(net "M_L_DQS_DN<16>")
		)
		(pad "134" smd rect
			(at 0 118.149878 90)
			(size 1.8034 0.508)
			(layers "F.Cu" "F.Mask" "F.Paste")
			(net "GND")
		)
		(pad "135" smd rect
			(at 0 119.000016 90)
			(size 1.8034 0.508)
			(layers "F.Cu" "F.Mask" "F.Paste")
			(net "M_L_DQ<63>")
		)
		(pad "136" smd rect
			(at 0 119.8499 90)
			(size 1.8034 0.508)
			(layers "F.Cu" "F.Mask" "F.Paste")
			(net "GND")
		)
		(pad "137" smd rect
			(at 0 120.700038 90)
			(size 1.8034 0.508)
			(layers "F.Cu" "F.Mask" "F.Paste")
			(net "M_L_DQ<59>")
		)
		(pad "138" smd rect
			(at 0 121.549922 90)
			(size 1.8034 0.508)
			(layers "F.Cu" "F.Mask" "F.Paste")
			(net "GND")
		)
		(pad "139" smd rect
			(at 0 122.40006 90)
			(size 1.8034 0.508)
			(layers "F.Cu" "F.Mask" "F.Paste")
			(net "GND")
		)
		(pad "140" smd rect
			(at 0 123.249944 90)
			(size 1.8034 0.508)
			(layers "F.Cu" "F.Mask" "F.Paste")
			(net "PVPP_KLM")
		)
		(pad "141" smd rect
			(at 0 124.100082 90)
			(size 1.8034 0.508)
			(layers "F.Cu" "F.Mask" "F.Paste")
			(net "SMB_DDR_KLM_VPP_SCL")
		)
		(pad "142" smd rect
			(at 0 124.949966 90)
			(size 1.8034 0.508)
			(layers "F.Cu" "F.Mask" "F.Paste")
			(net "PVPP_KLM")
		)
		(pad "143" smd rect
			(at 0 125.800104 90)
			(size 1.8034 0.508)
			(layers "F.Cu" "F.Mask" "F.Paste")
			(net "PVPP_KLM")
		)
		(pad "144" smd rect
			(at 0 126.649988 90)
			(size 1.8034 0.508)
			(layers "F.Cu" "F.Mask" "F.Paste")
			(net "TP_CH_L_DIMM_L0_RFU_2")
		)
		(pad "145" smd rect
			(at 4.59994 0 90)
			(size 1.8034 0.508)
			(layers "F.Cu" "F.Mask" "F.Paste")
			(net "P12V_NVDIMM_KLM")
		)
		(pad "146" smd rect
			(at 4.59994 0.849884 90)
			(size 1.8034 0.508)
			(layers "F.Cu" "F.Mask" "F.Paste")
			(net "M_L_VREF")
		)
		(pad "147" smd rect
			(at 4.59994 1.700022 90)
			(size 1.8034 0.508)
			(layers "F.Cu" "F.Mask" "F.Paste")
			(net "GND")
		)
		(pad "148" smd rect
			(at 4.59994 2.549906 90)
			(size 1.8034 0.508)
			(layers "F.Cu" "F.Mask" "F.Paste")
			(net "M_L_DQ<4>")
		)
		(pad "149" smd rect
			(at 4.59994 3.400044 90)
			(size 1.8034 0.508)
			(layers "F.Cu" "F.Mask" "F.Paste")
			(net "GND")
		)
		(pad "150" smd rect
			(at 4.59994 4.249928 90)
			(size 1.8034 0.508)
			(layers "F.Cu" "F.Mask" "F.Paste")
			(net "M_L_DQ<0>")
		)
		(pad "151" smd rect
			(at 4.59994 5.100066 90)
			(size 1.8034 0.508)
			(layers "F.Cu" "F.Mask" "F.Paste")
			(net "GND")
		)
		(pad "152" smd rect
			(at 4.59994 5.94995 90)
			(size 1.8034 0.508)
			(layers "F.Cu" "F.Mask" "F.Paste")
			(net "M_L_DQS_DN<0>")
		)
		(pad "153" smd rect
			(at 4.59994 6.800088 90)
			(size 1.8034 0.508)
			(layers "F.Cu" "F.Mask" "F.Paste")
			(net "M_L_DQS_DP<0>")
		)
		(pad "154" smd rect
			(at 4.59994 7.649972 90)
			(size 1.8034 0.508)
			(layers "F.Cu" "F.Mask" "F.Paste")
			(net "GND")
		)
		(pad "155" smd rect
			(at 4.59994 8.50011 90)
			(size 1.8034 0.508)
			(layers "F.Cu" "F.Mask" "F.Paste")
			(net "M_L_DQ<6>")
		)
		(pad "156" smd rect
			(at 4.59994 9.349994 90)
			(size 1.8034 0.508)
			(layers "F.Cu" "F.Mask" "F.Paste")
			(net "GND")
		)
		(pad "157" smd rect
			(at 4.59994 10.199878 90)
			(size 1.8034 0.508)
			(layers "F.Cu" "F.Mask" "F.Paste")
			(net "M_L_DQ<2>")
		)
		(pad "158" smd rect
			(at 4.59994 11.050016 90)
			(size 1.8034 0.508)
			(layers "F.Cu" "F.Mask" "F.Paste")
			(net "GND")
		)
		(pad "159" smd rect
			(at 4.59994 11.8999 90)
			(size 1.8034 0.508)
			(layers "F.Cu" "F.Mask" "F.Paste")
			(net "M_L_DQ<12>")
		)
		(pad "160" smd rect
			(at 4.59994 12.750038 90)
			(size 1.8034 0.508)
			(layers "F.Cu" "F.Mask" "F.Paste")
			(net "GND")
		)
		(pad "161" smd rect
			(at 4.59994 13.599922 90)
			(size 1.8034 0.508)
			(layers "F.Cu" "F.Mask" "F.Paste")
			(net "M_L_DQ<8>")
		)
		(pad "162" smd rect
			(at 4.59994 14.45006 90)
			(size 1.8034 0.508)
			(layers "F.Cu" "F.Mask" "F.Paste")
			(net "GND")
		)
		(pad "163" smd rect
			(at 4.59994 15.299944 90)
			(size 1.8034 0.508)
			(layers "F.Cu" "F.Mask" "F.Paste")
			(net "M_L_DQS_DN<1>")
		)
		(pad "164" smd rect
			(at 4.59994 16.150082 90)
			(size 1.8034 0.508)
			(layers "F.Cu" "F.Mask" "F.Paste")
			(net "M_L_DQS_DP<1>")
		)
		(pad "165" smd rect
			(at 4.59994 16.999966 90)
			(size 1.8034 0.508)
			(layers "F.Cu" "F.Mask" "F.Paste")
			(net "GND")
		)
		(pad "166" smd rect
			(at 4.59994 17.850104 90)
			(size 1.8034 0.508)
			(layers "F.Cu" "F.Mask" "F.Paste")
			(net "M_L_DQ<14>")
		)
		(pad "167" smd rect
			(at 4.59994 18.699988 90)
			(size 1.8034 0.508)
			(layers "F.Cu" "F.Mask" "F.Paste")
			(net "GND")
		)
		(pad "168" smd rect
			(at 4.59994 19.550126 90)
			(size 1.8034 0.508)
			(layers "F.Cu" "F.Mask" "F.Paste")
			(net "M_L_DQ<10>")
		)
		(pad "169" smd rect
			(at 4.59994 20.40001 90)
			(size 1.8034 0.508)
			(layers "F.Cu" "F.Mask" "F.Paste")
			(net "GND")
		)
		(pad "170" smd rect
			(at 4.59994 21.249894 90)
			(size 1.8034 0.508)
			(layers "F.Cu" "F.Mask" "F.Paste")
			(net "M_L_DQ<20>")
		)
		(pad "171" smd rect
			(at 4.59994 22.100032 90)
			(size 1.8034 0.508)
			(layers "F.Cu" "F.Mask" "F.Paste")
			(net "GND")
		)
		(pad "172" smd rect
			(at 4.59994 22.949916 90)
			(size 1.8034 0.508)
			(layers "F.Cu" "F.Mask" "F.Paste")
			(net "M_L_DQ<16>")
		)
		(pad "173" smd rect
			(at 4.59994 23.800054 90)
			(size 1.8034 0.508)
			(layers "F.Cu" "F.Mask" "F.Paste")
			(net "GND")
		)
		(pad "174" smd rect
			(at 4.59994 24.649938 90)
			(size 1.8034 0.508)
			(layers "F.Cu" "F.Mask" "F.Paste")
			(net "M_L_DQS_DN<2>")
		)
		(pad "175" smd rect
			(at 4.59994 25.500076 90)
			(size 1.8034 0.508)
			(layers "F.Cu" "F.Mask" "F.Paste")
			(net "M_L_DQS_DP<2>")
		)
		(pad "176" smd rect
			(at 4.59994 26.34996 90)
			(size 1.8034 0.508)
			(layers "F.Cu" "F.Mask" "F.Paste")
			(net "GND")
		)
		(pad "177" smd rect
			(at 4.59994 27.200098 90)
			(size 1.8034 0.508)
			(layers "F.Cu" "F.Mask" "F.Paste")
			(net "M_L_DQ<22>")
		)
		(pad "178" smd rect
			(at 4.59994 28.049982 90)
			(size 1.8034 0.508)
			(layers "F.Cu" "F.Mask" "F.Paste")
			(net "GND")
		)
		(pad "179" smd rect
			(at 4.59994 28.90012 90)
			(size 1.8034 0.508)
			(layers "F.Cu" "F.Mask" "F.Paste")
			(net "M_L_DQ<18>")
		)
		(pad "180" smd rect
			(at 4.59994 29.750004 90)
			(size 1.8034 0.508)
			(layers "F.Cu" "F.Mask" "F.Paste")
			(net "GND")
		)
		(pad "181" smd rect
			(at 4.59994 30.599888 90)
			(size 1.8034 0.508)
			(layers "F.Cu" "F.Mask" "F.Paste")
			(net "M_L_DQ<28>")
		)
		(pad "182" smd rect
			(at 4.59994 31.450026 90)
			(size 1.8034 0.508)
			(layers "F.Cu" "F.Mask" "F.Paste")
			(net "GND")
		)
		(pad "183" smd rect
			(at 4.59994 32.29991 90)
			(size 1.8034 0.508)
			(layers "F.Cu" "F.Mask" "F.Paste")
			(net "M_L_DQ<24>")
		)
		(pad "184" smd rect
			(at 4.59994 33.150048 90)
			(size 1.8034 0.508)
			(layers "F.Cu" "F.Mask" "F.Paste")
			(net "GND")
		)
		(pad "185" smd rect
			(at 4.59994 33.999932 90)
			(size 1.8034 0.508)
			(layers "F.Cu" "F.Mask" "F.Paste")
			(net "M_L_DQS_DN<3>")
		)
		(pad "186" smd rect
			(at 4.59994 34.85007 90)
			(size 1.8034 0.508)
			(layers "F.Cu" "F.Mask" "F.Paste")
			(net "M_L_DQS_DP<3>")
		)
		(pad "187" smd rect
			(at 4.59994 35.699954 90)
			(size 1.8034 0.508)
			(layers "F.Cu" "F.Mask" "F.Paste")
			(net "GND")
		)
		(pad "188" smd rect
			(at 4.59994 36.550092 90)
			(size 1.8034 0.508)
			(layers "F.Cu" "F.Mask" "F.Paste")
			(net "M_L_DQ<30>")
		)
		(pad "189" smd rect
			(at 4.59994 37.399976 90)
			(size 1.8034 0.508)
			(layers "F.Cu" "F.Mask" "F.Paste")
			(net "GND")
		)
		(pad "190" smd rect
			(at 4.59994 38.250114 90)
			(size 1.8034 0.508)
			(layers "F.Cu" "F.Mask" "F.Paste")
			(net "M_L_DQ<26>")
		)
		(pad "191" smd rect
			(at 4.59994 39.099998 90)
			(size 1.8034 0.508)
			(layers "F.Cu" "F.Mask" "F.Paste")
			(net "GND")
		)
		(pad "192" smd rect
			(at 4.59994 39.949882 90)
			(size 1.8034 0.508)
			(layers "F.Cu" "F.Mask" "F.Paste")
			(net "M_L_ECC<4>")
		)
		(pad "193" smd rect
			(at 4.59994 40.80002 90)
			(size 1.8034 0.508)
			(layers "F.Cu" "F.Mask" "F.Paste")
			(net "GND")
		)
		(pad "194" smd rect
			(at 4.59994 41.649904 90)
			(size 1.8034 0.508)
			(layers "F.Cu" "F.Mask" "F.Paste")
			(net "M_L_ECC<0>")
		)
		(pad "195" smd rect
			(at 4.59994 42.500042 90)
			(size 1.8034 0.508)
			(layers "F.Cu" "F.Mask" "F.Paste")
			(net "GND")
		)
		(pad "196" smd rect
			(at 4.59994 43.349926 90)
			(size 1.8034 0.508)
			(layers "F.Cu" "F.Mask" "F.Paste")
			(net "M_L_DQS_DN<8>")
		)
		(pad "197" smd rect
			(at 4.59994 44.200064 90)
			(size 1.8034 0.508)
			(layers "F.Cu" "F.Mask" "F.Paste")
			(net "M_L_DQS_DP<8>")
		)
		(pad "198" smd rect
			(at 4.59994 45.049948 90)
			(size 1.8034 0.508)
			(layers "F.Cu" "F.Mask" "F.Paste")
			(net "GND")
		)
		(pad "199" smd rect
			(at 4.59994 45.900086 90)
			(size 1.8034 0.508)
			(layers "F.Cu" "F.Mask" "F.Paste")
			(net "M_L_ECC<6>")
		)
		(pad "200" smd rect
			(at 4.59994 46.74997 90)
			(size 1.8034 0.508)
			(layers "F.Cu" "F.Mask" "F.Paste")
			(net "GND")
		)
		(pad "201" smd rect
			(at 4.59994 47.600108 90)
			(size 1.8034 0.508)
			(layers "F.Cu" "F.Mask" "F.Paste")
			(net "M_L_ECC<2>")
		)
		(pad "202" smd rect
			(at 4.59994 48.449992 90)
			(size 1.8034 0.508)
			(layers "F.Cu" "F.Mask" "F.Paste")
			(net "GND")
		)
		(pad "203" smd rect
			(at 4.59994 49.299876 90)
			(size 1.8034 0.508)
			(layers "F.Cu" "F.Mask" "F.Paste")
			(net "M_L_CKE<1>")
		)
		(pad "204" smd rect
			(at 4.59994 50.150014 90)
			(size 1.8034 0.508)
			(layers "F.Cu" "F.Mask" "F.Paste")
			(net "PVDDQ_KLM")
		)
		(pad "205" smd rect
			(at 4.59994 50.999898 90)
			(size 1.8034 0.508)
			(layers "F.Cu" "F.Mask" "F.Paste")
			(net "TP_CH_L_DIMM_L0_RFU_0")
		)
		(pad "206" smd rect
			(at 4.59994 51.850036 90)
			(size 1.8034 0.508)
			(layers "F.Cu" "F.Mask" "F.Paste")
			(net "PVDDQ_KLM")
		)
		(pad "207" smd rect
			(at 4.59994 52.69992 90)
			(size 1.8034 0.508)
			(layers "F.Cu" "F.Mask" "F.Paste")
			(net "M_L_BG<1>")
		)
		(pad "208" smd rect
			(at 4.59994 53.550058 90)
			(size 1.8034 0.508)
			(layers "F.Cu" "F.Mask" "F.Paste")
			(net "M_L_ALERT_N")
		)
		(pad "209" smd rect
			(at 4.59994 54.399942 90)
			(size 1.8034 0.508)
			(layers "F.Cu" "F.Mask" "F.Paste")
			(net "PVDDQ_KLM")
		)
		(pad "210" smd rect
			(at 4.59994 55.25008 90)
			(size 1.8034 0.508)
			(layers "F.Cu" "F.Mask" "F.Paste")
			(net "M_L_MA<11>")
		)
		(pad "211" smd rect
			(at 4.59994 56.099964 90)
			(size 1.8034 0.508)
			(layers "F.Cu" "F.Mask" "F.Paste")
			(net "M_L_MA<7>")
		)
		(pad "212" smd rect
			(at 4.59994 56.950102 90)
			(size 1.8034 0.508)
			(layers "F.Cu" "F.Mask" "F.Paste")
			(net "PVDDQ_KLM")
		)
		(pad "213" smd rect
			(at 4.59994 57.799986 90)
			(size 1.8034 0.508)
			(layers "F.Cu" "F.Mask" "F.Paste")
			(net "M_L_MA<5>")
		)
		(pad "214" smd rect
			(at 4.59994 58.650124 90)
			(size 1.8034 0.508)
			(layers "F.Cu" "F.Mask" "F.Paste")
			(net "M_L_MA<4>")
		)
		(pad "215" smd rect
			(at 4.59994 59.500008 90)
			(size 1.8034 0.508)
			(layers "F.Cu" "F.Mask" "F.Paste")
			(net "PVDDQ_KLM")
		)
		(pad "216" smd rect
			(at 4.59994 60.349892 90)
			(size 1.8034 0.508)
			(layers "F.Cu" "F.Mask" "F.Paste")
			(net "M_L_MA<2>")
		)
		(pad "217" smd rect
			(at 4.59994 61.20003 90)
			(size 1.8034 0.508)
			(layers "F.Cu" "F.Mask" "F.Paste")
			(net "PVDDQ_KLM")
		)
		(pad "218" smd rect
			(at 4.59994 62.049914 90)
			(size 1.8034 0.508)
			(layers "F.Cu" "F.Mask" "F.Paste")
			(net "M_L_CLK_DP<1>")
		)
		(pad "219" smd rect
			(at 4.59994 62.900052 90)
			(size 1.8034 0.508)
			(layers "F.Cu" "F.Mask" "F.Paste")
			(net "M_L_CLK_DN<1>")
		)
		(pad "220" smd rect
			(at 4.59994 63.749936 90)
			(size 1.8034 0.508)
			(layers "F.Cu" "F.Mask" "F.Paste")
			(net "PVDDQ_KLM")
		)
		(pad "221" smd rect
			(at 4.59994 64.600074 90)
			(size 1.8034 0.508)
			(layers "F.Cu" "F.Mask" "F.Paste")
			(net "PVTT_KLM")
		)
		(pad "222" smd rect
			(at 4.59994 70.550024 90)
			(size 1.8034 0.508)
			(layers "F.Cu" "F.Mask" "F.Paste")
			(net "M_L_PAR")
		)
		(pad "223" smd rect
			(at 4.59994 71.399908 90)
			(size 1.8034 0.508)
			(layers "F.Cu" "F.Mask" "F.Paste")
			(net "PVDDQ_KLM")
		)
		(pad "224" smd rect
			(at 4.59994 72.250046 90)
			(size 1.8034 0.508)
			(layers "F.Cu" "F.Mask" "F.Paste")
			(net "M_L_BA<1>")
		)
		(pad "225" smd rect
			(at 4.59994 73.09993 90)
			(size 1.8034 0.508)
			(layers "F.Cu" "F.Mask" "F.Paste")
			(net "M_L_MA<10>")
		)
		(pad "226" smd rect
			(at 4.59994 73.950068 90)
			(size 1.8034 0.508)
			(layers "F.Cu" "F.Mask" "F.Paste")
			(net "PVDDQ_KLM")
		)
		(pad "227" smd rect
			(at 4.59994 74.799952 90)
			(size 1.8034 0.508)
			(layers "F.Cu" "F.Mask" "F.Paste")
			(net "TP_CH_L_DIMM_L0_RFU_1")
		)
		(pad "228" smd rect
			(at 4.59994 75.65009 90)
			(size 1.8034 0.508)
			(layers "F.Cu" "F.Mask" "F.Paste")
			(net "M_L_MA<14>")
		)
		(pad "229" smd rect
			(at 4.59994 76.499974 90)
			(size 1.8034 0.508)
			(layers "F.Cu" "F.Mask" "F.Paste")
			(net "PVDDQ_KLM")
		)
		(pad "230" smd rect
			(at 4.59994 77.350112 90)
			(size 1.8034 0.508)
			(layers "F.Cu" "F.Mask" "F.Paste")
			(net "FM_ADR_COMPLETE_KLM_N")
		)
		(pad "231" smd rect
			(at 4.59994 78.199996 90)
			(size 1.8034 0.508)
			(layers "F.Cu" "F.Mask" "F.Paste")
			(net "PVDDQ_KLM")
		)
		(pad "232" smd rect
			(at 4.59994 79.04988 90)
			(size 1.8034 0.508)
			(layers "F.Cu" "F.Mask" "F.Paste")
			(net "M_L_MA<13>")
		)
		(pad "233" smd rect
			(at 4.59994 79.900018 90)
			(size 1.8034 0.508)
			(layers "F.Cu" "F.Mask" "F.Paste")
			(net "PVDDQ_KLM")
		)
		(pad "234" smd rect
			(at 4.59994 80.749902 90)
			(size 1.8034 0.508)
			(layers "F.Cu" "F.Mask" "F.Paste")
			(net "M_L_MA<17>")
		)
		(pad "235" smd rect
			(at 4.59994 81.60004 90)
			(size 1.8034 0.508)
			(layers "F.Cu" "F.Mask" "F.Paste")
			(net "M_L_C<2>")
		)
		(pad "236" smd rect
			(at 4.59994 82.449924 90)
			(size 1.8034 0.508)
			(layers "F.Cu" "F.Mask" "F.Paste")
			(net "PVDDQ_KLM")
		)
		(pad "237" smd rect
			(at 4.59994 83.300062 90)
			(size 1.8034 0.508)
			(layers "F.Cu" "F.Mask" "F.Paste")
			(net "M_L_CS_N<3>")
		)
		(pad "238" smd rect
			(at 4.59994 84.149946 90)
			(size 1.8034 0.508)
			(layers "F.Cu" "F.Mask" "F.Paste")
			(net "GND")
		)
		(pad "239" smd rect
			(at 4.59994 85.000084 90)
			(size 1.8034 0.508)
			(layers "F.Cu" "F.Mask" "F.Paste")
			(net "GND")
		)
		(pad "240" smd rect
			(at 4.59994 85.849968 90)
			(size 1.8034 0.508)
			(layers "F.Cu" "F.Mask" "F.Paste")
			(net "M_L_DQ<36>")
		)
		(pad "241" smd rect
			(at 4.59994 86.700106 90)
			(size 1.8034 0.508)
			(layers "F.Cu" "F.Mask" "F.Paste")
			(net "GND")
		)
		(pad "242" smd rect
			(at 4.59994 87.54999 90)
			(size 1.8034 0.508)
			(layers "F.Cu" "F.Mask" "F.Paste")
			(net "M_L_DQ<32>")
		)
		(pad "243" smd rect
			(at 4.59994 88.399874 90)
			(size 1.8034 0.508)
			(layers "F.Cu" "F.Mask" "F.Paste")
			(net "GND")
		)
		(pad "244" smd rect
			(at 4.59994 89.250012 90)
			(size 1.8034 0.508)
			(layers "F.Cu" "F.Mask" "F.Paste")
			(net "M_L_DQS_DN<4>")
		)
		(pad "245" smd rect
			(at 4.59994 90.099896 90)
			(size 1.8034 0.508)
			(layers "F.Cu" "F.Mask" "F.Paste")
			(net "M_L_DQS_DP<4>")
		)
		(pad "246" smd rect
			(at 4.59994 90.950034 90)
			(size 1.8034 0.508)
			(layers "F.Cu" "F.Mask" "F.Paste")
			(net "GND")
		)
		(pad "247" smd rect
			(at 4.59994 91.799918 90)
			(size 1.8034 0.508)
			(layers "F.Cu" "F.Mask" "F.Paste")
			(net "M_L_DQ<38>")
		)
		(pad "248" smd rect
			(at 4.59994 92.650056 90)
			(size 1.8034 0.508)
			(layers "F.Cu" "F.Mask" "F.Paste")
			(net "GND")
		)
		(pad "249" smd rect
			(at 4.59994 93.49994 90)
			(size 1.8034 0.508)
			(layers "F.Cu" "F.Mask" "F.Paste")
			(net "M_L_DQ<34>")
		)
		(pad "250" smd rect
			(at 4.59994 94.350078 90)
			(size 1.8034 0.508)
			(layers "F.Cu" "F.Mask" "F.Paste")
			(net "GND")
		)
		(pad "251" smd rect
			(at 4.59994 95.199962 90)
			(size 1.8034 0.508)
			(layers "F.Cu" "F.Mask" "F.Paste")
			(net "M_L_DQ<44>")
		)
		(pad "252" smd rect
			(at 4.59994 96.0501 90)
			(size 1.8034 0.508)
			(layers "F.Cu" "F.Mask" "F.Paste")
			(net "GND")
		)
		(pad "253" smd rect
			(at 4.59994 96.899984 90)
			(size 1.8034 0.508)
			(layers "F.Cu" "F.Mask" "F.Paste")
			(net "M_L_DQ<40>")
		)
		(pad "254" smd rect
			(at 4.59994 97.750122 90)
			(size 1.8034 0.508)
			(layers "F.Cu" "F.Mask" "F.Paste")
			(net "GND")
		)
		(pad "255" smd rect
			(at 4.59994 98.600006 90)
			(size 1.8034 0.508)
			(layers "F.Cu" "F.Mask" "F.Paste")
			(net "M_L_DQS_DN<5>")
		)
		(pad "256" smd rect
			(at 4.59994 99.44989 90)
			(size 1.8034 0.508)
			(layers "F.Cu" "F.Mask" "F.Paste")
			(net "M_L_DQS_DP<5>")
		)
		(pad "257" smd rect
			(at 4.59994 100.300028 90)
			(size 1.8034 0.508)
			(layers "F.Cu" "F.Mask" "F.Paste")
			(net "GND")
		)
		(pad "258" smd rect
			(at 4.59994 101.149912 90)
			(size 1.8034 0.508)
			(layers "F.Cu" "F.Mask" "F.Paste")
			(net "M_L_DQ<46>")
		)
		(pad "259" smd rect
			(at 4.59994 102.00005 90)
			(size 1.8034 0.508)
			(layers "F.Cu" "F.Mask" "F.Paste")
			(net "GND")
		)
		(pad "260" smd rect
			(at 4.59994 102.849934 90)
			(size 1.8034 0.508)
			(layers "F.Cu" "F.Mask" "F.Paste")
			(net "M_L_DQ<42>")
		)
		(pad "261" smd rect
			(at 4.59994 103.700072 90)
			(size 1.8034 0.508)
			(layers "F.Cu" "F.Mask" "F.Paste")
			(net "GND")
		)
		(pad "262" smd rect
			(at 4.59994 104.549956 90)
			(size 1.8034 0.508)
			(layers "F.Cu" "F.Mask" "F.Paste")
			(net "M_L_DQ<52>")
		)
		(pad "263" smd rect
			(at 4.59994 105.400094 90)
			(size 1.8034 0.508)
			(layers "F.Cu" "F.Mask" "F.Paste")
			(net "GND")
		)
		(pad "264" smd rect
			(at 4.59994 106.249978 90)
			(size 1.8034 0.508)
			(layers "F.Cu" "F.Mask" "F.Paste")
			(net "M_L_DQ<48>")
		)
		(pad "265" smd rect
			(at 4.59994 107.100116 90)
			(size 1.8034 0.508)
			(layers "F.Cu" "F.Mask" "F.Paste")
			(net "GND")
		)
		(pad "266" smd rect
			(at 4.59994 107.95 90)
			(size 1.8034 0.508)
			(layers "F.Cu" "F.Mask" "F.Paste")
			(net "M_L_DQS_DN<6>")
		)
		(pad "267" smd rect
			(at 4.59994 108.799884 90)
			(size 1.8034 0.508)
			(layers "F.Cu" "F.Mask" "F.Paste")
			(net "M_L_DQS_DP<6>")
		)
		(pad "268" smd rect
			(at 4.59994 109.650022 90)
			(size 1.8034 0.508)
			(layers "F.Cu" "F.Mask" "F.Paste")
			(net "GND")
		)
		(pad "269" smd rect
			(at 4.59994 110.499906 90)
			(size 1.8034 0.508)
			(layers "F.Cu" "F.Mask" "F.Paste")
			(net "M_L_DQ<54>")
		)
		(pad "270" smd rect
			(at 4.59994 111.350044 90)
			(size 1.8034 0.508)
			(layers "F.Cu" "F.Mask" "F.Paste")
			(net "GND")
		)
		(pad "271" smd rect
			(at 4.59994 112.199928 90)
			(size 1.8034 0.508)
			(layers "F.Cu" "F.Mask" "F.Paste")
			(net "M_L_DQ<50>")
		)
		(pad "272" smd rect
			(at 4.59994 113.050066 90)
			(size 1.8034 0.508)
			(layers "F.Cu" "F.Mask" "F.Paste")
			(net "GND")
		)
		(pad "273" smd rect
			(at 4.59994 113.89995 90)
			(size 1.8034 0.508)
			(layers "F.Cu" "F.Mask" "F.Paste")
			(net "M_L_DQ<60>")
		)
		(pad "274" smd rect
			(at 4.59994 114.750088 90)
			(size 1.8034 0.508)
			(layers "F.Cu" "F.Mask" "F.Paste")
			(net "GND")
		)
		(pad "275" smd rect
			(at 4.59994 115.599972 90)
			(size 1.8034 0.508)
			(layers "F.Cu" "F.Mask" "F.Paste")
			(net "M_L_DQ<56>")
		)
		(pad "276" smd rect
			(at 4.59994 116.45011 90)
			(size 1.8034 0.508)
			(layers "F.Cu" "F.Mask" "F.Paste")
			(net "GND")
		)
		(pad "277" smd rect
			(at 4.59994 117.299994 90)
			(size 1.8034 0.508)
			(layers "F.Cu" "F.Mask" "F.Paste")
			(net "M_L_DQS_DN<7>")
		)
		(pad "278" smd rect
			(at 4.59994 118.149878 90)
			(size 1.8034 0.508)
			(layers "F.Cu" "F.Mask" "F.Paste")
			(net "M_L_DQS_DP<7>")
		)
		(pad "279" smd rect
			(at 4.59994 119.000016 90)
			(size 1.8034 0.508)
			(layers "F.Cu" "F.Mask" "F.Paste")
			(net "GND")
		)
		(pad "280" smd rect
			(at 4.59994 119.8499 90)
			(size 1.8034 0.508)
			(layers "F.Cu" "F.Mask" "F.Paste")
			(net "M_L_DQ<62>")
		)
		(pad "281" smd rect
			(at 4.59994 120.700038 90)
			(size 1.8034 0.508)
			(layers "F.Cu" "F.Mask" "F.Paste")
			(net "GND")
		)
		(pad "282" smd rect
			(at 4.59994 121.549922 90)
			(size 1.8034 0.508)
			(layers "F.Cu" "F.Mask" "F.Paste")
			(net "M_L_DQ<58>")
		)
		(pad "283" smd rect
			(at 4.59994 122.40006 90)
			(size 1.8034 0.508)
			(layers "F.Cu" "F.Mask" "F.Paste")
			(net "GND")
		)
		(pad "284" smd rect
			(at 4.59994 123.249944 90)
			(size 1.8034 0.508)
			(layers "F.Cu" "F.Mask" "F.Paste")
			(net "PVPP_KLM")
		)
		(pad "285" smd rect
			(at 4.59994 124.100082 90)
			(size 1.8034 0.508)
			(layers "F.Cu" "F.Mask" "F.Paste")
			(net "SMB_DDR_KLM_VPP_SDA")
		)
		(pad "286" smd rect
			(at 4.59994 124.949966 90)
			(size 1.8034 0.508)
			(layers "F.Cu" "F.Mask" "F.Paste")
			(net "PVPP_KLM")
		)
		(pad "287" smd rect
			(at 4.59994 125.800104 90)
			(size 1.8034 0.508)
			(layers "F.Cu" "F.Mask" "F.Paste")
			(net "PVPP_KLM")
		)
		(pad "288" smd rect
			(at 4.59994 126.649988 90)
			(size 1.8034 0.508)
			(layers "F.Cu" "F.Mask" "F.Paste")
			(net "PVPP_KLM")
		)
	)
	(footprint ""
		(layer "F.Cu")
		(at 32.1564 -53.1368 -90)
		(property "Reference" "C1E8"
			(at 0 0 270)
			(layer "F.SilkS")
			(hide yes)
			(effects
				(font
					(size 1.27 1.27)
				)
			)
		)
		(property "Value" ""
			(at 0 0 270)
			(layer "F.Fab")
			(effects
				(font
					(size 1.27 1.27)
				)
			)
		)
		(duplicate_pad_numbers_are_jumpers no)
		(fp_rect
			(start 0.3048 0.9906)
			(end -0.3048 -0.1016)
			(stroke
				(width 0)
				(type default)
			)
			(fill no)
			(layer "F.CrtYd")
		)
		(fp_line
			(start -0.3048 0.9906)
			(end 0.3048 0.9906)
			(stroke
				(width 0.1)
				(type default)
			)
			(layer "F.Fab")
		)
		(fp_line
			(start 0.3048 0.9906)
			(end 0.3048 -0.1016)
			(stroke
				(width 0.1)
				(type default)
			)
			(layer "F.Fab")
		)
		(fp_line
			(start -0.3048 -0.1016)
			(end -0.3048 0.9906)
			(stroke
				(width 0.1)
				(type default)
			)
			(layer "F.Fab")
		)
		(fp_line
			(start 0.3048 -0.1016)
			(end -0.3048 -0.1016)
			(stroke
				(width 0.1)
				(type default)
			)
			(layer "F.Fab")
		)
		(pad "1" smd rect
			(at 0 0 270)
			(size 0.508 0.508)
			(layers "F.Cu" "F.Mask" "F.Paste")
			(net "VR_PVCCIN_CPU1_PH1_VCIN")
		)
		(pad "2" smd rect
			(at 0 0.889 270)
			(size 0.508 0.508)
			(layers "F.Cu" "F.Mask" "F.Paste")
			(net "GND")
		)
		(zone
			(layer "F.Cu")
			(hatch none 0.5)
			(connect_pads
				(clearance 0)
			)
			(min_thickness 0.25)
			(keepout
				(tracks not_allowed)
				(vias allowed)
				(pads allowed)
				(copperpour not_allowed)
				(footprints allowed)
			)
			(placement
				(enabled no)
				(sheetname "")
			)
			(fill
				(thermal_gap 0.5)
				(thermal_bridge_width 0.5)
				(island_removal_mode 0)
			)
			(polygon
				(pts
					(xy 31.5214 -52.8828) (xy 31.9024 -52.8828) (xy 31.9024 -53.3908) (xy 31.5214 -53.3908)
				)
			)
		)
		(zone
			(layer "F.Cu")
			(hatch none 0.5)
			(connect_pads
				(clearance 0)
			)
			(min_thickness 0.25)
			(keepout
				(tracks allowed)
				(vias not_allowed)
				(pads allowed)
				(copperpour not_allowed)
				(footprints allowed)
			)
			(placement
				(enabled no)
				(sheetname "")
			)
			(fill
				(thermal_gap 0.5)
				(thermal_bridge_width 0.5)
				(island_removal_mode 0)
			)
			(polygon
				(pts
					(xy 31.5214 -52.8828) (xy 31.9024 -52.8828) (xy 31.9024 -53.3908) (xy 31.5214 -53.3908)
				)
			)
		)
	)
	(footprint ""
		(layer "F.Cu")
		(at 177.994818 -51.051206 -90)
		(property "Reference" "C4E13"
			(at 0 0 270)
			(layer "F.SilkS")
			(hide yes)
			(effects
				(font
					(size 1.27 1.27)
				)
			)
		)
		(property "Value" ""
			(at 0 0 270)
			(layer "F.Fab")
			(effects
				(font
					(size 1.27 1.27)
				)
			)
		)
		(duplicate_pad_numbers_are_jumpers no)
		(fp_poly
			(pts
				(xy 0.3048 -0.1016) (xy 0.3048 0.9906) (xy -0.3048 0.9906) (xy -0.3048 -0.1016)
			)
			(stroke
				(width 0)
				(type default)
			)
			(fill no)
			(layer "F.CrtYd")
		)
		(fp_line
			(start -0.3048 0.9906)
			(end 0.3048 0.9906)
			(stroke
				(width 0.1)
				(type default)
			)
			(layer "F.Fab")
		)
		(fp_line
			(start 0.3048 0.9906)
			(end 0.3048 -0.1016)
			(stroke
				(width 0.1)
				(type default)
			)
			(layer "F.Fab")
		)
		(fp_line
			(start -0.3048 -0.1016)
			(end -0.3048 0.9906)
			(stroke
				(width 0.1)
				(type default)
			)
			(layer "F.Fab")
		)
		(fp_line
			(start 0.3048 -0.1016)
			(end -0.3048 -0.1016)
			(stroke
				(width 0.1)
				(type default)
			)
			(layer "F.Fab")
		)
		(pad "1" smd rect
			(at 0 0 270)
			(size 0.508 0.508)
			(layers "F.Cu" "F.Mask" "F.Paste")
			(net "VR_FET_SW_P12V_STBY_PVCCIN_CPU0")
		)
		(pad "2" smd rect
			(at 0 0.889 270)
			(size 0.508 0.508)
			(layers "F.Cu" "F.Mask" "F.Paste")
			(net "GND")
		)
		(zone
			(layer "F.Cu")
			(hatch none 0.5)
			(connect_pads
				(clearance 0)
			)
			(min_thickness 0.25)
			(keepout
				(tracks not_allowed)
				(vias allowed)
				(pads allowed)
				(copperpour not_allowed)
				(footprints allowed)
			)
			(placement
				(enabled no)
				(sheetname "")
			)
			(fill
				(thermal_gap 0.5)
				(thermal_bridge_width 0.5)
				(island_removal_mode 0)
			)
			(polygon
				(pts
					(xy 177.359818 -51.305206) (xy 177.359818 -50.797206) (xy 177.740818 -50.797206) (xy 177.740818 -51.305206)
				)
			)
		)
		(zone
			(layer "F.Cu")
			(hatch none 0.5)
			(connect_pads
				(clearance 0)
			)
			(min_thickness 0.25)
			(keepout
				(tracks allowed)
				(vias not_allowed)
				(pads allowed)
				(copperpour not_allowed)
				(footprints allowed)
			)
			(placement
				(enabled no)
				(sheetname "")
			)
			(fill
				(thermal_gap 0.5)
				(thermal_bridge_width 0.5)
				(island_removal_mode 0)
			)
			(polygon
				(pts
					(xy 177.740818 -51.305206) (xy 177.740818 -50.797206) (xy 177.359818 -50.797206) (xy 177.359818 -51.305206)
				)
			)
		)
	)
	(footprint ""
		(layer "F.Cu")
		(at 373.1006 -157.9118 -90)
		(property "Reference" "CT66"
			(at 5.79247 9.1694 0)
			(unlocked yes)
			(layer "F.SilkS")
			(effects
				(font
					(size 0.7874 0.5842)
					(thickness 0.1524)
				)
				(justify left)
			)
		)
		(property "Value" ""
			(at 0 0 270)
			(layer "F.Fab")
			(effects
				(font
					(size 1.27 1.27)
				)
			)
		)
		(duplicate_pad_numbers_are_jumpers no)
		(fp_poly
			(pts
				(xy 0.3048 -0.1016) (xy 0.3048 0.9906) (xy -0.3048 0.9906) (xy -0.3048 -0.1016)
			)
			(stroke
				(width 0)
				(type default)
			)
			(fill no)
			(layer "F.CrtYd")
		)
		(fp_line
			(start -0.3048 0.9906)
			(end 0.3048 0.9906)
			(stroke
				(width 0.1)
				(type default)
			)
			(layer "F.Fab")
		)
		(fp_line
			(start 0.3048 0.9906)
			(end 0.3048 -0.1016)
			(stroke
				(width 0.1)
				(type default)
			)
			(layer "F.Fab")
		)
		(fp_line
			(start -0.3048 -0.1016)
			(end -0.3048 0.9906)
			(stroke
				(width 0.1)
				(type default)
			)
			(layer "F.Fab")
		)
		(fp_line
			(start 0.3048 -0.1016)
			(end -0.3048 -0.1016)
			(stroke
				(width 0.1)
				(type default)
			)
			(layer "F.Fab")
		)
		(pad "1" smd rect
			(at 0 0 270)
			(size 0.508 0.508)
			(layers "F.Cu" "F.Mask" "F.Paste")
			(net "VR_PVNN_PCH_AIREF1")
		)
		(pad "2" smd rect
			(at 0 0.889 270)
			(size 0.508 0.508)
			(layers "F.Cu" "F.Mask" "F.Paste")
			(net "GND")
		)
		(zone
			(layer "F.Cu")
			(hatch none 0.5)
			(connect_pads
				(clearance 0)
			)
			(min_thickness 0.25)
			(keepout
				(tracks not_allowed)
				(vias allowed)
				(pads allowed)
				(copperpour not_allowed)
				(footprints allowed)
			)
			(placement
				(enabled no)
				(sheetname "")
			)
			(fill
				(thermal_gap 0.5)
				(thermal_bridge_width 0.5)
				(island_removal_mode 0)
			)
			(polygon
				(pts
					(xy 372.4656 -158.1658) (xy 372.4656 -157.6578) (xy 372.8466 -157.6578) (xy 372.8466 -158.1658)
				)
			)
		)
		(zone
			(layer "F.Cu")
			(hatch none 0.5)
			(connect_pads
				(clearance 0)
			)
			(min_thickness 0.25)
			(keepout
				(tracks allowed)
				(vias not_allowed)
				(pads allowed)
				(copperpour not_allowed)
				(footprints allowed)
			)
			(placement
				(enabled no)
				(sheetname "")
			)
			(fill
				(thermal_gap 0.5)
				(thermal_bridge_width 0.5)
				(island_removal_mode 0)
			)
			(polygon
				(pts
					(xy 372.8466 -158.1658) (xy 372.8466 -157.6578) (xy 372.4656 -157.6578) (xy 372.4656 -158.1658)
				)
			)
		)
	)
	(footprint ""
		(layer "F.Cu")
		(at 372.745 -74.295 180)
		(property "Reference" "U8D7"
			(at -0.635 -8.28167 0)
			(unlocked yes)
			(layer "F.SilkS")
			(effects
				(font
					(size 0.7874 0.5842)
					(thickness 0.1524)
				)
			)
		)
		(property "Value" ""
			(at 0 0 180)
			(layer "F.Fab")
			(effects
				(font
					(size 1.27 1.27)
				)
			)
		)
		(duplicate_pad_numbers_are_jumpers no)
		(fp_line
			(start 6.999986 6.999986)
			(end -6.999986 6.999986)
			(stroke
				(width 0.1524)
				(type default)
			)
			(layer "F.SilkS")
		)
		(fp_line
			(start 6.999986 -6.999986)
			(end 6.999986 6.999986)
			(stroke
				(width 0.1524)
				(type default)
			)
			(layer "F.SilkS")
		)
		(fp_line
			(start -6.999986 6.999986)
			(end -6.999986 -6.999986)
			(stroke
				(width 0.1524)
				(type default)
			)
			(layer "F.SilkS")
		)
		(fp_line
			(start -6.999986 -6.999986)
			(end 6.999986 -6.999986)
			(stroke
				(width 0.1524)
				(type default)
			)
			(layer "F.SilkS")
		)
		(fp_circle
			(center -7.60349 -6.731508)
			(end -7.73049 -6.731508)
			(stroke
				(width 0.254)
				(type default)
			)
			(fill no)
			(layer "F.SilkS")
		)
		(fp_poly
			(pts
				(xy -6.999986 -6.999986) (xy -6.999986 6.999986) (xy 6.999986 6.999986) (xy 6.999986 -6.999986)
			)
			(stroke
				(width 0)
				(type default)
			)
			(fill no)
			(layer "F.CrtYd")
		)
		(fp_line
			(start 6.999986 6.999986)
			(end -6.999986 6.999986)
			(stroke
				(width 0.1)
				(type default)
			)
			(layer "F.Fab")
		)
		(fp_line
			(start 6.999986 -6.999986)
			(end 6.999986 6.999986)
			(stroke
				(width 0.1)
				(type default)
			)
			(layer "F.Fab")
		)
		(fp_line
			(start -6.999986 6.999986)
			(end -6.999986 -6.999986)
			(stroke
				(width 0.1)
				(type default)
			)
			(layer "F.Fab")
		)
		(fp_line
			(start -6.999986 -6.999986)
			(end 6.999986 -6.999986)
			(stroke
				(width 0.1)
				(type default)
			)
			(layer "F.Fab")
		)
		(fp_circle
			(center -7.60349 -6.731508)
			(end -7.73049 -6.731508)
			(stroke
				(width 0.254)
				(type default)
			)
			(fill no)
			(layer "F.Fab")
		)
		(fp_text user "A16"
			(at 7.727442 -7.679182 0)
			(unlocked yes)
			(layer "F.SilkS")
			(effects
				(font
					(size 0.7874 0.5842)
					(thickness 0.1524)
				)
				(justify left)
			)
		)
		(fp_text user "T16"
			(at 7.682484 4.891786 90)
			(unlocked yes)
			(layer "F.SilkS")
			(effects
				(font
					(size 0.7874 0.5842)
					(thickness 0.1524)
				)
				(justify left)
			)
		)
		(fp_text user "T1"
			(at 0.381 9.04113 0)
			(unlocked yes)
			(layer "F.SilkS")
			(effects
				(font
					(size 0.7874 0.5842)
					(thickness 0.1524)
				)
				(justify left)
			)
		)
		(fp_text user "T16"
			(at 7.497318 5.94487 180)
			(unlocked yes)
			(layer "F.Fab")
			(effects
				(font
					(size 0.7874 0.5842)
					(thickness 0.1524)
				)
				(justify left)
			)
		)
		(fp_text user "A16"
			(at 5.4102 -7.61873 180)
			(unlocked yes)
			(layer "F.Fab")
			(effects
				(font
					(size 0.7874 0.5842)
					(thickness 0.1524)
				)
				(justify left)
			)
		)
		(fp_text user "T1"
			(at -1.0414 10.779506 180)
			(unlocked yes)
			(layer "F.Fab")
			(effects
				(font
					(size 0.7874 0.5842)
					(thickness 0.1524)
				)
				(justify left)
			)
		)
		(pad "A1" smd circle
			(at -5.999988 -5.999988 180)
			(size 0.3556 0.3556)
			(layers "F.Cu" "F.Mask" "F.Paste")
			(net "P3V3_STBY")
		)
		(pad "A2" smd circle
			(at -5.199888 -5.999988 180)
			(size 0.3556 0.3556)
			(layers "F.Cu" "F.Mask" "F.Paste")
			(net "Net_344")
		)
		(pad "A3" smd circle
			(at -4.400042 -5.999988 180)
			(size 0.3556 0.3556)
			(layers "F.Cu" "F.Mask" "F.Paste")
			(net "FM_PCH_PRSNT_N")
		)
		(pad "A4" smd circle
			(at -3.599942 -5.999988 180)
			(size 0.3556 0.3556)
			(layers "F.Cu" "F.Mask" "F.Paste")
			(net "FM_P3V3_CPLD_EN")
		)
		(pad "A5" smd circle
			(at -2.800096 -5.999988 180)
			(size 0.3556 0.3556)
			(layers "F.Cu" "F.Mask" "F.Paste")
			(net "TP_CPLD1_PT11A")
		)
		(pad "A6" smd circle
			(at -1.999996 -5.999988 180)
			(size 0.3556 0.3556)
			(layers "F.Cu" "F.Mask" "F.Paste")
			(net "JTAG_PLD_TDI")
		)
		(pad "A7" smd circle
			(at -1.199896 -5.999988 180)
			(size 0.3556 0.3556)
			(layers "F.Cu" "F.Mask" "F.Paste")
			(net "JTAG_PLD_TCK")
		)
		(pad "A8" smd circle
			(at -0.40005 -5.999988 180)
			(size 0.3556 0.3556)
			(layers "F.Cu" "F.Mask" "F.Paste")
			(net "TP_CPLD1_PT17B_PCLKC0_1")
		)
		(pad "A9" smd circle
			(at 0.40005 -5.999988 180)
			(size 0.3556 0.3556)
			(layers "F.Cu" "F.Mask" "F.Paste")
			(net "SMB_SENSOR_STBY_LVC3_SCL")
		)
		(pad "A10" smd circle
			(at 1.199896 -5.999988 180)
			(size 0.3556 0.3556)
			(layers "F.Cu" "F.Mask" "F.Paste")
			(net "FM_PVCCIN_PVCCSA_CPU0_EN_LVC1")
		)
		(pad "A11" smd circle
			(at 1.999996 -5.999988 180)
			(size 0.3556 0.3556)
			(layers "F.Cu" "F.Mask" "F.Paste")
			(net "FM_CPU0_OR_CPU1_MCP_PRES")
		)
		(pad "A12" smd circle
			(at 2.800096 -5.999988 180)
			(size 0.3556 0.3556)
			(layers "F.Cu" "F.Mask" "F.Paste")
			(net "PU_THERMTRIP_FORCE_N")
		)
		(pad "A13" smd circle
			(at 3.599942 -5.999988 180)
			(size 0.3556 0.3556)
			(layers "F.Cu" "F.Mask" "F.Paste")
			(net "TP_CPLD1_PT24C_INITN")
		)
		(pad "A14" smd circle
			(at 4.400042 -5.999988 180)
			(size 0.3556 0.3556)
			(layers "F.Cu" "F.Mask" "F.Paste")
			(net "TP_CPLD1_PT22D")
		)
		(pad "A15" smd circle
			(at 5.199888 -5.999988 180)
			(size 0.3556 0.3556)
			(layers "F.Cu" "F.Mask" "F.Paste")
			(net "TP_CPLD1_PT24B")
		)
		(pad "A16" smd circle
			(at 5.999988 -5.999988 180)
			(size 0.3556 0.3556)
			(layers "F.Cu" "F.Mask" "F.Paste")
			(net "P3V3_STBY")
		)
		(pad "B1" smd circle
			(at -5.999988 -5.199888 180)
			(size 0.3556 0.3556)
			(layers "F.Cu" "F.Mask" "F.Paste")
			(net "RST_PCIE_PCH_PERST_N")
		)
		(pad "B2" smd circle
			(at -5.199888 -5.199888 180)
			(size 0.3556 0.3556)
			(layers "F.Cu" "F.Mask" "F.Paste")
			(net "GND")
		)
		(pad "B3" smd circle
			(at -4.400042 -5.199888 180)
			(size 0.3556 0.3556)
			(layers "F.Cu" "F.Mask" "F.Paste")
			(net "FM_CTNR_PS_ON")
		)
		(pad "B4" smd circle
			(at -3.599942 -5.199888 180)
			(size 0.3556 0.3556)
			(layers "F.Cu" "F.Mask" "F.Paste")
			(net "PWRGD_PVTT_CPU0")
		)
		(pad "B5" smd circle
			(at -2.800096 -5.199888 180)
			(size 0.3556 0.3556)
			(layers "F.Cu" "F.Mask" "F.Paste")
			(net "PWRGD_P12V_MAIN")
		)
		(pad "B6" smd circle
			(at -1.999996 -5.199888 180)
			(size 0.3556 0.3556)
			(layers "F.Cu" "F.Mask" "F.Paste")
			(net "TP_CPLD1_PT11B")
		)
		(pad "B7" smd circle
			(at -1.199896 -5.199888 180)
			(size 0.3556 0.3556)
			(layers "F.Cu" "F.Mask" "F.Paste")
			(net "TP_CPLD1_PT13A")
		)
		(pad "B8" smd circle
			(at -0.40005 -5.199888 180)
			(size 0.3556 0.3556)
			(layers "F.Cu" "F.Mask" "F.Paste")
			(net "JTAG_PLD_TMS")
		)
		(pad "B9" smd circle
			(at 0.40005 -5.199888 180)
			(size 0.3556 0.3556)
			(layers "F.Cu" "F.Mask" "F.Paste")
			(net "PU_RST_PERST_BIT1")
		)
		(pad "B10" smd circle
			(at 1.199896 -5.199888 180)
			(size 0.3556 0.3556)
			(layers "F.Cu" "F.Mask" "F.Paste")
			(net "PU_CPLD1_PT20D_PROGRAMN")
		)
		(pad "B11" smd circle
			(at 1.999996 -5.199888 180)
			(size 0.3556 0.3556)
			(layers "F.Cu" "F.Mask" "F.Paste")
			(net "PWRGD_DSW_PWROK")
		)
		(pad "B12" smd circle
			(at 2.800096 -5.199888 180)
			(size 0.3556 0.3556)
			(layers "F.Cu" "F.Mask" "F.Paste")
			(net "FM_PCH_PWRBTN_R1_N")
		)
		(pad "B13" smd circle
			(at 3.599942 -5.199888 180)
			(size 0.3556 0.3556)
			(layers "F.Cu" "F.Mask" "F.Paste")
			(net "TP_CPLD1_PT22C")
		)
		(pad "B14" smd circle
			(at 4.400042 -5.199888 180)
			(size 0.3556 0.3556)
			(layers "F.Cu" "F.Mask" "F.Paste")
			(net "FM_SINT_PRSNT_N")
		)
		(pad "B15" smd circle
			(at 5.199888 -5.199888 180)
			(size 0.3556 0.3556)
			(layers "F.Cu" "F.Mask" "F.Paste")
			(net "GND")
		)
		(pad "B16" smd circle
			(at 5.999988 -5.199888 180)
			(size 0.3556 0.3556)
			(layers "F.Cu" "F.Mask" "F.Paste")
			(net "FM_ADR_COMPLETE_DLY")
		)
		(pad "C1" smd circle
			(at -5.999988 -4.400042 180)
			(size 0.3556 0.3556)
			(layers "F.Cu" "F.Mask" "F.Paste")
			(net "RST_PCIE_CPU_DEV1_N")
		)
		(pad "C2" smd circle
			(at -5.199888 -4.400042 180)
			(size 0.3556 0.3556)
			(layers "F.Cu" "F.Mask" "F.Paste")
			(net "FM_PCH_PLD_DATA")
		)
		(pad "C3" smd circle
			(at -4.400042 -4.400042 180)
			(size 0.3556 0.3556)
			(layers "F.Cu" "F.Mask" "F.Paste")
			(net "GND")
		)
		(pad "C4" smd circle
			(at -3.599942 -4.400042 180)
			(size 0.3556 0.3556)
			(layers "F.Cu" "F.Mask" "F.Paste")
			(net "FM_ADR_SMI_GPIO_R_N")
		)
		(pad "C5" smd circle
			(at -2.800096 -4.400042 180)
			(size 0.3556 0.3556)
			(layers "F.Cu" "F.Mask" "F.Paste")
			(net "FM_CPU1_THERMTRIP_LATCH_LVT3_N")
		)
		(pad "C6" smd circle
			(at -1.999996 -4.400042 180)
			(size 0.3556 0.3556)
			(layers "F.Cu" "F.Mask" "F.Paste")
			(net "JTAG_PLD_TDO")
		)
		(pad "C7" smd circle
			(at -1.199896 -4.400042 180)
			(size 0.3556 0.3556)
			(layers "F.Cu" "F.Mask" "F.Paste")
			(net "FM_BMC_ONCTL_N")
		)
		(pad "C8" smd circle
			(at -0.40005 -4.400042 180)
			(size 0.3556 0.3556)
			(layers "F.Cu" "F.Mask" "F.Paste")
			(net "FM_ADR_COMPLETE")
		)
		(pad "C9" smd circle
			(at 0.40005 -4.400042 180)
			(size 0.3556 0.3556)
			(layers "F.Cu" "F.Mask" "F.Paste")
			(net "SMB_SENSOR_STBY_LVC3_SDA")
		)
		(pad "C10" smd circle
			(at 1.199896 -4.400042 180)
			(size 0.3556 0.3556)
			(layers "F.Cu" "F.Mask" "F.Paste")
			(net "FM_JTAG_PLD_EN_DEBUG")
		)
		(pad "C11" smd circle
			(at 1.999996 -4.400042 180)
			(size 0.3556 0.3556)
			(layers "F.Cu" "F.Mask" "F.Paste")
			(net "FM_CPU0_CD_PRES")
		)
		(pad "C12" smd circle
			(at 2.800096 -4.400042 180)
			(size 0.3556 0.3556)
			(layers "F.Cu" "F.Mask" "F.Paste")
			(net "FM_SLPS4_N")
		)
		(pad "C13" smd circle
			(at 3.599942 -4.400042 180)
			(size 0.3556 0.3556)
			(layers "F.Cu" "F.Mask" "F.Paste")
			(net "TP_CPLD1_PT24D_DONE")
		)
		(pad "C14" smd circle
			(at 4.400042 -4.400042 180)
			(size 0.3556 0.3556)
			(layers "F.Cu" "F.Mask" "F.Paste")
			(net "GND")
		)
		(pad "C15" smd circle
			(at 5.199888 -4.400042 180)
			(size 0.3556 0.3556)
			(layers "F.Cu" "F.Mask" "F.Paste")
			(net "FM_DB1200_PWRGD")
		)
		(pad "C16" smd circle
			(at 5.999988 -4.400042 180)
			(size 0.3556 0.3556)
			(layers "F.Cu" "F.Mask" "F.Paste")
			(net "PWRGD_PCH_PWROK")
		)
		(pad "D1" smd circle
			(at -5.999988 -3.599942 180)
			(size 0.3556 0.3556)
			(layers "F.Cu" "F.Mask" "F.Paste")
			(net "TP_CPLD1_PL1B_L_GPLLC_FB")
		)
		(pad "D2" smd circle
			(at -5.199888 -3.599942 180)
			(size 0.3556 0.3556)
			(layers "F.Cu" "F.Mask" "F.Paste")
			(net "FM_MEM_EVENT_FUNC")
		)
		(pad "D3" smd circle
			(at -4.400042 -3.599942 180)
			(size 0.3556 0.3556)
			(layers "F.Cu" "F.Mask" "F.Paste")
			(net "TP_CPLD1_PL1A_L_GPLLT_FB")
		)
		(pad "D4" smd circle
			(at -3.599942 -3.599942 180)
			(size 0.3556 0.3556)
			(layers "F.Cu" "F.Mask" "F.Paste")
			(net "GND")
		)
		(pad "D5" smd circle
			(at -2.800096 -3.599942 180)
			(size 0.3556 0.3556)
			(layers "F.Cu" "F.Mask" "F.Paste")
			(net "P3V3_STBY")
		)
		(pad "D6" smd circle
			(at -1.999996 -3.599942 180)
			(size 0.3556 0.3556)
			(layers "F.Cu" "F.Mask" "F.Paste")
			(net "RST_PCIE_CPU_DEV0_N")
		)
		(pad "D7" smd circle
			(at -1.199896 -3.599942 180)
			(size 0.3556 0.3556)
			(layers "F.Cu" "F.Mask" "F.Paste")
			(net "FM_FORCE_ADR_N")
		)
		(pad "D8" smd circle
			(at -0.40005 -3.599942 180)
			(size 0.3556 0.3556)
			(layers "F.Cu" "F.Mask" "F.Paste")
			(net "TP_CPLD1_PT17C")
		)
		(pad "D9" smd circle
			(at 0.40005 -3.599942 180)
			(size 0.3556 0.3556)
			(layers "F.Cu" "F.Mask" "F.Paste")
			(net "RST_PCIE_MIDPLANE_N")
		)
		(pad "D10" smd circle
			(at 1.199896 -3.599942 180)
			(size 0.3556 0.3556)
			(layers "F.Cu" "F.Mask" "F.Paste")
			(net "TP_CPLD1_PT20A")
		)
		(pad "D11" smd circle
			(at 1.999996 -3.599942 180)
			(size 0.3556 0.3556)
			(layers "F.Cu" "F.Mask" "F.Paste")
			(net "FM_CPU0_AND_CPU1_MCP_PRES")
		)
		(pad "D12" smd circle
			(at 2.800096 -3.599942 180)
			(size 0.3556 0.3556)
			(layers "F.Cu" "F.Mask" "F.Paste")
			(net "P3V3_STBY")
		)
		(pad "D13" smd circle
			(at 3.599942 -3.599942 180)
			(size 0.3556 0.3556)
			(layers "F.Cu" "F.Mask" "F.Paste")
			(net "GND")
		)
		(pad "D14" smd circle
			(at 4.400042 -3.599942 180)
			(size 0.3556 0.3556)
			(layers "F.Cu" "F.Mask" "F.Paste")
			(net "PWRGD_SYS_PWROK")
		)
		(pad "D15" smd circle
			(at 5.199888 -3.599942 180)
			(size 0.3556 0.3556)
			(layers "F.Cu" "F.Mask" "F.Paste")
			(net "PWRGD_P1V8MCP_CPU0")
		)
		(pad "D16" smd circle
			(at 5.999988 -3.599942 180)
			(size 0.3556 0.3556)
			(layers "F.Cu" "F.Mask" "F.Paste")
			(net "PWRGD_P1V8MCP_CPU1")
		)
		(pad "E1" smd circle
			(at -5.999988 -2.800096 180)
			(size 0.3556 0.3556)
			(layers "F.Cu" "F.Mask" "F.Paste")
			(net "CLK_32K_SUSCLK_PLD")
		)
		(pad "E2" smd circle
			(at -5.199888 -2.800096 180)
			(size 0.3556 0.3556)
			(layers "F.Cu" "F.Mask" "F.Paste")
			(net "FM_CPU_CATERR_DLY_LVT3_N")
		)
		(pad "E3" smd circle
			(at -4.400042 -2.800096 180)
			(size 0.3556 0.3556)
			(layers "F.Cu" "F.Mask" "F.Paste")
			(net "TP_CPLD1_PL2B_L_GPLLC_IN")
		)
		(pad "E4" smd circle
			(at -3.599942 -2.800096 180)
			(size 0.3556 0.3556)
			(layers "F.Cu" "F.Mask" "F.Paste")
			(net "P3V3_STBY")
		)
		(pad "E5" smd circle
			(at -2.800096 -2.800096 180)
			(size 0.3556 0.3556)
			(layers "F.Cu" "F.Mask" "F.Paste")
			(net "GND")
		)
		(pad "E6" smd circle
			(at -1.999996 -2.800096 180)
			(size 0.3556 0.3556)
			(layers "F.Cu" "F.Mask" "F.Paste")
			(net "FM_CPU1_FIVR_FAULT_LVT3_N")
		)
		(pad "E7" smd circle
			(at -1.199896 -2.800096 180)
			(size 0.3556 0.3556)
			(layers "F.Cu" "F.Mask" "F.Paste")
			(net "PWRGD_P1V15_BMC_STBY")
		)
		(pad "E8" smd circle
			(at -0.40005 -2.800096 180)
			(size 0.3556 0.3556)
			(layers "F.Cu" "F.Mask" "F.Paste")
			(net "TP_CPLD1_PT16B")
		)
		(pad "E9" smd circle
			(at 0.40005 -2.800096 180)
			(size 0.3556 0.3556)
			(layers "F.Cu" "F.Mask" "F.Paste")
			(net "FM_SLP_SUS_N")
		)
		(pad "E10" smd circle
			(at 1.199896 -2.800096 180)
			(size 0.3556 0.3556)
			(layers "F.Cu" "F.Mask" "F.Paste")
			(net "TP_CPLD1_PT20B")
		)
		(pad "E11" smd circle
			(at 1.999996 -2.800096 180)
			(size 0.3556 0.3556)
			(layers "F.Cu" "F.Mask" "F.Paste")
			(net "TP_CPLD1_PT19D")
		)
		(pad "E12" smd circle
			(at 2.800096 -2.800096 180)
			(size 0.3556 0.3556)
			(layers "F.Cu" "F.Mask" "F.Paste")
			(net "GND")
		)
		(pad "E13" smd circle
			(at 3.599942 -2.800096 180)
			(size 0.3556 0.3556)
			(layers "F.Cu" "F.Mask" "F.Paste")
			(net "P3V3_STBY")
		)
		(pad "E14" smd circle
			(at 4.400042 -2.800096 180)
			(size 0.3556 0.3556)
			(layers "F.Cu" "F.Mask" "F.Paste")
			(net "FM_CPLD_ADR_TRIGGER_N")
		)
		(pad "E15" smd circle
			(at 5.199888 -2.800096 180)
			(size 0.3556 0.3556)
			(layers "F.Cu" "F.Mask" "F.Paste")
			(net "RST_PLTRST_N")
		)
		(pad "E16" smd circle
			(at 5.999988 -2.800096 180)
			(size 0.3556 0.3556)
			(layers "F.Cu" "F.Mask" "F.Paste")
			(net "FM_P1V8MCP_CPU0_EN")
		)
		(pad "F1" smd circle
			(at -5.999988 -1.999996 180)
			(size 0.3556 0.3556)
			(layers "F.Cu" "F.Mask" "F.Paste")
			(net "FM_CPU0_PROC_ID0")
		)
		(pad "F2" smd circle
			(at -5.199888 -1.999996 180)
			(size 0.3556 0.3556)
			(layers "F.Cu" "F.Mask" "F.Paste")
			(net "FM_CPU0_PKGID0")
		)
		(pad "F3" smd circle
			(at -4.400042 -1.999996 180)
			(size 0.3556 0.3556)
			(layers "F.Cu" "F.Mask" "F.Paste")
			(net "FM_CPU0_PROC_ID1")
		)
		(pad "F4" smd circle
			(at -3.599942 -1.999996 180)
			(size 0.3556 0.3556)
			(layers "F.Cu" "F.Mask" "F.Paste")
			(net "PU_RST_PERST_BIT0")
		)
		(pad "F5" smd circle
			(at -2.800096 -1.999996 180)
			(size 0.3556 0.3556)
			(layers "F.Cu" "F.Mask" "F.Paste")
			(net "FM_CPU0_FIVR_FAULT_LVT3_N")
		)
		(pad "F6" smd circle
			(at -1.999996 -1.999996 180)
			(size 0.3556 0.3556)
			(layers "F.Cu" "F.Mask" "F.Paste")
			(net "GND")
		)
		(pad "F7" smd circle
			(at -1.199896 -1.999996 180)
			(size 0.3556 0.3556)
			(layers "F.Cu" "F.Mask" "F.Paste")
			(net "FM_PLD_DEBUG_MODE_N")
		)
		(pad "F8" smd circle
			(at -0.40005 -1.999996 180)
			(size 0.3556 0.3556)
			(layers "F.Cu" "F.Mask" "F.Paste")
			(net "SGPIO_BMC_DIN_R")
		)
		(pad "F9" smd circle
			(at 0.40005 -1.999996 180)
			(size 0.3556 0.3556)
			(layers "F.Cu" "F.Mask" "F.Paste")
			(net "FM_PS_EN")
		)
		(pad "F10" smd circle
			(at 1.199896 -1.999996 180)
			(size 0.3556 0.3556)
			(layers "F.Cu" "F.Mask" "F.Paste")
			(net "FM_CPU1_CD_PRES_N")
		)
		(pad "F11" smd circle
			(at 1.999996 -1.999996 180)
			(size 0.3556 0.3556)
			(layers "F.Cu" "F.Mask" "F.Paste")
			(net "GND")
		)
		(pad "F12" smd circle
			(at 2.800096 -1.999996 180)
			(size 0.3556 0.3556)
			(layers "F.Cu" "F.Mask" "F.Paste")
			(net "FM_P1V8MCP_CPU1_EN")
		)
		(pad "F13" smd circle
			(at 3.599942 -1.999996 180)
			(size 0.3556 0.3556)
			(layers "F.Cu" "F.Mask" "F.Paste")
			(net "PWRGD_CPUPWRGD")
		)
		(pad "F14" smd circle
			(at 4.400042 -1.999996 180)
			(size 0.3556 0.3556)
			(layers "F.Cu" "F.Mask" "F.Paste")
			(net "RST_BMC_SYSRST_BTN_OUT_B_R1_N")
		)
		(pad "F15" smd circle
			(at 5.199888 -1.999996 180)
			(size 0.3556 0.3556)
			(layers "F.Cu" "F.Mask" "F.Paste")
			(net "FM_CPU0_MCP_CLK_EN_N")
		)
		(pad "F16" smd circle
			(at 5.999988 -1.999996 180)
			(size 0.3556 0.3556)
			(layers "F.Cu" "F.Mask" "F.Paste")
			(net "FM_CPU1_MCP_CLK_EN_N")
		)
		(pad "G1" smd circle
			(at -5.999988 -1.199896 180)
			(size 0.3556 0.3556)
			(layers "F.Cu" "F.Mask" "F.Paste")
			(net "FM_SLPS3_N")
		)
		(pad "G2" smd circle
			(at -5.199888 -1.199896 180)
			(size 0.3556 0.3556)
			(layers "F.Cu" "F.Mask" "F.Paste")
			(net "FM_CPU0_PKGID2")
		)
		(pad "G3" smd circle
			(at -4.400042 -1.199896 180)
			(size 0.3556 0.3556)
			(layers "F.Cu" "F.Mask" "F.Paste")
			(net "FM_CPU0_PKGID1")
		)
		(pad "G4" smd circle
			(at -3.599942 -1.199896 180)
			(size 0.3556 0.3556)
			(layers "F.Cu" "F.Mask" "F.Paste")
			(net "RST_RSMRST_R_N")
		)
		(pad "G5" smd circle
			(at -2.800096 -1.199896 180)
			(size 0.3556 0.3556)
			(layers "F.Cu" "F.Mask" "F.Paste")
			(net "FM_DEBUG_RST_BTN_N")
		)
		(pad "G6" smd circle
			(at -1.999996 -1.199896 180)
			(size 0.3556 0.3556)
			(layers "F.Cu" "F.Mask" "F.Paste")
			(net "FM_PWR_BTN_R2_N")
		)
		(pad "G7" smd circle
			(at -1.199896 -1.199896 180)
			(size 0.3556 0.3556)
			(layers "F.Cu" "F.Mask" "F.Paste")
			(net "P3V3_STBY")
		)
		(pad "G8" smd circle
			(at -0.40005 -1.199896 180)
			(size 0.3556 0.3556)
			(layers "F.Cu" "F.Mask" "F.Paste")
			(net "P3V3_STBY")
		)
		(pad "G9" smd circle
			(at 0.40005 -1.199896 180)
			(size 0.3556 0.3556)
			(layers "F.Cu" "F.Mask" "F.Paste")
			(net "P3V3_STBY")
		)
		(pad "G10" smd circle
			(at 1.199896 -1.199896 180)
			(size 0.3556 0.3556)
			(layers "F.Cu" "F.Mask" "F.Paste")
			(net "P3V3_STBY")
		)
		(pad "G11" smd circle
			(at 1.999996 -1.199896 180)
			(size 0.3556 0.3556)
			(layers "F.Cu" "F.Mask" "F.Paste")
			(net "FM_WBG_PRSNT_N")
		)
		(pad "G12" smd circle
			(at 2.800096 -1.199896 180)
			(size 0.3556 0.3556)
			(layers "F.Cu" "F.Mask" "F.Paste")
			(net "FM_CPU0_THERMTRIP_LATCH_LVT3_N")
		)
		(pad "G13" smd circle
			(at 3.599942 -1.199896 180)
			(size 0.3556 0.3556)
			(layers "F.Cu" "F.Mask" "F.Paste")
			(net "FM_CPU1_FIVR_FAULT_LVT3")
		)
		(pad "G14" smd circle
			(at 4.400042 -1.199896 180)
			(size 0.3556 0.3556)
			(layers "F.Cu" "F.Mask" "F.Paste")
			(net "FM_CPU1_THERMTRIP_LVT3_N")
		)
		(pad "G15" smd circle
			(at 5.199888 -1.199896 180)
			(size 0.3556 0.3556)
			(layers "F.Cu" "F.Mask" "F.Paste")
			(net "FM_UV_ADR_TRIGGER_N")
		)
		(pad "G16" smd circle
			(at 5.999988 -1.199896 180)
			(size 0.3556 0.3556)
			(layers "F.Cu" "F.Mask" "F.Paste")
			(net "FM_FAST_PROCHOT_THROTTLE_IN_N")
		)
		(pad "H1" smd circle
			(at -5.999988 -0.40005 180)
			(size 0.3556 0.3556)
			(layers "F.Cu" "F.Mask" "F.Paste")
			(net "RST_PCIE_CPU_DEV3_N")
		)
		(pad "H2" smd circle
			(at -5.199888 -0.40005 180)
			(size 0.3556 0.3556)
			(layers "F.Cu" "F.Mask" "F.Paste")
			(net "FM_PVCCMCP_CPU0_EN")
		)
		(pad "H3" smd circle
			(at -4.400042 -0.40005 180)
			(size 0.3556 0.3556)
			(layers "F.Cu" "F.Mask" "F.Paste")
			(net "RST_PCIE_CPU_DEV2_N")
		)
		(pad "H4" smd circle
			(at -3.599942 -0.40005 180)
			(size 0.3556 0.3556)
			(layers "F.Cu" "F.Mask" "F.Paste")
			(net "FM_MP_PS_FAIL_N")
		)
		(pad "H5" smd circle
			(at -2.800096 -0.40005 180)
			(size 0.3556 0.3556)
			(layers "F.Cu" "F.Mask" "F.Paste")
			(net "Net_480")
		)
		(pad "H6" smd circle
			(at -1.999996 -0.40005 180)
			(size 0.3556 0.3556)
			(layers "F.Cu" "F.Mask" "F.Paste")
			(net "PWRGD_P3V3")
		)
		(pad "H7" smd circle
			(at -1.199896 -0.40005 180)
			(size 0.3556 0.3556)
			(layers "F.Cu" "F.Mask" "F.Paste")
			(net "P3V3_STBY")
		)
		(pad "H8" smd circle
			(at -0.40005 -0.40005 180)
			(size 0.3556 0.3556)
			(layers "F.Cu" "F.Mask" "F.Paste")
			(net "GND")
		)
		(pad "H9" smd circle
			(at 0.40005 -0.40005 180)
			(size 0.3556 0.3556)
			(layers "F.Cu" "F.Mask" "F.Paste")
			(net "GND")
		)
		(pad "H10" smd circle
			(at 1.199896 -0.40005 180)
			(size 0.3556 0.3556)
			(layers "F.Cu" "F.Mask" "F.Paste")
			(net "P3V3_STBY")
		)
		(pad "H11" smd circle
			(at 1.999996 -0.40005 180)
			(size 0.3556 0.3556)
			(layers "F.Cu" "F.Mask" "F.Paste")
			(net "TP_CPLD1_PR9C")
		)
		(pad "H12" smd circle
			(at 2.800096 -0.40005 180)
			(size 0.3556 0.3556)
			(layers "F.Cu" "F.Mask" "F.Paste")
			(net "FM_UV_ADR_TRIGGER_EN")
		)
		(pad "H13" smd circle
			(at 3.599942 -0.40005 180)
			(size 0.3556 0.3556)
			(layers "F.Cu" "F.Mask" "F.Paste")
			(net "FM_PVDDQ_GHJ_EN")
		)
		(pad "H14" smd circle
			(at 4.400042 -0.40005 180)
			(size 0.3556 0.3556)
			(layers "F.Cu" "F.Mask" "F.Paste")
			(net "TP_CPLD1_PR7A_PCLKT1_0")
		)
		(pad "H15" smd circle
			(at 5.199888 -0.40005 180)
			(size 0.3556 0.3556)
			(layers "F.Cu" "F.Mask" "F.Paste")
			(net "FM_PVDDQ_KLM_EN")
		)
		(pad "H16" smd circle
			(at 5.999988 -0.40005 180)
			(size 0.3556 0.3556)
			(layers "F.Cu" "F.Mask" "F.Paste")
			(net "TP_CPLD1_PR7B_PCLKC1_0")
		)
		(pad "J1" smd circle
			(at -5.999988 0.40005 180)
			(size 0.3556 0.3556)
			(layers "F.Cu" "F.Mask" "F.Paste")
			(net "SGPIO_BMC_CLK")
		)
		(pad "J2" smd circle
			(at -5.199888 0.40005 180)
			(size 0.3556 0.3556)
			(layers "F.Cu" "F.Mask" "F.Paste")
			(net "SGPIO_BMC_DOUT")
		)
		(pad "J3" smd circle
			(at -4.400042 0.40005 180)
			(size 0.3556 0.3556)
			(layers "F.Cu" "F.Mask" "F.Paste")
			(net "TP_CPLD1_PL7D_PCLKT4_0")
		)
		(pad "J4" smd circle
			(at -3.599942 0.40005 180)
			(size 0.3556 0.3556)
			(layers "F.Cu" "F.Mask" "F.Paste")
			(net "Net_481")
		)
		(pad "J5" smd circle
			(at -2.800096 0.40005 180)
			(size 0.3556 0.3556)
			(layers "F.Cu" "F.Mask" "F.Paste")
			(net "UART_BMC_RXD5")
		)
		(pad "J6" smd circle
			(at -1.999996 0.40005 180)
			(size 0.3556 0.3556)
			(layers "F.Cu" "F.Mask" "F.Paste")
			(net "PWRGD_P5V")
		)
		(pad "J7" smd circle
			(at -1.199896 0.40005 180)
			(size 0.3556 0.3556)
			(layers "F.Cu" "F.Mask" "F.Paste")
			(net "P3V3_STBY")
		)
		(pad "J8" smd circle
			(at -0.40005 0.40005 180)
			(size 0.3556 0.3556)
			(layers "F.Cu" "F.Mask" "F.Paste")
			(net "GND")
		)
		(pad "J9" smd circle
			(at 0.40005 0.40005 180)
			(size 0.3556 0.3556)
			(layers "F.Cu" "F.Mask" "F.Paste")
			(net "GND")
		)
		(pad "J10" smd circle
			(at 1.199896 0.40005 180)
			(size 0.3556 0.3556)
			(layers "F.Cu" "F.Mask" "F.Paste")
			(net "P3V3_STBY")
		)
		(pad "J11" smd circle
			(at 1.999996 0.40005 180)
			(size 0.3556 0.3556)
			(layers "F.Cu" "F.Mask" "F.Paste")
			(net "TP_CPLD1_PR10C")
		)
		(pad "J12" smd circle
			(at 2.800096 0.40005 180)
			(size 0.3556 0.3556)
			(layers "F.Cu" "F.Mask" "F.Paste")
			(net "FM_FAST_PROCHOT_THROTTLE_DLY_N")
		)
		(pad "J13" smd circle
			(at 3.599942 0.40005 180)
			(size 0.3556 0.3556)
			(layers "F.Cu" "F.Mask" "F.Paste")
			(net "TP_CPLD1_PR9D")
		)
		(pad "J14" smd circle
			(at 4.400042 0.40005 180)
			(size 0.3556 0.3556)
			(layers "F.Cu" "F.Mask" "F.Paste")
			(net "TP_CPLD1_PR7D")
		)
		(pad "J15" smd circle
			(at 5.199888 0.40005 180)
			(size 0.3556 0.3556)
			(layers "F.Cu" "F.Mask" "F.Paste")
			(net "TP_CPLD1_PR9A")
		)
		(pad "J16" smd circle
			(at 5.999988 0.40005 180)
			(size 0.3556 0.3556)
			(layers "F.Cu" "F.Mask" "F.Paste")
			(net "TP_CPLD1_PR7C")
		)
		(pad "K1" smd circle
			(at -5.999988 1.199896 180)
			(size 0.3556 0.3556)
			(layers "F.Cu" "F.Mask" "F.Paste")
			(net "FM_PVCCIOMCP_CPU0_EN")
		)
		(pad "K2" smd circle
			(at -5.199888 1.199896 180)
			(size 0.3556 0.3556)
			(layers "F.Cu" "F.Mask" "F.Paste")
			(net "SP1_BMC_HOST_UART_TX")
		)
		(pad "K3" smd circle
			(at -4.400042 1.199896 180)
			(size 0.3556 0.3556)
			(layers "F.Cu" "F.Mask" "F.Paste")
			(net "SP1_BMC_HOST_UART_RX")
		)
		(pad "K4" smd circle
			(at -3.599942 1.199896 180)
			(size 0.3556 0.3556)
			(layers "F.Cu" "F.Mask" "F.Paste")
			(net "SGPIO_BMC_LD_N")
		)
		(pad "K5" smd circle
			(at -2.800096 1.199896 180)
			(size 0.3556 0.3556)
			(layers "F.Cu" "F.Mask" "F.Paste")
			(net "PWRGD_PVCCIN_CPU0")
		)
		(pad "K6" smd circle
			(at -1.999996 1.199896 180)
			(size 0.3556 0.3556)
			(layers "F.Cu" "F.Mask" "F.Paste")
			(net "UART_BMC_TXD5")
		)
		(pad "K7" smd circle
			(at -1.199896 1.199896 180)
			(size 0.3556 0.3556)
			(layers "F.Cu" "F.Mask" "F.Paste")
			(net "P3V3_STBY")
		)
		(pad "K8" smd circle
			(at -0.40005 1.199896 180)
			(size 0.3556 0.3556)
			(layers "F.Cu" "F.Mask" "F.Paste")
			(net "P3V3_STBY")
		)
		(pad "K9" smd circle
			(at 0.40005 1.199896 180)
			(size 0.3556 0.3556)
			(layers "F.Cu" "F.Mask" "F.Paste")
			(net "P3V3_STBY")
		)
		(pad "K10" smd circle
			(at 1.199896 1.199896 180)
			(size 0.3556 0.3556)
			(layers "F.Cu" "F.Mask" "F.Paste")
			(net "P3V3_STBY")
		)
		(pad "K11" smd circle
			(at 1.999996 1.199896 180)
			(size 0.3556 0.3556)
			(layers "F.Cu" "F.Mask" "F.Paste")
			(net "RST_PLTRST_BUF_N")
		)
		(pad "K12" smd circle
			(at 2.800096 1.199896 180)
			(size 0.3556 0.3556)
			(layers "F.Cu" "F.Mask" "F.Paste")
			(net "FM_MEM_THERM_EVENT_PCH_N")
		)
		(pad "K13" smd circle
			(at 3.599942 1.199896 180)
			(size 0.3556 0.3556)
			(layers "F.Cu" "F.Mask" "F.Paste")
			(net "FM_MEM_THERM_EVENT_LVT3_N")
		)
		(pad "K14" smd circle
			(at 4.400042 1.199896 180)
			(size 0.3556 0.3556)
			(layers "F.Cu" "F.Mask" "F.Paste")
			(net "FM_PVDDQ_ABC_EN")
		)
		(pad "K15" smd circle
			(at 5.199888 1.199896 180)
			(size 0.3556 0.3556)
			(layers "F.Cu" "F.Mask" "F.Paste")
			(net "FM_PVDDQ_DEF_EN")
		)
		(pad "K16" smd circle
			(at 5.999988 1.199896 180)
			(size 0.3556 0.3556)
			(layers "F.Cu" "F.Mask" "F.Paste")
			(net "PU_FAB2_MARKER_CPLD")
		)
		(pad "L1" smd circle
			(at -5.999988 1.999996 180)
			(size 0.3556 0.3556)
			(layers "F.Cu" "F.Mask" "F.Paste")
			(net "PWRGD_PVSA_CPU0")
		)
		(pad "L2" smd circle
			(at -5.199888 1.999996 180)
			(size 0.3556 0.3556)
			(layers "F.Cu" "F.Mask" "F.Paste")
			(net "CLK_25M_CPLD")
		)
		(pad "L3" smd circle
			(at -4.400042 1.999996 180)
			(size 0.3556 0.3556)
			(layers "F.Cu" "F.Mask" "F.Paste")
			(net "TP_CPLD1_PL11A")
		)
		(pad "L4" smd circle
			(at -3.599942 1.999996 180)
			(size 0.3556 0.3556)
			(layers "F.Cu" "F.Mask" "F.Paste")
			(net "PWRGD_PVCCMCP_CPU1")
		)
		(pad "L5" smd circle
			(at -2.800096 1.999996 180)
			(size 0.3556 0.3556)
			(layers "F.Cu" "F.Mask" "F.Paste")
			(net "PWRGD_CPU0_LVC3")
		)
		(pad "L6" smd circle
			(at -1.999996 1.999996 180)
			(size 0.3556 0.3556)
			(layers "F.Cu" "F.Mask" "F.Paste")
			(net "GND")
		)
		(pad "L7" smd circle
			(at -1.199896 1.999996 180)
			(size 0.3556 0.3556)
			(layers "F.Cu" "F.Mask" "F.Paste")
			(net "FM_OC0_USB_N")
		)
		(pad "L8" smd circle
			(at -0.40005 1.999996 180)
			(size 0.3556 0.3556)
			(layers "F.Cu" "F.Mask" "F.Paste")
			(net "PWRGD_PVCCIO_CPU0")
		)
		(pad "L9" smd circle
			(at 0.40005 1.999996 180)
			(size 0.3556 0.3556)
			(layers "F.Cu" "F.Mask" "F.Paste")
			(net "FM_IE_DISABLE_N")
		)
		(pad "L10" smd circle
			(at 1.199896 1.999996 180)
			(size 0.3556 0.3556)
			(layers "F.Cu" "F.Mask" "F.Paste")
			(net "FM_SOL_UART_CH_SEL")
		)
		(pad "L11" smd circle
			(at 1.999996 1.999996 180)
			(size 0.3556 0.3556)
			(layers "F.Cu" "F.Mask" "F.Paste")
			(net "GND")
		)
		(pad "L12" smd circle
			(at 2.800096 1.999996 180)
			(size 0.3556 0.3556)
			(layers "F.Cu" "F.Mask" "F.Paste")
			(net "PWRGD_P3V3_STBY")
		)
		(pad "L13" smd circle
			(at 3.599942 1.999996 180)
			(size 0.3556 0.3556)
			(layers "F.Cu" "F.Mask" "F.Paste")
			(net "TP_CPLD1_PR12D")
		)
		(pad "L14" smd circle
			(at 4.400042 1.999996 180)
			(size 0.3556 0.3556)
			(layers "F.Cu" "F.Mask" "F.Paste")
			(net "TP_CPLD1_PR11B")
		)
		(pad "L15" smd circle
			(at 5.199888 1.999996 180)
			(size 0.3556 0.3556)
			(layers "F.Cu" "F.Mask" "F.Paste")
			(net "FM_THERMTRIP_DLY")
		)
		(pad "L16" smd circle
			(at 5.999988 1.999996 180)
			(size 0.3556 0.3556)
			(layers "F.Cu" "F.Mask" "F.Paste")
			(net "PWRGD_PVCCIO_CPU1")
		)
		(pad "M1" smd circle
			(at -5.999988 2.800096 180)
			(size 0.3556 0.3556)
			(layers "F.Cu" "F.Mask" "F.Paste")
			(net "RST_RSMRST_DLY")
		)
		(pad "M2" smd circle
			(at -5.199888 2.800096 180)
			(size 0.3556 0.3556)
			(layers "F.Cu" "F.Mask" "F.Paste")
			(net "PWRGD_PVPP_GHJ")
		)
		(pad "M3" smd circle
			(at -4.400042 2.800096 180)
			(size 0.3556 0.3556)
			(layers "F.Cu" "F.Mask" "F.Paste")
			(net "RST_PCIE_RISER1_PERST_N")
		)
		(pad "M4" smd circle
			(at -3.599942 2.800096 180)
			(size 0.3556 0.3556)
			(layers "F.Cu" "F.Mask" "F.Paste")
			(net "P3V3_STBY")
		)
		(pad "M5" smd circle
			(at -2.800096 2.800096 180)
			(size 0.3556 0.3556)
			(layers "F.Cu" "F.Mask" "F.Paste")
			(net "GND")
		)
		(pad "M6" smd circle
			(at -1.999996 2.800096 180)
			(size 0.3556 0.3556)
			(layers "F.Cu" "F.Mask" "F.Paste")
			(net "PWRGD_PVPP_DEF")
		)
		(pad "M7" smd circle
			(at -1.199896 2.800096 180)
			(size 0.3556 0.3556)
			(layers "F.Cu" "F.Mask" "F.Paste")
			(net "FM_PVCCIO_CPU0_EN")
		)
		(pad "M8" smd circle
			(at -0.40005 2.800096 180)
			(size 0.3556 0.3556)
			(layers "F.Cu" "F.Mask" "F.Paste")
			(net "FM_PVCCMCP_CPU1_EN")
		)
		(pad "M9" smd circle
			(at 0.40005 2.800096 180)
			(size 0.3556 0.3556)
			(layers "F.Cu" "F.Mask" "F.Paste")
			(net "FM_CPLD_UART_CH_LOCK_N")
		)
		(pad "M10" smd circle
			(at 1.199896 2.800096 180)
			(size 0.3556 0.3556)
			(layers "F.Cu" "F.Mask" "F.Paste")
			(net "PWRGD_CPU1_LVC3")
		)
		(pad "M11" smd circle
			(at 1.999996 2.800096 180)
			(size 0.3556 0.3556)
			(layers "F.Cu" "F.Mask" "F.Paste")
			(net "XDP_PWRGD_RST_N")
		)
		(pad "M12" smd circle
			(at 2.800096 2.800096 180)
			(size 0.3556 0.3556)
			(layers "F.Cu" "F.Mask" "F.Paste")
			(net "GND")
		)
		(pad "M13" smd circle
			(at 3.599942 2.800096 180)
			(size 0.3556 0.3556)
			(layers "F.Cu" "F.Mask" "F.Paste")
			(net "P3V3_STBY")
		)
		(pad "M14" smd circle
			(at 4.400042 2.800096 180)
			(size 0.3556 0.3556)
			(layers "F.Cu" "F.Mask" "F.Paste")
			(net "FM_CPU1_PROC_ID1")
		)
		(pad "M15" smd circle
			(at 5.199888 2.800096 180)
			(size 0.3556 0.3556)
			(layers "F.Cu" "F.Mask" "F.Paste")
			(net "FM_CPU1_PROC_ID0")
		)
		(pad "M16" smd circle
			(at 5.999988 2.800096 180)
			(size 0.3556 0.3556)
			(layers "F.Cu" "F.Mask" "F.Paste")
			(net "FM_CPU0_FIVR_FAULT_LVT3")
		)
		(pad "N1" smd circle
			(at -5.999988 3.599942 180)
			(size 0.3556 0.3556)
			(layers "F.Cu" "F.Mask" "F.Paste")
			(net "PWRGD_PVCCIN_CPU1")
		)
		(pad "N2" smd circle
			(at -5.199888 3.599942 180)
			(size 0.3556 0.3556)
			(layers "F.Cu" "F.Mask" "F.Paste")
			(net "PWRGD_PVPP_KLM")
		)
		(pad "N3" smd circle
			(at -4.400042 3.599942 180)
			(size 0.3556 0.3556)
			(layers "F.Cu" "F.Mask" "F.Paste")
			(net "RST_CD_CPU0_POR_N")
		)
		(pad "N4" smd circle
			(at -3.599942 3.599942 180)
			(size 0.3556 0.3556)
			(layers "F.Cu" "F.Mask" "F.Paste")
			(net "GND")
		)
		(pad "N5" smd circle
			(at -2.800096 3.599942 180)
			(size 0.3556 0.3556)
			(layers "F.Cu" "F.Mask" "F.Paste")
			(net "P3V3_STBY")
		)
		(pad "N6" smd circle
			(at -1.999996 3.599942 180)
			(size 0.3556 0.3556)
			(layers "F.Cu" "F.Mask" "F.Paste")
			(net "PWRGD_PVCCIOMCP_CPU0")
		)
		(pad "N7" smd circle
			(at -1.199896 3.599942 180)
			(size 0.3556 0.3556)
			(layers "F.Cu" "F.Mask" "F.Paste")
			(net "PWRGD_PVPP_ABC")
		)
		(pad "N8" smd circle
			(at -0.40005 3.599942 180)
			(size 0.3556 0.3556)
			(layers "F.Cu" "F.Mask" "F.Paste")
			(net "FM_156M_CPU1_BRD_OSC_EN")
		)
		(pad "N9" smd circle
			(at 0.40005 3.599942 180)
			(size 0.3556 0.3556)
			(layers "F.Cu" "F.Mask" "F.Paste")
			(net "FM_CPLD_BMC_PWRDN_N")
		)
		(pad "N10" smd circle
			(at 1.199896 3.599942 180)
			(size 0.3556 0.3556)
			(layers "F.Cu" "F.Mask" "F.Paste")
			(net "RST_CPU1_LVC3_R1_N")
		)
		(pad "N11" smd circle
			(at 1.999996 3.599942 180)
			(size 0.3556 0.3556)
			(layers "F.Cu" "F.Mask" "F.Paste")
			(net "XDP_SYSPWROK")
		)
		(pad "N12" smd circle
			(at 2.800096 3.599942 180)
			(size 0.3556 0.3556)
			(layers "F.Cu" "F.Mask" "F.Paste")
			(net "P3V3_STBY")
		)
		(pad "N13" smd circle
			(at 3.599942 3.599942 180)
			(size 0.3556 0.3556)
			(layers "F.Cu" "F.Mask" "F.Paste")
			(net "GND")
		)
		(pad "N14" smd circle
			(at 4.400042 3.599942 180)
			(size 0.3556 0.3556)
			(layers "F.Cu" "F.Mask" "F.Paste")
			(net "FM_CPU1_VRM_OSC_EN")
		)
		(pad "N15" smd circle
			(at 5.199888 3.599942 180)
			(size 0.3556 0.3556)
			(layers "F.Cu" "F.Mask" "F.Paste")
			(net "FM_CPU0_THERMTRIP_LVT3_N")
		)
		(pad "N16" smd circle
			(at 5.999988 3.599942 180)
			(size 0.3556 0.3556)
			(layers "F.Cu" "F.Mask" "F.Paste")
			(net "FM_PVCCIN_PVCCSA_CPU1_EN_LVC1")
		)
		(pad "P1" smd circle
			(at -5.999988 4.400042 180)
			(size 0.3556 0.3556)
			(layers "F.Cu" "F.Mask" "F.Paste")
			(net "FM_GLOBAL_RST_WARN_N")
		)
		(pad "P2" smd circle
			(at -5.199888 4.400042 180)
			(size 0.3556 0.3556)
			(layers "F.Cu" "F.Mask" "F.Paste")
			(net "FM_UART_ALERT_N")
		)
		(pad "P3" smd circle
			(at -4.400042 4.400042 180)
			(size 0.3556 0.3556)
			(layers "F.Cu" "F.Mask" "F.Paste")
			(net "GND")
		)
		(pad "P4" smd circle
			(at -3.599942 4.400042 180)
			(size 0.3556 0.3556)
			(layers "F.Cu" "F.Mask" "F.Paste")
			(net "FM_CPU1_RC_EN")
		)
		(pad "P5" smd circle
			(at -2.800096 4.400042 180)
			(size 0.3556 0.3556)
			(layers "F.Cu" "F.Mask" "F.Paste")
			(net "PWRGD_PVCCMCP_CPU0")
		)
		(pad "P6" smd circle
			(at -1.999996 4.400042 180)
			(size 0.3556 0.3556)
			(layers "F.Cu" "F.Mask" "F.Paste")
			(net "TP_CPLD1_PB8A_MCLK_CCLK")
		)
		(pad "P7" smd circle
			(at -1.199896 4.400042 180)
			(size 0.3556 0.3556)
			(layers "F.Cu" "F.Mask" "F.Paste")
			(net "FM_PVCCIOMCP_CPU1_EN")
		)
		(pad "P8" smd circle
			(at -0.40005 4.400042 180)
			(size 0.3556 0.3556)
			(layers "F.Cu" "F.Mask" "F.Paste")
			(net "PWRGD_PVNN_P1V05_PCH")
		)
		(pad "P9" smd circle
			(at 0.40005 4.400042 180)
			(size 0.3556 0.3556)
			(layers "F.Cu" "F.Mask" "F.Paste")
			(net "TP_CPLD1_PB16B_PCLKC2_1")
		)
		(pad "P10" smd circle
			(at 1.199896 4.400042 180)
			(size 0.3556 0.3556)
			(layers "F.Cu" "F.Mask" "F.Paste")
			(net "RST_CD_CPU1_POR_N")
		)
		(pad "P11" smd circle
			(at 1.999996 4.400042 180)
			(size 0.3556 0.3556)
			(layers "F.Cu" "F.Mask" "F.Paste")
			(net "FM_UARTSW_MSB_N")
		)
		(pad "P12" smd circle
			(at 2.800096 4.400042 180)
			(size 0.3556 0.3556)
			(layers "F.Cu" "F.Mask" "F.Paste")
			(net "FM_CPU1_PKGID1")
		)
		(pad "P13" smd circle
			(at 3.599942 4.400042 180)
			(size 0.3556 0.3556)
			(layers "F.Cu" "F.Mask" "F.Paste")
			(net "TP_CPLD1_PB25B_SI_SISPI")
		)
		(pad "P14" smd circle
			(at 4.400042 4.400042 180)
			(size 0.3556 0.3556)
			(layers "F.Cu" "F.Mask" "F.Paste")
			(net "GND")
		)
		(pad "P15" smd circle
			(at 5.199888 4.400042 180)
			(size 0.3556 0.3556)
			(layers "F.Cu" "F.Mask" "F.Paste")
			(net "FM_PVPP_CPU0_EN")
		)
		(pad "P16" smd circle
			(at 5.999988 4.400042 180)
			(size 0.3556 0.3556)
			(layers "F.Cu" "F.Mask" "F.Paste")
			(net "FM_PVPP_CPU1_EN")
		)
		(pad "R1" smd circle
			(at -5.999988 5.199888 180)
			(size 0.3556 0.3556)
			(layers "F.Cu" "F.Mask" "F.Paste")
			(net "FM_BMC_CPLD_GPO")
		)
		(pad "R2" smd circle
			(at -5.199888 5.199888 180)
			(size 0.3556 0.3556)
			(layers "F.Cu" "F.Mask" "F.Paste")
			(net "GND")
		)
		(pad "R3" smd circle
			(at -4.400042 5.199888 180)
			(size 0.3556 0.3556)
			(layers "F.Cu" "F.Mask" "F.Paste")
			(net "FM_CPU0_RC_EN")
		)
		(pad "R4" smd circle
			(at -3.599942 5.199888 180)
			(size 0.3556 0.3556)
			(layers "F.Cu" "F.Mask" "F.Paste")
			(net "FM_BMC_CPLD_MP_RST_N")
		)
		(pad "R5" smd circle
			(at -2.800096 5.199888 180)
			(size 0.3556 0.3556)
			(layers "F.Cu" "F.Mask" "F.Paste")
			(net "TP_CPLD1_PB5A_CSSPIN")
		)
		(pad "R6" smd circle
			(at -1.999996 5.199888 180)
			(size 0.3556 0.3556)
			(layers "F.Cu" "F.Mask" "F.Paste")
			(net "RST_PCIE_M2_DEV_N")
		)
		(pad "R7" smd circle
			(at -1.199896 5.199888 180)
			(size 0.3556 0.3556)
			(layers "F.Cu" "F.Mask" "F.Paste")
			(net "PWRGD_PVTT_CPU1")
		)
		(pad "R8" smd circle
			(at -0.40005 5.199888 180)
			(size 0.3556 0.3556)
			(layers "F.Cu" "F.Mask" "F.Paste")
			(net "FM_CPLD_USB_P0_EN_N")
		)
		(pad "R9" smd circle
			(at 0.40005 5.199888 180)
			(size 0.3556 0.3556)
			(layers "F.Cu" "F.Mask" "F.Paste")
			(net "FM_UARTSW_LSB_N")
		)
		(pad "R10" smd circle
			(at 1.199896 5.199888 180)
			(size 0.3556 0.3556)
			(layers "F.Cu" "F.Mask" "F.Paste")
			(net "RST_CPU0_LVC3_R1_N")
		)
		(pad "R11" smd circle
			(at 1.999996 5.199888 180)
			(size 0.3556 0.3556)
			(layers "F.Cu" "F.Mask" "F.Paste")
			(net "FM_DB1200ZL_BCLKS_EN_N")
		)
		(pad "R12" smd circle
			(at 2.800096 5.199888 180)
			(size 0.3556 0.3556)
			(layers "F.Cu" "F.Mask" "F.Paste")
			(net "FM_CPU1_PKGID0")
		)
		(pad "R13" smd circle
			(at 3.599942 5.199888 180)
			(size 0.3556 0.3556)
			(layers "F.Cu" "F.Mask" "F.Paste")
			(net "FM_CPU0_VRM_OSC_EN")
		)
		(pad "R14" smd circle
			(at 4.400042 5.199888 180)
			(size 0.3556 0.3556)
			(layers "F.Cu" "F.Mask" "F.Paste")
			(net "FM_CPU_CATERR_LVT3_N")
		)
		(pad "R15" smd circle
			(at 5.199888 5.199888 180)
			(size 0.3556 0.3556)
			(layers "F.Cu" "F.Mask" "F.Paste")
			(net "GND")
		)
		(pad "R16" smd circle
			(at 5.999988 5.199888 180)
			(size 0.3556 0.3556)
			(layers "F.Cu" "F.Mask" "F.Paste")
			(net "FM_P12V_MAIN_SW_EN")
		)
		(pad "T1" smd circle
			(at -5.999988 5.999988 180)
			(size 0.3556 0.3556)
			(layers "F.Cu" "F.Mask" "F.Paste")
			(net "P3V3_STBY")
		)
		(pad "T2" smd circle
			(at -5.199888 5.999988 180)
			(size 0.3556 0.3556)
			(layers "F.Cu" "F.Mask" "F.Paste")
			(net "FM_ADR_MODE_SEL")
		)
		(pad "T3" smd circle
			(at -4.400042 5.999988 180)
			(size 0.3556 0.3556)
			(layers "F.Cu" "F.Mask" "F.Paste")
			(net "FM_DIS_ADR_DLY")
		)
		(pad "T4" smd circle
			(at -3.599942 5.999988 180)
			(size 0.3556 0.3556)
			(layers "F.Cu" "F.Mask" "F.Paste")
			(net "PWRGD_PVSA_CPU1")
		)
		(pad "T5" smd circle
			(at -2.800096 5.999988 180)
			(size 0.3556 0.3556)
			(layers "F.Cu" "F.Mask" "F.Paste")
			(net "PWRGD_PVCCIOMCP_CPU1")
		)
		(pad "T6" smd circle
			(at -1.999996 5.999988 180)
			(size 0.3556 0.3556)
			(layers "F.Cu" "F.Mask" "F.Paste")
			(net "TP_CPLD1_PB8B_SO_SPISO")
		)
		(pad "T7" smd circle
			(at -1.199896 5.999988 180)
			(size 0.3556 0.3556)
			(layers "F.Cu" "F.Mask" "F.Paste")
			(net "FM_PVCCIO_CPU1_EN")
		)
		(pad "T8" smd circle
			(at -0.40005 5.999988 180)
			(size 0.3556 0.3556)
			(layers "F.Cu" "F.Mask" "F.Paste")
			(net "FM_CPLD_DBG_PWR_EN_N")
		)
		(pad "T9" smd circle
			(at 0.40005 5.999988 180)
			(size 0.3556 0.3556)
			(layers "F.Cu" "F.Mask" "F.Paste")
			(net "TP_CPLD1_PB16A_PCLKT2_1")
		)
		(pad "T10" smd circle
			(at 1.199896 5.999988 180)
			(size 0.3556 0.3556)
			(layers "F.Cu" "F.Mask" "F.Paste")
			(net "FM_156M_CPU0_BRD_OSC_EN")
		)
		(pad "T11" smd circle
			(at 1.999996 5.999988 180)
			(size 0.3556 0.3556)
			(layers "F.Cu" "F.Mask" "F.Paste")
			(net "FM_CPU1_PKGID2")
		)
		(pad "T12" smd circle
			(at 2.800096 5.999988 180)
			(size 0.3556 0.3556)
			(layers "F.Cu" "F.Mask" "F.Paste")
			(net "FM_CPU1_SKTOCC_LVT3_N")
		)
		(pad "T13" smd circle
			(at 3.599942 5.999988 180)
			(size 0.3556 0.3556)
			(layers "F.Cu" "F.Mask" "F.Paste")
			(net "FM_CPU_MSMI_LVT3_N")
		)
		(pad "T14" smd circle
			(at 4.400042 5.999988 180)
			(size 0.3556 0.3556)
			(layers "F.Cu" "F.Mask" "F.Paste")
			(net "FM_CPU0_SKTOCC_LVT3_N")
		)
		(pad "T15" smd circle
			(at 5.199888 5.999988 180)
			(size 0.3556 0.3556)
			(layers "F.Cu" "F.Mask" "F.Paste")
			(net "PWRGD_DRAMPWRGD")
		)
		(pad "T16" smd circle
			(at 5.999988 5.999988 180)
			(size 0.3556 0.3556)
			(layers "F.Cu" "F.Mask" "F.Paste")
			(net "P3V3_STBY")
		)
	)
	(footprint ""
		(layer "F.Cu")
		(at 116.3066 -72.263 90)
		(property "Reference" "R3D17"
			(at 0 0 90)
			(layer "F.SilkS")
			(hide yes)
			(effects
				(font
					(size 1.27 1.27)
				)
			)
		)
		(property "Value" ""
			(at 0 0 90)
			(layer "F.Fab")
			(effects
				(font
					(size 1.27 1.27)
				)
			)
		)
		(duplicate_pad_numbers_are_jumpers no)
		(fp_poly
			(pts
				(xy -0.2794 -0.1016) (xy 0.2794 -0.1016) (xy 0.2794 0.9906) (xy -0.2794 0.9906)
			)
			(stroke
				(width 0)
				(type default)
			)
			(fill no)
			(layer "F.CrtYd")
		)
		(fp_line
			(start 0.2794 -0.1016)
			(end -0.2794 -0.1016)
			(stroke
				(width 0.1)
				(type default)
			)
			(layer "F.Fab")
		)
		(fp_line
			(start -0.2794 -0.1016)
			(end -0.2794 0.9906)
			(stroke
				(width 0.1)
				(type default)
			)
			(layer "F.Fab")
		)
		(fp_line
			(start 0.2794 0.9906)
			(end 0.2794 -0.1016)
			(stroke
				(width 0.1)
				(type default)
			)
			(layer "F.Fab")
		)
		(fp_line
			(start -0.2794 0.9906)
			(end 0.2794 0.9906)
			(stroke
				(width 0.1)
				(type default)
			)
			(layer "F.Fab")
		)
		(pad "1" smd rect
			(at 0 0 90)
			(size 0.508 0.508)
			(layers "F.Cu" "F.Mask" "F.Paste")
			(net "PVCCIO_CPU1")
		)
		(pad "2" smd rect
			(at 0 0.889 90)
			(size 0.508 0.508)
			(layers "F.Cu" "F.Mask" "F.Paste")
			(net "PU_CPU1_SOCKET_ID_1")
		)
		(zone
			(layer "F.Cu")
			(hatch none 0.5)
			(connect_pads
				(clearance 0)
			)
			(min_thickness 0.25)
			(keepout
				(tracks allowed)
				(vias not_allowed)
				(pads allowed)
				(copperpour not_allowed)
				(footprints allowed)
			)
			(placement
				(enabled no)
				(sheetname "")
			)
			(fill
				(thermal_gap 0.5)
				(thermal_bridge_width 0.5)
				(island_removal_mode 0)
			)
			(polygon
				(pts
					(xy 116.5606 -72.009) (xy 116.5606 -72.517) (xy 116.9416 -72.517) (xy 116.9416 -72.009)
				)
			)
		)
		(zone
			(layer "F.Cu")
			(hatch none 0.5)
			(connect_pads
				(clearance 0)
			)
			(min_thickness 0.25)
			(keepout
				(tracks not_allowed)
				(vias allowed)
				(pads allowed)
				(copperpour not_allowed)
				(footprints allowed)
			)
			(placement
				(enabled no)
				(sheetname "")
			)
			(fill
				(thermal_gap 0.5)
				(thermal_bridge_width 0.5)
				(island_removal_mode 0)
			)
			(polygon
				(pts
					(xy 116.9416 -72.009) (xy 116.9416 -72.517) (xy 116.5606 -72.517) (xy 116.5606 -72.009)
				)
			)
		)
	)
	(footprint ""
		(layer "F.Cu")
		(at 367.966244 -10.916158)
		(property "Reference" "C7G10"
			(at 0 0 0)
			(layer "F.SilkS")
			(hide yes)
			(effects
				(font
					(size 1.27 1.27)
				)
			)
		)
		(property "Value" ""
			(at 0 0 0)
			(layer "F.Fab")
			(effects
				(font
					(size 1.27 1.27)
				)
			)
		)
		(duplicate_pad_numbers_are_jumpers no)
		(fp_rect
			(start -0.3048 0.9906)
			(end 0.3048 -0.1016)
			(stroke
				(width 0)
				(type default)
			)
			(fill no)
			(layer "F.CrtYd")
		)
		(fp_line
			(start -0.3048 -0.1016)
			(end -0.3048 0.9906)
			(stroke
				(width 0.1)
				(type default)
			)
			(layer "F.Fab")
		)
		(fp_line
			(start -0.3048 0.9906)
			(end 0.3048 0.9906)
			(stroke
				(width 0.1)
				(type default)
			)
			(layer "F.Fab")
		)
		(fp_line
			(start 0.3048 -0.1016)
			(end -0.3048 -0.1016)
			(stroke
				(width 0.1)
				(type default)
			)
			(layer "F.Fab")
		)
		(fp_line
			(start 0.3048 0.9906)
			(end 0.3048 -0.1016)
			(stroke
				(width 0.1)
				(type default)
			)
			(layer "F.Fab")
		)
		(pad "1" smd rect
			(at 0 0)
			(size 0.508 0.508)
			(layers "F.Cu" "F.Mask" "F.Paste")
			(net "P3E_CPU0_PE2_SS_TXN<13>")
		)
		(pad "2" smd rect
			(at 0 0.889)
			(size 0.508 0.508)
			(layers "F.Cu" "F.Mask" "F.Paste")
			(net "P3E_CPU0_PE2_SS_C_TXN<13>")
		)
		(zone
			(layer "F.Cu")
			(hatch none 0.5)
			(connect_pads
				(clearance 0)
			)
			(min_thickness 0.25)
			(keepout
				(tracks not_allowed)
				(vias allowed)
				(pads allowed)
				(copperpour not_allowed)
				(footprints allowed)
			)
			(placement
				(enabled no)
				(sheetname "")
			)
			(fill
				(thermal_gap 0.5)
				(thermal_bridge_width 0.5)
				(island_removal_mode 0)
			)
			(polygon
				(pts
					(xy 367.712244 -10.281158) (xy 368.220244 -10.281158) (xy 368.220244 -10.662158) (xy 367.712244 -10.662158)
				)
			)
		)
		(zone
			(layer "F.Cu")
			(hatch none 0.5)
			(connect_pads
				(clearance 0)
			)
			(min_thickness 0.25)
			(keepout
				(tracks allowed)
				(vias not_allowed)
				(pads allowed)
				(copperpour not_allowed)
				(footprints allowed)
			)
			(placement
				(enabled no)
				(sheetname "")
			)
			(fill
				(thermal_gap 0.5)
				(thermal_bridge_width 0.5)
				(island_removal_mode 0)
			)
			(polygon
				(pts
					(xy 367.712244 -10.281158) (xy 368.220244 -10.281158) (xy 368.220244 -10.662158) (xy 367.712244 -10.662158)
				)
			)
		)
	)
	(footprint ""
		(layer "F.Cu")
		(at 420.624 -113.8555 180)
		(property "Reference" "R9W14"
			(at -0.8382 -0.67818 180)
			(unlocked yes)
			(layer "F.SilkS")
			(effects
				(font
					(size 0.4064 0.254)
					(thickness 0.1524)
				)
				(justify left)
			)
		)
		(property "Value" ""
			(at 0 0 180)
			(layer "F.Fab")
			(effects
				(font
					(size 1.27 1.27)
				)
			)
		)
		(duplicate_pad_numbers_are_jumpers no)
		(fp_poly
			(pts
				(xy -0.2794 -0.1016) (xy 0.2794 -0.1016) (xy 0.2794 0.9906) (xy -0.2794 0.9906)
			)
			(stroke
				(width 0)
				(type default)
			)
			(fill no)
			(layer "F.CrtYd")
		)
		(fp_line
			(start 0.2794 0.9906)
			(end 0.2794 -0.1016)
			(stroke
				(width 0.1)
				(type default)
			)
			(layer "F.Fab")
		)
		(fp_line
			(start 0.2794 -0.1016)
			(end -0.2794 -0.1016)
			(stroke
				(width 0.1)
				(type default)
			)
			(layer "F.Fab")
		)
		(fp_line
			(start -0.2794 0.9906)
			(end 0.2794 0.9906)
			(stroke
				(width 0.1)
				(type default)
			)
			(layer "F.Fab")
		)
		(fp_line
			(start -0.2794 -0.1016)
			(end -0.2794 0.9906)
			(stroke
				(width 0.1)
				(type default)
			)
			(layer "F.Fab")
		)
		(pad "1" smd rect
			(at 0 0 180)
			(size 0.508 0.508)
			(layers "F.Cu" "F.Mask" "F.Paste")
			(net "SMB_PEHPCPU0_STBY_LVC3_R_SCL")
		)
		(pad "2" smd rect
			(at 0 0.889 180)
			(size 0.508 0.508)
			(layers "F.Cu" "F.Mask" "F.Paste")
			(net "SMB_PEHPCPU0_STBY_LVC3_SCL")
		)
		(zone
			(layer "F.Cu")
			(hatch none 0.5)
			(connect_pads
				(clearance 0)
			)
			(min_thickness 0.25)
			(keepout
				(tracks not_allowed)
				(vias allowed)
				(pads allowed)
				(copperpour not_allowed)
				(footprints allowed)
			)
			(placement
				(enabled no)
				(sheetname "")
			)
			(fill
				(thermal_gap 0.5)
				(thermal_bridge_width 0.5)
				(island_removal_mode 0)
			)
			(polygon
				(pts
					(xy 420.878 -114.4905) (xy 420.37 -114.4905) (xy 420.37 -114.1095) (xy 420.878 -114.1095)
				)
			)
		)
		(zone
			(layer "F.Cu")
			(hatch none 0.5)
			(connect_pads
				(clearance 0)
			)
			(min_thickness 0.25)
			(keepout
				(tracks allowed)
				(vias not_allowed)
				(pads allowed)
				(copperpour not_allowed)
				(footprints allowed)
			)
			(placement
				(enabled no)
				(sheetname "")
			)
			(fill
				(thermal_gap 0.5)
				(thermal_bridge_width 0.5)
				(island_removal_mode 0)
			)
			(polygon
				(pts
					(xy 420.878 -114.1095) (xy 420.37 -114.1095) (xy 420.37 -114.4905) (xy 420.878 -114.4905)
				)
			)
		)
	)
	(footprint ""
		(layer "F.Cu")
		(at 13.462 -51.816 90)
		(property "Reference" "C1E16"
			(at 0 0 90)
			(layer "F.SilkS")
			(hide yes)
			(effects
				(font
					(size 1.27 1.27)
				)
			)
		)
		(property "Value" ""
			(at 0 0 90)
			(layer "F.Fab")
			(effects
				(font
					(size 1.27 1.27)
				)
			)
		)
		(duplicate_pad_numbers_are_jumpers no)
		(fp_rect
			(start -0.3048 -0.1016)
			(end 0.3048 0.9906)
			(stroke
				(width 0)
				(type default)
			)
			(fill no)
			(layer "F.CrtYd")
		)
		(fp_line
			(start 0.3048 -0.1016)
			(end -0.3048 -0.1016)
			(stroke
				(width 0.1)
				(type default)
			)
			(layer "F.Fab")
		)
		(fp_line
			(start -0.3048 -0.1016)
			(end -0.3048 0.9906)
			(stroke
				(width 0.1)
				(type default)
			)
			(layer "F.Fab")
		)
		(fp_line
			(start 0.3048 0.9906)
			(end 0.3048 -0.1016)
			(stroke
				(width 0.1)
				(type default)
			)
			(layer "F.Fab")
		)
		(fp_line
			(start -0.3048 0.9906)
			(end 0.3048 0.9906)
			(stroke
				(width 0.1)
				(type default)
			)
			(layer "F.Fab")
		)
		(pad "1" smd rect
			(at 0 0 90)
			(size 0.508 0.508)
			(layers "F.Cu" "F.Mask" "F.Paste")
			(net "P12V_PSU")
		)
		(pad "2" smd rect
			(at 0 0.889 90)
			(size 0.508 0.508)
			(layers "F.Cu" "F.Mask" "F.Paste")
			(net "GND")
		)
		(zone
			(layer "F.Cu")
			(hatch none 0.5)
			(connect_pads
				(clearance 0)
			)
			(min_thickness 0.25)
			(keepout
				(tracks allowed)
				(vias not_allowed)
				(pads allowed)
				(copperpour not_allowed)
				(footprints allowed)
			)
			(placement
				(enabled no)
				(sheetname "")
			)
			(fill
				(thermal_gap 0.5)
				(thermal_bridge_width 0.5)
				(island_removal_mode 0)
			)
			(polygon
				(pts
					(xy 13.716 -51.562) (xy 14.097 -51.562) (xy 14.097 -52.07) (xy 13.716 -52.07)
				)
			)
		)
		(zone
			(layer "F.Cu")
			(hatch none 0.5)
			(connect_pads
				(clearance 0)
			)
			(min_thickness 0.25)
			(keepout
				(tracks not_allowed)
				(vias allowed)
				(pads allowed)
				(copperpour not_allowed)
				(footprints allowed)
			)
			(placement
				(enabled no)
				(sheetname "")
			)
			(fill
				(thermal_gap 0.5)
				(thermal_bridge_width 0.5)
				(island_removal_mode 0)
			)
			(polygon
				(pts
					(xy 13.716 -51.562) (xy 14.097 -51.562) (xy 14.097 -52.07) (xy 13.716 -52.07)
				)
			)
		)
	)
	(footprint ""
		(layer "F.Cu")
		(at 204.8764 -61.214 -90)
		(property "Reference" "CT5"
			(at -0.8382 -0.67818 270)
			(unlocked yes)
			(layer "F.SilkS")
			(effects
				(font
					(size 0.4064 0.254)
					(thickness 0.1524)
				)
				(justify left)
			)
		)
		(property "Value" ""
			(at 0 0 270)
			(layer "F.Fab")
			(effects
				(font
					(size 1.27 1.27)
				)
			)
		)
		(duplicate_pad_numbers_are_jumpers no)
		(fp_poly
			(pts
				(xy 0.3048 -0.1016) (xy 0.3048 0.9906) (xy -0.3048 0.9906) (xy -0.3048 -0.1016)
			)
			(stroke
				(width 0)
				(type default)
			)
			(fill no)
			(layer "F.CrtYd")
		)
		(fp_line
			(start -0.3048 0.9906)
			(end 0.3048 0.9906)
			(stroke
				(width 0.1)
				(type default)
			)
			(layer "F.Fab")
		)
		(fp_line
			(start 0.3048 0.9906)
			(end 0.3048 -0.1016)
			(stroke
				(width 0.1)
				(type default)
			)
			(layer "F.Fab")
		)
		(fp_line
			(start -0.3048 -0.1016)
			(end -0.3048 0.9906)
			(stroke
				(width 0.1)
				(type default)
			)
			(layer "F.Fab")
		)
		(fp_line
			(start 0.3048 -0.1016)
			(end -0.3048 -0.1016)
			(stroke
				(width 0.1)
				(type default)
			)
			(layer "F.Fab")
		)
		(pad "1" smd rect
			(at 0 0 270)
			(size 0.508 0.508)
			(layers "F.Cu" "F.Mask" "F.Paste")
			(net "VR_PVCCIN_CPU0_PHASE2")
		)
		(pad "2" smd rect
			(at 0 0.889 270)
			(size 0.508 0.508)
			(layers "F.Cu" "F.Mask" "F.Paste")
			(net "VR_PVCCIN_CPU0_PHASE2_RC")
		)
		(zone
			(layer "F.Cu")
			(hatch none 0.5)
			(connect_pads
				(clearance 0)
			)
			(min_thickness 0.25)
			(keepout
				(tracks not_allowed)
				(vias allowed)
				(pads allowed)
				(copperpour not_allowed)
				(footprints allowed)
			)
			(placement
				(enabled no)
				(sheetname "")
			)
			(fill
				(thermal_gap 0.5)
				(thermal_bridge_width 0.5)
				(island_removal_mode 0)
			)
			(polygon
				(pts
					(xy 204.2414 -61.468) (xy 204.2414 -60.96) (xy 204.6224 -60.96) (xy 204.6224 -61.468)
				)
			)
		)
		(zone
			(layer "F.Cu")
			(hatch none 0.5)
			(connect_pads
				(clearance 0)
			)
			(min_thickness 0.25)
			(keepout
				(tracks allowed)
				(vias not_allowed)
				(pads allowed)
				(copperpour not_allowed)
				(footprints allowed)
			)
			(placement
				(enabled no)
				(sheetname "")
			)
			(fill
				(thermal_gap 0.5)
				(thermal_bridge_width 0.5)
				(island_removal_mode 0)
			)
			(polygon
				(pts
					(xy 204.6224 -61.468) (xy 204.6224 -60.96) (xy 204.2414 -60.96) (xy 204.2414 -61.468)
				)
			)
		)
	)
	(footprint ""
		(layer "F.Cu")
		(at 472.948 -144.7165)
		(property "Reference" "R9A16"
			(at 0 0 0)
			(layer "F.SilkS")
			(hide yes)
			(effects
				(font
					(size 1.27 1.27)
				)
			)
		)
		(property "Value" ""
			(at 0 0 0)
			(layer "F.Fab")
			(effects
				(font
					(size 1.27 1.27)
				)
			)
		)
		(duplicate_pad_numbers_are_jumpers no)
		(fp_poly
			(pts
				(xy -0.2794 -0.1016) (xy 0.2794 -0.1016) (xy 0.2794 0.9906) (xy -0.2794 0.9906)
			)
			(stroke
				(width 0)
				(type default)
			)
			(fill no)
			(layer "F.CrtYd")
		)
		(fp_line
			(start -0.2794 -0.1016)
			(end -0.2794 0.9906)
			(stroke
				(width 0.1)
				(type default)
			)
			(layer "F.Fab")
		)
		(fp_line
			(start -0.2794 0.9906)
			(end 0.2794 0.9906)
			(stroke
				(width 0.1)
				(type default)
			)
			(layer "F.Fab")
		)
		(fp_line
			(start 0.2794 -0.1016)
			(end -0.2794 -0.1016)
			(stroke
				(width 0.1)
				(type default)
			)
			(layer "F.Fab")
		)
		(fp_line
			(start 0.2794 0.9906)
			(end 0.2794 -0.1016)
			(stroke
				(width 0.1)
				(type default)
			)
			(layer "F.Fab")
		)
		(pad "1" smd rect
			(at 0 0)
			(size 0.508 0.508)
			(layers "F.Cu" "F.Mask" "F.Paste")
			(net "PU_KEY_CONN_PIN2_R")
		)
		(pad "2" smd rect
			(at 0 0.889)
			(size 0.508 0.508)
			(layers "F.Cu" "F.Mask" "F.Paste")
			(net "P3V3_STBY")
		)
		(zone
			(layer "F.Cu")
			(hatch none 0.5)
			(connect_pads
				(clearance 0)
			)
			(min_thickness 0.25)
			(keepout
				(tracks allowed)
				(vias not_allowed)
				(pads allowed)
				(copperpour not_allowed)
				(footprints allowed)
			)
			(placement
				(enabled no)
				(sheetname "")
			)
			(fill
				(thermal_gap 0.5)
				(thermal_bridge_width 0.5)
				(island_removal_mode 0)
			)
			(polygon
				(pts
					(xy 472.694 -144.4625) (xy 473.202 -144.4625) (xy 473.202 -144.0815) (xy 472.694 -144.0815)
				)
			)
		)
		(zone
			(layer "F.Cu")
			(hatch none 0.5)
			(connect_pads
				(clearance 0)
			)
			(min_thickness 0.25)
			(keepout
				(tracks not_allowed)
				(vias allowed)
				(pads allowed)
				(copperpour not_allowed)
				(footprints allowed)
			)
			(placement
				(enabled no)
				(sheetname "")
			)
			(fill
				(thermal_gap 0.5)
				(thermal_bridge_width 0.5)
				(island_removal_mode 0)
			)
			(polygon
				(pts
					(xy 472.694 -144.0815) (xy 473.202 -144.0815) (xy 473.202 -144.4625) (xy 472.694 -144.4625)
				)
			)
		)
	)
	(footprint ""
		(layer "F.Cu")
		(at 26.416 -64.516)
		(property "Reference" "C1E2"
			(at 0.02667 4.953 90)
			(unlocked yes)
			(layer "F.SilkS")
			(effects
				(font
					(size 0.7874 0.5842)
					(thickness 0.1524)
				)
			)
		)
		(property "Value" ""
			(at 0 0 0)
			(layer "F.Fab")
			(effects
				(font
					(size 1.27 1.27)
				)
			)
		)
		(duplicate_pad_numbers_are_jumpers no)
		(fp_line
			(start -0.9017 1.953006)
			(end -0.9017 0.823976)
			(stroke
				(width 0.1524)
				(type default)
			)
			(layer "F.SilkS")
		)
		(fp_line
			(start 0.9017 1.953768)
			(end 0.9017 0.824484)
			(stroke
				(width 0.1524)
				(type default)
			)
			(layer "F.SilkS")
		)
		(fp_poly
			(pts
				(xy -0.9017 -0.3048) (xy 0.9017 -0.3048) (xy 0.9017 3.0988) (xy -0.9017 3.0988)
			)
			(stroke
				(width 0)
				(type default)
			)
			(fill no)
			(layer "F.CrtYd")
		)
		(fp_line
			(start -0.9017 -0.3048)
			(end -0.9017 3.0988)
			(stroke
				(width 0.1)
				(type default)
			)
			(layer "F.Fab")
		)
		(fp_line
			(start -0.9017 3.0988)
			(end 0.9017 3.0988)
			(stroke
				(width 0.1)
				(type default)
			)
			(layer "F.Fab")
		)
		(fp_line
			(start 0.9017 -0.3048)
			(end -0.9017 -0.3048)
			(stroke
				(width 0.1)
				(type default)
			)
			(layer "F.Fab")
		)
		(fp_line
			(start 0.9017 3.0988)
			(end 0.9017 -0.3048)
			(stroke
				(width 0.1)
				(type default)
			)
			(layer "F.Fab")
		)
		(pad "1" smd rect
			(at 0 0)
			(size 1.524 1.016)
			(layers "F.Cu" "F.Mask" "F.Paste")
			(net "A_HSC_C")
		)
		(pad "2" smd rect
			(at 0 2.794)
			(size 1.524 1.016)
			(layers "F.Cu" "F.Mask" "F.Paste")
			(net "GND")
		)
		(zone
			(layer "F.Cu")
			(hatch none 0.5)
			(connect_pads
				(clearance 0)
			)
			(min_thickness 0.25)
			(keepout
				(tracks allowed)
				(vias not_allowed)
				(pads allowed)
				(copperpour not_allowed)
				(footprints allowed)
			)
			(placement
				(enabled no)
				(sheetname "")
			)
			(fill
				(thermal_gap 0.5)
				(thermal_bridge_width 0.5)
				(island_removal_mode 0)
			)
			(polygon
				(pts
					(xy 27.178 -64.008) (xy 27.178 -62.23) (xy 25.654 -62.23) (xy 25.654 -64.008)
				)
			)
		)
	)
	(footprint ""
		(layer "F.Cu")
		(at 27.423364 -73.744328 90)
		(property "Reference" "RT11"
			(at 1.01473 0.656336 0)
			(unlocked yes)
			(layer "F.SilkS")
			(effects
				(font
					(size 0.4064 0.254)
					(thickness 0.1524)
				)
			)
		)
		(property "Value" ""
			(at 0 0 90)
			(layer "F.Fab")
			(effects
				(font
					(size 1.27 1.27)
				)
			)
		)
		(duplicate_pad_numbers_are_jumpers no)
		(fp_poly
			(pts
				(xy -0.4953 -0.2032) (xy 0.4953 -0.2032) (xy 0.4953 1.6002) (xy -0.4953 1.6002)
			)
			(stroke
				(width 0)
				(type default)
			)
			(fill no)
			(layer "F.CrtYd")
		)
		(fp_line
			(start 0.4953 -0.2032)
			(end 0.4953 1.6002)
			(stroke
				(width 0.1)
				(type default)
			)
			(layer "F.Fab")
		)
		(fp_line
			(start -0.4953 -0.2032)
			(end 0.4953 -0.2032)
			(stroke
				(width 0.1)
				(type default)
			)
			(layer "F.Fab")
		)
		(fp_line
			(start 0.4953 1.6002)
			(end -0.4953 1.6002)
			(stroke
				(width 0.1)
				(type default)
			)
			(layer "F.Fab")
		)
		(fp_line
			(start -0.4953 1.6002)
			(end -0.4953 -0.2032)
			(stroke
				(width 0.1)
				(type default)
			)
			(layer "F.Fab")
		)
		(pad "1" smd rect
			(at 0 0 90)
			(size 0.762 0.889)
			(layers "F.Cu" "F.Mask" "F.Paste")
			(net "VR_PVCCIN_CPU1_PH3_BOOT")
		)
		(pad "2" smd rect
			(at 0 1.397 90)
			(size 0.762 0.889)
			(layers "F.Cu" "F.Mask" "F.Paste")
			(net "VR_PVCCIN_CPU1_PH3_BOOT_R")
		)
		(zone
			(layer "F.Cu")
			(hatch none 0.5)
			(connect_pads
				(clearance 0)
			)
			(min_thickness 0.25)
			(keepout
				(tracks allowed)
				(vias not_allowed)
				(pads allowed)
				(copperpour not_allowed)
				(footprints allowed)
			)
			(placement
				(enabled no)
				(sheetname "")
			)
			(fill
				(thermal_gap 0.5)
				(thermal_bridge_width 0.5)
				(island_removal_mode 0)
			)
			(polygon
				(pts
					(xy 28.375864 -74.125328) (xy 27.867864 -74.125328) (xy 27.867864 -73.363328) (xy 28.375864 -73.363328)
				)
			)
		)
		(zone
			(layer "F.Cu")
			(hatch none 0.5)
			(connect_pads
				(clearance 0)
			)
			(min_thickness 0.25)
			(keepout
				(tracks not_allowed)
				(vias allowed)
				(pads allowed)
				(copperpour not_allowed)
				(footprints allowed)
			)
			(placement
				(enabled no)
				(sheetname "")
			)
			(fill
				(thermal_gap 0.5)
				(thermal_bridge_width 0.5)
				(island_removal_mode 0)
			)
			(polygon
				(pts
					(xy 28.375864 -73.363328) (xy 28.375864 -74.125328) (xy 27.867864 -74.125328) (xy 27.867864 -73.363328)
				)
			)
		)
	)
	(footprint ""
		(layer "F.Cu")
		(at 466.217 -0.2032 90)
		(property "Reference" "C9G22"
			(at 0 0 90)
			(layer "F.SilkS")
			(hide yes)
			(effects
				(font
					(size 1.27 1.27)
				)
			)
		)
		(property "Value" ""
			(at 0 0 90)
			(layer "F.Fab")
			(effects
				(font
					(size 1.27 1.27)
				)
			)
		)
		(duplicate_pad_numbers_are_jumpers no)
		(fp_poly
			(pts
				(xy 0.3048 -0.1016) (xy 0.3048 0.9906) (xy -0.3048 0.9906) (xy -0.3048 -0.1016)
			)
			(stroke
				(width 0)
				(type default)
			)
			(fill no)
			(layer "F.CrtYd")
		)
		(fp_line
			(start 0.3048 -0.1016)
			(end -0.3048 -0.1016)
			(stroke
				(width 0.1)
				(type default)
			)
			(layer "F.Fab")
		)
		(fp_line
			(start -0.3048 -0.1016)
			(end -0.3048 0.9906)
			(stroke
				(width 0.1)
				(type default)
			)
			(layer "F.Fab")
		)
		(fp_line
			(start 0.3048 0.9906)
			(end 0.3048 -0.1016)
			(stroke
				(width 0.1)
				(type default)
			)
			(layer "F.Fab")
		)
		(fp_line
			(start -0.3048 0.9906)
			(end 0.3048 0.9906)
			(stroke
				(width 0.1)
				(type default)
			)
			(layer "F.Fab")
		)
		(pad "1" smd rect
			(at 0 0 90)
			(size 0.508 0.508)
			(layers "F.Cu" "F.Mask" "F.Paste")
			(net "A_P3V_BAT_SCALED")
		)
		(pad "2" smd rect
			(at 0 0.889 90)
			(size 0.508 0.508)
			(layers "F.Cu" "F.Mask" "F.Paste")
			(net "GND")
		)
		(zone
			(layer "F.Cu")
			(hatch none 0.5)
			(connect_pads
				(clearance 0)
			)
			(min_thickness 0.25)
			(keepout
				(tracks allowed)
				(vias not_allowed)
				(pads allowed)
				(copperpour not_allowed)
				(footprints allowed)
			)
			(placement
				(enabled no)
				(sheetname "")
			)
			(fill
				(thermal_gap 0.5)
				(thermal_bridge_width 0.5)
				(island_removal_mode 0)
			)
			(polygon
				(pts
					(xy 466.471 0.0508) (xy 466.471 -0.4572) (xy 466.852 -0.4572) (xy 466.852 0.0508)
				)
			)
		)
		(zone
			(layer "F.Cu")
			(hatch none 0.5)
			(connect_pads
				(clearance 0)
			)
			(min_thickness 0.25)
			(keepout
				(tracks not_allowed)
				(vias allowed)
				(pads allowed)
				(copperpour not_allowed)
				(footprints allowed)
			)
			(placement
				(enabled no)
				(sheetname "")
			)
			(fill
				(thermal_gap 0.5)
				(thermal_bridge_width 0.5)
				(island_removal_mode 0)
			)
			(polygon
				(pts
					(xy 466.852 0.0508) (xy 466.852 -0.4572) (xy 466.471 -0.4572) (xy 466.471 0.0508)
				)
			)
		)
	)
	(footprint ""
		(layer "F.Cu")
		(at 87.158068 -12.954 -90)
		(property "Reference" "C2G3"
			(at 1.848866 0.752348 270)
			(unlocked yes)
			(layer "F.SilkS")
			(effects
				(font
					(size 1.27 0.9652)
					(thickness 0.1524)
				)
			)
		)
		(property "Value" ""
			(at 0 0 270)
			(layer "F.Fab")
			(effects
				(font
					(size 1.27 1.27)
				)
			)
		)
		(duplicate_pad_numbers_are_jumpers no)
		(fp_rect
			(start -0.500126 1.598422)
			(end 0.500126 -0.201422)
			(stroke
				(width 0)
				(type default)
			)
			(fill no)
			(layer "F.CrtYd")
		)
		(fp_line
			(start -0.500126 1.598422)
			(end -0.500126 -0.201422)
			(stroke
				(width 0.1)
				(type default)
			)
			(layer "F.Fab")
		)
		(fp_line
			(start 0.500126 1.598422)
			(end -0.500126 1.598422)
			(stroke
				(width 0.1)
				(type default)
			)
			(layer "F.Fab")
		)
		(fp_line
			(start -0.500126 -0.201422)
			(end 0.500126 -0.201422)
			(stroke
				(width 0.1)
				(type default)
			)
			(layer "F.Fab")
		)
		(fp_line
			(start 0.500126 -0.201422)
			(end 0.500126 1.598422)
			(stroke
				(width 0.1)
				(type default)
			)
			(layer "F.Fab")
		)
		(pad "1" smd rect
			(at 0 0 180)
			(size 0.889 0.9906)
			(layers "F.Cu" "F.Mask" "F.Paste")
			(net "PVDDQ_GHJ")
		)
		(pad "2" smd rect
			(at 0 1.397 180)
			(size 0.889 0.9906)
			(layers "F.Cu" "F.Mask" "F.Paste")
			(net "GND")
		)
		(zone
			(layer "F.Cu")
			(hatch none 0.5)
			(connect_pads
				(clearance 0)
			)
			(min_thickness 0.25)
			(keepout
				(tracks not_allowed)
				(vias allowed)
				(pads allowed)
				(copperpour not_allowed)
				(footprints allowed)
			)
			(placement
				(enabled no)
				(sheetname "")
			)
			(fill
				(thermal_gap 0.5)
				(thermal_bridge_width 0.5)
				(island_removal_mode 0)
			)
			(polygon
				(pts
					(xy 86.205568 -13.4493) (xy 86.205568 -12.4587) (xy 86.713568 -12.4587) (xy 86.713568 -13.4493)
				)
			)
		)
		(zone
			(layer "F.Cu")
			(hatch none 0.5)
			(connect_pads
				(clearance 0)
			)
			(min_thickness 0.25)
			(keepout
				(tracks allowed)
				(vias not_allowed)
				(pads allowed)
				(copperpour not_allowed)
				(footprints allowed)
			)
			(placement
				(enabled no)
				(sheetname "")
			)
			(fill
				(thermal_gap 0.5)
				(thermal_bridge_width 0.5)
				(island_removal_mode 0)
			)
			(polygon
				(pts
					(xy 86.205568 -13.4493) (xy 86.205568 -12.4587) (xy 86.713568 -12.4587) (xy 86.713568 -13.4493)
				)
			)
		)
	)
	(footprint ""
		(layer "F.Cu")
		(at 427.609 -20.955 90)
		(property "Reference" "CR10W2"
			(at 1.06934 -0.39116 0)
			(unlocked yes)
			(layer "F.SilkS")
			(effects
				(font
					(size 0.4064 0.254)
					(thickness 0.1524)
				)
				(justify left)
			)
		)
		(property "Value" ""
			(at 0 0 90)
			(layer "F.Fab")
			(effects
				(font
					(size 1.27 1.27)
				)
			)
		)
		(duplicate_pad_numbers_are_jumpers no)
		(fp_line
			(start 1.103122 1.054354)
			(end 1.103122 2.177796)
			(stroke
				(width 0.1524)
				(type default)
			)
			(layer "F.SilkS")
		)
		(fp_line
			(start 1.583944 2.177796)
			(end 0.6223 2.177796)
			(stroke
				(width 0.1524)
				(type default)
			)
			(layer "F.SilkS")
		)
		(fp_line
			(start 1.103122 2.177796)
			(end 1.583944 3.010662)
			(stroke
				(width 0.1524)
				(type default)
			)
			(layer "F.SilkS")
		)
		(fp_line
			(start 1.583944 3.010662)
			(end 1.103122 3.010662)
			(stroke
				(width 0.1524)
				(type default)
			)
			(layer "F.SilkS")
		)
		(fp_line
			(start 1.103122 3.010662)
			(end 0.6223 3.010662)
			(stroke
				(width 0.1524)
				(type default)
			)
			(layer "F.SilkS")
		)
		(fp_line
			(start 0.6223 3.010662)
			(end 1.103122 2.177796)
			(stroke
				(width 0.1524)
				(type default)
			)
			(layer "F.SilkS")
		)
		(fp_line
			(start 1.103122 3.922268)
			(end 1.103122 3.010662)
			(stroke
				(width 0.1524)
				(type default)
			)
			(layer "F.SilkS")
		)
		(fp_poly
			(pts
				(xy -0.67437 0.24384) (xy -0.67437 2.04216) (xy 0.67437 2.04216) (xy 0.67437 0.24384)
			)
			(stroke
				(width 0)
				(type default)
			)
			(fill no)
			(layer "F.CrtYd")
		)
		(fp_line
			(start 0.67437 0.24384)
			(end -0.67437 0.24384)
			(stroke
				(width 0.1)
				(type default)
			)
			(layer "F.Fab")
		)
		(fp_line
			(start -0.67437 0.24384)
			(end -0.67437 2.04216)
			(stroke
				(width 0.1)
				(type default)
			)
			(layer "F.Fab")
		)
		(fp_line
			(start 0.67437 2.04216)
			(end 0.67437 0.24384)
			(stroke
				(width 0.1)
				(type default)
			)
			(layer "F.Fab")
		)
		(fp_line
			(start -0.67437 2.04216)
			(end 0.67437 2.04216)
			(stroke
				(width 0.1)
				(type default)
			)
			(layer "F.Fab")
		)
		(fp_line
			(start 1.583944 2.177796)
			(end 0.6223 2.177796)
			(stroke
				(width 0.1)
				(type default)
			)
			(layer "F.Fab")
		)
		(fp_line
			(start 1.103122 2.177796)
			(end 1.103122 1.054354)
			(stroke
				(width 0.1)
				(type default)
			)
			(layer "F.Fab")
		)
		(fp_line
			(start 1.103122 2.177796)
			(end 1.583944 3.010662)
			(stroke
				(width 0.1)
				(type default)
			)
			(layer "F.Fab")
		)
		(fp_line
			(start 1.583944 3.010662)
			(end 0.6223 3.010662)
			(stroke
				(width 0.1)
				(type default)
			)
			(layer "F.Fab")
		)
		(fp_line
			(start 1.103122 3.010662)
			(end 1.103122 3.922268)
			(stroke
				(width 0.1)
				(type default)
			)
			(layer "F.Fab")
		)
		(fp_line
			(start 0.6223 3.010662)
			(end 1.103122 2.177796)
			(stroke
				(width 0.1)
				(type default)
			)
			(layer "F.Fab")
		)
		(pad "1" smd rect
			(at 0 0 90)
			(size 0.4064 1.016)
			(layers "F.Cu" "F.Mask" "F.Paste")
			(net "P5V_STBY")
		)
		(pad "2" smd rect
			(at 0 2.286 90)
			(size 0.4064 1.016)
			(layers "F.Cu" "F.Mask" "F.Paste")
			(net "PUMP_PWM_OUT_R")
		)
	)
	(footprint ""
		(layer "F.Cu")
		(at 399.159222 -149.225 180)
		(property "Reference" "R8A6"
			(at 0 0 180)
			(layer "F.SilkS")
			(hide yes)
			(effects
				(font
					(size 1.27 1.27)
				)
			)
		)
		(property "Value" ""
			(at 0 0 180)
			(layer "F.Fab")
			(effects
				(font
					(size 1.27 1.27)
				)
			)
		)
		(duplicate_pad_numbers_are_jumpers no)
		(fp_poly
			(pts
				(xy -0.2794 -0.1016) (xy 0.2794 -0.1016) (xy 0.2794 0.9906) (xy -0.2794 0.9906)
			)
			(stroke
				(width 0)
				(type default)
			)
			(fill no)
			(layer "F.CrtYd")
		)
		(fp_line
			(start 0.2794 0.9906)
			(end 0.2794 -0.1016)
			(stroke
				(width 0.1)
				(type default)
			)
			(layer "F.Fab")
		)
		(fp_line
			(start 0.2794 -0.1016)
			(end -0.2794 -0.1016)
			(stroke
				(width 0.1)
				(type default)
			)
			(layer "F.Fab")
		)
		(fp_line
			(start -0.2794 0.9906)
			(end 0.2794 0.9906)
			(stroke
				(width 0.1)
				(type default)
			)
			(layer "F.Fab")
		)
		(fp_line
			(start -0.2794 -0.1016)
			(end -0.2794 0.9906)
			(stroke
				(width 0.1)
				(type default)
			)
			(layer "F.Fab")
		)
		(pad "1" smd rect
			(at 0 0 180)
			(size 0.508 0.508)
			(layers "F.Cu" "F.Mask" "F.Paste")
			(net "P3V3_STBY")
		)
		(pad "2" smd rect
			(at 0 0.889 180)
			(size 0.508 0.508)
			(layers "F.Cu" "F.Mask" "F.Paste")
			(net "PWRGD_PVNN_PCH_R")
		)
		(zone
			(layer "F.Cu")
			(hatch none 0.5)
			(connect_pads
				(clearance 0)
			)
			(min_thickness 0.25)
			(keepout
				(tracks not_allowed)
				(vias allowed)
				(pads allowed)
				(copperpour not_allowed)
				(footprints allowed)
			)
			(placement
				(enabled no)
				(sheetname "")
			)
			(fill
				(thermal_gap 0.5)
				(thermal_bridge_width 0.5)
				(island_removal_mode 0)
			)
			(polygon
				(pts
					(xy 399.413222 -149.86) (xy 398.905222 -149.86) (xy 398.905222 -149.479) (xy 399.413222 -149.479)
				)
			)
		)
		(zone
			(layer "F.Cu")
			(hatch none 0.5)
			(connect_pads
				(clearance 0)
			)
			(min_thickness 0.25)
			(keepout
				(tracks allowed)
				(vias not_allowed)
				(pads allowed)
				(copperpour not_allowed)
				(footprints allowed)
			)
			(placement
				(enabled no)
				(sheetname "")
			)
			(fill
				(thermal_gap 0.5)
				(thermal_bridge_width 0.5)
				(island_removal_mode 0)
			)
			(polygon
				(pts
					(xy 399.413222 -149.479) (xy 398.905222 -149.479) (xy 398.905222 -149.86) (xy 399.413222 -149.86)
				)
			)
		)
	)
	(footprint ""
		(layer "F.Cu")
		(at 347.1926 -10.2108 -90)
		(property "Reference" "C7G34"
			(at 0 0 270)
			(layer "F.SilkS")
			(hide yes)
			(effects
				(font
					(size 1.27 1.27)
				)
			)
		)
		(property "Value" ""
			(at 0 0 270)
			(layer "F.Fab")
			(effects
				(font
					(size 1.27 1.27)
				)
			)
		)
		(duplicate_pad_numbers_are_jumpers no)
		(fp_rect
			(start -0.3048 -0.1016)
			(end 0.3048 0.9906)
			(stroke
				(width 0)
				(type default)
			)
			(fill no)
			(layer "F.CrtYd")
		)
		(fp_line
			(start -0.3048 0.9906)
			(end 0.3048 0.9906)
			(stroke
				(width 0.1)
				(type default)
			)
			(layer "F.Fab")
		)
		(fp_line
			(start 0.3048 0.9906)
			(end 0.3048 -0.1016)
			(stroke
				(width 0.1)
				(type default)
			)
			(layer "F.Fab")
		)
		(fp_line
			(start -0.3048 -0.1016)
			(end -0.3048 0.9906)
			(stroke
				(width 0.1)
				(type default)
			)
			(layer "F.Fab")
		)
		(fp_line
			(start 0.3048 -0.1016)
			(end -0.3048 -0.1016)
			(stroke
				(width 0.1)
				(type default)
			)
			(layer "F.Fab")
		)
		(pad "1" smd rect
			(at 0 0 270)
			(size 0.508 0.508)
			(layers "F.Cu" "F.Mask" "F.Paste")
			(net "P5V_STBY")
		)
		(pad "2" smd rect
			(at 0 0.889 270)
			(size 0.508 0.508)
			(layers "F.Cu" "F.Mask" "F.Paste")
			(net "GND")
		)
		(zone
			(layer "F.Cu")
			(hatch none 0.5)
			(connect_pads
				(clearance 0)
			)
			(min_thickness 0.25)
			(keepout
				(tracks not_allowed)
				(vias allowed)
				(pads allowed)
				(copperpour not_allowed)
				(footprints allowed)
			)
			(placement
				(enabled no)
				(sheetname "")
			)
			(fill
				(thermal_gap 0.5)
				(thermal_bridge_width 0.5)
				(island_removal_mode 0)
			)
			(polygon
				(pts
					(xy 346.9386 -10.4648) (xy 346.5576 -10.4648) (xy 346.5576 -9.9568) (xy 346.9386 -9.9568)
				)
			)
		)
		(zone
			(layer "F.Cu")
			(hatch none 0.5)
			(connect_pads
				(clearance 0)
			)
			(min_thickness 0.25)
			(keepout
				(tracks allowed)
				(vias not_allowed)
				(pads allowed)
				(copperpour not_allowed)
				(footprints allowed)
			)
			(placement
				(enabled no)
				(sheetname "")
			)
			(fill
				(thermal_gap 0.5)
				(thermal_bridge_width 0.5)
				(island_removal_mode 0)
			)
			(polygon
				(pts
					(xy 346.9386 -10.4648) (xy 346.5576 -10.4648) (xy 346.5576 -9.9568) (xy 346.9386 -9.9568)
				)
			)
		)
	)
	(footprint ""
		(layer "F.Cu")
		(at 175.387 -83.947 90)
		(property "Reference" "R4D12"
			(at 0 0 90)
			(layer "F.SilkS")
			(hide yes)
			(effects
				(font
					(size 1.27 1.27)
				)
			)
		)
		(property "Value" ""
			(at 0 0 90)
			(layer "F.Fab")
			(effects
				(font
					(size 1.27 1.27)
				)
			)
		)
		(duplicate_pad_numbers_are_jumpers no)
		(fp_poly
			(pts
				(xy -0.2794 -0.1016) (xy 0.2794 -0.1016) (xy 0.2794 0.9906) (xy -0.2794 0.9906)
			)
			(stroke
				(width 0)
				(type default)
			)
			(fill no)
			(layer "F.CrtYd")
		)
		(fp_line
			(start 0.2794 -0.1016)
			(end -0.2794 -0.1016)
			(stroke
				(width 0.1)
				(type default)
			)
			(layer "F.Fab")
		)
		(fp_line
			(start -0.2794 -0.1016)
			(end -0.2794 0.9906)
			(stroke
				(width 0.1)
				(type default)
			)
			(layer "F.Fab")
		)
		(fp_line
			(start 0.2794 0.9906)
			(end 0.2794 -0.1016)
			(stroke
				(width 0.1)
				(type default)
			)
			(layer "F.Fab")
		)
		(fp_line
			(start -0.2794 0.9906)
			(end 0.2794 0.9906)
			(stroke
				(width 0.1)
				(type default)
			)
			(layer "F.Fab")
		)
		(pad "1" smd rect
			(at 0 0 90)
			(size 0.508 0.508)
			(layers "F.Cu" "F.Mask" "F.Paste")
			(net "CLK_100M_CPU0_PE_REFCLK_R_DP")
		)
		(pad "2" smd rect
			(at 0 0.889 90)
			(size 0.508 0.508)
			(layers "F.Cu" "F.Mask" "F.Paste")
			(net "CLK_100M_CPU0_PE_REFCLK_DP")
		)
		(zone
			(layer "F.Cu")
			(hatch none 0.5)
			(connect_pads
				(clearance 0)
			)
			(min_thickness 0.25)
			(keepout
				(tracks allowed)
				(vias not_allowed)
				(pads allowed)
				(copperpour not_allowed)
				(footprints allowed)
			)
			(placement
				(enabled no)
				(sheetname "")
			)
			(fill
				(thermal_gap 0.5)
				(thermal_bridge_width 0.5)
				(island_removal_mode 0)
			)
			(polygon
				(pts
					(xy 175.641 -83.693) (xy 175.641 -84.201) (xy 176.022 -84.201) (xy 176.022 -83.693)
				)
			)
		)
		(zone
			(layer "F.Cu")
			(hatch none 0.5)
			(connect_pads
				(clearance 0)
			)
			(min_thickness 0.25)
			(keepout
				(tracks not_allowed)
				(vias allowed)
				(pads allowed)
				(copperpour not_allowed)
				(footprints allowed)
			)
			(placement
				(enabled no)
				(sheetname "")
			)
			(fill
				(thermal_gap 0.5)
				(thermal_bridge_width 0.5)
				(island_removal_mode 0)
			)
			(polygon
				(pts
					(xy 176.022 -83.693) (xy 176.022 -84.201) (xy 175.641 -84.201) (xy 175.641 -83.693)
				)
			)
		)
	)
	(footprint ""
		(layer "F.Cu")
		(at 24.257 -32.385)
		(property "Reference" "CR1F1"
			(at 1.651 -1.11633 0)
			(unlocked yes)
			(layer "F.SilkS")
			(effects
				(font
					(size 0.7874 0.5842)
					(thickness 0.1524)
				)
				(justify left)
			)
		)
		(property "Value" ""
			(at 0 0 0)
			(layer "F.Fab")
			(effects
				(font
					(size 1.27 1.27)
				)
			)
		)
		(duplicate_pad_numbers_are_jumpers no)
		(fp_line
			(start -1.8161 1.664462)
			(end -1.335278 0.831596)
			(stroke
				(width 0.1524)
				(type default)
			)
			(layer "F.SilkS")
		)
		(fp_line
			(start -1.335278 -0.291846)
			(end -1.335278 0.831596)
			(stroke
				(width 0.1524)
				(type default)
			)
			(layer "F.SilkS")
		)
		(fp_line
			(start -1.335278 0.831596)
			(end -0.854456 1.664462)
			(stroke
				(width 0.1524)
				(type default)
			)
			(layer "F.SilkS")
		)
		(fp_line
			(start -1.335278 1.664462)
			(end -1.8161 1.664462)
			(stroke
				(width 0.1524)
				(type default)
			)
			(layer "F.SilkS")
		)
		(fp_line
			(start -1.335278 2.576068)
			(end -1.335278 1.664462)
			(stroke
				(width 0.1524)
				(type default)
			)
			(layer "F.SilkS")
		)
		(fp_line
			(start -0.854456 0.831596)
			(end -1.8161 0.831596)
			(stroke
				(width 0.1524)
				(type default)
			)
			(layer "F.SilkS")
		)
		(fp_line
			(start -0.854456 1.664462)
			(end -1.335278 1.664462)
			(stroke
				(width 0.1524)
				(type default)
			)
			(layer "F.SilkS")
		)
		(fp_rect
			(start -0.67437 2.04216)
			(end 0.67437 0.24384)
			(stroke
				(width 0)
				(type default)
			)
			(fill no)
			(layer "F.CrtYd")
		)
		(fp_line
			(start -1.8161 1.664462)
			(end -1.335278 0.831596)
			(stroke
				(width 0.1)
				(type default)
			)
			(layer "F.Fab")
		)
		(fp_line
			(start -1.335278 0.831596)
			(end -1.335278 -0.291846)
			(stroke
				(width 0.1)
				(type default)
			)
			(layer "F.Fab")
		)
		(fp_line
			(start -1.335278 0.831596)
			(end -0.854456 1.664462)
			(stroke
				(width 0.1)
				(type default)
			)
			(layer "F.Fab")
		)
		(fp_line
			(start -1.335278 1.664462)
			(end -1.335278 2.576068)
			(stroke
				(width 0.1)
				(type default)
			)
			(layer "F.Fab")
		)
		(fp_line
			(start -0.854456 0.831596)
			(end -1.8161 0.831596)
			(stroke
				(width 0.1)
				(type default)
			)
			(layer "F.Fab")
		)
		(fp_line
			(start -0.854456 1.664462)
			(end -1.8161 1.664462)
			(stroke
				(width 0.1)
				(type default)
			)
			(layer "F.Fab")
		)
		(fp_line
			(start -0.67437 0.24384)
			(end -0.67437 2.04216)
			(stroke
				(width 0.1)
				(type default)
			)
			(layer "F.Fab")
		)
		(fp_line
			(start -0.67437 2.04216)
			(end 0.67437 2.04216)
			(stroke
				(width 0.1)
				(type default)
			)
			(layer "F.Fab")
		)
		(fp_line
			(start 0.67437 0.24384)
			(end -0.67437 0.24384)
			(stroke
				(width 0.1)
				(type default)
			)
			(layer "F.Fab")
		)
		(fp_line
			(start 0.67437 2.04216)
			(end 0.67437 0.24384)
			(stroke
				(width 0.1)
				(type default)
			)
			(layer "F.Fab")
		)
		(pad "1" smd rect
			(at 0 0)
			(size 0.4064 1.016)
			(layers "F.Cu" "F.Mask" "F.Paste")
			(net "FAN_TACH0_CPU0_D1")
		)
		(pad "2" smd rect
			(at 0 2.286)
			(size 0.4064 1.016)
			(layers "F.Cu" "F.Mask" "F.Paste")
			(net "FAN_TACH0_CPU0_D2")
		)
	)
	(footprint ""
		(layer "F.Cu")
		(at 272.861532 -12.954 90)
		(property "Reference" "C5G7"
			(at 1.848866 0.752348 90)
			(unlocked yes)
			(layer "F.SilkS")
			(effects
				(font
					(size 1.27 0.9652)
					(thickness 0.1524)
				)
			)
		)
		(property "Value" ""
			(at 0 0 90)
			(layer "F.Fab")
			(effects
				(font
					(size 1.27 1.27)
				)
			)
		)
		(duplicate_pad_numbers_are_jumpers no)
		(fp_rect
			(start -0.500126 1.598422)
			(end 0.500126 -0.201422)
			(stroke
				(width 0)
				(type default)
			)
			(fill no)
			(layer "F.CrtYd")
		)
		(fp_line
			(start 0.500126 -0.201422)
			(end 0.500126 1.598422)
			(stroke
				(width 0.1)
				(type default)
			)
			(layer "F.Fab")
		)
		(fp_line
			(start -0.500126 -0.201422)
			(end 0.500126 -0.201422)
			(stroke
				(width 0.1)
				(type default)
			)
			(layer "F.Fab")
		)
		(fp_line
			(start 0.500126 1.598422)
			(end -0.500126 1.598422)
			(stroke
				(width 0.1)
				(type default)
			)
			(layer "F.Fab")
		)
		(fp_line
			(start -0.500126 1.598422)
			(end -0.500126 -0.201422)
			(stroke
				(width 0.1)
				(type default)
			)
			(layer "F.Fab")
		)
		(pad "1" smd rect
			(at 0 0)
			(size 0.889 0.9906)
			(layers "F.Cu" "F.Mask" "F.Paste")
			(net "PVDDQ_ABC")
		)
		(pad "2" smd rect
			(at 0 1.397)
			(size 0.889 0.9906)
			(layers "F.Cu" "F.Mask" "F.Paste")
			(net "GND")
		)
		(zone
			(layer "F.Cu")
			(hatch none 0.5)
			(connect_pads
				(clearance 0)
			)
			(min_thickness 0.25)
			(keepout
				(tracks allowed)
				(vias not_allowed)
				(pads allowed)
				(copperpour not_allowed)
				(footprints allowed)
			)
			(placement
				(enabled no)
				(sheetname "")
			)
			(fill
				(thermal_gap 0.5)
				(thermal_bridge_width 0.5)
				(island_removal_mode 0)
			)
			(polygon
				(pts
					(xy 273.814032 -12.4587) (xy 273.814032 -13.4493) (xy 273.306032 -13.4493) (xy 273.306032 -12.4587)
				)
			)
		)
		(zone
			(layer "F.Cu")
			(hatch none 0.5)
			(connect_pads
				(clearance 0)
			)
			(min_thickness 0.25)
			(keepout
				(tracks not_allowed)
				(vias allowed)
				(pads allowed)
				(copperpour not_allowed)
				(footprints allowed)
			)
			(placement
				(enabled no)
				(sheetname "")
			)
			(fill
				(thermal_gap 0.5)
				(thermal_bridge_width 0.5)
				(island_removal_mode 0)
			)
			(polygon
				(pts
					(xy 273.814032 -12.4587) (xy 273.814032 -13.4493) (xy 273.306032 -13.4493) (xy 273.306032 -12.4587)
				)
			)
		)
	)
	(footprint ""
		(layer "F.Cu")
		(at 281.776424 -80.9371)
		(property "Reference" "C6D1"
			(at 0 0 0)
			(layer "F.SilkS")
			(hide yes)
			(effects
				(font
					(size 1.27 1.27)
				)
			)
		)
		(property "Value" ""
			(at 0 0 0)
			(layer "F.Fab")
			(effects
				(font
					(size 1.27 1.27)
				)
			)
		)
		(duplicate_pad_numbers_are_jumpers no)
		(fp_poly
			(pts
				(xy -0.4953 -0.2032) (xy 0.4953 -0.2032) (xy 0.4953 1.6002) (xy -0.4953 1.6002)
			)
			(stroke
				(width 0)
				(type default)
			)
			(fill no)
			(layer "F.CrtYd")
		)
		(fp_line
			(start -0.4953 -0.2032)
			(end 0.4953 -0.2032)
			(stroke
				(width 0.1)
				(type default)
			)
			(layer "F.Fab")
		)
		(fp_line
			(start -0.4953 1.6002)
			(end -0.4953 -0.2032)
			(stroke
				(width 0.1)
				(type default)
			)
			(layer "F.Fab")
		)
		(fp_line
			(start 0.4953 -0.2032)
			(end 0.4953 1.6002)
			(stroke
				(width 0.1)
				(type default)
			)
			(layer "F.Fab")
		)
		(fp_line
			(start 0.4953 1.6002)
			(end -0.4953 1.6002)
			(stroke
				(width 0.1)
				(type default)
			)
			(layer "F.Fab")
		)
		(pad "1" smd rect
			(at 0 0)
			(size 0.762 0.889)
			(layers "F.Cu" "F.Mask" "F.Paste")
			(net "P1V8_MCP_CPU0")
		)
		(pad "2" smd rect
			(at 0 1.397)
			(size 0.762 0.889)
			(layers "F.Cu" "F.Mask" "F.Paste")
			(net "GND")
		)
		(zone
			(layer "F.Cu")
			(hatch none 0.5)
			(connect_pads
				(clearance 0)
			)
			(min_thickness 0.25)
			(keepout
				(tracks not_allowed)
				(vias allowed)
				(pads allowed)
				(copperpour not_allowed)
				(footprints allowed)
			)
			(placement
				(enabled no)
				(sheetname "")
			)
			(fill
				(thermal_gap 0.5)
				(thermal_bridge_width 0.5)
				(island_removal_mode 0)
			)
			(polygon
				(pts
					(xy 281.395424 -80.4926) (xy 282.157424 -80.4926) (xy 282.157424 -79.9846) (xy 281.395424 -79.9846)
				)
			)
		)
	)
	(footprint ""
		(layer "F.Cu")
		(at 405.47036 -57.79389)
		(property "Reference" "C8E9"
			(at 0 0 0)
			(layer "F.SilkS")
			(hide yes)
			(effects
				(font
					(size 1.27 1.27)
				)
			)
		)
		(property "Value" "*"
			(at -0.0762 -6.2357 0)
			(unlocked yes)
			(layer "F.Fab")
			(hide yes)
			(effects
				(font
					(size 1.27 1.016)
					(thickness 0.1524)
				)
			)
		)
		(property "Device Type" "SC22U16V5MX-4-GP_SMD-BCG5-SC22A"
			(at -0.0762 -8.2677 0)
			(unlocked yes)
			(layer "F.Fab")
			(hide yes)
			(effects
				(font
					(size 1.27 1.016)
					(thickness 0.1524)
				)
			)
		)
		(duplicate_pad_numbers_are_jumpers no)
		(fp_line
			(start 0.635 0)
			(end -0.635 0)
			(stroke
				(width 0.508)
				(type default)
			)
			(layer "F.SilkS")
		)
		(fp_rect
			(start -0.9652 1.778)
			(end 0.9652 -1.778)
			(stroke
				(width 0)
				(type default)
			)
			(fill no)
			(layer "F.CrtYd")
		)
		(fp_poly
			(pts
				(xy -0.9652 -1.778) (xy 0.9652 -1.778) (xy 0.9652 1.778) (xy -0.9652 1.778)
			)
			(stroke
				(width 0)
				(type default)
			)
			(fill no)
			(layer "F.Fab")
		)
		(pad "1" smd rect
			(at 0 -0.9652)
			(size 1.397 1.143)
			(layers "F.Cu" "F.Mask" "F.Paste")
			(net "P5V_STBY")
		)
		(pad "2" smd rect
			(at 0 0.9652)
			(size 1.397 1.143)
			(layers "F.Cu" "F.Mask" "F.Paste")
			(net "GND")
		)
	)
	(footprint ""
		(layer "F.Cu")
		(at 357.0605 -146.61642)
		(property "Reference" "C7W2"
			(at 0 0 0)
			(layer "F.SilkS")
			(hide yes)
			(effects
				(font
					(size 1.27 1.27)
				)
			)
		)
		(property "Value" "*"
			(at 3.5941 -1.41605 0)
			(unlocked yes)
			(layer "F.Fab")
			(hide yes)
			(effects
				(font
					(size 0.889 0.889)
					(thickness 0.1524)
				)
			)
		)
		(property "Device Type" "SE100U16VM-48-GP_SMD-TCG2-SE10A"
			(at 3.5941 -2.94005 0)
			(unlocked yes)
			(layer "F.Fab")
			(hide yes)
			(effects
				(font
					(size 0.889 0.889)
					(thickness 0.1524)
				)
			)
		)
		(duplicate_pad_numbers_are_jumpers no)
		(fp_line
			(start -2.7559 -2.0955)
			(end -2.0955 -2.7559)
			(stroke
				(width 0.1524)
				(type default)
			)
			(layer "F.SilkS")
		)
		(fp_line
			(start -2.7559 2.7559)
			(end -2.7559 -2.0955)
			(stroke
				(width 0.1524)
				(type default)
			)
			(layer "F.SilkS")
		)
		(fp_line
			(start -2.0955 -2.7559)
			(end -1.0287 -2.7559)
			(stroke
				(width 0.1524)
				(type default)
			)
			(layer "F.SilkS")
		)
		(fp_line
			(start -1.0287 2.7559)
			(end -2.7559 2.7559)
			(stroke
				(width 0.1524)
				(type default)
			)
			(layer "F.SilkS")
		)
		(fp_line
			(start 1.0287 -2.7559)
			(end 2.0955 -2.7559)
			(stroke
				(width 0.1524)
				(type default)
			)
			(layer "F.SilkS")
		)
		(fp_line
			(start 2.0955 -2.7559)
			(end 2.7559 -2.0955)
			(stroke
				(width 0.1524)
				(type default)
			)
			(layer "F.SilkS")
		)
		(fp_line
			(start 2.7559 -2.0955)
			(end 2.7559 2.7559)
			(stroke
				(width 0.1524)
				(type default)
			)
			(layer "F.SilkS")
		)
		(fp_line
			(start 2.7559 2.7559)
			(end 1.0287 2.7559)
			(stroke
				(width 0.1524)
				(type default)
			)
			(layer "F.SilkS")
		)
		(fp_poly
			(pts
				(xy -0.8001 3.7084) (xy -0.8001 2.7559) (xy -2.7559 2.7559) (xy -2.7559 -2.7559) (xy -0.8001 -2.7559)
				(xy -0.8001 -3.7084) (xy 0.8001 -3.7084) (xy 0.8001 -2.7559) (xy 2.7559 -2.7559) (xy 2.7559 2.7559)
				(xy 0.8001 2.7559) (xy 0.8001 3.7084)
			)
			(stroke
				(width 0)
				(type default)
			)
			(fill no)
			(layer "F.CrtYd")
		)
		(fp_poly
			(pts
				(xy -0.8001 3.7084) (xy -0.8001 2.7559) (xy -2.7559 2.7559) (xy -2.7559 -2.7559) (xy -0.8001 -2.7559)
				(xy -0.8001 -3.7084) (xy 0.8001 -3.7084) (xy 0.8001 -2.7559) (xy 2.7559 -2.7559) (xy 2.7559 2.7559)
				(xy 0.8001 2.7559) (xy 0.8001 3.7084)
			)
			(stroke
				(width 0)
				(type default)
			)
			(fill no)
			(layer "F.Fab")
		)
		(pad "1" smd rect
			(at 0 -2.199894)
			(size 1.6002 2.9972)
			(layers "F.Cu" "F.Mask" "F.Paste")
			(net "VR_FET_SW_P12V_STBY_PVDDQ_DEF")
		)
		(pad "2" smd rect
			(at 0 2.199894)
			(size 1.6002 2.9972)
			(layers "F.Cu" "F.Mask" "F.Paste")
			(net "GND")
		)
	)
	(footprint ""
		(layer "F.Cu")
		(at 181.847998 -4.432808 180)
		(property "Reference" "C4G14"
			(at 0 0 180)
			(layer "F.SilkS")
			(hide yes)
			(effects
				(font
					(size 1.27 1.27)
				)
			)
		)
		(property "Value" ""
			(at 0 0 180)
			(layer "F.Fab")
			(effects
				(font
					(size 1.27 1.27)
				)
			)
		)
		(duplicate_pad_numbers_are_jumpers no)
		(fp_rect
			(start 0.3048 0.9906)
			(end -0.3048 -0.1016)
			(stroke
				(width 0)
				(type default)
			)
			(fill no)
			(layer "F.CrtYd")
		)
		(fp_line
			(start 0.3048 0.9906)
			(end 0.3048 -0.1016)
			(stroke
				(width 0.1)
				(type default)
			)
			(layer "F.Fab")
		)
		(fp_line
			(start 0.3048 -0.1016)
			(end -0.3048 -0.1016)
			(stroke
				(width 0.1)
				(type default)
			)
			(layer "F.Fab")
		)
		(fp_line
			(start -0.3048 0.9906)
			(end 0.3048 0.9906)
			(stroke
				(width 0.1)
				(type default)
			)
			(layer "F.Fab")
		)
		(fp_line
			(start -0.3048 -0.1016)
			(end -0.3048 0.9906)
			(stroke
				(width 0.1)
				(type default)
			)
			(layer "F.Fab")
		)
		(pad "1" smd rect
			(at 0 0 180)
			(size 0.508 0.508)
			(layers "F.Cu" "F.Mask" "F.Paste")
			(net "PWRGD_PVTT_ABC_CPU0_R")
		)
		(pad "2" smd rect
			(at 0 0.889 180)
			(size 0.508 0.508)
			(layers "F.Cu" "F.Mask" "F.Paste")
			(net "GND")
		)
		(zone
			(layer "F.Cu")
			(hatch none 0.5)
			(connect_pads
				(clearance 0)
			)
			(min_thickness 0.25)
			(keepout
				(tracks allowed)
				(vias not_allowed)
				(pads allowed)
				(copperpour not_allowed)
				(footprints allowed)
			)
			(placement
				(enabled no)
				(sheetname "")
			)
			(fill
				(thermal_gap 0.5)
				(thermal_bridge_width 0.5)
				(island_removal_mode 0)
			)
			(polygon
				(pts
					(xy 181.593998 -5.067808) (xy 181.593998 -4.686808) (xy 182.101998 -4.686808) (xy 182.101998 -5.067808)
				)
			)
		)
		(zone
			(layer "F.Cu")
			(hatch none 0.5)
			(connect_pads
				(clearance 0)
			)
			(min_thickness 0.25)
			(keepout
				(tracks not_allowed)
				(vias allowed)
				(pads allowed)
				(copperpour not_allowed)
				(footprints allowed)
			)
			(placement
				(enabled no)
				(sheetname "")
			)
			(fill
				(thermal_gap 0.5)
				(thermal_bridge_width 0.5)
				(island_removal_mode 0)
			)
			(polygon
				(pts
					(xy 181.593998 -5.067808) (xy 181.593998 -4.686808) (xy 182.101998 -4.686808) (xy 182.101998 -5.067808)
				)
			)
		)
	)
	(footprint ""
		(layer "F.Cu")
		(at 459.3844 -15.3924)
		(property "Reference" "C8F14"
			(at 0 0 0)
			(layer "F.SilkS")
			(hide yes)
			(effects
				(font
					(size 1.27 1.27)
				)
			)
		)
		(property "Value" "*"
			(at 0 -9.7155 0)
			(unlocked yes)
			(layer "F.Fab")
			(hide yes)
			(effects
				(font
					(size 1.27 1.016)
					(thickness 0.1524)
				)
			)
		)
		(property "Device Type" "ST470U6D3VDM-7-GP_SMD-TCG4-ST4A"
			(at 0 -11.2395 0)
			(unlocked yes)
			(layer "F.Fab")
			(hide yes)
			(effects
				(font
					(size 1.27 1.016)
					(thickness 0.1524)
				)
			)
		)
		(duplicate_pad_numbers_are_jumpers no)
		(fp_line
			(start -2.286 -4.8768)
			(end -2.286 -2.032)
			(stroke
				(width 0.1524)
				(type default)
			)
			(layer "F.SilkS")
		)
		(fp_line
			(start -2.286 4.8768)
			(end -2.286 2.032)
			(stroke
				(width 0.1524)
				(type default)
			)
			(layer "F.SilkS")
		)
		(fp_line
			(start 2.1082 -4.699)
			(end -2.1082 -4.699)
			(stroke
				(width 0.508)
				(type default)
			)
			(layer "F.SilkS")
		)
		(fp_line
			(start 2.286 -4.8768)
			(end -2.286 -4.8768)
			(stroke
				(width 0.1524)
				(type default)
			)
			(layer "F.SilkS")
		)
		(fp_line
			(start 2.286 -2.032)
			(end 2.286 -4.8768)
			(stroke
				(width 0.1524)
				(type default)
			)
			(layer "F.SilkS")
		)
		(fp_line
			(start 2.286 2.032)
			(end 2.286 4.8768)
			(stroke
				(width 0.1524)
				(type default)
			)
			(layer "F.SilkS")
		)
		(fp_line
			(start 2.286 4.8768)
			(end -2.286 4.8768)
			(stroke
				(width 0.1524)
				(type default)
			)
			(layer "F.SilkS")
		)
		(fp_rect
			(start -2.1463 3.6449)
			(end 2.1463 -3.6449)
			(stroke
				(width 0)
				(type default)
			)
			(fill no)
			(layer "F.CrtYd")
		)
		(fp_poly
			(pts
				(xy -2.54 4.953) (xy -2.54 4.2926) (xy -3.81 4.2926) (xy -3.81 -4.2926) (xy -2.54 -4.2926) (xy -2.54 -4.953)
				(xy 2.54 -4.953) (xy 2.54 -4.2926) (xy 3.81 -4.2926) (xy 3.81 -1.6256) (xy 2.1463 -1.6256) (xy 2.1463 -3.6449)
				(xy -2.1463 -3.6449) (xy -2.1463 3.6449) (xy 2.1463 3.6449) (xy 2.1463 -1.6129) (xy 3.81 -1.6129)
				(xy 3.81 4.2926) (xy 2.54 4.2926) (xy 2.54 4.953)
			)
			(stroke
				(width 0)
				(type default)
			)
			(fill no)
			(layer "F.CrtYd")
		)
		(fp_rect
			(start -3.81 4.2926)
			(end -2.54 -4.2926)
			(stroke
				(width 0)
				(type default)
			)
			(fill no)
			(layer "F.Fab")
		)
		(fp_rect
			(start -2.54 4.953)
			(end 2.54 -4.953)
			(stroke
				(width 0)
				(type default)
			)
			(fill no)
			(layer "F.Fab")
		)
		(fp_rect
			(start 2.54 4.2926)
			(end 3.81 -4.2926)
			(stroke
				(width 0)
				(type default)
			)
			(fill no)
			(layer "F.Fab")
		)
		(pad "1" smd rect
			(at 0 -3.1496)
			(size 2.413 2.286)
			(layers "F.Cu" "F.Mask" "F.Paste")
			(net "P3V3_STBY")
		)
		(pad "2" smd rect
			(at 0 3.1496)
			(size 2.413 2.286)
			(layers "F.Cu" "F.Mask" "F.Paste")
			(net "GND")
		)
		(zone
			(layer "F.Cu")
			(hatch none 0.5)
			(connect_pads
				(clearance 0)
			)
			(min_thickness 0.25)
			(keepout
				(tracks allowed)
				(vias not_allowed)
				(pads allowed)
				(copperpour not_allowed)
				(footprints allowed)
			)
			(placement
				(enabled no)
				(sheetname "")
			)
			(fill
				(thermal_gap 0.5)
				(thermal_bridge_width 0.5)
				(island_removal_mode 0)
			)
			(polygon
				(pts
					(xy 457.8731 -10.795) (xy 460.8957 -10.795) (xy 460.8957 -13.6906) (xy 460.8957 -14.0208) (xy 457.8731 -14.0208)
					(xy 457.8731 -13.6906)
				)
			)
		)
		(zone
			(layer "F.Cu")
			(hatch none 0.5)
			(connect_pads
				(clearance 0)
			)
			(min_thickness 0.25)
			(keepout
				(tracks allowed)
				(vias not_allowed)
				(pads allowed)
				(copperpour not_allowed)
				(footprints allowed)
			)
			(placement
				(enabled no)
				(sheetname "")
			)
			(fill
				(thermal_gap 0.5)
				(thermal_bridge_width 0.5)
				(island_removal_mode 0)
			)
			(polygon
				(pts
					(xy 460.8957 -17.0815) (xy 460.8957 -19.9898) (xy 457.8731 -19.9898) (xy 457.8731 -17.0942) (xy 457.8731 -16.764)
					(xy 460.8957 -16.764)
				)
			)
		)
	)
	(footprint ""
		(layer "F.Cu")
		(at 437.690006 -43.568874 180)
		(property "Reference" "R25W51"
			(at 0 0 180)
			(layer "F.SilkS")
			(hide yes)
			(effects
				(font
					(size 1.27 1.27)
				)
			)
		)
		(property "Value" "*"
			(at 0.064008 -4.108196 180)
			(unlocked yes)
			(layer "F.Fab")
			(hide yes)
			(effects
				(font
					(size 1.27 1.016)
					(thickness 0.1524)
				)
			)
		)
		(property "Device Type" "120R2F-GP_RCL_GP-120R2F-GP,64.A"
			(at 0.064008 -5.632196 180)
			(unlocked yes)
			(layer "F.Fab")
			(hide yes)
			(effects
				(font
					(size 1.27 1.016)
					(thickness 0.1524)
				)
			)
		)
		(duplicate_pad_numbers_are_jumpers no)
		(fp_line
			(start 0.508 -0.9398)
			(end -0.508 -0.9398)
			(stroke
				(width 0.1524)
				(type default)
			)
			(layer "F.SilkS")
		)
		(fp_line
			(start -0.508 -0.9398)
			(end -0.508 0.9398)
			(stroke
				(width 0.1524)
				(type default)
			)
			(layer "F.SilkS")
		)
		(fp_rect
			(start -0.508 0.9398)
			(end 0.508 -0.9398)
			(stroke
				(width 0)
				(type default)
			)
			(fill no)
			(layer "F.CrtYd")
		)
		(fp_rect
			(start -0.508 0.9398)
			(end 0.508 -0.9398)
			(stroke
				(width 0)
				(type default)
			)
			(fill no)
			(layer "F.Fab")
		)
		(pad "1" smd custom
			(at 0 -0.4445 180)
			(size 0.1397 0.1397)
			(layers "F.Cu" "F.Mask" "F.Paste")
			(net "BMC_M_A13")
			(options
				(clearance outline)
				(anchor circle)
			)
			(primitives
				(gr_poly
					(pts
						(arc
							(start -0.1778 -0.2794)
							(mid -0.249642 -0.249642)
							(end -0.2794 -0.1778)
						)
						(arc
							(start -0.2794 0.1778)
							(mid -0.249642 0.249642)
							(end -0.1778 0.2794)
						)
						(arc
							(start 0.1778 0.2794)
							(mid 0.249642 0.249642)
							(end 0.2794 0.1778)
						)
						(arc
							(start 0.2794 -0.1778)
							(mid 0.249642 -0.249642)
							(end 0.1778 -0.2794)
						)
					)
					(width 0)
					(fill yes)
				)
			)
		)
		(pad "2" smd custom
			(at 0 0.4445 180)
			(size 0.1397 0.1397)
			(layers "F.Cu" "F.Mask" "F.Paste")
			(net "P1V2_AUX_BMC")
			(options
				(clearance outline)
				(anchor circle)
			)
			(primitives
				(gr_poly
					(pts
						(arc
							(start -0.1778 -0.2794)
							(mid -0.249642 -0.249642)
							(end -0.2794 -0.1778)
						)
						(arc
							(start -0.2794 0.1778)
							(mid -0.249642 0.249642)
							(end -0.1778 0.2794)
						)
						(arc
							(start 0.1778 0.2794)
							(mid 0.249642 0.249642)
							(end 0.2794 0.1778)
						)
						(arc
							(start 0.2794 -0.1778)
							(mid 0.249642 -0.249642)
							(end 0.1778 -0.2794)
						)
					)
					(width 0)
					(fill yes)
				)
			)
		)
	)
	(footprint ""
		(layer "F.Cu")
		(at 13.1572 -40.005 -90)
		(property "Reference" "R1F8"
			(at 0 0 270)
			(layer "F.SilkS")
			(hide yes)
			(effects
				(font
					(size 1.27 1.27)
				)
			)
		)
		(property "Value" ""
			(at 0 0 270)
			(layer "F.Fab")
			(effects
				(font
					(size 1.27 1.27)
				)
			)
		)
		(duplicate_pad_numbers_are_jumpers no)
		(fp_poly
			(pts
				(xy -0.2794 -0.1016) (xy 0.2794 -0.1016) (xy 0.2794 0.9906) (xy -0.2794 0.9906)
			)
			(stroke
				(width 0)
				(type default)
			)
			(fill no)
			(layer "F.CrtYd")
		)
		(fp_line
			(start -0.2794 0.9906)
			(end 0.2794 0.9906)
			(stroke
				(width 0.1)
				(type default)
			)
			(layer "F.Fab")
		)
		(fp_line
			(start 0.2794 0.9906)
			(end 0.2794 -0.1016)
			(stroke
				(width 0.1)
				(type default)
			)
			(layer "F.Fab")
		)
		(fp_line
			(start -0.2794 -0.1016)
			(end -0.2794 0.9906)
			(stroke
				(width 0.1)
				(type default)
			)
			(layer "F.Fab")
		)
		(fp_line
			(start 0.2794 -0.1016)
			(end -0.2794 -0.1016)
			(stroke
				(width 0.1)
				(type default)
			)
			(layer "F.Fab")
		)
		(pad "1" smd rect
			(at 0 0 270)
			(size 0.508 0.508)
			(layers "F.Cu" "F.Mask" "F.Paste")
			(net "FAN_TACH0")
		)
		(pad "2" smd rect
			(at 0 0.889 270)
			(size 0.508 0.508)
			(layers "F.Cu" "F.Mask" "F.Paste")
			(net "FAN_TACH0_R")
		)
		(zone
			(layer "F.Cu")
			(hatch none 0.5)
			(connect_pads
				(clearance 0)
			)
			(min_thickness 0.25)
			(keepout
				(tracks not_allowed)
				(vias allowed)
				(pads allowed)
				(copperpour not_allowed)
				(footprints allowed)
			)
			(placement
				(enabled no)
				(sheetname "")
			)
			(fill
				(thermal_gap 0.5)
				(thermal_bridge_width 0.5)
				(island_removal_mode 0)
			)
			(polygon
				(pts
					(xy 12.5222 -40.259) (xy 12.5222 -39.751) (xy 12.9032 -39.751) (xy 12.9032 -40.259)
				)
			)
		)
		(zone
			(layer "F.Cu")
			(hatch none 0.5)
			(connect_pads
				(clearance 0)
			)
			(min_thickness 0.25)
			(keepout
				(tracks allowed)
				(vias not_allowed)
				(pads allowed)
				(copperpour not_allowed)
				(footprints allowed)
			)
			(placement
				(enabled no)
				(sheetname "")
			)
			(fill
				(thermal_gap 0.5)
				(thermal_bridge_width 0.5)
				(island_removal_mode 0)
			)
			(polygon
				(pts
					(xy 12.9032 -40.259) (xy 12.9032 -39.751) (xy 12.5222 -39.751) (xy 12.5222 -40.259)
				)
			)
		)
	)
	(footprint ""
		(layer "F.Cu")
		(at 402.382482 -29.382466)
		(property "Reference" "R25W87"
			(at -0.8382 -0.67818 0)
			(unlocked yes)
			(layer "F.SilkS")
			(effects
				(font
					(size 0.4064 0.254)
					(thickness 0.1524)
				)
				(justify left)
			)
		)
		(property "Value" ""
			(at 0 0 0)
			(layer "F.Fab")
			(effects
				(font
					(size 1.27 1.27)
				)
			)
		)
		(duplicate_pad_numbers_are_jumpers no)
		(fp_poly
			(pts
				(xy -0.2794 -0.1016) (xy 0.2794 -0.1016) (xy 0.2794 0.9906) (xy -0.2794 0.9906)
			)
			(stroke
				(width 0)
				(type default)
			)
			(fill no)
			(layer "F.CrtYd")
		)
		(fp_line
			(start -0.2794 -0.1016)
			(end -0.2794 0.9906)
			(stroke
				(width 0.1)
				(type default)
			)
			(layer "F.Fab")
		)
		(fp_line
			(start -0.2794 0.9906)
			(end 0.2794 0.9906)
			(stroke
				(width 0.1)
				(type default)
			)
			(layer "F.Fab")
		)
		(fp_line
			(start 0.2794 -0.1016)
			(end -0.2794 -0.1016)
			(stroke
				(width 0.1)
				(type default)
			)
			(layer "F.Fab")
		)
		(fp_line
			(start 0.2794 0.9906)
			(end 0.2794 -0.1016)
			(stroke
				(width 0.1)
				(type default)
			)
			(layer "F.Fab")
		)
		(pad "1" smd rect
			(at 0 0)
			(size 0.508 0.508)
			(layers "F.Cu" "F.Mask" "F.Paste")
			(net "RMII_BMC_OCP_TXD1_R")
		)
		(pad "2" smd rect
			(at 0 0.889)
			(size 0.508 0.508)
			(layers "F.Cu" "F.Mask" "F.Paste")
			(net "RMII_BMC_OCP_TXD1")
		)
		(zone
			(layer "F.Cu")
			(hatch none 0.5)
			(connect_pads
				(clearance 0)
			)
			(min_thickness 0.25)
			(keepout
				(tracks allowed)
				(vias not_allowed)
				(pads allowed)
				(copperpour not_allowed)
				(footprints allowed)
			)
			(placement
				(enabled no)
				(sheetname "")
			)
			(fill
				(thermal_gap 0.5)
				(thermal_bridge_width 0.5)
				(island_removal_mode 0)
			)
			(polygon
				(pts
					(xy 402.128482 -29.128466) (xy 402.636482 -29.128466) (xy 402.636482 -28.747466) (xy 402.128482 -28.747466)
				)
			)
		)
		(zone
			(layer "F.Cu")
			(hatch none 0.5)
			(connect_pads
				(clearance 0)
			)
			(min_thickness 0.25)
			(keepout
				(tracks not_allowed)
				(vias allowed)
				(pads allowed)
				(copperpour not_allowed)
				(footprints allowed)
			)
			(placement
				(enabled no)
				(sheetname "")
			)
			(fill
				(thermal_gap 0.5)
				(thermal_bridge_width 0.5)
				(island_removal_mode 0)
			)
			(polygon
				(pts
					(xy 402.128482 -28.747466) (xy 402.636482 -28.747466) (xy 402.636482 -29.128466) (xy 402.128482 -29.128466)
				)
			)
		)
	)
	(footprint ""
		(layer "F.Cu")
		(at 396.515082 -157.707076 -90)
		(property "Reference" "RF24"
			(at -0.8382 -0.67818 270)
			(unlocked yes)
			(layer "F.SilkS")
			(effects
				(font
					(size 0.4064 0.254)
					(thickness 0.1524)
				)
				(justify left)
			)
		)
		(property "Value" ""
			(at 0 0 270)
			(layer "F.Fab")
			(effects
				(font
					(size 1.27 1.27)
				)
			)
		)
		(duplicate_pad_numbers_are_jumpers no)
		(fp_poly
			(pts
				(xy -0.2794 -0.1016) (xy 0.2794 -0.1016) (xy 0.2794 0.9906) (xy -0.2794 0.9906)
			)
			(stroke
				(width 0)
				(type default)
			)
			(fill no)
			(layer "F.CrtYd")
		)
		(fp_line
			(start -0.2794 0.9906)
			(end 0.2794 0.9906)
			(stroke
				(width 0.1)
				(type default)
			)
			(layer "F.Fab")
		)
		(fp_line
			(start 0.2794 0.9906)
			(end 0.2794 -0.1016)
			(stroke
				(width 0.1)
				(type default)
			)
			(layer "F.Fab")
		)
		(fp_line
			(start -0.2794 -0.1016)
			(end -0.2794 0.9906)
			(stroke
				(width 0.1)
				(type default)
			)
			(layer "F.Fab")
		)
		(fp_line
			(start 0.2794 -0.1016)
			(end -0.2794 -0.1016)
			(stroke
				(width 0.1)
				(type default)
			)
			(layer "F.Fab")
		)
		(pad "1" smd rect
			(at 0 0 270)
			(size 0.508 0.508)
			(layers "F.Cu" "F.Mask" "F.Paste")
			(net "VR_P1V05_PCH_BIREF1")
		)
		(pad "2" smd rect
			(at 0 0.889 270)
			(size 0.508 0.508)
			(layers "F.Cu" "F.Mask" "F.Paste")
			(net "ISENSE_P1V05_PCH_STBY_PH1_IMON")
		)
		(zone
			(layer "F.Cu")
			(hatch none 0.5)
			(connect_pads
				(clearance 0)
			)
			(min_thickness 0.25)
			(keepout
				(tracks not_allowed)
				(vias allowed)
				(pads allowed)
				(copperpour not_allowed)
				(footprints allowed)
			)
			(placement
				(enabled no)
				(sheetname "")
			)
			(fill
				(thermal_gap 0.5)
				(thermal_bridge_width 0.5)
				(island_removal_mode 0)
			)
			(polygon
				(pts
					(xy 395.880082 -157.961076) (xy 395.880082 -157.453076) (xy 396.261082 -157.453076) (xy 396.261082 -157.961076)
				)
			)
		)
		(zone
			(layer "F.Cu")
			(hatch none 0.5)
			(connect_pads
				(clearance 0)
			)
			(min_thickness 0.25)
			(keepout
				(tracks allowed)
				(vias not_allowed)
				(pads allowed)
				(copperpour not_allowed)
				(footprints allowed)
			)
			(placement
				(enabled no)
				(sheetname "")
			)
			(fill
				(thermal_gap 0.5)
				(thermal_bridge_width 0.5)
				(island_removal_mode 0)
			)
			(polygon
				(pts
					(xy 396.261082 -157.961076) (xy 396.261082 -157.453076) (xy 395.880082 -157.453076) (xy 395.880082 -157.961076)
				)
			)
		)
	)
	(footprint ""
		(layer "F.Cu")
		(at 492.228886 -47.458884)
		(property "Reference" "R25W139"
			(at -0.8382 -0.67818 0)
			(unlocked yes)
			(layer "F.SilkS")
			(effects
				(font
					(size 0.4064 0.254)
					(thickness 0.1524)
				)
				(justify left)
			)
		)
		(property "Value" ""
			(at 0 0 0)
			(layer "F.Fab")
			(effects
				(font
					(size 1.27 1.27)
				)
			)
		)
		(duplicate_pad_numbers_are_jumpers no)
		(fp_poly
			(pts
				(xy -0.2794 -0.1016) (xy 0.2794 -0.1016) (xy 0.2794 0.9906) (xy -0.2794 0.9906)
			)
			(stroke
				(width 0)
				(type default)
			)
			(fill no)
			(layer "F.CrtYd")
		)
		(fp_line
			(start -0.2794 -0.1016)
			(end -0.2794 0.9906)
			(stroke
				(width 0.1)
				(type default)
			)
			(layer "F.Fab")
		)
		(fp_line
			(start -0.2794 0.9906)
			(end 0.2794 0.9906)
			(stroke
				(width 0.1)
				(type default)
			)
			(layer "F.Fab")
		)
		(fp_line
			(start 0.2794 -0.1016)
			(end -0.2794 -0.1016)
			(stroke
				(width 0.1)
				(type default)
			)
			(layer "F.Fab")
		)
		(fp_line
			(start 0.2794 0.9906)
			(end 0.2794 -0.1016)
			(stroke
				(width 0.1)
				(type default)
			)
			(layer "F.Fab")
		)
		(pad "1" smd rect
			(at 0 0)
			(size 0.508 0.508)
			(layers "F.Cu" "F.Mask" "F.Paste")
			(net "VGA_REAR_VSYNC_S")
		)
		(pad "2" smd rect
			(at 0 0.889)
			(size 0.508 0.508)
			(layers "F.Cu" "F.Mask" "F.Paste")
			(net "V_IO_VSYNC_J")
		)
		(zone
			(layer "F.Cu")
			(hatch none 0.5)
			(connect_pads
				(clearance 0)
			)
			(min_thickness 0.25)
			(keepout
				(tracks allowed)
				(vias not_allowed)
				(pads allowed)
				(copperpour not_allowed)
				(footprints allowed)
			)
			(placement
				(enabled no)
				(sheetname "")
			)
			(fill
				(thermal_gap 0.5)
				(thermal_bridge_width 0.5)
				(island_removal_mode 0)
			)
			(polygon
				(pts
					(xy 491.974886 -47.204884) (xy 492.482886 -47.204884) (xy 492.482886 -46.823884) (xy 491.974886 -46.823884)
				)
			)
		)
		(zone
			(layer "F.Cu")
			(hatch none 0.5)
			(connect_pads
				(clearance 0)
			)
			(min_thickness 0.25)
			(keepout
				(tracks not_allowed)
				(vias allowed)
				(pads allowed)
				(copperpour not_allowed)
				(footprints allowed)
			)
			(placement
				(enabled no)
				(sheetname "")
			)
			(fill
				(thermal_gap 0.5)
				(thermal_bridge_width 0.5)
				(island_removal_mode 0)
			)
			(polygon
				(pts
					(xy 491.974886 -46.823884) (xy 492.482886 -46.823884) (xy 492.482886 -47.204884) (xy 491.974886 -47.204884)
				)
			)
		)
	)
	(footprint ""
		(layer "F.Cu")
		(at 368.4016 -130.429 180)
		(property "Reference" "C7B21"
			(at 0 0 180)
			(layer "F.SilkS")
			(hide yes)
			(effects
				(font
					(size 1.27 1.27)
				)
			)
		)
		(property "Value" ""
			(at 0 0 180)
			(layer "F.Fab")
			(effects
				(font
					(size 1.27 1.27)
				)
			)
		)
		(duplicate_pad_numbers_are_jumpers no)
		(fp_poly
			(pts
				(xy -0.4953 -0.2032) (xy 0.4953 -0.2032) (xy 0.4953 1.6002) (xy -0.4953 1.6002)
			)
			(stroke
				(width 0)
				(type default)
			)
			(fill no)
			(layer "F.CrtYd")
		)
		(fp_line
			(start 0.4953 1.6002)
			(end -0.4953 1.6002)
			(stroke
				(width 0.1)
				(type default)
			)
			(layer "F.Fab")
		)
		(fp_line
			(start 0.4953 -0.2032)
			(end 0.4953 1.6002)
			(stroke
				(width 0.1)
				(type default)
			)
			(layer "F.Fab")
		)
		(fp_line
			(start -0.4953 1.6002)
			(end -0.4953 -0.2032)
			(stroke
				(width 0.1)
				(type default)
			)
			(layer "F.Fab")
		)
		(fp_line
			(start -0.4953 -0.2032)
			(end 0.4953 -0.2032)
			(stroke
				(width 0.1)
				(type default)
			)
			(layer "F.Fab")
		)
		(pad "1" smd rect
			(at 0 0 180)
			(size 0.762 0.889)
			(layers "F.Cu" "F.Mask" "F.Paste")
			(net "P1V05_PCH_STBY")
		)
		(pad "2" smd rect
			(at 0 1.397 180)
			(size 0.762 0.889)
			(layers "F.Cu" "F.Mask" "F.Paste")
			(net "GND")
		)
		(zone
			(layer "F.Cu")
			(hatch none 0.5)
			(connect_pads
				(clearance 0)
			)
			(min_thickness 0.25)
			(keepout
				(tracks not_allowed)
				(vias allowed)
				(pads allowed)
				(copperpour not_allowed)
				(footprints allowed)
			)
			(placement
				(enabled no)
				(sheetname "")
			)
			(fill
				(thermal_gap 0.5)
				(thermal_bridge_width 0.5)
				(island_removal_mode 0)
			)
			(polygon
				(pts
					(xy 368.7826 -130.8735) (xy 368.0206 -130.8735) (xy 368.0206 -131.3815) (xy 368.7826 -131.3815)
				)
			)
		)
	)
	(footprint ""
		(layer "F.Cu")
		(at 419.0746 -21.6535)
		(property "Reference" "R2U1"
			(at 0 0 0)
			(layer "F.SilkS")
			(hide yes)
			(effects
				(font
					(size 1.27 1.27)
				)
			)
		)
		(property "Value" ""
			(at 0 0 0)
			(layer "F.Fab")
			(effects
				(font
					(size 1.27 1.27)
				)
			)
		)
		(duplicate_pad_numbers_are_jumpers no)
		(fp_poly
			(pts
				(xy -0.2794 -0.1016) (xy 0.2794 -0.1016) (xy 0.2794 0.9906) (xy -0.2794 0.9906)
			)
			(stroke
				(width 0)
				(type default)
			)
			(fill no)
			(layer "F.CrtYd")
		)
		(fp_line
			(start -0.2794 -0.1016)
			(end -0.2794 0.9906)
			(stroke
				(width 0.1)
				(type default)
			)
			(layer "F.Fab")
		)
		(fp_line
			(start -0.2794 0.9906)
			(end 0.2794 0.9906)
			(stroke
				(width 0.1)
				(type default)
			)
			(layer "F.Fab")
		)
		(fp_line
			(start 0.2794 -0.1016)
			(end -0.2794 -0.1016)
			(stroke
				(width 0.1)
				(type default)
			)
			(layer "F.Fab")
		)
		(fp_line
			(start 0.2794 0.9906)
			(end 0.2794 -0.1016)
			(stroke
				(width 0.1)
				(type default)
			)
			(layer "F.Fab")
		)
		(pad "1" smd rect
			(at 0 0)
			(size 0.508 0.508)
			(layers "F.Cu" "F.Mask" "F.Paste")
			(net "SMB_BMC_PMBUS_STBY_LVC3_SCL_R")
		)
		(pad "2" smd rect
			(at 0 0.889)
			(size 0.508 0.508)
			(layers "F.Cu" "F.Mask" "F.Paste")
			(net "SMB_BMC_PMBUS_STBY_LVC3_SCL")
		)
		(zone
			(layer "F.Cu")
			(hatch none 0.5)
			(connect_pads
				(clearance 0)
			)
			(min_thickness 0.25)
			(keepout
				(tracks allowed)
				(vias not_allowed)
				(pads allowed)
				(copperpour not_allowed)
				(footprints allowed)
			)
			(placement
				(enabled no)
				(sheetname "")
			)
			(fill
				(thermal_gap 0.5)
				(thermal_bridge_width 0.5)
				(island_removal_mode 0)
			)
			(polygon
				(pts
					(xy 418.8206 -21.3995) (xy 419.3286 -21.3995) (xy 419.3286 -21.0185) (xy 418.8206 -21.0185)
				)
			)
		)
		(zone
			(layer "F.Cu")
			(hatch none 0.5)
			(connect_pads
				(clearance 0)
			)
			(min_thickness 0.25)
			(keepout
				(tracks not_allowed)
				(vias allowed)
				(pads allowed)
				(copperpour not_allowed)
				(footprints allowed)
			)
			(placement
				(enabled no)
				(sheetname "")
			)
			(fill
				(thermal_gap 0.5)
				(thermal_bridge_width 0.5)
				(island_removal_mode 0)
			)
			(polygon
				(pts
					(xy 418.8206 -21.0185) (xy 419.3286 -21.0185) (xy 419.3286 -21.3995) (xy 418.8206 -21.3995)
				)
			)
		)
	)
	(footprint ""
		(layer "F.Cu")
		(at 312.650124 -30.26537)
		(property "Reference" "Y6F1"
			(at -0.1397 -2.153412 0)
			(unlocked yes)
			(layer "F.SilkS")
			(effects
				(font
					(size 0.7874 0.5842)
					(thickness 0.1524)
				)
				(justify left)
			)
		)
		(property "Value" ""
			(at 0 0 0)
			(layer "F.Fab")
			(effects
				(font
					(size 1.27 1.27)
				)
			)
		)
		(duplicate_pad_numbers_are_jumpers no)
		(fp_line
			(start -0.366522 -1.329944)
			(end 3.033522 -1.329944)
			(stroke
				(width 0.1524)
				(type default)
			)
			(layer "F.SilkS")
		)
		(fp_line
			(start -0.366522 -0.80391)
			(end -0.366522 -1.329944)
			(stroke
				(width 0.1524)
				(type default)
			)
			(layer "F.SilkS")
		)
		(fp_line
			(start -0.366522 3.869944)
			(end -0.366522 3.363468)
			(stroke
				(width 0.1524)
				(type default)
			)
			(layer "F.SilkS")
		)
		(fp_line
			(start 3.033522 -1.329944)
			(end 3.033522 -0.790956)
			(stroke
				(width 0.1524)
				(type default)
			)
			(layer "F.SilkS")
		)
		(fp_line
			(start 3.033522 3.370072)
			(end 3.033522 3.869944)
			(stroke
				(width 0.1524)
				(type default)
			)
			(layer "F.SilkS")
		)
		(fp_line
			(start 3.033522 3.869944)
			(end -0.366522 3.869944)
			(stroke
				(width 0.1524)
				(type default)
			)
			(layer "F.SilkS")
		)
		(fp_circle
			(center -1.406398 -0.537718)
			(end -1.279398 -0.537718)
			(stroke
				(width 0.254)
				(type default)
			)
			(fill no)
			(layer "F.SilkS")
		)
		(fp_rect
			(start -0.366522 3.869944)
			(end 3.033522 -1.329944)
			(stroke
				(width 0)
				(type default)
			)
			(fill no)
			(layer "F.CrtYd")
		)
		(fp_line
			(start -0.366522 -1.329944)
			(end 3.033522 -1.329944)
			(stroke
				(width 0.1)
				(type default)
			)
			(layer "F.Fab")
		)
		(fp_line
			(start -0.366522 3.869944)
			(end -0.366522 -1.329944)
			(stroke
				(width 0.1)
				(type default)
			)
			(layer "F.Fab")
		)
		(fp_line
			(start 3.033522 -1.329944)
			(end 3.033522 3.869944)
			(stroke
				(width 0.1)
				(type default)
			)
			(layer "F.Fab")
		)
		(fp_line
			(start 3.033522 3.869944)
			(end -0.366522 3.869944)
			(stroke
				(width 0.1)
				(type default)
			)
			(layer "F.Fab")
		)
		(fp_circle
			(center -1.405128 -0.544068)
			(end -1.278128 -0.544068)
			(stroke
				(width 0.254)
				(type default)
			)
			(fill no)
			(layer "F.Fab")
		)
		(pad "1" smd rect
			(at 0 0)
			(size 1.651 0.8382)
			(layers "F.Cu" "F.Mask" "F.Paste")
			(net "FM_CPU0_STL_BRD_OSC_EN")
		)
		(pad "2" smd rect
			(at 0 1.27)
			(size 1.651 0.8382)
			(layers "F.Cu" "F.Mask" "F.Paste")
			(net "NC_CLK_156M_CPU0_OSC")
		)
		(pad "3" smd rect
			(at 0 2.54)
			(size 1.651 0.8382)
			(layers "F.Cu" "F.Mask" "F.Paste")
			(net "GND")
		)
		(pad "4" smd rect
			(at 2.667 2.54)
			(size 1.651 0.8382)
			(layers "F.Cu" "F.Mask" "F.Paste")
			(net "CLK_156M_OSC_BRD_CPU0_DP")
		)
		(pad "5" smd rect
			(at 2.667 1.27)
			(size 1.651 0.8382)
			(layers "F.Cu" "F.Mask" "F.Paste")
			(net "CLK_156M_OSC_BRD_CPU0_DN")
		)
		(pad "6" smd rect
			(at 2.667 0)
			(size 1.651 0.8382)
			(layers "F.Cu" "F.Mask" "F.Paste")
			(net "P3V3")
		)
	)
	(footprint ""
		(layer "F.Cu")
		(at 211.831936 11.952478 -90)
		(property "Reference" "T1P3"
			(at 0 0 270)
			(layer "F.SilkS")
			(hide yes)
			(effects
				(font
					(size 1.27 1.27)
				)
			)
		)
		(property "Value" "*"
			(at -3.302 1.12395 270)
			(unlocked yes)
			(layer "F.Fab")
			(hide yes)
			(effects
				(font
					(size 0.889 0.889)
					(thickness 0.1524)
				)
			)
		)
		(property "Device Type" "TPAD-DIFF-4P-GP_DISCRET-GB3-TPA"
			(at -3.302 -0.40005 270)
			(unlocked yes)
			(layer "F.Fab")
			(hide yes)
			(effects
				(font
					(size 0.889 0.889)
					(thickness 0.1524)
				)
			)
		)
		(duplicate_pad_numbers_are_jumpers no)
		(fp_line
			(start -2.286 2.286)
			(end 2.286 2.286)
			(stroke
				(width 0.1524)
				(type default)
			)
			(layer "F.SilkS")
		)
		(fp_line
			(start 2.286 2.286)
			(end 2.286 -2.286)
			(stroke
				(width 0.1524)
				(type default)
			)
			(layer "F.SilkS")
		)
		(fp_line
			(start -2.286 -2.286)
			(end -2.286 2.286)
			(stroke
				(width 0.1524)
				(type default)
			)
			(layer "F.SilkS")
		)
		(fp_line
			(start 2.286 -2.286)
			(end -2.286 -2.286)
			(stroke
				(width 0.1524)
				(type default)
			)
			(layer "F.SilkS")
		)
		(fp_line
			(start -2.413 -2.413)
			(end -2.413 -1.143)
			(stroke
				(width 0.4064)
				(type default)
			)
			(layer "F.SilkS")
		)
		(fp_line
			(start -1.143 -2.413)
			(end -2.413 -2.413)
			(stroke
				(width 0.4064)
				(type default)
			)
			(layer "F.SilkS")
		)
		(fp_rect
			(start -2.54 2.54)
			(end 2.54 -2.54)
			(stroke
				(width 0)
				(type default)
			)
			(fill no)
			(layer "F.CrtYd")
		)
		(fp_rect
			(start -2.54 2.54)
			(end 2.54 -2.54)
			(stroke
				(width 0)
				(type default)
			)
			(fill no)
			(layer "F.Fab")
		)
		(pad "1" thru_hole circle
			(at -1.27 -1.27 270)
			(size 1.524 1.524)
			(drill 0.9144)
			(layers "*.Cu" "*.Mask")
			(remove_unused_layers no)
			(net "L5_85OHM_6INCH_DP")
			(clearance -0.0508)
			(thermal_gap 0.127)
			(padstack
				(mode front_inner_back)
				(layer "Inner"
					(shape circle)
					(size 1.1684 1.1684)
					(clearance 0.127)
				)
				(layer "B.Cu"
					(shape circle)
					(size 1.524 1.524)
					(clearance -0.0508)
				)
			)
		)
		(pad "2" thru_hole circle
			(at 1.27 -1.27 270)
			(size 1.524 1.524)
			(drill 0.9144)
			(layers "*.Cu" "*.Mask")
			(remove_unused_layers no)
			(net "L5_85OHM_6INCH_DN")
			(clearance -0.0508)
			(thermal_gap 0.127)
			(padstack
				(mode front_inner_back)
				(layer "Inner"
					(shape circle)
					(size 1.1684 1.1684)
					(clearance 0.127)
				)
				(layer "B.Cu"
					(shape circle)
					(size 1.524 1.524)
					(clearance -0.0508)
				)
			)
		)
		(pad "GND1" thru_hole rect
			(at -1.27 1.27 270)
			(size 1.524 1.524)
			(drill 0.9144)
			(layers "*.Cu" "*.Mask")
			(remove_unused_layers no)
			(net "GND")
			(clearance -0.0508)
			(thermal_gap 0.127)
			(padstack
				(mode front_inner_back)
				(layer "Inner"
					(shape circle)
					(size 1.1684 1.1684)
					(clearance 0.127)
				)
				(layer "B.Cu"
					(shape rect)
					(size 1.524 1.524)
					(clearance -0.0508)
				)
			)
		)
		(pad "GND2" thru_hole rect
			(at 1.27 1.27 270)
			(size 1.524 1.524)
			(drill 0.9144)
			(layers "*.Cu" "*.Mask")
			(remove_unused_layers no)
			(net "GND")
			(clearance -0.0508)
			(thermal_gap 0.127)
			(padstack
				(mode front_inner_back)
				(layer "Inner"
					(shape circle)
					(size 1.1684 1.1684)
					(clearance 0.127)
				)
				(layer "B.Cu"
					(shape rect)
					(size 1.524 1.524)
					(clearance -0.0508)
				)
			)
		)
	)
	(footprint ""
		(layer "F.Cu")
		(at 108.839 -68.072 90)
		(property "Reference" "R3D27"
			(at 0 0 90)
			(layer "F.SilkS")
			(hide yes)
			(effects
				(font
					(size 1.27 1.27)
				)
			)
		)
		(property "Value" ""
			(at 0 0 90)
			(layer "F.Fab")
			(effects
				(font
					(size 1.27 1.27)
				)
			)
		)
		(duplicate_pad_numbers_are_jumpers no)
		(fp_poly
			(pts
				(xy -0.2794 -0.1016) (xy 0.2794 -0.1016) (xy 0.2794 0.9906) (xy -0.2794 0.9906)
			)
			(stroke
				(width 0)
				(type default)
			)
			(fill no)
			(layer "F.CrtYd")
		)
		(fp_line
			(start 0.2794 -0.1016)
			(end -0.2794 -0.1016)
			(stroke
				(width 0.1)
				(type default)
			)
			(layer "F.Fab")
		)
		(fp_line
			(start -0.2794 -0.1016)
			(end -0.2794 0.9906)
			(stroke
				(width 0.1)
				(type default)
			)
			(layer "F.Fab")
		)
		(fp_line
			(start 0.2794 0.9906)
			(end 0.2794 -0.1016)
			(stroke
				(width 0.1)
				(type default)
			)
			(layer "F.Fab")
		)
		(fp_line
			(start -0.2794 0.9906)
			(end 0.2794 0.9906)
			(stroke
				(width 0.1)
				(type default)
			)
			(layer "F.Fab")
		)
		(pad "1" smd rect
			(at 0 0 90)
			(size 0.508 0.508)
			(layers "F.Cu" "F.Mask" "F.Paste")
			(net "VSENSE_PMAX_CPU1")
		)
		(pad "2" smd rect
			(at 0 0.889 90)
			(size 0.508 0.508)
			(layers "F.Cu" "F.Mask" "F.Paste")
			(net "GND")
		)
		(zone
			(layer "F.Cu")
			(hatch none 0.5)
			(connect_pads
				(clearance 0)
			)
			(min_thickness 0.25)
			(keepout
				(tracks allowed)
				(vias not_allowed)
				(pads allowed)
				(copperpour not_allowed)
				(footprints allowed)
			)
			(placement
				(enabled no)
				(sheetname "")
			)
			(fill
				(thermal_gap 0.5)
				(thermal_bridge_width 0.5)
				(island_removal_mode 0)
			)
			(polygon
				(pts
					(xy 109.093 -67.818) (xy 109.093 -68.326) (xy 109.474 -68.326) (xy 109.474 -67.818)
				)
			)
		)
		(zone
			(layer "F.Cu")
			(hatch none 0.5)
			(connect_pads
				(clearance 0)
			)
			(min_thickness 0.25)
			(keepout
				(tracks not_allowed)
				(vias allowed)
				(pads allowed)
				(copperpour not_allowed)
				(footprints allowed)
			)
			(placement
				(enabled no)
				(sheetname "")
			)
			(fill
				(thermal_gap 0.5)
				(thermal_bridge_width 0.5)
				(island_removal_mode 0)
			)
			(polygon
				(pts
					(xy 109.474 -67.818) (xy 109.474 -68.326) (xy 109.093 -68.326) (xy 109.093 -67.818)
				)
			)
		)
	)
	(footprint ""
		(layer "F.Cu")
		(at 348.0054 -19.304 180)
		(property "Reference" "C7F16"
			(at 0 0 180)
			(layer "F.SilkS")
			(hide yes)
			(effects
				(font
					(size 1.27 1.27)
				)
			)
		)
		(property "Value" ""
			(at 0 0 180)
			(layer "F.Fab")
			(effects
				(font
					(size 1.27 1.27)
				)
			)
		)
		(duplicate_pad_numbers_are_jumpers no)
		(fp_poly
			(pts
				(xy 0.3048 -0.1016) (xy 0.3048 0.9906) (xy -0.3048 0.9906) (xy -0.3048 -0.1016)
			)
			(stroke
				(width 0)
				(type default)
			)
			(fill no)
			(layer "F.CrtYd")
		)
		(fp_line
			(start 0.3048 0.9906)
			(end 0.3048 -0.1016)
			(stroke
				(width 0.1)
				(type default)
			)
			(layer "F.Fab")
		)
		(fp_line
			(start 0.3048 -0.1016)
			(end -0.3048 -0.1016)
			(stroke
				(width 0.1)
				(type default)
			)
			(layer "F.Fab")
		)
		(fp_line
			(start -0.3048 0.9906)
			(end 0.3048 0.9906)
			(stroke
				(width 0.1)
				(type default)
			)
			(layer "F.Fab")
		)
		(fp_line
			(start -0.3048 -0.1016)
			(end -0.3048 0.9906)
			(stroke
				(width 0.1)
				(type default)
			)
			(layer "F.Fab")
		)
		(pad "1" smd rect
			(at 0 0 180)
			(size 0.508 0.508)
			(layers "F.Cu" "F.Mask" "F.Paste")
			(net "VR_PVDDQ_ABC_VD12")
		)
		(pad "2" smd rect
			(at 0 0.889 180)
			(size 0.508 0.508)
			(layers "F.Cu" "F.Mask" "F.Paste")
			(net "GND")
		)
		(zone
			(layer "F.Cu")
			(hatch none 0.5)
			(connect_pads
				(clearance 0)
			)
			(min_thickness 0.25)
			(keepout
				(tracks not_allowed)
				(vias allowed)
				(pads allowed)
				(copperpour not_allowed)
				(footprints allowed)
			)
			(placement
				(enabled no)
				(sheetname "")
			)
			(fill
				(thermal_gap 0.5)
				(thermal_bridge_width 0.5)
				(island_removal_mode 0)
			)
			(polygon
				(pts
					(xy 348.2594 -19.939) (xy 347.7514 -19.939) (xy 347.7514 -19.558) (xy 348.2594 -19.558)
				)
			)
		)
		(zone
			(layer "F.Cu")
			(hatch none 0.5)
			(connect_pads
				(clearance 0)
			)
			(min_thickness 0.25)
			(keepout
				(tracks allowed)
				(vias not_allowed)
				(pads allowed)
				(copperpour not_allowed)
				(footprints allowed)
			)
			(placement
				(enabled no)
				(sheetname "")
			)
			(fill
				(thermal_gap 0.5)
				(thermal_bridge_width 0.5)
				(island_removal_mode 0)
			)
			(polygon
				(pts
					(xy 348.2594 -19.558) (xy 347.7514 -19.558) (xy 347.7514 -19.939) (xy 348.2594 -19.939)
				)
			)
		)
	)
	(footprint ""
		(layer "F.Cu")
		(at 466.344 -41.0972)
		(property "Reference" "C9E11"
			(at 0 0 0)
			(layer "F.SilkS")
			(hide yes)
			(effects
				(font
					(size 1.27 1.27)
				)
			)
		)
		(property "Value" ""
			(at 0 0 0)
			(layer "F.Fab")
			(effects
				(font
					(size 1.27 1.27)
				)
			)
		)
		(duplicate_pad_numbers_are_jumpers no)
		(fp_poly
			(pts
				(xy 0.3048 -0.1016) (xy 0.3048 0.9906) (xy -0.3048 0.9906) (xy -0.3048 -0.1016)
			)
			(stroke
				(width 0)
				(type default)
			)
			(fill no)
			(layer "F.CrtYd")
		)
		(fp_line
			(start -0.3048 -0.1016)
			(end -0.3048 0.9906)
			(stroke
				(width 0.1)
				(type default)
			)
			(layer "F.Fab")
		)
		(fp_line
			(start -0.3048 0.9906)
			(end 0.3048 0.9906)
			(stroke
				(width 0.1)
				(type default)
			)
			(layer "F.Fab")
		)
		(fp_line
			(start 0.3048 -0.1016)
			(end -0.3048 -0.1016)
			(stroke
				(width 0.1)
				(type default)
			)
			(layer "F.Fab")
		)
		(fp_line
			(start 0.3048 0.9906)
			(end 0.3048 -0.1016)
			(stroke
				(width 0.1)
				(type default)
			)
			(layer "F.Fab")
		)
		(pad "1" smd rect
			(at 0 0)
			(size 0.508 0.508)
			(layers "F.Cu" "F.Mask" "F.Paste")
			(net "P3V3_STBY")
		)
		(pad "2" smd rect
			(at 0 0.889)
			(size 0.508 0.508)
			(layers "F.Cu" "F.Mask" "F.Paste")
			(net "GND")
		)
		(zone
			(layer "F.Cu")
			(hatch none 0.5)
			(connect_pads
				(clearance 0)
			)
			(min_thickness 0.25)
			(keepout
				(tracks allowed)
				(vias not_allowed)
				(pads allowed)
				(copperpour not_allowed)
				(footprints allowed)
			)
			(placement
				(enabled no)
				(sheetname "")
			)
			(fill
				(thermal_gap 0.5)
				(thermal_bridge_width 0.5)
				(island_removal_mode 0)
			)
			(polygon
				(pts
					(xy 466.09 -40.8432) (xy 466.598 -40.8432) (xy 466.598 -40.4622) (xy 466.09 -40.4622)
				)
			)
		)
		(zone
			(layer "F.Cu")
			(hatch none 0.5)
			(connect_pads
				(clearance 0)
			)
			(min_thickness 0.25)
			(keepout
				(tracks not_allowed)
				(vias allowed)
				(pads allowed)
				(copperpour not_allowed)
				(footprints allowed)
			)
			(placement
				(enabled no)
				(sheetname "")
			)
			(fill
				(thermal_gap 0.5)
				(thermal_bridge_width 0.5)
				(island_removal_mode 0)
			)
			(polygon
				(pts
					(xy 466.09 -40.4622) (xy 466.598 -40.4622) (xy 466.598 -40.8432) (xy 466.09 -40.8432)
				)
			)
		)
	)
	(footprint ""
		(layer "F.Cu")
		(at 13.8938 -29.464 90)
		(property "Reference" "C1F12"
			(at 0 0 90)
			(layer "F.SilkS")
			(hide yes)
			(effects
				(font
					(size 1.27 1.27)
				)
			)
		)
		(property "Value" ""
			(at 0 0 90)
			(layer "F.Fab")
			(effects
				(font
					(size 1.27 1.27)
				)
			)
		)
		(duplicate_pad_numbers_are_jumpers no)
		(fp_rect
			(start -0.3048 -0.1016)
			(end 0.3048 0.9906)
			(stroke
				(width 0)
				(type default)
			)
			(fill no)
			(layer "F.CrtYd")
		)
		(fp_line
			(start 0.3048 -0.1016)
			(end -0.3048 -0.1016)
			(stroke
				(width 0.1)
				(type default)
			)
			(layer "F.Fab")
		)
		(fp_line
			(start -0.3048 -0.1016)
			(end -0.3048 0.9906)
			(stroke
				(width 0.1)
				(type default)
			)
			(layer "F.Fab")
		)
		(fp_line
			(start 0.3048 0.9906)
			(end 0.3048 -0.1016)
			(stroke
				(width 0.1)
				(type default)
			)
			(layer "F.Fab")
		)
		(fp_line
			(start -0.3048 0.9906)
			(end 0.3048 0.9906)
			(stroke
				(width 0.1)
				(type default)
			)
			(layer "F.Fab")
		)
		(pad "1" smd rect
			(at 0 0 90)
			(size 0.508 0.508)
			(layers "F.Cu" "F.Mask" "F.Paste")
			(net "P3E_CPU1_PE3_MP_C_TXP<3>")
		)
		(pad "2" smd rect
			(at 0 0.889 90)
			(size 0.508 0.508)
			(layers "F.Cu" "F.Mask" "F.Paste")
			(net "P3E_CPU1_PE3_MP_TXP<3>")
		)
		(zone
			(layer "F.Cu")
			(hatch none 0.5)
			(connect_pads
				(clearance 0)
			)
			(min_thickness 0.25)
			(keepout
				(tracks allowed)
				(vias not_allowed)
				(pads allowed)
				(copperpour not_allowed)
				(footprints allowed)
			)
			(placement
				(enabled no)
				(sheetname "")
			)
			(fill
				(thermal_gap 0.5)
				(thermal_bridge_width 0.5)
				(island_removal_mode 0)
			)
			(polygon
				(pts
					(xy 14.1478 -29.21) (xy 14.5288 -29.21) (xy 14.5288 -29.718) (xy 14.1478 -29.718)
				)
			)
		)
		(zone
			(layer "F.Cu")
			(hatch none 0.5)
			(connect_pads
				(clearance 0)
			)
			(min_thickness 0.25)
			(keepout
				(tracks not_allowed)
				(vias allowed)
				(pads allowed)
				(copperpour not_allowed)
				(footprints allowed)
			)
			(placement
				(enabled no)
				(sheetname "")
			)
			(fill
				(thermal_gap 0.5)
				(thermal_bridge_width 0.5)
				(island_removal_mode 0)
			)
			(polygon
				(pts
					(xy 14.1478 -29.21) (xy 14.5288 -29.21) (xy 14.5288 -29.718) (xy 14.1478 -29.718)
				)
			)
		)
	)
	(footprint ""
		(layer "F.Cu")
		(at 382.27 -87.3125 180)
		(property "Reference" "R7D7"
			(at 0 0 180)
			(layer "F.SilkS")
			(hide yes)
			(effects
				(font
					(size 1.27 1.27)
				)
			)
		)
		(property "Value" ""
			(at 0 0 180)
			(layer "F.Fab")
			(effects
				(font
					(size 1.27 1.27)
				)
			)
		)
		(duplicate_pad_numbers_are_jumpers no)
		(fp_poly
			(pts
				(xy -0.2794 -0.1016) (xy 0.2794 -0.1016) (xy 0.2794 0.9906) (xy -0.2794 0.9906)
			)
			(stroke
				(width 0)
				(type default)
			)
			(fill no)
			(layer "F.CrtYd")
		)
		(fp_line
			(start 0.2794 0.9906)
			(end 0.2794 -0.1016)
			(stroke
				(width 0.1)
				(type default)
			)
			(layer "F.Fab")
		)
		(fp_line
			(start 0.2794 -0.1016)
			(end -0.2794 -0.1016)
			(stroke
				(width 0.1)
				(type default)
			)
			(layer "F.Fab")
		)
		(fp_line
			(start -0.2794 0.9906)
			(end 0.2794 0.9906)
			(stroke
				(width 0.1)
				(type default)
			)
			(layer "F.Fab")
		)
		(fp_line
			(start -0.2794 -0.1016)
			(end -0.2794 0.9906)
			(stroke
				(width 0.1)
				(type default)
			)
			(layer "F.Fab")
		)
		(pad "1" smd rect
			(at 0 0 180)
			(size 0.508 0.508)
			(layers "F.Cu" "F.Mask" "F.Paste")
			(net "P3V3_STBY")
		)
		(pad "2" smd rect
			(at 0 0.889 180)
			(size 0.508 0.508)
			(layers "F.Cu" "F.Mask" "F.Paste")
			(net "IRQ_PIRQA_SPI_TPM_N")
		)
		(zone
			(layer "F.Cu")
			(hatch none 0.5)
			(connect_pads
				(clearance 0)
			)
			(min_thickness 0.25)
			(keepout
				(tracks not_allowed)
				(vias allowed)
				(pads allowed)
				(copperpour not_allowed)
				(footprints allowed)
			)
			(placement
				(enabled no)
				(sheetname "")
			)
			(fill
				(thermal_gap 0.5)
				(thermal_bridge_width 0.5)
				(island_removal_mode 0)
			)
			(polygon
				(pts
					(xy 382.524 -87.9475) (xy 382.016 -87.9475) (xy 382.016 -87.5665) (xy 382.524 -87.5665)
				)
			)
		)
		(zone
			(layer "F.Cu")
			(hatch none 0.5)
			(connect_pads
				(clearance 0)
			)
			(min_thickness 0.25)
			(keepout
				(tracks allowed)
				(vias not_allowed)
				(pads allowed)
				(copperpour not_allowed)
				(footprints allowed)
			)
			(placement
				(enabled no)
				(sheetname "")
			)
			(fill
				(thermal_gap 0.5)
				(thermal_bridge_width 0.5)
				(island_removal_mode 0)
			)
			(polygon
				(pts
					(xy 382.524 -87.5665) (xy 382.016 -87.5665) (xy 382.016 -87.9475) (xy 382.524 -87.9475)
				)
			)
		)
	)
	(footprint ""
		(layer "F.Cu")
		(at 35.7886 -61.214 -90)
		(property "Reference" "RT18"
			(at 0 0 270)
			(layer "F.SilkS")
			(hide yes)
			(effects
				(font
					(size 1.27 1.27)
				)
			)
		)
		(property "Value" "*"
			(at -0.0254 -2.6289 270)
			(unlocked yes)
			(layer "F.Fab")
			(hide yes)
			(effects
				(font
					(size 1.27 1.016)
					(thickness 0.1524)
				)
			)
		)
		(property "Device Type" "1R3F-GP_RCL_GP-1R3F-GP,64.1R00A"
			(at -0.0254 -4.1529 270)
			(unlocked yes)
			(layer "F.Fab")
			(hide yes)
			(effects
				(font
					(size 1.27 1.016)
					(thickness 0.1524)
				)
			)
		)
		(duplicate_pad_numbers_are_jumpers no)
		(fp_line
			(start -0.4826 0)
			(end -0.2032 0)
			(stroke
				(width 0.2032)
				(type default)
			)
			(layer "F.SilkS")
		)
		(fp_line
			(start 0.2032 0)
			(end 0.4826 0)
			(stroke
				(width 0.2032)
				(type default)
			)
			(layer "F.SilkS")
		)
		(fp_rect
			(start -0.5842 1.3335)
			(end 0.5842 -1.3335)
			(stroke
				(width 0)
				(type default)
			)
			(fill no)
			(layer "F.CrtYd")
		)
		(fp_rect
			(start -0.5842 1.3335)
			(end 0.5842 -1.3335)
			(stroke
				(width 0)
				(type default)
			)
			(fill no)
			(layer "F.Fab")
		)
		(pad "1" smd custom
			(at 0 -0.762 270)
			(size 0.2159 0.2159)
			(layers "F.Cu" "F.Mask" "F.Paste")
			(net "VR_PVCCIN_CPU1_PHASE2_RC")
			(options
				(clearance outline)
				(anchor circle)
			)
			(primitives
				(gr_poly
					(pts
						(arc
							(start -0.3302 -0.4318)
							(mid -0.402042 -0.402042)
							(end -0.4318 -0.3302)
						)
						(arc
							(start -0.4318 0.3302)
							(mid -0.402042 0.402042)
							(end -0.3302 0.4318)
						)
						(arc
							(start 0.3302 0.4318)
							(mid 0.402042 0.402042)
							(end 0.4318 0.3302)
						)
						(arc
							(start 0.4318 -0.3302)
							(mid 0.402042 -0.402042)
							(end 0.3302 -0.4318)
						)
					)
					(width 0)
					(fill yes)
				)
			)
		)
		(pad "2" smd custom
			(at 0 0.762 270)
			(size 0.2159 0.2159)
			(layers "F.Cu" "F.Mask" "F.Paste")
			(net "GND")
			(options
				(clearance outline)
				(anchor circle)
			)
			(primitives
				(gr_poly
					(pts
						(arc
							(start -0.3302 -0.4318)
							(mid -0.402042 -0.402042)
							(end -0.4318 -0.3302)
						)
						(arc
							(start -0.4318 0.3302)
							(mid -0.402042 0.402042)
							(end -0.3302 0.4318)
						)
						(arc
							(start 0.3302 0.4318)
							(mid 0.402042 0.402042)
							(end 0.4318 0.3302)
						)
						(arc
							(start 0.4318 -0.3302)
							(mid 0.402042 -0.402042)
							(end 0.3302 -0.4318)
						)
					)
					(width 0)
					(fill yes)
				)
			)
		)
	)
	(footprint ""
		(layer "F.Cu")
		(at 266.0142 -84.7598)
		(property "Reference" "C5D7"
			(at 0 0 0)
			(layer "F.SilkS")
			(hide yes)
			(effects
				(font
					(size 1.27 1.27)
				)
			)
		)
		(property "Value" ""
			(at 0 0 0)
			(layer "F.Fab")
			(effects
				(font
					(size 1.27 1.27)
				)
			)
		)
		(duplicate_pad_numbers_are_jumpers no)
		(fp_poly
			(pts
				(xy -0.4953 -0.2032) (xy 0.4953 -0.2032) (xy 0.4953 1.6002) (xy -0.4953 1.6002)
			)
			(stroke
				(width 0)
				(type default)
			)
			(fill no)
			(layer "F.CrtYd")
		)
		(fp_line
			(start -0.4953 -0.2032)
			(end 0.4953 -0.2032)
			(stroke
				(width 0.1)
				(type default)
			)
			(layer "F.Fab")
		)
		(fp_line
			(start -0.4953 1.6002)
			(end -0.4953 -0.2032)
			(stroke
				(width 0.1)
				(type default)
			)
			(layer "F.Fab")
		)
		(fp_line
			(start 0.4953 -0.2032)
			(end 0.4953 1.6002)
			(stroke
				(width 0.1)
				(type default)
			)
			(layer "F.Fab")
		)
		(fp_line
			(start 0.4953 1.6002)
			(end -0.4953 1.6002)
			(stroke
				(width 0.1)
				(type default)
			)
			(layer "F.Fab")
		)
		(pad "1" smd rect
			(at 0 0)
			(size 0.762 0.889)
			(layers "F.Cu" "F.Mask" "F.Paste")
			(net "PVDDQ_DEF")
		)
		(pad "2" smd rect
			(at 0 1.397)
			(size 0.762 0.889)
			(layers "F.Cu" "F.Mask" "F.Paste")
			(net "GND")
		)
		(zone
			(layer "F.Cu")
			(hatch none 0.5)
			(connect_pads
				(clearance 0)
			)
			(min_thickness 0.25)
			(keepout
				(tracks not_allowed)
				(vias allowed)
				(pads allowed)
				(copperpour not_allowed)
				(footprints allowed)
			)
			(placement
				(enabled no)
				(sheetname "")
			)
			(fill
				(thermal_gap 0.5)
				(thermal_bridge_width 0.5)
				(island_removal_mode 0)
			)
			(polygon
				(pts
					(xy 265.6332 -84.3153) (xy 266.3952 -84.3153) (xy 266.3952 -83.8073) (xy 265.6332 -83.8073)
				)
			)
		)
	)
	(footprint ""
		(layer "F.Cu")
		(at 343.9668 -32.8803 90)
		(property "Reference" "R7F7"
			(at 0 0 90)
			(layer "F.SilkS")
			(hide yes)
			(effects
				(font
					(size 1.27 1.27)
				)
			)
		)
		(property "Value" ""
			(at 0 0 90)
			(layer "F.Fab")
			(effects
				(font
					(size 1.27 1.27)
				)
			)
		)
		(duplicate_pad_numbers_are_jumpers no)
		(fp_rect
			(start -0.2794 -0.1016)
			(end 0.2794 0.9906)
			(stroke
				(width 0)
				(type default)
			)
			(fill no)
			(layer "F.CrtYd")
		)
		(fp_line
			(start 0.2794 -0.1016)
			(end -0.2794 -0.1016)
			(stroke
				(width 0.1)
				(type default)
			)
			(layer "F.Fab")
		)
		(fp_line
			(start -0.2794 -0.1016)
			(end -0.2794 0.9906)
			(stroke
				(width 0.1)
				(type default)
			)
			(layer "F.Fab")
		)
		(fp_line
			(start 0.2794 0.9906)
			(end 0.2794 -0.1016)
			(stroke
				(width 0.1)
				(type default)
			)
			(layer "F.Fab")
		)
		(fp_line
			(start -0.2794 0.9906)
			(end 0.2794 0.9906)
			(stroke
				(width 0.1)
				(type default)
			)
			(layer "F.Fab")
		)
		(pad "1" smd rect
			(at 0 0 90)
			(size 0.508 0.508)
			(layers "F.Cu" "F.Mask" "F.Paste")
			(net "VR_PVPP_ABC_SNUB")
		)
		(pad "2" smd rect
			(at 0 0.889 90)
			(size 0.508 0.508)
			(layers "F.Cu" "F.Mask" "F.Paste")
			(net "GND")
		)
		(zone
			(layer "F.Cu")
			(hatch none 0.5)
			(connect_pads
				(clearance 0)
			)
			(min_thickness 0.25)
			(keepout
				(tracks not_allowed)
				(vias allowed)
				(pads allowed)
				(copperpour not_allowed)
				(footprints allowed)
			)
			(placement
				(enabled no)
				(sheetname "")
			)
			(fill
				(thermal_gap 0.5)
				(thermal_bridge_width 0.5)
				(island_removal_mode 0)
			)
			(polygon
				(pts
					(xy 344.2208 -32.6263) (xy 344.6018 -32.6263) (xy 344.6018 -33.1343) (xy 344.2208 -33.1343)
				)
			)
		)
		(zone
			(layer "F.Cu")
			(hatch none 0.5)
			(connect_pads
				(clearance 0)
			)
			(min_thickness 0.25)
			(keepout
				(tracks allowed)
				(vias not_allowed)
				(pads allowed)
				(copperpour not_allowed)
				(footprints allowed)
			)
			(placement
				(enabled no)
				(sheetname "")
			)
			(fill
				(thermal_gap 0.5)
				(thermal_bridge_width 0.5)
				(island_removal_mode 0)
			)
			(polygon
				(pts
					(xy 344.2208 -32.6263) (xy 344.6018 -32.6263) (xy 344.6018 -33.1343) (xy 344.2208 -33.1343)
				)
			)
		)
	)
	(footprint ""
		(layer "F.Cu")
		(at 409.448 -126.238)
		(property "Reference" "C8B10"
			(at 0 0 0)
			(layer "F.SilkS")
			(hide yes)
			(effects
				(font
					(size 1.27 1.27)
				)
			)
		)
		(property "Value" ""
			(at 0 0 0)
			(layer "F.Fab")
			(effects
				(font
					(size 1.27 1.27)
				)
			)
		)
		(duplicate_pad_numbers_are_jumpers no)
		(fp_poly
			(pts
				(xy -0.4953 -0.2032) (xy 0.4953 -0.2032) (xy 0.4953 1.6002) (xy -0.4953 1.6002)
			)
			(stroke
				(width 0)
				(type default)
			)
			(fill no)
			(layer "F.CrtYd")
		)
		(fp_line
			(start -0.4953 -0.2032)
			(end 0.4953 -0.2032)
			(stroke
				(width 0.1)
				(type default)
			)
			(layer "F.Fab")
		)
		(fp_line
			(start -0.4953 1.6002)
			(end -0.4953 -0.2032)
			(stroke
				(width 0.1)
				(type default)
			)
			(layer "F.Fab")
		)
		(fp_line
			(start 0.4953 -0.2032)
			(end 0.4953 1.6002)
			(stroke
				(width 0.1)
				(type default)
			)
			(layer "F.Fab")
		)
		(fp_line
			(start 0.4953 1.6002)
			(end -0.4953 1.6002)
			(stroke
				(width 0.1)
				(type default)
			)
			(layer "F.Fab")
		)
		(pad "1" smd rect
			(at 0 0)
			(size 0.762 0.889)
			(layers "F.Cu" "F.Mask" "F.Paste")
			(net "P1V05_PCH_STBY")
		)
		(pad "2" smd rect
			(at 0 1.397)
			(size 0.762 0.889)
			(layers "F.Cu" "F.Mask" "F.Paste")
			(net "GND")
		)
		(zone
			(layer "F.Cu")
			(hatch none 0.5)
			(connect_pads
				(clearance 0)
			)
			(min_thickness 0.25)
			(keepout
				(tracks not_allowed)
				(vias allowed)
				(pads allowed)
				(copperpour not_allowed)
				(footprints allowed)
			)
			(placement
				(enabled no)
				(sheetname "")
			)
			(fill
				(thermal_gap 0.5)
				(thermal_bridge_width 0.5)
				(island_removal_mode 0)
			)
			(polygon
				(pts
					(xy 409.067 -125.7935) (xy 409.829 -125.7935) (xy 409.829 -125.2855) (xy 409.067 -125.2855)
				)
			)
		)
	)
	(footprint ""
		(layer "F.Cu")
		(at 337.0326 -128.2065 180)
		(property "Reference" "R7B15"
			(at 0 0 180)
			(layer "F.SilkS")
			(hide yes)
			(effects
				(font
					(size 1.27 1.27)
				)
			)
		)
		(property "Value" ""
			(at 0 0 180)
			(layer "F.Fab")
			(effects
				(font
					(size 1.27 1.27)
				)
			)
		)
		(duplicate_pad_numbers_are_jumpers no)
		(fp_poly
			(pts
				(xy -0.2794 -0.1016) (xy 0.2794 -0.1016) (xy 0.2794 0.9906) (xy -0.2794 0.9906)
			)
			(stroke
				(width 0)
				(type default)
			)
			(fill no)
			(layer "F.CrtYd")
		)
		(fp_line
			(start 0.2794 0.9906)
			(end 0.2794 -0.1016)
			(stroke
				(width 0.1)
				(type default)
			)
			(layer "F.Fab")
		)
		(fp_line
			(start 0.2794 -0.1016)
			(end -0.2794 -0.1016)
			(stroke
				(width 0.1)
				(type default)
			)
			(layer "F.Fab")
		)
		(fp_line
			(start -0.2794 0.9906)
			(end 0.2794 0.9906)
			(stroke
				(width 0.1)
				(type default)
			)
			(layer "F.Fab")
		)
		(fp_line
			(start -0.2794 -0.1016)
			(end -0.2794 0.9906)
			(stroke
				(width 0.1)
				(type default)
			)
			(layer "F.Fab")
		)
		(pad "1" smd rect
			(at 0 0 180)
			(size 0.508 0.508)
			(layers "F.Cu" "F.Mask" "F.Paste")
			(net "VSENSE_PVPP_DEF")
		)
		(pad "2" smd rect
			(at 0 0.889 180)
			(size 0.508 0.508)
			(layers "F.Cu" "F.Mask" "F.Paste")
			(net "VR_FB_PVPP_DEF")
		)
		(zone
			(layer "F.Cu")
			(hatch none 0.5)
			(connect_pads
				(clearance 0)
			)
			(min_thickness 0.25)
			(keepout
				(tracks not_allowed)
				(vias allowed)
				(pads allowed)
				(copperpour not_allowed)
				(footprints allowed)
			)
			(placement
				(enabled no)
				(sheetname "")
			)
			(fill
				(thermal_gap 0.5)
				(thermal_bridge_width 0.5)
				(island_removal_mode 0)
			)
			(polygon
				(pts
					(xy 337.2866 -128.8415) (xy 336.7786 -128.8415) (xy 336.7786 -128.4605) (xy 337.2866 -128.4605)
				)
			)
		)
		(zone
			(layer "F.Cu")
			(hatch none 0.5)
			(connect_pads
				(clearance 0)
			)
			(min_thickness 0.25)
			(keepout
				(tracks allowed)
				(vias not_allowed)
				(pads allowed)
				(copperpour not_allowed)
				(footprints allowed)
			)
			(placement
				(enabled no)
				(sheetname "")
			)
			(fill
				(thermal_gap 0.5)
				(thermal_bridge_width 0.5)
				(island_removal_mode 0)
			)
			(polygon
				(pts
					(xy 337.2866 -128.4605) (xy 336.7786 -128.4605) (xy 336.7786 -128.8415) (xy 337.2866 -128.8415)
				)
			)
		)
	)
	(footprint ""
		(layer "F.Cu")
		(at 171.577 -131.0005 180)
		(property "Reference" "C4B7"
			(at 0 0 180)
			(layer "F.SilkS")
			(hide yes)
			(effects
				(font
					(size 1.27 1.27)
				)
			)
		)
		(property "Value" ""
			(at 0 0 180)
			(layer "F.Fab")
			(effects
				(font
					(size 1.27 1.27)
				)
			)
		)
		(duplicate_pad_numbers_are_jumpers no)
		(fp_poly
			(pts
				(xy 0.3048 -0.1016) (xy 0.3048 0.9906) (xy -0.3048 0.9906) (xy -0.3048 -0.1016)
			)
			(stroke
				(width 0)
				(type default)
			)
			(fill no)
			(layer "F.CrtYd")
		)
		(fp_line
			(start 0.3048 0.9906)
			(end 0.3048 -0.1016)
			(stroke
				(width 0.1)
				(type default)
			)
			(layer "F.Fab")
		)
		(fp_line
			(start 0.3048 -0.1016)
			(end -0.3048 -0.1016)
			(stroke
				(width 0.1)
				(type default)
			)
			(layer "F.Fab")
		)
		(fp_line
			(start -0.3048 0.9906)
			(end 0.3048 0.9906)
			(stroke
				(width 0.1)
				(type default)
			)
			(layer "F.Fab")
		)
		(fp_line
			(start -0.3048 -0.1016)
			(end -0.3048 0.9906)
			(stroke
				(width 0.1)
				(type default)
			)
			(layer "F.Fab")
		)
		(pad "1" smd rect
			(at 0 0 180)
			(size 0.508 0.508)
			(layers "F.Cu" "F.Mask" "F.Paste")
			(net "VR_COMP_PVPP_KLM")
		)
		(pad "2" smd rect
			(at 0 0.889 180)
			(size 0.508 0.508)
			(layers "F.Cu" "F.Mask" "F.Paste")
			(net "VR_FB_PVPP_KLM")
		)
		(zone
			(layer "F.Cu")
			(hatch none 0.5)
			(connect_pads
				(clearance 0)
			)
			(min_thickness 0.25)
			(keepout
				(tracks not_allowed)
				(vias allowed)
				(pads allowed)
				(copperpour not_allowed)
				(footprints allowed)
			)
			(placement
				(enabled no)
				(sheetname "")
			)
			(fill
				(thermal_gap 0.5)
				(thermal_bridge_width 0.5)
				(island_removal_mode 0)
			)
			(polygon
				(pts
					(xy 171.831 -131.6355) (xy 171.323 -131.6355) (xy 171.323 -131.2545) (xy 171.831 -131.2545)
				)
			)
		)
		(zone
			(layer "F.Cu")
			(hatch none 0.5)
			(connect_pads
				(clearance 0)
			)
			(min_thickness 0.25)
			(keepout
				(tracks allowed)
				(vias not_allowed)
				(pads allowed)
				(copperpour not_allowed)
				(footprints allowed)
			)
			(placement
				(enabled no)
				(sheetname "")
			)
			(fill
				(thermal_gap 0.5)
				(thermal_bridge_width 0.5)
				(island_removal_mode 0)
			)
			(polygon
				(pts
					(xy 171.831 -131.2545) (xy 171.323 -131.2545) (xy 171.323 -131.6355) (xy 171.831 -131.6355)
				)
			)
		)
	)
	(footprint ""
		(layer "F.Cu")
		(at 323.6087 -32.42818 -90)
		(property "Reference" "U6F1"
			(at 1.94818 3.61823 90)
			(unlocked yes)
			(layer "F.SilkS")
			(effects
				(font
					(size 0.7874 0.5842)
					(thickness 0.1524)
				)
			)
		)
		(property "Value" ""
			(at 0 0 270)
			(layer "F.Fab")
			(effects
				(font
					(size 1.27 1.27)
				)
			)
		)
		(duplicate_pad_numbers_are_jumpers no)
		(fp_line
			(start 3.225038 2.52476)
			(end 1.348486 2.52476)
			(stroke
				(width 0.1524)
				(type default)
			)
			(layer "F.SilkS")
		)
		(fp_line
			(start 3.225292 -0.57404)
			(end 1.352804 -0.57404)
			(stroke
				(width 0.1524)
				(type default)
			)
			(layer "F.SilkS")
		)
		(fp_circle
			(center -0.946404 -0.683514)
			(end -0.946404 -0.810514)
			(stroke
				(width 0.254)
				(type default)
			)
			(fill no)
			(layer "F.SilkS")
		)
		(fp_poly
			(pts
				(xy 0.7366 -0.57404) (xy 3.8354 -0.57404) (xy 3.8354 2.52476) (xy 0.7366 2.52476)
			)
			(stroke
				(width 0)
				(type default)
			)
			(fill no)
			(layer "F.CrtYd")
		)
		(fp_line
			(start 0.7366 2.52476)
			(end 0.7366 -0.57404)
			(stroke
				(width 0.1)
				(type default)
			)
			(layer "F.Fab")
		)
		(fp_line
			(start 3.8354 2.52476)
			(end 0.7366 2.52476)
			(stroke
				(width 0.1)
				(type default)
			)
			(layer "F.Fab")
		)
		(fp_line
			(start 0.7366 -0.57404)
			(end 3.8354 -0.57404)
			(stroke
				(width 0.1)
				(type default)
			)
			(layer "F.Fab")
		)
		(fp_line
			(start 3.8354 -0.57404)
			(end 3.8354 2.52476)
			(stroke
				(width 0.1)
				(type default)
			)
			(layer "F.Fab")
		)
		(fp_circle
			(center -1.454404 -0.556514)
			(end -1.454404 -0.683514)
			(stroke
				(width 0.254)
				(type default)
			)
			(fill no)
			(layer "F.Fab")
		)
		(pad "1" smd rect
			(at 0 0 270)
			(size 1.778 0.4572)
			(layers "F.Cu" "F.Mask" "F.Paste")
			(net "PVCCIO_CPU0")
		)
		(pad "2" smd rect
			(at 0 0.65024 270)
			(size 1.778 0.4572)
			(layers "F.Cu" "F.Mask" "F.Paste")
			(net "SMB_DDR_ABC_SCL_G")
		)
		(pad "3" smd rect
			(at 0 1.30048 270)
			(size 1.778 0.4572)
			(layers "F.Cu" "F.Mask" "F.Paste")
			(net "SMB_DDR_ABC_SDA_G")
		)
		(pad "4" smd rect
			(at 0 1.95072 270)
			(size 1.778 0.4572)
			(layers "F.Cu" "F.Mask" "F.Paste")
			(net "GND")
		)
		(pad "5" smd rect
			(at 4.572 1.95072 270)
			(size 1.778 0.4572)
			(layers "F.Cu" "F.Mask" "F.Paste")
			(net "TP_SMB_DDR_ABC_EN")
		)
		(pad "6" smd rect
			(at 4.572 1.30048 270)
			(size 1.778 0.4572)
			(layers "F.Cu" "F.Mask" "F.Paste")
			(net "SMB_DDR_ABC_VPP_SDA_R")
		)
		(pad "7" smd rect
			(at 4.572 0.65024 270)
			(size 1.778 0.4572)
			(layers "F.Cu" "F.Mask" "F.Paste")
			(net "SMB_DDR_ABC_VPP_SCL_R")
		)
		(pad "8" smd rect
			(at 4.572 0 270)
			(size 1.778 0.4572)
			(layers "F.Cu" "F.Mask" "F.Paste")
			(net "PVPP_ABC")
		)
	)
	(footprint ""
		(layer "F.Cu")
		(at 195.58 -12.923012 90)
		(property "Reference" "C4G3"
			(at 0 0 90)
			(layer "F.SilkS")
			(hide yes)
			(effects
				(font
					(size 1.27 1.27)
				)
			)
		)
		(property "Value" ""
			(at 0 0 90)
			(layer "F.Fab")
			(effects
				(font
					(size 1.27 1.27)
				)
			)
		)
		(duplicate_pad_numbers_are_jumpers no)
		(fp_poly
			(pts
				(xy 0.3048 -0.1016) (xy 0.3048 0.9906) (xy -0.3048 0.9906) (xy -0.3048 -0.1016)
			)
			(stroke
				(width 0)
				(type default)
			)
			(fill no)
			(layer "F.CrtYd")
		)
		(fp_line
			(start 0.3048 -0.1016)
			(end -0.3048 -0.1016)
			(stroke
				(width 0.1)
				(type default)
			)
			(layer "F.Fab")
		)
		(fp_line
			(start -0.3048 -0.1016)
			(end -0.3048 0.9906)
			(stroke
				(width 0.1)
				(type default)
			)
			(layer "F.Fab")
		)
		(fp_line
			(start 0.3048 0.9906)
			(end 0.3048 -0.1016)
			(stroke
				(width 0.1)
				(type default)
			)
			(layer "F.Fab")
		)
		(fp_line
			(start -0.3048 0.9906)
			(end 0.3048 0.9906)
			(stroke
				(width 0.1)
				(type default)
			)
			(layer "F.Fab")
		)
		(pad "1" smd rect
			(at 0 0 90)
			(size 0.508 0.508)
			(layers "F.Cu" "F.Mask" "F.Paste")
			(net "M_B_VREF")
		)
		(pad "2" smd rect
			(at 0 0.889 90)
			(size 0.508 0.508)
			(layers "F.Cu" "F.Mask" "F.Paste")
			(net "GND")
		)
		(zone
			(layer "F.Cu")
			(hatch none 0.5)
			(connect_pads
				(clearance 0)
			)
			(min_thickness 0.25)
			(keepout
				(tracks allowed)
				(vias not_allowed)
				(pads allowed)
				(copperpour not_allowed)
				(footprints allowed)
			)
			(placement
				(enabled no)
				(sheetname "")
			)
			(fill
				(thermal_gap 0.5)
				(thermal_bridge_width 0.5)
				(island_removal_mode 0)
			)
			(polygon
				(pts
					(xy 195.834 -12.669012) (xy 195.834 -13.177012) (xy 196.215 -13.177012) (xy 196.215 -12.669012)
				)
			)
		)
		(zone
			(layer "F.Cu")
			(hatch none 0.5)
			(connect_pads
				(clearance 0)
			)
			(min_thickness 0.25)
			(keepout
				(tracks not_allowed)
				(vias allowed)
				(pads allowed)
				(copperpour not_allowed)
				(footprints allowed)
			)
			(placement
				(enabled no)
				(sheetname "")
			)
			(fill
				(thermal_gap 0.5)
				(thermal_bridge_width 0.5)
				(island_removal_mode 0)
			)
			(polygon
				(pts
					(xy 196.215 -12.669012) (xy 196.215 -13.177012) (xy 195.834 -13.177012) (xy 195.834 -12.669012)
				)
			)
		)
	)
	(footprint ""
		(layer "F.Cu")
		(at 485.875076 -28.104084)
		(property "Reference" "R9F67"
			(at 0 0 0)
			(layer "F.SilkS")
			(hide yes)
			(effects
				(font
					(size 1.27 1.27)
				)
			)
		)
		(property "Value" ""
			(at 0 0 0)
			(layer "F.Fab")
			(effects
				(font
					(size 1.27 1.27)
				)
			)
		)
		(duplicate_pad_numbers_are_jumpers no)
		(fp_poly
			(pts
				(xy -0.2794 -0.1016) (xy 0.2794 -0.1016) (xy 0.2794 0.9906) (xy -0.2794 0.9906)
			)
			(stroke
				(width 0)
				(type default)
			)
			(fill no)
			(layer "F.CrtYd")
		)
		(fp_line
			(start -0.2794 -0.1016)
			(end -0.2794 0.9906)
			(stroke
				(width 0.1)
				(type default)
			)
			(layer "F.Fab")
		)
		(fp_line
			(start -0.2794 0.9906)
			(end 0.2794 0.9906)
			(stroke
				(width 0.1)
				(type default)
			)
			(layer "F.Fab")
		)
		(fp_line
			(start 0.2794 -0.1016)
			(end -0.2794 -0.1016)
			(stroke
				(width 0.1)
				(type default)
			)
			(layer "F.Fab")
		)
		(fp_line
			(start 0.2794 0.9906)
			(end 0.2794 -0.1016)
			(stroke
				(width 0.1)
				(type default)
			)
			(layer "F.Fab")
		)
		(pad "1" smd rect
			(at 0 0)
			(size 0.508 0.508)
			(layers "F.Cu" "F.Mask" "F.Paste")
			(net "SP2_BMC_CM_UART_RX_R1")
		)
		(pad "2" smd rect
			(at 0 0.889)
			(size 0.508 0.508)
			(layers "F.Cu" "F.Mask" "F.Paste")
			(net "SPA_MID_DBG_TX_R")
		)
		(zone
			(layer "F.Cu")
			(hatch none 0.5)
			(connect_pads
				(clearance 0)
			)
			(min_thickness 0.25)
			(keepout
				(tracks allowed)
				(vias not_allowed)
				(pads allowed)
				(copperpour not_allowed)
				(footprints allowed)
			)
			(placement
				(enabled no)
				(sheetname "")
			)
			(fill
				(thermal_gap 0.5)
				(thermal_bridge_width 0.5)
				(island_removal_mode 0)
			)
			(polygon
				(pts
					(xy 485.621076 -27.850084) (xy 486.129076 -27.850084) (xy 486.129076 -27.469084) (xy 485.621076 -27.469084)
				)
			)
		)
		(zone
			(layer "F.Cu")
			(hatch none 0.5)
			(connect_pads
				(clearance 0)
			)
			(min_thickness 0.25)
			(keepout
				(tracks not_allowed)
				(vias allowed)
				(pads allowed)
				(copperpour not_allowed)
				(footprints allowed)
			)
			(placement
				(enabled no)
				(sheetname "")
			)
			(fill
				(thermal_gap 0.5)
				(thermal_bridge_width 0.5)
				(island_removal_mode 0)
			)
			(polygon
				(pts
					(xy 485.621076 -27.469084) (xy 486.129076 -27.469084) (xy 486.129076 -27.850084) (xy 485.621076 -27.850084)
				)
			)
		)
	)
	(footprint ""
		(layer "F.Cu")
		(at 428.63008 -36.07435 -90)
		(property "Reference" "R1T27"
			(at 0 0 270)
			(layer "F.SilkS")
			(hide yes)
			(effects
				(font
					(size 1.27 1.27)
				)
			)
		)
		(property "Value" ""
			(at 0 0 270)
			(layer "F.Fab")
			(effects
				(font
					(size 1.27 1.27)
				)
			)
		)
		(duplicate_pad_numbers_are_jumpers no)
		(fp_poly
			(pts
				(xy -0.2794 -0.1016) (xy 0.2794 -0.1016) (xy 0.2794 0.9906) (xy -0.2794 0.9906)
			)
			(stroke
				(width 0)
				(type default)
			)
			(fill no)
			(layer "F.CrtYd")
		)
		(fp_line
			(start -0.2794 0.9906)
			(end 0.2794 0.9906)
			(stroke
				(width 0.1)
				(type default)
			)
			(layer "F.Fab")
		)
		(fp_line
			(start 0.2794 0.9906)
			(end 0.2794 -0.1016)
			(stroke
				(width 0.1)
				(type default)
			)
			(layer "F.Fab")
		)
		(fp_line
			(start -0.2794 -0.1016)
			(end -0.2794 0.9906)
			(stroke
				(width 0.1)
				(type default)
			)
			(layer "F.Fab")
		)
		(fp_line
			(start 0.2794 -0.1016)
			(end -0.2794 -0.1016)
			(stroke
				(width 0.1)
				(type default)
			)
			(layer "F.Fab")
		)
		(pad "1" smd rect
			(at 0 0 270)
			(size 0.508 0.508)
			(layers "F.Cu" "F.Mask" "F.Paste")
			(net "GND")
		)
		(pad "2" smd rect
			(at 0 0.889 270)
			(size 0.508 0.508)
			(layers "F.Cu" "F.Mask" "F.Paste")
			(net "BMC_MIOZ")
		)
		(zone
			(layer "F.Cu")
			(hatch none 0.5)
			(connect_pads
				(clearance 0)
			)
			(min_thickness 0.25)
			(keepout
				(tracks not_allowed)
				(vias allowed)
				(pads allowed)
				(copperpour not_allowed)
				(footprints allowed)
			)
			(placement
				(enabled no)
				(sheetname "")
			)
			(fill
				(thermal_gap 0.5)
				(thermal_bridge_width 0.5)
				(island_removal_mode 0)
			)
			(polygon
				(pts
					(xy 427.99508 -36.32835) (xy 427.99508 -35.82035) (xy 428.37608 -35.82035) (xy 428.37608 -36.32835)
				)
			)
		)
		(zone
			(layer "F.Cu")
			(hatch none 0.5)
			(connect_pads
				(clearance 0)
			)
			(min_thickness 0.25)
			(keepout
				(tracks allowed)
				(vias not_allowed)
				(pads allowed)
				(copperpour not_allowed)
				(footprints allowed)
			)
			(placement
				(enabled no)
				(sheetname "")
			)
			(fill
				(thermal_gap 0.5)
				(thermal_bridge_width 0.5)
				(island_removal_mode 0)
			)
			(polygon
				(pts
					(xy 428.37608 -36.32835) (xy 428.37608 -35.82035) (xy 427.99508 -35.82035) (xy 427.99508 -36.32835)
				)
			)
		)
	)
	(footprint ""
		(layer "F.Cu")
		(at 9.585706 -3.355848 180)
		(property "Reference" "R1G9"
			(at 0 0 180)
			(layer "F.SilkS")
			(hide yes)
			(effects
				(font
					(size 1.27 1.27)
				)
			)
		)
		(property "Value" ""
			(at 0 0 180)
			(layer "F.Fab")
			(effects
				(font
					(size 1.27 1.27)
				)
			)
		)
		(duplicate_pad_numbers_are_jumpers no)
		(fp_rect
			(start 0.2794 0.9906)
			(end -0.2794 -0.1016)
			(stroke
				(width 0)
				(type default)
			)
			(fill no)
			(layer "F.CrtYd")
		)
		(fp_line
			(start 0.2794 0.9906)
			(end 0.2794 -0.1016)
			(stroke
				(width 0.1)
				(type default)
			)
			(layer "F.Fab")
		)
		(fp_line
			(start 0.2794 -0.1016)
			(end -0.2794 -0.1016)
			(stroke
				(width 0.1)
				(type default)
			)
			(layer "F.Fab")
		)
		(fp_line
			(start -0.2794 0.9906)
			(end 0.2794 0.9906)
			(stroke
				(width 0.1)
				(type default)
			)
			(layer "F.Fab")
		)
		(fp_line
			(start -0.2794 -0.1016)
			(end -0.2794 0.9906)
			(stroke
				(width 0.1)
				(type default)
			)
			(layer "F.Fab")
		)
		(pad "1" smd rect
			(at 0 0 180)
			(size 0.508 0.508)
			(layers "F.Cu" "F.Mask" "F.Paste")
			(net "SVID_ALERT_PVDDQ_GHJ")
		)
		(pad "2" smd rect
			(at 0 0.889 180)
			(size 0.508 0.508)
			(layers "F.Cu" "F.Mask" "F.Paste")
			(net "SVID_ALERT1_CPU1_R_N")
		)
		(zone
			(layer "F.Cu")
			(hatch none 0.5)
			(connect_pads
				(clearance 0)
			)
			(min_thickness 0.25)
			(keepout
				(tracks allowed)
				(vias not_allowed)
				(pads allowed)
				(copperpour not_allowed)
				(footprints allowed)
			)
			(placement
				(enabled no)
				(sheetname "")
			)
			(fill
				(thermal_gap 0.5)
				(thermal_bridge_width 0.5)
				(island_removal_mode 0)
			)
			(polygon
				(pts
					(xy 9.331706 -3.990848) (xy 9.331706 -3.609848) (xy 9.839706 -3.609848) (xy 9.839706 -3.990848)
				)
			)
		)
		(zone
			(layer "F.Cu")
			(hatch none 0.5)
			(connect_pads
				(clearance 0)
			)
			(min_thickness 0.25)
			(keepout
				(tracks not_allowed)
				(vias allowed)
				(pads allowed)
				(copperpour not_allowed)
				(footprints allowed)
			)
			(placement
				(enabled no)
				(sheetname "")
			)
			(fill
				(thermal_gap 0.5)
				(thermal_bridge_width 0.5)
				(island_removal_mode 0)
			)
			(polygon
				(pts
					(xy 9.331706 -3.990848) (xy 9.331706 -3.609848) (xy 9.839706 -3.609848) (xy 9.839706 -3.990848)
				)
			)
		)
	)
	(footprint ""
		(layer "F.Cu")
		(at 96.746568 -129.859024)
		(property "Reference" "C2B1"
			(at 0 0 0)
			(layer "F.SilkS")
			(hide yes)
			(effects
				(font
					(size 1.27 1.27)
				)
			)
		)
		(property "Value" ""
			(at 0 0 0)
			(layer "F.Fab")
			(effects
				(font
					(size 1.27 1.27)
				)
			)
		)
		(duplicate_pad_numbers_are_jumpers no)
		(fp_rect
			(start -0.500126 1.598422)
			(end 0.500126 -0.201422)
			(stroke
				(width 0)
				(type default)
			)
			(fill no)
			(layer "F.CrtYd")
		)
		(fp_line
			(start -0.500126 -0.201422)
			(end 0.500126 -0.201422)
			(stroke
				(width 0.1)
				(type default)
			)
			(layer "F.Fab")
		)
		(fp_line
			(start -0.500126 1.598422)
			(end -0.500126 -0.201422)
			(stroke
				(width 0.1)
				(type default)
			)
			(layer "F.Fab")
		)
		(fp_line
			(start 0.500126 -0.201422)
			(end 0.500126 1.598422)
			(stroke
				(width 0.1)
				(type default)
			)
			(layer "F.Fab")
		)
		(fp_line
			(start 0.500126 1.598422)
			(end -0.500126 1.598422)
			(stroke
				(width 0.1)
				(type default)
			)
			(layer "F.Fab")
		)
		(pad "1" smd rect
			(at 0 0 270)
			(size 0.889 0.9906)
			(layers "F.Cu" "F.Mask" "F.Paste")
			(net "PVDDQ_KLM")
		)
		(pad "2" smd rect
			(at 0 1.397 270)
			(size 0.889 0.9906)
			(layers "F.Cu" "F.Mask" "F.Paste")
			(net "GND")
		)
		(zone
			(layer "F.Cu")
			(hatch none 0.5)
			(connect_pads
				(clearance 0)
			)
			(min_thickness 0.25)
			(keepout
				(tracks allowed)
				(vias not_allowed)
				(pads allowed)
				(copperpour not_allowed)
				(footprints allowed)
			)
			(placement
				(enabled no)
				(sheetname "")
			)
			(fill
				(thermal_gap 0.5)
				(thermal_bridge_width 0.5)
				(island_removal_mode 0)
			)
			(polygon
				(pts
					(xy 96.251268 -128.906524) (xy 97.241868 -128.906524) (xy 97.241868 -129.414524) (xy 96.251268 -129.414524)
				)
			)
		)
		(zone
			(layer "F.Cu")
			(hatch none 0.5)
			(connect_pads
				(clearance 0)
			)
			(min_thickness 0.25)
			(keepout
				(tracks not_allowed)
				(vias allowed)
				(pads allowed)
				(copperpour not_allowed)
				(footprints allowed)
			)
			(placement
				(enabled no)
				(sheetname "")
			)
			(fill
				(thermal_gap 0.5)
				(thermal_bridge_width 0.5)
				(island_removal_mode 0)
			)
			(polygon
				(pts
					(xy 96.251268 -128.906524) (xy 97.241868 -128.906524) (xy 97.241868 -129.414524) (xy 96.251268 -129.414524)
				)
			)
		)
	)
	(footprint ""
		(layer "F.Cu")
		(at 198.912734 -97.679764 90)
		(property "Reference" "EU4C1"
			(at 3.893566 -0.538734 0)
			(unlocked yes)
			(layer "F.SilkS")
			(effects
				(font
					(size 0.7874 0.5842)
					(thickness 0.1524)
				)
			)
		)
		(property "Value" ""
			(at 0 0 90)
			(layer "F.Fab")
			(effects
				(font
					(size 1.27 1.27)
				)
			)
		)
		(duplicate_pad_numbers_are_jumpers no)
		(fp_line
			(start 2.9718 -3.5052)
			(end 2.9718 3.429)
			(stroke
				(width 0.1524)
				(type default)
			)
			(layer "F.SilkS")
		)
		(fp_line
			(start -3.0099 -3.5052)
			(end 2.9718 -3.5052)
			(stroke
				(width 0.1524)
				(type default)
			)
			(layer "F.SilkS")
		)
		(fp_line
			(start 2.9718 3.429)
			(end -3.0099 3.429)
			(stroke
				(width 0.1524)
				(type default)
			)
			(layer "F.SilkS")
		)
		(fp_line
			(start -3.0099 3.429)
			(end -3.0099 -3.5052)
			(stroke
				(width 0.1524)
				(type default)
			)
			(layer "F.SilkS")
		)
		(fp_circle
			(center -3.057398 -2.678684)
			(end -3.057398 -2.551684)
			(stroke
				(width 0.254)
				(type default)
			)
			(fill no)
			(layer "F.SilkS")
		)
		(fp_poly
			(pts
				(xy -2.9972 -3.4925) (xy -2.9972 -2.6924) (xy -2.1971 -3.4925)
			)
			(stroke
				(width 0)
				(type default)
			)
			(fill yes)
			(layer "F.SilkS")
		)
		(fp_poly
			(pts
				(xy -2.549906 -3.050032) (xy -2.549906 3.050032) (xy 2.549906 3.050032) (xy 2.549906 -3.050032)
			)
			(stroke
				(width 0)
				(type default)
			)
			(fill no)
			(layer "F.CrtYd")
		)
		(fp_line
			(start 2.549906 -3.050032)
			(end 2.549906 3.050032)
			(stroke
				(width 0.1)
				(type default)
			)
			(layer "F.Fab")
		)
		(fp_line
			(start -2.549906 -3.050032)
			(end 2.549906 -3.050032)
			(stroke
				(width 0.1)
				(type default)
			)
			(layer "F.Fab")
		)
		(fp_line
			(start 2.549906 3.050032)
			(end -2.549906 3.050032)
			(stroke
				(width 0.1)
				(type default)
			)
			(layer "F.Fab")
		)
		(fp_line
			(start -2.549906 3.050032)
			(end -2.549906 -3.050032)
			(stroke
				(width 0.1)
				(type default)
			)
			(layer "F.Fab")
		)
		(fp_circle
			(center -3.057398 -2.678684)
			(end -3.057398 -2.551684)
			(stroke
				(width 0.254)
				(type default)
			)
			(fill no)
			(layer "F.Fab")
		)
		(pad "1" smd rect
			(at -2.39522 -2.279904 90)
			(size 0.7112 0.254)
			(layers "F.Cu" "F.Mask" "F.Paste")
			(net "PVSA_CPU0")
		)
		(pad "2" smd rect
			(at -2.39522 -1.83007 90)
			(size 0.7112 0.254)
			(layers "F.Cu" "F.Mask" "F.Paste")
			(net "GND")
		)
		(pad "3" smd rect
			(at -2.39522 -1.379982 90)
			(size 0.7112 0.254)
			(layers "F.Cu" "F.Mask" "F.Paste")
			(net "VR_PVSA_CPU0_VCIN")
		)
		(pad "4" smd rect
			(at -2.39522 -0.929894 90)
			(size 0.7112 0.254)
			(layers "F.Cu" "F.Mask" "F.Paste")
			(net "P5V_STBY")
		)
		(pad "5" smd rect
			(at -2.39522 -0.48006 90)
			(size 0.7112 0.254)
			(layers "F.Cu" "F.Mask" "F.Paste")
			(net "GND")
		)
		(pad "6" smd rect
			(at -2.39522 -0.029972 90)
			(size 0.7112 0.254)
			(layers "F.Cu" "F.Mask" "F.Paste")
			(net "TP_PVSA_CPU0_GL_0")
		)
		(pad "7" smd custom
			(at 0.016764 1.145032 90)
			(size 0.53975 0.53975)
			(layers "F.Cu" "F.Mask" "F.Paste")
			(net "GND")
			(options
				(clearance outline)
				(anchor circle)
			)
			(primitives
				(gr_poly
					(pts
						(xy -2.7051 1.0795) (xy -2.7051 -0.3683) (xy -0.9271 -0.3683) (xy -0.9271 -1.0795) (xy 2.7051 -1.0795)
						(xy 2.7051 1.0795)
					)
					(width 0)
					(fill yes)
				)
			)
		)
		(pad "10" smd rect
			(at -0.008382 2.874772 90)
			(size 4.3434 0.6096)
			(layers "F.Cu" "F.Mask" "F.Paste")
			(net "VR_PVSA_CPU0_PHASE_SW")
		)
		(pad "25" smd rect
			(at 1.548384 -1.283208 90)
			(size 2.3368 2.0066)
			(layers "F.Cu" "F.Mask" "F.Paste")
			(net "VR_FET_SW_P12V_STBY_PVCCIN_CPU0")
		)
		(pad "30" smd rect
			(at 2.050034 -2.895092 90)
			(size 0.254 0.7112)
			(layers "F.Cu" "F.Mask" "F.Paste")
			(net "VR_FET_SW_P12V_STBY_PVCCIN_CPU0")
		)
		(pad "31" smd rect
			(at 1.599946 -2.895092 90)
			(size 0.254 0.7112)
			(layers "F.Cu" "F.Mask" "F.Paste")
			(net "Net_375")
		)
		(pad "32" smd rect
			(at 1.150112 -2.895092 90)
			(size 0.254 0.7112)
			(layers "F.Cu" "F.Mask" "F.Paste")
			(net "VR_PVSA_CPU0_PHASE")
		)
		(pad "33" smd rect
			(at 0.700024 -2.895092 90)
			(size 0.254 0.7112)
			(layers "F.Cu" "F.Mask" "F.Paste")
			(net "VR_PVSA_CPU0_BOOT_R")
		)
		(pad "34" smd rect
			(at 0.249936 -2.895092 90)
			(size 0.254 0.7112)
			(layers "F.Cu" "F.Mask" "F.Paste")
			(net "VR_PVSA_CPU0_PWM")
		)
		(pad "35" smd rect
			(at -0.199898 -2.895092 90)
			(size 0.254 0.7112)
			(layers "F.Cu" "F.Mask" "F.Paste")
			(net "P5V_STBY")
		)
		(pad "36" smd rect
			(at -0.649986 -2.895092 90)
			(size 0.254 0.7112)
			(layers "F.Cu" "F.Mask" "F.Paste")
			(net "A_TSENSE_PVSA_CPU0")
		)
		(pad "37" smd rect
			(at -1.100074 -2.895092 90)
			(size 0.254 0.7112)
			(layers "F.Cu" "F.Mask" "F.Paste")
			(net "VR_PVSA_CPU0_OCSET")
		)
		(pad "38" smd rect
			(at -1.549908 -2.895092 90)
			(size 0.254 0.7112)
			(layers "F.Cu" "F.Mask" "F.Paste")
			(net "ISENSE_PVSA_CPU0_IMON")
		)
		(pad "39" smd rect
			(at -1.999996 -2.895092 90)
			(size 0.254 0.7112)
			(layers "F.Cu" "F.Mask" "F.Paste")
			(net "VR_PVSA_CPU0_BIREF1")
		)
		(pad "40" smd rect
			(at -0.871728 -1.283208 90)
			(size 1.8034 2.0066)
			(layers "F.Cu" "F.Mask" "F.Paste")
			(net "GND")
		)
		(pad "41" smd rect
			(at -1.533906 0.247904 90)
			(size 0.508 0.3556)
			(layers "F.Cu" "F.Mask" "F.Paste")
			(net "TP_PVSA_CPU0_GL_1")
		)
	)
	(footprint ""
		(layer "F.Cu")
		(at 106.89844 -73.279)
		(property "Reference" "C3D21"
			(at 0 0 0)
			(layer "F.SilkS")
			(hide yes)
			(effects
				(font
					(size 1.27 1.27)
				)
			)
		)
		(property "Value" ""
			(at 0 0 0)
			(layer "F.Fab")
			(effects
				(font
					(size 1.27 1.27)
				)
			)
		)
		(duplicate_pad_numbers_are_jumpers no)
		(fp_poly
			(pts
				(xy -0.4953 -0.2032) (xy 0.4953 -0.2032) (xy 0.4953 1.6002) (xy -0.4953 1.6002)
			)
			(stroke
				(width 0)
				(type default)
			)
			(fill no)
			(layer "F.CrtYd")
		)
		(fp_line
			(start -0.4953 -0.2032)
			(end 0.4953 -0.2032)
			(stroke
				(width 0.1)
				(type default)
			)
			(layer "F.Fab")
		)
		(fp_line
			(start -0.4953 1.6002)
			(end -0.4953 -0.2032)
			(stroke
				(width 0.1)
				(type default)
			)
			(layer "F.Fab")
		)
		(fp_line
			(start 0.4953 -0.2032)
			(end 0.4953 1.6002)
			(stroke
				(width 0.1)
				(type default)
			)
			(layer "F.Fab")
		)
		(fp_line
			(start 0.4953 1.6002)
			(end -0.4953 1.6002)
			(stroke
				(width 0.1)
				(type default)
			)
			(layer "F.Fab")
		)
		(pad "1" smd rect
			(at 0 0)
			(size 0.762 0.889)
			(layers "F.Cu" "F.Mask" "F.Paste")
			(net "PVCCMCP_CPU1")
		)
		(pad "2" smd rect
			(at 0 1.397)
			(size 0.762 0.889)
			(layers "F.Cu" "F.Mask" "F.Paste")
			(net "GND")
		)
		(zone
			(layer "F.Cu")
			(hatch none 0.5)
			(connect_pads
				(clearance 0)
			)
			(min_thickness 0.25)
			(keepout
				(tracks not_allowed)
				(vias allowed)
				(pads allowed)
				(copperpour not_allowed)
				(footprints allowed)
			)
			(placement
				(enabled no)
				(sheetname "")
			)
			(fill
				(thermal_gap 0.5)
				(thermal_bridge_width 0.5)
				(island_removal_mode 0)
			)
			(polygon
				(pts
					(xy 106.51744 -72.8345) (xy 107.27944 -72.8345) (xy 107.27944 -72.3265) (xy 106.51744 -72.3265)
				)
			)
		)
	)
	(footprint ""
		(layer "F.Cu")
		(at 27.559 -57.785 90)
		(property "Reference" "RT15"
			(at 1.01473 0.656336 0)
			(unlocked yes)
			(layer "F.SilkS")
			(effects
				(font
					(size 0.4064 0.254)
					(thickness 0.1524)
				)
			)
		)
		(property "Value" ""
			(at 0 0 90)
			(layer "F.Fab")
			(effects
				(font
					(size 1.27 1.27)
				)
			)
		)
		(duplicate_pad_numbers_are_jumpers no)
		(fp_poly
			(pts
				(xy -0.4953 -0.2032) (xy 0.4953 -0.2032) (xy 0.4953 1.6002) (xy -0.4953 1.6002)
			)
			(stroke
				(width 0)
				(type default)
			)
			(fill no)
			(layer "F.CrtYd")
		)
		(fp_line
			(start 0.4953 -0.2032)
			(end 0.4953 1.6002)
			(stroke
				(width 0.1)
				(type default)
			)
			(layer "F.Fab")
		)
		(fp_line
			(start -0.4953 -0.2032)
			(end 0.4953 -0.2032)
			(stroke
				(width 0.1)
				(type default)
			)
			(layer "F.Fab")
		)
		(fp_line
			(start 0.4953 1.6002)
			(end -0.4953 1.6002)
			(stroke
				(width 0.1)
				(type default)
			)
			(layer "F.Fab")
		)
		(fp_line
			(start -0.4953 1.6002)
			(end -0.4953 -0.2032)
			(stroke
				(width 0.1)
				(type default)
			)
			(layer "F.Fab")
		)
		(pad "1" smd rect
			(at 0 0 90)
			(size 0.762 0.889)
			(layers "F.Cu" "F.Mask" "F.Paste")
			(net "VR_PVCCIN_CPU1_PH1_BOOT")
		)
		(pad "2" smd rect
			(at 0 1.397 90)
			(size 0.762 0.889)
			(layers "F.Cu" "F.Mask" "F.Paste")
			(net "VR_PVCCIN_CPU1_PH1_BOOT_R")
		)
		(zone
			(layer "F.Cu")
			(hatch none 0.5)
			(connect_pads
				(clearance 0)
			)
			(min_thickness 0.25)
			(keepout
				(tracks allowed)
				(vias not_allowed)
				(pads allowed)
				(copperpour not_allowed)
				(footprints allowed)
			)
			(placement
				(enabled no)
				(sheetname "")
			)
			(fill
				(thermal_gap 0.5)
				(thermal_bridge_width 0.5)
				(island_removal_mode 0)
			)
			(polygon
				(pts
					(xy 28.5115 -58.166) (xy 28.0035 -58.166) (xy 28.0035 -57.404) (xy 28.5115 -57.404)
				)
			)
		)
		(zone
			(layer "F.Cu")
			(hatch none 0.5)
			(connect_pads
				(clearance 0)
			)
			(min_thickness 0.25)
			(keepout
				(tracks not_allowed)
				(vias allowed)
				(pads allowed)
				(copperpour not_allowed)
				(footprints allowed)
			)
			(placement
				(enabled no)
				(sheetname "")
			)
			(fill
				(thermal_gap 0.5)
				(thermal_bridge_width 0.5)
				(island_removal_mode 0)
			)
			(polygon
				(pts
					(xy 28.5115 -57.404) (xy 28.5115 -58.166) (xy 28.0035 -58.166) (xy 28.0035 -57.404)
				)
			)
		)
	)
	(footprint ""
		(layer "F.Cu")
		(at 178.054 -81.026 180)
		(property "Reference" "R4D18"
			(at 0 0 180)
			(layer "F.SilkS")
			(hide yes)
			(effects
				(font
					(size 1.27 1.27)
				)
			)
		)
		(property "Value" ""
			(at 0 0 180)
			(layer "F.Fab")
			(effects
				(font
					(size 1.27 1.27)
				)
			)
		)
		(duplicate_pad_numbers_are_jumpers no)
		(fp_poly
			(pts
				(xy -0.2794 -0.1016) (xy 0.2794 -0.1016) (xy 0.2794 0.9906) (xy -0.2794 0.9906)
			)
			(stroke
				(width 0)
				(type default)
			)
			(fill no)
			(layer "F.CrtYd")
		)
		(fp_line
			(start 0.2794 0.9906)
			(end 0.2794 -0.1016)
			(stroke
				(width 0.1)
				(type default)
			)
			(layer "F.Fab")
		)
		(fp_line
			(start 0.2794 -0.1016)
			(end -0.2794 -0.1016)
			(stroke
				(width 0.1)
				(type default)
			)
			(layer "F.Fab")
		)
		(fp_line
			(start -0.2794 0.9906)
			(end 0.2794 0.9906)
			(stroke
				(width 0.1)
				(type default)
			)
			(layer "F.Fab")
		)
		(fp_line
			(start -0.2794 -0.1016)
			(end -0.2794 0.9906)
			(stroke
				(width 0.1)
				(type default)
			)
			(layer "F.Fab")
		)
		(pad "1" smd rect
			(at 0 0 180)
			(size 0.508 0.508)
			(layers "F.Cu" "F.Mask" "F.Paste")
			(net "CLK_100M_CPU0_BCLK1_DN")
		)
		(pad "2" smd rect
			(at 0 0.889 180)
			(size 0.508 0.508)
			(layers "F.Cu" "F.Mask" "F.Paste")
			(net "GND")
		)
		(zone
			(layer "F.Cu")
			(hatch none 0.5)
			(connect_pads
				(clearance 0)
			)
			(min_thickness 0.25)
			(keepout
				(tracks not_allowed)
				(vias allowed)
				(pads allowed)
				(copperpour not_allowed)
				(footprints allowed)
			)
			(placement
				(enabled no)
				(sheetname "")
			)
			(fill
				(thermal_gap 0.5)
				(thermal_bridge_width 0.5)
				(island_removal_mode 0)
			)
			(polygon
				(pts
					(xy 178.308 -81.661) (xy 177.8 -81.661) (xy 177.8 -81.28) (xy 178.308 -81.28)
				)
			)
		)
		(zone
			(layer "F.Cu")
			(hatch none 0.5)
			(connect_pads
				(clearance 0)
			)
			(min_thickness 0.25)
			(keepout
				(tracks allowed)
				(vias not_allowed)
				(pads allowed)
				(copperpour not_allowed)
				(footprints allowed)
			)
			(placement
				(enabled no)
				(sheetname "")
			)
			(fill
				(thermal_gap 0.5)
				(thermal_bridge_width 0.5)
				(island_removal_mode 0)
			)
			(polygon
				(pts
					(xy 178.308 -81.28) (xy 177.8 -81.28) (xy 177.8 -81.661) (xy 178.308 -81.661)
				)
			)
		)
	)
	(footprint ""
		(layer "F.Cu")
		(at 171.6532 -7.8232 90)
		(property "Reference" "C4G7"
			(at 0 0 90)
			(layer "F.SilkS")
			(hide yes)
			(effects
				(font
					(size 1.27 1.27)
				)
			)
		)
		(property "Value" ""
			(at 0 0 90)
			(layer "F.Fab")
			(effects
				(font
					(size 1.27 1.27)
				)
			)
		)
		(duplicate_pad_numbers_are_jumpers no)
		(fp_rect
			(start 0.3048 0.9906)
			(end -0.3048 -0.1016)
			(stroke
				(width 0)
				(type default)
			)
			(fill no)
			(layer "F.CrtYd")
		)
		(fp_line
			(start 0.3048 -0.1016)
			(end -0.3048 -0.1016)
			(stroke
				(width 0.1)
				(type default)
			)
			(layer "F.Fab")
		)
		(fp_line
			(start -0.3048 -0.1016)
			(end -0.3048 0.9906)
			(stroke
				(width 0.1)
				(type default)
			)
			(layer "F.Fab")
		)
		(fp_line
			(start 0.3048 0.9906)
			(end 0.3048 -0.1016)
			(stroke
				(width 0.1)
				(type default)
			)
			(layer "F.Fab")
		)
		(fp_line
			(start -0.3048 0.9906)
			(end 0.3048 0.9906)
			(stroke
				(width 0.1)
				(type default)
			)
			(layer "F.Fab")
		)
		(pad "1" smd rect
			(at 0 0 90)
			(size 0.508 0.508)
			(layers "F.Cu" "F.Mask" "F.Paste")
			(net "FM_PVPP_CPU1_EN")
		)
		(pad "2" smd rect
			(at 0 0.889 90)
			(size 0.508 0.508)
			(layers "F.Cu" "F.Mask" "F.Paste")
			(net "AGND_PVPP_GHJ")
		)
		(zone
			(layer "F.Cu")
			(hatch none 0.5)
			(connect_pads
				(clearance 0)
			)
			(min_thickness 0.25)
			(keepout
				(tracks not_allowed)
				(vias allowed)
				(pads allowed)
				(copperpour not_allowed)
				(footprints allowed)
			)
			(placement
				(enabled no)
				(sheetname "")
			)
			(fill
				(thermal_gap 0.5)
				(thermal_bridge_width 0.5)
				(island_removal_mode 0)
			)
			(polygon
				(pts
					(xy 172.2882 -8.0772) (xy 171.9072 -8.0772) (xy 171.9072 -7.5692) (xy 172.2882 -7.5692)
				)
			)
		)
		(zone
			(layer "F.Cu")
			(hatch none 0.5)
			(connect_pads
				(clearance 0)
			)
			(min_thickness 0.25)
			(keepout
				(tracks allowed)
				(vias not_allowed)
				(pads allowed)
				(copperpour not_allowed)
				(footprints allowed)
			)
			(placement
				(enabled no)
				(sheetname "")
			)
			(fill
				(thermal_gap 0.5)
				(thermal_bridge_width 0.5)
				(island_removal_mode 0)
			)
			(polygon
				(pts
					(xy 172.2882 -8.0772) (xy 171.9072 -8.0772) (xy 171.9072 -7.5692) (xy 172.2882 -7.5692)
				)
			)
		)
	)
	(footprint ""
		(layer "F.Cu")
		(at 421.627046 -48.968152)
		(property "Reference" "R25W103"
			(at -0.8382 -0.67818 0)
			(unlocked yes)
			(layer "F.SilkS")
			(effects
				(font
					(size 0.4064 0.254)
					(thickness 0.1524)
				)
				(justify left)
			)
		)
		(property "Value" ""
			(at 0 0 0)
			(layer "F.Fab")
			(effects
				(font
					(size 1.27 1.27)
				)
			)
		)
		(duplicate_pad_numbers_are_jumpers no)
		(fp_poly
			(pts
				(xy -0.2794 -0.1016) (xy 0.2794 -0.1016) (xy 0.2794 0.9906) (xy -0.2794 0.9906)
			)
			(stroke
				(width 0)
				(type default)
			)
			(fill no)
			(layer "F.CrtYd")
		)
		(fp_line
			(start -0.2794 -0.1016)
			(end -0.2794 0.9906)
			(stroke
				(width 0.1)
				(type default)
			)
			(layer "F.Fab")
		)
		(fp_line
			(start -0.2794 0.9906)
			(end 0.2794 0.9906)
			(stroke
				(width 0.1)
				(type default)
			)
			(layer "F.Fab")
		)
		(fp_line
			(start 0.2794 -0.1016)
			(end -0.2794 -0.1016)
			(stroke
				(width 0.1)
				(type default)
			)
			(layer "F.Fab")
		)
		(fp_line
			(start 0.2794 0.9906)
			(end 0.2794 -0.1016)
			(stroke
				(width 0.1)
				(type default)
			)
			(layer "F.Fab")
		)
		(pad "1" smd rect
			(at 0 0)
			(size 0.508 0.508)
			(layers "F.Cu" "F.Mask" "F.Paste")
			(net "P3V3_STBY")
		)
		(pad "2" smd rect
			(at 0 0.889)
			(size 0.508 0.508)
			(layers "F.Cu" "F.Mask" "F.Paste")
			(net "BMC_STRAP_BIT20")
		)
		(zone
			(layer "F.Cu")
			(hatch none 0.5)
			(connect_pads
				(clearance 0)
			)
			(min_thickness 0.25)
			(keepout
				(tracks allowed)
				(vias not_allowed)
				(pads allowed)
				(copperpour not_allowed)
				(footprints allowed)
			)
			(placement
				(enabled no)
				(sheetname "")
			)
			(fill
				(thermal_gap 0.5)
				(thermal_bridge_width 0.5)
				(island_removal_mode 0)
			)
			(polygon
				(pts
					(xy 421.373046 -48.714152) (xy 421.881046 -48.714152) (xy 421.881046 -48.333152) (xy 421.373046 -48.333152)
				)
			)
		)
		(zone
			(layer "F.Cu")
			(hatch none 0.5)
			(connect_pads
				(clearance 0)
			)
			(min_thickness 0.25)
			(keepout
				(tracks not_allowed)
				(vias allowed)
				(pads allowed)
				(copperpour not_allowed)
				(footprints allowed)
			)
			(placement
				(enabled no)
				(sheetname "")
			)
			(fill
				(thermal_gap 0.5)
				(thermal_bridge_width 0.5)
				(island_removal_mode 0)
			)
			(polygon
				(pts
					(xy 421.373046 -48.333152) (xy 421.881046 -48.333152) (xy 421.881046 -48.714152) (xy 421.373046 -48.714152)
				)
			)
		)
	)
	(footprint ""
		(layer "F.Cu")
		(at 372.491 -154.4955)
		(property "Reference" "C7A8"
			(at 0 0 0)
			(layer "F.SilkS")
			(hide yes)
			(effects
				(font
					(size 1.27 1.27)
				)
			)
		)
		(property "Value" ""
			(at 0 0 0)
			(layer "F.Fab")
			(effects
				(font
					(size 1.27 1.27)
				)
			)
		)
		(duplicate_pad_numbers_are_jumpers no)
		(fp_poly
			(pts
				(xy 0.3048 -0.1016) (xy 0.3048 0.9906) (xy -0.3048 0.9906) (xy -0.3048 -0.1016)
			)
			(stroke
				(width 0)
				(type default)
			)
			(fill no)
			(layer "F.CrtYd")
		)
		(fp_line
			(start -0.3048 -0.1016)
			(end -0.3048 0.9906)
			(stroke
				(width 0.1)
				(type default)
			)
			(layer "F.Fab")
		)
		(fp_line
			(start -0.3048 0.9906)
			(end 0.3048 0.9906)
			(stroke
				(width 0.1)
				(type default)
			)
			(layer "F.Fab")
		)
		(fp_line
			(start 0.3048 -0.1016)
			(end -0.3048 -0.1016)
			(stroke
				(width 0.1)
				(type default)
			)
			(layer "F.Fab")
		)
		(fp_line
			(start 0.3048 0.9906)
			(end 0.3048 -0.1016)
			(stroke
				(width 0.1)
				(type default)
			)
			(layer "F.Fab")
		)
		(pad "1" smd rect
			(at 0 0)
			(size 0.508 0.508)
			(layers "F.Cu" "F.Mask" "F.Paste")
			(net "P5V_STBY")
		)
		(pad "2" smd rect
			(at 0 0.889)
			(size 0.508 0.508)
			(layers "F.Cu" "F.Mask" "F.Paste")
			(net "GND")
		)
		(zone
			(layer "F.Cu")
			(hatch none 0.5)
			(connect_pads
				(clearance 0)
			)
			(min_thickness 0.25)
			(keepout
				(tracks allowed)
				(vias not_allowed)
				(pads allowed)
				(copperpour not_allowed)
				(footprints allowed)
			)
			(placement
				(enabled no)
				(sheetname "")
			)
			(fill
				(thermal_gap 0.5)
				(thermal_bridge_width 0.5)
				(island_removal_mode 0)
			)
			(polygon
				(pts
					(xy 372.237 -154.2415) (xy 372.745 -154.2415) (xy 372.745 -153.8605) (xy 372.237 -153.8605)
				)
			)
		)
		(zone
			(layer "F.Cu")
			(hatch none 0.5)
			(connect_pads
				(clearance 0)
			)
			(min_thickness 0.25)
			(keepout
				(tracks not_allowed)
				(vias allowed)
				(pads allowed)
				(copperpour not_allowed)
				(footprints allowed)
			)
			(placement
				(enabled no)
				(sheetname "")
			)
			(fill
				(thermal_gap 0.5)
				(thermal_bridge_width 0.5)
				(island_removal_mode 0)
			)
			(polygon
				(pts
					(xy 372.237 -153.8605) (xy 372.745 -153.8605) (xy 372.745 -154.2415) (xy 372.237 -154.2415)
				)
			)
		)
	)
	(footprint ""
		(layer "F.Cu")
		(at 406.9461 -64.897 90)
		(property "Reference" "R8E10"
			(at 0 0 90)
			(layer "F.SilkS")
			(hide yes)
			(effects
				(font
					(size 1.27 1.27)
				)
			)
		)
		(property "Value" ""
			(at 0 0 90)
			(layer "F.Fab")
			(effects
				(font
					(size 1.27 1.27)
				)
			)
		)
		(duplicate_pad_numbers_are_jumpers no)
		(fp_poly
			(pts
				(xy -0.2794 -0.1016) (xy 0.2794 -0.1016) (xy 0.2794 0.9906) (xy -0.2794 0.9906)
			)
			(stroke
				(width 0)
				(type default)
			)
			(fill no)
			(layer "F.CrtYd")
		)
		(pad "1" smd rect
			(at 0 0 90)
			(size 0.508 0.508)
			(layers "F.Cu" "F.Mask" "F.Paste")
			(net "SPI_PCH_MOSI")
		)
		(pad "2" smd rect
			(at 0 0.889 90)
			(size 0.508 0.508)
			(layers "F.Cu" "F.Mask" "F.Paste")
			(net "SPI_PCH_TPM_MOSI_R")
		)
		(zone
			(layer "F.Cu")
			(hatch none 0.5)
			(connect_pads
				(clearance 0)
			)
			(min_thickness 0.25)
			(keepout
				(tracks allowed)
				(vias not_allowed)
				(pads allowed)
				(copperpour not_allowed)
				(footprints allowed)
			)
			(placement
				(enabled no)
				(sheetname "")
			)
			(fill
				(thermal_gap 0.5)
				(thermal_bridge_width 0.5)
				(island_removal_mode 0)
			)
			(polygon
				(pts
					(xy 407.2001 -64.643) (xy 407.2001 -65.151) (xy 407.5811 -65.151) (xy 407.5811 -64.643)
				)
			)
		)
		(zone
			(layer "F.Cu")
			(hatch none 0.5)
			(connect_pads
				(clearance 0)
			)
			(min_thickness 0.25)
			(keepout
				(tracks not_allowed)
				(vias allowed)
				(pads allowed)
				(copperpour not_allowed)
				(footprints allowed)
			)
			(placement
				(enabled no)
				(sheetname "")
			)
			(fill
				(thermal_gap 0.5)
				(thermal_bridge_width 0.5)
				(island_removal_mode 0)
			)
			(polygon
				(pts
					(xy 407.5811 -64.643) (xy 407.5811 -65.151) (xy 407.2001 -65.151) (xy 407.2001 -64.643)
				)
			)
		)
	)
	(footprint ""
		(layer "F.Cu")
		(at 13.716 -97.028 180)
		(property "Reference" "C1C13"
			(at 0 0 180)
			(layer "F.SilkS")
			(hide yes)
			(effects
				(font
					(size 1.27 1.27)
				)
			)
		)
		(property "Value" ""
			(at 0 0 180)
			(layer "F.Fab")
			(effects
				(font
					(size 1.27 1.27)
				)
			)
		)
		(duplicate_pad_numbers_are_jumpers no)
		(fp_rect
			(start 0.3048 -0.1016)
			(end -0.3048 0.9906)
			(stroke
				(width 0)
				(type default)
			)
			(fill no)
			(layer "F.CrtYd")
		)
		(fp_line
			(start 0.3048 0.9906)
			(end 0.3048 -0.1016)
			(stroke
				(width 0.1)
				(type default)
			)
			(layer "F.Fab")
		)
		(fp_line
			(start 0.3048 -0.1016)
			(end -0.3048 -0.1016)
			(stroke
				(width 0.1)
				(type default)
			)
			(layer "F.Fab")
		)
		(fp_line
			(start -0.3048 0.9906)
			(end 0.3048 0.9906)
			(stroke
				(width 0.1)
				(type default)
			)
			(layer "F.Fab")
		)
		(fp_line
			(start -0.3048 -0.1016)
			(end -0.3048 0.9906)
			(stroke
				(width 0.1)
				(type default)
			)
			(layer "F.Fab")
		)
		(pad "1" smd rect
			(at 0 0 180)
			(size 0.508 0.508)
			(layers "F.Cu" "F.Mask" "F.Paste")
			(net "VR_PVCCIN_CPU1_VD12")
		)
		(pad "2" smd rect
			(at 0 0.889 180)
			(size 0.508 0.508)
			(layers "F.Cu" "F.Mask" "F.Paste")
			(net "GND")
		)
		(zone
			(layer "F.Cu")
			(hatch none 0.5)
			(connect_pads
				(clearance 0)
			)
			(min_thickness 0.25)
			(keepout
				(tracks allowed)
				(vias not_allowed)
				(pads allowed)
				(copperpour not_allowed)
				(footprints allowed)
			)
			(placement
				(enabled no)
				(sheetname "")
			)
			(fill
				(thermal_gap 0.5)
				(thermal_bridge_width 0.5)
				(island_removal_mode 0)
			)
			(polygon
				(pts
					(xy 13.462 -97.282) (xy 13.97 -97.282) (xy 13.97 -97.663) (xy 13.462 -97.663)
				)
			)
		)
		(zone
			(layer "F.Cu")
			(hatch none 0.5)
			(connect_pads
				(clearance 0)
			)
			(min_thickness 0.25)
			(keepout
				(tracks not_allowed)
				(vias allowed)
				(pads allowed)
				(copperpour not_allowed)
				(footprints allowed)
			)
			(placement
				(enabled no)
				(sheetname "")
			)
			(fill
				(thermal_gap 0.5)
				(thermal_bridge_width 0.5)
				(island_removal_mode 0)
			)
			(polygon
				(pts
					(xy 13.462 -97.282) (xy 13.97 -97.282) (xy 13.97 -97.663) (xy 13.462 -97.663)
				)
			)
		)
	)
	(footprint ""
		(layer "F.Cu")
		(at 87.158068 -140.208 -90)
		(property "Reference" "C2A11"
			(at 1.848866 0.752348 270)
			(unlocked yes)
			(layer "F.SilkS")
			(effects
				(font
					(size 1.27 0.9652)
					(thickness 0.1524)
				)
			)
		)
		(property "Value" ""
			(at 0 0 270)
			(layer "F.Fab")
			(effects
				(font
					(size 1.27 1.27)
				)
			)
		)
		(duplicate_pad_numbers_are_jumpers no)
		(fp_rect
			(start -0.500126 1.598422)
			(end 0.500126 -0.201422)
			(stroke
				(width 0)
				(type default)
			)
			(fill no)
			(layer "F.CrtYd")
		)
		(fp_line
			(start -0.500126 1.598422)
			(end -0.500126 -0.201422)
			(stroke
				(width 0.1)
				(type default)
			)
			(layer "F.Fab")
		)
		(fp_line
			(start 0.500126 1.598422)
			(end -0.500126 1.598422)
			(stroke
				(width 0.1)
				(type default)
			)
			(layer "F.Fab")
		)
		(fp_line
			(start -0.500126 -0.201422)
			(end 0.500126 -0.201422)
			(stroke
				(width 0.1)
				(type default)
			)
			(layer "F.Fab")
		)
		(fp_line
			(start 0.500126 -0.201422)
			(end 0.500126 1.598422)
			(stroke
				(width 0.1)
				(type default)
			)
			(layer "F.Fab")
		)
		(pad "1" smd rect
			(at 0 0 180)
			(size 0.889 0.9906)
			(layers "F.Cu" "F.Mask" "F.Paste")
			(net "PVDDQ_KLM")
		)
		(pad "2" smd rect
			(at 0 1.397 180)
			(size 0.889 0.9906)
			(layers "F.Cu" "F.Mask" "F.Paste")
			(net "GND")
		)
		(zone
			(layer "F.Cu")
			(hatch none 0.5)
			(connect_pads
				(clearance 0)
			)
			(min_thickness 0.25)
			(keepout
				(tracks allowed)
				(vias not_allowed)
				(pads allowed)
				(copperpour not_allowed)
				(footprints allowed)
			)
			(placement
				(enabled no)
				(sheetname "")
			)
			(fill
				(thermal_gap 0.5)
				(thermal_bridge_width 0.5)
				(island_removal_mode 0)
			)
			(polygon
				(pts
					(xy 86.205568 -140.7033) (xy 86.205568 -139.7127) (xy 86.713568 -139.7127) (xy 86.713568 -140.7033)
				)
			)
		)
		(zone
			(layer "F.Cu")
			(hatch none 0.5)
			(connect_pads
				(clearance 0)
			)
			(min_thickness 0.25)
			(keepout
				(tracks not_allowed)
				(vias allowed)
				(pads allowed)
				(copperpour not_allowed)
				(footprints allowed)
			)
			(placement
				(enabled no)
				(sheetname "")
			)
			(fill
				(thermal_gap 0.5)
				(thermal_bridge_width 0.5)
				(island_removal_mode 0)
			)
			(polygon
				(pts
					(xy 86.205568 -140.7033) (xy 86.205568 -139.7127) (xy 86.713568 -139.7127) (xy 86.713568 -140.7033)
				)
			)
		)
	)
	(footprint ""
		(layer "F.Cu")
		(at 182.5752 -55.3974 90)
		(property "Reference" "CT61"
			(at -4.6482 1.49987 90)
			(unlocked yes)
			(layer "F.SilkS")
			(effects
				(font
					(size 0.7874 0.5842)
					(thickness 0.1524)
				)
				(justify left)
			)
		)
		(property "Value" ""
			(at 0 0 90)
			(layer "F.Fab")
			(effects
				(font
					(size 1.27 1.27)
				)
			)
		)
		(duplicate_pad_numbers_are_jumpers no)
		(fp_poly
			(pts
				(xy 0.3048 -0.1016) (xy 0.3048 0.9906) (xy -0.3048 0.9906) (xy -0.3048 -0.1016)
			)
			(stroke
				(width 0)
				(type default)
			)
			(fill no)
			(layer "F.CrtYd")
		)
		(fp_line
			(start 0.3048 -0.1016)
			(end -0.3048 -0.1016)
			(stroke
				(width 0.1)
				(type default)
			)
			(layer "F.Fab")
		)
		(fp_line
			(start -0.3048 -0.1016)
			(end -0.3048 0.9906)
			(stroke
				(width 0.1)
				(type default)
			)
			(layer "F.Fab")
		)
		(fp_line
			(start 0.3048 0.9906)
			(end 0.3048 -0.1016)
			(stroke
				(width 0.1)
				(type default)
			)
			(layer "F.Fab")
		)
		(fp_line
			(start -0.3048 0.9906)
			(end 0.3048 0.9906)
			(stroke
				(width 0.1)
				(type default)
			)
			(layer "F.Fab")
		)
		(pad "1" smd rect
			(at 0 0 90)
			(size 0.508 0.508)
			(layers "F.Cu" "F.Mask" "F.Paste")
			(net "A_TSENSE_PVCCIO_CPU1")
		)
		(pad "2" smd rect
			(at 0 0.889 90)
			(size 0.508 0.508)
			(layers "F.Cu" "F.Mask" "F.Paste")
			(net "GND")
		)
		(zone
			(layer "F.Cu")
			(hatch none 0.5)
			(connect_pads
				(clearance 0)
			)
			(min_thickness 0.25)
			(keepout
				(tracks allowed)
				(vias not_allowed)
				(pads allowed)
				(copperpour not_allowed)
				(footprints allowed)
			)
			(placement
				(enabled no)
				(sheetname "")
			)
			(fill
				(thermal_gap 0.5)
				(thermal_bridge_width 0.5)
				(island_removal_mode 0)
			)
			(polygon
				(pts
					(xy 182.8292 -55.1434) (xy 182.8292 -55.6514) (xy 183.2102 -55.6514) (xy 183.2102 -55.1434)
				)
			)
		)
		(zone
			(layer "F.Cu")
			(hatch none 0.5)
			(connect_pads
				(clearance 0)
			)
			(min_thickness 0.25)
			(keepout
				(tracks not_allowed)
				(vias allowed)
				(pads allowed)
				(copperpour not_allowed)
				(footprints allowed)
			)
			(placement
				(enabled no)
				(sheetname "")
			)
			(fill
				(thermal_gap 0.5)
				(thermal_bridge_width 0.5)
				(island_removal_mode 0)
			)
			(polygon
				(pts
					(xy 183.2102 -55.1434) (xy 183.2102 -55.6514) (xy 182.8292 -55.6514) (xy 182.8292 -55.1434)
				)
			)
		)
	)
	(footprint ""
		(layer "F.Cu")
		(at 467.995 -42.164 180)
		(property "Reference" "C9F5"
			(at 0 0 180)
			(layer "F.SilkS")
			(hide yes)
			(effects
				(font
					(size 1.27 1.27)
				)
			)
		)
		(property "Value" ""
			(at 0 0 180)
			(layer "F.Fab")
			(effects
				(font
					(size 1.27 1.27)
				)
			)
		)
		(duplicate_pad_numbers_are_jumpers no)
		(fp_poly
			(pts
				(xy 0.3048 -0.1016) (xy 0.3048 0.9906) (xy -0.3048 0.9906) (xy -0.3048 -0.1016)
			)
			(stroke
				(width 0)
				(type default)
			)
			(fill no)
			(layer "F.CrtYd")
		)
		(fp_line
			(start 0.3048 0.9906)
			(end 0.3048 -0.1016)
			(stroke
				(width 0.1)
				(type default)
			)
			(layer "F.Fab")
		)
		(fp_line
			(start 0.3048 -0.1016)
			(end -0.3048 -0.1016)
			(stroke
				(width 0.1)
				(type default)
			)
			(layer "F.Fab")
		)
		(fp_line
			(start -0.3048 0.9906)
			(end 0.3048 0.9906)
			(stroke
				(width 0.1)
				(type default)
			)
			(layer "F.Fab")
		)
		(fp_line
			(start -0.3048 -0.1016)
			(end -0.3048 0.9906)
			(stroke
				(width 0.1)
				(type default)
			)
			(layer "F.Fab")
		)
		(pad "1" smd rect
			(at 0 0 180)
			(size 0.508 0.508)
			(layers "F.Cu" "F.Mask" "F.Paste")
			(net "P3V3_STBY")
		)
		(pad "2" smd rect
			(at 0 0.889 180)
			(size 0.508 0.508)
			(layers "F.Cu" "F.Mask" "F.Paste")
			(net "GND")
		)
		(zone
			(layer "F.Cu")
			(hatch none 0.5)
			(connect_pads
				(clearance 0)
			)
			(min_thickness 0.25)
			(keepout
				(tracks not_allowed)
				(vias allowed)
				(pads allowed)
				(copperpour not_allowed)
				(footprints allowed)
			)
			(placement
				(enabled no)
				(sheetname "")
			)
			(fill
				(thermal_gap 0.5)
				(thermal_bridge_width 0.5)
				(island_removal_mode 0)
			)
			(polygon
				(pts
					(xy 468.249 -42.799) (xy 467.741 -42.799) (xy 467.741 -42.418) (xy 468.249 -42.418)
				)
			)
		)
		(zone
			(layer "F.Cu")
			(hatch none 0.5)
			(connect_pads
				(clearance 0)
			)
			(min_thickness 0.25)
			(keepout
				(tracks allowed)
				(vias not_allowed)
				(pads allowed)
				(copperpour not_allowed)
				(footprints allowed)
			)
			(placement
				(enabled no)
				(sheetname "")
			)
			(fill
				(thermal_gap 0.5)
				(thermal_bridge_width 0.5)
				(island_removal_mode 0)
			)
			(polygon
				(pts
					(xy 468.249 -42.418) (xy 467.741 -42.418) (xy 467.741 -42.799) (xy 468.249 -42.799)
				)
			)
		)
	)
	(footprint ""
		(layer "F.Cu")
		(at 190.9318 -69.8754 180)
		(property "Reference" "CF4"
			(at 0 0 180)
			(layer "F.SilkS")
			(hide yes)
			(effects
				(font
					(size 1.27 1.27)
				)
			)
		)
		(property "Value" "*"
			(at 1.1811 -2.8194 180)
			(unlocked yes)
			(layer "F.Fab")
			(hide yes)
			(effects
				(font
					(size 1.27 1.016)
					(thickness 0.1524)
				)
			)
		)
		(property "Device Type" "SC22P50V2JN-4GP_SMD-BCG-SC22P5A"
			(at 1.1811 -4.3434 180)
			(unlocked yes)
			(layer "F.Fab")
			(hide yes)
			(effects
				(font
					(size 1.27 1.016)
					(thickness 0.1524)
				)
			)
		)
		(duplicate_pad_numbers_are_jumpers no)
		(fp_rect
			(start -0.4318 0.9525)
			(end 0.4318 -0.9525)
			(stroke
				(width 0)
				(type default)
			)
			(fill no)
			(layer "F.CrtYd")
		)
		(fp_rect
			(start -0.4318 0.9525)
			(end 0.4318 -0.9525)
			(stroke
				(width 0)
				(type default)
			)
			(fill no)
			(layer "F.Fab")
		)
		(pad "1" smd custom
			(at 0 -0.4445 180)
			(size 0.1524 0.1524)
			(layers "F.Cu" "F.Mask" "F.Paste")
			(net "VR_PVCCIN_CPU0_AIREF4")
			(options
				(clearance outline)
				(anchor circle)
			)
			(primitives
				(gr_poly
					(pts
						(arc
							(start 0.3048 -0.2032)
							(mid 0.275042 -0.275042)
							(end 0.2032 -0.3048)
						)
						(arc
							(start -0.2032 -0.3048)
							(mid -0.275042 -0.275042)
							(end -0.3048 -0.2032)
						)
						(arc
							(start -0.3048 0.2032)
							(mid -0.275042 0.275042)
							(end -0.2032 0.3048)
						)
						(arc
							(start 0.2032 0.3048)
							(mid 0.275042 0.275042)
							(end 0.3048 0.2032)
						)
					)
					(width 0)
					(fill yes)
				)
			)
		)
		(pad "2" smd custom
			(at 0 0.4445 180)
			(size 0.1524 0.1524)
			(layers "F.Cu" "F.Mask" "F.Paste")
			(net "ISENSE_PVCCIN_CPU0_PH4_IMON")
			(options
				(clearance outline)
				(anchor circle)
			)
			(primitives
				(gr_poly
					(pts
						(arc
							(start 0.3048 -0.2032)
							(mid 0.275042 -0.275042)
							(end 0.2032 -0.3048)
						)
						(arc
							(start -0.2032 -0.3048)
							(mid -0.275042 -0.275042)
							(end -0.3048 -0.2032)
						)
						(arc
							(start -0.3048 0.2032)
							(mid -0.275042 0.275042)
							(end -0.2032 0.3048)
						)
						(arc
							(start 0.2032 0.3048)
							(mid 0.275042 0.275042)
							(end 0.3048 0.2032)
						)
					)
					(width 0)
					(fill yes)
				)
			)
		)
	)
	(footprint ""
		(layer "F.Cu")
		(at 194.700398 -142.6718 90)
		(property "Reference" "J4A2"
			(at -2.369312 42.66311 0)
			(unlocked yes)
			(layer "F.SilkS")
			(effects
				(font
					(size 0.7874 0.5842)
					(thickness 0.1524)
				)
				(justify left)
			)
		)
		(property "Value" ""
			(at 0 0 90)
			(layer "F.Fab")
			(effects
				(font
					(size 1.27 1.27)
				)
			)
		)
		(duplicate_pad_numbers_are_jumpers no)
		(fp_line
			(start 5.5499 -7.675118)
			(end 5.5499 -1.480058)
			(stroke
				(width 0.1524)
				(type default)
			)
			(layer "F.SilkS")
		)
		(fp_line
			(start -0.94996 -7.675118)
			(end 5.5499 -7.675118)
			(stroke
				(width 0.1524)
				(type default)
			)
			(layer "F.SilkS")
		)
		(fp_line
			(start -0.94996 -1.480058)
			(end -0.94996 -7.675118)
			(stroke
				(width 0.1524)
				(type default)
			)
			(layer "F.SilkS")
		)
		(fp_line
			(start 5.5499 128.130046)
			(end 5.5499 134.325106)
			(stroke
				(width 0.1524)
				(type default)
			)
			(layer "F.SilkS")
		)
		(fp_line
			(start 5.5499 134.325106)
			(end -0.94996 134.325106)
			(stroke
				(width 0.1524)
				(type default)
			)
			(layer "F.SilkS")
		)
		(fp_line
			(start -0.94996 134.325106)
			(end -0.94996 128.130046)
			(stroke
				(width 0.1524)
				(type default)
			)
			(layer "F.SilkS")
		)
		(fp_poly
			(pts
				(xy -2.909062 -0.852424) (xy -2.909062 0.163576) (xy -1.639062 -0.344424)
			)
			(stroke
				(width 0)
				(type default)
			)
			(fill yes)
			(layer "F.SilkS")
		)
		(fp_poly
			(pts
				(xy -0.94996 -7.675118) (xy -0.94996 134.325106) (xy 5.5499 134.325106) (xy 5.5499 -7.675118)
			)
			(stroke
				(width 0)
				(type default)
			)
			(fill no)
			(layer "F.CrtYd")
		)
		(fp_line
			(start 5.5499 -7.675118)
			(end 5.5499 134.325106)
			(stroke
				(width 0.1)
				(type default)
			)
			(layer "F.Fab")
		)
		(fp_line
			(start -0.94996 -7.675118)
			(end 5.5499 -7.675118)
			(stroke
				(width 0.1)
				(type default)
			)
			(layer "F.Fab")
		)
		(fp_line
			(start 5.5499 134.325106)
			(end -0.94996 134.325106)
			(stroke
				(width 0.1)
				(type default)
			)
			(layer "F.Fab")
		)
		(fp_line
			(start -0.94996 134.325106)
			(end -0.94996 -7.675118)
			(stroke
				(width 0.1)
				(type default)
			)
			(layer "F.Fab")
		)
		(fp_poly
			(pts
				(xy -2.984246 -0.461264) (xy -2.984246 0.554736) (xy -1.714246 0.046736)
			)
			(stroke
				(width 0)
				(type default)
			)
			(fill yes)
			(layer "F.Fab")
		)
		(fp_text user "145"
			(at 6.063488 -0.75565 0)
			(unlocked yes)
			(layer "F.SilkS")
			(effects
				(font
					(size 0.7874 0.5842)
					(thickness 0.1524)
				)
				(justify left)
			)
		)
		(fp_text user "77"
			(at -1.539494 64.871346 0)
			(unlocked yes)
			(layer "F.SilkS")
			(effects
				(font
					(size 0.7874 0.5842)
					(thickness 0.1524)
				)
				(justify left)
			)
		)
		(fp_text user "221"
			(at 5.863336 65.093596 0)
			(unlocked yes)
			(layer "F.SilkS")
			(effects
				(font
					(size 0.7874 0.5842)
					(thickness 0.1524)
				)
				(justify left)
			)
		)
		(fp_text user "78"
			(at -1.542542 69.734938 0)
			(unlocked yes)
			(layer "F.SilkS")
			(effects
				(font
					(size 0.7874 0.5842)
					(thickness 0.1524)
				)
				(justify left)
			)
		)
		(fp_text user "222"
			(at 6.05663 69.891402 0)
			(unlocked yes)
			(layer "F.SilkS")
			(effects
				(font
					(size 0.7874 0.5842)
					(thickness 0.1524)
				)
				(justify left)
			)
		)
		(fp_text user "288"
			(at 6.520688 127.95631 0)
			(unlocked yes)
			(layer "F.SilkS")
			(effects
				(font
					(size 0.7874 0.5842)
					(thickness 0.1524)
				)
				(justify left)
			)
		)
		(fp_text user "144"
			(at -1.683512 128.05791 0)
			(unlocked yes)
			(layer "F.SilkS")
			(effects
				(font
					(size 0.7874 0.5842)
					(thickness 0.1524)
				)
				(justify left)
			)
		)
		(fp_text user "145"
			(at 6.062726 -0.755904 0)
			(unlocked yes)
			(layer "F.Fab")
			(effects
				(font
					(size 0.7874 0.5842)
					(thickness 0.1524)
				)
				(justify left)
			)
		)
		(fp_text user "221"
			(at 3.245358 65.90538 90)
			(unlocked yes)
			(layer "F.Fab")
			(effects
				(font
					(size 0.7874 0.5842)
					(thickness 0.1524)
				)
				(justify left)
			)
		)
		(fp_text user "77"
			(at -0.767842 66.31178 90)
			(unlocked yes)
			(layer "F.Fab")
			(effects
				(font
					(size 0.7874 0.5842)
					(thickness 0.1524)
				)
				(justify left)
			)
		)
		(fp_text user "78"
			(at -0.640842 68.59778 90)
			(unlocked yes)
			(layer "F.Fab")
			(effects
				(font
					(size 0.7874 0.5842)
					(thickness 0.1524)
				)
				(justify left)
			)
		)
		(fp_text user "222"
			(at 3.219958 68.75018 90)
			(unlocked yes)
			(layer "F.Fab")
			(effects
				(font
					(size 0.7874 0.5842)
					(thickness 0.1524)
				)
				(justify left)
			)
		)
		(fp_text user "288"
			(at 3.372358 127.52578 90)
			(unlocked yes)
			(layer "F.Fab")
			(effects
				(font
					(size 0.7874 0.5842)
					(thickness 0.1524)
				)
				(justify left)
			)
		)
		(fp_text user "144"
			(at -0.437642 127.52578 90)
			(unlocked yes)
			(layer "F.Fab")
			(effects
				(font
					(size 0.7874 0.5842)
					(thickness 0.1524)
				)
				(justify left)
			)
		)
		(pad "" thru_hole circle
			(at 2.29997 -5.649976 90)
			(size 2.8194 2.8194)
			(drill 2.4384)
			(layers "*.Cu" "*.Mask")
			(remove_unused_layers no)
			(clearance 0.127)
			(thermal_gap 0.127)
		)
		(pad "" thru_hole oval
			(at 2.29997 68.90004 90)
			(size 2.8194 1.5748)
			(drill oval 2.4384 1.1938)
			(layers "*.Cu" "*.Mask")
			(remove_unused_layers no)
			(clearance 0.127)
			(thermal_gap 0.127)
		)
		(pad "" thru_hole circle
			(at 2.29997 132.299964 90)
			(size 2.8194 2.8194)
			(drill 2.4384)
			(layers "*.Cu" "*.Mask")
			(remove_unused_layers no)
			(clearance 0.127)
			(thermal_gap 0.127)
		)
		(pad "1" smd rect
			(at 0 0 90)
			(size 1.8034 0.508)
			(layers "F.Cu" "F.Mask" "F.Paste")
			(net "P12V_NVDIMM_DEF")
		)
		(pad "2" smd rect
			(at 0 0.849884 90)
			(size 1.8034 0.508)
			(layers "F.Cu" "F.Mask" "F.Paste")
			(net "GND")
		)
		(pad "3" smd rect
			(at 0 1.700022 90)
			(size 1.8034 0.508)
			(layers "F.Cu" "F.Mask" "F.Paste")
			(net "M_E_DQ<5>")
		)
		(pad "4" smd rect
			(at 0 2.549906 90)
			(size 1.8034 0.508)
			(layers "F.Cu" "F.Mask" "F.Paste")
			(net "GND")
		)
		(pad "5" smd rect
			(at 0 3.400044 90)
			(size 1.8034 0.508)
			(layers "F.Cu" "F.Mask" "F.Paste")
			(net "M_E_DQ<1>")
		)
		(pad "6" smd rect
			(at 0 4.249928 90)
			(size 1.8034 0.508)
			(layers "F.Cu" "F.Mask" "F.Paste")
			(net "GND")
		)
		(pad "7" smd rect
			(at 0 5.100066 90)
			(size 1.8034 0.508)
			(layers "F.Cu" "F.Mask" "F.Paste")
			(net "M_E_DQS_DP<9>")
		)
		(pad "8" smd rect
			(at 0 5.94995 90)
			(size 1.8034 0.508)
			(layers "F.Cu" "F.Mask" "F.Paste")
			(net "M_E_DQS_DN<9>")
		)
		(pad "9" smd rect
			(at 0 6.800088 90)
			(size 1.8034 0.508)
			(layers "F.Cu" "F.Mask" "F.Paste")
			(net "GND")
		)
		(pad "10" smd rect
			(at 0 7.649972 90)
			(size 1.8034 0.508)
			(layers "F.Cu" "F.Mask" "F.Paste")
			(net "M_E_DQ<7>")
		)
		(pad "11" smd rect
			(at 0 8.50011 90)
			(size 1.8034 0.508)
			(layers "F.Cu" "F.Mask" "F.Paste")
			(net "GND")
		)
		(pad "12" smd rect
			(at 0 9.349994 90)
			(size 1.8034 0.508)
			(layers "F.Cu" "F.Mask" "F.Paste")
			(net "M_E_DQ<3>")
		)
		(pad "13" smd rect
			(at 0 10.199878 90)
			(size 1.8034 0.508)
			(layers "F.Cu" "F.Mask" "F.Paste")
			(net "GND")
		)
		(pad "14" smd rect
			(at 0 11.050016 90)
			(size 1.8034 0.508)
			(layers "F.Cu" "F.Mask" "F.Paste")
			(net "M_E_DQ<13>")
		)
		(pad "15" smd rect
			(at 0 11.8999 90)
			(size 1.8034 0.508)
			(layers "F.Cu" "F.Mask" "F.Paste")
			(net "GND")
		)
		(pad "16" smd rect
			(at 0 12.750038 90)
			(size 1.8034 0.508)
			(layers "F.Cu" "F.Mask" "F.Paste")
			(net "M_E_DQ<9>")
		)
		(pad "17" smd rect
			(at 0 13.599922 90)
			(size 1.8034 0.508)
			(layers "F.Cu" "F.Mask" "F.Paste")
			(net "GND")
		)
		(pad "18" smd rect
			(at 0 14.45006 90)
			(size 1.8034 0.508)
			(layers "F.Cu" "F.Mask" "F.Paste")
			(net "M_E_DQS_DP<10>")
		)
		(pad "19" smd rect
			(at 0 15.299944 90)
			(size 1.8034 0.508)
			(layers "F.Cu" "F.Mask" "F.Paste")
			(net "M_E_DQS_DN<10>")
		)
		(pad "20" smd rect
			(at 0 16.150082 90)
			(size 1.8034 0.508)
			(layers "F.Cu" "F.Mask" "F.Paste")
			(net "GND")
		)
		(pad "21" smd rect
			(at 0 16.999966 90)
			(size 1.8034 0.508)
			(layers "F.Cu" "F.Mask" "F.Paste")
			(net "M_E_DQ<15>")
		)
		(pad "22" smd rect
			(at 0 17.850104 90)
			(size 1.8034 0.508)
			(layers "F.Cu" "F.Mask" "F.Paste")
			(net "GND")
		)
		(pad "23" smd rect
			(at 0 18.699988 90)
			(size 1.8034 0.508)
			(layers "F.Cu" "F.Mask" "F.Paste")
			(net "M_E_DQ<11>")
		)
		(pad "24" smd rect
			(at 0 19.550126 90)
			(size 1.8034 0.508)
			(layers "F.Cu" "F.Mask" "F.Paste")
			(net "GND")
		)
		(pad "25" smd rect
			(at 0 20.40001 90)
			(size 1.8034 0.508)
			(layers "F.Cu" "F.Mask" "F.Paste")
			(net "M_E_DQ<21>")
		)
		(pad "26" smd rect
			(at 0 21.249894 90)
			(size 1.8034 0.508)
			(layers "F.Cu" "F.Mask" "F.Paste")
			(net "GND")
		)
		(pad "27" smd rect
			(at 0 22.100032 90)
			(size 1.8034 0.508)
			(layers "F.Cu" "F.Mask" "F.Paste")
			(net "M_E_DQ<17>")
		)
		(pad "28" smd rect
			(at 0 22.949916 90)
			(size 1.8034 0.508)
			(layers "F.Cu" "F.Mask" "F.Paste")
			(net "GND")
		)
		(pad "29" smd rect
			(at 0 23.800054 90)
			(size 1.8034 0.508)
			(layers "F.Cu" "F.Mask" "F.Paste")
			(net "M_E_DQS_DP<11>")
		)
		(pad "30" smd rect
			(at 0 24.649938 90)
			(size 1.8034 0.508)
			(layers "F.Cu" "F.Mask" "F.Paste")
			(net "M_E_DQS_DN<11>")
		)
		(pad "31" smd rect
			(at 0 25.500076 90)
			(size 1.8034 0.508)
			(layers "F.Cu" "F.Mask" "F.Paste")
			(net "GND")
		)
		(pad "32" smd rect
			(at 0 26.34996 90)
			(size 1.8034 0.508)
			(layers "F.Cu" "F.Mask" "F.Paste")
			(net "M_E_DQ<23>")
		)
		(pad "33" smd rect
			(at 0 27.200098 90)
			(size 1.8034 0.508)
			(layers "F.Cu" "F.Mask" "F.Paste")
			(net "GND")
		)
		(pad "34" smd rect
			(at 0 28.049982 90)
			(size 1.8034 0.508)
			(layers "F.Cu" "F.Mask" "F.Paste")
			(net "M_E_DQ<19>")
		)
		(pad "35" smd rect
			(at 0 28.90012 90)
			(size 1.8034 0.508)
			(layers "F.Cu" "F.Mask" "F.Paste")
			(net "GND")
		)
		(pad "36" smd rect
			(at 0 29.750004 90)
			(size 1.8034 0.508)
			(layers "F.Cu" "F.Mask" "F.Paste")
			(net "M_E_DQ<29>")
		)
		(pad "37" smd rect
			(at 0 30.599888 90)
			(size 1.8034 0.508)
			(layers "F.Cu" "F.Mask" "F.Paste")
			(net "GND")
		)
		(pad "38" smd rect
			(at 0 31.450026 90)
			(size 1.8034 0.508)
			(layers "F.Cu" "F.Mask" "F.Paste")
			(net "M_E_DQ<25>")
		)
		(pad "39" smd rect
			(at 0 32.29991 90)
			(size 1.8034 0.508)
			(layers "F.Cu" "F.Mask" "F.Paste")
			(net "GND")
		)
		(pad "40" smd rect
			(at 0 33.150048 90)
			(size 1.8034 0.508)
			(layers "F.Cu" "F.Mask" "F.Paste")
			(net "M_E_DQS_DP<12>")
		)
		(pad "41" smd rect
			(at 0 33.999932 90)
			(size 1.8034 0.508)
			(layers "F.Cu" "F.Mask" "F.Paste")
			(net "M_E_DQS_DN<12>")
		)
		(pad "42" smd rect
			(at 0 34.85007 90)
			(size 1.8034 0.508)
			(layers "F.Cu" "F.Mask" "F.Paste")
			(net "GND")
		)
		(pad "43" smd rect
			(at 0 35.699954 90)
			(size 1.8034 0.508)
			(layers "F.Cu" "F.Mask" "F.Paste")
			(net "M_E_DQ<31>")
		)
		(pad "44" smd rect
			(at 0 36.550092 90)
			(size 1.8034 0.508)
			(layers "F.Cu" "F.Mask" "F.Paste")
			(net "GND")
		)
		(pad "45" smd rect
			(at 0 37.399976 90)
			(size 1.8034 0.508)
			(layers "F.Cu" "F.Mask" "F.Paste")
			(net "M_E_DQ<27>")
		)
		(pad "46" smd rect
			(at 0 38.250114 90)
			(size 1.8034 0.508)
			(layers "F.Cu" "F.Mask" "F.Paste")
			(net "GND")
		)
		(pad "47" smd rect
			(at 0 39.099998 90)
			(size 1.8034 0.508)
			(layers "F.Cu" "F.Mask" "F.Paste")
			(net "M_E_ECC<5>")
		)
		(pad "48" smd rect
			(at 0 39.949882 90)
			(size 1.8034 0.508)
			(layers "F.Cu" "F.Mask" "F.Paste")
			(net "GND")
		)
		(pad "49" smd rect
			(at 0 40.80002 90)
			(size 1.8034 0.508)
			(layers "F.Cu" "F.Mask" "F.Paste")
			(net "M_E_ECC<1>")
		)
		(pad "50" smd rect
			(at 0 41.649904 90)
			(size 1.8034 0.508)
			(layers "F.Cu" "F.Mask" "F.Paste")
			(net "GND")
		)
		(pad "51" smd rect
			(at 0 42.500042 90)
			(size 1.8034 0.508)
			(layers "F.Cu" "F.Mask" "F.Paste")
			(net "M_E_DQS_DP<17>")
		)
		(pad "52" smd rect
			(at 0 43.349926 90)
			(size 1.8034 0.508)
			(layers "F.Cu" "F.Mask" "F.Paste")
			(net "M_E_DQS_DN<17>")
		)
		(pad "53" smd rect
			(at 0 44.200064 90)
			(size 1.8034 0.508)
			(layers "F.Cu" "F.Mask" "F.Paste")
			(net "GND")
		)
		(pad "54" smd rect
			(at 0 45.049948 90)
			(size 1.8034 0.508)
			(layers "F.Cu" "F.Mask" "F.Paste")
			(net "M_E_ECC<7>")
		)
		(pad "55" smd rect
			(at 0 45.900086 90)
			(size 1.8034 0.508)
			(layers "F.Cu" "F.Mask" "F.Paste")
			(net "GND")
		)
		(pad "56" smd rect
			(at 0 46.74997 90)
			(size 1.8034 0.508)
			(layers "F.Cu" "F.Mask" "F.Paste")
			(net "M_E_ECC<3>")
		)
		(pad "57" smd rect
			(at 0 47.600108 90)
			(size 1.8034 0.508)
			(layers "F.Cu" "F.Mask" "F.Paste")
			(net "GND")
		)
		(pad "58" smd rect
			(at 0 48.449992 90)
			(size 1.8034 0.508)
			(layers "F.Cu" "F.Mask" "F.Paste")
			(net "M_DEF_RST_N")
		)
		(pad "59" smd rect
			(at 0 49.299876 90)
			(size 1.8034 0.508)
			(layers "F.Cu" "F.Mask" "F.Paste")
			(net "PVDDQ_DEF")
		)
		(pad "60" smd rect
			(at 0 50.150014 90)
			(size 1.8034 0.508)
			(layers "F.Cu" "F.Mask" "F.Paste")
			(net "M_E_CKE<0>")
		)
		(pad "61" smd rect
			(at 0 50.999898 90)
			(size 1.8034 0.508)
			(layers "F.Cu" "F.Mask" "F.Paste")
			(net "PVDDQ_DEF")
		)
		(pad "62" smd rect
			(at 0 51.850036 90)
			(size 1.8034 0.508)
			(layers "F.Cu" "F.Mask" "F.Paste")
			(net "M_E_ACT_N")
		)
		(pad "63" smd rect
			(at 0 52.69992 90)
			(size 1.8034 0.508)
			(layers "F.Cu" "F.Mask" "F.Paste")
			(net "M_E_BG<0>")
		)
		(pad "64" smd rect
			(at 0 53.550058 90)
			(size 1.8034 0.508)
			(layers "F.Cu" "F.Mask" "F.Paste")
			(net "PVDDQ_DEF")
		)
		(pad "65" smd rect
			(at 0 54.399942 90)
			(size 1.8034 0.508)
			(layers "F.Cu" "F.Mask" "F.Paste")
			(net "M_E_MA<12>")
		)
		(pad "66" smd rect
			(at 0 55.25008 90)
			(size 1.8034 0.508)
			(layers "F.Cu" "F.Mask" "F.Paste")
			(net "M_E_MA<9>")
		)
		(pad "67" smd rect
			(at 0 56.099964 90)
			(size 1.8034 0.508)
			(layers "F.Cu" "F.Mask" "F.Paste")
			(net "PVDDQ_DEF")
		)
		(pad "68" smd rect
			(at 0 56.950102 90)
			(size 1.8034 0.508)
			(layers "F.Cu" "F.Mask" "F.Paste")
			(net "M_E_MA<8>")
		)
		(pad "69" smd rect
			(at 0 57.799986 90)
			(size 1.8034 0.508)
			(layers "F.Cu" "F.Mask" "F.Paste")
			(net "M_E_MA<6>")
		)
		(pad "70" smd rect
			(at 0 58.650124 90)
			(size 1.8034 0.508)
			(layers "F.Cu" "F.Mask" "F.Paste")
			(net "PVDDQ_DEF")
		)
		(pad "71" smd rect
			(at 0 59.500008 90)
			(size 1.8034 0.508)
			(layers "F.Cu" "F.Mask" "F.Paste")
			(net "M_E_MA<3>")
		)
		(pad "72" smd rect
			(at 0 60.349892 90)
			(size 1.8034 0.508)
			(layers "F.Cu" "F.Mask" "F.Paste")
			(net "M_E_MA<1>")
		)
		(pad "73" smd rect
			(at 0 61.20003 90)
			(size 1.8034 0.508)
			(layers "F.Cu" "F.Mask" "F.Paste")
			(net "PVDDQ_DEF")
		)
		(pad "74" smd rect
			(at 0 62.049914 90)
			(size 1.8034 0.508)
			(layers "F.Cu" "F.Mask" "F.Paste")
			(net "M_E_CLK_DP<0>")
		)
		(pad "75" smd rect
			(at 0 62.900052 90)
			(size 1.8034 0.508)
			(layers "F.Cu" "F.Mask" "F.Paste")
			(net "M_E_CLK_DN<0>")
		)
		(pad "76" smd rect
			(at 0 63.749936 90)
			(size 1.8034 0.508)
			(layers "F.Cu" "F.Mask" "F.Paste")
			(net "PVDDQ_DEF")
		)
		(pad "77" smd rect
			(at 0 64.600074 90)
			(size 1.8034 0.508)
			(layers "F.Cu" "F.Mask" "F.Paste")
			(net "PVTT_DEF")
		)
		(pad "78" smd rect
			(at 0 70.550024 90)
			(size 1.8034 0.508)
			(layers "F.Cu" "F.Mask" "F.Paste")
			(net "FM_DIMM_EVENT_COD_N")
		)
		(pad "79" smd rect
			(at 0 71.399908 90)
			(size 1.8034 0.508)
			(layers "F.Cu" "F.Mask" "F.Paste")
			(net "M_E_MA<0>")
		)
		(pad "80" smd rect
			(at 0 72.250046 90)
			(size 1.8034 0.508)
			(layers "F.Cu" "F.Mask" "F.Paste")
			(net "PVDDQ_DEF")
		)
		(pad "81" smd rect
			(at 0 73.09993 90)
			(size 1.8034 0.508)
			(layers "F.Cu" "F.Mask" "F.Paste")
			(net "M_E_BA<0>")
		)
		(pad "82" smd rect
			(at 0 73.950068 90)
			(size 1.8034 0.508)
			(layers "F.Cu" "F.Mask" "F.Paste")
			(net "M_E_MA<16>")
		)
		(pad "83" smd rect
			(at 0 74.799952 90)
			(size 1.8034 0.508)
			(layers "F.Cu" "F.Mask" "F.Paste")
			(net "PVDDQ_DEF")
		)
		(pad "84" smd rect
			(at 0 75.65009 90)
			(size 1.8034 0.508)
			(layers "F.Cu" "F.Mask" "F.Paste")
			(net "M_E_CS_N<0>")
		)
		(pad "85" smd rect
			(at 0 76.499974 90)
			(size 1.8034 0.508)
			(layers "F.Cu" "F.Mask" "F.Paste")
			(net "PVDDQ_DEF")
		)
		(pad "86" smd rect
			(at 0 77.350112 90)
			(size 1.8034 0.508)
			(layers "F.Cu" "F.Mask" "F.Paste")
			(net "M_E_MA<15>")
		)
		(pad "87" smd rect
			(at 0 78.199996 90)
			(size 1.8034 0.508)
			(layers "F.Cu" "F.Mask" "F.Paste")
			(net "M_E_ODT<0>")
		)
		(pad "88" smd rect
			(at 0 79.04988 90)
			(size 1.8034 0.508)
			(layers "F.Cu" "F.Mask" "F.Paste")
			(net "PVDDQ_DEF")
		)
		(pad "89" smd rect
			(at 0 79.900018 90)
			(size 1.8034 0.508)
			(layers "F.Cu" "F.Mask" "F.Paste")
			(net "M_E_CS_N<1>")
		)
		(pad "90" smd rect
			(at 0 80.749902 90)
			(size 1.8034 0.508)
			(layers "F.Cu" "F.Mask" "F.Paste")
			(net "PVDDQ_DEF")
		)
		(pad "91" smd rect
			(at 0 81.60004 90)
			(size 1.8034 0.508)
			(layers "F.Cu" "F.Mask" "F.Paste")
			(net "M_E_ODT<1>")
		)
		(pad "92" smd rect
			(at 0 82.449924 90)
			(size 1.8034 0.508)
			(layers "F.Cu" "F.Mask" "F.Paste")
			(net "PVDDQ_DEF")
		)
		(pad "93" smd rect
			(at 0 83.300062 90)
			(size 1.8034 0.508)
			(layers "F.Cu" "F.Mask" "F.Paste")
			(net "M_E_CS_N<2>")
		)
		(pad "94" smd rect
			(at 0 84.149946 90)
			(size 1.8034 0.508)
			(layers "F.Cu" "F.Mask" "F.Paste")
			(net "GND")
		)
		(pad "95" smd rect
			(at 0 85.000084 90)
			(size 1.8034 0.508)
			(layers "F.Cu" "F.Mask" "F.Paste")
			(net "M_E_DQ<37>")
		)
		(pad "96" smd rect
			(at 0 85.849968 90)
			(size 1.8034 0.508)
			(layers "F.Cu" "F.Mask" "F.Paste")
			(net "GND")
		)
		(pad "97" smd rect
			(at 0 86.700106 90)
			(size 1.8034 0.508)
			(layers "F.Cu" "F.Mask" "F.Paste")
			(net "M_E_DQ<33>")
		)
		(pad "98" smd rect
			(at 0 87.54999 90)
			(size 1.8034 0.508)
			(layers "F.Cu" "F.Mask" "F.Paste")
			(net "GND")
		)
		(pad "99" smd rect
			(at 0 88.399874 90)
			(size 1.8034 0.508)
			(layers "F.Cu" "F.Mask" "F.Paste")
			(net "M_E_DQS_DP<13>")
		)
		(pad "100" smd rect
			(at 0 89.250012 90)
			(size 1.8034 0.508)
			(layers "F.Cu" "F.Mask" "F.Paste")
			(net "M_E_DQS_DN<13>")
		)
		(pad "101" smd rect
			(at 0 90.099896 90)
			(size 1.8034 0.508)
			(layers "F.Cu" "F.Mask" "F.Paste")
			(net "GND")
		)
		(pad "102" smd rect
			(at 0 90.950034 90)
			(size 1.8034 0.508)
			(layers "F.Cu" "F.Mask" "F.Paste")
			(net "M_E_DQ<39>")
		)
		(pad "103" smd rect
			(at 0 91.799918 90)
			(size 1.8034 0.508)
			(layers "F.Cu" "F.Mask" "F.Paste")
			(net "GND")
		)
		(pad "104" smd rect
			(at 0 92.650056 90)
			(size 1.8034 0.508)
			(layers "F.Cu" "F.Mask" "F.Paste")
			(net "M_E_DQ<35>")
		)
		(pad "105" smd rect
			(at 0 93.49994 90)
			(size 1.8034 0.508)
			(layers "F.Cu" "F.Mask" "F.Paste")
			(net "GND")
		)
		(pad "106" smd rect
			(at 0 94.350078 90)
			(size 1.8034 0.508)
			(layers "F.Cu" "F.Mask" "F.Paste")
			(net "M_E_DQ<45>")
		)
		(pad "107" smd rect
			(at 0 95.199962 90)
			(size 1.8034 0.508)
			(layers "F.Cu" "F.Mask" "F.Paste")
			(net "GND")
		)
		(pad "108" smd rect
			(at 0 96.0501 90)
			(size 1.8034 0.508)
			(layers "F.Cu" "F.Mask" "F.Paste")
			(net "M_E_DQ<41>")
		)
		(pad "109" smd rect
			(at 0 96.899984 90)
			(size 1.8034 0.508)
			(layers "F.Cu" "F.Mask" "F.Paste")
			(net "GND")
		)
		(pad "110" smd rect
			(at 0 97.750122 90)
			(size 1.8034 0.508)
			(layers "F.Cu" "F.Mask" "F.Paste")
			(net "M_E_DQS_DP<14>")
		)
		(pad "111" smd rect
			(at 0 98.600006 90)
			(size 1.8034 0.508)
			(layers "F.Cu" "F.Mask" "F.Paste")
			(net "M_E_DQS_DN<14>")
		)
		(pad "112" smd rect
			(at 0 99.44989 90)
			(size 1.8034 0.508)
			(layers "F.Cu" "F.Mask" "F.Paste")
			(net "GND")
		)
		(pad "113" smd rect
			(at 0 100.300028 90)
			(size 1.8034 0.508)
			(layers "F.Cu" "F.Mask" "F.Paste")
			(net "M_E_DQ<47>")
		)
		(pad "114" smd rect
			(at 0 101.149912 90)
			(size 1.8034 0.508)
			(layers "F.Cu" "F.Mask" "F.Paste")
			(net "GND")
		)
		(pad "115" smd rect
			(at 0 102.00005 90)
			(size 1.8034 0.508)
			(layers "F.Cu" "F.Mask" "F.Paste")
			(net "M_E_DQ<43>")
		)
		(pad "116" smd rect
			(at 0 102.849934 90)
			(size 1.8034 0.508)
			(layers "F.Cu" "F.Mask" "F.Paste")
			(net "GND")
		)
		(pad "117" smd rect
			(at 0 103.700072 90)
			(size 1.8034 0.508)
			(layers "F.Cu" "F.Mask" "F.Paste")
			(net "M_E_DQ<53>")
		)
		(pad "118" smd rect
			(at 0 104.549956 90)
			(size 1.8034 0.508)
			(layers "F.Cu" "F.Mask" "F.Paste")
			(net "GND")
		)
		(pad "119" smd rect
			(at 0 105.400094 90)
			(size 1.8034 0.508)
			(layers "F.Cu" "F.Mask" "F.Paste")
			(net "M_E_DQ<49>")
		)
		(pad "120" smd rect
			(at 0 106.249978 90)
			(size 1.8034 0.508)
			(layers "F.Cu" "F.Mask" "F.Paste")
			(net "GND")
		)
		(pad "121" smd rect
			(at 0 107.100116 90)
			(size 1.8034 0.508)
			(layers "F.Cu" "F.Mask" "F.Paste")
			(net "M_E_DQS_DP<15>")
		)
		(pad "122" smd rect
			(at 0 107.95 90)
			(size 1.8034 0.508)
			(layers "F.Cu" "F.Mask" "F.Paste")
			(net "M_E_DQS_DN<15>")
		)
		(pad "123" smd rect
			(at 0 108.799884 90)
			(size 1.8034 0.508)
			(layers "F.Cu" "F.Mask" "F.Paste")
			(net "GND")
		)
		(pad "124" smd rect
			(at 0 109.650022 90)
			(size 1.8034 0.508)
			(layers "F.Cu" "F.Mask" "F.Paste")
			(net "M_E_DQ<55>")
		)
		(pad "125" smd rect
			(at 0 110.499906 90)
			(size 1.8034 0.508)
			(layers "F.Cu" "F.Mask" "F.Paste")
			(net "GND")
		)
		(pad "126" smd rect
			(at 0 111.350044 90)
			(size 1.8034 0.508)
			(layers "F.Cu" "F.Mask" "F.Paste")
			(net "M_E_DQ<51>")
		)
		(pad "127" smd rect
			(at 0 112.199928 90)
			(size 1.8034 0.508)
			(layers "F.Cu" "F.Mask" "F.Paste")
			(net "GND")
		)
		(pad "128" smd rect
			(at 0 113.050066 90)
			(size 1.8034 0.508)
			(layers "F.Cu" "F.Mask" "F.Paste")
			(net "M_E_DQ<61>")
		)
		(pad "129" smd rect
			(at 0 113.89995 90)
			(size 1.8034 0.508)
			(layers "F.Cu" "F.Mask" "F.Paste")
			(net "GND")
		)
		(pad "130" smd rect
			(at 0 114.750088 90)
			(size 1.8034 0.508)
			(layers "F.Cu" "F.Mask" "F.Paste")
			(net "M_E_DQ<57>")
		)
		(pad "131" smd rect
			(at 0 115.599972 90)
			(size 1.8034 0.508)
			(layers "F.Cu" "F.Mask" "F.Paste")
			(net "GND")
		)
		(pad "132" smd rect
			(at 0 116.45011 90)
			(size 1.8034 0.508)
			(layers "F.Cu" "F.Mask" "F.Paste")
			(net "M_E_DQS_DP<16>")
		)
		(pad "133" smd rect
			(at 0 117.299994 90)
			(size 1.8034 0.508)
			(layers "F.Cu" "F.Mask" "F.Paste")
			(net "M_E_DQS_DN<16>")
		)
		(pad "134" smd rect
			(at 0 118.149878 90)
			(size 1.8034 0.508)
			(layers "F.Cu" "F.Mask" "F.Paste")
			(net "GND")
		)
		(pad "135" smd rect
			(at 0 119.000016 90)
			(size 1.8034 0.508)
			(layers "F.Cu" "F.Mask" "F.Paste")
			(net "M_E_DQ<63>")
		)
		(pad "136" smd rect
			(at 0 119.8499 90)
			(size 1.8034 0.508)
			(layers "F.Cu" "F.Mask" "F.Paste")
			(net "GND")
		)
		(pad "137" smd rect
			(at 0 120.700038 90)
			(size 1.8034 0.508)
			(layers "F.Cu" "F.Mask" "F.Paste")
			(net "M_E_DQ<59>")
		)
		(pad "138" smd rect
			(at 0 121.549922 90)
			(size 1.8034 0.508)
			(layers "F.Cu" "F.Mask" "F.Paste")
			(net "GND")
		)
		(pad "139" smd rect
			(at 0 122.40006 90)
			(size 1.8034 0.508)
			(layers "F.Cu" "F.Mask" "F.Paste")
			(net "GND")
		)
		(pad "140" smd rect
			(at 0 123.249944 90)
			(size 1.8034 0.508)
			(layers "F.Cu" "F.Mask" "F.Paste")
			(net "PVPP_DEF")
		)
		(pad "141" smd rect
			(at 0 124.100082 90)
			(size 1.8034 0.508)
			(layers "F.Cu" "F.Mask" "F.Paste")
			(net "SMB_DDR_DEF_VPP_SCL")
		)
		(pad "142" smd rect
			(at 0 124.949966 90)
			(size 1.8034 0.508)
			(layers "F.Cu" "F.Mask" "F.Paste")
			(net "PVPP_DEF")
		)
		(pad "143" smd rect
			(at 0 125.800104 90)
			(size 1.8034 0.508)
			(layers "F.Cu" "F.Mask" "F.Paste")
			(net "PVPP_DEF")
		)
		(pad "144" smd rect
			(at 0 126.649988 90)
			(size 1.8034 0.508)
			(layers "F.Cu" "F.Mask" "F.Paste")
			(net "TP_CH_E_DIMM_E0_RFU_2")
		)
		(pad "145" smd rect
			(at 4.59994 0 90)
			(size 1.8034 0.508)
			(layers "F.Cu" "F.Mask" "F.Paste")
			(net "P12V_NVDIMM_DEF")
		)
		(pad "146" smd rect
			(at 4.59994 0.849884 90)
			(size 1.8034 0.508)
			(layers "F.Cu" "F.Mask" "F.Paste")
			(net "M_E_VREF")
		)
		(pad "147" smd rect
			(at 4.59994 1.700022 90)
			(size 1.8034 0.508)
			(layers "F.Cu" "F.Mask" "F.Paste")
			(net "GND")
		)
		(pad "148" smd rect
			(at 4.59994 2.549906 90)
			(size 1.8034 0.508)
			(layers "F.Cu" "F.Mask" "F.Paste")
			(net "M_E_DQ<4>")
		)
		(pad "149" smd rect
			(at 4.59994 3.400044 90)
			(size 1.8034 0.508)
			(layers "F.Cu" "F.Mask" "F.Paste")
			(net "GND")
		)
		(pad "150" smd rect
			(at 4.59994 4.249928 90)
			(size 1.8034 0.508)
			(layers "F.Cu" "F.Mask" "F.Paste")
			(net "M_E_DQ<0>")
		)
		(pad "151" smd rect
			(at 4.59994 5.100066 90)
			(size 1.8034 0.508)
			(layers "F.Cu" "F.Mask" "F.Paste")
			(net "GND")
		)
		(pad "152" smd rect
			(at 4.59994 5.94995 90)
			(size 1.8034 0.508)
			(layers "F.Cu" "F.Mask" "F.Paste")
			(net "M_E_DQS_DN<0>")
		)
		(pad "153" smd rect
			(at 4.59994 6.800088 90)
			(size 1.8034 0.508)
			(layers "F.Cu" "F.Mask" "F.Paste")
			(net "M_E_DQS_DP<0>")
		)
		(pad "154" smd rect
			(at 4.59994 7.649972 90)
			(size 1.8034 0.508)
			(layers "F.Cu" "F.Mask" "F.Paste")
			(net "GND")
		)
		(pad "155" smd rect
			(at 4.59994 8.50011 90)
			(size 1.8034 0.508)
			(layers "F.Cu" "F.Mask" "F.Paste")
			(net "M_E_DQ<6>")
		)
		(pad "156" smd rect
			(at 4.59994 9.349994 90)
			(size 1.8034 0.508)
			(layers "F.Cu" "F.Mask" "F.Paste")
			(net "GND")
		)
		(pad "157" smd rect
			(at 4.59994 10.199878 90)
			(size 1.8034 0.508)
			(layers "F.Cu" "F.Mask" "F.Paste")
			(net "M_E_DQ<2>")
		)
		(pad "158" smd rect
			(at 4.59994 11.050016 90)
			(size 1.8034 0.508)
			(layers "F.Cu" "F.Mask" "F.Paste")
			(net "GND")
		)
		(pad "159" smd rect
			(at 4.59994 11.8999 90)
			(size 1.8034 0.508)
			(layers "F.Cu" "F.Mask" "F.Paste")
			(net "M_E_DQ<12>")
		)
		(pad "160" smd rect
			(at 4.59994 12.750038 90)
			(size 1.8034 0.508)
			(layers "F.Cu" "F.Mask" "F.Paste")
			(net "GND")
		)
		(pad "161" smd rect
			(at 4.59994 13.599922 90)
			(size 1.8034 0.508)
			(layers "F.Cu" "F.Mask" "F.Paste")
			(net "M_E_DQ<8>")
		)
		(pad "162" smd rect
			(at 4.59994 14.45006 90)
			(size 1.8034 0.508)
			(layers "F.Cu" "F.Mask" "F.Paste")
			(net "GND")
		)
		(pad "163" smd rect
			(at 4.59994 15.299944 90)
			(size 1.8034 0.508)
			(layers "F.Cu" "F.Mask" "F.Paste")
			(net "M_E_DQS_DN<1>")
		)
		(pad "164" smd rect
			(at 4.59994 16.150082 90)
			(size 1.8034 0.508)
			(layers "F.Cu" "F.Mask" "F.Paste")
			(net "M_E_DQS_DP<1>")
		)
		(pad "165" smd rect
			(at 4.59994 16.999966 90)
			(size 1.8034 0.508)
			(layers "F.Cu" "F.Mask" "F.Paste")
			(net "GND")
		)
		(pad "166" smd rect
			(at 4.59994 17.850104 90)
			(size 1.8034 0.508)
			(layers "F.Cu" "F.Mask" "F.Paste")
			(net "M_E_DQ<14>")
		)
		(pad "167" smd rect
			(at 4.59994 18.699988 90)
			(size 1.8034 0.508)
			(layers "F.Cu" "F.Mask" "F.Paste")
			(net "GND")
		)
		(pad "168" smd rect
			(at 4.59994 19.550126 90)
			(size 1.8034 0.508)
			(layers "F.Cu" "F.Mask" "F.Paste")
			(net "M_E_DQ<10>")
		)
		(pad "169" smd rect
			(at 4.59994 20.40001 90)
			(size 1.8034 0.508)
			(layers "F.Cu" "F.Mask" "F.Paste")
			(net "GND")
		)
		(pad "170" smd rect
			(at 4.59994 21.249894 90)
			(size 1.8034 0.508)
			(layers "F.Cu" "F.Mask" "F.Paste")
			(net "M_E_DQ<20>")
		)
		(pad "171" smd rect
			(at 4.59994 22.100032 90)
			(size 1.8034 0.508)
			(layers "F.Cu" "F.Mask" "F.Paste")
			(net "GND")
		)
		(pad "172" smd rect
			(at 4.59994 22.949916 90)
			(size 1.8034 0.508)
			(layers "F.Cu" "F.Mask" "F.Paste")
			(net "M_E_DQ<16>")
		)
		(pad "173" smd rect
			(at 4.59994 23.800054 90)
			(size 1.8034 0.508)
			(layers "F.Cu" "F.Mask" "F.Paste")
			(net "GND")
		)
		(pad "174" smd rect
			(at 4.59994 24.649938 90)
			(size 1.8034 0.508)
			(layers "F.Cu" "F.Mask" "F.Paste")
			(net "M_E_DQS_DN<2>")
		)
		(pad "175" smd rect
			(at 4.59994 25.500076 90)
			(size 1.8034 0.508)
			(layers "F.Cu" "F.Mask" "F.Paste")
			(net "M_E_DQS_DP<2>")
		)
		(pad "176" smd rect
			(at 4.59994 26.34996 90)
			(size 1.8034 0.508)
			(layers "F.Cu" "F.Mask" "F.Paste")
			(net "GND")
		)
		(pad "177" smd rect
			(at 4.59994 27.200098 90)
			(size 1.8034 0.508)
			(layers "F.Cu" "F.Mask" "F.Paste")
			(net "M_E_DQ<22>")
		)
		(pad "178" smd rect
			(at 4.59994 28.049982 90)
			(size 1.8034 0.508)
			(layers "F.Cu" "F.Mask" "F.Paste")
			(net "GND")
		)
		(pad "179" smd rect
			(at 4.59994 28.90012 90)
			(size 1.8034 0.508)
			(layers "F.Cu" "F.Mask" "F.Paste")
			(net "M_E_DQ<18>")
		)
		(pad "180" smd rect
			(at 4.59994 29.750004 90)
			(size 1.8034 0.508)
			(layers "F.Cu" "F.Mask" "F.Paste")
			(net "GND")
		)
		(pad "181" smd rect
			(at 4.59994 30.599888 90)
			(size 1.8034 0.508)
			(layers "F.Cu" "F.Mask" "F.Paste")
			(net "M_E_DQ<28>")
		)
		(pad "182" smd rect
			(at 4.59994 31.450026 90)
			(size 1.8034 0.508)
			(layers "F.Cu" "F.Mask" "F.Paste")
			(net "GND")
		)
		(pad "183" smd rect
			(at 4.59994 32.29991 90)
			(size 1.8034 0.508)
			(layers "F.Cu" "F.Mask" "F.Paste")
			(net "M_E_DQ<24>")
		)
		(pad "184" smd rect
			(at 4.59994 33.150048 90)
			(size 1.8034 0.508)
			(layers "F.Cu" "F.Mask" "F.Paste")
			(net "GND")
		)
		(pad "185" smd rect
			(at 4.59994 33.999932 90)
			(size 1.8034 0.508)
			(layers "F.Cu" "F.Mask" "F.Paste")
			(net "M_E_DQS_DN<3>")
		)
		(pad "186" smd rect
			(at 4.59994 34.85007 90)
			(size 1.8034 0.508)
			(layers "F.Cu" "F.Mask" "F.Paste")
			(net "M_E_DQS_DP<3>")
		)
		(pad "187" smd rect
			(at 4.59994 35.699954 90)
			(size 1.8034 0.508)
			(layers "F.Cu" "F.Mask" "F.Paste")
			(net "GND")
		)
		(pad "188" smd rect
			(at 4.59994 36.550092 90)
			(size 1.8034 0.508)
			(layers "F.Cu" "F.Mask" "F.Paste")
			(net "M_E_DQ<30>")
		)
		(pad "189" smd rect
			(at 4.59994 37.399976 90)
			(size 1.8034 0.508)
			(layers "F.Cu" "F.Mask" "F.Paste")
			(net "GND")
		)
		(pad "190" smd rect
			(at 4.59994 38.250114 90)
			(size 1.8034 0.508)
			(layers "F.Cu" "F.Mask" "F.Paste")
			(net "M_E_DQ<26>")
		)
		(pad "191" smd rect
			(at 4.59994 39.099998 90)
			(size 1.8034 0.508)
			(layers "F.Cu" "F.Mask" "F.Paste")
			(net "GND")
		)
		(pad "192" smd rect
			(at 4.59994 39.949882 90)
			(size 1.8034 0.508)
			(layers "F.Cu" "F.Mask" "F.Paste")
			(net "M_E_ECC<4>")
		)
		(pad "193" smd rect
			(at 4.59994 40.80002 90)
			(size 1.8034 0.508)
			(layers "F.Cu" "F.Mask" "F.Paste")
			(net "GND")
		)
		(pad "194" smd rect
			(at 4.59994 41.649904 90)
			(size 1.8034 0.508)
			(layers "F.Cu" "F.Mask" "F.Paste")
			(net "M_E_ECC<0>")
		)
		(pad "195" smd rect
			(at 4.59994 42.500042 90)
			(size 1.8034 0.508)
			(layers "F.Cu" "F.Mask" "F.Paste")
			(net "GND")
		)
		(pad "196" smd rect
			(at 4.59994 43.349926 90)
			(size 1.8034 0.508)
			(layers "F.Cu" "F.Mask" "F.Paste")
			(net "M_E_DQS_DN<8>")
		)
		(pad "197" smd rect
			(at 4.59994 44.200064 90)
			(size 1.8034 0.508)
			(layers "F.Cu" "F.Mask" "F.Paste")
			(net "M_E_DQS_DP<8>")
		)
		(pad "198" smd rect
			(at 4.59994 45.049948 90)
			(size 1.8034 0.508)
			(layers "F.Cu" "F.Mask" "F.Paste")
			(net "GND")
		)
		(pad "199" smd rect
			(at 4.59994 45.900086 90)
			(size 1.8034 0.508)
			(layers "F.Cu" "F.Mask" "F.Paste")
			(net "M_E_ECC<6>")
		)
		(pad "200" smd rect
			(at 4.59994 46.74997 90)
			(size 1.8034 0.508)
			(layers "F.Cu" "F.Mask" "F.Paste")
			(net "GND")
		)
		(pad "201" smd rect
			(at 4.59994 47.600108 90)
			(size 1.8034 0.508)
			(layers "F.Cu" "F.Mask" "F.Paste")
			(net "M_E_ECC<2>")
		)
		(pad "202" smd rect
			(at 4.59994 48.449992 90)
			(size 1.8034 0.508)
			(layers "F.Cu" "F.Mask" "F.Paste")
			(net "GND")
		)
		(pad "203" smd rect
			(at 4.59994 49.299876 90)
			(size 1.8034 0.508)
			(layers "F.Cu" "F.Mask" "F.Paste")
			(net "M_E_CKE<1>")
		)
		(pad "204" smd rect
			(at 4.59994 50.150014 90)
			(size 1.8034 0.508)
			(layers "F.Cu" "F.Mask" "F.Paste")
			(net "PVDDQ_DEF")
		)
		(pad "205" smd rect
			(at 4.59994 50.999898 90)
			(size 1.8034 0.508)
			(layers "F.Cu" "F.Mask" "F.Paste")
			(net "TP_CH_E_DIMM_E0_RFU_0")
		)
		(pad "206" smd rect
			(at 4.59994 51.850036 90)
			(size 1.8034 0.508)
			(layers "F.Cu" "F.Mask" "F.Paste")
			(net "PVDDQ_DEF")
		)
		(pad "207" smd rect
			(at 4.59994 52.69992 90)
			(size 1.8034 0.508)
			(layers "F.Cu" "F.Mask" "F.Paste")
			(net "M_E_BG<1>")
		)
		(pad "208" smd rect
			(at 4.59994 53.550058 90)
			(size 1.8034 0.508)
			(layers "F.Cu" "F.Mask" "F.Paste")
			(net "M_E_ALERT_N")
		)
		(pad "209" smd rect
			(at 4.59994 54.399942 90)
			(size 1.8034 0.508)
			(layers "F.Cu" "F.Mask" "F.Paste")
			(net "PVDDQ_DEF")
		)
		(pad "210" smd rect
			(at 4.59994 55.25008 90)
			(size 1.8034 0.508)
			(layers "F.Cu" "F.Mask" "F.Paste")
			(net "M_E_MA<11>")
		)
		(pad "211" smd rect
			(at 4.59994 56.099964 90)
			(size 1.8034 0.508)
			(layers "F.Cu" "F.Mask" "F.Paste")
			(net "M_E_MA<7>")
		)
		(pad "212" smd rect
			(at 4.59994 56.950102 90)
			(size 1.8034 0.508)
			(layers "F.Cu" "F.Mask" "F.Paste")
			(net "PVDDQ_DEF")
		)
		(pad "213" smd rect
			(at 4.59994 57.799986 90)
			(size 1.8034 0.508)
			(layers "F.Cu" "F.Mask" "F.Paste")
			(net "M_E_MA<5>")
		)
		(pad "214" smd rect
			(at 4.59994 58.650124 90)
			(size 1.8034 0.508)
			(layers "F.Cu" "F.Mask" "F.Paste")
			(net "M_E_MA<4>")
		)
		(pad "215" smd rect
			(at 4.59994 59.500008 90)
			(size 1.8034 0.508)
			(layers "F.Cu" "F.Mask" "F.Paste")
			(net "PVDDQ_DEF")
		)
		(pad "216" smd rect
			(at 4.59994 60.349892 90)
			(size 1.8034 0.508)
			(layers "F.Cu" "F.Mask" "F.Paste")
			(net "M_E_MA<2>")
		)
		(pad "217" smd rect
			(at 4.59994 61.20003 90)
			(size 1.8034 0.508)
			(layers "F.Cu" "F.Mask" "F.Paste")
			(net "PVDDQ_DEF")
		)
		(pad "218" smd rect
			(at 4.59994 62.049914 90)
			(size 1.8034 0.508)
			(layers "F.Cu" "F.Mask" "F.Paste")
			(net "M_E_CLK_DP<1>")
		)
		(pad "219" smd rect
			(at 4.59994 62.900052 90)
			(size 1.8034 0.508)
			(layers "F.Cu" "F.Mask" "F.Paste")
			(net "M_E_CLK_DN<1>")
		)
		(pad "220" smd rect
			(at 4.59994 63.749936 90)
			(size 1.8034 0.508)
			(layers "F.Cu" "F.Mask" "F.Paste")
			(net "PVDDQ_DEF")
		)
		(pad "221" smd rect
			(at 4.59994 64.600074 90)
			(size 1.8034 0.508)
			(layers "F.Cu" "F.Mask" "F.Paste")
			(net "PVTT_DEF")
		)
		(pad "222" smd rect
			(at 4.59994 70.550024 90)
			(size 1.8034 0.508)
			(layers "F.Cu" "F.Mask" "F.Paste")
			(net "M_E_PAR")
		)
		(pad "223" smd rect
			(at 4.59994 71.399908 90)
			(size 1.8034 0.508)
			(layers "F.Cu" "F.Mask" "F.Paste")
			(net "PVDDQ_DEF")
		)
		(pad "224" smd rect
			(at 4.59994 72.250046 90)
			(size 1.8034 0.508)
			(layers "F.Cu" "F.Mask" "F.Paste")
			(net "M_E_BA<1>")
		)
		(pad "225" smd rect
			(at 4.59994 73.09993 90)
			(size 1.8034 0.508)
			(layers "F.Cu" "F.Mask" "F.Paste")
			(net "M_E_MA<10>")
		)
		(pad "226" smd rect
			(at 4.59994 73.950068 90)
			(size 1.8034 0.508)
			(layers "F.Cu" "F.Mask" "F.Paste")
			(net "PVDDQ_DEF")
		)
		(pad "227" smd rect
			(at 4.59994 74.799952 90)
			(size 1.8034 0.508)
			(layers "F.Cu" "F.Mask" "F.Paste")
			(net "TP_CH_E_DIMM_E0_RFU_1")
		)
		(pad "228" smd rect
			(at 4.59994 75.65009 90)
			(size 1.8034 0.508)
			(layers "F.Cu" "F.Mask" "F.Paste")
			(net "M_E_MA<14>")
		)
		(pad "229" smd rect
			(at 4.59994 76.499974 90)
			(size 1.8034 0.508)
			(layers "F.Cu" "F.Mask" "F.Paste")
			(net "PVDDQ_DEF")
		)
		(pad "230" smd rect
			(at 4.59994 77.350112 90)
			(size 1.8034 0.508)
			(layers "F.Cu" "F.Mask" "F.Paste")
			(net "FM_ADR_COMPLETE_DEF_N")
		)
		(pad "231" smd rect
			(at 4.59994 78.199996 90)
			(size 1.8034 0.508)
			(layers "F.Cu" "F.Mask" "F.Paste")
			(net "PVDDQ_DEF")
		)
		(pad "232" smd rect
			(at 4.59994 79.04988 90)
			(size 1.8034 0.508)
			(layers "F.Cu" "F.Mask" "F.Paste")
			(net "M_E_MA<13>")
		)
		(pad "233" smd rect
			(at 4.59994 79.900018 90)
			(size 1.8034 0.508)
			(layers "F.Cu" "F.Mask" "F.Paste")
			(net "PVDDQ_DEF")
		)
		(pad "234" smd rect
			(at 4.59994 80.749902 90)
			(size 1.8034 0.508)
			(layers "F.Cu" "F.Mask" "F.Paste")
			(net "M_E_MA<17>")
		)
		(pad "235" smd rect
			(at 4.59994 81.60004 90)
			(size 1.8034 0.508)
			(layers "F.Cu" "F.Mask" "F.Paste")
			(net "M_E_C<2>")
		)
		(pad "236" smd rect
			(at 4.59994 82.449924 90)
			(size 1.8034 0.508)
			(layers "F.Cu" "F.Mask" "F.Paste")
			(net "PVDDQ_DEF")
		)
		(pad "237" smd rect
			(at 4.59994 83.300062 90)
			(size 1.8034 0.508)
			(layers "F.Cu" "F.Mask" "F.Paste")
			(net "M_E_CS_N<3>")
		)
		(pad "238" smd rect
			(at 4.59994 84.149946 90)
			(size 1.8034 0.508)
			(layers "F.Cu" "F.Mask" "F.Paste")
			(net "GND")
		)
		(pad "239" smd rect
			(at 4.59994 85.000084 90)
			(size 1.8034 0.508)
			(layers "F.Cu" "F.Mask" "F.Paste")
			(net "GND")
		)
		(pad "240" smd rect
			(at 4.59994 85.849968 90)
			(size 1.8034 0.508)
			(layers "F.Cu" "F.Mask" "F.Paste")
			(net "M_E_DQ<36>")
		)
		(pad "241" smd rect
			(at 4.59994 86.700106 90)
			(size 1.8034 0.508)
			(layers "F.Cu" "F.Mask" "F.Paste")
			(net "GND")
		)
		(pad "242" smd rect
			(at 4.59994 87.54999 90)
			(size 1.8034 0.508)
			(layers "F.Cu" "F.Mask" "F.Paste")
			(net "M_E_DQ<32>")
		)
		(pad "243" smd rect
			(at 4.59994 88.399874 90)
			(size 1.8034 0.508)
			(layers "F.Cu" "F.Mask" "F.Paste")
			(net "GND")
		)
		(pad "244" smd rect
			(at 4.59994 89.250012 90)
			(size 1.8034 0.508)
			(layers "F.Cu" "F.Mask" "F.Paste")
			(net "M_E_DQS_DN<4>")
		)
		(pad "245" smd rect
			(at 4.59994 90.099896 90)
			(size 1.8034 0.508)
			(layers "F.Cu" "F.Mask" "F.Paste")
			(net "M_E_DQS_DP<4>")
		)
		(pad "246" smd rect
			(at 4.59994 90.950034 90)
			(size 1.8034 0.508)
			(layers "F.Cu" "F.Mask" "F.Paste")
			(net "GND")
		)
		(pad "247" smd rect
			(at 4.59994 91.799918 90)
			(size 1.8034 0.508)
			(layers "F.Cu" "F.Mask" "F.Paste")
			(net "M_E_DQ<38>")
		)
		(pad "248" smd rect
			(at 4.59994 92.650056 90)
			(size 1.8034 0.508)
			(layers "F.Cu" "F.Mask" "F.Paste")
			(net "GND")
		)
		(pad "249" smd rect
			(at 4.59994 93.49994 90)
			(size 1.8034 0.508)
			(layers "F.Cu" "F.Mask" "F.Paste")
			(net "M_E_DQ<34>")
		)
		(pad "250" smd rect
			(at 4.59994 94.350078 90)
			(size 1.8034 0.508)
			(layers "F.Cu" "F.Mask" "F.Paste")
			(net "GND")
		)
		(pad "251" smd rect
			(at 4.59994 95.199962 90)
			(size 1.8034 0.508)
			(layers "F.Cu" "F.Mask" "F.Paste")
			(net "M_E_DQ<44>")
		)
		(pad "252" smd rect
			(at 4.59994 96.0501 90)
			(size 1.8034 0.508)
			(layers "F.Cu" "F.Mask" "F.Paste")
			(net "GND")
		)
		(pad "253" smd rect
			(at 4.59994 96.899984 90)
			(size 1.8034 0.508)
			(layers "F.Cu" "F.Mask" "F.Paste")
			(net "M_E_DQ<40>")
		)
		(pad "254" smd rect
			(at 4.59994 97.750122 90)
			(size 1.8034 0.508)
			(layers "F.Cu" "F.Mask" "F.Paste")
			(net "GND")
		)
		(pad "255" smd rect
			(at 4.59994 98.600006 90)
			(size 1.8034 0.508)
			(layers "F.Cu" "F.Mask" "F.Paste")
			(net "M_E_DQS_DN<5>")
		)
		(pad "256" smd rect
			(at 4.59994 99.44989 90)
			(size 1.8034 0.508)
			(layers "F.Cu" "F.Mask" "F.Paste")
			(net "M_E_DQS_DP<5>")
		)
		(pad "257" smd rect
			(at 4.59994 100.300028 90)
			(size 1.8034 0.508)
			(layers "F.Cu" "F.Mask" "F.Paste")
			(net "GND")
		)
		(pad "258" smd rect
			(at 4.59994 101.149912 90)
			(size 1.8034 0.508)
			(layers "F.Cu" "F.Mask" "F.Paste")
			(net "M_E_DQ<46>")
		)
		(pad "259" smd rect
			(at 4.59994 102.00005 90)
			(size 1.8034 0.508)
			(layers "F.Cu" "F.Mask" "F.Paste")
			(net "GND")
		)
		(pad "260" smd rect
			(at 4.59994 102.849934 90)
			(size 1.8034 0.508)
			(layers "F.Cu" "F.Mask" "F.Paste")
			(net "M_E_DQ<42>")
		)
		(pad "261" smd rect
			(at 4.59994 103.700072 90)
			(size 1.8034 0.508)
			(layers "F.Cu" "F.Mask" "F.Paste")
			(net "GND")
		)
		(pad "262" smd rect
			(at 4.59994 104.549956 90)
			(size 1.8034 0.508)
			(layers "F.Cu" "F.Mask" "F.Paste")
			(net "M_E_DQ<52>")
		)
		(pad "263" smd rect
			(at 4.59994 105.400094 90)
			(size 1.8034 0.508)
			(layers "F.Cu" "F.Mask" "F.Paste")
			(net "GND")
		)
		(pad "264" smd rect
			(at 4.59994 106.249978 90)
			(size 1.8034 0.508)
			(layers "F.Cu" "F.Mask" "F.Paste")
			(net "M_E_DQ<48>")
		)
		(pad "265" smd rect
			(at 4.59994 107.100116 90)
			(size 1.8034 0.508)
			(layers "F.Cu" "F.Mask" "F.Paste")
			(net "GND")
		)
		(pad "266" smd rect
			(at 4.59994 107.95 90)
			(size 1.8034 0.508)
			(layers "F.Cu" "F.Mask" "F.Paste")
			(net "M_E_DQS_DN<6>")
		)
		(pad "267" smd rect
			(at 4.59994 108.799884 90)
			(size 1.8034 0.508)
			(layers "F.Cu" "F.Mask" "F.Paste")
			(net "M_E_DQS_DP<6>")
		)
		(pad "268" smd rect
			(at 4.59994 109.650022 90)
			(size 1.8034 0.508)
			(layers "F.Cu" "F.Mask" "F.Paste")
			(net "GND")
		)
		(pad "269" smd rect
			(at 4.59994 110.499906 90)
			(size 1.8034 0.508)
			(layers "F.Cu" "F.Mask" "F.Paste")
			(net "M_E_DQ<54>")
		)
		(pad "270" smd rect
			(at 4.59994 111.350044 90)
			(size 1.8034 0.508)
			(layers "F.Cu" "F.Mask" "F.Paste")
			(net "GND")
		)
		(pad "271" smd rect
			(at 4.59994 112.199928 90)
			(size 1.8034 0.508)
			(layers "F.Cu" "F.Mask" "F.Paste")
			(net "M_E_DQ<50>")
		)
		(pad "272" smd rect
			(at 4.59994 113.050066 90)
			(size 1.8034 0.508)
			(layers "F.Cu" "F.Mask" "F.Paste")
			(net "GND")
		)
		(pad "273" smd rect
			(at 4.59994 113.89995 90)
			(size 1.8034 0.508)
			(layers "F.Cu" "F.Mask" "F.Paste")
			(net "M_E_DQ<60>")
		)
		(pad "274" smd rect
			(at 4.59994 114.750088 90)
			(size 1.8034 0.508)
			(layers "F.Cu" "F.Mask" "F.Paste")
			(net "GND")
		)
		(pad "275" smd rect
			(at 4.59994 115.599972 90)
			(size 1.8034 0.508)
			(layers "F.Cu" "F.Mask" "F.Paste")
			(net "M_E_DQ<56>")
		)
		(pad "276" smd rect
			(at 4.59994 116.45011 90)
			(size 1.8034 0.508)
			(layers "F.Cu" "F.Mask" "F.Paste")
			(net "GND")
		)
		(pad "277" smd rect
			(at 4.59994 117.299994 90)
			(size 1.8034 0.508)
			(layers "F.Cu" "F.Mask" "F.Paste")
			(net "M_E_DQS_DN<7>")
		)
		(pad "278" smd rect
			(at 4.59994 118.149878 90)
			(size 1.8034 0.508)
			(layers "F.Cu" "F.Mask" "F.Paste")
			(net "M_E_DQS_DP<7>")
		)
		(pad "279" smd rect
			(at 4.59994 119.000016 90)
			(size 1.8034 0.508)
			(layers "F.Cu" "F.Mask" "F.Paste")
			(net "GND")
		)
		(pad "280" smd rect
			(at 4.59994 119.8499 90)
			(size 1.8034 0.508)
			(layers "F.Cu" "F.Mask" "F.Paste")
			(net "M_E_DQ<62>")
		)
		(pad "281" smd rect
			(at 4.59994 120.700038 90)
			(size 1.8034 0.508)
			(layers "F.Cu" "F.Mask" "F.Paste")
			(net "GND")
		)
		(pad "282" smd rect
			(at 4.59994 121.549922 90)
			(size 1.8034 0.508)
			(layers "F.Cu" "F.Mask" "F.Paste")
			(net "M_E_DQ<58>")
		)
		(pad "283" smd rect
			(at 4.59994 122.40006 90)
			(size 1.8034 0.508)
			(layers "F.Cu" "F.Mask" "F.Paste")
			(net "GND")
		)
		(pad "284" smd rect
			(at 4.59994 123.249944 90)
			(size 1.8034 0.508)
			(layers "F.Cu" "F.Mask" "F.Paste")
			(net "PVPP_DEF")
		)
		(pad "285" smd rect
			(at 4.59994 124.100082 90)
			(size 1.8034 0.508)
			(layers "F.Cu" "F.Mask" "F.Paste")
			(net "SMB_DDR_DEF_VPP_SDA")
		)
		(pad "286" smd rect
			(at 4.59994 124.949966 90)
			(size 1.8034 0.508)
			(layers "F.Cu" "F.Mask" "F.Paste")
			(net "PVPP_DEF")
		)
		(pad "287" smd rect
			(at 4.59994 125.800104 90)
			(size 1.8034 0.508)
			(layers "F.Cu" "F.Mask" "F.Paste")
			(net "PVPP_DEF")
		)
		(pad "288" smd rect
			(at 4.59994 126.649988 90)
			(size 1.8034 0.508)
			(layers "F.Cu" "F.Mask" "F.Paste")
			(net "PVPP_DEF")
		)
	)
	(footprint ""
		(layer "F.Cu")
		(at 30.583378 -22.160992 90)
		(property "Reference" "C1F22"
			(at 0 0 90)
			(layer "F.SilkS")
			(hide yes)
			(effects
				(font
					(size 1.27 1.27)
				)
			)
		)
		(property "Value" ""
			(at 0 0 90)
			(layer "F.Fab")
			(effects
				(font
					(size 1.27 1.27)
				)
			)
		)
		(duplicate_pad_numbers_are_jumpers no)
		(fp_poly
			(pts
				(xy 0.3048 -0.1016) (xy 0.3048 0.9906) (xy -0.3048 0.9906) (xy -0.3048 -0.1016)
			)
			(stroke
				(width 0)
				(type default)
			)
			(fill no)
			(layer "F.CrtYd")
		)
		(fp_line
			(start 0.3048 -0.1016)
			(end -0.3048 -0.1016)
			(stroke
				(width 0.1)
				(type default)
			)
			(layer "F.Fab")
		)
		(fp_line
			(start -0.3048 -0.1016)
			(end -0.3048 0.9906)
			(stroke
				(width 0.1)
				(type default)
			)
			(layer "F.Fab")
		)
		(fp_line
			(start 0.3048 0.9906)
			(end 0.3048 -0.1016)
			(stroke
				(width 0.1)
				(type default)
			)
			(layer "F.Fab")
		)
		(fp_line
			(start -0.3048 0.9906)
			(end 0.3048 0.9906)
			(stroke
				(width 0.1)
				(type default)
			)
			(layer "F.Fab")
		)
		(pad "1" smd rect
			(at 0 0 90)
			(size 0.508 0.508)
			(layers "F.Cu" "F.Mask" "F.Paste")
			(net "M_G_VREF")
		)
		(pad "2" smd rect
			(at 0 0.889 90)
			(size 0.508 0.508)
			(layers "F.Cu" "F.Mask" "F.Paste")
			(net "GND")
		)
		(zone
			(layer "F.Cu")
			(hatch none 0.5)
			(connect_pads
				(clearance 0)
			)
			(min_thickness 0.25)
			(keepout
				(tracks allowed)
				(vias not_allowed)
				(pads allowed)
				(copperpour not_allowed)
				(footprints allowed)
			)
			(placement
				(enabled no)
				(sheetname "")
			)
			(fill
				(thermal_gap 0.5)
				(thermal_bridge_width 0.5)
				(island_removal_mode 0)
			)
			(polygon
				(pts
					(xy 30.837378 -21.906992) (xy 30.837378 -22.414992) (xy 31.218378 -22.414992) (xy 31.218378 -21.906992)
				)
			)
		)
		(zone
			(layer "F.Cu")
			(hatch none 0.5)
			(connect_pads
				(clearance 0)
			)
			(min_thickness 0.25)
			(keepout
				(tracks not_allowed)
				(vias allowed)
				(pads allowed)
				(copperpour not_allowed)
				(footprints allowed)
			)
			(placement
				(enabled no)
				(sheetname "")
			)
			(fill
				(thermal_gap 0.5)
				(thermal_bridge_width 0.5)
				(island_removal_mode 0)
			)
			(polygon
				(pts
					(xy 31.218378 -21.906992) (xy 31.218378 -22.414992) (xy 30.837378 -22.414992) (xy 30.837378 -21.906992)
				)
			)
		)
	)
	(footprint ""
		(layer "F.Cu")
		(at 107.8611 -149.8092 90)
		(property "Reference" "C3A1"
			(at 1.848866 0.752348 90)
			(unlocked yes)
			(layer "F.SilkS")
			(effects
				(font
					(size 1.27 0.9652)
					(thickness 0.1524)
				)
			)
		)
		(property "Value" ""
			(at 0 0 90)
			(layer "F.Fab")
			(effects
				(font
					(size 1.27 1.27)
				)
			)
		)
		(duplicate_pad_numbers_are_jumpers no)
		(fp_rect
			(start -0.500126 1.598422)
			(end 0.500126 -0.201422)
			(stroke
				(width 0)
				(type default)
			)
			(fill no)
			(layer "F.CrtYd")
		)
		(fp_line
			(start 0.500126 -0.201422)
			(end 0.500126 1.598422)
			(stroke
				(width 0.1)
				(type default)
			)
			(layer "F.Fab")
		)
		(fp_line
			(start -0.500126 -0.201422)
			(end 0.500126 -0.201422)
			(stroke
				(width 0.1)
				(type default)
			)
			(layer "F.Fab")
		)
		(fp_line
			(start 0.500126 1.598422)
			(end -0.500126 1.598422)
			(stroke
				(width 0.1)
				(type default)
			)
			(layer "F.Fab")
		)
		(fp_line
			(start -0.500126 1.598422)
			(end -0.500126 -0.201422)
			(stroke
				(width 0.1)
				(type default)
			)
			(layer "F.Fab")
		)
		(pad "1" smd rect
			(at 0 0)
			(size 0.889 0.9906)
			(layers "F.Cu" "F.Mask" "F.Paste")
			(net "PVDDQ_KLM")
		)
		(pad "2" smd rect
			(at 0 1.397)
			(size 0.889 0.9906)
			(layers "F.Cu" "F.Mask" "F.Paste")
			(net "GND")
		)
		(zone
			(layer "F.Cu")
			(hatch none 0.5)
			(connect_pads
				(clearance 0)
			)
			(min_thickness 0.25)
			(keepout
				(tracks not_allowed)
				(vias allowed)
				(pads allowed)
				(copperpour not_allowed)
				(footprints allowed)
			)
			(placement
				(enabled no)
				(sheetname "")
			)
			(fill
				(thermal_gap 0.5)
				(thermal_bridge_width 0.5)
				(island_removal_mode 0)
			)
			(polygon
				(pts
					(xy 108.8136 -149.3139) (xy 108.8136 -150.3045) (xy 108.3056 -150.3045) (xy 108.3056 -149.3139)
				)
			)
		)
		(zone
			(layer "F.Cu")
			(hatch none 0.5)
			(connect_pads
				(clearance 0)
			)
			(min_thickness 0.25)
			(keepout
				(tracks allowed)
				(vias not_allowed)
				(pads allowed)
				(copperpour not_allowed)
				(footprints allowed)
			)
			(placement
				(enabled no)
				(sheetname "")
			)
			(fill
				(thermal_gap 0.5)
				(thermal_bridge_width 0.5)
				(island_removal_mode 0)
			)
			(polygon
				(pts
					(xy 108.8136 -149.3139) (xy 108.8136 -150.3045) (xy 108.3056 -150.3045) (xy 108.3056 -149.3139)
				)
			)
		)
	)
	(footprint ""
		(layer "F.Cu")
		(at 469.3031 -25.18156 180)
		(property "Reference" "C8E12"
			(at 0 0 180)
			(layer "F.SilkS")
			(hide yes)
			(effects
				(font
					(size 1.27 1.27)
				)
			)
		)
		(property "Value" ""
			(at 0 0 180)
			(layer "F.Fab")
			(effects
				(font
					(size 1.27 1.27)
				)
			)
		)
		(duplicate_pad_numbers_are_jumpers no)
		(fp_rect
			(start 0.4953 -0.2032)
			(end -0.4953 1.6002)
			(stroke
				(width 0)
				(type default)
			)
			(fill no)
			(layer "F.CrtYd")
		)
		(fp_line
			(start 0.4953 1.6002)
			(end -0.4953 1.6002)
			(stroke
				(width 0.1)
				(type default)
			)
			(layer "F.Fab")
		)
		(fp_line
			(start 0.4953 -0.2032)
			(end 0.4953 1.6002)
			(stroke
				(width 0.1)
				(type default)
			)
			(layer "F.Fab")
		)
		(fp_line
			(start -0.4953 1.6002)
			(end -0.4953 -0.2032)
			(stroke
				(width 0.1)
				(type default)
			)
			(layer "F.Fab")
		)
		(fp_line
			(start -0.4953 -0.2032)
			(end 0.4953 -0.2032)
			(stroke
				(width 0.1)
				(type default)
			)
			(layer "F.Fab")
		)
		(pad "1" smd rect
			(at 0 0 180)
			(size 0.762 0.889)
			(layers "F.Cu" "F.Mask" "F.Paste")
			(net "VR_P3V3_STBY_PHASE")
		)
		(pad "2" smd rect
			(at 0 1.397 180)
			(size 0.762 0.889)
			(layers "F.Cu" "F.Mask" "F.Paste")
			(net "VR_P3V3_STBY_BOOT_R")
		)
		(zone
			(layer "F.Cu")
			(hatch none 0.5)
			(connect_pads
				(clearance 0)
			)
			(min_thickness 0.25)
			(keepout
				(tracks not_allowed)
				(vias allowed)
				(pads allowed)
				(copperpour not_allowed)
				(footprints allowed)
			)
			(placement
				(enabled no)
				(sheetname "")
			)
			(fill
				(thermal_gap 0.5)
				(thermal_bridge_width 0.5)
				(island_removal_mode 0)
			)
			(polygon
				(pts
					(xy 468.9221 -25.62606) (xy 469.6841 -25.62606) (xy 469.6841 -26.13406) (xy 468.9221 -26.13406)
				)
			)
		)
	)
	(footprint ""
		(layer "F.Cu")
		(at 323.723 -34.163 90)
		(property "Reference" "R6F4"
			(at 0 0 90)
			(layer "F.SilkS")
			(hide yes)
			(effects
				(font
					(size 1.27 1.27)
				)
			)
		)
		(property "Value" ""
			(at 0 0 90)
			(layer "F.Fab")
			(effects
				(font
					(size 1.27 1.27)
				)
			)
		)
		(duplicate_pad_numbers_are_jumpers no)
		(fp_poly
			(pts
				(xy -0.2794 -0.1016) (xy 0.2794 -0.1016) (xy 0.2794 0.9906) (xy -0.2794 0.9906)
			)
			(stroke
				(width 0)
				(type default)
			)
			(fill no)
			(layer "F.CrtYd")
		)
		(fp_line
			(start 0.2794 -0.1016)
			(end -0.2794 -0.1016)
			(stroke
				(width 0.1)
				(type default)
			)
			(layer "F.Fab")
		)
		(fp_line
			(start -0.2794 -0.1016)
			(end -0.2794 0.9906)
			(stroke
				(width 0.1)
				(type default)
			)
			(layer "F.Fab")
		)
		(fp_line
			(start 0.2794 0.9906)
			(end 0.2794 -0.1016)
			(stroke
				(width 0.1)
				(type default)
			)
			(layer "F.Fab")
		)
		(fp_line
			(start -0.2794 0.9906)
			(end 0.2794 0.9906)
			(stroke
				(width 0.1)
				(type default)
			)
			(layer "F.Fab")
		)
		(pad "1" smd rect
			(at 0 0 90)
			(size 0.508 0.508)
			(layers "F.Cu" "F.Mask" "F.Paste")
			(net "IRQ_DIMM_SAVE_N")
		)
		(pad "2" smd rect
			(at 0 0.889 90)
			(size 0.508 0.508)
			(layers "F.Cu" "F.Mask" "F.Paste")
			(net "FM_ADR_COMPLETE_ABC_N")
		)
		(zone
			(layer "F.Cu")
			(hatch none 0.5)
			(connect_pads
				(clearance 0)
			)
			(min_thickness 0.25)
			(keepout
				(tracks allowed)
				(vias not_allowed)
				(pads allowed)
				(copperpour not_allowed)
				(footprints allowed)
			)
			(placement
				(enabled no)
				(sheetname "")
			)
			(fill
				(thermal_gap 0.5)
				(thermal_bridge_width 0.5)
				(island_removal_mode 0)
			)
			(polygon
				(pts
					(xy 323.977 -33.909) (xy 323.977 -34.417) (xy 324.358 -34.417) (xy 324.358 -33.909)
				)
			)
		)
		(zone
			(layer "F.Cu")
			(hatch none 0.5)
			(connect_pads
				(clearance 0)
			)
			(min_thickness 0.25)
			(keepout
				(tracks not_allowed)
				(vias allowed)
				(pads allowed)
				(copperpour not_allowed)
				(footprints allowed)
			)
			(placement
				(enabled no)
				(sheetname "")
			)
			(fill
				(thermal_gap 0.5)
				(thermal_bridge_width 0.5)
				(island_removal_mode 0)
			)
			(polygon
				(pts
					(xy 324.358 -33.909) (xy 324.358 -34.417) (xy 323.977 -34.417) (xy 323.977 -33.909)
				)
			)
		)
	)
	(footprint ""
		(layer "F.Cu")
		(at 461.098392 -37.067998 180)
		(property "Reference" "R9F13"
			(at 0 0 180)
			(layer "F.SilkS")
			(hide yes)
			(effects
				(font
					(size 1.27 1.27)
				)
			)
		)
		(property "Value" ""
			(at 0 0 180)
			(layer "F.Fab")
			(effects
				(font
					(size 1.27 1.27)
				)
			)
		)
		(duplicate_pad_numbers_are_jumpers no)
		(fp_poly
			(pts
				(xy -0.2794 -0.1016) (xy 0.2794 -0.1016) (xy 0.2794 0.9906) (xy -0.2794 0.9906)
			)
			(stroke
				(width 0)
				(type default)
			)
			(fill no)
			(layer "F.CrtYd")
		)
		(fp_line
			(start 0.2794 0.9906)
			(end 0.2794 -0.1016)
			(stroke
				(width 0.1)
				(type default)
			)
			(layer "F.Fab")
		)
		(fp_line
			(start 0.2794 -0.1016)
			(end -0.2794 -0.1016)
			(stroke
				(width 0.1)
				(type default)
			)
			(layer "F.Fab")
		)
		(fp_line
			(start -0.2794 0.9906)
			(end 0.2794 0.9906)
			(stroke
				(width 0.1)
				(type default)
			)
			(layer "F.Fab")
		)
		(fp_line
			(start -0.2794 -0.1016)
			(end -0.2794 0.9906)
			(stroke
				(width 0.1)
				(type default)
			)
			(layer "F.Fab")
		)
		(pad "1" smd rect
			(at 0 0 180)
			(size 0.508 0.508)
			(layers "F.Cu" "F.Mask" "F.Paste")
			(net "P3V3_STBY")
		)
		(pad "2" smd rect
			(at 0 0.889 180)
			(size 0.508 0.508)
			(layers "F.Cu" "F.Mask" "F.Paste")
			(net "PWRGD_P1V15_BMC_STBY_R")
		)
		(zone
			(layer "F.Cu")
			(hatch none 0.5)
			(connect_pads
				(clearance 0)
			)
			(min_thickness 0.25)
			(keepout
				(tracks not_allowed)
				(vias allowed)
				(pads allowed)
				(copperpour not_allowed)
				(footprints allowed)
			)
			(placement
				(enabled no)
				(sheetname "")
			)
			(fill
				(thermal_gap 0.5)
				(thermal_bridge_width 0.5)
				(island_removal_mode 0)
			)
			(polygon
				(pts
					(xy 461.352392 -37.702998) (xy 460.844392 -37.702998) (xy 460.844392 -37.321998) (xy 461.352392 -37.321998)
				)
			)
		)
		(zone
			(layer "F.Cu")
			(hatch none 0.5)
			(connect_pads
				(clearance 0)
			)
			(min_thickness 0.25)
			(keepout
				(tracks allowed)
				(vias not_allowed)
				(pads allowed)
				(copperpour not_allowed)
				(footprints allowed)
			)
			(placement
				(enabled no)
				(sheetname "")
			)
			(fill
				(thermal_gap 0.5)
				(thermal_bridge_width 0.5)
				(island_removal_mode 0)
			)
			(polygon
				(pts
					(xy 461.352392 -37.321998) (xy 460.844392 -37.321998) (xy 460.844392 -37.702998) (xy 461.352392 -37.702998)
				)
			)
		)
	)
	(footprint ""
		(layer "F.Cu")
		(at 489.077 -33.655 -90)
		(property "Reference" "R25W128"
			(at -0.8382 -0.67818 270)
			(unlocked yes)
			(layer "F.SilkS")
			(effects
				(font
					(size 0.4064 0.254)
					(thickness 0.1524)
				)
				(justify left)
			)
		)
		(property "Value" ""
			(at 0 0 270)
			(layer "F.Fab")
			(effects
				(font
					(size 1.27 1.27)
				)
			)
		)
		(duplicate_pad_numbers_are_jumpers no)
		(fp_poly
			(pts
				(xy -0.2794 -0.1016) (xy 0.2794 -0.1016) (xy 0.2794 0.9906) (xy -0.2794 0.9906)
			)
			(stroke
				(width 0)
				(type default)
			)
			(fill no)
			(layer "F.CrtYd")
		)
		(fp_line
			(start -0.2794 0.9906)
			(end 0.2794 0.9906)
			(stroke
				(width 0.1)
				(type default)
			)
			(layer "F.Fab")
		)
		(fp_line
			(start 0.2794 0.9906)
			(end 0.2794 -0.1016)
			(stroke
				(width 0.1)
				(type default)
			)
			(layer "F.Fab")
		)
		(fp_line
			(start -0.2794 -0.1016)
			(end -0.2794 0.9906)
			(stroke
				(width 0.1)
				(type default)
			)
			(layer "F.Fab")
		)
		(fp_line
			(start 0.2794 -0.1016)
			(end -0.2794 -0.1016)
			(stroke
				(width 0.1)
				(type default)
			)
			(layer "F.Fab")
		)
		(pad "1" smd rect
			(at 0 0 270)
			(size 0.508 0.508)
			(layers "F.Cu" "F.Mask" "F.Paste")
			(net "V_IO_R_J")
		)
		(pad "2" smd rect
			(at 0 0.889 270)
			(size 0.508 0.508)
			(layers "F.Cu" "F.Mask" "F.Paste")
			(net "GND")
		)
		(zone
			(layer "F.Cu")
			(hatch none 0.5)
			(connect_pads
				(clearance 0)
			)
			(min_thickness 0.25)
			(keepout
				(tracks not_allowed)
				(vias allowed)
				(pads allowed)
				(copperpour not_allowed)
				(footprints allowed)
			)
			(placement
				(enabled no)
				(sheetname "")
			)
			(fill
				(thermal_gap 0.5)
				(thermal_bridge_width 0.5)
				(island_removal_mode 0)
			)
			(polygon
				(pts
					(xy 488.442 -33.909) (xy 488.442 -33.401) (xy 488.823 -33.401) (xy 488.823 -33.909)
				)
			)
		)
		(zone
			(layer "F.Cu")
			(hatch none 0.5)
			(connect_pads
				(clearance 0)
			)
			(min_thickness 0.25)
			(keepout
				(tracks allowed)
				(vias not_allowed)
				(pads allowed)
				(copperpour not_allowed)
				(footprints allowed)
			)
			(placement
				(enabled no)
				(sheetname "")
			)
			(fill
				(thermal_gap 0.5)
				(thermal_bridge_width 0.5)
				(island_removal_mode 0)
			)
			(polygon
				(pts
					(xy 488.823 -33.909) (xy 488.823 -33.401) (xy 488.442 -33.401) (xy 488.442 -33.909)
				)
			)
		)
	)
	(footprint ""
		(layer "F.Cu")
		(at 13.35278 -154.178 -90)
		(property "Reference" "R1A1"
			(at 0 0 270)
			(layer "F.SilkS")
			(hide yes)
			(effects
				(font
					(size 1.27 1.27)
				)
			)
		)
		(property "Value" ""
			(at 0 0 270)
			(layer "F.Fab")
			(effects
				(font
					(size 1.27 1.27)
				)
			)
		)
		(duplicate_pad_numbers_are_jumpers no)
		(fp_rect
			(start 0.4953 1.6002)
			(end -0.4953 -0.2032)
			(stroke
				(width 0)
				(type default)
			)
			(fill no)
			(layer "F.CrtYd")
		)
		(fp_line
			(start -0.4953 1.6002)
			(end -0.4953 -0.2032)
			(stroke
				(width 0.1)
				(type default)
			)
			(layer "F.Fab")
		)
		(fp_line
			(start 0.4953 1.6002)
			(end -0.4953 1.6002)
			(stroke
				(width 0.1)
				(type default)
			)
			(layer "F.Fab")
		)
		(fp_line
			(start -0.4953 -0.2032)
			(end 0.4953 -0.2032)
			(stroke
				(width 0.1)
				(type default)
			)
			(layer "F.Fab")
		)
		(fp_line
			(start 0.4953 -0.2032)
			(end 0.4953 1.6002)
			(stroke
				(width 0.1)
				(type default)
			)
			(layer "F.Fab")
		)
		(pad "1" smd rect
			(at 0 0 270)
			(size 0.762 0.889)
			(layers "F.Cu" "F.Mask" "F.Paste")
			(net "PVDDQ_KLM")
		)
		(pad "2" smd rect
			(at 0 1.397 270)
			(size 0.762 0.889)
			(layers "F.Cu" "F.Mask" "F.Paste")
			(net "GND")
		)
		(zone
			(layer "F.Cu")
			(hatch none 0.5)
			(connect_pads
				(clearance 0)
			)
			(min_thickness 0.25)
			(keepout
				(tracks allowed)
				(vias not_allowed)
				(pads allowed)
				(copperpour not_allowed)
				(footprints allowed)
			)
			(placement
				(enabled no)
				(sheetname "")
			)
			(fill
				(thermal_gap 0.5)
				(thermal_bridge_width 0.5)
				(island_removal_mode 0)
			)
			(polygon
				(pts
					(xy 12.40028 -153.797) (xy 12.90828 -153.797) (xy 12.90828 -154.559) (xy 12.40028 -154.559)
				)
			)
		)
		(zone
			(layer "F.Cu")
			(hatch none 0.5)
			(connect_pads
				(clearance 0)
			)
			(min_thickness 0.25)
			(keepout
				(tracks not_allowed)
				(vias allowed)
				(pads allowed)
				(copperpour not_allowed)
				(footprints allowed)
			)
			(placement
				(enabled no)
				(sheetname "")
			)
			(fill
				(thermal_gap 0.5)
				(thermal_bridge_width 0.5)
				(island_removal_mode 0)
			)
			(polygon
				(pts
					(xy 12.40028 -153.797) (xy 12.90828 -153.797) (xy 12.90828 -154.559) (xy 12.40028 -154.559)
				)
			)
		)
	)
	(footprint ""
		(layer "F.Cu")
		(at 28.380182 -140.1826 -90)
		(property "Reference" "C1A16"
			(at 0 0 270)
			(layer "F.SilkS")
			(hide yes)
			(effects
				(font
					(size 1.27 1.27)
				)
			)
		)
		(property "Value" ""
			(at 0 0 270)
			(layer "F.Fab")
			(effects
				(font
					(size 1.27 1.27)
				)
			)
		)
		(duplicate_pad_numbers_are_jumpers no)
		(fp_poly
			(pts
				(xy -0.7239 -0.2159) (xy 0.7239 -0.2159) (xy 0.7239 1.9939) (xy -0.7239 1.9939)
			)
			(stroke
				(width 0)
				(type default)
			)
			(fill no)
			(layer "F.CrtYd")
		)
		(fp_line
			(start -0.7239 1.9939)
			(end 0.7239 1.9939)
			(stroke
				(width 0.1)
				(type default)
			)
			(layer "F.Fab")
		)
		(fp_line
			(start 0.7239 1.9939)
			(end 0.7239 -0.2159)
			(stroke
				(width 0.1)
				(type default)
			)
			(layer "F.Fab")
		)
		(fp_line
			(start -0.7239 -0.2159)
			(end -0.7239 1.9939)
			(stroke
				(width 0.1)
				(type default)
			)
			(layer "F.Fab")
		)
		(fp_line
			(start 0.7239 -0.2159)
			(end -0.7239 -0.2159)
			(stroke
				(width 0.1)
				(type default)
			)
			(layer "F.Fab")
		)
		(pad "1" smd rect
			(at 0 0 270)
			(size 1.27 1.016)
			(layers "F.Cu" "F.Mask" "F.Paste")
			(net "P12V_NVDIMM_KLM")
		)
		(pad "2" smd rect
			(at 0 1.778 270)
			(size 1.27 1.016)
			(layers "F.Cu" "F.Mask" "F.Paste")
			(net "GND")
		)
		(zone
			(layer "F.Cu")
			(hatch none 0.5)
			(connect_pads
				(clearance 0)
			)
			(min_thickness 0.25)
			(keepout
				(tracks not_allowed)
				(vias allowed)
				(pads allowed)
				(copperpour not_allowed)
				(footprints allowed)
			)
			(placement
				(enabled no)
				(sheetname "")
			)
			(fill
				(thermal_gap 0.5)
				(thermal_bridge_width 0.5)
				(island_removal_mode 0)
			)
			(polygon
				(pts
					(xy 27.872182 -140.8176) (xy 27.872182 -139.5476) (xy 27.110182 -139.5476) (xy 27.110182 -140.8176)
				)
			)
		)
	)
	(footprint ""
		(layer "F.Cu")
		(at 321.16522 -120.53316 -90)
		(property "Reference" "C840"
			(at -0.8382 -0.67818 270)
			(unlocked yes)
			(layer "F.SilkS")
			(effects
				(font
					(size 0.4064 0.254)
					(thickness 0.1524)
				)
				(justify left)
			)
		)
		(property "Value" ""
			(at 0 0 270)
			(layer "F.Fab")
			(effects
				(font
					(size 1.27 1.27)
				)
			)
		)
		(duplicate_pad_numbers_are_jumpers no)
		(fp_poly
			(pts
				(xy 0.3048 -0.1016) (xy 0.3048 0.9906) (xy -0.3048 0.9906) (xy -0.3048 -0.1016)
			)
			(stroke
				(width 0)
				(type default)
			)
			(fill no)
			(layer "F.CrtYd")
		)
		(fp_line
			(start -0.3048 0.9906)
			(end 0.3048 0.9906)
			(stroke
				(width 0.1)
				(type default)
			)
			(layer "F.Fab")
		)
		(fp_line
			(start 0.3048 0.9906)
			(end 0.3048 -0.1016)
			(stroke
				(width 0.1)
				(type default)
			)
			(layer "F.Fab")
		)
		(fp_line
			(start -0.3048 -0.1016)
			(end -0.3048 0.9906)
			(stroke
				(width 0.1)
				(type default)
			)
			(layer "F.Fab")
		)
		(fp_line
			(start 0.3048 -0.1016)
			(end -0.3048 -0.1016)
			(stroke
				(width 0.1)
				(type default)
			)
			(layer "F.Fab")
		)
		(pad "1" smd rect
			(at 0 0 270)
			(size 0.508 0.508)
			(layers "F.Cu" "F.Mask" "F.Paste")
			(net "P3E_CPU0_PE1_PCH_TXN<12>")
		)
		(pad "2" smd rect
			(at 0 0.889 270)
			(size 0.508 0.508)
			(layers "F.Cu" "F.Mask" "F.Paste")
			(net "P3E_CPU0_PE1_PCH_CON_TXN<12>")
		)
		(zone
			(layer "F.Cu")
			(hatch none 0.5)
			(connect_pads
				(clearance 0)
			)
			(min_thickness 0.25)
			(keepout
				(tracks not_allowed)
				(vias allowed)
				(pads allowed)
				(copperpour not_allowed)
				(footprints allowed)
			)
			(placement
				(enabled no)
				(sheetname "")
			)
			(fill
				(thermal_gap 0.5)
				(thermal_bridge_width 0.5)
				(island_removal_mode 0)
			)
			(polygon
				(pts
					(xy 320.53022 -120.78716) (xy 320.53022 -120.27916) (xy 320.91122 -120.27916) (xy 320.91122 -120.78716)
				)
			)
		)
		(zone
			(layer "F.Cu")
			(hatch none 0.5)
			(connect_pads
				(clearance 0)
			)
			(min_thickness 0.25)
			(keepout
				(tracks allowed)
				(vias not_allowed)
				(pads allowed)
				(copperpour not_allowed)
				(footprints allowed)
			)
			(placement
				(enabled no)
				(sheetname "")
			)
			(fill
				(thermal_gap 0.5)
				(thermal_bridge_width 0.5)
				(island_removal_mode 0)
			)
			(polygon
				(pts
					(xy 320.91122 -120.78716) (xy 320.91122 -120.27916) (xy 320.53022 -120.27916) (xy 320.53022 -120.78716)
				)
			)
		)
	)
	(footprint ""
		(layer "F.Cu")
		(at 33.093152 -68.525644 90)
		(property "Reference" "C1D34"
			(at 0 0 90)
			(layer "F.SilkS")
			(hide yes)
			(effects
				(font
					(size 1.27 1.27)
				)
			)
		)
		(property "Value" ""
			(at 0 0 90)
			(layer "F.Fab")
			(effects
				(font
					(size 1.27 1.27)
				)
			)
		)
		(duplicate_pad_numbers_are_jumpers no)
		(fp_rect
			(start 0.3048 0.9906)
			(end -0.3048 -0.1016)
			(stroke
				(width 0)
				(type default)
			)
			(fill no)
			(layer "F.CrtYd")
		)
		(fp_line
			(start 0.3048 -0.1016)
			(end -0.3048 -0.1016)
			(stroke
				(width 0.1)
				(type default)
			)
			(layer "F.Fab")
		)
		(fp_line
			(start -0.3048 -0.1016)
			(end -0.3048 0.9906)
			(stroke
				(width 0.1)
				(type default)
			)
			(layer "F.Fab")
		)
		(fp_line
			(start 0.3048 0.9906)
			(end 0.3048 -0.1016)
			(stroke
				(width 0.1)
				(type default)
			)
			(layer "F.Fab")
		)
		(fp_line
			(start -0.3048 0.9906)
			(end 0.3048 0.9906)
			(stroke
				(width 0.1)
				(type default)
			)
			(layer "F.Fab")
		)
		(pad "1" smd rect
			(at 0 0 90)
			(size 0.508 0.508)
			(layers "F.Cu" "F.Mask" "F.Paste")
			(net "VR_FET_SW_P12V_STBY_PVCCIN_CPU1")
		)
		(pad "2" smd rect
			(at 0 0.889 90)
			(size 0.508 0.508)
			(layers "F.Cu" "F.Mask" "F.Paste")
			(net "GND")
		)
		(zone
			(layer "F.Cu")
			(hatch none 0.5)
			(connect_pads
				(clearance 0)
			)
			(min_thickness 0.25)
			(keepout
				(tracks allowed)
				(vias not_allowed)
				(pads allowed)
				(copperpour not_allowed)
				(footprints allowed)
			)
			(placement
				(enabled no)
				(sheetname "")
			)
			(fill
				(thermal_gap 0.5)
				(thermal_bridge_width 0.5)
				(island_removal_mode 0)
			)
			(polygon
				(pts
					(xy 33.728152 -68.779644) (xy 33.347152 -68.779644) (xy 33.347152 -68.271644) (xy 33.728152 -68.271644)
				)
			)
		)
		(zone
			(layer "F.Cu")
			(hatch none 0.5)
			(connect_pads
				(clearance 0)
			)
			(min_thickness 0.25)
			(keepout
				(tracks not_allowed)
				(vias allowed)
				(pads allowed)
				(copperpour not_allowed)
				(footprints allowed)
			)
			(placement
				(enabled no)
				(sheetname "")
			)
			(fill
				(thermal_gap 0.5)
				(thermal_bridge_width 0.5)
				(island_removal_mode 0)
			)
			(polygon
				(pts
					(xy 33.728152 -68.779644) (xy 33.347152 -68.779644) (xy 33.347152 -68.271644) (xy 33.728152 -68.271644)
				)
			)
		)
	)
	(footprint ""
		(layer "F.Cu")
		(at 477.8756 -45.1739 180)
		(property "Reference" "C9E7"
			(at 0 0 180)
			(layer "F.SilkS")
			(hide yes)
			(effects
				(font
					(size 1.27 1.27)
				)
			)
		)
		(property "Value" ""
			(at 0 0 180)
			(layer "F.Fab")
			(effects
				(font
					(size 1.27 1.27)
				)
			)
		)
		(duplicate_pad_numbers_are_jumpers no)
		(fp_poly
			(pts
				(xy 0.3048 -0.1016) (xy 0.3048 0.9906) (xy -0.3048 0.9906) (xy -0.3048 -0.1016)
			)
			(stroke
				(width 0)
				(type default)
			)
			(fill no)
			(layer "F.CrtYd")
		)
		(fp_line
			(start 0.3048 0.9906)
			(end 0.3048 -0.1016)
			(stroke
				(width 0.1)
				(type default)
			)
			(layer "F.Fab")
		)
		(fp_line
			(start 0.3048 -0.1016)
			(end -0.3048 -0.1016)
			(stroke
				(width 0.1)
				(type default)
			)
			(layer "F.Fab")
		)
		(fp_line
			(start -0.3048 0.9906)
			(end 0.3048 0.9906)
			(stroke
				(width 0.1)
				(type default)
			)
			(layer "F.Fab")
		)
		(fp_line
			(start -0.3048 -0.1016)
			(end -0.3048 0.9906)
			(stroke
				(width 0.1)
				(type default)
			)
			(layer "F.Fab")
		)
		(pad "1" smd rect
			(at 0 0 180)
			(size 0.508 0.508)
			(layers "F.Cu" "F.Mask" "F.Paste")
			(net "A_CTOP")
		)
		(pad "2" smd rect
			(at 0 0.889 180)
			(size 0.508 0.508)
			(layers "F.Cu" "F.Mask" "F.Paste")
			(net "A_CBOT")
		)
		(zone
			(layer "F.Cu")
			(hatch none 0.5)
			(connect_pads
				(clearance 0)
			)
			(min_thickness 0.25)
			(keepout
				(tracks not_allowed)
				(vias allowed)
				(pads allowed)
				(copperpour not_allowed)
				(footprints allowed)
			)
			(placement
				(enabled no)
				(sheetname "")
			)
			(fill
				(thermal_gap 0.5)
				(thermal_bridge_width 0.5)
				(island_removal_mode 0)
			)
			(polygon
				(pts
					(xy 478.1296 -45.8089) (xy 477.6216 -45.8089) (xy 477.6216 -45.4279) (xy 478.1296 -45.4279)
				)
			)
		)
		(zone
			(layer "F.Cu")
			(hatch none 0.5)
			(connect_pads
				(clearance 0)
			)
			(min_thickness 0.25)
			(keepout
				(tracks allowed)
				(vias not_allowed)
				(pads allowed)
				(copperpour not_allowed)
				(footprints allowed)
			)
			(placement
				(enabled no)
				(sheetname "")
			)
			(fill
				(thermal_gap 0.5)
				(thermal_bridge_width 0.5)
				(island_removal_mode 0)
			)
			(polygon
				(pts
					(xy 478.1296 -45.4279) (xy 477.6216 -45.4279) (xy 477.6216 -45.8089) (xy 478.1296 -45.8089)
				)
			)
		)
	)
	(footprint ""
		(layer "F.Cu")
		(at 404.9522 -128.3335)
		(property "Reference" "C8B4"
			(at 0 0 0)
			(layer "F.SilkS")
			(hide yes)
			(effects
				(font
					(size 1.27 1.27)
				)
			)
		)
		(property "Value" ""
			(at 0 0 0)
			(layer "F.Fab")
			(effects
				(font
					(size 1.27 1.27)
				)
			)
		)
		(duplicate_pad_numbers_are_jumpers no)
		(fp_poly
			(pts
				(xy -0.4953 -0.2032) (xy 0.4953 -0.2032) (xy 0.4953 1.6002) (xy -0.4953 1.6002)
			)
			(stroke
				(width 0)
				(type default)
			)
			(fill no)
			(layer "F.CrtYd")
		)
		(fp_line
			(start -0.4953 -0.2032)
			(end 0.4953 -0.2032)
			(stroke
				(width 0.1)
				(type default)
			)
			(layer "F.Fab")
		)
		(fp_line
			(start -0.4953 1.6002)
			(end -0.4953 -0.2032)
			(stroke
				(width 0.1)
				(type default)
			)
			(layer "F.Fab")
		)
		(fp_line
			(start 0.4953 -0.2032)
			(end 0.4953 1.6002)
			(stroke
				(width 0.1)
				(type default)
			)
			(layer "F.Fab")
		)
		(fp_line
			(start 0.4953 1.6002)
			(end -0.4953 1.6002)
			(stroke
				(width 0.1)
				(type default)
			)
			(layer "F.Fab")
		)
		(pad "1" smd rect
			(at 0 0)
			(size 0.762 0.889)
			(layers "F.Cu" "F.Mask" "F.Paste")
			(net "P1V8_PCH_STBY")
		)
		(pad "2" smd rect
			(at 0 1.397)
			(size 0.762 0.889)
			(layers "F.Cu" "F.Mask" "F.Paste")
			(net "GND")
		)
		(zone
			(layer "F.Cu")
			(hatch none 0.5)
			(connect_pads
				(clearance 0)
			)
			(min_thickness 0.25)
			(keepout
				(tracks not_allowed)
				(vias allowed)
				(pads allowed)
				(copperpour not_allowed)
				(footprints allowed)
			)
			(placement
				(enabled no)
				(sheetname "")
			)
			(fill
				(thermal_gap 0.5)
				(thermal_bridge_width 0.5)
				(island_removal_mode 0)
			)
			(polygon
				(pts
					(xy 404.5712 -127.889) (xy 405.3332 -127.889) (xy 405.3332 -127.381) (xy 404.5712 -127.381)
				)
			)
		)
	)
	(footprint ""
		(layer "F.Cu")
		(at 174.244 -141.1605 90)
		(property "Reference" "C4A16"
			(at 0 0 90)
			(layer "F.SilkS")
			(hide yes)
			(effects
				(font
					(size 1.27 1.27)
				)
			)
		)
		(property "Value" ""
			(at 0 0 90)
			(layer "F.Fab")
			(effects
				(font
					(size 1.27 1.27)
				)
			)
		)
		(duplicate_pad_numbers_are_jumpers no)
		(fp_poly
			(pts
				(xy 0.3048 -0.1016) (xy 0.3048 0.9906) (xy -0.3048 0.9906) (xy -0.3048 -0.1016)
			)
			(stroke
				(width 0)
				(type default)
			)
			(fill no)
			(layer "F.CrtYd")
		)
		(fp_line
			(start 0.3048 -0.1016)
			(end -0.3048 -0.1016)
			(stroke
				(width 0.1)
				(type default)
			)
			(layer "F.Fab")
		)
		(fp_line
			(start -0.3048 -0.1016)
			(end -0.3048 0.9906)
			(stroke
				(width 0.1)
				(type default)
			)
			(layer "F.Fab")
		)
		(fp_line
			(start 0.3048 0.9906)
			(end 0.3048 -0.1016)
			(stroke
				(width 0.1)
				(type default)
			)
			(layer "F.Fab")
		)
		(fp_line
			(start -0.3048 0.9906)
			(end 0.3048 0.9906)
			(stroke
				(width 0.1)
				(type default)
			)
			(layer "F.Fab")
		)
		(pad "1" smd rect
			(at 0 0 90)
			(size 0.508 0.508)
			(layers "F.Cu" "F.Mask" "F.Paste")
			(net "VR_PVPP_KLM_PHASE")
		)
		(pad "2" smd rect
			(at 0 0.889 90)
			(size 0.508 0.508)
			(layers "F.Cu" "F.Mask" "F.Paste")
			(net "VR_PVPP_KLM_SNUB")
		)
		(zone
			(layer "F.Cu")
			(hatch none 0.5)
			(connect_pads
				(clearance 0)
			)
			(min_thickness 0.25)
			(keepout
				(tracks allowed)
				(vias not_allowed)
				(pads allowed)
				(copperpour not_allowed)
				(footprints allowed)
			)
			(placement
				(enabled no)
				(sheetname "")
			)
			(fill
				(thermal_gap 0.5)
				(thermal_bridge_width 0.5)
				(island_removal_mode 0)
			)
			(polygon
				(pts
					(xy 174.498 -140.9065) (xy 174.498 -141.4145) (xy 174.879 -141.4145) (xy 174.879 -140.9065)
				)
			)
		)
		(zone
			(layer "F.Cu")
			(hatch none 0.5)
			(connect_pads
				(clearance 0)
			)
			(min_thickness 0.25)
			(keepout
				(tracks not_allowed)
				(vias allowed)
				(pads allowed)
				(copperpour not_allowed)
				(footprints allowed)
			)
			(placement
				(enabled no)
				(sheetname "")
			)
			(fill
				(thermal_gap 0.5)
				(thermal_bridge_width 0.5)
				(island_removal_mode 0)
			)
			(polygon
				(pts
					(xy 174.879 -140.9065) (xy 174.879 -141.4145) (xy 174.498 -141.4145) (xy 174.498 -140.9065)
				)
			)
		)
	)
	(footprint ""
		(layer "F.Cu")
		(at 200.604628 -93.577918 -90)
		(property "Reference" "RT39"
			(at 0 0 270)
			(layer "F.SilkS")
			(hide yes)
			(effects
				(font
					(size 1.27 1.27)
				)
			)
		)
		(property "Value" "*"
			(at -0.0254 -2.6289 270)
			(unlocked yes)
			(layer "F.Fab")
			(hide yes)
			(effects
				(font
					(size 1.27 1.016)
					(thickness 0.1524)
				)
			)
		)
		(property "Device Type" "1R3F-GP_RCL_GP-1R3F-GP,64.1R00A"
			(at -0.0254 -4.1529 270)
			(unlocked yes)
			(layer "F.Fab")
			(hide yes)
			(effects
				(font
					(size 1.27 1.016)
					(thickness 0.1524)
				)
			)
		)
		(duplicate_pad_numbers_are_jumpers no)
		(fp_line
			(start -0.4826 0)
			(end -0.2032 0)
			(stroke
				(width 0.2032)
				(type default)
			)
			(layer "F.SilkS")
		)
		(fp_line
			(start 0.2032 0)
			(end 0.4826 0)
			(stroke
				(width 0.2032)
				(type default)
			)
			(layer "F.SilkS")
		)
		(fp_rect
			(start -0.5842 1.3335)
			(end 0.5842 -1.3335)
			(stroke
				(width 0)
				(type default)
			)
			(fill no)
			(layer "F.CrtYd")
		)
		(fp_rect
			(start -0.5842 1.3335)
			(end 0.5842 -1.3335)
			(stroke
				(width 0)
				(type default)
			)
			(fill no)
			(layer "F.Fab")
		)
		(pad "1" smd custom
			(at 0 -0.762 270)
			(size 0.2159 0.2159)
			(layers "F.Cu" "F.Mask" "F.Paste")
			(net "VR_PVSA_CPU0_PHASE_SW_RC")
			(options
				(clearance outline)
				(anchor circle)
			)
			(primitives
				(gr_poly
					(pts
						(arc
							(start -0.3302 -0.4318)
							(mid -0.402042 -0.402042)
							(end -0.4318 -0.3302)
						)
						(arc
							(start -0.4318 0.3302)
							(mid -0.402042 0.402042)
							(end -0.3302 0.4318)
						)
						(arc
							(start 0.3302 0.4318)
							(mid 0.402042 0.402042)
							(end 0.4318 0.3302)
						)
						(arc
							(start 0.4318 -0.3302)
							(mid 0.402042 -0.402042)
							(end 0.3302 -0.4318)
						)
					)
					(width 0)
					(fill yes)
				)
			)
		)
		(pad "2" smd custom
			(at 0 0.762 270)
			(size 0.2159 0.2159)
			(layers "F.Cu" "F.Mask" "F.Paste")
			(net "GND")
			(options
				(clearance outline)
				(anchor circle)
			)
			(primitives
				(gr_poly
					(pts
						(arc
							(start -0.3302 -0.4318)
							(mid -0.402042 -0.402042)
							(end -0.4318 -0.3302)
						)
						(arc
							(start -0.4318 0.3302)
							(mid -0.402042 0.402042)
							(end -0.3302 0.4318)
						)
						(arc
							(start 0.3302 0.4318)
							(mid 0.402042 0.402042)
							(end 0.4318 0.3302)
						)
						(arc
							(start 0.4318 -0.3302)
							(mid 0.402042 -0.402042)
							(end 0.3302 -0.4318)
						)
					)
					(width 0)
					(fill yes)
				)
			)
		)
	)
	(footprint ""
		(layer "F.Cu")
		(at 166.9415 -0.77978 -90)
		(property "Reference" "U4G1"
			(at -3.00482 2.09423 90)
			(unlocked yes)
			(layer "F.SilkS")
			(effects
				(font
					(size 0.7874 0.5842)
					(thickness 0.1524)
				)
			)
		)
		(property "Value" ""
			(at 0 0 270)
			(layer "F.Fab")
			(effects
				(font
					(size 1.27 1.27)
				)
			)
		)
		(duplicate_pad_numbers_are_jumpers no)
		(fp_line
			(start 3.225038 2.52476)
			(end 1.348486 2.52476)
			(stroke
				(width 0.1524)
				(type default)
			)
			(layer "F.SilkS")
		)
		(fp_line
			(start 3.225292 -0.57404)
			(end 1.352804 -0.57404)
			(stroke
				(width 0.1524)
				(type default)
			)
			(layer "F.SilkS")
		)
		(fp_circle
			(center -1.454404 -0.556514)
			(end -1.454404 -0.683514)
			(stroke
				(width 0.254)
				(type default)
			)
			(fill no)
			(layer "F.SilkS")
		)
		(fp_poly
			(pts
				(xy 0.7366 -0.57404) (xy 3.8354 -0.57404) (xy 3.8354 2.52476) (xy 0.7366 2.52476)
			)
			(stroke
				(width 0)
				(type default)
			)
			(fill no)
			(layer "F.CrtYd")
		)
		(fp_line
			(start 0.7366 2.52476)
			(end 0.7366 -0.57404)
			(stroke
				(width 0.1)
				(type default)
			)
			(layer "F.Fab")
		)
		(fp_line
			(start 3.8354 2.52476)
			(end 0.7366 2.52476)
			(stroke
				(width 0.1)
				(type default)
			)
			(layer "F.Fab")
		)
		(fp_line
			(start 0.7366 -0.57404)
			(end 3.8354 -0.57404)
			(stroke
				(width 0.1)
				(type default)
			)
			(layer "F.Fab")
		)
		(fp_line
			(start 3.8354 -0.57404)
			(end 3.8354 2.52476)
			(stroke
				(width 0.1)
				(type default)
			)
			(layer "F.Fab")
		)
		(fp_circle
			(center -1.454404 -0.556514)
			(end -1.454404 -0.683514)
			(stroke
				(width 0.254)
				(type default)
			)
			(fill no)
			(layer "F.Fab")
		)
		(pad "1" smd rect
			(at 0 0 270)
			(size 1.778 0.4572)
			(layers "F.Cu" "F.Mask" "F.Paste")
			(net "PVCCIO_CPU1")
		)
		(pad "2" smd rect
			(at 0 0.65024 270)
			(size 1.778 0.4572)
			(layers "F.Cu" "F.Mask" "F.Paste")
			(net "SMB_DDR_GHJ_SCL_G")
		)
		(pad "3" smd rect
			(at 0 1.30048 270)
			(size 1.778 0.4572)
			(layers "F.Cu" "F.Mask" "F.Paste")
			(net "SMB_DDR_GHJ_SDA_G")
		)
		(pad "4" smd rect
			(at 0 1.95072 270)
			(size 1.778 0.4572)
			(layers "F.Cu" "F.Mask" "F.Paste")
			(net "GND")
		)
		(pad "5" smd rect
			(at 4.572 1.95072 270)
			(size 1.778 0.4572)
			(layers "F.Cu" "F.Mask" "F.Paste")
			(net "TP_SMB_DDR_GHJ_EN")
		)
		(pad "6" smd rect
			(at 4.572 1.30048 270)
			(size 1.778 0.4572)
			(layers "F.Cu" "F.Mask" "F.Paste")
			(net "SMB_DDR_GHJ_VPP_SDA_R")
		)
		(pad "7" smd rect
			(at 4.572 0.65024 270)
			(size 1.778 0.4572)
			(layers "F.Cu" "F.Mask" "F.Paste")
			(net "SMB_DDR_GHJ_VPP_SCL_R")
		)
		(pad "8" smd rect
			(at 4.572 0 270)
			(size 1.778 0.4572)
			(layers "F.Cu" "F.Mask" "F.Paste")
			(net "PVPP_GHJ")
		)
	)
	(footprint ""
		(layer "F.Cu")
		(at 343.789 -23.45436 90)
		(property "Reference" "C7F9"
			(at 0 0 90)
			(layer "F.SilkS")
			(hide yes)
			(effects
				(font
					(size 1.27 1.27)
				)
			)
		)
		(property "Value" ""
			(at 0 0 90)
			(layer "F.Fab")
			(effects
				(font
					(size 1.27 1.27)
				)
			)
		)
		(duplicate_pad_numbers_are_jumpers no)
		(fp_poly
			(pts
				(xy 0.3048 -0.1016) (xy 0.3048 0.9906) (xy -0.3048 0.9906) (xy -0.3048 -0.1016)
			)
			(stroke
				(width 0)
				(type default)
			)
			(fill no)
			(layer "F.CrtYd")
		)
		(fp_line
			(start 0.3048 -0.1016)
			(end -0.3048 -0.1016)
			(stroke
				(width 0.1)
				(type default)
			)
			(layer "F.Fab")
		)
		(fp_line
			(start -0.3048 -0.1016)
			(end -0.3048 0.9906)
			(stroke
				(width 0.1)
				(type default)
			)
			(layer "F.Fab")
		)
		(fp_line
			(start 0.3048 0.9906)
			(end 0.3048 -0.1016)
			(stroke
				(width 0.1)
				(type default)
			)
			(layer "F.Fab")
		)
		(fp_line
			(start -0.3048 0.9906)
			(end 0.3048 0.9906)
			(stroke
				(width 0.1)
				(type default)
			)
			(layer "F.Fab")
		)
		(pad "1" smd rect
			(at 0 0 90)
			(size 0.508 0.508)
			(layers "F.Cu" "F.Mask" "F.Paste")
			(net "VR_FB_PVPP_ABC")
		)
		(pad "2" smd rect
			(at 0 0.889 90)
			(size 0.508 0.508)
			(layers "F.Cu" "F.Mask" "F.Paste")
			(net "VR_COMP_PVPP_ABC_3")
		)
		(zone
			(layer "F.Cu")
			(hatch none 0.5)
			(connect_pads
				(clearance 0)
			)
			(min_thickness 0.25)
			(keepout
				(tracks allowed)
				(vias not_allowed)
				(pads allowed)
				(copperpour not_allowed)
				(footprints allowed)
			)
			(placement
				(enabled no)
				(sheetname "")
			)
			(fill
				(thermal_gap 0.5)
				(thermal_bridge_width 0.5)
				(island_removal_mode 0)
			)
			(polygon
				(pts
					(xy 344.043 -23.20036) (xy 344.043 -23.70836) (xy 344.424 -23.70836) (xy 344.424 -23.20036)
				)
			)
		)
		(zone
			(layer "F.Cu")
			(hatch none 0.5)
			(connect_pads
				(clearance 0)
			)
			(min_thickness 0.25)
			(keepout
				(tracks not_allowed)
				(vias allowed)
				(pads allowed)
				(copperpour not_allowed)
				(footprints allowed)
			)
			(placement
				(enabled no)
				(sheetname "")
			)
			(fill
				(thermal_gap 0.5)
				(thermal_bridge_width 0.5)
				(island_removal_mode 0)
			)
			(polygon
				(pts
					(xy 344.424 -23.20036) (xy 344.424 -23.70836) (xy 344.043 -23.70836) (xy 344.043 -23.20036)
				)
			)
		)
	)
	(footprint ""
		(layer "F.Cu")
		(at 334.518 -11.3792 180)
		(property "Reference" "C7G28"
			(at 3.02133 6.9088 90)
			(unlocked yes)
			(layer "F.SilkS")
			(effects
				(font
					(size 0.7874 0.5842)
					(thickness 0.1524)
				)
			)
		)
		(property "Value" ""
			(at 0 0 180)
			(layer "F.Fab")
			(effects
				(font
					(size 1.27 1.27)
				)
			)
		)
		(duplicate_pad_numbers_are_jumpers no)
		(fp_line
			(start 2.504948 1.633728)
			(end 1.6002 1.633728)
			(stroke
				(width 0.1524)
				(type default)
			)
			(layer "F.SilkS")
		)
		(fp_line
			(start 2.504948 -1.616456)
			(end 2.504948 1.633728)
			(stroke
				(width 0.1524)
				(type default)
			)
			(layer "F.SilkS")
		)
		(fp_line
			(start 2.286 7.366)
			(end 2.286 1.63195)
			(stroke
				(width 0.1524)
				(type default)
			)
			(layer "F.SilkS")
		)
		(fp_line
			(start 2.286 7.366)
			(end 1.600708 7.366)
			(stroke
				(width 0.1524)
				(type default)
			)
			(layer "F.SilkS")
		)
		(fp_line
			(start 1.6002 -1.616456)
			(end 2.504948 -1.616456)
			(stroke
				(width 0.1524)
				(type default)
			)
			(layer "F.SilkS")
		)
		(fp_line
			(start -1.6002 -1.616456)
			(end -2.563114 -1.616456)
			(stroke
				(width 0.1524)
				(type default)
			)
			(layer "F.SilkS")
		)
		(fp_line
			(start -2.286 7.366)
			(end -1.60147 7.366)
			(stroke
				(width 0.1524)
				(type default)
			)
			(layer "F.SilkS")
		)
		(fp_line
			(start -2.286 7.366)
			(end -2.286 1.632712)
			(stroke
				(width 0.1524)
				(type default)
			)
			(layer "F.SilkS")
		)
		(fp_line
			(start -2.563114 1.633728)
			(end -1.6002 1.633728)
			(stroke
				(width 0.1524)
				(type default)
			)
			(layer "F.SilkS")
		)
		(fp_line
			(start -2.563114 -1.616456)
			(end -2.563114 1.633728)
			(stroke
				(width 0.1524)
				(type default)
			)
			(layer "F.SilkS")
		)
		(fp_rect
			(start 2.286 -0.254)
			(end -2.286 7.366)
			(stroke
				(width 0)
				(type default)
			)
			(fill no)
			(layer "F.CrtYd")
		)
		(fp_line
			(start 2.286 7.366)
			(end -2.286 7.366)
			(stroke
				(width 0.1)
				(type default)
			)
			(layer "F.Fab")
		)
		(fp_line
			(start 2.286 -0.254)
			(end 2.286 7.366)
			(stroke
				(width 0.1)
				(type default)
			)
			(layer "F.Fab")
		)
		(fp_line
			(start -2.286 7.366)
			(end -2.286 -0.254)
			(stroke
				(width 0.1)
				(type default)
			)
			(layer "F.Fab")
		)
		(fp_line
			(start -2.286 -0.254)
			(end 2.286 -0.254)
			(stroke
				(width 0.1)
				(type default)
			)
			(layer "F.Fab")
		)
		(pad "1" smd rect
			(at 0 0 180)
			(size 2.54 3.048)
			(layers "F.Cu" "F.Mask" "F.Paste")
			(net "PVDDQ_ABC")
		)
		(pad "2" smd rect
			(at 0 7.112 180)
			(size 2.54 3.048)
			(layers "F.Cu" "F.Mask" "F.Paste")
			(net "GND")
		)
	)
	(footprint ""
		(layer "F.Cu")
		(at 394.9192 -0.2286)
		(property "Reference" "R8G14"
			(at 0 0 0)
			(layer "F.SilkS")
			(hide yes)
			(effects
				(font
					(size 1.27 1.27)
				)
			)
		)
		(property "Value" ""
			(at 0 0 0)
			(layer "F.Fab")
			(effects
				(font
					(size 1.27 1.27)
				)
			)
		)
		(duplicate_pad_numbers_are_jumpers no)
		(fp_poly
			(pts
				(xy -0.2794 -0.1016) (xy 0.2794 -0.1016) (xy 0.2794 0.9906) (xy -0.2794 0.9906)
			)
			(stroke
				(width 0)
				(type default)
			)
			(fill no)
			(layer "F.CrtYd")
		)
		(fp_line
			(start -0.2794 -0.1016)
			(end -0.2794 0.9906)
			(stroke
				(width 0.1)
				(type default)
			)
			(layer "F.Fab")
		)
		(fp_line
			(start -0.2794 0.9906)
			(end 0.2794 0.9906)
			(stroke
				(width 0.1)
				(type default)
			)
			(layer "F.Fab")
		)
		(fp_line
			(start 0.2794 -0.1016)
			(end -0.2794 -0.1016)
			(stroke
				(width 0.1)
				(type default)
			)
			(layer "F.Fab")
		)
		(fp_line
			(start 0.2794 0.9906)
			(end 0.2794 -0.1016)
			(stroke
				(width 0.1)
				(type default)
			)
			(layer "F.Fab")
		)
		(pad "1" smd rect
			(at 0 0)
			(size 0.508 0.508)
			(layers "F.Cu" "F.Mask" "F.Paste")
			(net "JTAG_BMC_TMS")
		)
		(pad "2" smd rect
			(at 0 0.889)
			(size 0.508 0.508)
			(layers "F.Cu" "F.Mask" "F.Paste")
			(net "JTAG_TMS")
		)
		(zone
			(layer "F.Cu")
			(hatch none 0.5)
			(connect_pads
				(clearance 0)
			)
			(min_thickness 0.25)
			(keepout
				(tracks allowed)
				(vias not_allowed)
				(pads allowed)
				(copperpour not_allowed)
				(footprints allowed)
			)
			(placement
				(enabled no)
				(sheetname "")
			)
			(fill
				(thermal_gap 0.5)
				(thermal_bridge_width 0.5)
				(island_removal_mode 0)
			)
			(polygon
				(pts
					(xy 394.6652 0.0254) (xy 395.1732 0.0254) (xy 395.1732 0.4064) (xy 394.6652 0.4064)
				)
			)
		)
		(zone
			(layer "F.Cu")
			(hatch none 0.5)
			(connect_pads
				(clearance 0)
			)
			(min_thickness 0.25)
			(keepout
				(tracks not_allowed)
				(vias allowed)
				(pads allowed)
				(copperpour not_allowed)
				(footprints allowed)
			)
			(placement
				(enabled no)
				(sheetname "")
			)
			(fill
				(thermal_gap 0.5)
				(thermal_bridge_width 0.5)
				(island_removal_mode 0)
			)
			(polygon
				(pts
					(xy 394.6652 0.4064) (xy 395.1732 0.4064) (xy 395.1732 0.0254) (xy 394.6652 0.0254)
				)
			)
		)
	)
	(footprint ""
		(layer "F.Cu")
		(at 404.03018 -145.085816 -90)
		(property "Reference" "R8A12"
			(at 0 0 270)
			(layer "F.SilkS")
			(hide yes)
			(effects
				(font
					(size 1.27 1.27)
				)
			)
		)
		(property "Value" ""
			(at 0 0 270)
			(layer "F.Fab")
			(effects
				(font
					(size 1.27 1.27)
				)
			)
		)
		(duplicate_pad_numbers_are_jumpers no)
		(fp_poly
			(pts
				(xy -0.4953 -0.2032) (xy 0.4953 -0.2032) (xy 0.4953 1.6002) (xy -0.4953 1.6002)
			)
			(stroke
				(width 0)
				(type default)
			)
			(fill no)
			(layer "F.CrtYd")
		)
		(fp_line
			(start -0.4953 1.6002)
			(end -0.4953 -0.2032)
			(stroke
				(width 0.1)
				(type default)
			)
			(layer "F.Fab")
		)
		(fp_line
			(start 0.4953 1.6002)
			(end -0.4953 1.6002)
			(stroke
				(width 0.1)
				(type default)
			)
			(layer "F.Fab")
		)
		(fp_line
			(start -0.4953 -0.2032)
			(end 0.4953 -0.2032)
			(stroke
				(width 0.1)
				(type default)
			)
			(layer "F.Fab")
		)
		(fp_line
			(start 0.4953 -0.2032)
			(end 0.4953 1.6002)
			(stroke
				(width 0.1)
				(type default)
			)
			(layer "F.Fab")
		)
		(pad "1" smd rect
			(at 0 0 270)
			(size 0.762 0.889)
			(layers "F.Cu" "F.Mask" "F.Paste")
			(net "P1V8_PCH_STBY")
		)
		(pad "2" smd rect
			(at 0 1.397 270)
			(size 0.762 0.889)
			(layers "F.Cu" "F.Mask" "F.Paste")
			(net "GND")
		)
		(zone
			(layer "F.Cu")
			(hatch none 0.5)
			(connect_pads
				(clearance 0)
			)
			(min_thickness 0.25)
			(keepout
				(tracks not_allowed)
				(vias allowed)
				(pads allowed)
				(copperpour not_allowed)
				(footprints allowed)
			)
			(placement
				(enabled no)
				(sheetname "")
			)
			(fill
				(thermal_gap 0.5)
				(thermal_bridge_width 0.5)
				(island_removal_mode 0)
			)
			(polygon
				(pts
					(xy 403.07768 -145.466816) (xy 403.07768 -144.704816) (xy 403.58568 -144.704816) (xy 403.58568 -145.466816)
				)
			)
		)
		(zone
			(layer "F.Cu")
			(hatch none 0.5)
			(connect_pads
				(clearance 0)
			)
			(min_thickness 0.25)
			(keepout
				(tracks allowed)
				(vias not_allowed)
				(pads allowed)
				(copperpour not_allowed)
				(footprints allowed)
			)
			(placement
				(enabled no)
				(sheetname "")
			)
			(fill
				(thermal_gap 0.5)
				(thermal_bridge_width 0.5)
				(island_removal_mode 0)
			)
			(polygon
				(pts
					(xy 403.07768 -144.704816) (xy 403.58568 -144.704816) (xy 403.58568 -145.466816) (xy 403.07768 -145.466816)
				)
			)
		)
	)
	(footprint ""
		(layer "F.Cu")
		(at 29.807916 -22.105366 180)
		(property "Reference" "R1F6"
			(at 0 0 180)
			(layer "F.SilkS")
			(hide yes)
			(effects
				(font
					(size 1.27 1.27)
				)
			)
		)
		(property "Value" ""
			(at 0 0 180)
			(layer "F.Fab")
			(effects
				(font
					(size 1.27 1.27)
				)
			)
		)
		(duplicate_pad_numbers_are_jumpers no)
		(fp_poly
			(pts
				(xy -0.2794 -0.1016) (xy 0.2794 -0.1016) (xy 0.2794 0.9906) (xy -0.2794 0.9906)
			)
			(stroke
				(width 0)
				(type default)
			)
			(fill no)
			(layer "F.CrtYd")
		)
		(fp_line
			(start 0.2794 0.9906)
			(end 0.2794 -0.1016)
			(stroke
				(width 0.1)
				(type default)
			)
			(layer "F.Fab")
		)
		(fp_line
			(start 0.2794 -0.1016)
			(end -0.2794 -0.1016)
			(stroke
				(width 0.1)
				(type default)
			)
			(layer "F.Fab")
		)
		(fp_line
			(start -0.2794 0.9906)
			(end 0.2794 0.9906)
			(stroke
				(width 0.1)
				(type default)
			)
			(layer "F.Fab")
		)
		(fp_line
			(start -0.2794 -0.1016)
			(end -0.2794 0.9906)
			(stroke
				(width 0.1)
				(type default)
			)
			(layer "F.Fab")
		)
		(pad "1" smd rect
			(at 0 0 180)
			(size 0.508 0.508)
			(layers "F.Cu" "F.Mask" "F.Paste")
			(net "M_G_VREF")
		)
		(pad "2" smd rect
			(at 0 0.889 180)
			(size 0.508 0.508)
			(layers "F.Cu" "F.Mask" "F.Paste")
			(net "GND")
		)
		(zone
			(layer "F.Cu")
			(hatch none 0.5)
			(connect_pads
				(clearance 0)
			)
			(min_thickness 0.25)
			(keepout
				(tracks not_allowed)
				(vias allowed)
				(pads allowed)
				(copperpour not_allowed)
				(footprints allowed)
			)
			(placement
				(enabled no)
				(sheetname "")
			)
			(fill
				(thermal_gap 0.5)
				(thermal_bridge_width 0.5)
				(island_removal_mode 0)
			)
			(polygon
				(pts
					(xy 30.061916 -22.740366) (xy 29.553916 -22.740366) (xy 29.553916 -22.359366) (xy 30.061916 -22.359366)
				)
			)
		)
		(zone
			(layer "F.Cu")
			(hatch none 0.5)
			(connect_pads
				(clearance 0)
			)
			(min_thickness 0.25)
			(keepout
				(tracks allowed)
				(vias not_allowed)
				(pads allowed)
				(copperpour not_allowed)
				(footprints allowed)
			)
			(placement
				(enabled no)
				(sheetname "")
			)
			(fill
				(thermal_gap 0.5)
				(thermal_bridge_width 0.5)
				(island_removal_mode 0)
			)
			(polygon
				(pts
					(xy 30.061916 -22.359366) (xy 29.553916 -22.359366) (xy 29.553916 -22.740366) (xy 30.061916 -22.740366)
				)
			)
		)
	)
	(footprint ""
		(layer "F.Cu")
		(at 193.6242 -55.0164)
		(property "Reference" "R4E22"
			(at 0 0 0)
			(layer "F.SilkS")
			(hide yes)
			(effects
				(font
					(size 1.27 1.27)
				)
			)
		)
		(property "Value" ""
			(at 0 0 0)
			(layer "F.Fab")
			(effects
				(font
					(size 1.27 1.27)
				)
			)
		)
		(duplicate_pad_numbers_are_jumpers no)
		(fp_poly
			(pts
				(xy -0.2794 -0.1016) (xy 0.2794 -0.1016) (xy 0.2794 0.9906) (xy -0.2794 0.9906)
			)
			(stroke
				(width 0)
				(type default)
			)
			(fill no)
			(layer "F.CrtYd")
		)
		(fp_line
			(start -0.2794 -0.1016)
			(end -0.2794 0.9906)
			(stroke
				(width 0.1)
				(type default)
			)
			(layer "F.Fab")
		)
		(fp_line
			(start -0.2794 0.9906)
			(end 0.2794 0.9906)
			(stroke
				(width 0.1)
				(type default)
			)
			(layer "F.Fab")
		)
		(fp_line
			(start 0.2794 -0.1016)
			(end -0.2794 -0.1016)
			(stroke
				(width 0.1)
				(type default)
			)
			(layer "F.Fab")
		)
		(fp_line
			(start 0.2794 0.9906)
			(end 0.2794 -0.1016)
			(stroke
				(width 0.1)
				(type default)
			)
			(layer "F.Fab")
		)
		(pad "1" smd rect
			(at 0 0)
			(size 0.508 0.508)
			(layers "F.Cu" "F.Mask" "F.Paste")
			(net "VR_PVCCIN_CPU0_PH1_OCSET")
		)
		(pad "2" smd rect
			(at 0 0.889)
			(size 0.508 0.508)
			(layers "F.Cu" "F.Mask" "F.Paste")
			(net "GND")
		)
		(zone
			(layer "F.Cu")
			(hatch none 0.5)
			(connect_pads
				(clearance 0)
			)
			(min_thickness 0.25)
			(keepout
				(tracks allowed)
				(vias not_allowed)
				(pads allowed)
				(copperpour not_allowed)
				(footprints allowed)
			)
			(placement
				(enabled no)
				(sheetname "")
			)
			(fill
				(thermal_gap 0.5)
				(thermal_bridge_width 0.5)
				(island_removal_mode 0)
			)
			(polygon
				(pts
					(xy 193.3702 -54.7624) (xy 193.8782 -54.7624) (xy 193.8782 -54.3814) (xy 193.3702 -54.3814)
				)
			)
		)
		(zone
			(layer "F.Cu")
			(hatch none 0.5)
			(connect_pads
				(clearance 0)
			)
			(min_thickness 0.25)
			(keepout
				(tracks not_allowed)
				(vias allowed)
				(pads allowed)
				(copperpour not_allowed)
				(footprints allowed)
			)
			(placement
				(enabled no)
				(sheetname "")
			)
			(fill
				(thermal_gap 0.5)
				(thermal_bridge_width 0.5)
				(island_removal_mode 0)
			)
			(polygon
				(pts
					(xy 193.3702 -54.3814) (xy 193.8782 -54.3814) (xy 193.8782 -54.7624) (xy 193.3702 -54.7624)
				)
			)
		)
	)
	(footprint ""
		(layer "F.Cu")
		(at 436.547006 -43.556174 180)
		(property "Reference" "R25W45"
			(at 0 0 180)
			(layer "F.SilkS")
			(hide yes)
			(effects
				(font
					(size 1.27 1.27)
				)
			)
		)
		(property "Value" "*"
			(at 0.064008 -4.108196 180)
			(unlocked yes)
			(layer "F.Fab")
			(hide yes)
			(effects
				(font
					(size 1.27 1.016)
					(thickness 0.1524)
				)
			)
		)
		(property "Device Type" "120R2F-GP_RCL_GP-120R2F-GP,64.A"
			(at 0.064008 -5.632196 180)
			(unlocked yes)
			(layer "F.Fab")
			(hide yes)
			(effects
				(font
					(size 1.27 1.016)
					(thickness 0.1524)
				)
			)
		)
		(duplicate_pad_numbers_are_jumpers no)
		(fp_line
			(start 0.508 -0.9398)
			(end -0.508 -0.9398)
			(stroke
				(width 0.1524)
				(type default)
			)
			(layer "F.SilkS")
		)
		(fp_line
			(start -0.508 -0.9398)
			(end -0.508 0.9398)
			(stroke
				(width 0.1524)
				(type default)
			)
			(layer "F.SilkS")
		)
		(fp_rect
			(start -0.508 0.9398)
			(end 0.508 -0.9398)
			(stroke
				(width 0)
				(type default)
			)
			(fill no)
			(layer "F.CrtYd")
		)
		(fp_rect
			(start -0.508 0.9398)
			(end 0.508 -0.9398)
			(stroke
				(width 0)
				(type default)
			)
			(fill no)
			(layer "F.Fab")
		)
		(pad "1" smd custom
			(at 0 -0.4445 180)
			(size 0.1397 0.1397)
			(layers "F.Cu" "F.Mask" "F.Paste")
			(net "BMC_M_A7")
			(options
				(clearance outline)
				(anchor circle)
			)
			(primitives
				(gr_poly
					(pts
						(arc
							(start -0.1778 -0.2794)
							(mid -0.249642 -0.249642)
							(end -0.2794 -0.1778)
						)
						(arc
							(start -0.2794 0.1778)
							(mid -0.249642 0.249642)
							(end -0.1778 0.2794)
						)
						(arc
							(start 0.1778 0.2794)
							(mid 0.249642 0.249642)
							(end 0.2794 0.1778)
						)
						(arc
							(start 0.2794 -0.1778)
							(mid 0.249642 -0.249642)
							(end 0.1778 -0.2794)
						)
					)
					(width 0)
					(fill yes)
				)
			)
		)
		(pad "2" smd custom
			(at 0 0.4445 180)
			(size 0.1397 0.1397)
			(layers "F.Cu" "F.Mask" "F.Paste")
			(net "P1V2_AUX_BMC")
			(options
				(clearance outline)
				(anchor circle)
			)
			(primitives
				(gr_poly
					(pts
						(arc
							(start -0.1778 -0.2794)
							(mid -0.249642 -0.249642)
							(end -0.2794 -0.1778)
						)
						(arc
							(start -0.2794 0.1778)
							(mid -0.249642 0.249642)
							(end -0.1778 0.2794)
						)
						(arc
							(start 0.1778 0.2794)
							(mid 0.249642 0.249642)
							(end 0.2794 0.1778)
						)
						(arc
							(start 0.2794 -0.1778)
							(mid 0.249642 -0.249642)
							(end 0.1778 -0.2794)
						)
					)
					(width 0)
					(fill yes)
				)
			)
		)
	)
	(footprint ""
		(layer "F.Cu")
		(at 180.975 -5.334)
		(property "Reference" "R4G18"
			(at 0 0 0)
			(layer "F.SilkS")
			(hide yes)
			(effects
				(font
					(size 1.27 1.27)
				)
			)
		)
		(property "Value" ""
			(at 0 0 0)
			(layer "F.Fab")
			(effects
				(font
					(size 1.27 1.27)
				)
			)
		)
		(duplicate_pad_numbers_are_jumpers no)
		(fp_rect
			(start 0.2794 0.9906)
			(end -0.2794 -0.1016)
			(stroke
				(width 0)
				(type default)
			)
			(fill no)
			(layer "F.CrtYd")
		)
		(fp_line
			(start -0.2794 -0.1016)
			(end -0.2794 0.9906)
			(stroke
				(width 0.1)
				(type default)
			)
			(layer "F.Fab")
		)
		(fp_line
			(start -0.2794 0.9906)
			(end 0.2794 0.9906)
			(stroke
				(width 0.1)
				(type default)
			)
			(layer "F.Fab")
		)
		(fp_line
			(start 0.2794 -0.1016)
			(end -0.2794 -0.1016)
			(stroke
				(width 0.1)
				(type default)
			)
			(layer "F.Fab")
		)
		(fp_line
			(start 0.2794 0.9906)
			(end 0.2794 -0.1016)
			(stroke
				(width 0.1)
				(type default)
			)
			(layer "F.Fab")
		)
		(pad "1" smd rect
			(at 0 0)
			(size 0.508 0.508)
			(layers "F.Cu" "F.Mask" "F.Paste")
			(net "P3V3")
		)
		(pad "2" smd rect
			(at 0 0.889)
			(size 0.508 0.508)
			(layers "F.Cu" "F.Mask" "F.Paste")
			(net "PWRGD_PVTT_ABC_CPU0_R")
		)
		(zone
			(layer "F.Cu")
			(hatch none 0.5)
			(connect_pads
				(clearance 0)
			)
			(min_thickness 0.25)
			(keepout
				(tracks not_allowed)
				(vias allowed)
				(pads allowed)
				(copperpour not_allowed)
				(footprints allowed)
			)
			(placement
				(enabled no)
				(sheetname "")
			)
			(fill
				(thermal_gap 0.5)
				(thermal_bridge_width 0.5)
				(island_removal_mode 0)
			)
			(polygon
				(pts
					(xy 181.229 -4.699) (xy 181.229 -5.08) (xy 180.721 -5.08) (xy 180.721 -4.699)
				)
			)
		)
		(zone
			(layer "F.Cu")
			(hatch none 0.5)
			(connect_pads
				(clearance 0)
			)
			(min_thickness 0.25)
			(keepout
				(tracks allowed)
				(vias not_allowed)
				(pads allowed)
				(copperpour not_allowed)
				(footprints allowed)
			)
			(placement
				(enabled no)
				(sheetname "")
			)
			(fill
				(thermal_gap 0.5)
				(thermal_bridge_width 0.5)
				(island_removal_mode 0)
			)
			(polygon
				(pts
					(xy 181.229 -4.699) (xy 181.229 -5.08) (xy 180.721 -5.08) (xy 180.721 -4.699)
				)
			)
		)
	)
	(footprint ""
		(layer "F.Cu")
		(at 378.46 -87.3125 180)
		(property "Reference" "R7D2"
			(at 0 0 180)
			(layer "F.SilkS")
			(hide yes)
			(effects
				(font
					(size 1.27 1.27)
				)
			)
		)
		(property "Value" ""
			(at 0 0 180)
			(layer "F.Fab")
			(effects
				(font
					(size 1.27 1.27)
				)
			)
		)
		(duplicate_pad_numbers_are_jumpers no)
		(fp_poly
			(pts
				(xy -0.2794 -0.1016) (xy 0.2794 -0.1016) (xy 0.2794 0.9906) (xy -0.2794 0.9906)
			)
			(stroke
				(width 0)
				(type default)
			)
			(fill no)
			(layer "F.CrtYd")
		)
		(fp_line
			(start 0.2794 0.9906)
			(end 0.2794 -0.1016)
			(stroke
				(width 0.1)
				(type default)
			)
			(layer "F.Fab")
		)
		(fp_line
			(start 0.2794 -0.1016)
			(end -0.2794 -0.1016)
			(stroke
				(width 0.1)
				(type default)
			)
			(layer "F.Fab")
		)
		(fp_line
			(start -0.2794 0.9906)
			(end 0.2794 0.9906)
			(stroke
				(width 0.1)
				(type default)
			)
			(layer "F.Fab")
		)
		(fp_line
			(start -0.2794 -0.1016)
			(end -0.2794 0.9906)
			(stroke
				(width 0.1)
				(type default)
			)
			(layer "F.Fab")
		)
		(pad "1" smd rect
			(at 0 0 180)
			(size 0.508 0.508)
			(layers "F.Cu" "F.Mask" "F.Paste")
			(net "P3V3_STBY")
		)
		(pad "2" smd rect
			(at 0 0.889 180)
			(size 0.508 0.508)
			(layers "F.Cu" "F.Mask" "F.Paste")
			(net "PU_FM_RCIN_N")
		)
		(zone
			(layer "F.Cu")
			(hatch none 0.5)
			(connect_pads
				(clearance 0)
			)
			(min_thickness 0.25)
			(keepout
				(tracks not_allowed)
				(vias allowed)
				(pads allowed)
				(copperpour not_allowed)
				(footprints allowed)
			)
			(placement
				(enabled no)
				(sheetname "")
			)
			(fill
				(thermal_gap 0.5)
				(thermal_bridge_width 0.5)
				(island_removal_mode 0)
			)
			(polygon
				(pts
					(xy 378.714 -87.9475) (xy 378.206 -87.9475) (xy 378.206 -87.5665) (xy 378.714 -87.5665)
				)
			)
		)
		(zone
			(layer "F.Cu")
			(hatch none 0.5)
			(connect_pads
				(clearance 0)
			)
			(min_thickness 0.25)
			(keepout
				(tracks allowed)
				(vias not_allowed)
				(pads allowed)
				(copperpour not_allowed)
				(footprints allowed)
			)
			(placement
				(enabled no)
				(sheetname "")
			)
			(fill
				(thermal_gap 0.5)
				(thermal_bridge_width 0.5)
				(island_removal_mode 0)
			)
			(polygon
				(pts
					(xy 378.714 -87.5665) (xy 378.206 -87.5665) (xy 378.206 -87.9475) (xy 378.714 -87.9475)
				)
			)
		)
	)
	(footprint ""
		(layer "F.Cu")
		(at 409.1305 -50.038 90)
		(property "Reference" "R8D28"
			(at 0 0 90)
			(layer "F.SilkS")
			(hide yes)
			(effects
				(font
					(size 1.27 1.27)
				)
			)
		)
		(property "Value" ""
			(at 0 0 90)
			(layer "F.Fab")
			(effects
				(font
					(size 1.27 1.27)
				)
			)
		)
		(duplicate_pad_numbers_are_jumpers no)
		(fp_poly
			(pts
				(xy -0.2794 -0.1016) (xy 0.2794 -0.1016) (xy 0.2794 0.9906) (xy -0.2794 0.9906)
			)
			(stroke
				(width 0)
				(type default)
			)
			(fill no)
			(layer "F.CrtYd")
		)
		(fp_line
			(start 0.2794 -0.1016)
			(end -0.2794 -0.1016)
			(stroke
				(width 0.1)
				(type default)
			)
			(layer "F.Fab")
		)
		(fp_line
			(start -0.2794 -0.1016)
			(end -0.2794 0.9906)
			(stroke
				(width 0.1)
				(type default)
			)
			(layer "F.Fab")
		)
		(fp_line
			(start 0.2794 0.9906)
			(end 0.2794 -0.1016)
			(stroke
				(width 0.1)
				(type default)
			)
			(layer "F.Fab")
		)
		(fp_line
			(start -0.2794 0.9906)
			(end 0.2794 0.9906)
			(stroke
				(width 0.1)
				(type default)
			)
			(layer "F.Fab")
		)
		(pad "1" smd rect
			(at 0 0 90)
			(size 0.508 0.508)
			(layers "F.Cu" "F.Mask" "F.Paste")
			(net "P3V3_STBY")
		)
		(pad "2" smd rect
			(at 0 0.889 90)
			(size 0.508 0.508)
			(layers "F.Cu" "F.Mask" "F.Paste")
			(net "PU_AT24C64_A2")
		)
		(zone
			(layer "F.Cu")
			(hatch none 0.5)
			(connect_pads
				(clearance 0)
			)
			(min_thickness 0.25)
			(keepout
				(tracks allowed)
				(vias not_allowed)
				(pads allowed)
				(copperpour not_allowed)
				(footprints allowed)
			)
			(placement
				(enabled no)
				(sheetname "")
			)
			(fill
				(thermal_gap 0.5)
				(thermal_bridge_width 0.5)
				(island_removal_mode 0)
			)
			(polygon
				(pts
					(xy 409.3845 -49.784) (xy 409.3845 -50.292) (xy 409.7655 -50.292) (xy 409.7655 -49.784)
				)
			)
		)
		(zone
			(layer "F.Cu")
			(hatch none 0.5)
			(connect_pads
				(clearance 0)
			)
			(min_thickness 0.25)
			(keepout
				(tracks not_allowed)
				(vias allowed)
				(pads allowed)
				(copperpour not_allowed)
				(footprints allowed)
			)
			(placement
				(enabled no)
				(sheetname "")
			)
			(fill
				(thermal_gap 0.5)
				(thermal_bridge_width 0.5)
				(island_removal_mode 0)
			)
			(polygon
				(pts
					(xy 409.7655 -49.784) (xy 409.7655 -50.292) (xy 409.3845 -50.292) (xy 409.3845 -49.784)
				)
			)
		)
	)
	(footprint ""
		(layer "F.Cu")
		(at 458.177392 -38.591998 90)
		(property "Reference" "R9F8"
			(at 0 0 90)
			(layer "F.SilkS")
			(hide yes)
			(effects
				(font
					(size 1.27 1.27)
				)
			)
		)
		(property "Value" ""
			(at 0 0 90)
			(layer "F.Fab")
			(effects
				(font
					(size 1.27 1.27)
				)
			)
		)
		(duplicate_pad_numbers_are_jumpers no)
		(fp_poly
			(pts
				(xy -0.2794 -0.1016) (xy 0.2794 -0.1016) (xy 0.2794 0.9906) (xy -0.2794 0.9906)
			)
			(stroke
				(width 0)
				(type default)
			)
			(fill no)
			(layer "F.CrtYd")
		)
		(fp_line
			(start 0.2794 -0.1016)
			(end -0.2794 -0.1016)
			(stroke
				(width 0.1)
				(type default)
			)
			(layer "F.Fab")
		)
		(fp_line
			(start -0.2794 -0.1016)
			(end -0.2794 0.9906)
			(stroke
				(width 0.1)
				(type default)
			)
			(layer "F.Fab")
		)
		(fp_line
			(start 0.2794 0.9906)
			(end 0.2794 -0.1016)
			(stroke
				(width 0.1)
				(type default)
			)
			(layer "F.Fab")
		)
		(fp_line
			(start -0.2794 0.9906)
			(end 0.2794 0.9906)
			(stroke
				(width 0.1)
				(type default)
			)
			(layer "F.Fab")
		)
		(pad "1" smd rect
			(at 0 0 90)
			(size 0.508 0.508)
			(layers "F.Cu" "F.Mask" "F.Paste")
			(net "GND")
		)
		(pad "2" smd rect
			(at 0 0.889 90)
			(size 0.508 0.508)
			(layers "F.Cu" "F.Mask" "F.Paste")
			(net "VR_P1V15_BMC_STBY_FB")
		)
		(zone
			(layer "F.Cu")
			(hatch none 0.5)
			(connect_pads
				(clearance 0)
			)
			(min_thickness 0.25)
			(keepout
				(tracks allowed)
				(vias not_allowed)
				(pads allowed)
				(copperpour not_allowed)
				(footprints allowed)
			)
			(placement
				(enabled no)
				(sheetname "")
			)
			(fill
				(thermal_gap 0.5)
				(thermal_bridge_width 0.5)
				(island_removal_mode 0)
			)
			(polygon
				(pts
					(xy 458.431392 -38.337998) (xy 458.431392 -38.845998) (xy 458.812392 -38.845998) (xy 458.812392 -38.337998)
				)
			)
		)
		(zone
			(layer "F.Cu")
			(hatch none 0.5)
			(connect_pads
				(clearance 0)
			)
			(min_thickness 0.25)
			(keepout
				(tracks not_allowed)
				(vias allowed)
				(pads allowed)
				(copperpour not_allowed)
				(footprints allowed)
			)
			(placement
				(enabled no)
				(sheetname "")
			)
			(fill
				(thermal_gap 0.5)
				(thermal_bridge_width 0.5)
				(island_removal_mode 0)
			)
			(polygon
				(pts
					(xy 458.812392 -38.337998) (xy 458.812392 -38.845998) (xy 458.431392 -38.845998) (xy 458.431392 -38.337998)
				)
			)
		)
	)
	(footprint ""
		(layer "F.Cu")
		(at 330.962 -148.463 180)
		(property "Reference" "C6A4"
			(at 0 0 180)
			(layer "F.SilkS")
			(hide yes)
			(effects
				(font
					(size 1.27 1.27)
				)
			)
		)
		(property "Value" ""
			(at 0 0 180)
			(layer "F.Fab")
			(effects
				(font
					(size 1.27 1.27)
				)
			)
		)
		(duplicate_pad_numbers_are_jumpers no)
		(fp_rect
			(start -0.7239 1.9939)
			(end 0.7239 -0.2159)
			(stroke
				(width 0)
				(type default)
			)
			(fill no)
			(layer "F.CrtYd")
		)
		(fp_line
			(start 0.7239 1.9939)
			(end 0.7239 -0.2159)
			(stroke
				(width 0.1)
				(type default)
			)
			(layer "F.Fab")
		)
		(fp_line
			(start 0.7239 -0.2159)
			(end -0.7239 -0.2159)
			(stroke
				(width 0.1)
				(type default)
			)
			(layer "F.Fab")
		)
		(fp_line
			(start -0.7239 1.9939)
			(end 0.7239 1.9939)
			(stroke
				(width 0.1)
				(type default)
			)
			(layer "F.Fab")
		)
		(fp_line
			(start -0.7239 -0.2159)
			(end -0.7239 1.9939)
			(stroke
				(width 0.1)
				(type default)
			)
			(layer "F.Fab")
		)
		(pad "1" smd rect
			(at 0 0 180)
			(size 1.27 1.016)
			(layers "F.Cu" "F.Mask" "F.Paste")
			(net "PVDDQ_DEF")
		)
		(pad "2" smd rect
			(at 0 1.778 180)
			(size 1.27 1.016)
			(layers "F.Cu" "F.Mask" "F.Paste")
			(net "GND")
		)
		(zone
			(layer "F.Cu")
			(hatch none 0.5)
			(connect_pads
				(clearance 0)
			)
			(min_thickness 0.25)
			(keepout
				(tracks not_allowed)
				(vias allowed)
				(pads allowed)
				(copperpour not_allowed)
				(footprints allowed)
			)
			(placement
				(enabled no)
				(sheetname "")
			)
			(fill
				(thermal_gap 0.5)
				(thermal_bridge_width 0.5)
				(island_removal_mode 0)
			)
			(polygon
				(pts
					(xy 331.597 -149.733) (xy 330.327 -149.733) (xy 330.327 -148.971) (xy 331.597 -148.971)
				)
			)
		)
	)
	(footprint ""
		(layer "F.Cu")
		(at 49.4284 -78.359)
		(property "Reference" "C1D14"
			(at 0 0 0)
			(layer "F.SilkS")
			(hide yes)
			(effects
				(font
					(size 1.27 1.27)
				)
			)
		)
		(property "Value" ""
			(at 0 0 0)
			(layer "F.Fab")
			(effects
				(font
					(size 1.27 1.27)
				)
			)
		)
		(duplicate_pad_numbers_are_jumpers no)
		(fp_poly
			(pts
				(xy -0.4953 -0.2032) (xy 0.4953 -0.2032) (xy 0.4953 1.6002) (xy -0.4953 1.6002)
			)
			(stroke
				(width 0)
				(type default)
			)
			(fill no)
			(layer "F.CrtYd")
		)
		(fp_line
			(start -0.4953 -0.2032)
			(end 0.4953 -0.2032)
			(stroke
				(width 0.1)
				(type default)
			)
			(layer "F.Fab")
		)
		(fp_line
			(start -0.4953 1.6002)
			(end -0.4953 -0.2032)
			(stroke
				(width 0.1)
				(type default)
			)
			(layer "F.Fab")
		)
		(fp_line
			(start 0.4953 -0.2032)
			(end 0.4953 1.6002)
			(stroke
				(width 0.1)
				(type default)
			)
			(layer "F.Fab")
		)
		(fp_line
			(start 0.4953 1.6002)
			(end -0.4953 1.6002)
			(stroke
				(width 0.1)
				(type default)
			)
			(layer "F.Fab")
		)
		(pad "1" smd rect
			(at 0 0)
			(size 0.762 0.889)
			(layers "F.Cu" "F.Mask" "F.Paste")
			(net "PVCCIN_CPU1")
		)
		(pad "2" smd rect
			(at 0 1.397)
			(size 0.762 0.889)
			(layers "F.Cu" "F.Mask" "F.Paste")
			(net "GND")
		)
		(zone
			(layer "F.Cu")
			(hatch none 0.5)
			(connect_pads
				(clearance 0)
			)
			(min_thickness 0.25)
			(keepout
				(tracks not_allowed)
				(vias allowed)
				(pads allowed)
				(copperpour not_allowed)
				(footprints allowed)
			)
			(placement
				(enabled no)
				(sheetname "")
			)
			(fill
				(thermal_gap 0.5)
				(thermal_bridge_width 0.5)
				(island_removal_mode 0)
			)
			(polygon
				(pts
					(xy 49.0474 -77.9145) (xy 49.8094 -77.9145) (xy 49.8094 -77.4065) (xy 49.0474 -77.4065)
				)
			)
		)
	)
	(footprint ""
		(layer "F.Cu")
		(at 495.22126 -25.83942 -90)
		(property "Reference" "C8E19"
			(at 0 0 270)
			(layer "F.SilkS")
			(hide yes)
			(effects
				(font
					(size 1.27 1.27)
				)
			)
		)
		(property "Value" ""
			(at 0 0 270)
			(layer "F.Fab")
			(effects
				(font
					(size 1.27 1.27)
				)
			)
		)
		(duplicate_pad_numbers_are_jumpers no)
		(fp_rect
			(start 0.3048 0.9906)
			(end -0.3048 -0.1016)
			(stroke
				(width 0)
				(type default)
			)
			(fill no)
			(layer "F.CrtYd")
		)
		(fp_line
			(start -0.3048 0.9906)
			(end 0.3048 0.9906)
			(stroke
				(width 0.1)
				(type default)
			)
			(layer "F.Fab")
		)
		(fp_line
			(start 0.3048 0.9906)
			(end 0.3048 -0.1016)
			(stroke
				(width 0.1)
				(type default)
			)
			(layer "F.Fab")
		)
		(fp_line
			(start -0.3048 -0.1016)
			(end -0.3048 0.9906)
			(stroke
				(width 0.1)
				(type default)
			)
			(layer "F.Fab")
		)
		(fp_line
			(start 0.3048 -0.1016)
			(end -0.3048 -0.1016)
			(stroke
				(width 0.1)
				(type default)
			)
			(layer "F.Fab")
		)
		(pad "1" smd rect
			(at 0 0 270)
			(size 0.508 0.508)
			(layers "F.Cu" "F.Mask" "F.Paste")
			(net "P5V_STBY")
		)
		(pad "2" smd rect
			(at 0 0.889 270)
			(size 0.508 0.508)
			(layers "F.Cu" "F.Mask" "F.Paste")
			(net "GND")
		)
		(zone
			(layer "F.Cu")
			(hatch none 0.5)
			(connect_pads
				(clearance 0)
			)
			(min_thickness 0.25)
			(keepout
				(tracks allowed)
				(vias not_allowed)
				(pads allowed)
				(copperpour not_allowed)
				(footprints allowed)
			)
			(placement
				(enabled no)
				(sheetname "")
			)
			(fill
				(thermal_gap 0.5)
				(thermal_bridge_width 0.5)
				(island_removal_mode 0)
			)
			(polygon
				(pts
					(xy 494.58626 -25.58542) (xy 494.96726 -25.58542) (xy 494.96726 -26.09342) (xy 494.58626 -26.09342)
				)
			)
		)
		(zone
			(layer "F.Cu")
			(hatch none 0.5)
			(connect_pads
				(clearance 0)
			)
			(min_thickness 0.25)
			(keepout
				(tracks not_allowed)
				(vias allowed)
				(pads allowed)
				(copperpour not_allowed)
				(footprints allowed)
			)
			(placement
				(enabled no)
				(sheetname "")
			)
			(fill
				(thermal_gap 0.5)
				(thermal_bridge_width 0.5)
				(island_removal_mode 0)
			)
			(polygon
				(pts
					(xy 494.58626 -25.58542) (xy 494.96726 -25.58542) (xy 494.96726 -26.09342) (xy 494.58626 -26.09342)
				)
			)
		)
	)
	(footprint ""
		(layer "F.Cu")
		(at 437.930036 -135.64489 180)
		(property "Reference" "J2W2"
			(at 0 0 180)
			(layer "F.SilkS")
			(hide yes)
			(effects
				(font
					(size 1.27 1.27)
				)
			)
		)
		(property "Value" "*"
			(at -2.3622 -8.3185 180)
			(unlocked yes)
			(layer "F.Fab")
			(hide yes)
			(effects
				(font
					(size 1.27 1.016)
					(thickness 0.1524)
				)
			)
		)
		(property "Device Type" "SKT-SATA7P-6P-165-GP-U1_SOCKETA"
			(at -2.3622 -9.8425 180)
			(unlocked yes)
			(layer "F.Fab")
			(hide yes)
			(effects
				(font
					(size 1.27 1.016)
					(thickness 0.1524)
				)
			)
		)
		(duplicate_pad_numbers_are_jumpers no)
		(fp_line
			(start 17.8054 2.9337)
			(end -17.8054 2.9337)
			(stroke
				(width 0.1524)
				(type default)
			)
			(layer "F.SilkS")
		)
		(fp_line
			(start 17.8054 -3.3909)
			(end 17.8054 2.9337)
			(stroke
				(width 0.1524)
				(type default)
			)
			(layer "F.SilkS")
		)
		(fp_line
			(start -3.68808 0.649224)
			(end -3.68808 0.750824)
			(stroke
				(width 0.3048)
				(type default)
			)
			(layer "F.SilkS")
		)
		(fp_line
			(start -10.21207 0.750824)
			(end -10.21207 0.649224)
			(stroke
				(width 0.3048)
				(type default)
			)
			(layer "F.SilkS")
		)
		(fp_line
			(start -17.8054 2.9337)
			(end -17.8054 -3.3909)
			(stroke
				(width 0.1524)
				(type default)
			)
			(layer "F.SilkS")
		)
		(fp_line
			(start -17.8054 -3.3909)
			(end 17.8054 -3.3909)
			(stroke
				(width 0.1524)
				(type default)
			)
			(layer "F.SilkS")
		)
		(fp_arc
			(start 8.744966 1.28524)
			(mid 8.109966 1.563565)
			(end 7.474966 1.28524)
			(stroke
				(width 0.3048)
				(type default)
			)
			(layer "F.SilkS")
		)
		(fp_arc
			(start 8.744966 0.114808)
			(mid 10.243507 0.700024)
			(end 8.744966 1.28524)
			(stroke
				(width 0.3048)
				(type default)
			)
			(layer "F.SilkS")
		)
		(fp_arc
			(start 7.474966 1.28524)
			(mid 6.839966 1.563565)
			(end 6.204966 1.28524)
			(stroke
				(width 0.3048)
				(type default)
			)
			(layer "F.SilkS")
		)
		(fp_arc
			(start 7.474966 0.114808)
			(mid 8.109966 -0.163517)
			(end 8.744966 0.114808)
			(stroke
				(width 0.3048)
				(type default)
			)
			(layer "F.SilkS")
		)
		(fp_arc
			(start 6.204966 1.28524)
			(mid 5.569966 1.563565)
			(end 4.934966 1.28524)
			(stroke
				(width 0.3048)
				(type default)
			)
			(layer "F.SilkS")
		)
		(fp_arc
			(start 6.204966 0.114808)
			(mid 6.839966 -0.163517)
			(end 7.474966 0.114808)
			(stroke
				(width 0.3048)
				(type default)
			)
			(layer "F.SilkS")
		)
		(fp_arc
			(start 4.934966 1.28524)
			(mid 4.299966 1.563565)
			(end 3.664966 1.28524)
			(stroke
				(width 0.3048)
				(type default)
			)
			(layer "F.SilkS")
		)
		(fp_arc
			(start 4.934966 0.114808)
			(mid 5.569966 -0.163517)
			(end 6.204966 0.114808)
			(stroke
				(width 0.3048)
				(type default)
			)
			(layer "F.SilkS")
		)
		(fp_arc
			(start 3.664966 1.28524)
			(mid 3.029966 1.563565)
			(end 2.394966 1.28524)
			(stroke
				(width 0.3048)
				(type default)
			)
			(layer "F.SilkS")
		)
		(fp_arc
			(start 3.664966 0.114808)
			(mid 4.299966 -0.163517)
			(end 4.934966 0.114808)
			(stroke
				(width 0.3048)
				(type default)
			)
			(layer "F.SilkS")
		)
		(fp_arc
			(start 2.394966 1.28524)
			(mid 0.896425 0.700024)
			(end 2.394966 0.114808)
			(stroke
				(width 0.3048)
				(type default)
			)
			(layer "F.SilkS")
		)
		(fp_arc
			(start 2.394966 0.114808)
			(mid 3.029966 -0.163517)
			(end 3.664966 0.114808)
			(stroke
				(width 0.3048)
				(type default)
			)
			(layer "F.SilkS")
		)
		(fp_arc
			(start -3.68808 0.750824)
			(mid -4.134078 1.444212)
			(end -4.949952 1.32588)
			(stroke
				(width 0.3048)
				(type default)
			)
			(layer "F.SilkS")
		)
		(fp_arc
			(start -4.949952 1.32588)
			(mid -5.450078 1.512936)
			(end -5.950204 1.32588)
			(stroke
				(width 0.3048)
				(type default)
			)
			(layer "F.SilkS")
		)
		(fp_arc
			(start -4.949952 0.074168)
			(mid -4.134101 -0.044115)
			(end -3.68808 0.649224)
			(stroke
				(width 0.3048)
				(type default)
			)
			(layer "F.SilkS")
		)
		(fp_arc
			(start -5.950204 1.32588)
			(mid -6.450076 1.51277)
			(end -6.949948 1.32588)
			(stroke
				(width 0.3048)
				(type default)
			)
			(layer "F.SilkS")
		)
		(fp_arc
			(start -5.950204 0.074168)
			(mid -5.450078 -0.112888)
			(end -4.949952 0.074168)
			(stroke
				(width 0.3048)
				(type default)
			)
			(layer "F.SilkS")
		)
		(fp_arc
			(start -6.949948 1.32588)
			(mid -7.450074 1.512936)
			(end -7.9502 1.32588)
			(stroke
				(width 0.3048)
				(type default)
			)
			(layer "F.SilkS")
		)
		(fp_arc
			(start -6.949948 0.074168)
			(mid -6.450076 -0.112722)
			(end -5.950204 0.074168)
			(stroke
				(width 0.3048)
				(type default)
			)
			(layer "F.SilkS")
		)
		(fp_arc
			(start -7.9502 1.32588)
			(mid -8.450072 1.51277)
			(end -8.949944 1.32588)
			(stroke
				(width 0.3048)
				(type default)
			)
			(layer "F.SilkS")
		)
		(fp_arc
			(start -7.9502 0.074168)
			(mid -7.450074 -0.112888)
			(end -6.949948 0.074168)
			(stroke
				(width 0.3048)
				(type default)
			)
			(layer "F.SilkS")
		)
		(fp_arc
			(start -8.949944 1.32588)
			(mid -9.766031 1.444354)
			(end -10.21207 0.750824)
			(stroke
				(width 0.3048)
				(type default)
			)
			(layer "F.SilkS")
		)
		(fp_arc
			(start -8.949944 0.074168)
			(mid -8.450072 -0.112722)
			(end -7.9502 0.074168)
			(stroke
				(width 0.3048)
				(type default)
			)
			(layer "F.SilkS")
		)
		(fp_arc
			(start -10.21207 0.649224)
			(mid -9.765985 -0.044204)
			(end -8.949944 0.074168)
			(stroke
				(width 0.3048)
				(type default)
			)
			(layer "F.SilkS")
		)
		(fp_poly
			(pts
				(xy -15.9512 -3.1369) (xy -15.9512 -1.2446) (xy -17.0053 -1.2446) (xy -17.0053 1.2446) (xy -15.9512 1.2446)
				(xy -15.9512 2.6797) (xy 15.9512 2.6797) (xy 15.9512 1.2446) (xy 17.0053 1.2446) (xy 17.0053 -1.2446)
				(xy 15.9512 -1.2446) (xy 15.9512 -3.1369)
			)
			(stroke
				(width 0)
				(type default)
			)
			(fill no)
			(layer "F.CrtYd")
		)
		(fp_poly
			(pts
				(xy -18.0594 3.1877) (xy -18.0594 -3.6449) (xy 18.0594 -3.6449) (xy 18.0594 3.1877) (xy -0.4953 3.1877)
				(xy -0.4953 2.6797) (xy 15.9512 2.6797) (xy 15.9512 1.2446) (xy 17.0053 1.2446) (xy 17.0053 -1.2446)
				(xy 15.9512 -1.2446) (xy 15.9512 -3.1369) (xy -15.9512 -3.1369) (xy -15.9512 -1.2446) (xy -17.0053 -1.2446)
				(xy -17.0053 1.2446) (xy -15.9512 1.2446) (xy -15.9512 2.6797) (xy -0.508 2.6797) (xy -0.508 3.1877)
			)
			(stroke
				(width 0)
				(type default)
			)
			(fill no)
			(layer "F.CrtYd")
		)
		(fp_rect
			(start -18.0594 3.1877)
			(end 18.0594 -3.6449)
			(stroke
				(width 0)
				(type default)
			)
			(fill no)
			(layer "F.Fab")
		)
		(pad "" np_thru_hole circle
			(at -12.500102 -1.400048 180)
			(size 0.254 0.254)
			(drill 1.651)
			(layers "*.Cu" "*.Mask")
			(clearance 1.0541)
			(thermal_gap 1.0541)
		)
		(pad "" np_thru_hole circle
			(at 12.500102 -1.400048 180)
			(size 0.254 0.254)
			(drill 1.651)
			(layers "*.Cu" "*.Mask")
			(clearance 1.0541)
			(thermal_gap 1.0541)
		)
		(pad "H1" smd rect
			(at 16.249904 0 180)
			(size 2.5908 3.683)
			(layers "F.Cu" "F.Mask" "F.Paste")
			(net "GND")
		)
		(pad "H2" smd rect
			(at -16.249904 0 180)
			(size 2.5908 3.683)
			(layers "F.Cu" "F.Mask" "F.Paste")
			(net "GND")
		)
		(pad "P1" thru_hole oval
			(at -4.45008 0.700024 180)
			(size 0.8128 0.9144)
			(drill 0.5588)
			(layers "*.Cu" "*.Mask")
			(remove_unused_layers no)
			(net "P5V_HDD_SATA")
			(clearance 0.2286)
			(thermal_gap 0.2286)
		)
		(pad "P2" thru_hole oval
			(at -5.450078 0.700024 180)
			(size 0.8128 0.9144)
			(drill 0.5588)
			(layers "*.Cu" "*.Mask")
			(remove_unused_layers no)
			(net "P5V_HDD_SATA")
			(clearance 0.2286)
			(thermal_gap 0.2286)
		)
		(pad "P3" thru_hole oval
			(at -6.450076 0.700024 180)
			(size 0.8128 0.9144)
			(drill 0.5588)
			(layers "*.Cu" "*.Mask")
			(remove_unused_layers no)
			(net "GND")
			(clearance 0.2286)
			(thermal_gap 0.2286)
		)
		(pad "P4" thru_hole oval
			(at -7.450074 0.700024 180)
			(size 0.8128 0.9144)
			(drill 0.5588)
			(layers "*.Cu" "*.Mask")
			(remove_unused_layers no)
			(net "GND")
			(clearance 0.2286)
			(thermal_gap 0.2286)
		)
		(pad "P5" thru_hole oval
			(at -8.450072 0.700024 180)
			(size 0.8128 0.9144)
			(drill 0.5588)
			(layers "*.Cu" "*.Mask")
			(remove_unused_layers no)
			(net "P12V_HDD_SATA")
			(clearance 0.2286)
			(thermal_gap 0.2286)
		)
		(pad "P6" thru_hole oval
			(at -9.45007 0.700024 180)
			(size 0.8128 0.9144)
			(drill 0.5588)
			(layers "*.Cu" "*.Mask")
			(remove_unused_layers no)
			(net "P12V_HDD_SATA")
			(clearance 0.2286)
			(thermal_gap 0.2286)
		)
		(pad "S1" thru_hole circle
			(at 9.379966 0.700024 180)
			(size 1.016 1.016)
			(drill 0.6604)
			(layers "*.Cu" "*.Mask")
			(remove_unused_layers no)
			(net "GND")
			(clearance 0.1778)
			(thermal_gap 0.1778)
		)
		(pad "S2" thru_hole circle
			(at 8.109966 0.700024 180)
			(size 1.016 1.016)
			(drill 0.6604)
			(layers "*.Cu" "*.Mask")
			(remove_unused_layers no)
			(net "SATA6G_S1_TX_C_DP")
			(clearance 0.1778)
			(thermal_gap 0.1778)
		)
		(pad "S3" thru_hole circle
			(at 6.839966 0.700024 180)
			(size 1.016 1.016)
			(drill 0.6604)
			(layers "*.Cu" "*.Mask")
			(remove_unused_layers no)
			(net "SATA6G_S1_TX_C_DN")
			(clearance 0.1778)
			(thermal_gap 0.1778)
		)
		(pad "S4" thru_hole circle
			(at 5.569966 0.700024 180)
			(size 1.016 1.016)
			(drill 0.6604)
			(layers "*.Cu" "*.Mask")
			(remove_unused_layers no)
			(net "GND")
			(clearance 0.1778)
			(thermal_gap 0.1778)
		)
		(pad "S5" thru_hole circle
			(at 4.299966 0.700024 180)
			(size 1.016 1.016)
			(drill 0.6604)
			(layers "*.Cu" "*.Mask")
			(remove_unused_layers no)
			(net "SATA6G_S1_RX_C_DN")
			(clearance 0.1778)
			(thermal_gap 0.1778)
		)
		(pad "S6" thru_hole circle
			(at 3.029966 0.700024 180)
			(size 1.016 1.016)
			(drill 0.6604)
			(layers "*.Cu" "*.Mask")
			(remove_unused_layers no)
			(net "SATA6G_S1_RX_C_DP")
			(clearance 0.1778)
			(thermal_gap 0.1778)
		)
		(pad "S7" thru_hole circle
			(at 1.759966 0.700024 180)
			(size 1.016 1.016)
			(drill 0.6604)
			(layers "*.Cu" "*.Mask")
			(remove_unused_layers no)
			(net "GND")
			(clearance 0.1778)
			(thermal_gap 0.1778)
		)
		(zone
			(layers "F.Cu" "B.Cu" "In1.Cu" "In2.Cu" "In3.Cu" "In4.Cu" "In5.Cu" "In6.Cu"
				"In7.Cu" "In8.Cu" "In9.Cu" "In10.Cu" "In11.Cu" "In12.Cu"
			)
			(hatch none 0.5)
			(connect_pads
				(clearance 0)
			)
			(min_thickness 0.25)
			(keepout
				(tracks not_allowed)
				(vias allowed)
				(pads allowed)
				(copperpour not_allowed)
				(footprints allowed)
			)
			(placement
				(enabled no)
				(sheetname "")
			)
			(fill
				(thermal_gap 0.5)
				(thermal_bridge_width 0.5)
				(island_removal_mode 0)
			)
			(polygon
				(pts
					(arc
						(start 426.560234 -134.244842)
						(mid 424.299634 -134.244842)
						(end 426.560234 -134.244842)
					)
				)
			)
		)
		(zone
			(layers "F.Cu" "B.Cu" "In1.Cu" "In2.Cu" "In3.Cu" "In4.Cu" "In5.Cu" "In6.Cu"
				"In7.Cu" "In8.Cu" "In9.Cu" "In10.Cu" "In11.Cu" "In12.Cu"
			)
			(hatch none 0.5)
			(connect_pads
				(clearance 0)
			)
			(min_thickness 0.25)
			(keepout
				(tracks not_allowed)
				(vias allowed)
				(pads allowed)
				(copperpour not_allowed)
				(footprints allowed)
			)
			(placement
				(enabled no)
				(sheetname "")
			)
			(fill
				(thermal_gap 0.5)
				(thermal_bridge_width 0.5)
				(island_removal_mode 0)
			)
			(polygon
				(pts
					(arc
						(start 451.560438 -134.244842)
						(mid 449.299838 -134.244842)
						(end 451.560438 -134.244842)
					)
				)
			)
		)
	)
	(footprint ""
		(layer "F.Cu")
		(at 32.352234 -93.625162 -90)
		(property "Reference" "C1C5"
			(at 0 0 270)
			(layer "F.SilkS")
			(hide yes)
			(effects
				(font
					(size 1.27 1.27)
				)
			)
		)
		(property "Value" ""
			(at 0 0 270)
			(layer "F.Fab")
			(effects
				(font
					(size 1.27 1.27)
				)
			)
		)
		(duplicate_pad_numbers_are_jumpers no)
		(fp_rect
			(start 0.3048 0.9906)
			(end -0.3048 -0.1016)
			(stroke
				(width 0)
				(type default)
			)
			(fill no)
			(layer "F.CrtYd")
		)
		(fp_line
			(start -0.3048 0.9906)
			(end 0.3048 0.9906)
			(stroke
				(width 0.1)
				(type default)
			)
			(layer "F.Fab")
		)
		(fp_line
			(start 0.3048 0.9906)
			(end 0.3048 -0.1016)
			(stroke
				(width 0.1)
				(type default)
			)
			(layer "F.Fab")
		)
		(fp_line
			(start -0.3048 -0.1016)
			(end -0.3048 0.9906)
			(stroke
				(width 0.1)
				(type default)
			)
			(layer "F.Fab")
		)
		(fp_line
			(start 0.3048 -0.1016)
			(end -0.3048 -0.1016)
			(stroke
				(width 0.1)
				(type default)
			)
			(layer "F.Fab")
		)
		(pad "1" smd rect
			(at 0 0 270)
			(size 0.508 0.508)
			(layers "F.Cu" "F.Mask" "F.Paste")
			(net "VR_PVSA_CPU1_VCIN")
		)
		(pad "2" smd rect
			(at 0 0.889 270)
			(size 0.508 0.508)
			(layers "F.Cu" "F.Mask" "F.Paste")
			(net "GND")
		)
		(zone
			(layer "F.Cu")
			(hatch none 0.5)
			(connect_pads
				(clearance 0)
			)
			(min_thickness 0.25)
			(keepout
				(tracks allowed)
				(vias not_allowed)
				(pads allowed)
				(copperpour not_allowed)
				(footprints allowed)
			)
			(placement
				(enabled no)
				(sheetname "")
			)
			(fill
				(thermal_gap 0.5)
				(thermal_bridge_width 0.5)
				(island_removal_mode 0)
			)
			(polygon
				(pts
					(xy 31.717234 -93.371162) (xy 32.098234 -93.371162) (xy 32.098234 -93.879162) (xy 31.717234 -93.879162)
				)
			)
		)
		(zone
			(layer "F.Cu")
			(hatch none 0.5)
			(connect_pads
				(clearance 0)
			)
			(min_thickness 0.25)
			(keepout
				(tracks not_allowed)
				(vias allowed)
				(pads allowed)
				(copperpour not_allowed)
				(footprints allowed)
			)
			(placement
				(enabled no)
				(sheetname "")
			)
			(fill
				(thermal_gap 0.5)
				(thermal_bridge_width 0.5)
				(island_removal_mode 0)
			)
			(polygon
				(pts
					(xy 31.717234 -93.371162) (xy 32.098234 -93.371162) (xy 32.098234 -93.879162) (xy 31.717234 -93.879162)
				)
			)
		)
	)
	(footprint ""
		(layer "F.Cu")
		(at 381.2159 -137.4648)
		(property "Reference" "C7A31"
			(at 0 0 0)
			(layer "F.SilkS")
			(hide yes)
			(effects
				(font
					(size 1.27 1.27)
				)
			)
		)
		(property "Value" ""
			(at 0 0 0)
			(layer "F.Fab")
			(effects
				(font
					(size 1.27 1.27)
				)
			)
		)
		(duplicate_pad_numbers_are_jumpers no)
		(fp_rect
			(start -0.7239 1.9939)
			(end 0.7239 -0.2159)
			(stroke
				(width 0)
				(type default)
			)
			(fill no)
			(layer "F.CrtYd")
		)
		(fp_line
			(start -0.7239 -0.2159)
			(end -0.7239 1.9939)
			(stroke
				(width 0.1)
				(type default)
			)
			(layer "F.Fab")
		)
		(fp_line
			(start -0.7239 1.9939)
			(end 0.7239 1.9939)
			(stroke
				(width 0.1)
				(type default)
			)
			(layer "F.Fab")
		)
		(fp_line
			(start 0.7239 -0.2159)
			(end -0.7239 -0.2159)
			(stroke
				(width 0.1)
				(type default)
			)
			(layer "F.Fab")
		)
		(fp_line
			(start 0.7239 1.9939)
			(end 0.7239 -0.2159)
			(stroke
				(width 0.1)
				(type default)
			)
			(layer "F.Fab")
		)
		(pad "1" smd rect
			(at 0 0)
			(size 1.27 1.016)
			(layers "F.Cu" "F.Mask" "F.Paste")
			(net "PVNN_PCH_STBY")
		)
		(pad "2" smd rect
			(at 0 1.778)
			(size 1.27 1.016)
			(layers "F.Cu" "F.Mask" "F.Paste")
			(net "GND")
		)
		(zone
			(layer "F.Cu")
			(hatch none 0.5)
			(connect_pads
				(clearance 0)
			)
			(min_thickness 0.25)
			(keepout
				(tracks not_allowed)
				(vias allowed)
				(pads allowed)
				(copperpour not_allowed)
				(footprints allowed)
			)
			(placement
				(enabled no)
				(sheetname "")
			)
			(fill
				(thermal_gap 0.5)
				(thermal_bridge_width 0.5)
				(island_removal_mode 0)
			)
			(polygon
				(pts
					(xy 380.5809 -136.1948) (xy 381.8509 -136.1948) (xy 381.8509 -136.9568) (xy 380.5809 -136.9568)
				)
			)
		)
	)
	(footprint ""
		(layer "F.Cu")
		(at 369.4684 -141.2494 180)
		(property "Reference" "C7A27"
			(at -0.5588 -2.76987 0)
			(unlocked yes)
			(layer "F.SilkS")
			(effects
				(font
					(size 0.7874 0.5842)
					(thickness 0.1524)
				)
			)
		)
		(property "Value" ""
			(at 0 0 180)
			(layer "F.Fab")
			(effects
				(font
					(size 1.27 1.27)
				)
			)
		)
		(duplicate_pad_numbers_are_jumpers no)
		(fp_line
			(start 2.504948 1.633728)
			(end 1.6002 1.633728)
			(stroke
				(width 0.1524)
				(type default)
			)
			(layer "F.SilkS")
		)
		(fp_line
			(start 2.504948 -1.616456)
			(end 2.504948 1.633728)
			(stroke
				(width 0.1524)
				(type default)
			)
			(layer "F.SilkS")
		)
		(fp_line
			(start 2.286 7.366)
			(end 2.286 1.63195)
			(stroke
				(width 0.1524)
				(type default)
			)
			(layer "F.SilkS")
		)
		(fp_line
			(start 2.286 7.366)
			(end 1.600708 7.366)
			(stroke
				(width 0.1524)
				(type default)
			)
			(layer "F.SilkS")
		)
		(fp_line
			(start 1.6002 -1.616456)
			(end 2.504948 -1.616456)
			(stroke
				(width 0.1524)
				(type default)
			)
			(layer "F.SilkS")
		)
		(fp_line
			(start -1.6002 -1.616456)
			(end -2.563114 -1.616456)
			(stroke
				(width 0.1524)
				(type default)
			)
			(layer "F.SilkS")
		)
		(fp_line
			(start -2.286 7.366)
			(end -1.60147 7.366)
			(stroke
				(width 0.1524)
				(type default)
			)
			(layer "F.SilkS")
		)
		(fp_line
			(start -2.286 7.366)
			(end -2.286 1.632712)
			(stroke
				(width 0.1524)
				(type default)
			)
			(layer "F.SilkS")
		)
		(fp_line
			(start -2.563114 1.633728)
			(end -1.6002 1.633728)
			(stroke
				(width 0.1524)
				(type default)
			)
			(layer "F.SilkS")
		)
		(fp_line
			(start -2.563114 -1.616456)
			(end -2.563114 1.633728)
			(stroke
				(width 0.1524)
				(type default)
			)
			(layer "F.SilkS")
		)
		(fp_rect
			(start -2.286 7.366)
			(end 2.286 -0.254)
			(stroke
				(width 0)
				(type default)
			)
			(fill no)
			(layer "F.CrtYd")
		)
		(fp_line
			(start 2.286 7.366)
			(end -2.286 7.366)
			(stroke
				(width 0.1)
				(type default)
			)
			(layer "F.Fab")
		)
		(fp_line
			(start 2.286 -0.254)
			(end 2.286 7.366)
			(stroke
				(width 0.1)
				(type default)
			)
			(layer "F.Fab")
		)
		(fp_line
			(start -2.286 7.366)
			(end -2.286 -0.254)
			(stroke
				(width 0.1)
				(type default)
			)
			(layer "F.Fab")
		)
		(fp_line
			(start -2.286 -0.254)
			(end 2.286 -0.254)
			(stroke
				(width 0.1)
				(type default)
			)
			(layer "F.Fab")
		)
		(pad "1" smd rect
			(at 0 0 180)
			(size 2.54 3.048)
			(layers "F.Cu" "F.Mask" "F.Paste")
			(net "PVNN_PCH_STBY")
		)
		(pad "2" smd rect
			(at 0 7.112 180)
			(size 2.54 3.048)
			(layers "F.Cu" "F.Mask" "F.Paste")
			(net "GND")
		)
	)
	(footprint ""
		(layer "F.Cu")
		(at -2.667 -130.1242 -90)
		(property "Reference" "R12W34"
			(at -0.8382 -0.67818 270)
			(unlocked yes)
			(layer "F.SilkS")
			(effects
				(font
					(size 0.4064 0.254)
					(thickness 0.1524)
				)
				(justify left)
			)
		)
		(property "Value" ""
			(at 0 0 270)
			(layer "F.Fab")
			(effects
				(font
					(size 1.27 1.27)
				)
			)
		)
		(duplicate_pad_numbers_are_jumpers no)
		(fp_poly
			(pts
				(xy -0.2794 -0.1016) (xy 0.2794 -0.1016) (xy 0.2794 0.9906) (xy -0.2794 0.9906)
			)
			(stroke
				(width 0)
				(type default)
			)
			(fill no)
			(layer "F.CrtYd")
		)
		(fp_line
			(start -0.2794 0.9906)
			(end 0.2794 0.9906)
			(stroke
				(width 0.1)
				(type default)
			)
			(layer "F.Fab")
		)
		(fp_line
			(start 0.2794 0.9906)
			(end 0.2794 -0.1016)
			(stroke
				(width 0.1)
				(type default)
			)
			(layer "F.Fab")
		)
		(fp_line
			(start -0.2794 -0.1016)
			(end -0.2794 0.9906)
			(stroke
				(width 0.1)
				(type default)
			)
			(layer "F.Fab")
		)
		(fp_line
			(start 0.2794 -0.1016)
			(end -0.2794 -0.1016)
			(stroke
				(width 0.1)
				(type default)
			)
			(layer "F.Fab")
		)
		(pad "1" smd rect
			(at 0 0 270)
			(size 0.508 0.508)
			(layers "F.Cu" "F.Mask" "F.Paste")
			(net "PU_VR_PVDDQ_KLM_FAULT1")
		)
		(pad "2" smd rect
			(at 0 0.889 270)
			(size 0.508 0.508)
			(layers "F.Cu" "F.Mask" "F.Paste")
			(net "PWRGD_PVDDQ_KLM")
		)
		(zone
			(layer "F.Cu")
			(hatch none 0.5)
			(connect_pads
				(clearance 0)
			)
			(min_thickness 0.25)
			(keepout
				(tracks not_allowed)
				(vias allowed)
				(pads allowed)
				(copperpour not_allowed)
				(footprints allowed)
			)
			(placement
				(enabled no)
				(sheetname "")
			)
			(fill
				(thermal_gap 0.5)
				(thermal_bridge_width 0.5)
				(island_removal_mode 0)
			)
			(polygon
				(pts
					(xy -3.302 -130.3782) (xy -3.302 -129.8702) (xy -2.921 -129.8702) (xy -2.921 -130.3782)
				)
			)
		)
		(zone
			(layer "F.Cu")
			(hatch none 0.5)
			(connect_pads
				(clearance 0)
			)
			(min_thickness 0.25)
			(keepout
				(tracks allowed)
				(vias not_allowed)
				(pads allowed)
				(copperpour not_allowed)
				(footprints allowed)
			)
			(placement
				(enabled no)
				(sheetname "")
			)
			(fill
				(thermal_gap 0.5)
				(thermal_bridge_width 0.5)
				(island_removal_mode 0)
			)
			(polygon
				(pts
					(xy -2.921 -130.3782) (xy -2.921 -129.8702) (xy -3.302 -129.8702) (xy -3.302 -130.3782)
				)
			)
		)
	)
	(footprint ""
		(layer "F.Cu")
		(at 14.986 -84.963 -90)
		(property "Reference" "R1D11"
			(at 0 0 270)
			(layer "F.SilkS")
			(hide yes)
			(effects
				(font
					(size 1.27 1.27)
				)
			)
		)
		(property "Value" ""
			(at 0 0 270)
			(layer "F.Fab")
			(effects
				(font
					(size 1.27 1.27)
				)
			)
		)
		(duplicate_pad_numbers_are_jumpers no)
		(fp_poly
			(pts
				(xy -0.2794 -0.1016) (xy 0.2794 -0.1016) (xy 0.2794 0.9906) (xy -0.2794 0.9906)
			)
			(stroke
				(width 0)
				(type default)
			)
			(fill no)
			(layer "F.CrtYd")
		)
		(fp_line
			(start -0.2794 0.9906)
			(end 0.2794 0.9906)
			(stroke
				(width 0.1)
				(type default)
			)
			(layer "F.Fab")
		)
		(fp_line
			(start 0.2794 0.9906)
			(end 0.2794 -0.1016)
			(stroke
				(width 0.1)
				(type default)
			)
			(layer "F.Fab")
		)
		(fp_line
			(start -0.2794 -0.1016)
			(end -0.2794 0.9906)
			(stroke
				(width 0.1)
				(type default)
			)
			(layer "F.Fab")
		)
		(fp_line
			(start 0.2794 -0.1016)
			(end -0.2794 -0.1016)
			(stroke
				(width 0.1)
				(type default)
			)
			(layer "F.Fab")
		)
		(pad "1" smd rect
			(at 0 0 270)
			(size 0.508 0.508)
			(layers "F.Cu" "F.Mask" "F.Paste")
			(net "A_HSC_LOW_EN")
		)
		(pad "2" smd rect
			(at 0 0.889 270)
			(size 0.508 0.508)
			(layers "F.Cu" "F.Mask" "F.Paste")
			(net "AGND_HSC")
		)
		(zone
			(layer "F.Cu")
			(hatch none 0.5)
			(connect_pads
				(clearance 0)
			)
			(min_thickness 0.25)
			(keepout
				(tracks not_allowed)
				(vias allowed)
				(pads allowed)
				(copperpour not_allowed)
				(footprints allowed)
			)
			(placement
				(enabled no)
				(sheetname "")
			)
			(fill
				(thermal_gap 0.5)
				(thermal_bridge_width 0.5)
				(island_removal_mode 0)
			)
			(polygon
				(pts
					(xy 14.351 -85.217) (xy 14.351 -84.709) (xy 14.732 -84.709) (xy 14.732 -85.217)
				)
			)
		)
		(zone
			(layer "F.Cu")
			(hatch none 0.5)
			(connect_pads
				(clearance 0)
			)
			(min_thickness 0.25)
			(keepout
				(tracks allowed)
				(vias not_allowed)
				(pads allowed)
				(copperpour not_allowed)
				(footprints allowed)
			)
			(placement
				(enabled no)
				(sheetname "")
			)
			(fill
				(thermal_gap 0.5)
				(thermal_bridge_width 0.5)
				(island_removal_mode 0)
			)
			(polygon
				(pts
					(xy 14.732 -85.217) (xy 14.732 -84.709) (xy 14.351 -84.709) (xy 14.351 -85.217)
				)
			)
		)
	)
	(footprint ""
		(layer "F.Cu")
		(at 343.408 -143.2814)
		(property "Reference" "CT47"
			(at -0.8382 -0.67818 0)
			(unlocked yes)
			(layer "F.SilkS")
			(effects
				(font
					(size 0.4064 0.254)
					(thickness 0.1524)
				)
				(justify left)
			)
		)
		(property "Value" ""
			(at 0 0 0)
			(layer "F.Fab")
			(effects
				(font
					(size 1.27 1.27)
				)
			)
		)
		(duplicate_pad_numbers_are_jumpers no)
		(fp_poly
			(pts
				(xy 0.3048 -0.1016) (xy 0.3048 0.9906) (xy -0.3048 0.9906) (xy -0.3048 -0.1016)
			)
			(stroke
				(width 0)
				(type default)
			)
			(fill no)
			(layer "F.CrtYd")
		)
		(fp_line
			(start -0.3048 -0.1016)
			(end -0.3048 0.9906)
			(stroke
				(width 0.1)
				(type default)
			)
			(layer "F.Fab")
		)
		(fp_line
			(start -0.3048 0.9906)
			(end 0.3048 0.9906)
			(stroke
				(width 0.1)
				(type default)
			)
			(layer "F.Fab")
		)
		(fp_line
			(start 0.3048 -0.1016)
			(end -0.3048 -0.1016)
			(stroke
				(width 0.1)
				(type default)
			)
			(layer "F.Fab")
		)
		(fp_line
			(start 0.3048 0.9906)
			(end 0.3048 -0.1016)
			(stroke
				(width 0.1)
				(type default)
			)
			(layer "F.Fab")
		)
		(pad "1" smd rect
			(at 0 0)
			(size 0.508 0.508)
			(layers "F.Cu" "F.Mask" "F.Paste")
			(net "VR_PVDDQ_DEF_PH2_SW")
		)
		(pad "2" smd rect
			(at 0 0.889)
			(size 0.508 0.508)
			(layers "F.Cu" "F.Mask" "F.Paste")
			(net "VR_PVDDQ_DEF_PH2_SW_RC")
		)
		(zone
			(layer "F.Cu")
			(hatch none 0.5)
			(connect_pads
				(clearance 0)
			)
			(min_thickness 0.25)
			(keepout
				(tracks allowed)
				(vias not_allowed)
				(pads allowed)
				(copperpour not_allowed)
				(footprints allowed)
			)
			(placement
				(enabled no)
				(sheetname "")
			)
			(fill
				(thermal_gap 0.5)
				(thermal_bridge_width 0.5)
				(island_removal_mode 0)
			)
			(polygon
				(pts
					(xy 343.154 -143.0274) (xy 343.662 -143.0274) (xy 343.662 -142.6464) (xy 343.154 -142.6464)
				)
			)
		)
		(zone
			(layer "F.Cu")
			(hatch none 0.5)
			(connect_pads
				(clearance 0)
			)
			(min_thickness 0.25)
			(keepout
				(tracks not_allowed)
				(vias allowed)
				(pads allowed)
				(copperpour not_allowed)
				(footprints allowed)
			)
			(placement
				(enabled no)
				(sheetname "")
			)
			(fill
				(thermal_gap 0.5)
				(thermal_bridge_width 0.5)
				(island_removal_mode 0)
			)
			(polygon
				(pts
					(xy 343.154 -142.6464) (xy 343.662 -142.6464) (xy 343.662 -143.0274) (xy 343.154 -143.0274)
				)
			)
		)
	)
	(footprint ""
		(layer "F.Cu")
		(at 338.836 -14.732 -90)
		(property "Reference" "R12W27"
			(at -0.8382 -0.67818 270)
			(unlocked yes)
			(layer "F.SilkS")
			(effects
				(font
					(size 0.4064 0.254)
					(thickness 0.1524)
				)
				(justify left)
			)
		)
		(property "Value" ""
			(at 0 0 270)
			(layer "F.Fab")
			(effects
				(font
					(size 1.27 1.27)
				)
			)
		)
		(duplicate_pad_numbers_are_jumpers no)
		(fp_poly
			(pts
				(xy -0.2794 -0.1016) (xy 0.2794 -0.1016) (xy 0.2794 0.9906) (xy -0.2794 0.9906)
			)
			(stroke
				(width 0)
				(type default)
			)
			(fill no)
			(layer "F.CrtYd")
		)
		(fp_line
			(start -0.2794 0.9906)
			(end 0.2794 0.9906)
			(stroke
				(width 0.1)
				(type default)
			)
			(layer "F.Fab")
		)
		(fp_line
			(start 0.2794 0.9906)
			(end 0.2794 -0.1016)
			(stroke
				(width 0.1)
				(type default)
			)
			(layer "F.Fab")
		)
		(fp_line
			(start -0.2794 -0.1016)
			(end -0.2794 0.9906)
			(stroke
				(width 0.1)
				(type default)
			)
			(layer "F.Fab")
		)
		(fp_line
			(start 0.2794 -0.1016)
			(end -0.2794 -0.1016)
			(stroke
				(width 0.1)
				(type default)
			)
			(layer "F.Fab")
		)
		(pad "1" smd rect
			(at 0 0 270)
			(size 0.508 0.508)
			(layers "F.Cu" "F.Mask" "F.Paste")
			(net "TP_PVDDQ_ABC_MP2")
		)
		(pad "2" smd rect
			(at 0 0.889 270)
			(size 0.508 0.508)
			(layers "F.Cu" "F.Mask" "F.Paste")
			(net "PWRGD_PVDDQ_ABC")
		)
		(zone
			(layer "F.Cu")
			(hatch none 0.5)
			(connect_pads
				(clearance 0)
			)
			(min_thickness 0.25)
			(keepout
				(tracks not_allowed)
				(vias allowed)
				(pads allowed)
				(copperpour not_allowed)
				(footprints allowed)
			)
			(placement
				(enabled no)
				(sheetname "")
			)
			(fill
				(thermal_gap 0.5)
				(thermal_bridge_width 0.5)
				(island_removal_mode 0)
			)
			(polygon
				(pts
					(xy 338.201 -14.986) (xy 338.201 -14.478) (xy 338.582 -14.478) (xy 338.582 -14.986)
				)
			)
		)
		(zone
			(layer "F.Cu")
			(hatch none 0.5)
			(connect_pads
				(clearance 0)
			)
			(min_thickness 0.25)
			(keepout
				(tracks allowed)
				(vias not_allowed)
				(pads allowed)
				(copperpour not_allowed)
				(footprints allowed)
			)
			(placement
				(enabled no)
				(sheetname "")
			)
			(fill
				(thermal_gap 0.5)
				(thermal_bridge_width 0.5)
				(island_removal_mode 0)
			)
			(polygon
				(pts
					(xy 338.582 -14.986) (xy 338.582 -14.478) (xy 338.201 -14.478) (xy 338.201 -14.986)
				)
			)
		)
	)
	(footprint ""
		(layer "F.Cu")
		(at 364.600744 -10.916158)
		(property "Reference" "C7G7"
			(at 0 0 0)
			(layer "F.SilkS")
			(hide yes)
			(effects
				(font
					(size 1.27 1.27)
				)
			)
		)
		(property "Value" ""
			(at 0 0 0)
			(layer "F.Fab")
			(effects
				(font
					(size 1.27 1.27)
				)
			)
		)
		(duplicate_pad_numbers_are_jumpers no)
		(fp_rect
			(start -0.3048 0.9906)
			(end 0.3048 -0.1016)
			(stroke
				(width 0)
				(type default)
			)
			(fill no)
			(layer "F.CrtYd")
		)
		(fp_line
			(start -0.3048 -0.1016)
			(end -0.3048 0.9906)
			(stroke
				(width 0.1)
				(type default)
			)
			(layer "F.Fab")
		)
		(fp_line
			(start -0.3048 0.9906)
			(end 0.3048 0.9906)
			(stroke
				(width 0.1)
				(type default)
			)
			(layer "F.Fab")
		)
		(fp_line
			(start 0.3048 -0.1016)
			(end -0.3048 -0.1016)
			(stroke
				(width 0.1)
				(type default)
			)
			(layer "F.Fab")
		)
		(fp_line
			(start 0.3048 0.9906)
			(end 0.3048 -0.1016)
			(stroke
				(width 0.1)
				(type default)
			)
			(layer "F.Fab")
		)
		(pad "1" smd rect
			(at 0 0)
			(size 0.508 0.508)
			(layers "F.Cu" "F.Mask" "F.Paste")
			(net "P3E_CPU0_PE2_SS_TXN<14>")
		)
		(pad "2" smd rect
			(at 0 0.889)
			(size 0.508 0.508)
			(layers "F.Cu" "F.Mask" "F.Paste")
			(net "P3E_CPU0_PE2_SS_C_TXN<14>")
		)
		(zone
			(layer "F.Cu")
			(hatch none 0.5)
			(connect_pads
				(clearance 0)
			)
			(min_thickness 0.25)
			(keepout
				(tracks allowed)
				(vias not_allowed)
				(pads allowed)
				(copperpour not_allowed)
				(footprints allowed)
			)
			(placement
				(enabled no)
				(sheetname "")
			)
			(fill
				(thermal_gap 0.5)
				(thermal_bridge_width 0.5)
				(island_removal_mode 0)
			)
			(polygon
				(pts
					(xy 364.346744 -10.281158) (xy 364.854744 -10.281158) (xy 364.854744 -10.662158) (xy 364.346744 -10.662158)
				)
			)
		)
		(zone
			(layer "F.Cu")
			(hatch none 0.5)
			(connect_pads
				(clearance 0)
			)
			(min_thickness 0.25)
			(keepout
				(tracks not_allowed)
				(vias allowed)
				(pads allowed)
				(copperpour not_allowed)
				(footprints allowed)
			)
			(placement
				(enabled no)
				(sheetname "")
			)
			(fill
				(thermal_gap 0.5)
				(thermal_bridge_width 0.5)
				(island_removal_mode 0)
			)
			(polygon
				(pts
					(xy 364.346744 -10.281158) (xy 364.854744 -10.281158) (xy 364.854744 -10.662158) (xy 364.346744 -10.662158)
				)
			)
		)
	)
	(footprint ""
		(layer "F.Cu")
		(at 324.282816 -128.025652 180)
		(property "Reference" "R6B5"
			(at 0 0 180)
			(layer "F.SilkS")
			(hide yes)
			(effects
				(font
					(size 1.27 1.27)
				)
			)
		)
		(property "Value" ""
			(at 0 0 180)
			(layer "F.Fab")
			(effects
				(font
					(size 1.27 1.27)
				)
			)
		)
		(duplicate_pad_numbers_are_jumpers no)
		(fp_poly
			(pts
				(xy -0.2794 -0.1016) (xy 0.2794 -0.1016) (xy 0.2794 0.9906) (xy -0.2794 0.9906)
			)
			(stroke
				(width 0)
				(type default)
			)
			(fill no)
			(layer "F.CrtYd")
		)
		(fp_line
			(start 0.2794 0.9906)
			(end 0.2794 -0.1016)
			(stroke
				(width 0.1)
				(type default)
			)
			(layer "F.Fab")
		)
		(fp_line
			(start 0.2794 -0.1016)
			(end -0.2794 -0.1016)
			(stroke
				(width 0.1)
				(type default)
			)
			(layer "F.Fab")
		)
		(fp_line
			(start -0.2794 0.9906)
			(end 0.2794 0.9906)
			(stroke
				(width 0.1)
				(type default)
			)
			(layer "F.Fab")
		)
		(fp_line
			(start -0.2794 -0.1016)
			(end -0.2794 0.9906)
			(stroke
				(width 0.1)
				(type default)
			)
			(layer "F.Fab")
		)
		(pad "1" smd rect
			(at 0 0 180)
			(size 0.508 0.508)
			(layers "F.Cu" "F.Mask" "F.Paste")
			(net "SVID_CLK1_CPU0")
		)
		(pad "2" smd rect
			(at 0 0.889 180)
			(size 0.508 0.508)
			(layers "F.Cu" "F.Mask" "F.Paste")
			(net "SVID_CLK1_CPU0_R")
		)
		(zone
			(layer "F.Cu")
			(hatch none 0.5)
			(connect_pads
				(clearance 0)
			)
			(min_thickness 0.25)
			(keepout
				(tracks not_allowed)
				(vias allowed)
				(pads allowed)
				(copperpour not_allowed)
				(footprints allowed)
			)
			(placement
				(enabled no)
				(sheetname "")
			)
			(fill
				(thermal_gap 0.5)
				(thermal_bridge_width 0.5)
				(island_removal_mode 0)
			)
			(polygon
				(pts
					(xy 324.536816 -128.660652) (xy 324.028816 -128.660652) (xy 324.028816 -128.279652) (xy 324.536816 -128.279652)
				)
			)
		)
		(zone
			(layer "F.Cu")
			(hatch none 0.5)
			(connect_pads
				(clearance 0)
			)
			(min_thickness 0.25)
			(keepout
				(tracks allowed)
				(vias not_allowed)
				(pads allowed)
				(copperpour not_allowed)
				(footprints allowed)
			)
			(placement
				(enabled no)
				(sheetname "")
			)
			(fill
				(thermal_gap 0.5)
				(thermal_bridge_width 0.5)
				(island_removal_mode 0)
			)
			(polygon
				(pts
					(xy 324.536816 -128.279652) (xy 324.028816 -128.279652) (xy 324.028816 -128.660652) (xy 324.536816 -128.660652)
				)
			)
		)
	)
	(footprint ""
		(layer "F.Cu")
		(at 385.318 -87.3125 180)
		(property "Reference" "R7D12"
			(at 0 0 180)
			(layer "F.SilkS")
			(hide yes)
			(effects
				(font
					(size 1.27 1.27)
				)
			)
		)
		(property "Value" ""
			(at 0 0 180)
			(layer "F.Fab")
			(effects
				(font
					(size 1.27 1.27)
				)
			)
		)
		(duplicate_pad_numbers_are_jumpers no)
		(fp_poly
			(pts
				(xy -0.2794 -0.1016) (xy 0.2794 -0.1016) (xy 0.2794 0.9906) (xy -0.2794 0.9906)
			)
			(stroke
				(width 0)
				(type default)
			)
			(fill no)
			(layer "F.CrtYd")
		)
		(fp_line
			(start 0.2794 0.9906)
			(end 0.2794 -0.1016)
			(stroke
				(width 0.1)
				(type default)
			)
			(layer "F.Fab")
		)
		(fp_line
			(start 0.2794 -0.1016)
			(end -0.2794 -0.1016)
			(stroke
				(width 0.1)
				(type default)
			)
			(layer "F.Fab")
		)
		(fp_line
			(start -0.2794 0.9906)
			(end 0.2794 0.9906)
			(stroke
				(width 0.1)
				(type default)
			)
			(layer "F.Fab")
		)
		(fp_line
			(start -0.2794 -0.1016)
			(end -0.2794 0.9906)
			(stroke
				(width 0.1)
				(type default)
			)
			(layer "F.Fab")
		)
		(pad "1" smd rect
			(at 0 0 180)
			(size 0.508 0.508)
			(layers "F.Cu" "F.Mask" "F.Paste")
			(net "P3V3_STBY")
		)
		(pad "2" smd rect
			(at 0 0.889 180)
			(size 0.508 0.508)
			(layers "F.Cu" "F.Mask" "F.Paste")
			(net "FM_OCP_MEZZA_PRES")
		)
		(zone
			(layer "F.Cu")
			(hatch none 0.5)
			(connect_pads
				(clearance 0)
			)
			(min_thickness 0.25)
			(keepout
				(tracks not_allowed)
				(vias allowed)
				(pads allowed)
				(copperpour not_allowed)
				(footprints allowed)
			)
			(placement
				(enabled no)
				(sheetname "")
			)
			(fill
				(thermal_gap 0.5)
				(thermal_bridge_width 0.5)
				(island_removal_mode 0)
			)
			(polygon
				(pts
					(xy 385.572 -87.9475) (xy 385.064 -87.9475) (xy 385.064 -87.5665) (xy 385.572 -87.5665)
				)
			)
		)
		(zone
			(layer "F.Cu")
			(hatch none 0.5)
			(connect_pads
				(clearance 0)
			)
			(min_thickness 0.25)
			(keepout
				(tracks allowed)
				(vias not_allowed)
				(pads allowed)
				(copperpour not_allowed)
				(footprints allowed)
			)
			(placement
				(enabled no)
				(sheetname "")
			)
			(fill
				(thermal_gap 0.5)
				(thermal_bridge_width 0.5)
				(island_removal_mode 0)
			)
			(polygon
				(pts
					(xy 385.572 -87.5665) (xy 385.064 -87.5665) (xy 385.064 -87.9475) (xy 385.572 -87.9475)
				)
			)
		)
	)
	(footprint ""
		(layer "F.Cu")
		(at 13.8938 -30.353 90)
		(property "Reference" "C1F11"
			(at 0 0 90)
			(layer "F.SilkS")
			(hide yes)
			(effects
				(font
					(size 1.27 1.27)
				)
			)
		)
		(property "Value" ""
			(at 0 0 90)
			(layer "F.Fab")
			(effects
				(font
					(size 1.27 1.27)
				)
			)
		)
		(duplicate_pad_numbers_are_jumpers no)
		(fp_rect
			(start -0.3048 -0.1016)
			(end 0.3048 0.9906)
			(stroke
				(width 0)
				(type default)
			)
			(fill no)
			(layer "F.CrtYd")
		)
		(fp_line
			(start 0.3048 -0.1016)
			(end -0.3048 -0.1016)
			(stroke
				(width 0.1)
				(type default)
			)
			(layer "F.Fab")
		)
		(fp_line
			(start -0.3048 -0.1016)
			(end -0.3048 0.9906)
			(stroke
				(width 0.1)
				(type default)
			)
			(layer "F.Fab")
		)
		(fp_line
			(start 0.3048 0.9906)
			(end 0.3048 -0.1016)
			(stroke
				(width 0.1)
				(type default)
			)
			(layer "F.Fab")
		)
		(fp_line
			(start -0.3048 0.9906)
			(end 0.3048 0.9906)
			(stroke
				(width 0.1)
				(type default)
			)
			(layer "F.Fab")
		)
		(pad "1" smd rect
			(at 0 0 90)
			(size 0.508 0.508)
			(layers "F.Cu" "F.Mask" "F.Paste")
			(net "P3E_CPU1_PE3_MP_C_TXP<4>")
		)
		(pad "2" smd rect
			(at 0 0.889 90)
			(size 0.508 0.508)
			(layers "F.Cu" "F.Mask" "F.Paste")
			(net "P3E_CPU1_PE3_MP_TXP<4>")
		)
		(zone
			(layer "F.Cu")
			(hatch none 0.5)
			(connect_pads
				(clearance 0)
			)
			(min_thickness 0.25)
			(keepout
				(tracks allowed)
				(vias not_allowed)
				(pads allowed)
				(copperpour not_allowed)
				(footprints allowed)
			)
			(placement
				(enabled no)
				(sheetname "")
			)
			(fill
				(thermal_gap 0.5)
				(thermal_bridge_width 0.5)
				(island_removal_mode 0)
			)
			(polygon
				(pts
					(xy 14.1478 -30.099) (xy 14.5288 -30.099) (xy 14.5288 -30.607) (xy 14.1478 -30.607)
				)
			)
		)
		(zone
			(layer "F.Cu")
			(hatch none 0.5)
			(connect_pads
				(clearance 0)
			)
			(min_thickness 0.25)
			(keepout
				(tracks not_allowed)
				(vias allowed)
				(pads allowed)
				(copperpour not_allowed)
				(footprints allowed)
			)
			(placement
				(enabled no)
				(sheetname "")
			)
			(fill
				(thermal_gap 0.5)
				(thermal_bridge_width 0.5)
				(island_removal_mode 0)
			)
			(polygon
				(pts
					(xy 14.1478 -30.099) (xy 14.5288 -30.099) (xy 14.5288 -30.607) (xy 14.1478 -30.607)
				)
			)
		)
	)
	(footprint ""
		(layer "F.Cu")
		(at 431.766472 -45.05452 -90)
		(property "Reference" "R9F62"
			(at 0 0 270)
			(layer "F.SilkS")
			(hide yes)
			(effects
				(font
					(size 1.27 1.27)
				)
			)
		)
		(property "Value" ""
			(at 0 0 270)
			(layer "F.Fab")
			(effects
				(font
					(size 1.27 1.27)
				)
			)
		)
		(duplicate_pad_numbers_are_jumpers no)
		(fp_poly
			(pts
				(xy -0.2794 -0.1016) (xy 0.2794 -0.1016) (xy 0.2794 0.9906) (xy -0.2794 0.9906)
			)
			(stroke
				(width 0)
				(type default)
			)
			(fill no)
			(layer "F.CrtYd")
		)
		(fp_line
			(start -0.2794 0.9906)
			(end 0.2794 0.9906)
			(stroke
				(width 0.1)
				(type default)
			)
			(layer "F.Fab")
		)
		(fp_line
			(start 0.2794 0.9906)
			(end 0.2794 -0.1016)
			(stroke
				(width 0.1)
				(type default)
			)
			(layer "F.Fab")
		)
		(fp_line
			(start -0.2794 -0.1016)
			(end -0.2794 0.9906)
			(stroke
				(width 0.1)
				(type default)
			)
			(layer "F.Fab")
		)
		(fp_line
			(start 0.2794 -0.1016)
			(end -0.2794 -0.1016)
			(stroke
				(width 0.1)
				(type default)
			)
			(layer "F.Fab")
		)
		(pad "1" smd rect
			(at 0 0 270)
			(size 0.508 0.508)
			(layers "F.Cu" "F.Mask" "F.Paste")
			(net "CLK_24M_BMC_CLKIN_R")
		)
		(pad "2" smd rect
			(at 0 0.889 270)
			(size 0.508 0.508)
			(layers "F.Cu" "F.Mask" "F.Paste")
			(net "CLK_24M_25M_BMC_CLKIN")
		)
		(zone
			(layer "F.Cu")
			(hatch none 0.5)
			(connect_pads
				(clearance 0)
			)
			(min_thickness 0.25)
			(keepout
				(tracks not_allowed)
				(vias allowed)
				(pads allowed)
				(copperpour not_allowed)
				(footprints allowed)
			)
			(placement
				(enabled no)
				(sheetname "")
			)
			(fill
				(thermal_gap 0.5)
				(thermal_bridge_width 0.5)
				(island_removal_mode 0)
			)
			(polygon
				(pts
					(xy 431.131472 -45.30852) (xy 431.131472 -44.80052) (xy 431.512472 -44.80052) (xy 431.512472 -45.30852)
				)
			)
		)
		(zone
			(layer "F.Cu")
			(hatch none 0.5)
			(connect_pads
				(clearance 0)
			)
			(min_thickness 0.25)
			(keepout
				(tracks allowed)
				(vias not_allowed)
				(pads allowed)
				(copperpour not_allowed)
				(footprints allowed)
			)
			(placement
				(enabled no)
				(sheetname "")
			)
			(fill
				(thermal_gap 0.5)
				(thermal_bridge_width 0.5)
				(island_removal_mode 0)
			)
			(polygon
				(pts
					(xy 431.512472 -45.30852) (xy 431.512472 -44.80052) (xy 431.131472 -44.80052) (xy 431.131472 -45.30852)
				)
			)
		)
	)
	(footprint ""
		(layer "F.Cu")
		(at 184.260998 2.679192 -90)
		(property "Reference" "C4G24"
			(at 0 0 270)
			(layer "F.SilkS")
			(hide yes)
			(effects
				(font
					(size 1.27 1.27)
				)
			)
		)
		(property "Value" ""
			(at 0 0 270)
			(layer "F.Fab")
			(effects
				(font
					(size 1.27 1.27)
				)
			)
		)
		(duplicate_pad_numbers_are_jumpers no)
		(fp_rect
			(start 0.7239 1.9939)
			(end -0.7239 -0.2159)
			(stroke
				(width 0)
				(type default)
			)
			(fill no)
			(layer "F.CrtYd")
		)
		(fp_line
			(start -0.7239 1.9939)
			(end 0.7239 1.9939)
			(stroke
				(width 0.1)
				(type default)
			)
			(layer "F.Fab")
		)
		(fp_line
			(start 0.7239 1.9939)
			(end 0.7239 -0.2159)
			(stroke
				(width 0.1)
				(type default)
			)
			(layer "F.Fab")
		)
		(fp_line
			(start -0.7239 -0.2159)
			(end -0.7239 1.9939)
			(stroke
				(width 0.1)
				(type default)
			)
			(layer "F.Fab")
		)
		(fp_line
			(start 0.7239 -0.2159)
			(end -0.7239 -0.2159)
			(stroke
				(width 0.1)
				(type default)
			)
			(layer "F.Fab")
		)
		(pad "1" smd rect
			(at 0 0 270)
			(size 1.27 1.016)
			(layers "F.Cu" "F.Mask" "F.Paste")
			(net "PVTT_ABC")
		)
		(pad "2" smd rect
			(at 0 1.778 270)
			(size 1.27 1.016)
			(layers "F.Cu" "F.Mask" "F.Paste")
			(net "GND")
		)
		(zone
			(layer "F.Cu")
			(hatch none 0.5)
			(connect_pads
				(clearance 0)
			)
			(min_thickness 0.25)
			(keepout
				(tracks not_allowed)
				(vias allowed)
				(pads allowed)
				(copperpour not_allowed)
				(footprints allowed)
			)
			(placement
				(enabled no)
				(sheetname "")
			)
			(fill
				(thermal_gap 0.5)
				(thermal_bridge_width 0.5)
				(island_removal_mode 0)
			)
			(polygon
				(pts
					(xy 182.990998 3.314192) (xy 183.752998 3.314192) (xy 183.752998 2.044192) (xy 182.990998 2.044192)
				)
			)
		)
	)
	(footprint ""
		(layer "F.Cu")
		(at 99.438968 -79.6036 180)
		(property "Reference" "C2D14"
			(at 0 0 180)
			(layer "F.SilkS")
			(hide yes)
			(effects
				(font
					(size 1.27 1.27)
				)
			)
		)
		(property "Value" ""
			(at 0 0 180)
			(layer "F.Fab")
			(effects
				(font
					(size 1.27 1.27)
				)
			)
		)
		(duplicate_pad_numbers_are_jumpers no)
		(fp_poly
			(pts
				(xy -0.4953 -0.2032) (xy 0.4953 -0.2032) (xy 0.4953 1.6002) (xy -0.4953 1.6002)
			)
			(stroke
				(width 0)
				(type default)
			)
			(fill no)
			(layer "F.CrtYd")
		)
		(fp_line
			(start 0.4953 1.6002)
			(end -0.4953 1.6002)
			(stroke
				(width 0.1)
				(type default)
			)
			(layer "F.Fab")
		)
		(fp_line
			(start 0.4953 -0.2032)
			(end 0.4953 1.6002)
			(stroke
				(width 0.1)
				(type default)
			)
			(layer "F.Fab")
		)
		(fp_line
			(start -0.4953 1.6002)
			(end -0.4953 -0.2032)
			(stroke
				(width 0.1)
				(type default)
			)
			(layer "F.Fab")
		)
		(fp_line
			(start -0.4953 -0.2032)
			(end 0.4953 -0.2032)
			(stroke
				(width 0.1)
				(type default)
			)
			(layer "F.Fab")
		)
		(pad "1" smd rect
			(at 0 0 180)
			(size 0.762 0.889)
			(layers "F.Cu" "F.Mask" "F.Paste")
			(net "PVCCIN_CPU1")
		)
		(pad "2" smd rect
			(at 0 1.397 180)
			(size 0.762 0.889)
			(layers "F.Cu" "F.Mask" "F.Paste")
			(net "GND")
		)
		(zone
			(layer "F.Cu")
			(hatch none 0.5)
			(connect_pads
				(clearance 0)
			)
			(min_thickness 0.25)
			(keepout
				(tracks not_allowed)
				(vias allowed)
				(pads allowed)
				(copperpour not_allowed)
				(footprints allowed)
			)
			(placement
				(enabled no)
				(sheetname "")
			)
			(fill
				(thermal_gap 0.5)
				(thermal_bridge_width 0.5)
				(island_removal_mode 0)
			)
			(polygon
				(pts
					(xy 99.819968 -80.0481) (xy 99.057968 -80.0481) (xy 99.057968 -80.5561) (xy 99.819968 -80.5561)
				)
			)
		)
	)
	(footprint ""
		(layer "F.Cu")
		(at 29.699458 -5.822442 90)
		(property "Reference" "J1G2"
			(at 7.104888 34.562542 0)
			(unlocked yes)
			(layer "F.SilkS")
			(effects
				(font
					(size 0.7874 0.5842)
					(thickness 0.1524)
				)
				(justify left)
			)
		)
		(property "Value" ""
			(at 0 0 90)
			(layer "F.Fab")
			(effects
				(font
					(size 1.27 1.27)
				)
			)
		)
		(duplicate_pad_numbers_are_jumpers no)
		(fp_line
			(start 5.5499 -7.675118)
			(end 5.5499 -1.480058)
			(stroke
				(width 0.1524)
				(type default)
			)
			(layer "F.SilkS")
		)
		(fp_line
			(start -0.94996 -7.675118)
			(end 5.5499 -7.675118)
			(stroke
				(width 0.1524)
				(type default)
			)
			(layer "F.SilkS")
		)
		(fp_line
			(start -0.94996 -1.480058)
			(end -0.94996 -7.675118)
			(stroke
				(width 0.1524)
				(type default)
			)
			(layer "F.SilkS")
		)
		(fp_line
			(start 5.5499 128.130046)
			(end 5.5499 134.325106)
			(stroke
				(width 0.1524)
				(type default)
			)
			(layer "F.SilkS")
		)
		(fp_line
			(start 5.5499 134.325106)
			(end -0.94996 134.325106)
			(stroke
				(width 0.1524)
				(type default)
			)
			(layer "F.SilkS")
		)
		(fp_line
			(start -0.94996 134.325106)
			(end -0.94996 128.130046)
			(stroke
				(width 0.1524)
				(type default)
			)
			(layer "F.SilkS")
		)
		(fp_poly
			(pts
				(xy -3.044444 -4.193032) (xy -3.044444 -3.177032) (xy -1.774444 -3.685032)
			)
			(stroke
				(width 0)
				(type default)
			)
			(fill yes)
			(layer "F.SilkS")
		)
		(fp_poly
			(pts
				(xy -0.94996 -7.675118) (xy -0.94996 134.325106) (xy 5.5499 134.325106) (xy 5.5499 -7.675118)
			)
			(stroke
				(width 0)
				(type default)
			)
			(fill no)
			(layer "F.CrtYd")
		)
		(fp_line
			(start 5.5499 -7.675118)
			(end 5.5499 134.325106)
			(stroke
				(width 0.1)
				(type default)
			)
			(layer "F.Fab")
		)
		(fp_line
			(start -0.94996 -7.675118)
			(end 5.5499 -7.675118)
			(stroke
				(width 0.1)
				(type default)
			)
			(layer "F.Fab")
		)
		(fp_line
			(start 5.5499 134.325106)
			(end -0.94996 134.325106)
			(stroke
				(width 0.1)
				(type default)
			)
			(layer "F.Fab")
		)
		(fp_line
			(start -0.94996 134.325106)
			(end -0.94996 -7.675118)
			(stroke
				(width 0.1)
				(type default)
			)
			(layer "F.Fab")
		)
		(fp_poly
			(pts
				(xy -2.984246 -0.461264) (xy -2.984246 0.554736) (xy -1.714246 0.046736)
			)
			(stroke
				(width 0)
				(type default)
			)
			(fill yes)
			(layer "F.Fab")
		)
		(fp_text user "145"
			(at 6.043168 0.191262 0)
			(unlocked yes)
			(layer "F.SilkS")
			(effects
				(font
					(size 0.7874 0.5842)
					(thickness 0.1524)
				)
				(justify left)
			)
		)
		(fp_text user "77"
			(at -1.099312 65.753742 0)
			(unlocked yes)
			(layer "F.SilkS")
			(effects
				(font
					(size 0.7874 0.5842)
					(thickness 0.1524)
				)
				(justify left)
			)
		)
		(fp_text user "78"
			(at -2.04089 69.753734 0)
			(unlocked yes)
			(layer "F.SilkS")
			(effects
				(font
					(size 0.7874 0.5842)
					(thickness 0.1524)
				)
				(justify left)
			)
		)
		(fp_text user "222"
			(at 6.086094 70.179438 0)
			(unlocked yes)
			(layer "F.SilkS")
			(effects
				(font
					(size 0.7874 0.5842)
					(thickness 0.1524)
				)
				(justify left)
			)
		)
		(fp_text user "288"
			(at 6.241288 128.059942 0)
			(unlocked yes)
			(layer "F.SilkS")
			(effects
				(font
					(size 0.7874 0.5842)
					(thickness 0.1524)
				)
				(justify left)
			)
		)
		(fp_text user "144"
			(at -1.835912 128.059942 0)
			(unlocked yes)
			(layer "F.SilkS")
			(effects
				(font
					(size 0.7874 0.5842)
					(thickness 0.1524)
				)
				(justify left)
			)
		)
		(fp_text user "145"
			(at 3.067558 -0.843788 90)
			(unlocked yes)
			(layer "F.Fab")
			(effects
				(font
					(size 0.7874 0.5842)
					(thickness 0.1524)
				)
				(justify left)
			)
		)
		(fp_text user "77"
			(at -0.539242 65.907412 90)
			(unlocked yes)
			(layer "F.Fab")
			(effects
				(font
					(size 0.7874 0.5842)
					(thickness 0.1524)
				)
				(justify left)
			)
		)
		(fp_text user "221"
			(at 3.004058 65.966848 90)
			(unlocked yes)
			(layer "F.Fab")
			(effects
				(font
					(size 0.7874 0.5842)
					(thickness 0.1524)
				)
				(justify left)
			)
		)
		(fp_text user "78"
			(at -0.793242 69.234812 90)
			(unlocked yes)
			(layer "F.Fab")
			(effects
				(font
					(size 0.7874 0.5842)
					(thickness 0.1524)
				)
				(justify left)
			)
		)
		(fp_text user "222"
			(at 3.042158 69.361812 90)
			(unlocked yes)
			(layer "F.Fab")
			(effects
				(font
					(size 0.7874 0.5842)
					(thickness 0.1524)
				)
				(justify left)
			)
		)
		(fp_text user "288"
			(at 2.965958 127.883412 90)
			(unlocked yes)
			(layer "F.Fab")
			(effects
				(font
					(size 0.7874 0.5842)
					(thickness 0.1524)
				)
				(justify left)
			)
		)
		(fp_text user "144"
			(at -0.869442 127.883412 90)
			(unlocked yes)
			(layer "F.Fab")
			(effects
				(font
					(size 0.7874 0.5842)
					(thickness 0.1524)
				)
				(justify left)
			)
		)
		(pad "" thru_hole circle
			(at 2.29997 -5.649976 90)
			(size 2.8194 2.8194)
			(drill 2.4384)
			(layers "*.Cu" "*.Mask")
			(remove_unused_layers no)
			(clearance 0.127)
			(thermal_gap 0.127)
		)
		(pad "" thru_hole oval
			(at 2.29997 68.90004 90)
			(size 2.8194 1.5748)
			(drill oval 2.4384 1.1938)
			(layers "*.Cu" "*.Mask")
			(remove_unused_layers no)
			(clearance 0.127)
			(thermal_gap 0.127)
		)
		(pad "" thru_hole circle
			(at 2.29997 132.299964 90)
			(size 2.8194 2.8194)
			(drill 2.4384)
			(layers "*.Cu" "*.Mask")
			(remove_unused_layers no)
			(clearance 0.127)
			(thermal_gap 0.127)
		)
		(pad "1" smd rect
			(at 0 0 90)
			(size 1.8034 0.508)
			(layers "F.Cu" "F.Mask" "F.Paste")
			(net "P12V_NVDIMM_GHJ")
		)
		(pad "2" smd rect
			(at 0 0.849884 90)
			(size 1.8034 0.508)
			(layers "F.Cu" "F.Mask" "F.Paste")
			(net "GND")
		)
		(pad "3" smd rect
			(at 0 1.700022 90)
			(size 1.8034 0.508)
			(layers "F.Cu" "F.Mask" "F.Paste")
			(net "M_H_DQ<5>")
		)
		(pad "4" smd rect
			(at 0 2.549906 90)
			(size 1.8034 0.508)
			(layers "F.Cu" "F.Mask" "F.Paste")
			(net "GND")
		)
		(pad "5" smd rect
			(at 0 3.400044 90)
			(size 1.8034 0.508)
			(layers "F.Cu" "F.Mask" "F.Paste")
			(net "M_H_DQ<1>")
		)
		(pad "6" smd rect
			(at 0 4.249928 90)
			(size 1.8034 0.508)
			(layers "F.Cu" "F.Mask" "F.Paste")
			(net "GND")
		)
		(pad "7" smd rect
			(at 0 5.100066 90)
			(size 1.8034 0.508)
			(layers "F.Cu" "F.Mask" "F.Paste")
			(net "M_H_DQS_DP<9>")
		)
		(pad "8" smd rect
			(at 0 5.94995 90)
			(size 1.8034 0.508)
			(layers "F.Cu" "F.Mask" "F.Paste")
			(net "M_H_DQS_DN<9>")
		)
		(pad "9" smd rect
			(at 0 6.800088 90)
			(size 1.8034 0.508)
			(layers "F.Cu" "F.Mask" "F.Paste")
			(net "GND")
		)
		(pad "10" smd rect
			(at 0 7.649972 90)
			(size 1.8034 0.508)
			(layers "F.Cu" "F.Mask" "F.Paste")
			(net "M_H_DQ<7>")
		)
		(pad "11" smd rect
			(at 0 8.50011 90)
			(size 1.8034 0.508)
			(layers "F.Cu" "F.Mask" "F.Paste")
			(net "GND")
		)
		(pad "12" smd rect
			(at 0 9.349994 90)
			(size 1.8034 0.508)
			(layers "F.Cu" "F.Mask" "F.Paste")
			(net "M_H_DQ<3>")
		)
		(pad "13" smd rect
			(at 0 10.199878 90)
			(size 1.8034 0.508)
			(layers "F.Cu" "F.Mask" "F.Paste")
			(net "GND")
		)
		(pad "14" smd rect
			(at 0 11.050016 90)
			(size 1.8034 0.508)
			(layers "F.Cu" "F.Mask" "F.Paste")
			(net "M_H_DQ<13>")
		)
		(pad "15" smd rect
			(at 0 11.8999 90)
			(size 1.8034 0.508)
			(layers "F.Cu" "F.Mask" "F.Paste")
			(net "GND")
		)
		(pad "16" smd rect
			(at 0 12.750038 90)
			(size 1.8034 0.508)
			(layers "F.Cu" "F.Mask" "F.Paste")
			(net "M_H_DQ<9>")
		)
		(pad "17" smd rect
			(at 0 13.599922 90)
			(size 1.8034 0.508)
			(layers "F.Cu" "F.Mask" "F.Paste")
			(net "GND")
		)
		(pad "18" smd rect
			(at 0 14.45006 90)
			(size 1.8034 0.508)
			(layers "F.Cu" "F.Mask" "F.Paste")
			(net "M_H_DQS_DP<10>")
		)
		(pad "19" smd rect
			(at 0 15.299944 90)
			(size 1.8034 0.508)
			(layers "F.Cu" "F.Mask" "F.Paste")
			(net "M_H_DQS_DN<10>")
		)
		(pad "20" smd rect
			(at 0 16.150082 90)
			(size 1.8034 0.508)
			(layers "F.Cu" "F.Mask" "F.Paste")
			(net "GND")
		)
		(pad "21" smd rect
			(at 0 16.999966 90)
			(size 1.8034 0.508)
			(layers "F.Cu" "F.Mask" "F.Paste")
			(net "M_H_DQ<15>")
		)
		(pad "22" smd rect
			(at 0 17.850104 90)
			(size 1.8034 0.508)
			(layers "F.Cu" "F.Mask" "F.Paste")
			(net "GND")
		)
		(pad "23" smd rect
			(at 0 18.699988 90)
			(size 1.8034 0.508)
			(layers "F.Cu" "F.Mask" "F.Paste")
			(net "M_H_DQ<11>")
		)
		(pad "24" smd rect
			(at 0 19.550126 90)
			(size 1.8034 0.508)
			(layers "F.Cu" "F.Mask" "F.Paste")
			(net "GND")
		)
		(pad "25" smd rect
			(at 0 20.40001 90)
			(size 1.8034 0.508)
			(layers "F.Cu" "F.Mask" "F.Paste")
			(net "M_H_DQ<21>")
		)
		(pad "26" smd rect
			(at 0 21.249894 90)
			(size 1.8034 0.508)
			(layers "F.Cu" "F.Mask" "F.Paste")
			(net "GND")
		)
		(pad "27" smd rect
			(at 0 22.100032 90)
			(size 1.8034 0.508)
			(layers "F.Cu" "F.Mask" "F.Paste")
			(net "M_H_DQ<17>")
		)
		(pad "28" smd rect
			(at 0 22.949916 90)
			(size 1.8034 0.508)
			(layers "F.Cu" "F.Mask" "F.Paste")
			(net "GND")
		)
		(pad "29" smd rect
			(at 0 23.800054 90)
			(size 1.8034 0.508)
			(layers "F.Cu" "F.Mask" "F.Paste")
			(net "M_H_DQS_DP<11>")
		)
		(pad "30" smd rect
			(at 0 24.649938 90)
			(size 1.8034 0.508)
			(layers "F.Cu" "F.Mask" "F.Paste")
			(net "M_H_DQS_DN<11>")
		)
		(pad "31" smd rect
			(at 0 25.500076 90)
			(size 1.8034 0.508)
			(layers "F.Cu" "F.Mask" "F.Paste")
			(net "GND")
		)
		(pad "32" smd rect
			(at 0 26.34996 90)
			(size 1.8034 0.508)
			(layers "F.Cu" "F.Mask" "F.Paste")
			(net "M_H_DQ<23>")
		)
		(pad "33" smd rect
			(at 0 27.200098 90)
			(size 1.8034 0.508)
			(layers "F.Cu" "F.Mask" "F.Paste")
			(net "GND")
		)
		(pad "34" smd rect
			(at 0 28.049982 90)
			(size 1.8034 0.508)
			(layers "F.Cu" "F.Mask" "F.Paste")
			(net "M_H_DQ<19>")
		)
		(pad "35" smd rect
			(at 0 28.90012 90)
			(size 1.8034 0.508)
			(layers "F.Cu" "F.Mask" "F.Paste")
			(net "GND")
		)
		(pad "36" smd rect
			(at 0 29.750004 90)
			(size 1.8034 0.508)
			(layers "F.Cu" "F.Mask" "F.Paste")
			(net "M_H_DQ<29>")
		)
		(pad "37" smd rect
			(at 0 30.599888 90)
			(size 1.8034 0.508)
			(layers "F.Cu" "F.Mask" "F.Paste")
			(net "GND")
		)
		(pad "38" smd rect
			(at 0 31.450026 90)
			(size 1.8034 0.508)
			(layers "F.Cu" "F.Mask" "F.Paste")
			(net "M_H_DQ<25>")
		)
		(pad "39" smd rect
			(at 0 32.29991 90)
			(size 1.8034 0.508)
			(layers "F.Cu" "F.Mask" "F.Paste")
			(net "GND")
		)
		(pad "40" smd rect
			(at 0 33.150048 90)
			(size 1.8034 0.508)
			(layers "F.Cu" "F.Mask" "F.Paste")
			(net "M_H_DQS_DP<12>")
		)
		(pad "41" smd rect
			(at 0 33.999932 90)
			(size 1.8034 0.508)
			(layers "F.Cu" "F.Mask" "F.Paste")
			(net "M_H_DQS_DN<12>")
		)
		(pad "42" smd rect
			(at 0 34.85007 90)
			(size 1.8034 0.508)
			(layers "F.Cu" "F.Mask" "F.Paste")
			(net "GND")
		)
		(pad "43" smd rect
			(at 0 35.699954 90)
			(size 1.8034 0.508)
			(layers "F.Cu" "F.Mask" "F.Paste")
			(net "M_H_DQ<31>")
		)
		(pad "44" smd rect
			(at 0 36.550092 90)
			(size 1.8034 0.508)
			(layers "F.Cu" "F.Mask" "F.Paste")
			(net "GND")
		)
		(pad "45" smd rect
			(at 0 37.399976 90)
			(size 1.8034 0.508)
			(layers "F.Cu" "F.Mask" "F.Paste")
			(net "M_H_DQ<27>")
		)
		(pad "46" smd rect
			(at 0 38.250114 90)
			(size 1.8034 0.508)
			(layers "F.Cu" "F.Mask" "F.Paste")
			(net "GND")
		)
		(pad "47" smd rect
			(at 0 39.099998 90)
			(size 1.8034 0.508)
			(layers "F.Cu" "F.Mask" "F.Paste")
			(net "M_H_ECC<5>")
		)
		(pad "48" smd rect
			(at 0 39.949882 90)
			(size 1.8034 0.508)
			(layers "F.Cu" "F.Mask" "F.Paste")
			(net "GND")
		)
		(pad "49" smd rect
			(at 0 40.80002 90)
			(size 1.8034 0.508)
			(layers "F.Cu" "F.Mask" "F.Paste")
			(net "M_H_ECC<1>")
		)
		(pad "50" smd rect
			(at 0 41.649904 90)
			(size 1.8034 0.508)
			(layers "F.Cu" "F.Mask" "F.Paste")
			(net "GND")
		)
		(pad "51" smd rect
			(at 0 42.500042 90)
			(size 1.8034 0.508)
			(layers "F.Cu" "F.Mask" "F.Paste")
			(net "M_H_DQS_DP<17>")
		)
		(pad "52" smd rect
			(at 0 43.349926 90)
			(size 1.8034 0.508)
			(layers "F.Cu" "F.Mask" "F.Paste")
			(net "M_H_DQS_DN<17>")
		)
		(pad "53" smd rect
			(at 0 44.200064 90)
			(size 1.8034 0.508)
			(layers "F.Cu" "F.Mask" "F.Paste")
			(net "GND")
		)
		(pad "54" smd rect
			(at 0 45.049948 90)
			(size 1.8034 0.508)
			(layers "F.Cu" "F.Mask" "F.Paste")
			(net "M_H_ECC<7>")
		)
		(pad "55" smd rect
			(at 0 45.900086 90)
			(size 1.8034 0.508)
			(layers "F.Cu" "F.Mask" "F.Paste")
			(net "GND")
		)
		(pad "56" smd rect
			(at 0 46.74997 90)
			(size 1.8034 0.508)
			(layers "F.Cu" "F.Mask" "F.Paste")
			(net "M_H_ECC<3>")
		)
		(pad "57" smd rect
			(at 0 47.600108 90)
			(size 1.8034 0.508)
			(layers "F.Cu" "F.Mask" "F.Paste")
			(net "GND")
		)
		(pad "58" smd rect
			(at 0 48.449992 90)
			(size 1.8034 0.508)
			(layers "F.Cu" "F.Mask" "F.Paste")
			(net "M_GHJ_RST_N")
		)
		(pad "59" smd rect
			(at 0 49.299876 90)
			(size 1.8034 0.508)
			(layers "F.Cu" "F.Mask" "F.Paste")
			(net "PVDDQ_GHJ")
		)
		(pad "60" smd rect
			(at 0 50.150014 90)
			(size 1.8034 0.508)
			(layers "F.Cu" "F.Mask" "F.Paste")
			(net "M_H_CKE<0>")
		)
		(pad "61" smd rect
			(at 0 50.999898 90)
			(size 1.8034 0.508)
			(layers "F.Cu" "F.Mask" "F.Paste")
			(net "PVDDQ_GHJ")
		)
		(pad "62" smd rect
			(at 0 51.850036 90)
			(size 1.8034 0.508)
			(layers "F.Cu" "F.Mask" "F.Paste")
			(net "M_H_ACT_N")
		)
		(pad "63" smd rect
			(at 0 52.69992 90)
			(size 1.8034 0.508)
			(layers "F.Cu" "F.Mask" "F.Paste")
			(net "M_H_BG<0>")
		)
		(pad "64" smd rect
			(at 0 53.550058 90)
			(size 1.8034 0.508)
			(layers "F.Cu" "F.Mask" "F.Paste")
			(net "PVDDQ_GHJ")
		)
		(pad "65" smd rect
			(at 0 54.399942 90)
			(size 1.8034 0.508)
			(layers "F.Cu" "F.Mask" "F.Paste")
			(net "M_H_MA<12>")
		)
		(pad "66" smd rect
			(at 0 55.25008 90)
			(size 1.8034 0.508)
			(layers "F.Cu" "F.Mask" "F.Paste")
			(net "M_H_MA<9>")
		)
		(pad "67" smd rect
			(at 0 56.099964 90)
			(size 1.8034 0.508)
			(layers "F.Cu" "F.Mask" "F.Paste")
			(net "PVDDQ_GHJ")
		)
		(pad "68" smd rect
			(at 0 56.950102 90)
			(size 1.8034 0.508)
			(layers "F.Cu" "F.Mask" "F.Paste")
			(net "M_H_MA<8>")
		)
		(pad "69" smd rect
			(at 0 57.799986 90)
			(size 1.8034 0.508)
			(layers "F.Cu" "F.Mask" "F.Paste")
			(net "M_H_MA<6>")
		)
		(pad "70" smd rect
			(at 0 58.650124 90)
			(size 1.8034 0.508)
			(layers "F.Cu" "F.Mask" "F.Paste")
			(net "PVDDQ_GHJ")
		)
		(pad "71" smd rect
			(at 0 59.500008 90)
			(size 1.8034 0.508)
			(layers "F.Cu" "F.Mask" "F.Paste")
			(net "M_H_MA<3>")
		)
		(pad "72" smd rect
			(at 0 60.349892 90)
			(size 1.8034 0.508)
			(layers "F.Cu" "F.Mask" "F.Paste")
			(net "M_H_MA<1>")
		)
		(pad "73" smd rect
			(at 0 61.20003 90)
			(size 1.8034 0.508)
			(layers "F.Cu" "F.Mask" "F.Paste")
			(net "PVDDQ_GHJ")
		)
		(pad "74" smd rect
			(at 0 62.049914 90)
			(size 1.8034 0.508)
			(layers "F.Cu" "F.Mask" "F.Paste")
			(net "M_H_CLK_DP<0>")
		)
		(pad "75" smd rect
			(at 0 62.900052 90)
			(size 1.8034 0.508)
			(layers "F.Cu" "F.Mask" "F.Paste")
			(net "M_H_CLK_DN<0>")
		)
		(pad "76" smd rect
			(at 0 63.749936 90)
			(size 1.8034 0.508)
			(layers "F.Cu" "F.Mask" "F.Paste")
			(net "PVDDQ_GHJ")
		)
		(pad "77" smd rect
			(at 0 64.600074 90)
			(size 1.8034 0.508)
			(layers "F.Cu" "F.Mask" "F.Paste")
			(net "PVTT_GHJ")
		)
		(pad "78" smd rect
			(at 0 70.550024 90)
			(size 1.8034 0.508)
			(layers "F.Cu" "F.Mask" "F.Paste")
			(net "FM_DIMM_EVENT_COD_N")
		)
		(pad "79" smd rect
			(at 0 71.399908 90)
			(size 1.8034 0.508)
			(layers "F.Cu" "F.Mask" "F.Paste")
			(net "M_H_MA<0>")
		)
		(pad "80" smd rect
			(at 0 72.250046 90)
			(size 1.8034 0.508)
			(layers "F.Cu" "F.Mask" "F.Paste")
			(net "PVDDQ_GHJ")
		)
		(pad "81" smd rect
			(at 0 73.09993 90)
			(size 1.8034 0.508)
			(layers "F.Cu" "F.Mask" "F.Paste")
			(net "M_H_BA<0>")
		)
		(pad "82" smd rect
			(at 0 73.950068 90)
			(size 1.8034 0.508)
			(layers "F.Cu" "F.Mask" "F.Paste")
			(net "M_H_MA<16>")
		)
		(pad "83" smd rect
			(at 0 74.799952 90)
			(size 1.8034 0.508)
			(layers "F.Cu" "F.Mask" "F.Paste")
			(net "PVDDQ_GHJ")
		)
		(pad "84" smd rect
			(at 0 75.65009 90)
			(size 1.8034 0.508)
			(layers "F.Cu" "F.Mask" "F.Paste")
			(net "M_H_CS_N<0>")
		)
		(pad "85" smd rect
			(at 0 76.499974 90)
			(size 1.8034 0.508)
			(layers "F.Cu" "F.Mask" "F.Paste")
			(net "PVDDQ_GHJ")
		)
		(pad "86" smd rect
			(at 0 77.350112 90)
			(size 1.8034 0.508)
			(layers "F.Cu" "F.Mask" "F.Paste")
			(net "M_H_MA<15>")
		)
		(pad "87" smd rect
			(at 0 78.199996 90)
			(size 1.8034 0.508)
			(layers "F.Cu" "F.Mask" "F.Paste")
			(net "M_H_ODT<0>")
		)
		(pad "88" smd rect
			(at 0 79.04988 90)
			(size 1.8034 0.508)
			(layers "F.Cu" "F.Mask" "F.Paste")
			(net "PVDDQ_GHJ")
		)
		(pad "89" smd rect
			(at 0 79.900018 90)
			(size 1.8034 0.508)
			(layers "F.Cu" "F.Mask" "F.Paste")
			(net "M_H_CS_N<1>")
		)
		(pad "90" smd rect
			(at 0 80.749902 90)
			(size 1.8034 0.508)
			(layers "F.Cu" "F.Mask" "F.Paste")
			(net "PVDDQ_GHJ")
		)
		(pad "91" smd rect
			(at 0 81.60004 90)
			(size 1.8034 0.508)
			(layers "F.Cu" "F.Mask" "F.Paste")
			(net "M_H_ODT<1>")
		)
		(pad "92" smd rect
			(at 0 82.449924 90)
			(size 1.8034 0.508)
			(layers "F.Cu" "F.Mask" "F.Paste")
			(net "PVDDQ_GHJ")
		)
		(pad "93" smd rect
			(at 0 83.300062 90)
			(size 1.8034 0.508)
			(layers "F.Cu" "F.Mask" "F.Paste")
			(net "M_H_CS_N<2>")
		)
		(pad "94" smd rect
			(at 0 84.149946 90)
			(size 1.8034 0.508)
			(layers "F.Cu" "F.Mask" "F.Paste")
			(net "GND")
		)
		(pad "95" smd rect
			(at 0 85.000084 90)
			(size 1.8034 0.508)
			(layers "F.Cu" "F.Mask" "F.Paste")
			(net "M_H_DQ<37>")
		)
		(pad "96" smd rect
			(at 0 85.849968 90)
			(size 1.8034 0.508)
			(layers "F.Cu" "F.Mask" "F.Paste")
			(net "GND")
		)
		(pad "97" smd rect
			(at 0 86.700106 90)
			(size 1.8034 0.508)
			(layers "F.Cu" "F.Mask" "F.Paste")
			(net "M_H_DQ<33>")
		)
		(pad "98" smd rect
			(at 0 87.54999 90)
			(size 1.8034 0.508)
			(layers "F.Cu" "F.Mask" "F.Paste")
			(net "GND")
		)
		(pad "99" smd rect
			(at 0 88.399874 90)
			(size 1.8034 0.508)
			(layers "F.Cu" "F.Mask" "F.Paste")
			(net "M_H_DQS_DP<13>")
		)
		(pad "100" smd rect
			(at 0 89.250012 90)
			(size 1.8034 0.508)
			(layers "F.Cu" "F.Mask" "F.Paste")
			(net "M_H_DQS_DN<13>")
		)
		(pad "101" smd rect
			(at 0 90.099896 90)
			(size 1.8034 0.508)
			(layers "F.Cu" "F.Mask" "F.Paste")
			(net "GND")
		)
		(pad "102" smd rect
			(at 0 90.950034 90)
			(size 1.8034 0.508)
			(layers "F.Cu" "F.Mask" "F.Paste")
			(net "M_H_DQ<39>")
		)
		(pad "103" smd rect
			(at 0 91.799918 90)
			(size 1.8034 0.508)
			(layers "F.Cu" "F.Mask" "F.Paste")
			(net "GND")
		)
		(pad "104" smd rect
			(at 0 92.650056 90)
			(size 1.8034 0.508)
			(layers "F.Cu" "F.Mask" "F.Paste")
			(net "M_H_DQ<35>")
		)
		(pad "105" smd rect
			(at 0 93.49994 90)
			(size 1.8034 0.508)
			(layers "F.Cu" "F.Mask" "F.Paste")
			(net "GND")
		)
		(pad "106" smd rect
			(at 0 94.350078 90)
			(size 1.8034 0.508)
			(layers "F.Cu" "F.Mask" "F.Paste")
			(net "M_H_DQ<45>")
		)
		(pad "107" smd rect
			(at 0 95.199962 90)
			(size 1.8034 0.508)
			(layers "F.Cu" "F.Mask" "F.Paste")
			(net "GND")
		)
		(pad "108" smd rect
			(at 0 96.0501 90)
			(size 1.8034 0.508)
			(layers "F.Cu" "F.Mask" "F.Paste")
			(net "M_H_DQ<41>")
		)
		(pad "109" smd rect
			(at 0 96.899984 90)
			(size 1.8034 0.508)
			(layers "F.Cu" "F.Mask" "F.Paste")
			(net "GND")
		)
		(pad "110" smd rect
			(at 0 97.750122 90)
			(size 1.8034 0.508)
			(layers "F.Cu" "F.Mask" "F.Paste")
			(net "M_H_DQS_DP<14>")
		)
		(pad "111" smd rect
			(at 0 98.600006 90)
			(size 1.8034 0.508)
			(layers "F.Cu" "F.Mask" "F.Paste")
			(net "M_H_DQS_DN<14>")
		)
		(pad "112" smd rect
			(at 0 99.44989 90)
			(size 1.8034 0.508)
			(layers "F.Cu" "F.Mask" "F.Paste")
			(net "GND")
		)
		(pad "113" smd rect
			(at 0 100.300028 90)
			(size 1.8034 0.508)
			(layers "F.Cu" "F.Mask" "F.Paste")
			(net "M_H_DQ<47>")
		)
		(pad "114" smd rect
			(at 0 101.149912 90)
			(size 1.8034 0.508)
			(layers "F.Cu" "F.Mask" "F.Paste")
			(net "GND")
		)
		(pad "115" smd rect
			(at 0 102.00005 90)
			(size 1.8034 0.508)
			(layers "F.Cu" "F.Mask" "F.Paste")
			(net "M_H_DQ<43>")
		)
		(pad "116" smd rect
			(at 0 102.849934 90)
			(size 1.8034 0.508)
			(layers "F.Cu" "F.Mask" "F.Paste")
			(net "GND")
		)
		(pad "117" smd rect
			(at 0 103.700072 90)
			(size 1.8034 0.508)
			(layers "F.Cu" "F.Mask" "F.Paste")
			(net "M_H_DQ<53>")
		)
		(pad "118" smd rect
			(at 0 104.549956 90)
			(size 1.8034 0.508)
			(layers "F.Cu" "F.Mask" "F.Paste")
			(net "GND")
		)
		(pad "119" smd rect
			(at 0 105.400094 90)
			(size 1.8034 0.508)
			(layers "F.Cu" "F.Mask" "F.Paste")
			(net "M_H_DQ<49>")
		)
		(pad "120" smd rect
			(at 0 106.249978 90)
			(size 1.8034 0.508)
			(layers "F.Cu" "F.Mask" "F.Paste")
			(net "GND")
		)
		(pad "121" smd rect
			(at 0 107.100116 90)
			(size 1.8034 0.508)
			(layers "F.Cu" "F.Mask" "F.Paste")
			(net "M_H_DQS_DP<15>")
		)
		(pad "122" smd rect
			(at 0 107.95 90)
			(size 1.8034 0.508)
			(layers "F.Cu" "F.Mask" "F.Paste")
			(net "M_H_DQS_DN<15>")
		)
		(pad "123" smd rect
			(at 0 108.799884 90)
			(size 1.8034 0.508)
			(layers "F.Cu" "F.Mask" "F.Paste")
			(net "GND")
		)
		(pad "124" smd rect
			(at 0 109.650022 90)
			(size 1.8034 0.508)
			(layers "F.Cu" "F.Mask" "F.Paste")
			(net "M_H_DQ<55>")
		)
		(pad "125" smd rect
			(at 0 110.499906 90)
			(size 1.8034 0.508)
			(layers "F.Cu" "F.Mask" "F.Paste")
			(net "GND")
		)
		(pad "126" smd rect
			(at 0 111.350044 90)
			(size 1.8034 0.508)
			(layers "F.Cu" "F.Mask" "F.Paste")
			(net "M_H_DQ<51>")
		)
		(pad "127" smd rect
			(at 0 112.199928 90)
			(size 1.8034 0.508)
			(layers "F.Cu" "F.Mask" "F.Paste")
			(net "GND")
		)
		(pad "128" smd rect
			(at 0 113.050066 90)
			(size 1.8034 0.508)
			(layers "F.Cu" "F.Mask" "F.Paste")
			(net "M_H_DQ<61>")
		)
		(pad "129" smd rect
			(at 0 113.89995 90)
			(size 1.8034 0.508)
			(layers "F.Cu" "F.Mask" "F.Paste")
			(net "GND")
		)
		(pad "130" smd rect
			(at 0 114.750088 90)
			(size 1.8034 0.508)
			(layers "F.Cu" "F.Mask" "F.Paste")
			(net "M_H_DQ<57>")
		)
		(pad "131" smd rect
			(at 0 115.599972 90)
			(size 1.8034 0.508)
			(layers "F.Cu" "F.Mask" "F.Paste")
			(net "GND")
		)
		(pad "132" smd rect
			(at 0 116.45011 90)
			(size 1.8034 0.508)
			(layers "F.Cu" "F.Mask" "F.Paste")
			(net "M_H_DQS_DP<16>")
		)
		(pad "133" smd rect
			(at 0 117.299994 90)
			(size 1.8034 0.508)
			(layers "F.Cu" "F.Mask" "F.Paste")
			(net "M_H_DQS_DN<16>")
		)
		(pad "134" smd rect
			(at 0 118.149878 90)
			(size 1.8034 0.508)
			(layers "F.Cu" "F.Mask" "F.Paste")
			(net "GND")
		)
		(pad "135" smd rect
			(at 0 119.000016 90)
			(size 1.8034 0.508)
			(layers "F.Cu" "F.Mask" "F.Paste")
			(net "M_H_DQ<63>")
		)
		(pad "136" smd rect
			(at 0 119.8499 90)
			(size 1.8034 0.508)
			(layers "F.Cu" "F.Mask" "F.Paste")
			(net "GND")
		)
		(pad "137" smd rect
			(at 0 120.700038 90)
			(size 1.8034 0.508)
			(layers "F.Cu" "F.Mask" "F.Paste")
			(net "M_H_DQ<59>")
		)
		(pad "138" smd rect
			(at 0 121.549922 90)
			(size 1.8034 0.508)
			(layers "F.Cu" "F.Mask" "F.Paste")
			(net "GND")
		)
		(pad "139" smd rect
			(at 0 122.40006 90)
			(size 1.8034 0.508)
			(layers "F.Cu" "F.Mask" "F.Paste")
			(net "GND")
		)
		(pad "140" smd rect
			(at 0 123.249944 90)
			(size 1.8034 0.508)
			(layers "F.Cu" "F.Mask" "F.Paste")
			(net "PVPP_GHJ")
		)
		(pad "141" smd rect
			(at 0 124.100082 90)
			(size 1.8034 0.508)
			(layers "F.Cu" "F.Mask" "F.Paste")
			(net "SMB_DDR_GHJ_VPP_SCL")
		)
		(pad "142" smd rect
			(at 0 124.949966 90)
			(size 1.8034 0.508)
			(layers "F.Cu" "F.Mask" "F.Paste")
			(net "PVPP_GHJ")
		)
		(pad "143" smd rect
			(at 0 125.800104 90)
			(size 1.8034 0.508)
			(layers "F.Cu" "F.Mask" "F.Paste")
			(net "PVPP_GHJ")
		)
		(pad "144" smd rect
			(at 0 126.649988 90)
			(size 1.8034 0.508)
			(layers "F.Cu" "F.Mask" "F.Paste")
			(net "TP_CH_H_DIMM_H0_RFU_2")
		)
		(pad "145" smd rect
			(at 4.59994 0 90)
			(size 1.8034 0.508)
			(layers "F.Cu" "F.Mask" "F.Paste")
			(net "P12V_NVDIMM_GHJ")
		)
		(pad "146" smd rect
			(at 4.59994 0.849884 90)
			(size 1.8034 0.508)
			(layers "F.Cu" "F.Mask" "F.Paste")
			(net "M_H_VREF")
		)
		(pad "147" smd rect
			(at 4.59994 1.700022 90)
			(size 1.8034 0.508)
			(layers "F.Cu" "F.Mask" "F.Paste")
			(net "GND")
		)
		(pad "148" smd rect
			(at 4.59994 2.549906 90)
			(size 1.8034 0.508)
			(layers "F.Cu" "F.Mask" "F.Paste")
			(net "M_H_DQ<4>")
		)
		(pad "149" smd rect
			(at 4.59994 3.400044 90)
			(size 1.8034 0.508)
			(layers "F.Cu" "F.Mask" "F.Paste")
			(net "GND")
		)
		(pad "150" smd rect
			(at 4.59994 4.249928 90)
			(size 1.8034 0.508)
			(layers "F.Cu" "F.Mask" "F.Paste")
			(net "M_H_DQ<0>")
		)
		(pad "151" smd rect
			(at 4.59994 5.100066 90)
			(size 1.8034 0.508)
			(layers "F.Cu" "F.Mask" "F.Paste")
			(net "GND")
		)
		(pad "152" smd rect
			(at 4.59994 5.94995 90)
			(size 1.8034 0.508)
			(layers "F.Cu" "F.Mask" "F.Paste")
			(net "M_H_DQS_DN<0>")
		)
		(pad "153" smd rect
			(at 4.59994 6.800088 90)
			(size 1.8034 0.508)
			(layers "F.Cu" "F.Mask" "F.Paste")
			(net "M_H_DQS_DP<0>")
		)
		(pad "154" smd rect
			(at 4.59994 7.649972 90)
			(size 1.8034 0.508)
			(layers "F.Cu" "F.Mask" "F.Paste")
			(net "GND")
		)
		(pad "155" smd rect
			(at 4.59994 8.50011 90)
			(size 1.8034 0.508)
			(layers "F.Cu" "F.Mask" "F.Paste")
			(net "M_H_DQ<6>")
		)
		(pad "156" smd rect
			(at 4.59994 9.349994 90)
			(size 1.8034 0.508)
			(layers "F.Cu" "F.Mask" "F.Paste")
			(net "GND")
		)
		(pad "157" smd rect
			(at 4.59994 10.199878 90)
			(size 1.8034 0.508)
			(layers "F.Cu" "F.Mask" "F.Paste")
			(net "M_H_DQ<2>")
		)
		(pad "158" smd rect
			(at 4.59994 11.050016 90)
			(size 1.8034 0.508)
			(layers "F.Cu" "F.Mask" "F.Paste")
			(net "GND")
		)
		(pad "159" smd rect
			(at 4.59994 11.8999 90)
			(size 1.8034 0.508)
			(layers "F.Cu" "F.Mask" "F.Paste")
			(net "M_H_DQ<12>")
		)
		(pad "160" smd rect
			(at 4.59994 12.750038 90)
			(size 1.8034 0.508)
			(layers "F.Cu" "F.Mask" "F.Paste")
			(net "GND")
		)
		(pad "161" smd rect
			(at 4.59994 13.599922 90)
			(size 1.8034 0.508)
			(layers "F.Cu" "F.Mask" "F.Paste")
			(net "M_H_DQ<8>")
		)
		(pad "162" smd rect
			(at 4.59994 14.45006 90)
			(size 1.8034 0.508)
			(layers "F.Cu" "F.Mask" "F.Paste")
			(net "GND")
		)
		(pad "163" smd rect
			(at 4.59994 15.299944 90)
			(size 1.8034 0.508)
			(layers "F.Cu" "F.Mask" "F.Paste")
			(net "M_H_DQS_DN<1>")
		)
		(pad "164" smd rect
			(at 4.59994 16.150082 90)
			(size 1.8034 0.508)
			(layers "F.Cu" "F.Mask" "F.Paste")
			(net "M_H_DQS_DP<1>")
		)
		(pad "165" smd rect
			(at 4.59994 16.999966 90)
			(size 1.8034 0.508)
			(layers "F.Cu" "F.Mask" "F.Paste")
			(net "GND")
		)
		(pad "166" smd rect
			(at 4.59994 17.850104 90)
			(size 1.8034 0.508)
			(layers "F.Cu" "F.Mask" "F.Paste")
			(net "M_H_DQ<14>")
		)
		(pad "167" smd rect
			(at 4.59994 18.699988 90)
			(size 1.8034 0.508)
			(layers "F.Cu" "F.Mask" "F.Paste")
			(net "GND")
		)
		(pad "168" smd rect
			(at 4.59994 19.550126 90)
			(size 1.8034 0.508)
			(layers "F.Cu" "F.Mask" "F.Paste")
			(net "M_H_DQ<10>")
		)
		(pad "169" smd rect
			(at 4.59994 20.40001 90)
			(size 1.8034 0.508)
			(layers "F.Cu" "F.Mask" "F.Paste")
			(net "GND")
		)
		(pad "170" smd rect
			(at 4.59994 21.249894 90)
			(size 1.8034 0.508)
			(layers "F.Cu" "F.Mask" "F.Paste")
			(net "M_H_DQ<20>")
		)
		(pad "171" smd rect
			(at 4.59994 22.100032 90)
			(size 1.8034 0.508)
			(layers "F.Cu" "F.Mask" "F.Paste")
			(net "GND")
		)
		(pad "172" smd rect
			(at 4.59994 22.949916 90)
			(size 1.8034 0.508)
			(layers "F.Cu" "F.Mask" "F.Paste")
			(net "M_H_DQ<16>")
		)
		(pad "173" smd rect
			(at 4.59994 23.800054 90)
			(size 1.8034 0.508)
			(layers "F.Cu" "F.Mask" "F.Paste")
			(net "GND")
		)
		(pad "174" smd rect
			(at 4.59994 24.649938 90)
			(size 1.8034 0.508)
			(layers "F.Cu" "F.Mask" "F.Paste")
			(net "M_H_DQS_DN<2>")
		)
		(pad "175" smd rect
			(at 4.59994 25.500076 90)
			(size 1.8034 0.508)
			(layers "F.Cu" "F.Mask" "F.Paste")
			(net "M_H_DQS_DP<2>")
		)
		(pad "176" smd rect
			(at 4.59994 26.34996 90)
			(size 1.8034 0.508)
			(layers "F.Cu" "F.Mask" "F.Paste")
			(net "GND")
		)
		(pad "177" smd rect
			(at 4.59994 27.200098 90)
			(size 1.8034 0.508)
			(layers "F.Cu" "F.Mask" "F.Paste")
			(net "M_H_DQ<22>")
		)
		(pad "178" smd rect
			(at 4.59994 28.049982 90)
			(size 1.8034 0.508)
			(layers "F.Cu" "F.Mask" "F.Paste")
			(net "GND")
		)
		(pad "179" smd rect
			(at 4.59994 28.90012 90)
			(size 1.8034 0.508)
			(layers "F.Cu" "F.Mask" "F.Paste")
			(net "M_H_DQ<18>")
		)
		(pad "180" smd rect
			(at 4.59994 29.750004 90)
			(size 1.8034 0.508)
			(layers "F.Cu" "F.Mask" "F.Paste")
			(net "GND")
		)
		(pad "181" smd rect
			(at 4.59994 30.599888 90)
			(size 1.8034 0.508)
			(layers "F.Cu" "F.Mask" "F.Paste")
			(net "M_H_DQ<28>")
		)
		(pad "182" smd rect
			(at 4.59994 31.450026 90)
			(size 1.8034 0.508)
			(layers "F.Cu" "F.Mask" "F.Paste")
			(net "GND")
		)
		(pad "183" smd rect
			(at 4.59994 32.29991 90)
			(size 1.8034 0.508)
			(layers "F.Cu" "F.Mask" "F.Paste")
			(net "M_H_DQ<24>")
		)
		(pad "184" smd rect
			(at 4.59994 33.150048 90)
			(size 1.8034 0.508)
			(layers "F.Cu" "F.Mask" "F.Paste")
			(net "GND")
		)
		(pad "185" smd rect
			(at 4.59994 33.999932 90)
			(size 1.8034 0.508)
			(layers "F.Cu" "F.Mask" "F.Paste")
			(net "M_H_DQS_DN<3>")
		)
		(pad "186" smd rect
			(at 4.59994 34.85007 90)
			(size 1.8034 0.508)
			(layers "F.Cu" "F.Mask" "F.Paste")
			(net "M_H_DQS_DP<3>")
		)
		(pad "187" smd rect
			(at 4.59994 35.699954 90)
			(size 1.8034 0.508)
			(layers "F.Cu" "F.Mask" "F.Paste")
			(net "GND")
		)
		(pad "188" smd rect
			(at 4.59994 36.550092 90)
			(size 1.8034 0.508)
			(layers "F.Cu" "F.Mask" "F.Paste")
			(net "M_H_DQ<30>")
		)
		(pad "189" smd rect
			(at 4.59994 37.399976 90)
			(size 1.8034 0.508)
			(layers "F.Cu" "F.Mask" "F.Paste")
			(net "GND")
		)
		(pad "190" smd rect
			(at 4.59994 38.250114 90)
			(size 1.8034 0.508)
			(layers "F.Cu" "F.Mask" "F.Paste")
			(net "M_H_DQ<26>")
		)
		(pad "191" smd rect
			(at 4.59994 39.099998 90)
			(size 1.8034 0.508)
			(layers "F.Cu" "F.Mask" "F.Paste")
			(net "GND")
		)
		(pad "192" smd rect
			(at 4.59994 39.949882 90)
			(size 1.8034 0.508)
			(layers "F.Cu" "F.Mask" "F.Paste")
			(net "M_H_ECC<4>")
		)
		(pad "193" smd rect
			(at 4.59994 40.80002 90)
			(size 1.8034 0.508)
			(layers "F.Cu" "F.Mask" "F.Paste")
			(net "GND")
		)
		(pad "194" smd rect
			(at 4.59994 41.649904 90)
			(size 1.8034 0.508)
			(layers "F.Cu" "F.Mask" "F.Paste")
			(net "M_H_ECC<0>")
		)
		(pad "195" smd rect
			(at 4.59994 42.500042 90)
			(size 1.8034 0.508)
			(layers "F.Cu" "F.Mask" "F.Paste")
			(net "GND")
		)
		(pad "196" smd rect
			(at 4.59994 43.349926 90)
			(size 1.8034 0.508)
			(layers "F.Cu" "F.Mask" "F.Paste")
			(net "M_H_DQS_DN<8>")
		)
		(pad "197" smd rect
			(at 4.59994 44.200064 90)
			(size 1.8034 0.508)
			(layers "F.Cu" "F.Mask" "F.Paste")
			(net "M_H_DQS_DP<8>")
		)
		(pad "198" smd rect
			(at 4.59994 45.049948 90)
			(size 1.8034 0.508)
			(layers "F.Cu" "F.Mask" "F.Paste")
			(net "GND")
		)
		(pad "199" smd rect
			(at 4.59994 45.900086 90)
			(size 1.8034 0.508)
			(layers "F.Cu" "F.Mask" "F.Paste")
			(net "M_H_ECC<6>")
		)
		(pad "200" smd rect
			(at 4.59994 46.74997 90)
			(size 1.8034 0.508)
			(layers "F.Cu" "F.Mask" "F.Paste")
			(net "GND")
		)
		(pad "201" smd rect
			(at 4.59994 47.600108 90)
			(size 1.8034 0.508)
			(layers "F.Cu" "F.Mask" "F.Paste")
			(net "M_H_ECC<2>")
		)
		(pad "202" smd rect
			(at 4.59994 48.449992 90)
			(size 1.8034 0.508)
			(layers "F.Cu" "F.Mask" "F.Paste")
			(net "GND")
		)
		(pad "203" smd rect
			(at 4.59994 49.299876 90)
			(size 1.8034 0.508)
			(layers "F.Cu" "F.Mask" "F.Paste")
			(net "M_H_CKE<1>")
		)
		(pad "204" smd rect
			(at 4.59994 50.150014 90)
			(size 1.8034 0.508)
			(layers "F.Cu" "F.Mask" "F.Paste")
			(net "PVDDQ_GHJ")
		)
		(pad "205" smd rect
			(at 4.59994 50.999898 90)
			(size 1.8034 0.508)
			(layers "F.Cu" "F.Mask" "F.Paste")
			(net "TP_CH_H_DIMM_H0_RFU_0")
		)
		(pad "206" smd rect
			(at 4.59994 51.850036 90)
			(size 1.8034 0.508)
			(layers "F.Cu" "F.Mask" "F.Paste")
			(net "PVDDQ_GHJ")
		)
		(pad "207" smd rect
			(at 4.59994 52.69992 90)
			(size 1.8034 0.508)
			(layers "F.Cu" "F.Mask" "F.Paste")
			(net "M_H_BG<1>")
		)
		(pad "208" smd rect
			(at 4.59994 53.550058 90)
			(size 1.8034 0.508)
			(layers "F.Cu" "F.Mask" "F.Paste")
			(net "M_H_ALERT_N")
		)
		(pad "209" smd rect
			(at 4.59994 54.399942 90)
			(size 1.8034 0.508)
			(layers "F.Cu" "F.Mask" "F.Paste")
			(net "PVDDQ_GHJ")
		)
		(pad "210" smd rect
			(at 4.59994 55.25008 90)
			(size 1.8034 0.508)
			(layers "F.Cu" "F.Mask" "F.Paste")
			(net "M_H_MA<11>")
		)
		(pad "211" smd rect
			(at 4.59994 56.099964 90)
			(size 1.8034 0.508)
			(layers "F.Cu" "F.Mask" "F.Paste")
			(net "M_H_MA<7>")
		)
		(pad "212" smd rect
			(at 4.59994 56.950102 90)
			(size 1.8034 0.508)
			(layers "F.Cu" "F.Mask" "F.Paste")
			(net "PVDDQ_GHJ")
		)
		(pad "213" smd rect
			(at 4.59994 57.799986 90)
			(size 1.8034 0.508)
			(layers "F.Cu" "F.Mask" "F.Paste")
			(net "M_H_MA<5>")
		)
		(pad "214" smd rect
			(at 4.59994 58.650124 90)
			(size 1.8034 0.508)
			(layers "F.Cu" "F.Mask" "F.Paste")
			(net "M_H_MA<4>")
		)
		(pad "215" smd rect
			(at 4.59994 59.500008 90)
			(size 1.8034 0.508)
			(layers "F.Cu" "F.Mask" "F.Paste")
			(net "PVDDQ_GHJ")
		)
		(pad "216" smd rect
			(at 4.59994 60.349892 90)
			(size 1.8034 0.508)
			(layers "F.Cu" "F.Mask" "F.Paste")
			(net "M_H_MA<2>")
		)
		(pad "217" smd rect
			(at 4.59994 61.20003 90)
			(size 1.8034 0.508)
			(layers "F.Cu" "F.Mask" "F.Paste")
			(net "PVDDQ_GHJ")
		)
		(pad "218" smd rect
			(at 4.59994 62.049914 90)
			(size 1.8034 0.508)
			(layers "F.Cu" "F.Mask" "F.Paste")
			(net "M_H_CLK_DP<1>")
		)
		(pad "219" smd rect
			(at 4.59994 62.900052 90)
			(size 1.8034 0.508)
			(layers "F.Cu" "F.Mask" "F.Paste")
			(net "M_H_CLK_DN<1>")
		)
		(pad "220" smd rect
			(at 4.59994 63.749936 90)
			(size 1.8034 0.508)
			(layers "F.Cu" "F.Mask" "F.Paste")
			(net "PVDDQ_GHJ")
		)
		(pad "221" smd rect
			(at 4.59994 64.600074 90)
			(size 1.8034 0.508)
			(layers "F.Cu" "F.Mask" "F.Paste")
			(net "PVTT_GHJ")
		)
		(pad "222" smd rect
			(at 4.59994 70.550024 90)
			(size 1.8034 0.508)
			(layers "F.Cu" "F.Mask" "F.Paste")
			(net "M_H_PAR")
		)
		(pad "223" smd rect
			(at 4.59994 71.399908 90)
			(size 1.8034 0.508)
			(layers "F.Cu" "F.Mask" "F.Paste")
			(net "PVDDQ_GHJ")
		)
		(pad "224" smd rect
			(at 4.59994 72.250046 90)
			(size 1.8034 0.508)
			(layers "F.Cu" "F.Mask" "F.Paste")
			(net "M_H_BA<1>")
		)
		(pad "225" smd rect
			(at 4.59994 73.09993 90)
			(size 1.8034 0.508)
			(layers "F.Cu" "F.Mask" "F.Paste")
			(net "M_H_MA<10>")
		)
		(pad "226" smd rect
			(at 4.59994 73.950068 90)
			(size 1.8034 0.508)
			(layers "F.Cu" "F.Mask" "F.Paste")
			(net "PVDDQ_GHJ")
		)
		(pad "227" smd rect
			(at 4.59994 74.799952 90)
			(size 1.8034 0.508)
			(layers "F.Cu" "F.Mask" "F.Paste")
			(net "TP_CH_H_DIMM_H0_RFU_1")
		)
		(pad "228" smd rect
			(at 4.59994 75.65009 90)
			(size 1.8034 0.508)
			(layers "F.Cu" "F.Mask" "F.Paste")
			(net "M_H_MA<14>")
		)
		(pad "229" smd rect
			(at 4.59994 76.499974 90)
			(size 1.8034 0.508)
			(layers "F.Cu" "F.Mask" "F.Paste")
			(net "PVDDQ_GHJ")
		)
		(pad "230" smd rect
			(at 4.59994 77.350112 90)
			(size 1.8034 0.508)
			(layers "F.Cu" "F.Mask" "F.Paste")
			(net "FM_ADR_COMPLETE_GHJ_N")
		)
		(pad "231" smd rect
			(at 4.59994 78.199996 90)
			(size 1.8034 0.508)
			(layers "F.Cu" "F.Mask" "F.Paste")
			(net "PVDDQ_GHJ")
		)
		(pad "232" smd rect
			(at 4.59994 79.04988 90)
			(size 1.8034 0.508)
			(layers "F.Cu" "F.Mask" "F.Paste")
			(net "M_H_MA<13>")
		)
		(pad "233" smd rect
			(at 4.59994 79.900018 90)
			(size 1.8034 0.508)
			(layers "F.Cu" "F.Mask" "F.Paste")
			(net "PVDDQ_GHJ")
		)
		(pad "234" smd rect
			(at 4.59994 80.749902 90)
			(size 1.8034 0.508)
			(layers "F.Cu" "F.Mask" "F.Paste")
			(net "M_H_MA<17>")
		)
		(pad "235" smd rect
			(at 4.59994 81.60004 90)
			(size 1.8034 0.508)
			(layers "F.Cu" "F.Mask" "F.Paste")
			(net "M_H_C<2>")
		)
		(pad "236" smd rect
			(at 4.59994 82.449924 90)
			(size 1.8034 0.508)
			(layers "F.Cu" "F.Mask" "F.Paste")
			(net "PVDDQ_GHJ")
		)
		(pad "237" smd rect
			(at 4.59994 83.300062 90)
			(size 1.8034 0.508)
			(layers "F.Cu" "F.Mask" "F.Paste")
			(net "M_H_CS_N<3>")
		)
		(pad "238" smd rect
			(at 4.59994 84.149946 90)
			(size 1.8034 0.508)
			(layers "F.Cu" "F.Mask" "F.Paste")
			(net "GND")
		)
		(pad "239" smd rect
			(at 4.59994 85.000084 90)
			(size 1.8034 0.508)
			(layers "F.Cu" "F.Mask" "F.Paste")
			(net "GND")
		)
		(pad "240" smd rect
			(at 4.59994 85.849968 90)
			(size 1.8034 0.508)
			(layers "F.Cu" "F.Mask" "F.Paste")
			(net "M_H_DQ<36>")
		)
		(pad "241" smd rect
			(at 4.59994 86.700106 90)
			(size 1.8034 0.508)
			(layers "F.Cu" "F.Mask" "F.Paste")
			(net "GND")
		)
		(pad "242" smd rect
			(at 4.59994 87.54999 90)
			(size 1.8034 0.508)
			(layers "F.Cu" "F.Mask" "F.Paste")
			(net "M_H_DQ<32>")
		)
		(pad "243" smd rect
			(at 4.59994 88.399874 90)
			(size 1.8034 0.508)
			(layers "F.Cu" "F.Mask" "F.Paste")
			(net "GND")
		)
		(pad "244" smd rect
			(at 4.59994 89.250012 90)
			(size 1.8034 0.508)
			(layers "F.Cu" "F.Mask" "F.Paste")
			(net "M_H_DQS_DN<4>")
		)
		(pad "245" smd rect
			(at 4.59994 90.099896 90)
			(size 1.8034 0.508)
			(layers "F.Cu" "F.Mask" "F.Paste")
			(net "M_H_DQS_DP<4>")
		)
		(pad "246" smd rect
			(at 4.59994 90.950034 90)
			(size 1.8034 0.508)
			(layers "F.Cu" "F.Mask" "F.Paste")
			(net "GND")
		)
		(pad "247" smd rect
			(at 4.59994 91.799918 90)
			(size 1.8034 0.508)
			(layers "F.Cu" "F.Mask" "F.Paste")
			(net "M_H_DQ<38>")
		)
		(pad "248" smd rect
			(at 4.59994 92.650056 90)
			(size 1.8034 0.508)
			(layers "F.Cu" "F.Mask" "F.Paste")
			(net "GND")
		)
		(pad "249" smd rect
			(at 4.59994 93.49994 90)
			(size 1.8034 0.508)
			(layers "F.Cu" "F.Mask" "F.Paste")
			(net "M_H_DQ<34>")
		)
		(pad "250" smd rect
			(at 4.59994 94.350078 90)
			(size 1.8034 0.508)
			(layers "F.Cu" "F.Mask" "F.Paste")
			(net "GND")
		)
		(pad "251" smd rect
			(at 4.59994 95.199962 90)
			(size 1.8034 0.508)
			(layers "F.Cu" "F.Mask" "F.Paste")
			(net "M_H_DQ<44>")
		)
		(pad "252" smd rect
			(at 4.59994 96.0501 90)
			(size 1.8034 0.508)
			(layers "F.Cu" "F.Mask" "F.Paste")
			(net "GND")
		)
		(pad "253" smd rect
			(at 4.59994 96.899984 90)
			(size 1.8034 0.508)
			(layers "F.Cu" "F.Mask" "F.Paste")
			(net "M_H_DQ<40>")
		)
		(pad "254" smd rect
			(at 4.59994 97.750122 90)
			(size 1.8034 0.508)
			(layers "F.Cu" "F.Mask" "F.Paste")
			(net "GND")
		)
		(pad "255" smd rect
			(at 4.59994 98.600006 90)
			(size 1.8034 0.508)
			(layers "F.Cu" "F.Mask" "F.Paste")
			(net "M_H_DQS_DN<5>")
		)
		(pad "256" smd rect
			(at 4.59994 99.44989 90)
			(size 1.8034 0.508)
			(layers "F.Cu" "F.Mask" "F.Paste")
			(net "M_H_DQS_DP<5>")
		)
		(pad "257" smd rect
			(at 4.59994 100.300028 90)
			(size 1.8034 0.508)
			(layers "F.Cu" "F.Mask" "F.Paste")
			(net "GND")
		)
		(pad "258" smd rect
			(at 4.59994 101.149912 90)
			(size 1.8034 0.508)
			(layers "F.Cu" "F.Mask" "F.Paste")
			(net "M_H_DQ<46>")
		)
		(pad "259" smd rect
			(at 4.59994 102.00005 90)
			(size 1.8034 0.508)
			(layers "F.Cu" "F.Mask" "F.Paste")
			(net "GND")
		)
		(pad "260" smd rect
			(at 4.59994 102.849934 90)
			(size 1.8034 0.508)
			(layers "F.Cu" "F.Mask" "F.Paste")
			(net "M_H_DQ<42>")
		)
		(pad "261" smd rect
			(at 4.59994 103.700072 90)
			(size 1.8034 0.508)
			(layers "F.Cu" "F.Mask" "F.Paste")
			(net "GND")
		)
		(pad "262" smd rect
			(at 4.59994 104.549956 90)
			(size 1.8034 0.508)
			(layers "F.Cu" "F.Mask" "F.Paste")
			(net "M_H_DQ<52>")
		)
		(pad "263" smd rect
			(at 4.59994 105.400094 90)
			(size 1.8034 0.508)
			(layers "F.Cu" "F.Mask" "F.Paste")
			(net "GND")
		)
		(pad "264" smd rect
			(at 4.59994 106.249978 90)
			(size 1.8034 0.508)
			(layers "F.Cu" "F.Mask" "F.Paste")
			(net "M_H_DQ<48>")
		)
		(pad "265" smd rect
			(at 4.59994 107.100116 90)
			(size 1.8034 0.508)
			(layers "F.Cu" "F.Mask" "F.Paste")
			(net "GND")
		)
		(pad "266" smd rect
			(at 4.59994 107.95 90)
			(size 1.8034 0.508)
			(layers "F.Cu" "F.Mask" "F.Paste")
			(net "M_H_DQS_DN<6>")
		)
		(pad "267" smd rect
			(at 4.59994 108.799884 90)
			(size 1.8034 0.508)
			(layers "F.Cu" "F.Mask" "F.Paste")
			(net "M_H_DQS_DP<6>")
		)
		(pad "268" smd rect
			(at 4.59994 109.650022 90)
			(size 1.8034 0.508)
			(layers "F.Cu" "F.Mask" "F.Paste")
			(net "GND")
		)
		(pad "269" smd rect
			(at 4.59994 110.499906 90)
			(size 1.8034 0.508)
			(layers "F.Cu" "F.Mask" "F.Paste")
			(net "M_H_DQ<54>")
		)
		(pad "270" smd rect
			(at 4.59994 111.350044 90)
			(size 1.8034 0.508)
			(layers "F.Cu" "F.Mask" "F.Paste")
			(net "GND")
		)
		(pad "271" smd rect
			(at 4.59994 112.199928 90)
			(size 1.8034 0.508)
			(layers "F.Cu" "F.Mask" "F.Paste")
			(net "M_H_DQ<50>")
		)
		(pad "272" smd rect
			(at 4.59994 113.050066 90)
			(size 1.8034 0.508)
			(layers "F.Cu" "F.Mask" "F.Paste")
			(net "GND")
		)
		(pad "273" smd rect
			(at 4.59994 113.89995 90)
			(size 1.8034 0.508)
			(layers "F.Cu" "F.Mask" "F.Paste")
			(net "M_H_DQ<60>")
		)
		(pad "274" smd rect
			(at 4.59994 114.750088 90)
			(size 1.8034 0.508)
			(layers "F.Cu" "F.Mask" "F.Paste")
			(net "GND")
		)
		(pad "275" smd rect
			(at 4.59994 115.599972 90)
			(size 1.8034 0.508)
			(layers "F.Cu" "F.Mask" "F.Paste")
			(net "M_H_DQ<56>")
		)
		(pad "276" smd rect
			(at 4.59994 116.45011 90)
			(size 1.8034 0.508)
			(layers "F.Cu" "F.Mask" "F.Paste")
			(net "GND")
		)
		(pad "277" smd rect
			(at 4.59994 117.299994 90)
			(size 1.8034 0.508)
			(layers "F.Cu" "F.Mask" "F.Paste")
			(net "M_H_DQS_DN<7>")
		)
		(pad "278" smd rect
			(at 4.59994 118.149878 90)
			(size 1.8034 0.508)
			(layers "F.Cu" "F.Mask" "F.Paste")
			(net "M_H_DQS_DP<7>")
		)
		(pad "279" smd rect
			(at 4.59994 119.000016 90)
			(size 1.8034 0.508)
			(layers "F.Cu" "F.Mask" "F.Paste")
			(net "GND")
		)
		(pad "280" smd rect
			(at 4.59994 119.8499 90)
			(size 1.8034 0.508)
			(layers "F.Cu" "F.Mask" "F.Paste")
			(net "M_H_DQ<62>")
		)
		(pad "281" smd rect
			(at 4.59994 120.700038 90)
			(size 1.8034 0.508)
			(layers "F.Cu" "F.Mask" "F.Paste")
			(net "GND")
		)
		(pad "282" smd rect
			(at 4.59994 121.549922 90)
			(size 1.8034 0.508)
			(layers "F.Cu" "F.Mask" "F.Paste")
			(net "M_H_DQ<58>")
		)
		(pad "283" smd rect
			(at 4.59994 122.40006 90)
			(size 1.8034 0.508)
			(layers "F.Cu" "F.Mask" "F.Paste")
			(net "GND")
		)
		(pad "284" smd rect
			(at 4.59994 123.249944 90)
			(size 1.8034 0.508)
			(layers "F.Cu" "F.Mask" "F.Paste")
			(net "PVPP_GHJ")
		)
		(pad "285" smd rect
			(at 4.59994 124.100082 90)
			(size 1.8034 0.508)
			(layers "F.Cu" "F.Mask" "F.Paste")
			(net "SMB_DDR_GHJ_VPP_SDA")
		)
		(pad "286" smd rect
			(at 4.59994 124.949966 90)
			(size 1.8034 0.508)
			(layers "F.Cu" "F.Mask" "F.Paste")
			(net "PVPP_GHJ")
		)
		(pad "287" smd rect
			(at 4.59994 125.800104 90)
			(size 1.8034 0.508)
			(layers "F.Cu" "F.Mask" "F.Paste")
			(net "PVPP_GHJ")
		)
		(pad "288" smd rect
			(at 4.59994 126.649988 90)
			(size 1.8034 0.508)
			(layers "F.Cu" "F.Mask" "F.Paste")
			(net "PVPP_GHJ")
		)
	)
	(footprint ""
		(layer "F.Cu")
		(at -0.786384 -123.210574 90)
		(property "Reference" "CF21"
			(at 0 0 90)
			(layer "F.SilkS")
			(hide yes)
			(effects
				(font
					(size 1.27 1.27)
				)
			)
		)
		(property "Value" "*"
			(at 1.1811 -2.8194 90)
			(unlocked yes)
			(layer "F.Fab")
			(hide yes)
			(effects
				(font
					(size 1.27 1.016)
					(thickness 0.1524)
				)
			)
		)
		(property "Device Type" "SC22P50V2JN-4GP_SMD-BCG-SC22P5A"
			(at 1.1811 -4.3434 90)
			(unlocked yes)
			(layer "F.Fab")
			(hide yes)
			(effects
				(font
					(size 1.27 1.016)
					(thickness 0.1524)
				)
			)
		)
		(duplicate_pad_numbers_are_jumpers no)
		(fp_rect
			(start -0.4318 0.9525)
			(end 0.4318 -0.9525)
			(stroke
				(width 0)
				(type default)
			)
			(fill no)
			(layer "F.CrtYd")
		)
		(fp_rect
			(start -0.4318 0.9525)
			(end 0.4318 -0.9525)
			(stroke
				(width 0)
				(type default)
			)
			(fill no)
			(layer "F.Fab")
		)
		(pad "1" smd custom
			(at 0 -0.4445 90)
			(size 0.1524 0.1524)
			(layers "F.Cu" "F.Mask" "F.Paste")
			(net "VR_PVDDQ_KLM_AIREF1")
			(options
				(clearance outline)
				(anchor circle)
			)
			(primitives
				(gr_poly
					(pts
						(arc
							(start 0.3048 -0.2032)
							(mid 0.275042 -0.275042)
							(end 0.2032 -0.3048)
						)
						(arc
							(start -0.2032 -0.3048)
							(mid -0.275042 -0.275042)
							(end -0.3048 -0.2032)
						)
						(arc
							(start -0.3048 0.2032)
							(mid -0.275042 0.275042)
							(end -0.2032 0.3048)
						)
						(arc
							(start 0.2032 0.3048)
							(mid 0.275042 0.275042)
							(end 0.3048 0.2032)
						)
					)
					(width 0)
					(fill yes)
				)
			)
		)
		(pad "2" smd custom
			(at 0 0.4445 90)
			(size 0.1524 0.1524)
			(layers "F.Cu" "F.Mask" "F.Paste")
			(net "ISENSE_PVDDQ_KLM_PH1_IMON")
			(options
				(clearance outline)
				(anchor circle)
			)
			(primitives
				(gr_poly
					(pts
						(arc
							(start 0.3048 -0.2032)
							(mid 0.275042 -0.275042)
							(end 0.2032 -0.3048)
						)
						(arc
							(start -0.2032 -0.3048)
							(mid -0.275042 -0.275042)
							(end -0.3048 -0.2032)
						)
						(arc
							(start -0.3048 0.2032)
							(mid -0.275042 0.275042)
							(end -0.2032 0.3048)
						)
						(arc
							(start 0.2032 0.3048)
							(mid 0.275042 0.275042)
							(end 0.3048 0.2032)
						)
					)
					(width 0)
					(fill yes)
				)
			)
		)
	)
	(footprint ""
		(layer "F.Cu")
		(at 264.431272 -73.318116)
		(property "Reference" "C5D44"
			(at 0 0 0)
			(layer "F.SilkS")
			(hide yes)
			(effects
				(font
					(size 1.27 1.27)
				)
			)
		)
		(property "Value" ""
			(at 0 0 0)
			(layer "F.Fab")
			(effects
				(font
					(size 1.27 1.27)
				)
			)
		)
		(duplicate_pad_numbers_are_jumpers no)
		(fp_poly
			(pts
				(xy -0.4953 -0.2032) (xy 0.4953 -0.2032) (xy 0.4953 1.6002) (xy -0.4953 1.6002)
			)
			(stroke
				(width 0)
				(type default)
			)
			(fill no)
			(layer "F.CrtYd")
		)
		(fp_line
			(start -0.4953 -0.2032)
			(end 0.4953 -0.2032)
			(stroke
				(width 0.1)
				(type default)
			)
			(layer "F.Fab")
		)
		(fp_line
			(start -0.4953 1.6002)
			(end -0.4953 -0.2032)
			(stroke
				(width 0.1)
				(type default)
			)
			(layer "F.Fab")
		)
		(fp_line
			(start 0.4953 -0.2032)
			(end 0.4953 1.6002)
			(stroke
				(width 0.1)
				(type default)
			)
			(layer "F.Fab")
		)
		(fp_line
			(start 0.4953 1.6002)
			(end -0.4953 1.6002)
			(stroke
				(width 0.1)
				(type default)
			)
			(layer "F.Fab")
		)
		(pad "1" smd rect
			(at 0 0)
			(size 0.762 0.889)
			(layers "F.Cu" "F.Mask" "F.Paste")
			(net "PVCCIN_CPU0")
		)
		(pad "2" smd rect
			(at 0 1.397)
			(size 0.762 0.889)
			(layers "F.Cu" "F.Mask" "F.Paste")
			(net "GND")
		)
		(zone
			(layer "F.Cu")
			(hatch none 0.5)
			(connect_pads
				(clearance 0)
			)
			(min_thickness 0.25)
			(keepout
				(tracks not_allowed)
				(vias allowed)
				(pads allowed)
				(copperpour not_allowed)
				(footprints allowed)
			)
			(placement
				(enabled no)
				(sheetname "")
			)
			(fill
				(thermal_gap 0.5)
				(thermal_bridge_width 0.5)
				(island_removal_mode 0)
			)
			(polygon
				(pts
					(xy 264.050272 -72.873616) (xy 264.812272 -72.873616) (xy 264.812272 -72.365616) (xy 264.050272 -72.365616)
				)
			)
		)
	)
	(footprint ""
		(layer "F.Cu")
		(at 379.815344 -10.941558)
		(property "Reference" "C7G19"
			(at 0 0 0)
			(layer "F.SilkS")
			(hide yes)
			(effects
				(font
					(size 1.27 1.27)
				)
			)
		)
		(property "Value" ""
			(at 0 0 0)
			(layer "F.Fab")
			(effects
				(font
					(size 1.27 1.27)
				)
			)
		)
		(duplicate_pad_numbers_are_jumpers no)
		(fp_rect
			(start -0.3048 0.9906)
			(end 0.3048 -0.1016)
			(stroke
				(width 0)
				(type default)
			)
			(fill no)
			(layer "F.CrtYd")
		)
		(fp_line
			(start -0.3048 -0.1016)
			(end -0.3048 0.9906)
			(stroke
				(width 0.1)
				(type default)
			)
			(layer "F.Fab")
		)
		(fp_line
			(start -0.3048 0.9906)
			(end 0.3048 0.9906)
			(stroke
				(width 0.1)
				(type default)
			)
			(layer "F.Fab")
		)
		(fp_line
			(start 0.3048 -0.1016)
			(end -0.3048 -0.1016)
			(stroke
				(width 0.1)
				(type default)
			)
			(layer "F.Fab")
		)
		(fp_line
			(start 0.3048 0.9906)
			(end 0.3048 -0.1016)
			(stroke
				(width 0.1)
				(type default)
			)
			(layer "F.Fab")
		)
		(pad "1" smd rect
			(at 0 0)
			(size 0.508 0.508)
			(layers "F.Cu" "F.Mask" "F.Paste")
			(net "P3E_CPU0_PE2_SS_TXN<8>")
		)
		(pad "2" smd rect
			(at 0 0.889)
			(size 0.508 0.508)
			(layers "F.Cu" "F.Mask" "F.Paste")
			(net "P3E_CPU0_PE2_SS_C_TXN<8>")
		)
		(zone
			(layer "F.Cu")
			(hatch none 0.5)
			(connect_pads
				(clearance 0)
			)
			(min_thickness 0.25)
			(keepout
				(tracks not_allowed)
				(vias allowed)
				(pads allowed)
				(copperpour not_allowed)
				(footprints allowed)
			)
			(placement
				(enabled no)
				(sheetname "")
			)
			(fill
				(thermal_gap 0.5)
				(thermal_bridge_width 0.5)
				(island_removal_mode 0)
			)
			(polygon
				(pts
					(xy 379.561344 -10.306558) (xy 380.069344 -10.306558) (xy 380.069344 -10.687558) (xy 379.561344 -10.687558)
				)
			)
		)
		(zone
			(layer "F.Cu")
			(hatch none 0.5)
			(connect_pads
				(clearance 0)
			)
			(min_thickness 0.25)
			(keepout
				(tracks allowed)
				(vias not_allowed)
				(pads allowed)
				(copperpour not_allowed)
				(footprints allowed)
			)
			(placement
				(enabled no)
				(sheetname "")
			)
			(fill
				(thermal_gap 0.5)
				(thermal_bridge_width 0.5)
				(island_removal_mode 0)
			)
			(polygon
				(pts
					(xy 379.561344 -10.306558) (xy 380.069344 -10.306558) (xy 380.069344 -10.687558) (xy 379.561344 -10.687558)
				)
			)
		)
	)
	(footprint ""
		(layer "F.Cu")
		(at 4.29895 -13.642594 90)
		(property "Reference" "C1G29"
			(at 0 0 90)
			(layer "F.SilkS")
			(hide yes)
			(effects
				(font
					(size 1.27 1.27)
				)
			)
		)
		(property "Value" ""
			(at 0 0 90)
			(layer "F.Fab")
			(effects
				(font
					(size 1.27 1.27)
				)
			)
		)
		(duplicate_pad_numbers_are_jumpers no)
		(fp_rect
			(start 0.3048 0.9906)
			(end -0.3048 -0.1016)
			(stroke
				(width 0)
				(type default)
			)
			(fill no)
			(layer "F.CrtYd")
		)
		(fp_line
			(start 0.3048 -0.1016)
			(end -0.3048 -0.1016)
			(stroke
				(width 0.1)
				(type default)
			)
			(layer "F.Fab")
		)
		(fp_line
			(start -0.3048 -0.1016)
			(end -0.3048 0.9906)
			(stroke
				(width 0.1)
				(type default)
			)
			(layer "F.Fab")
		)
		(fp_line
			(start 0.3048 0.9906)
			(end 0.3048 -0.1016)
			(stroke
				(width 0.1)
				(type default)
			)
			(layer "F.Fab")
		)
		(fp_line
			(start -0.3048 0.9906)
			(end 0.3048 0.9906)
			(stroke
				(width 0.1)
				(type default)
			)
			(layer "F.Fab")
		)
		(pad "1" smd rect
			(at 0 0 90)
			(size 0.508 0.508)
			(layers "F.Cu" "F.Mask" "F.Paste")
			(net "P5V_STBY")
		)
		(pad "2" smd rect
			(at 0 0.889 90)
			(size 0.508 0.508)
			(layers "F.Cu" "F.Mask" "F.Paste")
			(net "GND")
		)
		(zone
			(layer "F.Cu")
			(hatch none 0.5)
			(connect_pads
				(clearance 0)
			)
			(min_thickness 0.25)
			(keepout
				(tracks not_allowed)
				(vias allowed)
				(pads allowed)
				(copperpour not_allowed)
				(footprints allowed)
			)
			(placement
				(enabled no)
				(sheetname "")
			)
			(fill
				(thermal_gap 0.5)
				(thermal_bridge_width 0.5)
				(island_removal_mode 0)
			)
			(polygon
				(pts
					(xy 4.93395 -13.896594) (xy 4.55295 -13.896594) (xy 4.55295 -13.388594) (xy 4.93395 -13.388594)
				)
			)
		)
		(zone
			(layer "F.Cu")
			(hatch none 0.5)
			(connect_pads
				(clearance 0)
			)
			(min_thickness 0.25)
			(keepout
				(tracks allowed)
				(vias not_allowed)
				(pads allowed)
				(copperpour not_allowed)
				(footprints allowed)
			)
			(placement
				(enabled no)
				(sheetname "")
			)
			(fill
				(thermal_gap 0.5)
				(thermal_bridge_width 0.5)
				(island_removal_mode 0)
			)
			(polygon
				(pts
					(xy 4.93395 -13.896594) (xy 4.55295 -13.896594) (xy 4.55295 -13.388594) (xy 4.93395 -13.388594)
				)
			)
		)
	)
	(footprint ""
		(layer "F.Cu")
		(at 7.69747 -110.891828 90)
		(property "Reference" "C1B19"
			(at -0.8382 -0.67818 90)
			(unlocked yes)
			(layer "F.SilkS")
			(effects
				(font
					(size 0.4064 0.254)
					(thickness 0.1524)
				)
				(justify left)
			)
		)
		(property "Value" ""
			(at 0 0 90)
			(layer "F.Fab")
			(effects
				(font
					(size 1.27 1.27)
				)
			)
		)
		(duplicate_pad_numbers_are_jumpers no)
		(fp_poly
			(pts
				(xy 0.3048 -0.1016) (xy 0.3048 0.9906) (xy -0.3048 0.9906) (xy -0.3048 -0.1016)
			)
			(stroke
				(width 0)
				(type default)
			)
			(fill no)
			(layer "F.CrtYd")
		)
		(fp_line
			(start 0.3048 -0.1016)
			(end -0.3048 -0.1016)
			(stroke
				(width 0.1)
				(type default)
			)
			(layer "F.Fab")
		)
		(fp_line
			(start -0.3048 -0.1016)
			(end -0.3048 0.9906)
			(stroke
				(width 0.1)
				(type default)
			)
			(layer "F.Fab")
		)
		(fp_line
			(start 0.3048 0.9906)
			(end 0.3048 -0.1016)
			(stroke
				(width 0.1)
				(type default)
			)
			(layer "F.Fab")
		)
		(fp_line
			(start -0.3048 0.9906)
			(end 0.3048 0.9906)
			(stroke
				(width 0.1)
				(type default)
			)
			(layer "F.Fab")
		)
		(pad "1" smd rect
			(at 0 0 90)
			(size 0.508 0.508)
			(layers "F.Cu" "F.Mask" "F.Paste")
			(net "P12V_FAN")
		)
		(pad "2" smd rect
			(at 0 0.889 90)
			(size 0.508 0.508)
			(layers "F.Cu" "F.Mask" "F.Paste")
			(net "GND")
		)
		(zone
			(layer "F.Cu")
			(hatch none 0.5)
			(connect_pads
				(clearance 0)
			)
			(min_thickness 0.25)
			(keepout
				(tracks allowed)
				(vias not_allowed)
				(pads allowed)
				(copperpour not_allowed)
				(footprints allowed)
			)
			(placement
				(enabled no)
				(sheetname "")
			)
			(fill
				(thermal_gap 0.5)
				(thermal_bridge_width 0.5)
				(island_removal_mode 0)
			)
			(polygon
				(pts
					(xy 7.95147 -110.637828) (xy 7.95147 -111.145828) (xy 8.33247 -111.145828) (xy 8.33247 -110.637828)
				)
			)
		)
		(zone
			(layer "F.Cu")
			(hatch none 0.5)
			(connect_pads
				(clearance 0)
			)
			(min_thickness 0.25)
			(keepout
				(tracks not_allowed)
				(vias allowed)
				(pads allowed)
				(copperpour not_allowed)
				(footprints allowed)
			)
			(placement
				(enabled no)
				(sheetname "")
			)
			(fill
				(thermal_gap 0.5)
				(thermal_bridge_width 0.5)
				(island_removal_mode 0)
			)
			(polygon
				(pts
					(xy 8.33247 -110.637828) (xy 8.33247 -111.145828) (xy 7.95147 -111.145828) (xy 7.95147 -110.637828)
				)
			)
		)
	)
	(footprint ""
		(layer "F.Cu")
		(at 163.576 -84.328 -90)
		(property "Reference" "R4D11"
			(at 0 0 270)
			(layer "F.SilkS")
			(hide yes)
			(effects
				(font
					(size 1.27 1.27)
				)
			)
		)
		(property "Value" ""
			(at 0 0 270)
			(layer "F.Fab")
			(effects
				(font
					(size 1.27 1.27)
				)
			)
		)
		(duplicate_pad_numbers_are_jumpers no)
		(fp_poly
			(pts
				(xy -0.2794 -0.1016) (xy 0.2794 -0.1016) (xy 0.2794 0.9906) (xy -0.2794 0.9906)
			)
			(stroke
				(width 0)
				(type default)
			)
			(fill no)
			(layer "F.CrtYd")
		)
		(fp_line
			(start -0.2794 0.9906)
			(end 0.2794 0.9906)
			(stroke
				(width 0.1)
				(type default)
			)
			(layer "F.Fab")
		)
		(fp_line
			(start 0.2794 0.9906)
			(end 0.2794 -0.1016)
			(stroke
				(width 0.1)
				(type default)
			)
			(layer "F.Fab")
		)
		(fp_line
			(start -0.2794 -0.1016)
			(end -0.2794 0.9906)
			(stroke
				(width 0.1)
				(type default)
			)
			(layer "F.Fab")
		)
		(fp_line
			(start 0.2794 -0.1016)
			(end -0.2794 -0.1016)
			(stroke
				(width 0.1)
				(type default)
			)
			(layer "F.Fab")
		)
		(pad "1" smd rect
			(at 0 0 270)
			(size 0.508 0.508)
			(layers "F.Cu" "F.Mask" "F.Paste")
			(net "CLK_100M_CPU1_BCLK2_R_DN")
		)
		(pad "2" smd rect
			(at 0 0.889 270)
			(size 0.508 0.508)
			(layers "F.Cu" "F.Mask" "F.Paste")
			(net "CLK_100M_CPU1_BCLK2_DN")
		)
		(zone
			(layer "F.Cu")
			(hatch none 0.5)
			(connect_pads
				(clearance 0)
			)
			(min_thickness 0.25)
			(keepout
				(tracks not_allowed)
				(vias allowed)
				(pads allowed)
				(copperpour not_allowed)
				(footprints allowed)
			)
			(placement
				(enabled no)
				(sheetname "")
			)
			(fill
				(thermal_gap 0.5)
				(thermal_bridge_width 0.5)
				(island_removal_mode 0)
			)
			(polygon
				(pts
					(xy 162.941 -84.582) (xy 162.941 -84.074) (xy 163.322 -84.074) (xy 163.322 -84.582)
				)
			)
		)
		(zone
			(layer "F.Cu")
			(hatch none 0.5)
			(connect_pads
				(clearance 0)
			)
			(min_thickness 0.25)
			(keepout
				(tracks allowed)
				(vias not_allowed)
				(pads allowed)
				(copperpour not_allowed)
				(footprints allowed)
			)
			(placement
				(enabled no)
				(sheetname "")
			)
			(fill
				(thermal_gap 0.5)
				(thermal_bridge_width 0.5)
				(island_removal_mode 0)
			)
			(polygon
				(pts
					(xy 163.322 -84.582) (xy 163.322 -84.074) (xy 162.941 -84.074) (xy 162.941 -84.582)
				)
			)
		)
	)
	(footprint ""
		(layer "F.Cu")
		(at 173.297088 -91.22156 -90)
		(property "Reference" "R4C10"
			(at 0 0 270)
			(layer "F.SilkS")
			(hide yes)
			(effects
				(font
					(size 1.27 1.27)
				)
			)
		)
		(property "Value" ""
			(at 0 0 270)
			(layer "F.Fab")
			(effects
				(font
					(size 1.27 1.27)
				)
			)
		)
		(duplicate_pad_numbers_are_jumpers no)
		(fp_poly
			(pts
				(xy -0.2794 -0.1016) (xy 0.2794 -0.1016) (xy 0.2794 0.9906) (xy -0.2794 0.9906)
			)
			(stroke
				(width 0)
				(type default)
			)
			(fill no)
			(layer "F.CrtYd")
		)
		(fp_line
			(start -0.2794 0.9906)
			(end 0.2794 0.9906)
			(stroke
				(width 0.1)
				(type default)
			)
			(layer "F.Fab")
		)
		(fp_line
			(start 0.2794 0.9906)
			(end 0.2794 -0.1016)
			(stroke
				(width 0.1)
				(type default)
			)
			(layer "F.Fab")
		)
		(fp_line
			(start -0.2794 -0.1016)
			(end -0.2794 0.9906)
			(stroke
				(width 0.1)
				(type default)
			)
			(layer "F.Fab")
		)
		(fp_line
			(start 0.2794 -0.1016)
			(end -0.2794 -0.1016)
			(stroke
				(width 0.1)
				(type default)
			)
			(layer "F.Fab")
		)
		(pad "1" smd rect
			(at 0 0 270)
			(size 0.508 0.508)
			(layers "F.Cu" "F.Mask" "F.Paste")
			(net "PVCCIO_CPU1")
		)
		(pad "2" smd rect
			(at 0 0.889 270)
			(size 0.508 0.508)
			(layers "F.Cu" "F.Mask" "F.Paste")
			(net "PU_CPU1_TSC_SYNC")
		)
		(zone
			(layer "F.Cu")
			(hatch none 0.5)
			(connect_pads
				(clearance 0)
			)
			(min_thickness 0.25)
			(keepout
				(tracks not_allowed)
				(vias allowed)
				(pads allowed)
				(copperpour not_allowed)
				(footprints allowed)
			)
			(placement
				(enabled no)
				(sheetname "")
			)
			(fill
				(thermal_gap 0.5)
				(thermal_bridge_width 0.5)
				(island_removal_mode 0)
			)
			(polygon
				(pts
					(xy 172.662088 -91.47556) (xy 172.662088 -90.96756) (xy 173.043088 -90.96756) (xy 173.043088 -91.47556)
				)
			)
		)
		(zone
			(layer "F.Cu")
			(hatch none 0.5)
			(connect_pads
				(clearance 0)
			)
			(min_thickness 0.25)
			(keepout
				(tracks allowed)
				(vias not_allowed)
				(pads allowed)
				(copperpour not_allowed)
				(footprints allowed)
			)
			(placement
				(enabled no)
				(sheetname "")
			)
			(fill
				(thermal_gap 0.5)
				(thermal_bridge_width 0.5)
				(island_removal_mode 0)
			)
			(polygon
				(pts
					(xy 173.043088 -91.47556) (xy 173.043088 -90.96756) (xy 172.662088 -90.96756) (xy 172.662088 -91.47556)
				)
			)
		)
	)
	(footprint ""
		(layer "F.Cu")
		(at 368.554 -109.601 90)
		(property "Reference" "C7C3"
			(at 0 0 90)
			(layer "F.SilkS")
			(hide yes)
			(effects
				(font
					(size 1.27 1.27)
				)
			)
		)
		(property "Value" ""
			(at 0 0 90)
			(layer "F.Fab")
			(effects
				(font
					(size 1.27 1.27)
				)
			)
		)
		(duplicate_pad_numbers_are_jumpers no)
		(fp_poly
			(pts
				(xy 0.3048 -0.1016) (xy 0.3048 0.9906) (xy -0.3048 0.9906) (xy -0.3048 -0.1016)
			)
			(stroke
				(width 0)
				(type default)
			)
			(fill no)
			(layer "F.CrtYd")
		)
		(fp_line
			(start 0.3048 -0.1016)
			(end -0.3048 -0.1016)
			(stroke
				(width 0.1)
				(type default)
			)
			(layer "F.Fab")
		)
		(fp_line
			(start -0.3048 -0.1016)
			(end -0.3048 0.9906)
			(stroke
				(width 0.1)
				(type default)
			)
			(layer "F.Fab")
		)
		(fp_line
			(start 0.3048 0.9906)
			(end 0.3048 -0.1016)
			(stroke
				(width 0.1)
				(type default)
			)
			(layer "F.Fab")
		)
		(fp_line
			(start -0.3048 0.9906)
			(end 0.3048 0.9906)
			(stroke
				(width 0.1)
				(type default)
			)
			(layer "F.Fab")
		)
		(pad "1" smd rect
			(at 0 0 90)
			(size 0.508 0.508)
			(layers "F.Cu" "F.Mask" "F.Paste")
			(net "DMI_CPU0_PCH_TX_DN<0>")
		)
		(pad "2" smd rect
			(at 0 0.889 90)
			(size 0.508 0.508)
			(layers "F.Cu" "F.Mask" "F.Paste")
			(net "DMI_CPU0_PCH_TX_C_DN<0>")
		)
		(zone
			(layer "F.Cu")
			(hatch none 0.5)
			(connect_pads
				(clearance 0)
			)
			(min_thickness 0.25)
			(keepout
				(tracks allowed)
				(vias not_allowed)
				(pads allowed)
				(copperpour not_allowed)
				(footprints allowed)
			)
			(placement
				(enabled no)
				(sheetname "")
			)
			(fill
				(thermal_gap 0.5)
				(thermal_bridge_width 0.5)
				(island_removal_mode 0)
			)
			(polygon
				(pts
					(xy 368.808 -109.347) (xy 368.808 -109.855) (xy 369.189 -109.855) (xy 369.189 -109.347)
				)
			)
		)
		(zone
			(layer "F.Cu")
			(hatch none 0.5)
			(connect_pads
				(clearance 0)
			)
			(min_thickness 0.25)
			(keepout
				(tracks not_allowed)
				(vias allowed)
				(pads allowed)
				(copperpour not_allowed)
				(footprints allowed)
			)
			(placement
				(enabled no)
				(sheetname "")
			)
			(fill
				(thermal_gap 0.5)
				(thermal_bridge_width 0.5)
				(island_removal_mode 0)
			)
			(polygon
				(pts
					(xy 369.189 -109.347) (xy 369.189 -109.855) (xy 368.808 -109.855) (xy 368.808 -109.347)
				)
			)
		)
	)
	(footprint ""
		(layer "F.Cu")
		(at 349.07728 -11.14933 -90)
		(property "Reference" "CT51"
			(at -1.72593 0.0508 0)
			(unlocked yes)
			(layer "F.SilkS")
			(effects
				(font
					(size 0.7874 0.5842)
					(thickness 0.1524)
				)
				(justify left)
			)
		)
		(property "Value" ""
			(at 0 0 270)
			(layer "F.Fab")
			(effects
				(font
					(size 1.27 1.27)
				)
			)
		)
		(duplicate_pad_numbers_are_jumpers no)
		(fp_poly
			(pts
				(xy 0.3048 -0.1016) (xy 0.3048 0.9906) (xy -0.3048 0.9906) (xy -0.3048 -0.1016)
			)
			(stroke
				(width 0)
				(type default)
			)
			(fill no)
			(layer "F.CrtYd")
		)
		(fp_line
			(start -0.3048 0.9906)
			(end 0.3048 0.9906)
			(stroke
				(width 0.1)
				(type default)
			)
			(layer "F.Fab")
		)
		(fp_line
			(start 0.3048 0.9906)
			(end 0.3048 -0.1016)
			(stroke
				(width 0.1)
				(type default)
			)
			(layer "F.Fab")
		)
		(fp_line
			(start -0.3048 -0.1016)
			(end -0.3048 0.9906)
			(stroke
				(width 0.1)
				(type default)
			)
			(layer "F.Fab")
		)
		(fp_line
			(start 0.3048 -0.1016)
			(end -0.3048 -0.1016)
			(stroke
				(width 0.1)
				(type default)
			)
			(layer "F.Fab")
		)
		(pad "1" smd rect
			(at 0 0 270)
			(size 0.508 0.508)
			(layers "F.Cu" "F.Mask" "F.Paste")
			(net "VR_PVDDQ_ABC_AIREF1")
		)
		(pad "2" smd rect
			(at 0 0.889 270)
			(size 0.508 0.508)
			(layers "F.Cu" "F.Mask" "F.Paste")
			(net "GND")
		)
		(zone
			(layer "F.Cu")
			(hatch none 0.5)
			(connect_pads
				(clearance 0)
			)
			(min_thickness 0.25)
			(keepout
				(tracks not_allowed)
				(vias allowed)
				(pads allowed)
				(copperpour not_allowed)
				(footprints allowed)
			)
			(placement
				(enabled no)
				(sheetname "")
			)
			(fill
				(thermal_gap 0.5)
				(thermal_bridge_width 0.5)
				(island_removal_mode 0)
			)
			(polygon
				(pts
					(xy 348.44228 -11.40333) (xy 348.44228 -10.89533) (xy 348.82328 -10.89533) (xy 348.82328 -11.40333)
				)
			)
		)
		(zone
			(layer "F.Cu")
			(hatch none 0.5)
			(connect_pads
				(clearance 0)
			)
			(min_thickness 0.25)
			(keepout
				(tracks allowed)
				(vias not_allowed)
				(pads allowed)
				(copperpour not_allowed)
				(footprints allowed)
			)
			(placement
				(enabled no)
				(sheetname "")
			)
			(fill
				(thermal_gap 0.5)
				(thermal_bridge_width 0.5)
				(island_removal_mode 0)
			)
			(polygon
				(pts
					(xy 348.82328 -11.40333) (xy 348.82328 -10.89533) (xy 348.44228 -10.89533) (xy 348.44228 -11.40333)
				)
			)
		)
	)
	(footprint ""
		(layer "F.Cu")
		(at 357.000048 1.999996 90)
		(property "Reference" "TH7G1"
			(at 3.624326 -3.051048 0)
			(unlocked yes)
			(layer "F.SilkS")
			(effects
				(font
					(size 0.7874 0.5842)
					(thickness 0.1524)
				)
				(justify left)
			)
		)
		(property "Value" ""
			(at 0 0 90)
			(layer "F.Fab")
			(effects
				(font
					(size 1.27 1.27)
				)
			)
		)
		(duplicate_pad_numbers_are_jumpers no)
		(fp_poly
			(pts
				(arc
					(start 3.0226 0.68834)
					(mid 3.042235 0.827855)
					(end 3.099562 0.956564)
				)
				(arc
					(start 3.099562 0.956564)
					(mid 4.012804 3.550073)
					(end 3.042158 6.12267)
				)
				(arc
					(start 3.042158 6.12267)
					(mid 0 7.518589)
					(end -3.042158 6.12267)
				)
				(arc
					(start -3.042158 6.12267)
					(mid -4.012854 3.55061)
					(end -3.100324 0.957326)
				)
				(arc
					(start -3.100324 0.957326)
					(mid -3.042498 0.827518)
					(end -3.0226 0.686816)
				)
				(arc
					(start -3.0226 -0.000254)
					(mid -2.137121 -2.137227)
					(end 0 -3.022346)
				)
				(arc
					(start 0 -3.022346)
					(mid 2.137227 -2.136973)
					(end 3.0226 0.000254)
				)
			)
			(stroke
				(width 0)
				(type default)
			)
			(fill no)
			(layer "F.CrtYd")
		)
		(pad "1" thru_hole custom
			(at 0 0 90)
			(size 2.00667 2.00667)
			(drill 0.3048)
			(layers "*.Cu" "*.Mask")
			(remove_unused_layers no)
			(net "GND")
			(clearance -0.889)
			(options
				(clearance outline)
				(anchor circle)
			)
			(primitives
				(gr_poly
					(pts
						(arc
							(start 3.042158 3.874516)
							(mid 0 5.270435)
							(end -3.042158 3.874516)
						)
						(arc
							(start -3.042158 3.874516)
							(mid -4.012854 1.302456)
							(end -3.100324 -1.290828)
						)
						(arc
							(start -3.100324 -1.290828)
							(mid -3.042498 -1.420636)
							(end -3.0226 -1.561338)
						)
						(arc
							(start -3.0226 -2.248408)
							(mid -2.137121 -4.385381)
							(end 0 -5.2705)
						)
						(arc
							(start 0 -5.2705)
							(mid 2.137227 -4.385127)
							(end 3.0226 -2.2479)
						)
						(arc
							(start 3.0226 -1.55956)
							(mid 3.04227 -1.420177)
							(end 3.099562 -1.29159)
						)
						(arc
							(start 3.099562 -1.29159)
							(mid 4.012804 1.301919)
							(end 3.042158 3.874516)
						)
					)
					(width 0)
					(fill yes)
				)
			)
		)
	)
	(footprint ""
		(layer "F.Cu")
		(at 482.03104 -51.36134)
		(property "Reference" "R9W36"
			(at -0.8382 -0.67818 0)
			(unlocked yes)
			(layer "F.SilkS")
			(effects
				(font
					(size 0.4064 0.254)
					(thickness 0.1524)
				)
				(justify left)
			)
		)
		(property "Value" ""
			(at 0 0 0)
			(layer "F.Fab")
			(effects
				(font
					(size 1.27 1.27)
				)
			)
		)
		(duplicate_pad_numbers_are_jumpers no)
		(fp_poly
			(pts
				(xy -0.2794 -0.1016) (xy 0.2794 -0.1016) (xy 0.2794 0.9906) (xy -0.2794 0.9906)
			)
			(stroke
				(width 0)
				(type default)
			)
			(fill no)
			(layer "F.CrtYd")
		)
		(fp_line
			(start -0.2794 -0.1016)
			(end -0.2794 0.9906)
			(stroke
				(width 0.1)
				(type default)
			)
			(layer "F.Fab")
		)
		(fp_line
			(start -0.2794 0.9906)
			(end 0.2794 0.9906)
			(stroke
				(width 0.1)
				(type default)
			)
			(layer "F.Fab")
		)
		(fp_line
			(start 0.2794 -0.1016)
			(end -0.2794 -0.1016)
			(stroke
				(width 0.1)
				(type default)
			)
			(layer "F.Fab")
		)
		(fp_line
			(start 0.2794 0.9906)
			(end 0.2794 -0.1016)
			(stroke
				(width 0.1)
				(type default)
			)
			(layer "F.Fab")
		)
		(pad "1" smd rect
			(at 0 0)
			(size 0.508 0.508)
			(layers "F.Cu" "F.Mask" "F.Paste")
			(net "P3V3_STBY")
		)
		(pad "2" smd rect
			(at 0 0.889)
			(size 0.508 0.508)
			(layers "F.Cu" "F.Mask" "F.Paste")
			(net "PU_DEV_OFF_N")
		)
		(zone
			(layer "F.Cu")
			(hatch none 0.5)
			(connect_pads
				(clearance 0)
			)
			(min_thickness 0.25)
			(keepout
				(tracks allowed)
				(vias not_allowed)
				(pads allowed)
				(copperpour not_allowed)
				(footprints allowed)
			)
			(placement
				(enabled no)
				(sheetname "")
			)
			(fill
				(thermal_gap 0.5)
				(thermal_bridge_width 0.5)
				(island_removal_mode 0)
			)
			(polygon
				(pts
					(xy 481.77704 -51.10734) (xy 482.28504 -51.10734) (xy 482.28504 -50.72634) (xy 481.77704 -50.72634)
				)
			)
		)
		(zone
			(layer "F.Cu")
			(hatch none 0.5)
			(connect_pads
				(clearance 0)
			)
			(min_thickness 0.25)
			(keepout
				(tracks not_allowed)
				(vias allowed)
				(pads allowed)
				(copperpour not_allowed)
				(footprints allowed)
			)
			(placement
				(enabled no)
				(sheetname "")
			)
			(fill
				(thermal_gap 0.5)
				(thermal_bridge_width 0.5)
				(island_removal_mode 0)
			)
			(polygon
				(pts
					(xy 481.77704 -50.72634) (xy 482.28504 -50.72634) (xy 482.28504 -51.10734) (xy 481.77704 -51.10734)
				)
			)
		)
	)
	(footprint ""
		(layer "F.Cu")
		(at 317.9826 -28.934918 90)
		(property "Reference" "R6F9"
			(at 0 0 90)
			(layer "F.SilkS")
			(hide yes)
			(effects
				(font
					(size 1.27 1.27)
				)
			)
		)
		(property "Value" ""
			(at 0 0 90)
			(layer "F.Fab")
			(effects
				(font
					(size 1.27 1.27)
				)
			)
		)
		(duplicate_pad_numbers_are_jumpers no)
		(fp_poly
			(pts
				(xy -0.2794 -0.1016) (xy 0.2794 -0.1016) (xy 0.2794 0.9906) (xy -0.2794 0.9906)
			)
			(stroke
				(width 0)
				(type default)
			)
			(fill no)
			(layer "F.CrtYd")
		)
		(fp_line
			(start 0.2794 -0.1016)
			(end -0.2794 -0.1016)
			(stroke
				(width 0.1)
				(type default)
			)
			(layer "F.Fab")
		)
		(fp_line
			(start -0.2794 -0.1016)
			(end -0.2794 0.9906)
			(stroke
				(width 0.1)
				(type default)
			)
			(layer "F.Fab")
		)
		(fp_line
			(start 0.2794 0.9906)
			(end 0.2794 -0.1016)
			(stroke
				(width 0.1)
				(type default)
			)
			(layer "F.Fab")
		)
		(fp_line
			(start -0.2794 0.9906)
			(end 0.2794 0.9906)
			(stroke
				(width 0.1)
				(type default)
			)
			(layer "F.Fab")
		)
		(pad "1" smd rect
			(at 0 0 90)
			(size 0.508 0.508)
			(layers "F.Cu" "F.Mask" "F.Paste")
			(net "CLK_156M_OSC_BRD_CPU0_DP")
		)
		(pad "2" smd rect
			(at 0 0.889 90)
			(size 0.508 0.508)
			(layers "F.Cu" "F.Mask" "F.Paste")
			(net "CLK_156M_OSC_CPU0_HFI_DP")
		)
		(zone
			(layer "F.Cu")
			(hatch none 0.5)
			(connect_pads
				(clearance 0)
			)
			(min_thickness 0.25)
			(keepout
				(tracks allowed)
				(vias not_allowed)
				(pads allowed)
				(copperpour not_allowed)
				(footprints allowed)
			)
			(placement
				(enabled no)
				(sheetname "")
			)
			(fill
				(thermal_gap 0.5)
				(thermal_bridge_width 0.5)
				(island_removal_mode 0)
			)
			(polygon
				(pts
					(xy 318.2366 -28.680918) (xy 318.2366 -29.188918) (xy 318.6176 -29.188918) (xy 318.6176 -28.680918)
				)
			)
		)
		(zone
			(layer "F.Cu")
			(hatch none 0.5)
			(connect_pads
				(clearance 0)
			)
			(min_thickness 0.25)
			(keepout
				(tracks not_allowed)
				(vias allowed)
				(pads allowed)
				(copperpour not_allowed)
				(footprints allowed)
			)
			(placement
				(enabled no)
				(sheetname "")
			)
			(fill
				(thermal_gap 0.5)
				(thermal_bridge_width 0.5)
				(island_removal_mode 0)
			)
			(polygon
				(pts
					(xy 318.6176 -28.680918) (xy 318.6176 -29.188918) (xy 318.2366 -29.188918) (xy 318.2366 -28.680918)
				)
			)
		)
	)
	(footprint ""
		(layer "F.Cu")
		(at 274.438872 -73.318116)
		(property "Reference" "C5D49"
			(at 0 0 0)
			(layer "F.SilkS")
			(hide yes)
			(effects
				(font
					(size 1.27 1.27)
				)
			)
		)
		(property "Value" ""
			(at 0 0 0)
			(layer "F.Fab")
			(effects
				(font
					(size 1.27 1.27)
				)
			)
		)
		(duplicate_pad_numbers_are_jumpers no)
		(fp_poly
			(pts
				(xy -0.4953 -0.2032) (xy 0.4953 -0.2032) (xy 0.4953 1.6002) (xy -0.4953 1.6002)
			)
			(stroke
				(width 0)
				(type default)
			)
			(fill no)
			(layer "F.CrtYd")
		)
		(fp_line
			(start -0.4953 -0.2032)
			(end 0.4953 -0.2032)
			(stroke
				(width 0.1)
				(type default)
			)
			(layer "F.Fab")
		)
		(fp_line
			(start -0.4953 1.6002)
			(end -0.4953 -0.2032)
			(stroke
				(width 0.1)
				(type default)
			)
			(layer "F.Fab")
		)
		(fp_line
			(start 0.4953 -0.2032)
			(end 0.4953 1.6002)
			(stroke
				(width 0.1)
				(type default)
			)
			(layer "F.Fab")
		)
		(fp_line
			(start 0.4953 1.6002)
			(end -0.4953 1.6002)
			(stroke
				(width 0.1)
				(type default)
			)
			(layer "F.Fab")
		)
		(pad "1" smd rect
			(at 0 0)
			(size 0.762 0.889)
			(layers "F.Cu" "F.Mask" "F.Paste")
			(net "PVCCMCP_CPU0")
		)
		(pad "2" smd rect
			(at 0 1.397)
			(size 0.762 0.889)
			(layers "F.Cu" "F.Mask" "F.Paste")
			(net "GND")
		)
		(zone
			(layer "F.Cu")
			(hatch none 0.5)
			(connect_pads
				(clearance 0)
			)
			(min_thickness 0.25)
			(keepout
				(tracks not_allowed)
				(vias allowed)
				(pads allowed)
				(copperpour not_allowed)
				(footprints allowed)
			)
			(placement
				(enabled no)
				(sheetname "")
			)
			(fill
				(thermal_gap 0.5)
				(thermal_bridge_width 0.5)
				(island_removal_mode 0)
			)
			(polygon
				(pts
					(xy 274.057872 -72.873616) (xy 274.819872 -72.873616) (xy 274.819872 -72.365616) (xy 274.057872 -72.365616)
				)
			)
		)
	)
	(footprint ""
		(layer "F.Cu")
		(at -3.739388 -114.954812 90)
		(property "Reference" "CR10W3"
			(at 1.06934 -0.39116 0)
			(unlocked yes)
			(layer "F.SilkS")
			(effects
				(font
					(size 0.4064 0.254)
					(thickness 0.1524)
				)
				(justify left)
			)
		)
		(property "Value" ""
			(at 0 0 90)
			(layer "F.Fab")
			(effects
				(font
					(size 1.27 1.27)
				)
			)
		)
		(duplicate_pad_numbers_are_jumpers no)
		(fp_line
			(start 0.819404 -0.070866)
			(end 0.819404 1.052576)
			(stroke
				(width 0.1524)
				(type default)
			)
			(layer "F.SilkS")
		)
		(fp_line
			(start 1.300226 1.052576)
			(end 0.338582 1.052576)
			(stroke
				(width 0.1524)
				(type default)
			)
			(layer "F.SilkS")
		)
		(fp_line
			(start 0.819404 1.052576)
			(end 1.300226 1.885442)
			(stroke
				(width 0.1524)
				(type default)
			)
			(layer "F.SilkS")
		)
		(fp_line
			(start 1.300226 1.885442)
			(end 0.819404 1.885442)
			(stroke
				(width 0.1524)
				(type default)
			)
			(layer "F.SilkS")
		)
		(fp_line
			(start 0.819404 1.885442)
			(end 0.338582 1.885442)
			(stroke
				(width 0.1524)
				(type default)
			)
			(layer "F.SilkS")
		)
		(fp_line
			(start 0.338582 1.885442)
			(end 0.819404 1.052576)
			(stroke
				(width 0.1524)
				(type default)
			)
			(layer "F.SilkS")
		)
		(fp_line
			(start 0.819404 2.797048)
			(end 0.819404 1.885442)
			(stroke
				(width 0.1524)
				(type default)
			)
			(layer "F.SilkS")
		)
		(fp_poly
			(pts
				(xy -0.67437 0.24384) (xy -0.67437 2.04216) (xy 0.67437 2.04216) (xy 0.67437 0.24384)
			)
			(stroke
				(width 0)
				(type default)
			)
			(fill no)
			(layer "F.CrtYd")
		)
		(fp_line
			(start 0.67437 0.24384)
			(end -0.67437 0.24384)
			(stroke
				(width 0.1)
				(type default)
			)
			(layer "F.Fab")
		)
		(fp_line
			(start -0.67437 0.24384)
			(end -0.67437 2.04216)
			(stroke
				(width 0.1)
				(type default)
			)
			(layer "F.Fab")
		)
		(fp_line
			(start -0.854456 0.831596)
			(end -1.8161 0.831596)
			(stroke
				(width 0.1)
				(type default)
			)
			(layer "F.Fab")
		)
		(fp_line
			(start -1.335278 0.831596)
			(end -1.335278 -0.291846)
			(stroke
				(width 0.1)
				(type default)
			)
			(layer "F.Fab")
		)
		(fp_line
			(start -1.335278 0.831596)
			(end -0.854456 1.664462)
			(stroke
				(width 0.1)
				(type default)
			)
			(layer "F.Fab")
		)
		(fp_line
			(start -0.854456 1.664462)
			(end -1.8161 1.664462)
			(stroke
				(width 0.1)
				(type default)
			)
			(layer "F.Fab")
		)
		(fp_line
			(start -1.335278 1.664462)
			(end -1.335278 2.576068)
			(stroke
				(width 0.1)
				(type default)
			)
			(layer "F.Fab")
		)
		(fp_line
			(start -1.8161 1.664462)
			(end -1.335278 0.831596)
			(stroke
				(width 0.1)
				(type default)
			)
			(layer "F.Fab")
		)
		(fp_line
			(start 0.67437 2.04216)
			(end 0.67437 0.24384)
			(stroke
				(width 0.1)
				(type default)
			)
			(layer "F.Fab")
		)
		(fp_line
			(start -0.67437 2.04216)
			(end 0.67437 2.04216)
			(stroke
				(width 0.1)
				(type default)
			)
			(layer "F.Fab")
		)
		(pad "1" smd rect
			(at 0 0 90)
			(size 0.4064 1.016)
			(layers "F.Cu" "F.Mask" "F.Paste")
			(net "PUMP_TACH1_D")
		)
		(pad "2" smd rect
			(at 0 2.286 90)
			(size 0.4064 1.016)
			(layers "F.Cu" "F.Mask" "F.Paste")
			(net "PUMP_TACH1_R")
		)
	)
	(footprint ""
		(layer "F.Cu")
		(at 349.123 -13.843 90)
		(property "Reference" "C7G3"
			(at 0 0 90)
			(layer "F.SilkS")
			(hide yes)
			(effects
				(font
					(size 1.27 1.27)
				)
			)
		)
		(property "Value" ""
			(at 0 0 90)
			(layer "F.Fab")
			(effects
				(font
					(size 1.27 1.27)
				)
			)
		)
		(duplicate_pad_numbers_are_jumpers no)
		(fp_rect
			(start -0.3048 -0.1016)
			(end 0.3048 0.9906)
			(stroke
				(width 0)
				(type default)
			)
			(fill no)
			(layer "F.CrtYd")
		)
		(fp_line
			(start 0.3048 -0.1016)
			(end -0.3048 -0.1016)
			(stroke
				(width 0.1)
				(type default)
			)
			(layer "F.Fab")
		)
		(fp_line
			(start -0.3048 -0.1016)
			(end -0.3048 0.9906)
			(stroke
				(width 0.1)
				(type default)
			)
			(layer "F.Fab")
		)
		(fp_line
			(start 0.3048 0.9906)
			(end 0.3048 -0.1016)
			(stroke
				(width 0.1)
				(type default)
			)
			(layer "F.Fab")
		)
		(fp_line
			(start -0.3048 0.9906)
			(end 0.3048 0.9906)
			(stroke
				(width 0.1)
				(type default)
			)
			(layer "F.Fab")
		)
		(pad "1" smd rect
			(at 0 0 90)
			(size 0.508 0.508)
			(layers "F.Cu" "F.Mask" "F.Paste")
			(net "A_TSENSE_PVDDQ_ABC")
		)
		(pad "2" smd rect
			(at 0 0.889 90)
			(size 0.508 0.508)
			(layers "F.Cu" "F.Mask" "F.Paste")
			(net "GND")
		)
		(zone
			(layer "F.Cu")
			(hatch none 0.5)
			(connect_pads
				(clearance 0)
			)
			(min_thickness 0.25)
			(keepout
				(tracks not_allowed)
				(vias allowed)
				(pads allowed)
				(copperpour not_allowed)
				(footprints allowed)
			)
			(placement
				(enabled no)
				(sheetname "")
			)
			(fill
				(thermal_gap 0.5)
				(thermal_bridge_width 0.5)
				(island_removal_mode 0)
			)
			(polygon
				(pts
					(xy 349.377 -13.589) (xy 349.758 -13.589) (xy 349.758 -14.097) (xy 349.377 -14.097)
				)
			)
		)
		(zone
			(layer "F.Cu")
			(hatch none 0.5)
			(connect_pads
				(clearance 0)
			)
			(min_thickness 0.25)
			(keepout
				(tracks allowed)
				(vias not_allowed)
				(pads allowed)
				(copperpour not_allowed)
				(footprints allowed)
			)
			(placement
				(enabled no)
				(sheetname "")
			)
			(fill
				(thermal_gap 0.5)
				(thermal_bridge_width 0.5)
				(island_removal_mode 0)
			)
			(polygon
				(pts
					(xy 349.377 -13.589) (xy 349.758 -13.589) (xy 349.758 -14.097) (xy 349.377 -14.097)
				)
			)
		)
	)
	(footprint ""
		(layer "F.Cu")
		(at 429.54448 -14.605 180)
		(property "Reference" "U6W11"
			(at 0 0 180)
			(layer "F.SilkS")
			(hide yes)
			(effects
				(font
					(size 1.27 1.27)
				)
			)
		)
		(property "Value" "*"
			(at 0.127 -12.51585 180)
			(unlocked yes)
			(layer "F.Fab")
			(hide yes)
			(effects
				(font
					(size 0.889 0.889)
					(thickness 0.1524)
				)
			)
		)
		(property "Device Type" "PCA9554PWR-GP_DISCRET-G1-PCA95A"
			(at 0.1016 -14.52245 180)
			(unlocked yes)
			(layer "F.Fab")
			(hide yes)
			(effects
				(font
					(size 0.889 0.889)
					(thickness 0.1524)
				)
			)
		)
		(duplicate_pad_numbers_are_jumpers no)
		(fp_line
			(start 2.3622 1.778)
			(end -2.921 1.778)
			(stroke
				(width 0.1524)
				(type default)
			)
			(layer "F.SilkS")
		)
		(fp_line
			(start 2.3622 -1.778)
			(end 2.3622 1.778)
			(stroke
				(width 0.1524)
				(type default)
			)
			(layer "F.SilkS")
		)
		(fp_line
			(start -2.54 0)
			(end -3.0988 0.5588)
			(stroke
				(width 0.1524)
				(type default)
			)
			(layer "F.SilkS")
		)
		(fp_line
			(start -2.54 0)
			(end -3.0988 -0.5588)
			(stroke
				(width 0.1524)
				(type default)
			)
			(layer "F.SilkS")
		)
		(fp_line
			(start -2.921 3.81)
			(end -2.921 1.778)
			(stroke
				(width 0.508)
				(type default)
			)
			(layer "F.SilkS")
		)
		(fp_line
			(start -3.0988 -1.778)
			(end 2.3622 -1.778)
			(stroke
				(width 0.1524)
				(type default)
			)
			(layer "F.SilkS")
		)
		(fp_line
			(start -3.0988 -1.778)
			(end -3.0988 1.778)
			(stroke
				(width 0.1524)
				(type default)
			)
			(layer "F.SilkS")
		)
		(fp_poly
			(pts
				(xy -2.4638 -1.778) (xy -2.4638 1.778) (xy 2.3622 1.778) (xy 2.3622 -1.778)
			)
			(stroke
				(width 0)
				(type default)
			)
			(fill yes)
			(layer "F.SilkS")
		)
		(fp_rect
			(start -3.175 4.064)
			(end 3.175 -4.064)
			(stroke
				(width 0)
				(type default)
			)
			(fill no)
			(layer "F.CrtYd")
		)
		(fp_poly
			(pts
				(xy -3.175 -4.064) (xy 3.175 -4.064) (xy 3.175 4.064) (xy -3.175 4.064)
			)
			(stroke
				(width 0)
				(type default)
			)
			(fill no)
			(layer "F.Fab")
		)
		(pad "1" smd rect
			(at -2.27584 2.8194 180)
			(size 0.3556 1.524)
			(layers "F.Cu" "F.Mask" "F.Paste")
			(net "PCA9554_A0")
		)
		(pad "2" smd rect
			(at -1.6256 2.8194 180)
			(size 0.3556 1.524)
			(layers "F.Cu" "F.Mask" "F.Paste")
			(net "PCA9554_A1")
		)
		(pad "3" smd rect
			(at -0.97536 2.8194 180)
			(size 0.3556 1.524)
			(layers "F.Cu" "F.Mask" "F.Paste")
			(net "PCA9554_A2")
		)
		(pad "4" smd rect
			(at -0.32512 2.8194 180)
			(size 0.3556 1.524)
			(layers "F.Cu" "F.Mask" "F.Paste")
			(net "FM_MB_SLOT_ID0")
		)
		(pad "5" smd rect
			(at 0.32512 2.8194 180)
			(size 0.3556 1.524)
			(layers "F.Cu" "F.Mask" "F.Paste")
			(net "FM_MB_SLOT_ID1")
		)
		(pad "6" smd rect
			(at 0.97536 2.8194 180)
			(size 0.3556 1.524)
			(layers "F.Cu" "F.Mask" "F.Paste")
			(net "FM_MB_SLOT_ID2")
		)
		(pad "7" smd rect
			(at 1.6256 2.8194 180)
			(size 0.3556 1.524)
			(layers "F.Cu" "F.Mask" "F.Paste")
			(net "FM_CPU_BMC_INIT")
		)
		(pad "8" smd rect
			(at 2.27584 2.8194 180)
			(size 0.3556 1.524)
			(layers "F.Cu" "F.Mask" "F.Paste")
			(net "GND")
		)
		(pad "9" smd rect
			(at 2.27584 -2.8194 180)
			(size 0.3556 1.524)
			(layers "F.Cu" "F.Mask" "F.Paste")
			(net "Net_6513")
		)
		(pad "10" smd rect
			(at 1.6256 -2.8194 180)
			(size 0.3556 1.524)
			(layers "F.Cu" "F.Mask" "F.Paste")
			(net "Net_6512")
		)
		(pad "11" smd rect
			(at 0.97536 -2.8194 180)
			(size 0.3556 1.524)
			(layers "F.Cu" "F.Mask" "F.Paste")
			(net "Net_6511")
		)
		(pad "12" smd rect
			(at 0.32512 -2.8194 180)
			(size 0.3556 1.524)
			(layers "F.Cu" "F.Mask" "F.Paste")
			(net "Net_6510")
		)
		(pad "13" smd rect
			(at -0.32512 -2.8194 180)
			(size 0.3556 1.524)
			(layers "F.Cu" "F.Mask" "F.Paste")
			(net "PCA9554_INT_N")
		)
		(pad "14" smd rect
			(at -0.97536 -2.8194 180)
			(size 0.3556 1.524)
			(layers "F.Cu" "F.Mask" "F.Paste")
			(net "SMB_SENSOR_STBY_LVC3_SCL")
		)
		(pad "15" smd rect
			(at -1.6256 -2.8194 180)
			(size 0.3556 1.524)
			(layers "F.Cu" "F.Mask" "F.Paste")
			(net "SMB_SENSOR_STBY_LVC3_SDA")
		)
		(pad "16" smd rect
			(at -2.27584 -2.8194 180)
			(size 0.3556 1.524)
			(layers "F.Cu" "F.Mask" "F.Paste")
			(net "P3V3_STBY")
		)
	)
	(footprint ""
		(layer "F.Cu")
		(at 320.194432 -149.86 90)
		(property "Reference" "C6A3"
			(at 0 0 90)
			(layer "F.SilkS")
			(hide yes)
			(effects
				(font
					(size 1.27 1.27)
				)
			)
		)
		(property "Value" ""
			(at 0 0 90)
			(layer "F.Fab")
			(effects
				(font
					(size 1.27 1.27)
				)
			)
		)
		(duplicate_pad_numbers_are_jumpers no)
		(fp_poly
			(pts
				(xy -0.4953 -0.2032) (xy 0.4953 -0.2032) (xy 0.4953 1.6002) (xy -0.4953 1.6002)
			)
			(stroke
				(width 0)
				(type default)
			)
			(fill no)
			(layer "F.CrtYd")
		)
		(fp_line
			(start 0.4953 -0.2032)
			(end 0.4953 1.6002)
			(stroke
				(width 0.1)
				(type default)
			)
			(layer "F.Fab")
		)
		(fp_line
			(start -0.4953 -0.2032)
			(end 0.4953 -0.2032)
			(stroke
				(width 0.1)
				(type default)
			)
			(layer "F.Fab")
		)
		(fp_line
			(start 0.4953 1.6002)
			(end -0.4953 1.6002)
			(stroke
				(width 0.1)
				(type default)
			)
			(layer "F.Fab")
		)
		(fp_line
			(start -0.4953 1.6002)
			(end -0.4953 -0.2032)
			(stroke
				(width 0.1)
				(type default)
			)
			(layer "F.Fab")
		)
		(pad "1" smd rect
			(at 0 0 90)
			(size 0.762 0.889)
			(layers "F.Cu" "F.Mask" "F.Paste")
			(net "PVPP_DEF")
		)
		(pad "2" smd rect
			(at 0 1.397 90)
			(size 0.762 0.889)
			(layers "F.Cu" "F.Mask" "F.Paste")
			(net "GND")
		)
		(zone
			(layer "F.Cu")
			(hatch none 0.5)
			(connect_pads
				(clearance 0)
			)
			(min_thickness 0.25)
			(keepout
				(tracks not_allowed)
				(vias allowed)
				(pads allowed)
				(copperpour not_allowed)
				(footprints allowed)
			)
			(placement
				(enabled no)
				(sheetname "")
			)
			(fill
				(thermal_gap 0.5)
				(thermal_bridge_width 0.5)
				(island_removal_mode 0)
			)
			(polygon
				(pts
					(xy 320.638932 -149.479) (xy 320.638932 -150.241) (xy 321.146932 -150.241) (xy 321.146932 -149.479)
				)
			)
		)
	)
	(footprint ""
		(layer "F.Cu")
		(at 278.070056 -69.969888)
		(property "Reference" "R6D14"
			(at 0 0 0)
			(layer "F.SilkS")
			(hide yes)
			(effects
				(font
					(size 1.27 1.27)
				)
			)
		)
		(property "Value" ""
			(at 0 0 0)
			(layer "F.Fab")
			(effects
				(font
					(size 1.27 1.27)
				)
			)
		)
		(duplicate_pad_numbers_are_jumpers no)
		(fp_poly
			(pts
				(xy -0.2794 -0.1016) (xy 0.2794 -0.1016) (xy 0.2794 0.9906) (xy -0.2794 0.9906)
			)
			(stroke
				(width 0)
				(type default)
			)
			(fill no)
			(layer "F.CrtYd")
		)
		(fp_line
			(start -0.2794 -0.1016)
			(end -0.2794 0.9906)
			(stroke
				(width 0.1)
				(type default)
			)
			(layer "F.Fab")
		)
		(fp_line
			(start -0.2794 0.9906)
			(end 0.2794 0.9906)
			(stroke
				(width 0.1)
				(type default)
			)
			(layer "F.Fab")
		)
		(fp_line
			(start 0.2794 -0.1016)
			(end -0.2794 -0.1016)
			(stroke
				(width 0.1)
				(type default)
			)
			(layer "F.Fab")
		)
		(fp_line
			(start 0.2794 0.9906)
			(end 0.2794 -0.1016)
			(stroke
				(width 0.1)
				(type default)
			)
			(layer "F.Fab")
		)
		(pad "1" smd rect
			(at 0 0)
			(size 0.508 0.508)
			(layers "F.Cu" "F.Mask" "F.Paste")
			(net "GND")
		)
		(pad "2" smd rect
			(at 0 0.889)
			(size 0.508 0.508)
			(layers "F.Cu" "F.Mask" "F.Paste")
			(net "PD_CPU0_EAR_N")
		)
		(zone
			(layer "F.Cu")
			(hatch none 0.5)
			(connect_pads
				(clearance 0)
			)
			(min_thickness 0.25)
			(keepout
				(tracks allowed)
				(vias not_allowed)
				(pads allowed)
				(copperpour not_allowed)
				(footprints allowed)
			)
			(placement
				(enabled no)
				(sheetname "")
			)
			(fill
				(thermal_gap 0.5)
				(thermal_bridge_width 0.5)
				(island_removal_mode 0)
			)
			(polygon
				(pts
					(xy 277.816056 -69.715888) (xy 278.324056 -69.715888) (xy 278.324056 -69.334888) (xy 277.816056 -69.334888)
				)
			)
		)
		(zone
			(layer "F.Cu")
			(hatch none 0.5)
			(connect_pads
				(clearance 0)
			)
			(min_thickness 0.25)
			(keepout
				(tracks not_allowed)
				(vias allowed)
				(pads allowed)
				(copperpour not_allowed)
				(footprints allowed)
			)
			(placement
				(enabled no)
				(sheetname "")
			)
			(fill
				(thermal_gap 0.5)
				(thermal_bridge_width 0.5)
				(island_removal_mode 0)
			)
			(polygon
				(pts
					(xy 277.816056 -69.334888) (xy 278.324056 -69.334888) (xy 278.324056 -69.715888) (xy 277.816056 -69.715888)
				)
			)
		)
	)
	(footprint ""
		(layer "F.Cu")
		(at 411.48 -87.8205 180)
		(property "Reference" "C2R6"
			(at 0 0 180)
			(layer "F.SilkS")
			(hide yes)
			(effects
				(font
					(size 1.27 1.27)
				)
			)
		)
		(property "Value" ""
			(at 0 0 180)
			(layer "F.Fab")
			(effects
				(font
					(size 1.27 1.27)
				)
			)
		)
		(duplicate_pad_numbers_are_jumpers no)
		(fp_poly
			(pts
				(xy 0.3048 -0.1016) (xy 0.3048 0.9906) (xy -0.3048 0.9906) (xy -0.3048 -0.1016)
			)
			(stroke
				(width 0)
				(type default)
			)
			(fill no)
			(layer "F.CrtYd")
		)
		(fp_line
			(start 0.3048 0.9906)
			(end 0.3048 -0.1016)
			(stroke
				(width 0.1)
				(type default)
			)
			(layer "F.Fab")
		)
		(fp_line
			(start 0.3048 -0.1016)
			(end -0.3048 -0.1016)
			(stroke
				(width 0.1)
				(type default)
			)
			(layer "F.Fab")
		)
		(fp_line
			(start -0.3048 0.9906)
			(end 0.3048 0.9906)
			(stroke
				(width 0.1)
				(type default)
			)
			(layer "F.Fab")
		)
		(fp_line
			(start -0.3048 -0.1016)
			(end -0.3048 0.9906)
			(stroke
				(width 0.1)
				(type default)
			)
			(layer "F.Fab")
		)
		(pad "1" smd rect
			(at 0 0 180)
			(size 0.508 0.508)
			(layers "F.Cu" "F.Mask" "F.Paste")
			(net "FM_PS_EN")
		)
		(pad "2" smd rect
			(at 0 0.889 180)
			(size 0.508 0.508)
			(layers "F.Cu" "F.Mask" "F.Paste")
			(net "GND")
		)
		(zone
			(layer "F.Cu")
			(hatch none 0.5)
			(connect_pads
				(clearance 0)
			)
			(min_thickness 0.25)
			(keepout
				(tracks not_allowed)
				(vias allowed)
				(pads allowed)
				(copperpour not_allowed)
				(footprints allowed)
			)
			(placement
				(enabled no)
				(sheetname "")
			)
			(fill
				(thermal_gap 0.5)
				(thermal_bridge_width 0.5)
				(island_removal_mode 0)
			)
			(polygon
				(pts
					(xy 411.734 -88.4555) (xy 411.226 -88.4555) (xy 411.226 -88.0745) (xy 411.734 -88.0745)
				)
			)
		)
		(zone
			(layer "F.Cu")
			(hatch none 0.5)
			(connect_pads
				(clearance 0)
			)
			(min_thickness 0.25)
			(keepout
				(tracks allowed)
				(vias not_allowed)
				(pads allowed)
				(copperpour not_allowed)
				(footprints allowed)
			)
			(placement
				(enabled no)
				(sheetname "")
			)
			(fill
				(thermal_gap 0.5)
				(thermal_bridge_width 0.5)
				(island_removal_mode 0)
			)
			(polygon
				(pts
					(xy 411.734 -88.0745) (xy 411.226 -88.0745) (xy 411.226 -88.4555) (xy 411.734 -88.4555)
				)
			)
		)
	)
	(footprint ""
		(layer "F.Cu")
		(at 486.687876 -27.227784 180)
		(property "Reference" "R9F69"
			(at 0 0 180)
			(layer "F.SilkS")
			(hide yes)
			(effects
				(font
					(size 1.27 1.27)
				)
			)
		)
		(property "Value" ""
			(at 0 0 180)
			(layer "F.Fab")
			(effects
				(font
					(size 1.27 1.27)
				)
			)
		)
		(duplicate_pad_numbers_are_jumpers no)
		(fp_poly
			(pts
				(xy -0.2794 -0.1016) (xy 0.2794 -0.1016) (xy 0.2794 0.9906) (xy -0.2794 0.9906)
			)
			(stroke
				(width 0)
				(type default)
			)
			(fill no)
			(layer "F.CrtYd")
		)
		(fp_line
			(start 0.2794 0.9906)
			(end 0.2794 -0.1016)
			(stroke
				(width 0.1)
				(type default)
			)
			(layer "F.Fab")
		)
		(fp_line
			(start 0.2794 -0.1016)
			(end -0.2794 -0.1016)
			(stroke
				(width 0.1)
				(type default)
			)
			(layer "F.Fab")
		)
		(fp_line
			(start -0.2794 0.9906)
			(end 0.2794 0.9906)
			(stroke
				(width 0.1)
				(type default)
			)
			(layer "F.Fab")
		)
		(fp_line
			(start -0.2794 -0.1016)
			(end -0.2794 0.9906)
			(stroke
				(width 0.1)
				(type default)
			)
			(layer "F.Fab")
		)
		(pad "1" smd rect
			(at 0 0 180)
			(size 0.508 0.508)
			(layers "F.Cu" "F.Mask" "F.Paste")
			(net "SP2_BMC_CM_UART_RX_R")
		)
		(pad "2" smd rect
			(at 0 0.889 180)
			(size 0.508 0.508)
			(layers "F.Cu" "F.Mask" "F.Paste")
			(net "SP2_BMC_CM_UART_RX_R1")
		)
		(zone
			(layer "F.Cu")
			(hatch none 0.5)
			(connect_pads
				(clearance 0)
			)
			(min_thickness 0.25)
			(keepout
				(tracks not_allowed)
				(vias allowed)
				(pads allowed)
				(copperpour not_allowed)
				(footprints allowed)
			)
			(placement
				(enabled no)
				(sheetname "")
			)
			(fill
				(thermal_gap 0.5)
				(thermal_bridge_width 0.5)
				(island_removal_mode 0)
			)
			(polygon
				(pts
					(xy 486.941876 -27.862784) (xy 486.433876 -27.862784) (xy 486.433876 -27.481784) (xy 486.941876 -27.481784)
				)
			)
		)
		(zone
			(layer "F.Cu")
			(hatch none 0.5)
			(connect_pads
				(clearance 0)
			)
			(min_thickness 0.25)
			(keepout
				(tracks allowed)
				(vias not_allowed)
				(pads allowed)
				(copperpour not_allowed)
				(footprints allowed)
			)
			(placement
				(enabled no)
				(sheetname "")
			)
			(fill
				(thermal_gap 0.5)
				(thermal_bridge_width 0.5)
				(island_removal_mode 0)
			)
			(polygon
				(pts
					(xy 486.941876 -27.481784) (xy 486.433876 -27.481784) (xy 486.433876 -27.862784) (xy 486.941876 -27.862784)
				)
			)
		)
	)
	(footprint ""
		(layer "F.Cu")
		(at 168.6941 -8.763 90)
		(property "Reference" "R4G7"
			(at 0 0 90)
			(layer "F.SilkS")
			(hide yes)
			(effects
				(font
					(size 1.27 1.27)
				)
			)
		)
		(property "Value" ""
			(at 0 0 90)
			(layer "F.Fab")
			(effects
				(font
					(size 1.27 1.27)
				)
			)
		)
		(duplicate_pad_numbers_are_jumpers no)
		(fp_rect
			(start -0.2794 -0.1016)
			(end 0.2794 0.9906)
			(stroke
				(width 0)
				(type default)
			)
			(fill no)
			(layer "F.CrtYd")
		)
		(fp_line
			(start 0.2794 -0.1016)
			(end -0.2794 -0.1016)
			(stroke
				(width 0.1)
				(type default)
			)
			(layer "F.Fab")
		)
		(fp_line
			(start -0.2794 -0.1016)
			(end -0.2794 0.9906)
			(stroke
				(width 0.1)
				(type default)
			)
			(layer "F.Fab")
		)
		(fp_line
			(start 0.2794 0.9906)
			(end 0.2794 -0.1016)
			(stroke
				(width 0.1)
				(type default)
			)
			(layer "F.Fab")
		)
		(fp_line
			(start -0.2794 0.9906)
			(end 0.2794 0.9906)
			(stroke
				(width 0.1)
				(type default)
			)
			(layer "F.Fab")
		)
		(pad "1" smd rect
			(at 0 0 90)
			(size 0.508 0.508)
			(layers "F.Cu" "F.Mask" "F.Paste")
			(net "VSENSE_PVPP_GHJ")
		)
		(pad "2" smd rect
			(at 0 0.889 90)
			(size 0.508 0.508)
			(layers "F.Cu" "F.Mask" "F.Paste")
			(net "VR_FB_PVPP_GHJ")
		)
		(zone
			(layer "F.Cu")
			(hatch none 0.5)
			(connect_pads
				(clearance 0)
			)
			(min_thickness 0.25)
			(keepout
				(tracks not_allowed)
				(vias allowed)
				(pads allowed)
				(copperpour not_allowed)
				(footprints allowed)
			)
			(placement
				(enabled no)
				(sheetname "")
			)
			(fill
				(thermal_gap 0.5)
				(thermal_bridge_width 0.5)
				(island_removal_mode 0)
			)
			(polygon
				(pts
					(xy 168.9481 -8.509) (xy 169.3291 -8.509) (xy 169.3291 -9.017) (xy 168.9481 -9.017)
				)
			)
		)
		(zone
			(layer "F.Cu")
			(hatch none 0.5)
			(connect_pads
				(clearance 0)
			)
			(min_thickness 0.25)
			(keepout
				(tracks allowed)
				(vias not_allowed)
				(pads allowed)
				(copperpour not_allowed)
				(footprints allowed)
			)
			(placement
				(enabled no)
				(sheetname "")
			)
			(fill
				(thermal_gap 0.5)
				(thermal_bridge_width 0.5)
				(island_removal_mode 0)
			)
			(polygon
				(pts
					(xy 168.9481 -8.509) (xy 169.3291 -8.509) (xy 169.3291 -9.017) (xy 168.9481 -9.017)
				)
			)
		)
	)
	(footprint ""
		(layer "F.Cu")
		(at 188.500512 -67.920108 180)
		(property "Reference" "RF3"
			(at -0.8382 -0.67818 180)
			(unlocked yes)
			(layer "F.SilkS")
			(effects
				(font
					(size 0.4064 0.254)
					(thickness 0.1524)
				)
				(justify left)
			)
		)
		(property "Value" ""
			(at 0 0 180)
			(layer "F.Fab")
			(effects
				(font
					(size 1.27 1.27)
				)
			)
		)
		(duplicate_pad_numbers_are_jumpers no)
		(fp_poly
			(pts
				(xy -0.2794 -0.1016) (xy 0.2794 -0.1016) (xy 0.2794 0.9906) (xy -0.2794 0.9906)
			)
			(stroke
				(width 0)
				(type default)
			)
			(fill no)
			(layer "F.CrtYd")
		)
		(fp_line
			(start 0.2794 0.9906)
			(end 0.2794 -0.1016)
			(stroke
				(width 0.1)
				(type default)
			)
			(layer "F.Fab")
		)
		(fp_line
			(start 0.2794 -0.1016)
			(end -0.2794 -0.1016)
			(stroke
				(width 0.1)
				(type default)
			)
			(layer "F.Fab")
		)
		(fp_line
			(start -0.2794 0.9906)
			(end 0.2794 0.9906)
			(stroke
				(width 0.1)
				(type default)
			)
			(layer "F.Fab")
		)
		(fp_line
			(start -0.2794 -0.1016)
			(end -0.2794 0.9906)
			(stroke
				(width 0.1)
				(type default)
			)
			(layer "F.Fab")
		)
		(pad "1" smd rect
			(at 0 0 180)
			(size 0.508 0.508)
			(layers "F.Cu" "F.Mask" "F.Paste")
			(net "VR_PVCCIN_CPU0_AIREF3")
		)
		(pad "2" smd rect
			(at 0 0.889 180)
			(size 0.508 0.508)
			(layers "F.Cu" "F.Mask" "F.Paste")
			(net "ISENSE_PVCCIN_CPU0_PH3_IMON")
		)
		(zone
			(layer "F.Cu")
			(hatch none 0.5)
			(connect_pads
				(clearance 0)
			)
			(min_thickness 0.25)
			(keepout
				(tracks not_allowed)
				(vias allowed)
				(pads allowed)
				(copperpour not_allowed)
				(footprints allowed)
			)
			(placement
				(enabled no)
				(sheetname "")
			)
			(fill
				(thermal_gap 0.5)
				(thermal_bridge_width 0.5)
				(island_removal_mode 0)
			)
			(polygon
				(pts
					(xy 188.754512 -68.555108) (xy 188.246512 -68.555108) (xy 188.246512 -68.174108) (xy 188.754512 -68.174108)
				)
			)
		)
		(zone
			(layer "F.Cu")
			(hatch none 0.5)
			(connect_pads
				(clearance 0)
			)
			(min_thickness 0.25)
			(keepout
				(tracks allowed)
				(vias not_allowed)
				(pads allowed)
				(copperpour not_allowed)
				(footprints allowed)
			)
			(placement
				(enabled no)
				(sheetname "")
			)
			(fill
				(thermal_gap 0.5)
				(thermal_bridge_width 0.5)
				(island_removal_mode 0)
			)
			(polygon
				(pts
					(xy 188.754512 -68.174108) (xy 188.246512 -68.174108) (xy 188.246512 -68.555108) (xy 188.754512 -68.555108)
				)
			)
		)
	)
	(footprint ""
		(layer "F.Cu")
		(at 463.3849 -23.2791)
		(property "Reference" "R8F1"
			(at 0 0 0)
			(layer "F.SilkS")
			(hide yes)
			(effects
				(font
					(size 1.27 1.27)
				)
			)
		)
		(property "Value" ""
			(at 0 0 0)
			(layer "F.Fab")
			(effects
				(font
					(size 1.27 1.27)
				)
			)
		)
		(duplicate_pad_numbers_are_jumpers no)
		(fp_rect
			(start 0.2794 0.9906)
			(end -0.2794 -0.1016)
			(stroke
				(width 0)
				(type default)
			)
			(fill no)
			(layer "F.CrtYd")
		)
		(fp_line
			(start -0.2794 -0.1016)
			(end -0.2794 0.9906)
			(stroke
				(width 0.1)
				(type default)
			)
			(layer "F.Fab")
		)
		(fp_line
			(start -0.2794 0.9906)
			(end 0.2794 0.9906)
			(stroke
				(width 0.1)
				(type default)
			)
			(layer "F.Fab")
		)
		(fp_line
			(start 0.2794 -0.1016)
			(end -0.2794 -0.1016)
			(stroke
				(width 0.1)
				(type default)
			)
			(layer "F.Fab")
		)
		(fp_line
			(start 0.2794 0.9906)
			(end 0.2794 -0.1016)
			(stroke
				(width 0.1)
				(type default)
			)
			(layer "F.Fab")
		)
		(pad "1" smd rect
			(at 0 0)
			(size 0.508 0.508)
			(layers "F.Cu" "F.Mask" "F.Paste")
			(net "PWRGD_P5V_STBY")
		)
		(pad "2" smd rect
			(at 0 0.889)
			(size 0.508 0.508)
			(layers "F.Cu" "F.Mask" "F.Paste")
			(net "GND")
		)
		(zone
			(layer "F.Cu")
			(hatch none 0.5)
			(connect_pads
				(clearance 0)
			)
			(min_thickness 0.25)
			(keepout
				(tracks not_allowed)
				(vias allowed)
				(pads allowed)
				(copperpour not_allowed)
				(footprints allowed)
			)
			(placement
				(enabled no)
				(sheetname "")
			)
			(fill
				(thermal_gap 0.5)
				(thermal_bridge_width 0.5)
				(island_removal_mode 0)
			)
			(polygon
				(pts
					(xy 463.6389 -22.6441) (xy 463.6389 -23.0251) (xy 463.1309 -23.0251) (xy 463.1309 -22.6441)
				)
			)
		)
		(zone
			(layer "F.Cu")
			(hatch none 0.5)
			(connect_pads
				(clearance 0)
			)
			(min_thickness 0.25)
			(keepout
				(tracks allowed)
				(vias not_allowed)
				(pads allowed)
				(copperpour not_allowed)
				(footprints allowed)
			)
			(placement
				(enabled no)
				(sheetname "")
			)
			(fill
				(thermal_gap 0.5)
				(thermal_bridge_width 0.5)
				(island_removal_mode 0)
			)
			(polygon
				(pts
					(xy 463.6389 -22.6441) (xy 463.6389 -23.0251) (xy 463.1309 -23.0251) (xy 463.1309 -22.6441)
				)
			)
		)
	)
	(footprint ""
		(layer "F.Cu")
		(at 430.026826 -131.636008)
		(property "Reference" "R8B4"
			(at 0 0 0)
			(layer "F.SilkS")
			(hide yes)
			(effects
				(font
					(size 1.27 1.27)
				)
			)
		)
		(property "Value" ""
			(at 0 0 0)
			(layer "F.Fab")
			(effects
				(font
					(size 1.27 1.27)
				)
			)
		)
		(duplicate_pad_numbers_are_jumpers no)
		(fp_poly
			(pts
				(xy -0.2794 -0.1016) (xy 0.2794 -0.1016) (xy 0.2794 0.9906) (xy -0.2794 0.9906)
			)
			(stroke
				(width 0)
				(type default)
			)
			(fill no)
			(layer "F.CrtYd")
		)
		(fp_line
			(start -0.2794 -0.1016)
			(end -0.2794 0.9906)
			(stroke
				(width 0.1)
				(type default)
			)
			(layer "F.Fab")
		)
		(fp_line
			(start -0.2794 0.9906)
			(end 0.2794 0.9906)
			(stroke
				(width 0.1)
				(type default)
			)
			(layer "F.Fab")
		)
		(fp_line
			(start 0.2794 -0.1016)
			(end -0.2794 -0.1016)
			(stroke
				(width 0.1)
				(type default)
			)
			(layer "F.Fab")
		)
		(fp_line
			(start 0.2794 0.9906)
			(end 0.2794 -0.1016)
			(stroke
				(width 0.1)
				(type default)
			)
			(layer "F.Fab")
		)
		(pad "1" smd rect
			(at 0 0)
			(size 0.508 0.508)
			(layers "F.Cu" "F.Mask" "F.Paste")
			(net "FM_CTNR_PS_ON")
		)
		(pad "2" smd rect
			(at 0 0.889)
			(size 0.508 0.508)
			(layers "F.Cu" "F.Mask" "F.Paste")
			(net "GND")
		)
		(zone
			(layer "F.Cu")
			(hatch none 0.5)
			(connect_pads
				(clearance 0)
			)
			(min_thickness 0.25)
			(keepout
				(tracks allowed)
				(vias not_allowed)
				(pads allowed)
				(copperpour not_allowed)
				(footprints allowed)
			)
			(placement
				(enabled no)
				(sheetname "")
			)
			(fill
				(thermal_gap 0.5)
				(thermal_bridge_width 0.5)
				(island_removal_mode 0)
			)
			(polygon
				(pts
					(xy 429.772826 -131.382008) (xy 430.280826 -131.382008) (xy 430.280826 -131.001008) (xy 429.772826 -131.001008)
				)
			)
		)
		(zone
			(layer "F.Cu")
			(hatch none 0.5)
			(connect_pads
				(clearance 0)
			)
			(min_thickness 0.25)
			(keepout
				(tracks not_allowed)
				(vias allowed)
				(pads allowed)
				(copperpour not_allowed)
				(footprints allowed)
			)
			(placement
				(enabled no)
				(sheetname "")
			)
			(fill
				(thermal_gap 0.5)
				(thermal_bridge_width 0.5)
				(island_removal_mode 0)
			)
			(polygon
				(pts
					(xy 429.772826 -131.001008) (xy 430.280826 -131.001008) (xy 430.280826 -131.382008) (xy 429.772826 -131.382008)
				)
			)
		)
	)
	(footprint ""
		(layer "F.Cu")
		(at 108.712 -69.85)
		(property "Reference" "R3D32"
			(at 0 0 0)
			(layer "F.SilkS")
			(hide yes)
			(effects
				(font
					(size 1.27 1.27)
				)
			)
		)
		(property "Value" ""
			(at 0 0 0)
			(layer "F.Fab")
			(effects
				(font
					(size 1.27 1.27)
				)
			)
		)
		(duplicate_pad_numbers_are_jumpers no)
		(fp_poly
			(pts
				(xy -0.2794 -0.1016) (xy 0.2794 -0.1016) (xy 0.2794 0.9906) (xy -0.2794 0.9906)
			)
			(stroke
				(width 0)
				(type default)
			)
			(fill no)
			(layer "F.CrtYd")
		)
		(fp_line
			(start -0.2794 -0.1016)
			(end -0.2794 0.9906)
			(stroke
				(width 0.1)
				(type default)
			)
			(layer "F.Fab")
		)
		(fp_line
			(start -0.2794 0.9906)
			(end 0.2794 0.9906)
			(stroke
				(width 0.1)
				(type default)
			)
			(layer "F.Fab")
		)
		(fp_line
			(start 0.2794 -0.1016)
			(end -0.2794 -0.1016)
			(stroke
				(width 0.1)
				(type default)
			)
			(layer "F.Fab")
		)
		(fp_line
			(start 0.2794 0.9906)
			(end 0.2794 -0.1016)
			(stroke
				(width 0.1)
				(type default)
			)
			(layer "F.Fab")
		)
		(pad "1" smd rect
			(at 0 0)
			(size 0.508 0.508)
			(layers "F.Cu" "F.Mask" "F.Paste")
			(net "PVCCIO_CPU1")
		)
		(pad "2" smd rect
			(at 0 0.889)
			(size 0.508 0.508)
			(layers "F.Cu" "F.Mask" "F.Paste")
			(net "VSENSE_PMAX_CPU1")
		)
		(zone
			(layer "F.Cu")
			(hatch none 0.5)
			(connect_pads
				(clearance 0)
			)
			(min_thickness 0.25)
			(keepout
				(tracks allowed)
				(vias not_allowed)
				(pads allowed)
				(copperpour not_allowed)
				(footprints allowed)
			)
			(placement
				(enabled no)
				(sheetname "")
			)
			(fill
				(thermal_gap 0.5)
				(thermal_bridge_width 0.5)
				(island_removal_mode 0)
			)
			(polygon
				(pts
					(xy 108.458 -69.596) (xy 108.966 -69.596) (xy 108.966 -69.215) (xy 108.458 -69.215)
				)
			)
		)
		(zone
			(layer "F.Cu")
			(hatch none 0.5)
			(connect_pads
				(clearance 0)
			)
			(min_thickness 0.25)
			(keepout
				(tracks not_allowed)
				(vias allowed)
				(pads allowed)
				(copperpour not_allowed)
				(footprints allowed)
			)
			(placement
				(enabled no)
				(sheetname "")
			)
			(fill
				(thermal_gap 0.5)
				(thermal_bridge_width 0.5)
				(island_removal_mode 0)
			)
			(polygon
				(pts
					(xy 108.458 -69.215) (xy 108.966 -69.215) (xy 108.966 -69.596) (xy 108.458 -69.596)
				)
			)
		)
	)
	(footprint ""
		(layer "F.Cu")
		(at 194.700398 -15.423642 90)
		(property "Reference" "J4G1"
			(at 9.060688 37.32911 0)
			(unlocked yes)
			(layer "F.SilkS")
			(effects
				(font
					(size 0.7874 0.5842)
					(thickness 0.1524)
				)
				(justify left)
			)
		)
		(property "Value" ""
			(at 0 0 90)
			(layer "F.Fab")
			(effects
				(font
					(size 1.27 1.27)
				)
			)
		)
		(duplicate_pad_numbers_are_jumpers no)
		(fp_line
			(start 5.5499 -7.675118)
			(end 5.5499 -1.480058)
			(stroke
				(width 0.1524)
				(type default)
			)
			(layer "F.SilkS")
		)
		(fp_line
			(start -0.94996 -7.675118)
			(end 5.5499 -7.675118)
			(stroke
				(width 0.1524)
				(type default)
			)
			(layer "F.SilkS")
		)
		(fp_line
			(start -0.94996 -1.480058)
			(end -0.94996 -7.675118)
			(stroke
				(width 0.1524)
				(type default)
			)
			(layer "F.SilkS")
		)
		(fp_line
			(start 5.5499 128.130046)
			(end 5.5499 134.325106)
			(stroke
				(width 0.1524)
				(type default)
			)
			(layer "F.SilkS")
		)
		(fp_line
			(start 5.5499 134.325106)
			(end -0.94996 134.325106)
			(stroke
				(width 0.1524)
				(type default)
			)
			(layer "F.SilkS")
		)
		(fp_line
			(start -0.94996 134.325106)
			(end -0.94996 128.130046)
			(stroke
				(width 0.1524)
				(type default)
			)
			(layer "F.SilkS")
		)
		(fp_poly
			(pts
				(xy -3.014218 -4.185666) (xy -3.014218 -3.169666) (xy -1.744218 -3.677666)
			)
			(stroke
				(width 0)
				(type default)
			)
			(fill yes)
			(layer "F.SilkS")
		)
		(fp_poly
			(pts
				(xy -0.94996 -7.675118) (xy -0.94996 134.325106) (xy 5.5499 134.325106) (xy 5.5499 -7.675118)
			)
			(stroke
				(width 0)
				(type default)
			)
			(fill no)
			(layer "F.CrtYd")
		)
		(fp_line
			(start 5.5499 -7.675118)
			(end 5.5499 134.325106)
			(stroke
				(width 0.1)
				(type default)
			)
			(layer "F.Fab")
		)
		(fp_line
			(start -0.94996 -7.675118)
			(end 5.5499 -7.675118)
			(stroke
				(width 0.1)
				(type default)
			)
			(layer "F.Fab")
		)
		(fp_line
			(start 5.5499 134.325106)
			(end -0.94996 134.325106)
			(stroke
				(width 0.1)
				(type default)
			)
			(layer "F.Fab")
		)
		(fp_line
			(start -0.94996 134.325106)
			(end -0.94996 -7.675118)
			(stroke
				(width 0.1)
				(type default)
			)
			(layer "F.Fab")
		)
		(fp_poly
			(pts
				(xy -2.984246 -0.461264) (xy -2.984246 0.554736) (xy -1.714246 0.046736)
			)
			(stroke
				(width 0)
				(type default)
			)
			(fill yes)
			(layer "F.Fab")
		)
		(fp_text user "145"
			(at 6.068568 -0.72263 0)
			(unlocked yes)
			(layer "F.SilkS")
			(effects
				(font
					(size 0.7874 0.5842)
					(thickness 0.1524)
				)
				(justify left)
			)
		)
		(fp_text user "221"
			(at 6.139688 64.63411 0)
			(unlocked yes)
			(layer "F.SilkS")
			(effects
				(font
					(size 0.7874 0.5842)
					(thickness 0.1524)
				)
				(justify left)
			)
		)
		(fp_text user "77"
			(at -1.226312 65.01511 0)
			(unlocked yes)
			(layer "F.SilkS")
			(effects
				(font
					(size 0.7874 0.5842)
					(thickness 0.1524)
				)
				(justify left)
			)
		)
		(fp_text user "78"
			(at -1.607312 69.71411 0)
			(unlocked yes)
			(layer "F.SilkS")
			(effects
				(font
					(size 0.7874 0.5842)
					(thickness 0.1524)
				)
				(justify left)
			)
		)
		(fp_text user "222"
			(at 6.139688 69.96811 0)
			(unlocked yes)
			(layer "F.SilkS")
			(effects
				(font
					(size 0.7874 0.5842)
					(thickness 0.1524)
				)
				(justify left)
			)
		)
		(fp_text user "144"
			(at -1.734312 127.75311 0)
			(unlocked yes)
			(layer "F.SilkS")
			(effects
				(font
					(size 0.7874 0.5842)
					(thickness 0.1524)
				)
				(justify left)
			)
		)
		(fp_text user "288"
			(at 6.213094 128.622806 0)
			(unlocked yes)
			(layer "F.SilkS")
			(effects
				(font
					(size 0.7874 0.5842)
					(thickness 0.1524)
				)
				(justify left)
			)
		)
		(fp_text user "145"
			(at -3.422142 -7.594092 90)
			(unlocked yes)
			(layer "F.Fab")
			(effects
				(font
					(size 0.7874 0.5842)
					(thickness 0.1524)
				)
				(justify left)
			)
		)
		(fp_text user "221"
			(at 3.626358 65.93078 90)
			(unlocked yes)
			(layer "F.Fab")
			(effects
				(font
					(size 0.7874 0.5842)
					(thickness 0.1524)
				)
				(justify left)
			)
		)
		(fp_text user "77"
			(at -0.818642 65.93078 90)
			(unlocked yes)
			(layer "F.Fab")
			(effects
				(font
					(size 0.7874 0.5842)
					(thickness 0.1524)
				)
				(justify left)
			)
		)
		(fp_text user "222"
			(at 3.956558 69.15658 90)
			(unlocked yes)
			(layer "F.Fab")
			(effects
				(font
					(size 0.7874 0.5842)
					(thickness 0.1524)
				)
				(justify left)
			)
		)
		(fp_text user "78"
			(at -2.689098 70.47357 90)
			(unlocked yes)
			(layer "F.Fab")
			(effects
				(font
					(size 0.7874 0.5842)
					(thickness 0.1524)
				)
				(justify left)
			)
		)
		(fp_text user "288"
			(at 2.991358 128.16078 90)
			(unlocked yes)
			(layer "F.Fab")
			(effects
				(font
					(size 0.7874 0.5842)
					(thickness 0.1524)
				)
				(justify left)
			)
		)
		(fp_text user "144"
			(at -0.818642 128.16078 90)
			(unlocked yes)
			(layer "F.Fab")
			(effects
				(font
					(size 0.7874 0.5842)
					(thickness 0.1524)
				)
				(justify left)
			)
		)
		(pad "" thru_hole circle
			(at 2.29997 -5.649976 90)
			(size 2.8194 2.8194)
			(drill 2.4384)
			(layers "*.Cu" "*.Mask")
			(remove_unused_layers no)
			(clearance 0.127)
			(thermal_gap 0.127)
		)
		(pad "" thru_hole oval
			(at 2.29997 68.90004 90)
			(size 2.8194 1.5748)
			(drill oval 2.4384 1.1938)
			(layers "*.Cu" "*.Mask")
			(remove_unused_layers no)
			(clearance 0.127)
			(thermal_gap 0.127)
		)
		(pad "" thru_hole circle
			(at 2.29997 132.299964 90)
			(size 2.8194 2.8194)
			(drill 2.4384)
			(layers "*.Cu" "*.Mask")
			(remove_unused_layers no)
			(clearance 0.127)
			(thermal_gap 0.127)
		)
		(pad "1" smd rect
			(at 0 0 90)
			(size 1.8034 0.508)
			(layers "F.Cu" "F.Mask" "F.Paste")
			(net "P12V_NVDIMM_ABC")
		)
		(pad "2" smd rect
			(at 0 0.849884 90)
			(size 1.8034 0.508)
			(layers "F.Cu" "F.Mask" "F.Paste")
			(net "GND")
		)
		(pad "3" smd rect
			(at 0 1.700022 90)
			(size 1.8034 0.508)
			(layers "F.Cu" "F.Mask" "F.Paste")
			(net "M_A_DQ<5>")
		)
		(pad "4" smd rect
			(at 0 2.549906 90)
			(size 1.8034 0.508)
			(layers "F.Cu" "F.Mask" "F.Paste")
			(net "GND")
		)
		(pad "5" smd rect
			(at 0 3.400044 90)
			(size 1.8034 0.508)
			(layers "F.Cu" "F.Mask" "F.Paste")
			(net "M_A_DQ<1>")
		)
		(pad "6" smd rect
			(at 0 4.249928 90)
			(size 1.8034 0.508)
			(layers "F.Cu" "F.Mask" "F.Paste")
			(net "GND")
		)
		(pad "7" smd rect
			(at 0 5.100066 90)
			(size 1.8034 0.508)
			(layers "F.Cu" "F.Mask" "F.Paste")
			(net "M_A_DQS_DP<9>")
		)
		(pad "8" smd rect
			(at 0 5.94995 90)
			(size 1.8034 0.508)
			(layers "F.Cu" "F.Mask" "F.Paste")
			(net "M_A_DQS_DN<9>")
		)
		(pad "9" smd rect
			(at 0 6.800088 90)
			(size 1.8034 0.508)
			(layers "F.Cu" "F.Mask" "F.Paste")
			(net "GND")
		)
		(pad "10" smd rect
			(at 0 7.649972 90)
			(size 1.8034 0.508)
			(layers "F.Cu" "F.Mask" "F.Paste")
			(net "M_A_DQ<7>")
		)
		(pad "11" smd rect
			(at 0 8.50011 90)
			(size 1.8034 0.508)
			(layers "F.Cu" "F.Mask" "F.Paste")
			(net "GND")
		)
		(pad "12" smd rect
			(at 0 9.349994 90)
			(size 1.8034 0.508)
			(layers "F.Cu" "F.Mask" "F.Paste")
			(net "M_A_DQ<3>")
		)
		(pad "13" smd rect
			(at 0 10.199878 90)
			(size 1.8034 0.508)
			(layers "F.Cu" "F.Mask" "F.Paste")
			(net "GND")
		)
		(pad "14" smd rect
			(at 0 11.050016 90)
			(size 1.8034 0.508)
			(layers "F.Cu" "F.Mask" "F.Paste")
			(net "M_A_DQ<13>")
		)
		(pad "15" smd rect
			(at 0 11.8999 90)
			(size 1.8034 0.508)
			(layers "F.Cu" "F.Mask" "F.Paste")
			(net "GND")
		)
		(pad "16" smd rect
			(at 0 12.750038 90)
			(size 1.8034 0.508)
			(layers "F.Cu" "F.Mask" "F.Paste")
			(net "M_A_DQ<9>")
		)
		(pad "17" smd rect
			(at 0 13.599922 90)
			(size 1.8034 0.508)
			(layers "F.Cu" "F.Mask" "F.Paste")
			(net "GND")
		)
		(pad "18" smd rect
			(at 0 14.45006 90)
			(size 1.8034 0.508)
			(layers "F.Cu" "F.Mask" "F.Paste")
			(net "M_A_DQS_DP<10>")
		)
		(pad "19" smd rect
			(at 0 15.299944 90)
			(size 1.8034 0.508)
			(layers "F.Cu" "F.Mask" "F.Paste")
			(net "M_A_DQS_DN<10>")
		)
		(pad "20" smd rect
			(at 0 16.150082 90)
			(size 1.8034 0.508)
			(layers "F.Cu" "F.Mask" "F.Paste")
			(net "GND")
		)
		(pad "21" smd rect
			(at 0 16.999966 90)
			(size 1.8034 0.508)
			(layers "F.Cu" "F.Mask" "F.Paste")
			(net "M_A_DQ<15>")
		)
		(pad "22" smd rect
			(at 0 17.850104 90)
			(size 1.8034 0.508)
			(layers "F.Cu" "F.Mask" "F.Paste")
			(net "GND")
		)
		(pad "23" smd rect
			(at 0 18.699988 90)
			(size 1.8034 0.508)
			(layers "F.Cu" "F.Mask" "F.Paste")
			(net "M_A_DQ<11>")
		)
		(pad "24" smd rect
			(at 0 19.550126 90)
			(size 1.8034 0.508)
			(layers "F.Cu" "F.Mask" "F.Paste")
			(net "GND")
		)
		(pad "25" smd rect
			(at 0 20.40001 90)
			(size 1.8034 0.508)
			(layers "F.Cu" "F.Mask" "F.Paste")
			(net "M_A_DQ<21>")
		)
		(pad "26" smd rect
			(at 0 21.249894 90)
			(size 1.8034 0.508)
			(layers "F.Cu" "F.Mask" "F.Paste")
			(net "GND")
		)
		(pad "27" smd rect
			(at 0 22.100032 90)
			(size 1.8034 0.508)
			(layers "F.Cu" "F.Mask" "F.Paste")
			(net "M_A_DQ<17>")
		)
		(pad "28" smd rect
			(at 0 22.949916 90)
			(size 1.8034 0.508)
			(layers "F.Cu" "F.Mask" "F.Paste")
			(net "GND")
		)
		(pad "29" smd rect
			(at 0 23.800054 90)
			(size 1.8034 0.508)
			(layers "F.Cu" "F.Mask" "F.Paste")
			(net "M_A_DQS_DP<11>")
		)
		(pad "30" smd rect
			(at 0 24.649938 90)
			(size 1.8034 0.508)
			(layers "F.Cu" "F.Mask" "F.Paste")
			(net "M_A_DQS_DN<11>")
		)
		(pad "31" smd rect
			(at 0 25.500076 90)
			(size 1.8034 0.508)
			(layers "F.Cu" "F.Mask" "F.Paste")
			(net "GND")
		)
		(pad "32" smd rect
			(at 0 26.34996 90)
			(size 1.8034 0.508)
			(layers "F.Cu" "F.Mask" "F.Paste")
			(net "M_A_DQ<23>")
		)
		(pad "33" smd rect
			(at 0 27.200098 90)
			(size 1.8034 0.508)
			(layers "F.Cu" "F.Mask" "F.Paste")
			(net "GND")
		)
		(pad "34" smd rect
			(at 0 28.049982 90)
			(size 1.8034 0.508)
			(layers "F.Cu" "F.Mask" "F.Paste")
			(net "M_A_DQ<19>")
		)
		(pad "35" smd rect
			(at 0 28.90012 90)
			(size 1.8034 0.508)
			(layers "F.Cu" "F.Mask" "F.Paste")
			(net "GND")
		)
		(pad "36" smd rect
			(at 0 29.750004 90)
			(size 1.8034 0.508)
			(layers "F.Cu" "F.Mask" "F.Paste")
			(net "M_A_DQ<29>")
		)
		(pad "37" smd rect
			(at 0 30.599888 90)
			(size 1.8034 0.508)
			(layers "F.Cu" "F.Mask" "F.Paste")
			(net "GND")
		)
		(pad "38" smd rect
			(at 0 31.450026 90)
			(size 1.8034 0.508)
			(layers "F.Cu" "F.Mask" "F.Paste")
			(net "M_A_DQ<25>")
		)
		(pad "39" smd rect
			(at 0 32.29991 90)
			(size 1.8034 0.508)
			(layers "F.Cu" "F.Mask" "F.Paste")
			(net "GND")
		)
		(pad "40" smd rect
			(at 0 33.150048 90)
			(size 1.8034 0.508)
			(layers "F.Cu" "F.Mask" "F.Paste")
			(net "M_A_DQS_DP<12>")
		)
		(pad "41" smd rect
			(at 0 33.999932 90)
			(size 1.8034 0.508)
			(layers "F.Cu" "F.Mask" "F.Paste")
			(net "M_A_DQS_DN<12>")
		)
		(pad "42" smd rect
			(at 0 34.85007 90)
			(size 1.8034 0.508)
			(layers "F.Cu" "F.Mask" "F.Paste")
			(net "GND")
		)
		(pad "43" smd rect
			(at 0 35.699954 90)
			(size 1.8034 0.508)
			(layers "F.Cu" "F.Mask" "F.Paste")
			(net "M_A_DQ<31>")
		)
		(pad "44" smd rect
			(at 0 36.550092 90)
			(size 1.8034 0.508)
			(layers "F.Cu" "F.Mask" "F.Paste")
			(net "GND")
		)
		(pad "45" smd rect
			(at 0 37.399976 90)
			(size 1.8034 0.508)
			(layers "F.Cu" "F.Mask" "F.Paste")
			(net "M_A_DQ<27>")
		)
		(pad "46" smd rect
			(at 0 38.250114 90)
			(size 1.8034 0.508)
			(layers "F.Cu" "F.Mask" "F.Paste")
			(net "GND")
		)
		(pad "47" smd rect
			(at 0 39.099998 90)
			(size 1.8034 0.508)
			(layers "F.Cu" "F.Mask" "F.Paste")
			(net "M_A_ECC<5>")
		)
		(pad "48" smd rect
			(at 0 39.949882 90)
			(size 1.8034 0.508)
			(layers "F.Cu" "F.Mask" "F.Paste")
			(net "GND")
		)
		(pad "49" smd rect
			(at 0 40.80002 90)
			(size 1.8034 0.508)
			(layers "F.Cu" "F.Mask" "F.Paste")
			(net "M_A_ECC<1>")
		)
		(pad "50" smd rect
			(at 0 41.649904 90)
			(size 1.8034 0.508)
			(layers "F.Cu" "F.Mask" "F.Paste")
			(net "GND")
		)
		(pad "51" smd rect
			(at 0 42.500042 90)
			(size 1.8034 0.508)
			(layers "F.Cu" "F.Mask" "F.Paste")
			(net "M_A_DQS_DP<17>")
		)
		(pad "52" smd rect
			(at 0 43.349926 90)
			(size 1.8034 0.508)
			(layers "F.Cu" "F.Mask" "F.Paste")
			(net "M_A_DQS_DN<17>")
		)
		(pad "53" smd rect
			(at 0 44.200064 90)
			(size 1.8034 0.508)
			(layers "F.Cu" "F.Mask" "F.Paste")
			(net "GND")
		)
		(pad "54" smd rect
			(at 0 45.049948 90)
			(size 1.8034 0.508)
			(layers "F.Cu" "F.Mask" "F.Paste")
			(net "M_A_ECC<7>")
		)
		(pad "55" smd rect
			(at 0 45.900086 90)
			(size 1.8034 0.508)
			(layers "F.Cu" "F.Mask" "F.Paste")
			(net "GND")
		)
		(pad "56" smd rect
			(at 0 46.74997 90)
			(size 1.8034 0.508)
			(layers "F.Cu" "F.Mask" "F.Paste")
			(net "M_A_ECC<3>")
		)
		(pad "57" smd rect
			(at 0 47.600108 90)
			(size 1.8034 0.508)
			(layers "F.Cu" "F.Mask" "F.Paste")
			(net "GND")
		)
		(pad "58" smd rect
			(at 0 48.449992 90)
			(size 1.8034 0.508)
			(layers "F.Cu" "F.Mask" "F.Paste")
			(net "M_ABC_RST_N")
		)
		(pad "59" smd rect
			(at 0 49.299876 90)
			(size 1.8034 0.508)
			(layers "F.Cu" "F.Mask" "F.Paste")
			(net "PVDDQ_ABC")
		)
		(pad "60" smd rect
			(at 0 50.150014 90)
			(size 1.8034 0.508)
			(layers "F.Cu" "F.Mask" "F.Paste")
			(net "M_A_CKE<0>")
		)
		(pad "61" smd rect
			(at 0 50.999898 90)
			(size 1.8034 0.508)
			(layers "F.Cu" "F.Mask" "F.Paste")
			(net "PVDDQ_ABC")
		)
		(pad "62" smd rect
			(at 0 51.850036 90)
			(size 1.8034 0.508)
			(layers "F.Cu" "F.Mask" "F.Paste")
			(net "M_A_ACT_N")
		)
		(pad "63" smd rect
			(at 0 52.69992 90)
			(size 1.8034 0.508)
			(layers "F.Cu" "F.Mask" "F.Paste")
			(net "M_A_BG<0>")
		)
		(pad "64" smd rect
			(at 0 53.550058 90)
			(size 1.8034 0.508)
			(layers "F.Cu" "F.Mask" "F.Paste")
			(net "PVDDQ_ABC")
		)
		(pad "65" smd rect
			(at 0 54.399942 90)
			(size 1.8034 0.508)
			(layers "F.Cu" "F.Mask" "F.Paste")
			(net "M_A_MA<12>")
		)
		(pad "66" smd rect
			(at 0 55.25008 90)
			(size 1.8034 0.508)
			(layers "F.Cu" "F.Mask" "F.Paste")
			(net "M_A_MA<9>")
		)
		(pad "67" smd rect
			(at 0 56.099964 90)
			(size 1.8034 0.508)
			(layers "F.Cu" "F.Mask" "F.Paste")
			(net "PVDDQ_ABC")
		)
		(pad "68" smd rect
			(at 0 56.950102 90)
			(size 1.8034 0.508)
			(layers "F.Cu" "F.Mask" "F.Paste")
			(net "M_A_MA<8>")
		)
		(pad "69" smd rect
			(at 0 57.799986 90)
			(size 1.8034 0.508)
			(layers "F.Cu" "F.Mask" "F.Paste")
			(net "M_A_MA<6>")
		)
		(pad "70" smd rect
			(at 0 58.650124 90)
			(size 1.8034 0.508)
			(layers "F.Cu" "F.Mask" "F.Paste")
			(net "PVDDQ_ABC")
		)
		(pad "71" smd rect
			(at 0 59.500008 90)
			(size 1.8034 0.508)
			(layers "F.Cu" "F.Mask" "F.Paste")
			(net "M_A_MA<3>")
		)
		(pad "72" smd rect
			(at 0 60.349892 90)
			(size 1.8034 0.508)
			(layers "F.Cu" "F.Mask" "F.Paste")
			(net "M_A_MA<1>")
		)
		(pad "73" smd rect
			(at 0 61.20003 90)
			(size 1.8034 0.508)
			(layers "F.Cu" "F.Mask" "F.Paste")
			(net "PVDDQ_ABC")
		)
		(pad "74" smd rect
			(at 0 62.049914 90)
			(size 1.8034 0.508)
			(layers "F.Cu" "F.Mask" "F.Paste")
			(net "M_A_CLK_DP<0>")
		)
		(pad "75" smd rect
			(at 0 62.900052 90)
			(size 1.8034 0.508)
			(layers "F.Cu" "F.Mask" "F.Paste")
			(net "M_A_CLK_DN<0>")
		)
		(pad "76" smd rect
			(at 0 63.749936 90)
			(size 1.8034 0.508)
			(layers "F.Cu" "F.Mask" "F.Paste")
			(net "PVDDQ_ABC")
		)
		(pad "77" smd rect
			(at 0 64.600074 90)
			(size 1.8034 0.508)
			(layers "F.Cu" "F.Mask" "F.Paste")
			(net "PVTT_ABC")
		)
		(pad "78" smd rect
			(at 0 70.550024 90)
			(size 1.8034 0.508)
			(layers "F.Cu" "F.Mask" "F.Paste")
			(net "FM_DIMM_EVENT_COD_N")
		)
		(pad "79" smd rect
			(at 0 71.399908 90)
			(size 1.8034 0.508)
			(layers "F.Cu" "F.Mask" "F.Paste")
			(net "M_A_MA<0>")
		)
		(pad "80" smd rect
			(at 0 72.250046 90)
			(size 1.8034 0.508)
			(layers "F.Cu" "F.Mask" "F.Paste")
			(net "PVDDQ_ABC")
		)
		(pad "81" smd rect
			(at 0 73.09993 90)
			(size 1.8034 0.508)
			(layers "F.Cu" "F.Mask" "F.Paste")
			(net "M_A_BA<0>")
		)
		(pad "82" smd rect
			(at 0 73.950068 90)
			(size 1.8034 0.508)
			(layers "F.Cu" "F.Mask" "F.Paste")
			(net "M_A_MA<16>")
		)
		(pad "83" smd rect
			(at 0 74.799952 90)
			(size 1.8034 0.508)
			(layers "F.Cu" "F.Mask" "F.Paste")
			(net "PVDDQ_ABC")
		)
		(pad "84" smd rect
			(at 0 75.65009 90)
			(size 1.8034 0.508)
			(layers "F.Cu" "F.Mask" "F.Paste")
			(net "M_A_CS_N<0>")
		)
		(pad "85" smd rect
			(at 0 76.499974 90)
			(size 1.8034 0.508)
			(layers "F.Cu" "F.Mask" "F.Paste")
			(net "PVDDQ_ABC")
		)
		(pad "86" smd rect
			(at 0 77.350112 90)
			(size 1.8034 0.508)
			(layers "F.Cu" "F.Mask" "F.Paste")
			(net "M_A_MA<15>")
		)
		(pad "87" smd rect
			(at 0 78.199996 90)
			(size 1.8034 0.508)
			(layers "F.Cu" "F.Mask" "F.Paste")
			(net "M_A_ODT<0>")
		)
		(pad "88" smd rect
			(at 0 79.04988 90)
			(size 1.8034 0.508)
			(layers "F.Cu" "F.Mask" "F.Paste")
			(net "PVDDQ_ABC")
		)
		(pad "89" smd rect
			(at 0 79.900018 90)
			(size 1.8034 0.508)
			(layers "F.Cu" "F.Mask" "F.Paste")
			(net "M_A_CS_N<1>")
		)
		(pad "90" smd rect
			(at 0 80.749902 90)
			(size 1.8034 0.508)
			(layers "F.Cu" "F.Mask" "F.Paste")
			(net "PVDDQ_ABC")
		)
		(pad "91" smd rect
			(at 0 81.60004 90)
			(size 1.8034 0.508)
			(layers "F.Cu" "F.Mask" "F.Paste")
			(net "M_A_ODT<1>")
		)
		(pad "92" smd rect
			(at 0 82.449924 90)
			(size 1.8034 0.508)
			(layers "F.Cu" "F.Mask" "F.Paste")
			(net "PVDDQ_ABC")
		)
		(pad "93" smd rect
			(at 0 83.300062 90)
			(size 1.8034 0.508)
			(layers "F.Cu" "F.Mask" "F.Paste")
			(net "M_A_CS_N<2>")
		)
		(pad "94" smd rect
			(at 0 84.149946 90)
			(size 1.8034 0.508)
			(layers "F.Cu" "F.Mask" "F.Paste")
			(net "GND")
		)
		(pad "95" smd rect
			(at 0 85.000084 90)
			(size 1.8034 0.508)
			(layers "F.Cu" "F.Mask" "F.Paste")
			(net "M_A_DQ<37>")
		)
		(pad "96" smd rect
			(at 0 85.849968 90)
			(size 1.8034 0.508)
			(layers "F.Cu" "F.Mask" "F.Paste")
			(net "GND")
		)
		(pad "97" smd rect
			(at 0 86.700106 90)
			(size 1.8034 0.508)
			(layers "F.Cu" "F.Mask" "F.Paste")
			(net "M_A_DQ<33>")
		)
		(pad "98" smd rect
			(at 0 87.54999 90)
			(size 1.8034 0.508)
			(layers "F.Cu" "F.Mask" "F.Paste")
			(net "GND")
		)
		(pad "99" smd rect
			(at 0 88.399874 90)
			(size 1.8034 0.508)
			(layers "F.Cu" "F.Mask" "F.Paste")
			(net "M_A_DQS_DP<13>")
		)
		(pad "100" smd rect
			(at 0 89.250012 90)
			(size 1.8034 0.508)
			(layers "F.Cu" "F.Mask" "F.Paste")
			(net "M_A_DQS_DN<13>")
		)
		(pad "101" smd rect
			(at 0 90.099896 90)
			(size 1.8034 0.508)
			(layers "F.Cu" "F.Mask" "F.Paste")
			(net "GND")
		)
		(pad "102" smd rect
			(at 0 90.950034 90)
			(size 1.8034 0.508)
			(layers "F.Cu" "F.Mask" "F.Paste")
			(net "M_A_DQ<39>")
		)
		(pad "103" smd rect
			(at 0 91.799918 90)
			(size 1.8034 0.508)
			(layers "F.Cu" "F.Mask" "F.Paste")
			(net "GND")
		)
		(pad "104" smd rect
			(at 0 92.650056 90)
			(size 1.8034 0.508)
			(layers "F.Cu" "F.Mask" "F.Paste")
			(net "M_A_DQ<35>")
		)
		(pad "105" smd rect
			(at 0 93.49994 90)
			(size 1.8034 0.508)
			(layers "F.Cu" "F.Mask" "F.Paste")
			(net "GND")
		)
		(pad "106" smd rect
			(at 0 94.350078 90)
			(size 1.8034 0.508)
			(layers "F.Cu" "F.Mask" "F.Paste")
			(net "M_A_DQ<45>")
		)
		(pad "107" smd rect
			(at 0 95.199962 90)
			(size 1.8034 0.508)
			(layers "F.Cu" "F.Mask" "F.Paste")
			(net "GND")
		)
		(pad "108" smd rect
			(at 0 96.0501 90)
			(size 1.8034 0.508)
			(layers "F.Cu" "F.Mask" "F.Paste")
			(net "M_A_DQ<41>")
		)
		(pad "109" smd rect
			(at 0 96.899984 90)
			(size 1.8034 0.508)
			(layers "F.Cu" "F.Mask" "F.Paste")
			(net "GND")
		)
		(pad "110" smd rect
			(at 0 97.750122 90)
			(size 1.8034 0.508)
			(layers "F.Cu" "F.Mask" "F.Paste")
			(net "M_A_DQS_DP<14>")
		)
		(pad "111" smd rect
			(at 0 98.600006 90)
			(size 1.8034 0.508)
			(layers "F.Cu" "F.Mask" "F.Paste")
			(net "M_A_DQS_DN<14>")
		)
		(pad "112" smd rect
			(at 0 99.44989 90)
			(size 1.8034 0.508)
			(layers "F.Cu" "F.Mask" "F.Paste")
			(net "GND")
		)
		(pad "113" smd rect
			(at 0 100.300028 90)
			(size 1.8034 0.508)
			(layers "F.Cu" "F.Mask" "F.Paste")
			(net "M_A_DQ<47>")
		)
		(pad "114" smd rect
			(at 0 101.149912 90)
			(size 1.8034 0.508)
			(layers "F.Cu" "F.Mask" "F.Paste")
			(net "GND")
		)
		(pad "115" smd rect
			(at 0 102.00005 90)
			(size 1.8034 0.508)
			(layers "F.Cu" "F.Mask" "F.Paste")
			(net "M_A_DQ<43>")
		)
		(pad "116" smd rect
			(at 0 102.849934 90)
			(size 1.8034 0.508)
			(layers "F.Cu" "F.Mask" "F.Paste")
			(net "GND")
		)
		(pad "117" smd rect
			(at 0 103.700072 90)
			(size 1.8034 0.508)
			(layers "F.Cu" "F.Mask" "F.Paste")
			(net "M_A_DQ<53>")
		)
		(pad "118" smd rect
			(at 0 104.549956 90)
			(size 1.8034 0.508)
			(layers "F.Cu" "F.Mask" "F.Paste")
			(net "GND")
		)
		(pad "119" smd rect
			(at 0 105.400094 90)
			(size 1.8034 0.508)
			(layers "F.Cu" "F.Mask" "F.Paste")
			(net "M_A_DQ<49>")
		)
		(pad "120" smd rect
			(at 0 106.249978 90)
			(size 1.8034 0.508)
			(layers "F.Cu" "F.Mask" "F.Paste")
			(net "GND")
		)
		(pad "121" smd rect
			(at 0 107.100116 90)
			(size 1.8034 0.508)
			(layers "F.Cu" "F.Mask" "F.Paste")
			(net "M_A_DQS_DP<15>")
		)
		(pad "122" smd rect
			(at 0 107.95 90)
			(size 1.8034 0.508)
			(layers "F.Cu" "F.Mask" "F.Paste")
			(net "M_A_DQS_DN<15>")
		)
		(pad "123" smd rect
			(at 0 108.799884 90)
			(size 1.8034 0.508)
			(layers "F.Cu" "F.Mask" "F.Paste")
			(net "GND")
		)
		(pad "124" smd rect
			(at 0 109.650022 90)
			(size 1.8034 0.508)
			(layers "F.Cu" "F.Mask" "F.Paste")
			(net "M_A_DQ<55>")
		)
		(pad "125" smd rect
			(at 0 110.499906 90)
			(size 1.8034 0.508)
			(layers "F.Cu" "F.Mask" "F.Paste")
			(net "GND")
		)
		(pad "126" smd rect
			(at 0 111.350044 90)
			(size 1.8034 0.508)
			(layers "F.Cu" "F.Mask" "F.Paste")
			(net "M_A_DQ<51>")
		)
		(pad "127" smd rect
			(at 0 112.199928 90)
			(size 1.8034 0.508)
			(layers "F.Cu" "F.Mask" "F.Paste")
			(net "GND")
		)
		(pad "128" smd rect
			(at 0 113.050066 90)
			(size 1.8034 0.508)
			(layers "F.Cu" "F.Mask" "F.Paste")
			(net "M_A_DQ<61>")
		)
		(pad "129" smd rect
			(at 0 113.89995 90)
			(size 1.8034 0.508)
			(layers "F.Cu" "F.Mask" "F.Paste")
			(net "GND")
		)
		(pad "130" smd rect
			(at 0 114.750088 90)
			(size 1.8034 0.508)
			(layers "F.Cu" "F.Mask" "F.Paste")
			(net "M_A_DQ<57>")
		)
		(pad "131" smd rect
			(at 0 115.599972 90)
			(size 1.8034 0.508)
			(layers "F.Cu" "F.Mask" "F.Paste")
			(net "GND")
		)
		(pad "132" smd rect
			(at 0 116.45011 90)
			(size 1.8034 0.508)
			(layers "F.Cu" "F.Mask" "F.Paste")
			(net "M_A_DQS_DP<16>")
		)
		(pad "133" smd rect
			(at 0 117.299994 90)
			(size 1.8034 0.508)
			(layers "F.Cu" "F.Mask" "F.Paste")
			(net "M_A_DQS_DN<16>")
		)
		(pad "134" smd rect
			(at 0 118.149878 90)
			(size 1.8034 0.508)
			(layers "F.Cu" "F.Mask" "F.Paste")
			(net "GND")
		)
		(pad "135" smd rect
			(at 0 119.000016 90)
			(size 1.8034 0.508)
			(layers "F.Cu" "F.Mask" "F.Paste")
			(net "M_A_DQ<63>")
		)
		(pad "136" smd rect
			(at 0 119.8499 90)
			(size 1.8034 0.508)
			(layers "F.Cu" "F.Mask" "F.Paste")
			(net "GND")
		)
		(pad "137" smd rect
			(at 0 120.700038 90)
			(size 1.8034 0.508)
			(layers "F.Cu" "F.Mask" "F.Paste")
			(net "M_A_DQ<59>")
		)
		(pad "138" smd rect
			(at 0 121.549922 90)
			(size 1.8034 0.508)
			(layers "F.Cu" "F.Mask" "F.Paste")
			(net "GND")
		)
		(pad "139" smd rect
			(at 0 122.40006 90)
			(size 1.8034 0.508)
			(layers "F.Cu" "F.Mask" "F.Paste")
			(net "GND")
		)
		(pad "140" smd rect
			(at 0 123.249944 90)
			(size 1.8034 0.508)
			(layers "F.Cu" "F.Mask" "F.Paste")
			(net "GND")
		)
		(pad "141" smd rect
			(at 0 124.100082 90)
			(size 1.8034 0.508)
			(layers "F.Cu" "F.Mask" "F.Paste")
			(net "SMB_DDR_ABC_VPP_SCL")
		)
		(pad "142" smd rect
			(at 0 124.949966 90)
			(size 1.8034 0.508)
			(layers "F.Cu" "F.Mask" "F.Paste")
			(net "PVPP_ABC")
		)
		(pad "143" smd rect
			(at 0 125.800104 90)
			(size 1.8034 0.508)
			(layers "F.Cu" "F.Mask" "F.Paste")
			(net "PVPP_ABC")
		)
		(pad "144" smd rect
			(at 0 126.649988 90)
			(size 1.8034 0.508)
			(layers "F.Cu" "F.Mask" "F.Paste")
			(net "TP_CH_A_DIMM_A0_RFU_2")
		)
		(pad "145" smd rect
			(at 4.59994 0 90)
			(size 1.8034 0.508)
			(layers "F.Cu" "F.Mask" "F.Paste")
			(net "P12V_NVDIMM_ABC")
		)
		(pad "146" smd rect
			(at 4.59994 0.849884 90)
			(size 1.8034 0.508)
			(layers "F.Cu" "F.Mask" "F.Paste")
			(net "M_A_VREF")
		)
		(pad "147" smd rect
			(at 4.59994 1.700022 90)
			(size 1.8034 0.508)
			(layers "F.Cu" "F.Mask" "F.Paste")
			(net "GND")
		)
		(pad "148" smd rect
			(at 4.59994 2.549906 90)
			(size 1.8034 0.508)
			(layers "F.Cu" "F.Mask" "F.Paste")
			(net "M_A_DQ<4>")
		)
		(pad "149" smd rect
			(at 4.59994 3.400044 90)
			(size 1.8034 0.508)
			(layers "F.Cu" "F.Mask" "F.Paste")
			(net "GND")
		)
		(pad "150" smd rect
			(at 4.59994 4.249928 90)
			(size 1.8034 0.508)
			(layers "F.Cu" "F.Mask" "F.Paste")
			(net "M_A_DQ<0>")
		)
		(pad "151" smd rect
			(at 4.59994 5.100066 90)
			(size 1.8034 0.508)
			(layers "F.Cu" "F.Mask" "F.Paste")
			(net "GND")
		)
		(pad "152" smd rect
			(at 4.59994 5.94995 90)
			(size 1.8034 0.508)
			(layers "F.Cu" "F.Mask" "F.Paste")
			(net "M_A_DQS_DN<0>")
		)
		(pad "153" smd rect
			(at 4.59994 6.800088 90)
			(size 1.8034 0.508)
			(layers "F.Cu" "F.Mask" "F.Paste")
			(net "M_A_DQS_DP<0>")
		)
		(pad "154" smd rect
			(at 4.59994 7.649972 90)
			(size 1.8034 0.508)
			(layers "F.Cu" "F.Mask" "F.Paste")
			(net "GND")
		)
		(pad "155" smd rect
			(at 4.59994 8.50011 90)
			(size 1.8034 0.508)
			(layers "F.Cu" "F.Mask" "F.Paste")
			(net "M_A_DQ<6>")
		)
		(pad "156" smd rect
			(at 4.59994 9.349994 90)
			(size 1.8034 0.508)
			(layers "F.Cu" "F.Mask" "F.Paste")
			(net "GND")
		)
		(pad "157" smd rect
			(at 4.59994 10.199878 90)
			(size 1.8034 0.508)
			(layers "F.Cu" "F.Mask" "F.Paste")
			(net "M_A_DQ<2>")
		)
		(pad "158" smd rect
			(at 4.59994 11.050016 90)
			(size 1.8034 0.508)
			(layers "F.Cu" "F.Mask" "F.Paste")
			(net "GND")
		)
		(pad "159" smd rect
			(at 4.59994 11.8999 90)
			(size 1.8034 0.508)
			(layers "F.Cu" "F.Mask" "F.Paste")
			(net "M_A_DQ<12>")
		)
		(pad "160" smd rect
			(at 4.59994 12.750038 90)
			(size 1.8034 0.508)
			(layers "F.Cu" "F.Mask" "F.Paste")
			(net "GND")
		)
		(pad "161" smd rect
			(at 4.59994 13.599922 90)
			(size 1.8034 0.508)
			(layers "F.Cu" "F.Mask" "F.Paste")
			(net "M_A_DQ<8>")
		)
		(pad "162" smd rect
			(at 4.59994 14.45006 90)
			(size 1.8034 0.508)
			(layers "F.Cu" "F.Mask" "F.Paste")
			(net "GND")
		)
		(pad "163" smd rect
			(at 4.59994 15.299944 90)
			(size 1.8034 0.508)
			(layers "F.Cu" "F.Mask" "F.Paste")
			(net "M_A_DQS_DN<1>")
		)
		(pad "164" smd rect
			(at 4.59994 16.150082 90)
			(size 1.8034 0.508)
			(layers "F.Cu" "F.Mask" "F.Paste")
			(net "M_A_DQS_DP<1>")
		)
		(pad "165" smd rect
			(at 4.59994 16.999966 90)
			(size 1.8034 0.508)
			(layers "F.Cu" "F.Mask" "F.Paste")
			(net "GND")
		)
		(pad "166" smd rect
			(at 4.59994 17.850104 90)
			(size 1.8034 0.508)
			(layers "F.Cu" "F.Mask" "F.Paste")
			(net "M_A_DQ<14>")
		)
		(pad "167" smd rect
			(at 4.59994 18.699988 90)
			(size 1.8034 0.508)
			(layers "F.Cu" "F.Mask" "F.Paste")
			(net "GND")
		)
		(pad "168" smd rect
			(at 4.59994 19.550126 90)
			(size 1.8034 0.508)
			(layers "F.Cu" "F.Mask" "F.Paste")
			(net "M_A_DQ<10>")
		)
		(pad "169" smd rect
			(at 4.59994 20.40001 90)
			(size 1.8034 0.508)
			(layers "F.Cu" "F.Mask" "F.Paste")
			(net "GND")
		)
		(pad "170" smd rect
			(at 4.59994 21.249894 90)
			(size 1.8034 0.508)
			(layers "F.Cu" "F.Mask" "F.Paste")
			(net "M_A_DQ<20>")
		)
		(pad "171" smd rect
			(at 4.59994 22.100032 90)
			(size 1.8034 0.508)
			(layers "F.Cu" "F.Mask" "F.Paste")
			(net "GND")
		)
		(pad "172" smd rect
			(at 4.59994 22.949916 90)
			(size 1.8034 0.508)
			(layers "F.Cu" "F.Mask" "F.Paste")
			(net "M_A_DQ<16>")
		)
		(pad "173" smd rect
			(at 4.59994 23.800054 90)
			(size 1.8034 0.508)
			(layers "F.Cu" "F.Mask" "F.Paste")
			(net "GND")
		)
		(pad "174" smd rect
			(at 4.59994 24.649938 90)
			(size 1.8034 0.508)
			(layers "F.Cu" "F.Mask" "F.Paste")
			(net "M_A_DQS_DN<2>")
		)
		(pad "175" smd rect
			(at 4.59994 25.500076 90)
			(size 1.8034 0.508)
			(layers "F.Cu" "F.Mask" "F.Paste")
			(net "M_A_DQS_DP<2>")
		)
		(pad "176" smd rect
			(at 4.59994 26.34996 90)
			(size 1.8034 0.508)
			(layers "F.Cu" "F.Mask" "F.Paste")
			(net "GND")
		)
		(pad "177" smd rect
			(at 4.59994 27.200098 90)
			(size 1.8034 0.508)
			(layers "F.Cu" "F.Mask" "F.Paste")
			(net "M_A_DQ<22>")
		)
		(pad "178" smd rect
			(at 4.59994 28.049982 90)
			(size 1.8034 0.508)
			(layers "F.Cu" "F.Mask" "F.Paste")
			(net "GND")
		)
		(pad "179" smd rect
			(at 4.59994 28.90012 90)
			(size 1.8034 0.508)
			(layers "F.Cu" "F.Mask" "F.Paste")
			(net "M_A_DQ<18>")
		)
		(pad "180" smd rect
			(at 4.59994 29.750004 90)
			(size 1.8034 0.508)
			(layers "F.Cu" "F.Mask" "F.Paste")
			(net "GND")
		)
		(pad "181" smd rect
			(at 4.59994 30.599888 90)
			(size 1.8034 0.508)
			(layers "F.Cu" "F.Mask" "F.Paste")
			(net "M_A_DQ<28>")
		)
		(pad "182" smd rect
			(at 4.59994 31.450026 90)
			(size 1.8034 0.508)
			(layers "F.Cu" "F.Mask" "F.Paste")
			(net "GND")
		)
		(pad "183" smd rect
			(at 4.59994 32.29991 90)
			(size 1.8034 0.508)
			(layers "F.Cu" "F.Mask" "F.Paste")
			(net "M_A_DQ<24>")
		)
		(pad "184" smd rect
			(at 4.59994 33.150048 90)
			(size 1.8034 0.508)
			(layers "F.Cu" "F.Mask" "F.Paste")
			(net "GND")
		)
		(pad "185" smd rect
			(at 4.59994 33.999932 90)
			(size 1.8034 0.508)
			(layers "F.Cu" "F.Mask" "F.Paste")
			(net "M_A_DQS_DN<3>")
		)
		(pad "186" smd rect
			(at 4.59994 34.85007 90)
			(size 1.8034 0.508)
			(layers "F.Cu" "F.Mask" "F.Paste")
			(net "M_A_DQS_DP<3>")
		)
		(pad "187" smd rect
			(at 4.59994 35.699954 90)
			(size 1.8034 0.508)
			(layers "F.Cu" "F.Mask" "F.Paste")
			(net "GND")
		)
		(pad "188" smd rect
			(at 4.59994 36.550092 90)
			(size 1.8034 0.508)
			(layers "F.Cu" "F.Mask" "F.Paste")
			(net "M_A_DQ<30>")
		)
		(pad "189" smd rect
			(at 4.59994 37.399976 90)
			(size 1.8034 0.508)
			(layers "F.Cu" "F.Mask" "F.Paste")
			(net "GND")
		)
		(pad "190" smd rect
			(at 4.59994 38.250114 90)
			(size 1.8034 0.508)
			(layers "F.Cu" "F.Mask" "F.Paste")
			(net "M_A_DQ<26>")
		)
		(pad "191" smd rect
			(at 4.59994 39.099998 90)
			(size 1.8034 0.508)
			(layers "F.Cu" "F.Mask" "F.Paste")
			(net "GND")
		)
		(pad "192" smd rect
			(at 4.59994 39.949882 90)
			(size 1.8034 0.508)
			(layers "F.Cu" "F.Mask" "F.Paste")
			(net "M_A_ECC<4>")
		)
		(pad "193" smd rect
			(at 4.59994 40.80002 90)
			(size 1.8034 0.508)
			(layers "F.Cu" "F.Mask" "F.Paste")
			(net "GND")
		)
		(pad "194" smd rect
			(at 4.59994 41.649904 90)
			(size 1.8034 0.508)
			(layers "F.Cu" "F.Mask" "F.Paste")
			(net "M_A_ECC<0>")
		)
		(pad "195" smd rect
			(at 4.59994 42.500042 90)
			(size 1.8034 0.508)
			(layers "F.Cu" "F.Mask" "F.Paste")
			(net "GND")
		)
		(pad "196" smd rect
			(at 4.59994 43.349926 90)
			(size 1.8034 0.508)
			(layers "F.Cu" "F.Mask" "F.Paste")
			(net "M_A_DQS_DN<8>")
		)
		(pad "197" smd rect
			(at 4.59994 44.200064 90)
			(size 1.8034 0.508)
			(layers "F.Cu" "F.Mask" "F.Paste")
			(net "M_A_DQS_DP<8>")
		)
		(pad "198" smd rect
			(at 4.59994 45.049948 90)
			(size 1.8034 0.508)
			(layers "F.Cu" "F.Mask" "F.Paste")
			(net "GND")
		)
		(pad "199" smd rect
			(at 4.59994 45.900086 90)
			(size 1.8034 0.508)
			(layers "F.Cu" "F.Mask" "F.Paste")
			(net "M_A_ECC<6>")
		)
		(pad "200" smd rect
			(at 4.59994 46.74997 90)
			(size 1.8034 0.508)
			(layers "F.Cu" "F.Mask" "F.Paste")
			(net "GND")
		)
		(pad "201" smd rect
			(at 4.59994 47.600108 90)
			(size 1.8034 0.508)
			(layers "F.Cu" "F.Mask" "F.Paste")
			(net "M_A_ECC<2>")
		)
		(pad "202" smd rect
			(at 4.59994 48.449992 90)
			(size 1.8034 0.508)
			(layers "F.Cu" "F.Mask" "F.Paste")
			(net "GND")
		)
		(pad "203" smd rect
			(at 4.59994 49.299876 90)
			(size 1.8034 0.508)
			(layers "F.Cu" "F.Mask" "F.Paste")
			(net "M_A_CKE<1>")
		)
		(pad "204" smd rect
			(at 4.59994 50.150014 90)
			(size 1.8034 0.508)
			(layers "F.Cu" "F.Mask" "F.Paste")
			(net "PVDDQ_ABC")
		)
		(pad "205" smd rect
			(at 4.59994 50.999898 90)
			(size 1.8034 0.508)
			(layers "F.Cu" "F.Mask" "F.Paste")
			(net "TP_CH_A_DIMM_A0_RFU_0")
		)
		(pad "206" smd rect
			(at 4.59994 51.850036 90)
			(size 1.8034 0.508)
			(layers "F.Cu" "F.Mask" "F.Paste")
			(net "PVDDQ_ABC")
		)
		(pad "207" smd rect
			(at 4.59994 52.69992 90)
			(size 1.8034 0.508)
			(layers "F.Cu" "F.Mask" "F.Paste")
			(net "M_A_BG<1>")
		)
		(pad "208" smd rect
			(at 4.59994 53.550058 90)
			(size 1.8034 0.508)
			(layers "F.Cu" "F.Mask" "F.Paste")
			(net "M_A_ALERT_N")
		)
		(pad "209" smd rect
			(at 4.59994 54.399942 90)
			(size 1.8034 0.508)
			(layers "F.Cu" "F.Mask" "F.Paste")
			(net "PVDDQ_ABC")
		)
		(pad "210" smd rect
			(at 4.59994 55.25008 90)
			(size 1.8034 0.508)
			(layers "F.Cu" "F.Mask" "F.Paste")
			(net "M_A_MA<11>")
		)
		(pad "211" smd rect
			(at 4.59994 56.099964 90)
			(size 1.8034 0.508)
			(layers "F.Cu" "F.Mask" "F.Paste")
			(net "M_A_MA<7>")
		)
		(pad "212" smd rect
			(at 4.59994 56.950102 90)
			(size 1.8034 0.508)
			(layers "F.Cu" "F.Mask" "F.Paste")
			(net "PVDDQ_ABC")
		)
		(pad "213" smd rect
			(at 4.59994 57.799986 90)
			(size 1.8034 0.508)
			(layers "F.Cu" "F.Mask" "F.Paste")
			(net "M_A_MA<5>")
		)
		(pad "214" smd rect
			(at 4.59994 58.650124 90)
			(size 1.8034 0.508)
			(layers "F.Cu" "F.Mask" "F.Paste")
			(net "M_A_MA<4>")
		)
		(pad "215" smd rect
			(at 4.59994 59.500008 90)
			(size 1.8034 0.508)
			(layers "F.Cu" "F.Mask" "F.Paste")
			(net "PVDDQ_ABC")
		)
		(pad "216" smd rect
			(at 4.59994 60.349892 90)
			(size 1.8034 0.508)
			(layers "F.Cu" "F.Mask" "F.Paste")
			(net "M_A_MA<2>")
		)
		(pad "217" smd rect
			(at 4.59994 61.20003 90)
			(size 1.8034 0.508)
			(layers "F.Cu" "F.Mask" "F.Paste")
			(net "PVDDQ_ABC")
		)
		(pad "218" smd rect
			(at 4.59994 62.049914 90)
			(size 1.8034 0.508)
			(layers "F.Cu" "F.Mask" "F.Paste")
			(net "M_A_CLK_DP<1>")
		)
		(pad "219" smd rect
			(at 4.59994 62.900052 90)
			(size 1.8034 0.508)
			(layers "F.Cu" "F.Mask" "F.Paste")
			(net "M_A_CLK_DN<1>")
		)
		(pad "220" smd rect
			(at 4.59994 63.749936 90)
			(size 1.8034 0.508)
			(layers "F.Cu" "F.Mask" "F.Paste")
			(net "PVDDQ_ABC")
		)
		(pad "221" smd rect
			(at 4.59994 64.600074 90)
			(size 1.8034 0.508)
			(layers "F.Cu" "F.Mask" "F.Paste")
			(net "PVTT_ABC")
		)
		(pad "222" smd rect
			(at 4.59994 70.550024 90)
			(size 1.8034 0.508)
			(layers "F.Cu" "F.Mask" "F.Paste")
			(net "M_A_PAR")
		)
		(pad "223" smd rect
			(at 4.59994 71.399908 90)
			(size 1.8034 0.508)
			(layers "F.Cu" "F.Mask" "F.Paste")
			(net "PVDDQ_ABC")
		)
		(pad "224" smd rect
			(at 4.59994 72.250046 90)
			(size 1.8034 0.508)
			(layers "F.Cu" "F.Mask" "F.Paste")
			(net "M_A_BA<1>")
		)
		(pad "225" smd rect
			(at 4.59994 73.09993 90)
			(size 1.8034 0.508)
			(layers "F.Cu" "F.Mask" "F.Paste")
			(net "M_A_MA<10>")
		)
		(pad "226" smd rect
			(at 4.59994 73.950068 90)
			(size 1.8034 0.508)
			(layers "F.Cu" "F.Mask" "F.Paste")
			(net "PVDDQ_ABC")
		)
		(pad "227" smd rect
			(at 4.59994 74.799952 90)
			(size 1.8034 0.508)
			(layers "F.Cu" "F.Mask" "F.Paste")
			(net "TP_CH_A_DIMM_A0_RFU_1")
		)
		(pad "228" smd rect
			(at 4.59994 75.65009 90)
			(size 1.8034 0.508)
			(layers "F.Cu" "F.Mask" "F.Paste")
			(net "M_A_MA<14>")
		)
		(pad "229" smd rect
			(at 4.59994 76.499974 90)
			(size 1.8034 0.508)
			(layers "F.Cu" "F.Mask" "F.Paste")
			(net "PVDDQ_ABC")
		)
		(pad "230" smd rect
			(at 4.59994 77.350112 90)
			(size 1.8034 0.508)
			(layers "F.Cu" "F.Mask" "F.Paste")
			(net "FM_ADR_COMPLETE_ABC_N")
		)
		(pad "231" smd rect
			(at 4.59994 78.199996 90)
			(size 1.8034 0.508)
			(layers "F.Cu" "F.Mask" "F.Paste")
			(net "PVDDQ_ABC")
		)
		(pad "232" smd rect
			(at 4.59994 79.04988 90)
			(size 1.8034 0.508)
			(layers "F.Cu" "F.Mask" "F.Paste")
			(net "M_A_MA<13>")
		)
		(pad "233" smd rect
			(at 4.59994 79.900018 90)
			(size 1.8034 0.508)
			(layers "F.Cu" "F.Mask" "F.Paste")
			(net "PVDDQ_ABC")
		)
		(pad "234" smd rect
			(at 4.59994 80.749902 90)
			(size 1.8034 0.508)
			(layers "F.Cu" "F.Mask" "F.Paste")
			(net "M_A_MA<17>")
		)
		(pad "235" smd rect
			(at 4.59994 81.60004 90)
			(size 1.8034 0.508)
			(layers "F.Cu" "F.Mask" "F.Paste")
			(net "M_A_C<2>")
		)
		(pad "236" smd rect
			(at 4.59994 82.449924 90)
			(size 1.8034 0.508)
			(layers "F.Cu" "F.Mask" "F.Paste")
			(net "PVDDQ_ABC")
		)
		(pad "237" smd rect
			(at 4.59994 83.300062 90)
			(size 1.8034 0.508)
			(layers "F.Cu" "F.Mask" "F.Paste")
			(net "M_A_CS_N<3>")
		)
		(pad "238" smd rect
			(at 4.59994 84.149946 90)
			(size 1.8034 0.508)
			(layers "F.Cu" "F.Mask" "F.Paste")
			(net "GND")
		)
		(pad "239" smd rect
			(at 4.59994 85.000084 90)
			(size 1.8034 0.508)
			(layers "F.Cu" "F.Mask" "F.Paste")
			(net "GND")
		)
		(pad "240" smd rect
			(at 4.59994 85.849968 90)
			(size 1.8034 0.508)
			(layers "F.Cu" "F.Mask" "F.Paste")
			(net "M_A_DQ<36>")
		)
		(pad "241" smd rect
			(at 4.59994 86.700106 90)
			(size 1.8034 0.508)
			(layers "F.Cu" "F.Mask" "F.Paste")
			(net "GND")
		)
		(pad "242" smd rect
			(at 4.59994 87.54999 90)
			(size 1.8034 0.508)
			(layers "F.Cu" "F.Mask" "F.Paste")
			(net "M_A_DQ<32>")
		)
		(pad "243" smd rect
			(at 4.59994 88.399874 90)
			(size 1.8034 0.508)
			(layers "F.Cu" "F.Mask" "F.Paste")
			(net "GND")
		)
		(pad "244" smd rect
			(at 4.59994 89.250012 90)
			(size 1.8034 0.508)
			(layers "F.Cu" "F.Mask" "F.Paste")
			(net "M_A_DQS_DN<4>")
		)
		(pad "245" smd rect
			(at 4.59994 90.099896 90)
			(size 1.8034 0.508)
			(layers "F.Cu" "F.Mask" "F.Paste")
			(net "M_A_DQS_DP<4>")
		)
		(pad "246" smd rect
			(at 4.59994 90.950034 90)
			(size 1.8034 0.508)
			(layers "F.Cu" "F.Mask" "F.Paste")
			(net "GND")
		)
		(pad "247" smd rect
			(at 4.59994 91.799918 90)
			(size 1.8034 0.508)
			(layers "F.Cu" "F.Mask" "F.Paste")
			(net "M_A_DQ<38>")
		)
		(pad "248" smd rect
			(at 4.59994 92.650056 90)
			(size 1.8034 0.508)
			(layers "F.Cu" "F.Mask" "F.Paste")
			(net "GND")
		)
		(pad "249" smd rect
			(at 4.59994 93.49994 90)
			(size 1.8034 0.508)
			(layers "F.Cu" "F.Mask" "F.Paste")
			(net "M_A_DQ<34>")
		)
		(pad "250" smd rect
			(at 4.59994 94.350078 90)
			(size 1.8034 0.508)
			(layers "F.Cu" "F.Mask" "F.Paste")
			(net "GND")
		)
		(pad "251" smd rect
			(at 4.59994 95.199962 90)
			(size 1.8034 0.508)
			(layers "F.Cu" "F.Mask" "F.Paste")
			(net "M_A_DQ<44>")
		)
		(pad "252" smd rect
			(at 4.59994 96.0501 90)
			(size 1.8034 0.508)
			(layers "F.Cu" "F.Mask" "F.Paste")
			(net "GND")
		)
		(pad "253" smd rect
			(at 4.59994 96.899984 90)
			(size 1.8034 0.508)
			(layers "F.Cu" "F.Mask" "F.Paste")
			(net "M_A_DQ<40>")
		)
		(pad "254" smd rect
			(at 4.59994 97.750122 90)
			(size 1.8034 0.508)
			(layers "F.Cu" "F.Mask" "F.Paste")
			(net "GND")
		)
		(pad "255" smd rect
			(at 4.59994 98.600006 90)
			(size 1.8034 0.508)
			(layers "F.Cu" "F.Mask" "F.Paste")
			(net "M_A_DQS_DN<5>")
		)
		(pad "256" smd rect
			(at 4.59994 99.44989 90)
			(size 1.8034 0.508)
			(layers "F.Cu" "F.Mask" "F.Paste")
			(net "M_A_DQS_DP<5>")
		)
		(pad "257" smd rect
			(at 4.59994 100.300028 90)
			(size 1.8034 0.508)
			(layers "F.Cu" "F.Mask" "F.Paste")
			(net "GND")
		)
		(pad "258" smd rect
			(at 4.59994 101.149912 90)
			(size 1.8034 0.508)
			(layers "F.Cu" "F.Mask" "F.Paste")
			(net "M_A_DQ<46>")
		)
		(pad "259" smd rect
			(at 4.59994 102.00005 90)
			(size 1.8034 0.508)
			(layers "F.Cu" "F.Mask" "F.Paste")
			(net "GND")
		)
		(pad "260" smd rect
			(at 4.59994 102.849934 90)
			(size 1.8034 0.508)
			(layers "F.Cu" "F.Mask" "F.Paste")
			(net "M_A_DQ<42>")
		)
		(pad "261" smd rect
			(at 4.59994 103.700072 90)
			(size 1.8034 0.508)
			(layers "F.Cu" "F.Mask" "F.Paste")
			(net "GND")
		)
		(pad "262" smd rect
			(at 4.59994 104.549956 90)
			(size 1.8034 0.508)
			(layers "F.Cu" "F.Mask" "F.Paste")
			(net "M_A_DQ<52>")
		)
		(pad "263" smd rect
			(at 4.59994 105.400094 90)
			(size 1.8034 0.508)
			(layers "F.Cu" "F.Mask" "F.Paste")
			(net "GND")
		)
		(pad "264" smd rect
			(at 4.59994 106.249978 90)
			(size 1.8034 0.508)
			(layers "F.Cu" "F.Mask" "F.Paste")
			(net "M_A_DQ<48>")
		)
		(pad "265" smd rect
			(at 4.59994 107.100116 90)
			(size 1.8034 0.508)
			(layers "F.Cu" "F.Mask" "F.Paste")
			(net "GND")
		)
		(pad "266" smd rect
			(at 4.59994 107.95 90)
			(size 1.8034 0.508)
			(layers "F.Cu" "F.Mask" "F.Paste")
			(net "M_A_DQS_DN<6>")
		)
		(pad "267" smd rect
			(at 4.59994 108.799884 90)
			(size 1.8034 0.508)
			(layers "F.Cu" "F.Mask" "F.Paste")
			(net "M_A_DQS_DP<6>")
		)
		(pad "268" smd rect
			(at 4.59994 109.650022 90)
			(size 1.8034 0.508)
			(layers "F.Cu" "F.Mask" "F.Paste")
			(net "GND")
		)
		(pad "269" smd rect
			(at 4.59994 110.499906 90)
			(size 1.8034 0.508)
			(layers "F.Cu" "F.Mask" "F.Paste")
			(net "M_A_DQ<54>")
		)
		(pad "270" smd rect
			(at 4.59994 111.350044 90)
			(size 1.8034 0.508)
			(layers "F.Cu" "F.Mask" "F.Paste")
			(net "GND")
		)
		(pad "271" smd rect
			(at 4.59994 112.199928 90)
			(size 1.8034 0.508)
			(layers "F.Cu" "F.Mask" "F.Paste")
			(net "M_A_DQ<50>")
		)
		(pad "272" smd rect
			(at 4.59994 113.050066 90)
			(size 1.8034 0.508)
			(layers "F.Cu" "F.Mask" "F.Paste")
			(net "GND")
		)
		(pad "273" smd rect
			(at 4.59994 113.89995 90)
			(size 1.8034 0.508)
			(layers "F.Cu" "F.Mask" "F.Paste")
			(net "M_A_DQ<60>")
		)
		(pad "274" smd rect
			(at 4.59994 114.750088 90)
			(size 1.8034 0.508)
			(layers "F.Cu" "F.Mask" "F.Paste")
			(net "GND")
		)
		(pad "275" smd rect
			(at 4.59994 115.599972 90)
			(size 1.8034 0.508)
			(layers "F.Cu" "F.Mask" "F.Paste")
			(net "M_A_DQ<56>")
		)
		(pad "276" smd rect
			(at 4.59994 116.45011 90)
			(size 1.8034 0.508)
			(layers "F.Cu" "F.Mask" "F.Paste")
			(net "GND")
		)
		(pad "277" smd rect
			(at 4.59994 117.299994 90)
			(size 1.8034 0.508)
			(layers "F.Cu" "F.Mask" "F.Paste")
			(net "M_A_DQS_DN<7>")
		)
		(pad "278" smd rect
			(at 4.59994 118.149878 90)
			(size 1.8034 0.508)
			(layers "F.Cu" "F.Mask" "F.Paste")
			(net "M_A_DQS_DP<7>")
		)
		(pad "279" smd rect
			(at 4.59994 119.000016 90)
			(size 1.8034 0.508)
			(layers "F.Cu" "F.Mask" "F.Paste")
			(net "GND")
		)
		(pad "280" smd rect
			(at 4.59994 119.8499 90)
			(size 1.8034 0.508)
			(layers "F.Cu" "F.Mask" "F.Paste")
			(net "M_A_DQ<62>")
		)
		(pad "281" smd rect
			(at 4.59994 120.700038 90)
			(size 1.8034 0.508)
			(layers "F.Cu" "F.Mask" "F.Paste")
			(net "GND")
		)
		(pad "282" smd rect
			(at 4.59994 121.549922 90)
			(size 1.8034 0.508)
			(layers "F.Cu" "F.Mask" "F.Paste")
			(net "M_A_DQ<58>")
		)
		(pad "283" smd rect
			(at 4.59994 122.40006 90)
			(size 1.8034 0.508)
			(layers "F.Cu" "F.Mask" "F.Paste")
			(net "GND")
		)
		(pad "284" smd rect
			(at 4.59994 123.249944 90)
			(size 1.8034 0.508)
			(layers "F.Cu" "F.Mask" "F.Paste")
			(net "PVPP_ABC")
		)
		(pad "285" smd rect
			(at 4.59994 124.100082 90)
			(size 1.8034 0.508)
			(layers "F.Cu" "F.Mask" "F.Paste")
			(net "SMB_DDR_ABC_VPP_SDA")
		)
		(pad "286" smd rect
			(at 4.59994 124.949966 90)
			(size 1.8034 0.508)
			(layers "F.Cu" "F.Mask" "F.Paste")
			(net "PVPP_ABC")
		)
		(pad "287" smd rect
			(at 4.59994 125.800104 90)
			(size 1.8034 0.508)
			(layers "F.Cu" "F.Mask" "F.Paste")
			(net "PVPP_ABC")
		)
		(pad "288" smd rect
			(at 4.59994 126.649988 90)
			(size 1.8034 0.508)
			(layers "F.Cu" "F.Mask" "F.Paste")
			(net "PVPP_ABC")
		)
	)
	(footprint ""
		(layer "F.Cu")
		(at 354.27412 -98.730054 90)
		(property "Reference" "CT71"
			(at -0.53467 1.8288 0)
			(unlocked yes)
			(layer "F.SilkS")
			(effects
				(font
					(size 0.7874 0.5842)
					(thickness 0.1524)
				)
				(justify left)
			)
		)
		(property "Value" ""
			(at 0 0 90)
			(layer "F.Fab")
			(effects
				(font
					(size 1.27 1.27)
				)
			)
		)
		(duplicate_pad_numbers_are_jumpers no)
		(fp_poly
			(pts
				(xy 0.3048 -0.1016) (xy 0.3048 0.9906) (xy -0.3048 0.9906) (xy -0.3048 -0.1016)
			)
			(stroke
				(width 0)
				(type default)
			)
			(fill no)
			(layer "F.CrtYd")
		)
		(fp_line
			(start 0.3048 -0.1016)
			(end -0.3048 -0.1016)
			(stroke
				(width 0.1)
				(type default)
			)
			(layer "F.Fab")
		)
		(fp_line
			(start -0.3048 -0.1016)
			(end -0.3048 0.9906)
			(stroke
				(width 0.1)
				(type default)
			)
			(layer "F.Fab")
		)
		(fp_line
			(start 0.3048 0.9906)
			(end 0.3048 -0.1016)
			(stroke
				(width 0.1)
				(type default)
			)
			(layer "F.Fab")
		)
		(fp_line
			(start -0.3048 0.9906)
			(end 0.3048 0.9906)
			(stroke
				(width 0.1)
				(type default)
			)
			(layer "F.Fab")
		)
		(pad "1" smd rect
			(at 0 0 90)
			(size 0.508 0.508)
			(layers "F.Cu" "F.Mask" "F.Paste")
			(net "A_TSENSE_PVCCIO_CPU0")
		)
		(pad "2" smd rect
			(at 0 0.889 90)
			(size 0.508 0.508)
			(layers "F.Cu" "F.Mask" "F.Paste")
			(net "GND")
		)
		(zone
			(layer "F.Cu")
			(hatch none 0.5)
			(connect_pads
				(clearance 0)
			)
			(min_thickness 0.25)
			(keepout
				(tracks allowed)
				(vias not_allowed)
				(pads allowed)
				(copperpour not_allowed)
				(footprints allowed)
			)
			(placement
				(enabled no)
				(sheetname "")
			)
			(fill
				(thermal_gap 0.5)
				(thermal_bridge_width 0.5)
				(island_removal_mode 0)
			)
			(polygon
				(pts
					(xy 354.52812 -98.476054) (xy 354.52812 -98.984054) (xy 354.90912 -98.984054) (xy 354.90912 -98.476054)
				)
			)
		)
		(zone
			(layer "F.Cu")
			(hatch none 0.5)
			(connect_pads
				(clearance 0)
			)
			(min_thickness 0.25)
			(keepout
				(tracks not_allowed)
				(vias allowed)
				(pads allowed)
				(copperpour not_allowed)
				(footprints allowed)
			)
			(placement
				(enabled no)
				(sheetname "")
			)
			(fill
				(thermal_gap 0.5)
				(thermal_bridge_width 0.5)
				(island_removal_mode 0)
			)
			(polygon
				(pts
					(xy 354.90912 -98.476054) (xy 354.90912 -98.984054) (xy 354.52812 -98.984054) (xy 354.52812 -98.476054)
				)
			)
		)
	)
	(footprint ""
		(layer "F.Cu")
		(at 412.4452 -115.230402 90)
		(property "Reference" "R2M8"
			(at 0 0 90)
			(layer "F.SilkS")
			(hide yes)
			(effects
				(font
					(size 1.27 1.27)
				)
			)
		)
		(property "Value" ""
			(at 0 0 90)
			(layer "F.Fab")
			(effects
				(font
					(size 1.27 1.27)
				)
			)
		)
		(duplicate_pad_numbers_are_jumpers no)
		(fp_poly
			(pts
				(xy -0.2794 -0.1016) (xy 0.2794 -0.1016) (xy 0.2794 0.9906) (xy -0.2794 0.9906)
			)
			(stroke
				(width 0)
				(type default)
			)
			(fill no)
			(layer "F.CrtYd")
		)
		(fp_line
			(start 0.2794 -0.1016)
			(end -0.2794 -0.1016)
			(stroke
				(width 0.1)
				(type default)
			)
			(layer "F.Fab")
		)
		(fp_line
			(start -0.2794 -0.1016)
			(end -0.2794 0.9906)
			(stroke
				(width 0.1)
				(type default)
			)
			(layer "F.Fab")
		)
		(fp_line
			(start 0.2794 0.9906)
			(end 0.2794 -0.1016)
			(stroke
				(width 0.1)
				(type default)
			)
			(layer "F.Fab")
		)
		(fp_line
			(start -0.2794 0.9906)
			(end 0.2794 0.9906)
			(stroke
				(width 0.1)
				(type default)
			)
			(layer "F.Fab")
		)
		(pad "1" smd rect
			(at 0 0 90)
			(size 0.508 0.508)
			(layers "F.Cu" "F.Mask" "F.Paste")
			(net "P3V3_STBY")
		)
		(pad "2" smd rect
			(at 0 0.889 90)
			(size 0.508 0.508)
			(layers "F.Cu" "F.Mask" "F.Paste")
			(net "FM_CPU0_RC_ERROR_N")
		)
		(zone
			(layer "F.Cu")
			(hatch none 0.5)
			(connect_pads
				(clearance 0)
			)
			(min_thickness 0.25)
			(keepout
				(tracks allowed)
				(vias not_allowed)
				(pads allowed)
				(copperpour not_allowed)
				(footprints allowed)
			)
			(placement
				(enabled no)
				(sheetname "")
			)
			(fill
				(thermal_gap 0.5)
				(thermal_bridge_width 0.5)
				(island_removal_mode 0)
			)
			(polygon
				(pts
					(xy 412.6992 -114.976402) (xy 412.6992 -115.484402) (xy 413.0802 -115.484402) (xy 413.0802 -114.976402)
				)
			)
		)
		(zone
			(layer "F.Cu")
			(hatch none 0.5)
			(connect_pads
				(clearance 0)
			)
			(min_thickness 0.25)
			(keepout
				(tracks not_allowed)
				(vias allowed)
				(pads allowed)
				(copperpour not_allowed)
				(footprints allowed)
			)
			(placement
				(enabled no)
				(sheetname "")
			)
			(fill
				(thermal_gap 0.5)
				(thermal_bridge_width 0.5)
				(island_removal_mode 0)
			)
			(polygon
				(pts
					(xy 413.0802 -114.976402) (xy 413.0802 -115.484402) (xy 412.6992 -115.484402) (xy 412.6992 -114.976402)
				)
			)
		)
	)
	(footprint ""
		(layer "F.Cu")
		(at 24.6888 -66.6242 -90)
		(property "Reference" "R1D48"
			(at 0 0 270)
			(layer "F.SilkS")
			(hide yes)
			(effects
				(font
					(size 1.27 1.27)
				)
			)
		)
		(property "Value" ""
			(at 0 0 270)
			(layer "F.Fab")
			(effects
				(font
					(size 1.27 1.27)
				)
			)
		)
		(duplicate_pad_numbers_are_jumpers no)
		(fp_rect
			(start 0.2794 -0.1016)
			(end -0.2794 0.9906)
			(stroke
				(width 0)
				(type default)
			)
			(fill no)
			(layer "F.CrtYd")
		)
		(fp_line
			(start -0.2794 0.9906)
			(end 0.2794 0.9906)
			(stroke
				(width 0.1)
				(type default)
			)
			(layer "F.Fab")
		)
		(fp_line
			(start 0.2794 0.9906)
			(end 0.2794 -0.1016)
			(stroke
				(width 0.1)
				(type default)
			)
			(layer "F.Fab")
		)
		(fp_line
			(start -0.2794 -0.1016)
			(end -0.2794 0.9906)
			(stroke
				(width 0.1)
				(type default)
			)
			(layer "F.Fab")
		)
		(fp_line
			(start 0.2794 -0.1016)
			(end -0.2794 -0.1016)
			(stroke
				(width 0.1)
				(type default)
			)
			(layer "F.Fab")
		)
		(pad "1" smd rect
			(at 0 0 270)
			(size 0.508 0.508)
			(layers "F.Cu" "F.Mask" "F.Paste")
			(net "A_HSC_GATE")
		)
		(pad "2" smd rect
			(at 0 0.889 270)
			(size 0.508 0.508)
			(layers "F.Cu" "F.Mask" "F.Paste")
			(net "A_HSC_GATE3_R")
		)
		(zone
			(layer "F.Cu")
			(hatch none 0.5)
			(connect_pads
				(clearance 0)
			)
			(min_thickness 0.25)
			(keepout
				(tracks allowed)
				(vias not_allowed)
				(pads allowed)
				(copperpour not_allowed)
				(footprints allowed)
			)
			(placement
				(enabled no)
				(sheetname "")
			)
			(fill
				(thermal_gap 0.5)
				(thermal_bridge_width 0.5)
				(island_removal_mode 0)
			)
			(polygon
				(pts
					(xy 24.4348 -66.3702) (xy 24.4348 -66.8782) (xy 24.0538 -66.8782) (xy 24.0538 -66.3702)
				)
			)
		)
		(zone
			(layer "F.Cu")
			(hatch none 0.5)
			(connect_pads
				(clearance 0)
			)
			(min_thickness 0.25)
			(keepout
				(tracks not_allowed)
				(vias allowed)
				(pads allowed)
				(copperpour not_allowed)
				(footprints allowed)
			)
			(placement
				(enabled no)
				(sheetname "")
			)
			(fill
				(thermal_gap 0.5)
				(thermal_bridge_width 0.5)
				(island_removal_mode 0)
			)
			(polygon
				(pts
					(xy 24.4348 -66.3702) (xy 24.4348 -66.8782) (xy 24.0538 -66.8782) (xy 24.0538 -66.3702)
				)
			)
		)
	)
	(footprint ""
		(layer "F.Cu")
		(at 374.015 -88.2015)
		(property "Reference" "R2R11"
			(at 0 0 0)
			(layer "F.SilkS")
			(hide yes)
			(effects
				(font
					(size 1.27 1.27)
				)
			)
		)
		(property "Value" ""
			(at 0 0 0)
			(layer "F.Fab")
			(effects
				(font
					(size 1.27 1.27)
				)
			)
		)
		(duplicate_pad_numbers_are_jumpers no)
		(fp_poly
			(pts
				(xy -0.2794 -0.1016) (xy 0.2794 -0.1016) (xy 0.2794 0.9906) (xy -0.2794 0.9906)
			)
			(stroke
				(width 0)
				(type default)
			)
			(fill no)
			(layer "F.CrtYd")
		)
		(fp_line
			(start -0.2794 -0.1016)
			(end -0.2794 0.9906)
			(stroke
				(width 0.1)
				(type default)
			)
			(layer "F.Fab")
		)
		(fp_line
			(start -0.2794 0.9906)
			(end 0.2794 0.9906)
			(stroke
				(width 0.1)
				(type default)
			)
			(layer "F.Fab")
		)
		(fp_line
			(start 0.2794 -0.1016)
			(end -0.2794 -0.1016)
			(stroke
				(width 0.1)
				(type default)
			)
			(layer "F.Fab")
		)
		(fp_line
			(start 0.2794 0.9906)
			(end 0.2794 -0.1016)
			(stroke
				(width 0.1)
				(type default)
			)
			(layer "F.Fab")
		)
		(pad "1" smd rect
			(at 0 0)
			(size 0.508 0.508)
			(layers "F.Cu" "F.Mask" "F.Paste")
			(net "SPI_PCH_IO2")
		)
		(pad "2" smd rect
			(at 0 0.889)
			(size 0.508 0.508)
			(layers "F.Cu" "F.Mask" "F.Paste")
			(net "GND")
		)
		(zone
			(layer "F.Cu")
			(hatch none 0.5)
			(connect_pads
				(clearance 0)
			)
			(min_thickness 0.25)
			(keepout
				(tracks allowed)
				(vias not_allowed)
				(pads allowed)
				(copperpour not_allowed)
				(footprints allowed)
			)
			(placement
				(enabled no)
				(sheetname "")
			)
			(fill
				(thermal_gap 0.5)
				(thermal_bridge_width 0.5)
				(island_removal_mode 0)
			)
			(polygon
				(pts
					(xy 373.761 -87.9475) (xy 374.269 -87.9475) (xy 374.269 -87.5665) (xy 373.761 -87.5665)
				)
			)
		)
		(zone
			(layer "F.Cu")
			(hatch none 0.5)
			(connect_pads
				(clearance 0)
			)
			(min_thickness 0.25)
			(keepout
				(tracks not_allowed)
				(vias allowed)
				(pads allowed)
				(copperpour not_allowed)
				(footprints allowed)
			)
			(placement
				(enabled no)
				(sheetname "")
			)
			(fill
				(thermal_gap 0.5)
				(thermal_bridge_width 0.5)
				(island_removal_mode 0)
			)
			(polygon
				(pts
					(xy 373.761 -87.5665) (xy 374.269 -87.5665) (xy 374.269 -87.9475) (xy 373.761 -87.9475)
				)
			)
		)
	)
	(footprint ""
		(layer "F.Cu")
		(at 2.794 -69.088 180)
		(property "Reference" "R1E9"
			(at 0 0 180)
			(layer "F.SilkS")
			(hide yes)
			(effects
				(font
					(size 1.27 1.27)
				)
			)
		)
		(property "Value" ""
			(at 0 0 180)
			(layer "F.Fab")
			(effects
				(font
					(size 1.27 1.27)
				)
			)
		)
		(duplicate_pad_numbers_are_jumpers no)
		(fp_poly
			(pts
				(xy -0.2794 -0.1016) (xy 0.2794 -0.1016) (xy 0.2794 0.9906) (xy -0.2794 0.9906)
			)
			(stroke
				(width 0)
				(type default)
			)
			(fill no)
			(layer "F.CrtYd")
		)
		(fp_line
			(start 0.2794 0.9906)
			(end 0.2794 -0.1016)
			(stroke
				(width 0.1)
				(type default)
			)
			(layer "F.Fab")
		)
		(fp_line
			(start 0.2794 -0.1016)
			(end -0.2794 -0.1016)
			(stroke
				(width 0.1)
				(type default)
			)
			(layer "F.Fab")
		)
		(fp_line
			(start -0.2794 0.9906)
			(end 0.2794 0.9906)
			(stroke
				(width 0.1)
				(type default)
			)
			(layer "F.Fab")
		)
		(fp_line
			(start -0.2794 -0.1016)
			(end -0.2794 0.9906)
			(stroke
				(width 0.1)
				(type default)
			)
			(layer "F.Fab")
		)
		(pad "1" smd rect
			(at 0 0 180)
			(size 0.508 0.508)
			(layers "F.Cu" "F.Mask" "F.Paste")
			(net "P3V3_STBY")
		)
		(pad "2" smd rect
			(at 0 0.889 180)
			(size 0.508 0.508)
			(layers "F.Cu" "F.Mask" "F.Paste")
			(net "PU_TMP421_2_A0")
		)
		(zone
			(layer "F.Cu")
			(hatch none 0.5)
			(connect_pads
				(clearance 0)
			)
			(min_thickness 0.25)
			(keepout
				(tracks not_allowed)
				(vias allowed)
				(pads allowed)
				(copperpour not_allowed)
				(footprints allowed)
			)
			(placement
				(enabled no)
				(sheetname "")
			)
			(fill
				(thermal_gap 0.5)
				(thermal_bridge_width 0.5)
				(island_removal_mode 0)
			)
			(polygon
				(pts
					(xy 3.048 -69.723) (xy 2.54 -69.723) (xy 2.54 -69.342) (xy 3.048 -69.342)
				)
			)
		)
		(zone
			(layer "F.Cu")
			(hatch none 0.5)
			(connect_pads
				(clearance 0)
			)
			(min_thickness 0.25)
			(keepout
				(tracks allowed)
				(vias not_allowed)
				(pads allowed)
				(copperpour not_allowed)
				(footprints allowed)
			)
			(placement
				(enabled no)
				(sheetname "")
			)
			(fill
				(thermal_gap 0.5)
				(thermal_bridge_width 0.5)
				(island_removal_mode 0)
			)
			(polygon
				(pts
					(xy 3.048 -69.342) (xy 2.54 -69.342) (xy 2.54 -69.723) (xy 3.048 -69.723)
				)
			)
		)
	)
	(footprint ""
		(layer "F.Cu")
		(at 422.744646 -48.968152)
		(property "Reference" "R25W102"
			(at -0.8382 -0.67818 0)
			(unlocked yes)
			(layer "F.SilkS")
			(effects
				(font
					(size 0.4064 0.254)
					(thickness 0.1524)
				)
				(justify left)
			)
		)
		(property "Value" ""
			(at 0 0 0)
			(layer "F.Fab")
			(effects
				(font
					(size 1.27 1.27)
				)
			)
		)
		(duplicate_pad_numbers_are_jumpers no)
		(fp_poly
			(pts
				(xy -0.2794 -0.1016) (xy 0.2794 -0.1016) (xy 0.2794 0.9906) (xy -0.2794 0.9906)
			)
			(stroke
				(width 0)
				(type default)
			)
			(fill no)
			(layer "F.CrtYd")
		)
		(fp_line
			(start -0.2794 -0.1016)
			(end -0.2794 0.9906)
			(stroke
				(width 0.1)
				(type default)
			)
			(layer "F.Fab")
		)
		(fp_line
			(start -0.2794 0.9906)
			(end 0.2794 0.9906)
			(stroke
				(width 0.1)
				(type default)
			)
			(layer "F.Fab")
		)
		(fp_line
			(start 0.2794 -0.1016)
			(end -0.2794 -0.1016)
			(stroke
				(width 0.1)
				(type default)
			)
			(layer "F.Fab")
		)
		(fp_line
			(start 0.2794 0.9906)
			(end 0.2794 -0.1016)
			(stroke
				(width 0.1)
				(type default)
			)
			(layer "F.Fab")
		)
		(pad "1" smd rect
			(at 0 0)
			(size 0.508 0.508)
			(layers "F.Cu" "F.Mask" "F.Paste")
			(net "P3V3_STBY")
		)
		(pad "2" smd rect
			(at 0 0.889)
			(size 0.508 0.508)
			(layers "F.Cu" "F.Mask" "F.Paste")
			(net "BMC_STRAP_BIT18")
		)
		(zone
			(layer "F.Cu")
			(hatch none 0.5)
			(connect_pads
				(clearance 0)
			)
			(min_thickness 0.25)
			(keepout
				(tracks allowed)
				(vias not_allowed)
				(pads allowed)
				(copperpour not_allowed)
				(footprints allowed)
			)
			(placement
				(enabled no)
				(sheetname "")
			)
			(fill
				(thermal_gap 0.5)
				(thermal_bridge_width 0.5)
				(island_removal_mode 0)
			)
			(polygon
				(pts
					(xy 422.490646 -48.714152) (xy 422.998646 -48.714152) (xy 422.998646 -48.333152) (xy 422.490646 -48.333152)
				)
			)
		)
		(zone
			(layer "F.Cu")
			(hatch none 0.5)
			(connect_pads
				(clearance 0)
			)
			(min_thickness 0.25)
			(keepout
				(tracks not_allowed)
				(vias allowed)
				(pads allowed)
				(copperpour not_allowed)
				(footprints allowed)
			)
			(placement
				(enabled no)
				(sheetname "")
			)
			(fill
				(thermal_gap 0.5)
				(thermal_bridge_width 0.5)
				(island_removal_mode 0)
			)
			(polygon
				(pts
					(xy 422.490646 -48.333152) (xy 422.998646 -48.333152) (xy 422.998646 -48.714152) (xy 422.490646 -48.714152)
				)
			)
		)
	)
	(footprint ""
		(layer "F.Cu")
		(at 25.521158 -102.40772 -90)
		(property "Reference" "C1C2"
			(at 4.445 -1.55067 90)
			(unlocked yes)
			(layer "F.SilkS")
			(effects
				(font
					(size 0.7874 0.5842)
					(thickness 0.1524)
				)
				(justify left)
			)
		)
		(property "Value" ""
			(at 0 0 270)
			(layer "F.Fab")
			(effects
				(font
					(size 1.27 1.27)
				)
			)
		)
		(duplicate_pad_numbers_are_jumpers no)
		(fp_line
			(start -3.400044 6.067044)
			(end -0.9017 6.067044)
			(stroke
				(width 0.1524)
				(type default)
			)
			(layer "F.SilkS")
		)
		(fp_line
			(start 0.9017 6.067044)
			(end 3.400044 6.067044)
			(stroke
				(width 0.1524)
				(type default)
			)
			(layer "F.SilkS")
		)
		(fp_line
			(start 3.400044 6.067044)
			(end 3.400044 0.028956)
			(stroke
				(width 0.1524)
				(type default)
			)
			(layer "F.SilkS")
		)
		(fp_line
			(start -0.9017 1.587754)
			(end -0.7239 1.587754)
			(stroke
				(width 0.1524)
				(type default)
			)
			(layer "F.SilkS")
		)
		(fp_line
			(start 0.7239 1.587754)
			(end 0.9017 1.587754)
			(stroke
				(width 0.1524)
				(type default)
			)
			(layer "F.SilkS")
		)
		(fp_line
			(start 0.9017 1.587754)
			(end 0.9017 -1.714246)
			(stroke
				(width 0.1524)
				(type default)
			)
			(layer "F.SilkS")
		)
		(fp_line
			(start -3.400044 0.028956)
			(end -3.400044 6.067044)
			(stroke
				(width 0.1524)
				(type default)
			)
			(layer "F.SilkS")
		)
		(fp_line
			(start 3.400044 0.028956)
			(end 2.638044 -0.733044)
			(stroke
				(width 0.1524)
				(type default)
			)
			(layer "F.SilkS")
		)
		(fp_line
			(start -2.638044 -0.733044)
			(end -3.400044 0.028956)
			(stroke
				(width 0.1524)
				(type default)
			)
			(layer "F.SilkS")
		)
		(fp_line
			(start -0.9017 -0.733044)
			(end -2.638044 -0.733044)
			(stroke
				(width 0.1524)
				(type default)
			)
			(layer "F.SilkS")
		)
		(fp_line
			(start 2.638044 -0.733044)
			(end 0.9017 -0.733044)
			(stroke
				(width 0.1524)
				(type default)
			)
			(layer "F.SilkS")
		)
		(fp_line
			(start -0.9017 -1.714246)
			(end -0.9017 1.587754)
			(stroke
				(width 0.1524)
				(type default)
			)
			(layer "F.SilkS")
		)
		(fp_line
			(start -0.7239 -1.714246)
			(end -0.9017 -1.714246)
			(stroke
				(width 0.1524)
				(type default)
			)
			(layer "F.SilkS")
		)
		(fp_line
			(start 0.9017 -1.714246)
			(end 0.7239 -1.714246)
			(stroke
				(width 0.1524)
				(type default)
			)
			(layer "F.SilkS")
		)
		(fp_poly
			(pts
				(xy -3.400044 6.067044) (xy 3.400044 6.067044) (xy 3.400044 0.028956) (xy 2.638044 -0.733044) (xy -2.638044 -0.733044)
				(xy -3.400044 0.028956)
			)
			(stroke
				(width 0)
				(type default)
			)
			(fill no)
			(layer "F.CrtYd")
		)
		(fp_line
			(start -3.400044 6.067044)
			(end 3.400044 6.067044)
			(stroke
				(width 0.1)
				(type default)
			)
			(layer "F.Fab")
		)
		(fp_line
			(start 3.400044 6.067044)
			(end 3.400044 0.028956)
			(stroke
				(width 0.1)
				(type default)
			)
			(layer "F.Fab")
		)
		(fp_line
			(start -3.400044 0.028956)
			(end -3.400044 6.067044)
			(stroke
				(width 0.1)
				(type default)
			)
			(layer "F.Fab")
		)
		(fp_line
			(start 3.400044 0.028956)
			(end 2.638044 -0.733044)
			(stroke
				(width 0.1)
				(type default)
			)
			(layer "F.Fab")
		)
		(fp_line
			(start -2.638044 -0.733044)
			(end -3.400044 0.028956)
			(stroke
				(width 0.1)
				(type default)
			)
			(layer "F.Fab")
		)
		(fp_line
			(start 2.638044 -0.733044)
			(end -2.638044 -0.733044)
			(stroke
				(width 0.1)
				(type default)
			)
			(layer "F.Fab")
		)
		(fp_circle
			(center 0 2.667)
			(end 0 -0.733044)
			(stroke
				(width 0.1)
				(type default)
			)
			(fill no)
			(layer "F.Fab")
		)
		(pad "1" smd rect
			(at 0 0 270)
			(size 0.7874 3.429)
			(layers "F.Cu" "F.Mask" "F.Paste")
			(net "VR_FET_SW_P12V_STBY_PVCCIN_CPU1")
		)
		(pad "2" smd rect
			(at 0 5.334 270)
			(size 0.7874 3.429)
			(layers "F.Cu" "F.Mask" "F.Paste")
			(net "GND")
		)
	)
	(footprint ""
		(layer "F.Cu")
		(at 13.8938 -24.13 90)
		(property "Reference" "C1F18"
			(at 0 0 90)
			(layer "F.SilkS")
			(hide yes)
			(effects
				(font
					(size 1.27 1.27)
				)
			)
		)
		(property "Value" ""
			(at 0 0 90)
			(layer "F.Fab")
			(effects
				(font
					(size 1.27 1.27)
				)
			)
		)
		(duplicate_pad_numbers_are_jumpers no)
		(fp_rect
			(start -0.3048 -0.1016)
			(end 0.3048 0.9906)
			(stroke
				(width 0)
				(type default)
			)
			(fill no)
			(layer "F.CrtYd")
		)
		(fp_line
			(start 0.3048 -0.1016)
			(end -0.3048 -0.1016)
			(stroke
				(width 0.1)
				(type default)
			)
			(layer "F.Fab")
		)
		(fp_line
			(start -0.3048 -0.1016)
			(end -0.3048 0.9906)
			(stroke
				(width 0.1)
				(type default)
			)
			(layer "F.Fab")
		)
		(fp_line
			(start 0.3048 0.9906)
			(end 0.3048 -0.1016)
			(stroke
				(width 0.1)
				(type default)
			)
			(layer "F.Fab")
		)
		(fp_line
			(start -0.3048 0.9906)
			(end 0.3048 0.9906)
			(stroke
				(width 0.1)
				(type default)
			)
			(layer "F.Fab")
		)
		(pad "1" smd rect
			(at 0 0 90)
			(size 0.508 0.508)
			(layers "F.Cu" "F.Mask" "F.Paste")
			(net "P3E_CPU1_PE3_MP_C_TXP<0>")
		)
		(pad "2" smd rect
			(at 0 0.889 90)
			(size 0.508 0.508)
			(layers "F.Cu" "F.Mask" "F.Paste")
			(net "P3E_CPU1_PE3_MP_TXP<0>")
		)
		(zone
			(layer "F.Cu")
			(hatch none 0.5)
			(connect_pads
				(clearance 0)
			)
			(min_thickness 0.25)
			(keepout
				(tracks allowed)
				(vias not_allowed)
				(pads allowed)
				(copperpour not_allowed)
				(footprints allowed)
			)
			(placement
				(enabled no)
				(sheetname "")
			)
			(fill
				(thermal_gap 0.5)
				(thermal_bridge_width 0.5)
				(island_removal_mode 0)
			)
			(polygon
				(pts
					(xy 14.1478 -23.876) (xy 14.5288 -23.876) (xy 14.5288 -24.384) (xy 14.1478 -24.384)
				)
			)
		)
		(zone
			(layer "F.Cu")
			(hatch none 0.5)
			(connect_pads
				(clearance 0)
			)
			(min_thickness 0.25)
			(keepout
				(tracks not_allowed)
				(vias allowed)
				(pads allowed)
				(copperpour not_allowed)
				(footprints allowed)
			)
			(placement
				(enabled no)
				(sheetname "")
			)
			(fill
				(thermal_gap 0.5)
				(thermal_bridge_width 0.5)
				(island_removal_mode 0)
			)
			(polygon
				(pts
					(xy 14.1478 -23.876) (xy 14.5288 -23.876) (xy 14.5288 -24.384) (xy 14.1478 -24.384)
				)
			)
		)
	)
	(footprint ""
		(layer "F.Cu")
		(at 378.926344 -10.941558)
		(property "Reference" "C7G20"
			(at 0 0 0)
			(layer "F.SilkS")
			(hide yes)
			(effects
				(font
					(size 1.27 1.27)
				)
			)
		)
		(property "Value" ""
			(at 0 0 0)
			(layer "F.Fab")
			(effects
				(font
					(size 1.27 1.27)
				)
			)
		)
		(duplicate_pad_numbers_are_jumpers no)
		(fp_rect
			(start -0.3048 0.9906)
			(end 0.3048 -0.1016)
			(stroke
				(width 0)
				(type default)
			)
			(fill no)
			(layer "F.CrtYd")
		)
		(fp_line
			(start -0.3048 -0.1016)
			(end -0.3048 0.9906)
			(stroke
				(width 0.1)
				(type default)
			)
			(layer "F.Fab")
		)
		(fp_line
			(start -0.3048 0.9906)
			(end 0.3048 0.9906)
			(stroke
				(width 0.1)
				(type default)
			)
			(layer "F.Fab")
		)
		(fp_line
			(start 0.3048 -0.1016)
			(end -0.3048 -0.1016)
			(stroke
				(width 0.1)
				(type default)
			)
			(layer "F.Fab")
		)
		(fp_line
			(start 0.3048 0.9906)
			(end 0.3048 -0.1016)
			(stroke
				(width 0.1)
				(type default)
			)
			(layer "F.Fab")
		)
		(pad "1" smd rect
			(at 0 0)
			(size 0.508 0.508)
			(layers "F.Cu" "F.Mask" "F.Paste")
			(net "P3E_CPU0_PE2_SS_TXP<8>")
		)
		(pad "2" smd rect
			(at 0 0.889)
			(size 0.508 0.508)
			(layers "F.Cu" "F.Mask" "F.Paste")
			(net "P3E_CPU0_PE2_SS_C_TXP<8>")
		)
		(zone
			(layer "F.Cu")
			(hatch none 0.5)
			(connect_pads
				(clearance 0)
			)
			(min_thickness 0.25)
			(keepout
				(tracks allowed)
				(vias not_allowed)
				(pads allowed)
				(copperpour not_allowed)
				(footprints allowed)
			)
			(placement
				(enabled no)
				(sheetname "")
			)
			(fill
				(thermal_gap 0.5)
				(thermal_bridge_width 0.5)
				(island_removal_mode 0)
			)
			(polygon
				(pts
					(xy 378.672344 -10.306558) (xy 379.180344 -10.306558) (xy 379.180344 -10.687558) (xy 378.672344 -10.687558)
				)
			)
		)
	)
	(footprint ""
		(layer "F.Cu")
		(at 452.247 -28.7655)
		(property "Reference" "C25W3"
			(at -0.8382 -0.67818 0)
			(unlocked yes)
			(layer "F.SilkS")
			(effects
				(font
					(size 0.4064 0.254)
					(thickness 0.1524)
				)
				(justify left)
			)
		)
		(property "Value" ""
			(at 0 0 0)
			(layer "F.Fab")
			(effects
				(font
					(size 1.27 1.27)
				)
			)
		)
		(duplicate_pad_numbers_are_jumpers no)
		(fp_poly
			(pts
				(xy 0.3048 -0.1016) (xy 0.3048 0.9906) (xy -0.3048 0.9906) (xy -0.3048 -0.1016)
			)
			(stroke
				(width 0)
				(type default)
			)
			(fill no)
			(layer "F.CrtYd")
		)
		(fp_line
			(start -0.3048 -0.1016)
			(end -0.3048 0.9906)
			(stroke
				(width 0.1)
				(type default)
			)
			(layer "F.Fab")
		)
		(fp_line
			(start -0.3048 0.9906)
			(end 0.3048 0.9906)
			(stroke
				(width 0.1)
				(type default)
			)
			(layer "F.Fab")
		)
		(fp_line
			(start 0.3048 -0.1016)
			(end -0.3048 -0.1016)
			(stroke
				(width 0.1)
				(type default)
			)
			(layer "F.Fab")
		)
		(fp_line
			(start 0.3048 0.9906)
			(end 0.3048 -0.1016)
			(stroke
				(width 0.1)
				(type default)
			)
			(layer "F.Fab")
		)
		(pad "1" smd rect
			(at 0 0)
			(size 0.508 0.508)
			(layers "F.Cu" "F.Mask" "F.Paste")
			(net "P1V2_AUX_BMC")
		)
		(pad "2" smd rect
			(at 0 0.889)
			(size 0.508 0.508)
			(layers "F.Cu" "F.Mask" "F.Paste")
			(net "GND")
		)
		(zone
			(layer "F.Cu")
			(hatch none 0.5)
			(connect_pads
				(clearance 0)
			)
			(min_thickness 0.25)
			(keepout
				(tracks allowed)
				(vias not_allowed)
				(pads allowed)
				(copperpour not_allowed)
				(footprints allowed)
			)
			(placement
				(enabled no)
				(sheetname "")
			)
			(fill
				(thermal_gap 0.5)
				(thermal_bridge_width 0.5)
				(island_removal_mode 0)
			)
			(polygon
				(pts
					(xy 451.993 -28.5115) (xy 452.501 -28.5115) (xy 452.501 -28.1305) (xy 451.993 -28.1305)
				)
			)
		)
		(zone
			(layer "F.Cu")
			(hatch none 0.5)
			(connect_pads
				(clearance 0)
			)
			(min_thickness 0.25)
			(keepout
				(tracks not_allowed)
				(vias allowed)
				(pads allowed)
				(copperpour not_allowed)
				(footprints allowed)
			)
			(placement
				(enabled no)
				(sheetname "")
			)
			(fill
				(thermal_gap 0.5)
				(thermal_bridge_width 0.5)
				(island_removal_mode 0)
			)
			(polygon
				(pts
					(xy 451.993 -28.1305) (xy 452.501 -28.1305) (xy 452.501 -28.5115) (xy 451.993 -28.5115)
				)
			)
		)
	)
	(footprint ""
		(layer "F.Cu")
		(at 10.033 0.24765 180)
		(property "Reference" "EU1G2"
			(at 2.4638 -3.53187 0)
			(unlocked yes)
			(layer "F.SilkS")
			(effects
				(font
					(size 0.7874 0.5842)
					(thickness 0.1524)
				)
				(justify left)
			)
		)
		(property "Value" ""
			(at 0 0 180)
			(layer "F.Fab")
			(effects
				(font
					(size 1.27 1.27)
				)
			)
		)
		(duplicate_pad_numbers_are_jumpers no)
		(fp_line
			(start 3.0607 3.0607)
			(end -3.0607 3.0607)
			(stroke
				(width 0.1524)
				(type default)
			)
			(layer "F.SilkS")
		)
		(fp_line
			(start 3.0607 -3.0607)
			(end 3.0607 3.0607)
			(stroke
				(width 0.1524)
				(type default)
			)
			(layer "F.SilkS")
		)
		(fp_line
			(start 2.549906 2.549906)
			(end 2.249678 2.549906)
			(stroke
				(width 0.1524)
				(type default)
			)
			(layer "F.SilkS")
		)
		(fp_line
			(start 2.549906 2.233422)
			(end 2.549906 2.549906)
			(stroke
				(width 0.1524)
				(type default)
			)
			(layer "F.SilkS")
		)
		(fp_line
			(start 2.549906 -2.549906)
			(end 2.549906 -2.258314)
			(stroke
				(width 0.1524)
				(type default)
			)
			(layer "F.SilkS")
		)
		(fp_line
			(start 2.245614 -2.549906)
			(end 2.549906 -2.549906)
			(stroke
				(width 0.1524)
				(type default)
			)
			(layer "F.SilkS")
		)
		(fp_line
			(start -2.277618 2.549906)
			(end -2.549906 2.549906)
			(stroke
				(width 0.1524)
				(type default)
			)
			(layer "F.SilkS")
		)
		(fp_line
			(start -2.549906 2.549906)
			(end -2.549906 2.267204)
			(stroke
				(width 0.1524)
				(type default)
			)
			(layer "F.SilkS")
		)
		(fp_line
			(start -2.549906 -2.29362)
			(end -2.549906 -2.549906)
			(stroke
				(width 0.1524)
				(type default)
			)
			(layer "F.SilkS")
		)
		(fp_line
			(start -2.549906 -2.549906)
			(end -2.249678 -2.549906)
			(stroke
				(width 0.1524)
				(type default)
			)
			(layer "F.SilkS")
		)
		(fp_line
			(start -3.0607 3.0607)
			(end -3.0607 -3.0607)
			(stroke
				(width 0.1524)
				(type default)
			)
			(layer "F.SilkS")
		)
		(fp_line
			(start -3.0607 -3.0607)
			(end 3.0607 -3.0607)
			(stroke
				(width 0.1524)
				(type default)
			)
			(layer "F.SilkS")
		)
		(fp_circle
			(center -3.237738 -2.256536)
			(end -3.364738 -2.256536)
			(stroke
				(width 0.254)
				(type default)
			)
			(fill no)
			(layer "F.SilkS")
		)
		(fp_poly
			(pts
				(xy -3.0607 -3.0607) (xy -3.0607 -2.0193) (xy -2.0193 -3.0607)
			)
			(stroke
				(width 0)
				(type default)
			)
			(fill yes)
			(layer "F.SilkS")
		)
		(fp_rect
			(start -1.8415 1.8415)
			(end 1.8415 -1.8415)
			(stroke
				(width 0)
				(type default)
			)
			(fill yes)
			(layer "F.Paste")
		)
		(fp_rect
			(start -2.549906 2.549906)
			(end 2.549906 -2.549906)
			(stroke
				(width 0)
				(type default)
			)
			(fill no)
			(layer "F.CrtYd")
		)
		(fp_line
			(start 2.549906 2.549906)
			(end -2.549906 2.549906)
			(stroke
				(width 0.1)
				(type default)
			)
			(layer "F.Fab")
		)
		(fp_line
			(start 2.549906 -2.549906)
			(end 2.549906 2.549906)
			(stroke
				(width 0.1)
				(type default)
			)
			(layer "F.Fab")
		)
		(fp_line
			(start -2.549906 2.549906)
			(end -2.549906 -2.549906)
			(stroke
				(width 0.1)
				(type default)
			)
			(layer "F.Fab")
		)
		(fp_line
			(start -2.549906 -2.549906)
			(end 2.549906 -2.549906)
			(stroke
				(width 0.1)
				(type default)
			)
			(layer "F.Fab")
		)
		(fp_circle
			(center -3.237738 -2.256536)
			(end -3.364738 -2.256536)
			(stroke
				(width 0.254)
				(type default)
			)
			(fill no)
			(layer "F.Fab")
		)
		(pad "1" smd custom
			(at -2.4511 -1.800098 180)
			(size 0.0508 0.0508)
			(layers "F.Cu" "F.Mask" "F.Paste")
			(net "Net_285")
			(options
				(clearance outline)
				(anchor circle)
			)
			(primitives
				(gr_poly
					(pts
						(arc
							(start 0.254 -0.1016)
							(mid 0.3556 0)
							(end 0.254 0.1016)
						)
						(xy -0.3556 0.1016) (xy -0.3556 -0.1016)
					)
					(width 0)
					(fill yes)
				)
			)
		)
		(pad "2" smd custom
			(at -2.4511 -1.400048 180)
			(size 0.0508 0.0508)
			(layers "F.Cu" "F.Mask" "F.Paste")
			(net "Net_349")
			(options
				(clearance outline)
				(anchor circle)
			)
			(primitives
				(gr_poly
					(pts
						(arc
							(start 0.254 -0.1016)
							(mid 0.3556 0)
							(end 0.254 0.1016)
						)
						(xy -0.3556 0.1016) (xy -0.3556 -0.1016)
					)
					(width 0)
					(fill yes)
				)
			)
		)
		(pad "3" smd custom
			(at -2.4511 -0.999998 180)
			(size 0.0508 0.0508)
			(layers "F.Cu" "F.Mask" "F.Paste")
			(net "Net_316")
			(options
				(clearance outline)
				(anchor circle)
			)
			(primitives
				(gr_poly
					(pts
						(arc
							(start 0.254 -0.1016)
							(mid 0.3556 0)
							(end 0.254 0.1016)
						)
						(xy -0.3556 0.1016) (xy -0.3556 -0.1016)
					)
					(width 0)
					(fill yes)
				)
			)
		)
		(pad "4" smd custom
			(at -2.4511 -0.599948 180)
			(size 0.0508 0.0508)
			(layers "F.Cu" "F.Mask" "F.Paste")
			(net "VR_PVDDQ_GHJ_PWM2")
			(options
				(clearance outline)
				(anchor circle)
			)
			(primitives
				(gr_poly
					(pts
						(arc
							(start 0.254 -0.1016)
							(mid 0.3556 0)
							(end 0.254 0.1016)
						)
						(xy -0.3556 0.1016) (xy -0.3556 -0.1016)
					)
					(width 0)
					(fill yes)
				)
			)
		)
		(pad "5" smd custom
			(at -2.4511 -0.199898 180)
			(size 0.0508 0.0508)
			(layers "F.Cu" "F.Mask" "F.Paste")
			(net "VR_PVDDQ_GHJ_PWM1")
			(options
				(clearance outline)
				(anchor circle)
			)
			(primitives
				(gr_poly
					(pts
						(arc
							(start 0.254 -0.1016)
							(mid 0.3556 0)
							(end 0.254 0.1016)
						)
						(xy -0.3556 0.1016) (xy -0.3556 -0.1016)
					)
					(width 0)
					(fill yes)
				)
			)
		)
		(pad "6" smd custom
			(at -2.4511 0.199898 180)
			(size 0.0508 0.0508)
			(layers "F.Cu" "F.Mask" "F.Paste")
			(net "SMB_VR_STBY_LVC3_SDA")
			(options
				(clearance outline)
				(anchor circle)
			)
			(primitives
				(gr_poly
					(pts
						(arc
							(start 0.254 -0.1016)
							(mid 0.3556 0)
							(end 0.254 0.1016)
						)
						(xy -0.3556 0.1016) (xy -0.3556 -0.1016)
					)
					(width 0)
					(fill yes)
				)
			)
		)
		(pad "7" smd custom
			(at -2.4511 0.599948 180)
			(size 0.0508 0.0508)
			(layers "F.Cu" "F.Mask" "F.Paste")
			(net "SMB_VR_STBY_LVC3_SCL")
			(options
				(clearance outline)
				(anchor circle)
			)
			(primitives
				(gr_poly
					(pts
						(arc
							(start 0.254 -0.1016)
							(mid 0.3556 0)
							(end 0.254 0.1016)
						)
						(xy -0.3556 0.1016) (xy -0.3556 -0.1016)
					)
					(width 0)
					(fill yes)
				)
			)
		)
		(pad "8" smd custom
			(at -2.4511 0.999998 180)
			(size 0.0508 0.0508)
			(layers "F.Cu" "F.Mask" "F.Paste")
			(net "Net_286")
			(options
				(clearance outline)
				(anchor circle)
			)
			(primitives
				(gr_poly
					(pts
						(arc
							(start 0.254 -0.1016)
							(mid 0.3556 0)
							(end 0.254 0.1016)
						)
						(xy -0.3556 0.1016) (xy -0.3556 -0.1016)
					)
					(width 0)
					(fill yes)
				)
			)
		)
		(pad "9" smd custom
			(at -2.4511 1.400048 180)
			(size 0.0508 0.0508)
			(layers "F.Cu" "F.Mask" "F.Paste")
			(net "PWRGD_PVDDQ_GHJ_R")
			(options
				(clearance outline)
				(anchor circle)
			)
			(primitives
				(gr_poly
					(pts
						(arc
							(start 0.254 -0.1016)
							(mid 0.3556 0)
							(end 0.254 0.1016)
						)
						(xy -0.3556 0.1016) (xy -0.3556 -0.1016)
					)
					(width 0)
					(fill yes)
				)
			)
		)
		(pad "10" smd custom
			(at -2.4511 1.800098 180)
			(size 0.0508 0.0508)
			(layers "F.Cu" "F.Mask" "F.Paste")
			(net "VR_PVDDQ_GHJ_VREN")
			(options
				(clearance outline)
				(anchor circle)
			)
			(primitives
				(gr_poly
					(pts
						(arc
							(start 0.254 -0.1016)
							(mid 0.3556 0)
							(end 0.254 0.1016)
						)
						(xy -0.3556 0.1016) (xy -0.3556 -0.1016)
					)
					(width 0)
					(fill yes)
				)
			)
		)
		(pad "11" smd custom
			(at -1.800098 2.4511 180)
			(size 0.0508 0.0508)
			(layers "F.Cu" "F.Mask" "F.Paste")
			(net "IRQ_PVDDQ_GHJ_VRHOT_LVT3_R_N")
			(options
				(clearance outline)
				(anchor circle)
			)
			(primitives
				(gr_poly
					(pts
						(arc
							(start -0.1016 -0.254)
							(mid 0 -0.3556)
							(end 0.1016 -0.254)
						)
						(xy 0.1016 0.3556) (xy -0.1016 0.3556)
					)
					(width 0)
					(fill yes)
				)
			)
		)
		(pad "12" smd custom
			(at -1.400048 2.4511 180)
			(size 0.0508 0.0508)
			(layers "F.Cu" "F.Mask" "F.Paste")
			(net "Net_315")
			(options
				(clearance outline)
				(anchor circle)
			)
			(primitives
				(gr_poly
					(pts
						(arc
							(start -0.1016 -0.254)
							(mid 0 -0.3556)
							(end 0.1016 -0.254)
						)
						(xy 0.1016 0.3556) (xy -0.1016 0.3556)
					)
					(width 0)
					(fill yes)
				)
			)
		)
		(pad "13" smd custom
			(at -0.999998 2.4511 180)
			(size 0.0508 0.0508)
			(layers "F.Cu" "F.Mask" "F.Paste")
			(net "PU_VR_PVDDQ_GHJ_FAULT1")
			(options
				(clearance outline)
				(anchor circle)
			)
			(primitives
				(gr_poly
					(pts
						(arc
							(start -0.1016 -0.254)
							(mid 0 -0.3556)
							(end 0.1016 -0.254)
						)
						(xy 0.1016 0.3556) (xy -0.1016 0.3556)
					)
					(width 0)
					(fill yes)
				)
			)
		)
		(pad "14" smd custom
			(at -0.599948 2.4511 180)
			(size 0.0508 0.0508)
			(layers "F.Cu" "F.Mask" "F.Paste")
			(net "TP_PVDDQ_GHJ_MP1")
			(options
				(clearance outline)
				(anchor circle)
			)
			(primitives
				(gr_poly
					(pts
						(arc
							(start -0.1016 -0.254)
							(mid 0 -0.3556)
							(end 0.1016 -0.254)
						)
						(xy 0.1016 0.3556) (xy -0.1016 0.3556)
					)
					(width 0)
					(fill yes)
				)
			)
		)
		(pad "15" smd custom
			(at -0.199898 2.4511 180)
			(size 0.0508 0.0508)
			(layers "F.Cu" "F.Mask" "F.Paste")
			(net "SVID_CLK_PVDDQ_GHJ")
			(options
				(clearance outline)
				(anchor circle)
			)
			(primitives
				(gr_poly
					(pts
						(arc
							(start -0.1016 -0.254)
							(mid 0 -0.3556)
							(end 0.1016 -0.254)
						)
						(xy 0.1016 0.3556) (xy -0.1016 0.3556)
					)
					(width 0)
					(fill yes)
				)
			)
		)
		(pad "16" smd custom
			(at 0.199898 2.4511 180)
			(size 0.0508 0.0508)
			(layers "F.Cu" "F.Mask" "F.Paste")
			(net "SVID_VDIO_PVDDQ_GHJ")
			(options
				(clearance outline)
				(anchor circle)
			)
			(primitives
				(gr_poly
					(pts
						(arc
							(start -0.1016 -0.254)
							(mid 0 -0.3556)
							(end 0.1016 -0.254)
						)
						(xy 0.1016 0.3556) (xy -0.1016 0.3556)
					)
					(width 0)
					(fill yes)
				)
			)
		)
		(pad "17" smd custom
			(at 0.599948 2.4511 180)
			(size 0.0508 0.0508)
			(layers "F.Cu" "F.Mask" "F.Paste")
			(net "SVID_ALERT_PVDDQ_GHJ")
			(options
				(clearance outline)
				(anchor circle)
			)
			(primitives
				(gr_poly
					(pts
						(arc
							(start -0.1016 -0.254)
							(mid 0 -0.3556)
							(end 0.1016 -0.254)
						)
						(xy 0.1016 0.3556) (xy -0.1016 0.3556)
					)
					(width 0)
					(fill yes)
				)
			)
		)
		(pad "18" smd custom
			(at 0.999998 2.4511 180)
			(size 0.0508 0.0508)
			(layers "F.Cu" "F.Mask" "F.Paste")
			(net "TP_PVDDQ_GHJ_MP2")
			(options
				(clearance outline)
				(anchor circle)
			)
			(primitives
				(gr_poly
					(pts
						(arc
							(start -0.1016 -0.254)
							(mid 0 -0.3556)
							(end 0.1016 -0.254)
						)
						(xy 0.1016 0.3556) (xy -0.1016 0.3556)
					)
					(width 0)
					(fill yes)
				)
			)
		)
		(pad "19" smd custom
			(at 1.400048 2.4511 180)
			(size 0.0508 0.0508)
			(layers "F.Cu" "F.Mask" "F.Paste")
			(net "VR_PVDDQ_GHJ_AVSP")
			(options
				(clearance outline)
				(anchor circle)
			)
			(primitives
				(gr_poly
					(pts
						(arc
							(start -0.1016 -0.254)
							(mid 0 -0.3556)
							(end 0.1016 -0.254)
						)
						(xy 0.1016 0.3556) (xy -0.1016 0.3556)
					)
					(width 0)
					(fill yes)
				)
			)
		)
		(pad "20" smd custom
			(at 1.800098 2.4511 180)
			(size 0.0508 0.0508)
			(layers "F.Cu" "F.Mask" "F.Paste")
			(net "VSENSE_PVDDQ_GHJ_N")
			(options
				(clearance outline)
				(anchor circle)
			)
			(primitives
				(gr_poly
					(pts
						(arc
							(start -0.1016 -0.254)
							(mid 0 -0.3556)
							(end 0.1016 -0.254)
						)
						(xy 0.1016 0.3556) (xy -0.1016 0.3556)
					)
					(width 0)
					(fill yes)
				)
			)
		)
		(pad "21" smd custom
			(at 2.4511 1.800098 180)
			(size 0.0508 0.0508)
			(layers "F.Cu" "F.Mask" "F.Paste")
			(net "VR_PVDDQ_GHJ_AIREF1")
			(options
				(clearance outline)
				(anchor circle)
			)
			(primitives
				(gr_poly
					(pts
						(arc
							(start -0.254 0.1016)
							(mid -0.3556 0)
							(end -0.254 -0.1016)
						)
						(xy 0.3556 -0.1016) (xy 0.3556 0.1016)
					)
					(width 0)
					(fill yes)
				)
			)
		)
		(pad "22" smd custom
			(at 2.4511 1.400048 180)
			(size 0.0508 0.0508)
			(layers "F.Cu" "F.Mask" "F.Paste")
			(net "ISENSE_PVDDQ_GHJ_PH1_IMON")
			(options
				(clearance outline)
				(anchor circle)
			)
			(primitives
				(gr_poly
					(pts
						(arc
							(start -0.254 0.1016)
							(mid -0.3556 0)
							(end -0.254 -0.1016)
						)
						(xy 0.3556 -0.1016) (xy 0.3556 0.1016)
					)
					(width 0)
					(fill yes)
				)
			)
		)
		(pad "23" smd custom
			(at 2.4511 0.999998 180)
			(size 0.0508 0.0508)
			(layers "F.Cu" "F.Mask" "F.Paste")
			(net "VR_PVDDQ_GHJ_AIREF2")
			(options
				(clearance outline)
				(anchor circle)
			)
			(primitives
				(gr_poly
					(pts
						(arc
							(start -0.254 0.1016)
							(mid -0.3556 0)
							(end -0.254 -0.1016)
						)
						(xy 0.3556 -0.1016) (xy 0.3556 0.1016)
					)
					(width 0)
					(fill yes)
				)
			)
		)
		(pad "24" smd custom
			(at 2.4511 0.599948 180)
			(size 0.0508 0.0508)
			(layers "F.Cu" "F.Mask" "F.Paste")
			(net "ISENSE_PVDDQ_GHJ_PH2_IMON")
			(options
				(clearance outline)
				(anchor circle)
			)
			(primitives
				(gr_poly
					(pts
						(arc
							(start -0.254 0.1016)
							(mid -0.3556 0)
							(end -0.254 -0.1016)
						)
						(xy 0.3556 -0.1016) (xy 0.3556 0.1016)
					)
					(width 0)
					(fill yes)
				)
			)
		)
		(pad "25" smd custom
			(at 2.4511 0.199898 180)
			(size 0.0508 0.0508)
			(layers "F.Cu" "F.Mask" "F.Paste")
			(net "Net_247")
			(options
				(clearance outline)
				(anchor circle)
			)
			(primitives
				(gr_poly
					(pts
						(arc
							(start -0.254 0.1016)
							(mid -0.3556 0)
							(end -0.254 -0.1016)
						)
						(xy 0.3556 -0.1016) (xy 0.3556 0.1016)
					)
					(width 0)
					(fill yes)
				)
			)
		)
		(pad "26" smd custom
			(at 2.4511 -0.199898 180)
			(size 0.0508 0.0508)
			(layers "F.Cu" "F.Mask" "F.Paste")
			(net "Net_246")
			(options
				(clearance outline)
				(anchor circle)
			)
			(primitives
				(gr_poly
					(pts
						(arc
							(start -0.254 0.1016)
							(mid -0.3556 0)
							(end -0.254 -0.1016)
						)
						(xy 0.3556 -0.1016) (xy 0.3556 0.1016)
					)
					(width 0)
					(fill yes)
				)
			)
		)
		(pad "27" smd custom
			(at 2.4511 -0.599948 180)
			(size 0.0508 0.0508)
			(layers "F.Cu" "F.Mask" "F.Paste")
			(net "GND")
			(options
				(clearance outline)
				(anchor circle)
			)
			(primitives
				(gr_poly
					(pts
						(arc
							(start -0.254 0.1016)
							(mid -0.3556 0)
							(end -0.254 -0.1016)
						)
						(xy 0.3556 -0.1016) (xy 0.3556 0.1016)
					)
					(width 0)
					(fill yes)
				)
			)
		)
		(pad "28" smd custom
			(at 2.4511 -0.999998 180)
			(size 0.0508 0.0508)
			(layers "F.Cu" "F.Mask" "F.Paste")
			(net "Net_350")
			(options
				(clearance outline)
				(anchor circle)
			)
			(primitives
				(gr_poly
					(pts
						(arc
							(start -0.254 0.1016)
							(mid -0.3556 0)
							(end -0.254 -0.1016)
						)
						(xy 0.3556 -0.1016) (xy 0.3556 0.1016)
					)
					(width 0)
					(fill yes)
				)
			)
		)
		(pad "29" smd custom
			(at 2.4511 -1.400048 180)
			(size 0.0508 0.0508)
			(layers "F.Cu" "F.Mask" "F.Paste")
			(net "Net_234")
			(options
				(clearance outline)
				(anchor circle)
			)
			(primitives
				(gr_poly
					(pts
						(arc
							(start -0.254 0.1016)
							(mid -0.3556 0)
							(end -0.254 -0.1016)
						)
						(xy 0.3556 -0.1016) (xy 0.3556 0.1016)
					)
					(width 0)
					(fill yes)
				)
			)
		)
		(pad "30" smd custom
			(at 2.4511 -1.800098 180)
			(size 0.0508 0.0508)
			(layers "F.Cu" "F.Mask" "F.Paste")
			(net "Net_233")
			(options
				(clearance outline)
				(anchor circle)
			)
			(primitives
				(gr_poly
					(pts
						(arc
							(start -0.254 0.1016)
							(mid -0.3556 0)
							(end -0.254 -0.1016)
						)
						(xy 0.3556 -0.1016) (xy 0.3556 0.1016)
					)
					(width 0)
					(fill yes)
				)
			)
		)
		(pad "31" smd custom
			(at 1.800098 -2.4511 180)
			(size 0.0508 0.0508)
			(layers "F.Cu" "F.Mask" "F.Paste")
			(net "Net_231")
			(options
				(clearance outline)
				(anchor circle)
			)
			(primitives
				(gr_poly
					(pts
						(arc
							(start 0.1016 0.254)
							(mid 0 0.3556)
							(end -0.1016 0.254)
						)
						(xy -0.1016 -0.3556) (xy 0.1016 -0.3556)
					)
					(width 0)
					(fill yes)
				)
			)
		)
		(pad "32" smd custom
			(at 1.400048 -2.4511 180)
			(size 0.0508 0.0508)
			(layers "F.Cu" "F.Mask" "F.Paste")
			(net "GND")
			(options
				(clearance outline)
				(anchor circle)
			)
			(primitives
				(gr_poly
					(pts
						(arc
							(start 0.1016 0.254)
							(mid 0 0.3556)
							(end -0.1016 0.254)
						)
						(xy -0.1016 -0.3556) (xy 0.1016 -0.3556)
					)
					(width 0)
					(fill yes)
				)
			)
		)
		(pad "33" smd custom
			(at 0.999998 -2.4511 180)
			(size 0.0508 0.0508)
			(layers "F.Cu" "F.Mask" "F.Paste")
			(net "VR_PVDDQ_GHJ_XADDR2")
			(options
				(clearance outline)
				(anchor circle)
			)
			(primitives
				(gr_poly
					(pts
						(arc
							(start 0.1016 0.254)
							(mid 0 0.3556)
							(end -0.1016 0.254)
						)
						(xy -0.1016 -0.3556) (xy 0.1016 -0.3556)
					)
					(width 0)
					(fill yes)
				)
			)
		)
		(pad "34" smd custom
			(at 0.599948 -2.4511 180)
			(size 0.0508 0.0508)
			(layers "F.Cu" "F.Mask" "F.Paste")
			(net "Net_232")
			(options
				(clearance outline)
				(anchor circle)
			)
			(primitives
				(gr_poly
					(pts
						(arc
							(start 0.1016 0.254)
							(mid 0 0.3556)
							(end -0.1016 0.254)
						)
						(xy -0.1016 -0.3556) (xy 0.1016 -0.3556)
					)
					(width 0)
					(fill yes)
				)
			)
		)
		(pad "35" smd custom
			(at 0.199898 -2.4511 180)
			(size 0.0508 0.0508)
			(layers "F.Cu" "F.Mask" "F.Paste")
			(net "A_TSENSE_PVDDQ_GHJ")
			(options
				(clearance outline)
				(anchor circle)
			)
			(primitives
				(gr_poly
					(pts
						(arc
							(start 0.1016 0.254)
							(mid 0 0.3556)
							(end -0.1016 0.254)
						)
						(xy -0.1016 -0.3556) (xy 0.1016 -0.3556)
					)
					(width 0)
					(fill yes)
				)
			)
		)
		(pad "36" smd custom
			(at -0.199898 -2.4511 180)
			(size 0.0508 0.0508)
			(layers "F.Cu" "F.Mask" "F.Paste")
			(net "VR_PVDDQ_GHJ_XADDR1")
			(options
				(clearance outline)
				(anchor circle)
			)
			(primitives
				(gr_poly
					(pts
						(arc
							(start 0.1016 0.254)
							(mid 0 0.3556)
							(end -0.1016 0.254)
						)
						(xy -0.1016 -0.3556) (xy 0.1016 -0.3556)
					)
					(width 0)
					(fill yes)
				)
			)
		)
		(pad "37" smd custom
			(at -0.599948 -2.4511 180)
			(size 0.0508 0.0508)
			(layers "F.Cu" "F.Mask" "F.Paste")
			(net "VR_PVDDQ_GHJ_VINSEN")
			(options
				(clearance outline)
				(anchor circle)
			)
			(primitives
				(gr_poly
					(pts
						(arc
							(start 0.1016 0.254)
							(mid 0 0.3556)
							(end -0.1016 0.254)
						)
						(xy -0.1016 -0.3556) (xy 0.1016 -0.3556)
					)
					(width 0)
					(fill yes)
				)
			)
		)
		(pad "38" smd custom
			(at -0.999998 -2.4511 180)
			(size 0.0508 0.0508)
			(layers "F.Cu" "F.Mask" "F.Paste")
			(net "VR_PVDDQ_GHJ_AIINSEN")
			(options
				(clearance outline)
				(anchor circle)
			)
			(primitives
				(gr_poly
					(pts
						(arc
							(start 0.1016 0.254)
							(mid 0 0.3556)
							(end -0.1016 0.254)
						)
						(xy -0.1016 -0.3556) (xy 0.1016 -0.3556)
					)
					(width 0)
					(fill yes)
				)
			)
		)
		(pad "39" smd custom
			(at -1.400048 -2.4511 180)
			(size 0.0508 0.0508)
			(layers "F.Cu" "F.Mask" "F.Paste")
			(net "VR_PVDDQ_GHJ_VDD")
			(options
				(clearance outline)
				(anchor circle)
			)
			(primitives
				(gr_poly
					(pts
						(arc
							(start 0.1016 0.254)
							(mid 0 0.3556)
							(end -0.1016 0.254)
						)
						(xy -0.1016 -0.3556) (xy 0.1016 -0.3556)
					)
					(width 0)
					(fill yes)
				)
			)
		)
		(pad "40" smd custom
			(at -1.800098 -2.4511 180)
			(size 0.0508 0.0508)
			(layers "F.Cu" "F.Mask" "F.Paste")
			(net "VR_PVDDQ_GHJ_VD12")
			(options
				(clearance outline)
				(anchor circle)
			)
			(primitives
				(gr_poly
					(pts
						(arc
							(start 0.1016 0.254)
							(mid 0 0.3556)
							(end -0.1016 0.254)
						)
						(xy -0.1016 -0.3556) (xy 0.1016 -0.3556)
					)
					(width 0)
					(fill yes)
				)
			)
		)
		(pad "41" smd rect
			(at 0 0 180)
			(size 3.683 3.683)
			(layers "F.Cu" "F.Mask" "F.Paste")
			(net "GND")
		)
		(zone
			(layer "F.Cu")
			(hatch none 0.5)
			(connect_pads
				(clearance 0)
			)
			(min_thickness 0.25)
			(keepout
				(tracks allowed)
				(vias not_allowed)
				(pads allowed)
				(copperpour not_allowed)
				(footprints allowed)
			)
			(placement
				(enabled no)
				(sheetname "")
			)
			(fill
				(thermal_gap 0.5)
				(thermal_bridge_width 0.5)
				(island_removal_mode 0)
			)
			(polygon
				(pts
					(xy 12.1285 -1.84785) (xy 12.1285 -1.38684) (xy 11.8745 -1.38684) (xy 11.8745 -1.59385) (xy 8.1915 -1.59385)
					(xy 8.1915 2.08915) (xy 11.8745 2.08915) (xy 11.8745 -1.384808) (xy 12.1285 -1.384808) (xy 12.1285 2.34315)
					(xy 7.9375 2.34315) (xy 7.9375 -1.84785)
				)
			)
		)
		(zone
			(layer "F.Cu")
			(hatch none 0.5)
			(connect_pads
				(clearance 0)
			)
			(min_thickness 0.25)
			(keepout
				(tracks not_allowed)
				(vias allowed)
				(pads allowed)
				(copperpour not_allowed)
				(footprints allowed)
			)
			(placement
				(enabled no)
				(sheetname "")
			)
			(fill
				(thermal_gap 0.5)
				(thermal_bridge_width 0.5)
				(island_removal_mode 0)
			)
			(polygon
				(pts
					(xy 12.1285 -1.84785) (xy 12.1285 -1.38684) (xy 11.8745 -1.38684) (xy 11.8745 -1.59385) (xy 8.1915 -1.59385)
					(xy 8.1915 2.08915) (xy 11.8745 2.08915) (xy 11.8745 -1.384808) (xy 12.1285 -1.384808) (xy 12.1285 2.34315)
					(xy 7.9375 2.34315) (xy 7.9375 -1.84785)
				)
			)
		)
	)
	(footprint ""
		(layer "F.Cu")
		(at 101.3968 -3.3528 90)
		(property "Reference" "C2G13"
			(at 1.848866 0.752348 90)
			(unlocked yes)
			(layer "F.SilkS")
			(effects
				(font
					(size 1.27 0.9652)
					(thickness 0.1524)
				)
			)
		)
		(property "Value" ""
			(at 0 0 90)
			(layer "F.Fab")
			(effects
				(font
					(size 1.27 1.27)
				)
			)
		)
		(duplicate_pad_numbers_are_jumpers no)
		(fp_rect
			(start -0.500126 1.598422)
			(end 0.500126 -0.201422)
			(stroke
				(width 0)
				(type default)
			)
			(fill no)
			(layer "F.CrtYd")
		)
		(fp_line
			(start 0.500126 -0.201422)
			(end 0.500126 1.598422)
			(stroke
				(width 0.1)
				(type default)
			)
			(layer "F.Fab")
		)
		(fp_line
			(start -0.500126 -0.201422)
			(end 0.500126 -0.201422)
			(stroke
				(width 0.1)
				(type default)
			)
			(layer "F.Fab")
		)
		(fp_line
			(start 0.500126 1.598422)
			(end -0.500126 1.598422)
			(stroke
				(width 0.1)
				(type default)
			)
			(layer "F.Fab")
		)
		(fp_line
			(start -0.500126 1.598422)
			(end -0.500126 -0.201422)
			(stroke
				(width 0.1)
				(type default)
			)
			(layer "F.Fab")
		)
		(pad "1" smd rect
			(at 0 0)
			(size 0.889 0.9906)
			(layers "F.Cu" "F.Mask" "F.Paste")
			(net "PVDDQ_GHJ")
		)
		(pad "2" smd rect
			(at 0 1.397)
			(size 0.889 0.9906)
			(layers "F.Cu" "F.Mask" "F.Paste")
			(net "GND")
		)
		(zone
			(layer "F.Cu")
			(hatch none 0.5)
			(connect_pads
				(clearance 0)
			)
			(min_thickness 0.25)
			(keepout
				(tracks allowed)
				(vias not_allowed)
				(pads allowed)
				(copperpour not_allowed)
				(footprints allowed)
			)
			(placement
				(enabled no)
				(sheetname "")
			)
			(fill
				(thermal_gap 0.5)
				(thermal_bridge_width 0.5)
				(island_removal_mode 0)
			)
			(polygon
				(pts
					(xy 102.3493 -2.8575) (xy 102.3493 -3.8481) (xy 101.8413 -3.8481) (xy 101.8413 -2.8575)
				)
			)
		)
		(zone
			(layer "F.Cu")
			(hatch none 0.5)
			(connect_pads
				(clearance 0)
			)
			(min_thickness 0.25)
			(keepout
				(tracks not_allowed)
				(vias allowed)
				(pads allowed)
				(copperpour not_allowed)
				(footprints allowed)
			)
			(placement
				(enabled no)
				(sheetname "")
			)
			(fill
				(thermal_gap 0.5)
				(thermal_bridge_width 0.5)
				(island_removal_mode 0)
			)
			(polygon
				(pts
					(xy 102.3493 -2.8575) (xy 102.3493 -3.8481) (xy 101.8413 -3.8481) (xy 101.8413 -2.8575)
				)
			)
		)
	)
	(footprint ""
		(layer "F.Cu")
		(at 194.7545 -59.817 -90)
		(property "Reference" "C4E19"
			(at 0 0 270)
			(layer "F.SilkS")
			(hide yes)
			(effects
				(font
					(size 1.27 1.27)
				)
			)
		)
		(property "Value" ""
			(at 0 0 270)
			(layer "F.Fab")
			(effects
				(font
					(size 1.27 1.27)
				)
			)
		)
		(duplicate_pad_numbers_are_jumpers no)
		(fp_poly
			(pts
				(xy 0.3048 -0.1016) (xy 0.3048 0.9906) (xy -0.3048 0.9906) (xy -0.3048 -0.1016)
			)
			(stroke
				(width 0)
				(type default)
			)
			(fill no)
			(layer "F.CrtYd")
		)
		(fp_line
			(start -0.3048 0.9906)
			(end 0.3048 0.9906)
			(stroke
				(width 0.1)
				(type default)
			)
			(layer "F.Fab")
		)
		(fp_line
			(start 0.3048 0.9906)
			(end 0.3048 -0.1016)
			(stroke
				(width 0.1)
				(type default)
			)
			(layer "F.Fab")
		)
		(fp_line
			(start -0.3048 -0.1016)
			(end -0.3048 0.9906)
			(stroke
				(width 0.1)
				(type default)
			)
			(layer "F.Fab")
		)
		(fp_line
			(start 0.3048 -0.1016)
			(end -0.3048 -0.1016)
			(stroke
				(width 0.1)
				(type default)
			)
			(layer "F.Fab")
		)
		(pad "1" smd rect
			(at 0 0 270)
			(size 0.508 0.508)
			(layers "F.Cu" "F.Mask" "F.Paste")
			(net "VR_FET_SW_P12V_STBY_PVCCIN_CPU0")
		)
		(pad "2" smd rect
			(at 0 0.889 270)
			(size 0.508 0.508)
			(layers "F.Cu" "F.Mask" "F.Paste")
			(net "GND")
		)
		(zone
			(layer "F.Cu")
			(hatch none 0.5)
			(connect_pads
				(clearance 0)
			)
			(min_thickness 0.25)
			(keepout
				(tracks not_allowed)
				(vias allowed)
				(pads allowed)
				(copperpour not_allowed)
				(footprints allowed)
			)
			(placement
				(enabled no)
				(sheetname "")
			)
			(fill
				(thermal_gap 0.5)
				(thermal_bridge_width 0.5)
				(island_removal_mode 0)
			)
			(polygon
				(pts
					(xy 194.1195 -60.071) (xy 194.1195 -59.563) (xy 194.5005 -59.563) (xy 194.5005 -60.071)
				)
			)
		)
		(zone
			(layer "F.Cu")
			(hatch none 0.5)
			(connect_pads
				(clearance 0)
			)
			(min_thickness 0.25)
			(keepout
				(tracks allowed)
				(vias not_allowed)
				(pads allowed)
				(copperpour not_allowed)
				(footprints allowed)
			)
			(placement
				(enabled no)
				(sheetname "")
			)
			(fill
				(thermal_gap 0.5)
				(thermal_bridge_width 0.5)
				(island_removal_mode 0)
			)
			(polygon
				(pts
					(xy 194.5005 -60.071) (xy 194.5005 -59.563) (xy 194.1195 -59.563) (xy 194.1195 -60.071)
				)
			)
		)
	)
	(footprint ""
		(layer "F.Cu")
		(at 11.249914 -45.310044 -90)
		(property "Reference" "RM1E1"
			(at 1.495044 -4.651756 90)
			(unlocked yes)
			(layer "F.SilkS")
			(effects
				(font
					(size 0.7874 0.5842)
					(thickness 0.1524)
				)
				(justify left)
			)
		)
		(property "Value" ""
			(at 0 0 270)
			(layer "F.Fab")
			(effects
				(font
					(size 1.27 1.27)
				)
			)
		)
		(duplicate_pad_numbers_are_jumpers no)
		(fp_line
			(start -3.549904 17.223994)
			(end -3.549904 -3.929888)
			(stroke
				(width 0.1524)
				(type default)
			)
			(layer "F.SilkS")
		)
		(fp_line
			(start -3.549904 -3.929888)
			(end 3.549904 -3.929888)
			(stroke
				(width 0.1524)
				(type default)
			)
			(layer "F.SilkS")
		)
		(fp_line
			(start 3.549904 -3.929888)
			(end 3.549904 17.202912)
			(stroke
				(width 0.1524)
				(type default)
			)
			(layer "F.SilkS")
		)
		(fp_poly
			(pts
				(xy 4.863084 -2.237486) (xy 3.593084 -2.745486) (xy 4.863084 -3.253486)
			)
			(stroke
				(width 0)
				(type default)
			)
			(fill yes)
			(layer "F.SilkS")
		)
		(fp_poly
			(pts
				(xy 5.80644 0.05715) (xy 4.53644 -0.45085) (xy 5.80644 -0.95885)
			)
			(stroke
				(width 0)
				(type default)
			)
			(fill yes)
			(layer "B.SilkS")
		)
		(fp_poly
			(pts
				(xy -3.549904 -3.929888) (xy 3.549904 -3.929888) (xy 3.549904 20.7899) (xy 1.599946 20.7899) (xy 1.599946 42.489882)
				(xy -1.599946 42.489882) (xy -1.599946 20.7899) (xy -3.549904 20.7899)
			)
			(stroke
				(width 0)
				(type default)
			)
			(fill no)
			(layer "F.CrtYd")
		)
		(fp_poly
			(pts
				(xy 6.134608 0.049022) (xy 4.864608 -0.458978) (xy 6.134608 -0.966978)
			)
			(stroke
				(width 0)
				(type default)
			)
			(fill yes)
			(layer "B.Fab")
		)
		(fp_line
			(start -1.599946 42.489882)
			(end -1.599946 20.7899)
			(stroke
				(width 0.1)
				(type default)
			)
			(layer "F.Fab")
		)
		(fp_line
			(start 1.599946 42.489882)
			(end -1.599946 42.489882)
			(stroke
				(width 0.1)
				(type default)
			)
			(layer "F.Fab")
		)
		(fp_line
			(start -3.549904 20.7899)
			(end -3.549904 -3.929888)
			(stroke
				(width 0.1)
				(type default)
			)
			(layer "F.Fab")
		)
		(fp_line
			(start -1.599946 20.7899)
			(end -3.549904 20.7899)
			(stroke
				(width 0.1)
				(type default)
			)
			(layer "F.Fab")
		)
		(fp_line
			(start 1.599946 20.7899)
			(end 1.599946 42.489882)
			(stroke
				(width 0.1)
				(type default)
			)
			(layer "F.Fab")
		)
		(fp_line
			(start 3.549904 20.7899)
			(end 1.599946 20.7899)
			(stroke
				(width 0.1)
				(type default)
			)
			(layer "F.Fab")
		)
		(fp_line
			(start -3.549904 -3.929888)
			(end 3.549904 -3.929888)
			(stroke
				(width 0.1)
				(type default)
			)
			(layer "F.Fab")
		)
		(fp_line
			(start 3.549904 -3.929888)
			(end 3.549904 20.7899)
			(stroke
				(width 0.1)
				(type default)
			)
			(layer "F.Fab")
		)
		(fp_poly
			(pts
				(xy 6.134608 0.051054) (xy 4.864608 -0.456946) (xy 6.134608 -0.964946)
			)
			(stroke
				(width 0)
				(type default)
			)
			(fill yes)
			(layer "F.Fab")
		)
		(fp_text user "2"
			(at -4.34721 -1.956308 0)
			(unlocked yes)
			(layer "F.SilkS")
			(effects
				(font
					(size 0.7874 0.5842)
					(thickness 0.1524)
				)
				(justify left)
			)
		)
		(fp_text user "3"
			(at -4.120642 -3.068066 0)
			(unlocked yes)
			(layer "F.SilkS")
			(effects
				(font
					(size 0.7874 0.5842)
					(thickness 0.1524)
				)
				(justify left)
			)
		)
		(fp_text user "2"
			(at 2.892044 11.624564 270)
			(unlocked yes)
			(layer "B.Fab")
			(effects
				(font
					(size 0.635 0.635)
					(thickness 0.1524)
				)
				(justify left mirror)
			)
		)
		(fp_text user "3"
			(at -2.518156 6.747764 270)
			(unlocked yes)
			(layer "B.Fab")
			(effects
				(font
					(size 0.635 0.635)
					(thickness 0.1524)
				)
				(justify left mirror)
			)
		)
		(fp_text user "2"
			(at 2.257044 11.624564 270)
			(unlocked yes)
			(layer "F.Fab")
			(effects
				(font
					(size 0.635 0.635)
					(thickness 0.1524)
				)
				(justify left)
			)
		)
		(fp_text user "3"
			(at -2.848356 6.722364 270)
			(unlocked yes)
			(layer "F.Fab")
			(effects
				(font
					(size 0.635 0.635)
					(thickness 0.1524)
				)
				(justify left)
			)
		)
		(pad "1" thru_hole rect
			(at 0 0 270)
			(size 3.556 3.556)
			(drill 3.175)
			(layers "*.Cu" "*.Mask")
			(remove_unused_layers no)
			(net "GND")
			(clearance 0.127)
			(thermal_gap 0.127)
			(padstack
				(mode front_inner_back)
				(layer "Inner"
					(shape circle)
					(size 3.556 3.556)
					(clearance 0.127)
				)
				(layer "B.Cu"
					(shape rect)
					(size 3.556 3.556)
					(clearance 0.127)
				)
			)
		)
		(pad "2" thru_hole circle
			(at 0 11.75004 270)
			(size 3.556 3.556)
			(drill 3.175)
			(layers "*.Cu" "*.Mask")
			(remove_unused_layers no)
			(net "GND")
			(clearance 0.127)
			(thermal_gap 0.127)
		)
		(pad "3" thru_hole circle
			(at 0 6.620002 270)
			(size 3.556 3.556)
			(drill 3.175)
			(layers "*.Cu" "*.Mask")
			(remove_unused_layers no)
			(net "GND")
			(clearance 0.127)
			(thermal_gap 0.127)
		)
	)
	(footprint ""
		(layer "F.Cu")
		(at 324.5485 -121.666 90)
		(property "Reference" "C6B9"
			(at -0.8382 -0.67818 90)
			(unlocked yes)
			(layer "F.SilkS")
			(effects
				(font
					(size 0.4064 0.254)
					(thickness 0.1524)
				)
				(justify left)
			)
		)
		(property "Value" ""
			(at 0 0 90)
			(layer "F.Fab")
			(effects
				(font
					(size 1.27 1.27)
				)
			)
		)
		(duplicate_pad_numbers_are_jumpers no)
		(fp_poly
			(pts
				(xy 0.3048 -0.1016) (xy 0.3048 0.9906) (xy -0.3048 0.9906) (xy -0.3048 -0.1016)
			)
			(stroke
				(width 0)
				(type default)
			)
			(fill no)
			(layer "F.CrtYd")
		)
		(fp_line
			(start 0.3048 -0.1016)
			(end -0.3048 -0.1016)
			(stroke
				(width 0.1)
				(type default)
			)
			(layer "F.Fab")
		)
		(fp_line
			(start -0.3048 -0.1016)
			(end -0.3048 0.9906)
			(stroke
				(width 0.1)
				(type default)
			)
			(layer "F.Fab")
		)
		(fp_line
			(start 0.3048 0.9906)
			(end 0.3048 -0.1016)
			(stroke
				(width 0.1)
				(type default)
			)
			(layer "F.Fab")
		)
		(fp_line
			(start -0.3048 0.9906)
			(end 0.3048 0.9906)
			(stroke
				(width 0.1)
				(type default)
			)
			(layer "F.Fab")
		)
		(pad "1" smd rect
			(at 0 0 90)
			(size 0.508 0.508)
			(layers "F.Cu" "F.Mask" "F.Paste")
			(net "P3E_CPU0_PE1_PCH_TXN<13>")
		)
		(pad "2" smd rect
			(at 0 0.889 90)
			(size 0.508 0.508)
			(layers "F.Cu" "F.Mask" "F.Paste")
			(net "P3E_CPU0_PE1_PCH_C_TXN<13>")
		)
		(zone
			(layer "F.Cu")
			(hatch none 0.5)
			(connect_pads
				(clearance 0)
			)
			(min_thickness 0.25)
			(keepout
				(tracks allowed)
				(vias not_allowed)
				(pads allowed)
				(copperpour not_allowed)
				(footprints allowed)
			)
			(placement
				(enabled no)
				(sheetname "")
			)
			(fill
				(thermal_gap 0.5)
				(thermal_bridge_width 0.5)
				(island_removal_mode 0)
			)
			(polygon
				(pts
					(xy 324.8025 -121.412) (xy 324.8025 -121.92) (xy 325.1835 -121.92) (xy 325.1835 -121.412)
				)
			)
		)
	)
	(footprint ""
		(layer "F.Cu")
		(at 185.4454 -153.416)
		(property "Reference" "R4A2"
			(at 0 0 0)
			(layer "F.SilkS")
			(hide yes)
			(effects
				(font
					(size 1.27 1.27)
				)
			)
		)
		(property "Value" ""
			(at 0 0 0)
			(layer "F.Fab")
			(effects
				(font
					(size 1.27 1.27)
				)
			)
		)
		(duplicate_pad_numbers_are_jumpers no)
		(fp_poly
			(pts
				(xy -0.2794 -0.1016) (xy 0.2794 -0.1016) (xy 0.2794 0.9906) (xy -0.2794 0.9906)
			)
			(stroke
				(width 0)
				(type default)
			)
			(fill no)
			(layer "F.CrtYd")
		)
		(fp_line
			(start -0.2794 -0.1016)
			(end -0.2794 0.9906)
			(stroke
				(width 0.1)
				(type default)
			)
			(layer "F.Fab")
		)
		(fp_line
			(start -0.2794 0.9906)
			(end 0.2794 0.9906)
			(stroke
				(width 0.1)
				(type default)
			)
			(layer "F.Fab")
		)
		(fp_line
			(start 0.2794 -0.1016)
			(end -0.2794 -0.1016)
			(stroke
				(width 0.1)
				(type default)
			)
			(layer "F.Fab")
		)
		(fp_line
			(start 0.2794 0.9906)
			(end 0.2794 -0.1016)
			(stroke
				(width 0.1)
				(type default)
			)
			(layer "F.Fab")
		)
		(pad "1" smd rect
			(at 0 0)
			(size 0.508 0.508)
			(layers "F.Cu" "F.Mask" "F.Paste")
			(net "PWRGD_PVDDQ_DEF_R")
		)
		(pad "2" smd rect
			(at 0 0.889)
			(size 0.508 0.508)
			(layers "F.Cu" "F.Mask" "F.Paste")
			(net "FM_PVTT_DEF_EN_R")
		)
		(zone
			(layer "F.Cu")
			(hatch none 0.5)
			(connect_pads
				(clearance 0)
			)
			(min_thickness 0.25)
			(keepout
				(tracks allowed)
				(vias not_allowed)
				(pads allowed)
				(copperpour not_allowed)
				(footprints allowed)
			)
			(placement
				(enabled no)
				(sheetname "")
			)
			(fill
				(thermal_gap 0.5)
				(thermal_bridge_width 0.5)
				(island_removal_mode 0)
			)
			(polygon
				(pts
					(xy 185.1914 -153.162) (xy 185.6994 -153.162) (xy 185.6994 -152.781) (xy 185.1914 -152.781)
				)
			)
		)
		(zone
			(layer "F.Cu")
			(hatch none 0.5)
			(connect_pads
				(clearance 0)
			)
			(min_thickness 0.25)
			(keepout
				(tracks not_allowed)
				(vias allowed)
				(pads allowed)
				(copperpour not_allowed)
				(footprints allowed)
			)
			(placement
				(enabled no)
				(sheetname "")
			)
			(fill
				(thermal_gap 0.5)
				(thermal_bridge_width 0.5)
				(island_removal_mode 0)
			)
			(polygon
				(pts
					(xy 185.1914 -152.781) (xy 185.6994 -152.781) (xy 185.6994 -153.162) (xy 185.1914 -153.162)
				)
			)
		)
	)
	(footprint ""
		(layer "F.Cu")
		(at 448.437 -20.2565)
		(property "Reference" "C9W10"
			(at -0.8382 -0.67818 0)
			(unlocked yes)
			(layer "F.SilkS")
			(effects
				(font
					(size 0.4064 0.254)
					(thickness 0.1524)
				)
				(justify left)
			)
		)
		(property "Value" ""
			(at 0 0 0)
			(layer "F.Fab")
			(effects
				(font
					(size 1.27 1.27)
				)
			)
		)
		(duplicate_pad_numbers_are_jumpers no)
		(fp_poly
			(pts
				(xy 0.3048 -0.1016) (xy 0.3048 0.9906) (xy -0.3048 0.9906) (xy -0.3048 -0.1016)
			)
			(stroke
				(width 0)
				(type default)
			)
			(fill no)
			(layer "F.CrtYd")
		)
		(fp_line
			(start -0.3048 -0.1016)
			(end -0.3048 0.9906)
			(stroke
				(width 0.1)
				(type default)
			)
			(layer "F.Fab")
		)
		(fp_line
			(start -0.3048 0.9906)
			(end 0.3048 0.9906)
			(stroke
				(width 0.1)
				(type default)
			)
			(layer "F.Fab")
		)
		(fp_line
			(start 0.3048 -0.1016)
			(end -0.3048 -0.1016)
			(stroke
				(width 0.1)
				(type default)
			)
			(layer "F.Fab")
		)
		(fp_line
			(start 0.3048 0.9906)
			(end 0.3048 -0.1016)
			(stroke
				(width 0.1)
				(type default)
			)
			(layer "F.Fab")
		)
		(pad "1" smd rect
			(at 0 0)
			(size 0.508 0.508)
			(layers "F.Cu" "F.Mask" "F.Paste")
			(net "PWRGD_P2V5_BMC_STBY_R")
		)
		(pad "2" smd rect
			(at 0 0.889)
			(size 0.508 0.508)
			(layers "F.Cu" "F.Mask" "F.Paste")
			(net "GND")
		)
		(zone
			(layer "F.Cu")
			(hatch none 0.5)
			(connect_pads
				(clearance 0)
			)
			(min_thickness 0.25)
			(keepout
				(tracks allowed)
				(vias not_allowed)
				(pads allowed)
				(copperpour not_allowed)
				(footprints allowed)
			)
			(placement
				(enabled no)
				(sheetname "")
			)
			(fill
				(thermal_gap 0.5)
				(thermal_bridge_width 0.5)
				(island_removal_mode 0)
			)
			(polygon
				(pts
					(xy 448.183 -20.0025) (xy 448.691 -20.0025) (xy 448.691 -19.6215) (xy 448.183 -19.6215)
				)
			)
		)
		(zone
			(layer "F.Cu")
			(hatch none 0.5)
			(connect_pads
				(clearance 0)
			)
			(min_thickness 0.25)
			(keepout
				(tracks not_allowed)
				(vias allowed)
				(pads allowed)
				(copperpour not_allowed)
				(footprints allowed)
			)
			(placement
				(enabled no)
				(sheetname "")
			)
			(fill
				(thermal_gap 0.5)
				(thermal_bridge_width 0.5)
				(island_removal_mode 0)
			)
			(polygon
				(pts
					(xy 448.183 -19.6215) (xy 448.691 -19.6215) (xy 448.691 -20.0025) (xy 448.183 -20.0025)
				)
			)
		)
	)
	(footprint ""
		(layer "F.Cu")
		(at 184.6072 -152.527 180)
		(property "Reference" "C4A2"
			(at 0 0 180)
			(layer "F.SilkS")
			(hide yes)
			(effects
				(font
					(size 1.27 1.27)
				)
			)
		)
		(property "Value" ""
			(at 0 0 180)
			(layer "F.Fab")
			(effects
				(font
					(size 1.27 1.27)
				)
			)
		)
		(duplicate_pad_numbers_are_jumpers no)
		(fp_rect
			(start -0.3048 0.9906)
			(end 0.3048 -0.1016)
			(stroke
				(width 0)
				(type default)
			)
			(fill no)
			(layer "F.CrtYd")
		)
		(fp_line
			(start 0.3048 0.9906)
			(end 0.3048 -0.1016)
			(stroke
				(width 0.1)
				(type default)
			)
			(layer "F.Fab")
		)
		(fp_line
			(start 0.3048 -0.1016)
			(end -0.3048 -0.1016)
			(stroke
				(width 0.1)
				(type default)
			)
			(layer "F.Fab")
		)
		(fp_line
			(start -0.3048 0.9906)
			(end 0.3048 0.9906)
			(stroke
				(width 0.1)
				(type default)
			)
			(layer "F.Fab")
		)
		(fp_line
			(start -0.3048 -0.1016)
			(end -0.3048 0.9906)
			(stroke
				(width 0.1)
				(type default)
			)
			(layer "F.Fab")
		)
		(pad "1" smd rect
			(at 0 0 180)
			(size 0.508 0.508)
			(layers "F.Cu" "F.Mask" "F.Paste")
			(net "FM_PVTT_DEF_EN_R")
		)
		(pad "2" smd rect
			(at 0 0.889 180)
			(size 0.508 0.508)
			(layers "F.Cu" "F.Mask" "F.Paste")
			(net "GND")
		)
		(zone
			(layer "F.Cu")
			(hatch none 0.5)
			(connect_pads
				(clearance 0)
			)
			(min_thickness 0.25)
			(keepout
				(tracks not_allowed)
				(vias allowed)
				(pads allowed)
				(copperpour not_allowed)
				(footprints allowed)
			)
			(placement
				(enabled no)
				(sheetname "")
			)
			(fill
				(thermal_gap 0.5)
				(thermal_bridge_width 0.5)
				(island_removal_mode 0)
			)
			(polygon
				(pts
					(xy 184.8612 -153.162) (xy 184.3532 -153.162) (xy 184.3532 -152.781) (xy 184.8612 -152.781)
				)
			)
		)
		(zone
			(layer "F.Cu")
			(hatch none 0.5)
			(connect_pads
				(clearance 0)
			)
			(min_thickness 0.25)
			(keepout
				(tracks allowed)
				(vias not_allowed)
				(pads allowed)
				(copperpour not_allowed)
				(footprints allowed)
			)
			(placement
				(enabled no)
				(sheetname "")
			)
			(fill
				(thermal_gap 0.5)
				(thermal_bridge_width 0.5)
				(island_removal_mode 0)
			)
			(polygon
				(pts
					(xy 184.8612 -153.162) (xy 184.3532 -153.162) (xy 184.3532 -152.781) (xy 184.8612 -152.781)
				)
			)
		)
	)
	(footprint ""
		(layer "F.Cu")
		(at 356.09784 -134.22757)
		(property "Reference" "C7B1"
			(at 0 0 0)
			(layer "F.SilkS")
			(hide yes)
			(effects
				(font
					(size 1.27 1.27)
				)
			)
		)
		(property "Value" ""
			(at 0 0 0)
			(layer "F.Fab")
			(effects
				(font
					(size 1.27 1.27)
				)
			)
		)
		(duplicate_pad_numbers_are_jumpers no)
		(fp_poly
			(pts
				(xy 0.3048 -0.1016) (xy 0.3048 0.9906) (xy -0.3048 0.9906) (xy -0.3048 -0.1016)
			)
			(stroke
				(width 0)
				(type default)
			)
			(fill no)
			(layer "F.CrtYd")
		)
		(fp_line
			(start -0.3048 -0.1016)
			(end -0.3048 0.9906)
			(stroke
				(width 0.1)
				(type default)
			)
			(layer "F.Fab")
		)
		(fp_line
			(start -0.3048 0.9906)
			(end 0.3048 0.9906)
			(stroke
				(width 0.1)
				(type default)
			)
			(layer "F.Fab")
		)
		(fp_line
			(start 0.3048 -0.1016)
			(end -0.3048 -0.1016)
			(stroke
				(width 0.1)
				(type default)
			)
			(layer "F.Fab")
		)
		(fp_line
			(start 0.3048 0.9906)
			(end 0.3048 -0.1016)
			(stroke
				(width 0.1)
				(type default)
			)
			(layer "F.Fab")
		)
		(pad "1" smd rect
			(at 0 0)
			(size 0.508 0.508)
			(layers "F.Cu" "F.Mask" "F.Paste")
			(net "VR_PVDDQ_DEF_VD12")
		)
		(pad "2" smd rect
			(at 0 0.889)
			(size 0.508 0.508)
			(layers "F.Cu" "F.Mask" "F.Paste")
			(net "GND")
		)
		(zone
			(layer "F.Cu")
			(hatch none 0.5)
			(connect_pads
				(clearance 0)
			)
			(min_thickness 0.25)
			(keepout
				(tracks allowed)
				(vias not_allowed)
				(pads allowed)
				(copperpour not_allowed)
				(footprints allowed)
			)
			(placement
				(enabled no)
				(sheetname "")
			)
			(fill
				(thermal_gap 0.5)
				(thermal_bridge_width 0.5)
				(island_removal_mode 0)
			)
			(polygon
				(pts
					(xy 355.84384 -133.97357) (xy 356.35184 -133.97357) (xy 356.35184 -133.59257) (xy 355.84384 -133.59257)
				)
			)
		)
		(zone
			(layer "F.Cu")
			(hatch none 0.5)
			(connect_pads
				(clearance 0)
			)
			(min_thickness 0.25)
			(keepout
				(tracks not_allowed)
				(vias allowed)
				(pads allowed)
				(copperpour not_allowed)
				(footprints allowed)
			)
			(placement
				(enabled no)
				(sheetname "")
			)
			(fill
				(thermal_gap 0.5)
				(thermal_bridge_width 0.5)
				(island_removal_mode 0)
			)
			(polygon
				(pts
					(xy 355.84384 -133.59257) (xy 356.35184 -133.59257) (xy 356.35184 -133.97357) (xy 355.84384 -133.97357)
				)
			)
		)
	)
	(footprint ""
		(layer "F.Cu")
		(at 389.9535 -79.8322 180)
		(property "Reference" "R7W4"
			(at -0.8382 -0.67818 180)
			(unlocked yes)
			(layer "F.SilkS")
			(effects
				(font
					(size 0.4064 0.254)
					(thickness 0.1524)
				)
				(justify left)
			)
		)
		(property "Value" ""
			(at 0 0 180)
			(layer "F.Fab")
			(effects
				(font
					(size 1.27 1.27)
				)
			)
		)
		(duplicate_pad_numbers_are_jumpers no)
		(fp_poly
			(pts
				(xy -0.2794 -0.1016) (xy 0.2794 -0.1016) (xy 0.2794 0.9906) (xy -0.2794 0.9906)
			)
			(stroke
				(width 0)
				(type default)
			)
			(fill no)
			(layer "F.CrtYd")
		)
		(fp_line
			(start 0.2794 0.9906)
			(end 0.2794 -0.1016)
			(stroke
				(width 0.1)
				(type default)
			)
			(layer "F.Fab")
		)
		(fp_line
			(start 0.2794 -0.1016)
			(end -0.2794 -0.1016)
			(stroke
				(width 0.1)
				(type default)
			)
			(layer "F.Fab")
		)
		(fp_line
			(start -0.2794 0.9906)
			(end 0.2794 0.9906)
			(stroke
				(width 0.1)
				(type default)
			)
			(layer "F.Fab")
		)
		(fp_line
			(start -0.2794 -0.1016)
			(end -0.2794 0.9906)
			(stroke
				(width 0.1)
				(type default)
			)
			(layer "F.Fab")
		)
		(pad "1" smd rect
			(at 0 0 180)
			(size 0.508 0.508)
			(layers "F.Cu" "F.Mask" "F.Paste")
			(net "PVCCIO_CPU0")
		)
		(pad "2" smd rect
			(at 0 0.889 180)
			(size 0.508 0.508)
			(layers "F.Cu" "F.Mask" "F.Paste")
			(net "P0V7_GTL2104_VREF_0")
		)
		(zone
			(layer "F.Cu")
			(hatch none 0.5)
			(connect_pads
				(clearance 0)
			)
			(min_thickness 0.25)
			(keepout
				(tracks not_allowed)
				(vias allowed)
				(pads allowed)
				(copperpour not_allowed)
				(footprints allowed)
			)
			(placement
				(enabled no)
				(sheetname "")
			)
			(fill
				(thermal_gap 0.5)
				(thermal_bridge_width 0.5)
				(island_removal_mode 0)
			)
			(polygon
				(pts
					(xy 390.2075 -80.4672) (xy 389.6995 -80.4672) (xy 389.6995 -80.0862) (xy 390.2075 -80.0862)
				)
			)
		)
		(zone
			(layer "F.Cu")
			(hatch none 0.5)
			(connect_pads
				(clearance 0)
			)
			(min_thickness 0.25)
			(keepout
				(tracks allowed)
				(vias not_allowed)
				(pads allowed)
				(copperpour not_allowed)
				(footprints allowed)
			)
			(placement
				(enabled no)
				(sheetname "")
			)
			(fill
				(thermal_gap 0.5)
				(thermal_bridge_width 0.5)
				(island_removal_mode 0)
			)
			(polygon
				(pts
					(xy 390.2075 -80.0862) (xy 389.6995 -80.0862) (xy 389.6995 -80.4672) (xy 390.2075 -80.4672)
				)
			)
		)
	)
	(footprint ""
		(layer "F.Cu")
		(at 347.622114 -22.5933 180)
		(property "Reference" "R7F19"
			(at 0 0 180)
			(layer "F.SilkS")
			(hide yes)
			(effects
				(font
					(size 1.27 1.27)
				)
			)
		)
		(property "Value" ""
			(at 0 0 180)
			(layer "F.Fab")
			(effects
				(font
					(size 1.27 1.27)
				)
			)
		)
		(duplicate_pad_numbers_are_jumpers no)
		(fp_rect
			(start 0.2794 -0.1016)
			(end -0.2794 0.9906)
			(stroke
				(width 0)
				(type default)
			)
			(fill no)
			(layer "F.CrtYd")
		)
		(fp_line
			(start 0.2794 0.9906)
			(end 0.2794 -0.1016)
			(stroke
				(width 0.1)
				(type default)
			)
			(layer "F.Fab")
		)
		(fp_line
			(start 0.2794 -0.1016)
			(end -0.2794 -0.1016)
			(stroke
				(width 0.1)
				(type default)
			)
			(layer "F.Fab")
		)
		(fp_line
			(start -0.2794 0.9906)
			(end 0.2794 0.9906)
			(stroke
				(width 0.1)
				(type default)
			)
			(layer "F.Fab")
		)
		(fp_line
			(start -0.2794 -0.1016)
			(end -0.2794 0.9906)
			(stroke
				(width 0.1)
				(type default)
			)
			(layer "F.Fab")
		)
		(pad "1" smd rect
			(at 0 0 180)
			(size 0.508 0.508)
			(layers "F.Cu" "F.Mask" "F.Paste")
			(net "P3V3_STBY")
		)
		(pad "2" smd rect
			(at 0 0.889 180)
			(size 0.508 0.508)
			(layers "F.Cu" "F.Mask" "F.Paste")
			(net "PWRGD_PVPP_ABC_R")
		)
		(zone
			(layer "F.Cu")
			(hatch none 0.5)
			(connect_pads
				(clearance 0)
			)
			(min_thickness 0.25)
			(keepout
				(tracks not_allowed)
				(vias allowed)
				(pads allowed)
				(copperpour not_allowed)
				(footprints allowed)
			)
			(placement
				(enabled no)
				(sheetname "")
			)
			(fill
				(thermal_gap 0.5)
				(thermal_bridge_width 0.5)
				(island_removal_mode 0)
			)
			(polygon
				(pts
					(xy 347.368114 -22.8473) (xy 347.876114 -22.8473) (xy 347.876114 -23.2283) (xy 347.368114 -23.2283)
				)
			)
		)
		(zone
			(layer "F.Cu")
			(hatch none 0.5)
			(connect_pads
				(clearance 0)
			)
			(min_thickness 0.25)
			(keepout
				(tracks allowed)
				(vias not_allowed)
				(pads allowed)
				(copperpour not_allowed)
				(footprints allowed)
			)
			(placement
				(enabled no)
				(sheetname "")
			)
			(fill
				(thermal_gap 0.5)
				(thermal_bridge_width 0.5)
				(island_removal_mode 0)
			)
			(polygon
				(pts
					(xy 347.368114 -22.8473) (xy 347.876114 -22.8473) (xy 347.876114 -23.2283) (xy 347.368114 -23.2283)
				)
			)
		)
	)
	(footprint ""
		(layer "F.Cu")
		(at 189.70498 -73.5457)
		(property "Reference" "R4D39"
			(at 0 0 0)
			(layer "F.SilkS")
			(hide yes)
			(effects
				(font
					(size 1.27 1.27)
				)
			)
		)
		(property "Value" ""
			(at 0 0 0)
			(layer "F.Fab")
			(effects
				(font
					(size 1.27 1.27)
				)
			)
		)
		(duplicate_pad_numbers_are_jumpers no)
		(fp_rect
			(start -0.2794 0.9906)
			(end 0.2794 -0.1016)
			(stroke
				(width 0)
				(type default)
			)
			(fill no)
			(layer "F.CrtYd")
		)
		(fp_line
			(start -0.2794 -0.1016)
			(end -0.2794 0.9906)
			(stroke
				(width 0.1)
				(type default)
			)
			(layer "F.Fab")
		)
		(fp_line
			(start -0.2794 0.9906)
			(end 0.2794 0.9906)
			(stroke
				(width 0.1)
				(type default)
			)
			(layer "F.Fab")
		)
		(fp_line
			(start 0.2794 -0.1016)
			(end -0.2794 -0.1016)
			(stroke
				(width 0.1)
				(type default)
			)
			(layer "F.Fab")
		)
		(fp_line
			(start 0.2794 0.9906)
			(end 0.2794 -0.1016)
			(stroke
				(width 0.1)
				(type default)
			)
			(layer "F.Fab")
		)
		(pad "1" smd rect
			(at 0 0)
			(size 0.508 0.508)
			(layers "F.Cu" "F.Mask" "F.Paste")
			(net "VSENSE_PVSA_CPU0_P")
		)
		(pad "2" smd rect
			(at 0 0.889)
			(size 0.508 0.508)
			(layers "F.Cu" "F.Mask" "F.Paste")
			(net "VSENSE_PVSA_CPU0_BVSP")
		)
		(zone
			(layer "F.Cu")
			(hatch none 0.5)
			(connect_pads
				(clearance 0)
			)
			(min_thickness 0.25)
			(keepout
				(tracks not_allowed)
				(vias allowed)
				(pads allowed)
				(copperpour not_allowed)
				(footprints allowed)
			)
			(placement
				(enabled no)
				(sheetname "")
			)
			(fill
				(thermal_gap 0.5)
				(thermal_bridge_width 0.5)
				(island_removal_mode 0)
			)
			(polygon
				(pts
					(xy 189.45098 -72.9107) (xy 189.95898 -72.9107) (xy 189.95898 -73.2917) (xy 189.45098 -73.2917)
				)
			)
		)
		(zone
			(layer "F.Cu")
			(hatch none 0.5)
			(connect_pads
				(clearance 0)
			)
			(min_thickness 0.25)
			(keepout
				(tracks allowed)
				(vias not_allowed)
				(pads allowed)
				(copperpour not_allowed)
				(footprints allowed)
			)
			(placement
				(enabled no)
				(sheetname "")
			)
			(fill
				(thermal_gap 0.5)
				(thermal_bridge_width 0.5)
				(island_removal_mode 0)
			)
			(polygon
				(pts
					(xy 189.45098 -72.9107) (xy 189.95898 -72.9107) (xy 189.95898 -73.2917) (xy 189.45098 -73.2917)
				)
			)
		)
	)
	(footprint ""
		(layer "F.Cu")
		(at 488.887516 -125.92685 180)
		(property "Reference" "Q9B1"
			(at 0 0 180)
			(layer "F.SilkS")
			(hide yes)
			(effects
				(font
					(size 1.27 1.27)
				)
			)
		)
		(property "Value" "*"
			(at -4.8514 -0.40005 180)
			(unlocked yes)
			(layer "F.Fab")
			(hide yes)
			(effects
				(font
					(size 0.889 0.889)
					(thickness 0.1524)
				)
			)
		)
		(property "Device Type" "2SB2907A-B0-00001-GP_DISCRET-GA"
			(at -4.8514 -1.92405 180)
			(unlocked yes)
			(layer "F.Fab")
			(hide yes)
			(effects
				(font
					(size 0.889 0.889)
					(thickness 0.1524)
				)
			)
		)
		(duplicate_pad_numbers_are_jumpers no)
		(fp_line
			(start 3.3274 0.8255)
			(end 2.59334 0.8255)
			(stroke
				(width 0.1524)
				(type default)
			)
			(layer "F.SilkS")
		)
		(fp_line
			(start 3.3274 -0.8255)
			(end 3.3274 0.8255)
			(stroke
				(width 0.1524)
				(type default)
			)
			(layer "F.SilkS")
		)
		(fp_line
			(start 2.460752 -0.8255)
			(end 3.3274 -0.8255)
			(stroke
				(width 0.1524)
				(type default)
			)
			(layer "F.SilkS")
		)
		(fp_line
			(start -2.188718 -1.3208)
			(end 2.188718 -1.3208)
			(stroke
				(width 0.1524)
				(type default)
			)
			(layer "F.SilkS")
		)
		(fp_line
			(start -2.59334 0.8255)
			(end -3.3274 0.8255)
			(stroke
				(width 0.1524)
				(type default)
			)
			(layer "F.SilkS")
		)
		(fp_line
			(start -3.3274 0.8255)
			(end -3.3274 -0.8255)
			(stroke
				(width 0.1524)
				(type default)
			)
			(layer "F.SilkS")
		)
		(fp_line
			(start -3.3274 -0.8255)
			(end -2.460752 -0.8255)
			(stroke
				(width 0.1524)
				(type default)
			)
			(layer "F.SilkS")
		)
		(fp_arc
			(start 2.59334 0.8255)
			(mid 0 2.870159)
			(end -2.59334 0.8255)
			(stroke
				(width 0.1524)
				(type default)
			)
			(layer "F.SilkS")
		)
		(fp_arc
			(start 2.188718 -1.3208)
			(mid 2.337892 -1.080376)
			(end 2.460752 -0.8255)
			(stroke
				(width 0.1524)
				(type default)
			)
			(layer "F.SilkS")
		)
		(fp_arc
			(start -2.460752 -0.8255)
			(mid -2.337885 -1.080372)
			(end -2.188718 -1.3208)
			(stroke
				(width 0.1524)
				(type default)
			)
			(layer "F.SilkS")
		)
		(fp_poly
			(pts
				(arc
					(start 2.413 0.2286)
					(mid 0 2.616334)
					(end -2.413 0.2286)
				)
				(xy -2.7432 0.2286) (xy -2.7432 -0.2286)
				(arc
					(start -2.374138 -0.2286)
					(mid -2.252325 -0.662833)
					(end -2.051812 -1.0668)
				)
				(arc
					(start 2.051812 -1.0668)
					(mid 2.252296 -0.662822)
					(end 2.374138 -0.2286)
				)
				(xy 2.7432 -0.2286) (xy 2.7432 0.2286)
			)
			(stroke
				(width 0)
				(type default)
			)
			(fill no)
			(layer "F.CrtYd")
		)
		(fp_poly
			(pts
				(arc
					(start 2.786634 1.0795)
					(mid 0 3.124369)
					(end -2.786634 1.0795)
				)
				(xy -3.5814 1.0795) (xy -3.5814 -1.0795)
				(arc
					(start -2.624328 -1.0795)
					(mid -2.483414 -1.33481)
					(end -2.31775 -1.5748)
				)
				(xy -0.000762 -1.5748) (xy -0.000762 -1.067054)
				(arc
					(start -2.052066 -1.067054)
					(mid -2.252571 -0.663082)
					(end -2.374392 -0.228854)
				)
				(xy -2.743454 -0.228854) (xy -2.743454 0.228854)
				(arc
					(start -2.413254 0.228854)
					(mid 0 2.61659)
					(end 2.413254 0.228854)
				)
				(xy 2.743454 0.228854) (xy 2.743454 -0.228854)
				(arc
					(start 2.374392 -0.228854)
					(mid 2.252549 -0.663073)
					(end 2.052066 -1.067054)
				)
				(xy 0.000762 -1.067054) (xy 0.000762 -1.5748)
				(arc
					(start 2.31775 -1.5748)
					(mid 2.483417 -1.334811)
					(end 2.624328 -1.0795)
				)
				(xy 3.5814 -1.0795) (xy 3.5814 1.0795)
			)
			(stroke
				(width 0)
				(type default)
			)
			(fill no)
			(layer "F.CrtYd")
		)
		(fp_poly
			(pts
				(arc
					(start 2.786634 1.0795)
					(mid 0 3.124369)
					(end -2.786634 1.0795)
				)
				(xy -3.5814 1.0795) (xy -3.5814 -1.0795)
				(arc
					(start -2.624328 -1.0795)
					(mid -2.483414 -1.33481)
					(end -2.31775 -1.5748)
				)
				(arc
					(start 2.31775 -1.5748)
					(mid 2.483417 -1.334811)
					(end 2.624328 -1.0795)
				)
				(xy 3.5814 -1.0795) (xy 3.5814 1.0795)
			)
			(stroke
				(width 0)
				(type default)
			)
			(fill no)
			(layer "F.Fab")
		)
		(pad "B" thru_hole circle
			(at 0 0 180)
			(size 1.143 1.143)
			(drill 0.7874)
			(layers "*.Cu" "*.Mask")
			(remove_unused_layers no)
			(net "ISENSE_TMP421_1_BC")
			(clearance 0.1778)
			(thermal_gap 0.1778)
		)
		(pad "C" thru_hole circle
			(at -2.500122 0 180)
			(size 1.143 1.143)
			(drill 0.7874)
			(layers "*.Cu" "*.Mask")
			(remove_unused_layers no)
			(net "ISENSE_TMP421_1_BC")
			(clearance 0.1778)
			(thermal_gap 0.1778)
		)
		(pad "E" thru_hole circle
			(at 2.500122 0 180)
			(size 1.143 1.143)
			(drill 0.7874)
			(layers "*.Cu" "*.Mask")
			(remove_unused_layers no)
			(net "ISENSE_TMP421_1_E")
			(clearance 0.1778)
			(thermal_gap 0.1778)
		)
	)
	(footprint ""
		(layer "F.Cu")
		(at 332.90002 -118.5164 -90)
		(property "Reference" "C842"
			(at -0.8382 -0.67818 270)
			(unlocked yes)
			(layer "F.SilkS")
			(effects
				(font
					(size 0.4064 0.254)
					(thickness 0.1524)
				)
				(justify left)
			)
		)
		(property "Value" ""
			(at 0 0 270)
			(layer "F.Fab")
			(effects
				(font
					(size 1.27 1.27)
				)
			)
		)
		(duplicate_pad_numbers_are_jumpers no)
		(fp_poly
			(pts
				(xy 0.3048 -0.1016) (xy 0.3048 0.9906) (xy -0.3048 0.9906) (xy -0.3048 -0.1016)
			)
			(stroke
				(width 0)
				(type default)
			)
			(fill no)
			(layer "F.CrtYd")
		)
		(fp_line
			(start -0.3048 0.9906)
			(end 0.3048 0.9906)
			(stroke
				(width 0.1)
				(type default)
			)
			(layer "F.Fab")
		)
		(fp_line
			(start 0.3048 0.9906)
			(end 0.3048 -0.1016)
			(stroke
				(width 0.1)
				(type default)
			)
			(layer "F.Fab")
		)
		(fp_line
			(start -0.3048 -0.1016)
			(end -0.3048 0.9906)
			(stroke
				(width 0.1)
				(type default)
			)
			(layer "F.Fab")
		)
		(fp_line
			(start 0.3048 -0.1016)
			(end -0.3048 -0.1016)
			(stroke
				(width 0.1)
				(type default)
			)
			(layer "F.Fab")
		)
		(pad "1" smd rect
			(at 0 0 270)
			(size 0.508 0.508)
			(layers "F.Cu" "F.Mask" "F.Paste")
			(net "P3E_CPU0_PE1_PCH_TXN<8>")
		)
		(pad "2" smd rect
			(at 0 0.889 270)
			(size 0.508 0.508)
			(layers "F.Cu" "F.Mask" "F.Paste")
			(net "P3E_CPU0_PE1_PCH_CON_TXN<8>")
		)
		(zone
			(layer "F.Cu")
			(hatch none 0.5)
			(connect_pads
				(clearance 0)
			)
			(min_thickness 0.25)
			(keepout
				(tracks not_allowed)
				(vias allowed)
				(pads allowed)
				(copperpour not_allowed)
				(footprints allowed)
			)
			(placement
				(enabled no)
				(sheetname "")
			)
			(fill
				(thermal_gap 0.5)
				(thermal_bridge_width 0.5)
				(island_removal_mode 0)
			)
			(polygon
				(pts
					(xy 332.26502 -118.7704) (xy 332.26502 -118.2624) (xy 332.64602 -118.2624) (xy 332.64602 -118.7704)
				)
			)
		)
		(zone
			(layer "F.Cu")
			(hatch none 0.5)
			(connect_pads
				(clearance 0)
			)
			(min_thickness 0.25)
			(keepout
				(tracks allowed)
				(vias not_allowed)
				(pads allowed)
				(copperpour not_allowed)
				(footprints allowed)
			)
			(placement
				(enabled no)
				(sheetname "")
			)
			(fill
				(thermal_gap 0.5)
				(thermal_bridge_width 0.5)
				(island_removal_mode 0)
			)
			(polygon
				(pts
					(xy 332.64602 -118.7704) (xy 332.64602 -118.2624) (xy 332.26502 -118.2624) (xy 332.26502 -118.7704)
				)
			)
		)
	)
	(footprint ""
		(layer "F.Cu")
		(at 23.697184 -97.562416 180)
		(property "Reference" "RF12"
			(at -0.8382 -0.67818 180)
			(unlocked yes)
			(layer "F.SilkS")
			(effects
				(font
					(size 0.4064 0.254)
					(thickness 0.1524)
				)
				(justify left)
			)
		)
		(property "Value" ""
			(at 0 0 180)
			(layer "F.Fab")
			(effects
				(font
					(size 1.27 1.27)
				)
			)
		)
		(duplicate_pad_numbers_are_jumpers no)
		(fp_poly
			(pts
				(xy -0.2794 -0.1016) (xy 0.2794 -0.1016) (xy 0.2794 0.9906) (xy -0.2794 0.9906)
			)
			(stroke
				(width 0)
				(type default)
			)
			(fill no)
			(layer "F.CrtYd")
		)
		(fp_line
			(start 0.2794 0.9906)
			(end 0.2794 -0.1016)
			(stroke
				(width 0.1)
				(type default)
			)
			(layer "F.Fab")
		)
		(fp_line
			(start 0.2794 -0.1016)
			(end -0.2794 -0.1016)
			(stroke
				(width 0.1)
				(type default)
			)
			(layer "F.Fab")
		)
		(fp_line
			(start -0.2794 0.9906)
			(end 0.2794 0.9906)
			(stroke
				(width 0.1)
				(type default)
			)
			(layer "F.Fab")
		)
		(fp_line
			(start -0.2794 -0.1016)
			(end -0.2794 0.9906)
			(stroke
				(width 0.1)
				(type default)
			)
			(layer "F.Fab")
		)
		(pad "1" smd rect
			(at 0 0 180)
			(size 0.508 0.508)
			(layers "F.Cu" "F.Mask" "F.Paste")
			(net "VR_PVSA_CPU1_BIREF1")
		)
		(pad "2" smd rect
			(at 0 0.889 180)
			(size 0.508 0.508)
			(layers "F.Cu" "F.Mask" "F.Paste")
			(net "ISENSE_PVSA_CPU1_IMON")
		)
		(zone
			(layer "F.Cu")
			(hatch none 0.5)
			(connect_pads
				(clearance 0)
			)
			(min_thickness 0.25)
			(keepout
				(tracks not_allowed)
				(vias allowed)
				(pads allowed)
				(copperpour not_allowed)
				(footprints allowed)
			)
			(placement
				(enabled no)
				(sheetname "")
			)
			(fill
				(thermal_gap 0.5)
				(thermal_bridge_width 0.5)
				(island_removal_mode 0)
			)
			(polygon
				(pts
					(xy 23.951184 -98.197416) (xy 23.443184 -98.197416) (xy 23.443184 -97.816416) (xy 23.951184 -97.816416)
				)
			)
		)
		(zone
			(layer "F.Cu")
			(hatch none 0.5)
			(connect_pads
				(clearance 0)
			)
			(min_thickness 0.25)
			(keepout
				(tracks allowed)
				(vias not_allowed)
				(pads allowed)
				(copperpour not_allowed)
				(footprints allowed)
			)
			(placement
				(enabled no)
				(sheetname "")
			)
			(fill
				(thermal_gap 0.5)
				(thermal_bridge_width 0.5)
				(island_removal_mode 0)
			)
			(polygon
				(pts
					(xy 23.951184 -97.816416) (xy 23.443184 -97.816416) (xy 23.443184 -98.197416) (xy 23.951184 -98.197416)
				)
			)
		)
	)
	(footprint ""
		(layer "F.Cu")
		(at 201.422 -85.4456 -90)
		(property "Reference" "RT24"
			(at 0 0 270)
			(layer "F.SilkS")
			(hide yes)
			(effects
				(font
					(size 1.27 1.27)
				)
			)
		)
		(property "Value" "*"
			(at -0.0254 -2.6289 270)
			(unlocked yes)
			(layer "F.Fab")
			(hide yes)
			(effects
				(font
					(size 1.27 1.016)
					(thickness 0.1524)
				)
			)
		)
		(property "Device Type" "1R3F-GP_RCL_GP-1R3F-GP,64.1R00A"
			(at -0.0254 -4.1529 270)
			(unlocked yes)
			(layer "F.Fab")
			(hide yes)
			(effects
				(font
					(size 1.27 1.016)
					(thickness 0.1524)
				)
			)
		)
		(duplicate_pad_numbers_are_jumpers no)
		(fp_line
			(start -0.4826 0)
			(end -0.2032 0)
			(stroke
				(width 0.2032)
				(type default)
			)
			(layer "F.SilkS")
		)
		(fp_line
			(start 0.2032 0)
			(end 0.4826 0)
			(stroke
				(width 0.2032)
				(type default)
			)
			(layer "F.SilkS")
		)
		(fp_rect
			(start -0.5842 1.3335)
			(end 0.5842 -1.3335)
			(stroke
				(width 0)
				(type default)
			)
			(fill no)
			(layer "F.CrtYd")
		)
		(fp_rect
			(start -0.5842 1.3335)
			(end 0.5842 -1.3335)
			(stroke
				(width 0)
				(type default)
			)
			(fill no)
			(layer "F.Fab")
		)
		(pad "1" smd custom
			(at 0 -0.762 270)
			(size 0.2159 0.2159)
			(layers "F.Cu" "F.Mask" "F.Paste")
			(net "VR_PVCCIN_CPU0_PHASE5_RC")
			(options
				(clearance outline)
				(anchor circle)
			)
			(primitives
				(gr_poly
					(pts
						(arc
							(start -0.3302 -0.4318)
							(mid -0.402042 -0.402042)
							(end -0.4318 -0.3302)
						)
						(arc
							(start -0.4318 0.3302)
							(mid -0.402042 0.402042)
							(end -0.3302 0.4318)
						)
						(arc
							(start 0.3302 0.4318)
							(mid 0.402042 0.402042)
							(end 0.4318 0.3302)
						)
						(arc
							(start 0.4318 -0.3302)
							(mid 0.402042 -0.402042)
							(end 0.3302 -0.4318)
						)
					)
					(width 0)
					(fill yes)
				)
			)
		)
		(pad "2" smd custom
			(at 0 0.762 270)
			(size 0.2159 0.2159)
			(layers "F.Cu" "F.Mask" "F.Paste")
			(net "GND")
			(options
				(clearance outline)
				(anchor circle)
			)
			(primitives
				(gr_poly
					(pts
						(arc
							(start -0.3302 -0.4318)
							(mid -0.402042 -0.402042)
							(end -0.4318 -0.3302)
						)
						(arc
							(start -0.4318 0.3302)
							(mid -0.402042 0.402042)
							(end -0.3302 0.4318)
						)
						(arc
							(start 0.3302 0.4318)
							(mid 0.402042 0.402042)
							(end 0.4318 0.3302)
						)
						(arc
							(start 0.4318 -0.3302)
							(mid 0.402042 -0.402042)
							(end 0.3302 -0.4318)
						)
					)
					(width 0)
					(fill yes)
				)
			)
		)
	)
	(footprint ""
		(layer "F.Cu")
		(at 339.3948 -103.9368 90)
		(property "Reference" "C7C6"
			(at 0 0 90)
			(layer "F.SilkS")
			(hide yes)
			(effects
				(font
					(size 1.27 1.27)
				)
			)
		)
		(property "Value" ""
			(at 0 0 90)
			(layer "F.Fab")
			(effects
				(font
					(size 1.27 1.27)
				)
			)
		)
		(duplicate_pad_numbers_are_jumpers no)
		(fp_poly
			(pts
				(xy -0.4953 -0.2032) (xy 0.4953 -0.2032) (xy 0.4953 1.6002) (xy -0.4953 1.6002)
			)
			(stroke
				(width 0)
				(type default)
			)
			(fill no)
			(layer "F.CrtYd")
		)
		(fp_line
			(start 0.4953 -0.2032)
			(end 0.4953 1.6002)
			(stroke
				(width 0.1)
				(type default)
			)
			(layer "F.Fab")
		)
		(fp_line
			(start -0.4953 -0.2032)
			(end 0.4953 -0.2032)
			(stroke
				(width 0.1)
				(type default)
			)
			(layer "F.Fab")
		)
		(fp_line
			(start 0.4953 1.6002)
			(end -0.4953 1.6002)
			(stroke
				(width 0.1)
				(type default)
			)
			(layer "F.Fab")
		)
		(fp_line
			(start -0.4953 1.6002)
			(end -0.4953 -0.2032)
			(stroke
				(width 0.1)
				(type default)
			)
			(layer "F.Fab")
		)
		(pad "1" smd rect
			(at 0 0 90)
			(size 0.762 0.889)
			(layers "F.Cu" "F.Mask" "F.Paste")
			(net "PVCCIO_CPU0")
		)
		(pad "2" smd rect
			(at 0 1.397 90)
			(size 0.762 0.889)
			(layers "F.Cu" "F.Mask" "F.Paste")
			(net "GND")
		)
		(zone
			(layer "F.Cu")
			(hatch none 0.5)
			(connect_pads
				(clearance 0)
			)
			(min_thickness 0.25)
			(keepout
				(tracks not_allowed)
				(vias allowed)
				(pads allowed)
				(copperpour not_allowed)
				(footprints allowed)
			)
			(placement
				(enabled no)
				(sheetname "")
			)
			(fill
				(thermal_gap 0.5)
				(thermal_bridge_width 0.5)
				(island_removal_mode 0)
			)
			(polygon
				(pts
					(xy 339.8393 -103.5558) (xy 339.8393 -104.3178) (xy 340.3473 -104.3178) (xy 340.3473 -103.5558)
				)
			)
		)
	)
	(footprint ""
		(layer "F.Cu")
		(at 13.8938 -25.019 90)
		(property "Reference" "C1F17"
			(at 0 0 90)
			(layer "F.SilkS")
			(hide yes)
			(effects
				(font
					(size 1.27 1.27)
				)
			)
		)
		(property "Value" ""
			(at 0 0 90)
			(layer "F.Fab")
			(effects
				(font
					(size 1.27 1.27)
				)
			)
		)
		(duplicate_pad_numbers_are_jumpers no)
		(fp_rect
			(start -0.3048 -0.1016)
			(end 0.3048 0.9906)
			(stroke
				(width 0)
				(type default)
			)
			(fill no)
			(layer "F.CrtYd")
		)
		(fp_line
			(start 0.3048 -0.1016)
			(end -0.3048 -0.1016)
			(stroke
				(width 0.1)
				(type default)
			)
			(layer "F.Fab")
		)
		(fp_line
			(start -0.3048 -0.1016)
			(end -0.3048 0.9906)
			(stroke
				(width 0.1)
				(type default)
			)
			(layer "F.Fab")
		)
		(fp_line
			(start 0.3048 0.9906)
			(end 0.3048 -0.1016)
			(stroke
				(width 0.1)
				(type default)
			)
			(layer "F.Fab")
		)
		(fp_line
			(start -0.3048 0.9906)
			(end 0.3048 0.9906)
			(stroke
				(width 0.1)
				(type default)
			)
			(layer "F.Fab")
		)
		(pad "1" smd rect
			(at 0 0 90)
			(size 0.508 0.508)
			(layers "F.Cu" "F.Mask" "F.Paste")
			(net "P3E_CPU1_PE3_MP_C_TXP<1>")
		)
		(pad "2" smd rect
			(at 0 0.889 90)
			(size 0.508 0.508)
			(layers "F.Cu" "F.Mask" "F.Paste")
			(net "P3E_CPU1_PE3_MP_TXP<1>")
		)
		(zone
			(layer "F.Cu")
			(hatch none 0.5)
			(connect_pads
				(clearance 0)
			)
			(min_thickness 0.25)
			(keepout
				(tracks allowed)
				(vias not_allowed)
				(pads allowed)
				(copperpour not_allowed)
				(footprints allowed)
			)
			(placement
				(enabled no)
				(sheetname "")
			)
			(fill
				(thermal_gap 0.5)
				(thermal_bridge_width 0.5)
				(island_removal_mode 0)
			)
			(polygon
				(pts
					(xy 14.1478 -24.765) (xy 14.5288 -24.765) (xy 14.5288 -25.273) (xy 14.1478 -25.273)
				)
			)
		)
		(zone
			(layer "F.Cu")
			(hatch none 0.5)
			(connect_pads
				(clearance 0)
			)
			(min_thickness 0.25)
			(keepout
				(tracks not_allowed)
				(vias allowed)
				(pads allowed)
				(copperpour not_allowed)
				(footprints allowed)
			)
			(placement
				(enabled no)
				(sheetname "")
			)
			(fill
				(thermal_gap 0.5)
				(thermal_bridge_width 0.5)
				(island_removal_mode 0)
			)
			(polygon
				(pts
					(xy 14.1478 -24.765) (xy 14.5288 -24.765) (xy 14.5288 -25.273) (xy 14.1478 -25.273)
				)
			)
		)
	)
	(footprint ""
		(layer "F.Cu")
		(at 101.3968 -149.8092 90)
		(property "Reference" "C2A6"
			(at 1.848866 0.752348 90)
			(unlocked yes)
			(layer "F.SilkS")
			(effects
				(font
					(size 1.27 0.9652)
					(thickness 0.1524)
				)
			)
		)
		(property "Value" ""
			(at 0 0 90)
			(layer "F.Fab")
			(effects
				(font
					(size 1.27 1.27)
				)
			)
		)
		(duplicate_pad_numbers_are_jumpers no)
		(fp_rect
			(start -0.500126 1.598422)
			(end 0.500126 -0.201422)
			(stroke
				(width 0)
				(type default)
			)
			(fill no)
			(layer "F.CrtYd")
		)
		(fp_line
			(start 0.500126 -0.201422)
			(end 0.500126 1.598422)
			(stroke
				(width 0.1)
				(type default)
			)
			(layer "F.Fab")
		)
		(fp_line
			(start -0.500126 -0.201422)
			(end 0.500126 -0.201422)
			(stroke
				(width 0.1)
				(type default)
			)
			(layer "F.Fab")
		)
		(fp_line
			(start 0.500126 1.598422)
			(end -0.500126 1.598422)
			(stroke
				(width 0.1)
				(type default)
			)
			(layer "F.Fab")
		)
		(fp_line
			(start -0.500126 1.598422)
			(end -0.500126 -0.201422)
			(stroke
				(width 0.1)
				(type default)
			)
			(layer "F.Fab")
		)
		(pad "1" smd rect
			(at 0 0)
			(size 0.889 0.9906)
			(layers "F.Cu" "F.Mask" "F.Paste")
			(net "PVDDQ_KLM")
		)
		(pad "2" smd rect
			(at 0 1.397)
			(size 0.889 0.9906)
			(layers "F.Cu" "F.Mask" "F.Paste")
			(net "GND")
		)
		(zone
			(layer "F.Cu")
			(hatch none 0.5)
			(connect_pads
				(clearance 0)
			)
			(min_thickness 0.25)
			(keepout
				(tracks allowed)
				(vias not_allowed)
				(pads allowed)
				(copperpour not_allowed)
				(footprints allowed)
			)
			(placement
				(enabled no)
				(sheetname "")
			)
			(fill
				(thermal_gap 0.5)
				(thermal_bridge_width 0.5)
				(island_removal_mode 0)
			)
			(polygon
				(pts
					(xy 102.3493 -149.3139) (xy 102.3493 -150.3045) (xy 101.8413 -150.3045) (xy 101.8413 -149.3139)
				)
			)
		)
		(zone
			(layer "F.Cu")
			(hatch none 0.5)
			(connect_pads
				(clearance 0)
			)
			(min_thickness 0.25)
			(keepout
				(tracks not_allowed)
				(vias allowed)
				(pads allowed)
				(copperpour not_allowed)
				(footprints allowed)
			)
			(placement
				(enabled no)
				(sheetname "")
			)
			(fill
				(thermal_gap 0.5)
				(thermal_bridge_width 0.5)
				(island_removal_mode 0)
			)
			(polygon
				(pts
					(xy 102.3493 -149.3139) (xy 102.3493 -150.3045) (xy 101.8413 -150.3045) (xy 101.8413 -149.3139)
				)
			)
		)
	)
	(footprint ""
		(layer "F.Cu")
		(at 173.736 -86.868 180)
		(property "Reference" "R4D8"
			(at 0 0 180)
			(layer "F.SilkS")
			(hide yes)
			(effects
				(font
					(size 1.27 1.27)
				)
			)
		)
		(property "Value" ""
			(at 0 0 180)
			(layer "F.Fab")
			(effects
				(font
					(size 1.27 1.27)
				)
			)
		)
		(duplicate_pad_numbers_are_jumpers no)
		(fp_poly
			(pts
				(xy -0.2794 -0.1016) (xy 0.2794 -0.1016) (xy 0.2794 0.9906) (xy -0.2794 0.9906)
			)
			(stroke
				(width 0)
				(type default)
			)
			(fill no)
			(layer "F.CrtYd")
		)
		(fp_line
			(start 0.2794 0.9906)
			(end 0.2794 -0.1016)
			(stroke
				(width 0.1)
				(type default)
			)
			(layer "F.Fab")
		)
		(fp_line
			(start 0.2794 -0.1016)
			(end -0.2794 -0.1016)
			(stroke
				(width 0.1)
				(type default)
			)
			(layer "F.Fab")
		)
		(fp_line
			(start -0.2794 0.9906)
			(end 0.2794 0.9906)
			(stroke
				(width 0.1)
				(type default)
			)
			(layer "F.Fab")
		)
		(fp_line
			(start -0.2794 -0.1016)
			(end -0.2794 0.9906)
			(stroke
				(width 0.1)
				(type default)
			)
			(layer "F.Fab")
		)
		(pad "1" smd rect
			(at 0 0 180)
			(size 0.508 0.508)
			(layers "F.Cu" "F.Mask" "F.Paste")
			(net "CLK_100M_CPU0_RC_REFCLK0_R_DP")
		)
		(pad "2" smd rect
			(at 0 0.889 180)
			(size 0.508 0.508)
			(layers "F.Cu" "F.Mask" "F.Paste")
			(net "CLK_100M_CPU0_RC_REFCLK0_DP")
		)
		(zone
			(layer "F.Cu")
			(hatch none 0.5)
			(connect_pads
				(clearance 0)
			)
			(min_thickness 0.25)
			(keepout
				(tracks not_allowed)
				(vias allowed)
				(pads allowed)
				(copperpour not_allowed)
				(footprints allowed)
			)
			(placement
				(enabled no)
				(sheetname "")
			)
			(fill
				(thermal_gap 0.5)
				(thermal_bridge_width 0.5)
				(island_removal_mode 0)
			)
			(polygon
				(pts
					(xy 173.99 -87.503) (xy 173.482 -87.503) (xy 173.482 -87.122) (xy 173.99 -87.122)
				)
			)
		)
		(zone
			(layer "F.Cu")
			(hatch none 0.5)
			(connect_pads
				(clearance 0)
			)
			(min_thickness 0.25)
			(keepout
				(tracks allowed)
				(vias not_allowed)
				(pads allowed)
				(copperpour not_allowed)
				(footprints allowed)
			)
			(placement
				(enabled no)
				(sheetname "")
			)
			(fill
				(thermal_gap 0.5)
				(thermal_bridge_width 0.5)
				(island_removal_mode 0)
			)
			(polygon
				(pts
					(xy 173.99 -87.122) (xy 173.482 -87.122) (xy 173.482 -87.503) (xy 173.99 -87.503)
				)
			)
		)
	)
	(footprint ""
		(layer "F.Cu")
		(at 386.2705 -79.8322 90)
		(property "Reference" "R7D26"
			(at 0 0 90)
			(layer "F.SilkS")
			(hide yes)
			(effects
				(font
					(size 1.27 1.27)
				)
			)
		)
		(property "Value" ""
			(at 0 0 90)
			(layer "F.Fab")
			(effects
				(font
					(size 1.27 1.27)
				)
			)
		)
		(duplicate_pad_numbers_are_jumpers no)
		(fp_poly
			(pts
				(xy -0.2794 -0.1016) (xy 0.2794 -0.1016) (xy 0.2794 0.9906) (xy -0.2794 0.9906)
			)
			(stroke
				(width 0)
				(type default)
			)
			(fill no)
			(layer "F.CrtYd")
		)
		(fp_line
			(start 0.2794 -0.1016)
			(end -0.2794 -0.1016)
			(stroke
				(width 0.1)
				(type default)
			)
			(layer "F.Fab")
		)
		(fp_line
			(start -0.2794 -0.1016)
			(end -0.2794 0.9906)
			(stroke
				(width 0.1)
				(type default)
			)
			(layer "F.Fab")
		)
		(fp_line
			(start 0.2794 0.9906)
			(end 0.2794 -0.1016)
			(stroke
				(width 0.1)
				(type default)
			)
			(layer "F.Fab")
		)
		(fp_line
			(start -0.2794 0.9906)
			(end 0.2794 0.9906)
			(stroke
				(width 0.1)
				(type default)
			)
			(layer "F.Fab")
		)
		(pad "1" smd rect
			(at 0 0 90)
			(size 0.508 0.508)
			(layers "F.Cu" "F.Mask" "F.Paste")
			(net "PD_GTL2104_DIR_0")
		)
		(pad "2" smd rect
			(at 0 0.889 90)
			(size 0.508 0.508)
			(layers "F.Cu" "F.Mask" "F.Paste")
			(net "GND")
		)
		(zone
			(layer "F.Cu")
			(hatch none 0.5)
			(connect_pads
				(clearance 0)
			)
			(min_thickness 0.25)
			(keepout
				(tracks allowed)
				(vias not_allowed)
				(pads allowed)
				(copperpour not_allowed)
				(footprints allowed)
			)
			(placement
				(enabled no)
				(sheetname "")
			)
			(fill
				(thermal_gap 0.5)
				(thermal_bridge_width 0.5)
				(island_removal_mode 0)
			)
			(polygon
				(pts
					(xy 386.5245 -79.5782) (xy 386.5245 -80.0862) (xy 386.9055 -80.0862) (xy 386.9055 -79.5782)
				)
			)
		)
		(zone
			(layer "F.Cu")
			(hatch none 0.5)
			(connect_pads
				(clearance 0)
			)
			(min_thickness 0.25)
			(keepout
				(tracks not_allowed)
				(vias allowed)
				(pads allowed)
				(copperpour not_allowed)
				(footprints allowed)
			)
			(placement
				(enabled no)
				(sheetname "")
			)
			(fill
				(thermal_gap 0.5)
				(thermal_bridge_width 0.5)
				(island_removal_mode 0)
			)
			(polygon
				(pts
					(xy 386.9055 -79.5782) (xy 386.9055 -80.0862) (xy 386.5245 -80.0862) (xy 386.5245 -79.5782)
				)
			)
		)
	)
	(footprint ""
		(layer "F.Cu")
		(at 168.7322 -8.0137)
		(property "Reference" "R4G10"
			(at 0 0 0)
			(layer "F.SilkS")
			(hide yes)
			(effects
				(font
					(size 1.27 1.27)
				)
			)
		)
		(property "Value" ""
			(at 0 0 0)
			(layer "F.Fab")
			(effects
				(font
					(size 1.27 1.27)
				)
			)
		)
		(duplicate_pad_numbers_are_jumpers no)
		(fp_poly
			(pts
				(xy -0.2794 -0.1016) (xy 0.2794 -0.1016) (xy 0.2794 0.9906) (xy -0.2794 0.9906)
			)
			(stroke
				(width 0)
				(type default)
			)
			(fill no)
			(layer "F.CrtYd")
		)
		(fp_line
			(start -0.2794 -0.1016)
			(end -0.2794 0.9906)
			(stroke
				(width 0.1)
				(type default)
			)
			(layer "F.Fab")
		)
		(fp_line
			(start -0.2794 0.9906)
			(end 0.2794 0.9906)
			(stroke
				(width 0.1)
				(type default)
			)
			(layer "F.Fab")
		)
		(fp_line
			(start 0.2794 -0.1016)
			(end -0.2794 -0.1016)
			(stroke
				(width 0.1)
				(type default)
			)
			(layer "F.Fab")
		)
		(fp_line
			(start 0.2794 0.9906)
			(end 0.2794 -0.1016)
			(stroke
				(width 0.1)
				(type default)
			)
			(layer "F.Fab")
		)
		(pad "1" smd rect
			(at 0 0)
			(size 0.508 0.508)
			(layers "F.Cu" "F.Mask" "F.Paste")
			(net "VSENSE_PVPP_GHJ")
		)
		(pad "2" smd rect
			(at 0 0.889)
			(size 0.508 0.508)
			(layers "F.Cu" "F.Mask" "F.Paste")
			(net "VR_COMP_PVPP_GHJ")
		)
		(zone
			(layer "F.Cu")
			(hatch none 0.5)
			(connect_pads
				(clearance 0)
			)
			(min_thickness 0.25)
			(keepout
				(tracks allowed)
				(vias not_allowed)
				(pads allowed)
				(copperpour not_allowed)
				(footprints allowed)
			)
			(placement
				(enabled no)
				(sheetname "")
			)
			(fill
				(thermal_gap 0.5)
				(thermal_bridge_width 0.5)
				(island_removal_mode 0)
			)
			(polygon
				(pts
					(xy 168.4782 -7.7597) (xy 168.9862 -7.7597) (xy 168.9862 -7.3787) (xy 168.4782 -7.3787)
				)
			)
		)
		(zone
			(layer "F.Cu")
			(hatch none 0.5)
			(connect_pads
				(clearance 0)
			)
			(min_thickness 0.25)
			(keepout
				(tracks not_allowed)
				(vias allowed)
				(pads allowed)
				(copperpour not_allowed)
				(footprints allowed)
			)
			(placement
				(enabled no)
				(sheetname "")
			)
			(fill
				(thermal_gap 0.5)
				(thermal_bridge_width 0.5)
				(island_removal_mode 0)
			)
			(polygon
				(pts
					(xy 168.4782 -7.3787) (xy 168.9862 -7.3787) (xy 168.9862 -7.7597) (xy 168.4782 -7.7597)
				)
			)
		)
	)
	(footprint ""
		(layer "F.Cu")
		(at 401.7518 -53.53558 -90)
		(property "Reference" "R7F5"
			(at 0 0 270)
			(layer "F.SilkS")
			(hide yes)
			(effects
				(font
					(size 1.27 1.27)
				)
			)
		)
		(property "Value" ""
			(at 0 0 270)
			(layer "F.Fab")
			(effects
				(font
					(size 1.27 1.27)
				)
			)
		)
		(duplicate_pad_numbers_are_jumpers no)
		(fp_poly
			(pts
				(xy -0.2794 -0.1016) (xy 0.2794 -0.1016) (xy 0.2794 0.9906) (xy -0.2794 0.9906)
			)
			(stroke
				(width 0)
				(type default)
			)
			(fill no)
			(layer "F.CrtYd")
		)
		(fp_line
			(start -0.2794 0.9906)
			(end 0.2794 0.9906)
			(stroke
				(width 0.1)
				(type default)
			)
			(layer "F.Fab")
		)
		(fp_line
			(start 0.2794 0.9906)
			(end 0.2794 -0.1016)
			(stroke
				(width 0.1)
				(type default)
			)
			(layer "F.Fab")
		)
		(fp_line
			(start -0.2794 -0.1016)
			(end -0.2794 0.9906)
			(stroke
				(width 0.1)
				(type default)
			)
			(layer "F.Fab")
		)
		(fp_line
			(start 0.2794 -0.1016)
			(end -0.2794 -0.1016)
			(stroke
				(width 0.1)
				(type default)
			)
			(layer "F.Fab")
		)
		(pad "1" smd rect
			(at 0 0 270)
			(size 0.508 0.508)
			(layers "F.Cu" "F.Mask" "F.Paste")
			(net "P3V3_STBY")
		)
		(pad "2" smd rect
			(at 0 0.889 270)
			(size 0.508 0.508)
			(layers "F.Cu" "F.Mask" "F.Paste")
			(net "SPI_CS0_PRIMARY_R_N")
		)
		(zone
			(layer "F.Cu")
			(hatch none 0.5)
			(connect_pads
				(clearance 0)
			)
			(min_thickness 0.25)
			(keepout
				(tracks not_allowed)
				(vias allowed)
				(pads allowed)
				(copperpour not_allowed)
				(footprints allowed)
			)
			(placement
				(enabled no)
				(sheetname "")
			)
			(fill
				(thermal_gap 0.5)
				(thermal_bridge_width 0.5)
				(island_removal_mode 0)
			)
			(polygon
				(pts
					(xy 401.1168 -53.78958) (xy 401.1168 -53.28158) (xy 401.4978 -53.28158) (xy 401.4978 -53.78958)
				)
			)
		)
		(zone
			(layer "F.Cu")
			(hatch none 0.5)
			(connect_pads
				(clearance 0)
			)
			(min_thickness 0.25)
			(keepout
				(tracks allowed)
				(vias not_allowed)
				(pads allowed)
				(copperpour not_allowed)
				(footprints allowed)
			)
			(placement
				(enabled no)
				(sheetname "")
			)
			(fill
				(thermal_gap 0.5)
				(thermal_bridge_width 0.5)
				(island_removal_mode 0)
			)
			(polygon
				(pts
					(xy 401.4978 -53.78958) (xy 401.4978 -53.28158) (xy 401.1168 -53.28158) (xy 401.1168 -53.78958)
				)
			)
		)
	)
	(footprint ""
		(layer "F.Cu")
		(at 198.00443 -69.318124 90)
		(property "Reference" "C4D13"
			(at -0.8382 -0.67818 90)
			(unlocked yes)
			(layer "F.SilkS")
			(effects
				(font
					(size 0.4064 0.254)
					(thickness 0.1524)
				)
				(justify left)
			)
		)
		(property "Value" ""
			(at 0 0 90)
			(layer "F.Fab")
			(effects
				(font
					(size 1.27 1.27)
				)
			)
		)
		(duplicate_pad_numbers_are_jumpers no)
		(fp_poly
			(pts
				(xy 0.3048 -0.1016) (xy 0.3048 0.9906) (xy -0.3048 0.9906) (xy -0.3048 -0.1016)
			)
			(stroke
				(width 0)
				(type default)
			)
			(fill no)
			(layer "F.CrtYd")
		)
		(fp_line
			(start 0.3048 -0.1016)
			(end -0.3048 -0.1016)
			(stroke
				(width 0.1)
				(type default)
			)
			(layer "F.Fab")
		)
		(fp_line
			(start -0.3048 -0.1016)
			(end -0.3048 0.9906)
			(stroke
				(width 0.1)
				(type default)
			)
			(layer "F.Fab")
		)
		(fp_line
			(start 0.3048 0.9906)
			(end 0.3048 -0.1016)
			(stroke
				(width 0.1)
				(type default)
			)
			(layer "F.Fab")
		)
		(fp_line
			(start -0.3048 0.9906)
			(end 0.3048 0.9906)
			(stroke
				(width 0.1)
				(type default)
			)
			(layer "F.Fab")
		)
		(pad "1" smd rect
			(at 0 0 90)
			(size 0.508 0.508)
			(layers "F.Cu" "F.Mask" "F.Paste")
			(net "P5V_STBY")
		)
		(pad "2" smd rect
			(at 0 0.889 90)
			(size 0.508 0.508)
			(layers "F.Cu" "F.Mask" "F.Paste")
			(net "GND")
		)
		(zone
			(layer "F.Cu")
			(hatch none 0.5)
			(connect_pads
				(clearance 0)
			)
			(min_thickness 0.25)
			(keepout
				(tracks allowed)
				(vias not_allowed)
				(pads allowed)
				(copperpour not_allowed)
				(footprints allowed)
			)
			(placement
				(enabled no)
				(sheetname "")
			)
			(fill
				(thermal_gap 0.5)
				(thermal_bridge_width 0.5)
				(island_removal_mode 0)
			)
			(polygon
				(pts
					(xy 198.25843 -69.064124) (xy 198.25843 -69.572124) (xy 198.63943 -69.572124) (xy 198.63943 -69.064124)
				)
			)
		)
		(zone
			(layer "F.Cu")
			(hatch none 0.5)
			(connect_pads
				(clearance 0)
			)
			(min_thickness 0.25)
			(keepout
				(tracks not_allowed)
				(vias allowed)
				(pads allowed)
				(copperpour not_allowed)
				(footprints allowed)
			)
			(placement
				(enabled no)
				(sheetname "")
			)
			(fill
				(thermal_gap 0.5)
				(thermal_bridge_width 0.5)
				(island_removal_mode 0)
			)
			(polygon
				(pts
					(xy 198.63943 -69.064124) (xy 198.63943 -69.572124) (xy 198.25843 -69.572124) (xy 198.25843 -69.064124)
				)
			)
		)
	)
	(footprint ""
		(layer "F.Cu")
		(at 163.88842 -124.5235)
		(property "Reference" "Q4B2"
			(at 1.33858 -1.05283 0)
			(unlocked yes)
			(layer "F.SilkS")
			(effects
				(font
					(size 0.7874 0.5842)
					(thickness 0.1524)
				)
				(justify left)
			)
		)
		(property "Value" ""
			(at 0 0 0)
			(layer "F.Fab")
			(effects
				(font
					(size 1.27 1.27)
				)
			)
		)
		(duplicate_pad_numbers_are_jumpers no)
		(fp_circle
			(center -0.508 -0.7874)
			(end -0.381 -0.7874)
			(stroke
				(width 0.254)
				(type default)
			)
			(fill no)
			(layer "F.SilkS")
		)
		(fp_poly
			(pts
				(xy 0.2159 1.7526) (xy 1.5621 1.7526) (xy 1.5621 -0.4572) (xy 0.2159 -0.4572)
			)
			(stroke
				(width 0)
				(type default)
			)
			(fill no)
			(layer "F.CrtYd")
		)
		(fp_line
			(start 0.2159 -0.45466)
			(end 0.2159 1.75514)
			(stroke
				(width 0.1)
				(type default)
			)
			(layer "F.Fab")
		)
		(fp_line
			(start 0.2159 1.75514)
			(end 1.5621 1.75514)
			(stroke
				(width 0.1)
				(type default)
			)
			(layer "F.Fab")
		)
		(fp_line
			(start 1.5621 -0.45466)
			(end 0.2159 -0.45466)
			(stroke
				(width 0.1)
				(type default)
			)
			(layer "F.Fab")
		)
		(fp_line
			(start 1.5621 1.75514)
			(end 1.5621 -0.45466)
			(stroke
				(width 0.1)
				(type default)
			)
			(layer "F.Fab")
		)
		(fp_circle
			(center -0.508 -0.7874)
			(end -0.381 -0.7874)
			(stroke
				(width 0.254)
				(type default)
			)
			(fill no)
			(layer "F.Fab")
		)
		(pad "1" smd rect
			(at 0 0)
			(size 1.016 0.381)
			(layers "F.Cu" "F.Mask" "F.Paste")
			(net "GND")
		)
		(pad "2" smd rect
			(at 0 0.65024)
			(size 1.016 0.381)
			(layers "F.Cu" "F.Mask" "F.Paste")
			(net "FM_SYS_THROTTLE_LVC3")
		)
		(pad "3" smd rect
			(at 0 1.30048)
			(size 1.016 0.381)
			(layers "F.Cu" "F.Mask" "F.Paste")
			(net "H_CPU1_MEMKLM_MEMHOT_G_N")
		)
		(pad "4" smd rect
			(at 1.778 1.30048)
			(size 1.016 0.381)
			(layers "F.Cu" "F.Mask" "F.Paste")
			(net "GND")
		)
		(pad "5" smd rect
			(at 1.778 0.65024)
			(size 1.016 0.381)
			(layers "F.Cu" "F.Mask" "F.Paste")
			(net "FM_SYS_THROTTLE_LVC3")
		)
		(pad "6" smd rect
			(at 1.778 0)
			(size 1.016 0.381)
			(layers "F.Cu" "F.Mask" "F.Paste")
			(net "H_CPU1_MEMGHJ_MEMHOT_G_N")
		)
		(zone
			(layer "F.Cu")
			(hatch none 0.5)
			(connect_pads
				(clearance 0)
			)
			(min_thickness 0.25)
			(keepout
				(tracks allowed)
				(vias not_allowed)
				(pads allowed)
				(copperpour not_allowed)
				(footprints allowed)
			)
			(placement
				(enabled no)
				(sheetname "")
			)
			(fill
				(thermal_gap 0.5)
				(thermal_bridge_width 0.5)
				(island_removal_mode 0)
			)
			(polygon
				(pts
					(xy 163.38042 -124.714) (xy 164.39642 -124.714) (xy 164.39642 -123.0249) (xy 163.38042 -123.0249)
				)
			)
		)
		(zone
			(layer "F.Cu")
			(hatch none 0.5)
			(connect_pads
				(clearance 0)
			)
			(min_thickness 0.25)
			(keepout
				(tracks allowed)
				(vias not_allowed)
				(pads allowed)
				(copperpour not_allowed)
				(footprints allowed)
			)
			(placement
				(enabled no)
				(sheetname "")
			)
			(fill
				(thermal_gap 0.5)
				(thermal_bridge_width 0.5)
				(island_removal_mode 0)
			)
			(polygon
				(pts
					(xy 165.15842 -124.714) (xy 166.17442 -124.714) (xy 166.17442 -123.0249) (xy 165.15842 -123.0249)
				)
			)
		)
	)
	(footprint ""
		(layer "F.Cu")
		(at 170.7896 -131.0005 180)
		(property "Reference" "R4B5"
			(at 0 0 180)
			(layer "F.SilkS")
			(hide yes)
			(effects
				(font
					(size 1.27 1.27)
				)
			)
		)
		(property "Value" ""
			(at 0 0 180)
			(layer "F.Fab")
			(effects
				(font
					(size 1.27 1.27)
				)
			)
		)
		(duplicate_pad_numbers_are_jumpers no)
		(fp_poly
			(pts
				(xy -0.2794 -0.1016) (xy 0.2794 -0.1016) (xy 0.2794 0.9906) (xy -0.2794 0.9906)
			)
			(stroke
				(width 0)
				(type default)
			)
			(fill no)
			(layer "F.CrtYd")
		)
		(fp_line
			(start 0.2794 0.9906)
			(end 0.2794 -0.1016)
			(stroke
				(width 0.1)
				(type default)
			)
			(layer "F.Fab")
		)
		(fp_line
			(start 0.2794 -0.1016)
			(end -0.2794 -0.1016)
			(stroke
				(width 0.1)
				(type default)
			)
			(layer "F.Fab")
		)
		(fp_line
			(start -0.2794 0.9906)
			(end 0.2794 0.9906)
			(stroke
				(width 0.1)
				(type default)
			)
			(layer "F.Fab")
		)
		(fp_line
			(start -0.2794 -0.1016)
			(end -0.2794 0.9906)
			(stroke
				(width 0.1)
				(type default)
			)
			(layer "F.Fab")
		)
		(pad "1" smd rect
			(at 0 0 180)
			(size 0.508 0.508)
			(layers "F.Cu" "F.Mask" "F.Paste")
			(net "VSENSE_PVPP_KLM")
		)
		(pad "2" smd rect
			(at 0 0.889 180)
			(size 0.508 0.508)
			(layers "F.Cu" "F.Mask" "F.Paste")
			(net "VR_FB_PVPP_KLM")
		)
		(zone
			(layer "F.Cu")
			(hatch none 0.5)
			(connect_pads
				(clearance 0)
			)
			(min_thickness 0.25)
			(keepout
				(tracks not_allowed)
				(vias allowed)
				(pads allowed)
				(copperpour not_allowed)
				(footprints allowed)
			)
			(placement
				(enabled no)
				(sheetname "")
			)
			(fill
				(thermal_gap 0.5)
				(thermal_bridge_width 0.5)
				(island_removal_mode 0)
			)
			(polygon
				(pts
					(xy 171.0436 -131.6355) (xy 170.5356 -131.6355) (xy 170.5356 -131.2545) (xy 171.0436 -131.2545)
				)
			)
		)
		(zone
			(layer "F.Cu")
			(hatch none 0.5)
			(connect_pads
				(clearance 0)
			)
			(min_thickness 0.25)
			(keepout
				(tracks allowed)
				(vias not_allowed)
				(pads allowed)
				(copperpour not_allowed)
				(footprints allowed)
			)
			(placement
				(enabled no)
				(sheetname "")
			)
			(fill
				(thermal_gap 0.5)
				(thermal_bridge_width 0.5)
				(island_removal_mode 0)
			)
			(polygon
				(pts
					(xy 171.0436 -131.2545) (xy 170.5356 -131.2545) (xy 170.5356 -131.6355) (xy 171.0436 -131.6355)
				)
			)
		)
	)
	(footprint ""
		(layer "F.Cu")
		(at 174.3583 -150.114 90)
		(property "Reference" "R4A4"
			(at 0 0 90)
			(layer "F.SilkS")
			(hide yes)
			(effects
				(font
					(size 1.27 1.27)
				)
			)
		)
		(property "Value" ""
			(at 0 0 90)
			(layer "F.Fab")
			(effects
				(font
					(size 1.27 1.27)
				)
			)
		)
		(duplicate_pad_numbers_are_jumpers no)
		(fp_poly
			(pts
				(xy -0.2794 -0.1016) (xy 0.2794 -0.1016) (xy 0.2794 0.9906) (xy -0.2794 0.9906)
			)
			(stroke
				(width 0)
				(type default)
			)
			(fill no)
			(layer "F.CrtYd")
		)
		(fp_line
			(start 0.2794 -0.1016)
			(end -0.2794 -0.1016)
			(stroke
				(width 0.1)
				(type default)
			)
			(layer "F.Fab")
		)
		(fp_line
			(start -0.2794 -0.1016)
			(end -0.2794 0.9906)
			(stroke
				(width 0.1)
				(type default)
			)
			(layer "F.Fab")
		)
		(fp_line
			(start 0.2794 0.9906)
			(end 0.2794 -0.1016)
			(stroke
				(width 0.1)
				(type default)
			)
			(layer "F.Fab")
		)
		(fp_line
			(start -0.2794 0.9906)
			(end 0.2794 0.9906)
			(stroke
				(width 0.1)
				(type default)
			)
			(layer "F.Fab")
		)
		(pad "1" smd rect
			(at 0 0 90)
			(size 0.508 0.508)
			(layers "F.Cu" "F.Mask" "F.Paste")
			(net "PWRGD_PVTT_KLM_CPU1_R")
		)
		(pad "2" smd rect
			(at 0 0.889 90)
			(size 0.508 0.508)
			(layers "F.Cu" "F.Mask" "F.Paste")
			(net "PWRGD_PVTT_CPU1")
		)
		(zone
			(layer "F.Cu")
			(hatch none 0.5)
			(connect_pads
				(clearance 0)
			)
			(min_thickness 0.25)
			(keepout
				(tracks allowed)
				(vias not_allowed)
				(pads allowed)
				(copperpour not_allowed)
				(footprints allowed)
			)
			(placement
				(enabled no)
				(sheetname "")
			)
			(fill
				(thermal_gap 0.5)
				(thermal_bridge_width 0.5)
				(island_removal_mode 0)
			)
			(polygon
				(pts
					(xy 174.6123 -149.86) (xy 174.6123 -150.368) (xy 174.9933 -150.368) (xy 174.9933 -149.86)
				)
			)
		)
		(zone
			(layer "F.Cu")
			(hatch none 0.5)
			(connect_pads
				(clearance 0)
			)
			(min_thickness 0.25)
			(keepout
				(tracks not_allowed)
				(vias allowed)
				(pads allowed)
				(copperpour not_allowed)
				(footprints allowed)
			)
			(placement
				(enabled no)
				(sheetname "")
			)
			(fill
				(thermal_gap 0.5)
				(thermal_bridge_width 0.5)
				(island_removal_mode 0)
			)
			(polygon
				(pts
					(xy 174.9933 -149.86) (xy 174.9933 -150.368) (xy 174.6123 -150.368) (xy 174.6123 -149.86)
				)
			)
		)
	)
	(footprint ""
		(layer "F.Cu")
		(at 6.35 -125.095 90)
		(property "Reference" "R1B15"
			(at 0 0 90)
			(layer "F.SilkS")
			(hide yes)
			(effects
				(font
					(size 1.27 1.27)
				)
			)
		)
		(property "Value" ""
			(at 0 0 90)
			(layer "F.Fab")
			(effects
				(font
					(size 1.27 1.27)
				)
			)
		)
		(duplicate_pad_numbers_are_jumpers no)
		(fp_poly
			(pts
				(xy -0.2794 -0.1016) (xy 0.2794 -0.1016) (xy 0.2794 0.9906) (xy -0.2794 0.9906)
			)
			(stroke
				(width 0)
				(type default)
			)
			(fill no)
			(layer "F.CrtYd")
		)
		(fp_line
			(start 0.2794 -0.1016)
			(end -0.2794 -0.1016)
			(stroke
				(width 0.1)
				(type default)
			)
			(layer "F.Fab")
		)
		(fp_line
			(start -0.2794 -0.1016)
			(end -0.2794 0.9906)
			(stroke
				(width 0.1)
				(type default)
			)
			(layer "F.Fab")
		)
		(fp_line
			(start 0.2794 0.9906)
			(end 0.2794 -0.1016)
			(stroke
				(width 0.1)
				(type default)
			)
			(layer "F.Fab")
		)
		(fp_line
			(start -0.2794 0.9906)
			(end 0.2794 0.9906)
			(stroke
				(width 0.1)
				(type default)
			)
			(layer "F.Fab")
		)
		(pad "1" smd rect
			(at 0 0 90)
			(size 0.508 0.508)
			(layers "F.Cu" "F.Mask" "F.Paste")
			(net "VR_PVDDQ_KLM_XADDR2")
		)
		(pad "2" smd rect
			(at 0 0.889 90)
			(size 0.508 0.508)
			(layers "F.Cu" "F.Mask" "F.Paste")
			(net "GND")
		)
		(zone
			(layer "F.Cu")
			(hatch none 0.5)
			(connect_pads
				(clearance 0)
			)
			(min_thickness 0.25)
			(keepout
				(tracks allowed)
				(vias not_allowed)
				(pads allowed)
				(copperpour not_allowed)
				(footprints allowed)
			)
			(placement
				(enabled no)
				(sheetname "")
			)
			(fill
				(thermal_gap 0.5)
				(thermal_bridge_width 0.5)
				(island_removal_mode 0)
			)
			(polygon
				(pts
					(xy 6.604 -124.841) (xy 6.604 -125.349) (xy 6.985 -125.349) (xy 6.985 -124.841)
				)
			)
		)
		(zone
			(layer "F.Cu")
			(hatch none 0.5)
			(connect_pads
				(clearance 0)
			)
			(min_thickness 0.25)
			(keepout
				(tracks not_allowed)
				(vias allowed)
				(pads allowed)
				(copperpour not_allowed)
				(footprints allowed)
			)
			(placement
				(enabled no)
				(sheetname "")
			)
			(fill
				(thermal_gap 0.5)
				(thermal_bridge_width 0.5)
				(island_removal_mode 0)
			)
			(polygon
				(pts
					(xy 6.985 -124.841) (xy 6.985 -125.349) (xy 6.604 -125.349) (xy 6.604 -124.841)
				)
			)
		)
	)
	(footprint ""
		(layer "F.Cu")
		(at 0.635 -143.256 -90)
		(property "Reference" "C1A6"
			(at 0 0 270)
			(layer "F.SilkS")
			(hide yes)
			(effects
				(font
					(size 1.27 1.27)
				)
			)
		)
		(property "Value" ""
			(at 0 0 270)
			(layer "F.Fab")
			(effects
				(font
					(size 1.27 1.27)
				)
			)
		)
		(duplicate_pad_numbers_are_jumpers no)
		(fp_poly
			(pts
				(xy 0.3048 -0.1016) (xy 0.3048 0.9906) (xy -0.3048 0.9906) (xy -0.3048 -0.1016)
			)
			(stroke
				(width 0)
				(type default)
			)
			(fill no)
			(layer "F.CrtYd")
		)
		(fp_line
			(start -0.3048 0.9906)
			(end 0.3048 0.9906)
			(stroke
				(width 0.1)
				(type default)
			)
			(layer "F.Fab")
		)
		(fp_line
			(start 0.3048 0.9906)
			(end 0.3048 -0.1016)
			(stroke
				(width 0.1)
				(type default)
			)
			(layer "F.Fab")
		)
		(fp_line
			(start -0.3048 -0.1016)
			(end -0.3048 0.9906)
			(stroke
				(width 0.1)
				(type default)
			)
			(layer "F.Fab")
		)
		(fp_line
			(start 0.3048 -0.1016)
			(end -0.3048 -0.1016)
			(stroke
				(width 0.1)
				(type default)
			)
			(layer "F.Fab")
		)
		(pad "1" smd rect
			(at 0 0 270)
			(size 0.508 0.508)
			(layers "F.Cu" "F.Mask" "F.Paste")
			(net "VR_PVDDQ_KLM_PH2_VCIN")
		)
		(pad "2" smd rect
			(at 0 0.889 270)
			(size 0.508 0.508)
			(layers "F.Cu" "F.Mask" "F.Paste")
			(net "GND")
		)
		(zone
			(layer "F.Cu")
			(hatch none 0.5)
			(connect_pads
				(clearance 0)
			)
			(min_thickness 0.25)
			(keepout
				(tracks not_allowed)
				(vias allowed)
				(pads allowed)
				(copperpour not_allowed)
				(footprints allowed)
			)
			(placement
				(enabled no)
				(sheetname "")
			)
			(fill
				(thermal_gap 0.5)
				(thermal_bridge_width 0.5)
				(island_removal_mode 0)
			)
			(polygon
				(pts
					(xy 0 -143.51) (xy 0 -143.002) (xy 0.381 -143.002) (xy 0.381 -143.51)
				)
			)
		)
		(zone
			(layer "F.Cu")
			(hatch none 0.5)
			(connect_pads
				(clearance 0)
			)
			(min_thickness 0.25)
			(keepout
				(tracks allowed)
				(vias not_allowed)
				(pads allowed)
				(copperpour not_allowed)
				(footprints allowed)
			)
			(placement
				(enabled no)
				(sheetname "")
			)
			(fill
				(thermal_gap 0.5)
				(thermal_bridge_width 0.5)
				(island_removal_mode 0)
			)
			(polygon
				(pts
					(xy 0.381 -143.51) (xy 0.381 -143.002) (xy 0 -143.002) (xy 0 -143.51)
				)
			)
		)
	)
	(footprint ""
		(layer "F.Cu")
		(at 380.032768 -33.7185 -90)
		(property "Reference" "C8F7"
			(at 0 0 270)
			(layer "F.SilkS")
			(hide yes)
			(effects
				(font
					(size 1.27 1.27)
				)
			)
		)
		(property "Value" ""
			(at 0 0 270)
			(layer "F.Fab")
			(effects
				(font
					(size 1.27 1.27)
				)
			)
		)
		(duplicate_pad_numbers_are_jumpers no)
		(fp_poly
			(pts
				(xy 0.3048 -0.1016) (xy 0.3048 0.9906) (xy -0.3048 0.9906) (xy -0.3048 -0.1016)
			)
			(stroke
				(width 0)
				(type default)
			)
			(fill no)
			(layer "F.CrtYd")
		)
		(fp_line
			(start -0.3048 0.9906)
			(end 0.3048 0.9906)
			(stroke
				(width 0.1)
				(type default)
			)
			(layer "F.Fab")
		)
		(fp_line
			(start 0.3048 0.9906)
			(end 0.3048 -0.1016)
			(stroke
				(width 0.1)
				(type default)
			)
			(layer "F.Fab")
		)
		(fp_line
			(start -0.3048 -0.1016)
			(end -0.3048 0.9906)
			(stroke
				(width 0.1)
				(type default)
			)
			(layer "F.Fab")
		)
		(fp_line
			(start 0.3048 -0.1016)
			(end -0.3048 -0.1016)
			(stroke
				(width 0.1)
				(type default)
			)
			(layer "F.Fab")
		)
		(pad "1" smd rect
			(at 0 0 270)
			(size 0.508 0.508)
			(layers "F.Cu" "F.Mask" "F.Paste")
			(net "P3E_PCH_TX_0_DP")
		)
		(pad "2" smd rect
			(at 0 0.889 270)
			(size 0.508 0.508)
			(layers "F.Cu" "F.Mask" "F.Paste")
			(net "P3E_PCH_M2_SATA6G_TX_R_DP")
		)
		(zone
			(layer "F.Cu")
			(hatch none 0.5)
			(connect_pads
				(clearance 0)
			)
			(min_thickness 0.25)
			(keepout
				(tracks not_allowed)
				(vias allowed)
				(pads allowed)
				(copperpour not_allowed)
				(footprints allowed)
			)
			(placement
				(enabled no)
				(sheetname "")
			)
			(fill
				(thermal_gap 0.5)
				(thermal_bridge_width 0.5)
				(island_removal_mode 0)
			)
			(polygon
				(pts
					(xy 379.397768 -33.9725) (xy 379.397768 -33.4645) (xy 379.778768 -33.4645) (xy 379.778768 -33.9725)
				)
			)
		)
		(zone
			(layer "F.Cu")
			(hatch none 0.5)
			(connect_pads
				(clearance 0)
			)
			(min_thickness 0.25)
			(keepout
				(tracks allowed)
				(vias not_allowed)
				(pads allowed)
				(copperpour not_allowed)
				(footprints allowed)
			)
			(placement
				(enabled no)
				(sheetname "")
			)
			(fill
				(thermal_gap 0.5)
				(thermal_bridge_width 0.5)
				(island_removal_mode 0)
			)
			(polygon
				(pts
					(xy 379.778768 -33.9725) (xy 379.778768 -33.4645) (xy 379.397768 -33.4645) (xy 379.397768 -33.9725)
				)
			)
		)
	)
	(footprint ""
		(layer "F.Cu")
		(at 429.26 -130.7465 180)
		(property "Reference" "R8E12"
			(at 0 0 180)
			(layer "F.SilkS")
			(hide yes)
			(effects
				(font
					(size 1.27 1.27)
				)
			)
		)
		(property "Value" ""
			(at 0 0 180)
			(layer "F.Fab")
			(effects
				(font
					(size 1.27 1.27)
				)
			)
		)
		(duplicate_pad_numbers_are_jumpers no)
		(fp_poly
			(pts
				(xy -0.2794 -0.1016) (xy 0.2794 -0.1016) (xy 0.2794 0.9906) (xy -0.2794 0.9906)
			)
			(stroke
				(width 0)
				(type default)
			)
			(fill no)
			(layer "F.CrtYd")
		)
		(fp_line
			(start 0.2794 0.9906)
			(end 0.2794 -0.1016)
			(stroke
				(width 0.1)
				(type default)
			)
			(layer "F.Fab")
		)
		(fp_line
			(start 0.2794 -0.1016)
			(end -0.2794 -0.1016)
			(stroke
				(width 0.1)
				(type default)
			)
			(layer "F.Fab")
		)
		(fp_line
			(start -0.2794 0.9906)
			(end 0.2794 0.9906)
			(stroke
				(width 0.1)
				(type default)
			)
			(layer "F.Fab")
		)
		(fp_line
			(start -0.2794 -0.1016)
			(end -0.2794 0.9906)
			(stroke
				(width 0.1)
				(type default)
			)
			(layer "F.Fab")
		)
		(pad "1" smd rect
			(at 0 0 180)
			(size 0.508 0.508)
			(layers "F.Cu" "F.Mask" "F.Paste")
			(net "P3V3_STBY")
		)
		(pad "2" smd rect
			(at 0 0.889 180)
			(size 0.508 0.508)
			(layers "F.Cu" "F.Mask" "F.Paste")
			(net "FM_CTNR_PS_ON")
		)
		(zone
			(layer "F.Cu")
			(hatch none 0.5)
			(connect_pads
				(clearance 0)
			)
			(min_thickness 0.25)
			(keepout
				(tracks not_allowed)
				(vias allowed)
				(pads allowed)
				(copperpour not_allowed)
				(footprints allowed)
			)
			(placement
				(enabled no)
				(sheetname "")
			)
			(fill
				(thermal_gap 0.5)
				(thermal_bridge_width 0.5)
				(island_removal_mode 0)
			)
			(polygon
				(pts
					(xy 429.514 -131.3815) (xy 429.006 -131.3815) (xy 429.006 -131.0005) (xy 429.514 -131.0005)
				)
			)
		)
		(zone
			(layer "F.Cu")
			(hatch none 0.5)
			(connect_pads
				(clearance 0)
			)
			(min_thickness 0.25)
			(keepout
				(tracks allowed)
				(vias not_allowed)
				(pads allowed)
				(copperpour not_allowed)
				(footprints allowed)
			)
			(placement
				(enabled no)
				(sheetname "")
			)
			(fill
				(thermal_gap 0.5)
				(thermal_bridge_width 0.5)
				(island_removal_mode 0)
			)
			(polygon
				(pts
					(xy 429.514 -131.0005) (xy 429.006 -131.0005) (xy 429.006 -131.3815) (xy 429.514 -131.3815)
				)
			)
		)
	)
	(footprint ""
		(layer "F.Cu")
		(at 192.786 -13.3985)
		(property "Reference" "R4G1"
			(at 0 0 0)
			(layer "F.SilkS")
			(hide yes)
			(effects
				(font
					(size 1.27 1.27)
				)
			)
		)
		(property "Value" ""
			(at 0 0 0)
			(layer "F.Fab")
			(effects
				(font
					(size 1.27 1.27)
				)
			)
		)
		(duplicate_pad_numbers_are_jumpers no)
		(fp_poly
			(pts
				(xy -0.2794 -0.1016) (xy 0.2794 -0.1016) (xy 0.2794 0.9906) (xy -0.2794 0.9906)
			)
			(stroke
				(width 0)
				(type default)
			)
			(fill no)
			(layer "F.CrtYd")
		)
		(fp_line
			(start -0.2794 -0.1016)
			(end -0.2794 0.9906)
			(stroke
				(width 0.1)
				(type default)
			)
			(layer "F.Fab")
		)
		(fp_line
			(start -0.2794 0.9906)
			(end 0.2794 0.9906)
			(stroke
				(width 0.1)
				(type default)
			)
			(layer "F.Fab")
		)
		(fp_line
			(start 0.2794 -0.1016)
			(end -0.2794 -0.1016)
			(stroke
				(width 0.1)
				(type default)
			)
			(layer "F.Fab")
		)
		(fp_line
			(start 0.2794 0.9906)
			(end 0.2794 -0.1016)
			(stroke
				(width 0.1)
				(type default)
			)
			(layer "F.Fab")
		)
		(pad "1" smd rect
			(at 0 0)
			(size 0.508 0.508)
			(layers "F.Cu" "F.Mask" "F.Paste")
			(net "M_B_CPU_VREF")
		)
		(pad "2" smd rect
			(at 0 0.889)
			(size 0.508 0.508)
			(layers "F.Cu" "F.Mask" "F.Paste")
			(net "M_B_VREF")
		)
		(zone
			(layer "F.Cu")
			(hatch none 0.5)
			(connect_pads
				(clearance 0)
			)
			(min_thickness 0.25)
			(keepout
				(tracks allowed)
				(vias not_allowed)
				(pads allowed)
				(copperpour not_allowed)
				(footprints allowed)
			)
			(placement
				(enabled no)
				(sheetname "")
			)
			(fill
				(thermal_gap 0.5)
				(thermal_bridge_width 0.5)
				(island_removal_mode 0)
			)
			(polygon
				(pts
					(xy 192.532 -13.1445) (xy 193.04 -13.1445) (xy 193.04 -12.7635) (xy 192.532 -12.7635)
				)
			)
		)
		(zone
			(layer "F.Cu")
			(hatch none 0.5)
			(connect_pads
				(clearance 0)
			)
			(min_thickness 0.25)
			(keepout
				(tracks not_allowed)
				(vias allowed)
				(pads allowed)
				(copperpour not_allowed)
				(footprints allowed)
			)
			(placement
				(enabled no)
				(sheetname "")
			)
			(fill
				(thermal_gap 0.5)
				(thermal_bridge_width 0.5)
				(island_removal_mode 0)
			)
			(polygon
				(pts
					(xy 192.532 -12.7635) (xy 193.04 -12.7635) (xy 193.04 -13.1445) (xy 192.532 -13.1445)
				)
			)
		)
	)
	(footprint ""
		(layer "F.Cu")
		(at 18.923 -79.629 180)
		(property "Reference" "C1D11"
			(at 0 0 180)
			(layer "F.SilkS")
			(hide yes)
			(effects
				(font
					(size 1.27 1.27)
				)
			)
		)
		(property "Value" ""
			(at 0 0 180)
			(layer "F.Fab")
			(effects
				(font
					(size 1.27 1.27)
				)
			)
		)
		(duplicate_pad_numbers_are_jumpers no)
		(fp_rect
			(start -0.3048 -0.1016)
			(end 0.3048 0.9906)
			(stroke
				(width 0)
				(type default)
			)
			(fill no)
			(layer "F.CrtYd")
		)
		(fp_line
			(start 0.3048 0.9906)
			(end 0.3048 -0.1016)
			(stroke
				(width 0.1)
				(type default)
			)
			(layer "F.Fab")
		)
		(fp_line
			(start 0.3048 -0.1016)
			(end -0.3048 -0.1016)
			(stroke
				(width 0.1)
				(type default)
			)
			(layer "F.Fab")
		)
		(fp_line
			(start -0.3048 0.9906)
			(end 0.3048 0.9906)
			(stroke
				(width 0.1)
				(type default)
			)
			(layer "F.Fab")
		)
		(fp_line
			(start -0.3048 -0.1016)
			(end -0.3048 0.9906)
			(stroke
				(width 0.1)
				(type default)
			)
			(layer "F.Fab")
		)
		(pad "1" smd rect
			(at 0 0 180)
			(size 0.508 0.508)
			(layers "F.Cu" "F.Mask" "F.Paste")
			(net "FM_P12V_HOTSWAP0_EN")
		)
		(pad "2" smd rect
			(at 0 0.889 180)
			(size 0.508 0.508)
			(layers "F.Cu" "F.Mask" "F.Paste")
			(net "AGND_HSC")
		)
		(zone
			(layer "F.Cu")
			(hatch none 0.5)
			(connect_pads
				(clearance 0)
			)
			(min_thickness 0.25)
			(keepout
				(tracks allowed)
				(vias not_allowed)
				(pads allowed)
				(copperpour not_allowed)
				(footprints allowed)
			)
			(placement
				(enabled no)
				(sheetname "")
			)
			(fill
				(thermal_gap 0.5)
				(thermal_bridge_width 0.5)
				(island_removal_mode 0)
			)
			(polygon
				(pts
					(xy 19.177 -79.883) (xy 19.177 -80.264) (xy 18.669 -80.264) (xy 18.669 -79.883)
				)
			)
		)
		(zone
			(layer "F.Cu")
			(hatch none 0.5)
			(connect_pads
				(clearance 0)
			)
			(min_thickness 0.25)
			(keepout
				(tracks not_allowed)
				(vias allowed)
				(pads allowed)
				(copperpour not_allowed)
				(footprints allowed)
			)
			(placement
				(enabled no)
				(sheetname "")
			)
			(fill
				(thermal_gap 0.5)
				(thermal_bridge_width 0.5)
				(island_removal_mode 0)
			)
			(polygon
				(pts
					(xy 19.177 -79.883) (xy 19.177 -80.264) (xy 18.669 -80.264) (xy 18.669 -79.883)
				)
			)
		)
	)
	(footprint ""
		(layer "F.Cu")
		(at 210.058 -45.974)
		(property "Reference" ""
			(at 0 0 0)
			(layer "F.SilkS")
			(hide yes)
			(effects
				(font
					(size 1.27 1.27)
				)
			)
		)
		(property "Value" ""
			(at 0 0 0)
			(layer "F.Fab")
			(effects
				(font
					(size 1.27 1.27)
				)
			)
		)
		(duplicate_pad_numbers_are_jumpers no)
		(fp_poly
			(pts
				(arc
					(start 2.032 0)
					(mid -2.032 0)
					(end 2.032 0)
				)
			)
			(stroke
				(width 0)
				(type default)
			)
			(fill no)
			(layer "F.CrtYd")
		)
		(pad "1" smd circle
			(at 0 0)
			(size 1.016 1.016)
			(layers "F.Cu" "F.Mask" "F.Paste")
			(net "Net_395")
		)
		(zone
			(layer "F.Cu")
			(hatch none 0.5)
			(connect_pads
				(clearance 0)
			)
			(min_thickness 0.25)
			(keepout
				(tracks not_allowed)
				(vias allowed)
				(pads allowed)
				(copperpour not_allowed)
				(footprints allowed)
			)
			(placement
				(enabled no)
				(sheetname "")
			)
			(fill
				(thermal_gap 0.5)
				(thermal_bridge_width 0.5)
				(island_removal_mode 0)
			)
			(polygon
				(pts
					(arc
						(start 211.582 -45.974)
						(mid 208.534 -45.974)
						(end 211.582 -45.974)
					)
				)
			)
		)
		(zone
			(layers "F.Cu" "B.Cu" "In1.Cu" "In2.Cu" "In3.Cu" "In4.Cu" "In5.Cu" "In6.Cu"
				"In7.Cu" "In8.Cu" "In9.Cu" "In10.Cu" "In11.Cu" "In12.Cu"
			)
			(hatch none 0.5)
			(connect_pads
				(clearance 0)
			)
			(min_thickness 0.25)
			(keepout
				(tracks allowed)
				(vias not_allowed)
				(pads allowed)
				(copperpour not_allowed)
				(footprints allowed)
			)
			(placement
				(enabled no)
				(sheetname "")
			)
			(fill
				(thermal_gap 0.5)
				(thermal_bridge_width 0.5)
				(island_removal_mode 0)
			)
			(polygon
				(pts
					(arc
						(start 211.582 -45.974)
						(mid 208.534 -45.974)
						(end 211.582 -45.974)
					)
				)
			)
		)
	)
	(footprint ""
		(layer "F.Cu")
		(at 407.631392 -10.916666)
		(property "Reference" "C8G7"
			(at 0 0 0)
			(layer "F.SilkS")
			(hide yes)
			(effects
				(font
					(size 1.27 1.27)
				)
			)
		)
		(property "Value" ""
			(at 0 0 0)
			(layer "F.Fab")
			(effects
				(font
					(size 1.27 1.27)
				)
			)
		)
		(duplicate_pad_numbers_are_jumpers no)
		(fp_rect
			(start -0.3048 0.9906)
			(end 0.3048 -0.1016)
			(stroke
				(width 0)
				(type default)
			)
			(fill no)
			(layer "F.CrtYd")
		)
		(fp_line
			(start -0.3048 -0.1016)
			(end -0.3048 0.9906)
			(stroke
				(width 0.1)
				(type default)
			)
			(layer "F.Fab")
		)
		(fp_line
			(start -0.3048 0.9906)
			(end 0.3048 0.9906)
			(stroke
				(width 0.1)
				(type default)
			)
			(layer "F.Fab")
		)
		(fp_line
			(start 0.3048 -0.1016)
			(end -0.3048 -0.1016)
			(stroke
				(width 0.1)
				(type default)
			)
			(layer "F.Fab")
		)
		(fp_line
			(start 0.3048 0.9906)
			(end 0.3048 -0.1016)
			(stroke
				(width 0.1)
				(type default)
			)
			(layer "F.Fab")
		)
		(pad "1" smd rect
			(at 0 0)
			(size 0.508 0.508)
			(layers "F.Cu" "F.Mask" "F.Paste")
			(net "P3E_CPU0_PE2_SS_TXN<1>")
		)
		(pad "2" smd rect
			(at 0 0.889)
			(size 0.508 0.508)
			(layers "F.Cu" "F.Mask" "F.Paste")
			(net "P3E_CPU0_PE2_SS_C_TXN<1>")
		)
		(zone
			(layer "F.Cu")
			(hatch none 0.5)
			(connect_pads
				(clearance 0)
			)
			(min_thickness 0.25)
			(keepout
				(tracks allowed)
				(vias not_allowed)
				(pads allowed)
				(copperpour not_allowed)
				(footprints allowed)
			)
			(placement
				(enabled no)
				(sheetname "")
			)
			(fill
				(thermal_gap 0.5)
				(thermal_bridge_width 0.5)
				(island_removal_mode 0)
			)
			(polygon
				(pts
					(xy 407.377392 -10.281666) (xy 407.885392 -10.281666) (xy 407.885392 -10.662666) (xy 407.377392 -10.662666)
				)
			)
		)
	)
	(footprint ""
		(layer "F.Cu")
		(at 163.576 -79.248 -90)
		(property "Reference" "R4D21"
			(at 0 0 270)
			(layer "F.SilkS")
			(hide yes)
			(effects
				(font
					(size 1.27 1.27)
				)
			)
		)
		(property "Value" ""
			(at 0 0 270)
			(layer "F.Fab")
			(effects
				(font
					(size 1.27 1.27)
				)
			)
		)
		(duplicate_pad_numbers_are_jumpers no)
		(fp_poly
			(pts
				(xy -0.2794 -0.1016) (xy 0.2794 -0.1016) (xy 0.2794 0.9906) (xy -0.2794 0.9906)
			)
			(stroke
				(width 0)
				(type default)
			)
			(fill no)
			(layer "F.CrtYd")
		)
		(fp_line
			(start -0.2794 0.9906)
			(end 0.2794 0.9906)
			(stroke
				(width 0.1)
				(type default)
			)
			(layer "F.Fab")
		)
		(fp_line
			(start 0.2794 0.9906)
			(end 0.2794 -0.1016)
			(stroke
				(width 0.1)
				(type default)
			)
			(layer "F.Fab")
		)
		(fp_line
			(start -0.2794 -0.1016)
			(end -0.2794 0.9906)
			(stroke
				(width 0.1)
				(type default)
			)
			(layer "F.Fab")
		)
		(fp_line
			(start 0.2794 -0.1016)
			(end -0.2794 -0.1016)
			(stroke
				(width 0.1)
				(type default)
			)
			(layer "F.Fab")
		)
		(pad "1" smd rect
			(at 0 0 270)
			(size 0.508 0.508)
			(layers "F.Cu" "F.Mask" "F.Paste")
			(net "CLK_100M_CPU1_RC_REFCLK0_R_DN")
		)
		(pad "2" smd rect
			(at 0 0.889 270)
			(size 0.508 0.508)
			(layers "F.Cu" "F.Mask" "F.Paste")
			(net "CLK_100M_CPU1_RC_REFCLK0_DN")
		)
		(zone
			(layer "F.Cu")
			(hatch none 0.5)
			(connect_pads
				(clearance 0)
			)
			(min_thickness 0.25)
			(keepout
				(tracks not_allowed)
				(vias allowed)
				(pads allowed)
				(copperpour not_allowed)
				(footprints allowed)
			)
			(placement
				(enabled no)
				(sheetname "")
			)
			(fill
				(thermal_gap 0.5)
				(thermal_bridge_width 0.5)
				(island_removal_mode 0)
			)
			(polygon
				(pts
					(xy 162.941 -79.502) (xy 162.941 -78.994) (xy 163.322 -78.994) (xy 163.322 -79.502)
				)
			)
		)
		(zone
			(layer "F.Cu")
			(hatch none 0.5)
			(connect_pads
				(clearance 0)
			)
			(min_thickness 0.25)
			(keepout
				(tracks allowed)
				(vias not_allowed)
				(pads allowed)
				(copperpour not_allowed)
				(footprints allowed)
			)
			(placement
				(enabled no)
				(sheetname "")
			)
			(fill
				(thermal_gap 0.5)
				(thermal_bridge_width 0.5)
				(island_removal_mode 0)
			)
			(polygon
				(pts
					(xy 163.322 -79.502) (xy 163.322 -78.994) (xy 162.941 -78.994) (xy 162.941 -79.502)
				)
			)
		)
	)
	(footprint ""
		(layer "F.Cu")
		(at 197.066154 -61.205364 -90)
		(property "Reference" "C4E26"
			(at 0 0 270)
			(layer "F.SilkS")
			(hide yes)
			(effects
				(font
					(size 1.27 1.27)
				)
			)
		)
		(property "Value" ""
			(at 0 0 270)
			(layer "F.Fab")
			(effects
				(font
					(size 1.27 1.27)
				)
			)
		)
		(duplicate_pad_numbers_are_jumpers no)
		(fp_poly
			(pts
				(xy 0.3048 -0.1016) (xy 0.3048 0.9906) (xy -0.3048 0.9906) (xy -0.3048 -0.1016)
			)
			(stroke
				(width 0)
				(type default)
			)
			(fill no)
			(layer "F.CrtYd")
		)
		(fp_line
			(start -0.3048 0.9906)
			(end 0.3048 0.9906)
			(stroke
				(width 0.1)
				(type default)
			)
			(layer "F.Fab")
		)
		(fp_line
			(start 0.3048 0.9906)
			(end 0.3048 -0.1016)
			(stroke
				(width 0.1)
				(type default)
			)
			(layer "F.Fab")
		)
		(fp_line
			(start -0.3048 -0.1016)
			(end -0.3048 0.9906)
			(stroke
				(width 0.1)
				(type default)
			)
			(layer "F.Fab")
		)
		(fp_line
			(start 0.3048 -0.1016)
			(end -0.3048 -0.1016)
			(stroke
				(width 0.1)
				(type default)
			)
			(layer "F.Fab")
		)
		(pad "1" smd rect
			(at 0 0 270)
			(size 0.508 0.508)
			(layers "F.Cu" "F.Mask" "F.Paste")
			(net "VR_PVCCIN_CPU0_PH2_VCIN")
		)
		(pad "2" smd rect
			(at 0 0.889 270)
			(size 0.508 0.508)
			(layers "F.Cu" "F.Mask" "F.Paste")
			(net "GND")
		)
		(zone
			(layer "F.Cu")
			(hatch none 0.5)
			(connect_pads
				(clearance 0)
			)
			(min_thickness 0.25)
			(keepout
				(tracks not_allowed)
				(vias allowed)
				(pads allowed)
				(copperpour not_allowed)
				(footprints allowed)
			)
			(placement
				(enabled no)
				(sheetname "")
			)
			(fill
				(thermal_gap 0.5)
				(thermal_bridge_width 0.5)
				(island_removal_mode 0)
			)
			(polygon
				(pts
					(xy 196.431154 -61.459364) (xy 196.431154 -60.951364) (xy 196.812154 -60.951364) (xy 196.812154 -61.459364)
				)
			)
		)
		(zone
			(layer "F.Cu")
			(hatch none 0.5)
			(connect_pads
				(clearance 0)
			)
			(min_thickness 0.25)
			(keepout
				(tracks allowed)
				(vias not_allowed)
				(pads allowed)
				(copperpour not_allowed)
				(footprints allowed)
			)
			(placement
				(enabled no)
				(sheetname "")
			)
			(fill
				(thermal_gap 0.5)
				(thermal_bridge_width 0.5)
				(island_removal_mode 0)
			)
			(polygon
				(pts
					(xy 196.812154 -61.459364) (xy 196.812154 -60.951364) (xy 196.431154 -60.951364) (xy 196.431154 -61.459364)
				)
			)
		)
	)
	(footprint ""
		(layer "F.Cu")
		(at 6.0452 -130.302 180)
		(property "Reference" "C1B5"
			(at -0.8382 -0.67818 180)
			(unlocked yes)
			(layer "F.SilkS")
			(effects
				(font
					(size 0.4064 0.254)
					(thickness 0.1524)
				)
				(justify left)
			)
		)
		(property "Value" ""
			(at 0 0 180)
			(layer "F.Fab")
			(effects
				(font
					(size 1.27 1.27)
				)
			)
		)
		(duplicate_pad_numbers_are_jumpers no)
		(fp_poly
			(pts
				(xy 0.3048 -0.1016) (xy 0.3048 0.9906) (xy -0.3048 0.9906) (xy -0.3048 -0.1016)
			)
			(stroke
				(width 0)
				(type default)
			)
			(fill no)
			(layer "F.CrtYd")
		)
		(fp_line
			(start 0.3048 0.9906)
			(end 0.3048 -0.1016)
			(stroke
				(width 0.1)
				(type default)
			)
			(layer "F.Fab")
		)
		(fp_line
			(start 0.3048 -0.1016)
			(end -0.3048 -0.1016)
			(stroke
				(width 0.1)
				(type default)
			)
			(layer "F.Fab")
		)
		(fp_line
			(start -0.3048 0.9906)
			(end 0.3048 0.9906)
			(stroke
				(width 0.1)
				(type default)
			)
			(layer "F.Fab")
		)
		(fp_line
			(start -0.3048 -0.1016)
			(end -0.3048 0.9906)
			(stroke
				(width 0.1)
				(type default)
			)
			(layer "F.Fab")
		)
		(pad "1" smd rect
			(at 0 0 180)
			(size 0.508 0.508)
			(layers "F.Cu" "F.Mask" "F.Paste")
			(net "VR_PVDDQ_KLM_VDD")
		)
		(pad "2" smd rect
			(at 0 0.889 180)
			(size 0.508 0.508)
			(layers "F.Cu" "F.Mask" "F.Paste")
			(net "GND")
		)
		(zone
			(layer "F.Cu")
			(hatch none 0.5)
			(connect_pads
				(clearance 0)
			)
			(min_thickness 0.25)
			(keepout
				(tracks not_allowed)
				(vias allowed)
				(pads allowed)
				(copperpour not_allowed)
				(footprints allowed)
			)
			(placement
				(enabled no)
				(sheetname "")
			)
			(fill
				(thermal_gap 0.5)
				(thermal_bridge_width 0.5)
				(island_removal_mode 0)
			)
			(polygon
				(pts
					(xy 6.2992 -130.937) (xy 5.7912 -130.937) (xy 5.7912 -130.556) (xy 6.2992 -130.556)
				)
			)
		)
		(zone
			(layer "F.Cu")
			(hatch none 0.5)
			(connect_pads
				(clearance 0)
			)
			(min_thickness 0.25)
			(keepout
				(tracks allowed)
				(vias not_allowed)
				(pads allowed)
				(copperpour not_allowed)
				(footprints allowed)
			)
			(placement
				(enabled no)
				(sheetname "")
			)
			(fill
				(thermal_gap 0.5)
				(thermal_bridge_width 0.5)
				(island_removal_mode 0)
			)
			(polygon
				(pts
					(xy 6.2992 -130.556) (xy 5.7912 -130.556) (xy 5.7912 -130.937) (xy 6.2992 -130.937)
				)
			)
		)
	)
	(footprint ""
		(layer "F.Cu")
		(at 2.032 -75.057 180)
		(property "Reference" "R9R8"
			(at 0 0 180)
			(layer "F.SilkS")
			(hide yes)
			(effects
				(font
					(size 1.27 1.27)
				)
			)
		)
		(property "Value" ""
			(at 0 0 180)
			(layer "F.Fab")
			(effects
				(font
					(size 1.27 1.27)
				)
			)
		)
		(duplicate_pad_numbers_are_jumpers no)
		(fp_poly
			(pts
				(xy -0.2794 -0.1016) (xy 0.2794 -0.1016) (xy 0.2794 0.9906) (xy -0.2794 0.9906)
			)
			(stroke
				(width 0)
				(type default)
			)
			(fill no)
			(layer "F.CrtYd")
		)
		(fp_line
			(start 0.2794 0.9906)
			(end 0.2794 -0.1016)
			(stroke
				(width 0.1)
				(type default)
			)
			(layer "F.Fab")
		)
		(fp_line
			(start 0.2794 -0.1016)
			(end -0.2794 -0.1016)
			(stroke
				(width 0.1)
				(type default)
			)
			(layer "F.Fab")
		)
		(fp_line
			(start -0.2794 0.9906)
			(end 0.2794 0.9906)
			(stroke
				(width 0.1)
				(type default)
			)
			(layer "F.Fab")
		)
		(fp_line
			(start -0.2794 -0.1016)
			(end -0.2794 0.9906)
			(stroke
				(width 0.1)
				(type default)
			)
			(layer "F.Fab")
		)
		(pad "1" smd rect
			(at 0 0 180)
			(size 0.508 0.508)
			(layers "F.Cu" "F.Mask" "F.Paste")
			(net "SMB_SENSOR_TMP421_2_SDA")
		)
		(pad "2" smd rect
			(at 0 0.889 180)
			(size 0.508 0.508)
			(layers "F.Cu" "F.Mask" "F.Paste")
			(net "SMB_SENSOR_STBY_LVC3_SDA")
		)
		(zone
			(layer "F.Cu")
			(hatch none 0.5)
			(connect_pads
				(clearance 0)
			)
			(min_thickness 0.25)
			(keepout
				(tracks not_allowed)
				(vias allowed)
				(pads allowed)
				(copperpour not_allowed)
				(footprints allowed)
			)
			(placement
				(enabled no)
				(sheetname "")
			)
			(fill
				(thermal_gap 0.5)
				(thermal_bridge_width 0.5)
				(island_removal_mode 0)
			)
			(polygon
				(pts
					(xy 2.286 -75.692) (xy 1.778 -75.692) (xy 1.778 -75.311) (xy 2.286 -75.311)
				)
			)
		)
		(zone
			(layer "F.Cu")
			(hatch none 0.5)
			(connect_pads
				(clearance 0)
			)
			(min_thickness 0.25)
			(keepout
				(tracks allowed)
				(vias not_allowed)
				(pads allowed)
				(copperpour not_allowed)
				(footprints allowed)
			)
			(placement
				(enabled no)
				(sheetname "")
			)
			(fill
				(thermal_gap 0.5)
				(thermal_bridge_width 0.5)
				(island_removal_mode 0)
			)
			(polygon
				(pts
					(xy 2.286 -75.311) (xy 1.778 -75.311) (xy 1.778 -75.692) (xy 2.286 -75.692)
				)
			)
		)
	)
	(footprint ""
		(layer "F.Cu")
		(at 38.91534 -61.090048 -90)
		(property "Reference" "CT27"
			(at -0.8382 -0.67818 270)
			(unlocked yes)
			(layer "F.SilkS")
			(effects
				(font
					(size 0.4064 0.254)
					(thickness 0.1524)
				)
				(justify left)
			)
		)
		(property "Value" ""
			(at 0 0 270)
			(layer "F.Fab")
			(effects
				(font
					(size 1.27 1.27)
				)
			)
		)
		(duplicate_pad_numbers_are_jumpers no)
		(fp_poly
			(pts
				(xy 0.3048 -0.1016) (xy 0.3048 0.9906) (xy -0.3048 0.9906) (xy -0.3048 -0.1016)
			)
			(stroke
				(width 0)
				(type default)
			)
			(fill no)
			(layer "F.CrtYd")
		)
		(fp_line
			(start -0.3048 0.9906)
			(end 0.3048 0.9906)
			(stroke
				(width 0.1)
				(type default)
			)
			(layer "F.Fab")
		)
		(fp_line
			(start 0.3048 0.9906)
			(end 0.3048 -0.1016)
			(stroke
				(width 0.1)
				(type default)
			)
			(layer "F.Fab")
		)
		(fp_line
			(start -0.3048 -0.1016)
			(end -0.3048 0.9906)
			(stroke
				(width 0.1)
				(type default)
			)
			(layer "F.Fab")
		)
		(fp_line
			(start 0.3048 -0.1016)
			(end -0.3048 -0.1016)
			(stroke
				(width 0.1)
				(type default)
			)
			(layer "F.Fab")
		)
		(pad "1" smd rect
			(at 0 0 270)
			(size 0.508 0.508)
			(layers "F.Cu" "F.Mask" "F.Paste")
			(net "VR_PVCCIN_CPU1_PHASE2")
		)
		(pad "2" smd rect
			(at 0 0.889 270)
			(size 0.508 0.508)
			(layers "F.Cu" "F.Mask" "F.Paste")
			(net "VR_PVCCIN_CPU1_PHASE2_RC")
		)
		(zone
			(layer "F.Cu")
			(hatch none 0.5)
			(connect_pads
				(clearance 0)
			)
			(min_thickness 0.25)
			(keepout
				(tracks not_allowed)
				(vias allowed)
				(pads allowed)
				(copperpour not_allowed)
				(footprints allowed)
			)
			(placement
				(enabled no)
				(sheetname "")
			)
			(fill
				(thermal_gap 0.5)
				(thermal_bridge_width 0.5)
				(island_removal_mode 0)
			)
			(polygon
				(pts
					(xy 38.28034 -61.344048) (xy 38.28034 -60.836048) (xy 38.66134 -60.836048) (xy 38.66134 -61.344048)
				)
			)
		)
		(zone
			(layer "F.Cu")
			(hatch none 0.5)
			(connect_pads
				(clearance 0)
			)
			(min_thickness 0.25)
			(keepout
				(tracks allowed)
				(vias not_allowed)
				(pads allowed)
				(copperpour not_allowed)
				(footprints allowed)
			)
			(placement
				(enabled no)
				(sheetname "")
			)
			(fill
				(thermal_gap 0.5)
				(thermal_bridge_width 0.5)
				(island_removal_mode 0)
			)
			(polygon
				(pts
					(xy 38.66134 -61.344048) (xy 38.66134 -60.836048) (xy 38.28034 -60.836048) (xy 38.28034 -61.344048)
				)
			)
		)
	)
	(footprint ""
		(layer "F.Cu")
		(at 342.802464 -11.013694 90)
		(property "Reference" "CF15"
			(at 0 0 90)
			(layer "F.SilkS")
			(hide yes)
			(effects
				(font
					(size 1.27 1.27)
				)
			)
		)
		(property "Value" "*"
			(at 1.1811 -2.8194 90)
			(unlocked yes)
			(layer "F.Fab")
			(hide yes)
			(effects
				(font
					(size 1.27 1.016)
					(thickness 0.1524)
				)
			)
		)
		(property "Device Type" "SC22P50V2JN-4GP_SMD-BCG-SC22P5A"
			(at 1.1811 -4.3434 90)
			(unlocked yes)
			(layer "F.Fab")
			(hide yes)
			(effects
				(font
					(size 1.27 1.016)
					(thickness 0.1524)
				)
			)
		)
		(duplicate_pad_numbers_are_jumpers no)
		(fp_rect
			(start -0.4318 0.9525)
			(end 0.4318 -0.9525)
			(stroke
				(width 0)
				(type default)
			)
			(fill no)
			(layer "F.CrtYd")
		)
		(fp_rect
			(start -0.4318 0.9525)
			(end 0.4318 -0.9525)
			(stroke
				(width 0)
				(type default)
			)
			(fill no)
			(layer "F.Fab")
		)
		(pad "1" smd custom
			(at 0 -0.4445 90)
			(size 0.1524 0.1524)
			(layers "F.Cu" "F.Mask" "F.Paste")
			(net "VR_PVDDQ_ABC_AIREF1")
			(options
				(clearance outline)
				(anchor circle)
			)
			(primitives
				(gr_poly
					(pts
						(arc
							(start 0.3048 -0.2032)
							(mid 0.275042 -0.275042)
							(end 0.2032 -0.3048)
						)
						(arc
							(start -0.2032 -0.3048)
							(mid -0.275042 -0.275042)
							(end -0.3048 -0.2032)
						)
						(arc
							(start -0.3048 0.2032)
							(mid -0.275042 0.275042)
							(end -0.2032 0.3048)
						)
						(arc
							(start 0.2032 0.3048)
							(mid 0.275042 0.275042)
							(end 0.3048 0.2032)
						)
					)
					(width 0)
					(fill yes)
				)
			)
		)
		(pad "2" smd custom
			(at 0 0.4445 90)
			(size 0.1524 0.1524)
			(layers "F.Cu" "F.Mask" "F.Paste")
			(net "ISENSE_PVDDQ_ABC_PH1_IMON")
			(options
				(clearance outline)
				(anchor circle)
			)
			(primitives
				(gr_poly
					(pts
						(arc
							(start 0.3048 -0.2032)
							(mid 0.275042 -0.275042)
							(end 0.2032 -0.3048)
						)
						(arc
							(start -0.2032 -0.3048)
							(mid -0.275042 -0.275042)
							(end -0.3048 -0.2032)
						)
						(arc
							(start -0.3048 0.2032)
							(mid -0.275042 0.275042)
							(end -0.2032 0.3048)
						)
						(arc
							(start 0.2032 0.3048)
							(mid 0.275042 0.275042)
							(end 0.3048 0.2032)
						)
					)
					(width 0)
					(fill yes)
				)
			)
		)
	)
	(footprint ""
		(layer "F.Cu")
		(at 108.48721 -84.890102)
		(property "Reference" "C3D2"
			(at 0 0 0)
			(layer "F.SilkS")
			(hide yes)
			(effects
				(font
					(size 1.27 1.27)
				)
			)
		)
		(property "Value" ""
			(at 0 0 0)
			(layer "F.Fab")
			(effects
				(font
					(size 1.27 1.27)
				)
			)
		)
		(duplicate_pad_numbers_are_jumpers no)
		(fp_poly
			(pts
				(xy -0.4953 -0.2032) (xy 0.4953 -0.2032) (xy 0.4953 1.6002) (xy -0.4953 1.6002)
			)
			(stroke
				(width 0)
				(type default)
			)
			(fill no)
			(layer "F.CrtYd")
		)
		(fp_line
			(start -0.4953 -0.2032)
			(end 0.4953 -0.2032)
			(stroke
				(width 0.1)
				(type default)
			)
			(layer "F.Fab")
		)
		(fp_line
			(start -0.4953 1.6002)
			(end -0.4953 -0.2032)
			(stroke
				(width 0.1)
				(type default)
			)
			(layer "F.Fab")
		)
		(fp_line
			(start 0.4953 -0.2032)
			(end 0.4953 1.6002)
			(stroke
				(width 0.1)
				(type default)
			)
			(layer "F.Fab")
		)
		(fp_line
			(start 0.4953 1.6002)
			(end -0.4953 1.6002)
			(stroke
				(width 0.1)
				(type default)
			)
			(layer "F.Fab")
		)
		(pad "1" smd rect
			(at 0 0)
			(size 0.762 0.889)
			(layers "F.Cu" "F.Mask" "F.Paste")
			(net "PVCCIN_CPU1")
		)
		(pad "2" smd rect
			(at 0 1.397)
			(size 0.762 0.889)
			(layers "F.Cu" "F.Mask" "F.Paste")
			(net "GND")
		)
		(zone
			(layer "F.Cu")
			(hatch none 0.5)
			(connect_pads
				(clearance 0)
			)
			(min_thickness 0.25)
			(keepout
				(tracks not_allowed)
				(vias allowed)
				(pads allowed)
				(copperpour not_allowed)
				(footprints allowed)
			)
			(placement
				(enabled no)
				(sheetname "")
			)
			(fill
				(thermal_gap 0.5)
				(thermal_bridge_width 0.5)
				(island_removal_mode 0)
			)
			(polygon
				(pts
					(xy 108.10621 -84.445602) (xy 108.86821 -84.445602) (xy 108.86821 -83.937602) (xy 108.10621 -83.937602)
				)
			)
		)
	)
	(footprint ""
		(layer "F.Cu")
		(at 111.97844 -73.318116)
		(property "Reference" "C3D20"
			(at 0 0 0)
			(layer "F.SilkS")
			(hide yes)
			(effects
				(font
					(size 1.27 1.27)
				)
			)
		)
		(property "Value" ""
			(at 0 0 0)
			(layer "F.Fab")
			(effects
				(font
					(size 1.27 1.27)
				)
			)
		)
		(duplicate_pad_numbers_are_jumpers no)
		(fp_poly
			(pts
				(xy -0.4953 -0.2032) (xy 0.4953 -0.2032) (xy 0.4953 1.6002) (xy -0.4953 1.6002)
			)
			(stroke
				(width 0)
				(type default)
			)
			(fill no)
			(layer "F.CrtYd")
		)
		(fp_line
			(start -0.4953 -0.2032)
			(end 0.4953 -0.2032)
			(stroke
				(width 0.1)
				(type default)
			)
			(layer "F.Fab")
		)
		(fp_line
			(start -0.4953 1.6002)
			(end -0.4953 -0.2032)
			(stroke
				(width 0.1)
				(type default)
			)
			(layer "F.Fab")
		)
		(fp_line
			(start 0.4953 -0.2032)
			(end 0.4953 1.6002)
			(stroke
				(width 0.1)
				(type default)
			)
			(layer "F.Fab")
		)
		(fp_line
			(start 0.4953 1.6002)
			(end -0.4953 1.6002)
			(stroke
				(width 0.1)
				(type default)
			)
			(layer "F.Fab")
		)
		(pad "1" smd rect
			(at 0 0)
			(size 0.762 0.889)
			(layers "F.Cu" "F.Mask" "F.Paste")
			(net "PVCCMCP_CPU1")
		)
		(pad "2" smd rect
			(at 0 1.397)
			(size 0.762 0.889)
			(layers "F.Cu" "F.Mask" "F.Paste")
			(net "GND")
		)
		(zone
			(layer "F.Cu")
			(hatch none 0.5)
			(connect_pads
				(clearance 0)
			)
			(min_thickness 0.25)
			(keepout
				(tracks not_allowed)
				(vias allowed)
				(pads allowed)
				(copperpour not_allowed)
				(footprints allowed)
			)
			(placement
				(enabled no)
				(sheetname "")
			)
			(fill
				(thermal_gap 0.5)
				(thermal_bridge_width 0.5)
				(island_removal_mode 0)
			)
			(polygon
				(pts
					(xy 111.59744 -72.873616) (xy 112.35944 -72.873616) (xy 112.35944 -72.365616) (xy 111.59744 -72.365616)
				)
			)
		)
	)
	(footprint ""
		(layer "F.Cu")
		(at 391.795 -155.067 -90)
		(property "Reference" "R8A2"
			(at 0 0 270)
			(layer "F.SilkS")
			(hide yes)
			(effects
				(font
					(size 1.27 1.27)
				)
			)
		)
		(property "Value" ""
			(at 0 0 270)
			(layer "F.Fab")
			(effects
				(font
					(size 1.27 1.27)
				)
			)
		)
		(duplicate_pad_numbers_are_jumpers no)
		(fp_poly
			(pts
				(xy -0.2794 -0.1016) (xy 0.2794 -0.1016) (xy 0.2794 0.9906) (xy -0.2794 0.9906)
			)
			(stroke
				(width 0)
				(type default)
			)
			(fill no)
			(layer "F.CrtYd")
		)
		(fp_line
			(start -0.2794 0.9906)
			(end 0.2794 0.9906)
			(stroke
				(width 0.1)
				(type default)
			)
			(layer "F.Fab")
		)
		(fp_line
			(start 0.2794 0.9906)
			(end 0.2794 -0.1016)
			(stroke
				(width 0.1)
				(type default)
			)
			(layer "F.Fab")
		)
		(fp_line
			(start -0.2794 -0.1016)
			(end -0.2794 0.9906)
			(stroke
				(width 0.1)
				(type default)
			)
			(layer "F.Fab")
		)
		(fp_line
			(start 0.2794 -0.1016)
			(end -0.2794 -0.1016)
			(stroke
				(width 0.1)
				(type default)
			)
			(layer "F.Fab")
		)
		(pad "1" smd rect
			(at 0 0 270)
			(size 0.508 0.508)
			(layers "F.Cu" "F.Mask" "F.Paste")
			(net "VR_PVNN_PCH_XADDR2")
		)
		(pad "2" smd rect
			(at 0 0.889 270)
			(size 0.508 0.508)
			(layers "F.Cu" "F.Mask" "F.Paste")
			(net "GND")
		)
		(zone
			(layer "F.Cu")
			(hatch none 0.5)
			(connect_pads
				(clearance 0)
			)
			(min_thickness 0.25)
			(keepout
				(tracks not_allowed)
				(vias allowed)
				(pads allowed)
				(copperpour not_allowed)
				(footprints allowed)
			)
			(placement
				(enabled no)
				(sheetname "")
			)
			(fill
				(thermal_gap 0.5)
				(thermal_bridge_width 0.5)
				(island_removal_mode 0)
			)
			(polygon
				(pts
					(xy 391.16 -155.321) (xy 391.16 -154.813) (xy 391.541 -154.813) (xy 391.541 -155.321)
				)
			)
		)
		(zone
			(layer "F.Cu")
			(hatch none 0.5)
			(connect_pads
				(clearance 0)
			)
			(min_thickness 0.25)
			(keepout
				(tracks allowed)
				(vias not_allowed)
				(pads allowed)
				(copperpour not_allowed)
				(footprints allowed)
			)
			(placement
				(enabled no)
				(sheetname "")
			)
			(fill
				(thermal_gap 0.5)
				(thermal_bridge_width 0.5)
				(island_removal_mode 0)
			)
			(polygon
				(pts
					(xy 391.541 -155.321) (xy 391.541 -154.813) (xy 391.16 -154.813) (xy 391.16 -155.321)
				)
			)
		)
	)
	(footprint ""
		(layer "F.Cu")
		(at 388.8232 -0.254)
		(property "Reference" "R7G19"
			(at 0 0 0)
			(layer "F.SilkS")
			(hide yes)
			(effects
				(font
					(size 1.27 1.27)
				)
			)
		)
		(property "Value" ""
			(at 0 0 0)
			(layer "F.Fab")
			(effects
				(font
					(size 1.27 1.27)
				)
			)
		)
		(duplicate_pad_numbers_are_jumpers no)
		(fp_poly
			(pts
				(xy -0.2794 -0.1016) (xy 0.2794 -0.1016) (xy 0.2794 0.9906) (xy -0.2794 0.9906)
			)
			(stroke
				(width 0)
				(type default)
			)
			(fill no)
			(layer "F.CrtYd")
		)
		(fp_line
			(start -0.2794 -0.1016)
			(end -0.2794 0.9906)
			(stroke
				(width 0.1)
				(type default)
			)
			(layer "F.Fab")
		)
		(fp_line
			(start -0.2794 0.9906)
			(end 0.2794 0.9906)
			(stroke
				(width 0.1)
				(type default)
			)
			(layer "F.Fab")
		)
		(fp_line
			(start 0.2794 -0.1016)
			(end -0.2794 -0.1016)
			(stroke
				(width 0.1)
				(type default)
			)
			(layer "F.Fab")
		)
		(fp_line
			(start 0.2794 0.9906)
			(end 0.2794 -0.1016)
			(stroke
				(width 0.1)
				(type default)
			)
			(layer "F.Fab")
		)
		(pad "1" smd rect
			(at 0 0)
			(size 0.508 0.508)
			(layers "F.Cu" "F.Mask" "F.Paste")
			(net "JTAG_PCH_GBE_TDI")
		)
		(pad "2" smd rect
			(at 0 0.889)
			(size 0.508 0.508)
			(layers "F.Cu" "F.Mask" "F.Paste")
			(net "JTAG_TDI")
		)
		(zone
			(layer "F.Cu")
			(hatch none 0.5)
			(connect_pads
				(clearance 0)
			)
			(min_thickness 0.25)
			(keepout
				(tracks allowed)
				(vias not_allowed)
				(pads allowed)
				(copperpour not_allowed)
				(footprints allowed)
			)
			(placement
				(enabled no)
				(sheetname "")
			)
			(fill
				(thermal_gap 0.5)
				(thermal_bridge_width 0.5)
				(island_removal_mode 0)
			)
			(polygon
				(pts
					(xy 388.5692 0) (xy 389.0772 0) (xy 389.0772 0.381) (xy 388.5692 0.381)
				)
			)
		)
		(zone
			(layer "F.Cu")
			(hatch none 0.5)
			(connect_pads
				(clearance 0)
			)
			(min_thickness 0.25)
			(keepout
				(tracks not_allowed)
				(vias allowed)
				(pads allowed)
				(copperpour not_allowed)
				(footprints allowed)
			)
			(placement
				(enabled no)
				(sheetname "")
			)
			(fill
				(thermal_gap 0.5)
				(thermal_bridge_width 0.5)
				(island_removal_mode 0)
			)
			(polygon
				(pts
					(xy 388.5692 0.381) (xy 389.0772 0.381) (xy 389.0772 0) (xy 388.5692 0)
				)
			)
		)
	)
	(footprint ""
		(layer "F.Cu")
		(at 176.037494 -58.982356)
		(property "Reference" "C22W19"
			(at 0 0 0)
			(layer "F.SilkS")
			(hide yes)
			(effects
				(font
					(size 1.27 1.27)
				)
			)
		)
		(property "Value" "*"
			(at -0.0762 -6.2357 0)
			(unlocked yes)
			(layer "F.Fab")
			(hide yes)
			(effects
				(font
					(size 1.27 1.016)
					(thickness 0.1524)
				)
			)
		)
		(property "Device Type" "SC22U16V5MX-4-GP_SMD-BCG5-SC22A"
			(at -0.0762 -8.2677 0)
			(unlocked yes)
			(layer "F.Fab")
			(hide yes)
			(effects
				(font
					(size 1.27 1.016)
					(thickness 0.1524)
				)
			)
		)
		(duplicate_pad_numbers_are_jumpers no)
		(fp_line
			(start 0.635 0)
			(end -0.635 0)
			(stroke
				(width 0.508)
				(type default)
			)
			(layer "F.SilkS")
		)
		(fp_rect
			(start -0.9652 1.778)
			(end 0.9652 -1.778)
			(stroke
				(width 0)
				(type default)
			)
			(fill no)
			(layer "F.CrtYd")
		)
		(fp_poly
			(pts
				(xy -0.9652 -1.778) (xy 0.9652 -1.778) (xy 0.9652 1.778) (xy -0.9652 1.778)
			)
			(stroke
				(width 0)
				(type default)
			)
			(fill no)
			(layer "F.Fab")
		)
		(pad "1" smd rect
			(at 0 -0.9652)
			(size 1.397 1.143)
			(layers "F.Cu" "F.Mask" "F.Paste")
			(net "VR_FET_SW_P12V_STBY_PVCCIN_CPU0")
		)
		(pad "2" smd rect
			(at 0 0.9652)
			(size 1.397 1.143)
			(layers "F.Cu" "F.Mask" "F.Paste")
			(net "GND")
		)
	)
	(footprint ""
		(layer "F.Cu")
		(at 338.836 -18.161 -90)
		(property "Reference" "R12W26"
			(at -0.8382 -0.67818 270)
			(unlocked yes)
			(layer "F.SilkS")
			(effects
				(font
					(size 0.4064 0.254)
					(thickness 0.1524)
				)
				(justify left)
			)
		)
		(property "Value" ""
			(at 0 0 270)
			(layer "F.Fab")
			(effects
				(font
					(size 1.27 1.27)
				)
			)
		)
		(duplicate_pad_numbers_are_jumpers no)
		(fp_poly
			(pts
				(xy -0.2794 -0.1016) (xy 0.2794 -0.1016) (xy 0.2794 0.9906) (xy -0.2794 0.9906)
			)
			(stroke
				(width 0)
				(type default)
			)
			(fill no)
			(layer "F.CrtYd")
		)
		(fp_line
			(start -0.2794 0.9906)
			(end 0.2794 0.9906)
			(stroke
				(width 0.1)
				(type default)
			)
			(layer "F.Fab")
		)
		(fp_line
			(start 0.2794 0.9906)
			(end 0.2794 -0.1016)
			(stroke
				(width 0.1)
				(type default)
			)
			(layer "F.Fab")
		)
		(fp_line
			(start -0.2794 -0.1016)
			(end -0.2794 0.9906)
			(stroke
				(width 0.1)
				(type default)
			)
			(layer "F.Fab")
		)
		(fp_line
			(start 0.2794 -0.1016)
			(end -0.2794 -0.1016)
			(stroke
				(width 0.1)
				(type default)
			)
			(layer "F.Fab")
		)
		(pad "1" smd rect
			(at 0 0 270)
			(size 0.508 0.508)
			(layers "F.Cu" "F.Mask" "F.Paste")
			(net "TP_PVDDQ_ABC_MP1")
		)
		(pad "2" smd rect
			(at 0 0.889 270)
			(size 0.508 0.508)
			(layers "F.Cu" "F.Mask" "F.Paste")
			(net "PWRGD_PVDDQ_ABC")
		)
		(zone
			(layer "F.Cu")
			(hatch none 0.5)
			(connect_pads
				(clearance 0)
			)
			(min_thickness 0.25)
			(keepout
				(tracks not_allowed)
				(vias allowed)
				(pads allowed)
				(copperpour not_allowed)
				(footprints allowed)
			)
			(placement
				(enabled no)
				(sheetname "")
			)
			(fill
				(thermal_gap 0.5)
				(thermal_bridge_width 0.5)
				(island_removal_mode 0)
			)
			(polygon
				(pts
					(xy 338.201 -18.415) (xy 338.201 -17.907) (xy 338.582 -17.907) (xy 338.582 -18.415)
				)
			)
		)
		(zone
			(layer "F.Cu")
			(hatch none 0.5)
			(connect_pads
				(clearance 0)
			)
			(min_thickness 0.25)
			(keepout
				(tracks allowed)
				(vias not_allowed)
				(pads allowed)
				(copperpour not_allowed)
				(footprints allowed)
			)
			(placement
				(enabled no)
				(sheetname "")
			)
			(fill
				(thermal_gap 0.5)
				(thermal_bridge_width 0.5)
				(island_removal_mode 0)
			)
			(polygon
				(pts
					(xy 338.582 -18.415) (xy 338.582 -17.907) (xy 338.201 -17.907) (xy 338.201 -18.415)
				)
			)
		)
	)
	(footprint ""
		(layer "F.Cu")
		(at 377.5202 -29.232352 90)
		(property "Reference" "C8F13"
			(at -0.8382 -0.67818 90)
			(unlocked yes)
			(layer "F.SilkS")
			(effects
				(font
					(size 0.4064 0.254)
					(thickness 0.1524)
				)
				(justify left)
			)
		)
		(property "Value" ""
			(at 0 0 90)
			(layer "F.Fab")
			(effects
				(font
					(size 1.27 1.27)
				)
			)
		)
		(duplicate_pad_numbers_are_jumpers no)
		(fp_poly
			(pts
				(xy 0.3048 -0.1016) (xy 0.3048 0.9906) (xy -0.3048 0.9906) (xy -0.3048 -0.1016)
			)
			(stroke
				(width 0)
				(type default)
			)
			(fill no)
			(layer "F.CrtYd")
		)
		(fp_line
			(start 0.3048 -0.1016)
			(end -0.3048 -0.1016)
			(stroke
				(width 0.1)
				(type default)
			)
			(layer "F.Fab")
		)
		(fp_line
			(start -0.3048 -0.1016)
			(end -0.3048 0.9906)
			(stroke
				(width 0.1)
				(type default)
			)
			(layer "F.Fab")
		)
		(fp_line
			(start 0.3048 0.9906)
			(end 0.3048 -0.1016)
			(stroke
				(width 0.1)
				(type default)
			)
			(layer "F.Fab")
		)
		(fp_line
			(start -0.3048 0.9906)
			(end 0.3048 0.9906)
			(stroke
				(width 0.1)
				(type default)
			)
			(layer "F.Fab")
		)
		(pad "1" smd rect
			(at 0 0 90)
			(size 0.508 0.508)
			(layers "F.Cu" "F.Mask" "F.Paste")
			(net "SATA6G_S0_RX_DP")
		)
		(pad "2" smd rect
			(at 0 0.889 90)
			(size 0.508 0.508)
			(layers "F.Cu" "F.Mask" "F.Paste")
			(net "P3E_PCH_M2_SATA6G_RX_R_DP")
		)
		(zone
			(layer "F.Cu")
			(hatch none 0.5)
			(connect_pads
				(clearance 0)
			)
			(min_thickness 0.25)
			(keepout
				(tracks allowed)
				(vias not_allowed)
				(pads allowed)
				(copperpour not_allowed)
				(footprints allowed)
			)
			(placement
				(enabled no)
				(sheetname "")
			)
			(fill
				(thermal_gap 0.5)
				(thermal_bridge_width 0.5)
				(island_removal_mode 0)
			)
			(polygon
				(pts
					(xy 377.7742 -28.978352) (xy 377.7742 -29.486352) (xy 378.1552 -29.486352) (xy 378.1552 -28.978352)
				)
			)
		)
		(zone
			(layer "F.Cu")
			(hatch none 0.5)
			(connect_pads
				(clearance 0)
			)
			(min_thickness 0.25)
			(keepout
				(tracks not_allowed)
				(vias allowed)
				(pads allowed)
				(copperpour not_allowed)
				(footprints allowed)
			)
			(placement
				(enabled no)
				(sheetname "")
			)
			(fill
				(thermal_gap 0.5)
				(thermal_bridge_width 0.5)
				(island_removal_mode 0)
			)
			(polygon
				(pts
					(xy 378.1552 -28.978352) (xy 378.1552 -29.486352) (xy 377.7742 -29.486352) (xy 377.7742 -28.978352)
				)
			)
		)
	)
	(footprint ""
		(layer "F.Cu")
		(at 32.667194 -102.285292 90)
		(property "Reference" "C1C15"
			(at 0 0 90)
			(layer "F.SilkS")
			(hide yes)
			(effects
				(font
					(size 1.27 1.27)
				)
			)
		)
		(property "Value" ""
			(at 0 0 90)
			(layer "F.Fab")
			(effects
				(font
					(size 1.27 1.27)
				)
			)
		)
		(duplicate_pad_numbers_are_jumpers no)
		(fp_rect
			(start 0.3048 -0.1016)
			(end -0.3048 0.9906)
			(stroke
				(width 0)
				(type default)
			)
			(fill no)
			(layer "F.CrtYd")
		)
		(fp_line
			(start 0.3048 -0.1016)
			(end -0.3048 -0.1016)
			(stroke
				(width 0.1)
				(type default)
			)
			(layer "F.Fab")
		)
		(fp_line
			(start -0.3048 -0.1016)
			(end -0.3048 0.9906)
			(stroke
				(width 0.1)
				(type default)
			)
			(layer "F.Fab")
		)
		(fp_line
			(start 0.3048 0.9906)
			(end 0.3048 -0.1016)
			(stroke
				(width 0.1)
				(type default)
			)
			(layer "F.Fab")
		)
		(fp_line
			(start -0.3048 0.9906)
			(end 0.3048 0.9906)
			(stroke
				(width 0.1)
				(type default)
			)
			(layer "F.Fab")
		)
		(pad "1" smd rect
			(at 0 0 90)
			(size 0.508 0.508)
			(layers "F.Cu" "F.Mask" "F.Paste")
			(net "VR_FET_SW_P12V_STBY_PVCCIN_CPU1")
		)
		(pad "2" smd rect
			(at 0 0.889 90)
			(size 0.508 0.508)
			(layers "F.Cu" "F.Mask" "F.Paste")
			(net "GND")
		)
		(zone
			(layer "F.Cu")
			(hatch none 0.5)
			(connect_pads
				(clearance 0)
			)
			(min_thickness 0.25)
			(keepout
				(tracks allowed)
				(vias not_allowed)
				(pads allowed)
				(copperpour not_allowed)
				(footprints allowed)
			)
			(placement
				(enabled no)
				(sheetname "")
			)
			(fill
				(thermal_gap 0.5)
				(thermal_bridge_width 0.5)
				(island_removal_mode 0)
			)
			(polygon
				(pts
					(xy 32.921194 -102.539292) (xy 32.921194 -102.031292) (xy 33.302194 -102.031292) (xy 33.302194 -102.539292)
				)
			)
		)
		(zone
			(layer "F.Cu")
			(hatch none 0.5)
			(connect_pads
				(clearance 0)
			)
			(min_thickness 0.25)
			(keepout
				(tracks not_allowed)
				(vias allowed)
				(pads allowed)
				(copperpour not_allowed)
				(footprints allowed)
			)
			(placement
				(enabled no)
				(sheetname "")
			)
			(fill
				(thermal_gap 0.5)
				(thermal_bridge_width 0.5)
				(island_removal_mode 0)
			)
			(polygon
				(pts
					(xy 32.921194 -102.539292) (xy 32.921194 -102.031292) (xy 33.302194 -102.031292) (xy 33.302194 -102.539292)
				)
			)
		)
	)
	(footprint ""
		(layer "F.Cu")
		(at 336.2706 -129.0955)
		(property "Reference" "R7B11"
			(at 0 0 0)
			(layer "F.SilkS")
			(hide yes)
			(effects
				(font
					(size 1.27 1.27)
				)
			)
		)
		(property "Value" ""
			(at 0 0 0)
			(layer "F.Fab")
			(effects
				(font
					(size 1.27 1.27)
				)
			)
		)
		(duplicate_pad_numbers_are_jumpers no)
		(fp_poly
			(pts
				(xy -0.2794 -0.1016) (xy 0.2794 -0.1016) (xy 0.2794 0.9906) (xy -0.2794 0.9906)
			)
			(stroke
				(width 0)
				(type default)
			)
			(fill no)
			(layer "F.CrtYd")
		)
		(fp_line
			(start -0.2794 -0.1016)
			(end -0.2794 0.9906)
			(stroke
				(width 0.1)
				(type default)
			)
			(layer "F.Fab")
		)
		(fp_line
			(start -0.2794 0.9906)
			(end 0.2794 0.9906)
			(stroke
				(width 0.1)
				(type default)
			)
			(layer "F.Fab")
		)
		(fp_line
			(start 0.2794 -0.1016)
			(end -0.2794 -0.1016)
			(stroke
				(width 0.1)
				(type default)
			)
			(layer "F.Fab")
		)
		(fp_line
			(start 0.2794 0.9906)
			(end 0.2794 -0.1016)
			(stroke
				(width 0.1)
				(type default)
			)
			(layer "F.Fab")
		)
		(pad "1" smd rect
			(at 0 0)
			(size 0.508 0.508)
			(layers "F.Cu" "F.Mask" "F.Paste")
			(net "PVPP_DEF")
		)
		(pad "2" smd rect
			(at 0 0.889)
			(size 0.508 0.508)
			(layers "F.Cu" "F.Mask" "F.Paste")
			(net "VSENSE_PVPP_DEF")
		)
		(zone
			(layer "F.Cu")
			(hatch none 0.5)
			(connect_pads
				(clearance 0)
			)
			(min_thickness 0.25)
			(keepout
				(tracks allowed)
				(vias not_allowed)
				(pads allowed)
				(copperpour not_allowed)
				(footprints allowed)
			)
			(placement
				(enabled no)
				(sheetname "")
			)
			(fill
				(thermal_gap 0.5)
				(thermal_bridge_width 0.5)
				(island_removal_mode 0)
			)
			(polygon
				(pts
					(xy 336.0166 -128.8415) (xy 336.5246 -128.8415) (xy 336.5246 -128.4605) (xy 336.0166 -128.4605)
				)
			)
		)
		(zone
			(layer "F.Cu")
			(hatch none 0.5)
			(connect_pads
				(clearance 0)
			)
			(min_thickness 0.25)
			(keepout
				(tracks not_allowed)
				(vias allowed)
				(pads allowed)
				(copperpour not_allowed)
				(footprints allowed)
			)
			(placement
				(enabled no)
				(sheetname "")
			)
			(fill
				(thermal_gap 0.5)
				(thermal_bridge_width 0.5)
				(island_removal_mode 0)
			)
			(polygon
				(pts
					(xy 336.0166 -128.4605) (xy 336.5246 -128.4605) (xy 336.5246 -128.8415) (xy 336.0166 -128.8415)
				)
			)
		)
	)
	(footprint ""
		(layer "F.Cu")
		(at 194.749928 -75.954382 -90)
		(property "Reference" "C4D30"
			(at 0 0 270)
			(layer "F.SilkS")
			(hide yes)
			(effects
				(font
					(size 1.27 1.27)
				)
			)
		)
		(property "Value" ""
			(at 0 0 270)
			(layer "F.Fab")
			(effects
				(font
					(size 1.27 1.27)
				)
			)
		)
		(duplicate_pad_numbers_are_jumpers no)
		(fp_poly
			(pts
				(xy 0.3048 -0.1016) (xy 0.3048 0.9906) (xy -0.3048 0.9906) (xy -0.3048 -0.1016)
			)
			(stroke
				(width 0)
				(type default)
			)
			(fill no)
			(layer "F.CrtYd")
		)
		(fp_line
			(start -0.3048 0.9906)
			(end 0.3048 0.9906)
			(stroke
				(width 0.1)
				(type default)
			)
			(layer "F.Fab")
		)
		(fp_line
			(start 0.3048 0.9906)
			(end 0.3048 -0.1016)
			(stroke
				(width 0.1)
				(type default)
			)
			(layer "F.Fab")
		)
		(fp_line
			(start -0.3048 -0.1016)
			(end -0.3048 0.9906)
			(stroke
				(width 0.1)
				(type default)
			)
			(layer "F.Fab")
		)
		(fp_line
			(start 0.3048 -0.1016)
			(end -0.3048 -0.1016)
			(stroke
				(width 0.1)
				(type default)
			)
			(layer "F.Fab")
		)
		(pad "1" smd rect
			(at 0 0 270)
			(size 0.508 0.508)
			(layers "F.Cu" "F.Mask" "F.Paste")
			(net "VR_FET_SW_P12V_STBY_PVCCIN_CPU0")
		)
		(pad "2" smd rect
			(at 0 0.889 270)
			(size 0.508 0.508)
			(layers "F.Cu" "F.Mask" "F.Paste")
			(net "GND")
		)
		(zone
			(layer "F.Cu")
			(hatch none 0.5)
			(connect_pads
				(clearance 0)
			)
			(min_thickness 0.25)
			(keepout
				(tracks not_allowed)
				(vias allowed)
				(pads allowed)
				(copperpour not_allowed)
				(footprints allowed)
			)
			(placement
				(enabled no)
				(sheetname "")
			)
			(fill
				(thermal_gap 0.5)
				(thermal_bridge_width 0.5)
				(island_removal_mode 0)
			)
			(polygon
				(pts
					(xy 194.114928 -76.208382) (xy 194.114928 -75.700382) (xy 194.495928 -75.700382) (xy 194.495928 -76.208382)
				)
			)
		)
		(zone
			(layer "F.Cu")
			(hatch none 0.5)
			(connect_pads
				(clearance 0)
			)
			(min_thickness 0.25)
			(keepout
				(tracks allowed)
				(vias not_allowed)
				(pads allowed)
				(copperpour not_allowed)
				(footprints allowed)
			)
			(placement
				(enabled no)
				(sheetname "")
			)
			(fill
				(thermal_gap 0.5)
				(thermal_bridge_width 0.5)
				(island_removal_mode 0)
			)
			(polygon
				(pts
					(xy 194.495928 -76.208382) (xy 194.495928 -75.700382) (xy 194.114928 -75.700382) (xy 194.114928 -76.208382)
				)
			)
		)
	)
	(footprint ""
		(layer "F.Cu")
		(at 440.817 -143.764 90)
		(property "Reference" "R25W161"
			(at -0.8382 -0.67818 90)
			(unlocked yes)
			(layer "F.SilkS")
			(effects
				(font
					(size 0.4064 0.254)
					(thickness 0.1524)
				)
				(justify left)
			)
		)
		(property "Value" ""
			(at 0 0 90)
			(layer "F.Fab")
			(effects
				(font
					(size 1.27 1.27)
				)
			)
		)
		(duplicate_pad_numbers_are_jumpers no)
		(fp_poly
			(pts
				(xy -0.2794 -0.1016) (xy 0.2794 -0.1016) (xy 0.2794 0.9906) (xy -0.2794 0.9906)
			)
			(stroke
				(width 0)
				(type default)
			)
			(fill no)
			(layer "F.CrtYd")
		)
		(fp_line
			(start 0.2794 -0.1016)
			(end -0.2794 -0.1016)
			(stroke
				(width 0.1)
				(type default)
			)
			(layer "F.Fab")
		)
		(fp_line
			(start -0.2794 -0.1016)
			(end -0.2794 0.9906)
			(stroke
				(width 0.1)
				(type default)
			)
			(layer "F.Fab")
		)
		(fp_line
			(start 0.2794 0.9906)
			(end 0.2794 -0.1016)
			(stroke
				(width 0.1)
				(type default)
			)
			(layer "F.Fab")
		)
		(fp_line
			(start -0.2794 0.9906)
			(end 0.2794 0.9906)
			(stroke
				(width 0.1)
				(type default)
			)
			(layer "F.Fab")
		)
		(pad "1" smd rect
			(at 0 0 90)
			(size 0.508 0.508)
			(layers "F.Cu" "F.Mask" "F.Paste")
			(net "P3V3_STBY")
		)
		(pad "2" smd rect
			(at 0 0.889 90)
			(size 0.508 0.508)
			(layers "F.Cu" "F.Mask" "F.Paste")
			(net "JTAG_BMC_BUF_TMS")
		)
		(zone
			(layer "F.Cu")
			(hatch none 0.5)
			(connect_pads
				(clearance 0)
			)
			(min_thickness 0.25)
			(keepout
				(tracks allowed)
				(vias not_allowed)
				(pads allowed)
				(copperpour not_allowed)
				(footprints allowed)
			)
			(placement
				(enabled no)
				(sheetname "")
			)
			(fill
				(thermal_gap 0.5)
				(thermal_bridge_width 0.5)
				(island_removal_mode 0)
			)
			(polygon
				(pts
					(xy 441.071 -143.51) (xy 441.071 -144.018) (xy 441.452 -144.018) (xy 441.452 -143.51)
				)
			)
		)
		(zone
			(layer "F.Cu")
			(hatch none 0.5)
			(connect_pads
				(clearance 0)
			)
			(min_thickness 0.25)
			(keepout
				(tracks not_allowed)
				(vias allowed)
				(pads allowed)
				(copperpour not_allowed)
				(footprints allowed)
			)
			(placement
				(enabled no)
				(sheetname "")
			)
			(fill
				(thermal_gap 0.5)
				(thermal_bridge_width 0.5)
				(island_removal_mode 0)
			)
			(polygon
				(pts
					(xy 441.452 -143.51) (xy 441.452 -144.018) (xy 441.071 -144.018) (xy 441.071 -143.51)
				)
			)
		)
	)
	(footprint ""
		(layer "F.Cu")
		(at 415.191194 -132.7404)
		(property "Reference" "J8B1"
			(at 1.59258 -3.68427 0)
			(unlocked yes)
			(layer "F.SilkS")
			(effects
				(font
					(size 0.7874 0.5842)
					(thickness 0.1524)
				)
				(justify left)
			)
		)
		(property "Value" ""
			(at 0 0 0)
			(layer "F.Fab")
			(effects
				(font
					(size 1.27 1.27)
				)
			)
		)
		(duplicate_pad_numbers_are_jumpers no)
		(fp_line
			(start -0.181102 -1.774952)
			(end 1.851914 -1.774952)
			(stroke
				(width 0.1524)
				(type default)
			)
			(layer "F.SilkS")
		)
		(fp_line
			(start -0.181102 -0.747014)
			(end -0.181102 -1.774952)
			(stroke
				(width 0.1524)
				(type default)
			)
			(layer "F.SilkS")
		)
		(fp_line
			(start -0.181102 12.77493)
			(end -0.181102 11.744452)
			(stroke
				(width 0.1524)
				(type default)
			)
			(layer "F.SilkS")
		)
		(fp_line
			(start 1.851914 12.77493)
			(end -0.181102 12.77493)
			(stroke
				(width 0.1524)
				(type default)
			)
			(layer "F.SilkS")
		)
		(fp_line
			(start 4.535424 -1.774952)
			(end 5.769102 -1.774952)
			(stroke
				(width 0.1524)
				(type default)
			)
			(layer "F.SilkS")
		)
		(fp_line
			(start 5.769102 -1.774952)
			(end 5.769102 -0.747014)
			(stroke
				(width 0.1524)
				(type default)
			)
			(layer "F.SilkS")
		)
		(fp_line
			(start 5.769102 11.744452)
			(end 5.769102 12.77493)
			(stroke
				(width 0.1524)
				(type default)
			)
			(layer "F.SilkS")
		)
		(fp_line
			(start 5.769102 12.77493)
			(end 4.535424 12.77493)
			(stroke
				(width 0.1524)
				(type default)
			)
			(layer "F.SilkS")
		)
		(fp_poly
			(pts
				(xy -1.325372 0.029718) (xy -2.595372 0.537718) (xy -2.595372 -0.478282)
			)
			(stroke
				(width 0)
				(type default)
			)
			(fill yes)
			(layer "F.SilkS")
		)
		(fp_poly
			(pts
				(xy -0.181102 -1.774952) (xy -0.181102 12.77493) (xy 5.769102 12.77493) (xy 5.769102 -1.774952)
			)
			(stroke
				(width 0)
				(type default)
			)
			(fill no)
			(layer "F.CrtYd")
		)
		(fp_line
			(start -0.181102 -1.774952)
			(end 5.769102 -1.774952)
			(stroke
				(width 0.1)
				(type default)
			)
			(layer "F.Fab")
		)
		(fp_line
			(start -0.181102 12.77493)
			(end -0.181102 -1.774952)
			(stroke
				(width 0.1)
				(type default)
			)
			(layer "F.Fab")
		)
		(fp_line
			(start 5.769102 -1.774952)
			(end 5.769102 12.77493)
			(stroke
				(width 0.1)
				(type default)
			)
			(layer "F.Fab")
		)
		(fp_line
			(start 5.769102 12.77493)
			(end -0.181102 12.77493)
			(stroke
				(width 0.1)
				(type default)
			)
			(layer "F.Fab")
		)
		(fp_poly
			(pts
				(xy -1.325372 0.029718) (xy -2.595372 -0.478282) (xy -2.595372 0.537718)
			)
			(stroke
				(width 0)
				(type default)
			)
			(fill yes)
			(layer "F.Fab")
		)
		(fp_text user "23"
			(at -2.31902 11.571224 0)
			(unlocked yes)
			(layer "F.SilkS")
			(effects
				(font
					(size 0.7874 0.5842)
					(thickness 0.1524)
				)
				(justify left)
			)
		)
		(fp_text user "2"
			(at 6.677406 1.16967 0)
			(unlocked yes)
			(layer "F.SilkS")
			(effects
				(font
					(size 0.7874 0.5842)
					(thickness 0.1524)
				)
				(justify left)
			)
		)
		(fp_text user "24"
			(at 6.884924 11.015218 0)
			(unlocked yes)
			(layer "F.SilkS")
			(effects
				(font
					(size 0.7874 0.5842)
					(thickness 0.1524)
				)
				(justify left)
			)
		)
		(fp_text user "23"
			(at -2.319274 11.573764 0)
			(unlocked yes)
			(layer "F.Fab")
			(effects
				(font
					(size 0.7874 0.5842)
					(thickness 0.1524)
				)
				(justify left)
			)
		)
		(fp_text user "24"
			(at 6.884924 11.012678 0)
			(unlocked yes)
			(layer "F.Fab")
			(effects
				(font
					(size 0.7874 0.5842)
					(thickness 0.1524)
				)
				(justify left)
			)
		)
		(pad "" np_thru_hole circle
			(at 0.89408 -0.849884)
			(size 0.254 0.254)
			(drill 0.5588)
			(layers "*.Cu" "*.Mask")
			(clearance 0.4699)
			(thermal_gap 0.4699)
		)
		(pad "" np_thru_hole circle
			(at 0.89408 11.850116)
			(size 0.254 0.254)
			(drill 0.5588)
			(layers "*.Cu" "*.Mask")
			(clearance 0.4699)
			(thermal_gap 0.4699)
		)
		(pad "1" smd rect
			(at 0 0)
			(size 1.6002 0.6096)
			(layers "F.Cu" "F.Mask" "F.Paste")
			(net "GND")
		)
		(pad "2" smd rect
			(at 5.588 0)
			(size 1.6002 0.6096)
			(layers "F.Cu" "F.Mask" "F.Paste")
			(net "SMB_HFI0_CPU0_LVC2_SCL")
		)
		(pad "3" smd rect
			(at 0 0.999998)
			(size 1.6002 0.6096)
			(layers "F.Cu" "F.Mask" "F.Paste")
			(net "FM_MODPRST_HFI0_CPU0_LVT2_N")
		)
		(pad "4" smd rect
			(at 5.588 0.999998)
			(size 1.6002 0.6096)
			(layers "F.Cu" "F.Mask" "F.Paste")
			(net "SMB_HFI0_CPU0_LVC2_SDA")
		)
		(pad "5" smd rect
			(at 0 1.999996)
			(size 1.6002 0.6096)
			(layers "F.Cu" "F.Mask" "F.Paste")
			(net "LED_HFI0_CPU0_N")
		)
		(pad "6" smd rect
			(at 5.588 1.999996)
			(size 1.6002 0.6096)
			(layers "F.Cu" "F.Mask" "F.Paste")
			(net "RST_HFI0_CPU0_LVT2_N")
		)
		(pad "7" smd rect
			(at 0 2.999994)
			(size 1.6002 0.6096)
			(layers "F.Cu" "F.Mask" "F.Paste")
			(net "GND")
		)
		(pad "8" smd rect
			(at 5.588 2.999994)
			(size 1.6002 0.6096)
			(layers "F.Cu" "F.Mask" "F.Paste")
			(net "IRQ_HFI0_CPU0_LVT2_N")
		)
		(pad "9" smd rect
			(at 0 3.999992)
			(size 1.6002 0.6096)
			(layers "F.Cu" "F.Mask" "F.Paste")
			(net "GND")
		)
		(pad "10" smd rect
			(at 5.588 3.999992)
			(size 1.6002 0.6096)
			(layers "F.Cu" "F.Mask" "F.Paste")
			(net "SMB_HFI1_CPU0_LVC2_SCL")
		)
		(pad "11" smd rect
			(at 0 4.99999)
			(size 1.6002 0.6096)
			(layers "F.Cu" "F.Mask" "F.Paste")
			(net "FM_MODPRST_HFI1_CPU0_LVT2_N")
		)
		(pad "12" smd rect
			(at 5.588 4.99999)
			(size 1.6002 0.6096)
			(layers "F.Cu" "F.Mask" "F.Paste")
			(net "SMB_HFI1_CPU0_LVC2_SDA")
		)
		(pad "13" smd rect
			(at 0 5.999988)
			(size 1.6002 0.6096)
			(layers "F.Cu" "F.Mask" "F.Paste")
			(net "LED_HFI1_CPU0_N")
		)
		(pad "14" smd rect
			(at 5.588 5.999988)
			(size 1.6002 0.6096)
			(layers "F.Cu" "F.Mask" "F.Paste")
			(net "RST_HFI1_CPU0_LVT2_N")
		)
		(pad "15" smd rect
			(at 0 6.999986)
			(size 1.6002 0.6096)
			(layers "F.Cu" "F.Mask" "F.Paste")
			(net "GND")
		)
		(pad "16" smd rect
			(at 5.588 6.999986)
			(size 1.6002 0.6096)
			(layers "F.Cu" "F.Mask" "F.Paste")
			(net "IRQ_HFI1_CPU0_LVT2_N")
		)
		(pad "17" smd rect
			(at 0 7.999984)
			(size 1.6002 0.6096)
			(layers "F.Cu" "F.Mask" "F.Paste")
			(net "TP_HFI_IO_CONN0_RSVD_17")
		)
		(pad "18" smd rect
			(at 5.588 7.999984)
			(size 1.6002 0.6096)
			(layers "F.Cu" "F.Mask" "F.Paste")
			(net "P3V3")
		)
		(pad "19" smd rect
			(at 0 8.999982)
			(size 1.6002 0.6096)
			(layers "F.Cu" "F.Mask" "F.Paste")
			(net "PWRGD_PVPP_ABC")
		)
		(pad "20" smd rect
			(at 5.588 8.999982)
			(size 1.6002 0.6096)
			(layers "F.Cu" "F.Mask" "F.Paste")
			(net "P3V3")
		)
		(pad "21" smd rect
			(at 0 9.99998)
			(size 1.6002 0.6096)
			(layers "F.Cu" "F.Mask" "F.Paste")
			(net "PVPP_ABC")
		)
		(pad "22" smd rect
			(at 5.588 9.99998)
			(size 1.6002 0.6096)
			(layers "F.Cu" "F.Mask" "F.Paste")
			(net "SMB_OCP_FRU_STBY_LVC3_SCL")
		)
		(pad "23" smd rect
			(at 0 10.999978)
			(size 1.6002 0.6096)
			(layers "F.Cu" "F.Mask" "F.Paste")
			(net "GND")
		)
		(pad "24" smd rect
			(at 5.588 10.999978)
			(size 1.6002 0.6096)
			(layers "F.Cu" "F.Mask" "F.Paste")
			(net "SMB_OCP_FRU_STBY_LVC3_SDA")
		)
		(pad "MP1" smd rect
			(at 3.19405 -1.325118)
			(size 1.8034 0.889)
			(layers "F.Cu" "F.Mask" "F.Paste")
			(net "GND")
		)
		(pad "MP2" smd rect
			(at 3.19405 12.325096)
			(size 1.8034 0.889)
			(layers "F.Cu" "F.Mask" "F.Paste")
			(net "GND")
		)
		(zone
			(layers "F.Cu" "B.Cu" "In1.Cu" "In2.Cu" "In3.Cu" "In4.Cu" "In5.Cu" "In6.Cu"
				"In7.Cu" "In8.Cu" "In9.Cu" "In10.Cu" "In11.Cu" "In12.Cu"
			)
			(hatch none 0.5)
			(connect_pads
				(clearance 0)
			)
			(min_thickness 0.25)
			(keepout
				(tracks not_allowed)
				(vias allowed)
				(pads allowed)
				(copperpour not_allowed)
				(footprints allowed)
			)
			(placement
				(enabled no)
				(sheetname "")
			)
			(fill
				(thermal_gap 0.5)
				(thermal_bridge_width 0.5)
				(island_removal_mode 0)
			)
			(polygon
				(pts
					(arc
						(start 416.68192 -133.590284)
						(mid 415.488628 -133.590284)
						(end 416.68192 -133.590284)
					)
				)
			)
		)
		(zone
			(layers "F.Cu" "B.Cu" "In1.Cu" "In2.Cu" "In3.Cu" "In4.Cu" "In5.Cu" "In6.Cu"
				"In7.Cu" "In8.Cu" "In9.Cu" "In10.Cu" "In11.Cu" "In12.Cu"
			)
			(hatch none 0.5)
			(connect_pads
				(clearance 0)
			)
			(min_thickness 0.25)
			(keepout
				(tracks not_allowed)
				(vias allowed)
				(pads allowed)
				(copperpour not_allowed)
				(footprints allowed)
			)
			(placement
				(enabled no)
				(sheetname "")
			)
			(fill
				(thermal_gap 0.5)
				(thermal_bridge_width 0.5)
				(island_removal_mode 0)
			)
			(polygon
				(pts
					(arc
						(start 416.68192 -120.890284)
						(mid 415.488628 -120.890284)
						(end 416.68192 -120.890284)
					)
				)
			)
		)
	)
	(footprint ""
		(layer "F.Cu")
		(at 450.723 -20.2692 -90)
		(property "Reference" "R9W12"
			(at -0.8382 -0.67818 270)
			(unlocked yes)
			(layer "F.SilkS")
			(effects
				(font
					(size 0.4064 0.254)
					(thickness 0.1524)
				)
				(justify left)
			)
		)
		(property "Value" ""
			(at 0 0 270)
			(layer "F.Fab")
			(effects
				(font
					(size 1.27 1.27)
				)
			)
		)
		(duplicate_pad_numbers_are_jumpers no)
		(fp_poly
			(pts
				(xy -0.2794 -0.1016) (xy 0.2794 -0.1016) (xy 0.2794 0.9906) (xy -0.2794 0.9906)
			)
			(stroke
				(width 0)
				(type default)
			)
			(fill no)
			(layer "F.CrtYd")
		)
		(fp_line
			(start -0.2794 0.9906)
			(end 0.2794 0.9906)
			(stroke
				(width 0.1)
				(type default)
			)
			(layer "F.Fab")
		)
		(fp_line
			(start 0.2794 0.9906)
			(end 0.2794 -0.1016)
			(stroke
				(width 0.1)
				(type default)
			)
			(layer "F.Fab")
		)
		(fp_line
			(start -0.2794 -0.1016)
			(end -0.2794 0.9906)
			(stroke
				(width 0.1)
				(type default)
			)
			(layer "F.Fab")
		)
		(fp_line
			(start 0.2794 -0.1016)
			(end -0.2794 -0.1016)
			(stroke
				(width 0.1)
				(type default)
			)
			(layer "F.Fab")
		)
		(pad "1" smd rect
			(at 0 0 270)
			(size 0.508 0.508)
			(layers "F.Cu" "F.Mask" "F.Paste")
			(net "P3V3_STBY")
		)
		(pad "2" smd rect
			(at 0 0.889 270)
			(size 0.508 0.508)
			(layers "F.Cu" "F.Mask" "F.Paste")
			(net "PWRGD_P2V5_BMC_STBY_R")
		)
		(zone
			(layer "F.Cu")
			(hatch none 0.5)
			(connect_pads
				(clearance 0)
			)
			(min_thickness 0.25)
			(keepout
				(tracks not_allowed)
				(vias allowed)
				(pads allowed)
				(copperpour not_allowed)
				(footprints allowed)
			)
			(placement
				(enabled no)
				(sheetname "")
			)
			(fill
				(thermal_gap 0.5)
				(thermal_bridge_width 0.5)
				(island_removal_mode 0)
			)
			(polygon
				(pts
					(xy 450.088 -20.5232) (xy 450.088 -20.0152) (xy 450.469 -20.0152) (xy 450.469 -20.5232)
				)
			)
		)
		(zone
			(layer "F.Cu")
			(hatch none 0.5)
			(connect_pads
				(clearance 0)
			)
			(min_thickness 0.25)
			(keepout
				(tracks allowed)
				(vias not_allowed)
				(pads allowed)
				(copperpour not_allowed)
				(footprints allowed)
			)
			(placement
				(enabled no)
				(sheetname "")
			)
			(fill
				(thermal_gap 0.5)
				(thermal_bridge_width 0.5)
				(island_removal_mode 0)
			)
			(polygon
				(pts
					(xy 450.469 -20.5232) (xy 450.469 -20.0152) (xy 450.088 -20.0152) (xy 450.088 -20.5232)
				)
			)
		)
	)
	(footprint ""
		(layer "F.Cu")
		(at 367.922556 -156.250894 180)
		(property "Reference" "C22W25"
			(at 0 0 180)
			(layer "F.SilkS")
			(hide yes)
			(effects
				(font
					(size 1.27 1.27)
				)
			)
		)
		(property "Value" "*"
			(at -0.0762 -6.2357 180)
			(unlocked yes)
			(layer "F.Fab")
			(hide yes)
			(effects
				(font
					(size 1.27 1.016)
					(thickness 0.1524)
				)
			)
		)
		(property "Device Type" "SC22U16V5MX-4-GP_SMD-BCG5-SC22A"
			(at -0.0762 -8.2677 180)
			(unlocked yes)
			(layer "F.Fab")
			(hide yes)
			(effects
				(font
					(size 1.27 1.016)
					(thickness 0.1524)
				)
			)
		)
		(duplicate_pad_numbers_are_jumpers no)
		(fp_line
			(start 0.635 0)
			(end -0.635 0)
			(stroke
				(width 0.508)
				(type default)
			)
			(layer "F.SilkS")
		)
		(fp_rect
			(start -0.9652 1.778)
			(end 0.9652 -1.778)
			(stroke
				(width 0)
				(type default)
			)
			(fill no)
			(layer "F.CrtYd")
		)
		(fp_poly
			(pts
				(xy -0.9652 -1.778) (xy 0.9652 -1.778) (xy 0.9652 1.778) (xy -0.9652 1.778)
			)
			(stroke
				(width 0)
				(type default)
			)
			(fill no)
			(layer "F.Fab")
		)
		(pad "1" smd rect
			(at 0 -0.9652 180)
			(size 1.397 1.143)
			(layers "F.Cu" "F.Mask" "F.Paste")
			(net "VR_FET_SW_P12V_STBY_PVDDQ_DEF")
		)
		(pad "2" smd rect
			(at 0 0.9652 180)
			(size 1.397 1.143)
			(layers "F.Cu" "F.Mask" "F.Paste")
			(net "GND")
		)
	)
	(footprint ""
		(layer "F.Cu")
		(at 161.6456 -64.897 180)
		(property "Reference" "C3D27"
			(at 0 0 180)
			(layer "F.SilkS")
			(hide yes)
			(effects
				(font
					(size 1.27 1.27)
				)
			)
		)
		(property "Value" ""
			(at 0 0 180)
			(layer "F.Fab")
			(effects
				(font
					(size 1.27 1.27)
				)
			)
		)
		(duplicate_pad_numbers_are_jumpers no)
		(fp_poly
			(pts
				(xy 0.3048 -0.1016) (xy 0.3048 0.9906) (xy -0.3048 0.9906) (xy -0.3048 -0.1016)
			)
			(stroke
				(width 0)
				(type default)
			)
			(fill no)
			(layer "F.CrtYd")
		)
		(fp_line
			(start 0.3048 0.9906)
			(end 0.3048 -0.1016)
			(stroke
				(width 0.1)
				(type default)
			)
			(layer "F.Fab")
		)
		(fp_line
			(start 0.3048 -0.1016)
			(end -0.3048 -0.1016)
			(stroke
				(width 0.1)
				(type default)
			)
			(layer "F.Fab")
		)
		(fp_line
			(start -0.3048 0.9906)
			(end 0.3048 0.9906)
			(stroke
				(width 0.1)
				(type default)
			)
			(layer "F.Fab")
		)
		(fp_line
			(start -0.3048 -0.1016)
			(end -0.3048 0.9906)
			(stroke
				(width 0.1)
				(type default)
			)
			(layer "F.Fab")
		)
		(pad "1" smd rect
			(at 0 0 180)
			(size 0.508 0.508)
			(layers "F.Cu" "F.Mask" "F.Paste")
			(net "VSENSE_PVCCIO_CPU1_SKT_VSEN")
		)
		(pad "2" smd rect
			(at 0 0.889 180)
			(size 0.508 0.508)
			(layers "F.Cu" "F.Mask" "F.Paste")
			(net "VSENSE_PVCCIO_CPU1_SKT_VRTN")
		)
		(zone
			(layer "F.Cu")
			(hatch none 0.5)
			(connect_pads
				(clearance 0)
			)
			(min_thickness 0.25)
			(keepout
				(tracks not_allowed)
				(vias allowed)
				(pads allowed)
				(copperpour not_allowed)
				(footprints allowed)
			)
			(placement
				(enabled no)
				(sheetname "")
			)
			(fill
				(thermal_gap 0.5)
				(thermal_bridge_width 0.5)
				(island_removal_mode 0)
			)
			(polygon
				(pts
					(xy 161.8996 -65.532) (xy 161.3916 -65.532) (xy 161.3916 -65.151) (xy 161.8996 -65.151)
				)
			)
		)
		(zone
			(layer "F.Cu")
			(hatch none 0.5)
			(connect_pads
				(clearance 0)
			)
			(min_thickness 0.25)
			(keepout
				(tracks allowed)
				(vias not_allowed)
				(pads allowed)
				(copperpour not_allowed)
				(footprints allowed)
			)
			(placement
				(enabled no)
				(sheetname "")
			)
			(fill
				(thermal_gap 0.5)
				(thermal_bridge_width 0.5)
				(island_removal_mode 0)
			)
			(polygon
				(pts
					(xy 161.8996 -65.151) (xy 161.3916 -65.151) (xy 161.3916 -65.532) (xy 161.8996 -65.532)
				)
			)
		)
	)
	(footprint ""
		(layer "F.Cu")
		(at 406.516078 -121.083832 90)
		(property "Reference" "R1W19"
			(at -0.8382 -0.67818 90)
			(unlocked yes)
			(layer "F.SilkS")
			(effects
				(font
					(size 0.4064 0.254)
					(thickness 0.1524)
				)
				(justify left)
			)
		)
		(property "Value" ""
			(at 0 0 90)
			(layer "F.Fab")
			(effects
				(font
					(size 1.27 1.27)
				)
			)
		)
		(duplicate_pad_numbers_are_jumpers no)
		(fp_poly
			(pts
				(xy -0.2794 -0.1016) (xy 0.2794 -0.1016) (xy 0.2794 0.9906) (xy -0.2794 0.9906)
			)
			(stroke
				(width 0)
				(type default)
			)
			(fill no)
			(layer "F.CrtYd")
		)
		(fp_line
			(start 0.2794 -0.1016)
			(end -0.2794 -0.1016)
			(stroke
				(width 0.1)
				(type default)
			)
			(layer "F.Fab")
		)
		(fp_line
			(start -0.2794 -0.1016)
			(end -0.2794 0.9906)
			(stroke
				(width 0.1)
				(type default)
			)
			(layer "F.Fab")
		)
		(fp_line
			(start 0.2794 0.9906)
			(end 0.2794 -0.1016)
			(stroke
				(width 0.1)
				(type default)
			)
			(layer "F.Fab")
		)
		(fp_line
			(start -0.2794 0.9906)
			(end 0.2794 0.9906)
			(stroke
				(width 0.1)
				(type default)
			)
			(layer "F.Fab")
		)
		(pad "1" smd rect
			(at 0 0 90)
			(size 0.508 0.508)
			(layers "F.Cu" "F.Mask" "F.Paste")
			(net "USB2_P02_DN_R")
		)
		(pad "2" smd rect
			(at 0 0.889 90)
			(size 0.508 0.508)
			(layers "F.Cu" "F.Mask" "F.Paste")
			(net "USB2_P02_DN")
		)
		(zone
			(layer "F.Cu")
			(hatch none 0.5)
			(connect_pads
				(clearance 0)
			)
			(min_thickness 0.25)
			(keepout
				(tracks allowed)
				(vias not_allowed)
				(pads allowed)
				(copperpour not_allowed)
				(footprints allowed)
			)
			(placement
				(enabled no)
				(sheetname "")
			)
			(fill
				(thermal_gap 0.5)
				(thermal_bridge_width 0.5)
				(island_removal_mode 0)
			)
			(polygon
				(pts
					(xy 406.770078 -120.829832) (xy 406.770078 -121.337832) (xy 407.151078 -121.337832) (xy 407.151078 -120.829832)
				)
			)
		)
		(zone
			(layer "F.Cu")
			(hatch none 0.5)
			(connect_pads
				(clearance 0)
			)
			(min_thickness 0.25)
			(keepout
				(tracks not_allowed)
				(vias allowed)
				(pads allowed)
				(copperpour not_allowed)
				(footprints allowed)
			)
			(placement
				(enabled no)
				(sheetname "")
			)
			(fill
				(thermal_gap 0.5)
				(thermal_bridge_width 0.5)
				(island_removal_mode 0)
			)
			(polygon
				(pts
					(xy 407.151078 -120.829832) (xy 407.151078 -121.337832) (xy 406.770078 -121.337832) (xy 406.770078 -120.829832)
				)
			)
		)
	)
	(footprint ""
		(layer "F.Cu")
		(at 14.986 -82.169 -90)
		(property "Reference" "R1D18"
			(at 0 0 270)
			(layer "F.SilkS")
			(hide yes)
			(effects
				(font
					(size 1.27 1.27)
				)
			)
		)
		(property "Value" ""
			(at 0 0 270)
			(layer "F.Fab")
			(effects
				(font
					(size 1.27 1.27)
				)
			)
		)
		(duplicate_pad_numbers_are_jumpers no)
		(fp_poly
			(pts
				(xy -0.2794 -0.1016) (xy 0.2794 -0.1016) (xy 0.2794 0.9906) (xy -0.2794 0.9906)
			)
			(stroke
				(width 0)
				(type default)
			)
			(fill no)
			(layer "F.CrtYd")
		)
		(fp_line
			(start -0.2794 0.9906)
			(end 0.2794 0.9906)
			(stroke
				(width 0.1)
				(type default)
			)
			(layer "F.Fab")
		)
		(fp_line
			(start 0.2794 0.9906)
			(end 0.2794 -0.1016)
			(stroke
				(width 0.1)
				(type default)
			)
			(layer "F.Fab")
		)
		(fp_line
			(start -0.2794 -0.1016)
			(end -0.2794 0.9906)
			(stroke
				(width 0.1)
				(type default)
			)
			(layer "F.Fab")
		)
		(fp_line
			(start 0.2794 -0.1016)
			(end -0.2794 -0.1016)
			(stroke
				(width 0.1)
				(type default)
			)
			(layer "F.Fab")
		)
		(pad "1" smd rect
			(at 0 0 270)
			(size 0.508 0.508)
			(layers "F.Cu" "F.Mask" "F.Paste")
			(net "A_HSC_HIGH_EN")
		)
		(pad "2" smd rect
			(at 0 0.889 270)
			(size 0.508 0.508)
			(layers "F.Cu" "F.Mask" "F.Paste")
			(net "AGND_HSC")
		)
		(zone
			(layer "F.Cu")
			(hatch none 0.5)
			(connect_pads
				(clearance 0)
			)
			(min_thickness 0.25)
			(keepout
				(tracks not_allowed)
				(vias allowed)
				(pads allowed)
				(copperpour not_allowed)
				(footprints allowed)
			)
			(placement
				(enabled no)
				(sheetname "")
			)
			(fill
				(thermal_gap 0.5)
				(thermal_bridge_width 0.5)
				(island_removal_mode 0)
			)
			(polygon
				(pts
					(xy 14.351 -82.423) (xy 14.351 -81.915) (xy 14.732 -81.915) (xy 14.732 -82.423)
				)
			)
		)
		(zone
			(layer "F.Cu")
			(hatch none 0.5)
			(connect_pads
				(clearance 0)
			)
			(min_thickness 0.25)
			(keepout
				(tracks allowed)
				(vias not_allowed)
				(pads allowed)
				(copperpour not_allowed)
				(footprints allowed)
			)
			(placement
				(enabled no)
				(sheetname "")
			)
			(fill
				(thermal_gap 0.5)
				(thermal_bridge_width 0.5)
				(island_removal_mode 0)
			)
			(polygon
				(pts
					(xy 14.732 -82.423) (xy 14.732 -81.915) (xy 14.351 -81.915) (xy 14.351 -82.423)
				)
			)
		)
	)
	(footprint ""
		(layer "F.Cu")
		(at 363.87024 -140.88237 180)
		(property "Reference" "C7A28"
			(at 0 0 180)
			(layer "F.SilkS")
			(hide yes)
			(effects
				(font
					(size 1.27 1.27)
				)
			)
		)
		(property "Value" ""
			(at 0 0 180)
			(layer "F.Fab")
			(effects
				(font
					(size 1.27 1.27)
				)
			)
		)
		(duplicate_pad_numbers_are_jumpers no)
		(fp_rect
			(start 0.3048 -0.1016)
			(end -0.3048 0.9906)
			(stroke
				(width 0)
				(type default)
			)
			(fill no)
			(layer "F.CrtYd")
		)
		(fp_line
			(start 0.3048 0.9906)
			(end 0.3048 -0.1016)
			(stroke
				(width 0.1)
				(type default)
			)
			(layer "F.Fab")
		)
		(fp_line
			(start 0.3048 -0.1016)
			(end -0.3048 -0.1016)
			(stroke
				(width 0.1)
				(type default)
			)
			(layer "F.Fab")
		)
		(fp_line
			(start -0.3048 0.9906)
			(end 0.3048 0.9906)
			(stroke
				(width 0.1)
				(type default)
			)
			(layer "F.Fab")
		)
		(fp_line
			(start -0.3048 -0.1016)
			(end -0.3048 0.9906)
			(stroke
				(width 0.1)
				(type default)
			)
			(layer "F.Fab")
		)
		(pad "1" smd rect
			(at 0 0 180)
			(size 0.508 0.508)
			(layers "F.Cu" "F.Mask" "F.Paste")
			(net "VR_PVDDQ_DEF_AVSP")
		)
		(pad "2" smd rect
			(at 0 0.889 180)
			(size 0.508 0.508)
			(layers "F.Cu" "F.Mask" "F.Paste")
			(net "VSENSE_PVDDQ_DEF_N")
		)
		(zone
			(layer "F.Cu")
			(hatch none 0.5)
			(connect_pads
				(clearance 0)
			)
			(min_thickness 0.25)
			(keepout
				(tracks allowed)
				(vias not_allowed)
				(pads allowed)
				(copperpour not_allowed)
				(footprints allowed)
			)
			(placement
				(enabled no)
				(sheetname "")
			)
			(fill
				(thermal_gap 0.5)
				(thermal_bridge_width 0.5)
				(island_removal_mode 0)
			)
			(polygon
				(pts
					(xy 363.61624 -141.13637) (xy 364.12424 -141.13637) (xy 364.12424 -141.51737) (xy 363.61624 -141.51737)
				)
			)
		)
		(zone
			(layer "F.Cu")
			(hatch none 0.5)
			(connect_pads
				(clearance 0)
			)
			(min_thickness 0.25)
			(keepout
				(tracks not_allowed)
				(vias allowed)
				(pads allowed)
				(copperpour not_allowed)
				(footprints allowed)
			)
			(placement
				(enabled no)
				(sheetname "")
			)
			(fill
				(thermal_gap 0.5)
				(thermal_bridge_width 0.5)
				(island_removal_mode 0)
			)
			(polygon
				(pts
					(xy 363.61624 -141.13637) (xy 364.12424 -141.13637) (xy 364.12424 -141.51737) (xy 363.61624 -141.51737)
				)
			)
		)
	)
	(footprint ""
		(layer "F.Cu")
		(at 478.545144 -15.251938 -90)
		(property "Reference" "R9G20"
			(at -0.8382 -0.67818 270)
			(unlocked yes)
			(layer "F.SilkS")
			(effects
				(font
					(size 0.4064 0.254)
					(thickness 0.1524)
				)
				(justify left)
			)
		)
		(property "Value" ""
			(at 0 0 270)
			(layer "F.Fab")
			(effects
				(font
					(size 1.27 1.27)
				)
			)
		)
		(duplicate_pad_numbers_are_jumpers no)
		(fp_poly
			(pts
				(xy -0.2794 -0.1016) (xy 0.2794 -0.1016) (xy 0.2794 0.9906) (xy -0.2794 0.9906)
			)
			(stroke
				(width 0)
				(type default)
			)
			(fill no)
			(layer "F.CrtYd")
		)
		(fp_line
			(start -0.2794 0.9906)
			(end 0.2794 0.9906)
			(stroke
				(width 0.1)
				(type default)
			)
			(layer "F.Fab")
		)
		(fp_line
			(start 0.2794 0.9906)
			(end 0.2794 -0.1016)
			(stroke
				(width 0.1)
				(type default)
			)
			(layer "F.Fab")
		)
		(fp_line
			(start -0.2794 -0.1016)
			(end -0.2794 0.9906)
			(stroke
				(width 0.1)
				(type default)
			)
			(layer "F.Fab")
		)
		(fp_line
			(start 0.2794 -0.1016)
			(end -0.2794 -0.1016)
			(stroke
				(width 0.1)
				(type default)
			)
			(layer "F.Fab")
		)
		(pad "1" smd rect
			(at 0 0 270)
			(size 0.508 0.508)
			(layers "F.Cu" "F.Mask" "F.Paste")
			(net "NIC_MDI_SPRV_RJ45_1_DN")
		)
		(pad "2" smd rect
			(at 0 0.889 270)
			(size 0.508 0.508)
			(layers "F.Cu" "F.Mask" "F.Paste")
			(net "NIC_MDI_SPRV_RJ45_1_R_DN")
		)
		(zone
			(layer "F.Cu")
			(hatch none 0.5)
			(connect_pads
				(clearance 0)
			)
			(min_thickness 0.25)
			(keepout
				(tracks not_allowed)
				(vias allowed)
				(pads allowed)
				(copperpour not_allowed)
				(footprints allowed)
			)
			(placement
				(enabled no)
				(sheetname "")
			)
			(fill
				(thermal_gap 0.5)
				(thermal_bridge_width 0.5)
				(island_removal_mode 0)
			)
			(polygon
				(pts
					(xy 477.910144 -15.505938) (xy 477.910144 -14.997938) (xy 478.291144 -14.997938) (xy 478.291144 -15.505938)
				)
			)
		)
		(zone
			(layer "F.Cu")
			(hatch none 0.5)
			(connect_pads
				(clearance 0)
			)
			(min_thickness 0.25)
			(keepout
				(tracks allowed)
				(vias not_allowed)
				(pads allowed)
				(copperpour not_allowed)
				(footprints allowed)
			)
			(placement
				(enabled no)
				(sheetname "")
			)
			(fill
				(thermal_gap 0.5)
				(thermal_bridge_width 0.5)
				(island_removal_mode 0)
			)
			(polygon
				(pts
					(xy 478.291144 -15.505938) (xy 478.291144 -14.997938) (xy 477.910144 -14.997938) (xy 477.910144 -15.505938)
				)
			)
		)
	)
	(footprint ""
		(layer "F.Cu")
		(at 318.8716 -28.045918 -90)
		(property "Reference" "R6F11"
			(at 0 0 270)
			(layer "F.SilkS")
			(hide yes)
			(effects
				(font
					(size 1.27 1.27)
				)
			)
		)
		(property "Value" ""
			(at 0 0 270)
			(layer "F.Fab")
			(effects
				(font
					(size 1.27 1.27)
				)
			)
		)
		(duplicate_pad_numbers_are_jumpers no)
		(fp_poly
			(pts
				(xy -0.2794 -0.1016) (xy 0.2794 -0.1016) (xy 0.2794 0.9906) (xy -0.2794 0.9906)
			)
			(stroke
				(width 0)
				(type default)
			)
			(fill no)
			(layer "F.CrtYd")
		)
		(fp_line
			(start -0.2794 0.9906)
			(end 0.2794 0.9906)
			(stroke
				(width 0.1)
				(type default)
			)
			(layer "F.Fab")
		)
		(fp_line
			(start 0.2794 0.9906)
			(end 0.2794 -0.1016)
			(stroke
				(width 0.1)
				(type default)
			)
			(layer "F.Fab")
		)
		(fp_line
			(start -0.2794 -0.1016)
			(end -0.2794 0.9906)
			(stroke
				(width 0.1)
				(type default)
			)
			(layer "F.Fab")
		)
		(fp_line
			(start 0.2794 -0.1016)
			(end -0.2794 -0.1016)
			(stroke
				(width 0.1)
				(type default)
			)
			(layer "F.Fab")
		)
		(pad "1" smd rect
			(at 0 0 270)
			(size 0.508 0.508)
			(layers "F.Cu" "F.Mask" "F.Paste")
			(net "CLK_322M_156M_CPU0_OSC_VRM_DP")
		)
		(pad "2" smd rect
			(at 0 0.889 270)
			(size 0.508 0.508)
			(layers "F.Cu" "F.Mask" "F.Paste")
			(net "CLK_322M_OSC_CPU0_RC_DP")
		)
		(zone
			(layer "F.Cu")
			(hatch none 0.5)
			(connect_pads
				(clearance 0)
			)
			(min_thickness 0.25)
			(keepout
				(tracks not_allowed)
				(vias allowed)
				(pads allowed)
				(copperpour not_allowed)
				(footprints allowed)
			)
			(placement
				(enabled no)
				(sheetname "")
			)
			(fill
				(thermal_gap 0.5)
				(thermal_bridge_width 0.5)
				(island_removal_mode 0)
			)
			(polygon
				(pts
					(xy 318.2366 -28.299918) (xy 318.2366 -27.791918) (xy 318.6176 -27.791918) (xy 318.6176 -28.299918)
				)
			)
		)
		(zone
			(layer "F.Cu")
			(hatch none 0.5)
			(connect_pads
				(clearance 0)
			)
			(min_thickness 0.25)
			(keepout
				(tracks allowed)
				(vias not_allowed)
				(pads allowed)
				(copperpour not_allowed)
				(footprints allowed)
			)
			(placement
				(enabled no)
				(sheetname "")
			)
			(fill
				(thermal_gap 0.5)
				(thermal_bridge_width 0.5)
				(island_removal_mode 0)
			)
			(polygon
				(pts
					(xy 318.6176 -28.299918) (xy 318.6176 -27.791918) (xy 318.2366 -27.791918) (xy 318.2366 -28.299918)
				)
			)
		)
	)
	(footprint ""
		(layer "F.Cu")
		(at 22.479 -32.258)
		(property "Reference" "CR1F4"
			(at -1.016 -1.24333 0)
			(unlocked yes)
			(layer "F.SilkS")
			(effects
				(font
					(size 0.7874 0.5842)
					(thickness 0.1524)
				)
				(justify left)
			)
		)
		(property "Value" ""
			(at 0 0 0)
			(layer "F.Fab")
			(effects
				(font
					(size 1.27 1.27)
				)
			)
		)
		(duplicate_pad_numbers_are_jumpers no)
		(fp_line
			(start -1.8161 1.664462)
			(end -1.335278 0.831596)
			(stroke
				(width 0.1524)
				(type default)
			)
			(layer "F.SilkS")
		)
		(fp_line
			(start -1.335278 -0.291846)
			(end -1.335278 0.831596)
			(stroke
				(width 0.1524)
				(type default)
			)
			(layer "F.SilkS")
		)
		(fp_line
			(start -1.335278 0.831596)
			(end -0.854456 1.664462)
			(stroke
				(width 0.1524)
				(type default)
			)
			(layer "F.SilkS")
		)
		(fp_line
			(start -1.335278 1.664462)
			(end -1.8161 1.664462)
			(stroke
				(width 0.1524)
				(type default)
			)
			(layer "F.SilkS")
		)
		(fp_line
			(start -1.335278 2.576068)
			(end -1.335278 1.664462)
			(stroke
				(width 0.1524)
				(type default)
			)
			(layer "F.SilkS")
		)
		(fp_line
			(start -0.854456 0.831596)
			(end -1.8161 0.831596)
			(stroke
				(width 0.1524)
				(type default)
			)
			(layer "F.SilkS")
		)
		(fp_line
			(start -0.854456 1.664462)
			(end -1.335278 1.664462)
			(stroke
				(width 0.1524)
				(type default)
			)
			(layer "F.SilkS")
		)
		(fp_rect
			(start -0.67437 2.04216)
			(end 0.67437 0.24384)
			(stroke
				(width 0)
				(type default)
			)
			(fill no)
			(layer "F.CrtYd")
		)
		(fp_line
			(start -1.8161 1.664462)
			(end -1.335278 0.831596)
			(stroke
				(width 0.1)
				(type default)
			)
			(layer "F.Fab")
		)
		(fp_line
			(start -1.335278 0.831596)
			(end -1.335278 -0.291846)
			(stroke
				(width 0.1)
				(type default)
			)
			(layer "F.Fab")
		)
		(fp_line
			(start -1.335278 0.831596)
			(end -0.854456 1.664462)
			(stroke
				(width 0.1)
				(type default)
			)
			(layer "F.Fab")
		)
		(fp_line
			(start -1.335278 1.664462)
			(end -1.335278 2.576068)
			(stroke
				(width 0.1)
				(type default)
			)
			(layer "F.Fab")
		)
		(fp_line
			(start -0.854456 0.831596)
			(end -1.8161 0.831596)
			(stroke
				(width 0.1)
				(type default)
			)
			(layer "F.Fab")
		)
		(fp_line
			(start -0.854456 1.664462)
			(end -1.8161 1.664462)
			(stroke
				(width 0.1)
				(type default)
			)
			(layer "F.Fab")
		)
		(fp_line
			(start -0.67437 0.24384)
			(end -0.67437 2.04216)
			(stroke
				(width 0.1)
				(type default)
			)
			(layer "F.Fab")
		)
		(fp_line
			(start -0.67437 2.04216)
			(end 0.67437 2.04216)
			(stroke
				(width 0.1)
				(type default)
			)
			(layer "F.Fab")
		)
		(fp_line
			(start 0.67437 0.24384)
			(end -0.67437 0.24384)
			(stroke
				(width 0.1)
				(type default)
			)
			(layer "F.Fab")
		)
		(fp_line
			(start 0.67437 2.04216)
			(end 0.67437 0.24384)
			(stroke
				(width 0.1)
				(type default)
			)
			(layer "F.Fab")
		)
		(pad "1" smd rect
			(at 0 0)
			(size 0.4064 1.016)
			(layers "F.Cu" "F.Mask" "F.Paste")
			(net "FM_MATED_IN_D1_N")
		)
		(pad "2" smd rect
			(at 0 2.286)
			(size 0.4064 1.016)
			(layers "F.Cu" "F.Mask" "F.Paste")
			(net "FM_MATED_IN_N")
		)
	)
	(footprint ""
		(layer "F.Cu")
		(at 104.5591 -140.208 90)
		(property "Reference" "C2A15"
			(at 1.848866 0.752348 90)
			(unlocked yes)
			(layer "F.SilkS")
			(effects
				(font
					(size 1.27 0.9652)
					(thickness 0.1524)
				)
			)
		)
		(property "Value" ""
			(at 0 0 90)
			(layer "F.Fab")
			(effects
				(font
					(size 1.27 1.27)
				)
			)
		)
		(duplicate_pad_numbers_are_jumpers no)
		(fp_rect
			(start -0.500126 1.598422)
			(end 0.500126 -0.201422)
			(stroke
				(width 0)
				(type default)
			)
			(fill no)
			(layer "F.CrtYd")
		)
		(fp_line
			(start 0.500126 -0.201422)
			(end 0.500126 1.598422)
			(stroke
				(width 0.1)
				(type default)
			)
			(layer "F.Fab")
		)
		(fp_line
			(start -0.500126 -0.201422)
			(end 0.500126 -0.201422)
			(stroke
				(width 0.1)
				(type default)
			)
			(layer "F.Fab")
		)
		(fp_line
			(start 0.500126 1.598422)
			(end -0.500126 1.598422)
			(stroke
				(width 0.1)
				(type default)
			)
			(layer "F.Fab")
		)
		(fp_line
			(start -0.500126 1.598422)
			(end -0.500126 -0.201422)
			(stroke
				(width 0.1)
				(type default)
			)
			(layer "F.Fab")
		)
		(pad "1" smd rect
			(at 0 0)
			(size 0.889 0.9906)
			(layers "F.Cu" "F.Mask" "F.Paste")
			(net "PVDDQ_KLM")
		)
		(pad "2" smd rect
			(at 0 1.397)
			(size 0.889 0.9906)
			(layers "F.Cu" "F.Mask" "F.Paste")
			(net "GND")
		)
		(zone
			(layer "F.Cu")
			(hatch none 0.5)
			(connect_pads
				(clearance 0)
			)
			(min_thickness 0.25)
			(keepout
				(tracks not_allowed)
				(vias allowed)
				(pads allowed)
				(copperpour not_allowed)
				(footprints allowed)
			)
			(placement
				(enabled no)
				(sheetname "")
			)
			(fill
				(thermal_gap 0.5)
				(thermal_bridge_width 0.5)
				(island_removal_mode 0)
			)
			(polygon
				(pts
					(xy 105.5116 -139.7127) (xy 105.5116 -140.7033) (xy 105.0036 -140.7033) (xy 105.0036 -139.7127)
				)
			)
		)
		(zone
			(layer "F.Cu")
			(hatch none 0.5)
			(connect_pads
				(clearance 0)
			)
			(min_thickness 0.25)
			(keepout
				(tracks allowed)
				(vias not_allowed)
				(pads allowed)
				(copperpour not_allowed)
				(footprints allowed)
			)
			(placement
				(enabled no)
				(sheetname "")
			)
			(fill
				(thermal_gap 0.5)
				(thermal_bridge_width 0.5)
				(island_removal_mode 0)
			)
			(polygon
				(pts
					(xy 105.5116 -139.7127) (xy 105.5116 -140.7033) (xy 105.0036 -140.7033) (xy 105.0036 -139.7127)
				)
			)
		)
	)
	(footprint ""
		(layer "F.Cu")
		(at 13.54836 4.266184)
		(property "Reference" "C1G25"
			(at 0 0 0)
			(layer "F.SilkS")
			(hide yes)
			(effects
				(font
					(size 1.27 1.27)
				)
			)
		)
		(property "Value" ""
			(at 0 0 0)
			(layer "F.Fab")
			(effects
				(font
					(size 1.27 1.27)
				)
			)
		)
		(duplicate_pad_numbers_are_jumpers no)
		(fp_rect
			(start 0.3048 -0.1016)
			(end -0.3048 0.9906)
			(stroke
				(width 0)
				(type default)
			)
			(fill no)
			(layer "F.CrtYd")
		)
		(fp_line
			(start -0.3048 -0.1016)
			(end -0.3048 0.9906)
			(stroke
				(width 0.1)
				(type default)
			)
			(layer "F.Fab")
		)
		(fp_line
			(start -0.3048 0.9906)
			(end 0.3048 0.9906)
			(stroke
				(width 0.1)
				(type default)
			)
			(layer "F.Fab")
		)
		(fp_line
			(start 0.3048 -0.1016)
			(end -0.3048 -0.1016)
			(stroke
				(width 0.1)
				(type default)
			)
			(layer "F.Fab")
		)
		(fp_line
			(start 0.3048 0.9906)
			(end 0.3048 -0.1016)
			(stroke
				(width 0.1)
				(type default)
			)
			(layer "F.Fab")
		)
		(pad "1" smd rect
			(at 0 0)
			(size 0.508 0.508)
			(layers "F.Cu" "F.Mask" "F.Paste")
			(net "VR_PVDDQ_GHJ_VDD")
		)
		(pad "2" smd rect
			(at 0 0.889)
			(size 0.508 0.508)
			(layers "F.Cu" "F.Mask" "F.Paste")
			(net "GND")
		)
		(zone
			(layer "F.Cu")
			(hatch none 0.5)
			(connect_pads
				(clearance 0)
			)
			(min_thickness 0.25)
			(keepout
				(tracks not_allowed)
				(vias allowed)
				(pads allowed)
				(copperpour not_allowed)
				(footprints allowed)
			)
			(placement
				(enabled no)
				(sheetname "")
			)
			(fill
				(thermal_gap 0.5)
				(thermal_bridge_width 0.5)
				(island_removal_mode 0)
			)
			(polygon
				(pts
					(xy 13.80236 4.520184) (xy 13.29436 4.520184) (xy 13.29436 4.901184) (xy 13.80236 4.901184)
				)
			)
		)
		(zone
			(layer "F.Cu")
			(hatch none 0.5)
			(connect_pads
				(clearance 0)
			)
			(min_thickness 0.25)
			(keepout
				(tracks allowed)
				(vias not_allowed)
				(pads allowed)
				(copperpour not_allowed)
				(footprints allowed)
			)
			(placement
				(enabled no)
				(sheetname "")
			)
			(fill
				(thermal_gap 0.5)
				(thermal_bridge_width 0.5)
				(island_removal_mode 0)
			)
			(polygon
				(pts
					(xy 13.80236 4.520184) (xy 13.29436 4.520184) (xy 13.29436 4.901184) (xy 13.80236 4.901184)
				)
			)
		)
	)
	(footprint ""
		(layer "F.Cu")
		(at 23.114 -78.613 -90)
		(property "Reference" "R1D29"
			(at 0 0 270)
			(layer "F.SilkS")
			(hide yes)
			(effects
				(font
					(size 1.27 1.27)
				)
			)
		)
		(property "Value" ""
			(at 0 0 270)
			(layer "F.Fab")
			(effects
				(font
					(size 1.27 1.27)
				)
			)
		)
		(duplicate_pad_numbers_are_jumpers no)
		(fp_rect
			(start -0.2794 -0.1016)
			(end 0.2794 0.9906)
			(stroke
				(width 0)
				(type default)
			)
			(fill no)
			(layer "F.CrtYd")
		)
		(fp_line
			(start -0.2794 0.9906)
			(end 0.2794 0.9906)
			(stroke
				(width 0.1)
				(type default)
			)
			(layer "F.Fab")
		)
		(fp_line
			(start 0.2794 0.9906)
			(end 0.2794 -0.1016)
			(stroke
				(width 0.1)
				(type default)
			)
			(layer "F.Fab")
		)
		(fp_line
			(start -0.2794 -0.1016)
			(end -0.2794 0.9906)
			(stroke
				(width 0.1)
				(type default)
			)
			(layer "F.Fab")
		)
		(fp_line
			(start 0.2794 -0.1016)
			(end -0.2794 -0.1016)
			(stroke
				(width 0.1)
				(type default)
			)
			(layer "F.Fab")
		)
		(pad "1" smd rect
			(at 0 0 270)
			(size 0.508 0.508)
			(layers "F.Cu" "F.Mask" "F.Paste")
			(net "A_HSC_VCAP")
		)
		(pad "2" smd rect
			(at 0 0.889 270)
			(size 0.508 0.508)
			(layers "F.Cu" "F.Mask" "F.Paste")
			(net "FM_P12V_HSC_ADR1")
		)
		(zone
			(layer "F.Cu")
			(hatch none 0.5)
			(connect_pads
				(clearance 0)
			)
			(min_thickness 0.25)
			(keepout
				(tracks allowed)
				(vias not_allowed)
				(pads allowed)
				(copperpour not_allowed)
				(footprints allowed)
			)
			(placement
				(enabled no)
				(sheetname "")
			)
			(fill
				(thermal_gap 0.5)
				(thermal_bridge_width 0.5)
				(island_removal_mode 0)
			)
			(polygon
				(pts
					(xy 22.86 -78.867) (xy 22.479 -78.867) (xy 22.479 -78.359) (xy 22.86 -78.359)
				)
			)
		)
		(zone
			(layer "F.Cu")
			(hatch none 0.5)
			(connect_pads
				(clearance 0)
			)
			(min_thickness 0.25)
			(keepout
				(tracks not_allowed)
				(vias allowed)
				(pads allowed)
				(copperpour not_allowed)
				(footprints allowed)
			)
			(placement
				(enabled no)
				(sheetname "")
			)
			(fill
				(thermal_gap 0.5)
				(thermal_bridge_width 0.5)
				(island_removal_mode 0)
			)
			(polygon
				(pts
					(xy 22.86 -78.867) (xy 22.479 -78.867) (xy 22.479 -78.359) (xy 22.86 -78.359)
				)
			)
		)
	)
	(footprint ""
		(layer "F.Cu")
		(at 394.6525 -77.597 90)
		(property "Reference" "R7D29"
			(at 0 0 90)
			(layer "F.SilkS")
			(hide yes)
			(effects
				(font
					(size 1.27 1.27)
				)
			)
		)
		(property "Value" ""
			(at 0 0 90)
			(layer "F.Fab")
			(effects
				(font
					(size 1.27 1.27)
				)
			)
		)
		(duplicate_pad_numbers_are_jumpers no)
		(fp_poly
			(pts
				(xy -0.2794 -0.1016) (xy 0.2794 -0.1016) (xy 0.2794 0.9906) (xy -0.2794 0.9906)
			)
			(stroke
				(width 0)
				(type default)
			)
			(fill no)
			(layer "F.CrtYd")
		)
		(fp_line
			(start 0.2794 -0.1016)
			(end -0.2794 -0.1016)
			(stroke
				(width 0.1)
				(type default)
			)
			(layer "F.Fab")
		)
		(fp_line
			(start -0.2794 -0.1016)
			(end -0.2794 0.9906)
			(stroke
				(width 0.1)
				(type default)
			)
			(layer "F.Fab")
		)
		(fp_line
			(start 0.2794 0.9906)
			(end 0.2794 -0.1016)
			(stroke
				(width 0.1)
				(type default)
			)
			(layer "F.Fab")
		)
		(fp_line
			(start -0.2794 0.9906)
			(end 0.2794 0.9906)
			(stroke
				(width 0.1)
				(type default)
			)
			(layer "F.Fab")
		)
		(pad "1" smd rect
			(at 0 0 90)
			(size 0.508 0.508)
			(layers "F.Cu" "F.Mask" "F.Paste")
			(net "FM_CPU0_FIVR_FAULT_R_LVT3")
		)
		(pad "2" smd rect
			(at 0 0.889 90)
			(size 0.508 0.508)
			(layers "F.Cu" "F.Mask" "F.Paste")
			(net "FM_CPU0_FIVR_FAULT_LVT3")
		)
		(zone
			(layer "F.Cu")
			(hatch none 0.5)
			(connect_pads
				(clearance 0)
			)
			(min_thickness 0.25)
			(keepout
				(tracks allowed)
				(vias not_allowed)
				(pads allowed)
				(copperpour not_allowed)
				(footprints allowed)
			)
			(placement
				(enabled no)
				(sheetname "")
			)
			(fill
				(thermal_gap 0.5)
				(thermal_bridge_width 0.5)
				(island_removal_mode 0)
			)
			(polygon
				(pts
					(xy 394.9065 -77.343) (xy 394.9065 -77.851) (xy 395.2875 -77.851) (xy 395.2875 -77.343)
				)
			)
		)
		(zone
			(layer "F.Cu")
			(hatch none 0.5)
			(connect_pads
				(clearance 0)
			)
			(min_thickness 0.25)
			(keepout
				(tracks not_allowed)
				(vias allowed)
				(pads allowed)
				(copperpour not_allowed)
				(footprints allowed)
			)
			(placement
				(enabled no)
				(sheetname "")
			)
			(fill
				(thermal_gap 0.5)
				(thermal_bridge_width 0.5)
				(island_removal_mode 0)
			)
			(polygon
				(pts
					(xy 395.2875 -77.343) (xy 395.2875 -77.851) (xy 394.9065 -77.851) (xy 394.9065 -77.343)
				)
			)
		)
	)
	(footprint ""
		(layer "F.Cu")
		(at 471.507566 -26.299668 180)
		(property "Reference" "C8E14"
			(at 0 0 180)
			(layer "F.SilkS")
			(hide yes)
			(effects
				(font
					(size 1.27 1.27)
				)
			)
		)
		(property "Value" ""
			(at 0 0 180)
			(layer "F.Fab")
			(effects
				(font
					(size 1.27 1.27)
				)
			)
		)
		(duplicate_pad_numbers_are_jumpers no)
		(fp_poly
			(pts
				(xy 0.3048 -0.1016) (xy 0.3048 0.9906) (xy -0.3048 0.9906) (xy -0.3048 -0.1016)
			)
			(stroke
				(width 0)
				(type default)
			)
			(fill no)
			(layer "F.CrtYd")
		)
		(fp_line
			(start 0.3048 0.9906)
			(end 0.3048 -0.1016)
			(stroke
				(width 0.1)
				(type default)
			)
			(layer "F.Fab")
		)
		(fp_line
			(start 0.3048 -0.1016)
			(end -0.3048 -0.1016)
			(stroke
				(width 0.1)
				(type default)
			)
			(layer "F.Fab")
		)
		(fp_line
			(start -0.3048 0.9906)
			(end 0.3048 0.9906)
			(stroke
				(width 0.1)
				(type default)
			)
			(layer "F.Fab")
		)
		(fp_line
			(start -0.3048 -0.1016)
			(end -0.3048 0.9906)
			(stroke
				(width 0.1)
				(type default)
			)
			(layer "F.Fab")
		)
		(pad "1" smd rect
			(at 0 0 180)
			(size 0.508 0.508)
			(layers "F.Cu" "F.Mask" "F.Paste")
			(net "VR_FET_SW_P12V_STBY_P3V3_STBY")
		)
		(pad "2" smd rect
			(at 0 0.889 180)
			(size 0.508 0.508)
			(layers "F.Cu" "F.Mask" "F.Paste")
			(net "GND")
		)
		(zone
			(layer "F.Cu")
			(hatch none 0.5)
			(connect_pads
				(clearance 0)
			)
			(min_thickness 0.25)
			(keepout
				(tracks not_allowed)
				(vias allowed)
				(pads allowed)
				(copperpour not_allowed)
				(footprints allowed)
			)
			(placement
				(enabled no)
				(sheetname "")
			)
			(fill
				(thermal_gap 0.5)
				(thermal_bridge_width 0.5)
				(island_removal_mode 0)
			)
			(polygon
				(pts
					(xy 471.761566 -26.934668) (xy 471.253566 -26.934668) (xy 471.253566 -26.553668) (xy 471.761566 -26.553668)
				)
			)
		)
		(zone
			(layer "F.Cu")
			(hatch none 0.5)
			(connect_pads
				(clearance 0)
			)
			(min_thickness 0.25)
			(keepout
				(tracks allowed)
				(vias not_allowed)
				(pads allowed)
				(copperpour not_allowed)
				(footprints allowed)
			)
			(placement
				(enabled no)
				(sheetname "")
			)
			(fill
				(thermal_gap 0.5)
				(thermal_bridge_width 0.5)
				(island_removal_mode 0)
			)
			(polygon
				(pts
					(xy 471.761566 -26.553668) (xy 471.253566 -26.553668) (xy 471.253566 -26.934668) (xy 471.761566 -26.934668)
				)
			)
		)
	)
	(footprint ""
		(layer "F.Cu")
		(at 466.09 -148.0185 180)
		(property "Reference" "C9A2"
			(at 0 0 180)
			(layer "F.SilkS")
			(hide yes)
			(effects
				(font
					(size 1.27 1.27)
				)
			)
		)
		(property "Value" ""
			(at 0 0 180)
			(layer "F.Fab")
			(effects
				(font
					(size 1.27 1.27)
				)
			)
		)
		(duplicate_pad_numbers_are_jumpers no)
		(fp_poly
			(pts
				(xy 0.3048 -0.1016) (xy 0.3048 0.9906) (xy -0.3048 0.9906) (xy -0.3048 -0.1016)
			)
			(stroke
				(width 0)
				(type default)
			)
			(fill no)
			(layer "F.CrtYd")
		)
		(fp_line
			(start 0.3048 0.9906)
			(end 0.3048 -0.1016)
			(stroke
				(width 0.1)
				(type default)
			)
			(layer "F.Fab")
		)
		(fp_line
			(start 0.3048 -0.1016)
			(end -0.3048 -0.1016)
			(stroke
				(width 0.1)
				(type default)
			)
			(layer "F.Fab")
		)
		(fp_line
			(start -0.3048 0.9906)
			(end 0.3048 0.9906)
			(stroke
				(width 0.1)
				(type default)
			)
			(layer "F.Fab")
		)
		(fp_line
			(start -0.3048 -0.1016)
			(end -0.3048 0.9906)
			(stroke
				(width 0.1)
				(type default)
			)
			(layer "F.Fab")
		)
		(pad "1" smd rect
			(at 0 0 180)
			(size 0.508 0.508)
			(layers "F.Cu" "F.Mask" "F.Paste")
			(net "XDP_SYSPWROK")
		)
		(pad "2" smd rect
			(at 0 0.889 180)
			(size 0.508 0.508)
			(layers "F.Cu" "F.Mask" "F.Paste")
			(net "GND")
		)
		(zone
			(layer "F.Cu")
			(hatch none 0.5)
			(connect_pads
				(clearance 0)
			)
			(min_thickness 0.25)
			(keepout
				(tracks not_allowed)
				(vias allowed)
				(pads allowed)
				(copperpour not_allowed)
				(footprints allowed)
			)
			(placement
				(enabled no)
				(sheetname "")
			)
			(fill
				(thermal_gap 0.5)
				(thermal_bridge_width 0.5)
				(island_removal_mode 0)
			)
			(polygon
				(pts
					(xy 466.344 -148.6535) (xy 465.836 -148.6535) (xy 465.836 -148.2725) (xy 466.344 -148.2725)
				)
			)
		)
		(zone
			(layer "F.Cu")
			(hatch none 0.5)
			(connect_pads
				(clearance 0)
			)
			(min_thickness 0.25)
			(keepout
				(tracks allowed)
				(vias not_allowed)
				(pads allowed)
				(copperpour not_allowed)
				(footprints allowed)
			)
			(placement
				(enabled no)
				(sheetname "")
			)
			(fill
				(thermal_gap 0.5)
				(thermal_bridge_width 0.5)
				(island_removal_mode 0)
			)
			(polygon
				(pts
					(xy 466.344 -148.2725) (xy 465.836 -148.2725) (xy 465.836 -148.6535) (xy 466.344 -148.6535)
				)
			)
		)
	)
	(footprint ""
		(layer "F.Cu")
		(at 165.481 -70.6374 180)
		(property "Reference" "C4D33"
			(at 0 0 180)
			(layer "F.SilkS")
			(hide yes)
			(effects
				(font
					(size 1.27 1.27)
				)
			)
		)
		(property "Value" ""
			(at 0 0 180)
			(layer "F.Fab")
			(effects
				(font
					(size 1.27 1.27)
				)
			)
		)
		(duplicate_pad_numbers_are_jumpers no)
		(fp_poly
			(pts
				(xy 0.3048 -0.1016) (xy 0.3048 0.9906) (xy -0.3048 0.9906) (xy -0.3048 -0.1016)
			)
			(stroke
				(width 0)
				(type default)
			)
			(fill no)
			(layer "F.CrtYd")
		)
		(fp_line
			(start 0.3048 0.9906)
			(end 0.3048 -0.1016)
			(stroke
				(width 0.1)
				(type default)
			)
			(layer "F.Fab")
		)
		(fp_line
			(start 0.3048 -0.1016)
			(end -0.3048 -0.1016)
			(stroke
				(width 0.1)
				(type default)
			)
			(layer "F.Fab")
		)
		(fp_line
			(start -0.3048 0.9906)
			(end 0.3048 0.9906)
			(stroke
				(width 0.1)
				(type default)
			)
			(layer "F.Fab")
		)
		(fp_line
			(start -0.3048 -0.1016)
			(end -0.3048 0.9906)
			(stroke
				(width 0.1)
				(type default)
			)
			(layer "F.Fab")
		)
		(pad "1" smd rect
			(at 0 0 180)
			(size 0.508 0.508)
			(layers "F.Cu" "F.Mask" "F.Paste")
			(net "PWRGD_PVCCIO_CPU1_R")
		)
		(pad "2" smd rect
			(at 0 0.889 180)
			(size 0.508 0.508)
			(layers "F.Cu" "F.Mask" "F.Paste")
			(net "GND")
		)
		(zone
			(layer "F.Cu")
			(hatch none 0.5)
			(connect_pads
				(clearance 0)
			)
			(min_thickness 0.25)
			(keepout
				(tracks not_allowed)
				(vias allowed)
				(pads allowed)
				(copperpour not_allowed)
				(footprints allowed)
			)
			(placement
				(enabled no)
				(sheetname "")
			)
			(fill
				(thermal_gap 0.5)
				(thermal_bridge_width 0.5)
				(island_removal_mode 0)
			)
			(polygon
				(pts
					(xy 165.735 -71.2724) (xy 165.227 -71.2724) (xy 165.227 -70.8914) (xy 165.735 -70.8914)
				)
			)
		)
		(zone
			(layer "F.Cu")
			(hatch none 0.5)
			(connect_pads
				(clearance 0)
			)
			(min_thickness 0.25)
			(keepout
				(tracks allowed)
				(vias not_allowed)
				(pads allowed)
				(copperpour not_allowed)
				(footprints allowed)
			)
			(placement
				(enabled no)
				(sheetname "")
			)
			(fill
				(thermal_gap 0.5)
				(thermal_bridge_width 0.5)
				(island_removal_mode 0)
			)
			(polygon
				(pts
					(xy 165.735 -70.8914) (xy 165.227 -70.8914) (xy 165.227 -71.2724) (xy 165.735 -71.2724)
				)
			)
		)
	)
	(footprint ""
		(layer "F.Cu")
		(at 151.892 -120.142 -90)
		(property "Reference" "C3B6"
			(at 3.20167 3.81 0)
			(unlocked yes)
			(layer "F.SilkS")
			(effects
				(font
					(size 0.7874 0.5842)
					(thickness 0.1524)
				)
			)
		)
		(property "Value" ""
			(at 0 0 270)
			(layer "F.Fab")
			(effects
				(font
					(size 1.27 1.27)
				)
			)
		)
		(duplicate_pad_numbers_are_jumpers no)
		(fp_line
			(start -2.286 7.366)
			(end -1.60147 7.366)
			(stroke
				(width 0.1524)
				(type default)
			)
			(layer "F.SilkS")
		)
		(fp_line
			(start -2.286 7.366)
			(end -2.286 1.632712)
			(stroke
				(width 0.1524)
				(type default)
			)
			(layer "F.SilkS")
		)
		(fp_line
			(start 2.286 7.366)
			(end 1.600708 7.366)
			(stroke
				(width 0.1524)
				(type default)
			)
			(layer "F.SilkS")
		)
		(fp_line
			(start 2.286 7.366)
			(end 2.286 1.63195)
			(stroke
				(width 0.1524)
				(type default)
			)
			(layer "F.SilkS")
		)
		(fp_line
			(start -2.563114 1.633728)
			(end -1.6002 1.633728)
			(stroke
				(width 0.1524)
				(type default)
			)
			(layer "F.SilkS")
		)
		(fp_line
			(start 2.504948 1.633728)
			(end 1.6002 1.633728)
			(stroke
				(width 0.1524)
				(type default)
			)
			(layer "F.SilkS")
		)
		(fp_line
			(start -2.563114 -1.616456)
			(end -2.563114 1.633728)
			(stroke
				(width 0.1524)
				(type default)
			)
			(layer "F.SilkS")
		)
		(fp_line
			(start -1.6002 -1.616456)
			(end -2.563114 -1.616456)
			(stroke
				(width 0.1524)
				(type default)
			)
			(layer "F.SilkS")
		)
		(fp_line
			(start 1.6002 -1.616456)
			(end 2.504948 -1.616456)
			(stroke
				(width 0.1524)
				(type default)
			)
			(layer "F.SilkS")
		)
		(fp_line
			(start 2.504948 -1.616456)
			(end 2.504948 1.633728)
			(stroke
				(width 0.1524)
				(type default)
			)
			(layer "F.SilkS")
		)
		(fp_rect
			(start -2.286 7.366)
			(end 2.286 -0.254)
			(stroke
				(width 0)
				(type default)
			)
			(fill no)
			(layer "F.CrtYd")
		)
		(fp_line
			(start -2.286 7.366)
			(end -2.286 -0.254)
			(stroke
				(width 0.1)
				(type default)
			)
			(layer "F.Fab")
		)
		(fp_line
			(start 2.286 7.366)
			(end -2.286 7.366)
			(stroke
				(width 0.1)
				(type default)
			)
			(layer "F.Fab")
		)
		(fp_line
			(start -2.286 -0.254)
			(end 2.286 -0.254)
			(stroke
				(width 0.1)
				(type default)
			)
			(layer "F.Fab")
		)
		(fp_line
			(start 2.286 -0.254)
			(end 2.286 7.366)
			(stroke
				(width 0.1)
				(type default)
			)
			(layer "F.Fab")
		)
		(pad "1" smd rect
			(at 0 0 270)
			(size 2.54 3.048)
			(layers "F.Cu" "F.Mask" "F.Paste")
			(net "P12V_STBY")
		)
		(pad "2" smd rect
			(at 0 7.112 270)
			(size 2.54 3.048)
			(layers "F.Cu" "F.Mask" "F.Paste")
			(net "GND")
		)
	)
	(footprint ""
		(layer "F.Cu")
		(at 386.326888 -78.388718)
		(property "Reference" "U7D2"
			(at -0.070104 -1.190752 0)
			(unlocked yes)
			(layer "F.SilkS")
			(effects
				(font
					(size 0.7874 0.5842)
					(thickness 0.1524)
				)
				(justify left)
			)
		)
		(property "Value" ""
			(at 0 0 0)
			(layer "F.Fab")
			(effects
				(font
					(size 1.27 1.27)
				)
			)
		)
		(duplicate_pad_numbers_are_jumpers no)
		(fp_line
			(start 1.5367 -0.64008)
			(end 4.4323 -0.64008)
			(stroke
				(width 0.1524)
				(type default)
			)
			(layer "F.SilkS")
		)
		(fp_line
			(start 1.5367 4.52628)
			(end 1.5367 -0.64008)
			(stroke
				(width 0.1524)
				(type default)
			)
			(layer "F.SilkS")
		)
		(fp_line
			(start 2.667 -0.64008)
			(end 2.667 0.49022)
			(stroke
				(width 0.1524)
				(type default)
			)
			(layer "F.SilkS")
		)
		(fp_line
			(start 2.667 0.49022)
			(end 3.302 0.49022)
			(stroke
				(width 0.1524)
				(type default)
			)
			(layer "F.SilkS")
		)
		(fp_line
			(start 3.302 0.49022)
			(end 3.302 -0.64008)
			(stroke
				(width 0.1524)
				(type default)
			)
			(layer "F.SilkS")
		)
		(fp_line
			(start 4.4323 -0.64008)
			(end 4.4323 4.52628)
			(stroke
				(width 0.1524)
				(type default)
			)
			(layer "F.SilkS")
		)
		(fp_line
			(start 4.4323 4.52628)
			(end 1.5367 4.52628)
			(stroke
				(width 0.1524)
				(type default)
			)
			(layer "F.SilkS")
		)
		(fp_circle
			(center -1.612138 -0.684784)
			(end -1.485138 -0.684784)
			(stroke
				(width 0.254)
				(type default)
			)
			(fill no)
			(layer "F.SilkS")
		)
		(fp_poly
			(pts
				(xy 0.7366 4.54152) (xy 0.7366 -0.64008) (xy 4.7244 -0.64008) (xy 5.2324 -0.64008) (xy 5.2324 4.54152)
				(xy 4.7244 4.54152)
			)
			(stroke
				(width 0)
				(type default)
			)
			(fill no)
			(layer "F.CrtYd")
		)
		(fp_line
			(start 0.7366 -0.64008)
			(end 5.2324 -0.64008)
			(stroke
				(width 0.1)
				(type default)
			)
			(layer "F.Fab")
		)
		(fp_line
			(start 0.7366 4.54152)
			(end 0.7366 -0.64008)
			(stroke
				(width 0.1)
				(type default)
			)
			(layer "F.Fab")
		)
		(fp_line
			(start 2.667 -0.64008)
			(end 2.667 0.49022)
			(stroke
				(width 0.1)
				(type default)
			)
			(layer "F.Fab")
		)
		(fp_line
			(start 2.667 0.49022)
			(end 3.302 0.49022)
			(stroke
				(width 0.1)
				(type default)
			)
			(layer "F.Fab")
		)
		(fp_line
			(start 3.302 0.49022)
			(end 3.302 -0.64008)
			(stroke
				(width 0.1)
				(type default)
			)
			(layer "F.Fab")
		)
		(fp_line
			(start 5.2324 -0.64008)
			(end 5.2324 4.54152)
			(stroke
				(width 0.1)
				(type default)
			)
			(layer "F.Fab")
		)
		(fp_line
			(start 5.2324 4.54152)
			(end 0.7366 4.54152)
			(stroke
				(width 0.1)
				(type default)
			)
			(layer "F.Fab")
		)
		(fp_circle
			(center -1.612138 -0.684784)
			(end -1.485138 -0.684784)
			(stroke
				(width 0.254)
				(type default)
			)
			(fill no)
			(layer "F.Fab")
		)
		(pad "1" smd rect
			(at 0 0)
			(size 2.159 0.381)
			(layers "F.Cu" "F.Mask" "F.Paste")
			(net "PD_GTL2104_DIR_0")
		)
		(pad "2" smd rect
			(at 0 0.65024)
			(size 2.159 0.381)
			(layers "F.Cu" "F.Mask" "F.Paste")
			(net "H_CPU_MSMI_G_N")
		)
		(pad "3" smd rect
			(at 0 1.30048)
			(size 2.159 0.381)
			(layers "F.Cu" "F.Mask" "F.Paste")
			(net "H_CPU0_FIVR_FAULT_G")
		)
		(pad "4" smd rect
			(at 0 1.95072)
			(size 2.159 0.381)
			(layers "F.Cu" "F.Mask" "F.Paste")
			(net "P0V7_GTL2104_VREF_0")
		)
		(pad "5" smd rect
			(at 0 2.60096)
			(size 2.159 0.381)
			(layers "F.Cu" "F.Mask" "F.Paste")
			(net "H_CPU_ERR2_GTL_N")
		)
		(pad "6" smd rect
			(at 0 3.2512)
			(size 2.159 0.381)
			(layers "F.Cu" "F.Mask" "F.Paste")
			(net "H_CPU0_THERMTRIP_G_N")
		)
		(pad "7" smd rect
			(at 0 3.90144)
			(size 2.159 0.381)
			(layers "F.Cu" "F.Mask" "F.Paste")
			(net "GND")
		)
		(pad "8" smd rect
			(at 5.969 3.90144)
			(size 2.159 0.381)
			(layers "F.Cu" "F.Mask" "F.Paste")
			(net "GND")
		)
		(pad "9" smd rect
			(at 5.969 3.2512)
			(size 2.159 0.381)
			(layers "F.Cu" "F.Mask" "F.Paste")
			(net "FM_CPU0_THERMTRIP_LVT3_R_N")
		)
		(pad "10" smd rect
			(at 5.969 2.60096)
			(size 2.159 0.381)
			(layers "F.Cu" "F.Mask" "F.Paste")
			(net "FM_CPU_ERR2_LVT3_R_N")
		)
		(pad "11" smd rect
			(at 5.969 1.95072)
			(size 2.159 0.381)
			(layers "F.Cu" "F.Mask" "F.Paste")
			(net "GND")
		)
		(pad "12" smd rect
			(at 5.969 1.30048)
			(size 2.159 0.381)
			(layers "F.Cu" "F.Mask" "F.Paste")
			(net "FM_CPU0_FIVR_FAULT_R_LVT3")
		)
		(pad "13" smd rect
			(at 5.969 0.65024)
			(size 2.159 0.381)
			(layers "F.Cu" "F.Mask" "F.Paste")
			(net "FM_CPU_MSMI_LVT3_R_N")
		)
		(pad "14" smd rect
			(at 5.969 0)
			(size 2.159 0.381)
			(layers "F.Cu" "F.Mask" "F.Paste")
			(net "P3V3")
		)
	)
	(footprint ""
		(layer "F.Cu")
		(at 10.362184 -3.532124 180)
		(property "Reference" "R1G10"
			(at 0 0 180)
			(layer "F.SilkS")
			(hide yes)
			(effects
				(font
					(size 1.27 1.27)
				)
			)
		)
		(property "Value" ""
			(at 0 0 180)
			(layer "F.Fab")
			(effects
				(font
					(size 1.27 1.27)
				)
			)
		)
		(duplicate_pad_numbers_are_jumpers no)
		(fp_rect
			(start 0.2794 0.9906)
			(end -0.2794 -0.1016)
			(stroke
				(width 0)
				(type default)
			)
			(fill no)
			(layer "F.CrtYd")
		)
		(fp_line
			(start 0.2794 0.9906)
			(end 0.2794 -0.1016)
			(stroke
				(width 0.1)
				(type default)
			)
			(layer "F.Fab")
		)
		(fp_line
			(start 0.2794 -0.1016)
			(end -0.2794 -0.1016)
			(stroke
				(width 0.1)
				(type default)
			)
			(layer "F.Fab")
		)
		(fp_line
			(start -0.2794 0.9906)
			(end 0.2794 0.9906)
			(stroke
				(width 0.1)
				(type default)
			)
			(layer "F.Fab")
		)
		(fp_line
			(start -0.2794 -0.1016)
			(end -0.2794 0.9906)
			(stroke
				(width 0.1)
				(type default)
			)
			(layer "F.Fab")
		)
		(pad "1" smd rect
			(at 0 0 180)
			(size 0.508 0.508)
			(layers "F.Cu" "F.Mask" "F.Paste")
			(net "SVID_VDIO_PVDDQ_GHJ")
		)
		(pad "2" smd rect
			(at 0 0.889 180)
			(size 0.508 0.508)
			(layers "F.Cu" "F.Mask" "F.Paste")
			(net "SVID_DIO1_CPU1_R")
		)
		(zone
			(layer "F.Cu")
			(hatch none 0.5)
			(connect_pads
				(clearance 0)
			)
			(min_thickness 0.25)
			(keepout
				(tracks not_allowed)
				(vias allowed)
				(pads allowed)
				(copperpour not_allowed)
				(footprints allowed)
			)
			(placement
				(enabled no)
				(sheetname "")
			)
			(fill
				(thermal_gap 0.5)
				(thermal_bridge_width 0.5)
				(island_removal_mode 0)
			)
			(polygon
				(pts
					(xy 10.108184 -4.167124) (xy 10.108184 -3.786124) (xy 10.616184 -3.786124) (xy 10.616184 -4.167124)
				)
			)
		)
		(zone
			(layer "F.Cu")
			(hatch none 0.5)
			(connect_pads
				(clearance 0)
			)
			(min_thickness 0.25)
			(keepout
				(tracks allowed)
				(vias not_allowed)
				(pads allowed)
				(copperpour not_allowed)
				(footprints allowed)
			)
			(placement
				(enabled no)
				(sheetname "")
			)
			(fill
				(thermal_gap 0.5)
				(thermal_bridge_width 0.5)
				(island_removal_mode 0)
			)
			(polygon
				(pts
					(xy 10.108184 -4.167124) (xy 10.108184 -3.786124) (xy 10.616184 -3.786124) (xy 10.616184 -4.167124)
				)
			)
		)
	)
	(footprint ""
		(layer "F.Cu")
		(at 394.72235 -78.462886 90)
		(property "Reference" "R7D25"
			(at 0 0 90)
			(layer "F.SilkS")
			(hide yes)
			(effects
				(font
					(size 1.27 1.27)
				)
			)
		)
		(property "Value" ""
			(at 0 0 90)
			(layer "F.Fab")
			(effects
				(font
					(size 1.27 1.27)
				)
			)
		)
		(duplicate_pad_numbers_are_jumpers no)
		(fp_poly
			(pts
				(xy -0.2794 -0.1016) (xy 0.2794 -0.1016) (xy 0.2794 0.9906) (xy -0.2794 0.9906)
			)
			(stroke
				(width 0)
				(type default)
			)
			(fill no)
			(layer "F.CrtYd")
		)
		(fp_line
			(start 0.2794 -0.1016)
			(end -0.2794 -0.1016)
			(stroke
				(width 0.1)
				(type default)
			)
			(layer "F.Fab")
		)
		(fp_line
			(start -0.2794 -0.1016)
			(end -0.2794 0.9906)
			(stroke
				(width 0.1)
				(type default)
			)
			(layer "F.Fab")
		)
		(fp_line
			(start 0.2794 0.9906)
			(end 0.2794 -0.1016)
			(stroke
				(width 0.1)
				(type default)
			)
			(layer "F.Fab")
		)
		(fp_line
			(start -0.2794 0.9906)
			(end 0.2794 0.9906)
			(stroke
				(width 0.1)
				(type default)
			)
			(layer "F.Fab")
		)
		(pad "1" smd rect
			(at 0 0 90)
			(size 0.508 0.508)
			(layers "F.Cu" "F.Mask" "F.Paste")
			(net "FM_CPU_MSMI_LVT3_R_N")
		)
		(pad "2" smd rect
			(at 0 0.889 90)
			(size 0.508 0.508)
			(layers "F.Cu" "F.Mask" "F.Paste")
			(net "FM_CPU_MSMI_LVT3_N")
		)
		(zone
			(layer "F.Cu")
			(hatch none 0.5)
			(connect_pads
				(clearance 0)
			)
			(min_thickness 0.25)
			(keepout
				(tracks allowed)
				(vias not_allowed)
				(pads allowed)
				(copperpour not_allowed)
				(footprints allowed)
			)
			(placement
				(enabled no)
				(sheetname "")
			)
			(fill
				(thermal_gap 0.5)
				(thermal_bridge_width 0.5)
				(island_removal_mode 0)
			)
			(polygon
				(pts
					(xy 394.97635 -78.208886) (xy 394.97635 -78.716886) (xy 395.35735 -78.716886) (xy 395.35735 -78.208886)
				)
			)
		)
		(zone
			(layer "F.Cu")
			(hatch none 0.5)
			(connect_pads
				(clearance 0)
			)
			(min_thickness 0.25)
			(keepout
				(tracks not_allowed)
				(vias allowed)
				(pads allowed)
				(copperpour not_allowed)
				(footprints allowed)
			)
			(placement
				(enabled no)
				(sheetname "")
			)
			(fill
				(thermal_gap 0.5)
				(thermal_bridge_width 0.5)
				(island_removal_mode 0)
			)
			(polygon
				(pts
					(xy 395.35735 -78.208886) (xy 395.35735 -78.716886) (xy 394.97635 -78.716886) (xy 394.97635 -78.208886)
				)
			)
		)
	)
	(footprint ""
		(layer "F.Cu")
		(at 4.962906 -9.493758 90)
		(property "Reference" "EU1G1"
			(at -1.289558 -4.047236 90)
			(unlocked yes)
			(layer "F.SilkS")
			(effects
				(font
					(size 0.7874 0.5842)
					(thickness 0.1524)
				)
			)
		)
		(property "Value" ""
			(at 0 0 90)
			(layer "F.Fab")
			(effects
				(font
					(size 1.27 1.27)
				)
			)
		)
		(duplicate_pad_numbers_are_jumpers no)
		(fp_line
			(start 2.9718 -3.5052)
			(end 2.9718 3.429)
			(stroke
				(width 0.1524)
				(type default)
			)
			(layer "F.SilkS")
		)
		(fp_line
			(start -3.0099 -3.5052)
			(end 2.9718 -3.5052)
			(stroke
				(width 0.1524)
				(type default)
			)
			(layer "F.SilkS")
		)
		(fp_line
			(start 2.9718 3.429)
			(end -3.0099 3.429)
			(stroke
				(width 0.1524)
				(type default)
			)
			(layer "F.SilkS")
		)
		(fp_line
			(start -3.0099 3.429)
			(end -3.0099 -3.5052)
			(stroke
				(width 0.1524)
				(type default)
			)
			(layer "F.SilkS")
		)
		(fp_circle
			(center -3.057398 -2.678684)
			(end -3.057398 -2.551684)
			(stroke
				(width 0.254)
				(type default)
			)
			(fill no)
			(layer "F.SilkS")
		)
		(fp_poly
			(pts
				(xy -2.9972 -3.4925) (xy -2.9972 -2.6924) (xy -2.1971 -3.4925)
			)
			(stroke
				(width 0)
				(type default)
			)
			(fill yes)
			(layer "F.SilkS")
		)
		(fp_poly
			(pts
				(xy -2.549906 -3.050032) (xy -2.549906 3.050032) (xy 2.549906 3.050032) (xy 2.549906 -3.050032)
			)
			(stroke
				(width 0)
				(type default)
			)
			(fill no)
			(layer "F.CrtYd")
		)
		(fp_line
			(start 2.549906 -3.050032)
			(end 2.549906 3.050032)
			(stroke
				(width 0.1)
				(type default)
			)
			(layer "F.Fab")
		)
		(fp_line
			(start -2.549906 -3.050032)
			(end 2.549906 -3.050032)
			(stroke
				(width 0.1)
				(type default)
			)
			(layer "F.Fab")
		)
		(fp_line
			(start 2.549906 3.050032)
			(end -2.549906 3.050032)
			(stroke
				(width 0.1)
				(type default)
			)
			(layer "F.Fab")
		)
		(fp_line
			(start -2.549906 3.050032)
			(end -2.549906 -3.050032)
			(stroke
				(width 0.1)
				(type default)
			)
			(layer "F.Fab")
		)
		(fp_circle
			(center -3.057398 -2.678684)
			(end -3.057398 -2.551684)
			(stroke
				(width 0.254)
				(type default)
			)
			(fill no)
			(layer "F.Fab")
		)
		(pad "1" smd rect
			(at -2.39522 -2.279904 90)
			(size 0.7112 0.254)
			(layers "F.Cu" "F.Mask" "F.Paste")
			(net "PVDDQ_GHJ")
		)
		(pad "2" smd rect
			(at -2.39522 -1.83007 90)
			(size 0.7112 0.254)
			(layers "F.Cu" "F.Mask" "F.Paste")
			(net "GND")
		)
		(pad "3" smd rect
			(at -2.39522 -1.379982 90)
			(size 0.7112 0.254)
			(layers "F.Cu" "F.Mask" "F.Paste")
			(net "VR_PVDDQ_GHJ_PH1_VCIN")
		)
		(pad "4" smd rect
			(at -2.39522 -0.929894 90)
			(size 0.7112 0.254)
			(layers "F.Cu" "F.Mask" "F.Paste")
			(net "P5V_STBY")
		)
		(pad "5" smd rect
			(at -2.39522 -0.48006 90)
			(size 0.7112 0.254)
			(layers "F.Cu" "F.Mask" "F.Paste")
			(net "GND")
		)
		(pad "6" smd rect
			(at -2.39522 -0.029972 90)
			(size 0.7112 0.254)
			(layers "F.Cu" "F.Mask" "F.Paste")
			(net "TP_PVDDQ_GHJ_PH1_GL_0")
		)
		(pad "7" smd custom
			(at 0.016764 1.145032 90)
			(size 0.53975 0.53975)
			(layers "F.Cu" "F.Mask" "F.Paste")
			(net "GND")
			(options
				(clearance outline)
				(anchor circle)
			)
			(primitives
				(gr_poly
					(pts
						(xy -2.7051 1.0795) (xy -2.7051 -0.3683) (xy -0.9271 -0.3683) (xy -0.9271 -1.0795) (xy 2.7051 -1.0795)
						(xy 2.7051 1.0795)
					)
					(width 0)
					(fill yes)
				)
			)
		)
		(pad "10" smd rect
			(at -0.008382 2.874772 90)
			(size 4.3434 0.6096)
			(layers "F.Cu" "F.Mask" "F.Paste")
			(net "VR_PVDDQ_GHJ_PH1_SW")
		)
		(pad "25" smd rect
			(at 1.548384 -1.283208 90)
			(size 2.3368 2.0066)
			(layers "F.Cu" "F.Mask" "F.Paste")
			(net "VR_FET_SW_P12V_STBY_PVDDQ_GHJ")
		)
		(pad "30" smd rect
			(at 2.050034 -2.895092 90)
			(size 0.254 0.7112)
			(layers "F.Cu" "F.Mask" "F.Paste")
			(net "VR_FET_SW_P12V_STBY_PVDDQ_GHJ")
		)
		(pad "31" smd rect
			(at 1.599946 -2.895092 90)
			(size 0.254 0.7112)
			(layers "F.Cu" "F.Mask" "F.Paste")
			(net "Net_296")
		)
		(pad "32" smd rect
			(at 1.150112 -2.895092 90)
			(size 0.254 0.7112)
			(layers "F.Cu" "F.Mask" "F.Paste")
			(net "VR_PVDDQ_GHJ_PH1_PHASE")
		)
		(pad "33" smd rect
			(at 0.700024 -2.895092 90)
			(size 0.254 0.7112)
			(layers "F.Cu" "F.Mask" "F.Paste")
			(net "VR_PVDDQ_GHJ_PH1_BOOT_R")
		)
		(pad "34" smd rect
			(at 0.249936 -2.895092 90)
			(size 0.254 0.7112)
			(layers "F.Cu" "F.Mask" "F.Paste")
			(net "VR_PVDDQ_GHJ_PWM1")
		)
		(pad "35" smd rect
			(at -0.199898 -2.895092 90)
			(size 0.254 0.7112)
			(layers "F.Cu" "F.Mask" "F.Paste")
			(net "P5V_STBY")
		)
		(pad "36" smd rect
			(at -0.649986 -2.895092 90)
			(size 0.254 0.7112)
			(layers "F.Cu" "F.Mask" "F.Paste")
			(net "A_TSENSE_PVDDQ_GHJ")
		)
		(pad "37" smd rect
			(at -1.100074 -2.895092 90)
			(size 0.254 0.7112)
			(layers "F.Cu" "F.Mask" "F.Paste")
			(net "VR_PVDDQ_GHJ_PH1_OCSET")
		)
		(pad "38" smd rect
			(at -1.549908 -2.895092 90)
			(size 0.254 0.7112)
			(layers "F.Cu" "F.Mask" "F.Paste")
			(net "ISENSE_PVDDQ_GHJ_PH1_IMON")
		)
		(pad "39" smd rect
			(at -1.999996 -2.895092 90)
			(size 0.254 0.7112)
			(layers "F.Cu" "F.Mask" "F.Paste")
			(net "VR_PVDDQ_GHJ_AIREF1")
		)
		(pad "40" smd rect
			(at -0.871728 -1.283208 90)
			(size 1.8034 2.0066)
			(layers "F.Cu" "F.Mask" "F.Paste")
			(net "GND")
		)
		(pad "41" smd rect
			(at -1.533906 0.247904 90)
			(size 0.508 0.3556)
			(layers "F.Cu" "F.Mask" "F.Paste")
			(net "TP_PVDDQ_GHJ_PH1_GL_1")
		)
	)
	(footprint ""
		(layer "F.Cu")
		(at 18.161 -75.692 180)
		(property "Reference" "EU1D2"
			(at -0.127 -3.58267 0)
			(unlocked yes)
			(layer "F.SilkS")
			(effects
				(font
					(size 0.7874 0.5842)
					(thickness 0.1524)
				)
			)
		)
		(property "Value" ""
			(at 0 0 180)
			(layer "F.Fab")
			(effects
				(font
					(size 1.27 1.27)
				)
			)
		)
		(duplicate_pad_numbers_are_jumpers no)
		(fp_line
			(start 2.9591 2.9591)
			(end -2.9591 2.9591)
			(stroke
				(width 0.1524)
				(type default)
			)
			(layer "F.SilkS")
		)
		(fp_line
			(start 2.9591 -2.9591)
			(end 2.9591 2.9591)
			(stroke
				(width 0.1524)
				(type default)
			)
			(layer "F.SilkS")
		)
		(fp_line
			(start 2.55016 2.55016)
			(end 2.257552 2.55016)
			(stroke
				(width 0.1524)
				(type default)
			)
			(layer "F.SilkS")
		)
		(fp_line
			(start 2.55016 2.257552)
			(end 2.55016 2.55016)
			(stroke
				(width 0.1524)
				(type default)
			)
			(layer "F.SilkS")
		)
		(fp_line
			(start 2.55016 -2.257552)
			(end 2.549652 -2.257552)
			(stroke
				(width 0.1524)
				(type default)
			)
			(layer "F.SilkS")
		)
		(fp_line
			(start 2.55016 -2.55016)
			(end 2.55016 -2.257552)
			(stroke
				(width 0.1524)
				(type default)
			)
			(layer "F.SilkS")
		)
		(fp_line
			(start 2.257552 2.55016)
			(end 2.257552 2.549652)
			(stroke
				(width 0.1524)
				(type default)
			)
			(layer "F.SilkS")
		)
		(fp_line
			(start 2.257552 -2.55016)
			(end 2.55016 -2.55016)
			(stroke
				(width 0.1524)
				(type default)
			)
			(layer "F.SilkS")
		)
		(fp_line
			(start -2.257552 2.55016)
			(end -2.55016 2.55016)
			(stroke
				(width 0.1524)
				(type default)
			)
			(layer "F.SilkS")
		)
		(fp_line
			(start -2.257552 -2.55016)
			(end -2.257552 -2.549652)
			(stroke
				(width 0.1524)
				(type default)
			)
			(layer "F.SilkS")
		)
		(fp_line
			(start -2.55016 2.55016)
			(end -2.55016 2.257552)
			(stroke
				(width 0.1524)
				(type default)
			)
			(layer "F.SilkS")
		)
		(fp_line
			(start -2.55016 2.257552)
			(end -2.549652 2.257552)
			(stroke
				(width 0.1524)
				(type default)
			)
			(layer "F.SilkS")
		)
		(fp_line
			(start -2.55016 -2.257552)
			(end -2.55016 -2.55016)
			(stroke
				(width 0.1524)
				(type default)
			)
			(layer "F.SilkS")
		)
		(fp_line
			(start -2.55016 -2.55016)
			(end -2.257552 -2.55016)
			(stroke
				(width 0.1524)
				(type default)
			)
			(layer "F.SilkS")
		)
		(fp_line
			(start -2.9591 2.9591)
			(end -2.9591 -2.9591)
			(stroke
				(width 0.1524)
				(type default)
			)
			(layer "F.SilkS")
		)
		(fp_line
			(start -2.9591 -2.9591)
			(end 2.9591 -2.9591)
			(stroke
				(width 0.1524)
				(type default)
			)
			(layer "F.SilkS")
		)
		(fp_circle
			(center -3.344926 -1.694942)
			(end -3.471926 -1.694942)
			(stroke
				(width 0.254)
				(type default)
			)
			(fill no)
			(layer "F.SilkS")
		)
		(fp_poly
			(pts
				(xy -2.9591 -2.9591) (xy -2.9591 -2.1209) (xy -2.1209 -2.9591)
			)
			(stroke
				(width 0)
				(type default)
			)
			(fill yes)
			(layer "F.SilkS")
		)
		(fp_poly
			(pts
				(xy -1.651 1.651) (xy 1.651 1.651) (xy 1.651 -1.651) (xy -1.651 -1.651)
			)
			(stroke
				(width 0)
				(type default)
			)
			(fill yes)
			(layer "F.Paste")
		)
		(fp_poly
			(pts
				(xy -2.55016 2.55016) (xy 2.55016 2.55016) (xy 2.55016 -2.55016) (xy -2.55016 -2.55016)
			)
			(stroke
				(width 0)
				(type default)
			)
			(fill no)
			(layer "F.CrtYd")
		)
		(fp_line
			(start 2.55016 2.55016)
			(end -2.55016 2.55016)
			(stroke
				(width 0.1)
				(type default)
			)
			(layer "F.Fab")
		)
		(fp_line
			(start 2.55016 -2.55016)
			(end 2.55016 2.55016)
			(stroke
				(width 0.1)
				(type default)
			)
			(layer "F.Fab")
		)
		(fp_line
			(start -2.55016 2.55016)
			(end -2.55016 -2.55016)
			(stroke
				(width 0.1)
				(type default)
			)
			(layer "F.Fab")
		)
		(fp_line
			(start -2.55016 -2.55016)
			(end 2.55016 -2.55016)
			(stroke
				(width 0.1)
				(type default)
			)
			(layer "F.Fab")
		)
		(fp_circle
			(center -3.309366 -2.156714)
			(end -3.436366 -2.156714)
			(stroke
				(width 0.254)
				(type default)
			)
			(fill no)
			(layer "F.Fab")
		)
		(pad "1" smd custom
			(at -2.3495 -1.75133 180)
			(size 0.0762 0.0762)
			(layers "F.Cu" "F.Mask" "F.Paste")
			(net "A_HSC_PSET")
			(options
				(clearance outline)
				(anchor circle)
			)
			(primitives
				(gr_poly
					(pts
						(xy -0.3556 0.1524) (xy -0.3556 -0.1524)
						(arc
							(start 0.2032 -0.1524)
							(mid 0.3556 0)
							(end 0.2032 0.1524)
						)
					)
					(width 0)
					(fill yes)
				)
			)
		)
		(pad "2" smd custom
			(at -2.3495 -1.25095 180)
			(size 0.0762 0.0762)
			(layers "F.Cu" "F.Mask" "F.Paste")
			(net "A_HSC_VCAP")
			(options
				(clearance outline)
				(anchor circle)
			)
			(primitives
				(gr_poly
					(pts
						(xy -0.3556 0.1524) (xy -0.3556 -0.1524)
						(arc
							(start 0.2032 -0.1524)
							(mid 0.3556 0)
							(end 0.2032 0.1524)
						)
					)
					(width 0)
					(fill yes)
				)
			)
		)
		(pad "3" smd custom
			(at -2.3495 -0.75057 180)
			(size 0.0762 0.0762)
			(layers "F.Cu" "F.Mask" "F.Paste")
			(net "A_HSC_ISET")
			(options
				(clearance outline)
				(anchor circle)
			)
			(primitives
				(gr_poly
					(pts
						(xy -0.3556 0.1524) (xy -0.3556 -0.1524)
						(arc
							(start 0.2032 -0.1524)
							(mid 0.3556 0)
							(end 0.2032 0.1524)
						)
					)
					(width 0)
					(fill yes)
				)
			)
		)
		(pad "4" smd custom
			(at -2.3495 -0.25019 180)
			(size 0.0762 0.0762)
			(layers "F.Cu" "F.Mask" "F.Paste")
			(net "A_HSC_ISTART")
			(options
				(clearance outline)
				(anchor circle)
			)
			(primitives
				(gr_poly
					(pts
						(xy -0.3556 0.1524) (xy -0.3556 -0.1524)
						(arc
							(start 0.2032 -0.1524)
							(mid 0.3556 0)
							(end 0.2032 0.1524)
						)
					)
					(width 0)
					(fill yes)
				)
			)
		)
		(pad "5" smd custom
			(at -2.3495 0.25019 180)
			(size 0.0762 0.0762)
			(layers "F.Cu" "F.Mask" "F.Paste")
			(net "A_HSC_TIMER")
			(options
				(clearance outline)
				(anchor circle)
			)
			(primitives
				(gr_poly
					(pts
						(xy -0.3556 0.1524) (xy -0.3556 -0.1524)
						(arc
							(start 0.2032 -0.1524)
							(mid 0.3556 0)
							(end 0.2032 0.1524)
						)
					)
					(width 0)
					(fill yes)
				)
			)
		)
		(pad "6" smd custom
			(at -2.3495 0.75057 180)
			(size 0.0762 0.0762)
			(layers "F.Cu" "F.Mask" "F.Paste")
			(net "IRQ_HSC_FAULT_R_N")
			(options
				(clearance outline)
				(anchor circle)
			)
			(primitives
				(gr_poly
					(pts
						(xy -0.3556 0.1524) (xy -0.3556 -0.1524)
						(arc
							(start 0.2032 -0.1524)
							(mid 0.3556 0)
							(end 0.2032 0.1524)
						)
					)
					(width 0)
					(fill yes)
				)
			)
		)
		(pad "7" smd custom
			(at -2.3495 1.25095 180)
			(size 0.0762 0.0762)
			(layers "F.Cu" "F.Mask" "F.Paste")
			(net "FM_P12V_HSC_ADR1")
			(options
				(clearance outline)
				(anchor circle)
			)
			(primitives
				(gr_poly
					(pts
						(xy -0.3556 0.1524) (xy -0.3556 -0.1524)
						(arc
							(start 0.2032 -0.1524)
							(mid 0.3556 0)
							(end 0.2032 0.1524)
						)
					)
					(width 0)
					(fill yes)
				)
			)
		)
		(pad "8" smd custom
			(at -2.3495 1.75133 180)
			(size 0.0762 0.0762)
			(layers "F.Cu" "F.Mask" "F.Paste")
			(net "FM_P12V_HSC_ADR2")
			(options
				(clearance outline)
				(anchor circle)
			)
			(primitives
				(gr_poly
					(pts
						(xy -0.3556 0.1524) (xy -0.3556 -0.1524)
						(arc
							(start 0.2032 -0.1524)
							(mid 0.3556 0)
							(end 0.2032 0.1524)
						)
					)
					(width 0)
					(fill yes)
				)
			)
		)
		(pad "9" smd custom
			(at -1.75133 2.3495 180)
			(size 0.0762 0.0762)
			(layers "F.Cu" "F.Mask" "F.Paste")
			(net "TP_HSC_SPISSN")
			(options
				(clearance outline)
				(anchor circle)
			)
			(primitives
				(gr_poly
					(pts
						(xy 0.1524 0.3556) (xy -0.1524 0.3556)
						(arc
							(start -0.1524 -0.2032)
							(mid 0 -0.3556)
							(end 0.1524 -0.2032)
						)
					)
					(width 0)
					(fill yes)
				)
			)
		)
		(pad "10" smd custom
			(at -1.25095 2.3495 180)
			(size 0.0762 0.0762)
			(layers "F.Cu" "F.Mask" "F.Paste")
			(net "TP_HSC_MCLK")
			(options
				(clearance outline)
				(anchor circle)
			)
			(primitives
				(gr_poly
					(pts
						(xy 0.1524 0.3556) (xy -0.1524 0.3556)
						(arc
							(start -0.1524 -0.2032)
							(mid 0 -0.3556)
							(end 0.1524 -0.2032)
						)
					)
					(width 0)
					(fill yes)
				)
			)
		)
		(pad "11" smd custom
			(at -0.75057 2.3495 180)
			(size 0.0762 0.0762)
			(layers "F.Cu" "F.Mask" "F.Paste")
			(net "TP_HSC_MDAT")
			(options
				(clearance outline)
				(anchor circle)
			)
			(primitives
				(gr_poly
					(pts
						(xy 0.1524 0.3556) (xy -0.1524 0.3556)
						(arc
							(start -0.1524 -0.2032)
							(mid 0 -0.3556)
							(end 0.1524 -0.2032)
						)
					)
					(width 0)
					(fill yes)
				)
			)
		)
		(pad "12" smd custom
			(at -0.25019 2.3495 180)
			(size 0.0762 0.0762)
			(layers "F.Cu" "F.Mask" "F.Paste")
			(net "FM_P12V_HOTSWAP0_EN")
			(options
				(clearance outline)
				(anchor circle)
			)
			(primitives
				(gr_poly
					(pts
						(xy 0.1524 0.3556) (xy -0.1524 0.3556)
						(arc
							(start -0.1524 -0.2032)
							(mid 0 -0.3556)
							(end 0.1524 -0.2032)
						)
					)
					(width 0)
					(fill yes)
				)
			)
		)
		(pad "13" smd custom
			(at 0.25019 2.3495 180)
			(size 0.0762 0.0762)
			(layers "F.Cu" "F.Mask" "F.Paste")
			(net "IRQ_SML1_PMBUS_ALERT_R_N")
			(options
				(clearance outline)
				(anchor circle)
			)
			(primitives
				(gr_poly
					(pts
						(xy 0.1524 0.3556) (xy -0.1524 0.3556)
						(arc
							(start -0.1524 -0.2032)
							(mid 0 -0.3556)
							(end 0.1524 -0.2032)
						)
					)
					(width 0)
					(fill yes)
				)
			)
		)
		(pad "14" smd custom
			(at 0.75057 2.3495 180)
			(size 0.0762 0.0762)
			(layers "F.Cu" "F.Mask" "F.Paste")
			(net "TP_HSC_ALERT2_N")
			(options
				(clearance outline)
				(anchor circle)
			)
			(primitives
				(gr_poly
					(pts
						(xy 0.1524 0.3556) (xy -0.1524 0.3556)
						(arc
							(start -0.1524 -0.2032)
							(mid 0 -0.3556)
							(end 0.1524 -0.2032)
						)
					)
					(width 0)
					(fill yes)
				)
			)
		)
		(pad "15" smd custom
			(at 1.25095 2.3495 180)
			(size 0.0762 0.0762)
			(layers "F.Cu" "F.Mask" "F.Paste")
			(net "SMB_3V3SB_HSC_SDA_R")
			(options
				(clearance outline)
				(anchor circle)
			)
			(primitives
				(gr_poly
					(pts
						(xy 0.1524 0.3556) (xy -0.1524 0.3556)
						(arc
							(start -0.1524 -0.2032)
							(mid 0 -0.3556)
							(end 0.1524 -0.2032)
						)
					)
					(width 0)
					(fill yes)
				)
			)
		)
		(pad "16" smd custom
			(at 1.75133 2.3495 180)
			(size 0.0762 0.0762)
			(layers "F.Cu" "F.Mask" "F.Paste")
			(net "SMB_3V3SB_HSC_SCL_R")
			(options
				(clearance outline)
				(anchor circle)
			)
			(primitives
				(gr_poly
					(pts
						(xy 0.1524 0.3556) (xy -0.1524 0.3556)
						(arc
							(start -0.1524 -0.2032)
							(mid 0 -0.3556)
							(end 0.1524 -0.2032)
						)
					)
					(width 0)
					(fill yes)
				)
			)
		)
		(pad "17" smd custom
			(at 2.3495 1.75133 180)
			(size 0.0762 0.0762)
			(layers "F.Cu" "F.Mask" "F.Paste")
			(net "PD_HSC_RETRY_N")
			(options
				(clearance outline)
				(anchor circle)
			)
			(primitives
				(gr_poly
					(pts
						(xy 0.3556 -0.1524) (xy 0.3556 0.1524)
						(arc
							(start -0.2032 0.1524)
							(mid -0.3556 0)
							(end -0.2032 -0.1524)
						)
					)
					(width 0)
					(fill yes)
				)
			)
		)
		(pad "18" smd custom
			(at 2.3495 1.25095 180)
			(size 0.0762 0.0762)
			(layers "F.Cu" "F.Mask" "F.Paste")
			(net "PWRGD_P12V_R")
			(options
				(clearance outline)
				(anchor circle)
			)
			(primitives
				(gr_poly
					(pts
						(xy 0.3556 -0.1524) (xy 0.3556 0.1524)
						(arc
							(start -0.2032 0.1524)
							(mid -0.3556 0)
							(end -0.2032 -0.1524)
						)
					)
					(width 0)
					(fill yes)
				)
			)
		)
		(pad "19" smd custom
			(at 2.3495 0.75057 180)
			(size 0.0762 0.0762)
			(layers "F.Cu" "F.Mask" "F.Paste")
			(net "A_HSC_CSOUT")
			(options
				(clearance outline)
				(anchor circle)
			)
			(primitives
				(gr_poly
					(pts
						(xy 0.3556 -0.1524) (xy 0.3556 0.1524)
						(arc
							(start -0.2032 0.1524)
							(mid -0.3556 0)
							(end -0.2032 -0.1524)
						)
					)
					(width 0)
					(fill yes)
				)
			)
		)
		(pad "20" smd custom
			(at 2.3495 0.25019 180)
			(size 0.0762 0.0762)
			(layers "F.Cu" "F.Mask" "F.Paste")
			(net "A_HSC_VOUT")
			(options
				(clearance outline)
				(anchor circle)
			)
			(primitives
				(gr_poly
					(pts
						(xy 0.3556 -0.1524) (xy 0.3556 0.1524)
						(arc
							(start -0.2032 0.1524)
							(mid -0.3556 0)
							(end -0.2032 -0.1524)
						)
					)
					(width 0)
					(fill yes)
				)
			)
		)
		(pad "21" smd custom
			(at 2.3495 -0.25019 180)
			(size 0.0762 0.0762)
			(layers "F.Cu" "F.Mask" "F.Paste")
			(net "A_HSC_PWGIN")
			(options
				(clearance outline)
				(anchor circle)
			)
			(primitives
				(gr_poly
					(pts
						(xy 0.3556 -0.1524) (xy 0.3556 0.1524)
						(arc
							(start -0.2032 0.1524)
							(mid -0.3556 0)
							(end -0.2032 -0.1524)
						)
					)
					(width 0)
					(fill yes)
				)
			)
		)
		(pad "22" smd custom
			(at 2.3495 -0.75057 180)
			(size 0.0762 0.0762)
			(layers "F.Cu" "F.Mask" "F.Paste")
			(net "AGND_HSC")
			(options
				(clearance outline)
				(anchor circle)
			)
			(primitives
				(gr_poly
					(pts
						(xy 0.3556 -0.1524) (xy 0.3556 0.1524)
						(arc
							(start -0.2032 0.1524)
							(mid -0.3556 0)
							(end -0.2032 -0.1524)
						)
					)
					(width 0)
					(fill yes)
				)
			)
		)
		(pad "23" smd custom
			(at 2.3495 -1.25095 180)
			(size 0.0762 0.0762)
			(layers "F.Cu" "F.Mask" "F.Paste")
			(net "GND")
			(options
				(clearance outline)
				(anchor circle)
			)
			(primitives
				(gr_poly
					(pts
						(xy 0.3556 -0.1524) (xy 0.3556 0.1524)
						(arc
							(start -0.2032 0.1524)
							(mid -0.3556 0)
							(end -0.2032 -0.1524)
						)
					)
					(width 0)
					(fill yes)
				)
			)
		)
		(pad "24" smd custom
			(at 2.3495 -1.75133 180)
			(size 0.0762 0.0762)
			(layers "F.Cu" "F.Mask" "F.Paste")
			(net "A_HSC_GATE")
			(options
				(clearance outline)
				(anchor circle)
			)
			(primitives
				(gr_poly
					(pts
						(xy 0.3556 -0.1524) (xy 0.3556 0.1524)
						(arc
							(start -0.2032 0.1524)
							(mid -0.3556 0)
							(end -0.2032 -0.1524)
						)
					)
					(width 0)
					(fill yes)
				)
			)
		)
		(pad "25" smd custom
			(at 1.75133 -2.3495 180)
			(size 0.0762 0.0762)
			(layers "F.Cu" "F.Mask" "F.Paste")
			(net "A_HSC_TEMP")
			(options
				(clearance outline)
				(anchor circle)
			)
			(primitives
				(gr_poly
					(pts
						(xy -0.1524 -0.3556) (xy 0.1524 -0.3556)
						(arc
							(start 0.1524 0.2032)
							(mid 0 0.3556)
							(end -0.1524 0.2032)
						)
					)
					(width 0)
					(fill yes)
				)
			)
		)
		(pad "26" smd custom
			(at 1.25095 -2.3495 180)
			(size 0.0762 0.0762)
			(layers "F.Cu" "F.Mask" "F.Paste")
			(net "A_HSC_MON")
			(options
				(clearance outline)
				(anchor circle)
			)
			(primitives
				(gr_poly
					(pts
						(xy -0.1524 -0.3556) (xy 0.1524 -0.3556)
						(arc
							(start 0.1524 0.2032)
							(mid 0 0.3556)
							(end -0.1524 0.2032)
						)
					)
					(width 0)
					(fill yes)
				)
			)
		)
		(pad "27" smd custom
			(at 0.75057 -2.3495 180)
			(size 0.0762 0.0762)
			(layers "F.Cu" "F.Mask" "F.Paste")
			(net "A_HSC_HSN")
			(options
				(clearance outline)
				(anchor circle)
			)
			(primitives
				(gr_poly
					(pts
						(xy -0.1524 -0.3556) (xy 0.1524 -0.3556)
						(arc
							(start 0.1524 0.2032)
							(mid 0 0.3556)
							(end -0.1524 0.2032)
						)
					)
					(width 0)
					(fill yes)
				)
			)
		)
		(pad "28" smd custom
			(at 0.25019 -2.3495 180)
			(size 0.0762 0.0762)
			(layers "F.Cu" "F.Mask" "F.Paste")
			(net "A_HSC_HSP")
			(options
				(clearance outline)
				(anchor circle)
			)
			(primitives
				(gr_poly
					(pts
						(xy -0.1524 -0.3556) (xy 0.1524 -0.3556)
						(arc
							(start 0.1524 0.2032)
							(mid 0 0.3556)
							(end -0.1524 0.2032)
						)
					)
					(width 0)
					(fill yes)
				)
			)
		)
		(pad "29" smd custom
			(at -0.25019 -2.3495 180)
			(size 0.0762 0.0762)
			(layers "F.Cu" "F.Mask" "F.Paste")
			(net "A_HSC_MOP")
			(options
				(clearance outline)
				(anchor circle)
			)
			(primitives
				(gr_poly
					(pts
						(xy -0.1524 -0.3556) (xy 0.1524 -0.3556)
						(arc
							(start 0.1524 0.2032)
							(mid 0 0.3556)
							(end -0.1524 0.2032)
						)
					)
					(width 0)
					(fill yes)
				)
			)
		)
		(pad "30" smd custom
			(at -0.75057 -2.3495 180)
			(size 0.0762 0.0762)
			(layers "F.Cu" "F.Mask" "F.Paste")
			(net "P12V_HSC_VCC")
			(options
				(clearance outline)
				(anchor circle)
			)
			(primitives
				(gr_poly
					(pts
						(xy -0.1524 -0.3556) (xy 0.1524 -0.3556)
						(arc
							(start 0.1524 0.2032)
							(mid 0 0.3556)
							(end -0.1524 0.2032)
						)
					)
					(width 0)
					(fill yes)
				)
			)
		)
		(pad "31" smd custom
			(at -1.25095 -2.3495 180)
			(size 0.0762 0.0762)
			(layers "F.Cu" "F.Mask" "F.Paste")
			(net "A_HSC_UV")
			(options
				(clearance outline)
				(anchor circle)
			)
			(primitives
				(gr_poly
					(pts
						(xy -0.1524 -0.3556) (xy 0.1524 -0.3556)
						(arc
							(start 0.1524 0.2032)
							(mid 0 0.3556)
							(end -0.1524 0.2032)
						)
					)
					(width 0)
					(fill yes)
				)
			)
		)
		(pad "32" smd custom
			(at -1.75133 -2.3495 180)
			(size 0.0762 0.0762)
			(layers "F.Cu" "F.Mask" "F.Paste")
			(net "A_HSC_OV")
			(options
				(clearance outline)
				(anchor circle)
			)
			(primitives
				(gr_poly
					(pts
						(xy -0.1524 -0.3556) (xy 0.1524 -0.3556)
						(arc
							(start 0.1524 0.2032)
							(mid 0 0.3556)
							(end -0.1524 0.2032)
						)
					)
					(width 0)
					(fill yes)
				)
			)
		)
		(pad "33" smd rect
			(at 0 0 180)
			(size 3.302 3.302)
			(layers "F.Cu" "F.Mask" "F.Paste")
			(net "AGND_HSC")
		)
	)
	(footprint ""
		(layer "F.Cu")
		(at 380.74219 -37.22751)
		(property "Reference" "R8F34"
			(at 0 0 0)
			(layer "F.SilkS")
			(hide yes)
			(effects
				(font
					(size 1.27 1.27)
				)
			)
		)
		(property "Value" ""
			(at 0 0 0)
			(layer "F.Fab")
			(effects
				(font
					(size 1.27 1.27)
				)
			)
		)
		(duplicate_pad_numbers_are_jumpers no)
		(fp_poly
			(pts
				(xy -0.2794 -0.1016) (xy 0.2794 -0.1016) (xy 0.2794 0.9906) (xy -0.2794 0.9906)
			)
			(stroke
				(width 0)
				(type default)
			)
			(fill no)
			(layer "F.CrtYd")
		)
		(fp_line
			(start -0.2794 -0.1016)
			(end -0.2794 0.9906)
			(stroke
				(width 0.1)
				(type default)
			)
			(layer "F.Fab")
		)
		(fp_line
			(start -0.2794 0.9906)
			(end 0.2794 0.9906)
			(stroke
				(width 0.1)
				(type default)
			)
			(layer "F.Fab")
		)
		(fp_line
			(start 0.2794 -0.1016)
			(end -0.2794 -0.1016)
			(stroke
				(width 0.1)
				(type default)
			)
			(layer "F.Fab")
		)
		(fp_line
			(start 0.2794 0.9906)
			(end 0.2794 -0.1016)
			(stroke
				(width 0.1)
				(type default)
			)
			(layer "F.Fab")
		)
		(pad "1" smd rect
			(at 0 0)
			(size 0.508 0.508)
			(layers "F.Cu" "F.Mask" "F.Paste")
			(net "P3V3_STBY")
		)
		(pad "2" smd rect
			(at 0 0.889)
			(size 0.508 0.508)
			(layers "F.Cu" "F.Mask" "F.Paste")
			(net "PU_SPI_BMC_BT_WP_N")
		)
		(zone
			(layer "F.Cu")
			(hatch none 0.5)
			(connect_pads
				(clearance 0)
			)
			(min_thickness 0.25)
			(keepout
				(tracks allowed)
				(vias not_allowed)
				(pads allowed)
				(copperpour not_allowed)
				(footprints allowed)
			)
			(placement
				(enabled no)
				(sheetname "")
			)
			(fill
				(thermal_gap 0.5)
				(thermal_bridge_width 0.5)
				(island_removal_mode 0)
			)
			(polygon
				(pts
					(xy 380.48819 -36.97351) (xy 380.99619 -36.97351) (xy 380.99619 -36.59251) (xy 380.48819 -36.59251)
				)
			)
		)
		(zone
			(layer "F.Cu")
			(hatch none 0.5)
			(connect_pads
				(clearance 0)
			)
			(min_thickness 0.25)
			(keepout
				(tracks not_allowed)
				(vias allowed)
				(pads allowed)
				(copperpour not_allowed)
				(footprints allowed)
			)
			(placement
				(enabled no)
				(sheetname "")
			)
			(fill
				(thermal_gap 0.5)
				(thermal_bridge_width 0.5)
				(island_removal_mode 0)
			)
			(polygon
				(pts
					(xy 380.48819 -36.59251) (xy 380.99619 -36.59251) (xy 380.99619 -36.97351) (xy 380.48819 -36.97351)
				)
			)
		)
	)
	(footprint ""
		(layer "F.Cu")
		(at 270.000222 -76.550012 180)
		(property "Reference" "U5D1"
			(at 19.124422 31.601918 0)
			(unlocked yes)
			(layer "F.SilkS")
			(effects
				(font
					(size 0.7874 0.5842)
					(thickness 0.1524)
				)
			)
		)
		(property "Value" ""
			(at 0 0 180)
			(layer "F.Fab")
			(effects
				(font
					(size 1.27 1.27)
				)
			)
		)
		(duplicate_pad_numbers_are_jumpers no)
		(fp_line
			(start -34.147506 26.518616)
			(end -34.147506 26.519886)
			(stroke
				(width 0.1)
				(type default)
			)
			(layer "F.SilkS")
		)
		(fp_line
			(start -36.773358 14.507718)
			(end -36.773358 14.5034)
			(stroke
				(width 0.1)
				(type default)
			)
			(layer "F.SilkS")
		)
		(fp_line
			(start -37.19576 22.425914)
			(end -37.19576 22.427184)
			(stroke
				(width 0.1)
				(type default)
			)
			(layer "F.SilkS")
		)
		(fp_line
			(start -38.05047 -13.229082)
			(end -37.362892 -13.229082)
			(stroke
				(width 0.1)
				(type default)
			)
			(layer "F.SilkS")
		)
		(fp_line
			(start -38.079426 -9.269984)
			(end -38.079426 -9.27354)
			(stroke
				(width 0.1)
				(type default)
			)
			(layer "F.SilkS")
		)
		(fp_line
			(start -38.443662 -17.203166)
			(end -37.402008 -17.20342)
			(stroke
				(width 0.1)
				(type default)
			)
			(layer "F.SilkS")
		)
		(fp_line
			(start -40.971724 10.539984)
			(end -37.31641 10.539984)
			(stroke
				(width 0.1)
				(type default)
			)
			(layer "F.SilkS")
		)
		(fp_line
			(start -41.111424 6.581394)
			(end -37.311076 6.581394)
			(stroke
				(width 0.1)
				(type default)
			)
			(layer "F.SilkS")
		)
		(fp_line
			(start -41.185846 14.507718)
			(end -36.773358 14.507718)
			(stroke
				(width 0.1)
				(type default)
			)
			(layer "F.SilkS")
		)
		(fp_line
			(start -41.30675 -1.345184)
			(end -35.209988 -1.345184)
			(stroke
				(width 0.1)
				(type default)
			)
			(layer "F.SilkS")
		)
		(fp_line
			(start -41.33469 2.613406)
			(end -35.209988 2.613406)
			(stroke
				(width 0.1)
				(type default)
			)
			(layer "F.SilkS")
		)
		(fp_line
			(start -41.409112 26.518616)
			(end -34.147506 26.518616)
			(stroke
				(width 0.1)
				(type default)
			)
			(layer "F.SilkS")
		)
		(fp_line
			(start -41.632886 -13.229082)
			(end -38.05047 -13.229082)
			(stroke
				(width 0.1)
				(type default)
			)
			(layer "F.SilkS")
		)
		(fp_line
			(start -41.661842 -9.269984)
			(end -38.079426 -9.269984)
			(stroke
				(width 0.1)
				(type default)
			)
			(layer "F.SilkS")
		)
		(fp_line
			(start -41.693592 18.463514)
			(end -38.127686 18.463514)
			(stroke
				(width 0.1)
				(type default)
			)
			(layer "F.SilkS")
		)
		(fp_line
			(start -41.773094 22.425914)
			(end -37.19576 22.425914)
			(stroke
				(width 0.1)
				(type default)
			)
			(layer "F.SilkS")
		)
		(fp_line
			(start -41.78046 -5.310886)
			(end -36.942268 -5.310886)
			(stroke
				(width 0.1)
				(type default)
			)
			(layer "F.SilkS")
		)
		(fp_line
			(start -41.784016 23.911814)
			(end -36.476178 23.911814)
			(stroke
				(width 0.1)
				(type default)
			)
			(layer "F.SilkS")
		)
		(fp_line
			(start -41.811702 -25.122886)
			(end -36.071048 -25.122886)
			(stroke
				(width 0.1)
				(type default)
			)
			(layer "F.SilkS")
		)
		(fp_line
			(start -41.96842 -21.160486)
			(end -37.452808 -21.160486)
			(stroke
				(width 0.1)
				(type default)
			)
			(layer "F.SilkS")
		)
		(fp_line
			(start -42.026078 -17.203166)
			(end -38.443662 -17.203166)
			(stroke
				(width 0.1)
				(type default)
			)
			(layer "F.SilkS")
		)
		(fp_circle
			(center -48.051212 -28.315412)
			(end -48.177958 -28.315412)
			(stroke
				(width 0.254)
				(type default)
			)
			(fill no)
			(layer "F.SilkS")
		)
		(fp_poly
			(pts
				(xy -37.999924 -28.24988) (xy -0.000254 -28.24988) (xy -0.000254 -9.750298) (xy -6.460236 -9.750298)
				(xy -13.05052 -5.790184) (xy -13.05052 5.790184) (xy -6.459982 9.750298) (xy 6.459982 9.750298)
				(xy 13.05052 5.78993) (xy 13.05052 -5.790184) (xy 6.459982 -9.750298) (xy 0.000254 -9.750298) (xy 0.000254 -28.24988)
				(xy 37.999924 -28.24988)
				(arc
					(start 37.999924 14.925802)
					(mid 37.110691 16.000198)
					(end 37.999924 17.074388)
				)
				(xy 37.999924 28.24988) (xy -37.999924 28.24988)
				(arc
					(start -37.999924 17.064228)
					(mid -37.118649 16.000198)
					(end -37.999924 14.935962)
				)
			)
			(stroke
				(width 0)
				(type default)
			)
			(fill no)
			(layer "F.CrtYd")
		)
		(fp_line
			(start 37.999924 28.24988)
			(end 37.999924 17.074388)
			(stroke
				(width 0.1)
				(type default)
			)
			(layer "F.Fab")
		)
		(fp_line
			(start 37.999924 14.925802)
			(end 37.999924 -28.24988)
			(stroke
				(width 0.1)
				(type default)
			)
			(layer "F.Fab")
		)
		(fp_line
			(start 37.999924 -28.24988)
			(end -37.999924 -28.24988)
			(stroke
				(width 0.1)
				(type default)
			)
			(layer "F.Fab")
		)
		(fp_line
			(start -37.12464 15.99819)
			(end -37.124894 16.00708)
			(stroke
				(width 0.1)
				(type default)
			)
			(layer "F.Fab")
		)
		(fp_line
			(start -37.124894 16.02359)
			(end -37.125148 16.032226)
			(stroke
				(width 0.1)
				(type default)
			)
			(layer "F.Fab")
		)
		(fp_line
			(start -37.124894 16.017494)
			(end -37.124894 16.02359)
			(stroke
				(width 0.1)
				(type default)
			)
			(layer "F.Fab")
		)
		(fp_line
			(start -37.124894 16.00962)
			(end -37.124894 16.017494)
			(stroke
				(width 0.1)
				(type default)
			)
			(layer "F.Fab")
		)
		(fp_line
			(start -37.124894 16.00708)
			(end -37.124894 16.00962)
			(stroke
				(width 0.1)
				(type default)
			)
			(layer "F.Fab")
		)
		(fp_line
			(start -37.124894 15.99311)
			(end -37.12464 15.99819)
			(stroke
				(width 0.1)
				(type default)
			)
			(layer "F.Fab")
		)
		(fp_line
			(start -37.125148 16.032226)
			(end -37.125656 16.043402)
			(stroke
				(width 0.1)
				(type default)
			)
			(layer "F.Fab")
		)
		(fp_line
			(start -37.125402 15.961868)
			(end -37.124894 15.99311)
			(stroke
				(width 0.1)
				(type default)
			)
			(layer "F.Fab")
		)
		(fp_line
			(start -37.125656 16.043402)
			(end -37.126164 16.054578)
			(stroke
				(width 0.1)
				(type default)
			)
			(layer "F.Fab")
		)
		(fp_line
			(start -37.12591 15.949676)
			(end -37.125402 15.961868)
			(stroke
				(width 0.1)
				(type default)
			)
			(layer "F.Fab")
		)
		(fp_line
			(start -37.126164 16.054578)
			(end -37.126672 16.063214)
			(stroke
				(width 0.1)
				(type default)
			)
			(layer "F.Fab")
		)
		(fp_line
			(start -37.126418 15.938754)
			(end -37.12591 15.949676)
			(stroke
				(width 0.1)
				(type default)
			)
			(layer "F.Fab")
		)
		(fp_line
			(start -37.126672 16.063214)
			(end -37.12718 16.07439)
			(stroke
				(width 0.1)
				(type default)
			)
			(layer "F.Fab")
		)
		(fp_line
			(start -37.126926 15.930118)
			(end -37.126418 15.938754)
			(stroke
				(width 0.1)
				(type default)
			)
			(layer "F.Fab")
		)
		(fp_line
			(start -37.12718 16.07439)
			(end -37.127688 16.079978)
			(stroke
				(width 0.1)
				(type default)
			)
			(layer "F.Fab")
		)
		(fp_line
			(start -37.127688 16.079978)
			(end -37.128196 16.086836)
			(stroke
				(width 0.1)
				(type default)
			)
			(layer "F.Fab")
		)
		(fp_line
			(start -37.127688 15.921736)
			(end -37.126926 15.930118)
			(stroke
				(width 0.1)
				(type default)
			)
			(layer "F.Fab")
		)
		(fp_line
			(start -37.128196 16.086836)
			(end -37.128958 16.094964)
			(stroke
				(width 0.1)
				(type default)
			)
			(layer "F.Fab")
		)
		(fp_line
			(start -37.128196 15.914624)
			(end -37.127688 15.921736)
			(stroke
				(width 0.1)
				(type default)
			)
			(layer "F.Fab")
		)
		(fp_line
			(start -37.128704 15.906496)
			(end -37.128196 15.914624)
			(stroke
				(width 0.1)
				(type default)
			)
			(layer "F.Fab")
		)
		(fp_line
			(start -37.128958 16.094964)
			(end -37.129466 16.100298)
			(stroke
				(width 0.1)
				(type default)
			)
			(layer "F.Fab")
		)
		(fp_line
			(start -37.129466 16.100298)
			(end -37.130228 16.109696)
			(stroke
				(width 0.1)
				(type default)
			)
			(layer "F.Fab")
		)
		(fp_line
			(start -37.12972 15.895574)
			(end -37.128704 15.906496)
			(stroke
				(width 0.1)
				(type default)
			)
			(layer "F.Fab")
		)
		(fp_line
			(start -37.130228 16.109696)
			(end -37.13099 16.115538)
			(stroke
				(width 0.1)
				(type default)
			)
			(layer "F.Fab")
		)
		(fp_line
			(start -37.130736 15.88643)
			(end -37.12972 15.895574)
			(stroke
				(width 0.1)
				(type default)
			)
			(layer "F.Fab")
		)
		(fp_line
			(start -37.13099 16.115538)
			(end -37.131752 16.122904)
			(stroke
				(width 0.1)
				(type default)
			)
			(layer "F.Fab")
		)
		(fp_line
			(start -37.131498 15.879064)
			(end -37.130736 15.88643)
			(stroke
				(width 0.1)
				(type default)
			)
			(layer "F.Fab")
		)
		(fp_line
			(start -37.131752 16.122904)
			(end -37.13226 16.127984)
			(stroke
				(width 0.1)
				(type default)
			)
			(layer "F.Fab")
		)
		(fp_line
			(start -37.13226 16.127984)
			(end -37.133022 16.13281)
			(stroke
				(width 0.1)
				(type default)
			)
			(layer "F.Fab")
		)
		(fp_line
			(start -37.13226 15.872968)
			(end -37.131498 15.879064)
			(stroke
				(width 0.1)
				(type default)
			)
			(layer "F.Fab")
		)
		(fp_line
			(start -37.133022 16.13281)
			(end -37.134292 16.143478)
			(stroke
				(width 0.1)
				(type default)
			)
			(layer "F.Fab")
		)
		(fp_line
			(start -37.133022 15.86738)
			(end -37.13226 15.872968)
			(stroke
				(width 0.1)
				(type default)
			)
			(layer "F.Fab")
		)
		(fp_line
			(start -37.133276 15.864078)
			(end -37.133022 15.86738)
			(stroke
				(width 0.1)
				(type default)
			)
			(layer "F.Fab")
		)
		(fp_line
			(start -37.134038 15.858744)
			(end -37.133276 15.864078)
			(stroke
				(width 0.1)
				(type default)
			)
			(layer "F.Fab")
		)
		(fp_line
			(start -37.134292 16.143478)
			(end -37.1348 16.147288)
			(stroke
				(width 0.1)
				(type default)
			)
			(layer "F.Fab")
		)
		(fp_line
			(start -37.1348 16.147288)
			(end -37.135308 16.150844)
			(stroke
				(width 0.1)
				(type default)
			)
			(layer "F.Fab")
		)
		(fp_line
			(start -37.135308 16.150844)
			(end -37.13607 16.155924)
			(stroke
				(width 0.1)
				(type default)
			)
			(layer "F.Fab")
		)
		(fp_line
			(start -37.135308 15.849854)
			(end -37.134038 15.858744)
			(stroke
				(width 0.1)
				(type default)
			)
			(layer "F.Fab")
		)
		(fp_line
			(start -37.13607 16.155924)
			(end -37.137086 16.163798)
			(stroke
				(width 0.1)
				(type default)
			)
			(layer "F.Fab")
		)
		(fp_line
			(start -37.136578 15.84071)
			(end -37.135308 15.849854)
			(stroke
				(width 0.1)
				(type default)
			)
			(layer "F.Fab")
		)
		(fp_line
			(start -37.137086 16.163798)
			(end -37.137848 16.167862)
			(stroke
				(width 0.1)
				(type default)
			)
			(layer "F.Fab")
		)
		(fp_line
			(start -37.137848 16.167862)
			(end -37.138356 16.17091)
			(stroke
				(width 0.1)
				(type default)
			)
			(layer "F.Fab")
		)
		(fp_line
			(start -37.138356 16.17091)
			(end -37.13861 16.17345)
			(stroke
				(width 0.1)
				(type default)
			)
			(layer "F.Fab")
		)
		(fp_line
			(start -37.13861 16.17345)
			(end -37.139118 16.176498)
			(stroke
				(width 0.1)
				(type default)
			)
			(layer "F.Fab")
		)
		(fp_line
			(start -37.13861 15.827756)
			(end -37.136578 15.84071)
			(stroke
				(width 0.1)
				(type default)
			)
			(layer "F.Fab")
		)
		(fp_line
			(start -37.139118 16.176498)
			(end -37.139626 16.179546)
			(stroke
				(width 0.1)
				(type default)
			)
			(layer "F.Fab")
		)
		(fp_line
			(start -37.139626 16.179546)
			(end -37.140388 16.18361)
			(stroke
				(width 0.1)
				(type default)
			)
			(layer "F.Fab")
		)
		(fp_line
			(start -37.140388 16.18361)
			(end -37.140896 16.186658)
			(stroke
				(width 0.1)
				(type default)
			)
			(layer "F.Fab")
		)
		(fp_line
			(start -37.140388 15.817088)
			(end -37.13861 15.827756)
			(stroke
				(width 0.1)
				(type default)
			)
			(layer "F.Fab")
		)
		(fp_line
			(start -37.140896 16.186658)
			(end -37.141404 16.189452)
			(stroke
				(width 0.1)
				(type default)
			)
			(layer "F.Fab")
		)
		(fp_line
			(start -37.141404 16.189452)
			(end -37.141658 16.190976)
			(stroke
				(width 0.1)
				(type default)
			)
			(layer "F.Fab")
		)
		(fp_line
			(start -37.141404 15.809976)
			(end -37.140388 15.817088)
			(stroke
				(width 0.1)
				(type default)
			)
			(layer "F.Fab")
		)
		(fp_line
			(start -37.141658 16.190976)
			(end -37.142166 16.193262)
			(stroke
				(width 0.1)
				(type default)
			)
			(layer "F.Fab")
		)
		(fp_line
			(start -37.142166 16.193262)
			(end -37.142928 16.19758)
			(stroke
				(width 0.1)
				(type default)
			)
			(layer "F.Fab")
		)
		(fp_line
			(start -37.142674 15.803118)
			(end -37.141404 15.809976)
			(stroke
				(width 0.1)
				(type default)
			)
			(layer "F.Fab")
		)
		(fp_line
			(start -37.142928 16.19758)
			(end -37.143182 16.199866)
			(stroke
				(width 0.1)
				(type default)
			)
			(layer "F.Fab")
		)
		(fp_line
			(start -37.143182 16.199866)
			(end -37.144198 16.2052)
			(stroke
				(width 0.1)
				(type default)
			)
			(layer "F.Fab")
		)
		(fp_line
			(start -37.143944 15.797022)
			(end -37.142674 15.803118)
			(stroke
				(width 0.1)
				(type default)
			)
			(layer "F.Fab")
		)
		(fp_line
			(start -37.144198 16.2052)
			(end -37.14496 16.208756)
			(stroke
				(width 0.1)
				(type default)
			)
			(layer "F.Fab")
		)
		(fp_line
			(start -37.14496 16.208756)
			(end -37.148262 16.224504)
			(stroke
				(width 0.1)
				(type default)
			)
			(layer "F.Fab")
		)
		(fp_line
			(start -37.145468 15.789402)
			(end -37.143944 15.797022)
			(stroke
				(width 0.1)
				(type default)
			)
			(layer "F.Fab")
		)
		(fp_line
			(start -37.146738 15.782798)
			(end -37.145468 15.789402)
			(stroke
				(width 0.1)
				(type default)
			)
			(layer "F.Fab")
		)
		(fp_line
			(start -37.148008 15.776448)
			(end -37.146738 15.782798)
			(stroke
				(width 0.1)
				(type default)
			)
			(layer "F.Fab")
		)
		(fp_line
			(start -37.148262 16.224504)
			(end -37.149532 16.2306)
			(stroke
				(width 0.1)
				(type default)
			)
			(layer "F.Fab")
		)
		(fp_line
			(start -37.149532 16.2306)
			(end -37.151564 16.23949)
			(stroke
				(width 0.1)
				(type default)
			)
			(layer "F.Fab")
		)
		(fp_line
			(start -37.149786 15.767812)
			(end -37.148008 15.776448)
			(stroke
				(width 0.1)
				(type default)
			)
			(layer "F.Fab")
		)
		(fp_line
			(start -37.151564 16.23949)
			(end -37.152834 16.245078)
			(stroke
				(width 0.1)
				(type default)
			)
			(layer "F.Fab")
		)
		(fp_line
			(start -37.151818 15.759684)
			(end -37.149786 15.767812)
			(stroke
				(width 0.1)
				(type default)
			)
			(layer "F.Fab")
		)
		(fp_line
			(start -37.152834 16.245078)
			(end -37.153596 16.248888)
			(stroke
				(width 0.1)
				(type default)
			)
			(layer "F.Fab")
		)
		(fp_line
			(start -37.153342 15.752826)
			(end -37.151818 15.759684)
			(stroke
				(width 0.1)
				(type default)
			)
			(layer "F.Fab")
		)
		(fp_line
			(start -37.153596 16.248888)
			(end -37.15512 16.254222)
			(stroke
				(width 0.1)
				(type default)
			)
			(layer "F.Fab")
		)
		(fp_line
			(start -37.15512 16.254222)
			(end -37.15639 16.25981)
			(stroke
				(width 0.1)
				(type default)
			)
			(layer "F.Fab")
		)
		(fp_line
			(start -37.15512 15.745206)
			(end -37.153342 15.752826)
			(stroke
				(width 0.1)
				(type default)
			)
			(layer "F.Fab")
		)
		(fp_line
			(start -37.15639 16.25981)
			(end -37.157406 16.264382)
			(stroke
				(width 0.1)
				(type default)
			)
			(layer "F.Fab")
		)
		(fp_line
			(start -37.157152 15.737078)
			(end -37.15512 15.745206)
			(stroke
				(width 0.1)
				(type default)
			)
			(layer "F.Fab")
		)
		(fp_line
			(start -37.157406 16.264382)
			(end -37.158422 16.268192)
			(stroke
				(width 0.1)
				(type default)
			)
			(layer "F.Fab")
		)
		(fp_line
			(start -37.158422 16.268192)
			(end -37.159692 16.272764)
			(stroke
				(width 0.1)
				(type default)
			)
			(layer "F.Fab")
		)
		(fp_line
			(start -37.15893 15.729712)
			(end -37.157152 15.737078)
			(stroke
				(width 0.1)
				(type default)
			)
			(layer "F.Fab")
		)
		(fp_line
			(start -37.159692 16.272764)
			(end -37.161216 16.278606)
			(stroke
				(width 0.1)
				(type default)
			)
			(layer "F.Fab")
		)
		(fp_line
			(start -37.161216 16.278606)
			(end -37.162486 16.283686)
			(stroke
				(width 0.1)
				(type default)
			)
			(layer "F.Fab")
		)
		(fp_line
			(start -37.161978 15.718536)
			(end -37.15893 15.729712)
			(stroke
				(width 0.1)
				(type default)
			)
			(layer "F.Fab")
		)
		(fp_line
			(start -37.162486 16.283686)
			(end -37.164264 16.29029)
			(stroke
				(width 0.1)
				(type default)
			)
			(layer "F.Fab")
		)
		(fp_line
			(start -37.162486 15.715996)
			(end -37.161978 15.718536)
			(stroke
				(width 0.1)
				(type default)
			)
			(layer "F.Fab")
		)
		(fp_line
			(start -37.163502 15.713202)
			(end -37.162486 15.715996)
			(stroke
				(width 0.1)
				(type default)
			)
			(layer "F.Fab")
		)
		(fp_line
			(start -37.164264 16.29029)
			(end -37.166042 16.296386)
			(stroke
				(width 0.1)
				(type default)
			)
			(layer "F.Fab")
		)
		(fp_line
			(start -37.164772 15.708376)
			(end -37.163502 15.713202)
			(stroke
				(width 0.1)
				(type default)
			)
			(layer "F.Fab")
		)
		(fp_line
			(start -37.166042 16.296386)
			(end -37.16782 16.30299)
			(stroke
				(width 0.1)
				(type default)
			)
			(layer "F.Fab")
		)
		(fp_line
			(start -37.166296 15.702534)
			(end -37.164772 15.708376)
			(stroke
				(width 0.1)
				(type default)
			)
			(layer "F.Fab")
		)
		(fp_line
			(start -37.16782 16.30299)
			(end -37.170614 16.312388)
			(stroke
				(width 0.1)
				(type default)
			)
			(layer "F.Fab")
		)
		(fp_line
			(start -37.168328 15.695676)
			(end -37.166296 15.702534)
			(stroke
				(width 0.1)
				(type default)
			)
			(layer "F.Fab")
		)
		(fp_line
			(start -37.170614 16.312388)
			(end -37.172138 16.317214)
			(stroke
				(width 0.1)
				(type default)
			)
			(layer "F.Fab")
		)
		(fp_line
			(start -37.171122 15.686024)
			(end -37.168328 15.695676)
			(stroke
				(width 0.1)
				(type default)
			)
			(layer "F.Fab")
		)
		(fp_line
			(start -37.172138 16.317214)
			(end -37.173662 16.321786)
			(stroke
				(width 0.1)
				(type default)
			)
			(layer "F.Fab")
		)
		(fp_line
			(start -37.173662 16.321786)
			(end -37.174932 16.326358)
			(stroke
				(width 0.1)
				(type default)
			)
			(layer "F.Fab")
		)
		(fp_line
			(start -37.174424 15.67561)
			(end -37.171122 15.686024)
			(stroke
				(width 0.1)
				(type default)
			)
			(layer "F.Fab")
		)
		(fp_line
			(start -37.174932 16.326358)
			(end -37.17671 16.331692)
			(stroke
				(width 0.1)
				(type default)
			)
			(layer "F.Fab")
		)
		(fp_line
			(start -37.17671 16.331692)
			(end -37.178488 16.33728)
			(stroke
				(width 0.1)
				(type default)
			)
			(layer "F.Fab")
		)
		(fp_line
			(start -37.177726 15.665196)
			(end -37.174424 15.67561)
			(stroke
				(width 0.1)
				(type default)
			)
			(layer "F.Fab")
		)
		(fp_line
			(start -37.178488 16.33728)
			(end -37.182044 16.347948)
			(stroke
				(width 0.1)
				(type default)
			)
			(layer "F.Fab")
		)
		(fp_line
			(start -37.182044 16.347948)
			(end -37.183314 16.352012)
			(stroke
				(width 0.1)
				(type default)
			)
			(layer "F.Fab")
		)
		(fp_line
			(start -37.182298 15.651226)
			(end -37.177726 15.665196)
			(stroke
				(width 0.1)
				(type default)
			)
			(layer "F.Fab")
		)
		(fp_line
			(start -37.183314 16.352012)
			(end -37.184838 16.356076)
			(stroke
				(width 0.1)
				(type default)
			)
			(layer "F.Fab")
		)
		(fp_line
			(start -37.184838 16.356076)
			(end -37.186616 16.361156)
			(stroke
				(width 0.1)
				(type default)
			)
			(layer "F.Fab")
		)
		(fp_line
			(start -37.184838 15.644114)
			(end -37.182298 15.651226)
			(stroke
				(width 0.1)
				(type default)
			)
			(layer "F.Fab")
		)
		(fp_line
			(start -37.186616 16.361156)
			(end -37.187378 16.363188)
			(stroke
				(width 0.1)
				(type default)
			)
			(layer "F.Fab")
		)
		(fp_line
			(start -37.187378 16.363188)
			(end -37.188902 16.367506)
			(stroke
				(width 0.1)
				(type default)
			)
			(layer "F.Fab")
		)
		(fp_line
			(start -37.187632 15.635732)
			(end -37.184838 15.644114)
			(stroke
				(width 0.1)
				(type default)
			)
			(layer "F.Fab")
		)
		(fp_line
			(start -37.188902 16.367506)
			(end -37.19068 16.372586)
			(stroke
				(width 0.1)
				(type default)
			)
			(layer "F.Fab")
		)
		(fp_line
			(start -37.190426 15.628112)
			(end -37.187632 15.635732)
			(stroke
				(width 0.1)
				(type default)
			)
			(layer "F.Fab")
		)
		(fp_line
			(start -37.19068 16.372586)
			(end -37.192712 16.377666)
			(stroke
				(width 0.1)
				(type default)
			)
			(layer "F.Fab")
		)
		(fp_line
			(start -37.192712 16.377666)
			(end -37.194236 16.381984)
			(stroke
				(width 0.1)
				(type default)
			)
			(layer "F.Fab")
		)
		(fp_line
			(start -37.193474 15.61973)
			(end -37.190426 15.628112)
			(stroke
				(width 0.1)
				(type default)
			)
			(layer "F.Fab")
		)
		(fp_line
			(start -37.194236 16.381984)
			(end -37.196522 16.387826)
			(stroke
				(width 0.1)
				(type default)
			)
			(layer "F.Fab")
		)
		(fp_line
			(start -37.196522 16.387826)
			(end -37.1983 16.392398)
			(stroke
				(width 0.1)
				(type default)
			)
			(layer "F.Fab")
		)
		(fp_line
			(start -37.197284 15.610332)
			(end -37.193474 15.61973)
			(stroke
				(width 0.1)
				(type default)
			)
			(layer "F.Fab")
		)
		(fp_line
			(start -37.1983 16.392398)
			(end -37.199316 16.395446)
			(stroke
				(width 0.1)
				(type default)
			)
			(layer "F.Fab")
		)
		(fp_line
			(start -37.199316 16.395446)
			(end -37.200078 16.397478)
			(stroke
				(width 0.1)
				(type default)
			)
			(layer "F.Fab")
		)
		(fp_line
			(start -37.200078 16.397478)
			(end -37.203634 16.406114)
			(stroke
				(width 0.1)
				(type default)
			)
			(layer "F.Fab")
		)
		(fp_line
			(start -37.201602 15.598902)
			(end -37.197284 15.610332)
			(stroke
				(width 0.1)
				(type default)
			)
			(layer "F.Fab")
		)
		(fp_line
			(start -37.203634 16.406114)
			(end -37.205412 16.410686)
			(stroke
				(width 0.1)
				(type default)
			)
			(layer "F.Fab")
		)
		(fp_line
			(start -37.205412 16.410686)
			(end -37.20719 16.415004)
			(stroke
				(width 0.1)
				(type default)
			)
			(layer "F.Fab")
		)
		(fp_line
			(start -37.205412 15.589504)
			(end -37.201602 15.598902)
			(stroke
				(width 0.1)
				(type default)
			)
			(layer "F.Fab")
		)
		(fp_line
			(start -37.20719 16.415004)
			(end -37.209222 16.419322)
			(stroke
				(width 0.1)
				(type default)
			)
			(layer "F.Fab")
		)
		(fp_line
			(start -37.208968 15.580868)
			(end -37.205412 15.589504)
			(stroke
				(width 0.1)
				(type default)
			)
			(layer "F.Fab")
		)
		(fp_line
			(start -37.209222 16.419322)
			(end -37.210492 16.422624)
			(stroke
				(width 0.1)
				(type default)
			)
			(layer "F.Fab")
		)
		(fp_line
			(start -37.210492 16.422624)
			(end -37.211508 16.425164)
			(stroke
				(width 0.1)
				(type default)
			)
			(layer "F.Fab")
		)
		(fp_line
			(start -37.211508 16.425164)
			(end -37.212778 16.428212)
			(stroke
				(width 0.1)
				(type default)
			)
			(layer "F.Fab")
		)
		(fp_line
			(start -37.212778 16.428212)
			(end -37.215318 16.4338)
			(stroke
				(width 0.1)
				(type default)
			)
			(layer "F.Fab")
		)
		(fp_line
			(start -37.214302 15.568168)
			(end -37.208968 15.580868)
			(stroke
				(width 0.1)
				(type default)
			)
			(layer "F.Fab")
		)
		(fp_line
			(start -37.215318 16.4338)
			(end -37.216334 16.43634)
			(stroke
				(width 0.1)
				(type default)
			)
			(layer "F.Fab")
		)
		(fp_line
			(start -37.216334 16.43634)
			(end -37.217858 16.439642)
			(stroke
				(width 0.1)
				(type default)
			)
			(layer "F.Fab")
		)
		(fp_line
			(start -37.217858 16.439642)
			(end -37.21989 16.444214)
			(stroke
				(width 0.1)
				(type default)
			)
			(layer "F.Fab")
		)
		(fp_line
			(start -37.219128 15.5575)
			(end -37.214302 15.568168)
			(stroke
				(width 0.1)
				(type default)
			)
			(layer "F.Fab")
		)
		(fp_line
			(start -37.21989 16.444214)
			(end -37.222684 16.45031)
			(stroke
				(width 0.1)
				(type default)
			)
			(layer "F.Fab")
		)
		(fp_line
			(start -37.222684 16.45031)
			(end -37.225224 16.456152)
			(stroke
				(width 0.1)
				(type default)
			)
			(layer "F.Fab")
		)
		(fp_line
			(start -37.224208 15.546578)
			(end -37.219128 15.5575)
			(stroke
				(width 0.1)
				(type default)
			)
			(layer "F.Fab")
		)
		(fp_line
			(start -37.225224 16.456152)
			(end -37.226748 16.4592)
			(stroke
				(width 0.1)
				(type default)
			)
			(layer "F.Fab")
		)
		(fp_line
			(start -37.226748 16.4592)
			(end -37.228272 16.462502)
			(stroke
				(width 0.1)
				(type default)
			)
			(layer "F.Fab")
		)
		(fp_line
			(start -37.227764 15.538704)
			(end -37.224208 15.546578)
			(stroke
				(width 0.1)
				(type default)
			)
			(layer "F.Fab")
		)
		(fp_line
			(start -37.228272 16.462502)
			(end -37.23005 16.466058)
			(stroke
				(width 0.1)
				(type default)
			)
			(layer "F.Fab")
		)
		(fp_line
			(start -37.23005 16.466058)
			(end -37.23132 16.468598)
			(stroke
				(width 0.1)
				(type default)
			)
			(layer "F.Fab")
		)
		(fp_line
			(start -37.23132 16.468598)
			(end -37.23259 16.471646)
			(stroke
				(width 0.1)
				(type default)
			)
			(layer "F.Fab")
		)
		(fp_line
			(start -37.231574 15.530322)
			(end -37.227764 15.538704)
			(stroke
				(width 0.1)
				(type default)
			)
			(layer "F.Fab")
		)
		(fp_line
			(start -37.23259 16.471646)
			(end -37.23386 16.473932)
			(stroke
				(width 0.1)
				(type default)
			)
			(layer "F.Fab")
		)
		(fp_line
			(start -37.233098 15.527528)
			(end -37.231574 15.530322)
			(stroke
				(width 0.1)
				(type default)
			)
			(layer "F.Fab")
		)
		(fp_line
			(start -37.23386 16.473932)
			(end -37.238178 16.482822)
			(stroke
				(width 0.1)
				(type default)
			)
			(layer "F.Fab")
		)
		(fp_line
			(start -37.236146 15.521178)
			(end -37.233098 15.527528)
			(stroke
				(width 0.1)
				(type default)
			)
			(layer "F.Fab")
		)
		(fp_line
			(start -37.238178 16.482822)
			(end -37.240972 16.488664)
			(stroke
				(width 0.1)
				(type default)
			)
			(layer "F.Fab")
		)
		(fp_line
			(start -37.239194 15.514828)
			(end -37.236146 15.521178)
			(stroke
				(width 0.1)
				(type default)
			)
			(layer "F.Fab")
		)
		(fp_line
			(start -37.240972 16.488664)
			(end -37.242496 16.491204)
			(stroke
				(width 0.1)
				(type default)
			)
			(layer "F.Fab")
		)
		(fp_line
			(start -37.242496 16.491204)
			(end -37.244274 16.495268)
			(stroke
				(width 0.1)
				(type default)
			)
			(layer "F.Fab")
		)
		(fp_line
			(start -37.243512 15.506446)
			(end -37.239194 15.514828)
			(stroke
				(width 0.1)
				(type default)
			)
			(layer "F.Fab")
		)
		(fp_line
			(start -37.244274 16.495268)
			(end -37.247576 16.50111)
			(stroke
				(width 0.1)
				(type default)
			)
			(layer "F.Fab")
		)
		(fp_line
			(start -37.247068 15.499842)
			(end -37.243512 15.506446)
			(stroke
				(width 0.1)
				(type default)
			)
			(layer "F.Fab")
		)
		(fp_line
			(start -37.247576 16.50111)
			(end -37.249862 16.505682)
			(stroke
				(width 0.1)
				(type default)
			)
			(layer "F.Fab")
		)
		(fp_line
			(start -37.249608 15.495016)
			(end -37.247068 15.499842)
			(stroke
				(width 0.1)
				(type default)
			)
			(layer "F.Fab")
		)
		(fp_line
			(start -37.249862 16.505682)
			(end -37.251894 16.509492)
			(stroke
				(width 0.1)
				(type default)
			)
			(layer "F.Fab")
		)
		(fp_line
			(start -37.251894 16.509492)
			(end -37.254434 16.514318)
			(stroke
				(width 0.1)
				(type default)
			)
			(layer "F.Fab")
		)
		(fp_line
			(start -37.25291 15.48892)
			(end -37.249608 15.495016)
			(stroke
				(width 0.1)
				(type default)
			)
			(layer "F.Fab")
		)
		(fp_line
			(start -37.254434 16.514318)
			(end -37.257482 16.52016)
			(stroke
				(width 0.1)
				(type default)
			)
			(layer "F.Fab")
		)
		(fp_line
			(start -37.25545 15.484094)
			(end -37.25291 15.48892)
			(stroke
				(width 0.1)
				(type default)
			)
			(layer "F.Fab")
		)
		(fp_line
			(start -37.257482 16.52016)
			(end -37.258498 16.521684)
			(stroke
				(width 0.1)
				(type default)
			)
			(layer "F.Fab")
		)
		(fp_line
			(start -37.257482 15.480284)
			(end -37.25545 15.484094)
			(stroke
				(width 0.1)
				(type default)
			)
			(layer "F.Fab")
		)
		(fp_line
			(start -37.258498 16.521684)
			(end -37.259514 16.523716)
			(stroke
				(width 0.1)
				(type default)
			)
			(layer "F.Fab")
		)
		(fp_line
			(start -37.259514 16.523716)
			(end -37.261546 16.527272)
			(stroke
				(width 0.1)
				(type default)
			)
			(layer "F.Fab")
		)
		(fp_line
			(start -37.260276 15.47495)
			(end -37.257482 15.480284)
			(stroke
				(width 0.1)
				(type default)
			)
			(layer "F.Fab")
		)
		(fp_line
			(start -37.261546 16.527272)
			(end -37.263578 16.531082)
			(stroke
				(width 0.1)
				(type default)
			)
			(layer "F.Fab")
		)
		(fp_line
			(start -37.263324 15.469616)
			(end -37.260276 15.47495)
			(stroke
				(width 0.1)
				(type default)
			)
			(layer "F.Fab")
		)
		(fp_line
			(start -37.263578 16.531082)
			(end -37.266372 16.535908)
			(stroke
				(width 0.1)
				(type default)
			)
			(layer "F.Fab")
		)
		(fp_line
			(start -37.265864 15.465298)
			(end -37.263324 15.469616)
			(stroke
				(width 0.1)
				(type default)
			)
			(layer "F.Fab")
		)
		(fp_line
			(start -37.266372 16.535908)
			(end -37.267388 16.537686)
			(stroke
				(width 0.1)
				(type default)
			)
			(layer "F.Fab")
		)
		(fp_line
			(start -37.267388 16.537686)
			(end -37.269166 16.540734)
			(stroke
				(width 0.1)
				(type default)
			)
			(layer "F.Fab")
		)
		(fp_line
			(start -37.268658 15.460218)
			(end -37.265864 15.465298)
			(stroke
				(width 0.1)
				(type default)
			)
			(layer "F.Fab")
		)
		(fp_line
			(start -37.269166 16.540734)
			(end -37.274754 16.550386)
			(stroke
				(width 0.1)
				(type default)
			)
			(layer "F.Fab")
		)
		(fp_line
			(start -37.271706 15.45463)
			(end -37.268658 15.460218)
			(stroke
				(width 0.1)
				(type default)
			)
			(layer "F.Fab")
		)
		(fp_line
			(start -37.274754 16.550386)
			(end -37.279072 16.557752)
			(stroke
				(width 0.1)
				(type default)
			)
			(layer "F.Fab")
		)
		(fp_line
			(start -37.275516 15.448534)
			(end -37.271706 15.45463)
			(stroke
				(width 0.1)
				(type default)
			)
			(layer "F.Fab")
		)
		(fp_line
			(start -37.278564 15.4432)
			(end -37.275516 15.448534)
			(stroke
				(width 0.1)
				(type default)
			)
			(layer "F.Fab")
		)
		(fp_line
			(start -37.279072 16.557752)
			(end -37.283644 16.565372)
			(stroke
				(width 0.1)
				(type default)
			)
			(layer "F.Fab")
		)
		(fp_line
			(start -37.281358 15.438628)
			(end -37.278564 15.4432)
			(stroke
				(width 0.1)
				(type default)
			)
			(layer "F.Fab")
		)
		(fp_line
			(start -37.283644 16.565372)
			(end -37.286692 16.570198)
			(stroke
				(width 0.1)
				(type default)
			)
			(layer "F.Fab")
		)
		(fp_line
			(start -37.28466 15.43304)
			(end -37.281358 15.438628)
			(stroke
				(width 0.1)
				(type default)
			)
			(layer "F.Fab")
		)
		(fp_line
			(start -37.286184 15.4305)
			(end -37.28466 15.43304)
			(stroke
				(width 0.1)
				(type default)
			)
			(layer "F.Fab")
		)
		(fp_line
			(start -37.286692 16.570198)
			(end -37.289994 16.575532)
			(stroke
				(width 0.1)
				(type default)
			)
			(layer "F.Fab")
		)
		(fp_line
			(start -37.289994 16.575532)
			(end -37.292788 16.580104)
			(stroke
				(width 0.1)
				(type default)
			)
			(layer "F.Fab")
		)
		(fp_line
			(start -37.290756 15.423388)
			(end -37.286184 15.4305)
			(stroke
				(width 0.1)
				(type default)
			)
			(layer "F.Fab")
		)
		(fp_line
			(start -37.292788 16.580104)
			(end -37.295328 16.584168)
			(stroke
				(width 0.1)
				(type default)
			)
			(layer "F.Fab")
		)
		(fp_line
			(start -37.293296 15.419578)
			(end -37.290756 15.423388)
			(stroke
				(width 0.1)
				(type default)
			)
			(layer "F.Fab")
		)
		(fp_line
			(start -37.295328 16.584168)
			(end -37.300154 16.59128)
			(stroke
				(width 0.1)
				(type default)
			)
			(layer "F.Fab")
		)
		(fp_line
			(start -37.296598 15.41399)
			(end -37.293296 15.419578)
			(stroke
				(width 0.1)
				(type default)
			)
			(layer "F.Fab")
		)
		(fp_line
			(start -37.300154 16.59128)
			(end -37.304726 16.598138)
			(stroke
				(width 0.1)
				(type default)
			)
			(layer "F.Fab")
		)
		(fp_line
			(start -37.300662 15.407894)
			(end -37.296598 15.41399)
			(stroke
				(width 0.1)
				(type default)
			)
			(layer "F.Fab")
		)
		(fp_line
			(start -37.30371 15.403322)
			(end -37.300662 15.407894)
			(stroke
				(width 0.1)
				(type default)
			)
			(layer "F.Fab")
		)
		(fp_line
			(start -37.304726 16.598138)
			(end -37.309298 16.604996)
			(stroke
				(width 0.1)
				(type default)
			)
			(layer "F.Fab")
		)
		(fp_line
			(start -37.307012 15.397988)
			(end -37.30371 15.403322)
			(stroke
				(width 0.1)
				(type default)
			)
			(layer "F.Fab")
		)
		(fp_line
			(start -37.309298 16.604996)
			(end -37.314124 16.612108)
			(stroke
				(width 0.1)
				(type default)
			)
			(layer "F.Fab")
		)
		(fp_line
			(start -37.311076 15.3924)
			(end -37.307012 15.397988)
			(stroke
				(width 0.1)
				(type default)
			)
			(layer "F.Fab")
		)
		(fp_line
			(start -37.314124 16.612108)
			(end -37.317934 16.617696)
			(stroke
				(width 0.1)
				(type default)
			)
			(layer "F.Fab")
		)
		(fp_line
			(start -37.315394 15.38605)
			(end -37.311076 15.3924)
			(stroke
				(width 0.1)
				(type default)
			)
			(layer "F.Fab")
		)
		(fp_line
			(start -37.317934 16.617696)
			(end -37.324284 16.62684)
			(stroke
				(width 0.1)
				(type default)
			)
			(layer "F.Fab")
		)
		(fp_line
			(start -37.31895 15.380716)
			(end -37.315394 15.38605)
			(stroke
				(width 0.1)
				(type default)
			)
			(layer "F.Fab")
		)
		(fp_line
			(start -37.324284 16.62684)
			(end -37.330888 16.635984)
			(stroke
				(width 0.1)
				(type default)
			)
			(layer "F.Fab")
		)
		(fp_line
			(start -37.330888 16.635984)
			(end -37.33927 16.647414)
			(stroke
				(width 0.1)
				(type default)
			)
			(layer "F.Fab")
		)
		(fp_line
			(start -37.332158 15.362174)
			(end -37.31895 15.380716)
			(stroke
				(width 0.1)
				(type default)
			)
			(layer "F.Fab")
		)
		(fp_line
			(start -37.333174 15.36065)
			(end -37.332158 15.362174)
			(stroke
				(width 0.1)
				(type default)
			)
			(layer "F.Fab")
		)
		(fp_line
			(start -37.336984 15.355316)
			(end -37.333174 15.36065)
			(stroke
				(width 0.1)
				(type default)
			)
			(layer "F.Fab")
		)
		(fp_line
			(start -37.33927 16.647414)
			(end -37.350446 16.6624)
			(stroke
				(width 0.1)
				(type default)
			)
			(layer "F.Fab")
		)
		(fp_line
			(start -37.34181 15.34922)
			(end -37.336984 15.355316)
			(stroke
				(width 0.1)
				(type default)
			)
			(layer "F.Fab")
		)
		(fp_line
			(start -37.34562 15.34414)
			(end -37.34181 15.34922)
			(stroke
				(width 0.1)
				(type default)
			)
			(layer "F.Fab")
		)
		(fp_line
			(start -37.349684 15.338806)
			(end -37.34562 15.34414)
			(stroke
				(width 0.1)
				(type default)
			)
			(layer "F.Fab")
		)
		(fp_line
			(start -37.350446 16.6624)
			(end -37.353494 16.66621)
			(stroke
				(width 0.1)
				(type default)
			)
			(layer "F.Fab")
		)
		(fp_line
			(start -37.353494 16.66621)
			(end -37.358828 16.673068)
			(stroke
				(width 0.1)
				(type default)
			)
			(layer "F.Fab")
		)
		(fp_line
			(start -37.353748 15.333472)
			(end -37.349684 15.338806)
			(stroke
				(width 0.1)
				(type default)
			)
			(layer "F.Fab")
		)
		(fp_line
			(start -37.357812 15.328138)
			(end -37.353748 15.333472)
			(stroke
				(width 0.1)
				(type default)
			)
			(layer "F.Fab")
		)
		(fp_line
			(start -37.358828 16.673068)
			(end -37.362384 16.677386)
			(stroke
				(width 0.1)
				(type default)
			)
			(layer "F.Fab")
		)
		(fp_line
			(start -37.362384 16.677386)
			(end -37.36848 16.68526)
			(stroke
				(width 0.1)
				(type default)
			)
			(layer "F.Fab")
		)
		(fp_line
			(start -37.36848 16.68526)
			(end -37.374576 16.692626)
			(stroke
				(width 0.1)
				(type default)
			)
			(layer "F.Fab")
		)
		(fp_line
			(start -37.374576 16.692626)
			(end -37.383974 16.703802)
			(stroke
				(width 0.1)
				(type default)
			)
			(layer "F.Fab")
		)
		(fp_line
			(start -37.383974 16.703802)
			(end -37.39261 16.713708)
			(stroke
				(width 0.1)
				(type default)
			)
			(layer "F.Fab")
		)
		(fp_line
			(start -37.39261 16.713708)
			(end -37.4015 16.723868)
			(stroke
				(width 0.1)
				(type default)
			)
			(layer "F.Fab")
		)
		(fp_line
			(start -37.39642 15.281402)
			(end -37.357812 15.328138)
			(stroke
				(width 0.1)
				(type default)
			)
			(layer "F.Fab")
		)
		(fp_line
			(start -37.399214 15.278608)
			(end -37.39642 15.281402)
			(stroke
				(width 0.1)
				(type default)
			)
			(layer "F.Fab")
		)
		(fp_line
			(start -37.4015 16.723868)
			(end -37.41039 16.73352)
			(stroke
				(width 0.1)
				(type default)
			)
			(layer "F.Fab")
		)
		(fp_line
			(start -37.40531 15.271496)
			(end -37.399214 15.278608)
			(stroke
				(width 0.1)
				(type default)
			)
			(layer "F.Fab")
		)
		(fp_line
			(start -37.410136 15.266416)
			(end -37.40531 15.271496)
			(stroke
				(width 0.1)
				(type default)
			)
			(layer "F.Fab")
		)
		(fp_line
			(start -37.41039 16.73352)
			(end -37.419534 16.743426)
			(stroke
				(width 0.1)
				(type default)
			)
			(layer "F.Fab")
		)
		(fp_line
			(start -37.419534 16.743426)
			(end -37.427916 16.752062)
			(stroke
				(width 0.1)
				(type default)
			)
			(layer "F.Fab")
		)
		(fp_line
			(start -37.427916 16.752062)
			(end -37.430456 16.754602)
			(stroke
				(width 0.1)
				(type default)
			)
			(layer "F.Fab")
		)
		(fp_line
			(start -37.430456 16.754602)
			(end -37.434012 16.758412)
			(stroke
				(width 0.1)
				(type default)
			)
			(layer "F.Fab")
		)
		(fp_line
			(start -37.434012 16.758412)
			(end -37.444426 16.76908)
			(stroke
				(width 0.1)
				(type default)
			)
			(layer "F.Fab")
		)
		(fp_line
			(start -37.444426 16.76908)
			(end -37.451284 16.775684)
			(stroke
				(width 0.1)
				(type default)
			)
			(layer "F.Fab")
		)
		(fp_line
			(start -37.451284 16.775684)
			(end -37.457888 16.782034)
			(stroke
				(width 0.1)
				(type default)
			)
			(layer "F.Fab")
		)
		(fp_line
			(start -37.457888 16.782034)
			(end -37.466016 16.789908)
			(stroke
				(width 0.1)
				(type default)
			)
			(layer "F.Fab")
		)
		(fp_line
			(start -37.459412 15.21587)
			(end -37.410136 15.266416)
			(stroke
				(width 0.1)
				(type default)
			)
			(layer "F.Fab")
		)
		(fp_line
			(start -37.460682 15.2146)
			(end -37.459412 15.21587)
			(stroke
				(width 0.1)
				(type default)
			)
			(layer "F.Fab")
		)
		(fp_line
			(start -37.464492 15.211298)
			(end -37.460682 15.2146)
			(stroke
				(width 0.1)
				(type default)
			)
			(layer "F.Fab")
		)
		(fp_line
			(start -37.466016 16.789908)
			(end -37.472366 16.79575)
			(stroke
				(width 0.1)
				(type default)
			)
			(layer "F.Fab")
		)
		(fp_line
			(start -37.469826 15.206218)
			(end -37.464492 15.211298)
			(stroke
				(width 0.1)
				(type default)
			)
			(layer "F.Fab")
		)
		(fp_line
			(start -37.472366 16.79575)
			(end -37.479224 16.8021)
			(stroke
				(width 0.1)
				(type default)
			)
			(layer "F.Fab")
		)
		(fp_line
			(start -37.474652 15.201646)
			(end -37.469826 15.206218)
			(stroke
				(width 0.1)
				(type default)
			)
			(layer "F.Fab")
		)
		(fp_line
			(start -37.479224 16.8021)
			(end -37.488114 16.809974)
			(stroke
				(width 0.1)
				(type default)
			)
			(layer "F.Fab")
		)
		(fp_line
			(start -37.479478 15.197328)
			(end -37.474652 15.201646)
			(stroke
				(width 0.1)
				(type default)
			)
			(layer "F.Fab")
		)
		(fp_line
			(start -37.484304 15.19301)
			(end -37.479478 15.197328)
			(stroke
				(width 0.1)
				(type default)
			)
			(layer "F.Fab")
		)
		(fp_line
			(start -37.488114 16.809974)
			(end -37.492686 16.814038)
			(stroke
				(width 0.1)
				(type default)
			)
			(layer "F.Fab")
		)
		(fp_line
			(start -37.48913 15.188692)
			(end -37.484304 15.19301)
			(stroke
				(width 0.1)
				(type default)
			)
			(layer "F.Fab")
		)
		(fp_line
			(start -37.492432 15.185644)
			(end -37.48913 15.188692)
			(stroke
				(width 0.1)
				(type default)
			)
			(layer "F.Fab")
		)
		(fp_line
			(start -37.492686 16.814038)
			(end -37.49675 16.817594)
			(stroke
				(width 0.1)
				(type default)
			)
			(layer "F.Fab")
		)
		(fp_line
			(start -37.496242 15.182342)
			(end -37.492432 15.185644)
			(stroke
				(width 0.1)
				(type default)
			)
			(layer "F.Fab")
		)
		(fp_line
			(start -37.49675 16.817594)
			(end -37.502592 16.822674)
			(stroke
				(width 0.1)
				(type default)
			)
			(layer "F.Fab")
		)
		(fp_line
			(start -37.500306 15.178786)
			(end -37.496242 15.182342)
			(stroke
				(width 0.1)
				(type default)
			)
			(layer "F.Fab")
		)
		(fp_line
			(start -37.502592 16.822674)
			(end -37.511228 16.83004)
			(stroke
				(width 0.1)
				(type default)
			)
			(layer "F.Fab")
		)
		(fp_line
			(start -37.5031 15.1765)
			(end -37.500306 15.178786)
			(stroke
				(width 0.1)
				(type default)
			)
			(layer "F.Fab")
		)
		(fp_line
			(start -37.505386 15.174722)
			(end -37.5031 15.1765)
			(stroke
				(width 0.1)
				(type default)
			)
			(layer "F.Fab")
		)
		(fp_line
			(start -37.509704 15.170912)
			(end -37.505386 15.174722)
			(stroke
				(width 0.1)
				(type default)
			)
			(layer "F.Fab")
		)
		(fp_line
			(start -37.511228 16.83004)
			(end -37.516308 16.834104)
			(stroke
				(width 0.1)
				(type default)
			)
			(layer "F.Fab")
		)
		(fp_line
			(start -37.513514 15.16761)
			(end -37.509704 15.170912)
			(stroke
				(width 0.1)
				(type default)
			)
			(layer "F.Fab")
		)
		(fp_line
			(start -37.516308 16.834104)
			(end -37.520118 16.837406)
			(stroke
				(width 0.1)
				(type default)
			)
			(layer "F.Fab")
		)
		(fp_line
			(start -37.51707 15.164816)
			(end -37.513514 15.16761)
			(stroke
				(width 0.1)
				(type default)
			)
			(layer "F.Fab")
		)
		(fp_line
			(start -37.520118 16.837406)
			(end -37.525706 16.841978)
			(stroke
				(width 0.1)
				(type default)
			)
			(layer "F.Fab")
		)
		(fp_line
			(start -37.522404 15.160498)
			(end -37.51707 15.164816)
			(stroke
				(width 0.1)
				(type default)
			)
			(layer "F.Fab")
		)
		(fp_line
			(start -37.525706 16.841978)
			(end -37.531294 16.84655)
			(stroke
				(width 0.1)
				(type default)
			)
			(layer "F.Fab")
		)
		(fp_line
			(start -37.5285 15.155418)
			(end -37.522404 15.160498)
			(stroke
				(width 0.1)
				(type default)
			)
			(layer "F.Fab")
		)
		(fp_line
			(start -37.531294 16.84655)
			(end -37.536628 16.850868)
			(stroke
				(width 0.1)
				(type default)
			)
			(layer "F.Fab")
		)
		(fp_line
			(start -37.532056 15.152624)
			(end -37.5285 15.155418)
			(stroke
				(width 0.1)
				(type default)
			)
			(layer "F.Fab")
		)
		(fp_line
			(start -37.536374 15.149068)
			(end -37.532056 15.152624)
			(stroke
				(width 0.1)
				(type default)
			)
			(layer "F.Fab")
		)
		(fp_line
			(start -37.536628 16.850868)
			(end -37.540184 16.853408)
			(stroke
				(width 0.1)
				(type default)
			)
			(layer "F.Fab")
		)
		(fp_line
			(start -37.540184 16.853408)
			(end -37.543232 16.855948)
			(stroke
				(width 0.1)
				(type default)
			)
			(layer "F.Fab")
		)
		(fp_line
			(start -37.540184 15.14602)
			(end -37.536374 15.149068)
			(stroke
				(width 0.1)
				(type default)
			)
			(layer "F.Fab")
		)
		(fp_line
			(start -37.543232 16.855948)
			(end -37.547296 16.858996)
			(stroke
				(width 0.1)
				(type default)
			)
			(layer "F.Fab")
		)
		(fp_line
			(start -37.545772 15.141702)
			(end -37.540184 15.14602)
			(stroke
				(width 0.1)
				(type default)
			)
			(layer "F.Fab")
		)
		(fp_line
			(start -37.547296 16.858996)
			(end -37.551106 16.862044)
			(stroke
				(width 0.1)
				(type default)
			)
			(layer "F.Fab")
		)
		(fp_line
			(start -37.551106 16.862044)
			(end -37.554408 16.864584)
			(stroke
				(width 0.1)
				(type default)
			)
			(layer "F.Fab")
		)
		(fp_line
			(start -37.551106 15.137638)
			(end -37.545772 15.141702)
			(stroke
				(width 0.1)
				(type default)
			)
			(layer "F.Fab")
		)
		(fp_line
			(start -37.554408 16.864584)
			(end -37.559742 16.868648)
			(stroke
				(width 0.1)
				(type default)
			)
			(layer "F.Fab")
		)
		(fp_line
			(start -37.556948 15.13332)
			(end -37.551106 15.137638)
			(stroke
				(width 0.1)
				(type default)
			)
			(layer "F.Fab")
		)
		(fp_line
			(start -37.559742 16.868648)
			(end -37.564822 16.872204)
			(stroke
				(width 0.1)
				(type default)
			)
			(layer "F.Fab")
		)
		(fp_line
			(start -37.561774 15.12951)
			(end -37.556948 15.13332)
			(stroke
				(width 0.1)
				(type default)
			)
			(layer "F.Fab")
		)
		(fp_line
			(start -37.564822 16.872204)
			(end -37.568886 16.875506)
			(stroke
				(width 0.1)
				(type default)
			)
			(layer "F.Fab")
		)
		(fp_line
			(start -37.568886 16.875506)
			(end -37.574728 16.87957)
			(stroke
				(width 0.1)
				(type default)
			)
			(layer "F.Fab")
		)
		(fp_line
			(start -37.57041 15.12316)
			(end -37.561774 15.12951)
			(stroke
				(width 0.1)
				(type default)
			)
			(layer "F.Fab")
		)
		(fp_line
			(start -37.574728 16.87957)
			(end -37.581586 16.884396)
			(stroke
				(width 0.1)
				(type default)
			)
			(layer "F.Fab")
		)
		(fp_line
			(start -37.574982 15.119858)
			(end -37.57041 15.12316)
			(stroke
				(width 0.1)
				(type default)
			)
			(layer "F.Fab")
		)
		(fp_line
			(start -37.581586 16.884396)
			(end -37.586666 16.887952)
			(stroke
				(width 0.1)
				(type default)
			)
			(layer "F.Fab")
		)
		(fp_line
			(start -37.582602 15.114524)
			(end -37.574982 15.119858)
			(stroke
				(width 0.1)
				(type default)
			)
			(layer "F.Fab")
		)
		(fp_line
			(start -37.586666 16.887952)
			(end -37.592 16.891762)
			(stroke
				(width 0.1)
				(type default)
			)
			(layer "F.Fab")
		)
		(fp_line
			(start -37.588444 15.11046)
			(end -37.582602 15.114524)
			(stroke
				(width 0.1)
				(type default)
			)
			(layer "F.Fab")
		)
		(fp_line
			(start -37.592 16.891762)
			(end -37.598604 16.89608)
			(stroke
				(width 0.1)
				(type default)
			)
			(layer "F.Fab")
		)
		(fp_line
			(start -37.594794 15.106142)
			(end -37.588444 15.11046)
			(stroke
				(width 0.1)
				(type default)
			)
			(layer "F.Fab")
		)
		(fp_line
			(start -37.597842 15.10411)
			(end -37.594794 15.106142)
			(stroke
				(width 0.1)
				(type default)
			)
			(layer "F.Fab")
		)
		(fp_line
			(start -37.598604 16.89608)
			(end -37.610542 16.904208)
			(stroke
				(width 0.1)
				(type default)
			)
			(layer "F.Fab")
		)
		(fp_line
			(start -37.600636 15.102078)
			(end -37.597842 15.10411)
			(stroke
				(width 0.1)
				(type default)
			)
			(layer "F.Fab")
		)
		(fp_line
			(start -37.607748 15.097252)
			(end -37.600636 15.102078)
			(stroke
				(width 0.1)
				(type default)
			)
			(layer "F.Fab")
		)
		(fp_line
			(start -37.610542 16.904208)
			(end -37.615368 16.90751)
			(stroke
				(width 0.1)
				(type default)
			)
			(layer "F.Fab")
		)
		(fp_line
			(start -37.61105 15.09522)
			(end -37.607748 15.097252)
			(stroke
				(width 0.1)
				(type default)
			)
			(layer "F.Fab")
		)
		(fp_line
			(start -37.615368 16.90751)
			(end -37.619178 16.909796)
			(stroke
				(width 0.1)
				(type default)
			)
			(layer "F.Fab")
		)
		(fp_line
			(start -37.619178 16.909796)
			(end -37.624258 16.913098)
			(stroke
				(width 0.1)
				(type default)
			)
			(layer "F.Fab")
		)
		(fp_line
			(start -37.619178 15.089632)
			(end -37.61105 15.09522)
			(stroke
				(width 0.1)
				(type default)
			)
			(layer "F.Fab")
		)
		(fp_line
			(start -37.624258 16.913098)
			(end -37.628576 16.915892)
			(stroke
				(width 0.1)
				(type default)
			)
			(layer "F.Fab")
		)
		(fp_line
			(start -37.626544 15.08506)
			(end -37.619178 15.089632)
			(stroke
				(width 0.1)
				(type default)
			)
			(layer "F.Fab")
		)
		(fp_line
			(start -37.628576 16.915892)
			(end -37.634926 16.919956)
			(stroke
				(width 0.1)
				(type default)
			)
			(layer "F.Fab")
		)
		(fp_line
			(start -37.630608 15.08252)
			(end -37.626544 15.08506)
			(stroke
				(width 0.1)
				(type default)
			)
			(layer "F.Fab")
		)
		(fp_line
			(start -37.634926 16.919956)
			(end -37.6428 16.924782)
			(stroke
				(width 0.1)
				(type default)
			)
			(layer "F.Fab")
		)
		(fp_line
			(start -37.635434 15.079472)
			(end -37.630608 15.08252)
			(stroke
				(width 0.1)
				(type default)
			)
			(layer "F.Fab")
		)
		(fp_line
			(start -37.640006 15.076678)
			(end -37.635434 15.079472)
			(stroke
				(width 0.1)
				(type default)
			)
			(layer "F.Fab")
		)
		(fp_line
			(start -37.642292 15.075154)
			(end -37.640006 15.076678)
			(stroke
				(width 0.1)
				(type default)
			)
			(layer "F.Fab")
		)
		(fp_line
			(start -37.6428 16.924782)
			(end -37.647118 16.927576)
			(stroke
				(width 0.1)
				(type default)
			)
			(layer "F.Fab")
		)
		(fp_line
			(start -37.64534 15.073376)
			(end -37.642292 15.075154)
			(stroke
				(width 0.1)
				(type default)
			)
			(layer "F.Fab")
		)
		(fp_line
			(start -37.647118 16.927576)
			(end -37.653214 16.931132)
			(stroke
				(width 0.1)
				(type default)
			)
			(layer "F.Fab")
		)
		(fp_line
			(start -37.648134 15.071598)
			(end -37.64534 15.073376)
			(stroke
				(width 0.1)
				(type default)
			)
			(layer "F.Fab")
		)
		(fp_line
			(start -37.651944 15.069312)
			(end -37.648134 15.071598)
			(stroke
				(width 0.1)
				(type default)
			)
			(layer "F.Fab")
		)
		(fp_line
			(start -37.653214 16.931132)
			(end -37.658802 16.934434)
			(stroke
				(width 0.1)
				(type default)
			)
			(layer "F.Fab")
		)
		(fp_line
			(start -37.657024 15.066264)
			(end -37.651944 15.069312)
			(stroke
				(width 0.1)
				(type default)
			)
			(layer "F.Fab")
		)
		(fp_line
			(start -37.658802 16.934434)
			(end -37.665406 16.938498)
			(stroke
				(width 0.1)
				(type default)
			)
			(layer "F.Fab")
		)
		(fp_line
			(start -37.661596 15.063724)
			(end -37.657024 15.066264)
			(stroke
				(width 0.1)
				(type default)
			)
			(layer "F.Fab")
		)
		(fp_line
			(start -37.665406 16.938498)
			(end -37.67455 16.943578)
			(stroke
				(width 0.1)
				(type default)
			)
			(layer "F.Fab")
		)
		(fp_line
			(start -37.665406 15.061438)
			(end -37.661596 15.063724)
			(stroke
				(width 0.1)
				(type default)
			)
			(layer "F.Fab")
		)
		(fp_line
			(start -37.673026 15.05712)
			(end -37.665406 15.061438)
			(stroke
				(width 0.1)
				(type default)
			)
			(layer "F.Fab")
		)
		(fp_line
			(start -37.67455 16.943578)
			(end -37.679376 16.946372)
			(stroke
				(width 0.1)
				(type default)
			)
			(layer "F.Fab")
		)
		(fp_line
			(start -37.677344 15.05458)
			(end -37.673026 15.05712)
			(stroke
				(width 0.1)
				(type default)
			)
			(layer "F.Fab")
		)
		(fp_line
			(start -37.679376 16.946372)
			(end -37.687758 16.950944)
			(stroke
				(width 0.1)
				(type default)
			)
			(layer "F.Fab")
		)
		(fp_line
			(start -37.681662 15.052294)
			(end -37.677344 15.05458)
			(stroke
				(width 0.1)
				(type default)
			)
			(layer "F.Fab")
		)
		(fp_line
			(start -37.687758 16.950944)
			(end -37.692584 16.953484)
			(stroke
				(width 0.1)
				(type default)
			)
			(layer "F.Fab")
		)
		(fp_line
			(start -37.688774 15.04823)
			(end -37.681662 15.052294)
			(stroke
				(width 0.1)
				(type default)
			)
			(layer "F.Fab")
		)
		(fp_line
			(start -37.692584 16.953484)
			(end -37.69741 16.956278)
			(stroke
				(width 0.1)
				(type default)
			)
			(layer "F.Fab")
		)
		(fp_line
			(start -37.69741 16.956278)
			(end -37.701474 16.95831)
			(stroke
				(width 0.1)
				(type default)
			)
			(layer "F.Fab")
		)
		(fp_line
			(start -37.701474 16.95831)
			(end -37.705284 16.960342)
			(stroke
				(width 0.1)
				(type default)
			)
			(layer "F.Fab")
		)
		(fp_line
			(start -37.705284 16.960342)
			(end -37.710364 16.962882)
			(stroke
				(width 0.1)
				(type default)
			)
			(layer "F.Fab")
		)
		(fp_line
			(start -37.707824 15.038324)
			(end -37.688774 15.04823)
			(stroke
				(width 0.1)
				(type default)
			)
			(layer "F.Fab")
		)
		(fp_line
			(start -37.710364 16.962882)
			(end -37.717222 16.966438)
			(stroke
				(width 0.1)
				(type default)
			)
			(layer "F.Fab")
		)
		(fp_line
			(start -37.713412 15.035276)
			(end -37.707824 15.038324)
			(stroke
				(width 0.1)
				(type default)
			)
			(layer "F.Fab")
		)
		(fp_line
			(start -37.717222 16.966438)
			(end -37.72789 16.972026)
			(stroke
				(width 0.1)
				(type default)
			)
			(layer "F.Fab")
		)
		(fp_line
			(start -37.721286 15.031212)
			(end -37.713412 15.035276)
			(stroke
				(width 0.1)
				(type default)
			)
			(layer "F.Fab")
		)
		(fp_line
			(start -37.72789 16.972026)
			(end -37.732208 16.974058)
			(stroke
				(width 0.1)
				(type default)
			)
			(layer "F.Fab")
		)
		(fp_line
			(start -37.728906 15.027402)
			(end -37.721286 15.031212)
			(stroke
				(width 0.1)
				(type default)
			)
			(layer "F.Fab")
		)
		(fp_line
			(start -37.732208 16.974058)
			(end -37.738304 16.976852)
			(stroke
				(width 0.1)
				(type default)
			)
			(layer "F.Fab")
		)
		(fp_line
			(start -37.733986 15.024862)
			(end -37.728906 15.027402)
			(stroke
				(width 0.1)
				(type default)
			)
			(layer "F.Fab")
		)
		(fp_line
			(start -37.738304 16.976852)
			(end -37.742876 16.979138)
			(stroke
				(width 0.1)
				(type default)
			)
			(layer "F.Fab")
		)
		(fp_line
			(start -37.739574 15.022322)
			(end -37.733986 15.024862)
			(stroke
				(width 0.1)
				(type default)
			)
			(layer "F.Fab")
		)
		(fp_line
			(start -37.742876 16.979138)
			(end -37.74821 16.981678)
			(stroke
				(width 0.1)
				(type default)
			)
			(layer "F.Fab")
		)
		(fp_line
			(start -37.74567 15.019274)
			(end -37.739574 15.022322)
			(stroke
				(width 0.1)
				(type default)
			)
			(layer "F.Fab")
		)
		(fp_line
			(start -37.74821 16.981678)
			(end -37.753036 16.983964)
			(stroke
				(width 0.1)
				(type default)
			)
			(layer "F.Fab")
		)
		(fp_line
			(start -37.74948 15.017496)
			(end -37.74567 15.019274)
			(stroke
				(width 0.1)
				(type default)
			)
			(layer "F.Fab")
		)
		(fp_line
			(start -37.753036 16.983964)
			(end -37.756084 16.985488)
			(stroke
				(width 0.1)
				(type default)
			)
			(layer "F.Fab")
		)
		(fp_line
			(start -37.753798 15.015718)
			(end -37.74948 15.017496)
			(stroke
				(width 0.1)
				(type default)
			)
			(layer "F.Fab")
		)
		(fp_line
			(start -37.756084 16.985488)
			(end -37.765228 16.989552)
			(stroke
				(width 0.1)
				(type default)
			)
			(layer "F.Fab")
		)
		(fp_line
			(start -37.759894 15.01267)
			(end -37.753798 15.015718)
			(stroke
				(width 0.1)
				(type default)
			)
			(layer "F.Fab")
		)
		(fp_line
			(start -37.763196 15.0114)
			(end -37.759894 15.01267)
			(stroke
				(width 0.1)
				(type default)
			)
			(layer "F.Fab")
		)
		(fp_line
			(start -37.765228 16.989552)
			(end -37.768784 16.991076)
			(stroke
				(width 0.1)
				(type default)
			)
			(layer "F.Fab")
		)
		(fp_line
			(start -37.767006 15.009622)
			(end -37.763196 15.0114)
			(stroke
				(width 0.1)
				(type default)
			)
			(layer "F.Fab")
		)
		(fp_line
			(start -37.768784 16.991076)
			(end -37.773102 16.993108)
			(stroke
				(width 0.1)
				(type default)
			)
			(layer "F.Fab")
		)
		(fp_line
			(start -37.773102 16.993108)
			(end -37.777674 16.994886)
			(stroke
				(width 0.1)
				(type default)
			)
			(layer "F.Fab")
		)
		(fp_line
			(start -37.773102 15.006828)
			(end -37.767006 15.009622)
			(stroke
				(width 0.1)
				(type default)
			)
			(layer "F.Fab")
		)
		(fp_line
			(start -37.777674 16.994886)
			(end -37.78758 16.999204)
			(stroke
				(width 0.1)
				(type default)
			)
			(layer "F.Fab")
		)
		(fp_line
			(start -37.777674 15.004796)
			(end -37.773102 15.006828)
			(stroke
				(width 0.1)
				(type default)
			)
			(layer "F.Fab")
		)
		(fp_line
			(start -37.782754 15.002764)
			(end -37.777674 15.004796)
			(stroke
				(width 0.1)
				(type default)
			)
			(layer "F.Fab")
		)
		(fp_line
			(start -37.78758 16.999204)
			(end -37.804852 17.006316)
			(stroke
				(width 0.1)
				(type default)
			)
			(layer "F.Fab")
		)
		(fp_line
			(start -37.788088 15.000478)
			(end -37.782754 15.002764)
			(stroke
				(width 0.1)
				(type default)
			)
			(layer "F.Fab")
		)
		(fp_line
			(start -37.79647 14.996922)
			(end -37.788088 15.000478)
			(stroke
				(width 0.1)
				(type default)
			)
			(layer "F.Fab")
		)
		(fp_line
			(start -37.804852 17.006316)
			(end -37.819838 17.012158)
			(stroke
				(width 0.1)
				(type default)
			)
			(layer "F.Fab")
		)
		(fp_line
			(start -37.812218 14.990572)
			(end -37.79647 14.996922)
			(stroke
				(width 0.1)
				(type default)
			)
			(layer "F.Fab")
		)
		(fp_line
			(start -37.819838 17.012158)
			(end -37.828982 17.015714)
			(stroke
				(width 0.1)
				(type default)
			)
			(layer "F.Fab")
		)
		(fp_line
			(start -37.828982 17.015714)
			(end -37.836856 17.018508)
			(stroke
				(width 0.1)
				(type default)
			)
			(layer "F.Fab")
		)
		(fp_line
			(start -37.829998 14.983714)
			(end -37.812218 14.990572)
			(stroke
				(width 0.1)
				(type default)
			)
			(layer "F.Fab")
		)
		(fp_line
			(start -37.834824 14.98219)
			(end -37.829998 14.983714)
			(stroke
				(width 0.1)
				(type default)
			)
			(layer "F.Fab")
		)
		(fp_line
			(start -37.836348 14.981428)
			(end -37.834824 14.98219)
			(stroke
				(width 0.1)
				(type default)
			)
			(layer "F.Fab")
		)
		(fp_line
			(start -37.836856 17.018508)
			(end -37.841682 17.020286)
			(stroke
				(width 0.1)
				(type default)
			)
			(layer "F.Fab")
		)
		(fp_line
			(start -37.839904 14.980158)
			(end -37.836348 14.981428)
			(stroke
				(width 0.1)
				(type default)
			)
			(layer "F.Fab")
		)
		(fp_line
			(start -37.841682 17.020286)
			(end -37.84981 17.023334)
			(stroke
				(width 0.1)
				(type default)
			)
			(layer "F.Fab")
		)
		(fp_line
			(start -37.843206 14.978888)
			(end -37.839904 14.980158)
			(stroke
				(width 0.1)
				(type default)
			)
			(layer "F.Fab")
		)
		(fp_line
			(start -37.847778 14.977364)
			(end -37.843206 14.978888)
			(stroke
				(width 0.1)
				(type default)
			)
			(layer "F.Fab")
		)
		(fp_line
			(start -37.84981 17.023334)
			(end -37.857176 17.025874)
			(stroke
				(width 0.1)
				(type default)
			)
			(layer "F.Fab")
		)
		(fp_line
			(start -37.851334 14.976094)
			(end -37.847778 14.977364)
			(stroke
				(width 0.1)
				(type default)
			)
			(layer "F.Fab")
		)
		(fp_line
			(start -37.856414 14.974316)
			(end -37.851334 14.976094)
			(stroke
				(width 0.1)
				(type default)
			)
			(layer "F.Fab")
		)
		(fp_line
			(start -37.857176 17.025874)
			(end -37.864542 17.028414)
			(stroke
				(width 0.1)
				(type default)
			)
			(layer "F.Fab")
		)
		(fp_line
			(start -37.861748 14.972538)
			(end -37.856414 14.974316)
			(stroke
				(width 0.1)
				(type default)
			)
			(layer "F.Fab")
		)
		(fp_line
			(start -37.864542 17.028414)
			(end -37.875718 17.03197)
			(stroke
				(width 0.1)
				(type default)
			)
			(layer "F.Fab")
		)
		(fp_line
			(start -37.86632 14.971014)
			(end -37.861748 14.972538)
			(stroke
				(width 0.1)
				(type default)
			)
			(layer "F.Fab")
		)
		(fp_line
			(start -37.871146 14.96949)
			(end -37.86632 14.971014)
			(stroke
				(width 0.1)
				(type default)
			)
			(layer "F.Fab")
		)
		(fp_line
			(start -37.874702 14.96822)
			(end -37.871146 14.96949)
			(stroke
				(width 0.1)
				(type default)
			)
			(layer "F.Fab")
		)
		(fp_line
			(start -37.875718 17.03197)
			(end -37.881306 17.033748)
			(stroke
				(width 0.1)
				(type default)
			)
			(layer "F.Fab")
		)
		(fp_line
			(start -37.878258 14.967204)
			(end -37.874702 14.96822)
			(stroke
				(width 0.1)
				(type default)
			)
			(layer "F.Fab")
		)
		(fp_line
			(start -37.881052 14.966188)
			(end -37.878258 14.967204)
			(stroke
				(width 0.1)
				(type default)
			)
			(layer "F.Fab")
		)
		(fp_line
			(start -37.881306 17.033748)
			(end -37.88791 17.03578)
			(stroke
				(width 0.1)
				(type default)
			)
			(layer "F.Fab")
		)
		(fp_line
			(start -37.886894 14.96441)
			(end -37.881052 14.966188)
			(stroke
				(width 0.1)
				(type default)
			)
			(layer "F.Fab")
		)
		(fp_line
			(start -37.88791 17.03578)
			(end -37.894514 17.037812)
			(stroke
				(width 0.1)
				(type default)
			)
			(layer "F.Fab")
		)
		(fp_line
			(start -37.889942 14.963394)
			(end -37.886894 14.96441)
			(stroke
				(width 0.1)
				(type default)
			)
			(layer "F.Fab")
		)
		(fp_line
			(start -37.894514 17.037812)
			(end -37.90061 17.03959)
			(stroke
				(width 0.1)
				(type default)
			)
			(layer "F.Fab")
		)
		(fp_line
			(start -37.895022 14.96187)
			(end -37.889942 14.963394)
			(stroke
				(width 0.1)
				(type default)
			)
			(layer "F.Fab")
		)
		(fp_line
			(start -37.90061 17.03959)
			(end -37.905436 17.041114)
			(stroke
				(width 0.1)
				(type default)
			)
			(layer "F.Fab")
		)
		(fp_line
			(start -37.903404 14.95933)
			(end -37.895022 14.96187)
			(stroke
				(width 0.1)
				(type default)
			)
			(layer "F.Fab")
		)
		(fp_line
			(start -37.905436 17.041114)
			(end -37.910008 17.042384)
			(stroke
				(width 0.1)
				(type default)
			)
			(layer "F.Fab")
		)
		(fp_line
			(start -37.907468 14.958314)
			(end -37.903404 14.95933)
			(stroke
				(width 0.1)
				(type default)
			)
			(layer "F.Fab")
		)
		(fp_line
			(start -37.910008 17.042384)
			(end -37.914326 17.043654)
			(stroke
				(width 0.1)
				(type default)
			)
			(layer "F.Fab")
		)
		(fp_line
			(start -37.912294 14.95679)
			(end -37.907468 14.958314)
			(stroke
				(width 0.1)
				(type default)
			)
			(layer "F.Fab")
		)
		(fp_line
			(start -37.914326 17.043654)
			(end -37.921184 17.045686)
			(stroke
				(width 0.1)
				(type default)
			)
			(layer "F.Fab")
		)
		(fp_line
			(start -37.917882 14.955266)
			(end -37.912294 14.95679)
			(stroke
				(width 0.1)
				(type default)
			)
			(layer "F.Fab")
		)
		(fp_line
			(start -37.92093 14.954504)
			(end -37.917882 14.955266)
			(stroke
				(width 0.1)
				(type default)
			)
			(layer "F.Fab")
		)
		(fp_line
			(start -37.921184 17.045686)
			(end -37.927788 17.047464)
			(stroke
				(width 0.1)
				(type default)
			)
			(layer "F.Fab")
		)
		(fp_line
			(start -37.927788 17.047464)
			(end -37.93109 17.048226)
			(stroke
				(width 0.1)
				(type default)
			)
			(layer "F.Fab")
		)
		(fp_line
			(start -37.927788 14.952472)
			(end -37.92093 14.954504)
			(stroke
				(width 0.1)
				(type default)
			)
			(layer "F.Fab")
		)
		(fp_line
			(start -37.93109 17.048226)
			(end -37.93617 17.049496)
			(stroke
				(width 0.1)
				(type default)
			)
			(layer "F.Fab")
		)
		(fp_line
			(start -37.933884 14.950948)
			(end -37.927788 14.952472)
			(stroke
				(width 0.1)
				(type default)
			)
			(layer "F.Fab")
		)
		(fp_line
			(start -37.93617 17.049496)
			(end -37.94379 17.051528)
			(stroke
				(width 0.1)
				(type default)
			)
			(layer "F.Fab")
		)
		(fp_line
			(start -37.942012 14.948916)
			(end -37.933884 14.950948)
			(stroke
				(width 0.1)
				(type default)
			)
			(layer "F.Fab")
		)
		(fp_line
			(start -37.94379 17.051528)
			(end -37.948616 17.052798)
			(stroke
				(width 0.1)
				(type default)
			)
			(layer "F.Fab")
		)
		(fp_line
			(start -37.948616 17.052798)
			(end -37.956998 17.05483)
			(stroke
				(width 0.1)
				(type default)
			)
			(layer "F.Fab")
		)
		(fp_line
			(start -37.94887 14.947138)
			(end -37.942012 14.948916)
			(stroke
				(width 0.1)
				(type default)
			)
			(layer "F.Fab")
		)
		(fp_line
			(start -37.953188 14.946122)
			(end -37.94887 14.947138)
			(stroke
				(width 0.1)
				(type default)
			)
			(layer "F.Fab")
		)
		(fp_line
			(start -37.956998 17.05483)
			(end -37.96538 17.057116)
			(stroke
				(width 0.1)
				(type default)
			)
			(layer "F.Fab")
		)
		(fp_line
			(start -37.957506 14.945106)
			(end -37.953188 14.946122)
			(stroke
				(width 0.1)
				(type default)
			)
			(layer "F.Fab")
		)
		(fp_line
			(start -37.96538 17.057116)
			(end -37.977064 17.059402)
			(stroke
				(width 0.1)
				(type default)
			)
			(layer "F.Fab")
		)
		(fp_line
			(start -37.972492 14.94155)
			(end -37.957506 14.945106)
			(stroke
				(width 0.1)
				(type default)
			)
			(layer "F.Fab")
		)
		(fp_line
			(start -37.977064 17.059402)
			(end -37.992558 17.062704)
			(stroke
				(width 0.1)
				(type default)
			)
			(layer "F.Fab")
		)
		(fp_line
			(start -37.992558 17.062704)
			(end -37.99967 17.063974)
			(stroke
				(width 0.1)
				(type default)
			)
			(layer "F.Fab")
		)
		(fp_line
			(start -37.99967 17.063974)
			(end -37.999924 17.064228)
			(stroke
				(width 0.1)
				(type default)
			)
			(layer "F.Fab")
		)
		(fp_line
			(start -37.999924 28.24988)
			(end 37.999924 28.24988)
			(stroke
				(width 0.1)
				(type default)
			)
			(layer "F.Fab")
		)
		(fp_line
			(start -37.999924 17.064228)
			(end -37.999924 28.24988)
			(stroke
				(width 0.1)
				(type default)
			)
			(layer "F.Fab")
		)
		(fp_line
			(start -37.999924 14.935962)
			(end -37.972492 14.94155)
			(stroke
				(width 0.1)
				(type default)
			)
			(layer "F.Fab")
		)
		(fp_line
			(start -37.999924 -28.24988)
			(end -37.999924 14.935962)
			(stroke
				(width 0.1)
				(type default)
			)
			(layer "F.Fab")
		)
		(fp_arc
			(start 37.999924 17.074388)
			(mid 37.111766 16.000198)
			(end 37.999924 14.925802)
			(stroke
				(width 0.1)
				(type default)
			)
			(layer "F.Fab")
		)
		(fp_circle
			(center -48.051212 -28.315412)
			(end -48.177958 -28.315412)
			(stroke
				(width 0.254)
				(type default)
			)
			(fill no)
			(layer "F.Fab")
		)
		(fp_text user "86"
			(at 37.222684 -32.61868 180)
			(unlocked yes)
			(layer "F.SilkS")
			(effects
				(font
					(size 0.7874 0.5842)
					(thickness 0.1524)
				)
			)
		)
		(fp_text user "85"
			(at 36.380928 -31.678118 180)
			(unlocked yes)
			(layer "F.SilkS")
			(effects
				(font
					(size 0.7874 0.5842)
					(thickness 0.1524)
				)
			)
		)
		(fp_text user "84"
			(at 35.505898 -32.61868 180)
			(unlocked yes)
			(layer "F.SilkS")
			(effects
				(font
					(size 0.7874 0.5842)
					(thickness 0.1524)
				)
			)
		)
		(fp_text user "83"
			(at 34.663888 -31.678118 180)
			(unlocked yes)
			(layer "F.SilkS")
			(effects
				(font
					(size 0.7874 0.5842)
					(thickness 0.1524)
				)
			)
		)
		(fp_text user "82"
			(at 33.788858 -32.61868 180)
			(unlocked yes)
			(layer "F.SilkS")
			(effects
				(font
					(size 0.7874 0.5842)
					(thickness 0.1524)
				)
			)
		)
		(fp_text user "81"
			(at 32.946848 -31.678118 180)
			(unlocked yes)
			(layer "F.SilkS")
			(effects
				(font
					(size 0.7874 0.5842)
					(thickness 0.1524)
				)
			)
		)
		(fp_text user "80"
			(at 32.071818 -32.61868 180)
			(unlocked yes)
			(layer "F.SilkS")
			(effects
				(font
					(size 0.7874 0.5842)
					(thickness 0.1524)
				)
			)
		)
		(fp_text user "79"
			(at 31.229808 -31.678118 180)
			(unlocked yes)
			(layer "F.SilkS")
			(effects
				(font
					(size 0.7874 0.5842)
					(thickness 0.1524)
				)
			)
		)
		(fp_text user "78"
			(at 30.354778 -32.61868 180)
			(unlocked yes)
			(layer "F.SilkS")
			(effects
				(font
					(size 0.7874 0.5842)
					(thickness 0.1524)
				)
			)
		)
		(fp_text user "77"
			(at 29.513022 -31.678118 180)
			(unlocked yes)
			(layer "F.SilkS")
			(effects
				(font
					(size 0.7874 0.5842)
					(thickness 0.1524)
				)
			)
		)
		(fp_text user "76"
			(at 28.637738 -32.61868 180)
			(unlocked yes)
			(layer "F.SilkS")
			(effects
				(font
					(size 0.7874 0.5842)
					(thickness 0.1524)
				)
			)
		)
		(fp_text user "75"
			(at 27.751786 -31.18358 180)
			(unlocked yes)
			(layer "F.SilkS")
			(effects
				(font
					(size 0.7874 0.5842)
					(thickness 0.1524)
				)
			)
		)
		(fp_text user "74"
			(at 26.920698 -32.23768 180)
			(unlocked yes)
			(layer "F.SilkS")
			(effects
				(font
					(size 0.7874 0.5842)
					(thickness 0.1524)
				)
			)
		)
		(fp_text user "73"
			(at 26.034746 -31.18358 180)
			(unlocked yes)
			(layer "F.SilkS")
			(effects
				(font
					(size 0.7874 0.5842)
					(thickness 0.1524)
				)
			)
		)
		(fp_text user "72"
			(at 25.203912 -32.23768 180)
			(unlocked yes)
			(layer "F.SilkS")
			(effects
				(font
					(size 0.7874 0.5842)
					(thickness 0.1524)
				)
			)
		)
		(fp_text user "71"
			(at 24.317706 -31.18358 180)
			(unlocked yes)
			(layer "F.SilkS")
			(effects
				(font
					(size 0.7874 0.5842)
					(thickness 0.1524)
				)
			)
		)
		(fp_text user "70"
			(at 23.486872 -32.23768 180)
			(unlocked yes)
			(layer "F.SilkS")
			(effects
				(font
					(size 0.7874 0.5842)
					(thickness 0.1524)
				)
			)
		)
		(fp_text user "69"
			(at 22.600666 -31.18358 180)
			(unlocked yes)
			(layer "F.SilkS")
			(effects
				(font
					(size 0.7874 0.5842)
					(thickness 0.1524)
				)
			)
		)
		(fp_text user "68"
			(at 21.769832 -32.23768 180)
			(unlocked yes)
			(layer "F.SilkS")
			(effects
				(font
					(size 0.7874 0.5842)
					(thickness 0.1524)
				)
			)
		)
		(fp_text user "67"
			(at 20.883626 -31.18358 180)
			(unlocked yes)
			(layer "F.SilkS")
			(effects
				(font
					(size 0.7874 0.5842)
					(thickness 0.1524)
				)
			)
		)
		(fp_text user "66"
			(at 20.052792 -32.23768 180)
			(unlocked yes)
			(layer "F.SilkS")
			(effects
				(font
					(size 0.7874 0.5842)
					(thickness 0.1524)
				)
			)
		)
		(fp_text user "65"
			(at 19.166586 -31.18358 180)
			(unlocked yes)
			(layer "F.SilkS")
			(effects
				(font
					(size 0.7874 0.5842)
					(thickness 0.1524)
				)
			)
		)
		(fp_text user "64"
			(at 18.335752 -32.23768 180)
			(unlocked yes)
			(layer "F.SilkS")
			(effects
				(font
					(size 0.7874 0.5842)
					(thickness 0.1524)
				)
			)
		)
		(fp_text user "63"
			(at 17.4498 -31.18358 180)
			(unlocked yes)
			(layer "F.SilkS")
			(effects
				(font
					(size 0.7874 0.5842)
					(thickness 0.1524)
				)
			)
		)
		(fp_text user "62"
			(at 16.618712 -32.23768 180)
			(unlocked yes)
			(layer "F.SilkS")
			(effects
				(font
					(size 0.7874 0.5842)
					(thickness 0.1524)
				)
			)
		)
		(fp_text user "61"
			(at 15.73276 -31.18358 180)
			(unlocked yes)
			(layer "F.SilkS")
			(effects
				(font
					(size 0.7874 0.5842)
					(thickness 0.1524)
				)
			)
		)
		(fp_text user "60"
			(at 14.901926 -32.23768 180)
			(unlocked yes)
			(layer "F.SilkS")
			(effects
				(font
					(size 0.7874 0.5842)
					(thickness 0.1524)
				)
			)
		)
		(fp_text user "59"
			(at 14.01572 -31.18358 180)
			(unlocked yes)
			(layer "F.SilkS")
			(effects
				(font
					(size 0.7874 0.5842)
					(thickness 0.1524)
				)
			)
		)
		(fp_text user "58"
			(at 13.184886 -32.23768 180)
			(unlocked yes)
			(layer "F.SilkS")
			(effects
				(font
					(size 0.7874 0.5842)
					(thickness 0.1524)
				)
			)
		)
		(fp_text user "57"
			(at 12.29868 -31.18358 180)
			(unlocked yes)
			(layer "F.SilkS")
			(effects
				(font
					(size 0.7874 0.5842)
					(thickness 0.1524)
				)
			)
		)
		(fp_text user "56"
			(at 11.467846 -32.23768 180)
			(unlocked yes)
			(layer "F.SilkS")
			(effects
				(font
					(size 0.7874 0.5842)
					(thickness 0.1524)
				)
			)
		)
		(fp_text user "55"
			(at 10.58164 -31.18358 180)
			(unlocked yes)
			(layer "F.SilkS")
			(effects
				(font
					(size 0.7874 0.5842)
					(thickness 0.1524)
				)
			)
		)
		(fp_text user "54"
			(at 9.750806 -32.23768 180)
			(unlocked yes)
			(layer "F.SilkS")
			(effects
				(font
					(size 0.7874 0.5842)
					(thickness 0.1524)
				)
			)
		)
		(fp_text user "53"
			(at 8.8646 -31.18358 180)
			(unlocked yes)
			(layer "F.SilkS")
			(effects
				(font
					(size 0.7874 0.5842)
					(thickness 0.1524)
				)
			)
		)
		(fp_text user "52"
			(at 8.033766 -32.23768 180)
			(unlocked yes)
			(layer "F.SilkS")
			(effects
				(font
					(size 0.7874 0.5842)
					(thickness 0.1524)
				)
			)
		)
		(fp_text user "51"
			(at 7.147814 -31.18358 180)
			(unlocked yes)
			(layer "F.SilkS")
			(effects
				(font
					(size 0.7874 0.5842)
					(thickness 0.1524)
				)
			)
		)
		(fp_text user "50"
			(at 6.316726 -32.23768 180)
			(unlocked yes)
			(layer "F.SilkS")
			(effects
				(font
					(size 0.7874 0.5842)
					(thickness 0.1524)
				)
			)
		)
		(fp_text user "49"
			(at 5.430774 -31.18358 180)
			(unlocked yes)
			(layer "F.SilkS")
			(effects
				(font
					(size 0.7874 0.5842)
					(thickness 0.1524)
				)
			)
		)
		(fp_text user "48"
			(at 4.599686 -32.23768 180)
			(unlocked yes)
			(layer "F.SilkS")
			(effects
				(font
					(size 0.7874 0.5842)
					(thickness 0.1524)
				)
			)
		)
		(fp_text user "47"
			(at 3.713734 -31.18358 180)
			(unlocked yes)
			(layer "F.SilkS")
			(effects
				(font
					(size 0.7874 0.5842)
					(thickness 0.1524)
				)
			)
		)
		(fp_text user "46"
			(at 2.8829 -32.23768 180)
			(unlocked yes)
			(layer "F.SilkS")
			(effects
				(font
					(size 0.7874 0.5842)
					(thickness 0.1524)
				)
			)
		)
		(fp_text user "45"
			(at 1.996694 -31.18358 180)
			(unlocked yes)
			(layer "F.SilkS")
			(effects
				(font
					(size 0.7874 0.5842)
					(thickness 0.1524)
				)
			)
		)
		(fp_text user "44"
			(at 1.16586 -32.23768 180)
			(unlocked yes)
			(layer "F.SilkS")
			(effects
				(font
					(size 0.7874 0.5842)
					(thickness 0.1524)
				)
			)
		)
		(fp_text user "43"
			(at -1.218184 -31.335726 180)
			(unlocked yes)
			(layer "F.SilkS")
			(effects
				(font
					(size 0.7874 0.5842)
					(thickness 0.1524)
				)
			)
		)
		(fp_text user "42"
			(at -2.093214 -32.276288 180)
			(unlocked yes)
			(layer "F.SilkS")
			(effects
				(font
					(size 0.7874 0.5842)
					(thickness 0.1524)
				)
			)
		)
		(fp_text user "41"
			(at -2.935224 -31.335726 180)
			(unlocked yes)
			(layer "F.SilkS")
			(effects
				(font
					(size 0.7874 0.5842)
					(thickness 0.1524)
				)
			)
		)
		(fp_text user "40"
			(at -3.810254 -32.276288 180)
			(unlocked yes)
			(layer "F.SilkS")
			(effects
				(font
					(size 0.7874 0.5842)
					(thickness 0.1524)
				)
			)
		)
		(fp_text user "39"
			(at -4.65201 -31.335726 180)
			(unlocked yes)
			(layer "F.SilkS")
			(effects
				(font
					(size 0.7874 0.5842)
					(thickness 0.1524)
				)
			)
		)
		(fp_text user "38"
			(at -5.527294 -32.276288 180)
			(unlocked yes)
			(layer "F.SilkS")
			(effects
				(font
					(size 0.7874 0.5842)
					(thickness 0.1524)
				)
			)
		)
		(fp_text user "37"
			(at -6.36905 -31.335726 180)
			(unlocked yes)
			(layer "F.SilkS")
			(effects
				(font
					(size 0.7874 0.5842)
					(thickness 0.1524)
				)
			)
		)
		(fp_text user "36"
			(at -7.24408 -32.276288 180)
			(unlocked yes)
			(layer "F.SilkS")
			(effects
				(font
					(size 0.7874 0.5842)
					(thickness 0.1524)
				)
			)
		)
		(fp_text user "35"
			(at -8.08609 -31.335726 180)
			(unlocked yes)
			(layer "F.SilkS")
			(effects
				(font
					(size 0.7874 0.5842)
					(thickness 0.1524)
				)
			)
		)
		(fp_text user "34"
			(at -8.96112 -32.276288 180)
			(unlocked yes)
			(layer "F.SilkS")
			(effects
				(font
					(size 0.7874 0.5842)
					(thickness 0.1524)
				)
			)
		)
		(fp_text user "33"
			(at -9.80313 -31.335726 180)
			(unlocked yes)
			(layer "F.SilkS")
			(effects
				(font
					(size 0.7874 0.5842)
					(thickness 0.1524)
				)
			)
		)
		(fp_text user "32"
			(at -10.67816 -32.276288 180)
			(unlocked yes)
			(layer "F.SilkS")
			(effects
				(font
					(size 0.7874 0.5842)
					(thickness 0.1524)
				)
			)
		)
		(fp_text user "31"
			(at -11.52017 -31.335726 180)
			(unlocked yes)
			(layer "F.SilkS")
			(effects
				(font
					(size 0.7874 0.5842)
					(thickness 0.1524)
				)
			)
		)
		(fp_text user "30"
			(at -12.3952 -32.276288 180)
			(unlocked yes)
			(layer "F.SilkS")
			(effects
				(font
					(size 0.7874 0.5842)
					(thickness 0.1524)
				)
			)
		)
		(fp_text user "29"
			(at -13.23721 -31.335726 180)
			(unlocked yes)
			(layer "F.SilkS")
			(effects
				(font
					(size 0.7874 0.5842)
					(thickness 0.1524)
				)
			)
		)
		(fp_text user "28"
			(at -14.11224 -32.276288 180)
			(unlocked yes)
			(layer "F.SilkS")
			(effects
				(font
					(size 0.7874 0.5842)
					(thickness 0.1524)
				)
			)
		)
		(fp_text user "27"
			(at -14.953996 -31.335726 180)
			(unlocked yes)
			(layer "F.SilkS")
			(effects
				(font
					(size 0.7874 0.5842)
					(thickness 0.1524)
				)
			)
		)
		(fp_text user "26"
			(at -15.82928 -32.276288 180)
			(unlocked yes)
			(layer "F.SilkS")
			(effects
				(font
					(size 0.7874 0.5842)
					(thickness 0.1524)
				)
			)
		)
		(fp_text user "25"
			(at -16.671036 -31.335726 180)
			(unlocked yes)
			(layer "F.SilkS")
			(effects
				(font
					(size 0.7874 0.5842)
					(thickness 0.1524)
				)
			)
		)
		(fp_text user "24"
			(at -17.54632 -32.276288 180)
			(unlocked yes)
			(layer "F.SilkS")
			(effects
				(font
					(size 0.7874 0.5842)
					(thickness 0.1524)
				)
			)
		)
		(fp_text user "23"
			(at -18.388076 -31.335726 180)
			(unlocked yes)
			(layer "F.SilkS")
			(effects
				(font
					(size 0.7874 0.5842)
					(thickness 0.1524)
				)
			)
		)
		(fp_text user "22"
			(at -19.263106 -32.276288 180)
			(unlocked yes)
			(layer "F.SilkS")
			(effects
				(font
					(size 0.7874 0.5842)
					(thickness 0.1524)
				)
			)
		)
		(fp_text user "21"
			(at -20.105116 -31.335726 180)
			(unlocked yes)
			(layer "F.SilkS")
			(effects
				(font
					(size 0.7874 0.5842)
					(thickness 0.1524)
				)
			)
		)
		(fp_text user "20"
			(at -20.980146 -32.276288 180)
			(unlocked yes)
			(layer "F.SilkS")
			(effects
				(font
					(size 0.7874 0.5842)
					(thickness 0.1524)
				)
			)
		)
		(fp_text user "19"
			(at -21.822156 -31.335726 180)
			(unlocked yes)
			(layer "F.SilkS")
			(effects
				(font
					(size 0.7874 0.5842)
					(thickness 0.1524)
				)
			)
		)
		(fp_text user "18"
			(at -22.697186 -32.276288 180)
			(unlocked yes)
			(layer "F.SilkS")
			(effects
				(font
					(size 0.7874 0.5842)
					(thickness 0.1524)
				)
			)
		)
		(fp_text user "17"
			(at -23.539196 -31.335726 180)
			(unlocked yes)
			(layer "F.SilkS")
			(effects
				(font
					(size 0.7874 0.5842)
					(thickness 0.1524)
				)
			)
		)
		(fp_text user "16"
			(at -24.414226 -32.276288 180)
			(unlocked yes)
			(layer "F.SilkS")
			(effects
				(font
					(size 0.7874 0.5842)
					(thickness 0.1524)
				)
			)
		)
		(fp_text user "15"
			(at -25.255982 -31.335726 180)
			(unlocked yes)
			(layer "F.SilkS")
			(effects
				(font
					(size 0.7874 0.5842)
					(thickness 0.1524)
				)
			)
		)
		(fp_text user "14"
			(at -26.131266 -32.276288 180)
			(unlocked yes)
			(layer "F.SilkS")
			(effects
				(font
					(size 0.7874 0.5842)
					(thickness 0.1524)
				)
			)
		)
		(fp_text user "13"
			(at -26.973022 -31.335726 180)
			(unlocked yes)
			(layer "F.SilkS")
			(effects
				(font
					(size 0.7874 0.5842)
					(thickness 0.1524)
				)
			)
		)
		(fp_text user "12"
			(at -27.848306 -32.276288 180)
			(unlocked yes)
			(layer "F.SilkS")
			(effects
				(font
					(size 0.7874 0.5842)
					(thickness 0.1524)
				)
			)
		)
		(fp_text user "11"
			(at -28.690062 -31.335726 180)
			(unlocked yes)
			(layer "F.SilkS")
			(effects
				(font
					(size 0.7874 0.5842)
					(thickness 0.1524)
				)
			)
		)
		(fp_text user "10"
			(at -29.565092 -32.276288 180)
			(unlocked yes)
			(layer "F.SilkS")
			(effects
				(font
					(size 0.7874 0.5842)
					(thickness 0.1524)
				)
			)
		)
		(fp_text user "9"
			(at -30.407102 -31.335726 180)
			(unlocked yes)
			(layer "F.SilkS")
			(effects
				(font
					(size 0.7874 0.5842)
					(thickness 0.1524)
				)
			)
		)
		(fp_text user "8"
			(at -31.282132 -32.657288 180)
			(unlocked yes)
			(layer "F.SilkS")
			(effects
				(font
					(size 0.7874 0.5842)
					(thickness 0.1524)
				)
			)
		)
		(fp_text user "7"
			(at -32.124142 -31.716726 180)
			(unlocked yes)
			(layer "F.SilkS")
			(effects
				(font
					(size 0.7874 0.5842)
					(thickness 0.1524)
				)
			)
		)
		(fp_text user "6"
			(at -32.999172 -32.657288 180)
			(unlocked yes)
			(layer "F.SilkS")
			(effects
				(font
					(size 0.7874 0.5842)
					(thickness 0.1524)
				)
			)
		)
		(fp_text user "5"
			(at -33.841182 -31.716726 180)
			(unlocked yes)
			(layer "F.SilkS")
			(effects
				(font
					(size 0.7874 0.5842)
					(thickness 0.1524)
				)
			)
		)
		(fp_text user "4"
			(at -34.716212 -32.657288 180)
			(unlocked yes)
			(layer "F.SilkS")
			(effects
				(font
					(size 0.7874 0.5842)
					(thickness 0.1524)
				)
			)
		)
		(fp_text user "3"
			(at -35.558222 -31.716726 180)
			(unlocked yes)
			(layer "F.SilkS")
			(effects
				(font
					(size 0.7874 0.5842)
					(thickness 0.1524)
				)
			)
		)
		(fp_text user "2"
			(at -36.433252 -32.657288 180)
			(unlocked yes)
			(layer "F.SilkS")
			(effects
				(font
					(size 0.7874 0.5842)
					(thickness 0.1524)
				)
			)
		)
		(fp_text user "1"
			(at -37.275008 -31.716726 180)
			(unlocked yes)
			(layer "F.SilkS")
			(effects
				(font
					(size 0.7874 0.5842)
					(thickness 0.1524)
				)
			)
		)
		(fp_text user "EE"
			(at -42.250614 26.504646 180)
			(unlocked yes)
			(layer "F.SilkS")
			(effects
				(font
					(size 0.7874 0.5842)
					(thickness 0.1524)
				)
			)
		)
		(fp_text user "DU"
			(at -42.618406 22.409912 180)
			(unlocked yes)
			(layer "F.SilkS")
			(effects
				(font
					(size 0.7874 0.5842)
					(thickness 0.1524)
				)
			)
		)
		(fp_text user "DJ"
			(at -42.618406 18.447512 180)
			(unlocked yes)
			(layer "F.SilkS")
			(effects
				(font
					(size 0.7874 0.5842)
					(thickness 0.1524)
				)
			)
		)
		(fp_text user "DA"
			(at -42.618406 14.485112 180)
			(unlocked yes)
			(layer "F.SilkS")
			(effects
				(font
					(size 0.7874 0.5842)
					(thickness 0.1524)
				)
			)
		)
		(fp_text user "CN"
			(at -42.618406 10.522712 180)
			(unlocked yes)
			(layer "F.SilkS")
			(effects
				(font
					(size 0.7874 0.5842)
					(thickness 0.1524)
				)
			)
		)
		(fp_text user "CE"
			(at -42.618406 6.560312 180)
			(unlocked yes)
			(layer "F.SilkS")
			(effects
				(font
					(size 0.7874 0.5842)
					(thickness 0.1524)
				)
			)
		)
		(fp_text user "BU"
			(at -42.618406 2.597912 180)
			(unlocked yes)
			(layer "F.SilkS")
			(effects
				(font
					(size 0.7874 0.5842)
					(thickness 0.1524)
				)
			)
		)
		(fp_text user "BJ"
			(at -42.618406 -1.364488 180)
			(unlocked yes)
			(layer "F.SilkS")
			(effects
				(font
					(size 0.7874 0.5842)
					(thickness 0.1524)
				)
			)
		)
		(fp_text user "BA"
			(at -42.618406 -5.326888 180)
			(unlocked yes)
			(layer "F.SilkS")
			(effects
				(font
					(size 0.7874 0.5842)
					(thickness 0.1524)
				)
			)
		)
		(fp_text user "AN"
			(at -42.618406 -9.289288 180)
			(unlocked yes)
			(layer "F.SilkS")
			(effects
				(font
					(size 0.7874 0.5842)
					(thickness 0.1524)
				)
			)
		)
		(fp_text user "AE"
			(at -42.618406 -13.251688 180)
			(unlocked yes)
			(layer "F.SilkS")
			(effects
				(font
					(size 0.7874 0.5842)
					(thickness 0.1524)
				)
			)
		)
		(fp_text user "U"
			(at -42.618406 -17.214088 180)
			(unlocked yes)
			(layer "F.SilkS")
			(effects
				(font
					(size 0.7874 0.5842)
					(thickness 0.1524)
				)
			)
		)
		(fp_text user "J"
			(at -42.618406 -21.176488 180)
			(unlocked yes)
			(layer "F.SilkS")
			(effects
				(font
					(size 0.7874 0.5842)
					(thickness 0.1524)
				)
			)
		)
		(fp_text user "A"
			(at -42.618406 -25.138888 180)
			(unlocked yes)
			(layer "F.SilkS")
			(effects
				(font
					(size 0.7874 0.5842)
					(thickness 0.1524)
				)
			)
		)
		(fp_text user "DY"
			(at -42.625772 23.897844 180)
			(unlocked yes)
			(layer "F.SilkS")
			(effects
				(font
					(size 0.7874 0.5842)
					(thickness 0.1524)
				)
			)
		)
		(fp_text user "86"
			(at 37.222684 -32.23768 180)
			(unlocked yes)
			(layer "F.Fab")
			(effects
				(font
					(size 0.7874 0.5842)
					(thickness 0.1524)
				)
			)
		)
		(fp_text user "85"
			(at 36.380928 -31.297118 180)
			(unlocked yes)
			(layer "F.Fab")
			(effects
				(font
					(size 0.7874 0.5842)
					(thickness 0.1524)
				)
			)
		)
		(fp_text user "84"
			(at 35.505898 -32.23768 180)
			(unlocked yes)
			(layer "F.Fab")
			(effects
				(font
					(size 0.7874 0.5842)
					(thickness 0.1524)
				)
			)
		)
		(fp_text user "83"
			(at 34.663888 -31.297118 180)
			(unlocked yes)
			(layer "F.Fab")
			(effects
				(font
					(size 0.7874 0.5842)
					(thickness 0.1524)
				)
			)
		)
		(fp_text user "82"
			(at 33.788858 -32.23768 180)
			(unlocked yes)
			(layer "F.Fab")
			(effects
				(font
					(size 0.7874 0.5842)
					(thickness 0.1524)
				)
			)
		)
		(fp_text user "81"
			(at 32.946848 -31.297118 180)
			(unlocked yes)
			(layer "F.Fab")
			(effects
				(font
					(size 0.7874 0.5842)
					(thickness 0.1524)
				)
			)
		)
		(fp_text user "80"
			(at 32.071818 -32.23768 180)
			(unlocked yes)
			(layer "F.Fab")
			(effects
				(font
					(size 0.7874 0.5842)
					(thickness 0.1524)
				)
			)
		)
		(fp_text user "79"
			(at 31.229808 -31.297118 180)
			(unlocked yes)
			(layer "F.Fab")
			(effects
				(font
					(size 0.7874 0.5842)
					(thickness 0.1524)
				)
			)
		)
		(fp_text user "78"
			(at 30.354778 -32.23768 180)
			(unlocked yes)
			(layer "F.Fab")
			(effects
				(font
					(size 0.7874 0.5842)
					(thickness 0.1524)
				)
			)
		)
		(fp_text user "77"
			(at 29.513022 -31.297118 180)
			(unlocked yes)
			(layer "F.Fab")
			(effects
				(font
					(size 0.7874 0.5842)
					(thickness 0.1524)
				)
			)
		)
		(fp_text user "76"
			(at 28.637738 -32.23768 180)
			(unlocked yes)
			(layer "F.Fab")
			(effects
				(font
					(size 0.7874 0.5842)
					(thickness 0.1524)
				)
			)
		)
		(fp_text user "75"
			(at 27.795982 -31.297118 180)
			(unlocked yes)
			(layer "F.Fab")
			(effects
				(font
					(size 0.7874 0.5842)
					(thickness 0.1524)
				)
			)
		)
		(fp_text user "74"
			(at 26.920698 -32.23768 180)
			(unlocked yes)
			(layer "F.Fab")
			(effects
				(font
					(size 0.7874 0.5842)
					(thickness 0.1524)
				)
			)
		)
		(fp_text user "73"
			(at 26.078942 -31.297118 180)
			(unlocked yes)
			(layer "F.Fab")
			(effects
				(font
					(size 0.7874 0.5842)
					(thickness 0.1524)
				)
			)
		)
		(fp_text user "72"
			(at 25.203912 -32.23768 180)
			(unlocked yes)
			(layer "F.Fab")
			(effects
				(font
					(size 0.7874 0.5842)
					(thickness 0.1524)
				)
			)
		)
		(fp_text user "71"
			(at 24.361902 -31.297118 180)
			(unlocked yes)
			(layer "F.Fab")
			(effects
				(font
					(size 0.7874 0.5842)
					(thickness 0.1524)
				)
			)
		)
		(fp_text user "70"
			(at 23.486872 -32.23768 180)
			(unlocked yes)
			(layer "F.Fab")
			(effects
				(font
					(size 0.7874 0.5842)
					(thickness 0.1524)
				)
			)
		)
		(fp_text user "69"
			(at 22.644862 -31.297118 180)
			(unlocked yes)
			(layer "F.Fab")
			(effects
				(font
					(size 0.7874 0.5842)
					(thickness 0.1524)
				)
			)
		)
		(fp_text user "68"
			(at 21.769832 -32.23768 180)
			(unlocked yes)
			(layer "F.Fab")
			(effects
				(font
					(size 0.7874 0.5842)
					(thickness 0.1524)
				)
			)
		)
		(fp_text user "67"
			(at 20.927822 -31.297118 180)
			(unlocked yes)
			(layer "F.Fab")
			(effects
				(font
					(size 0.7874 0.5842)
					(thickness 0.1524)
				)
			)
		)
		(fp_text user "66"
			(at 20.052792 -32.23768 180)
			(unlocked yes)
			(layer "F.Fab")
			(effects
				(font
					(size 0.7874 0.5842)
					(thickness 0.1524)
				)
			)
		)
		(fp_text user "65"
			(at 19.210782 -31.297118 180)
			(unlocked yes)
			(layer "F.Fab")
			(effects
				(font
					(size 0.7874 0.5842)
					(thickness 0.1524)
				)
			)
		)
		(fp_text user "64"
			(at 18.335752 -32.23768 180)
			(unlocked yes)
			(layer "F.Fab")
			(effects
				(font
					(size 0.7874 0.5842)
					(thickness 0.1524)
				)
			)
		)
		(fp_text user "63"
			(at 17.493996 -31.297118 180)
			(unlocked yes)
			(layer "F.Fab")
			(effects
				(font
					(size 0.7874 0.5842)
					(thickness 0.1524)
				)
			)
		)
		(fp_text user "62"
			(at 16.618712 -32.23768 180)
			(unlocked yes)
			(layer "F.Fab")
			(effects
				(font
					(size 0.7874 0.5842)
					(thickness 0.1524)
				)
			)
		)
		(fp_text user "61"
			(at 15.776956 -31.297118 180)
			(unlocked yes)
			(layer "F.Fab")
			(effects
				(font
					(size 0.7874 0.5842)
					(thickness 0.1524)
				)
			)
		)
		(fp_text user "60"
			(at 14.901926 -32.23768 180)
			(unlocked yes)
			(layer "F.Fab")
			(effects
				(font
					(size 0.7874 0.5842)
					(thickness 0.1524)
				)
			)
		)
		(fp_text user "59"
			(at 14.059916 -31.297118 180)
			(unlocked yes)
			(layer "F.Fab")
			(effects
				(font
					(size 0.7874 0.5842)
					(thickness 0.1524)
				)
			)
		)
		(fp_text user "58"
			(at 13.184886 -32.23768 180)
			(unlocked yes)
			(layer "F.Fab")
			(effects
				(font
					(size 0.7874 0.5842)
					(thickness 0.1524)
				)
			)
		)
		(fp_text user "57"
			(at 12.342876 -31.297118 180)
			(unlocked yes)
			(layer "F.Fab")
			(effects
				(font
					(size 0.7874 0.5842)
					(thickness 0.1524)
				)
			)
		)
		(fp_text user "56"
			(at 11.467846 -32.23768 180)
			(unlocked yes)
			(layer "F.Fab")
			(effects
				(font
					(size 0.7874 0.5842)
					(thickness 0.1524)
				)
			)
		)
		(fp_text user "55"
			(at 10.625836 -31.297118 180)
			(unlocked yes)
			(layer "F.Fab")
			(effects
				(font
					(size 0.7874 0.5842)
					(thickness 0.1524)
				)
			)
		)
		(fp_text user "54"
			(at 9.750806 -32.23768 180)
			(unlocked yes)
			(layer "F.Fab")
			(effects
				(font
					(size 0.7874 0.5842)
					(thickness 0.1524)
				)
			)
		)
		(fp_text user "53"
			(at 8.908796 -31.297118 180)
			(unlocked yes)
			(layer "F.Fab")
			(effects
				(font
					(size 0.7874 0.5842)
					(thickness 0.1524)
				)
			)
		)
		(fp_text user "52"
			(at 8.033766 -32.23768 180)
			(unlocked yes)
			(layer "F.Fab")
			(effects
				(font
					(size 0.7874 0.5842)
					(thickness 0.1524)
				)
			)
		)
		(fp_text user "51"
			(at 7.19201 -31.297118 180)
			(unlocked yes)
			(layer "F.Fab")
			(effects
				(font
					(size 0.7874 0.5842)
					(thickness 0.1524)
				)
			)
		)
		(fp_text user "50"
			(at 6.316726 -32.23768 180)
			(unlocked yes)
			(layer "F.Fab")
			(effects
				(font
					(size 0.7874 0.5842)
					(thickness 0.1524)
				)
			)
		)
		(fp_text user "49"
			(at 5.47497 -31.297118 180)
			(unlocked yes)
			(layer "F.Fab")
			(effects
				(font
					(size 0.7874 0.5842)
					(thickness 0.1524)
				)
			)
		)
		(fp_text user "48"
			(at 4.599686 -32.23768 180)
			(unlocked yes)
			(layer "F.Fab")
			(effects
				(font
					(size 0.7874 0.5842)
					(thickness 0.1524)
				)
			)
		)
		(fp_text user "47"
			(at 3.75793 -31.297118 180)
			(unlocked yes)
			(layer "F.Fab")
			(effects
				(font
					(size 0.7874 0.5842)
					(thickness 0.1524)
				)
			)
		)
		(fp_text user "46"
			(at 2.8829 -32.23768 180)
			(unlocked yes)
			(layer "F.Fab")
			(effects
				(font
					(size 0.7874 0.5842)
					(thickness 0.1524)
				)
			)
		)
		(fp_text user "45"
			(at 2.04089 -31.297118 180)
			(unlocked yes)
			(layer "F.Fab")
			(effects
				(font
					(size 0.7874 0.5842)
					(thickness 0.1524)
				)
			)
		)
		(fp_text user "44"
			(at 1.16586 -32.23768 180)
			(unlocked yes)
			(layer "F.Fab")
			(effects
				(font
					(size 0.7874 0.5842)
					(thickness 0.1524)
				)
			)
		)
		(fp_text user "43"
			(at -1.218184 -31.335726 180)
			(unlocked yes)
			(layer "F.Fab")
			(effects
				(font
					(size 0.7874 0.5842)
					(thickness 0.1524)
				)
			)
		)
		(fp_text user "42"
			(at -2.093214 -32.276288 180)
			(unlocked yes)
			(layer "F.Fab")
			(effects
				(font
					(size 0.7874 0.5842)
					(thickness 0.1524)
				)
			)
		)
		(fp_text user "41"
			(at -2.935224 -31.335726 180)
			(unlocked yes)
			(layer "F.Fab")
			(effects
				(font
					(size 0.7874 0.5842)
					(thickness 0.1524)
				)
			)
		)
		(fp_text user "40"
			(at -3.810254 -32.276288 180)
			(unlocked yes)
			(layer "F.Fab")
			(effects
				(font
					(size 0.7874 0.5842)
					(thickness 0.1524)
				)
			)
		)
		(fp_text user "39"
			(at -4.65201 -31.335726 180)
			(unlocked yes)
			(layer "F.Fab")
			(effects
				(font
					(size 0.7874 0.5842)
					(thickness 0.1524)
				)
			)
		)
		(fp_text user "38"
			(at -5.527294 -32.276288 180)
			(unlocked yes)
			(layer "F.Fab")
			(effects
				(font
					(size 0.7874 0.5842)
					(thickness 0.1524)
				)
			)
		)
		(fp_text user "37"
			(at -6.36905 -31.335726 180)
			(unlocked yes)
			(layer "F.Fab")
			(effects
				(font
					(size 0.7874 0.5842)
					(thickness 0.1524)
				)
			)
		)
		(fp_text user "36"
			(at -7.24408 -32.276288 180)
			(unlocked yes)
			(layer "F.Fab")
			(effects
				(font
					(size 0.7874 0.5842)
					(thickness 0.1524)
				)
			)
		)
		(fp_text user "35"
			(at -8.08609 -31.335726 180)
			(unlocked yes)
			(layer "F.Fab")
			(effects
				(font
					(size 0.7874 0.5842)
					(thickness 0.1524)
				)
			)
		)
		(fp_text user "34"
			(at -8.96112 -32.276288 180)
			(unlocked yes)
			(layer "F.Fab")
			(effects
				(font
					(size 0.7874 0.5842)
					(thickness 0.1524)
				)
			)
		)
		(fp_text user "33"
			(at -9.80313 -31.335726 180)
			(unlocked yes)
			(layer "F.Fab")
			(effects
				(font
					(size 0.7874 0.5842)
					(thickness 0.1524)
				)
			)
		)
		(fp_text user "32"
			(at -10.67816 -32.276288 180)
			(unlocked yes)
			(layer "F.Fab")
			(effects
				(font
					(size 0.7874 0.5842)
					(thickness 0.1524)
				)
			)
		)
		(fp_text user "31"
			(at -11.52017 -31.335726 180)
			(unlocked yes)
			(layer "F.Fab")
			(effects
				(font
					(size 0.7874 0.5842)
					(thickness 0.1524)
				)
			)
		)
		(fp_text user "30"
			(at -12.3952 -32.276288 180)
			(unlocked yes)
			(layer "F.Fab")
			(effects
				(font
					(size 0.7874 0.5842)
					(thickness 0.1524)
				)
			)
		)
		(fp_text user "29"
			(at -13.23721 -31.335726 180)
			(unlocked yes)
			(layer "F.Fab")
			(effects
				(font
					(size 0.7874 0.5842)
					(thickness 0.1524)
				)
			)
		)
		(fp_text user "28"
			(at -14.11224 -32.276288 180)
			(unlocked yes)
			(layer "F.Fab")
			(effects
				(font
					(size 0.7874 0.5842)
					(thickness 0.1524)
				)
			)
		)
		(fp_text user "27"
			(at -14.953996 -31.335726 180)
			(unlocked yes)
			(layer "F.Fab")
			(effects
				(font
					(size 0.7874 0.5842)
					(thickness 0.1524)
				)
			)
		)
		(fp_text user "26"
			(at -15.82928 -32.276288 180)
			(unlocked yes)
			(layer "F.Fab")
			(effects
				(font
					(size 0.7874 0.5842)
					(thickness 0.1524)
				)
			)
		)
		(fp_text user "25"
			(at -16.671036 -31.335726 180)
			(unlocked yes)
			(layer "F.Fab")
			(effects
				(font
					(size 0.7874 0.5842)
					(thickness 0.1524)
				)
			)
		)
		(fp_text user "24"
			(at -17.54632 -32.276288 180)
			(unlocked yes)
			(layer "F.Fab")
			(effects
				(font
					(size 0.7874 0.5842)
					(thickness 0.1524)
				)
			)
		)
		(fp_text user "23"
			(at -18.388076 -31.335726 180)
			(unlocked yes)
			(layer "F.Fab")
			(effects
				(font
					(size 0.7874 0.5842)
					(thickness 0.1524)
				)
			)
		)
		(fp_text user "22"
			(at -19.263106 -32.276288 180)
			(unlocked yes)
			(layer "F.Fab")
			(effects
				(font
					(size 0.7874 0.5842)
					(thickness 0.1524)
				)
			)
		)
		(fp_text user "21"
			(at -20.105116 -31.335726 180)
			(unlocked yes)
			(layer "F.Fab")
			(effects
				(font
					(size 0.7874 0.5842)
					(thickness 0.1524)
				)
			)
		)
		(fp_text user "20"
			(at -20.980146 -32.276288 180)
			(unlocked yes)
			(layer "F.Fab")
			(effects
				(font
					(size 0.7874 0.5842)
					(thickness 0.1524)
				)
			)
		)
		(fp_text user "19"
			(at -21.822156 -31.335726 180)
			(unlocked yes)
			(layer "F.Fab")
			(effects
				(font
					(size 0.7874 0.5842)
					(thickness 0.1524)
				)
			)
		)
		(fp_text user "18"
			(at -22.697186 -32.276288 180)
			(unlocked yes)
			(layer "F.Fab")
			(effects
				(font
					(size 0.7874 0.5842)
					(thickness 0.1524)
				)
			)
		)
		(fp_text user "17"
			(at -23.539196 -31.335726 180)
			(unlocked yes)
			(layer "F.Fab")
			(effects
				(font
					(size 0.7874 0.5842)
					(thickness 0.1524)
				)
			)
		)
		(fp_text user "16"
			(at -24.414226 -32.276288 180)
			(unlocked yes)
			(layer "F.Fab")
			(effects
				(font
					(size 0.7874 0.5842)
					(thickness 0.1524)
				)
			)
		)
		(fp_text user "15"
			(at -25.255982 -31.335726 180)
			(unlocked yes)
			(layer "F.Fab")
			(effects
				(font
					(size 0.7874 0.5842)
					(thickness 0.1524)
				)
			)
		)
		(fp_text user "14"
			(at -26.131266 -32.276288 180)
			(unlocked yes)
			(layer "F.Fab")
			(effects
				(font
					(size 0.7874 0.5842)
					(thickness 0.1524)
				)
			)
		)
		(fp_text user "13"
			(at -26.973022 -31.335726 180)
			(unlocked yes)
			(layer "F.Fab")
			(effects
				(font
					(size 0.7874 0.5842)
					(thickness 0.1524)
				)
			)
		)
		(fp_text user "12"
			(at -27.848306 -32.276288 180)
			(unlocked yes)
			(layer "F.Fab")
			(effects
				(font
					(size 0.7874 0.5842)
					(thickness 0.1524)
				)
			)
		)
		(fp_text user "11"
			(at -28.690062 -31.335726 180)
			(unlocked yes)
			(layer "F.Fab")
			(effects
				(font
					(size 0.7874 0.5842)
					(thickness 0.1524)
				)
			)
		)
		(fp_text user "10"
			(at -29.565092 -32.276288 180)
			(unlocked yes)
			(layer "F.Fab")
			(effects
				(font
					(size 0.7874 0.5842)
					(thickness 0.1524)
				)
			)
		)
		(fp_text user "9"
			(at -30.407102 -31.335726 180)
			(unlocked yes)
			(layer "F.Fab")
			(effects
				(font
					(size 0.7874 0.5842)
					(thickness 0.1524)
				)
			)
		)
		(fp_text user "8"
			(at -31.282132 -32.276288 180)
			(unlocked yes)
			(layer "F.Fab")
			(effects
				(font
					(size 0.7874 0.5842)
					(thickness 0.1524)
				)
			)
		)
		(fp_text user "7"
			(at -32.124142 -31.335726 180)
			(unlocked yes)
			(layer "F.Fab")
			(effects
				(font
					(size 0.7874 0.5842)
					(thickness 0.1524)
				)
			)
		)
		(fp_text user "6"
			(at -32.999172 -32.276288 180)
			(unlocked yes)
			(layer "F.Fab")
			(effects
				(font
					(size 0.7874 0.5842)
					(thickness 0.1524)
				)
			)
		)
		(fp_text user "5"
			(at -33.841182 -31.335726 180)
			(unlocked yes)
			(layer "F.Fab")
			(effects
				(font
					(size 0.7874 0.5842)
					(thickness 0.1524)
				)
			)
		)
		(fp_text user "4"
			(at -34.716212 -32.276288 180)
			(unlocked yes)
			(layer "F.Fab")
			(effects
				(font
					(size 0.7874 0.5842)
					(thickness 0.1524)
				)
			)
		)
		(fp_text user "3"
			(at -35.558222 -31.335726 180)
			(unlocked yes)
			(layer "F.Fab")
			(effects
				(font
					(size 0.7874 0.5842)
					(thickness 0.1524)
				)
			)
		)
		(fp_text user "2"
			(at -36.433252 -32.276288 180)
			(unlocked yes)
			(layer "F.Fab")
			(effects
				(font
					(size 0.7874 0.5842)
					(thickness 0.1524)
				)
			)
		)
		(fp_text user "1"
			(at -37.275008 -31.335726 180)
			(unlocked yes)
			(layer "F.Fab")
			(effects
				(font
					(size 0.7874 0.5842)
					(thickness 0.1524)
				)
			)
		)
		(fp_text user "DW"
			(at -39.0652 23.349204 180)
			(unlocked yes)
			(layer "F.Fab")
			(effects
				(font
					(size 0.7874 0.5842)
					(thickness 0.1524)
				)
			)
		)
		(fp_text user "DU"
			(at -39.0652 22.358604 180)
			(unlocked yes)
			(layer "F.Fab")
			(effects
				(font
					(size 0.7874 0.5842)
					(thickness 0.1524)
				)
			)
		)
		(fp_text user "DR"
			(at -39.0652 21.368004 180)
			(unlocked yes)
			(layer "F.Fab")
			(effects
				(font
					(size 0.7874 0.5842)
					(thickness 0.1524)
				)
			)
		)
		(fp_text user "DN"
			(at -39.0652 20.377404 180)
			(unlocked yes)
			(layer "F.Fab")
			(effects
				(font
					(size 0.7874 0.5842)
					(thickness 0.1524)
				)
			)
		)
		(fp_text user "DL"
			(at -39.0652 19.386804 180)
			(unlocked yes)
			(layer "F.Fab")
			(effects
				(font
					(size 0.7874 0.5842)
					(thickness 0.1524)
				)
			)
		)
		(fp_text user "DJ"
			(at -39.0652 18.396204 180)
			(unlocked yes)
			(layer "F.Fab")
			(effects
				(font
					(size 0.7874 0.5842)
					(thickness 0.1524)
				)
			)
		)
		(fp_text user "DG"
			(at -39.0652 17.405604 180)
			(unlocked yes)
			(layer "F.Fab")
			(effects
				(font
					(size 0.7874 0.5842)
					(thickness 0.1524)
				)
			)
		)
		(fp_text user "DE"
			(at -39.0652 16.415004 180)
			(unlocked yes)
			(layer "F.Fab")
			(effects
				(font
					(size 0.7874 0.5842)
					(thickness 0.1524)
				)
			)
		)
		(fp_text user "DC"
			(at -39.0652 15.424404 180)
			(unlocked yes)
			(layer "F.Fab")
			(effects
				(font
					(size 0.7874 0.5842)
					(thickness 0.1524)
				)
			)
		)
		(fp_text user "DA"
			(at -39.0652 14.433804 180)
			(unlocked yes)
			(layer "F.Fab")
			(effects
				(font
					(size 0.7874 0.5842)
					(thickness 0.1524)
				)
			)
		)
		(fp_text user "CW"
			(at -39.0652 13.443204 180)
			(unlocked yes)
			(layer "F.Fab")
			(effects
				(font
					(size 0.7874 0.5842)
					(thickness 0.1524)
				)
			)
		)
		(fp_text user "CU"
			(at -39.0652 12.452604 180)
			(unlocked yes)
			(layer "F.Fab")
			(effects
				(font
					(size 0.7874 0.5842)
					(thickness 0.1524)
				)
			)
		)
		(fp_text user "CR"
			(at -39.0652 11.462004 180)
			(unlocked yes)
			(layer "F.Fab")
			(effects
				(font
					(size 0.7874 0.5842)
					(thickness 0.1524)
				)
			)
		)
		(fp_text user "CN"
			(at -39.0652 10.471404 180)
			(unlocked yes)
			(layer "F.Fab")
			(effects
				(font
					(size 0.7874 0.5842)
					(thickness 0.1524)
				)
			)
		)
		(fp_text user "CL"
			(at -39.0652 9.480804 180)
			(unlocked yes)
			(layer "F.Fab")
			(effects
				(font
					(size 0.7874 0.5842)
					(thickness 0.1524)
				)
			)
		)
		(fp_text user "CJ"
			(at -39.0652 8.490204 180)
			(unlocked yes)
			(layer "F.Fab")
			(effects
				(font
					(size 0.7874 0.5842)
					(thickness 0.1524)
				)
			)
		)
		(fp_text user "CG"
			(at -39.0652 7.499604 180)
			(unlocked yes)
			(layer "F.Fab")
			(effects
				(font
					(size 0.7874 0.5842)
					(thickness 0.1524)
				)
			)
		)
		(fp_text user "CE"
			(at -39.0652 6.509004 180)
			(unlocked yes)
			(layer "F.Fab")
			(effects
				(font
					(size 0.7874 0.5842)
					(thickness 0.1524)
				)
			)
		)
		(fp_text user "CC"
			(at -39.0652 5.518404 180)
			(unlocked yes)
			(layer "F.Fab")
			(effects
				(font
					(size 0.7874 0.5842)
					(thickness 0.1524)
				)
			)
		)
		(fp_text user "CA"
			(at -39.0652 4.527804 180)
			(unlocked yes)
			(layer "F.Fab")
			(effects
				(font
					(size 0.7874 0.5842)
					(thickness 0.1524)
				)
			)
		)
		(fp_text user "BW"
			(at -39.0652 3.537204 180)
			(unlocked yes)
			(layer "F.Fab")
			(effects
				(font
					(size 0.7874 0.5842)
					(thickness 0.1524)
				)
			)
		)
		(fp_text user "BU"
			(at -39.0652 2.546604 180)
			(unlocked yes)
			(layer "F.Fab")
			(effects
				(font
					(size 0.7874 0.5842)
					(thickness 0.1524)
				)
			)
		)
		(fp_text user "BR"
			(at -39.0652 1.556004 180)
			(unlocked yes)
			(layer "F.Fab")
			(effects
				(font
					(size 0.7874 0.5842)
					(thickness 0.1524)
				)
			)
		)
		(fp_text user "BN"
			(at -39.0652 0.565404 180)
			(unlocked yes)
			(layer "F.Fab")
			(effects
				(font
					(size 0.7874 0.5842)
					(thickness 0.1524)
				)
			)
		)
		(fp_text user "BL"
			(at -39.0652 -0.425196 180)
			(unlocked yes)
			(layer "F.Fab")
			(effects
				(font
					(size 0.7874 0.5842)
					(thickness 0.1524)
				)
			)
		)
		(fp_text user "BJ"
			(at -39.0652 -1.415796 180)
			(unlocked yes)
			(layer "F.Fab")
			(effects
				(font
					(size 0.7874 0.5842)
					(thickness 0.1524)
				)
			)
		)
		(fp_text user "BG"
			(at -39.0652 -2.406396 180)
			(unlocked yes)
			(layer "F.Fab")
			(effects
				(font
					(size 0.7874 0.5842)
					(thickness 0.1524)
				)
			)
		)
		(fp_text user "BE"
			(at -39.0652 -3.396996 180)
			(unlocked yes)
			(layer "F.Fab")
			(effects
				(font
					(size 0.7874 0.5842)
					(thickness 0.1524)
				)
			)
		)
		(fp_text user "BC"
			(at -39.0652 -4.387596 180)
			(unlocked yes)
			(layer "F.Fab")
			(effects
				(font
					(size 0.7874 0.5842)
					(thickness 0.1524)
				)
			)
		)
		(fp_text user "BA"
			(at -39.0652 -5.378196 180)
			(unlocked yes)
			(layer "F.Fab")
			(effects
				(font
					(size 0.7874 0.5842)
					(thickness 0.1524)
				)
			)
		)
		(fp_text user "AW"
			(at -39.0652 -6.368796 180)
			(unlocked yes)
			(layer "F.Fab")
			(effects
				(font
					(size 0.7874 0.5842)
					(thickness 0.1524)
				)
			)
		)
		(fp_text user "AU"
			(at -39.0652 -7.359396 180)
			(unlocked yes)
			(layer "F.Fab")
			(effects
				(font
					(size 0.7874 0.5842)
					(thickness 0.1524)
				)
			)
		)
		(fp_text user "AR"
			(at -39.0652 -8.349996 180)
			(unlocked yes)
			(layer "F.Fab")
			(effects
				(font
					(size 0.7874 0.5842)
					(thickness 0.1524)
				)
			)
		)
		(fp_text user "AN"
			(at -39.0652 -9.340596 180)
			(unlocked yes)
			(layer "F.Fab")
			(effects
				(font
					(size 0.7874 0.5842)
					(thickness 0.1524)
				)
			)
		)
		(fp_text user "AL"
			(at -39.0652 -10.331196 180)
			(unlocked yes)
			(layer "F.Fab")
			(effects
				(font
					(size 0.7874 0.5842)
					(thickness 0.1524)
				)
			)
		)
		(fp_text user "AJ"
			(at -39.0652 -11.321796 180)
			(unlocked yes)
			(layer "F.Fab")
			(effects
				(font
					(size 0.7874 0.5842)
					(thickness 0.1524)
				)
			)
		)
		(fp_text user "AG"
			(at -39.0652 -12.312396 180)
			(unlocked yes)
			(layer "F.Fab")
			(effects
				(font
					(size 0.7874 0.5842)
					(thickness 0.1524)
				)
			)
		)
		(fp_text user "AE"
			(at -39.0652 -13.302996 180)
			(unlocked yes)
			(layer "F.Fab")
			(effects
				(font
					(size 0.7874 0.5842)
					(thickness 0.1524)
				)
			)
		)
		(fp_text user "AC"
			(at -39.0652 -14.293596 180)
			(unlocked yes)
			(layer "F.Fab")
			(effects
				(font
					(size 0.7874 0.5842)
					(thickness 0.1524)
				)
			)
		)
		(fp_text user "AA"
			(at -39.0652 -15.284196 180)
			(unlocked yes)
			(layer "F.Fab")
			(effects
				(font
					(size 0.7874 0.5842)
					(thickness 0.1524)
				)
			)
		)
		(fp_text user "W"
			(at -39.0652 -16.274796 180)
			(unlocked yes)
			(layer "F.Fab")
			(effects
				(font
					(size 0.7874 0.5842)
					(thickness 0.1524)
				)
			)
		)
		(fp_text user "U"
			(at -39.0652 -17.265396 180)
			(unlocked yes)
			(layer "F.Fab")
			(effects
				(font
					(size 0.7874 0.5842)
					(thickness 0.1524)
				)
			)
		)
		(fp_text user "R"
			(at -39.0652 -18.255996 180)
			(unlocked yes)
			(layer "F.Fab")
			(effects
				(font
					(size 0.7874 0.5842)
					(thickness 0.1524)
				)
			)
		)
		(fp_text user "N"
			(at -39.0652 -19.246596 180)
			(unlocked yes)
			(layer "F.Fab")
			(effects
				(font
					(size 0.7874 0.5842)
					(thickness 0.1524)
				)
			)
		)
		(fp_text user "L"
			(at -39.0652 -20.237196 180)
			(unlocked yes)
			(layer "F.Fab")
			(effects
				(font
					(size 0.7874 0.5842)
					(thickness 0.1524)
				)
			)
		)
		(fp_text user "J"
			(at -39.0652 -21.227796 180)
			(unlocked yes)
			(layer "F.Fab")
			(effects
				(font
					(size 0.7874 0.5842)
					(thickness 0.1524)
				)
			)
		)
		(fp_text user "G"
			(at -39.0652 -22.218396 180)
			(unlocked yes)
			(layer "F.Fab")
			(effects
				(font
					(size 0.7874 0.5842)
					(thickness 0.1524)
				)
			)
		)
		(fp_text user "E"
			(at -39.0652 -23.208996 180)
			(unlocked yes)
			(layer "F.Fab")
			(effects
				(font
					(size 0.7874 0.5842)
					(thickness 0.1524)
				)
			)
		)
		(fp_text user "C"
			(at -39.0652 -24.199596 180)
			(unlocked yes)
			(layer "F.Fab")
			(effects
				(font
					(size 0.7874 0.5842)
					(thickness 0.1524)
				)
			)
		)
		(fp_text user "A"
			(at -39.0652 -25.190196 180)
			(unlocked yes)
			(layer "F.Fab")
			(effects
				(font
					(size 0.7874 0.5842)
					(thickness 0.1524)
				)
			)
		)
		(fp_text user "Y"
			(at -39.815008 -15.779496 180)
			(unlocked yes)
			(layer "F.Fab")
			(effects
				(font
					(size 0.7874 0.5842)
					(thickness 0.1524)
				)
			)
		)
		(fp_text user "V"
			(at -39.815008 -16.770096 180)
			(unlocked yes)
			(layer "F.Fab")
			(effects
				(font
					(size 0.7874 0.5842)
					(thickness 0.1524)
				)
			)
		)
		(fp_text user "T"
			(at -39.815008 -17.760696 180)
			(unlocked yes)
			(layer "F.Fab")
			(effects
				(font
					(size 0.7874 0.5842)
					(thickness 0.1524)
				)
			)
		)
		(fp_text user "P"
			(at -39.815008 -18.751296 180)
			(unlocked yes)
			(layer "F.Fab")
			(effects
				(font
					(size 0.7874 0.5842)
					(thickness 0.1524)
				)
			)
		)
		(fp_text user "M"
			(at -39.815008 -19.741896 180)
			(unlocked yes)
			(layer "F.Fab")
			(effects
				(font
					(size 0.7874 0.5842)
					(thickness 0.1524)
				)
			)
		)
		(fp_text user "K"
			(at -39.815008 -20.732496 180)
			(unlocked yes)
			(layer "F.Fab")
			(effects
				(font
					(size 0.7874 0.5842)
					(thickness 0.1524)
				)
			)
		)
		(fp_text user "H"
			(at -39.815008 -21.723096 180)
			(unlocked yes)
			(layer "F.Fab")
			(effects
				(font
					(size 0.7874 0.5842)
					(thickness 0.1524)
				)
			)
		)
		(fp_text user "F"
			(at -39.815008 -22.713696 180)
			(unlocked yes)
			(layer "F.Fab")
			(effects
				(font
					(size 0.7874 0.5842)
					(thickness 0.1524)
				)
			)
		)
		(fp_text user "D"
			(at -39.815008 -23.704296 180)
			(unlocked yes)
			(layer "F.Fab")
			(effects
				(font
					(size 0.7874 0.5842)
					(thickness 0.1524)
				)
			)
		)
		(fp_text user "B"
			(at -39.815008 -24.694896 180)
			(unlocked yes)
			(layer "F.Fab")
			(effects
				(font
					(size 0.7874 0.5842)
					(thickness 0.1524)
				)
			)
		)
		(fp_text user "DY"
			(at -40.462708 23.895558 180)
			(unlocked yes)
			(layer "F.Fab")
			(effects
				(font
					(size 0.7874 0.5842)
					(thickness 0.1524)
				)
			)
		)
		(fp_text user "DV"
			(at -40.462708 22.904958 180)
			(unlocked yes)
			(layer "F.Fab")
			(effects
				(font
					(size 0.7874 0.5842)
					(thickness 0.1524)
				)
			)
		)
		(fp_text user "DT"
			(at -40.462708 21.914358 180)
			(unlocked yes)
			(layer "F.Fab")
			(effects
				(font
					(size 0.7874 0.5842)
					(thickness 0.1524)
				)
			)
		)
		(fp_text user "DP"
			(at -40.462708 20.923758 180)
			(unlocked yes)
			(layer "F.Fab")
			(effects
				(font
					(size 0.7874 0.5842)
					(thickness 0.1524)
				)
			)
		)
		(fp_text user "DM"
			(at -40.462708 19.933158 180)
			(unlocked yes)
			(layer "F.Fab")
			(effects
				(font
					(size 0.7874 0.5842)
					(thickness 0.1524)
				)
			)
		)
		(fp_text user "DK"
			(at -40.462708 18.942558 180)
			(unlocked yes)
			(layer "F.Fab")
			(effects
				(font
					(size 0.7874 0.5842)
					(thickness 0.1524)
				)
			)
		)
		(fp_text user "DH"
			(at -40.462708 17.951958 180)
			(unlocked yes)
			(layer "F.Fab")
			(effects
				(font
					(size 0.7874 0.5842)
					(thickness 0.1524)
				)
			)
		)
		(fp_text user "DF"
			(at -40.462708 16.961358 180)
			(unlocked yes)
			(layer "F.Fab")
			(effects
				(font
					(size 0.7874 0.5842)
					(thickness 0.1524)
				)
			)
		)
		(fp_text user "DD"
			(at -40.462708 15.970758 180)
			(unlocked yes)
			(layer "F.Fab")
			(effects
				(font
					(size 0.7874 0.5842)
					(thickness 0.1524)
				)
			)
		)
		(fp_text user "DB"
			(at -40.462708 14.980158 180)
			(unlocked yes)
			(layer "F.Fab")
			(effects
				(font
					(size 0.7874 0.5842)
					(thickness 0.1524)
				)
			)
		)
		(fp_text user "CY"
			(at -40.462708 13.989558 180)
			(unlocked yes)
			(layer "F.Fab")
			(effects
				(font
					(size 0.7874 0.5842)
					(thickness 0.1524)
				)
			)
		)
		(fp_text user "CV"
			(at -40.462708 12.998958 180)
			(unlocked yes)
			(layer "F.Fab")
			(effects
				(font
					(size 0.7874 0.5842)
					(thickness 0.1524)
				)
			)
		)
		(fp_text user "CT"
			(at -40.462708 12.008358 180)
			(unlocked yes)
			(layer "F.Fab")
			(effects
				(font
					(size 0.7874 0.5842)
					(thickness 0.1524)
				)
			)
		)
		(fp_text user "CP"
			(at -40.462708 11.017758 180)
			(unlocked yes)
			(layer "F.Fab")
			(effects
				(font
					(size 0.7874 0.5842)
					(thickness 0.1524)
				)
			)
		)
		(fp_text user "CM"
			(at -40.462708 10.027158 180)
			(unlocked yes)
			(layer "F.Fab")
			(effects
				(font
					(size 0.7874 0.5842)
					(thickness 0.1524)
				)
			)
		)
		(fp_text user "CK"
			(at -40.462708 9.036558 180)
			(unlocked yes)
			(layer "F.Fab")
			(effects
				(font
					(size 0.7874 0.5842)
					(thickness 0.1524)
				)
			)
		)
		(fp_text user "CH"
			(at -40.462708 8.045958 180)
			(unlocked yes)
			(layer "F.Fab")
			(effects
				(font
					(size 0.7874 0.5842)
					(thickness 0.1524)
				)
			)
		)
		(fp_text user "CF"
			(at -40.462708 7.055358 180)
			(unlocked yes)
			(layer "F.Fab")
			(effects
				(font
					(size 0.7874 0.5842)
					(thickness 0.1524)
				)
			)
		)
		(fp_text user "CD"
			(at -40.462708 6.064758 180)
			(unlocked yes)
			(layer "F.Fab")
			(effects
				(font
					(size 0.7874 0.5842)
					(thickness 0.1524)
				)
			)
		)
		(fp_text user "CB"
			(at -40.462708 5.074158 180)
			(unlocked yes)
			(layer "F.Fab")
			(effects
				(font
					(size 0.7874 0.5842)
					(thickness 0.1524)
				)
			)
		)
		(fp_text user "BY"
			(at -40.462708 4.083558 180)
			(unlocked yes)
			(layer "F.Fab")
			(effects
				(font
					(size 0.7874 0.5842)
					(thickness 0.1524)
				)
			)
		)
		(fp_text user "BV"
			(at -40.462708 3.092958 180)
			(unlocked yes)
			(layer "F.Fab")
			(effects
				(font
					(size 0.7874 0.5842)
					(thickness 0.1524)
				)
			)
		)
		(fp_text user "BT"
			(at -40.462708 2.102358 180)
			(unlocked yes)
			(layer "F.Fab")
			(effects
				(font
					(size 0.7874 0.5842)
					(thickness 0.1524)
				)
			)
		)
		(fp_text user "BP"
			(at -40.462708 1.111758 180)
			(unlocked yes)
			(layer "F.Fab")
			(effects
				(font
					(size 0.7874 0.5842)
					(thickness 0.1524)
				)
			)
		)
		(fp_text user "BM"
			(at -40.462708 0.121158 180)
			(unlocked yes)
			(layer "F.Fab")
			(effects
				(font
					(size 0.7874 0.5842)
					(thickness 0.1524)
				)
			)
		)
		(fp_text user "BK"
			(at -40.462708 -0.869442 180)
			(unlocked yes)
			(layer "F.Fab")
			(effects
				(font
					(size 0.7874 0.5842)
					(thickness 0.1524)
				)
			)
		)
		(fp_text user "BH"
			(at -40.462708 -1.860042 180)
			(unlocked yes)
			(layer "F.Fab")
			(effects
				(font
					(size 0.7874 0.5842)
					(thickness 0.1524)
				)
			)
		)
		(fp_text user "BF"
			(at -40.462708 -2.850642 180)
			(unlocked yes)
			(layer "F.Fab")
			(effects
				(font
					(size 0.7874 0.5842)
					(thickness 0.1524)
				)
			)
		)
		(fp_text user "BD"
			(at -40.462708 -3.841242 180)
			(unlocked yes)
			(layer "F.Fab")
			(effects
				(font
					(size 0.7874 0.5842)
					(thickness 0.1524)
				)
			)
		)
		(fp_text user "BB"
			(at -40.462708 -4.831842 180)
			(unlocked yes)
			(layer "F.Fab")
			(effects
				(font
					(size 0.7874 0.5842)
					(thickness 0.1524)
				)
			)
		)
		(fp_text user "AY"
			(at -40.462708 -5.822442 180)
			(unlocked yes)
			(layer "F.Fab")
			(effects
				(font
					(size 0.7874 0.5842)
					(thickness 0.1524)
				)
			)
		)
		(fp_text user "AV"
			(at -40.462708 -6.813042 180)
			(unlocked yes)
			(layer "F.Fab")
			(effects
				(font
					(size 0.7874 0.5842)
					(thickness 0.1524)
				)
			)
		)
		(fp_text user "AT"
			(at -40.462708 -7.803642 180)
			(unlocked yes)
			(layer "F.Fab")
			(effects
				(font
					(size 0.7874 0.5842)
					(thickness 0.1524)
				)
			)
		)
		(fp_text user "AP"
			(at -40.462708 -8.794242 180)
			(unlocked yes)
			(layer "F.Fab")
			(effects
				(font
					(size 0.7874 0.5842)
					(thickness 0.1524)
				)
			)
		)
		(fp_text user "AM"
			(at -40.462708 -9.784842 180)
			(unlocked yes)
			(layer "F.Fab")
			(effects
				(font
					(size 0.7874 0.5842)
					(thickness 0.1524)
				)
			)
		)
		(fp_text user "AK"
			(at -40.462708 -10.775442 180)
			(unlocked yes)
			(layer "F.Fab")
			(effects
				(font
					(size 0.7874 0.5842)
					(thickness 0.1524)
				)
			)
		)
		(fp_text user "AH"
			(at -40.462708 -11.766042 180)
			(unlocked yes)
			(layer "F.Fab")
			(effects
				(font
					(size 0.7874 0.5842)
					(thickness 0.1524)
				)
			)
		)
		(fp_text user "AF"
			(at -40.462708 -12.756642 180)
			(unlocked yes)
			(layer "F.Fab")
			(effects
				(font
					(size 0.7874 0.5842)
					(thickness 0.1524)
				)
			)
		)
		(fp_text user "AD"
			(at -40.462708 -13.747242 180)
			(unlocked yes)
			(layer "F.Fab")
			(effects
				(font
					(size 0.7874 0.5842)
					(thickness 0.1524)
				)
			)
		)
		(fp_text user "AB"
			(at -40.462708 -14.737842 180)
			(unlocked yes)
			(layer "F.Fab")
			(effects
				(font
					(size 0.7874 0.5842)
					(thickness 0.1524)
				)
			)
		)
		(pad "A4" smd custom
			(at -34.675064 -25.103074 45)
			(size 0.10795 0.10795)
			(layers "F.Cu" "F.Mask" "F.Paste")
			(net "TP_CPU0_RSVD_304")
			(options
				(clearance outline)
				(anchor circle)
			)
			(primitives
				(gr_poly
					(pts
						(arc
							(start 0.2159 -0.0381)
							(mid 0 -0.254)
							(end -0.2159 -0.0381)
						)
						(arc
							(start -0.2159 0.0381)
							(mid 0 0.254)
							(end 0.2159 0.0381)
						)
					)
					(width 0)
					(fill yes)
				)
			)
		)
		(pad "A6" smd custom
			(at -32.958024 -25.103074 45)
			(size 0.10795 0.10795)
			(layers "F.Cu" "F.Mask" "F.Paste")
			(net "TP_CPU0_RSVD_303")
			(options
				(clearance outline)
				(anchor circle)
			)
			(primitives
				(gr_poly
					(pts
						(arc
							(start 0.2159 -0.0381)
							(mid 0 -0.254)
							(end -0.2159 -0.0381)
						)
						(arc
							(start -0.2159 0.0381)
							(mid 0 0.254)
							(end 0.2159 0.0381)
						)
					)
					(width 0)
					(fill yes)
				)
			)
		)
		(pad "A8" smd custom
			(at -31.240984 -25.103074)
			(size 0.10795 0.10795)
			(layers "F.Cu" "F.Mask" "F.Paste")
			(net "PVPP_ABC")
			(options
				(clearance outline)
				(anchor circle)
			)
			(primitives
				(gr_poly
					(pts
						(arc
							(start 0.2159 -0.0381)
							(mid 0 -0.254)
							(end -0.2159 -0.0381)
						)
						(arc
							(start -0.2159 0.0381)
							(mid 0 0.254)
							(end 0.2159 0.0381)
						)
					)
					(width 0)
					(fill yes)
				)
			)
		)
		(pad "A10" smd custom
			(at -29.523944 -25.103074)
			(size 0.10795 0.10795)
			(layers "F.Cu" "F.Mask" "F.Paste")
			(net "PVPP_ABC")
			(options
				(clearance outline)
				(anchor circle)
			)
			(primitives
				(gr_poly
					(pts
						(arc
							(start 0.2159 -0.0381)
							(mid 0 -0.254)
							(end -0.2159 -0.0381)
						)
						(arc
							(start -0.2159 0.0381)
							(mid 0 0.254)
							(end 0.2159 0.0381)
						)
					)
					(width 0)
					(fill yes)
				)
			)
		)
		(pad "A12" smd custom
			(at -27.806904 -25.103074)
			(size 0.10795 0.10795)
			(layers "F.Cu" "F.Mask" "F.Paste")
			(net "PVPP_ABC")
			(options
				(clearance outline)
				(anchor circle)
			)
			(primitives
				(gr_poly
					(pts
						(arc
							(start 0.2159 -0.0381)
							(mid 0 -0.254)
							(end -0.2159 -0.0381)
						)
						(arc
							(start -0.2159 0.0381)
							(mid 0 0.254)
							(end 0.2159 0.0381)
						)
					)
					(width 0)
					(fill yes)
				)
			)
		)
		(pad "A14" smd custom
			(at -26.090118 -25.103074)
			(size 0.10795 0.10795)
			(layers "F.Cu" "F.Mask" "F.Paste")
			(net "P1V8_MCP_CPU0")
			(options
				(clearance outline)
				(anchor circle)
			)
			(primitives
				(gr_poly
					(pts
						(arc
							(start 0.2159 -0.0381)
							(mid 0 -0.254)
							(end -0.2159 -0.0381)
						)
						(arc
							(start -0.2159 0.0381)
							(mid 0 0.254)
							(end 0.2159 0.0381)
						)
					)
					(width 0)
					(fill yes)
				)
			)
		)
		(pad "A16" smd custom
			(at -24.373078 -25.103074)
			(size 0.10795 0.10795)
			(layers "F.Cu" "F.Mask" "F.Paste")
			(net "P1V8_MCP_CPU0")
			(options
				(clearance outline)
				(anchor circle)
			)
			(primitives
				(gr_poly
					(pts
						(arc
							(start 0.2159 -0.0381)
							(mid 0 -0.254)
							(end -0.2159 -0.0381)
						)
						(arc
							(start -0.2159 0.0381)
							(mid 0 0.254)
							(end 0.2159 0.0381)
						)
					)
					(width 0)
					(fill yes)
				)
			)
		)
		(pad "A24" smd custom
			(at -17.504918 -25.103074)
			(size 0.10795 0.10795)
			(layers "F.Cu" "F.Mask" "F.Paste")
			(net "TP_CPU0_RSVD_300")
			(options
				(clearance outline)
				(anchor circle)
			)
			(primitives
				(gr_poly
					(pts
						(arc
							(start 0.2159 -0.0381)
							(mid 0 -0.254)
							(end -0.2159 -0.0381)
						)
						(arc
							(start -0.2159 0.0381)
							(mid 0 0.254)
							(end 0.2159 0.0381)
						)
					)
					(width 0)
					(fill yes)
				)
			)
		)
		(pad "A26" smd custom
			(at -15.787878 -25.103074)
			(size 0.10795 0.10795)
			(layers "F.Cu" "F.Mask" "F.Paste")
			(net "GND")
			(options
				(clearance outline)
				(anchor circle)
			)
			(primitives
				(gr_poly
					(pts
						(arc
							(start 0.2159 -0.0381)
							(mid 0 -0.254)
							(end -0.2159 -0.0381)
						)
						(arc
							(start -0.2159 0.0381)
							(mid 0 0.254)
							(end 0.2159 0.0381)
						)
					)
					(width 0)
					(fill yes)
				)
			)
		)
		(pad "A28" smd custom
			(at -14.071092 -25.103074)
			(size 0.10795 0.10795)
			(layers "F.Cu" "F.Mask" "F.Paste")
			(net "M_B_DQS_DN<15>")
			(options
				(clearance outline)
				(anchor circle)
			)
			(primitives
				(gr_poly
					(pts
						(arc
							(start 0.2159 -0.0381)
							(mid 0 -0.254)
							(end -0.2159 -0.0381)
						)
						(arc
							(start -0.2159 0.0381)
							(mid 0 0.254)
							(end 0.2159 0.0381)
						)
					)
					(width 0)
					(fill yes)
				)
			)
		)
		(pad "A30" smd custom
			(at -12.354052 -25.103074)
			(size 0.10795 0.10795)
			(layers "F.Cu" "F.Mask" "F.Paste")
			(net "GND")
			(options
				(clearance outline)
				(anchor circle)
			)
			(primitives
				(gr_poly
					(pts
						(arc
							(start 0.2159 -0.0381)
							(mid 0 -0.254)
							(end -0.2159 -0.0381)
						)
						(arc
							(start -0.2159 0.0381)
							(mid 0 0.254)
							(end 0.2159 0.0381)
						)
					)
					(width 0)
					(fill yes)
				)
			)
		)
		(pad "A32" smd custom
			(at -10.637012 -25.103074)
			(size 0.10795 0.10795)
			(layers "F.Cu" "F.Mask" "F.Paste")
			(net "GND")
			(options
				(clearance outline)
				(anchor circle)
			)
			(primitives
				(gr_poly
					(pts
						(arc
							(start 0.2159 -0.0381)
							(mid 0 -0.254)
							(end -0.2159 -0.0381)
						)
						(arc
							(start -0.2159 0.0381)
							(mid 0 0.254)
							(end 0.2159 0.0381)
						)
					)
					(width 0)
					(fill yes)
				)
			)
		)
		(pad "A34" smd custom
			(at -8.919972 -25.103074)
			(size 0.10795 0.10795)
			(layers "F.Cu" "F.Mask" "F.Paste")
			(net "M_B_DQS_DN<14>")
			(options
				(clearance outline)
				(anchor circle)
			)
			(primitives
				(gr_poly
					(pts
						(arc
							(start 0.2159 -0.0381)
							(mid 0 -0.254)
							(end -0.2159 -0.0381)
						)
						(arc
							(start -0.2159 0.0381)
							(mid 0 0.254)
							(end 0.2159 0.0381)
						)
					)
					(width 0)
					(fill yes)
				)
			)
		)
		(pad "A36" smd custom
			(at -7.202932 -25.103074)
			(size 0.10795 0.10795)
			(layers "F.Cu" "F.Mask" "F.Paste")
			(net "GND")
			(options
				(clearance outline)
				(anchor circle)
			)
			(primitives
				(gr_poly
					(pts
						(arc
							(start 0.2159 -0.0381)
							(mid 0 -0.254)
							(end -0.2159 -0.0381)
						)
						(arc
							(start -0.2159 0.0381)
							(mid 0 0.254)
							(end 0.2159 0.0381)
						)
					)
					(width 0)
					(fill yes)
				)
			)
		)
		(pad "A38" smd custom
			(at -5.485892 -25.103074)
			(size 0.10795 0.10795)
			(layers "F.Cu" "F.Mask" "F.Paste")
			(net "GND")
			(options
				(clearance outline)
				(anchor circle)
			)
			(primitives
				(gr_poly
					(pts
						(arc
							(start 0.2159 -0.0381)
							(mid 0 -0.254)
							(end -0.2159 -0.0381)
						)
						(arc
							(start -0.2159 0.0381)
							(mid 0 0.254)
							(end 0.2159 0.0381)
						)
					)
					(width 0)
					(fill yes)
				)
			)
		)
		(pad "A40" smd custom
			(at -3.769106 -25.103074)
			(size 0.10795 0.10795)
			(layers "F.Cu" "F.Mask" "F.Paste")
			(net "M_A_DQS_DN<13>")
			(options
				(clearance outline)
				(anchor circle)
			)
			(primitives
				(gr_poly
					(pts
						(arc
							(start 0.2159 -0.0381)
							(mid 0 -0.254)
							(end -0.2159 -0.0381)
						)
						(arc
							(start -0.2159 0.0381)
							(mid 0 0.254)
							(end 0.2159 0.0381)
						)
					)
					(width 0)
					(fill yes)
				)
			)
		)
		(pad "A42" smd custom
			(at -2.052066 -25.103074 315)
			(size 0.10795 0.10795)
			(layers "F.Cu" "F.Mask" "F.Paste")
			(net "GND")
			(options
				(clearance outline)
				(anchor circle)
			)
			(primitives
				(gr_poly
					(pts
						(arc
							(start 0.2159 -0.0381)
							(mid 0 -0.254)
							(end -0.2159 -0.0381)
						)
						(arc
							(start -0.2159 0.0381)
							(mid 0 0.254)
							(end 0.2159 0.0381)
						)
					)
					(width 0)
					(fill yes)
				)
			)
		)
		(pad "AA2" smd circle
			(at -36.392104 -15.197074)
			(size 0.4318 0.4318)
			(layers "F.Cu" "F.Mask" "F.Paste")
			(net "UPI_CPU0_CPU1_P0P0_DP<15>")
		)
		(pad "AA4" smd circle
			(at -34.675064 -15.197074)
			(size 0.4318 0.4318)
			(layers "F.Cu" "F.Mask" "F.Paste")
			(net "GND")
		)
		(pad "AA6" smd circle
			(at -32.958024 -15.197074)
			(size 0.4318 0.4318)
			(layers "F.Cu" "F.Mask" "F.Paste")
			(net "UPI_CPU1_CPU0_P0P0_DP<17>")
		)
		(pad "AA8" smd circle
			(at -31.240984 -15.197074)
			(size 0.4318 0.4318)
			(layers "F.Cu" "F.Mask" "F.Paste")
			(net "UPI_CPU1_CPU0_P0P0_DN<18>")
		)
		(pad "AA10" smd circle
			(at -29.523944 -15.197074)
			(size 0.4318 0.4318)
			(layers "F.Cu" "F.Mask" "F.Paste")
			(net "PVCCIO_CPU0")
		)
		(pad "AA12" smd circle
			(at -27.806904 -15.197074)
			(size 0.4318 0.4318)
			(layers "F.Cu" "F.Mask" "F.Paste")
			(net "TP_XDP_CPU0_OBSDATA_A2_MBP4_N")
		)
		(pad "AA14" smd circle
			(at -26.090118 -15.197074)
			(size 0.4318 0.4318)
			(layers "F.Cu" "F.Mask" "F.Paste")
			(net "XDP_CPU_TCK0")
		)
		(pad "AA16" smd circle
			(at -24.373078 -15.197074)
			(size 0.4318 0.4318)
			(layers "F.Cu" "F.Mask" "F.Paste")
			(net "GND")
		)
		(pad "AA18" smd circle
			(at -22.656038 -15.197074)
			(size 0.4318 0.4318)
			(layers "F.Cu" "F.Mask" "F.Paste")
			(net "GND")
		)
		(pad "AA20" smd circle
			(at -20.938998 -15.197074)
			(size 0.4318 0.4318)
			(layers "F.Cu" "F.Mask" "F.Paste")
			(net "UPI_CPU1_CPU0_P1P1_DP<0>")
		)
		(pad "AA22" smd circle
			(at -19.221958 -15.197074)
			(size 0.4318 0.4318)
			(layers "F.Cu" "F.Mask" "F.Paste")
			(net "GND")
		)
		(pad "AA24" smd circle
			(at -17.504918 -15.197074)
			(size 0.4318 0.4318)
			(layers "F.Cu" "F.Mask" "F.Paste")
			(net "GND")
		)
		(pad "AA26" smd circle
			(at -15.787878 -15.197074)
			(size 0.4318 0.4318)
			(layers "F.Cu" "F.Mask" "F.Paste")
			(net "M_B_DQ<63>")
		)
		(pad "AA28" smd circle
			(at -14.071092 -15.197074)
			(size 0.4318 0.4318)
			(layers "F.Cu" "F.Mask" "F.Paste")
			(net "M_B_DQ<57>")
		)
		(pad "AA30" smd circle
			(at -12.354052 -15.197074)
			(size 0.4318 0.4318)
			(layers "F.Cu" "F.Mask" "F.Paste")
			(net "GND")
		)
		(pad "AA32" smd circle
			(at -10.637012 -15.197074)
			(size 0.4318 0.4318)
			(layers "F.Cu" "F.Mask" "F.Paste")
			(net "M_C_DQ<47>")
		)
		(pad "AA34" smd circle
			(at -8.919972 -15.197074)
			(size 0.4318 0.4318)
			(layers "F.Cu" "F.Mask" "F.Paste")
			(net "M_C_DQ<41>")
		)
		(pad "AA36" smd circle
			(at -7.202932 -15.197074)
			(size 0.4318 0.4318)
			(layers "F.Cu" "F.Mask" "F.Paste")
			(net "GND")
		)
		(pad "AA38" smd circle
			(at -5.485892 -15.197074)
			(size 0.4318 0.4318)
			(layers "F.Cu" "F.Mask" "F.Paste")
			(net "M_C_DQ<39>")
		)
		(pad "AA40" smd circle
			(at -3.769106 -15.197074)
			(size 0.4318 0.4318)
			(layers "F.Cu" "F.Mask" "F.Paste")
			(net "M_C_DQ<33>")
		)
		(pad "AA42" smd circle
			(at -2.052066 -15.197074)
			(size 0.4318 0.4318)
			(layers "F.Cu" "F.Mask" "F.Paste")
			(net "GND")
		)
		(pad "AA46" smd circle
			(at 2.910586 -16.997172)
			(size 0.4318 0.4318)
			(layers "F.Cu" "F.Mask" "F.Paste")
			(net "M_C_CS_N<3>")
		)
		(pad "AA48" smd circle
			(at 4.627626 -16.997172)
			(size 0.4318 0.4318)
			(layers "F.Cu" "F.Mask" "F.Paste")
			(net "M_C_ODT<1>")
		)
		(pad "AA50" smd circle
			(at 6.344412 -16.997172)
			(size 0.4318 0.4318)
			(layers "F.Cu" "F.Mask" "F.Paste")
			(net "M_C_ODT<0>")
		)
		(pad "AA52" smd circle
			(at 8.061452 -16.997172)
			(size 0.4318 0.4318)
			(layers "F.Cu" "F.Mask" "F.Paste")
			(net "M_C_MA<16>")
		)
		(pad "AA54" smd circle
			(at 9.778492 -16.997172)
			(size 0.4318 0.4318)
			(layers "F.Cu" "F.Mask" "F.Paste")
			(net "M_C_CLK_DN<0>")
		)
		(pad "AA56" smd circle
			(at 11.495532 -16.997172)
			(size 0.4318 0.4318)
			(layers "F.Cu" "F.Mask" "F.Paste")
			(net "M_C_CLK_DN<2>")
		)
		(pad "AA58" smd circle
			(at 13.212572 -16.997172)
			(size 0.4318 0.4318)
			(layers "F.Cu" "F.Mask" "F.Paste")
			(net "M_C_MA<4>")
		)
		(pad "AA60" smd circle
			(at 14.929612 -16.997172)
			(size 0.4318 0.4318)
			(layers "F.Cu" "F.Mask" "F.Paste")
			(net "M_C_BG<0>")
		)
		(pad "AA62" smd circle
			(at 16.646398 -16.997172)
			(size 0.4318 0.4318)
			(layers "F.Cu" "F.Mask" "F.Paste")
			(net "M_C_CKE<0>")
		)
		(pad "AA64" smd circle
			(at 18.363438 -16.997172)
			(size 0.4318 0.4318)
			(layers "F.Cu" "F.Mask" "F.Paste")
			(net "GND")
		)
		(pad "AA66" smd circle
			(at 20.080478 -16.997172)
			(size 0.4318 0.4318)
			(layers "F.Cu" "F.Mask" "F.Paste")
			(net "GND")
		)
		(pad "AA68" smd circle
			(at 21.797518 -16.997172)
			(size 0.4318 0.4318)
			(layers "F.Cu" "F.Mask" "F.Paste")
			(net "GND")
		)
		(pad "AA70" smd circle
			(at 23.514558 -16.997172)
			(size 0.4318 0.4318)
			(layers "F.Cu" "F.Mask" "F.Paste")
			(net "M_C_DQ<17>")
		)
		(pad "AA72" smd circle
			(at 25.231598 -16.997172)
			(size 0.4318 0.4318)
			(layers "F.Cu" "F.Mask" "F.Paste")
			(net "M_C_DQ<20>")
		)
		(pad "AA74" smd circle
			(at 26.948384 -16.997172)
			(size 0.4318 0.4318)
			(layers "F.Cu" "F.Mask" "F.Paste")
			(net "M_C_DQS_DN<1>")
		)
		(pad "AA76" smd circle
			(at 28.665424 -16.997172)
			(size 0.4318 0.4318)
			(layers "F.Cu" "F.Mask" "F.Paste")
			(net "GND")
		)
		(pad "AA78" smd circle
			(at 30.382464 -16.997172)
			(size 0.4318 0.4318)
			(layers "F.Cu" "F.Mask" "F.Paste")
			(net "GND")
		)
		(pad "AA80" smd circle
			(at 32.099504 -16.997172)
			(size 0.4318 0.4318)
			(layers "F.Cu" "F.Mask" "F.Paste")
			(net "GND")
		)
		(pad "AA82" smd circle
			(at 33.816544 -16.997172)
			(size 0.4318 0.4318)
			(layers "F.Cu" "F.Mask" "F.Paste")
			(net "GND")
		)
		(pad "AA84" smd circle
			(at 35.533584 -16.997172)
			(size 0.4318 0.4318)
			(layers "F.Cu" "F.Mask" "F.Paste")
			(net "M_A_DQ<13>")
		)
		(pad "AA86" smd custom
			(at 37.250624 -16.997172 270)
			(size 0.10795 0.10795)
			(layers "F.Cu" "F.Mask" "F.Paste")
			(net "M_A_DQ<12>")
			(options
				(clearance outline)
				(anchor circle)
			)
			(primitives
				(gr_poly
					(pts
						(arc
							(start 0.2159 -0.0381)
							(mid 0 -0.254)
							(end -0.2159 -0.0381)
						)
						(arc
							(start -0.2159 0.0381)
							(mid 0 0.254)
							(end 0.2159 0.0381)
						)
					)
					(width 0)
					(fill yes)
				)
			)
		)
		(pad "AB1" smd custom
			(at -37.250624 -14.702028 90)
			(size 0.10795 0.10795)
			(layers "F.Cu" "F.Mask" "F.Paste")
			(net "GND")
			(options
				(clearance outline)
				(anchor circle)
			)
			(primitives
				(gr_poly
					(pts
						(arc
							(start 0.2159 -0.0381)
							(mid 0 -0.254)
							(end -0.2159 -0.0381)
						)
						(arc
							(start -0.2159 0.0381)
							(mid 0 0.254)
							(end 0.2159 0.0381)
						)
					)
					(width 0)
					(fill yes)
				)
			)
		)
		(pad "AB3" smd circle
			(at -35.533584 -14.702028)
			(size 0.4318 0.4318)
			(layers "F.Cu" "F.Mask" "F.Paste")
			(net "UPI_CPU0_CPU1_P0P0_DN<15>")
		)
		(pad "AB5" smd circle
			(at -33.816544 -14.702028)
			(size 0.4318 0.4318)
			(layers "F.Cu" "F.Mask" "F.Paste")
			(net "GND")
		)
		(pad "AB7" smd circle
			(at -32.099504 -14.702028)
			(size 0.4318 0.4318)
			(layers "F.Cu" "F.Mask" "F.Paste")
			(net "UPI_CPU1_CPU0_P0P0_DN<17>")
		)
		(pad "AB9" smd circle
			(at -30.382464 -14.702028)
			(size 0.4318 0.4318)
			(layers "F.Cu" "F.Mask" "F.Paste")
			(net "UPI_CPU1_CPU0_P0P0_DP<19>")
		)
		(pad "AB11" smd circle
			(at -28.665424 -14.702028)
			(size 0.4318 0.4318)
			(layers "F.Cu" "F.Mask" "F.Paste")
			(net "GND")
		)
		(pad "AB13" smd circle
			(at -26.948384 -14.702028)
			(size 0.4318 0.4318)
			(layers "F.Cu" "F.Mask" "F.Paste")
			(net "FM_CPU0_SKTOCC_LVT3_N")
		)
		(pad "AB15" smd circle
			(at -25.231598 -14.702028)
			(size 0.4318 0.4318)
			(layers "F.Cu" "F.Mask" "F.Paste")
			(net "H_CPU0_THERMTRIP_G_N")
		)
		(pad "AB17" smd circle
			(at -23.514558 -14.702028)
			(size 0.4318 0.4318)
			(layers "F.Cu" "F.Mask" "F.Paste")
			(net "TP_CPU0_PROCDIS_G_N")
		)
		(pad "AB19" smd circle
			(at -21.797518 -14.702028)
			(size 0.4318 0.4318)
			(layers "F.Cu" "F.Mask" "F.Paste")
			(net "UPI_CPU1_CPU0_P1P1_DN<0>")
		)
		(pad "AB21" smd circle
			(at -20.080478 -14.702028)
			(size 0.4318 0.4318)
			(layers "F.Cu" "F.Mask" "F.Paste")
			(net "GND")
		)
		(pad "AB23" smd circle
			(at -18.363438 -14.702028)
			(size 0.4318 0.4318)
			(layers "F.Cu" "F.Mask" "F.Paste")
			(net "GND")
		)
		(pad "AB25" smd circle
			(at -16.646398 -14.702028)
			(size 0.4318 0.4318)
			(layers "F.Cu" "F.Mask" "F.Paste")
			(net "GND")
		)
		(pad "AB27" smd circle
			(at -14.929612 -14.702028)
			(size 0.4318 0.4318)
			(layers "F.Cu" "F.Mask" "F.Paste")
			(net "M_B_DQS_DN<7>")
		)
		(pad "AB29" smd circle
			(at -13.212572 -14.702028)
			(size 0.4318 0.4318)
			(layers "F.Cu" "F.Mask" "F.Paste")
			(net "GND")
		)
		(pad "AB31" smd circle
			(at -11.495532 -14.702028)
			(size 0.4318 0.4318)
			(layers "F.Cu" "F.Mask" "F.Paste")
			(net "GND")
		)
		(pad "AB33" smd circle
			(at -9.778492 -14.702028)
			(size 0.4318 0.4318)
			(layers "F.Cu" "F.Mask" "F.Paste")
			(net "M_C_DQS_DN<5>")
		)
		(pad "AB35" smd circle
			(at -8.061452 -14.702028)
			(size 0.4318 0.4318)
			(layers "F.Cu" "F.Mask" "F.Paste")
			(net "GND")
		)
		(pad "AB37" smd circle
			(at -6.344412 -14.702028)
			(size 0.4318 0.4318)
			(layers "F.Cu" "F.Mask" "F.Paste")
			(net "GND")
		)
		(pad "AB39" smd circle
			(at -4.627626 -14.702028)
			(size 0.4318 0.4318)
			(layers "F.Cu" "F.Mask" "F.Paste")
			(net "M_C_DQS_DN<4>")
		)
		(pad "AB41" smd circle
			(at -2.910586 -14.702028)
			(size 0.4318 0.4318)
			(layers "F.Cu" "F.Mask" "F.Paste")
			(net "GND")
		)
		(pad "AB43" smd circle
			(at -1.193546 -14.702028)
			(size 0.4318 0.4318)
			(layers "F.Cu" "F.Mask" "F.Paste")
			(net "A_CPU0_ABC_RCOMP1")
		)
		(pad "AB45" smd circle
			(at 2.052066 -16.502126)
			(size 0.508 0.508)
			(layers "F.Cu" "F.Mask" "F.Paste")
			(net "M_C_C<2>")
		)
		(pad "AB47" smd circle
			(at 3.769106 -16.502126)
			(size 0.4318 0.4318)
			(layers "F.Cu" "F.Mask" "F.Paste")
			(net "M_C_ODT<3>")
		)
		(pad "AB49" smd circle
			(at 5.485892 -16.502126)
			(size 0.4318 0.4318)
			(layers "F.Cu" "F.Mask" "F.Paste")
			(net "M_C_CS_N<1>")
		)
		(pad "AB51" smd circle
			(at 7.202932 -16.502126)
			(size 0.4318 0.4318)
			(layers "F.Cu" "F.Mask" "F.Paste")
			(net "M_C_CS_N<4>")
		)
		(pad "AB53" smd circle
			(at 8.919972 -16.502126)
			(size 0.4318 0.4318)
			(layers "F.Cu" "F.Mask" "F.Paste")
			(net "M_C_MA<0>")
		)
		(pad "AB55" smd circle
			(at 10.637012 -16.502126)
			(size 0.4318 0.4318)
			(layers "F.Cu" "F.Mask" "F.Paste")
			(net "M_C_CLK_DP<0>")
		)
		(pad "AB57" smd circle
			(at 12.354052 -16.502126)
			(size 0.4318 0.4318)
			(layers "F.Cu" "F.Mask" "F.Paste")
			(net "M_C_CLK_DP<2>")
		)
		(pad "AB59" smd circle
			(at 14.071092 -16.502126)
			(size 0.4318 0.4318)
			(layers "F.Cu" "F.Mask" "F.Paste")
			(net "M_C_MA<6>")
		)
		(pad "AB61" smd circle
			(at 15.787878 -16.502126)
			(size 0.4318 0.4318)
			(layers "F.Cu" "F.Mask" "F.Paste")
			(net "M_C_ACT_N")
		)
		(pad "AB63" smd circle
			(at 17.504918 -16.502126)
			(size 0.4318 0.4318)
			(layers "F.Cu" "F.Mask" "F.Paste")
			(net "M_C_CKE<3>")
		)
		(pad "AB65" smd circle
			(at 19.221958 -16.502126)
			(size 0.4318 0.4318)
			(layers "F.Cu" "F.Mask" "F.Paste")
			(net "GND")
		)
		(pad "AB67" smd circle
			(at 20.938998 -16.502126)
			(size 0.4318 0.4318)
			(layers "F.Cu" "F.Mask" "F.Paste")
			(net "M_A_DQS_DN<17>")
		)
		(pad "AB69" smd circle
			(at 22.656038 -16.502126)
			(size 0.4318 0.4318)
			(layers "F.Cu" "F.Mask" "F.Paste")
			(net "GND")
		)
		(pad "AB71" smd circle
			(at 24.373078 -16.502126)
			(size 0.4318 0.4318)
			(layers "F.Cu" "F.Mask" "F.Paste")
			(net "M_C_DQ<21>")
		)
		(pad "AB73" smd circle
			(at 26.090118 -16.502126)
			(size 0.4318 0.4318)
			(layers "F.Cu" "F.Mask" "F.Paste")
			(net "GND")
		)
		(pad "AB75" smd circle
			(at 27.806904 -16.502126)
			(size 0.4318 0.4318)
			(layers "F.Cu" "F.Mask" "F.Paste")
			(net "M_C_DQS_DP<1>")
		)
		(pad "AB77" smd circle
			(at 29.523944 -16.502126)
			(size 0.4318 0.4318)
			(layers "F.Cu" "F.Mask" "F.Paste")
			(net "M_C_DQ<14>")
		)
		(pad "AB79" smd circle
			(at 31.240984 -16.502126)
			(size 0.4318 0.4318)
			(layers "F.Cu" "F.Mask" "F.Paste")
			(net "GND")
		)
		(pad "AB81" smd circle
			(at 32.958024 -16.502126)
			(size 0.4318 0.4318)
			(layers "F.Cu" "F.Mask" "F.Paste")
			(net "M_B_DQ<11>")
		)
		(pad "AB83" smd circle
			(at 34.675064 -16.502126)
			(size 0.4318 0.4318)
			(layers "F.Cu" "F.Mask" "F.Paste")
			(net "GND")
		)
		(pad "AB85" smd circle
			(at 36.392104 -16.502126)
			(size 0.4318 0.4318)
			(layers "F.Cu" "F.Mask" "F.Paste")
			(net "GND")
		)
		(pad "AC2" smd circle
			(at -36.392104 -14.206474)
			(size 0.4318 0.4318)
			(layers "F.Cu" "F.Mask" "F.Paste")
			(net "UPI_CPU0_CPU1_P0P0_DN<14>")
		)
		(pad "AC4" smd circle
			(at -34.675064 -14.206474)
			(size 0.4318 0.4318)
			(layers "F.Cu" "F.Mask" "F.Paste")
			(net "PVCCIO_CPU0")
		)
		(pad "AC6" smd circle
			(at -32.958024 -14.206474)
			(size 0.4318 0.4318)
			(layers "F.Cu" "F.Mask" "F.Paste")
			(net "UPI_CPU1_CPU0_P0P0_DP<16>")
		)
		(pad "AC8" smd circle
			(at -31.240984 -14.206474)
			(size 0.4318 0.4318)
			(layers "F.Cu" "F.Mask" "F.Paste")
			(net "UPI_CPU1_CPU0_P0P0_DP<18>")
		)
		(pad "AC10" smd circle
			(at -29.523944 -14.206474)
			(size 0.4318 0.4318)
			(layers "F.Cu" "F.Mask" "F.Paste")
			(net "UPI_CPU1_CPU0_P0P0_DN<19>")
		)
		(pad "AC12" smd circle
			(at -27.806904 -14.206474)
			(size 0.4318 0.4318)
			(layers "F.Cu" "F.Mask" "F.Paste")
			(net "XDP_CPU_OBSFN_B1_MBP7_N")
		)
		(pad "AC14" smd circle
			(at -26.090118 -14.206474)
			(size 0.4318 0.4318)
			(layers "F.Cu" "F.Mask" "F.Paste")
			(net "XDP_CPU_TDI")
		)
		(pad "AC16" smd circle
			(at -24.373078 -14.206474)
			(size 0.4318 0.4318)
			(layers "F.Cu" "F.Mask" "F.Paste")
			(net "H_CPU0_PROCHOT_G_N")
		)
		(pad "AC18" smd circle
			(at -22.656038 -14.206474)
			(size 0.4318 0.4318)
			(layers "F.Cu" "F.Mask" "F.Paste")
			(net "GND")
		)
		(pad "AC20" smd circle
			(at -20.938998 -14.206474)
			(size 0.4318 0.4318)
			(layers "F.Cu" "F.Mask" "F.Paste")
			(net "PVCCIO_CPU0")
		)
		(pad "AC22" smd circle
			(at -19.221958 -14.206474)
			(size 0.4318 0.4318)
			(layers "F.Cu" "F.Mask" "F.Paste")
			(net "GND")
		)
		(pad "AC24" smd circle
			(at -17.504918 -14.206474)
			(size 0.4318 0.4318)
			(layers "F.Cu" "F.Mask" "F.Paste")
			(net "M_C_DQS_DN<16>")
		)
		(pad "AC26" smd circle
			(at -15.787878 -14.206474)
			(size 0.4318 0.4318)
			(layers "F.Cu" "F.Mask" "F.Paste")
			(net "GND")
		)
		(pad "AC28" smd circle
			(at -14.071092 -14.206474)
			(size 0.4318 0.4318)
			(layers "F.Cu" "F.Mask" "F.Paste")
			(net "GND")
		)
		(pad "AC30" smd circle
			(at -12.354052 -14.206474)
			(size 0.4318 0.4318)
			(layers "F.Cu" "F.Mask" "F.Paste")
			(net "M_C_DQS_DN<15>")
		)
		(pad "AC32" smd circle
			(at -10.637012 -14.206474)
			(size 0.4318 0.4318)
			(layers "F.Cu" "F.Mask" "F.Paste")
			(net "GND")
		)
		(pad "AC34" smd circle
			(at -8.919972 -14.206474)
			(size 0.4318 0.4318)
			(layers "F.Cu" "F.Mask" "F.Paste")
			(net "GND")
		)
		(pad "AC36" smd circle
			(at -7.202932 -14.206474)
			(size 0.4318 0.4318)
			(layers "F.Cu" "F.Mask" "F.Paste")
			(net "PVCCIO_CPU0")
		)
		(pad "AC38" smd circle
			(at -5.485892 -14.206474)
			(size 0.4318 0.4318)
			(layers "F.Cu" "F.Mask" "F.Paste")
			(net "GND")
		)
		(pad "AC40" smd circle
			(at -3.769106 -14.206474)
			(size 0.4318 0.4318)
			(layers "F.Cu" "F.Mask" "F.Paste")
			(net "GND")
		)
		(pad "AC42" smd circle
			(at -2.052066 -14.206474)
			(size 0.4318 0.4318)
			(layers "F.Cu" "F.Mask" "F.Paste")
			(net "A_CPU0_ABC_RCOMP2")
		)
		(pad "AC46" smd circle
			(at 2.910586 -16.006572)
			(size 0.4318 0.4318)
			(layers "F.Cu" "F.Mask" "F.Paste")
			(net "M_C_MA<17>")
		)
		(pad "AC48" smd circle
			(at 4.627626 -16.006572)
			(size 0.4318 0.4318)
			(layers "F.Cu" "F.Mask" "F.Paste")
			(net "GND")
		)
		(pad "AC50" smd circle
			(at 6.344412 -16.006572)
			(size 0.4318 0.4318)
			(layers "F.Cu" "F.Mask" "F.Paste")
			(net "GND")
		)
		(pad "AC52" smd circle
			(at 8.061452 -16.006572)
			(size 0.4318 0.4318)
			(layers "F.Cu" "F.Mask" "F.Paste")
			(net "GND")
		)
		(pad "AC54" smd circle
			(at 9.778492 -16.006572)
			(size 0.4318 0.4318)
			(layers "F.Cu" "F.Mask" "F.Paste")
			(net "GND")
		)
		(pad "AC56" smd circle
			(at 11.495532 -16.006572)
			(size 0.4318 0.4318)
			(layers "F.Cu" "F.Mask" "F.Paste")
			(net "GND")
		)
		(pad "AC58" smd circle
			(at 13.212572 -16.006572)
			(size 0.4318 0.4318)
			(layers "F.Cu" "F.Mask" "F.Paste")
			(net "GND")
		)
		(pad "AC60" smd circle
			(at 14.929612 -16.006572)
			(size 0.4318 0.4318)
			(layers "F.Cu" "F.Mask" "F.Paste")
			(net "GND")
		)
		(pad "AC62" smd circle
			(at 16.646398 -16.006572)
			(size 0.4318 0.4318)
			(layers "F.Cu" "F.Mask" "F.Paste")
			(net "GND")
		)
		(pad "AC64" smd circle
			(at 18.363438 -16.006572)
			(size 0.4318 0.4318)
			(layers "F.Cu" "F.Mask" "F.Paste")
			(net "GND")
		)
		(pad "AC66" smd circle
			(at 20.080478 -16.006572)
			(size 0.4318 0.4318)
			(layers "F.Cu" "F.Mask" "F.Paste")
			(net "M_A_ECC<6>")
		)
		(pad "AC68" smd circle
			(at 21.797518 -16.006572)
			(size 0.4318 0.4318)
			(layers "F.Cu" "F.Mask" "F.Paste")
			(net "M_A_ECC<0>")
		)
		(pad "AC70" smd circle
			(at 23.514558 -16.006572)
			(size 0.4318 0.4318)
			(layers "F.Cu" "F.Mask" "F.Paste")
			(net "GND")
		)
		(pad "AC72" smd circle
			(at 25.231598 -16.006572)
			(size 0.4318 0.4318)
			(layers "F.Cu" "F.Mask" "F.Paste")
			(net "GND")
		)
		(pad "AC74" smd circle
			(at 26.948384 -16.006572)
			(size 0.4318 0.4318)
			(layers "F.Cu" "F.Mask" "F.Paste")
			(net "M_C_DQ<9>")
		)
		(pad "AC76" smd circle
			(at 28.665424 -16.006572)
			(size 0.4318 0.4318)
			(layers "F.Cu" "F.Mask" "F.Paste")
			(net "M_C_DQS_DP<10>")
		)
		(pad "AC78" smd circle
			(at 30.382464 -16.006572)
			(size 0.4318 0.4318)
			(layers "F.Cu" "F.Mask" "F.Paste")
			(net "GND")
		)
		(pad "AC80" smd circle
			(at 32.099504 -16.006572)
			(size 0.4318 0.4318)
			(layers "F.Cu" "F.Mask" "F.Paste")
			(net "M_B_DQ<15>")
		)
		(pad "AC82" smd circle
			(at 33.816544 -16.006572)
			(size 0.4318 0.4318)
			(layers "F.Cu" "F.Mask" "F.Paste")
			(net "M_B_DQ<10>")
		)
		(pad "AC84" smd circle
			(at 35.533584 -16.006572)
			(size 0.4318 0.4318)
			(layers "F.Cu" "F.Mask" "F.Paste")
			(net "GND")
		)
		(pad "AC86" smd custom
			(at 37.250624 -16.006572 270)
			(size 0.10795 0.10795)
			(layers "F.Cu" "F.Mask" "F.Paste")
			(net "GND")
			(options
				(clearance outline)
				(anchor circle)
			)
			(primitives
				(gr_poly
					(pts
						(arc
							(start 0.2159 -0.0381)
							(mid 0 -0.254)
							(end -0.2159 -0.0381)
						)
						(arc
							(start -0.2159 0.0381)
							(mid 0 0.254)
							(end 0.2159 0.0381)
						)
					)
					(width 0)
					(fill yes)
				)
			)
		)
		(pad "AD1" smd custom
			(at -37.250624 -13.711428 90)
			(size 0.10795 0.10795)
			(layers "F.Cu" "F.Mask" "F.Paste")
			(net "UPI_CPU0_CPU1_P0P0_DP<14>")
			(options
				(clearance outline)
				(anchor circle)
			)
			(primitives
				(gr_poly
					(pts
						(arc
							(start 0.2159 -0.0381)
							(mid 0 -0.254)
							(end -0.2159 -0.0381)
						)
						(arc
							(start -0.2159 0.0381)
							(mid 0 0.254)
							(end 0.2159 0.0381)
						)
					)
					(width 0)
					(fill yes)
				)
			)
		)
		(pad "AD3" smd circle
			(at -35.533584 -13.711428)
			(size 0.4318 0.4318)
			(layers "F.Cu" "F.Mask" "F.Paste")
			(net "GND")
		)
		(pad "AD5" smd circle
			(at -33.816544 -13.711428)
			(size 0.4318 0.4318)
			(layers "F.Cu" "F.Mask" "F.Paste")
			(net "UPI_CPU1_CPU0_P0P0_DN<16>")
		)
		(pad "AD7" smd circle
			(at -32.099504 -13.711428)
			(size 0.4318 0.4318)
			(layers "F.Cu" "F.Mask" "F.Paste")
			(net "GND")
		)
		(pad "AD9" smd circle
			(at -30.382464 -13.711428)
			(size 0.4318 0.4318)
			(layers "F.Cu" "F.Mask" "F.Paste")
			(net "GND")
		)
		(pad "AD11" smd circle
			(at -28.665424 -13.711428)
			(size 0.4318 0.4318)
			(layers "F.Cu" "F.Mask" "F.Paste")
			(net "GND")
		)
		(pad "AD13" smd circle
			(at -26.948384 -13.711428)
			(size 0.4318 0.4318)
			(layers "F.Cu" "F.Mask" "F.Paste")
			(net "GND")
		)
		(pad "AD15" smd circle
			(at -25.231598 -13.711428)
			(size 0.4318 0.4318)
			(layers "F.Cu" "F.Mask" "F.Paste")
			(net "GND")
		)
		(pad "AD17" smd circle
			(at -23.514558 -13.711428)
			(size 0.4318 0.4318)
			(layers "F.Cu" "F.Mask" "F.Paste")
			(net "SMB_DDR_DEF_SDA_G_R")
		)
		(pad "AD19" smd circle
			(at -21.797518 -13.711428)
			(size 0.4318 0.4318)
			(layers "F.Cu" "F.Mask" "F.Paste")
			(net "GND")
		)
		(pad "AD21" smd circle
			(at -20.080478 -13.711428)
			(size 0.4318 0.4318)
			(layers "F.Cu" "F.Mask" "F.Paste")
			(net "GND")
		)
		(pad "AD23" smd circle
			(at -18.363438 -13.711428)
			(size 0.4318 0.4318)
			(layers "F.Cu" "F.Mask" "F.Paste")
			(net "M_C_DQ<62>")
		)
		(pad "AD25" smd circle
			(at -16.646398 -13.711428)
			(size 0.4318 0.4318)
			(layers "F.Cu" "F.Mask" "F.Paste")
			(net "M_C_DQ<56>")
		)
		(pad "AD27" smd circle
			(at -14.929612 -13.711428)
			(size 0.4318 0.4318)
			(layers "F.Cu" "F.Mask" "F.Paste")
			(net "GND")
		)
		(pad "AD29" smd circle
			(at -13.212572 -13.711428)
			(size 0.4318 0.4318)
			(layers "F.Cu" "F.Mask" "F.Paste")
			(net "M_C_DQ<54>")
		)
		(pad "AD31" smd circle
			(at -11.495532 -13.711428)
			(size 0.4318 0.4318)
			(layers "F.Cu" "F.Mask" "F.Paste")
			(net "M_C_DQ<48>")
		)
		(pad "AD33" smd circle
			(at -9.778492 -13.711428)
			(size 0.4318 0.4318)
			(layers "F.Cu" "F.Mask" "F.Paste")
			(net "GND")
		)
		(pad "AD35" smd circle
			(at -8.061452 -13.711428)
			(size 0.4318 0.4318)
			(layers "F.Cu" "F.Mask" "F.Paste")
			(net "PVCCIO_CPU0")
		)
		(pad "AD37" smd circle
			(at -6.344412 -13.711428)
			(size 0.4318 0.4318)
			(layers "F.Cu" "F.Mask" "F.Paste")
			(net "PVCCIO_CPU0")
		)
		(pad "AD39" smd circle
			(at -4.627626 -13.711428)
			(size 0.4318 0.4318)
			(layers "F.Cu" "F.Mask" "F.Paste")
			(net "GND")
		)
		(pad "AD41" smd circle
			(at -2.910586 -13.711428)
			(size 0.4318 0.4318)
			(layers "F.Cu" "F.Mask" "F.Paste")
			(net "VSENSE_PMAX_CPU0")
		)
		(pad "AD43" smd circle
			(at -1.193546 -13.711428)
			(size 0.4318 0.4318)
			(layers "F.Cu" "F.Mask" "F.Paste")
			(net "GND")
		)
		(pad "AD45" smd circle
			(at 2.052066 -15.511526)
			(size 0.508 0.508)
			(layers "F.Cu" "F.Mask" "F.Paste")
			(net "PVDDQ_ABC")
		)
		(pad "AD47" smd circle
			(at 3.769106 -15.511526)
			(size 0.4318 0.4318)
			(layers "F.Cu" "F.Mask" "F.Paste")
			(net "TP_CPU0_RSVD_254")
		)
		(pad "AD49" smd circle
			(at 5.485892 -15.511526)
			(size 0.4318 0.4318)
			(layers "F.Cu" "F.Mask" "F.Paste")
			(net "TP_CPU0_RSVD_253")
		)
		(pad "AD51" smd circle
			(at 7.202932 -15.511526)
			(size 0.4318 0.4318)
			(layers "F.Cu" "F.Mask" "F.Paste")
			(net "TP_CPU0_RSVD_252")
		)
		(pad "AD53" smd circle
			(at 8.919972 -15.511526)
			(size 0.4318 0.4318)
			(layers "F.Cu" "F.Mask" "F.Paste")
			(net "M_C_MA<13>")
		)
		(pad "AD55" smd circle
			(at 10.637012 -15.511526)
			(size 0.4318 0.4318)
			(layers "F.Cu" "F.Mask" "F.Paste")
			(net "M_C_MA<10>")
		)
		(pad "AD57" smd circle
			(at 12.354052 -15.511526)
			(size 0.4318 0.4318)
			(layers "F.Cu" "F.Mask" "F.Paste")
			(net "M_C_MA<2>")
		)
		(pad "AD59" smd circle
			(at 14.071092 -15.511526)
			(size 0.4318 0.4318)
			(layers "F.Cu" "F.Mask" "F.Paste")
			(net "M_C_MA<8>")
		)
		(pad "AD61" smd circle
			(at 15.787878 -15.511526)
			(size 0.4318 0.4318)
			(layers "F.Cu" "F.Mask" "F.Paste")
			(net "M_C_ALERT_N")
		)
		(pad "AD63" smd circle
			(at 17.504918 -15.511526)
			(size 0.4318 0.4318)
			(layers "F.Cu" "F.Mask" "F.Paste")
			(net "M_C_CKE<1>")
		)
		(pad "AD65" smd circle
			(at 19.221958 -15.511526)
			(size 0.4318 0.4318)
			(layers "F.Cu" "F.Mask" "F.Paste")
			(net "M_A_ECC<2>")
		)
		(pad "AD67" smd circle
			(at 20.938998 -15.511526)
			(size 0.4318 0.4318)
			(layers "F.Cu" "F.Mask" "F.Paste")
			(net "M_A_DQS_DP<17>")
		)
		(pad "AD69" smd circle
			(at 22.656038 -15.511526)
			(size 0.4318 0.4318)
			(layers "F.Cu" "F.Mask" "F.Paste")
			(net "M_A_ECC<4>")
		)
		(pad "AD71" smd circle
			(at 24.373078 -15.511526)
			(size 0.4318 0.4318)
			(layers "F.Cu" "F.Mask" "F.Paste")
			(net "GND")
		)
		(pad "AD73" smd circle
			(at 26.090118 -15.511526)
			(size 0.4318 0.4318)
			(layers "F.Cu" "F.Mask" "F.Paste")
			(net "GND")
		)
		(pad "AD75" smd circle
			(at 27.806904 -15.511526)
			(size 0.4318 0.4318)
			(layers "F.Cu" "F.Mask" "F.Paste")
			(net "GND")
		)
		(pad "AD77" smd circle
			(at 29.523944 -15.511526)
			(size 0.4318 0.4318)
			(layers "F.Cu" "F.Mask" "F.Paste")
			(net "M_C_DQS_DN<10>")
		)
		(pad "AD79" smd circle
			(at 31.240984 -15.511526)
			(size 0.4318 0.4318)
			(layers "F.Cu" "F.Mask" "F.Paste")
			(net "M_B_DQS_DN<1>")
		)
		(pad "AD81" smd circle
			(at 32.958024 -15.511526)
			(size 0.4318 0.4318)
			(layers "F.Cu" "F.Mask" "F.Paste")
			(net "GND")
		)
		(pad "AD83" smd circle
			(at 34.675064 -15.511526)
			(size 0.4318 0.4318)
			(layers "F.Cu" "F.Mask" "F.Paste")
			(net "GND")
		)
		(pad "AD85" smd circle
			(at 36.392104 -15.511526)
			(size 0.4318 0.4318)
			(layers "F.Cu" "F.Mask" "F.Paste")
			(net "GND")
		)
		(pad "AE2" smd circle
			(at -36.392104 -13.215874)
			(size 0.4318 0.4318)
			(layers "F.Cu" "F.Mask" "F.Paste")
			(net "UPI_CPU0_CPU1_P0P0_DN<12>")
		)
		(pad "AE4" smd circle
			(at -34.675064 -13.215874)
			(size 0.4318 0.4318)
			(layers "F.Cu" "F.Mask" "F.Paste")
			(net "GND")
		)
		(pad "AE6" smd circle
			(at -32.958024 -13.215874)
			(size 0.4318 0.4318)
			(layers "F.Cu" "F.Mask" "F.Paste")
			(net "UPI_CPU1_CPU0_P0P0_DN<15>")
		)
		(pad "AE8" smd circle
			(at -31.240984 -13.215874)
			(size 0.4318 0.4318)
			(layers "F.Cu" "F.Mask" "F.Paste")
			(net "GND")
		)
		(pad "AE10" smd circle
			(at -29.523944 -13.215874)
			(size 0.4318 0.4318)
			(layers "F.Cu" "F.Mask" "F.Paste")
			(net "PVCCIO_CPU0")
		)
		(pad "AE12" smd circle
			(at -27.806904 -13.215874)
			(size 0.4318 0.4318)
			(layers "F.Cu" "F.Mask" "F.Paste")
			(net "XDP_CPU_OBSFN_B0_MBP6_N")
		)
		(pad "AE14" smd circle
			(at -26.090118 -13.215874)
			(size 0.4318 0.4318)
			(layers "F.Cu" "F.Mask" "F.Paste")
			(net "XDP_CPU0_TDO")
		)
		(pad "AE16" smd circle
			(at -24.373078 -13.215874)
			(size 0.4318 0.4318)
			(layers "F.Cu" "F.Mask" "F.Paste")
			(net "GND")
		)
		(pad "AE18" smd circle
			(at -22.656038 -13.215874)
			(size 0.4318 0.4318)
			(layers "F.Cu" "F.Mask" "F.Paste")
			(net "SMB_DDR_DEF_SCL_G_R")
		)
		(pad "AE20" smd circle
			(at -20.938998 -13.215874)
			(size 0.4318 0.4318)
			(layers "F.Cu" "F.Mask" "F.Paste")
			(net "PU_CPU0_LEGACY_SKT")
		)
		(pad "AE22" smd circle
			(at -19.221958 -13.215874)
			(size 0.4318 0.4318)
			(layers "F.Cu" "F.Mask" "F.Paste")
			(net "M_C_DQ<58>")
		)
		(pad "AE24" smd circle
			(at -17.504918 -13.215874)
			(size 0.4318 0.4318)
			(layers "F.Cu" "F.Mask" "F.Paste")
			(net "M_C_DQS_DP<16>")
		)
		(pad "AE26" smd circle
			(at -15.787878 -13.215874)
			(size 0.4318 0.4318)
			(layers "F.Cu" "F.Mask" "F.Paste")
			(net "M_C_DQ<60>")
		)
		(pad "AE28" smd circle
			(at -14.071092 -13.215874)
			(size 0.4318 0.4318)
			(layers "F.Cu" "F.Mask" "F.Paste")
			(net "M_C_DQ<50>")
		)
		(pad "AE30" smd circle
			(at -12.354052 -13.215874)
			(size 0.4318 0.4318)
			(layers "F.Cu" "F.Mask" "F.Paste")
			(net "M_C_DQS_DP<15>")
		)
		(pad "AE32" smd circle
			(at -10.637012 -13.215874)
			(size 0.4318 0.4318)
			(layers "F.Cu" "F.Mask" "F.Paste")
			(net "M_C_DQ<52>")
		)
		(pad "AE34" smd circle
			(at -8.919972 -13.215874)
			(size 0.4318 0.4318)
			(layers "F.Cu" "F.Mask" "F.Paste")
			(net "PVCCIO_CPU0")
		)
		(pad "AE36" smd circle
			(at -7.202932 -13.215874)
			(size 0.4318 0.4318)
			(layers "F.Cu" "F.Mask" "F.Paste")
			(net "PVCCIO_CPU0")
		)
		(pad "AE38" smd circle
			(at -5.485892 -13.215874)
			(size 0.4318 0.4318)
			(layers "F.Cu" "F.Mask" "F.Paste")
			(net "GND")
		)
		(pad "AE40" smd circle
			(at -3.769106 -13.215874)
			(size 0.4318 0.4318)
			(layers "F.Cu" "F.Mask" "F.Paste")
			(net "GND")
		)
		(pad "AE42" smd circle
			(at -2.052066 -13.215874)
			(size 0.4318 0.4318)
			(layers "F.Cu" "F.Mask" "F.Paste")
			(net "GND")
		)
		(pad "AE46" smd circle
			(at 2.910586 -15.015972)
			(size 0.4318 0.4318)
			(layers "F.Cu" "F.Mask" "F.Paste")
			(net "TP_CPU0_RSVD_251")
		)
		(pad "AE48" smd circle
			(at 4.627626 -15.015972)
			(size 0.4318 0.4318)
			(layers "F.Cu" "F.Mask" "F.Paste")
			(net "TP_CPU0_RSVD_250")
		)
		(pad "AE50" smd circle
			(at 6.344412 -15.015972)
			(size 0.4318 0.4318)
			(layers "F.Cu" "F.Mask" "F.Paste")
			(net "TP_CPU0_RSVD_249")
		)
		(pad "AE52" smd circle
			(at 8.061452 -15.015972)
			(size 0.4318 0.4318)
			(layers "F.Cu" "F.Mask" "F.Paste")
			(net "TP_CPU0_RSVD_248")
		)
		(pad "AE54" smd circle
			(at 9.778492 -15.015972)
			(size 0.4318 0.4318)
			(layers "F.Cu" "F.Mask" "F.Paste")
			(net "M_C_MA<15>")
		)
		(pad "AE56" smd circle
			(at 11.495532 -15.015972)
			(size 0.4318 0.4318)
			(layers "F.Cu" "F.Mask" "F.Paste")
			(net "M_C_BA<1>")
		)
		(pad "AE58" smd circle
			(at 13.212572 -15.015972)
			(size 0.4318 0.4318)
			(layers "F.Cu" "F.Mask" "F.Paste")
			(net "M_C_MA<1>")
		)
		(pad "AE60" smd circle
			(at 14.929612 -15.015972)
			(size 0.4318 0.4318)
			(layers "F.Cu" "F.Mask" "F.Paste")
			(net "M_C_MA<7>")
		)
		(pad "AE62" smd circle
			(at 16.646398 -15.015972)
			(size 0.4318 0.4318)
			(layers "F.Cu" "F.Mask" "F.Paste")
			(net "M_C_BG<1>")
		)
		(pad "AE64" smd circle
			(at 18.363438 -15.015972)
			(size 0.4318 0.4318)
			(layers "F.Cu" "F.Mask" "F.Paste")
			(net "GND")
		)
		(pad "AE66" smd circle
			(at 20.080478 -15.015972)
			(size 0.4318 0.4318)
			(layers "F.Cu" "F.Mask" "F.Paste")
			(net "GND")
		)
		(pad "AE68" smd circle
			(at 21.797518 -15.015972)
			(size 0.4318 0.4318)
			(layers "F.Cu" "F.Mask" "F.Paste")
			(net "GND")
		)
		(pad "AE70" smd circle
			(at 23.514558 -15.015972)
			(size 0.4318 0.4318)
			(layers "F.Cu" "F.Mask" "F.Paste")
			(net "GND")
		)
		(pad "AE72" smd circle
			(at 25.231598 -15.015972)
			(size 0.4318 0.4318)
			(layers "F.Cu" "F.Mask" "F.Paste")
			(net "TP_CPU0_RSVD_247")
		)
		(pad "AE74" smd circle
			(at 26.948384 -15.015972)
			(size 0.4318 0.4318)
			(layers "F.Cu" "F.Mask" "F.Paste")
			(net "M_C_DQ<13>")
		)
		(pad "AE76" smd circle
			(at 28.665424 -15.015972)
			(size 0.4318 0.4318)
			(layers "F.Cu" "F.Mask" "F.Paste")
			(net "M_C_DQ<8>")
		)
		(pad "AE78" smd circle
			(at 30.382464 -15.015972)
			(size 0.4318 0.4318)
			(layers "F.Cu" "F.Mask" "F.Paste")
			(net "GND")
		)
		(pad "AE80" smd circle
			(at 32.099504 -15.015972)
			(size 0.4318 0.4318)
			(layers "F.Cu" "F.Mask" "F.Paste")
			(net "M_B_DQS_DP<1>")
		)
		(pad "AE82" smd circle
			(at 33.816544 -15.015972)
			(size 0.4318 0.4318)
			(layers "F.Cu" "F.Mask" "F.Paste")
			(net "M_B_DQ<14>")
		)
		(pad "AE84" smd circle
			(at 35.533584 -15.015972)
			(size 0.4318 0.4318)
			(layers "F.Cu" "F.Mask" "F.Paste")
			(net "M_A_DQ<3>")
		)
		(pad "AE86" smd custom
			(at 37.250624 -15.015972 270)
			(size 0.10795 0.10795)
			(layers "F.Cu" "F.Mask" "F.Paste")
			(net "M_A_DQ<2>")
			(options
				(clearance outline)
				(anchor circle)
			)
			(primitives
				(gr_poly
					(pts
						(arc
							(start 0.2159 -0.0381)
							(mid 0 -0.254)
							(end -0.2159 -0.0381)
						)
						(arc
							(start -0.2159 0.0381)
							(mid 0 0.254)
							(end 0.2159 0.0381)
						)
					)
					(width 0)
					(fill yes)
				)
			)
		)
		(pad "AF1" smd custom
			(at -37.250624 -12.720828 90)
			(size 0.10795 0.10795)
			(layers "F.Cu" "F.Mask" "F.Paste")
			(net "GND")
			(options
				(clearance outline)
				(anchor circle)
			)
			(primitives
				(gr_poly
					(pts
						(arc
							(start 0.2159 -0.0381)
							(mid 0 -0.254)
							(end -0.2159 -0.0381)
						)
						(arc
							(start -0.2159 0.0381)
							(mid 0 0.254)
							(end 0.2159 0.0381)
						)
					)
					(width 0)
					(fill yes)
				)
			)
		)
		(pad "AF3" smd circle
			(at -35.533584 -12.720828)
			(size 0.4318 0.4318)
			(layers "F.Cu" "F.Mask" "F.Paste")
			(net "UPI_CPU0_CPU1_P0P0_DP<13>")
		)
		(pad "AF5" smd circle
			(at -33.816544 -12.720828)
			(size 0.4318 0.4318)
			(layers "F.Cu" "F.Mask" "F.Paste")
			(net "PVCCIO_CPU0")
		)
		(pad "AF7" smd circle
			(at -32.099504 -12.720828)
			(size 0.4318 0.4318)
			(layers "F.Cu" "F.Mask" "F.Paste")
			(net "UPI_CPU1_CPU0_P0P0_DP<14>")
		)
		(pad "AF9" smd circle
			(at -30.382464 -12.720828)
			(size 0.4318 0.4318)
			(layers "F.Cu" "F.Mask" "F.Paste")
			(net "GND")
		)
		(pad "AF11" smd circle
			(at -28.665424 -12.720828)
			(size 0.4318 0.4318)
			(layers "F.Cu" "F.Mask" "F.Paste")
			(net "TP_XDP_CPU0_OBSDATA_A1_MBP3_N")
		)
		(pad "AF13" smd circle
			(at -26.948384 -12.720828)
			(size 0.4318 0.4318)
			(layers "F.Cu" "F.Mask" "F.Paste")
			(net "H_CPU0_MEMDEF_MEMHOT_G_N")
		)
		(pad "AF15" smd circle
			(at -25.231598 -12.720828)
			(size 0.4318 0.4318)
			(layers "F.Cu" "F.Mask" "F.Paste")
			(net "H_CPU0_FAST_WAKE_N")
		)
		(pad "AF17" smd circle
			(at -23.514558 -12.720828)
			(size 0.4318 0.4318)
			(layers "F.Cu" "F.Mask" "F.Paste")
			(net "SMB_DDR_ABC_SDA_G_R")
		)
		(pad "AF19" smd circle
			(at -21.797518 -12.720828)
			(size 0.4318 0.4318)
			(layers "F.Cu" "F.Mask" "F.Paste")
			(net "TP_CPU0_RSVD_246")
		)
		(pad "AF21" smd circle
			(at -20.080478 -12.720828)
			(size 0.4318 0.4318)
			(layers "F.Cu" "F.Mask" "F.Paste")
			(net "GND")
		)
		(pad "AF23" smd circle
			(at -18.363438 -12.720828)
			(size 0.4318 0.4318)
			(layers "F.Cu" "F.Mask" "F.Paste")
			(net "GND")
		)
		(pad "AF25" smd circle
			(at -16.646398 -12.720828)
			(size 0.4318 0.4318)
			(layers "F.Cu" "F.Mask" "F.Paste")
			(net "GND")
		)
		(pad "AF27" smd circle
			(at -14.929612 -12.720828)
			(size 0.4318 0.4318)
			(layers "F.Cu" "F.Mask" "F.Paste")
			(net "GND")
		)
		(pad "AF29" smd circle
			(at -13.212572 -12.720828)
			(size 0.4318 0.4318)
			(layers "F.Cu" "F.Mask" "F.Paste")
			(net "GND")
		)
		(pad "AF31" smd circle
			(at -11.495532 -12.720828)
			(size 0.4318 0.4318)
			(layers "F.Cu" "F.Mask" "F.Paste")
			(net "GND")
		)
		(pad "AF33" smd circle
			(at -9.778492 -12.720828)
			(size 0.4318 0.4318)
			(layers "F.Cu" "F.Mask" "F.Paste")
			(net "GND")
		)
		(pad "AF35" smd circle
			(at -8.061452 -12.720828)
			(size 0.4318 0.4318)
			(layers "F.Cu" "F.Mask" "F.Paste")
			(net "PVCCIO_CPU0")
		)
		(pad "AF37" smd circle
			(at -6.344412 -12.720828)
			(size 0.4318 0.4318)
			(layers "F.Cu" "F.Mask" "F.Paste")
			(net "GND")
		)
		(pad "AF39" smd circle
			(at -4.627626 -12.720828)
			(size 0.4318 0.4318)
			(layers "F.Cu" "F.Mask" "F.Paste")
			(net "GND")
		)
		(pad "AF41" smd circle
			(at -2.910586 -12.720828)
			(size 0.4318 0.4318)
			(layers "F.Cu" "F.Mask" "F.Paste")
			(net "GND")
		)
		(pad "AF43" smd circle
			(at -1.193546 -12.720828)
			(size 0.4318 0.4318)
			(layers "F.Cu" "F.Mask" "F.Paste")
			(net "PVCCIN_CPU0")
		)
		(pad "AF45" smd circle
			(at 2.052066 -14.520926)
			(size 0.508 0.508)
			(layers "F.Cu" "F.Mask" "F.Paste")
			(net "PD_CPU0_RSVD_TEST_1")
		)
		(pad "AF47" smd circle
			(at 3.769106 -14.520926)
			(size 0.4318 0.4318)
			(layers "F.Cu" "F.Mask" "F.Paste")
			(net "TP_CPU0_RSVD_245")
		)
		(pad "AF49" smd circle
			(at 5.485892 -14.520926)
			(size 0.4318 0.4318)
			(layers "F.Cu" "F.Mask" "F.Paste")
			(net "TP_CPU0_RSVD_244")
		)
		(pad "AF51" smd circle
			(at 7.202932 -14.520926)
			(size 0.4318 0.4318)
			(layers "F.Cu" "F.Mask" "F.Paste")
			(net "TP_CPU0_RSVD_243")
		)
		(pad "AF53" smd circle
			(at 8.919972 -14.520926)
			(size 0.4318 0.4318)
			(layers "F.Cu" "F.Mask" "F.Paste")
			(net "TP_CPU0_RSVD_242")
		)
		(pad "AF55" smd circle
			(at 10.637012 -14.520926)
			(size 0.4318 0.4318)
			(layers "F.Cu" "F.Mask" "F.Paste")
			(net "PVDDQ_ABC")
		)
		(pad "AF57" smd circle
			(at 12.354052 -14.520926)
			(size 0.4318 0.4318)
			(layers "F.Cu" "F.Mask" "F.Paste")
			(net "PVDDQ_ABC")
		)
		(pad "AF59" smd circle
			(at 14.071092 -14.520926)
			(size 0.4318 0.4318)
			(layers "F.Cu" "F.Mask" "F.Paste")
			(net "PVDDQ_ABC")
		)
		(pad "AF61" smd circle
			(at 15.787878 -14.520926)
			(size 0.4318 0.4318)
			(layers "F.Cu" "F.Mask" "F.Paste")
			(net "PVDDQ_ABC")
		)
		(pad "AF63" smd circle
			(at 17.504918 -14.520926)
			(size 0.4318 0.4318)
			(layers "F.Cu" "F.Mask" "F.Paste")
			(net "PVDDQ_ABC")
		)
		(pad "AF65" smd circle
			(at 19.221958 -14.520926)
			(size 0.4318 0.4318)
			(layers "F.Cu" "F.Mask" "F.Paste")
			(net "M_A_ECC<3>")
		)
		(pad "AF67" smd circle
			(at 20.938998 -14.520926)
			(size 0.4318 0.4318)
			(layers "F.Cu" "F.Mask" "F.Paste")
			(net "M_A_DQS_DP<8>")
		)
		(pad "AF69" smd circle
			(at 22.656038 -14.520926)
			(size 0.4318 0.4318)
			(layers "F.Cu" "F.Mask" "F.Paste")
			(net "M_A_ECC<5>")
		)
		(pad "AF71" smd circle
			(at 24.373078 -14.520926)
			(size 0.4318 0.4318)
			(layers "F.Cu" "F.Mask" "F.Paste")
			(net "TP_CPU0_RSVD_241")
		)
		(pad "AF73" smd circle
			(at 26.090118 -14.520926)
			(size 0.4318 0.4318)
			(layers "F.Cu" "F.Mask" "F.Paste")
			(net "GND")
		)
		(pad "AF75" smd circle
			(at 27.806904 -14.520926)
			(size 0.4318 0.4318)
			(layers "F.Cu" "F.Mask" "F.Paste")
			(net "M_C_DQ<12>")
		)
		(pad "AF77" smd circle
			(at 29.523944 -14.520926)
			(size 0.4318 0.4318)
			(layers "F.Cu" "F.Mask" "F.Paste")
			(net "GND")
		)
		(pad "AF79" smd circle
			(at 31.240984 -14.520926)
			(size 0.4318 0.4318)
			(layers "F.Cu" "F.Mask" "F.Paste")
			(net "M_B_DQ<9>")
		)
		(pad "AF81" smd circle
			(at 32.958024 -14.520926)
			(size 0.4318 0.4318)
			(layers "F.Cu" "F.Mask" "F.Paste")
			(net "M_B_DQS_DP<10>")
		)
		(pad "AF83" smd circle
			(at 34.675064 -14.520926)
			(size 0.4318 0.4318)
			(layers "F.Cu" "F.Mask" "F.Paste")
			(net "GND")
		)
		(pad "AF85" smd circle
			(at 36.392104 -14.520926)
			(size 0.4318 0.4318)
			(layers "F.Cu" "F.Mask" "F.Paste")
			(net "GND")
		)
		(pad "AG2" smd circle
			(at -36.392104 -12.225274)
			(size 0.4318 0.4318)
			(layers "F.Cu" "F.Mask" "F.Paste")
			(net "UPI_CPU0_CPU1_P0P0_DP<12>")
		)
		(pad "AG4" smd circle
			(at -34.675064 -12.225274)
			(size 0.4318 0.4318)
			(layers "F.Cu" "F.Mask" "F.Paste")
			(net "UPI_CPU0_CPU1_P0P0_DN<13>")
		)
		(pad "AG6" smd circle
			(at -32.958024 -12.225274)
			(size 0.4318 0.4318)
			(layers "F.Cu" "F.Mask" "F.Paste")
			(net "UPI_CPU1_CPU0_P0P0_DP<15>")
		)
		(pad "AG8" smd circle
			(at -31.240984 -12.225274)
			(size 0.4318 0.4318)
			(layers "F.Cu" "F.Mask" "F.Paste")
			(net "UPI_CPU1_CPU0_P0P0_DN<14>")
		)
		(pad "AG10" smd circle
			(at -29.523944 -12.225274)
			(size 0.4318 0.4318)
			(layers "F.Cu" "F.Mask" "F.Paste")
			(net "TP_XDP_CPU0_OBSDATA_A0_MBP2_N")
		)
		(pad "AG12" smd circle
			(at -27.806904 -12.225274)
			(size 0.4318 0.4318)
			(layers "F.Cu" "F.Mask" "F.Paste")
			(net "GND")
		)
		(pad "AG14" smd circle
			(at -26.090118 -12.225274)
			(size 0.4318 0.4318)
			(layers "F.Cu" "F.Mask" "F.Paste")
			(net "GND")
		)
		(pad "AG16" smd circle
			(at -24.373078 -12.225274)
			(size 0.4318 0.4318)
			(layers "F.Cu" "F.Mask" "F.Paste")
			(net "XDP_CPU_PRDY_N")
		)
		(pad "AG18" smd circle
			(at -22.656038 -12.225274)
			(size 0.4318 0.4318)
			(layers "F.Cu" "F.Mask" "F.Paste")
			(net "GND")
		)
		(pad "AG20" smd circle
			(at -20.938998 -12.225274)
			(size 0.4318 0.4318)
			(layers "F.Cu" "F.Mask" "F.Paste")
			(net "TP_CPU0_RSVD_240")
		)
		(pad "AG22" smd circle
			(at -19.221958 -12.225274)
			(size 0.4318 0.4318)
			(layers "F.Cu" "F.Mask" "F.Paste")
			(net "M_C_DQ<59>")
		)
		(pad "AG24" smd circle
			(at -17.504918 -12.225274)
			(size 0.4318 0.4318)
			(layers "F.Cu" "F.Mask" "F.Paste")
			(net "M_C_DQS_DP<7>")
		)
		(pad "AG26" smd circle
			(at -15.787878 -12.225274)
			(size 0.4318 0.4318)
			(layers "F.Cu" "F.Mask" "F.Paste")
			(net "M_C_DQ<61>")
		)
		(pad "AG28" smd circle
			(at -14.071092 -12.225274)
			(size 0.4318 0.4318)
			(layers "F.Cu" "F.Mask" "F.Paste")
			(net "M_C_DQ<51>")
		)
		(pad "AG30" smd circle
			(at -12.354052 -12.225274)
			(size 0.4318 0.4318)
			(layers "F.Cu" "F.Mask" "F.Paste")
			(net "M_C_DQS_DP<6>")
		)
		(pad "AG32" smd circle
			(at -10.637012 -12.225274)
			(size 0.4318 0.4318)
			(layers "F.Cu" "F.Mask" "F.Paste")
			(net "M_C_DQ<53>")
		)
		(pad "AG34" smd circle
			(at -8.919972 -12.225274)
			(size 0.4318 0.4318)
			(layers "F.Cu" "F.Mask" "F.Paste")
			(net "PVCCIO_CPU0")
		)
		(pad "AG36" smd circle
			(at -7.202932 -12.225274)
			(size 0.4318 0.4318)
			(layers "F.Cu" "F.Mask" "F.Paste")
			(net "GND")
		)
		(pad "AG38" smd circle
			(at -5.485892 -12.225274)
			(size 0.4318 0.4318)
			(layers "F.Cu" "F.Mask" "F.Paste")
			(net "PVCCIN_CPU0")
		)
		(pad "AG40" smd circle
			(at -3.769106 -12.225274)
			(size 0.4318 0.4318)
			(layers "F.Cu" "F.Mask" "F.Paste")
			(net "PVCCIN_CPU0")
		)
		(pad "AG42" smd circle
			(at -2.052066 -12.225274)
			(size 0.4318 0.4318)
			(layers "F.Cu" "F.Mask" "F.Paste")
			(net "PVCCIN_CPU0")
		)
		(pad "AG46" smd circle
			(at 2.910586 -14.025372)
			(size 0.4318 0.4318)
			(layers "F.Cu" "F.Mask" "F.Paste")
			(net "PD_CPU0_RSVD_TEST_2")
		)
		(pad "AG48" smd circle
			(at 4.627626 -14.025372)
			(size 0.4318 0.4318)
			(layers "F.Cu" "F.Mask" "F.Paste")
			(net "TP_CPU0_RSVD_239")
		)
		(pad "AG50" smd circle
			(at 6.344412 -14.025372)
			(size 0.4318 0.4318)
			(layers "F.Cu" "F.Mask" "F.Paste")
			(net "TP_CPU0_RSVD_238")
		)
		(pad "AG52" smd circle
			(at 8.061452 -14.025372)
			(size 0.4318 0.4318)
			(layers "F.Cu" "F.Mask" "F.Paste")
			(net "TP_CPU0_RSVD_237")
		)
		(pad "AG54" smd circle
			(at 9.778492 -14.025372)
			(size 0.4318 0.4318)
			(layers "F.Cu" "F.Mask" "F.Paste")
			(net "TP_CPU0_RSVD_236")
		)
		(pad "AG56" smd circle
			(at 11.495532 -14.025372)
			(size 0.4318 0.4318)
			(layers "F.Cu" "F.Mask" "F.Paste")
			(net "TP_CPU0_RSVD_235")
		)
		(pad "AG58" smd circle
			(at 13.212572 -14.025372)
			(size 0.4318 0.4318)
			(layers "F.Cu" "F.Mask" "F.Paste")
			(net "M_C_MA<9>")
		)
		(pad "AG60" smd circle
			(at 14.929612 -14.025372)
			(size 0.4318 0.4318)
			(layers "F.Cu" "F.Mask" "F.Paste")
			(net "M_C_MA<11>")
		)
		(pad "AG62" smd circle
			(at 16.646398 -14.025372)
			(size 0.4318 0.4318)
			(layers "F.Cu" "F.Mask" "F.Paste")
			(net "M_C_MA<12>")
		)
		(pad "AG64" smd circle
			(at 18.363438 -14.025372)
			(size 0.4318 0.4318)
			(layers "F.Cu" "F.Mask" "F.Paste")
			(net "GND")
		)
		(pad "AG66" smd circle
			(at 20.080478 -14.025372)
			(size 0.4318 0.4318)
			(layers "F.Cu" "F.Mask" "F.Paste")
			(net "M_A_ECC<7>")
		)
		(pad "AG68" smd circle
			(at 21.797518 -14.025372)
			(size 0.4318 0.4318)
			(layers "F.Cu" "F.Mask" "F.Paste")
			(net "M_A_ECC<1>")
		)
		(pad "AG70" smd circle
			(at 23.514558 -14.025372)
			(size 0.4318 0.4318)
			(layers "F.Cu" "F.Mask" "F.Paste")
			(net "GND")
		)
		(pad "AG72" smd circle
			(at 25.231598 -14.025372)
			(size 0.4318 0.4318)
			(layers "F.Cu" "F.Mask" "F.Paste")
			(net "TP_CPU0_RSVD_234")
		)
		(pad "AG74" smd circle
			(at 26.948384 -14.025372)
			(size 0.4318 0.4318)
			(layers "F.Cu" "F.Mask" "F.Paste")
			(net "GND")
		)
		(pad "AG76" smd circle
			(at 28.665424 -14.025372)
			(size 0.4318 0.4318)
			(layers "F.Cu" "F.Mask" "F.Paste")
			(net "GND")
		)
		(pad "AG78" smd circle
			(at 30.382464 -14.025372)
			(size 0.4318 0.4318)
			(layers "F.Cu" "F.Mask" "F.Paste")
			(net "GND")
		)
		(pad "AG80" smd circle
			(at 32.099504 -14.025372)
			(size 0.4318 0.4318)
			(layers "F.Cu" "F.Mask" "F.Paste")
			(net "GND")
		)
		(pad "AG82" smd circle
			(at 33.816544 -14.025372)
			(size 0.4318 0.4318)
			(layers "F.Cu" "F.Mask" "F.Paste")
			(net "M_B_DQS_DN<10>")
		)
		(pad "AG84" smd circle
			(at 35.533584 -14.025372)
			(size 0.4318 0.4318)
			(layers "F.Cu" "F.Mask" "F.Paste")
			(net "M_A_DQ<7>")
		)
		(pad "AG86" smd custom
			(at 37.250624 -14.025372 270)
			(size 0.10795 0.10795)
			(layers "F.Cu" "F.Mask" "F.Paste")
			(net "M_A_DQ<6>")
			(options
				(clearance outline)
				(anchor circle)
			)
			(primitives
				(gr_poly
					(pts
						(arc
							(start 0.2159 -0.0381)
							(mid 0 -0.254)
							(end -0.2159 -0.0381)
						)
						(arc
							(start -0.2159 0.0381)
							(mid 0 0.254)
							(end 0.2159 0.0381)
						)
					)
					(width 0)
					(fill yes)
				)
			)
		)
		(pad "AH1" smd custom
			(at -37.250624 -11.730228 90)
			(size 0.10795 0.10795)
			(layers "F.Cu" "F.Mask" "F.Paste")
			(net "GND")
			(options
				(clearance outline)
				(anchor circle)
			)
			(primitives
				(gr_poly
					(pts
						(arc
							(start 0.2159 -0.0381)
							(mid 0 -0.254)
							(end -0.2159 -0.0381)
						)
						(arc
							(start -0.2159 0.0381)
							(mid 0 0.254)
							(end 0.2159 0.0381)
						)
					)
					(width 0)
					(fill yes)
				)
			)
		)
		(pad "AH3" smd circle
			(at -35.533584 -11.730228)
			(size 0.4318 0.4318)
			(layers "F.Cu" "F.Mask" "F.Paste")
			(net "UPI_CPU0_CPU1_P0P0_DN<11>")
		)
		(pad "AH5" smd circle
			(at -33.816544 -11.730228)
			(size 0.4318 0.4318)
			(layers "F.Cu" "F.Mask" "F.Paste")
			(net "GND")
		)
		(pad "AH7" smd circle
			(at -32.099504 -11.730228)
			(size 0.4318 0.4318)
			(layers "F.Cu" "F.Mask" "F.Paste")
			(net "UPI_CPU1_CPU0_P0P0_DP<13>")
		)
		(pad "AH9" smd circle
			(at -30.382464 -11.730228)
			(size 0.4318 0.4318)
			(layers "F.Cu" "F.Mask" "F.Paste")
			(net "PVCCIO_CPU0")
		)
		(pad "AH11" smd circle
			(at -28.665424 -11.730228)
			(size 0.4318 0.4318)
			(layers "F.Cu" "F.Mask" "F.Paste")
			(net "XDP_CPU_MBP1_N")
		)
		(pad "AH13" smd circle
			(at -26.948384 -11.730228)
			(size 0.4318 0.4318)
			(layers "F.Cu" "F.Mask" "F.Paste")
			(net "H_CPU0_MEMABC_MEMHOT_G_N")
		)
		(pad "AH15" smd circle
			(at -25.231598 -11.730228)
			(size 0.4318 0.4318)
			(layers "F.Cu" "F.Mask" "F.Paste")
			(net "TP_CPU0_RSVD_233")
		)
		(pad "AH19" smd circle
			(at -21.797518 -11.730228)
			(size 0.4318 0.4318)
			(layers "F.Cu" "F.Mask" "F.Paste")
			(net "TP_CPU0_RSVD_232")
		)
		(pad "AH21" smd circle
			(at -20.080478 -11.730228)
			(size 0.4318 0.4318)
			(layers "F.Cu" "F.Mask" "F.Paste")
			(net "GND")
		)
		(pad "AH23" smd circle
			(at -18.363438 -11.730228)
			(size 0.4318 0.4318)
			(layers "F.Cu" "F.Mask" "F.Paste")
			(net "M_C_DQ<63>")
		)
		(pad "AH25" smd circle
			(at -16.646398 -11.730228)
			(size 0.4318 0.4318)
			(layers "F.Cu" "F.Mask" "F.Paste")
			(net "M_C_DQ<57>")
		)
		(pad "AH27" smd circle
			(at -14.929612 -11.730228)
			(size 0.4318 0.4318)
			(layers "F.Cu" "F.Mask" "F.Paste")
			(net "GND")
		)
		(pad "AH29" smd circle
			(at -13.212572 -11.730228)
			(size 0.4318 0.4318)
			(layers "F.Cu" "F.Mask" "F.Paste")
			(net "M_C_DQ<55>")
		)
		(pad "AH31" smd circle
			(at -11.495532 -11.730228)
			(size 0.4318 0.4318)
			(layers "F.Cu" "F.Mask" "F.Paste")
			(net "M_C_DQ<49>")
		)
		(pad "AH33" smd circle
			(at -9.778492 -11.730228)
			(size 0.4318 0.4318)
			(layers "F.Cu" "F.Mask" "F.Paste")
			(net "GND")
		)
		(pad "AH35" smd circle
			(at -8.061452 -11.730228)
			(size 0.4318 0.4318)
			(layers "F.Cu" "F.Mask" "F.Paste")
			(net "GND")
		)
		(pad "AH37" smd circle
			(at -6.344412 -11.730228)
			(size 0.4318 0.4318)
			(layers "F.Cu" "F.Mask" "F.Paste")
			(net "PVCCIN_CPU0")
		)
		(pad "AH39" smd circle
			(at -4.627626 -11.730228)
			(size 0.4318 0.4318)
			(layers "F.Cu" "F.Mask" "F.Paste")
			(net "PVCCIN_CPU0")
		)
		(pad "AH41" smd circle
			(at -2.910586 -11.730228)
			(size 0.4318 0.4318)
			(layers "F.Cu" "F.Mask" "F.Paste")
			(net "PVCCIN_CPU0")
		)
		(pad "AH45" smd circle
			(at 2.052066 -13.530326)
			(size 0.508 0.508)
			(layers "F.Cu" "F.Mask" "F.Paste")
			(net "GND")
		)
		(pad "AH47" smd circle
			(at 3.769106 -13.530326)
			(size 0.4318 0.4318)
			(layers "F.Cu" "F.Mask" "F.Paste")
			(net "GND")
		)
		(pad "AH49" smd circle
			(at 5.485892 -13.530326)
			(size 0.4318 0.4318)
			(layers "F.Cu" "F.Mask" "F.Paste")
			(net "GND")
		)
		(pad "AH51" smd circle
			(at 7.202932 -13.530326)
			(size 0.4318 0.4318)
			(layers "F.Cu" "F.Mask" "F.Paste")
			(net "GND")
		)
		(pad "AH53" smd circle
			(at 8.919972 -13.530326)
			(size 0.4318 0.4318)
			(layers "F.Cu" "F.Mask" "F.Paste")
			(net "GND")
		)
		(pad "AH55" smd circle
			(at 10.637012 -13.530326)
			(size 0.4318 0.4318)
			(layers "F.Cu" "F.Mask" "F.Paste")
			(net "TP_CPU0_RSVD_231")
		)
		(pad "AH57" smd circle
			(at 12.354052 -13.530326)
			(size 0.4318 0.4318)
			(layers "F.Cu" "F.Mask" "F.Paste")
			(net "TP_CPU0_RSVD_230")
		)
		(pad "AH59" smd circle
			(at 14.071092 -13.530326)
			(size 0.4318 0.4318)
			(layers "F.Cu" "F.Mask" "F.Paste")
			(net "GND")
		)
		(pad "AH61" smd circle
			(at 15.787878 -13.530326)
			(size 0.4318 0.4318)
			(layers "F.Cu" "F.Mask" "F.Paste")
			(net "GND")
		)
		(pad "AH63" smd circle
			(at 17.504918 -13.530326)
			(size 0.4318 0.4318)
			(layers "F.Cu" "F.Mask" "F.Paste")
			(net "M_C_CPU_VREF")
		)
		(pad "AH65" smd circle
			(at 19.221958 -13.530326)
			(size 0.4318 0.4318)
			(layers "F.Cu" "F.Mask" "F.Paste")
			(net "GND")
		)
		(pad "AH67" smd circle
			(at 20.938998 -13.530326)
			(size 0.4318 0.4318)
			(layers "F.Cu" "F.Mask" "F.Paste")
			(net "M_A_DQS_DN<8>")
		)
		(pad "AH69" smd circle
			(at 22.656038 -13.530326)
			(size 0.4318 0.4318)
			(layers "F.Cu" "F.Mask" "F.Paste")
			(net "GND")
		)
		(pad "AH71" smd circle
			(at 24.373078 -13.530326)
			(size 0.4318 0.4318)
			(layers "F.Cu" "F.Mask" "F.Paste")
			(net "TP_CPU0_RSVD_229")
		)
		(pad "AH73" smd circle
			(at 26.090118 -13.530326)
			(size 0.4318 0.4318)
			(layers "F.Cu" "F.Mask" "F.Paste")
			(net "TP_CPU0_RSVD_228")
		)
		(pad "AH75" smd circle
			(at 27.806904 -13.530326)
			(size 0.4318 0.4318)
			(layers "F.Cu" "F.Mask" "F.Paste")
			(net "GND")
		)
		(pad "AH77" smd circle
			(at 29.523944 -13.530326)
			(size 0.4318 0.4318)
			(layers "F.Cu" "F.Mask" "F.Paste")
			(net "GND")
		)
		(pad "AH79" smd circle
			(at 31.240984 -13.530326)
			(size 0.4318 0.4318)
			(layers "F.Cu" "F.Mask" "F.Paste")
			(net "M_B_DQ<13>")
		)
		(pad "AH81" smd circle
			(at 32.958024 -13.530326)
			(size 0.4318 0.4318)
			(layers "F.Cu" "F.Mask" "F.Paste")
			(net "M_B_DQ<8>")
		)
		(pad "AH83" smd circle
			(at 34.675064 -13.530326)
			(size 0.4318 0.4318)
			(layers "F.Cu" "F.Mask" "F.Paste")
			(net "GND")
		)
		(pad "AH85" smd circle
			(at 36.392104 -13.530326)
			(size 0.4318 0.4318)
			(layers "F.Cu" "F.Mask" "F.Paste")
			(net "M_A_DQS_DP<0>")
		)
		(pad "AJ2" smd circle
			(at -36.392104 -11.234674)
			(size 0.4318 0.4318)
			(layers "F.Cu" "F.Mask" "F.Paste")
			(net "UPI_CPU0_CPU1_P0P0_DP<11>")
		)
		(pad "AJ4" smd circle
			(at -34.675064 -11.234674)
			(size 0.4318 0.4318)
			(layers "F.Cu" "F.Mask" "F.Paste")
			(net "GND")
		)
		(pad "AJ6" smd circle
			(at -32.958024 -11.234674)
			(size 0.4318 0.4318)
			(layers "F.Cu" "F.Mask" "F.Paste")
			(net "UPI_CPU1_CPU0_P0P0_DN<13>")
		)
		(pad "AJ8" smd circle
			(at -31.240984 -11.234674)
			(size 0.4318 0.4318)
			(layers "F.Cu" "F.Mask" "F.Paste")
			(net "GND")
		)
		(pad "AJ10" smd circle
			(at -29.523944 -11.234674)
			(size 0.4318 0.4318)
			(layers "F.Cu" "F.Mask" "F.Paste")
			(net "XDP_CPU_MBP0_N")
		)
		(pad "AJ12" smd circle
			(at -27.806904 -11.234674)
			(size 0.4318 0.4318)
			(layers "F.Cu" "F.Mask" "F.Paste")
			(net "H_CPU0_ERR0_G_N")
		)
		(pad "AJ14" smd circle
			(at -26.090118 -11.234674)
			(size 0.4318 0.4318)
			(layers "F.Cu" "F.Mask" "F.Paste")
			(net "PD_CPU0_EAR_N")
		)
		(pad "AJ18" smd circle
			(at -22.656038 -11.234674)
			(size 0.4318 0.4318)
			(layers "F.Cu" "F.Mask" "F.Paste")
			(net "SMB_DDR_ABC_SCL_G_R")
		)
		(pad "AJ20" smd circle
			(at -20.938998 -11.234674)
			(size 0.4318 0.4318)
			(layers "F.Cu" "F.Mask" "F.Paste")
			(net "TP_CPU0_RSVD_227")
		)
		(pad "AJ22" smd circle
			(at -19.221958 -11.234674)
			(size 0.4318 0.4318)
			(layers "F.Cu" "F.Mask" "F.Paste")
			(net "GND")
		)
		(pad "AJ24" smd circle
			(at -17.504918 -11.234674)
			(size 0.4318 0.4318)
			(layers "F.Cu" "F.Mask" "F.Paste")
			(net "M_C_DQS_DN<7>")
		)
		(pad "AJ26" smd circle
			(at -15.787878 -11.234674)
			(size 0.4318 0.4318)
			(layers "F.Cu" "F.Mask" "F.Paste")
			(net "GND")
		)
		(pad "AJ28" smd circle
			(at -14.071092 -11.234674)
			(size 0.4318 0.4318)
			(layers "F.Cu" "F.Mask" "F.Paste")
			(net "GND")
		)
		(pad "AJ30" smd circle
			(at -12.354052 -11.234674)
			(size 0.4318 0.4318)
			(layers "F.Cu" "F.Mask" "F.Paste")
			(net "M_C_DQS_DN<6>")
		)
		(pad "AJ32" smd circle
			(at -10.637012 -11.234674)
			(size 0.4318 0.4318)
			(layers "F.Cu" "F.Mask" "F.Paste")
			(net "GND")
		)
		(pad "AJ34" smd circle
			(at -8.919972 -11.234674)
			(size 0.4318 0.4318)
			(layers "F.Cu" "F.Mask" "F.Paste")
			(net "GND")
		)
		(pad "AJ36" smd circle
			(at -7.202932 -11.234674)
			(size 0.4318 0.4318)
			(layers "F.Cu" "F.Mask" "F.Paste")
			(net "PVCCIN_CPU0")
		)
		(pad "AJ46" smd circle
			(at 2.910586 -13.034772)
			(size 0.4318 0.4318)
			(layers "F.Cu" "F.Mask" "F.Paste")
			(net "GND")
		)
		(pad "AJ48" smd circle
			(at 4.627626 -13.034772)
			(size 0.4318 0.4318)
			(layers "F.Cu" "F.Mask" "F.Paste")
			(net "GND")
		)
		(pad "AJ50" smd circle
			(at 6.344412 -13.034772)
			(size 0.4318 0.4318)
			(layers "F.Cu" "F.Mask" "F.Paste")
			(net "GND")
		)
		(pad "AJ52" smd circle
			(at 8.061452 -13.034772)
			(size 0.4318 0.4318)
			(layers "F.Cu" "F.Mask" "F.Paste")
			(net "GND")
		)
		(pad "AJ54" smd circle
			(at 9.778492 -13.034772)
			(size 0.4318 0.4318)
			(layers "F.Cu" "F.Mask" "F.Paste")
			(net "GND")
		)
		(pad "AJ56" smd circle
			(at 11.495532 -13.034772)
			(size 0.4318 0.4318)
			(layers "F.Cu" "F.Mask" "F.Paste")
			(net "TP_CPU0_RSVD_226")
		)
		(pad "AJ58" smd circle
			(at 13.212572 -13.034772)
			(size 0.4318 0.4318)
			(layers "F.Cu" "F.Mask" "F.Paste")
			(net "TP_CPU0_RSVD_225")
		)
		(pad "AJ60" smd circle
			(at 14.929612 -13.034772)
			(size 0.4318 0.4318)
			(layers "F.Cu" "F.Mask" "F.Paste")
			(net "TP_CPU0_RSVD_224")
		)
		(pad "AJ62" smd circle
			(at 16.646398 -13.034772)
			(size 0.4318 0.4318)
			(layers "F.Cu" "F.Mask" "F.Paste")
			(net "TP_CPU0_RSVD_223")
		)
		(pad "AJ64" smd circle
			(at 18.363438 -13.034772)
			(size 0.4318 0.4318)
			(layers "F.Cu" "F.Mask" "F.Paste")
			(net "M_A_CPU_VREF")
		)
		(pad "AJ66" smd circle
			(at 20.080478 -13.034772)
			(size 0.4318 0.4318)
			(layers "F.Cu" "F.Mask" "F.Paste")
			(net "GND")
		)
		(pad "AJ68" smd circle
			(at 21.797518 -13.034772)
			(size 0.4318 0.4318)
			(layers "F.Cu" "F.Mask" "F.Paste")
			(net "GND")
		)
		(pad "AJ70" smd circle
			(at 23.514558 -13.034772)
			(size 0.4318 0.4318)
			(layers "F.Cu" "F.Mask" "F.Paste")
			(net "TP_CPU0_RSVD_222")
		)
		(pad "AJ74" smd circle
			(at 26.948384 -13.034772)
			(size 0.4318 0.4318)
			(layers "F.Cu" "F.Mask" "F.Paste")
			(net "GND")
		)
		(pad "AJ76" smd circle
			(at 28.665424 -13.034772)
			(size 0.4318 0.4318)
			(layers "F.Cu" "F.Mask" "F.Paste")
			(net "M_C_DQ<3>")
		)
		(pad "AJ78" smd circle
			(at 30.382464 -13.034772)
			(size 0.4318 0.4318)
			(layers "F.Cu" "F.Mask" "F.Paste")
			(net "GND")
		)
		(pad "AJ80" smd circle
			(at 32.099504 -13.034772)
			(size 0.4318 0.4318)
			(layers "F.Cu" "F.Mask" "F.Paste")
			(net "M_B_DQ<12>")
		)
		(pad "AJ82" smd circle
			(at 33.816544 -13.034772)
			(size 0.4318 0.4318)
			(layers "F.Cu" "F.Mask" "F.Paste")
			(net "GND")
		)
		(pad "AJ84" smd circle
			(at 35.533584 -13.034772)
			(size 0.4318 0.4318)
			(layers "F.Cu" "F.Mask" "F.Paste")
			(net "M_A_DQS_DN<0>")
		)
		(pad "AJ86" smd custom
			(at 37.250624 -13.034772 270)
			(size 0.10795 0.10795)
			(layers "F.Cu" "F.Mask" "F.Paste")
			(net "GND")
			(options
				(clearance outline)
				(anchor circle)
			)
			(primitives
				(gr_poly
					(pts
						(arc
							(start 0.2159 -0.0381)
							(mid 0 -0.254)
							(end -0.2159 -0.0381)
						)
						(arc
							(start -0.2159 0.0381)
							(mid 0 0.254)
							(end 0.2159 0.0381)
						)
					)
					(width 0)
					(fill yes)
				)
			)
		)
		(pad "AK1" smd custom
			(at -37.250624 -10.739628 90)
			(size 0.10795 0.10795)
			(layers "F.Cu" "F.Mask" "F.Paste")
			(net "UPI_CPU0_CPU1_P0P0_DP<10>")
			(options
				(clearance outline)
				(anchor circle)
			)
			(primitives
				(gr_poly
					(pts
						(arc
							(start 0.2159 -0.0381)
							(mid 0 -0.254)
							(end -0.2159 -0.0381)
						)
						(arc
							(start -0.2159 0.0381)
							(mid 0 0.254)
							(end 0.2159 0.0381)
						)
					)
					(width 0)
					(fill yes)
				)
			)
		)
		(pad "AK3" smd circle
			(at -35.533584 -10.739628)
			(size 0.4318 0.4318)
			(layers "F.Cu" "F.Mask" "F.Paste")
			(net "UPI_CPU0_CPU1_P0P0_DP<9>")
		)
		(pad "AK5" smd circle
			(at -33.816544 -10.739628)
			(size 0.4318 0.4318)
			(layers "F.Cu" "F.Mask" "F.Paste")
			(net "UPI_CPU1_CPU0_P0P0_DP<12>")
		)
		(pad "AK7" smd circle
			(at -32.099504 -10.739628)
			(size 0.4318 0.4318)
			(layers "F.Cu" "F.Mask" "F.Paste")
			(net "UPI_CPU1_CPU0_P0P0_DN<11>")
		)
		(pad "AK9" smd circle
			(at -30.382464 -10.739628)
			(size 0.4318 0.4318)
			(layers "F.Cu" "F.Mask" "F.Paste")
			(net "GND")
		)
		(pad "AK11" smd circle
			(at -28.665424 -10.739628)
			(size 0.4318 0.4318)
			(layers "F.Cu" "F.Mask" "F.Paste")
			(net "H_CPU0_ERR1_G_N")
		)
		(pad "AK13" smd circle
			(at -26.948384 -10.739628)
			(size 0.4318 0.4318)
			(layers "F.Cu" "F.Mask" "F.Paste")
			(net "GND")
		)
		(pad "AK19" smd circle
			(at -21.797518 -10.739628)
			(size 0.4318 0.4318)
			(layers "F.Cu" "F.Mask" "F.Paste")
			(net "GND")
		)
		(pad "AK21" smd circle
			(at -20.080478 -10.739628)
			(size 0.4318 0.4318)
			(layers "F.Cu" "F.Mask" "F.Paste")
			(net "VSENSE_P1V8MCP_CPU0_SKT_VSEN")
		)
		(pad "AK23" smd circle
			(at -18.363438 -10.739628)
			(size 0.4318 0.4318)
			(layers "F.Cu" "F.Mask" "F.Paste")
			(net "GND")
		)
		(pad "AK25" smd circle
			(at -16.646398 -10.739628)
			(size 0.4318 0.4318)
			(layers "F.Cu" "F.Mask" "F.Paste")
			(net "GND")
		)
		(pad "AK27" smd circle
			(at -14.929612 -10.739628)
			(size 0.4318 0.4318)
			(layers "F.Cu" "F.Mask" "F.Paste")
			(net "CLK_322M_OSC_CPU0_RC_DP")
		)
		(pad "AK29" smd circle
			(at -13.212572 -10.739628)
			(size 0.4318 0.4318)
			(layers "F.Cu" "F.Mask" "F.Paste")
			(net "GND")
		)
		(pad "AK31" smd circle
			(at -11.495532 -10.739628)
			(size 0.4318 0.4318)
			(layers "F.Cu" "F.Mask" "F.Paste")
			(net "GND")
		)
		(pad "AK33" smd circle
			(at -9.778492 -10.739628)
			(size 0.4318 0.4318)
			(layers "F.Cu" "F.Mask" "F.Paste")
			(net "GND")
		)
		(pad "AK35" smd circle
			(at -8.061452 -10.739628)
			(size 0.4318 0.4318)
			(layers "F.Cu" "F.Mask" "F.Paste")
			(net "PVCCIN_CPU0")
		)
		(pad "AK45" smd circle
			(at 2.052066 -12.539726)
			(size 0.508 0.508)
			(layers "F.Cu" "F.Mask" "F.Paste")
			(net "PVCCIN_CPU0")
		)
		(pad "AK47" smd circle
			(at 3.769106 -12.539726)
			(size 0.4318 0.4318)
			(layers "F.Cu" "F.Mask" "F.Paste")
			(net "PVCCIN_CPU0")
		)
		(pad "AK49" smd circle
			(at 5.485892 -12.539726)
			(size 0.4318 0.4318)
			(layers "F.Cu" "F.Mask" "F.Paste")
			(net "PVCCIN_CPU0")
		)
		(pad "AK51" smd circle
			(at 7.202932 -12.539726)
			(size 0.4318 0.4318)
			(layers "F.Cu" "F.Mask" "F.Paste")
			(net "PVCCIN_CPU0")
		)
		(pad "AK53" smd circle
			(at 8.919972 -12.539726)
			(size 0.4318 0.4318)
			(layers "F.Cu" "F.Mask" "F.Paste")
			(net "PVCCIN_CPU0")
		)
		(pad "AK55" smd circle
			(at 10.637012 -12.539726)
			(size 0.4318 0.4318)
			(layers "F.Cu" "F.Mask" "F.Paste")
			(net "GND")
		)
		(pad "AK57" smd circle
			(at 12.354052 -12.539726)
			(size 0.4318 0.4318)
			(layers "F.Cu" "F.Mask" "F.Paste")
			(net "TP_CPU0_RSVD_219")
		)
		(pad "AK59" smd circle
			(at 14.071092 -12.539726)
			(size 0.4318 0.4318)
			(layers "F.Cu" "F.Mask" "F.Paste")
			(net "TP_CPU0_RSVD_218")
		)
		(pad "AK61" smd circle
			(at 15.787878 -12.539726)
			(size 0.4318 0.4318)
			(layers "F.Cu" "F.Mask" "F.Paste")
			(net "TP_CPU0_RSVD_217")
		)
		(pad "AK63" smd circle
			(at 17.504918 -12.539726)
			(size 0.4318 0.4318)
			(layers "F.Cu" "F.Mask" "F.Paste")
			(net "M_B_CPU_VREF")
		)
		(pad "AK65" smd circle
			(at 19.221958 -12.539726)
			(size 0.4318 0.4318)
			(layers "F.Cu" "F.Mask" "F.Paste")
			(net "GND")
		)
		(pad "AK67" smd circle
			(at 20.938998 -12.539726)
			(size 0.4318 0.4318)
			(layers "F.Cu" "F.Mask" "F.Paste")
			(net "GND")
		)
		(pad "AK69" smd circle
			(at 22.656038 -12.539726)
			(size 0.4318 0.4318)
			(layers "F.Cu" "F.Mask" "F.Paste")
			(net "TP_CPU0_RSVD_216")
		)
		(pad "AK73" smd circle
			(at 26.090118 -12.539726)
			(size 0.4318 0.4318)
			(layers "F.Cu" "F.Mask" "F.Paste")
			(net "GND")
		)
		(pad "AK75" smd circle
			(at 27.806904 -12.539726)
			(size 0.4318 0.4318)
			(layers "F.Cu" "F.Mask" "F.Paste")
			(net "M_C_DQ<7>")
		)
		(pad "AK77" smd circle
			(at 29.523944 -12.539726)
			(size 0.4318 0.4318)
			(layers "F.Cu" "F.Mask" "F.Paste")
			(net "M_C_DQ<2>")
		)
		(pad "AK79" smd circle
			(at 31.240984 -12.539726)
			(size 0.4318 0.4318)
			(layers "F.Cu" "F.Mask" "F.Paste")
			(net "GND")
		)
		(pad "AK81" smd circle
			(at 32.958024 -12.539726)
			(size 0.4318 0.4318)
			(layers "F.Cu" "F.Mask" "F.Paste")
			(net "GND")
		)
		(pad "AK83" smd circle
			(at 34.675064 -12.539726)
			(size 0.4318 0.4318)
			(layers "F.Cu" "F.Mask" "F.Paste")
			(net "GND")
		)
		(pad "AK85" smd circle
			(at 36.392104 -12.539726)
			(size 0.4318 0.4318)
			(layers "F.Cu" "F.Mask" "F.Paste")
			(net "GND")
		)
		(pad "AL2" smd circle
			(at -36.392104 -10.244074)
			(size 0.4318 0.4318)
			(layers "F.Cu" "F.Mask" "F.Paste")
			(net "UPI_CPU0_CPU1_P0P0_DN<10>")
		)
		(pad "AL4" smd circle
			(at -34.675064 -10.244074)
			(size 0.4318 0.4318)
			(layers "F.Cu" "F.Mask" "F.Paste")
			(net "GND")
		)
		(pad "AL6" smd circle
			(at -32.958024 -10.244074)
			(size 0.4318 0.4318)
			(layers "F.Cu" "F.Mask" "F.Paste")
			(net "UPI_CPU1_CPU0_P0P0_DN<12>")
		)
		(pad "AL8" smd circle
			(at -31.240984 -10.244074)
			(size 0.4318 0.4318)
			(layers "F.Cu" "F.Mask" "F.Paste")
			(net "UPI_CPU1_CPU0_P0P0_DP<10>")
		)
		(pad "AL10" smd circle
			(at -29.523944 -10.244074)
			(size 0.4318 0.4318)
			(layers "F.Cu" "F.Mask" "F.Paste")
			(net "GND")
		)
		(pad "AL12" smd circle
			(at -27.806904 -10.244074)
			(size 0.4318 0.4318)
			(layers "F.Cu" "F.Mask" "F.Paste")
			(net "H_CPU0_ERR2_G_N")
		)
		(pad "AL14" smd circle
			(at -26.090118 -10.244074)
			(size 0.4318 0.4318)
			(layers "F.Cu" "F.Mask" "F.Paste")
			(net "H_CPU0_CATERR_G_N")
		)
		(pad "AL18" smd circle
			(at -22.656038 -10.244074)
			(size 0.4318 0.4318)
			(layers "F.Cu" "F.Mask" "F.Paste")
			(net "SMB_CPU0_PE_HP_GTL_SDA")
		)
		(pad "AL20" smd circle
			(at -20.938998 -10.244074)
			(size 0.4318 0.4318)
			(layers "F.Cu" "F.Mask" "F.Paste")
			(net "VSENSE_P1V8MCP_CPU0_SKT_VRTN")
		)
		(pad "AL22" smd circle
			(at -19.221958 -10.244074)
			(size 0.4318 0.4318)
			(layers "F.Cu" "F.Mask" "F.Paste")
			(net "TP_CPU0_RSVD_214")
		)
		(pad "AL24" smd circle
			(at -17.504918 -10.244074)
			(size 0.4318 0.4318)
			(layers "F.Cu" "F.Mask" "F.Paste")
			(net "GND")
		)
		(pad "AL26" smd circle
			(at -15.787878 -10.244074)
			(size 0.4318 0.4318)
			(layers "F.Cu" "F.Mask" "F.Paste")
			(net "CLK_322M_OSC_CPU0_RC_DN")
		)
		(pad "AL28" smd circle
			(at -14.071092 -10.244074)
			(size 0.4318 0.4318)
			(layers "F.Cu" "F.Mask" "F.Paste")
			(net "PVCCIO_CPU0")
		)
		(pad "AL30" smd circle
			(at -12.354052 -10.244074)
			(size 0.4318 0.4318)
			(layers "F.Cu" "F.Mask" "F.Paste")
			(net "GND")
		)
		(pad "AL32" smd circle
			(at -10.637012 -10.244074)
			(size 0.4318 0.4318)
			(layers "F.Cu" "F.Mask" "F.Paste")
			(net "GND")
		)
		(pad "AL34" smd circle
			(at -8.919972 -10.244074)
			(size 0.4318 0.4318)
			(layers "F.Cu" "F.Mask" "F.Paste")
			(net "PVCCIN_CPU0")
		)
		(pad "AL46" smd circle
			(at 2.910586 -12.044172)
			(size 0.508 0.508)
			(layers "F.Cu" "F.Mask" "F.Paste")
			(net "PVCCIN_CPU0")
		)
		(pad "AL48" smd circle
			(at 4.627626 -12.044172)
			(size 0.508 0.508)
			(layers "F.Cu" "F.Mask" "F.Paste")
			(net "PVCCIN_CPU0")
		)
		(pad "AL50" smd circle
			(at 6.344412 -12.044172)
			(size 0.508 0.508)
			(layers "F.Cu" "F.Mask" "F.Paste")
			(net "PVCCIN_CPU0")
		)
		(pad "AL52" smd circle
			(at 8.061452 -12.044172)
			(size 0.508 0.508)
			(layers "F.Cu" "F.Mask" "F.Paste")
			(net "PVCCIN_CPU0")
		)
		(pad "AL54" smd circle
			(at 9.778492 -12.044172)
			(size 0.4318 0.4318)
			(layers "F.Cu" "F.Mask" "F.Paste")
			(net "PVCCIN_CPU0")
		)
		(pad "AL56" smd circle
			(at 11.495532 -12.044172)
			(size 0.4318 0.4318)
			(layers "F.Cu" "F.Mask" "F.Paste")
			(net "GND")
		)
		(pad "AL58" smd circle
			(at 13.212572 -12.044172)
			(size 0.4318 0.4318)
			(layers "F.Cu" "F.Mask" "F.Paste")
			(net "TP_CPU0_RSVD_212")
		)
		(pad "AL60" smd circle
			(at 14.929612 -12.044172)
			(size 0.4318 0.4318)
			(layers "F.Cu" "F.Mask" "F.Paste")
			(net "TP_CPU0_RSVD_211")
		)
		(pad "AL62" smd circle
			(at 16.646398 -12.044172)
			(size 0.4318 0.4318)
			(layers "F.Cu" "F.Mask" "F.Paste")
			(net "TP_CPU0_RSVD_210")
		)
		(pad "AL64" smd circle
			(at 18.363438 -12.044172)
			(size 0.4318 0.4318)
			(layers "F.Cu" "F.Mask" "F.Paste")
			(net "GND")
		)
		(pad "AL66" smd circle
			(at 20.080478 -12.044172)
			(size 0.4318 0.4318)
			(layers "F.Cu" "F.Mask" "F.Paste")
			(net "M_C_DQS_DN<12>")
		)
		(pad "AL68" smd circle
			(at 21.797518 -12.044172)
			(size 0.4318 0.4318)
			(layers "F.Cu" "F.Mask" "F.Paste")
			(net "GND")
		)
		(pad "AL74" smd circle
			(at 26.948384 -12.044172)
			(size 0.4318 0.4318)
			(layers "F.Cu" "F.Mask" "F.Paste")
			(net "M_C_DQS_DN<0>")
		)
		(pad "AL76" smd circle
			(at 28.665424 -12.044172)
			(size 0.4318 0.4318)
			(layers "F.Cu" "F.Mask" "F.Paste")
			(net "GND")
		)
		(pad "AL78" smd circle
			(at 30.382464 -12.044172)
			(size 0.4318 0.4318)
			(layers "F.Cu" "F.Mask" "F.Paste")
			(net "GND")
		)
		(pad "AL80" smd circle
			(at 32.099504 -12.044172)
			(size 0.4318 0.4318)
			(layers "F.Cu" "F.Mask" "F.Paste")
			(net "GND")
		)
		(pad "AL82" smd circle
			(at 33.816544 -12.044172)
			(size 0.4318 0.4318)
			(layers "F.Cu" "F.Mask" "F.Paste")
			(net "GND")
		)
		(pad "AL84" smd circle
			(at 35.533584 -12.044172)
			(size 0.4318 0.4318)
			(layers "F.Cu" "F.Mask" "F.Paste")
			(net "M_A_DQS_DN<9>")
		)
		(pad "AL86" smd custom
			(at 37.250624 -12.044172 270)
			(size 0.10795 0.10795)
			(layers "F.Cu" "F.Mask" "F.Paste")
			(net "GND")
			(options
				(clearance outline)
				(anchor circle)
			)
			(primitives
				(gr_poly
					(pts
						(arc
							(start 0.2159 -0.0381)
							(mid 0 -0.254)
							(end -0.2159 -0.0381)
						)
						(arc
							(start -0.2159 0.0381)
							(mid 0 0.254)
							(end 0.2159 0.0381)
						)
					)
					(width 0)
					(fill yes)
				)
			)
		)
		(pad "AM1" smd custom
			(at -37.250624 -9.749028 90)
			(size 0.10795 0.10795)
			(layers "F.Cu" "F.Mask" "F.Paste")
			(net "GND")
			(options
				(clearance outline)
				(anchor circle)
			)
			(primitives
				(gr_poly
					(pts
						(arc
							(start 0.2159 -0.0381)
							(mid 0 -0.254)
							(end -0.2159 -0.0381)
						)
						(arc
							(start -0.2159 0.0381)
							(mid 0 0.254)
							(end 0.2159 0.0381)
						)
					)
					(width 0)
					(fill yes)
				)
			)
		)
		(pad "AM3" smd circle
			(at -35.533584 -9.749028)
			(size 0.4318 0.4318)
			(layers "F.Cu" "F.Mask" "F.Paste")
			(net "UPI_CPU0_CPU1_P0P0_DN<9>")
		)
		(pad "AM5" smd circle
			(at -33.816544 -9.749028)
			(size 0.4318 0.4318)
			(layers "F.Cu" "F.Mask" "F.Paste")
			(net "PVCCIO_CPU0")
		)
		(pad "AM7" smd circle
			(at -32.099504 -9.749028)
			(size 0.4318 0.4318)
			(layers "F.Cu" "F.Mask" "F.Paste")
			(net "UPI_CPU1_CPU0_P0P0_DP<11>")
		)
		(pad "AM9" smd circle
			(at -30.382464 -9.749028)
			(size 0.4318 0.4318)
			(layers "F.Cu" "F.Mask" "F.Paste")
			(net "UPI_CPU1_CPU0_P0P0_DN<10>")
		)
		(pad "AM11" smd circle
			(at -28.665424 -9.749028)
			(size 0.4318 0.4318)
			(layers "F.Cu" "F.Mask" "F.Paste")
			(net "PU_CPU0_TSC_SYNC")
		)
		(pad "AM13" smd circle
			(at -26.948384 -9.749028)
			(size 0.4318 0.4318)
			(layers "F.Cu" "F.Mask" "F.Paste")
			(net "TP_CPU0_RSVD_TEST_3")
		)
		(pad "AM19" smd circle
			(at -21.797518 -9.749028)
			(size 0.4318 0.4318)
			(layers "F.Cu" "F.Mask" "F.Paste")
			(net "SMB_CPU0_PE_HP_GTL_SCL")
		)
		(pad "AM21" smd circle
			(at -20.080478 -9.749028)
			(size 0.4318 0.4318)
			(layers "F.Cu" "F.Mask" "F.Paste")
			(net "PVCCMCP_CPU0")
		)
		(pad "AM23" smd circle
			(at -18.363438 -9.749028)
			(size 0.4318 0.4318)
			(layers "F.Cu" "F.Mask" "F.Paste")
			(net "TP_CPU0_RSVD_208")
		)
		(pad "AM25" smd circle
			(at -16.646398 -9.749028)
			(size 0.4318 0.4318)
			(layers "F.Cu" "F.Mask" "F.Paste")
			(net "PVCCMCP_CPU0")
		)
		(pad "AM27" smd circle
			(at -14.929612 -9.749028)
			(size 0.4318 0.4318)
			(layers "F.Cu" "F.Mask" "F.Paste")
			(net "CLK_100M_CPU0_RC_REFCLK0_DP")
		)
		(pad "AM29" smd circle
			(at -13.212572 -9.749028)
			(size 0.4318 0.4318)
			(layers "F.Cu" "F.Mask" "F.Paste")
			(net "PVCCIO_CPU0")
		)
		(pad "AM31" smd circle
			(at -11.495532 -9.749028)
			(size 0.4318 0.4318)
			(layers "F.Cu" "F.Mask" "F.Paste")
			(net "GND")
		)
		(pad "AM33" smd circle
			(at -9.778492 -9.749028)
			(size 0.4318 0.4318)
			(layers "F.Cu" "F.Mask" "F.Paste")
			(net "PVCCIN_CPU0")
		)
		(pad "AM53" smd circle
			(at 8.919972 -11.549126)
			(size 0.508 0.508)
			(layers "F.Cu" "F.Mask" "F.Paste")
			(net "PVCCIN_CPU0")
		)
		(pad "AM55" smd circle
			(at 10.637012 -11.549126)
			(size 0.4318 0.4318)
			(layers "F.Cu" "F.Mask" "F.Paste")
			(net "PVCCIN_CPU0")
		)
		(pad "AM57" smd circle
			(at 12.354052 -11.549126)
			(size 0.4318 0.4318)
			(layers "F.Cu" "F.Mask" "F.Paste")
			(net "GND")
		)
		(pad "AM59" smd circle
			(at 14.071092 -11.549126)
			(size 0.4318 0.4318)
			(layers "F.Cu" "F.Mask" "F.Paste")
			(net "TP_CPU0_RSVD_205")
		)
		(pad "AM61" smd circle
			(at 15.787878 -11.549126)
			(size 0.4318 0.4318)
			(layers "F.Cu" "F.Mask" "F.Paste")
			(net "TP_CPU0_RSVD_204")
		)
		(pad "AM63" smd circle
			(at 17.504918 -11.549126)
			(size 0.4318 0.4318)
			(layers "F.Cu" "F.Mask" "F.Paste")
			(net "GND")
		)
		(pad "AM65" smd circle
			(at 19.221958 -11.549126)
			(size 0.4318 0.4318)
			(layers "F.Cu" "F.Mask" "F.Paste")
			(net "M_C_DQ<30>")
		)
		(pad "AM67" smd circle
			(at 20.938998 -11.549126)
			(size 0.4318 0.4318)
			(layers "F.Cu" "F.Mask" "F.Paste")
			(net "M_C_DQ<24>")
		)
		(pad "AM69" smd circle
			(at 22.656038 -11.549126)
			(size 0.4318 0.4318)
			(layers "F.Cu" "F.Mask" "F.Paste")
			(net "GND")
		)
		(pad "AM73" smd circle
			(at 26.090118 -11.549126)
			(size 0.4318 0.4318)
			(layers "F.Cu" "F.Mask" "F.Paste")
			(net "GND")
		)
		(pad "AM75" smd circle
			(at 27.806904 -11.549126)
			(size 0.4318 0.4318)
			(layers "F.Cu" "F.Mask" "F.Paste")
			(net "M_C_DQS_DP<0>")
		)
		(pad "AM77" smd circle
			(at 29.523944 -11.549126)
			(size 0.4318 0.4318)
			(layers "F.Cu" "F.Mask" "F.Paste")
			(net "M_C_DQ<6>")
		)
		(pad "AM79" smd circle
			(at 31.240984 -11.549126)
			(size 0.4318 0.4318)
			(layers "F.Cu" "F.Mask" "F.Paste")
			(net "GND")
		)
		(pad "AM81" smd circle
			(at 32.958024 -11.549126)
			(size 0.4318 0.4318)
			(layers "F.Cu" "F.Mask" "F.Paste")
			(net "M_B_DQ<3>")
		)
		(pad "AM83" smd circle
			(at 34.675064 -11.549126)
			(size 0.4318 0.4318)
			(layers "F.Cu" "F.Mask" "F.Paste")
			(net "GND")
		)
		(pad "AM85" smd circle
			(at 36.392104 -11.549126)
			(size 0.4318 0.4318)
			(layers "F.Cu" "F.Mask" "F.Paste")
			(net "M_A_DQS_DP<9>")
		)
		(pad "AN2" smd circle
			(at -36.392104 -9.253474)
			(size 0.4318 0.4318)
			(layers "F.Cu" "F.Mask" "F.Paste")
			(net "GND")
		)
		(pad "AN4" smd circle
			(at -34.675064 -9.253474)
			(size 0.4318 0.4318)
			(layers "F.Cu" "F.Mask" "F.Paste")
			(net "UPI_CPU0_CPU1_P0P0_DN<8>")
		)
		(pad "AN6" smd circle
			(at -32.958024 -9.253474)
			(size 0.4318 0.4318)
			(layers "F.Cu" "F.Mask" "F.Paste")
			(net "GND")
		)
		(pad "AN8" smd circle
			(at -31.240984 -9.253474)
			(size 0.4318 0.4318)
			(layers "F.Cu" "F.Mask" "F.Paste")
			(net "UPI_CPU1_CPU0_P0P0_DP<9>")
		)
		(pad "AN10" smd circle
			(at -29.523944 -9.253474)
			(size 0.4318 0.4318)
			(layers "F.Cu" "F.Mask" "F.Paste")
			(net "PVCCIO_CPU0")
		)
		(pad "AN12" smd circle
			(at -27.806904 -9.253474)
			(size 0.4318 0.4318)
			(layers "F.Cu" "F.Mask" "F.Paste")
			(net "TP_CPU0_RSVD_TEST_4")
		)
		(pad "AN14" smd circle
			(at -26.090118 -9.253474)
			(size 0.4318 0.4318)
			(layers "F.Cu" "F.Mask" "F.Paste")
			(net "TP_CPU0_RSVD_TEST_5")
		)
		(pad "AN18" smd circle
			(at -22.656038 -9.253474)
			(size 0.4318 0.4318)
			(layers "F.Cu" "F.Mask" "F.Paste")
			(net "PVCCMCP_CPU0")
		)
		(pad "AN20" smd circle
			(at -20.938998 -9.253474)
			(size 0.4318 0.4318)
			(layers "F.Cu" "F.Mask" "F.Paste")
			(net "H_CPU0_MSMI_G_N")
		)
		(pad "AN22" smd circle
			(at -19.221958 -9.253474)
			(size 0.4318 0.4318)
			(layers "F.Cu" "F.Mask" "F.Paste")
			(net "PVCCMCP_CPU0")
		)
		(pad "AN24" smd circle
			(at -17.504918 -9.253474)
			(size 0.4318 0.4318)
			(layers "F.Cu" "F.Mask" "F.Paste")
			(net "PVCCMCP_CPU0")
		)
		(pad "AN26" smd circle
			(at -15.787878 -9.253474)
			(size 0.4318 0.4318)
			(layers "F.Cu" "F.Mask" "F.Paste")
			(net "PVCCMCP_CPU0")
		)
		(pad "AN28" smd circle
			(at -14.071092 -9.253474)
			(size 0.4318 0.4318)
			(layers "F.Cu" "F.Mask" "F.Paste")
			(net "GND")
		)
		(pad "AN30" smd circle
			(at -12.354052 -9.253474)
			(size 0.4318 0.4318)
			(layers "F.Cu" "F.Mask" "F.Paste")
			(net "PWRGD_CPU0_DRAMPWROK_ABC_G")
		)
		(pad "AN32" smd circle
			(at -10.637012 -9.253474)
			(size 0.4318 0.4318)
			(layers "F.Cu" "F.Mask" "F.Paste")
			(net "PVCCIN_CPU0")
		)
		(pad "AN54" smd circle
			(at 9.778492 -11.053572)
			(size 0.508 0.508)
			(layers "F.Cu" "F.Mask" "F.Paste")
			(net "PVCCIN_CPU0")
		)
		(pad "AN56" smd circle
			(at 11.495532 -11.053572)
			(size 0.4318 0.4318)
			(layers "F.Cu" "F.Mask" "F.Paste")
			(net "PVCCIN_CPU0")
		)
		(pad "AN58" smd circle
			(at 13.212572 -11.053572)
			(size 0.4318 0.4318)
			(layers "F.Cu" "F.Mask" "F.Paste")
			(net "GND")
		)
		(pad "AN60" smd circle
			(at 14.929612 -11.053572)
			(size 0.4318 0.4318)
			(layers "F.Cu" "F.Mask" "F.Paste")
			(net "TP_CPU0_RSVD_199")
		)
		(pad "AN62" smd circle
			(at 16.646398 -11.053572)
			(size 0.4318 0.4318)
			(layers "F.Cu" "F.Mask" "F.Paste")
			(net "TP_CPU0_RSVD_198")
		)
		(pad "AN64" smd circle
			(at 18.363438 -11.053572)
			(size 0.4318 0.4318)
			(layers "F.Cu" "F.Mask" "F.Paste")
			(net "M_C_DQ<26>")
		)
		(pad "AN66" smd circle
			(at 20.080478 -11.053572)
			(size 0.4318 0.4318)
			(layers "F.Cu" "F.Mask" "F.Paste")
			(net "M_C_DQS_DP<12>")
		)
		(pad "AN68" smd circle
			(at 21.797518 -11.053572)
			(size 0.4318 0.4318)
			(layers "F.Cu" "F.Mask" "F.Paste")
			(net "M_C_DQ<28>")
		)
		(pad "AN74" smd circle
			(at 26.948384 -11.053572)
			(size 0.4318 0.4318)
			(layers "F.Cu" "F.Mask" "F.Paste")
			(net "M_C_DQ<1>")
		)
		(pad "AN76" smd circle
			(at 28.665424 -11.053572)
			(size 0.4318 0.4318)
			(layers "F.Cu" "F.Mask" "F.Paste")
			(net "M_C_DQS_DP<9>")
		)
		(pad "AN78" smd circle
			(at 30.382464 -11.053572)
			(size 0.4318 0.4318)
			(layers "F.Cu" "F.Mask" "F.Paste")
			(net "GND")
		)
		(pad "AN80" smd circle
			(at 32.099504 -11.053572)
			(size 0.4318 0.4318)
			(layers "F.Cu" "F.Mask" "F.Paste")
			(net "M_B_DQ<7>")
		)
		(pad "AN82" smd circle
			(at 33.816544 -11.053572)
			(size 0.4318 0.4318)
			(layers "F.Cu" "F.Mask" "F.Paste")
			(net "M_B_DQ<2>")
		)
		(pad "AN84" smd circle
			(at 35.533584 -11.053572)
			(size 0.4318 0.4318)
			(layers "F.Cu" "F.Mask" "F.Paste")
			(net "M_A_DQ<1>")
		)
		(pad "AN86" smd custom
			(at 37.250624 -11.053572 270)
			(size 0.10795 0.10795)
			(layers "F.Cu" "F.Mask" "F.Paste")
			(net "M_A_DQ<0>")
			(options
				(clearance outline)
				(anchor circle)
			)
			(primitives
				(gr_poly
					(pts
						(arc
							(start 0.2159 -0.0381)
							(mid 0 -0.254)
							(end -0.2159 -0.0381)
						)
						(arc
							(start -0.2159 0.0381)
							(mid 0 0.254)
							(end 0.2159 0.0381)
						)
					)
					(width 0)
					(fill yes)
				)
			)
		)
		(pad "AP1" smd custom
			(at -37.250624 -8.758428 90)
			(size 0.10795 0.10795)
			(layers "F.Cu" "F.Mask" "F.Paste")
			(net "UPI_CPU0_CPU1_P0P0_DP<7>")
			(options
				(clearance outline)
				(anchor circle)
			)
			(primitives
				(gr_poly
					(pts
						(arc
							(start 0.2159 -0.0381)
							(mid 0 -0.254)
							(end -0.2159 -0.0381)
						)
						(arc
							(start -0.2159 0.0381)
							(mid 0 0.254)
							(end 0.2159 0.0381)
						)
					)
					(width 0)
					(fill yes)
				)
			)
		)
		(pad "AP3" smd circle
			(at -35.533584 -8.758428)
			(size 0.4318 0.4318)
			(layers "F.Cu" "F.Mask" "F.Paste")
			(net "UPI_CPU0_CPU1_P0P0_DP<8>")
		)
		(pad "AP5" smd circle
			(at -33.816544 -8.758428)
			(size 0.4318 0.4318)
			(layers "F.Cu" "F.Mask" "F.Paste")
			(net "GND")
		)
		(pad "AP7" smd circle
			(at -32.099504 -8.758428)
			(size 0.4318 0.4318)
			(layers "F.Cu" "F.Mask" "F.Paste")
			(net "UPI_CPU1_CPU0_P0P0_DN<9>")
		)
		(pad "AP9" smd circle
			(at -30.382464 -8.758428)
			(size 0.4318 0.4318)
			(layers "F.Cu" "F.Mask" "F.Paste")
			(net "GND")
		)
		(pad "AP11" smd circle
			(at -28.665424 -8.758428)
			(size 0.4318 0.4318)
			(layers "F.Cu" "F.Mask" "F.Paste")
			(net "TP_NMI_CPU0")
		)
		(pad "AP13" smd circle
			(at -26.948384 -8.758428)
			(size 0.4318 0.4318)
			(layers "F.Cu" "F.Mask" "F.Paste")
			(net "GND")
		)
		(pad "AP17" smd circle
			(at -23.514558 -8.758428)
			(size 0.4318 0.4318)
			(layers "F.Cu" "F.Mask" "F.Paste")
			(net "XDP_CPU_PWR_DEBUG_N")
		)
		(pad "AP19" smd circle
			(at -21.797518 -8.758428)
			(size 0.4318 0.4318)
			(layers "F.Cu" "F.Mask" "F.Paste")
			(net "GND")
		)
		(pad "AP21" smd circle
			(at -20.080478 -8.758428)
			(size 0.4318 0.4318)
			(layers "F.Cu" "F.Mask" "F.Paste")
			(net "RST_CPU0_G_N")
		)
		(pad "AP23" smd circle
			(at -18.363438 -8.758428)
			(size 0.4318 0.4318)
			(layers "F.Cu" "F.Mask" "F.Paste")
			(net "PVCCMCP_CPU0")
		)
		(pad "AP25" smd circle
			(at -16.646398 -8.758428)
			(size 0.4318 0.4318)
			(layers "F.Cu" "F.Mask" "F.Paste")
			(net "PVCCMCP_CPU0")
		)
		(pad "AP27" smd circle
			(at -14.929612 -8.758428)
			(size 0.4318 0.4318)
			(layers "F.Cu" "F.Mask" "F.Paste")
			(net "CLK_100M_CPU0_RC_REFCLK0_DN")
		)
		(pad "AP29" smd circle
			(at -13.212572 -8.758428)
			(size 0.4318 0.4318)
			(layers "F.Cu" "F.Mask" "F.Paste")
			(net "A_CPU0_UPI01_RBIAS")
		)
		(pad "AP31" smd circle
			(at -11.495532 -8.758428)
			(size 0.4318 0.4318)
			(layers "F.Cu" "F.Mask" "F.Paste")
			(net "GND")
		)
		(pad "AP55" smd circle
			(at 10.637012 -10.558526)
			(size 0.508 0.508)
			(layers "F.Cu" "F.Mask" "F.Paste")
			(net "PVCCIN_CPU0")
		)
		(pad "AP57" smd circle
			(at 12.354052 -10.558526)
			(size 0.4318 0.4318)
			(layers "F.Cu" "F.Mask" "F.Paste")
			(net "PVCCIN_CPU0")
		)
		(pad "AP59" smd circle
			(at 14.071092 -10.558526)
			(size 0.4318 0.4318)
			(layers "F.Cu" "F.Mask" "F.Paste")
			(net "GND")
		)
		(pad "AP61" smd circle
			(at 15.787878 -10.558526)
			(size 0.4318 0.4318)
			(layers "F.Cu" "F.Mask" "F.Paste")
			(net "TP_CPU0_RSVD_194")
		)
		(pad "AP63" smd circle
			(at 17.504918 -10.558526)
			(size 0.4318 0.4318)
			(layers "F.Cu" "F.Mask" "F.Paste")
			(net "GND")
		)
		(pad "AP65" smd circle
			(at 19.221958 -10.558526)
			(size 0.4318 0.4318)
			(layers "F.Cu" "F.Mask" "F.Paste")
			(net "GND")
		)
		(pad "AP67" smd circle
			(at 20.938998 -10.558526)
			(size 0.4318 0.4318)
			(layers "F.Cu" "F.Mask" "F.Paste")
			(net "GND")
		)
		(pad "AP69" smd circle
			(at 22.656038 -10.558526)
			(size 0.4318 0.4318)
			(layers "F.Cu" "F.Mask" "F.Paste")
			(net "GND")
		)
		(pad "AP73" smd circle
			(at 26.090118 -10.558526)
			(size 0.4318 0.4318)
			(layers "F.Cu" "F.Mask" "F.Paste")
			(net "GND")
		)
		(pad "AP75" smd circle
			(at 27.806904 -10.558526)
			(size 0.4318 0.4318)
			(layers "F.Cu" "F.Mask" "F.Paste")
			(net "GND")
		)
		(pad "AP77" smd circle
			(at 29.523944 -10.558526)
			(size 0.4318 0.4318)
			(layers "F.Cu" "F.Mask" "F.Paste")
			(net "M_C_DQS_DN<9>")
		)
		(pad "AP79" smd circle
			(at 31.240984 -10.558526)
			(size 0.4318 0.4318)
			(layers "F.Cu" "F.Mask" "F.Paste")
			(net "M_B_DQS_DN<0>")
		)
		(pad "AP81" smd circle
			(at 32.958024 -10.558526)
			(size 0.4318 0.4318)
			(layers "F.Cu" "F.Mask" "F.Paste")
			(net "GND")
		)
		(pad "AP83" smd circle
			(at 34.675064 -10.558526)
			(size 0.4318 0.4318)
			(layers "F.Cu" "F.Mask" "F.Paste")
			(net "GND")
		)
		(pad "AP85" smd circle
			(at 36.392104 -10.558526)
			(size 0.4318 0.4318)
			(layers "F.Cu" "F.Mask" "F.Paste")
			(net "GND")
		)
		(pad "AR2" smd circle
			(at -36.392104 -8.262874)
			(size 0.4318 0.4318)
			(layers "F.Cu" "F.Mask" "F.Paste")
			(net "UPI_CPU0_CPU1_P0P0_DP<6>")
		)
		(pad "AR4" smd circle
			(at -34.675064 -8.262874)
			(size 0.4318 0.4318)
			(layers "F.Cu" "F.Mask" "F.Paste")
			(net "UPI_CPU0_CPU1_P0P0_DP<5>")
		)
		(pad "AR6" smd circle
			(at -32.958024 -8.262874)
			(size 0.4318 0.4318)
			(layers "F.Cu" "F.Mask" "F.Paste")
			(net "GND")
		)
		(pad "AR8" smd circle
			(at -31.240984 -8.262874)
			(size 0.4318 0.4318)
			(layers "F.Cu" "F.Mask" "F.Paste")
			(net "UPI_CPU1_CPU0_P0P0_DN<8>")
		)
		(pad "AR10" smd circle
			(at -29.523944 -8.262874)
			(size 0.4318 0.4318)
			(layers "F.Cu" "F.Mask" "F.Paste")
			(net "GND")
		)
		(pad "AR12" smd circle
			(at -27.806904 -8.262874)
			(size 0.4318 0.4318)
			(layers "F.Cu" "F.Mask" "F.Paste")
			(net "XDP_CPU_PREQ_N")
		)
		(pad "AR14" smd circle
			(at -26.090118 -8.262874)
			(size 0.4318 0.4318)
			(layers "F.Cu" "F.Mask" "F.Paste")
			(net "H_PM_SYNC_GTL_R1")
		)
		(pad "AR16" smd circle
			(at -24.373078 -8.262874)
			(size 0.4318 0.4318)
			(layers "F.Cu" "F.Mask" "F.Paste")
			(net "TP_CPU0_TEST_6")
		)
		(pad "AR18" smd circle
			(at -22.656038 -8.262874)
			(size 0.4318 0.4318)
			(layers "F.Cu" "F.Mask" "F.Paste")
			(net "PU_CPU0_SAFE_MODE_BOOT")
		)
		(pad "AR20" smd circle
			(at -20.938998 -8.262874)
			(size 0.4318 0.4318)
			(layers "F.Cu" "F.Mask" "F.Paste")
			(net "PVCCMCP_CPU0")
		)
		(pad "AR22" smd circle
			(at -19.221958 -8.262874)
			(size 0.4318 0.4318)
			(layers "F.Cu" "F.Mask" "F.Paste")
			(net "PVCCMCP_CPU0")
		)
		(pad "AR24" smd circle
			(at -17.504918 -8.262874)
			(size 0.4318 0.4318)
			(layers "F.Cu" "F.Mask" "F.Paste")
			(net "GND")
		)
		(pad "AR26" smd circle
			(at -15.787878 -8.262874)
			(size 0.4318 0.4318)
			(layers "F.Cu" "F.Mask" "F.Paste")
			(net "PVCCMCP_CPU0")
		)
		(pad "AR28" smd circle
			(at -14.071092 -8.262874)
			(size 0.4318 0.4318)
			(layers "F.Cu" "F.Mask" "F.Paste")
			(net "PVCCIO_CPU0")
		)
		(pad "AR30" smd circle
			(at -12.354052 -8.262874)
			(size 0.4318 0.4318)
			(layers "F.Cu" "F.Mask" "F.Paste")
			(net "GND")
		)
		(pad "AR56" smd circle
			(at 11.495532 -10.062972)
			(size 0.508 0.508)
			(layers "F.Cu" "F.Mask" "F.Paste")
			(net "PVCCIN_CPU0")
		)
		(pad "AR58" smd circle
			(at 13.212572 -10.062972)
			(size 0.4318 0.4318)
			(layers "F.Cu" "F.Mask" "F.Paste")
			(net "PVCCIN_CPU0")
		)
		(pad "AR60" smd circle
			(at 14.929612 -10.062972)
			(size 0.4318 0.4318)
			(layers "F.Cu" "F.Mask" "F.Paste")
			(net "GND")
		)
		(pad "AR62" smd circle
			(at 16.646398 -10.062972)
			(size 0.4318 0.4318)
			(layers "F.Cu" "F.Mask" "F.Paste")
			(net "TP_CPU0_RSVD_190")
		)
		(pad "AR64" smd circle
			(at 18.363438 -10.062972)
			(size 0.4318 0.4318)
			(layers "F.Cu" "F.Mask" "F.Paste")
			(net "M_C_DQ<27>")
		)
		(pad "AR66" smd circle
			(at 20.080478 -10.062972)
			(size 0.4318 0.4318)
			(layers "F.Cu" "F.Mask" "F.Paste")
			(net "M_C_DQS_DP<3>")
		)
		(pad "AR68" smd circle
			(at 21.797518 -10.062972)
			(size 0.4318 0.4318)
			(layers "F.Cu" "F.Mask" "F.Paste")
			(net "M_C_DQ<29>")
		)
		(pad "AR72" smd circle
			(at 25.231598 -10.062972)
			(size 0.4318 0.4318)
			(layers "F.Cu" "F.Mask" "F.Paste")
			(net "GND")
		)
		(pad "AR74" smd circle
			(at 26.948384 -10.062972)
			(size 0.4318 0.4318)
			(layers "F.Cu" "F.Mask" "F.Paste")
			(net "M_C_DQ<5>")
		)
		(pad "AR76" smd circle
			(at 28.665424 -10.062972)
			(size 0.4318 0.4318)
			(layers "F.Cu" "F.Mask" "F.Paste")
			(net "M_C_DQ<0>")
		)
		(pad "AR78" smd circle
			(at 30.382464 -10.062972)
			(size 0.4318 0.4318)
			(layers "F.Cu" "F.Mask" "F.Paste")
			(net "GND")
		)
		(pad "AR80" smd circle
			(at 32.099504 -10.062972)
			(size 0.4318 0.4318)
			(layers "F.Cu" "F.Mask" "F.Paste")
			(net "M_B_DQS_DP<0>")
		)
		(pad "AR82" smd circle
			(at 33.816544 -10.062972)
			(size 0.4318 0.4318)
			(layers "F.Cu" "F.Mask" "F.Paste")
			(net "M_B_DQ<6>")
		)
		(pad "AR84" smd circle
			(at 35.533584 -10.062972)
			(size 0.4318 0.4318)
			(layers "F.Cu" "F.Mask" "F.Paste")
			(net "M_A_DQ<5>")
		)
		(pad "AR86" smd custom
			(at 37.250624 -10.062972 270)
			(size 0.10795 0.10795)
			(layers "F.Cu" "F.Mask" "F.Paste")
			(net "M_A_DQ<4>")
			(options
				(clearance outline)
				(anchor circle)
			)
			(primitives
				(gr_poly
					(pts
						(arc
							(start 0.2159 -0.0381)
							(mid 0 -0.254)
							(end -0.2159 -0.0381)
						)
						(arc
							(start -0.2159 0.0381)
							(mid 0 0.254)
							(end 0.2159 0.0381)
						)
					)
					(width 0)
					(fill yes)
				)
			)
		)
		(pad "AT1" smd custom
			(at -37.250624 -7.767828 90)
			(size 0.10795 0.10795)
			(layers "F.Cu" "F.Mask" "F.Paste")
			(net "UPI_CPU0_CPU1_P0P0_DN<7>")
			(options
				(clearance outline)
				(anchor circle)
			)
			(primitives
				(gr_poly
					(pts
						(arc
							(start 0.2159 -0.0381)
							(mid 0 -0.254)
							(end -0.2159 -0.0381)
						)
						(arc
							(start -0.2159 0.0381)
							(mid 0 0.254)
							(end 0.2159 0.0381)
						)
					)
					(width 0)
					(fill yes)
				)
			)
		)
		(pad "AT3" smd circle
			(at -35.533584 -7.767828)
			(size 0.4318 0.4318)
			(layers "F.Cu" "F.Mask" "F.Paste")
			(net "UPI_CPU0_CPU1_P0P0_DN<6>")
		)
		(pad "AT5" smd circle
			(at -33.816544 -7.767828)
			(size 0.4318 0.4318)
			(layers "F.Cu" "F.Mask" "F.Paste")
			(net "PVCCIO_CPU0")
		)
		(pad "AT7" smd circle
			(at -32.099504 -7.767828)
			(size 0.4318 0.4318)
			(layers "F.Cu" "F.Mask" "F.Paste")
			(net "PVCCIO_CPU0")
		)
		(pad "AT9" smd circle
			(at -30.382464 -7.767828)
			(size 0.4318 0.4318)
			(layers "F.Cu" "F.Mask" "F.Paste")
			(net "UPI_CPU1_CPU0_P0P0_DP<7>")
		)
		(pad "AT11" smd circle
			(at -28.665424 -7.767828)
			(size 0.4318 0.4318)
			(layers "F.Cu" "F.Mask" "F.Paste")
			(net "PVCCIO_CPU0")
		)
		(pad "AT13" smd circle
			(at -26.948384 -7.767828)
			(size 0.4318 0.4318)
			(layers "F.Cu" "F.Mask" "F.Paste")
			(net "TP_CPU0_RSVD_189")
		)
		(pad "AT15" smd circle
			(at -25.231598 -7.767828)
			(size 0.4318 0.4318)
			(layers "F.Cu" "F.Mask" "F.Paste")
			(net "GND")
		)
		(pad "AT17" smd circle
			(at -23.514558 -7.767828)
			(size 0.4318 0.4318)
			(layers "F.Cu" "F.Mask" "F.Paste")
			(net "GND")
		)
		(pad "AT19" smd circle
			(at -21.797518 -7.767828)
			(size 0.4318 0.4318)
			(layers "F.Cu" "F.Mask" "F.Paste")
			(net "H_PMSYNC_CLK_24M_CPU0")
		)
		(pad "AT21" smd circle
			(at -20.080478 -7.767828)
			(size 0.4318 0.4318)
			(layers "F.Cu" "F.Mask" "F.Paste")
			(net "GND")
		)
		(pad "AT23" smd circle
			(at -18.363438 -7.767828)
			(size 0.4318 0.4318)
			(layers "F.Cu" "F.Mask" "F.Paste")
			(net "PVCCMCP_CPU0")
		)
		(pad "AT25" smd circle
			(at -16.646398 -7.767828)
			(size 0.4318 0.4318)
			(layers "F.Cu" "F.Mask" "F.Paste")
			(net "PVCCMCP_CPU0")
		)
		(pad "AT27" smd circle
			(at -14.929612 -7.767828)
			(size 0.4318 0.4318)
			(layers "F.Cu" "F.Mask" "F.Paste")
			(net "GND")
		)
		(pad "AT29" smd circle
			(at -13.212572 -7.767828)
			(size 0.4318 0.4318)
			(layers "F.Cu" "F.Mask" "F.Paste")
			(net "A_CPU0_UPI01_RBIAS")
		)
		(pad "AT57" smd circle
			(at 12.354052 -9.567926)
			(size 0.508 0.508)
			(layers "F.Cu" "F.Mask" "F.Paste")
			(net "PVCCIN_CPU0")
		)
		(pad "AT59" smd circle
			(at 14.071092 -9.567926)
			(size 0.4318 0.4318)
			(layers "F.Cu" "F.Mask" "F.Paste")
			(net "PVCCIN_CPU0")
		)
		(pad "AT61" smd circle
			(at 15.787878 -9.567926)
			(size 0.4318 0.4318)
			(layers "F.Cu" "F.Mask" "F.Paste")
			(net "GND")
		)
		(pad "AT63" smd circle
			(at 17.504918 -9.567926)
			(size 0.4318 0.4318)
			(layers "F.Cu" "F.Mask" "F.Paste")
			(net "GND")
		)
		(pad "AT65" smd circle
			(at 19.221958 -9.567926)
			(size 0.4318 0.4318)
			(layers "F.Cu" "F.Mask" "F.Paste")
			(net "M_C_DQ<31>")
		)
		(pad "AT67" smd circle
			(at 20.938998 -9.567926)
			(size 0.4318 0.4318)
			(layers "F.Cu" "F.Mask" "F.Paste")
			(net "M_C_DQ<25>")
		)
		(pad "AT69" smd circle
			(at 22.656038 -9.567926)
			(size 0.4318 0.4318)
			(layers "F.Cu" "F.Mask" "F.Paste")
			(net "GND")
		)
		(pad "AT71" smd circle
			(at 24.373078 -9.567926)
			(size 0.4318 0.4318)
			(layers "F.Cu" "F.Mask" "F.Paste")
			(net "M_C_DQS_DN<17>")
		)
		(pad "AT73" smd circle
			(at 26.090118 -9.567926)
			(size 0.4318 0.4318)
			(layers "F.Cu" "F.Mask" "F.Paste")
			(net "GND")
		)
		(pad "AT75" smd circle
			(at 27.806904 -9.567926)
			(size 0.4318 0.4318)
			(layers "F.Cu" "F.Mask" "F.Paste")
			(net "M_C_DQ<4>")
		)
		(pad "AT77" smd circle
			(at 29.523944 -9.567926)
			(size 0.4318 0.4318)
			(layers "F.Cu" "F.Mask" "F.Paste")
			(net "GND")
		)
		(pad "AT79" smd circle
			(at 31.240984 -9.567926)
			(size 0.4318 0.4318)
			(layers "F.Cu" "F.Mask" "F.Paste")
			(net "M_B_DQ<1>")
		)
		(pad "AT81" smd circle
			(at 32.958024 -9.567926)
			(size 0.4318 0.4318)
			(layers "F.Cu" "F.Mask" "F.Paste")
			(net "M_B_DQS_DP<9>")
		)
		(pad "AT83" smd circle
			(at 34.675064 -9.567926)
			(size 0.4318 0.4318)
			(layers "F.Cu" "F.Mask" "F.Paste")
			(net "GND")
		)
		(pad "AT85" smd circle
			(at 36.392104 -9.567926)
			(size 0.4318 0.4318)
			(layers "F.Cu" "F.Mask" "F.Paste")
			(net "GND")
		)
		(pad "AU2" smd circle
			(at -36.392104 -7.272274)
			(size 0.4318 0.4318)
			(layers "F.Cu" "F.Mask" "F.Paste")
			(net "GND")
		)
		(pad "AU4" smd circle
			(at -34.675064 -7.272274)
			(size 0.4318 0.4318)
			(layers "F.Cu" "F.Mask" "F.Paste")
			(net "UPI_CPU0_CPU1_P0P0_DN<5>")
		)
		(pad "AU6" smd circle
			(at -32.958024 -7.272274)
			(size 0.4318 0.4318)
			(layers "F.Cu" "F.Mask" "F.Paste")
			(net "GND")
		)
		(pad "AU8" smd circle
			(at -31.240984 -7.272274)
			(size 0.4318 0.4318)
			(layers "F.Cu" "F.Mask" "F.Paste")
			(net "UPI_CPU1_CPU0_P0P0_DP<8>")
		)
		(pad "AU10" smd circle
			(at -29.523944 -7.272274)
			(size 0.4318 0.4318)
			(layers "F.Cu" "F.Mask" "F.Paste")
			(net "UPI_CPU1_CPU0_P0P0_DN<7>")
		)
		(pad "AU12" smd circle
			(at -27.806904 -7.272274)
			(size 0.4318 0.4318)
			(layers "F.Cu" "F.Mask" "F.Paste")
			(net "PECI_CPU_G")
		)
		(pad "AU14" smd circle
			(at -26.090118 -7.272274)
			(size 0.4318 0.4318)
			(layers "F.Cu" "F.Mask" "F.Paste")
			(net "H_CPU0_FIVR_FAULT_G")
		)
		(pad "AU16" smd circle
			(at -24.373078 -7.272274)
			(size 0.4318 0.4318)
			(layers "F.Cu" "F.Mask" "F.Paste")
			(net "PU_CPU0_SOCKET_ID_1")
		)
		(pad "AU18" smd circle
			(at -22.656038 -7.272274)
			(size 0.4318 0.4318)
			(layers "F.Cu" "F.Mask" "F.Paste")
			(net "TP_CPU0_TEST_7")
		)
		(pad "AU20" smd circle
			(at -20.938998 -7.272274)
			(size 0.4318 0.4318)
			(layers "F.Cu" "F.Mask" "F.Paste")
			(net "TP_CPU0_SOCKET_ID_2")
		)
		(pad "AU22" smd circle
			(at -19.221958 -7.272274)
			(size 0.4318 0.4318)
			(layers "F.Cu" "F.Mask" "F.Paste")
			(net "PU_CPU0_SOCKET_ID_0")
		)
		(pad "AU24" smd circle
			(at -17.504918 -7.272274)
			(size 0.4318 0.4318)
			(layers "F.Cu" "F.Mask" "F.Paste")
			(net "CLK_100M_CPU0_BCLK0_DN")
		)
		(pad "AU26" smd circle
			(at -15.787878 -7.272274)
			(size 0.4318 0.4318)
			(layers "F.Cu" "F.Mask" "F.Paste")
			(net "GND")
		)
		(pad "AU28" smd circle
			(at -14.071092 -7.272274)
			(size 0.4318 0.4318)
			(layers "F.Cu" "F.Mask" "F.Paste")
			(net "GND")
		)
		(pad "AU58" smd circle
			(at 13.212572 -9.072372)
			(size 0.508 0.508)
			(layers "F.Cu" "F.Mask" "F.Paste")
			(net "PVCCIN_CPU0")
		)
		(pad "AU60" smd circle
			(at 14.929612 -9.072372)
			(size 0.4318 0.4318)
			(layers "F.Cu" "F.Mask" "F.Paste")
			(net "PVCCIN_CPU0")
		)
		(pad "AU62" smd circle
			(at 16.646398 -9.072372)
			(size 0.4318 0.4318)
			(layers "F.Cu" "F.Mask" "F.Paste")
			(net "GND")
		)
		(pad "AU64" smd circle
			(at 18.363438 -9.072372)
			(size 0.4318 0.4318)
			(layers "F.Cu" "F.Mask" "F.Paste")
			(net "GND")
		)
		(pad "AU66" smd circle
			(at 20.080478 -9.072372)
			(size 0.4318 0.4318)
			(layers "F.Cu" "F.Mask" "F.Paste")
			(net "M_C_DQS_DN<3>")
		)
		(pad "AU68" smd circle
			(at 21.797518 -9.072372)
			(size 0.4318 0.4318)
			(layers "F.Cu" "F.Mask" "F.Paste")
			(net "GND")
		)
		(pad "AU70" smd circle
			(at 23.514558 -9.072372)
			(size 0.4318 0.4318)
			(layers "F.Cu" "F.Mask" "F.Paste")
			(net "M_C_ECC<6>")
		)
		(pad "AU72" smd circle
			(at 25.231598 -9.072372)
			(size 0.4318 0.4318)
			(layers "F.Cu" "F.Mask" "F.Paste")
			(net "M_C_ECC<0>")
		)
		(pad "AU74" smd circle
			(at 26.948384 -9.072372)
			(size 0.4318 0.4318)
			(layers "F.Cu" "F.Mask" "F.Paste")
			(net "GND")
		)
		(pad "AU76" smd circle
			(at 28.665424 -9.072372)
			(size 0.4318 0.4318)
			(layers "F.Cu" "F.Mask" "F.Paste")
			(net "GND")
		)
		(pad "AU78" smd circle
			(at 30.382464 -9.072372)
			(size 0.4318 0.4318)
			(layers "F.Cu" "F.Mask" "F.Paste")
			(net "GND")
		)
		(pad "AU80" smd circle
			(at 32.099504 -9.072372)
			(size 0.4318 0.4318)
			(layers "F.Cu" "F.Mask" "F.Paste")
			(net "GND")
		)
		(pad "AU82" smd circle
			(at 33.816544 -9.072372)
			(size 0.4318 0.4318)
			(layers "F.Cu" "F.Mask" "F.Paste")
			(net "M_B_DQS_DN<9>")
		)
		(pad "AU84" smd circle
			(at 35.533584 -9.072372)
			(size 0.4318 0.4318)
			(layers "F.Cu" "F.Mask" "F.Paste")
			(net "GND")
		)
		(pad "AU86" smd custom
			(at 37.250624 -9.072372 270)
			(size 0.10795 0.10795)
			(layers "F.Cu" "F.Mask" "F.Paste")
			(net "GND")
			(options
				(clearance outline)
				(anchor circle)
			)
			(primitives
				(gr_poly
					(pts
						(arc
							(start 0.2159 -0.0381)
							(mid 0 -0.254)
							(end -0.2159 -0.0381)
						)
						(arc
							(start -0.2159 0.0381)
							(mid 0 0.254)
							(end 0.2159 0.0381)
						)
					)
					(width 0)
					(fill yes)
				)
			)
		)
		(pad "AV1" smd custom
			(at -37.250624 -6.777228 90)
			(size 0.10795 0.10795)
			(layers "F.Cu" "F.Mask" "F.Paste")
			(net "GND")
			(options
				(clearance outline)
				(anchor circle)
			)
			(primitives
				(gr_poly
					(pts
						(arc
							(start 0.2159 -0.0381)
							(mid 0 -0.254)
							(end -0.2159 -0.0381)
						)
						(arc
							(start -0.2159 0.0381)
							(mid 0 0.254)
							(end 0.2159 0.0381)
						)
					)
					(width 0)
					(fill yes)
				)
			)
		)
		(pad "AV3" smd circle
			(at -35.533584 -6.777228)
			(size 0.4318 0.4318)
			(layers "F.Cu" "F.Mask" "F.Paste")
			(net "GND")
		)
		(pad "AV5" smd circle
			(at -33.816544 -6.777228)
			(size 0.4318 0.4318)
			(layers "F.Cu" "F.Mask" "F.Paste")
			(net "UPI_CPU0_CPU1_P0P0_DN<4>")
		)
		(pad "AV7" smd circle
			(at -32.099504 -6.777228)
			(size 0.4318 0.4318)
			(layers "F.Cu" "F.Mask" "F.Paste")
			(net "GND")
		)
		(pad "AV9" smd circle
			(at -30.382464 -6.777228)
			(size 0.4318 0.4318)
			(layers "F.Cu" "F.Mask" "F.Paste")
			(net "UPI_CPU1_CPU0_P0P0_DP<3>")
		)
		(pad "AV11" smd circle
			(at -28.665424 -6.777228)
			(size 0.4318 0.4318)
			(layers "F.Cu" "F.Mask" "F.Paste")
			(net "GND")
		)
		(pad "AV13" smd circle
			(at -26.948384 -6.777228)
			(size 0.4318 0.4318)
			(layers "F.Cu" "F.Mask" "F.Paste")
			(net "GND")
		)
		(pad "AV15" smd circle
			(at -25.231598 -6.777228)
			(size 0.4318 0.4318)
			(layers "F.Cu" "F.Mask" "F.Paste")
			(net "PD_CPU0_TXT_PLTEN")
		)
		(pad "AV17" smd circle
			(at -23.514558 -6.777228)
			(size 0.4318 0.4318)
			(layers "F.Cu" "F.Mask" "F.Paste")
			(net "PU_CPU0_FRMAGENT")
		)
		(pad "AV19" smd circle
			(at -21.797518 -6.777228)
			(size 0.4318 0.4318)
			(layers "F.Cu" "F.Mask" "F.Paste")
			(net "GND")
		)
		(pad "AV21" smd circle
			(at -20.080478 -6.777228)
			(size 0.4318 0.4318)
			(layers "F.Cu" "F.Mask" "F.Paste")
			(net "CPU_XDP_PRESENT_N")
		)
		(pad "AV23" smd circle
			(at -18.363438 -6.777228)
			(size 0.4318 0.4318)
			(layers "F.Cu" "F.Mask" "F.Paste")
			(net "GND")
		)
		(pad "AV25" smd circle
			(at -16.646398 -6.777228)
			(size 0.4318 0.4318)
			(layers "F.Cu" "F.Mask" "F.Paste")
			(net "GND")
		)
		(pad "AV27" smd circle
			(at -14.929612 -6.777228)
			(size 0.4318 0.4318)
			(layers "F.Cu" "F.Mask" "F.Paste")
			(net "PVCCIO_CPU0")
		)
		(pad "AV59" smd circle
			(at 14.071092 -8.577326)
			(size 0.508 0.508)
			(layers "F.Cu" "F.Mask" "F.Paste")
			(net "PVCCIN_CPU0")
		)
		(pad "AV61" smd circle
			(at 15.787878 -8.577326)
			(size 0.4318 0.4318)
			(layers "F.Cu" "F.Mask" "F.Paste")
			(net "PVCCIN_CPU0")
		)
		(pad "AV63" smd circle
			(at 17.504918 -8.577326)
			(size 0.4318 0.4318)
			(layers "F.Cu" "F.Mask" "F.Paste")
			(net "GND")
		)
		(pad "AV65" smd circle
			(at 19.221958 -8.577326)
			(size 0.4318 0.4318)
			(layers "F.Cu" "F.Mask" "F.Paste")
			(net "GND")
		)
		(pad "AV67" smd circle
			(at 20.938998 -8.577326)
			(size 0.4318 0.4318)
			(layers "F.Cu" "F.Mask" "F.Paste")
			(net "GND")
		)
		(pad "AV69" smd circle
			(at 22.656038 -8.577326)
			(size 0.4318 0.4318)
			(layers "F.Cu" "F.Mask" "F.Paste")
			(net "M_C_ECC<2>")
		)
		(pad "AV71" smd circle
			(at 24.373078 -8.577326)
			(size 0.4318 0.4318)
			(layers "F.Cu" "F.Mask" "F.Paste")
			(net "M_C_DQS_DP<17>")
		)
		(pad "AV73" smd circle
			(at 26.090118 -8.577326)
			(size 0.4318 0.4318)
			(layers "F.Cu" "F.Mask" "F.Paste")
			(net "M_C_ECC<4>")
		)
		(pad "AV75" smd circle
			(at 27.806904 -8.577326)
			(size 0.4318 0.4318)
			(layers "F.Cu" "F.Mask" "F.Paste")
			(net "GND")
		)
		(pad "AV77" smd circle
			(at 29.523944 -8.577326)
			(size 0.4318 0.4318)
			(layers "F.Cu" "F.Mask" "F.Paste")
			(net "TP_CPU0_RSVD_186")
		)
		(pad "AV79" smd circle
			(at 31.240984 -8.577326)
			(size 0.4318 0.4318)
			(layers "F.Cu" "F.Mask" "F.Paste")
			(net "M_B_DQ<5>")
		)
		(pad "AV81" smd circle
			(at 32.958024 -8.577326)
			(size 0.4318 0.4318)
			(layers "F.Cu" "F.Mask" "F.Paste")
			(net "M_B_DQ<0>")
		)
		(pad "AV83" smd circle
			(at 34.675064 -8.577326)
			(size 0.4318 0.4318)
			(layers "F.Cu" "F.Mask" "F.Paste")
			(net "GND")
		)
		(pad "AV85" smd circle
			(at 36.392104 -8.577326)
			(size 0.4318 0.4318)
			(layers "F.Cu" "F.Mask" "F.Paste")
			(net "VSENSE_VCCINR2PMAX_CPU0")
		)
		(pad "AW2" smd custom
			(at -36.392104 -6.281928 90)
			(size 0.10795 0.10795)
			(layers "F.Cu" "F.Mask" "F.Paste")
			(net "GND")
			(options
				(clearance outline)
				(anchor circle)
			)
			(primitives
				(gr_poly
					(pts
						(arc
							(start 0.2159 -0.0381)
							(mid 0 -0.254)
							(end -0.2159 -0.0381)
						)
						(arc
							(start -0.2159 0.0381)
							(mid 0 0.254)
							(end 0.2159 0.0381)
						)
					)
					(width 0)
					(fill yes)
				)
			)
		)
		(pad "AW4" smd circle
			(at -34.675064 -6.281928)
			(size 0.4318 0.4318)
			(layers "F.Cu" "F.Mask" "F.Paste")
			(net "UPI_CPU0_CPU1_P0P0_DP<4>")
		)
		(pad "AW6" smd circle
			(at -32.958024 -6.281928)
			(size 0.4318 0.4318)
			(layers "F.Cu" "F.Mask" "F.Paste")
			(net "PVCCIO_CPU0")
		)
		(pad "AW8" smd circle
			(at -31.240984 -6.281928)
			(size 0.4318 0.4318)
			(layers "F.Cu" "F.Mask" "F.Paste")
			(net "UPI_CPU1_CPU0_P0P0_DN<3>")
		)
		(pad "AW10" smd circle
			(at -29.523944 -6.281928)
			(size 0.4318 0.4318)
			(layers "F.Cu" "F.Mask" "F.Paste")
			(net "GND")
		)
		(pad "AW12" smd circle
			(at -27.806904 -6.281928)
			(size 0.4318 0.4318)
			(layers "F.Cu" "F.Mask" "F.Paste")
			(net "PD_CPU0_DMIMODE_OVERRIDE")
		)
		(pad "AW14" smd circle
			(at -26.090118 -6.281928)
			(size 0.4318 0.4318)
			(layers "F.Cu" "F.Mask" "F.Paste")
			(net "PD_CPU0_KSFC_DIS")
		)
		(pad "AW16" smd circle
			(at -24.373078 -6.281928)
			(size 0.4318 0.4318)
			(layers "F.Cu" "F.Mask" "F.Paste")
			(net "TP_CPU0_TEST_8")
		)
		(pad "AW18" smd circle
			(at -22.656038 -6.281928)
			(size 0.4318 0.4318)
			(layers "F.Cu" "F.Mask" "F.Paste")
			(net "PU_CPU0_TXT_AGENT")
		)
		(pad "AW20" smd circle
			(at -20.938998 -6.281928)
			(size 0.4318 0.4318)
			(layers "F.Cu" "F.Mask" "F.Paste")
			(net "TP_CPU0_TEST_9")
		)
		(pad "AW22" smd circle
			(at -19.221958 -6.281928)
			(size 0.4318 0.4318)
			(layers "F.Cu" "F.Mask" "F.Paste")
			(net "TP_CPU0_TEST_10")
		)
		(pad "AW24" smd circle
			(at -17.504918 -6.281928)
			(size 0.4318 0.4318)
			(layers "F.Cu" "F.Mask" "F.Paste")
			(net "CLK_100M_CPU0_BCLK0_DP")
		)
		(pad "AW26" smd circle
			(at -15.787878 -6.281928)
			(size 0.4318 0.4318)
			(layers "F.Cu" "F.Mask" "F.Paste")
			(net "PVCCIO_CPU0")
		)
		(pad "AW60" smd circle
			(at 14.929612 -8.081772)
			(size 0.508 0.508)
			(layers "F.Cu" "F.Mask" "F.Paste")
			(net "PVCCIN_CPU0")
		)
		(pad "AW62" smd circle
			(at 16.646398 -8.081772)
			(size 0.4318 0.4318)
			(layers "F.Cu" "F.Mask" "F.Paste")
			(net "GND")
		)
		(pad "AW64" smd circle
			(at 18.363438 -8.081772)
			(size 0.4318 0.4318)
			(layers "F.Cu" "F.Mask" "F.Paste")
			(net "TP_CPU0_RSVD_184")
		)
		(pad "AW66" smd circle
			(at 20.080478 -8.081772)
			(size 0.4318 0.4318)
			(layers "F.Cu" "F.Mask" "F.Paste")
			(net "GND")
		)
		(pad "AW68" smd circle
			(at 21.797518 -8.081772)
			(size 0.4318 0.4318)
			(layers "F.Cu" "F.Mask" "F.Paste")
			(net "GND")
		)
		(pad "AW70" smd circle
			(at 23.514558 -8.081772)
			(size 0.4318 0.4318)
			(layers "F.Cu" "F.Mask" "F.Paste")
			(net "GND")
		)
		(pad "AW72" smd circle
			(at 25.231598 -8.081772)
			(size 0.4318 0.4318)
			(layers "F.Cu" "F.Mask" "F.Paste")
			(net "GND")
		)
		(pad "AW74" smd circle
			(at 26.948384 -8.081772)
			(size 0.4318 0.4318)
			(layers "F.Cu" "F.Mask" "F.Paste")
			(net "GND")
		)
		(pad "AW76" smd circle
			(at 28.665424 -8.081772)
			(size 0.4318 0.4318)
			(layers "F.Cu" "F.Mask" "F.Paste")
			(net "TP_CPU0_RSVD_183")
		)
		(pad "AW78" smd circle
			(at 30.382464 -8.081772)
			(size 0.4318 0.4318)
			(layers "F.Cu" "F.Mask" "F.Paste")
			(net "GND")
		)
		(pad "AW80" smd circle
			(at 32.099504 -8.081772)
			(size 0.4318 0.4318)
			(layers "F.Cu" "F.Mask" "F.Paste")
			(net "M_B_DQ<4>")
		)
		(pad "AW82" smd circle
			(at 33.816544 -8.081772)
			(size 0.4318 0.4318)
			(layers "F.Cu" "F.Mask" "F.Paste")
			(net "GND")
		)
		(pad "AW84" smd circle
			(at 35.533584 -8.081772)
			(size 0.4318 0.4318)
			(layers "F.Cu" "F.Mask" "F.Paste")
			(net "GND")
		)
		(pad "AW86" smd custom
			(at 37.250624 -8.081772 270)
			(size 0.10795 0.10795)
			(layers "F.Cu" "F.Mask" "F.Paste")
			(net "VSENSE_VCCINR2PMAX_CPU0")
			(options
				(clearance outline)
				(anchor circle)
			)
			(primitives
				(gr_poly
					(pts
						(arc
							(start 0.2159 -0.0381)
							(mid 0 -0.254)
							(end -0.2159 -0.0381)
						)
						(arc
							(start -0.2159 0.0381)
							(mid 0 0.254)
							(end 0.2159 0.0381)
						)
					)
					(width 0)
					(fill yes)
				)
			)
		)
		(pad "AY3" smd circle
			(at -35.533584 -5.786628)
			(size 0.4318 0.4318)
			(layers "F.Cu" "F.Mask" "F.Paste")
			(net "UPI_CPU0_CPU1_P0P0_DP<3>")
		)
		(pad "AY5" smd circle
			(at -33.816544 -5.786628)
			(size 0.4318 0.4318)
			(layers "F.Cu" "F.Mask" "F.Paste")
			(net "GND")
		)
		(pad "AY7" smd circle
			(at -32.099504 -5.786628)
			(size 0.4318 0.4318)
			(layers "F.Cu" "F.Mask" "F.Paste")
			(net "UPI_CPU1_CPU0_P0P0_DP<6>")
		)
		(pad "AY9" smd circle
			(at -30.382464 -5.786628)
			(size 0.4318 0.4318)
			(layers "F.Cu" "F.Mask" "F.Paste")
			(net "UPI_CPU1_CPU0_P0P0_DN<2>")
		)
		(pad "AY11" smd circle
			(at -28.665424 -5.786628)
			(size 0.4318 0.4318)
			(layers "F.Cu" "F.Mask" "F.Paste")
			(net "PVCCIO_CPU0")
		)
		(pad "AY13" smd circle
			(at -26.948384 -5.786628)
			(size 0.4318 0.4318)
			(layers "F.Cu" "F.Mask" "F.Paste")
			(net "TP_CPU0_RSVD_TEST_11")
		)
		(pad "AY15" smd circle
			(at -25.231598 -5.786628)
			(size 0.4318 0.4318)
			(layers "F.Cu" "F.Mask" "F.Paste")
			(net "GND")
		)
		(pad "AY17" smd circle
			(at -23.514558 -5.786628)
			(size 0.4318 0.4318)
			(layers "F.Cu" "F.Mask" "F.Paste")
			(net "GND")
		)
		(pad "AY19" smd circle
			(at -21.797518 -5.786628)
			(size 0.4318 0.4318)
			(layers "F.Cu" "F.Mask" "F.Paste")
			(net "PD_CPU0_TEST12")
		)
		(pad "AY21" smd circle
			(at -20.080478 -5.786628)
			(size 0.4318 0.4318)
			(layers "F.Cu" "F.Mask" "F.Paste")
			(net "GND")
		)
		(pad "AY23" smd circle
			(at -18.363438 -5.786628)
			(size 0.4318 0.4318)
			(layers "F.Cu" "F.Mask" "F.Paste")
			(net "GND")
		)
		(pad "AY25" smd circle
			(at -16.646398 -5.786628)
			(size 0.4318 0.4318)
			(layers "F.Cu" "F.Mask" "F.Paste")
			(net "GND")
		)
		(pad "AY27" smd circle
			(at -14.929612 -5.786628)
			(size 0.4318 0.4318)
			(layers "F.Cu" "F.Mask" "F.Paste")
			(net "PVCCIO_CPU0")
		)
		(pad "AY61" smd circle
			(at 15.787878 -7.586726)
			(size 0.4318 0.4318)
			(layers "F.Cu" "F.Mask" "F.Paste")
			(net "PVCCIN_CPU0")
		)
		(pad "AY63" smd circle
			(at 17.504918 -7.586726)
			(size 0.4318 0.4318)
			(layers "F.Cu" "F.Mask" "F.Paste")
			(net "GND")
		)
		(pad "AY65" smd circle
			(at 19.221958 -7.586726)
			(size 0.4318 0.4318)
			(layers "F.Cu" "F.Mask" "F.Paste")
			(net "TP_CPU0_RSVD_182")
		)
		(pad "AY67" smd circle
			(at 20.938998 -7.586726)
			(size 0.4318 0.4318)
			(layers "F.Cu" "F.Mask" "F.Paste")
			(net "TP_CPU0_RSVD_181")
		)
		(pad "AY69" smd circle
			(at 22.656038 -7.586726)
			(size 0.4318 0.4318)
			(layers "F.Cu" "F.Mask" "F.Paste")
			(net "M_C_ECC<3>")
		)
		(pad "AY71" smd circle
			(at 24.373078 -7.586726)
			(size 0.4318 0.4318)
			(layers "F.Cu" "F.Mask" "F.Paste")
			(net "M_C_DQS_DP<8>")
		)
		(pad "AY73" smd circle
			(at 26.090118 -7.586726)
			(size 0.4318 0.4318)
			(layers "F.Cu" "F.Mask" "F.Paste")
			(net "M_C_ECC<5>")
		)
		(pad "AY75" smd circle
			(at 27.806904 -7.586726)
			(size 0.4318 0.4318)
			(layers "F.Cu" "F.Mask" "F.Paste")
			(net "TP_CPU0_RSVD_180")
		)
		(pad "AY77" smd circle
			(at 29.523944 -7.586726)
			(size 0.4318 0.4318)
			(layers "F.Cu" "F.Mask" "F.Paste")
			(net "TP_CPU0_RSVD_179")
		)
		(pad "AY79" smd circle
			(at 31.240984 -7.586726)
			(size 0.4318 0.4318)
			(layers "F.Cu" "F.Mask" "F.Paste")
			(net "GND")
		)
		(pad "AY81" smd circle
			(at 32.958024 -7.586726)
			(size 0.4318 0.4318)
			(layers "F.Cu" "F.Mask" "F.Paste")
			(net "GND")
		)
		(pad "AY83" smd circle
			(at 34.675064 -7.586726)
			(size 0.4318 0.4318)
			(layers "F.Cu" "F.Mask" "F.Paste")
			(net "TP_CPU0_RSVD_255")
		)
		(pad "AY85" smd circle
			(at 36.392104 -7.586726)
			(size 0.4318 0.4318)
			(layers "F.Cu" "F.Mask" "F.Paste")
			(net "VSENSE_PVCCIN_CPU0_SKT_VRTN")
		)
		(pad "B3" smd custom
			(at -35.533584 -24.608028 45)
			(size 0.10795 0.10795)
			(layers "F.Cu" "F.Mask" "F.Paste")
			(net "TP_CPU0_RSVD_299")
			(options
				(clearance outline)
				(anchor circle)
			)
			(primitives
				(gr_poly
					(pts
						(arc
							(start 0.2159 -0.0381)
							(mid 0 -0.254)
							(end -0.2159 -0.0381)
						)
						(arc
							(start -0.2159 0.0381)
							(mid 0 0.254)
							(end 0.2159 0.0381)
						)
					)
					(width 0)
					(fill yes)
				)
			)
		)
		(pad "B5" smd custom
			(at -33.816544 -24.608028 45)
			(size 0.10795 0.10795)
			(layers "F.Cu" "F.Mask" "F.Paste")
			(net "GND")
			(options
				(clearance outline)
				(anchor circle)
			)
			(primitives
				(gr_poly
					(pts
						(arc
							(start 0.2159 -0.0381)
							(mid 0 -0.254)
							(end -0.2159 -0.0381)
						)
						(arc
							(start -0.2159 0.0381)
							(mid 0 0.254)
							(end 0.2159 0.0381)
						)
					)
					(width 0)
					(fill yes)
				)
			)
		)
		(pad "B7" smd custom
			(at -32.099504 -24.608028)
			(size 0.10795 0.10795)
			(layers "F.Cu" "F.Mask" "F.Paste")
			(net "TP_CPU0_RSVD_298")
			(options
				(clearance outline)
				(anchor circle)
			)
			(primitives
				(gr_poly
					(pts
						(arc
							(start 0.2159 -0.0381)
							(mid 0 -0.254)
							(end -0.2159 -0.0381)
						)
						(arc
							(start -0.2159 0.0381)
							(mid 0 0.254)
							(end 0.2159 0.0381)
						)
					)
					(width 0)
					(fill yes)
				)
			)
		)
		(pad "B9" smd circle
			(at -30.382464 -24.608028)
			(size 0.4318 0.4318)
			(layers "F.Cu" "F.Mask" "F.Paste")
			(net "GND")
		)
		(pad "B11" smd circle
			(at -28.665424 -24.608028)
			(size 0.4318 0.4318)
			(layers "F.Cu" "F.Mask" "F.Paste")
			(net "PVPP_ABC")
		)
		(pad "B13" smd circle
			(at -26.948384 -24.608028)
			(size 0.4318 0.4318)
			(layers "F.Cu" "F.Mask" "F.Paste")
			(net "P1V8_MCP_CPU0")
		)
		(pad "B15" smd circle
			(at -25.231598 -24.608028)
			(size 0.4318 0.4318)
			(layers "F.Cu" "F.Mask" "F.Paste")
			(net "P1V8_MCP_CPU0")
		)
		(pad "B17" smd custom
			(at -23.514558 -24.608028)
			(size 0.10795 0.10795)
			(layers "F.Cu" "F.Mask" "F.Paste")
			(net "P1V8_MCP_CPU0")
			(options
				(clearance outline)
				(anchor circle)
			)
			(primitives
				(gr_poly
					(pts
						(arc
							(start 0.2159 -0.0381)
							(mid 0 -0.254)
							(end -0.2159 -0.0381)
						)
						(arc
							(start -0.2159 0.0381)
							(mid 0 0.254)
							(end 0.2159 0.0381)
						)
					)
					(width 0)
					(fill yes)
				)
			)
		)
		(pad "B25" smd circle
			(at -16.646398 -24.608028)
			(size 0.4318 0.4318)
			(layers "F.Cu" "F.Mask" "F.Paste")
			(net "GND")
		)
		(pad "B27" smd circle
			(at -14.929612 -24.608028)
			(size 0.4318 0.4318)
			(layers "F.Cu" "F.Mask" "F.Paste")
			(net "M_B_DQ<54>")
		)
		(pad "B29" smd circle
			(at -13.212572 -24.608028)
			(size 0.4318 0.4318)
			(layers "F.Cu" "F.Mask" "F.Paste")
			(net "M_B_DQ<49>")
		)
		(pad "B31" smd circle
			(at -11.495532 -24.608028)
			(size 0.4318 0.4318)
			(layers "F.Cu" "F.Mask" "F.Paste")
			(net "GND")
		)
		(pad "B33" smd circle
			(at -9.778492 -24.608028)
			(size 0.4318 0.4318)
			(layers "F.Cu" "F.Mask" "F.Paste")
			(net "M_B_DQ<46>")
		)
		(pad "B35" smd circle
			(at -8.061452 -24.608028)
			(size 0.4318 0.4318)
			(layers "F.Cu" "F.Mask" "F.Paste")
			(net "M_B_DQ<41>")
		)
		(pad "B37" smd circle
			(at -6.344412 -24.608028)
			(size 0.4318 0.4318)
			(layers "F.Cu" "F.Mask" "F.Paste")
			(net "GND")
		)
		(pad "B39" smd circle
			(at -4.627626 -24.608028)
			(size 0.4318 0.4318)
			(layers "F.Cu" "F.Mask" "F.Paste")
			(net "M_A_DQ<38>")
		)
		(pad "B41" smd circle
			(at -2.910586 -24.608028)
			(size 0.4318 0.4318)
			(layers "F.Cu" "F.Mask" "F.Paste")
			(net "M_A_DQ<33>")
		)
		(pad "B43" smd custom
			(at -1.193546 -24.608028 315)
			(size 0.10795 0.10795)
			(layers "F.Cu" "F.Mask" "F.Paste")
			(net "GND")
			(options
				(clearance outline)
				(anchor circle)
			)
			(primitives
				(gr_poly
					(pts
						(arc
							(start 0.2159 -0.0381)
							(mid 0 -0.254)
							(end -0.2159 -0.0381)
						)
						(arc
							(start -0.2159 0.0381)
							(mid 0 0.254)
							(end 0.2159 0.0381)
						)
					)
					(width 0)
					(fill yes)
				)
			)
		)
		(pad "B47" smd custom
			(at 3.769106 -26.408126 45)
			(size 0.10795 0.10795)
			(layers "F.Cu" "F.Mask" "F.Paste")
			(net "PVDDQ_ABC")
			(options
				(clearance outline)
				(anchor circle)
			)
			(primitives
				(gr_poly
					(pts
						(arc
							(start 0.2159 -0.0381)
							(mid 0 -0.254)
							(end -0.2159 -0.0381)
						)
						(arc
							(start -0.2159 0.0381)
							(mid 0 0.254)
							(end 0.2159 0.0381)
						)
					)
					(width 0)
					(fill yes)
				)
			)
		)
		(pad "B49" smd custom
			(at 5.485892 -26.408126)
			(size 0.10795 0.10795)
			(layers "F.Cu" "F.Mask" "F.Paste")
			(net "PVDDQ_ABC")
			(options
				(clearance outline)
				(anchor circle)
			)
			(primitives
				(gr_poly
					(pts
						(arc
							(start 0.2159 -0.0381)
							(mid 0 -0.254)
							(end -0.2159 -0.0381)
						)
						(arc
							(start -0.2159 0.0381)
							(mid 0 0.254)
							(end 0.2159 0.0381)
						)
					)
					(width 0)
					(fill yes)
				)
			)
		)
		(pad "B51" smd custom
			(at 7.202932 -26.408126)
			(size 0.10795 0.10795)
			(layers "F.Cu" "F.Mask" "F.Paste")
			(net "M_A_CS_N<4>")
			(options
				(clearance outline)
				(anchor circle)
			)
			(primitives
				(gr_poly
					(pts
						(arc
							(start 0.2159 -0.0381)
							(mid 0 -0.254)
							(end -0.2159 -0.0381)
						)
						(arc
							(start -0.2159 0.0381)
							(mid 0 0.254)
							(end 0.2159 0.0381)
						)
					)
					(width 0)
					(fill yes)
				)
			)
		)
		(pad "B53" smd custom
			(at 8.919972 -26.408126)
			(size 0.10795 0.10795)
			(layers "F.Cu" "F.Mask" "F.Paste")
			(net "PVDDQ_ABC")
			(options
				(clearance outline)
				(anchor circle)
			)
			(primitives
				(gr_poly
					(pts
						(arc
							(start 0.2159 -0.0381)
							(mid 0 -0.254)
							(end -0.2159 -0.0381)
						)
						(arc
							(start -0.2159 0.0381)
							(mid 0 0.254)
							(end 0.2159 0.0381)
						)
					)
					(width 0)
					(fill yes)
				)
			)
		)
		(pad "B55" smd custom
			(at 10.637012 -26.408126)
			(size 0.10795 0.10795)
			(layers "F.Cu" "F.Mask" "F.Paste")
			(net "M_A_CLK_DP<1>")
			(options
				(clearance outline)
				(anchor circle)
			)
			(primitives
				(gr_poly
					(pts
						(arc
							(start 0.2159 -0.0381)
							(mid 0 -0.254)
							(end -0.2159 -0.0381)
						)
						(arc
							(start -0.2159 0.0381)
							(mid 0 0.254)
							(end 0.2159 0.0381)
						)
					)
					(width 0)
					(fill yes)
				)
			)
		)
		(pad "B57" smd custom
			(at 12.354052 -26.408126)
			(size 0.10795 0.10795)
			(layers "F.Cu" "F.Mask" "F.Paste")
			(net "M_A_CLK_DP<3>")
			(options
				(clearance outline)
				(anchor circle)
			)
			(primitives
				(gr_poly
					(pts
						(arc
							(start 0.2159 -0.0381)
							(mid 0 -0.254)
							(end -0.2159 -0.0381)
						)
						(arc
							(start -0.2159 0.0381)
							(mid 0 0.254)
							(end 0.2159 0.0381)
						)
					)
					(width 0)
					(fill yes)
				)
			)
		)
		(pad "B59" smd custom
			(at 14.071092 -26.408126)
			(size 0.10795 0.10795)
			(layers "F.Cu" "F.Mask" "F.Paste")
			(net "PVDDQ_ABC")
			(options
				(clearance outline)
				(anchor circle)
			)
			(primitives
				(gr_poly
					(pts
						(arc
							(start 0.2159 -0.0381)
							(mid 0 -0.254)
							(end -0.2159 -0.0381)
						)
						(arc
							(start -0.2159 0.0381)
							(mid 0 0.254)
							(end 0.2159 0.0381)
						)
					)
					(width 0)
					(fill yes)
				)
			)
		)
		(pad "B61" smd custom
			(at 15.787878 -26.408126)
			(size 0.10795 0.10795)
			(layers "F.Cu" "F.Mask" "F.Paste")
			(net "M_A_ALERT_N")
			(options
				(clearance outline)
				(anchor circle)
			)
			(primitives
				(gr_poly
					(pts
						(arc
							(start 0.2159 -0.0381)
							(mid 0 -0.254)
							(end -0.2159 -0.0381)
						)
						(arc
							(start -0.2159 0.0381)
							(mid 0 0.254)
							(end 0.2159 0.0381)
						)
					)
					(width 0)
					(fill yes)
				)
			)
		)
		(pad "B63" smd custom
			(at 17.504918 -26.408126)
			(size 0.10795 0.10795)
			(layers "F.Cu" "F.Mask" "F.Paste")
			(net "M_A_CKE<2>")
			(options
				(clearance outline)
				(anchor circle)
			)
			(primitives
				(gr_poly
					(pts
						(arc
							(start 0.2159 -0.0381)
							(mid 0 -0.254)
							(end -0.2159 -0.0381)
						)
						(arc
							(start -0.2159 0.0381)
							(mid 0 0.254)
							(end 0.2159 0.0381)
						)
					)
					(width 0)
					(fill yes)
				)
			)
		)
		(pad "B71" smd custom
			(at 24.373078 -26.408126)
			(size 0.10795 0.10795)
			(layers "F.Cu" "F.Mask" "F.Paste")
			(net "GND")
			(options
				(clearance outline)
				(anchor circle)
			)
			(primitives
				(gr_poly
					(pts
						(arc
							(start 0.2159 -0.0381)
							(mid 0 -0.254)
							(end -0.2159 -0.0381)
						)
						(arc
							(start -0.2159 0.0381)
							(mid 0 0.254)
							(end 0.2159 0.0381)
						)
					)
					(width 0)
					(fill yes)
				)
			)
		)
		(pad "B73" smd custom
			(at 26.090118 -26.408126)
			(size 0.10795 0.10795)
			(layers "F.Cu" "F.Mask" "F.Paste")
			(net "M_B_DQS_DN<12>")
			(options
				(clearance outline)
				(anchor circle)
			)
			(primitives
				(gr_poly
					(pts
						(arc
							(start 0.2159 -0.0381)
							(mid 0 -0.254)
							(end -0.2159 -0.0381)
						)
						(arc
							(start -0.2159 0.0381)
							(mid 0 0.254)
							(end 0.2159 0.0381)
						)
					)
					(width 0)
					(fill yes)
				)
			)
		)
		(pad "B75" smd custom
			(at 27.806904 -26.408126)
			(size 0.10795 0.10795)
			(layers "F.Cu" "F.Mask" "F.Paste")
			(net "GND")
			(options
				(clearance outline)
				(anchor circle)
			)
			(primitives
				(gr_poly
					(pts
						(arc
							(start 0.2159 -0.0381)
							(mid 0 -0.254)
							(end -0.2159 -0.0381)
						)
						(arc
							(start -0.2159 0.0381)
							(mid 0 0.254)
							(end 0.2159 0.0381)
						)
					)
					(width 0)
					(fill yes)
				)
			)
		)
		(pad "B77" smd custom
			(at 29.523944 -26.408126)
			(size 0.10795 0.10795)
			(layers "F.Cu" "F.Mask" "F.Paste")
			(net "TP_CPU0_RSVD_293")
			(options
				(clearance outline)
				(anchor circle)
			)
			(primitives
				(gr_poly
					(pts
						(arc
							(start 0.2159 -0.0381)
							(mid 0 -0.254)
							(end -0.2159 -0.0381)
						)
						(arc
							(start -0.2159 0.0381)
							(mid 0 0.254)
							(end 0.2159 0.0381)
						)
					)
					(width 0)
					(fill yes)
				)
			)
		)
		(pad "B79" smd custom
			(at 31.240984 -26.408126 315)
			(size 0.10795 0.10795)
			(layers "F.Cu" "F.Mask" "F.Paste")
			(net "GND")
			(options
				(clearance outline)
				(anchor circle)
			)
			(primitives
				(gr_poly
					(pts
						(arc
							(start 0.2159 -0.0381)
							(mid 0 -0.254)
							(end -0.2159 -0.0381)
						)
						(arc
							(start -0.2159 0.0381)
							(mid 0 0.254)
							(end 0.2159 0.0381)
						)
					)
					(width 0)
					(fill yes)
				)
			)
		)
		(pad "B81" smd custom
			(at 32.958024 -26.408126 315)
			(size 0.10795 0.10795)
			(layers "F.Cu" "F.Mask" "F.Paste")
			(net "TP_CPU0_RSVD_292")
			(options
				(clearance outline)
				(anchor circle)
			)
			(primitives
				(gr_poly
					(pts
						(arc
							(start 0.2159 -0.0381)
							(mid 0 -0.254)
							(end -0.2159 -0.0381)
						)
						(arc
							(start -0.2159 0.0381)
							(mid 0 0.254)
							(end 0.2159 0.0381)
						)
					)
					(width 0)
					(fill yes)
				)
			)
		)
		(pad "BA2" smd custom
			(at -36.392104 -5.291074 90)
			(size 0.10795 0.10795)
			(layers "F.Cu" "F.Mask" "F.Paste")
			(net "GND")
			(options
				(clearance outline)
				(anchor circle)
			)
			(primitives
				(gr_poly
					(pts
						(arc
							(start 0.2159 -0.0381)
							(mid 0 -0.254)
							(end -0.2159 -0.0381)
						)
						(arc
							(start -0.2159 0.0381)
							(mid 0 0.254)
							(end 0.2159 0.0381)
						)
					)
					(width 0)
					(fill yes)
				)
			)
		)
		(pad "BA4" smd circle
			(at -34.675064 -5.291074)
			(size 0.4318 0.4318)
			(layers "F.Cu" "F.Mask" "F.Paste")
			(net "UPI_CPU0_CPU1_P0P0_DN<3>")
		)
		(pad "BA6" smd circle
			(at -32.958024 -5.291074)
			(size 0.4318 0.4318)
			(layers "F.Cu" "F.Mask" "F.Paste")
			(net "GND")
		)
		(pad "BA8" smd circle
			(at -31.240984 -5.291074)
			(size 0.4318 0.4318)
			(layers "F.Cu" "F.Mask" "F.Paste")
			(net "UPI_CPU1_CPU0_P0P0_DN<6>")
		)
		(pad "BA10" smd circle
			(at -29.523944 -5.291074)
			(size 0.4318 0.4318)
			(layers "F.Cu" "F.Mask" "F.Paste")
			(net "UPI_CPU1_CPU0_P0P0_DP<0>")
		)
		(pad "BA12" smd circle
			(at -27.806904 -5.291074)
			(size 0.4318 0.4318)
			(layers "F.Cu" "F.Mask" "F.Paste")
			(net "GND")
		)
		(pad "BA14" smd circle
			(at -26.090118 -5.291074)
			(size 0.4318 0.4318)
			(layers "F.Cu" "F.Mask" "F.Paste")
			(net "TP_CPU0_RSVD_178")
		)
		(pad "BA16" smd circle
			(at -24.373078 -5.291074)
			(size 0.4318 0.4318)
			(layers "F.Cu" "F.Mask" "F.Paste")
			(net "TP_CPU0_RSVD_177")
		)
		(pad "BA18" smd circle
			(at -22.656038 -5.291074)
			(size 0.4318 0.4318)
			(layers "F.Cu" "F.Mask" "F.Paste")
			(net "TP_CPU0_RSVD_176")
		)
		(pad "BA20" smd circle
			(at -20.938998 -5.291074)
			(size 0.4318 0.4318)
			(layers "F.Cu" "F.Mask" "F.Paste")
			(net "PD_CPU0_BIST_ENABLE")
		)
		(pad "BA22" smd circle
			(at -19.221958 -5.291074)
			(size 0.4318 0.4318)
			(layers "F.Cu" "F.Mask" "F.Paste")
			(net "TP_CPU0_RSVD_175")
		)
		(pad "BA24" smd circle
			(at -17.504918 -5.291074)
			(size 0.4318 0.4318)
			(layers "F.Cu" "F.Mask" "F.Paste")
			(net "PVCCIO_CPU0")
		)
		(pad "BA26" smd circle
			(at -15.787878 -5.291074)
			(size 0.4318 0.4318)
			(layers "F.Cu" "F.Mask" "F.Paste")
			(net "PVCCIO_CPU0")
		)
		(pad "BA60" smd circle
			(at 14.929612 -7.091172)
			(size 0.508 0.508)
			(layers "F.Cu" "F.Mask" "F.Paste")
			(net "PVCCIN_CPU0")
		)
		(pad "BA62" smd circle
			(at 16.646398 -7.091172)
			(size 0.4318 0.4318)
			(layers "F.Cu" "F.Mask" "F.Paste")
			(net "GND")
		)
		(pad "BA64" smd circle
			(at 18.363438 -7.091172)
			(size 0.4318 0.4318)
			(layers "F.Cu" "F.Mask" "F.Paste")
			(net "TP_CPU0_RSVD_174")
		)
		(pad "BA66" smd circle
			(at 20.080478 -7.091172)
			(size 0.4318 0.4318)
			(layers "F.Cu" "F.Mask" "F.Paste")
			(net "TP_CPU0_RSVD_173")
		)
		(pad "BA68" smd circle
			(at 21.797518 -7.091172)
			(size 0.4318 0.4318)
			(layers "F.Cu" "F.Mask" "F.Paste")
			(net "GND")
		)
		(pad "BA70" smd circle
			(at 23.514558 -7.091172)
			(size 0.4318 0.4318)
			(layers "F.Cu" "F.Mask" "F.Paste")
			(net "M_C_ECC<7>")
		)
		(pad "BA72" smd circle
			(at 25.231598 -7.091172)
			(size 0.4318 0.4318)
			(layers "F.Cu" "F.Mask" "F.Paste")
			(net "M_C_ECC<1>")
		)
		(pad "BA74" smd circle
			(at 26.948384 -7.091172)
			(size 0.4318 0.4318)
			(layers "F.Cu" "F.Mask" "F.Paste")
			(net "GND")
		)
		(pad "BA76" smd circle
			(at 28.665424 -7.091172)
			(size 0.4318 0.4318)
			(layers "F.Cu" "F.Mask" "F.Paste")
			(net "TP_CPU0_RSVD_172")
		)
		(pad "BA78" smd circle
			(at 30.382464 -7.091172)
			(size 0.4318 0.4318)
			(layers "F.Cu" "F.Mask" "F.Paste")
			(net "TP_CPU0_RSVD_171")
		)
		(pad "BA80" smd circle
			(at 32.099504 -7.091172)
			(size 0.4318 0.4318)
			(layers "F.Cu" "F.Mask" "F.Paste")
			(net "GND")
		)
		(pad "BA82" smd circle
			(at 33.816544 -7.091172)
			(size 0.4318 0.4318)
			(layers "F.Cu" "F.Mask" "F.Paste")
			(net "TP_CPU0_RSVD_170")
		)
		(pad "BA84" smd circle
			(at 35.533584 -7.091172)
			(size 0.4318 0.4318)
			(layers "F.Cu" "F.Mask" "F.Paste")
			(net "GND")
		)
		(pad "BA86" smd custom
			(at 37.250624 -7.091172 270)
			(size 0.10795 0.10795)
			(layers "F.Cu" "F.Mask" "F.Paste")
			(net "VSENSE_PVCCIN_CPU0_SKT_VSEN")
			(options
				(clearance outline)
				(anchor circle)
			)
			(primitives
				(gr_poly
					(pts
						(arc
							(start 0.2159 -0.0381)
							(mid 0 -0.254)
							(end -0.2159 -0.0381)
						)
						(arc
							(start -0.2159 0.0381)
							(mid 0 0.254)
							(end 0.2159 0.0381)
						)
					)
					(width 0)
					(fill yes)
				)
			)
		)
		(pad "BB3" smd circle
			(at -35.533584 -4.796028)
			(size 0.4318 0.4318)
			(layers "F.Cu" "F.Mask" "F.Paste")
			(net "UPI_CPU0_CPU1_P0P0_DN<2>")
		)
		(pad "BB5" smd circle
			(at -33.816544 -4.796028)
			(size 0.4318 0.4318)
			(layers "F.Cu" "F.Mask" "F.Paste")
			(net "PVCCIO_CPU0")
		)
		(pad "BB7" smd circle
			(at -32.099504 -4.796028)
			(size 0.4318 0.4318)
			(layers "F.Cu" "F.Mask" "F.Paste")
			(net "UPI_CPU1_CPU0_P0P0_DP<5>")
		)
		(pad "BB9" smd circle
			(at -30.382464 -4.796028)
			(size 0.4318 0.4318)
			(layers "F.Cu" "F.Mask" "F.Paste")
			(net "UPI_CPU1_CPU0_P0P0_DP<2>")
		)
		(pad "BB11" smd circle
			(at -28.665424 -4.796028)
			(size 0.4318 0.4318)
			(layers "F.Cu" "F.Mask" "F.Paste")
			(net "UPI_CPU1_CPU0_P0P0_DN<0>")
		)
		(pad "BB13" smd circle
			(at -26.948384 -4.796028)
			(size 0.4318 0.4318)
			(layers "F.Cu" "F.Mask" "F.Paste")
			(net "TP_CPU0_RSVD_169")
		)
		(pad "BB15" smd circle
			(at -25.231598 -4.796028)
			(size 0.4318 0.4318)
			(layers "F.Cu" "F.Mask" "F.Paste")
			(net "TP_CPU0_RSVD_168")
		)
		(pad "BB17" smd circle
			(at -23.514558 -4.796028)
			(size 0.4318 0.4318)
			(layers "F.Cu" "F.Mask" "F.Paste")
			(net "TP_CPU0_RSVD_167")
		)
		(pad "BB19" smd circle
			(at -21.797518 -4.796028)
			(size 0.4318 0.4318)
			(layers "F.Cu" "F.Mask" "F.Paste")
			(net "GND")
		)
		(pad "BB21" smd circle
			(at -20.080478 -4.796028)
			(size 0.4318 0.4318)
			(layers "F.Cu" "F.Mask" "F.Paste")
			(net "TP_CPU0_RSVD_166")
		)
		(pad "BB23" smd circle
			(at -18.363438 -4.796028)
			(size 0.4318 0.4318)
			(layers "F.Cu" "F.Mask" "F.Paste")
			(net "GND")
		)
		(pad "BB25" smd circle
			(at -16.646398 -4.796028)
			(size 0.4318 0.4318)
			(layers "F.Cu" "F.Mask" "F.Paste")
			(net "CLK_100M_CPU0_RC_REFCLK1_DN")
		)
		(pad "BB27" smd circle
			(at -14.929612 -4.796028)
			(size 0.4318 0.4318)
			(layers "F.Cu" "F.Mask" "F.Paste")
			(net "PVCCIO_CPU0")
		)
		(pad "BB61" smd circle
			(at 15.787878 -6.596126)
			(size 0.4318 0.4318)
			(layers "F.Cu" "F.Mask" "F.Paste")
			(net "PVCCIN_CPU0")
		)
		(pad "BB63" smd circle
			(at 17.504918 -6.596126)
			(size 0.4318 0.4318)
			(layers "F.Cu" "F.Mask" "F.Paste")
			(net "GND")
		)
		(pad "BB65" smd circle
			(at 19.221958 -6.596126)
			(size 0.4318 0.4318)
			(layers "F.Cu" "F.Mask" "F.Paste")
			(net "TP_CPU0_RSVD_164")
		)
		(pad "BB67" smd circle
			(at 20.938998 -6.596126)
			(size 0.4318 0.4318)
			(layers "F.Cu" "F.Mask" "F.Paste")
			(net "TP_CPU0_RSVD_163")
		)
		(pad "BB69" smd circle
			(at 22.656038 -6.596126)
			(size 0.4318 0.4318)
			(layers "F.Cu" "F.Mask" "F.Paste")
			(net "GND")
		)
		(pad "BB71" smd circle
			(at 24.373078 -6.596126)
			(size 0.4318 0.4318)
			(layers "F.Cu" "F.Mask" "F.Paste")
			(net "M_C_DQS_DN<8>")
		)
		(pad "BB73" smd circle
			(at 26.090118 -6.596126)
			(size 0.4318 0.4318)
			(layers "F.Cu" "F.Mask" "F.Paste")
			(net "GND")
		)
		(pad "BB75" smd circle
			(at 27.806904 -6.596126)
			(size 0.4318 0.4318)
			(layers "F.Cu" "F.Mask" "F.Paste")
			(net "GND")
		)
		(pad "BB77" smd circle
			(at 29.523944 -6.596126)
			(size 0.4318 0.4318)
			(layers "F.Cu" "F.Mask" "F.Paste")
			(net "GND")
		)
		(pad "BB79" smd circle
			(at 31.240984 -6.596126)
			(size 0.4318 0.4318)
			(layers "F.Cu" "F.Mask" "F.Paste")
			(net "GND")
		)
		(pad "BB81" smd circle
			(at 32.958024 -6.596126)
			(size 0.4318 0.4318)
			(layers "F.Cu" "F.Mask" "F.Paste")
			(net "GND")
		)
		(pad "BB83" smd circle
			(at 34.675064 -6.596126)
			(size 0.4318 0.4318)
			(layers "F.Cu" "F.Mask" "F.Paste")
			(net "GND")
		)
		(pad "BB85" smd custom
			(at 36.392104 -6.596126 270)
			(size 0.10795 0.10795)
			(layers "F.Cu" "F.Mask" "F.Paste")
			(net "PVCCIN_CPU0")
			(options
				(clearance outline)
				(anchor circle)
			)
			(primitives
				(gr_poly
					(pts
						(arc
							(start 0.2159 -0.0381)
							(mid 0 -0.254)
							(end -0.2159 -0.0381)
						)
						(arc
							(start -0.2159 0.0381)
							(mid 0 0.254)
							(end 0.2159 0.0381)
						)
					)
					(width 0)
					(fill yes)
				)
			)
		)
		(pad "BC2" smd custom
			(at -36.392104 -4.300474 90)
			(size 0.10795 0.10795)
			(layers "F.Cu" "F.Mask" "F.Paste")
			(net "UPI_CPU0_CPU1_P0P0_DP<2>")
			(options
				(clearance outline)
				(anchor circle)
			)
			(primitives
				(gr_poly
					(pts
						(arc
							(start 0.2159 -0.0381)
							(mid 0 -0.254)
							(end -0.2159 -0.0381)
						)
						(arc
							(start -0.2159 0.0381)
							(mid 0 0.254)
							(end 0.2159 0.0381)
						)
					)
					(width 0)
					(fill yes)
				)
			)
		)
		(pad "BC4" smd circle
			(at -34.675064 -4.300474)
			(size 0.4318 0.4318)
			(layers "F.Cu" "F.Mask" "F.Paste")
			(net "GND")
		)
		(pad "BC6" smd circle
			(at -32.958024 -4.300474)
			(size 0.4318 0.4318)
			(layers "F.Cu" "F.Mask" "F.Paste")
			(net "UPI_CPU1_CPU0_P0P0_DN<5>")
		)
		(pad "BC8" smd circle
			(at -31.240984 -4.300474)
			(size 0.4318 0.4318)
			(layers "F.Cu" "F.Mask" "F.Paste")
			(net "GND")
		)
		(pad "BC10" smd circle
			(at -29.523944 -4.300474)
			(size 0.4318 0.4318)
			(layers "F.Cu" "F.Mask" "F.Paste")
			(net "UPI_CPU1_CPU0_P0P0_DP<1>")
		)
		(pad "BC12" smd circle
			(at -27.806904 -4.300474)
			(size 0.4318 0.4318)
			(layers "F.Cu" "F.Mask" "F.Paste")
			(net "GND")
		)
		(pad "BC14" smd circle
			(at -26.090118 -4.300474)
			(size 0.4318 0.4318)
			(layers "F.Cu" "F.Mask" "F.Paste")
			(net "TP_CPU0_RSVD_162")
		)
		(pad "BC16" smd circle
			(at -24.373078 -4.300474)
			(size 0.4318 0.4318)
			(layers "F.Cu" "F.Mask" "F.Paste")
			(net "GND")
		)
		(pad "BC18" smd circle
			(at -22.656038 -4.300474)
			(size 0.4318 0.4318)
			(layers "F.Cu" "F.Mask" "F.Paste")
			(net "TP_CPU0_RSVD_161")
		)
		(pad "BC20" smd circle
			(at -20.938998 -4.300474)
			(size 0.4318 0.4318)
			(layers "F.Cu" "F.Mask" "F.Paste")
			(net "TP_CPU0_RSVD_160")
		)
		(pad "BC22" smd circle
			(at -19.221958 -4.300474)
			(size 0.4318 0.4318)
			(layers "F.Cu" "F.Mask" "F.Paste")
			(net "TP_CPU0_RSVD_159")
		)
		(pad "BC24" smd circle
			(at -17.504918 -4.300474)
			(size 0.4318 0.4318)
			(layers "F.Cu" "F.Mask" "F.Paste")
			(net "PWRGD_CPU0_G")
		)
		(pad "BC26" smd circle
			(at -15.787878 -4.300474)
			(size 0.4318 0.4318)
			(layers "F.Cu" "F.Mask" "F.Paste")
			(net "PVCCIO_CPU0")
		)
		(pad "BC60" smd circle
			(at 14.929612 -6.100572)
			(size 0.508 0.508)
			(layers "F.Cu" "F.Mask" "F.Paste")
			(net "PVCCIN_CPU0")
		)
		(pad "BC62" smd circle
			(at 16.646398 -6.100572)
			(size 0.4318 0.4318)
			(layers "F.Cu" "F.Mask" "F.Paste")
			(net "PVCCIN_CPU0")
		)
		(pad "BC64" smd circle
			(at 18.363438 -6.100572)
			(size 0.4318 0.4318)
			(layers "F.Cu" "F.Mask" "F.Paste")
			(net "TP_CPU0_RSVD_158")
		)
		(pad "BC66" smd circle
			(at 20.080478 -6.100572)
			(size 0.4318 0.4318)
			(layers "F.Cu" "F.Mask" "F.Paste")
			(net "TP_CPU0_RSVD_157")
		)
		(pad "BC68" smd circle
			(at 21.797518 -6.100572)
			(size 0.4318 0.4318)
			(layers "F.Cu" "F.Mask" "F.Paste")
			(net "TP_CPU0_RSVD_156")
		)
		(pad "BC70" smd circle
			(at 23.514558 -6.100572)
			(size 0.4318 0.4318)
			(layers "F.Cu" "F.Mask" "F.Paste")
			(net "GND")
		)
		(pad "BC72" smd circle
			(at 25.231598 -6.100572)
			(size 0.4318 0.4318)
			(layers "F.Cu" "F.Mask" "F.Paste")
			(net "GND")
		)
		(pad "BC74" smd circle
			(at 26.948384 -6.100572)
			(size 0.4318 0.4318)
			(layers "F.Cu" "F.Mask" "F.Paste")
			(net "GND")
		)
		(pad "BC76" smd circle
			(at 28.665424 -6.100572)
			(size 0.4318 0.4318)
			(layers "F.Cu" "F.Mask" "F.Paste")
			(net "GND")
		)
		(pad "BC78" smd circle
			(at 30.382464 -6.100572)
			(size 0.4318 0.4318)
			(layers "F.Cu" "F.Mask" "F.Paste")
			(net "GND")
		)
		(pad "BC80" smd circle
			(at 32.099504 -6.100572)
			(size 0.4318 0.4318)
			(layers "F.Cu" "F.Mask" "F.Paste")
			(net "GND")
		)
		(pad "BC82" smd circle
			(at 33.816544 -6.100572)
			(size 0.4318 0.4318)
			(layers "F.Cu" "F.Mask" "F.Paste")
			(net "GND")
		)
		(pad "BC84" smd circle
			(at 35.533584 -6.100572)
			(size 0.4318 0.4318)
			(layers "F.Cu" "F.Mask" "F.Paste")
			(net "PVCCIN_CPU0")
		)
		(pad "BD3" smd custom
			(at -35.533584 -3.805428 90)
			(size 0.10795 0.10795)
			(layers "F.Cu" "F.Mask" "F.Paste")
			(net "UPI_CPU0_CPU1_P0P0_DP<1>")
			(options
				(clearance outline)
				(anchor circle)
			)
			(primitives
				(gr_poly
					(pts
						(arc
							(start 0.2159 -0.0381)
							(mid 0 -0.254)
							(end -0.2159 -0.0381)
						)
						(arc
							(start -0.2159 0.0381)
							(mid 0 0.254)
							(end 0.2159 0.0381)
						)
					)
					(width 0)
					(fill yes)
				)
			)
		)
		(pad "BD5" smd circle
			(at -33.816544 -3.805428)
			(size 0.4318 0.4318)
			(layers "F.Cu" "F.Mask" "F.Paste")
			(net "GND")
		)
		(pad "BD7" smd circle
			(at -32.099504 -3.805428)
			(size 0.4318 0.4318)
			(layers "F.Cu" "F.Mask" "F.Paste")
			(net "UPI_CPU1_CPU0_P0P0_DN<4>")
		)
		(pad "BD9" smd circle
			(at -30.382464 -3.805428)
			(size 0.4318 0.4318)
			(layers "F.Cu" "F.Mask" "F.Paste")
			(net "UPI_CPU1_CPU0_P0P0_DN<1>")
		)
		(pad "BD11" smd circle
			(at -28.665424 -3.805428)
			(size 0.4318 0.4318)
			(layers "F.Cu" "F.Mask" "F.Paste")
			(net "GND")
		)
		(pad "BD13" smd circle
			(at -26.948384 -3.805428)
			(size 0.4318 0.4318)
			(layers "F.Cu" "F.Mask" "F.Paste")
			(net "PVCCMCP_CPU0")
		)
		(pad "BD15" smd circle
			(at -25.231598 -3.805428)
			(size 0.4318 0.4318)
			(layers "F.Cu" "F.Mask" "F.Paste")
			(net "GND")
		)
		(pad "BD17" smd circle
			(at -23.514558 -3.805428)
			(size 0.4318 0.4318)
			(layers "F.Cu" "F.Mask" "F.Paste")
			(net "TP_CPU0_RSVD_155")
		)
		(pad "BD19" smd circle
			(at -21.797518 -3.805428)
			(size 0.4318 0.4318)
			(layers "F.Cu" "F.Mask" "F.Paste")
			(net "TP_CPU0_RSVD_154")
		)
		(pad "BD21" smd circle
			(at -20.080478 -3.805428)
			(size 0.4318 0.4318)
			(layers "F.Cu" "F.Mask" "F.Paste")
			(net "GND")
		)
		(pad "BD23" smd circle
			(at -18.363438 -3.805428)
			(size 0.4318 0.4318)
			(layers "F.Cu" "F.Mask" "F.Paste")
			(net "H_CPU0_BMCINIT")
		)
		(pad "BD25" smd circle
			(at -16.646398 -3.805428)
			(size 0.4318 0.4318)
			(layers "F.Cu" "F.Mask" "F.Paste")
			(net "CLK_100M_CPU0_RC_REFCLK1_DP")
		)
		(pad "BD27" smd circle
			(at -14.929612 -3.805428)
			(size 0.4318 0.4318)
			(layers "F.Cu" "F.Mask" "F.Paste")
			(net "GND")
		)
		(pad "BD61" smd circle
			(at 15.787878 -5.605272)
			(size 0.4318 0.4318)
			(layers "F.Cu" "F.Mask" "F.Paste")
			(net "PVCCIN_CPU0")
		)
		(pad "BD63" smd circle
			(at 17.504918 -5.605272)
			(size 0.4318 0.4318)
			(layers "F.Cu" "F.Mask" "F.Paste")
			(net "GND")
		)
		(pad "BD65" smd circle
			(at 19.221958 -5.605272)
			(size 0.4318 0.4318)
			(layers "F.Cu" "F.Mask" "F.Paste")
			(net "TP_CPU0_RSVD_152")
		)
		(pad "BD67" smd circle
			(at 20.938998 -5.605272)
			(size 0.4318 0.4318)
			(layers "F.Cu" "F.Mask" "F.Paste")
			(net "TP_CPU0_RSVD_151")
		)
		(pad "BD69" smd circle
			(at 22.656038 -5.605272)
			(size 0.4318 0.4318)
			(layers "F.Cu" "F.Mask" "F.Paste")
			(net "TP_CPU0_RSVD_150")
		)
		(pad "BD71" smd circle
			(at 24.373078 -5.605272)
			(size 0.4318 0.4318)
			(layers "F.Cu" "F.Mask" "F.Paste")
			(net "GND")
		)
		(pad "BD73" smd circle
			(at 26.090118 -5.605272)
			(size 0.4318 0.4318)
			(layers "F.Cu" "F.Mask" "F.Paste")
			(net "PVCCIN_CPU0")
		)
		(pad "BD75" smd circle
			(at 27.806904 -5.605272)
			(size 0.4318 0.4318)
			(layers "F.Cu" "F.Mask" "F.Paste")
			(net "PVCCIN_CPU0")
		)
		(pad "BD77" smd circle
			(at 29.523944 -5.605272)
			(size 0.4318 0.4318)
			(layers "F.Cu" "F.Mask" "F.Paste")
			(net "PVCCIN_CPU0")
		)
		(pad "BD79" smd circle
			(at 31.240984 -5.605272)
			(size 0.4318 0.4318)
			(layers "F.Cu" "F.Mask" "F.Paste")
			(net "PVCCIN_CPU0")
		)
		(pad "BD81" smd circle
			(at 32.958024 -5.605272)
			(size 0.4318 0.4318)
			(layers "F.Cu" "F.Mask" "F.Paste")
			(net "PVCCIN_CPU0")
		)
		(pad "BD83" smd circle
			(at 34.675064 -5.605272)
			(size 0.4318 0.4318)
			(layers "F.Cu" "F.Mask" "F.Paste")
			(net "PVCCIN_CPU0")
		)
		(pad "BD85" smd custom
			(at 36.392104 -5.605272 270)
			(size 0.10795 0.10795)
			(layers "F.Cu" "F.Mask" "F.Paste")
			(net "PVCCIN_CPU0")
			(options
				(clearance outline)
				(anchor circle)
			)
			(primitives
				(gr_poly
					(pts
						(arc
							(start 0.2159 -0.0381)
							(mid 0 -0.254)
							(end -0.2159 -0.0381)
						)
						(arc
							(start -0.2159 0.0381)
							(mid 0 0.254)
							(end 0.2159 0.0381)
						)
					)
					(width 0)
					(fill yes)
				)
			)
		)
		(pad "BE4" smd circle
			(at -34.675064 -3.309874)
			(size 0.4318 0.4318)
			(layers "F.Cu" "F.Mask" "F.Paste")
			(net "GND")
		)
		(pad "BE6" smd circle
			(at -32.958024 -3.309874)
			(size 0.4318 0.4318)
			(layers "F.Cu" "F.Mask" "F.Paste")
			(net "GND")
		)
		(pad "BE8" smd circle
			(at -31.240984 -3.309874)
			(size 0.4318 0.4318)
			(layers "F.Cu" "F.Mask" "F.Paste")
			(net "GND")
		)
		(pad "BE10" smd circle
			(at -29.523944 -3.309874)
			(size 0.4318 0.4318)
			(layers "F.Cu" "F.Mask" "F.Paste")
			(net "GND")
		)
		(pad "BE12" smd circle
			(at -27.806904 -3.309874)
			(size 0.4318 0.4318)
			(layers "F.Cu" "F.Mask" "F.Paste")
			(net "PVCCMCP_CPU0")
		)
		(pad "BE14" smd circle
			(at -26.090118 -3.309874)
			(size 0.4318 0.4318)
			(layers "F.Cu" "F.Mask" "F.Paste")
			(net "PVCCMCP_CPU0")
		)
		(pad "BE16" smd circle
			(at -24.373078 -3.309874)
			(size 0.4318 0.4318)
			(layers "F.Cu" "F.Mask" "F.Paste")
			(net "CLK_156M_OSC_CPU0_HFI_DN")
		)
		(pad "BE18" smd circle
			(at -22.656038 -3.309874)
			(size 0.4318 0.4318)
			(layers "F.Cu" "F.Mask" "F.Paste")
			(net "TP_CPU0_RSVD_149")
		)
		(pad "BE20" smd circle
			(at -20.938998 -3.309874)
			(size 0.4318 0.4318)
			(layers "F.Cu" "F.Mask" "F.Paste")
			(net "TP_CPU0_RSVD_148")
		)
		(pad "BE22" smd circle
			(at -19.221958 -3.309874)
			(size 0.4318 0.4318)
			(layers "F.Cu" "F.Mask" "F.Paste")
			(net "TP_CPU0_RSVD_147")
		)
		(pad "BE24" smd circle
			(at -17.504918 -3.309874)
			(size 0.4318 0.4318)
			(layers "F.Cu" "F.Mask" "F.Paste")
			(net "PVCCIO_CPU0")
		)
		(pad "BE26" smd circle
			(at -15.787878 -3.309874)
			(size 0.4318 0.4318)
			(layers "F.Cu" "F.Mask" "F.Paste")
			(net "GND")
		)
		(pad "BE60" smd circle
			(at 14.929612 -5.109972)
			(size 0.508 0.508)
			(layers "F.Cu" "F.Mask" "F.Paste")
			(net "PVCCIN_CPU0")
		)
		(pad "BE62" smd circle
			(at 16.646398 -5.109972)
			(size 0.4318 0.4318)
			(layers "F.Cu" "F.Mask" "F.Paste")
			(net "PVCCIN_CPU0")
		)
		(pad "BE64" smd circle
			(at 18.363438 -5.109972)
			(size 0.4318 0.4318)
			(layers "F.Cu" "F.Mask" "F.Paste")
			(net "GND")
		)
		(pad "BE66" smd circle
			(at 20.080478 -5.109972)
			(size 0.4318 0.4318)
			(layers "F.Cu" "F.Mask" "F.Paste")
			(net "GND")
		)
		(pad "BE68" smd circle
			(at 21.797518 -5.109972)
			(size 0.4318 0.4318)
			(layers "F.Cu" "F.Mask" "F.Paste")
			(net "GND")
		)
		(pad "BE70" smd circle
			(at 23.514558 -5.109972)
			(size 0.4318 0.4318)
			(layers "F.Cu" "F.Mask" "F.Paste")
			(net "GND")
		)
		(pad "BE72" smd circle
			(at 25.231598 -5.109972)
			(size 0.4318 0.4318)
			(layers "F.Cu" "F.Mask" "F.Paste")
			(net "PVCCIN_CPU0")
		)
		(pad "BE74" smd circle
			(at 26.948384 -5.109972)
			(size 0.4318 0.4318)
			(layers "F.Cu" "F.Mask" "F.Paste")
			(net "PVCCIN_CPU0")
		)
		(pad "BE76" smd circle
			(at 28.665424 -5.109972)
			(size 0.4318 0.4318)
			(layers "F.Cu" "F.Mask" "F.Paste")
			(net "PVCCIN_CPU0")
		)
		(pad "BE78" smd circle
			(at 30.382464 -5.109972)
			(size 0.4318 0.4318)
			(layers "F.Cu" "F.Mask" "F.Paste")
			(net "PVCCIN_CPU0")
		)
		(pad "BE80" smd circle
			(at 32.099504 -5.109972)
			(size 0.4318 0.4318)
			(layers "F.Cu" "F.Mask" "F.Paste")
			(net "PVCCIN_CPU0")
		)
		(pad "BE82" smd circle
			(at 33.816544 -5.109972)
			(size 0.4318 0.4318)
			(layers "F.Cu" "F.Mask" "F.Paste")
			(net "PVCCIN_CPU0")
		)
		(pad "BE84" smd circle
			(at 35.533584 -5.109972)
			(size 0.4318 0.4318)
			(layers "F.Cu" "F.Mask" "F.Paste")
			(net "PVCCIN_CPU0")
		)
		(pad "BF3" smd custom
			(at -35.533584 -2.814828 90)
			(size 0.10795 0.10795)
			(layers "F.Cu" "F.Mask" "F.Paste")
			(net "UPI_CPU0_CPU1_P0P0_DN<1>")
			(options
				(clearance outline)
				(anchor circle)
			)
			(primitives
				(gr_poly
					(pts
						(arc
							(start 0.2159 -0.0381)
							(mid 0 -0.254)
							(end -0.2159 -0.0381)
						)
						(arc
							(start -0.2159 0.0381)
							(mid 0 0.254)
							(end 0.2159 0.0381)
						)
					)
					(width 0)
					(fill yes)
				)
			)
		)
		(pad "BF5" smd circle
			(at -33.816544 -2.814828)
			(size 0.4318 0.4318)
			(layers "F.Cu" "F.Mask" "F.Paste")
			(net "VSENSE_PVCCIO_CPU0_SKT_VRTN")
		)
		(pad "BF7" smd circle
			(at -32.099504 -2.814828)
			(size 0.4318 0.4318)
			(layers "F.Cu" "F.Mask" "F.Paste")
			(net "UPI_CPU1_CPU0_P0P0_DP<4>")
		)
		(pad "BF9" smd circle
			(at -30.382464 -2.814828)
			(size 0.4318 0.4318)
			(layers "F.Cu" "F.Mask" "F.Paste")
			(net "GND")
		)
		(pad "BF11" smd circle
			(at -28.665424 -2.814828)
			(size 0.4318 0.4318)
			(layers "F.Cu" "F.Mask" "F.Paste")
			(net "PVCCMCP_CPU0")
		)
		(pad "BF13" smd circle
			(at -26.948384 -2.814828)
			(size 0.4318 0.4318)
			(layers "F.Cu" "F.Mask" "F.Paste")
			(net "PVCCMCP_CPU0")
		)
		(pad "BF15" smd circle
			(at -25.231598 -2.814828)
			(size 0.4318 0.4318)
			(layers "F.Cu" "F.Mask" "F.Paste")
			(net "GND")
		)
		(pad "BF17" smd circle
			(at -23.514558 -2.814828)
			(size 0.4318 0.4318)
			(layers "F.Cu" "F.Mask" "F.Paste")
			(net "GND")
		)
		(pad "BF19" smd circle
			(at -21.797518 -2.814828)
			(size 0.4318 0.4318)
			(layers "F.Cu" "F.Mask" "F.Paste")
			(net "GND")
		)
		(pad "BF21" smd circle
			(at -20.080478 -2.814828)
			(size 0.4318 0.4318)
			(layers "F.Cu" "F.Mask" "F.Paste")
			(net "TP_CPU0_RSVD_146")
		)
		(pad "BF23" smd circle
			(at -18.363438 -2.814828)
			(size 0.4318 0.4318)
			(layers "F.Cu" "F.Mask" "F.Paste")
			(net "PVCCIO_CPU0")
		)
		(pad "BF25" smd circle
			(at -16.646398 -2.814828)
			(size 0.4318 0.4318)
			(layers "F.Cu" "F.Mask" "F.Paste")
			(net "GND")
		)
		(pad "BF27" smd circle
			(at -14.929612 -2.814828)
			(size 0.4318 0.4318)
			(layers "F.Cu" "F.Mask" "F.Paste")
			(net "PVCCIO_CPU0")
		)
		(pad "BF61" smd circle
			(at 15.787878 -4.614926)
			(size 0.4318 0.4318)
			(layers "F.Cu" "F.Mask" "F.Paste")
			(net "PVCCIN_CPU0")
		)
		(pad "BF63" smd circle
			(at 17.504918 -4.614926)
			(size 0.4318 0.4318)
			(layers "F.Cu" "F.Mask" "F.Paste")
			(net "GND")
		)
		(pad "BF65" smd circle
			(at 19.221958 -4.614926)
			(size 0.4318 0.4318)
			(layers "F.Cu" "F.Mask" "F.Paste")
			(net "GND")
		)
		(pad "BF67" smd circle
			(at 20.938998 -4.614926)
			(size 0.4318 0.4318)
			(layers "F.Cu" "F.Mask" "F.Paste")
			(net "GND")
		)
		(pad "BF69" smd circle
			(at 22.656038 -4.614926)
			(size 0.4318 0.4318)
			(layers "F.Cu" "F.Mask" "F.Paste")
			(net "GND")
		)
		(pad "BF71" smd circle
			(at 24.373078 -4.614926)
			(size 0.4318 0.4318)
			(layers "F.Cu" "F.Mask" "F.Paste")
			(net "GND")
		)
		(pad "BF73" smd circle
			(at 26.090118 -4.614926)
			(size 0.4318 0.4318)
			(layers "F.Cu" "F.Mask" "F.Paste")
			(net "PVCCIN_CPU0")
		)
		(pad "BF75" smd circle
			(at 27.806904 -4.614926)
			(size 0.4318 0.4318)
			(layers "F.Cu" "F.Mask" "F.Paste")
			(net "PVCCIN_CPU0")
		)
		(pad "BF77" smd circle
			(at 29.523944 -4.614926)
			(size 0.4318 0.4318)
			(layers "F.Cu" "F.Mask" "F.Paste")
			(net "PVCCIN_CPU0")
		)
		(pad "BF79" smd circle
			(at 31.240984 -4.614926)
			(size 0.4318 0.4318)
			(layers "F.Cu" "F.Mask" "F.Paste")
			(net "PVCCIN_CPU0")
		)
		(pad "BF81" smd circle
			(at 32.958024 -4.614926)
			(size 0.4318 0.4318)
			(layers "F.Cu" "F.Mask" "F.Paste")
			(net "PVCCIN_CPU0")
		)
		(pad "BF83" smd circle
			(at 34.675064 -4.614926)
			(size 0.4318 0.4318)
			(layers "F.Cu" "F.Mask" "F.Paste")
			(net "PVCCIN_CPU0")
		)
		(pad "BF85" smd custom
			(at 36.392104 -4.614926 270)
			(size 0.10795 0.10795)
			(layers "F.Cu" "F.Mask" "F.Paste")
			(net "PVCCIN_CPU0")
			(options
				(clearance outline)
				(anchor circle)
			)
			(primitives
				(gr_poly
					(pts
						(arc
							(start 0.2159 -0.0381)
							(mid 0 -0.254)
							(end -0.2159 -0.0381)
						)
						(arc
							(start -0.2159 0.0381)
							(mid 0 0.254)
							(end 0.2159 0.0381)
						)
					)
					(width 0)
					(fill yes)
				)
			)
		)
		(pad "BG4" smd circle
			(at -34.675064 -2.319274)
			(size 0.4318 0.4318)
			(layers "F.Cu" "F.Mask" "F.Paste")
			(net "UPI_CPU0_CPU1_P0P0_DN<0>")
		)
		(pad "BG6" smd circle
			(at -32.958024 -2.319274)
			(size 0.4318 0.4318)
			(layers "F.Cu" "F.Mask" "F.Paste")
			(net "GND")
		)
		(pad "BG8" smd circle
			(at -31.240984 -2.319274)
			(size 0.4318 0.4318)
			(layers "F.Cu" "F.Mask" "F.Paste")
			(net "GND")
		)
		(pad "BG10" smd circle
			(at -29.523944 -2.319274)
			(size 0.4318 0.4318)
			(layers "F.Cu" "F.Mask" "F.Paste")
			(net "GND")
		)
		(pad "BG12" smd circle
			(at -27.806904 -2.319274)
			(size 0.4318 0.4318)
			(layers "F.Cu" "F.Mask" "F.Paste")
			(net "PVCCMCP_CPU0")
		)
		(pad "BG14" smd circle
			(at -26.090118 -2.319274)
			(size 0.4318 0.4318)
			(layers "F.Cu" "F.Mask" "F.Paste")
			(net "PVCCMCP_CPU0")
		)
		(pad "BG16" smd circle
			(at -24.373078 -2.319274)
			(size 0.4318 0.4318)
			(layers "F.Cu" "F.Mask" "F.Paste")
			(net "CLK_156M_OSC_CPU0_HFI_DP")
		)
		(pad "BG18" smd circle
			(at -22.656038 -2.319274)
			(size 0.4318 0.4318)
			(layers "F.Cu" "F.Mask" "F.Paste")
			(net "TP_CPU0_RSVD_145")
		)
		(pad "BG20" smd circle
			(at -20.938998 -2.319274)
			(size 0.4318 0.4318)
			(layers "F.Cu" "F.Mask" "F.Paste")
			(net "TP_CPU0_RSVD_144")
		)
		(pad "BG22" smd circle
			(at -19.221958 -2.319274)
			(size 0.4318 0.4318)
			(layers "F.Cu" "F.Mask" "F.Paste")
			(net "GND")
		)
		(pad "BG24" smd circle
			(at -17.504918 -2.319274)
			(size 0.4318 0.4318)
			(layers "F.Cu" "F.Mask" "F.Paste")
			(net "GND")
		)
		(pad "BG26" smd circle
			(at -15.787878 -2.319274)
			(size 0.4318 0.4318)
			(layers "F.Cu" "F.Mask" "F.Paste")
			(net "PVCCIO_CPU0")
		)
		(pad "BG60" smd circle
			(at 14.929612 -4.119372)
			(size 0.508 0.508)
			(layers "F.Cu" "F.Mask" "F.Paste")
			(net "PVCCIN_CPU0")
		)
		(pad "BG62" smd circle
			(at 16.646398 -4.119372)
			(size 0.4318 0.4318)
			(layers "F.Cu" "F.Mask" "F.Paste")
			(net "PVCCIN_CPU0")
		)
		(pad "BG64" smd circle
			(at 18.363438 -4.119372)
			(size 0.4318 0.4318)
			(layers "F.Cu" "F.Mask" "F.Paste")
			(net "PVCCIN_CPU0")
		)
		(pad "BG66" smd circle
			(at 20.080478 -4.119372)
			(size 0.4318 0.4318)
			(layers "F.Cu" "F.Mask" "F.Paste")
			(net "PVCCIN_CPU0")
		)
		(pad "BG68" smd circle
			(at 21.797518 -4.119372)
			(size 0.4318 0.4318)
			(layers "F.Cu" "F.Mask" "F.Paste")
			(net "PVCCIN_CPU0")
		)
		(pad "BG70" smd circle
			(at 23.514558 -4.119372)
			(size 0.4318 0.4318)
			(layers "F.Cu" "F.Mask" "F.Paste")
			(net "PVCCIN_CPU0")
		)
		(pad "BG72" smd circle
			(at 25.231598 -4.119372)
			(size 0.4318 0.4318)
			(layers "F.Cu" "F.Mask" "F.Paste")
			(net "GND")
		)
		(pad "BG74" smd circle
			(at 26.948384 -4.119372)
			(size 0.4318 0.4318)
			(layers "F.Cu" "F.Mask" "F.Paste")
			(net "GND")
		)
		(pad "BG76" smd circle
			(at 28.665424 -4.119372)
			(size 0.4318 0.4318)
			(layers "F.Cu" "F.Mask" "F.Paste")
			(net "GND")
		)
		(pad "BG78" smd circle
			(at 30.382464 -4.119372)
			(size 0.4318 0.4318)
			(layers "F.Cu" "F.Mask" "F.Paste")
			(net "GND")
		)
		(pad "BG80" smd circle
			(at 32.099504 -4.119372)
			(size 0.4318 0.4318)
			(layers "F.Cu" "F.Mask" "F.Paste")
			(net "GND")
		)
		(pad "BG82" smd circle
			(at 33.816544 -4.119372)
			(size 0.4318 0.4318)
			(layers "F.Cu" "F.Mask" "F.Paste")
			(net "GND")
		)
		(pad "BG84" smd custom
			(at 35.533584 -4.119372 270)
			(size 0.10795 0.10795)
			(layers "F.Cu" "F.Mask" "F.Paste")
			(net "PVCCIN_CPU0")
			(options
				(clearance outline)
				(anchor circle)
			)
			(primitives
				(gr_poly
					(pts
						(arc
							(start 0.2159 -0.0381)
							(mid 0 -0.254)
							(end -0.2159 -0.0381)
						)
						(arc
							(start -0.2159 0.0381)
							(mid 0 0.254)
							(end 0.2159 0.0381)
						)
					)
					(width 0)
					(fill yes)
				)
			)
		)
		(pad "BH3" smd custom
			(at -35.533584 -1.824228 90)
			(size 0.10795 0.10795)
			(layers "F.Cu" "F.Mask" "F.Paste")
			(net "UPI_CPU0_CPU1_P0P0_DP<0>")
			(options
				(clearance outline)
				(anchor circle)
			)
			(primitives
				(gr_poly
					(pts
						(arc
							(start 0.2159 -0.0381)
							(mid 0 -0.254)
							(end -0.2159 -0.0381)
						)
						(arc
							(start -0.2159 0.0381)
							(mid 0 0.254)
							(end 0.2159 0.0381)
						)
					)
					(width 0)
					(fill yes)
				)
			)
		)
		(pad "BH5" smd circle
			(at -33.816544 -1.824228)
			(size 0.4318 0.4318)
			(layers "F.Cu" "F.Mask" "F.Paste")
			(net "VSENSE_PVCCIO_CPU0_SKT_VSEN")
		)
		(pad "BH7" smd circle
			(at -32.099504 -1.824228)
			(size 0.4318 0.4318)
			(layers "F.Cu" "F.Mask" "F.Paste")
			(net "GND")
		)
		(pad "BH9" smd circle
			(at -30.382464 -1.824228)
			(size 0.4318 0.4318)
			(layers "F.Cu" "F.Mask" "F.Paste")
			(net "GND")
		)
		(pad "BH11" smd circle
			(at -28.665424 -1.824228)
			(size 0.4318 0.4318)
			(layers "F.Cu" "F.Mask" "F.Paste")
			(net "GND")
		)
		(pad "BH13" smd circle
			(at -26.948384 -1.824228)
			(size 0.4318 0.4318)
			(layers "F.Cu" "F.Mask" "F.Paste")
			(net "PVCCMCP_CPU0")
		)
		(pad "BH15" smd circle
			(at -25.231598 -1.824228)
			(size 0.4318 0.4318)
			(layers "F.Cu" "F.Mask" "F.Paste")
			(net "GND")
		)
		(pad "BH17" smd circle
			(at -23.514558 -1.824228)
			(size 0.4318 0.4318)
			(layers "F.Cu" "F.Mask" "F.Paste")
			(net "GND")
		)
		(pad "BH19" smd circle
			(at -21.797518 -1.824228)
			(size 0.4318 0.4318)
			(layers "F.Cu" "F.Mask" "F.Paste")
			(net "PVCCMCP_CPU0")
		)
		(pad "BH21" smd circle
			(at -20.080478 -1.824228)
			(size 0.4318 0.4318)
			(layers "F.Cu" "F.Mask" "F.Paste")
			(net "GND")
		)
		(pad "BH23" smd circle
			(at -18.363438 -1.824228)
			(size 0.4318 0.4318)
			(layers "F.Cu" "F.Mask" "F.Paste")
			(net "SMB_HFI1_CPU0_LVC2_SDA")
		)
		(pad "BH25" smd circle
			(at -16.646398 -1.824228)
			(size 0.4318 0.4318)
			(layers "F.Cu" "F.Mask" "F.Paste")
			(net "PVCCIO_CPU0")
		)
		(pad "BH27" smd circle
			(at -14.929612 -1.824228)
			(size 0.4318 0.4318)
			(layers "F.Cu" "F.Mask" "F.Paste")
			(net "PVCCIO_CPU0")
		)
		(pad "BH61" smd circle
			(at 15.787878 -3.624326)
			(size 0.4318 0.4318)
			(layers "F.Cu" "F.Mask" "F.Paste")
			(net "PVCCIN_CPU0")
		)
		(pad "BH63" smd circle
			(at 17.504918 -3.624326)
			(size 0.4318 0.4318)
			(layers "F.Cu" "F.Mask" "F.Paste")
			(net "PVCCIN_CPU0")
		)
		(pad "BH65" smd circle
			(at 19.221958 -3.624326)
			(size 0.4318 0.4318)
			(layers "F.Cu" "F.Mask" "F.Paste")
			(net "PVCCIN_CPU0")
		)
		(pad "BH67" smd circle
			(at 20.938998 -3.624326)
			(size 0.4318 0.4318)
			(layers "F.Cu" "F.Mask" "F.Paste")
			(net "PVCCIN_CPU0")
		)
		(pad "BH69" smd circle
			(at 22.656038 -3.624326)
			(size 0.4318 0.4318)
			(layers "F.Cu" "F.Mask" "F.Paste")
			(net "PVCCIN_CPU0")
		)
		(pad "BH71" smd circle
			(at 24.373078 -3.624326)
			(size 0.4318 0.4318)
			(layers "F.Cu" "F.Mask" "F.Paste")
			(net "PVCCIN_CPU0")
		)
		(pad "BH73" smd circle
			(at 26.090118 -3.624326)
			(size 0.4318 0.4318)
			(layers "F.Cu" "F.Mask" "F.Paste")
			(net "PVCCIN_CPU0")
		)
		(pad "BH75" smd circle
			(at 27.806904 -3.624326)
			(size 0.4318 0.4318)
			(layers "F.Cu" "F.Mask" "F.Paste")
			(net "PVCCIN_CPU0")
		)
		(pad "BH77" smd circle
			(at 29.523944 -3.624326)
			(size 0.4318 0.4318)
			(layers "F.Cu" "F.Mask" "F.Paste")
			(net "PVCCIN_CPU0")
		)
		(pad "BH79" smd circle
			(at 31.240984 -3.624326)
			(size 0.4318 0.4318)
			(layers "F.Cu" "F.Mask" "F.Paste")
			(net "PVCCIN_CPU0")
		)
		(pad "BH81" smd circle
			(at 32.958024 -3.624326)
			(size 0.4318 0.4318)
			(layers "F.Cu" "F.Mask" "F.Paste")
			(net "PVCCIN_CPU0")
		)
		(pad "BH83" smd circle
			(at 34.675064 -3.624326)
			(size 0.4318 0.4318)
			(layers "F.Cu" "F.Mask" "F.Paste")
			(net "PVCCIN_CPU0")
		)
		(pad "BJ4" smd circle
			(at -34.675064 -1.328674)
			(size 0.4318 0.4318)
			(layers "F.Cu" "F.Mask" "F.Paste")
			(net "GND")
		)
		(pad "BJ6" smd circle
			(at -32.958024 -1.328674)
			(size 0.4318 0.4318)
			(layers "F.Cu" "F.Mask" "F.Paste")
			(net "GND")
		)
		(pad "BJ8" smd circle
			(at -31.240984 -1.328674)
			(size 0.4318 0.4318)
			(layers "F.Cu" "F.Mask" "F.Paste")
			(net "P3E_CPU0_PE2_SS_RXP<14>")
		)
		(pad "BJ10" smd circle
			(at -29.523944 -1.328674)
			(size 0.4318 0.4318)
			(layers "F.Cu" "F.Mask" "F.Paste")
			(net "P3E_CPU0_PE2_SS_RXP<15>")
		)
		(pad "BJ12" smd circle
			(at -27.806904 -1.328674)
			(size 0.4318 0.4318)
			(layers "F.Cu" "F.Mask" "F.Paste")
			(net "PVCCMCP_CPU0")
		)
		(pad "BJ14" smd circle
			(at -26.090118 -1.328674)
			(size 0.4318 0.4318)
			(layers "F.Cu" "F.Mask" "F.Paste")
			(net "PVCCMCP_CPU0")
		)
		(pad "BJ16" smd circle
			(at -24.373078 -1.328674)
			(size 0.4318 0.4318)
			(layers "F.Cu" "F.Mask" "F.Paste")
			(net "PVCCMCP_CPU0")
		)
		(pad "BJ18" smd circle
			(at -22.656038 -1.328674)
			(size 0.4318 0.4318)
			(layers "F.Cu" "F.Mask" "F.Paste")
			(net "PVCCMCP_CPU0")
		)
		(pad "BJ20" smd circle
			(at -20.938998 -1.328674)
			(size 0.4318 0.4318)
			(layers "F.Cu" "F.Mask" "F.Paste")
			(net "PVCCMCP_CPU0")
		)
		(pad "BJ22" smd circle
			(at -19.221958 -1.328674)
			(size 0.4318 0.4318)
			(layers "F.Cu" "F.Mask" "F.Paste")
			(net "SMB_HFI1_CPU0_LVC2_SCL")
		)
		(pad "BJ24" smd circle
			(at -17.504918 -1.328674)
			(size 0.4318 0.4318)
			(layers "F.Cu" "F.Mask" "F.Paste")
			(net "PVCCIO_CPU0")
		)
		(pad "BJ26" smd circle
			(at -15.787878 -1.328674)
			(size 0.4318 0.4318)
			(layers "F.Cu" "F.Mask" "F.Paste")
			(net "PVCCIO_CPU0")
		)
		(pad "BJ60" smd circle
			(at 14.929612 -3.128772)
			(size 0.508 0.508)
			(layers "F.Cu" "F.Mask" "F.Paste")
			(net "PVCCIN_CPU0")
		)
		(pad "BJ62" smd circle
			(at 16.646398 -3.128772)
			(size 0.4318 0.4318)
			(layers "F.Cu" "F.Mask" "F.Paste")
			(net "PVCCIN_CPU0")
		)
		(pad "BJ64" smd circle
			(at 18.363438 -3.128772)
			(size 0.4318 0.4318)
			(layers "F.Cu" "F.Mask" "F.Paste")
			(net "PVCCIN_CPU0")
		)
		(pad "BJ66" smd circle
			(at 20.080478 -3.128772)
			(size 0.4318 0.4318)
			(layers "F.Cu" "F.Mask" "F.Paste")
			(net "PVCCIN_CPU0")
		)
		(pad "BJ68" smd circle
			(at 21.797518 -3.128772)
			(size 0.4318 0.4318)
			(layers "F.Cu" "F.Mask" "F.Paste")
			(net "PVCCIN_CPU0")
		)
		(pad "BJ70" smd circle
			(at 23.514558 -3.128772)
			(size 0.4318 0.4318)
			(layers "F.Cu" "F.Mask" "F.Paste")
			(net "PVCCIN_CPU0")
		)
		(pad "BJ72" smd circle
			(at 25.231598 -3.128772)
			(size 0.4318 0.4318)
			(layers "F.Cu" "F.Mask" "F.Paste")
			(net "PVCCIN_CPU0")
		)
		(pad "BJ74" smd circle
			(at 26.948384 -3.128772)
			(size 0.4318 0.4318)
			(layers "F.Cu" "F.Mask" "F.Paste")
			(net "PVCCIN_CPU0")
		)
		(pad "BJ76" smd circle
			(at 28.665424 -3.128772)
			(size 0.4318 0.4318)
			(layers "F.Cu" "F.Mask" "F.Paste")
			(net "PVCCIN_CPU0")
		)
		(pad "BJ78" smd circle
			(at 30.382464 -3.128772)
			(size 0.4318 0.4318)
			(layers "F.Cu" "F.Mask" "F.Paste")
			(net "PVCCIN_CPU0")
		)
		(pad "BJ80" smd circle
			(at 32.099504 -3.128772)
			(size 0.4318 0.4318)
			(layers "F.Cu" "F.Mask" "F.Paste")
			(net "PVCCIN_CPU0")
		)
		(pad "BJ82" smd circle
			(at 33.816544 -3.128772)
			(size 0.4318 0.4318)
			(layers "F.Cu" "F.Mask" "F.Paste")
			(net "PVCCIN_CPU0")
		)
		(pad "BJ84" smd custom
			(at 35.533584 -3.128772 270)
			(size 0.10795 0.10795)
			(layers "F.Cu" "F.Mask" "F.Paste")
			(net "PVCCIN_CPU0")
			(options
				(clearance outline)
				(anchor circle)
			)
			(primitives
				(gr_poly
					(pts
						(arc
							(start 0.2159 -0.0381)
							(mid 0 -0.254)
							(end -0.2159 -0.0381)
						)
						(arc
							(start -0.2159 0.0381)
							(mid 0 0.254)
							(end 0.2159 0.0381)
						)
					)
					(width 0)
					(fill yes)
				)
			)
		)
		(pad "BK3" smd custom
			(at -35.533584 -0.833628 90)
			(size 0.10795 0.10795)
			(layers "F.Cu" "F.Mask" "F.Paste")
			(net "GND")
			(options
				(clearance outline)
				(anchor circle)
			)
			(primitives
				(gr_poly
					(pts
						(arc
							(start 0.2159 -0.0381)
							(mid 0 -0.254)
							(end -0.2159 -0.0381)
						)
						(arc
							(start -0.2159 0.0381)
							(mid 0 0.254)
							(end 0.2159 0.0381)
						)
					)
					(width 0)
					(fill yes)
				)
			)
		)
		(pad "BK5" smd circle
			(at -33.816544 -0.833628)
			(size 0.4318 0.4318)
			(layers "F.Cu" "F.Mask" "F.Paste")
			(net "P3E_CPU0_PE2_SS_TXP<15>")
		)
		(pad "BK7" smd circle
			(at -32.099504 -0.833628)
			(size 0.4318 0.4318)
			(layers "F.Cu" "F.Mask" "F.Paste")
			(net "GND")
		)
		(pad "BK9" smd circle
			(at -30.382464 -0.833628)
			(size 0.4318 0.4318)
			(layers "F.Cu" "F.Mask" "F.Paste")
			(net "P3E_CPU0_PE2_SS_RXN<15>")
		)
		(pad "BK11" smd circle
			(at -28.665424 -0.833628)
			(size 0.4318 0.4318)
			(layers "F.Cu" "F.Mask" "F.Paste")
			(net "GND")
		)
		(pad "BK13" smd circle
			(at -26.948384 -0.833628)
			(size 0.4318 0.4318)
			(layers "F.Cu" "F.Mask" "F.Paste")
			(net "PVCCMCP_CPU0")
		)
		(pad "BK15" smd circle
			(at -25.231598 -0.833628)
			(size 0.4318 0.4318)
			(layers "F.Cu" "F.Mask" "F.Paste")
			(net "PVCCMCP_CPU0")
		)
		(pad "BK17" smd circle
			(at -23.514558 -0.833628)
			(size 0.4318 0.4318)
			(layers "F.Cu" "F.Mask" "F.Paste")
			(net "PVCCMCP_CPU0")
		)
		(pad "BK19" smd circle
			(at -21.797518 -0.833628)
			(size 0.4318 0.4318)
			(layers "F.Cu" "F.Mask" "F.Paste")
			(net "GND")
		)
		(pad "BK21" smd circle
			(at -20.080478 -0.833628)
			(size 0.4318 0.4318)
			(layers "F.Cu" "F.Mask" "F.Paste")
			(net "LED_HFI0_CPU0_N")
		)
		(pad "BK23" smd circle
			(at -18.363438 -0.833628)
			(size 0.4318 0.4318)
			(layers "F.Cu" "F.Mask" "F.Paste")
			(net "RST_HFI1_CPU0_LVT2_N")
		)
		(pad "BK25" smd circle
			(at -16.646398 -0.833628)
			(size 0.4318 0.4318)
			(layers "F.Cu" "F.Mask" "F.Paste")
			(net "PVCCIO_CPU0")
		)
		(pad "BK27" smd circle
			(at -14.929612 -0.833628)
			(size 0.4318 0.4318)
			(layers "F.Cu" "F.Mask" "F.Paste")
			(net "PVCCIO_CPU0")
		)
		(pad "BK61" smd circle
			(at 15.787878 -2.633726)
			(size 0.4318 0.4318)
			(layers "F.Cu" "F.Mask" "F.Paste")
			(net "PVCCIN_CPU0")
		)
		(pad "BK63" smd circle
			(at 17.504918 -2.633726)
			(size 0.4318 0.4318)
			(layers "F.Cu" "F.Mask" "F.Paste")
			(net "PVCCIN_CPU0")
		)
		(pad "BK65" smd circle
			(at 19.221958 -2.633726)
			(size 0.4318 0.4318)
			(layers "F.Cu" "F.Mask" "F.Paste")
			(net "PVCCIN_CPU0")
		)
		(pad "BK67" smd circle
			(at 20.938998 -2.633726)
			(size 0.4318 0.4318)
			(layers "F.Cu" "F.Mask" "F.Paste")
			(net "PVCCIN_CPU0")
		)
		(pad "BK69" smd circle
			(at 22.656038 -2.633726)
			(size 0.4318 0.4318)
			(layers "F.Cu" "F.Mask" "F.Paste")
			(net "PVCCIN_CPU0")
		)
		(pad "BK71" smd circle
			(at 24.373078 -2.633726)
			(size 0.4318 0.4318)
			(layers "F.Cu" "F.Mask" "F.Paste")
			(net "PVCCIN_CPU0")
		)
		(pad "BK73" smd circle
			(at 26.090118 -2.633726)
			(size 0.4318 0.4318)
			(layers "F.Cu" "F.Mask" "F.Paste")
			(net "PVCCIN_CPU0")
		)
		(pad "BK75" smd circle
			(at 27.806904 -2.633726)
			(size 0.4318 0.4318)
			(layers "F.Cu" "F.Mask" "F.Paste")
			(net "PVCCIN_CPU0")
		)
		(pad "BK77" smd circle
			(at 29.523944 -2.633726)
			(size 0.4318 0.4318)
			(layers "F.Cu" "F.Mask" "F.Paste")
			(net "PVCCIN_CPU0")
		)
		(pad "BK79" smd circle
			(at 31.240984 -2.633726)
			(size 0.4318 0.4318)
			(layers "F.Cu" "F.Mask" "F.Paste")
			(net "PVCCIN_CPU0")
		)
		(pad "BK81" smd circle
			(at 32.958024 -2.633726)
			(size 0.4318 0.4318)
			(layers "F.Cu" "F.Mask" "F.Paste")
			(net "PVCCIN_CPU0")
		)
		(pad "BK83" smd circle
			(at 34.675064 -2.633726)
			(size 0.4318 0.4318)
			(layers "F.Cu" "F.Mask" "F.Paste")
			(net "PVCCIN_CPU0")
		)
		(pad "BL4" smd circle
			(at -34.675064 -0.338074)
			(size 0.4318 0.4318)
			(layers "F.Cu" "F.Mask" "F.Paste")
			(net "P3E_CPU0_PE2_SS_TXN<14>")
		)
		(pad "BL6" smd circle
			(at -32.958024 -0.338074)
			(size 0.4318 0.4318)
			(layers "F.Cu" "F.Mask" "F.Paste")
			(net "GND")
		)
		(pad "BL8" smd circle
			(at -31.240984 -0.338074)
			(size 0.4318 0.4318)
			(layers "F.Cu" "F.Mask" "F.Paste")
			(net "P3E_CPU0_PE2_SS_RXN<14>")
		)
		(pad "BL10" smd circle
			(at -29.523944 -0.338074)
			(size 0.4318 0.4318)
			(layers "F.Cu" "F.Mask" "F.Paste")
			(net "GND")
		)
		(pad "BL12" smd circle
			(at -27.806904 -0.338074)
			(size 0.4318 0.4318)
			(layers "F.Cu" "F.Mask" "F.Paste")
			(net "GND")
		)
		(pad "BL14" smd circle
			(at -26.090118 -0.338074)
			(size 0.4318 0.4318)
			(layers "F.Cu" "F.Mask" "F.Paste")
			(net "PVCCMCP_CPU0")
		)
		(pad "BL16" smd circle
			(at -24.373078 -0.338074)
			(size 0.4318 0.4318)
			(layers "F.Cu" "F.Mask" "F.Paste")
			(net "VSENSE_PVCCMCP_CPU0_SKT_VRTN")
		)
		(pad "BL18" smd circle
			(at -22.656038 -0.338074)
			(size 0.4318 0.4318)
			(layers "F.Cu" "F.Mask" "F.Paste")
			(net "PVCCIOMCP_CPU0")
		)
		(pad "BL20" smd circle
			(at -20.938998 -0.338074)
			(size 0.4318 0.4318)
			(layers "F.Cu" "F.Mask" "F.Paste")
			(net "PVCCMCP_CPU0")
		)
		(pad "BL22" smd circle
			(at -19.221958 -0.338074)
			(size 0.4318 0.4318)
			(layers "F.Cu" "F.Mask" "F.Paste")
			(net "GND")
		)
		(pad "BL24" smd circle
			(at -17.504918 -0.338074)
			(size 0.4318 0.4318)
			(layers "F.Cu" "F.Mask" "F.Paste")
			(net "GND")
		)
		(pad "BL26" smd circle
			(at -15.787878 -0.338074)
			(size 0.4318 0.4318)
			(layers "F.Cu" "F.Mask" "F.Paste")
			(net "PVCCIO_CPU0")
		)
		(pad "BL60" smd circle
			(at 14.929612 -2.138426)
			(size 0.508 0.508)
			(layers "F.Cu" "F.Mask" "F.Paste")
			(net "PVCCIN_CPU0")
		)
		(pad "BL62" smd circle
			(at 16.646398 -2.138426)
			(size 0.4318 0.4318)
			(layers "F.Cu" "F.Mask" "F.Paste")
			(net "PVCCIN_CPU0")
		)
		(pad "BL64" smd circle
			(at 18.363438 -2.138426)
			(size 0.4318 0.4318)
			(layers "F.Cu" "F.Mask" "F.Paste")
			(net "GND")
		)
		(pad "BL66" smd circle
			(at 20.080478 -2.138426)
			(size 0.4318 0.4318)
			(layers "F.Cu" "F.Mask" "F.Paste")
			(net "GND")
		)
		(pad "BL68" smd circle
			(at 21.797518 -2.138426)
			(size 0.4318 0.4318)
			(layers "F.Cu" "F.Mask" "F.Paste")
			(net "GND")
		)
		(pad "BL70" smd circle
			(at 23.514558 -2.138426)
			(size 0.4318 0.4318)
			(layers "F.Cu" "F.Mask" "F.Paste")
			(net "GND")
		)
		(pad "BL72" smd circle
			(at 25.231598 -2.138426)
			(size 0.4318 0.4318)
			(layers "F.Cu" "F.Mask" "F.Paste")
			(net "GND")
		)
		(pad "BL74" smd circle
			(at 26.948384 -2.138426)
			(size 0.4318 0.4318)
			(layers "F.Cu" "F.Mask" "F.Paste")
			(net "GND")
		)
		(pad "BL76" smd circle
			(at 28.665424 -2.138426)
			(size 0.4318 0.4318)
			(layers "F.Cu" "F.Mask" "F.Paste")
			(net "GND")
		)
		(pad "BL78" smd circle
			(at 30.382464 -2.138426)
			(size 0.4318 0.4318)
			(layers "F.Cu" "F.Mask" "F.Paste")
			(net "GND")
		)
		(pad "BL80" smd circle
			(at 32.099504 -2.138426)
			(size 0.4318 0.4318)
			(layers "F.Cu" "F.Mask" "F.Paste")
			(net "GND")
		)
		(pad "BL82" smd circle
			(at 33.816544 -2.138426)
			(size 0.4318 0.4318)
			(layers "F.Cu" "F.Mask" "F.Paste")
			(net "GND")
		)
		(pad "BL84" smd custom
			(at 35.533584 -2.138426 270)
			(size 0.10795 0.10795)
			(layers "F.Cu" "F.Mask" "F.Paste")
			(net "PVCCIN_CPU0")
			(options
				(clearance outline)
				(anchor circle)
			)
			(primitives
				(gr_poly
					(pts
						(arc
							(start 0.2159 -0.0381)
							(mid 0 -0.254)
							(end -0.2159 -0.0381)
						)
						(arc
							(start -0.2159 0.0381)
							(mid 0 0.254)
							(end 0.2159 0.0381)
						)
					)
					(width 0)
					(fill yes)
				)
			)
		)
		(pad "BM3" smd custom
			(at -35.533584 0.156972 90)
			(size 0.10795 0.10795)
			(layers "F.Cu" "F.Mask" "F.Paste")
			(net "P3E_CPU0_PE2_SS_TXP<14>")
			(options
				(clearance outline)
				(anchor circle)
			)
			(primitives
				(gr_poly
					(pts
						(arc
							(start 0.2159 -0.0381)
							(mid 0 -0.254)
							(end -0.2159 -0.0381)
						)
						(arc
							(start -0.2159 0.0381)
							(mid 0 0.254)
							(end 0.2159 0.0381)
						)
					)
					(width 0)
					(fill yes)
				)
			)
		)
		(pad "BM5" smd circle
			(at -33.816544 0.156972)
			(size 0.4318 0.4318)
			(layers "F.Cu" "F.Mask" "F.Paste")
			(net "P3E_CPU0_PE2_SS_TXN<15>")
		)
		(pad "BM7" smd circle
			(at -32.099504 0.156972)
			(size 0.4318 0.4318)
			(layers "F.Cu" "F.Mask" "F.Paste")
			(net "P3E_CPU0_PE2_SS_RXP<13>")
		)
		(pad "BM9" smd circle
			(at -30.382464 0.156972)
			(size 0.4318 0.4318)
			(layers "F.Cu" "F.Mask" "F.Paste")
			(net "GND")
		)
		(pad "BM11" smd circle
			(at -28.665424 0.156972)
			(size 0.4318 0.4318)
			(layers "F.Cu" "F.Mask" "F.Paste")
			(net "PVCCIOMCP_CPU0")
		)
		(pad "BM13" smd circle
			(at -26.948384 0.156972)
			(size 0.4318 0.4318)
			(layers "F.Cu" "F.Mask" "F.Paste")
			(net "GND")
		)
		(pad "BM15" smd circle
			(at -25.231598 0.156972)
			(size 0.4318 0.4318)
			(layers "F.Cu" "F.Mask" "F.Paste")
			(net "GND")
		)
		(pad "BM17" smd circle
			(at -23.514558 0.156972)
			(size 0.4318 0.4318)
			(layers "F.Cu" "F.Mask" "F.Paste")
			(net "PVCCIOMCP_CPU0")
		)
		(pad "BM19" smd circle
			(at -21.797518 0.156972)
			(size 0.4318 0.4318)
			(layers "F.Cu" "F.Mask" "F.Paste")
			(net "PVCCMCP_CPU0")
		)
		(pad "BM21" smd circle
			(at -20.080478 0.156972)
			(size 0.4318 0.4318)
			(layers "F.Cu" "F.Mask" "F.Paste")
			(net "IRQ_HFI1_CPU0_LVT2_N")
		)
		(pad "BM23" smd circle
			(at -18.363438 0.156972)
			(size 0.4318 0.4318)
			(layers "F.Cu" "F.Mask" "F.Paste")
			(net "LED_HFI1_CPU0_N")
		)
		(pad "BM25" smd circle
			(at -16.646398 0.156972)
			(size 0.4318 0.4318)
			(layers "F.Cu" "F.Mask" "F.Paste")
			(net "GND")
		)
		(pad "BM27" smd circle
			(at -14.929612 0.156972)
			(size 0.4318 0.4318)
			(layers "F.Cu" "F.Mask" "F.Paste")
			(net "PVCCIO_CPU0")
		)
		(pad "BM61" smd circle
			(at 15.787878 -1.643126)
			(size 0.4318 0.4318)
			(layers "F.Cu" "F.Mask" "F.Paste")
			(net "PVCCIN_CPU0")
		)
		(pad "BM63" smd circle
			(at 17.504918 -1.643126)
			(size 0.4318 0.4318)
			(layers "F.Cu" "F.Mask" "F.Paste")
			(net "PVCCIN_CPU0")
		)
		(pad "BM65" smd circle
			(at 19.221958 -1.643126)
			(size 0.4318 0.4318)
			(layers "F.Cu" "F.Mask" "F.Paste")
			(net "PVCCIN_CPU0")
		)
		(pad "BM67" smd circle
			(at 20.938998 -1.643126)
			(size 0.4318 0.4318)
			(layers "F.Cu" "F.Mask" "F.Paste")
			(net "PVCCIN_CPU0")
		)
		(pad "BM69" smd circle
			(at 22.656038 -1.643126)
			(size 0.4318 0.4318)
			(layers "F.Cu" "F.Mask" "F.Paste")
			(net "PVCCIN_CPU0")
		)
		(pad "BM71" smd circle
			(at 24.373078 -1.643126)
			(size 0.4318 0.4318)
			(layers "F.Cu" "F.Mask" "F.Paste")
			(net "PVCCIN_CPU0")
		)
		(pad "BM73" smd circle
			(at 26.090118 -1.643126)
			(size 0.4318 0.4318)
			(layers "F.Cu" "F.Mask" "F.Paste")
			(net "PVCCIN_CPU0")
		)
		(pad "BM75" smd circle
			(at 27.806904 -1.643126)
			(size 0.4318 0.4318)
			(layers "F.Cu" "F.Mask" "F.Paste")
			(net "PVCCIN_CPU0")
		)
		(pad "BM77" smd circle
			(at 29.523944 -1.643126)
			(size 0.4318 0.4318)
			(layers "F.Cu" "F.Mask" "F.Paste")
			(net "PVCCIN_CPU0")
		)
		(pad "BM79" smd circle
			(at 31.240984 -1.643126)
			(size 0.4318 0.4318)
			(layers "F.Cu" "F.Mask" "F.Paste")
			(net "PVCCIN_CPU0")
		)
		(pad "BM81" smd circle
			(at 32.958024 -1.643126)
			(size 0.4318 0.4318)
			(layers "F.Cu" "F.Mask" "F.Paste")
			(net "PVCCIN_CPU0")
		)
		(pad "BM83" smd circle
			(at 34.675064 -1.643126)
			(size 0.4318 0.4318)
			(layers "F.Cu" "F.Mask" "F.Paste")
			(net "PVCCIN_CPU0")
		)
		(pad "BN4" smd circle
			(at -34.675064 0.652526)
			(size 0.4318 0.4318)
			(layers "F.Cu" "F.Mask" "F.Paste")
			(net "P3E_CPU0_PE2_SS_TXP<13>")
		)
		(pad "BN6" smd circle
			(at -32.958024 0.652526)
			(size 0.4318 0.4318)
			(layers "F.Cu" "F.Mask" "F.Paste")
			(net "GND")
		)
		(pad "BN8" smd circle
			(at -31.240984 0.652526)
			(size 0.4318 0.4318)
			(layers "F.Cu" "F.Mask" "F.Paste")
			(net "P3E_CPU0_PE2_SS_RXN<13>")
		)
		(pad "BN10" smd circle
			(at -29.523944 0.652526)
			(size 0.4318 0.4318)
			(layers "F.Cu" "F.Mask" "F.Paste")
			(net "GND")
		)
		(pad "BN12" smd circle
			(at -27.806904 0.652526)
			(size 0.4318 0.4318)
			(layers "F.Cu" "F.Mask" "F.Paste")
			(net "PVCCIOMCP_CPU0")
		)
		(pad "BN14" smd circle
			(at -26.090118 0.652526)
			(size 0.4318 0.4318)
			(layers "F.Cu" "F.Mask" "F.Paste")
			(net "PVCCIOMCP_CPU0")
		)
		(pad "BN16" smd circle
			(at -24.373078 0.652526)
			(size 0.4318 0.4318)
			(layers "F.Cu" "F.Mask" "F.Paste")
			(net "VSENSE_PVCCMCP_CPU0_SKT_VSEN")
		)
		(pad "BN18" smd circle
			(at -22.656038 0.652526)
			(size 0.4318 0.4318)
			(layers "F.Cu" "F.Mask" "F.Paste")
			(net "PVCCIOMCP_CPU0")
		)
		(pad "BN20" smd circle
			(at -20.938998 0.652526)
			(size 0.4318 0.4318)
			(layers "F.Cu" "F.Mask" "F.Paste")
			(net "GND")
		)
		(pad "BN22" smd circle
			(at -19.221958 0.652526)
			(size 0.4318 0.4318)
			(layers "F.Cu" "F.Mask" "F.Paste")
			(net "SMB_HFI0_CPU0_LVC2_SCL")
		)
		(pad "BN24" smd circle
			(at -17.504918 0.652526)
			(size 0.4318 0.4318)
			(layers "F.Cu" "F.Mask" "F.Paste")
			(net "RST_HFI0_CPU0_LVT2_N")
		)
		(pad "BN26" smd circle
			(at -15.787878 0.652526)
			(size 0.4318 0.4318)
			(layers "F.Cu" "F.Mask" "F.Paste")
			(net "GND")
		)
		(pad "BN60" smd circle
			(at 14.929612 -1.147572)
			(size 0.508 0.508)
			(layers "F.Cu" "F.Mask" "F.Paste")
			(net "PVCCIN_CPU0")
		)
		(pad "BN62" smd circle
			(at 16.646398 -1.147572)
			(size 0.4318 0.4318)
			(layers "F.Cu" "F.Mask" "F.Paste")
			(net "PVCCIN_CPU0")
		)
		(pad "BN64" smd circle
			(at 18.363438 -1.147572)
			(size 0.4318 0.4318)
			(layers "F.Cu" "F.Mask" "F.Paste")
			(net "PVCCIN_CPU0")
		)
		(pad "BN66" smd circle
			(at 20.080478 -1.147572)
			(size 0.4318 0.4318)
			(layers "F.Cu" "F.Mask" "F.Paste")
			(net "PVCCIN_CPU0")
		)
		(pad "BN68" smd circle
			(at 21.797518 -1.147572)
			(size 0.4318 0.4318)
			(layers "F.Cu" "F.Mask" "F.Paste")
			(net "PVCCIN_CPU0")
		)
		(pad "BN70" smd circle
			(at 23.514558 -1.147572)
			(size 0.4318 0.4318)
			(layers "F.Cu" "F.Mask" "F.Paste")
			(net "PVCCIN_CPU0")
		)
		(pad "BN72" smd circle
			(at 25.231598 -1.147572)
			(size 0.4318 0.4318)
			(layers "F.Cu" "F.Mask" "F.Paste")
			(net "PVCCIN_CPU0")
		)
		(pad "BN74" smd circle
			(at 26.948384 -1.147572)
			(size 0.4318 0.4318)
			(layers "F.Cu" "F.Mask" "F.Paste")
			(net "PVCCIN_CPU0")
		)
		(pad "BN76" smd circle
			(at 28.665424 -1.147572)
			(size 0.4318 0.4318)
			(layers "F.Cu" "F.Mask" "F.Paste")
			(net "PVCCIN_CPU0")
		)
		(pad "BN78" smd circle
			(at 30.382464 -1.147572)
			(size 0.4318 0.4318)
			(layers "F.Cu" "F.Mask" "F.Paste")
			(net "PVCCIN_CPU0")
		)
		(pad "BN80" smd circle
			(at 32.099504 -1.147572)
			(size 0.4318 0.4318)
			(layers "F.Cu" "F.Mask" "F.Paste")
			(net "PVCCIN_CPU0")
		)
		(pad "BN82" smd circle
			(at 33.816544 -1.147572)
			(size 0.4318 0.4318)
			(layers "F.Cu" "F.Mask" "F.Paste")
			(net "PVCCIN_CPU0")
		)
		(pad "BN84" smd custom
			(at 35.533584 -1.147572 270)
			(size 0.10795 0.10795)
			(layers "F.Cu" "F.Mask" "F.Paste")
			(net "PVCCIN_CPU0")
			(options
				(clearance outline)
				(anchor circle)
			)
			(primitives
				(gr_poly
					(pts
						(arc
							(start 0.2159 -0.0381)
							(mid 0 -0.254)
							(end -0.2159 -0.0381)
						)
						(arc
							(start -0.2159 0.0381)
							(mid 0 0.254)
							(end 0.2159 0.0381)
						)
					)
					(width 0)
					(fill yes)
				)
			)
		)
		(pad "BP3" smd custom
			(at -35.533584 1.147572 90)
			(size 0.10795 0.10795)
			(layers "F.Cu" "F.Mask" "F.Paste")
			(net "GND")
			(options
				(clearance outline)
				(anchor circle)
			)
			(primitives
				(gr_poly
					(pts
						(arc
							(start 0.2159 -0.0381)
							(mid 0 -0.254)
							(end -0.2159 -0.0381)
						)
						(arc
							(start -0.2159 0.0381)
							(mid 0 0.254)
							(end 0.2159 0.0381)
						)
					)
					(width 0)
					(fill yes)
				)
			)
		)
		(pad "BP5" smd circle
			(at -33.816544 1.147572)
			(size 0.4318 0.4318)
			(layers "F.Cu" "F.Mask" "F.Paste")
			(net "P3E_CPU0_PE2_SS_TXN<13>")
		)
		(pad "BP7" smd circle
			(at -32.099504 1.147572)
			(size 0.4318 0.4318)
			(layers "F.Cu" "F.Mask" "F.Paste")
			(net "P3E_CPU0_PE2_SS_RXP<11>")
		)
		(pad "BP9" smd circle
			(at -30.382464 1.147572)
			(size 0.4318 0.4318)
			(layers "F.Cu" "F.Mask" "F.Paste")
			(net "P3E_CPU0_PE2_SS_RXP<12>")
		)
		(pad "BP11" smd circle
			(at -28.665424 1.147572)
			(size 0.4318 0.4318)
			(layers "F.Cu" "F.Mask" "F.Paste")
			(net "PVCCIOMCP_CPU0")
		)
		(pad "BP13" smd circle
			(at -26.948384 1.147572)
			(size 0.4318 0.4318)
			(layers "F.Cu" "F.Mask" "F.Paste")
			(net "PVCCIOMCP_CPU0")
		)
		(pad "BP15" smd circle
			(at -25.231598 1.147572)
			(size 0.4318 0.4318)
			(layers "F.Cu" "F.Mask" "F.Paste")
			(net "PVCCIOMCP_CPU0")
		)
		(pad "BP17" smd circle
			(at -23.514558 1.147572)
			(size 0.4318 0.4318)
			(layers "F.Cu" "F.Mask" "F.Paste")
			(net "PVCCIOMCP_CPU0")
		)
		(pad "BP19" smd circle
			(at -21.797518 1.147572)
			(size 0.4318 0.4318)
			(layers "F.Cu" "F.Mask" "F.Paste")
			(net "IRQ_HFI0_CPU0_LVT2_N")
		)
		(pad "BP21" smd circle
			(at -20.080478 1.147572)
			(size 0.4318 0.4318)
			(layers "F.Cu" "F.Mask" "F.Paste")
			(net "PVCCMCP_CPU0")
		)
		(pad "BP23" smd circle
			(at -18.363438 1.147572)
			(size 0.4318 0.4318)
			(layers "F.Cu" "F.Mask" "F.Paste")
			(net "SMB_HFI0_CPU0_LVC2_SDA")
		)
		(pad "BP25" smd circle
			(at -16.646398 1.147572)
			(size 0.4318 0.4318)
			(layers "F.Cu" "F.Mask" "F.Paste")
			(net "PVCCIO_CPU0")
		)
		(pad "BP27" smd circle
			(at -14.929612 1.147572)
			(size 0.4318 0.4318)
			(layers "F.Cu" "F.Mask" "F.Paste")
			(net "GND")
		)
		(pad "BP61" smd circle
			(at 15.787878 -0.652526)
			(size 0.4318 0.4318)
			(layers "F.Cu" "F.Mask" "F.Paste")
			(net "PVCCIN_CPU0")
		)
		(pad "BP63" smd circle
			(at 17.504918 -0.652526)
			(size 0.4318 0.4318)
			(layers "F.Cu" "F.Mask" "F.Paste")
			(net "PVCCIN_CPU0")
		)
		(pad "BP65" smd circle
			(at 19.221958 -0.652526)
			(size 0.4318 0.4318)
			(layers "F.Cu" "F.Mask" "F.Paste")
			(net "PVCCIN_CPU0")
		)
		(pad "BP67" smd circle
			(at 20.938998 -0.652526)
			(size 0.4318 0.4318)
			(layers "F.Cu" "F.Mask" "F.Paste")
			(net "PVCCIN_CPU0")
		)
		(pad "BP69" smd circle
			(at 22.656038 -0.652526)
			(size 0.4318 0.4318)
			(layers "F.Cu" "F.Mask" "F.Paste")
			(net "PVCCIN_CPU0")
		)
		(pad "BP71" smd circle
			(at 24.373078 -0.652526)
			(size 0.4318 0.4318)
			(layers "F.Cu" "F.Mask" "F.Paste")
			(net "PVCCIN_CPU0")
		)
		(pad "BP73" smd circle
			(at 26.090118 -0.652526)
			(size 0.4318 0.4318)
			(layers "F.Cu" "F.Mask" "F.Paste")
			(net "PVCCIN_CPU0")
		)
		(pad "BP75" smd circle
			(at 27.806904 -0.652526)
			(size 0.4318 0.4318)
			(layers "F.Cu" "F.Mask" "F.Paste")
			(net "PVCCIN_CPU0")
		)
		(pad "BP77" smd circle
			(at 29.523944 -0.652526)
			(size 0.4318 0.4318)
			(layers "F.Cu" "F.Mask" "F.Paste")
			(net "PVCCIN_CPU0")
		)
		(pad "BP79" smd circle
			(at 31.240984 -0.652526)
			(size 0.4318 0.4318)
			(layers "F.Cu" "F.Mask" "F.Paste")
			(net "PVCCIN_CPU0")
		)
		(pad "BP81" smd circle
			(at 32.958024 -0.652526)
			(size 0.4318 0.4318)
			(layers "F.Cu" "F.Mask" "F.Paste")
			(net "PVCCIN_CPU0")
		)
		(pad "BP83" smd circle
			(at 34.675064 -0.652526)
			(size 0.4318 0.4318)
			(layers "F.Cu" "F.Mask" "F.Paste")
			(net "PVCCIN_CPU0")
		)
		(pad "BR4" smd circle
			(at -34.675064 1.643126)
			(size 0.4318 0.4318)
			(layers "F.Cu" "F.Mask" "F.Paste")
			(net "P3E_CPU0_PE2_SS_TXP<12>")
		)
		(pad "BR6" smd circle
			(at -32.958024 1.643126)
			(size 0.4318 0.4318)
			(layers "F.Cu" "F.Mask" "F.Paste")
			(net "GND")
		)
		(pad "BR8" smd circle
			(at -31.240984 1.643126)
			(size 0.4318 0.4318)
			(layers "F.Cu" "F.Mask" "F.Paste")
			(net "P3E_CPU0_PE2_SS_RXN<12>")
		)
		(pad "BR10" smd circle
			(at -29.523944 1.643126)
			(size 0.4318 0.4318)
			(layers "F.Cu" "F.Mask" "F.Paste")
			(net "GND")
		)
		(pad "BR12" smd circle
			(at -27.806904 1.643126)
			(size 0.4318 0.4318)
			(layers "F.Cu" "F.Mask" "F.Paste")
			(net "PVCCIOMCP_CPU0")
		)
		(pad "BR14" smd circle
			(at -26.090118 1.643126)
			(size 0.4318 0.4318)
			(layers "F.Cu" "F.Mask" "F.Paste")
			(net "PVCCIOMCP_CPU0")
		)
		(pad "BR16" smd circle
			(at -24.373078 1.643126)
			(size 0.4318 0.4318)
			(layers "F.Cu" "F.Mask" "F.Paste")
			(net "GND")
		)
		(pad "BR18" smd circle
			(at -22.656038 1.643126)
			(size 0.4318 0.4318)
			(layers "F.Cu" "F.Mask" "F.Paste")
			(net "GND")
		)
		(pad "BR20" smd circle
			(at -20.938998 1.643126)
			(size 0.4318 0.4318)
			(layers "F.Cu" "F.Mask" "F.Paste")
			(net "FM_MODPRST_HFI0_CPU0_LVT2_N")
		)
		(pad "BR22" smd circle
			(at -19.221958 1.643126)
			(size 0.4318 0.4318)
			(layers "F.Cu" "F.Mask" "F.Paste")
			(net "PVCCMCP_CPU0")
		)
		(pad "BR24" smd circle
			(at -17.504918 1.643126)
			(size 0.4318 0.4318)
			(layers "F.Cu" "F.Mask" "F.Paste")
			(net "PVCCMCP_CPU0")
		)
		(pad "BR26" smd circle
			(at -15.787878 1.643126)
			(size 0.4318 0.4318)
			(layers "F.Cu" "F.Mask" "F.Paste")
			(net "GND")
		)
		(pad "BR60" smd circle
			(at 14.929612 -0.156972)
			(size 0.508 0.508)
			(layers "F.Cu" "F.Mask" "F.Paste")
			(net "PVCCIN_CPU0")
		)
		(pad "BR62" smd circle
			(at 16.646398 -0.156972)
			(size 0.4318 0.4318)
			(layers "F.Cu" "F.Mask" "F.Paste")
			(net "PVCCIN_CPU0")
		)
		(pad "BR64" smd circle
			(at 18.363438 -0.156972)
			(size 0.4318 0.4318)
			(layers "F.Cu" "F.Mask" "F.Paste")
			(net "GND")
		)
		(pad "BR66" smd circle
			(at 20.080478 -0.156972)
			(size 0.4318 0.4318)
			(layers "F.Cu" "F.Mask" "F.Paste")
			(net "GND")
		)
		(pad "BR68" smd circle
			(at 21.797518 -0.156972)
			(size 0.4318 0.4318)
			(layers "F.Cu" "F.Mask" "F.Paste")
			(net "GND")
		)
		(pad "BR70" smd circle
			(at 23.514558 -0.156972)
			(size 0.4318 0.4318)
			(layers "F.Cu" "F.Mask" "F.Paste")
			(net "GND")
		)
		(pad "BR72" smd circle
			(at 25.231598 -0.156972)
			(size 0.4318 0.4318)
			(layers "F.Cu" "F.Mask" "F.Paste")
			(net "GND")
		)
		(pad "BR74" smd circle
			(at 26.948384 -0.156972)
			(size 0.4318 0.4318)
			(layers "F.Cu" "F.Mask" "F.Paste")
			(net "GND")
		)
		(pad "BR76" smd circle
			(at 28.665424 -0.156972)
			(size 0.4318 0.4318)
			(layers "F.Cu" "F.Mask" "F.Paste")
			(net "GND")
		)
		(pad "BR78" smd circle
			(at 30.382464 -0.156972)
			(size 0.4318 0.4318)
			(layers "F.Cu" "F.Mask" "F.Paste")
			(net "GND")
		)
		(pad "BR80" smd circle
			(at 32.099504 -0.156972)
			(size 0.4318 0.4318)
			(layers "F.Cu" "F.Mask" "F.Paste")
			(net "GND")
		)
		(pad "BR82" smd circle
			(at 33.816544 -0.156972)
			(size 0.4318 0.4318)
			(layers "F.Cu" "F.Mask" "F.Paste")
			(net "GND")
		)
		(pad "BR84" smd custom
			(at 35.533584 -0.156972 270)
			(size 0.10795 0.10795)
			(layers "F.Cu" "F.Mask" "F.Paste")
			(net "PVCCIN_CPU0")
			(options
				(clearance outline)
				(anchor circle)
			)
			(primitives
				(gr_poly
					(pts
						(arc
							(start 0.2159 -0.0381)
							(mid 0 -0.254)
							(end -0.2159 -0.0381)
						)
						(arc
							(start -0.2159 0.0381)
							(mid 0 0.254)
							(end 0.2159 0.0381)
						)
					)
					(width 0)
					(fill yes)
				)
			)
		)
		(pad "BT3" smd custom
			(at -35.533584 2.138426 90)
			(size 0.10795 0.10795)
			(layers "F.Cu" "F.Mask" "F.Paste")
			(net "GND")
			(options
				(clearance outline)
				(anchor circle)
			)
			(primitives
				(gr_poly
					(pts
						(arc
							(start 0.2159 -0.0381)
							(mid 0 -0.254)
							(end -0.2159 -0.0381)
						)
						(arc
							(start -0.2159 0.0381)
							(mid 0 0.254)
							(end 0.2159 0.0381)
						)
					)
					(width 0)
					(fill yes)
				)
			)
		)
		(pad "BT5" smd circle
			(at -33.816544 2.138426)
			(size 0.4318 0.4318)
			(layers "F.Cu" "F.Mask" "F.Paste")
			(net "GND")
		)
		(pad "BT7" smd circle
			(at -32.099504 2.138426)
			(size 0.4318 0.4318)
			(layers "F.Cu" "F.Mask" "F.Paste")
			(net "P3E_CPU0_PE2_SS_RXN<11>")
		)
		(pad "BT9" smd circle
			(at -30.382464 2.138426)
			(size 0.4318 0.4318)
			(layers "F.Cu" "F.Mask" "F.Paste")
			(net "GND")
		)
		(pad "BT11" smd circle
			(at -28.665424 2.138426)
			(size 0.4318 0.4318)
			(layers "F.Cu" "F.Mask" "F.Paste")
			(net "PVCCIOMCP_CPU0")
		)
		(pad "BT13" smd circle
			(at -26.948384 2.138426)
			(size 0.4318 0.4318)
			(layers "F.Cu" "F.Mask" "F.Paste")
			(net "PVCCIOMCP_CPU0")
		)
		(pad "BT15" smd circle
			(at -25.231598 2.138426)
			(size 0.4318 0.4318)
			(layers "F.Cu" "F.Mask" "F.Paste")
			(net "PVCCIOMCP_CPU0")
		)
		(pad "BT17" smd circle
			(at -23.514558 2.138426)
			(size 0.4318 0.4318)
			(layers "F.Cu" "F.Mask" "F.Paste")
			(net "VSENSE_PVCCIOMCP_CPU0_SKT_VSEN")
		)
		(pad "BT19" smd circle
			(at -21.797518 2.138426)
			(size 0.4318 0.4318)
			(layers "F.Cu" "F.Mask" "F.Paste")
			(net "FM_MODPRST_HFI1_CPU0_LVT2_N")
		)
		(pad "BT21" smd circle
			(at -20.080478 2.138426)
			(size 0.4318 0.4318)
			(layers "F.Cu" "F.Mask" "F.Paste")
			(net "GND")
		)
		(pad "BT23" smd circle
			(at -18.363438 2.138426)
			(size 0.4318 0.4318)
			(layers "F.Cu" "F.Mask" "F.Paste")
			(net "GND")
		)
		(pad "BT25" smd circle
			(at -16.646398 2.138426)
			(size 0.4318 0.4318)
			(layers "F.Cu" "F.Mask" "F.Paste")
			(net "GND")
		)
		(pad "BT27" smd circle
			(at -14.929612 2.138426)
			(size 0.4318 0.4318)
			(layers "F.Cu" "F.Mask" "F.Paste")
			(net "P1V8_MCP_CPU0")
		)
		(pad "BT61" smd circle
			(at 15.787878 0.338074)
			(size 0.4318 0.4318)
			(layers "F.Cu" "F.Mask" "F.Paste")
			(net "PVCCIN_CPU0")
		)
		(pad "BT63" smd circle
			(at 17.504918 0.338074)
			(size 0.4318 0.4318)
			(layers "F.Cu" "F.Mask" "F.Paste")
			(net "PVCCIN_CPU0")
		)
		(pad "BT65" smd circle
			(at 19.221958 0.338074)
			(size 0.4318 0.4318)
			(layers "F.Cu" "F.Mask" "F.Paste")
			(net "PVCCIN_CPU0")
		)
		(pad "BT67" smd circle
			(at 20.938998 0.338074)
			(size 0.4318 0.4318)
			(layers "F.Cu" "F.Mask" "F.Paste")
			(net "PVCCIN_CPU0")
		)
		(pad "BT69" smd circle
			(at 22.656038 0.338074)
			(size 0.4318 0.4318)
			(layers "F.Cu" "F.Mask" "F.Paste")
			(net "PVCCIN_CPU0")
		)
		(pad "BT71" smd circle
			(at 24.373078 0.338074)
			(size 0.4318 0.4318)
			(layers "F.Cu" "F.Mask" "F.Paste")
			(net "PVCCIN_CPU0")
		)
		(pad "BT73" smd circle
			(at 26.090118 0.338074)
			(size 0.4318 0.4318)
			(layers "F.Cu" "F.Mask" "F.Paste")
			(net "PVCCIN_CPU0")
		)
		(pad "BT75" smd circle
			(at 27.806904 0.338074)
			(size 0.4318 0.4318)
			(layers "F.Cu" "F.Mask" "F.Paste")
			(net "PVCCIN_CPU0")
		)
		(pad "BT77" smd circle
			(at 29.523944 0.338074)
			(size 0.4318 0.4318)
			(layers "F.Cu" "F.Mask" "F.Paste")
			(net "PVCCIN_CPU0")
		)
		(pad "BT79" smd circle
			(at 31.240984 0.338074)
			(size 0.4318 0.4318)
			(layers "F.Cu" "F.Mask" "F.Paste")
			(net "PVCCIN_CPU0")
		)
		(pad "BT81" smd circle
			(at 32.958024 0.338074)
			(size 0.4318 0.4318)
			(layers "F.Cu" "F.Mask" "F.Paste")
			(net "PVCCIN_CPU0")
		)
		(pad "BT83" smd circle
			(at 34.675064 0.338074)
			(size 0.4318 0.4318)
			(layers "F.Cu" "F.Mask" "F.Paste")
			(net "PVCCIN_CPU0")
		)
		(pad "BU4" smd circle
			(at -34.675064 2.633726)
			(size 0.4318 0.4318)
			(layers "F.Cu" "F.Mask" "F.Paste")
			(net "P3E_CPU0_PE2_SS_TXN<12>")
		)
		(pad "BU6" smd circle
			(at -32.958024 2.633726)
			(size 0.4318 0.4318)
			(layers "F.Cu" "F.Mask" "F.Paste")
			(net "P3E_CPU0_PE2_SS_RXP<10>")
		)
		(pad "BU8" smd circle
			(at -31.240984 2.633726)
			(size 0.4318 0.4318)
			(layers "F.Cu" "F.Mask" "F.Paste")
			(net "GND")
		)
		(pad "BU10" smd circle
			(at -29.523944 2.633726)
			(size 0.4318 0.4318)
			(layers "F.Cu" "F.Mask" "F.Paste")
			(net "GND")
		)
		(pad "BU12" smd circle
			(at -27.806904 2.633726)
			(size 0.4318 0.4318)
			(layers "F.Cu" "F.Mask" "F.Paste")
			(net "PVCCIOMCP_CPU0")
		)
		(pad "BU14" smd circle
			(at -26.090118 2.633726)
			(size 0.4318 0.4318)
			(layers "F.Cu" "F.Mask" "F.Paste")
			(net "PVCCIOMCP_CPU0")
		)
		(pad "BU16" smd circle
			(at -24.373078 2.633726)
			(size 0.4318 0.4318)
			(layers "F.Cu" "F.Mask" "F.Paste")
			(net "VSENSE_PVCCIOMCP_CPU0_SKT_VRTN")
		)
		(pad "BU18" smd circle
			(at -22.656038 2.633726)
			(size 0.4318 0.4318)
			(layers "F.Cu" "F.Mask" "F.Paste")
			(net "PVCCIOMCP_CPU0")
		)
		(pad "BU20" smd circle
			(at -20.938998 2.633726)
			(size 0.4318 0.4318)
			(layers "F.Cu" "F.Mask" "F.Paste")
			(net "PVCCMCP_CPU0")
		)
		(pad "BU22" smd circle
			(at -19.221958 2.633726)
			(size 0.4318 0.4318)
			(layers "F.Cu" "F.Mask" "F.Paste")
			(net "PVCCMCP_CPU0")
		)
		(pad "BU24" smd circle
			(at -17.504918 2.633726)
			(size 0.4318 0.4318)
			(layers "F.Cu" "F.Mask" "F.Paste")
			(net "CLK_100M_CPU0_PE_REFCLK_DN")
		)
		(pad "BU26" smd circle
			(at -15.787878 2.633726)
			(size 0.4318 0.4318)
			(layers "F.Cu" "F.Mask" "F.Paste")
			(net "P1V8_MCP_CPU0")
		)
		(pad "BU60" smd circle
			(at 14.929612 0.833628)
			(size 0.508 0.508)
			(layers "F.Cu" "F.Mask" "F.Paste")
			(net "PVCCIN_CPU0")
		)
		(pad "BU62" smd circle
			(at 16.646398 0.833628)
			(size 0.4318 0.4318)
			(layers "F.Cu" "F.Mask" "F.Paste")
			(net "PVCCIN_CPU0")
		)
		(pad "BU64" smd circle
			(at 18.363438 0.833628)
			(size 0.4318 0.4318)
			(layers "F.Cu" "F.Mask" "F.Paste")
			(net "PVCCIN_CPU0")
		)
		(pad "BU66" smd circle
			(at 20.080478 0.833628)
			(size 0.4318 0.4318)
			(layers "F.Cu" "F.Mask" "F.Paste")
			(net "PVCCIN_CPU0")
		)
		(pad "BU68" smd circle
			(at 21.797518 0.833628)
			(size 0.4318 0.4318)
			(layers "F.Cu" "F.Mask" "F.Paste")
			(net "PVCCIN_CPU0")
		)
		(pad "BU70" smd circle
			(at 23.514558 0.833628)
			(size 0.4318 0.4318)
			(layers "F.Cu" "F.Mask" "F.Paste")
			(net "PVCCIN_CPU0")
		)
		(pad "BU72" smd circle
			(at 25.231598 0.833628)
			(size 0.4318 0.4318)
			(layers "F.Cu" "F.Mask" "F.Paste")
			(net "PVCCIN_CPU0")
		)
		(pad "BU74" smd circle
			(at 26.948384 0.833628)
			(size 0.4318 0.4318)
			(layers "F.Cu" "F.Mask" "F.Paste")
			(net "PVCCIN_CPU0")
		)
		(pad "BU76" smd circle
			(at 28.665424 0.833628)
			(size 0.4318 0.4318)
			(layers "F.Cu" "F.Mask" "F.Paste")
			(net "PVCCIN_CPU0")
		)
		(pad "BU78" smd circle
			(at 30.382464 0.833628)
			(size 0.4318 0.4318)
			(layers "F.Cu" "F.Mask" "F.Paste")
			(net "PVCCIN_CPU0")
		)
		(pad "BU80" smd circle
			(at 32.099504 0.833628)
			(size 0.4318 0.4318)
			(layers "F.Cu" "F.Mask" "F.Paste")
			(net "PVCCIN_CPU0")
		)
		(pad "BU82" smd circle
			(at 33.816544 0.833628)
			(size 0.4318 0.4318)
			(layers "F.Cu" "F.Mask" "F.Paste")
			(net "PVCCIN_CPU0")
		)
		(pad "BU84" smd custom
			(at 35.533584 0.833628 270)
			(size 0.10795 0.10795)
			(layers "F.Cu" "F.Mask" "F.Paste")
			(net "PVCCIN_CPU0")
			(options
				(clearance outline)
				(anchor circle)
			)
			(primitives
				(gr_poly
					(pts
						(arc
							(start 0.2159 -0.0381)
							(mid 0 -0.254)
							(end -0.2159 -0.0381)
						)
						(arc
							(start -0.2159 0.0381)
							(mid 0 0.254)
							(end 0.2159 0.0381)
						)
					)
					(width 0)
					(fill yes)
				)
			)
		)
		(pad "BV3" smd custom
			(at -35.533584 3.128772 90)
			(size 0.10795 0.10795)
			(layers "F.Cu" "F.Mask" "F.Paste")
			(net "P3E_CPU0_PE2_SS_TXP<11>")
			(options
				(clearance outline)
				(anchor circle)
			)
			(primitives
				(gr_poly
					(pts
						(arc
							(start 0.2159 -0.0381)
							(mid 0 -0.254)
							(end -0.2159 -0.0381)
						)
						(arc
							(start -0.2159 0.0381)
							(mid 0 0.254)
							(end 0.2159 0.0381)
						)
					)
					(width 0)
					(fill yes)
				)
			)
		)
		(pad "BV5" smd circle
			(at -33.816544 3.128772)
			(size 0.4318 0.4318)
			(layers "F.Cu" "F.Mask" "F.Paste")
			(net "GND")
		)
		(pad "BV7" smd circle
			(at -32.099504 3.128772)
			(size 0.4318 0.4318)
			(layers "F.Cu" "F.Mask" "F.Paste")
			(net "P3E_CPU0_PE2_SS_RXN<10>")
		)
		(pad "BV9" smd circle
			(at -30.382464 3.128772)
			(size 0.4318 0.4318)
			(layers "F.Cu" "F.Mask" "F.Paste")
			(net "P3E_CPU0_PE2_SS_RXP<8>")
		)
		(pad "BV11" smd circle
			(at -28.665424 3.128772)
			(size 0.4318 0.4318)
			(layers "F.Cu" "F.Mask" "F.Paste")
			(net "PVCCIOMCP_CPU0")
		)
		(pad "BV13" smd circle
			(at -26.948384 3.128772)
			(size 0.4318 0.4318)
			(layers "F.Cu" "F.Mask" "F.Paste")
			(net "PVCCIOMCP_CPU0")
		)
		(pad "BV15" smd circle
			(at -25.231598 3.128772)
			(size 0.4318 0.4318)
			(layers "F.Cu" "F.Mask" "F.Paste")
			(net "PVCCIOMCP_CPU0")
		)
		(pad "BV17" smd circle
			(at -23.514558 3.128772)
			(size 0.4318 0.4318)
			(layers "F.Cu" "F.Mask" "F.Paste")
			(net "GND")
		)
		(pad "BV19" smd circle
			(at -21.797518 3.128772)
			(size 0.4318 0.4318)
			(layers "F.Cu" "F.Mask" "F.Paste")
			(net "PVCCMCP_CPU0")
		)
		(pad "BV21" smd circle
			(at -20.080478 3.128772)
			(size 0.4318 0.4318)
			(layers "F.Cu" "F.Mask" "F.Paste")
			(net "PVCCMCP_CPU0")
		)
		(pad "BV23" smd circle
			(at -18.363438 3.128772)
			(size 0.4318 0.4318)
			(layers "F.Cu" "F.Mask" "F.Paste")
			(net "TP_CPU0_RSVD_124")
		)
		(pad "BV25" smd circle
			(at -16.646398 3.128772)
			(size 0.4318 0.4318)
			(layers "F.Cu" "F.Mask" "F.Paste")
			(net "GND")
		)
		(pad "BV27" smd circle
			(at -14.929612 3.128772)
			(size 0.4318 0.4318)
			(layers "F.Cu" "F.Mask" "F.Paste")
			(net "P1V8_MCP_CPU0")
		)
		(pad "BV61" smd circle
			(at 15.787878 1.328674)
			(size 0.4318 0.4318)
			(layers "F.Cu" "F.Mask" "F.Paste")
			(net "PVCCIN_CPU0")
		)
		(pad "BV63" smd circle
			(at 17.504918 1.328674)
			(size 0.4318 0.4318)
			(layers "F.Cu" "F.Mask" "F.Paste")
			(net "PVCCIN_CPU0")
		)
		(pad "BV65" smd circle
			(at 19.221958 1.328674)
			(size 0.4318 0.4318)
			(layers "F.Cu" "F.Mask" "F.Paste")
			(net "PVCCIN_CPU0")
		)
		(pad "BV67" smd circle
			(at 20.938998 1.328674)
			(size 0.4318 0.4318)
			(layers "F.Cu" "F.Mask" "F.Paste")
			(net "PVCCIN_CPU0")
		)
		(pad "BV69" smd circle
			(at 22.656038 1.328674)
			(size 0.4318 0.4318)
			(layers "F.Cu" "F.Mask" "F.Paste")
			(net "PVCCIN_CPU0")
		)
		(pad "BV71" smd circle
			(at 24.373078 1.328674)
			(size 0.4318 0.4318)
			(layers "F.Cu" "F.Mask" "F.Paste")
			(net "PVCCIN_CPU0")
		)
		(pad "BV73" smd circle
			(at 26.090118 1.328674)
			(size 0.4318 0.4318)
			(layers "F.Cu" "F.Mask" "F.Paste")
			(net "PVCCIN_CPU0")
		)
		(pad "BV75" smd circle
			(at 27.806904 1.328674)
			(size 0.4318 0.4318)
			(layers "F.Cu" "F.Mask" "F.Paste")
			(net "PVCCIN_CPU0")
		)
		(pad "BV77" smd circle
			(at 29.523944 1.328674)
			(size 0.4318 0.4318)
			(layers "F.Cu" "F.Mask" "F.Paste")
			(net "PVCCIN_CPU0")
		)
		(pad "BV79" smd circle
			(at 31.240984 1.328674)
			(size 0.4318 0.4318)
			(layers "F.Cu" "F.Mask" "F.Paste")
			(net "PVCCIN_CPU0")
		)
		(pad "BV81" smd circle
			(at 32.958024 1.328674)
			(size 0.4318 0.4318)
			(layers "F.Cu" "F.Mask" "F.Paste")
			(net "PVCCIN_CPU0")
		)
		(pad "BV83" smd circle
			(at 34.675064 1.328674)
			(size 0.4318 0.4318)
			(layers "F.Cu" "F.Mask" "F.Paste")
			(net "PVCCIN_CPU0")
		)
		(pad "BW4" smd circle
			(at -34.675064 3.624326)
			(size 0.4318 0.4318)
			(layers "F.Cu" "F.Mask" "F.Paste")
			(net "P3E_CPU0_PE2_SS_TXN<11>")
		)
		(pad "BW6" smd circle
			(at -32.958024 3.624326)
			(size 0.4318 0.4318)
			(layers "F.Cu" "F.Mask" "F.Paste")
			(net "GND")
		)
		(pad "BW8" smd circle
			(at -31.240984 3.624326)
			(size 0.4318 0.4318)
			(layers "F.Cu" "F.Mask" "F.Paste")
			(net "P3E_CPU0_PE2_SS_RXP<9>")
		)
		(pad "BW10" smd circle
			(at -29.523944 3.624326)
			(size 0.4318 0.4318)
			(layers "F.Cu" "F.Mask" "F.Paste")
			(net "TP_CPU0_RSVD_123")
		)
		(pad "BW12" smd circle
			(at -27.806904 3.624326)
			(size 0.4318 0.4318)
			(layers "F.Cu" "F.Mask" "F.Paste")
			(net "GND")
		)
		(pad "BW14" smd circle
			(at -26.090118 3.624326)
			(size 0.4318 0.4318)
			(layers "F.Cu" "F.Mask" "F.Paste")
			(net "GND")
		)
		(pad "BW16" smd circle
			(at -24.373078 3.624326)
			(size 0.4318 0.4318)
			(layers "F.Cu" "F.Mask" "F.Paste")
			(net "GND")
		)
		(pad "BW18" smd circle
			(at -22.656038 3.624326)
			(size 0.4318 0.4318)
			(layers "F.Cu" "F.Mask" "F.Paste")
			(net "GND")
		)
		(pad "BW20" smd circle
			(at -20.938998 3.624326)
			(size 0.4318 0.4318)
			(layers "F.Cu" "F.Mask" "F.Paste")
			(net "PVCCMCP_CPU0")
		)
		(pad "BW22" smd circle
			(at -19.221958 3.624326)
			(size 0.4318 0.4318)
			(layers "F.Cu" "F.Mask" "F.Paste")
			(net "TP_CPU0_RSVD_121")
		)
		(pad "BW24" smd circle
			(at -17.504918 3.624326)
			(size 0.4318 0.4318)
			(layers "F.Cu" "F.Mask" "F.Paste")
			(net "CLK_100M_CPU0_PE_REFCLK_DP")
		)
		(pad "BW26" smd circle
			(at -15.787878 3.624326)
			(size 0.4318 0.4318)
			(layers "F.Cu" "F.Mask" "F.Paste")
			(net "GND")
		)
		(pad "BW60" smd circle
			(at 14.929612 1.824228)
			(size 0.508 0.508)
			(layers "F.Cu" "F.Mask" "F.Paste")
			(net "PVCCIN_CPU0")
		)
		(pad "BW62" smd circle
			(at 16.646398 1.824228)
			(size 0.4318 0.4318)
			(layers "F.Cu" "F.Mask" "F.Paste")
			(net "PVCCIN_CPU0")
		)
		(pad "BW64" smd circle
			(at 18.363438 1.824228)
			(size 0.4318 0.4318)
			(layers "F.Cu" "F.Mask" "F.Paste")
			(net "PVCCIN_CPU0")
		)
		(pad "BW66" smd circle
			(at 20.080478 1.824228)
			(size 0.4318 0.4318)
			(layers "F.Cu" "F.Mask" "F.Paste")
			(net "PVCCIN_CPU0")
		)
		(pad "BW68" smd circle
			(at 21.797518 1.824228)
			(size 0.4318 0.4318)
			(layers "F.Cu" "F.Mask" "F.Paste")
			(net "PVCCIN_CPU0")
		)
		(pad "BW70" smd circle
			(at 23.514558 1.824228)
			(size 0.4318 0.4318)
			(layers "F.Cu" "F.Mask" "F.Paste")
			(net "PVCCIN_CPU0")
		)
		(pad "BW72" smd circle
			(at 25.231598 1.824228)
			(size 0.4318 0.4318)
			(layers "F.Cu" "F.Mask" "F.Paste")
			(net "GND")
		)
		(pad "BW74" smd circle
			(at 26.948384 1.824228)
			(size 0.4318 0.4318)
			(layers "F.Cu" "F.Mask" "F.Paste")
			(net "GND")
		)
		(pad "BW76" smd circle
			(at 28.665424 1.824228)
			(size 0.4318 0.4318)
			(layers "F.Cu" "F.Mask" "F.Paste")
			(net "GND")
		)
		(pad "BW78" smd circle
			(at 30.382464 1.824228)
			(size 0.4318 0.4318)
			(layers "F.Cu" "F.Mask" "F.Paste")
			(net "GND")
		)
		(pad "BW80" smd circle
			(at 32.099504 1.824228)
			(size 0.4318 0.4318)
			(layers "F.Cu" "F.Mask" "F.Paste")
			(net "GND")
		)
		(pad "BW82" smd circle
			(at 33.816544 1.824228)
			(size 0.4318 0.4318)
			(layers "F.Cu" "F.Mask" "F.Paste")
			(net "GND")
		)
		(pad "BW84" smd custom
			(at 35.533584 1.824228 270)
			(size 0.10795 0.10795)
			(layers "F.Cu" "F.Mask" "F.Paste")
			(net "PVCCIN_CPU0")
			(options
				(clearance outline)
				(anchor circle)
			)
			(primitives
				(gr_poly
					(pts
						(arc
							(start 0.2159 -0.0381)
							(mid 0 -0.254)
							(end -0.2159 -0.0381)
						)
						(arc
							(start -0.2159 0.0381)
							(mid 0 0.254)
							(end 0.2159 0.0381)
						)
					)
					(width 0)
					(fill yes)
				)
			)
		)
		(pad "BY3" smd custom
			(at -35.533584 4.119372 90)
			(size 0.10795 0.10795)
			(layers "F.Cu" "F.Mask" "F.Paste")
			(net "P3E_CPU0_PE2_SS_TXP<9>")
			(options
				(clearance outline)
				(anchor circle)
			)
			(primitives
				(gr_poly
					(pts
						(arc
							(start 0.2159 -0.0381)
							(mid 0 -0.254)
							(end -0.2159 -0.0381)
						)
						(arc
							(start -0.2159 0.0381)
							(mid 0 0.254)
							(end 0.2159 0.0381)
						)
					)
					(width 0)
					(fill yes)
				)
			)
		)
		(pad "BY5" smd circle
			(at -33.816544 4.119372)
			(size 0.4318 0.4318)
			(layers "F.Cu" "F.Mask" "F.Paste")
			(net "P3E_CPU0_PE2_SS_TXP<10>")
		)
		(pad "BY7" smd circle
			(at -32.099504 4.119372)
			(size 0.4318 0.4318)
			(layers "F.Cu" "F.Mask" "F.Paste")
			(net "P3E_CPU0_PE2_SS_RXN<9>")
		)
		(pad "BY9" smd circle
			(at -30.382464 4.119372)
			(size 0.4318 0.4318)
			(layers "F.Cu" "F.Mask" "F.Paste")
			(net "P3E_CPU0_PE2_SS_RXN<8>")
		)
		(pad "BY11" smd circle
			(at -28.665424 4.119372)
			(size 0.4318 0.4318)
			(layers "F.Cu" "F.Mask" "F.Paste")
			(net "GND")
		)
		(pad "BY13" smd circle
			(at -26.948384 4.119372)
			(size 0.4318 0.4318)
			(layers "F.Cu" "F.Mask" "F.Paste")
			(net "GND")
		)
		(pad "BY15" smd circle
			(at -25.231598 4.119372)
			(size 0.4318 0.4318)
			(layers "F.Cu" "F.Mask" "F.Paste")
			(net "GND")
		)
		(pad "BY17" smd circle
			(at -23.514558 4.119372)
			(size 0.4318 0.4318)
			(layers "F.Cu" "F.Mask" "F.Paste")
			(net "GND")
		)
		(pad "BY19" smd circle
			(at -21.797518 4.119372)
			(size 0.4318 0.4318)
			(layers "F.Cu" "F.Mask" "F.Paste")
			(net "PVCCMCP_CPU0")
		)
		(pad "BY21" smd circle
			(at -20.080478 4.119372)
			(size 0.4318 0.4318)
			(layers "F.Cu" "F.Mask" "F.Paste")
			(net "JTAG_MCP_CPU0_TDI")
		)
		(pad "BY23" smd circle
			(at -18.363438 4.119372)
			(size 0.4318 0.4318)
			(layers "F.Cu" "F.Mask" "F.Paste")
			(net "GND")
		)
		(pad "BY25" smd circle
			(at -16.646398 4.119372)
			(size 0.4318 0.4318)
			(layers "F.Cu" "F.Mask" "F.Paste")
			(net "TP_CPU0_RSVD_119")
		)
		(pad "BY27" smd circle
			(at -14.929612 4.119372)
			(size 0.4318 0.4318)
			(layers "F.Cu" "F.Mask" "F.Paste")
			(net "P1V8_MCP_CPU0")
		)
		(pad "BY61" smd circle
			(at 15.787878 2.319274)
			(size 0.4318 0.4318)
			(layers "F.Cu" "F.Mask" "F.Paste")
			(net "PVCCIN_CPU0")
		)
		(pad "BY63" smd circle
			(at 17.504918 2.319274)
			(size 0.4318 0.4318)
			(layers "F.Cu" "F.Mask" "F.Paste")
			(net "GND")
		)
		(pad "BY65" smd circle
			(at 19.221958 2.319274)
			(size 0.4318 0.4318)
			(layers "F.Cu" "F.Mask" "F.Paste")
			(net "GND")
		)
		(pad "BY67" smd circle
			(at 20.938998 2.319274)
			(size 0.4318 0.4318)
			(layers "F.Cu" "F.Mask" "F.Paste")
			(net "GND")
		)
		(pad "BY69" smd circle
			(at 22.656038 2.319274)
			(size 0.4318 0.4318)
			(layers "F.Cu" "F.Mask" "F.Paste")
			(net "GND")
		)
		(pad "BY71" smd circle
			(at 24.373078 2.319274)
			(size 0.4318 0.4318)
			(layers "F.Cu" "F.Mask" "F.Paste")
			(net "GND")
		)
		(pad "BY73" smd circle
			(at 26.090118 2.319274)
			(size 0.4318 0.4318)
			(layers "F.Cu" "F.Mask" "F.Paste")
			(net "PVCCIN_CPU0")
		)
		(pad "BY75" smd circle
			(at 27.806904 2.319274)
			(size 0.4318 0.4318)
			(layers "F.Cu" "F.Mask" "F.Paste")
			(net "PVCCIN_CPU0")
		)
		(pad "BY77" smd circle
			(at 29.523944 2.319274)
			(size 0.4318 0.4318)
			(layers "F.Cu" "F.Mask" "F.Paste")
			(net "PVCCIN_CPU0")
		)
		(pad "BY79" smd circle
			(at 31.240984 2.319274)
			(size 0.4318 0.4318)
			(layers "F.Cu" "F.Mask" "F.Paste")
			(net "PVCCIN_CPU0")
		)
		(pad "BY81" smd circle
			(at 32.958024 2.319274)
			(size 0.4318 0.4318)
			(layers "F.Cu" "F.Mask" "F.Paste")
			(net "PVCCIN_CPU0")
		)
		(pad "BY83" smd circle
			(at 34.675064 2.319274)
			(size 0.4318 0.4318)
			(layers "F.Cu" "F.Mask" "F.Paste")
			(net "PVCCIN_CPU0")
		)
		(pad "C4" smd custom
			(at -34.675064 -24.112474 45)
			(size 0.10795 0.10795)
			(layers "F.Cu" "F.Mask" "F.Paste")
			(net "GND")
			(options
				(clearance outline)
				(anchor circle)
			)
			(primitives
				(gr_poly
					(pts
						(arc
							(start 0.2159 -0.0381)
							(mid 0 -0.254)
							(end -0.2159 -0.0381)
						)
						(arc
							(start -0.2159 0.0381)
							(mid 0 0.254)
							(end 0.2159 0.0381)
						)
					)
					(width 0)
					(fill yes)
				)
			)
		)
		(pad "C6" smd custom
			(at -32.958024 -24.112474)
			(size 0.10795 0.10795)
			(layers "F.Cu" "F.Mask" "F.Paste")
			(net "TP_CPU0_RSVD_291")
			(options
				(clearance outline)
				(anchor circle)
			)
			(primitives
				(gr_poly
					(pts
						(arc
							(start 0.2159 -0.0381)
							(mid 0 -0.254)
							(end -0.2159 -0.0381)
						)
						(arc
							(start -0.2159 0.0381)
							(mid 0 0.254)
							(end 0.2159 0.0381)
						)
					)
					(width 0)
					(fill yes)
				)
			)
		)
		(pad "C8" smd circle
			(at -31.240984 -24.112474)
			(size 0.4318 0.4318)
			(layers "F.Cu" "F.Mask" "F.Paste")
			(net "GND")
		)
		(pad "C10" smd circle
			(at -29.523944 -24.112474)
			(size 0.4318 0.4318)
			(layers "F.Cu" "F.Mask" "F.Paste")
			(net "GND")
		)
		(pad "C12" smd circle
			(at -27.806904 -24.112474)
			(size 0.4318 0.4318)
			(layers "F.Cu" "F.Mask" "F.Paste")
			(net "GND")
		)
		(pad "C14" smd circle
			(at -26.090118 -24.112474)
			(size 0.4318 0.4318)
			(layers "F.Cu" "F.Mask" "F.Paste")
			(net "GND")
		)
		(pad "C16" smd circle
			(at -24.373078 -24.112474)
			(size 0.4318 0.4318)
			(layers "F.Cu" "F.Mask" "F.Paste")
			(net "GND")
		)
		(pad "C18" smd custom
			(at -22.656038 -24.112474)
			(size 0.10795 0.10795)
			(layers "F.Cu" "F.Mask" "F.Paste")
			(net "TP_CPU0_RSVD_290")
			(options
				(clearance outline)
				(anchor circle)
			)
			(primitives
				(gr_poly
					(pts
						(arc
							(start 0.2159 -0.0381)
							(mid 0 -0.254)
							(end -0.2159 -0.0381)
						)
						(arc
							(start -0.2159 0.0381)
							(mid 0 0.254)
							(end 0.2159 0.0381)
						)
					)
					(width 0)
					(fill yes)
				)
			)
		)
		(pad "C24" smd custom
			(at -17.504918 -24.112474)
			(size 0.10795 0.10795)
			(layers "F.Cu" "F.Mask" "F.Paste")
			(net "TP_CPU0_RSVD_289")
			(options
				(clearance outline)
				(anchor circle)
			)
			(primitives
				(gr_poly
					(pts
						(arc
							(start 0.2159 -0.0381)
							(mid 0 -0.254)
							(end -0.2159 -0.0381)
						)
						(arc
							(start -0.2159 0.0381)
							(mid 0 0.254)
							(end 0.2159 0.0381)
						)
					)
					(width 0)
					(fill yes)
				)
			)
		)
		(pad "C26" smd circle
			(at -15.787878 -24.112474)
			(size 0.4318 0.4318)
			(layers "F.Cu" "F.Mask" "F.Paste")
			(net "M_B_DQ<50>")
		)
		(pad "C28" smd circle
			(at -14.071092 -24.112474)
			(size 0.4318 0.4318)
			(layers "F.Cu" "F.Mask" "F.Paste")
			(net "M_B_DQS_DP<15>")
		)
		(pad "C30" smd circle
			(at -12.354052 -24.112474)
			(size 0.4318 0.4318)
			(layers "F.Cu" "F.Mask" "F.Paste")
			(net "M_B_DQ<48>")
		)
		(pad "C32" smd circle
			(at -10.637012 -24.112474)
			(size 0.4318 0.4318)
			(layers "F.Cu" "F.Mask" "F.Paste")
			(net "M_B_DQ<42>")
		)
		(pad "C34" smd circle
			(at -8.919972 -24.112474)
			(size 0.4318 0.4318)
			(layers "F.Cu" "F.Mask" "F.Paste")
			(net "M_B_DQS_DP<14>")
		)
		(pad "C36" smd circle
			(at -7.202932 -24.112474)
			(size 0.4318 0.4318)
			(layers "F.Cu" "F.Mask" "F.Paste")
			(net "M_B_DQ<40>")
		)
		(pad "C38" smd circle
			(at -5.485892 -24.112474)
			(size 0.4318 0.4318)
			(layers "F.Cu" "F.Mask" "F.Paste")
			(net "M_A_DQ<34>")
		)
		(pad "C40" smd circle
			(at -3.769106 -24.112474)
			(size 0.4318 0.4318)
			(layers "F.Cu" "F.Mask" "F.Paste")
			(net "M_A_DQS_DP<13>")
		)
		(pad "C42" smd circle
			(at -2.052066 -24.112474)
			(size 0.4318 0.4318)
			(layers "F.Cu" "F.Mask" "F.Paste")
			(net "M_A_DQ<32>")
		)
		(pad "C46" smd custom
			(at 2.910586 -25.912572 45)
			(size 0.10795 0.10795)
			(layers "F.Cu" "F.Mask" "F.Paste")
			(net "PVDDQ_ABC")
			(options
				(clearance outline)
				(anchor circle)
			)
			(primitives
				(gr_poly
					(pts
						(arc
							(start 0.2159 -0.0381)
							(mid 0 -0.254)
							(end -0.2159 -0.0381)
						)
						(arc
							(start -0.2159 0.0381)
							(mid 0 0.254)
							(end 0.2159 0.0381)
						)
					)
					(width 0)
					(fill yes)
				)
			)
		)
		(pad "C48" smd circle
			(at 4.627626 -25.912572)
			(size 0.4318 0.4318)
			(layers "F.Cu" "F.Mask" "F.Paste")
			(net "M_A_ODT<1>")
		)
		(pad "C50" smd circle
			(at 6.344412 -25.912572)
			(size 0.4318 0.4318)
			(layers "F.Cu" "F.Mask" "F.Paste")
			(net "M_A_ODT<0>")
		)
		(pad "C52" smd circle
			(at 8.061452 -25.912572)
			(size 0.4318 0.4318)
			(layers "F.Cu" "F.Mask" "F.Paste")
			(net "M_A_BA<0>")
		)
		(pad "C54" smd circle
			(at 9.778492 -25.912572)
			(size 0.4318 0.4318)
			(layers "F.Cu" "F.Mask" "F.Paste")
			(net "M_A_CLK_DN<1>")
		)
		(pad "C56" smd circle
			(at 11.495532 -25.912572)
			(size 0.4318 0.4318)
			(layers "F.Cu" "F.Mask" "F.Paste")
			(net "M_A_CLK_DN<3>")
		)
		(pad "C58" smd circle
			(at 13.212572 -25.912572)
			(size 0.4318 0.4318)
			(layers "F.Cu" "F.Mask" "F.Paste")
			(net "M_A_MA<3>")
		)
		(pad "C60" smd circle
			(at 14.929612 -25.912572)
			(size 0.4318 0.4318)
			(layers "F.Cu" "F.Mask" "F.Paste")
			(net "M_A_MA<8>")
		)
		(pad "C62" smd circle
			(at 16.646398 -25.912572)
			(size 0.4318 0.4318)
			(layers "F.Cu" "F.Mask" "F.Paste")
			(net "M_A_CKE<0>")
		)
		(pad "C64" smd custom
			(at 18.363438 -25.912572)
			(size 0.10795 0.10795)
			(layers "F.Cu" "F.Mask" "F.Paste")
			(net "M_A_CKE<1>")
			(options
				(clearance outline)
				(anchor circle)
			)
			(primitives
				(gr_poly
					(pts
						(arc
							(start 0.2159 -0.0381)
							(mid 0 -0.254)
							(end -0.2159 -0.0381)
						)
						(arc
							(start -0.2159 0.0381)
							(mid 0 0.254)
							(end 0.2159 0.0381)
						)
					)
					(width 0)
					(fill yes)
				)
			)
		)
		(pad "C72" smd circle
			(at 25.231598 -25.912572)
			(size 0.4318 0.4318)
			(layers "F.Cu" "F.Mask" "F.Paste")
			(net "M_B_DQ<30>")
		)
		(pad "C74" smd circle
			(at 26.948384 -25.912572)
			(size 0.4318 0.4318)
			(layers "F.Cu" "F.Mask" "F.Paste")
			(net "M_B_DQ<25>")
		)
		(pad "C76" smd circle
			(at 28.665424 -25.912572)
			(size 0.4318 0.4318)
			(layers "F.Cu" "F.Mask" "F.Paste")
			(net "GND")
		)
		(pad "C78" smd circle
			(at 30.382464 -25.912572)
			(size 0.4318 0.4318)
			(layers "F.Cu" "F.Mask" "F.Paste")
			(net "GND")
		)
		(pad "C80" smd custom
			(at 32.099504 -25.912572 315)
			(size 0.10795 0.10795)
			(layers "F.Cu" "F.Mask" "F.Paste")
			(net "GND")
			(options
				(clearance outline)
				(anchor circle)
			)
			(primitives
				(gr_poly
					(pts
						(arc
							(start 0.2159 -0.0381)
							(mid 0 -0.254)
							(end -0.2159 -0.0381)
						)
						(arc
							(start -0.2159 0.0381)
							(mid 0 0.254)
							(end 0.2159 0.0381)
						)
					)
					(width 0)
					(fill yes)
				)
			)
		)
		(pad "C82" smd custom
			(at 33.816544 -25.912572 315)
			(size 0.10795 0.10795)
			(layers "F.Cu" "F.Mask" "F.Paste")
			(net "TP_CPU0_RSVD_288")
			(options
				(clearance outline)
				(anchor circle)
			)
			(primitives
				(gr_poly
					(pts
						(arc
							(start 0.2159 -0.0381)
							(mid 0 -0.254)
							(end -0.2159 -0.0381)
						)
						(arc
							(start -0.2159 0.0381)
							(mid 0 0.254)
							(end 0.2159 0.0381)
						)
					)
					(width 0)
					(fill yes)
				)
			)
		)
		(pad "CA2" smd custom
			(at -36.392104 4.614926 90)
			(size 0.10795 0.10795)
			(layers "F.Cu" "F.Mask" "F.Paste")
			(net "GND")
			(options
				(clearance outline)
				(anchor circle)
			)
			(primitives
				(gr_poly
					(pts
						(arc
							(start 0.2159 -0.0381)
							(mid 0 -0.254)
							(end -0.2159 -0.0381)
						)
						(arc
							(start -0.2159 0.0381)
							(mid 0 0.254)
							(end 0.2159 0.0381)
						)
					)
					(width 0)
					(fill yes)
				)
			)
		)
		(pad "CA4" smd circle
			(at -34.675064 4.614926)
			(size 0.4318 0.4318)
			(layers "F.Cu" "F.Mask" "F.Paste")
			(net "P3E_CPU0_PE2_SS_TXN<10>")
		)
		(pad "CA6" smd circle
			(at -32.958024 4.614926)
			(size 0.4318 0.4318)
			(layers "F.Cu" "F.Mask" "F.Paste")
			(net "GND")
		)
		(pad "CA8" smd circle
			(at -31.240984 4.614926)
			(size 0.4318 0.4318)
			(layers "F.Cu" "F.Mask" "F.Paste")
			(net "GND")
		)
		(pad "CA10" smd circle
			(at -29.523944 4.614926)
			(size 0.4318 0.4318)
			(layers "F.Cu" "F.Mask" "F.Paste")
			(net "GND")
		)
		(pad "CA12" smd circle
			(at -27.806904 4.614926)
			(size 0.4318 0.4318)
			(layers "F.Cu" "F.Mask" "F.Paste")
			(net "TP_CPU0_UPI2_RSVD_DP21")
		)
		(pad "CA14" smd circle
			(at -26.090118 4.614926)
			(size 0.4318 0.4318)
			(layers "F.Cu" "F.Mask" "F.Paste")
			(net "GND")
		)
		(pad "CA16" smd circle
			(at -24.373078 4.614926)
			(size 0.4318 0.4318)
			(layers "F.Cu" "F.Mask" "F.Paste")
			(net "GND")
		)
		(pad "CA18" smd circle
			(at -22.656038 4.614926)
			(size 0.4318 0.4318)
			(layers "F.Cu" "F.Mask" "F.Paste")
			(net "GND")
		)
		(pad "CA20" smd circle
			(at -20.938998 4.614926)
			(size 0.4318 0.4318)
			(layers "F.Cu" "F.Mask" "F.Paste")
			(net "GND")
		)
		(pad "CA22" smd circle
			(at -19.221958 4.614926)
			(size 0.4318 0.4318)
			(layers "F.Cu" "F.Mask" "F.Paste")
			(net "PVCCMCP_CPU0")
		)
		(pad "CA24" smd circle
			(at -17.504918 4.614926)
			(size 0.4318 0.4318)
			(layers "F.Cu" "F.Mask" "F.Paste")
			(net "TP_CPU0_RSVD_117")
		)
		(pad "CA26" smd circle
			(at -15.787878 4.614926)
			(size 0.4318 0.4318)
			(layers "F.Cu" "F.Mask" "F.Paste")
			(net "GND")
		)
		(pad "CA60" smd circle
			(at 14.929612 2.814828)
			(size 0.508 0.508)
			(layers "F.Cu" "F.Mask" "F.Paste")
			(net "PVCCIN_CPU0")
		)
		(pad "CA62" smd circle
			(at 16.646398 2.814828)
			(size 0.4318 0.4318)
			(layers "F.Cu" "F.Mask" "F.Paste")
			(net "PVCCIN_CPU0")
		)
		(pad "CA64" smd circle
			(at 18.363438 2.814828)
			(size 0.4318 0.4318)
			(layers "F.Cu" "F.Mask" "F.Paste")
			(net "GND")
		)
		(pad "CA66" smd circle
			(at 20.080478 2.814828)
			(size 0.4318 0.4318)
			(layers "F.Cu" "F.Mask" "F.Paste")
			(net "GND")
		)
		(pad "CA68" smd circle
			(at 21.797518 2.814828)
			(size 0.4318 0.4318)
			(layers "F.Cu" "F.Mask" "F.Paste")
			(net "GND")
		)
		(pad "CA70" smd circle
			(at 23.514558 2.814828)
			(size 0.4318 0.4318)
			(layers "F.Cu" "F.Mask" "F.Paste")
			(net "GND")
		)
		(pad "CA72" smd circle
			(at 25.231598 2.814828)
			(size 0.4318 0.4318)
			(layers "F.Cu" "F.Mask" "F.Paste")
			(net "PVCCIN_CPU0")
		)
		(pad "CA74" smd circle
			(at 26.948384 2.814828)
			(size 0.4318 0.4318)
			(layers "F.Cu" "F.Mask" "F.Paste")
			(net "PVCCIN_CPU0")
		)
		(pad "CA76" smd circle
			(at 28.665424 2.814828)
			(size 0.4318 0.4318)
			(layers "F.Cu" "F.Mask" "F.Paste")
			(net "PVCCIN_CPU0")
		)
		(pad "CA78" smd circle
			(at 30.382464 2.814828)
			(size 0.4318 0.4318)
			(layers "F.Cu" "F.Mask" "F.Paste")
			(net "PVCCIN_CPU0")
		)
		(pad "CA80" smd circle
			(at 32.099504 2.814828)
			(size 0.4318 0.4318)
			(layers "F.Cu" "F.Mask" "F.Paste")
			(net "PVCCIN_CPU0")
		)
		(pad "CA82" smd circle
			(at 33.816544 2.814828)
			(size 0.4318 0.4318)
			(layers "F.Cu" "F.Mask" "F.Paste")
			(net "PVCCIN_CPU0")
		)
		(pad "CA84" smd custom
			(at 35.533584 2.814828 270)
			(size 0.10795 0.10795)
			(layers "F.Cu" "F.Mask" "F.Paste")
			(net "PVCCIN_CPU0")
			(options
				(clearance outline)
				(anchor circle)
			)
			(primitives
				(gr_poly
					(pts
						(arc
							(start 0.2159 -0.0381)
							(mid 0 -0.254)
							(end -0.2159 -0.0381)
						)
						(arc
							(start -0.2159 0.0381)
							(mid 0 0.254)
							(end 0.2159 0.0381)
						)
					)
					(width 0)
					(fill yes)
				)
			)
		)
		(pad "CB3" smd circle
			(at -35.533584 5.109972)
			(size 0.4318 0.4318)
			(layers "F.Cu" "F.Mask" "F.Paste")
			(net "P3E_CPU0_PE2_SS_TXN<9>")
		)
		(pad "CB5" smd circle
			(at -33.816544 5.109972)
			(size 0.4318 0.4318)
			(layers "F.Cu" "F.Mask" "F.Paste")
			(net "TP_CPU0_RSVD_113")
		)
		(pad "CB7" smd circle
			(at -32.099504 5.109972)
			(size 0.4318 0.4318)
			(layers "F.Cu" "F.Mask" "F.Paste")
			(net "GND")
		)
		(pad "CB9" smd circle
			(at -30.382464 5.109972)
			(size 0.4318 0.4318)
			(layers "F.Cu" "F.Mask" "F.Paste")
			(net "GND")
		)
		(pad "CB11" smd circle
			(at -28.665424 5.109972)
			(size 0.4318 0.4318)
			(layers "F.Cu" "F.Mask" "F.Paste")
			(net "TP_CPU0_UPI2_RSVD_DN20")
		)
		(pad "CB13" smd circle
			(at -26.948384 5.109972)
			(size 0.4318 0.4318)
			(layers "F.Cu" "F.Mask" "F.Paste")
			(net "PVCCIO_CPU0")
		)
		(pad "CB15" smd circle
			(at -25.231598 5.109972)
			(size 0.4318 0.4318)
			(layers "F.Cu" "F.Mask" "F.Paste")
			(net "GND")
		)
		(pad "CB17" smd circle
			(at -23.514558 5.109972)
			(size 0.4318 0.4318)
			(layers "F.Cu" "F.Mask" "F.Paste")
			(net "PVCCIO_CPU0")
		)
		(pad "CB19" smd circle
			(at -21.797518 5.109972)
			(size 0.4318 0.4318)
			(layers "F.Cu" "F.Mask" "F.Paste")
			(net "PVCCMCP_CPU0")
		)
		(pad "CB21" smd circle
			(at -20.080478 5.109972)
			(size 0.4318 0.4318)
			(layers "F.Cu" "F.Mask" "F.Paste")
			(net "PVCCMCP_CPU0")
		)
		(pad "CB23" smd circle
			(at -18.363438 5.109972)
			(size 0.4318 0.4318)
			(layers "F.Cu" "F.Mask" "F.Paste")
			(net "JTAG_MCP_TCK")
		)
		(pad "CB25" smd circle
			(at -16.646398 5.109972)
			(size 0.4318 0.4318)
			(layers "F.Cu" "F.Mask" "F.Paste")
			(net "TP_CPU0_RSVD_114")
		)
		(pad "CB27" smd circle
			(at -14.929612 5.109972)
			(size 0.4318 0.4318)
			(layers "F.Cu" "F.Mask" "F.Paste")
			(net "GND")
		)
		(pad "CB61" smd circle
			(at 15.787878 3.309874)
			(size 0.4318 0.4318)
			(layers "F.Cu" "F.Mask" "F.Paste")
			(net "PVCCIN_CPU0")
		)
		(pad "CB63" smd circle
			(at 17.504918 3.309874)
			(size 0.4318 0.4318)
			(layers "F.Cu" "F.Mask" "F.Paste")
			(net "GND")
		)
		(pad "CB65" smd circle
			(at 19.221958 3.309874)
			(size 0.4318 0.4318)
			(layers "F.Cu" "F.Mask" "F.Paste")
			(net "PVSA_CPU0")
		)
		(pad "CB67" smd circle
			(at 20.938998 3.309874)
			(size 0.4318 0.4318)
			(layers "F.Cu" "F.Mask" "F.Paste")
			(net "PVSA_CPU0")
		)
		(pad "CB69" smd circle
			(at 22.656038 3.309874)
			(size 0.4318 0.4318)
			(layers "F.Cu" "F.Mask" "F.Paste")
			(net "PVSA_CPU0")
		)
		(pad "CB71" smd circle
			(at 24.373078 3.309874)
			(size 0.4318 0.4318)
			(layers "F.Cu" "F.Mask" "F.Paste")
			(net "GND")
		)
		(pad "CB73" smd circle
			(at 26.090118 3.309874)
			(size 0.4318 0.4318)
			(layers "F.Cu" "F.Mask" "F.Paste")
			(net "PVCCIN_CPU0")
		)
		(pad "CB75" smd circle
			(at 27.806904 3.309874)
			(size 0.4318 0.4318)
			(layers "F.Cu" "F.Mask" "F.Paste")
			(net "PVCCIN_CPU0")
		)
		(pad "CB77" smd circle
			(at 29.523944 3.309874)
			(size 0.4318 0.4318)
			(layers "F.Cu" "F.Mask" "F.Paste")
			(net "PVCCIN_CPU0")
		)
		(pad "CB79" smd circle
			(at 31.240984 3.309874)
			(size 0.4318 0.4318)
			(layers "F.Cu" "F.Mask" "F.Paste")
			(net "PVCCIN_CPU0")
		)
		(pad "CB81" smd circle
			(at 32.958024 3.309874)
			(size 0.4318 0.4318)
			(layers "F.Cu" "F.Mask" "F.Paste")
			(net "PVCCIN_CPU0")
		)
		(pad "CB83" smd circle
			(at 34.675064 3.309874)
			(size 0.4318 0.4318)
			(layers "F.Cu" "F.Mask" "F.Paste")
			(net "PVCCIN_CPU0")
		)
		(pad "CC2" smd custom
			(at -36.392104 5.605272 90)
			(size 0.10795 0.10795)
			(layers "F.Cu" "F.Mask" "F.Paste")
			(net "P3E_CPU0_PE2_SS_TXN<8>")
			(options
				(clearance outline)
				(anchor circle)
			)
			(primitives
				(gr_poly
					(pts
						(arc
							(start 0.2159 -0.0381)
							(mid 0 -0.254)
							(end -0.2159 -0.0381)
						)
						(arc
							(start -0.2159 0.0381)
							(mid 0 0.254)
							(end 0.2159 0.0381)
						)
					)
					(width 0)
					(fill yes)
				)
			)
		)
		(pad "CC4" smd circle
			(at -34.675064 5.605272)
			(size 0.4318 0.4318)
			(layers "F.Cu" "F.Mask" "F.Paste")
			(net "GND")
		)
		(pad "CC6" smd circle
			(at -32.958024 5.605272)
			(size 0.4318 0.4318)
			(layers "F.Cu" "F.Mask" "F.Paste")
			(net "TP_CPU0_RSVD_111")
		)
		(pad "CC8" smd circle
			(at -31.240984 5.605272)
			(size 0.4318 0.4318)
			(layers "F.Cu" "F.Mask" "F.Paste")
			(net "P3E_CPU0_PE2_SS_RXP<7>")
		)
		(pad "CC10" smd circle
			(at -29.523944 5.605272)
			(size 0.4318 0.4318)
			(layers "F.Cu" "F.Mask" "F.Paste")
			(net "TP_CPU0_UPI2_RSVD_DM21")
		)
		(pad "CC12" smd circle
			(at -27.806904 5.605272)
			(size 0.4318 0.4318)
			(layers "F.Cu" "F.Mask" "F.Paste")
			(net "TP_CPU0_UPI2_RSVD_DT21")
		)
		(pad "CC14" smd circle
			(at -26.090118 5.605272)
			(size 0.4318 0.4318)
			(layers "F.Cu" "F.Mask" "F.Paste")
			(net "GND")
		)
		(pad "CC16" smd circle
			(at -24.373078 5.605272)
			(size 0.4318 0.4318)
			(layers "F.Cu" "F.Mask" "F.Paste")
			(net "GND")
		)
		(pad "CC18" smd circle
			(at -22.656038 5.605272)
			(size 0.4318 0.4318)
			(layers "F.Cu" "F.Mask" "F.Paste")
			(net "GND")
		)
		(pad "CC20" smd circle
			(at -20.938998 5.605272)
			(size 0.4318 0.4318)
			(layers "F.Cu" "F.Mask" "F.Paste")
			(net "PVCCMCP_CPU0")
		)
		(pad "CC22" smd circle
			(at -19.221958 5.605272)
			(size 0.4318 0.4318)
			(layers "F.Cu" "F.Mask" "F.Paste")
			(net "JTAG_MCP_CPU0_TDO")
		)
		(pad "CC24" smd circle
			(at -17.504918 5.605272)
			(size 0.4318 0.4318)
			(layers "F.Cu" "F.Mask" "F.Paste")
			(net "GND")
		)
		(pad "CC26" smd circle
			(at -15.787878 5.605272)
			(size 0.4318 0.4318)
			(layers "F.Cu" "F.Mask" "F.Paste")
			(net "PVCCIO_CPU0")
		)
		(pad "CC60" smd circle
			(at 14.929612 3.805428)
			(size 0.508 0.508)
			(layers "F.Cu" "F.Mask" "F.Paste")
			(net "PVCCIN_CPU0")
		)
		(pad "CC62" smd circle
			(at 16.646398 3.805428)
			(size 0.4318 0.4318)
			(layers "F.Cu" "F.Mask" "F.Paste")
			(net "PVCCIN_CPU0")
		)
		(pad "CC64" smd circle
			(at 18.363438 3.805428)
			(size 0.4318 0.4318)
			(layers "F.Cu" "F.Mask" "F.Paste")
			(net "GND")
		)
		(pad "CC66" smd circle
			(at 20.080478 3.805428)
			(size 0.4318 0.4318)
			(layers "F.Cu" "F.Mask" "F.Paste")
			(net "PVSA_CPU0")
		)
		(pad "CC68" smd circle
			(at 21.797518 3.805428)
			(size 0.4318 0.4318)
			(layers "F.Cu" "F.Mask" "F.Paste")
			(net "PVSA_CPU0")
		)
		(pad "CC70" smd circle
			(at 23.514558 3.805428)
			(size 0.4318 0.4318)
			(layers "F.Cu" "F.Mask" "F.Paste")
			(net "PVSA_CPU0")
		)
		(pad "CC72" smd circle
			(at 25.231598 3.805428)
			(size 0.4318 0.4318)
			(layers "F.Cu" "F.Mask" "F.Paste")
			(net "GND")
		)
		(pad "CC74" smd circle
			(at 26.948384 3.805428)
			(size 0.4318 0.4318)
			(layers "F.Cu" "F.Mask" "F.Paste")
			(net "GND")
		)
		(pad "CC76" smd circle
			(at 28.665424 3.805428)
			(size 0.4318 0.4318)
			(layers "F.Cu" "F.Mask" "F.Paste")
			(net "GND")
		)
		(pad "CC78" smd circle
			(at 30.382464 3.805428)
			(size 0.4318 0.4318)
			(layers "F.Cu" "F.Mask" "F.Paste")
			(net "GND")
		)
		(pad "CC80" smd circle
			(at 32.099504 3.805428)
			(size 0.4318 0.4318)
			(layers "F.Cu" "F.Mask" "F.Paste")
			(net "GND")
		)
		(pad "CC82" smd circle
			(at 33.816544 3.805428)
			(size 0.4318 0.4318)
			(layers "F.Cu" "F.Mask" "F.Paste")
			(net "GND")
		)
		(pad "CC84" smd custom
			(at 35.533584 3.805428 270)
			(size 0.10795 0.10795)
			(layers "F.Cu" "F.Mask" "F.Paste")
			(net "PVCCIN_CPU0")
			(options
				(clearance outline)
				(anchor circle)
			)
			(primitives
				(gr_poly
					(pts
						(arc
							(start 0.2159 -0.0381)
							(mid 0 -0.254)
							(end -0.2159 -0.0381)
						)
						(arc
							(start -0.2159 0.0381)
							(mid 0 0.254)
							(end 0.2159 0.0381)
						)
					)
					(width 0)
					(fill yes)
				)
			)
		)
		(pad "CD3" smd circle
			(at -35.533584 6.100572)
			(size 0.4318 0.4318)
			(layers "F.Cu" "F.Mask" "F.Paste")
			(net "P3E_CPU0_PE2_SS_TXP<8>")
		)
		(pad "CD5" smd circle
			(at -33.816544 6.100572)
			(size 0.4318 0.4318)
			(layers "F.Cu" "F.Mask" "F.Paste")
			(net "GND")
		)
		(pad "CD7" smd circle
			(at -32.099504 6.100572)
			(size 0.4318 0.4318)
			(layers "F.Cu" "F.Mask" "F.Paste")
			(net "P3E_CPU0_PE2_SS_RXP<6>")
		)
		(pad "CD9" smd circle
			(at -30.382464 6.100572)
			(size 0.4318 0.4318)
			(layers "F.Cu" "F.Mask" "F.Paste")
			(net "PVCCIO_CPU0")
		)
		(pad "CD11" smd circle
			(at -28.665424 6.100572)
			(size 0.4318 0.4318)
			(layers "F.Cu" "F.Mask" "F.Paste")
			(net "TP_CPU0_UPI2_RSVD_DK19")
		)
		(pad "CD13" smd circle
			(at -26.948384 6.100572)
			(size 0.4318 0.4318)
			(layers "F.Cu" "F.Mask" "F.Paste")
			(net "GND")
		)
		(pad "CD15" smd circle
			(at -25.231598 6.100572)
			(size 0.4318 0.4318)
			(layers "F.Cu" "F.Mask" "F.Paste")
			(net "GND")
		)
		(pad "CD17" smd circle
			(at -23.514558 6.100572)
			(size 0.4318 0.4318)
			(layers "F.Cu" "F.Mask" "F.Paste")
			(net "GND")
		)
		(pad "CD19" smd circle
			(at -21.797518 6.100572)
			(size 0.4318 0.4318)
			(layers "F.Cu" "F.Mask" "F.Paste")
			(net "PVCCMCP_CPU0")
		)
		(pad "CD21" smd circle
			(at -20.080478 6.100572)
			(size 0.4318 0.4318)
			(layers "F.Cu" "F.Mask" "F.Paste")
			(net "PVCCMCP_CPU0")
		)
		(pad "CD23" smd circle
			(at -18.363438 6.100572)
			(size 0.4318 0.4318)
			(layers "F.Cu" "F.Mask" "F.Paste")
			(net "JTAG_MCP_TRST_N")
		)
		(pad "CD25" smd circle
			(at -16.646398 6.100572)
			(size 0.4318 0.4318)
			(layers "F.Cu" "F.Mask" "F.Paste")
			(net "TP_CPU0_RSVD_108")
		)
		(pad "CD27" smd circle
			(at -14.929612 6.100572)
			(size 0.4318 0.4318)
			(layers "F.Cu" "F.Mask" "F.Paste")
			(net "PVCCIO_CPU0")
		)
		(pad "CD61" smd circle
			(at 15.787878 4.300474)
			(size 0.4318 0.4318)
			(layers "F.Cu" "F.Mask" "F.Paste")
			(net "PVCCIN_CPU0")
		)
		(pad "CD63" smd circle
			(at 17.504918 4.300474)
			(size 0.4318 0.4318)
			(layers "F.Cu" "F.Mask" "F.Paste")
			(net "GND")
		)
		(pad "CD65" smd circle
			(at 19.221958 4.300474)
			(size 0.4318 0.4318)
			(layers "F.Cu" "F.Mask" "F.Paste")
			(net "PVSA_CPU0")
		)
		(pad "CD67" smd circle
			(at 20.938998 4.300474)
			(size 0.4318 0.4318)
			(layers "F.Cu" "F.Mask" "F.Paste")
			(net "PVSA_CPU0")
		)
		(pad "CD69" smd circle
			(at 22.656038 4.300474)
			(size 0.4318 0.4318)
			(layers "F.Cu" "F.Mask" "F.Paste")
			(net "PVSA_CPU0")
		)
		(pad "CD71" smd circle
			(at 24.373078 4.300474)
			(size 0.4318 0.4318)
			(layers "F.Cu" "F.Mask" "F.Paste")
			(net "PVSA_CPU0")
		)
		(pad "CD73" smd circle
			(at 26.090118 4.300474)
			(size 0.4318 0.4318)
			(layers "F.Cu" "F.Mask" "F.Paste")
			(net "GND")
		)
		(pad "CD75" smd circle
			(at 27.806904 4.300474)
			(size 0.4318 0.4318)
			(layers "F.Cu" "F.Mask" "F.Paste")
			(net "GND")
		)
		(pad "CD77" smd circle
			(at 29.523944 4.300474)
			(size 0.4318 0.4318)
			(layers "F.Cu" "F.Mask" "F.Paste")
			(net "GND")
		)
		(pad "CD79" smd circle
			(at 31.240984 4.300474)
			(size 0.4318 0.4318)
			(layers "F.Cu" "F.Mask" "F.Paste")
			(net "GND")
		)
		(pad "CD81" smd circle
			(at 32.958024 4.300474)
			(size 0.4318 0.4318)
			(layers "F.Cu" "F.Mask" "F.Paste")
			(net "GND")
		)
		(pad "CD83" smd circle
			(at 34.675064 4.300474)
			(size 0.4318 0.4318)
			(layers "F.Cu" "F.Mask" "F.Paste")
			(net "PVCCIN_CPU0")
		)
		(pad "CD85" smd custom
			(at 36.392104 4.300474 270)
			(size 0.10795 0.10795)
			(layers "F.Cu" "F.Mask" "F.Paste")
			(net "PVCCIN_CPU0")
			(options
				(clearance outline)
				(anchor circle)
			)
			(primitives
				(gr_poly
					(pts
						(arc
							(start 0.2159 -0.0381)
							(mid 0 -0.254)
							(end -0.2159 -0.0381)
						)
						(arc
							(start -0.2159 0.0381)
							(mid 0 0.254)
							(end 0.2159 0.0381)
						)
					)
					(width 0)
					(fill yes)
				)
			)
		)
		(pad "CE2" smd custom
			(at -36.392104 6.596126 90)
			(size 0.10795 0.10795)
			(layers "F.Cu" "F.Mask" "F.Paste")
			(net "P3E_CPU0_PE2_SS_TXP<6>")
			(options
				(clearance outline)
				(anchor circle)
			)
			(primitives
				(gr_poly
					(pts
						(arc
							(start 0.2159 -0.0381)
							(mid 0 -0.254)
							(end -0.2159 -0.0381)
						)
						(arc
							(start -0.2159 0.0381)
							(mid 0 0.254)
							(end 0.2159 0.0381)
						)
					)
					(width 0)
					(fill yes)
				)
			)
		)
		(pad "CE4" smd circle
			(at -34.675064 6.596126)
			(size 0.4318 0.4318)
			(layers "F.Cu" "F.Mask" "F.Paste")
			(net "P3E_CPU0_PE2_SS_TXP<7>")
		)
		(pad "CE6" smd circle
			(at -32.958024 6.596126)
			(size 0.4318 0.4318)
			(layers "F.Cu" "F.Mask" "F.Paste")
			(net "P3E_CPU0_PE2_SS_RXN<6>")
		)
		(pad "CE8" smd circle
			(at -31.240984 6.596126)
			(size 0.4318 0.4318)
			(layers "F.Cu" "F.Mask" "F.Paste")
			(net "P3E_CPU0_PE2_SS_RXN<7>")
		)
		(pad "CE10" smd circle
			(at -29.523944 6.596126)
			(size 0.4318 0.4318)
			(layers "F.Cu" "F.Mask" "F.Paste")
			(net "GND")
		)
		(pad "CE12" smd circle
			(at -27.806904 6.596126)
			(size 0.4318 0.4318)
			(layers "F.Cu" "F.Mask" "F.Paste")
			(net "TP_CPU0_UPI2_RSVD_DL20")
		)
		(pad "CE14" smd circle
			(at -26.090118 6.596126)
			(size 0.4318 0.4318)
			(layers "F.Cu" "F.Mask" "F.Paste")
			(net "GND")
		)
		(pad "CE16" smd circle
			(at -24.373078 6.596126)
			(size 0.4318 0.4318)
			(layers "F.Cu" "F.Mask" "F.Paste")
			(net "GND")
		)
		(pad "CE18" smd circle
			(at -22.656038 6.596126)
			(size 0.4318 0.4318)
			(layers "F.Cu" "F.Mask" "F.Paste")
			(net "PVCCIO_CPU0")
		)
		(pad "CE20" smd circle
			(at -20.938998 6.596126)
			(size 0.4318 0.4318)
			(layers "F.Cu" "F.Mask" "F.Paste")
			(net "GND")
		)
		(pad "CE22" smd circle
			(at -19.221958 6.596126)
			(size 0.4318 0.4318)
			(layers "F.Cu" "F.Mask" "F.Paste")
			(net "PVCCMCP_CPU0")
		)
		(pad "CE24" smd circle
			(at -17.504918 6.596126)
			(size 0.4318 0.4318)
			(layers "F.Cu" "F.Mask" "F.Paste")
			(net "JTAG_MCP_TMS")
		)
		(pad "CE26" smd circle
			(at -15.787878 6.596126)
			(size 0.4318 0.4318)
			(layers "F.Cu" "F.Mask" "F.Paste")
			(net "GND")
		)
		(pad "CE60" smd circle
			(at 14.929612 4.796028)
			(size 0.508 0.508)
			(layers "F.Cu" "F.Mask" "F.Paste")
			(net "PVCCIN_CPU0")
		)
		(pad "CE62" smd circle
			(at 16.646398 4.796028)
			(size 0.4318 0.4318)
			(layers "F.Cu" "F.Mask" "F.Paste")
			(net "GND")
		)
		(pad "CE64" smd circle
			(at 18.363438 4.796028)
			(size 0.4318 0.4318)
			(layers "F.Cu" "F.Mask" "F.Paste")
			(net "PVSA_CPU0")
		)
		(pad "CE66" smd circle
			(at 20.080478 4.796028)
			(size 0.4318 0.4318)
			(layers "F.Cu" "F.Mask" "F.Paste")
			(net "PVSA_CPU0")
		)
		(pad "CE68" smd circle
			(at 21.797518 4.796028)
			(size 0.4318 0.4318)
			(layers "F.Cu" "F.Mask" "F.Paste")
			(net "PVSA_CPU0")
		)
		(pad "CE70" smd circle
			(at 23.514558 4.796028)
			(size 0.4318 0.4318)
			(layers "F.Cu" "F.Mask" "F.Paste")
			(net "GND")
		)
		(pad "CE72" smd circle
			(at 25.231598 4.796028)
			(size 0.4318 0.4318)
			(layers "F.Cu" "F.Mask" "F.Paste")
			(net "PVSA_CPU0")
		)
		(pad "CE74" smd circle
			(at 26.948384 4.796028)
			(size 0.4318 0.4318)
			(layers "F.Cu" "F.Mask" "F.Paste")
			(net "PVSA_CPU0")
		)
		(pad "CE76" smd circle
			(at 28.665424 4.796028)
			(size 0.4318 0.4318)
			(layers "F.Cu" "F.Mask" "F.Paste")
			(net "VSENSE_PVSA_CPU0_SKT_VSEN")
		)
		(pad "CE78" smd circle
			(at 30.382464 4.796028)
			(size 0.4318 0.4318)
			(layers "F.Cu" "F.Mask" "F.Paste")
			(net "TP_CPU0_RSVD_106")
		)
		(pad "CE80" smd circle
			(at 32.099504 4.796028)
			(size 0.4318 0.4318)
			(layers "F.Cu" "F.Mask" "F.Paste")
			(net "TP_CPU0_RSVD_105")
		)
		(pad "CE82" smd circle
			(at 33.816544 4.796028)
			(size 0.4318 0.4318)
			(layers "F.Cu" "F.Mask" "F.Paste")
			(net "GND")
		)
		(pad "CE84" smd circle
			(at 35.533584 4.796028)
			(size 0.4318 0.4318)
			(layers "F.Cu" "F.Mask" "F.Paste")
			(net "PVCCIN_CPU0")
		)
		(pad "CF3" smd circle
			(at -35.533584 7.091172)
			(size 0.4318 0.4318)
			(layers "F.Cu" "F.Mask" "F.Paste")
			(net "P3E_CPU0_PE2_SS_TXN<7>")
		)
		(pad "CF5" smd circle
			(at -33.816544 7.091172)
			(size 0.4318 0.4318)
			(layers "F.Cu" "F.Mask" "F.Paste")
			(net "PVCCIO_CPU0")
		)
		(pad "CF7" smd circle
			(at -32.099504 7.091172)
			(size 0.4318 0.4318)
			(layers "F.Cu" "F.Mask" "F.Paste")
			(net "P3E_CPU0_PE2_SS_RXP<5>")
		)
		(pad "CF9" smd circle
			(at -30.382464 7.091172)
			(size 0.4318 0.4318)
			(layers "F.Cu" "F.Mask" "F.Paste")
			(net "GND")
		)
		(pad "CF11" smd circle
			(at -28.665424 7.091172)
			(size 0.4318 0.4318)
			(layers "F.Cu" "F.Mask" "F.Paste")
			(net "TP_CPU0_UPI2_RSVD_DJ20")
		)
		(pad "CF13" smd circle
			(at -26.948384 7.091172)
			(size 0.4318 0.4318)
			(layers "F.Cu" "F.Mask" "F.Paste")
			(net "TP_CPU0_UPI2_RSVD_DH19")
		)
		(pad "CF15" smd circle
			(at -25.231598 7.091172)
			(size 0.4318 0.4318)
			(layers "F.Cu" "F.Mask" "F.Paste")
			(net "GND")
		)
		(pad "CF17" smd circle
			(at -23.514558 7.091172)
			(size 0.4318 0.4318)
			(layers "F.Cu" "F.Mask" "F.Paste")
			(net "GND")
		)
		(pad "CF19" smd circle
			(at -21.797518 7.091172)
			(size 0.4318 0.4318)
			(layers "F.Cu" "F.Mask" "F.Paste")
			(net "PVCCMCP_CPU0")
		)
		(pad "CF21" smd circle
			(at -20.080478 7.091172)
			(size 0.4318 0.4318)
			(layers "F.Cu" "F.Mask" "F.Paste")
			(net "PVCCMCP_CPU0")
		)
		(pad "CF23" smd circle
			(at -18.363438 7.091172)
			(size 0.4318 0.4318)
			(layers "F.Cu" "F.Mask" "F.Paste")
			(net "PVCCMCP_CPU0")
		)
		(pad "CF25" smd circle
			(at -16.646398 7.091172)
			(size 0.4318 0.4318)
			(layers "F.Cu" "F.Mask" "F.Paste")
			(net "RST_CD_CPU0_POR_N")
		)
		(pad "CF27" smd circle
			(at -14.929612 7.091172)
			(size 0.4318 0.4318)
			(layers "F.Cu" "F.Mask" "F.Paste")
			(net "PVCCIO_CPU0")
		)
		(pad "CF61" smd circle
			(at 15.787878 5.291074)
			(size 0.4318 0.4318)
			(layers "F.Cu" "F.Mask" "F.Paste")
			(net "PVCCIN_CPU0")
		)
		(pad "CF63" smd circle
			(at 17.504918 5.291074)
			(size 0.4318 0.4318)
			(layers "F.Cu" "F.Mask" "F.Paste")
			(net "GND")
		)
		(pad "CF65" smd circle
			(at 19.221958 5.291074)
			(size 0.4318 0.4318)
			(layers "F.Cu" "F.Mask" "F.Paste")
			(net "PVSA_CPU0")
		)
		(pad "CF67" smd circle
			(at 20.938998 5.291074)
			(size 0.4318 0.4318)
			(layers "F.Cu" "F.Mask" "F.Paste")
			(net "PVSA_CPU0")
		)
		(pad "CF69" smd circle
			(at 22.656038 5.291074)
			(size 0.4318 0.4318)
			(layers "F.Cu" "F.Mask" "F.Paste")
			(net "GND")
		)
		(pad "CF71" smd circle
			(at 24.373078 5.291074)
			(size 0.4318 0.4318)
			(layers "F.Cu" "F.Mask" "F.Paste")
			(net "GND")
		)
		(pad "CF73" smd circle
			(at 26.090118 5.291074)
			(size 0.4318 0.4318)
			(layers "F.Cu" "F.Mask" "F.Paste")
			(net "PVSA_CPU0")
		)
		(pad "CF75" smd circle
			(at 27.806904 5.291074)
			(size 0.4318 0.4318)
			(layers "F.Cu" "F.Mask" "F.Paste")
			(net "PVSA_CPU0")
		)
		(pad "CF77" smd circle
			(at 29.523944 5.291074)
			(size 0.4318 0.4318)
			(layers "F.Cu" "F.Mask" "F.Paste")
			(net "GND")
		)
		(pad "CF79" smd circle
			(at 31.240984 5.291074)
			(size 0.4318 0.4318)
			(layers "F.Cu" "F.Mask" "F.Paste")
			(net "TP_CPU0_RSVD_101")
		)
		(pad "CF81" smd circle
			(at 32.958024 5.291074)
			(size 0.4318 0.4318)
			(layers "F.Cu" "F.Mask" "F.Paste")
			(net "TP_CPU0_RSVD_100")
		)
		(pad "CF83" smd circle
			(at 34.675064 5.291074)
			(size 0.4318 0.4318)
			(layers "F.Cu" "F.Mask" "F.Paste")
			(net "GND")
		)
		(pad "CF85" smd custom
			(at 36.392104 5.291074 270)
			(size 0.10795 0.10795)
			(layers "F.Cu" "F.Mask" "F.Paste")
			(net "PVCCIN_CPU0")
			(options
				(clearance outline)
				(anchor circle)
			)
			(primitives
				(gr_poly
					(pts
						(arc
							(start 0.2159 -0.0381)
							(mid 0 -0.254)
							(end -0.2159 -0.0381)
						)
						(arc
							(start -0.2159 0.0381)
							(mid 0 0.254)
							(end 0.2159 0.0381)
						)
					)
					(width 0)
					(fill yes)
				)
			)
		)
		(pad "CG2" smd custom
			(at -36.392104 7.586726 90)
			(size 0.10795 0.10795)
			(layers "F.Cu" "F.Mask" "F.Paste")
			(net "P3E_CPU0_PE2_SS_TXN<6>")
			(options
				(clearance outline)
				(anchor circle)
			)
			(primitives
				(gr_poly
					(pts
						(arc
							(start 0.2159 -0.0381)
							(mid 0 -0.254)
							(end -0.2159 -0.0381)
						)
						(arc
							(start -0.2159 0.0381)
							(mid 0 0.254)
							(end 0.2159 0.0381)
						)
					)
					(width 0)
					(fill yes)
				)
			)
		)
		(pad "CG4" smd circle
			(at -34.675064 7.586726)
			(size 0.4318 0.4318)
			(layers "F.Cu" "F.Mask" "F.Paste")
			(net "DMI_CPU0_PCH_TX_DN<0>")
		)
		(pad "CG6" smd circle
			(at -32.958024 7.586726)
			(size 0.4318 0.4318)
			(layers "F.Cu" "F.Mask" "F.Paste")
			(net "GND")
		)
		(pad "CG8" smd circle
			(at -31.240984 7.586726)
			(size 0.4318 0.4318)
			(layers "F.Cu" "F.Mask" "F.Paste")
			(net "P3E_CPU0_PE2_SS_RXN<5>")
		)
		(pad "CG10" smd circle
			(at -29.523944 7.586726)
			(size 0.4318 0.4318)
			(layers "F.Cu" "F.Mask" "F.Paste")
			(net "TP_CPU0_RSVD_99")
		)
		(pad "CG12" smd circle
			(at -27.806904 7.586726)
			(size 0.4318 0.4318)
			(layers "F.Cu" "F.Mask" "F.Paste")
			(net "TP_CPU0_UPI2_RSVD_DJ18")
		)
		(pad "CG14" smd circle
			(at -26.090118 7.586726)
			(size 0.4318 0.4318)
			(layers "F.Cu" "F.Mask" "F.Paste")
			(net "PVCCIO_CPU0")
		)
		(pad "CG16" smd circle
			(at -24.373078 7.586726)
			(size 0.4318 0.4318)
			(layers "F.Cu" "F.Mask" "F.Paste")
			(net "GND")
		)
		(pad "CG18" smd circle
			(at -22.656038 7.586726)
			(size 0.4318 0.4318)
			(layers "F.Cu" "F.Mask" "F.Paste")
			(net "GND")
		)
		(pad "CG20" smd circle
			(at -20.938998 7.586726)
			(size 0.4318 0.4318)
			(layers "F.Cu" "F.Mask" "F.Paste")
			(net "PVCCMCP_CPU0")
		)
		(pad "CG22" smd circle
			(at -19.221958 7.586726)
			(size 0.4318 0.4318)
			(layers "F.Cu" "F.Mask" "F.Paste")
			(net "GND")
		)
		(pad "CG24" smd circle
			(at -17.504918 7.586726)
			(size 0.4318 0.4318)
			(layers "F.Cu" "F.Mask" "F.Paste")
			(net "TP_CPU0_RSVD_97")
		)
		(pad "CG26" smd circle
			(at -15.787878 7.586726)
			(size 0.4318 0.4318)
			(layers "F.Cu" "F.Mask" "F.Paste")
			(net "PVCCMCP_CPU0")
		)
		(pad "CG60" smd circle
			(at 14.929612 5.786628)
			(size 0.508 0.508)
			(layers "F.Cu" "F.Mask" "F.Paste")
			(net "PVCCIN_CPU0")
		)
		(pad "CG62" smd circle
			(at 16.646398 5.786628)
			(size 0.4318 0.4318)
			(layers "F.Cu" "F.Mask" "F.Paste")
			(net "GND")
		)
		(pad "CG64" smd circle
			(at 18.363438 5.786628)
			(size 0.4318 0.4318)
			(layers "F.Cu" "F.Mask" "F.Paste")
			(net "PVSA_CPU0")
		)
		(pad "CG66" smd circle
			(at 20.080478 5.786628)
			(size 0.4318 0.4318)
			(layers "F.Cu" "F.Mask" "F.Paste")
			(net "PVSA_CPU0")
		)
		(pad "CG68" smd circle
			(at 21.797518 5.786628)
			(size 0.4318 0.4318)
			(layers "F.Cu" "F.Mask" "F.Paste")
			(net "GND")
		)
		(pad "CG70" smd circle
			(at 23.514558 5.786628)
			(size 0.4318 0.4318)
			(layers "F.Cu" "F.Mask" "F.Paste")
			(net "M_F_DQS_DP<17>")
		)
		(pad "CG72" smd circle
			(at 25.231598 5.786628)
			(size 0.4318 0.4318)
			(layers "F.Cu" "F.Mask" "F.Paste")
			(net "GND")
		)
		(pad "CG74" smd circle
			(at 26.948384 5.786628)
			(size 0.4318 0.4318)
			(layers "F.Cu" "F.Mask" "F.Paste")
			(net "PVSA_CPU0")
		)
		(pad "CG76" smd circle
			(at 28.665424 5.786628)
			(size 0.4318 0.4318)
			(layers "F.Cu" "F.Mask" "F.Paste")
			(net "VSENSE_PVSA_CPU0_SKT_VRTN")
		)
		(pad "CG78" smd circle
			(at 30.382464 5.786628)
			(size 0.4318 0.4318)
			(layers "F.Cu" "F.Mask" "F.Paste")
			(net "TP_CPU0_RSVD_95")
		)
		(pad "CG80" smd circle
			(at 32.099504 5.786628)
			(size 0.4318 0.4318)
			(layers "F.Cu" "F.Mask" "F.Paste")
			(net "GND")
		)
		(pad "CG82" smd circle
			(at 33.816544 5.786628)
			(size 0.4318 0.4318)
			(layers "F.Cu" "F.Mask" "F.Paste")
			(net "TP_CPU0_RSVD_94")
		)
		(pad "CG84" smd circle
			(at 35.533584 5.786628)
			(size 0.4318 0.4318)
			(layers "F.Cu" "F.Mask" "F.Paste")
			(net "PVCCIN_CPU0")
		)
		(pad "CH1" smd custom
			(at -37.250624 8.081772 90)
			(size 0.10795 0.10795)
			(layers "F.Cu" "F.Mask" "F.Paste")
			(net "GND")
			(options
				(clearance outline)
				(anchor circle)
			)
			(primitives
				(gr_poly
					(pts
						(arc
							(start 0.2159 -0.0381)
							(mid 0 -0.254)
							(end -0.2159 -0.0381)
						)
						(arc
							(start -0.2159 0.0381)
							(mid 0 0.254)
							(end 0.2159 0.0381)
						)
					)
					(width 0)
					(fill yes)
				)
			)
		)
		(pad "CH3" smd circle
			(at -35.533584 8.081772)
			(size 0.4318 0.4318)
			(layers "F.Cu" "F.Mask" "F.Paste")
			(net "GND")
		)
		(pad "CH5" smd circle
			(at -33.816544 8.081772)
			(size 0.4318 0.4318)
			(layers "F.Cu" "F.Mask" "F.Paste")
			(net "DMI_CPU0_PCH_TX_DP<0>")
		)
		(pad "CH7" smd circle
			(at -32.099504 8.081772)
			(size 0.4318 0.4318)
			(layers "F.Cu" "F.Mask" "F.Paste")
			(net "P3E_CPU0_PE2_SS_RXP<4>")
		)
		(pad "CH9" smd circle
			(at -30.382464 8.081772)
			(size 0.4318 0.4318)
			(layers "F.Cu" "F.Mask" "F.Paste")
			(net "PVCCIO_CPU0")
		)
		(pad "CH11" smd circle
			(at -28.665424 8.081772)
			(size 0.4318 0.4318)
			(layers "F.Cu" "F.Mask" "F.Paste")
			(net "TP_CPU0_UPI2_RSVD_DG20")
		)
		(pad "CH13" smd circle
			(at -26.948384 8.081772)
			(size 0.4318 0.4318)
			(layers "F.Cu" "F.Mask" "F.Paste")
			(net "TP_CPU0_UPI2_RSVD_DH17")
		)
		(pad "CH15" smd circle
			(at -25.231598 8.081772)
			(size 0.4318 0.4318)
			(layers "F.Cu" "F.Mask" "F.Paste")
			(net "GND")
		)
		(pad "CH17" smd circle
			(at -23.514558 8.081772)
			(size 0.4318 0.4318)
			(layers "F.Cu" "F.Mask" "F.Paste")
			(net "GND")
		)
		(pad "CH19" smd circle
			(at -21.797518 8.081772)
			(size 0.4318 0.4318)
			(layers "F.Cu" "F.Mask" "F.Paste")
			(net "GND")
		)
		(pad "CH21" smd circle
			(at -20.080478 8.081772)
			(size 0.4318 0.4318)
			(layers "F.Cu" "F.Mask" "F.Paste")
			(net "PVCCMCP_CPU0")
		)
		(pad "CH23" smd circle
			(at -18.363438 8.081772)
			(size 0.4318 0.4318)
			(layers "F.Cu" "F.Mask" "F.Paste")
			(net "PVCCMCP_CPU0")
		)
		(pad "CH25" smd circle
			(at -16.646398 8.081772)
			(size 0.4318 0.4318)
			(layers "F.Cu" "F.Mask" "F.Paste")
			(net "TP_CPU0_RSVD_91")
		)
		(pad "CH27" smd circle
			(at -14.929612 8.081772)
			(size 0.4318 0.4318)
			(layers "F.Cu" "F.Mask" "F.Paste")
			(net "PVCCIO_CPU0")
		)
		(pad "CH61" smd circle
			(at 15.787878 6.281928)
			(size 0.4318 0.4318)
			(layers "F.Cu" "F.Mask" "F.Paste")
			(net "PVCCIN_CPU0")
		)
		(pad "CH63" smd circle
			(at 17.504918 6.281928)
			(size 0.4318 0.4318)
			(layers "F.Cu" "F.Mask" "F.Paste")
			(net "GND")
		)
		(pad "CH65" smd circle
			(at 19.221958 6.281928)
			(size 0.4318 0.4318)
			(layers "F.Cu" "F.Mask" "F.Paste")
			(net "PVSA_CPU0")
		)
		(pad "CH67" smd circle
			(at 20.938998 6.281928)
			(size 0.4318 0.4318)
			(layers "F.Cu" "F.Mask" "F.Paste")
			(net "GND")
		)
		(pad "CH69" smd circle
			(at 22.656038 6.281928)
			(size 0.4318 0.4318)
			(layers "F.Cu" "F.Mask" "F.Paste")
			(net "M_F_ECC<6>")
		)
		(pad "CH71" smd circle
			(at 24.373078 6.281928)
			(size 0.4318 0.4318)
			(layers "F.Cu" "F.Mask" "F.Paste")
			(net "M_F_ECC<0>")
		)
		(pad "CH73" smd circle
			(at 26.090118 6.281928)
			(size 0.4318 0.4318)
			(layers "F.Cu" "F.Mask" "F.Paste")
			(net "GND")
		)
		(pad "CH75" smd circle
			(at 27.806904 6.281928)
			(size 0.4318 0.4318)
			(layers "F.Cu" "F.Mask" "F.Paste")
			(net "PVSA_CPU0")
		)
		(pad "CH77" smd circle
			(at 29.523944 6.281928)
			(size 0.4318 0.4318)
			(layers "F.Cu" "F.Mask" "F.Paste")
			(net "TP_CPU0_RSVD_90")
		)
		(pad "CH79" smd circle
			(at 31.240984 6.281928)
			(size 0.4318 0.4318)
			(layers "F.Cu" "F.Mask" "F.Paste")
			(net "GND")
		)
		(pad "CH81" smd circle
			(at 32.958024 6.281928)
			(size 0.4318 0.4318)
			(layers "F.Cu" "F.Mask" "F.Paste")
			(net "GND")
		)
		(pad "CH83" smd circle
			(at 34.675064 6.281928)
			(size 0.4318 0.4318)
			(layers "F.Cu" "F.Mask" "F.Paste")
			(net "GND")
		)
		(pad "CH85" smd custom
			(at 36.392104 6.281928 270)
			(size 0.10795 0.10795)
			(layers "F.Cu" "F.Mask" "F.Paste")
			(net "PVCCIN_CPU0")
			(options
				(clearance outline)
				(anchor circle)
			)
			(primitives
				(gr_poly
					(pts
						(arc
							(start 0.2159 -0.0381)
							(mid 0 -0.254)
							(end -0.2159 -0.0381)
						)
						(arc
							(start -0.2159 0.0381)
							(mid 0 0.254)
							(end 0.2159 0.0381)
						)
					)
					(width 0)
					(fill yes)
				)
			)
		)
		(pad "CJ2" smd circle
			(at -36.392104 8.577326)
			(size 0.4318 0.4318)
			(layers "F.Cu" "F.Mask" "F.Paste")
			(net "GND")
		)
		(pad "CJ4" smd circle
			(at -34.675064 8.577326)
			(size 0.4318 0.4318)
			(layers "F.Cu" "F.Mask" "F.Paste")
			(net "DMI_CPU0_PCH_TX_DN<1>")
		)
		(pad "CJ6" smd circle
			(at -32.958024 8.577326)
			(size 0.4318 0.4318)
			(layers "F.Cu" "F.Mask" "F.Paste")
			(net "GND")
		)
		(pad "CJ8" smd circle
			(at -31.240984 8.577326)
			(size 0.4318 0.4318)
			(layers "F.Cu" "F.Mask" "F.Paste")
			(net "GND")
		)
		(pad "CJ10" smd circle
			(at -29.523944 8.577326)
			(size 0.4318 0.4318)
			(layers "F.Cu" "F.Mask" "F.Paste")
			(net "GND")
		)
		(pad "CJ12" smd circle
			(at -27.806904 8.577326)
			(size 0.4318 0.4318)
			(layers "F.Cu" "F.Mask" "F.Paste")
			(net "GND")
		)
		(pad "CJ14" smd circle
			(at -26.090118 8.577326)
			(size 0.4318 0.4318)
			(layers "F.Cu" "F.Mask" "F.Paste")
			(net "TP_CPU0_UPI2_RSVD_DK17")
		)
		(pad "CJ16" smd circle
			(at -24.373078 8.577326)
			(size 0.4318 0.4318)
			(layers "F.Cu" "F.Mask" "F.Paste")
			(net "GND")
		)
		(pad "CJ18" smd circle
			(at -22.656038 8.577326)
			(size 0.4318 0.4318)
			(layers "F.Cu" "F.Mask" "F.Paste")
			(net "GND")
		)
		(pad "CJ20" smd circle
			(at -20.938998 8.577326)
			(size 0.4318 0.4318)
			(layers "F.Cu" "F.Mask" "F.Paste")
			(net "PVCCMCP_CPU0")
		)
		(pad "CJ22" smd circle
			(at -19.221958 8.577326)
			(size 0.4318 0.4318)
			(layers "F.Cu" "F.Mask" "F.Paste")
			(net "PVCCMCP_CPU0")
		)
		(pad "CJ24" smd circle
			(at -17.504918 8.577326)
			(size 0.4318 0.4318)
			(layers "F.Cu" "F.Mask" "F.Paste")
			(net "PVCCMCP_CPU0")
		)
		(pad "CJ26" smd circle
			(at -15.787878 8.577326)
			(size 0.4318 0.4318)
			(layers "F.Cu" "F.Mask" "F.Paste")
			(net "PVCCMCP_CPU0")
		)
		(pad "CJ28" smd circle
			(at -14.071092 8.577326)
			(size 0.4318 0.4318)
			(layers "F.Cu" "F.Mask" "F.Paste")
			(net "PVCCIO_CPU0")
		)
		(pad "CJ60" smd circle
			(at 14.929612 6.777228)
			(size 0.508 0.508)
			(layers "F.Cu" "F.Mask" "F.Paste")
			(net "PVCCIN_CPU0")
		)
		(pad "CJ62" smd circle
			(at 16.646398 6.777228)
			(size 0.4318 0.4318)
			(layers "F.Cu" "F.Mask" "F.Paste")
			(net "GND")
		)
		(pad "CJ64" smd circle
			(at 18.363438 6.777228)
			(size 0.4318 0.4318)
			(layers "F.Cu" "F.Mask" "F.Paste")
			(net "PVSA_CPU0")
		)
		(pad "CJ66" smd circle
			(at 20.080478 6.777228)
			(size 0.4318 0.4318)
			(layers "F.Cu" "F.Mask" "F.Paste")
			(net "PVSA_CPU0")
		)
		(pad "CJ68" smd circle
			(at 21.797518 6.777228)
			(size 0.4318 0.4318)
			(layers "F.Cu" "F.Mask" "F.Paste")
			(net "M_F_ECC<2>")
		)
		(pad "CJ70" smd circle
			(at 23.514558 6.777228)
			(size 0.4318 0.4318)
			(layers "F.Cu" "F.Mask" "F.Paste")
			(net "M_F_DQS_DN<17>")
		)
		(pad "CJ72" smd circle
			(at 25.231598 6.777228)
			(size 0.4318 0.4318)
			(layers "F.Cu" "F.Mask" "F.Paste")
			(net "M_F_ECC<4>")
		)
		(pad "CJ74" smd circle
			(at 26.948384 6.777228)
			(size 0.4318 0.4318)
			(layers "F.Cu" "F.Mask" "F.Paste")
			(net "GND")
		)
		(pad "CJ76" smd circle
			(at 28.665424 6.777228)
			(size 0.4318 0.4318)
			(layers "F.Cu" "F.Mask" "F.Paste")
			(net "GND")
		)
		(pad "CJ78" smd circle
			(at 30.382464 6.777228)
			(size 0.4318 0.4318)
			(layers "F.Cu" "F.Mask" "F.Paste")
			(net "GND")
		)
		(pad "CJ80" smd circle
			(at 32.099504 6.777228)
			(size 0.4318 0.4318)
			(layers "F.Cu" "F.Mask" "F.Paste")
			(net "M_E_DQ<5>")
		)
		(pad "CJ82" smd circle
			(at 33.816544 6.777228)
			(size 0.4318 0.4318)
			(layers "F.Cu" "F.Mask" "F.Paste")
			(net "GND")
		)
		(pad "CJ84" smd circle
			(at 35.533584 6.777228)
			(size 0.4318 0.4318)
			(layers "F.Cu" "F.Mask" "F.Paste")
			(net "GND")
		)
		(pad "CJ86" smd custom
			(at 37.250624 6.777228 270)
			(size 0.10795 0.10795)
			(layers "F.Cu" "F.Mask" "F.Paste")
			(net "GND")
			(options
				(clearance outline)
				(anchor circle)
			)
			(primitives
				(gr_poly
					(pts
						(arc
							(start 0.2159 -0.0381)
							(mid 0 -0.254)
							(end -0.2159 -0.0381)
						)
						(arc
							(start -0.2159 0.0381)
							(mid 0 0.254)
							(end 0.2159 0.0381)
						)
					)
					(width 0)
					(fill yes)
				)
			)
		)
		(pad "CK1" smd custom
			(at -37.250624 9.072372 90)
			(size 0.10795 0.10795)
			(layers "F.Cu" "F.Mask" "F.Paste")
			(net "P3E_CPU0_PE2_SS_TXP<4>")
			(options
				(clearance outline)
				(anchor circle)
			)
			(primitives
				(gr_poly
					(pts
						(arc
							(start 0.2159 -0.0381)
							(mid 0 -0.254)
							(end -0.2159 -0.0381)
						)
						(arc
							(start -0.2159 0.0381)
							(mid 0 0.254)
							(end 0.2159 0.0381)
						)
					)
					(width 0)
					(fill yes)
				)
			)
		)
		(pad "CK3" smd circle
			(at -35.533584 9.072372)
			(size 0.4318 0.4318)
			(layers "F.Cu" "F.Mask" "F.Paste")
			(net "P3E_CPU0_PE2_SS_TXP<5>")
		)
		(pad "CK5" smd circle
			(at -33.816544 9.072372)
			(size 0.4318 0.4318)
			(layers "F.Cu" "F.Mask" "F.Paste")
			(net "PVCCIO_CPU0")
		)
		(pad "CK7" smd circle
			(at -32.099504 9.072372)
			(size 0.4318 0.4318)
			(layers "F.Cu" "F.Mask" "F.Paste")
			(net "P3E_CPU0_PE2_SS_RXN<4>")
		)
		(pad "CK9" smd circle
			(at -30.382464 9.072372)
			(size 0.4318 0.4318)
			(layers "F.Cu" "F.Mask" "F.Paste")
			(net "DMI_CPU0_PCH_RX_C_DN<0>")
		)
		(pad "CK11" smd circle
			(at -28.665424 9.072372)
			(size 0.4318 0.4318)
			(layers "F.Cu" "F.Mask" "F.Paste")
			(net "GND")
		)
		(pad "CK13" smd circle
			(at -26.948384 9.072372)
			(size 0.4318 0.4318)
			(layers "F.Cu" "F.Mask" "F.Paste")
			(net "TP_CPU0_UPI2_RSVD_DF17")
		)
		(pad "CK15" smd circle
			(at -25.231598 9.072372)
			(size 0.4318 0.4318)
			(layers "F.Cu" "F.Mask" "F.Paste")
			(net "GND")
		)
		(pad "CK17" smd circle
			(at -23.514558 9.072372)
			(size 0.4318 0.4318)
			(layers "F.Cu" "F.Mask" "F.Paste")
			(net "GND")
		)
		(pad "CK19" smd circle
			(at -21.797518 9.072372)
			(size 0.4318 0.4318)
			(layers "F.Cu" "F.Mask" "F.Paste")
			(net "TP_CPU0_RSVD_85")
		)
		(pad "CK21" smd circle
			(at -20.080478 9.072372)
			(size 0.4318 0.4318)
			(layers "F.Cu" "F.Mask" "F.Paste")
			(net "GND")
		)
		(pad "CK23" smd circle
			(at -18.363438 9.072372)
			(size 0.4318 0.4318)
			(layers "F.Cu" "F.Mask" "F.Paste")
			(net "PVCCMCP_CPU0")
		)
		(pad "CK25" smd circle
			(at -16.646398 9.072372)
			(size 0.4318 0.4318)
			(layers "F.Cu" "F.Mask" "F.Paste")
			(net "PVCCMCP_CPU0")
		)
		(pad "CK27" smd circle
			(at -14.929612 9.072372)
			(size 0.4318 0.4318)
			(layers "F.Cu" "F.Mask" "F.Paste")
			(net "GND")
		)
		(pad "CK29" smd circle
			(at -13.212572 9.072372)
			(size 0.4318 0.4318)
			(layers "F.Cu" "F.Mask" "F.Paste")
			(net "A_CPU0_UPI2_RBIAS")
		)
		(pad "CK59" smd circle
			(at 14.071092 7.272274)
			(size 0.508 0.508)
			(layers "F.Cu" "F.Mask" "F.Paste")
			(net "PVCCIN_CPU0")
		)
		(pad "CK61" smd circle
			(at 15.787878 7.272274)
			(size 0.4318 0.4318)
			(layers "F.Cu" "F.Mask" "F.Paste")
			(net "PVCCIN_CPU0")
		)
		(pad "CK63" smd circle
			(at 17.504918 7.272274)
			(size 0.4318 0.4318)
			(layers "F.Cu" "F.Mask" "F.Paste")
			(net "GND")
		)
		(pad "CK65" smd circle
			(at 19.221958 7.272274)
			(size 0.4318 0.4318)
			(layers "F.Cu" "F.Mask" "F.Paste")
			(net "GND")
		)
		(pad "CK67" smd circle
			(at 20.938998 7.272274)
			(size 0.4318 0.4318)
			(layers "F.Cu" "F.Mask" "F.Paste")
			(net "GND")
		)
		(pad "CK69" smd circle
			(at 22.656038 7.272274)
			(size 0.4318 0.4318)
			(layers "F.Cu" "F.Mask" "F.Paste")
			(net "GND")
		)
		(pad "CK71" smd circle
			(at 24.373078 7.272274)
			(size 0.4318 0.4318)
			(layers "F.Cu" "F.Mask" "F.Paste")
			(net "GND")
		)
		(pad "CK73" smd circle
			(at 26.090118 7.272274)
			(size 0.4318 0.4318)
			(layers "F.Cu" "F.Mask" "F.Paste")
			(net "GND")
		)
		(pad "CK75" smd circle
			(at 27.806904 7.272274)
			(size 0.4318 0.4318)
			(layers "F.Cu" "F.Mask" "F.Paste")
			(net "GND")
		)
		(pad "CK77" smd circle
			(at 29.523944 7.272274)
			(size 0.4318 0.4318)
			(layers "F.Cu" "F.Mask" "F.Paste")
			(net "TP_CPU0_RSVD_82")
		)
		(pad "CK79" smd circle
			(at 31.240984 7.272274)
			(size 0.4318 0.4318)
			(layers "F.Cu" "F.Mask" "F.Paste")
			(net "M_E_DQ<4>")
		)
		(pad "CK81" smd circle
			(at 32.958024 7.272274)
			(size 0.4318 0.4318)
			(layers "F.Cu" "F.Mask" "F.Paste")
			(net "M_E_DQ<1>")
		)
		(pad "CK83" smd circle
			(at 34.675064 7.272274)
			(size 0.4318 0.4318)
			(layers "F.Cu" "F.Mask" "F.Paste")
			(net "GND")
		)
		(pad "CK85" smd circle
			(at 36.392104 7.272274)
			(size 0.4318 0.4318)
			(layers "F.Cu" "F.Mask" "F.Paste")
			(net "GND")
		)
		(pad "CL2" smd circle
			(at -36.392104 9.567926)
			(size 0.4318 0.4318)
			(layers "F.Cu" "F.Mask" "F.Paste")
			(net "P3E_CPU0_PE2_SS_TXN<5>")
		)
		(pad "CL4" smd circle
			(at -34.675064 9.567926)
			(size 0.4318 0.4318)
			(layers "F.Cu" "F.Mask" "F.Paste")
			(net "DMI_CPU0_PCH_TX_DP<1>")
		)
		(pad "CL6" smd circle
			(at -32.958024 9.567926)
			(size 0.4318 0.4318)
			(layers "F.Cu" "F.Mask" "F.Paste")
			(net "P3E_CPU0_PE2_SS_RXP<3>")
		)
		(pad "CL8" smd circle
			(at -31.240984 9.567926)
			(size 0.4318 0.4318)
			(layers "F.Cu" "F.Mask" "F.Paste")
			(net "GND")
		)
		(pad "CL10" smd circle
			(at -29.523944 9.567926)
			(size 0.4318 0.4318)
			(layers "F.Cu" "F.Mask" "F.Paste")
			(net "DMI_CPU0_PCH_RX_C_DP<0>")
		)
		(pad "CL12" smd circle
			(at -27.806904 9.567926)
			(size 0.4318 0.4318)
			(layers "F.Cu" "F.Mask" "F.Paste")
			(net "PVCCIO_CPU0")
		)
		(pad "CL14" smd circle
			(at -26.090118 9.567926)
			(size 0.4318 0.4318)
			(layers "F.Cu" "F.Mask" "F.Paste")
			(net "GND")
		)
		(pad "CL16" smd circle
			(at -24.373078 9.567926)
			(size 0.4318 0.4318)
			(layers "F.Cu" "F.Mask" "F.Paste")
			(net "GND")
		)
		(pad "CL18" smd circle
			(at -22.656038 9.567926)
			(size 0.4318 0.4318)
			(layers "F.Cu" "F.Mask" "F.Paste")
			(net "GND")
		)
		(pad "CL20" smd circle
			(at -20.938998 9.567926)
			(size 0.4318 0.4318)
			(layers "F.Cu" "F.Mask" "F.Paste")
			(net "PVCCIO_CPU0")
		)
		(pad "CL22" smd circle
			(at -19.221958 9.567926)
			(size 0.4318 0.4318)
			(layers "F.Cu" "F.Mask" "F.Paste")
			(net "GND")
		)
		(pad "CL24" smd circle
			(at -17.504918 9.567926)
			(size 0.4318 0.4318)
			(layers "F.Cu" "F.Mask" "F.Paste")
			(net "PVCCMCP_CPU0")
		)
		(pad "CL26" smd circle
			(at -15.787878 9.567926)
			(size 0.4318 0.4318)
			(layers "F.Cu" "F.Mask" "F.Paste")
			(net "PVCCMCP_CPU0")
		)
		(pad "CL28" smd circle
			(at -14.071092 9.567926)
			(size 0.4318 0.4318)
			(layers "F.Cu" "F.Mask" "F.Paste")
			(net "A_CPU0_UPI2_RBIAS")
		)
		(pad "CL30" smd circle
			(at -12.354052 9.567926)
			(size 0.4318 0.4318)
			(layers "F.Cu" "F.Mask" "F.Paste")
			(net "A_CPU0_PE012_RBIAS")
		)
		(pad "CL58" smd circle
			(at 13.212572 7.767828)
			(size 0.508 0.508)
			(layers "F.Cu" "F.Mask" "F.Paste")
			(net "PVCCIN_CPU0")
		)
		(pad "CL60" smd circle
			(at 14.929612 7.767828)
			(size 0.4318 0.4318)
			(layers "F.Cu" "F.Mask" "F.Paste")
			(net "PVCCIN_CPU0")
		)
		(pad "CL62" smd circle
			(at 16.646398 7.767828)
			(size 0.4318 0.4318)
			(layers "F.Cu" "F.Mask" "F.Paste")
			(net "GND")
		)
		(pad "CL64" smd circle
			(at 18.363438 7.767828)
			(size 0.4318 0.4318)
			(layers "F.Cu" "F.Mask" "F.Paste")
			(net "GND")
		)
		(pad "CL66" smd circle
			(at 20.080478 7.767828)
			(size 0.4318 0.4318)
			(layers "F.Cu" "F.Mask" "F.Paste")
			(net "GND")
		)
		(pad "CL68" smd circle
			(at 21.797518 7.767828)
			(size 0.4318 0.4318)
			(layers "F.Cu" "F.Mask" "F.Paste")
			(net "M_F_ECC<3>")
		)
		(pad "CL70" smd circle
			(at 23.514558 7.767828)
			(size 0.4318 0.4318)
			(layers "F.Cu" "F.Mask" "F.Paste")
			(net "M_F_DQS_DP<8>")
		)
		(pad "CL72" smd circle
			(at 25.231598 7.767828)
			(size 0.4318 0.4318)
			(layers "F.Cu" "F.Mask" "F.Paste")
			(net "M_F_ECC<5>")
		)
		(pad "CL74" smd circle
			(at 26.948384 7.767828)
			(size 0.4318 0.4318)
			(layers "F.Cu" "F.Mask" "F.Paste")
			(net "GND")
		)
		(pad "CL76" smd circle
			(at 28.665424 7.767828)
			(size 0.4318 0.4318)
			(layers "F.Cu" "F.Mask" "F.Paste")
			(net "GND")
		)
		(pad "CL78" smd circle
			(at 30.382464 7.767828)
			(size 0.4318 0.4318)
			(layers "F.Cu" "F.Mask" "F.Paste")
			(net "GND")
		)
		(pad "CL80" smd circle
			(at 32.099504 7.767828)
			(size 0.4318 0.4318)
			(layers "F.Cu" "F.Mask" "F.Paste")
			(net "GND")
		)
		(pad "CL82" smd circle
			(at 33.816544 7.767828)
			(size 0.4318 0.4318)
			(layers "F.Cu" "F.Mask" "F.Paste")
			(net "M_E_DQS_DN<0>")
		)
		(pad "CL84" smd circle
			(at 35.533584 7.767828)
			(size 0.4318 0.4318)
			(layers "F.Cu" "F.Mask" "F.Paste")
			(net "M_D_DQ<4>")
		)
		(pad "CL86" smd custom
			(at 37.250624 7.767828 270)
			(size 0.10795 0.10795)
			(layers "F.Cu" "F.Mask" "F.Paste")
			(net "M_D_DQ<5>")
			(options
				(clearance outline)
				(anchor circle)
			)
			(primitives
				(gr_poly
					(pts
						(arc
							(start 0.2159 -0.0381)
							(mid 0 -0.254)
							(end -0.2159 -0.0381)
						)
						(arc
							(start -0.2159 0.0381)
							(mid 0 0.254)
							(end 0.2159 0.0381)
						)
					)
					(width 0)
					(fill yes)
				)
			)
		)
		(pad "CM1" smd custom
			(at -37.250624 10.062972 90)
			(size 0.10795 0.10795)
			(layers "F.Cu" "F.Mask" "F.Paste")
			(net "P3E_CPU0_PE2_SS_TXN<4>")
			(options
				(clearance outline)
				(anchor circle)
			)
			(primitives
				(gr_poly
					(pts
						(arc
							(start 0.2159 -0.0381)
							(mid 0 -0.254)
							(end -0.2159 -0.0381)
						)
						(arc
							(start -0.2159 0.0381)
							(mid 0 0.254)
							(end 0.2159 0.0381)
						)
					)
					(width 0)
					(fill yes)
				)
			)
		)
		(pad "CM3" smd circle
			(at -35.533584 10.062972)
			(size 0.4318 0.4318)
			(layers "F.Cu" "F.Mask" "F.Paste")
			(net "DMI_CPU0_PCH_TX_DP<2>")
		)
		(pad "CM5" smd circle
			(at -33.816544 10.062972)
			(size 0.4318 0.4318)
			(layers "F.Cu" "F.Mask" "F.Paste")
			(net "GND")
		)
		(pad "CM7" smd circle
			(at -32.099504 10.062972)
			(size 0.4318 0.4318)
			(layers "F.Cu" "F.Mask" "F.Paste")
			(net "P3E_CPU0_PE2_SS_RXN<3>")
		)
		(pad "CM9" smd circle
			(at -30.382464 10.062972)
			(size 0.4318 0.4318)
			(layers "F.Cu" "F.Mask" "F.Paste")
			(net "P3E_CPU0_PE2_SS_RXP<1>")
		)
		(pad "CM11" smd circle
			(at -28.665424 10.062972)
			(size 0.4318 0.4318)
			(layers "F.Cu" "F.Mask" "F.Paste")
			(net "DMI_CPU0_PCH_RX_C_DN<1>")
		)
		(pad "CM13" smd circle
			(at -26.948384 10.062972)
			(size 0.4318 0.4318)
			(layers "F.Cu" "F.Mask" "F.Paste")
			(net "TP_CPU0_UPI2_RSVD_DG18")
		)
		(pad "CM15" smd circle
			(at -25.231598 10.062972)
			(size 0.4318 0.4318)
			(layers "F.Cu" "F.Mask" "F.Paste")
			(net "PVCCIO_CPU0")
		)
		(pad "CM19" smd circle
			(at -21.797518 10.062972)
			(size 0.4318 0.4318)
			(layers "F.Cu" "F.Mask" "F.Paste")
			(net "GND")
		)
		(pad "CM21" smd circle
			(at -20.080478 10.062972)
			(size 0.4318 0.4318)
			(layers "F.Cu" "F.Mask" "F.Paste")
			(net "GND")
		)
		(pad "CM23" smd circle
			(at -18.363438 10.062972)
			(size 0.4318 0.4318)
			(layers "F.Cu" "F.Mask" "F.Paste")
			(net "PVCCMCP_CPU0")
		)
		(pad "CM25" smd circle
			(at -16.646398 10.062972)
			(size 0.4318 0.4318)
			(layers "F.Cu" "F.Mask" "F.Paste")
			(net "PVCCMCP_CPU0")
		)
		(pad "CM27" smd circle
			(at -14.929612 10.062972)
			(size 0.4318 0.4318)
			(layers "F.Cu" "F.Mask" "F.Paste")
			(net "GND")
		)
		(pad "CM29" smd circle
			(at -13.212572 10.062972)
			(size 0.4318 0.4318)
			(layers "F.Cu" "F.Mask" "F.Paste")
			(net "GND")
		)
		(pad "CM31" smd circle
			(at -11.495532 10.062972)
			(size 0.4318 0.4318)
			(layers "F.Cu" "F.Mask" "F.Paste")
			(net "GND")
		)
		(pad "CM57" smd circle
			(at 12.354052 8.262874)
			(size 0.508 0.508)
			(layers "F.Cu" "F.Mask" "F.Paste")
			(net "PVCCIN_CPU0")
		)
		(pad "CM59" smd circle
			(at 14.071092 8.262874)
			(size 0.4318 0.4318)
			(layers "F.Cu" "F.Mask" "F.Paste")
			(net "PVCCIN_CPU0")
		)
		(pad "CM61" smd circle
			(at 15.787878 8.262874)
			(size 0.4318 0.4318)
			(layers "F.Cu" "F.Mask" "F.Paste")
			(net "GND")
		)
		(pad "CM63" smd circle
			(at 17.504918 8.262874)
			(size 0.4318 0.4318)
			(layers "F.Cu" "F.Mask" "F.Paste")
			(net "GND")
		)
		(pad "CM65" smd circle
			(at 19.221958 8.262874)
			(size 0.4318 0.4318)
			(layers "F.Cu" "F.Mask" "F.Paste")
			(net "M_F_DQS_DP<12>")
		)
		(pad "CM67" smd circle
			(at 20.938998 8.262874)
			(size 0.4318 0.4318)
			(layers "F.Cu" "F.Mask" "F.Paste")
			(net "GND")
		)
		(pad "CM69" smd circle
			(at 22.656038 8.262874)
			(size 0.4318 0.4318)
			(layers "F.Cu" "F.Mask" "F.Paste")
			(net "M_F_ECC<7>")
		)
		(pad "CM71" smd circle
			(at 24.373078 8.262874)
			(size 0.4318 0.4318)
			(layers "F.Cu" "F.Mask" "F.Paste")
			(net "M_F_ECC<1>")
		)
		(pad "CM73" smd circle
			(at 26.090118 8.262874)
			(size 0.4318 0.4318)
			(layers "F.Cu" "F.Mask" "F.Paste")
			(net "GND")
		)
		(pad "CM75" smd circle
			(at 27.806904 8.262874)
			(size 0.4318 0.4318)
			(layers "F.Cu" "F.Mask" "F.Paste")
			(net "M_F_DQ<5>")
		)
		(pad "CM77" smd circle
			(at 29.523944 8.262874)
			(size 0.4318 0.4318)
			(layers "F.Cu" "F.Mask" "F.Paste")
			(net "GND")
		)
		(pad "CM79" smd circle
			(at 31.240984 8.262874)
			(size 0.4318 0.4318)
			(layers "F.Cu" "F.Mask" "F.Paste")
			(net "M_E_DQ<0>")
		)
		(pad "CM81" smd circle
			(at 32.958024 8.262874)
			(size 0.4318 0.4318)
			(layers "F.Cu" "F.Mask" "F.Paste")
			(net "M_E_DQS_DP<0>")
		)
		(pad "CM83" smd circle
			(at 34.675064 8.262874)
			(size 0.4318 0.4318)
			(layers "F.Cu" "F.Mask" "F.Paste")
			(net "GND")
		)
		(pad "CM85" smd circle
			(at 36.392104 8.262874)
			(size 0.4318 0.4318)
			(layers "F.Cu" "F.Mask" "F.Paste")
			(net "GND")
		)
		(pad "CN2" smd circle
			(at -36.392104 10.558526)
			(size 0.4318 0.4318)
			(layers "F.Cu" "F.Mask" "F.Paste")
			(net "GND")
		)
		(pad "CN4" smd circle
			(at -34.675064 10.558526)
			(size 0.4318 0.4318)
			(layers "F.Cu" "F.Mask" "F.Paste")
			(net "DMI_CPU0_PCH_TX_DN<2>")
		)
		(pad "CN6" smd circle
			(at -32.958024 10.558526)
			(size 0.4318 0.4318)
			(layers "F.Cu" "F.Mask" "F.Paste")
			(net "PVCCIO_CPU0")
		)
		(pad "CN8" smd circle
			(at -31.240984 10.558526)
			(size 0.4318 0.4318)
			(layers "F.Cu" "F.Mask" "F.Paste")
			(net "P3E_CPU0_PE2_SS_RXP<2>")
		)
		(pad "CN10" smd circle
			(at -29.523944 10.558526)
			(size 0.4318 0.4318)
			(layers "F.Cu" "F.Mask" "F.Paste")
			(net "DMI_CPU0_PCH_RX_C_DP<1>")
		)
		(pad "CN12" smd circle
			(at -27.806904 10.558526)
			(size 0.4318 0.4318)
			(layers "F.Cu" "F.Mask" "F.Paste")
			(net "GND")
		)
		(pad "CN14" smd circle
			(at -26.090118 10.558526)
			(size 0.4318 0.4318)
			(layers "F.Cu" "F.Mask" "F.Paste")
			(net "GND")
		)
		(pad "CN18" smd circle
			(at -22.656038 10.558526)
			(size 0.4318 0.4318)
			(layers "F.Cu" "F.Mask" "F.Paste")
			(net "GND")
		)
		(pad "CN20" smd circle
			(at -20.938998 10.558526)
			(size 0.4318 0.4318)
			(layers "F.Cu" "F.Mask" "F.Paste")
			(net "GND")
		)
		(pad "CN22" smd circle
			(at -19.221958 10.558526)
			(size 0.4318 0.4318)
			(layers "F.Cu" "F.Mask" "F.Paste")
			(net "TP_CPU0_KTI2_AMONV")
		)
		(pad "CN24" smd circle
			(at -17.504918 10.558526)
			(size 0.4318 0.4318)
			(layers "F.Cu" "F.Mask" "F.Paste")
			(net "PVCCMCP_CPU0")
		)
		(pad "CN26" smd circle
			(at -15.787878 10.558526)
			(size 0.4318 0.4318)
			(layers "F.Cu" "F.Mask" "F.Paste")
			(net "GND")
		)
		(pad "CN28" smd circle
			(at -14.071092 10.558526)
			(size 0.4318 0.4318)
			(layers "F.Cu" "F.Mask" "F.Paste")
			(net "PD_CPU0_MCP01_DMON")
		)
		(pad "CN30" smd circle
			(at -12.354052 10.558526)
			(size 0.4318 0.4318)
			(layers "F.Cu" "F.Mask" "F.Paste")
			(net "A_CPU0_PE012_RBIAS")
		)
		(pad "CN32" smd circle
			(at -10.637012 10.558526)
			(size 0.4318 0.4318)
			(layers "F.Cu" "F.Mask" "F.Paste")
			(net "GND")
		)
		(pad "CN56" smd circle
			(at 11.495532 8.758428)
			(size 0.508 0.508)
			(layers "F.Cu" "F.Mask" "F.Paste")
			(net "PVCCIN_CPU0")
		)
		(pad "CN58" smd circle
			(at 13.212572 8.758428)
			(size 0.4318 0.4318)
			(layers "F.Cu" "F.Mask" "F.Paste")
			(net "PVCCIN_CPU0")
		)
		(pad "CN60" smd circle
			(at 14.929612 8.758428)
			(size 0.4318 0.4318)
			(layers "F.Cu" "F.Mask" "F.Paste")
			(net "GND")
		)
		(pad "CN62" smd circle
			(at 16.646398 8.758428)
			(size 0.4318 0.4318)
			(layers "F.Cu" "F.Mask" "F.Paste")
			(net "GND")
		)
		(pad "CN64" smd circle
			(at 18.363438 8.758428)
			(size 0.4318 0.4318)
			(layers "F.Cu" "F.Mask" "F.Paste")
			(net "M_F_DQ<30>")
		)
		(pad "CN66" smd circle
			(at 20.080478 8.758428)
			(size 0.4318 0.4318)
			(layers "F.Cu" "F.Mask" "F.Paste")
			(net "M_F_DQ<24>")
		)
		(pad "CN68" smd circle
			(at 21.797518 8.758428)
			(size 0.4318 0.4318)
			(layers "F.Cu" "F.Mask" "F.Paste")
			(net "GND")
		)
		(pad "CN70" smd circle
			(at 23.514558 8.758428)
			(size 0.4318 0.4318)
			(layers "F.Cu" "F.Mask" "F.Paste")
			(net "M_F_DQS_DN<8>")
		)
		(pad "CN74" smd circle
			(at 26.948384 8.758428)
			(size 0.4318 0.4318)
			(layers "F.Cu" "F.Mask" "F.Paste")
			(net "M_F_DQ<4>")
		)
		(pad "CN76" smd circle
			(at 28.665424 8.758428)
			(size 0.4318 0.4318)
			(layers "F.Cu" "F.Mask" "F.Paste")
			(net "M_F_DQ<1>")
		)
		(pad "CN78" smd circle
			(at 30.382464 8.758428)
			(size 0.4318 0.4318)
			(layers "F.Cu" "F.Mask" "F.Paste")
			(net "GND")
		)
		(pad "CN80" smd circle
			(at 32.099504 8.758428)
			(size 0.4318 0.4318)
			(layers "F.Cu" "F.Mask" "F.Paste")
			(net "M_E_DQS_DN<9>")
		)
		(pad "CN82" smd circle
			(at 33.816544 8.758428)
			(size 0.4318 0.4318)
			(layers "F.Cu" "F.Mask" "F.Paste")
			(net "M_E_DQ<7>")
		)
		(pad "CN84" smd circle
			(at 35.533584 8.758428)
			(size 0.4318 0.4318)
			(layers "F.Cu" "F.Mask" "F.Paste")
			(net "M_D_DQ<0>")
		)
		(pad "CN86" smd custom
			(at 37.250624 8.758428 270)
			(size 0.10795 0.10795)
			(layers "F.Cu" "F.Mask" "F.Paste")
			(net "M_D_DQ<1>")
			(options
				(clearance outline)
				(anchor circle)
			)
			(primitives
				(gr_poly
					(pts
						(arc
							(start 0.2159 -0.0381)
							(mid 0 -0.254)
							(end -0.2159 -0.0381)
						)
						(arc
							(start -0.2159 0.0381)
							(mid 0 0.254)
							(end 0.2159 0.0381)
						)
					)
					(width 0)
					(fill yes)
				)
			)
		)
		(pad "CP1" smd custom
			(at -37.250624 11.053572 90)
			(size 0.10795 0.10795)
			(layers "F.Cu" "F.Mask" "F.Paste")
			(net "GND")
			(options
				(clearance outline)
				(anchor circle)
			)
			(primitives
				(gr_poly
					(pts
						(arc
							(start 0.2159 -0.0381)
							(mid 0 -0.254)
							(end -0.2159 -0.0381)
						)
						(arc
							(start -0.2159 0.0381)
							(mid 0 0.254)
							(end 0.2159 0.0381)
						)
					)
					(width 0)
					(fill yes)
				)
			)
		)
		(pad "CP3" smd circle
			(at -35.533584 11.053572)
			(size 0.4318 0.4318)
			(layers "F.Cu" "F.Mask" "F.Paste")
			(net "P3E_CPU0_PE2_SS_TXP<3>")
		)
		(pad "CP5" smd circle
			(at -33.816544 11.053572)
			(size 0.4318 0.4318)
			(layers "F.Cu" "F.Mask" "F.Paste")
			(net "DMI_CPU0_PCH_TX_DN<3>")
		)
		(pad "CP7" smd circle
			(at -32.099504 11.053572)
			(size 0.4318 0.4318)
			(layers "F.Cu" "F.Mask" "F.Paste")
			(net "P3E_CPU0_PE2_SS_RXN<2>")
		)
		(pad "CP9" smd circle
			(at -30.382464 11.053572)
			(size 0.4318 0.4318)
			(layers "F.Cu" "F.Mask" "F.Paste")
			(net "P3E_CPU0_PE2_SS_RXN<1>")
		)
		(pad "CP11" smd circle
			(at -28.665424 11.053572)
			(size 0.4318 0.4318)
			(layers "F.Cu" "F.Mask" "F.Paste")
			(net "DMI_CPU0_PCH_RX_C_DP<2>")
		)
		(pad "CP13" smd circle
			(at -26.948384 11.053572)
			(size 0.4318 0.4318)
			(layers "F.Cu" "F.Mask" "F.Paste")
			(net "PVCCIO_CPU0")
		)
		(pad "CP19" smd circle
			(at -21.797518 11.053572)
			(size 0.4318 0.4318)
			(layers "F.Cu" "F.Mask" "F.Paste")
			(net "GND")
		)
		(pad "CP21" smd circle
			(at -20.080478 11.053572)
			(size 0.4318 0.4318)
			(layers "F.Cu" "F.Mask" "F.Paste")
			(net "GND")
		)
		(pad "CP23" smd circle
			(at -18.363438 11.053572)
			(size 0.4318 0.4318)
			(layers "F.Cu" "F.Mask" "F.Paste")
			(net "PVCCMCP_CPU0")
		)
		(pad "CP25" smd circle
			(at -16.646398 11.053572)
			(size 0.4318 0.4318)
			(layers "F.Cu" "F.Mask" "F.Paste")
			(net "GND")
		)
		(pad "CP27" smd circle
			(at -14.929612 11.053572)
			(size 0.4318 0.4318)
			(layers "F.Cu" "F.Mask" "F.Paste")
			(net "CLK_100M_CPU0_BCLK1_DP")
		)
		(pad "CP29" smd circle
			(at -13.212572 11.053572)
			(size 0.4318 0.4318)
			(layers "F.Cu" "F.Mask" "F.Paste")
			(net "A_CPU0_PE3_RBIAS")
		)
		(pad "CP31" smd circle
			(at -11.495532 11.053572)
			(size 0.4318 0.4318)
			(layers "F.Cu" "F.Mask" "F.Paste")
			(net "TP_CPU0_RSVD_73")
		)
		(pad "CP33" smd circle
			(at -9.778492 11.053572)
			(size 0.4318 0.4318)
			(layers "F.Cu" "F.Mask" "F.Paste")
			(net "PVCCIN_CPU0")
		)
		(pad "CP55" smd circle
			(at 10.637012 9.253474)
			(size 0.508 0.508)
			(layers "F.Cu" "F.Mask" "F.Paste")
			(net "PVCCIN_CPU0")
		)
		(pad "CP57" smd circle
			(at 12.354052 9.253474)
			(size 0.4318 0.4318)
			(layers "F.Cu" "F.Mask" "F.Paste")
			(net "PVCCIN_CPU0")
		)
		(pad "CP59" smd circle
			(at 14.071092 9.253474)
			(size 0.4318 0.4318)
			(layers "F.Cu" "F.Mask" "F.Paste")
			(net "GND")
		)
		(pad "CP61" smd circle
			(at 15.787878 9.253474)
			(size 0.4318 0.4318)
			(layers "F.Cu" "F.Mask" "F.Paste")
			(net "M_D_CPU_VREF")
		)
		(pad "CP63" smd circle
			(at 17.504918 9.253474)
			(size 0.4318 0.4318)
			(layers "F.Cu" "F.Mask" "F.Paste")
			(net "M_F_DQ<26>")
		)
		(pad "CP65" smd circle
			(at 19.221958 9.253474)
			(size 0.4318 0.4318)
			(layers "F.Cu" "F.Mask" "F.Paste")
			(net "M_F_DQS_DN<12>")
		)
		(pad "CP67" smd circle
			(at 20.938998 9.253474)
			(size 0.4318 0.4318)
			(layers "F.Cu" "F.Mask" "F.Paste")
			(net "M_F_DQ<28>")
		)
		(pad "CP69" smd circle
			(at 22.656038 9.253474)
			(size 0.4318 0.4318)
			(layers "F.Cu" "F.Mask" "F.Paste")
			(net "GND")
		)
		(pad "CP73" smd circle
			(at 26.090118 9.253474)
			(size 0.4318 0.4318)
			(layers "F.Cu" "F.Mask" "F.Paste")
			(net "GND")
		)
		(pad "CP75" smd circle
			(at 27.806904 9.253474)
			(size 0.4318 0.4318)
			(layers "F.Cu" "F.Mask" "F.Paste")
			(net "GND")
		)
		(pad "CP77" smd circle
			(at 29.523944 9.253474)
			(size 0.4318 0.4318)
			(layers "F.Cu" "F.Mask" "F.Paste")
			(net "M_F_DQS_DN<0>")
		)
		(pad "CP79" smd circle
			(at 31.240984 9.253474)
			(size 0.4318 0.4318)
			(layers "F.Cu" "F.Mask" "F.Paste")
			(net "M_E_DQS_DP<9>")
		)
		(pad "CP81" smd circle
			(at 32.958024 9.253474)
			(size 0.4318 0.4318)
			(layers "F.Cu" "F.Mask" "F.Paste")
			(net "GND")
		)
		(pad "CP83" smd circle
			(at 34.675064 9.253474)
			(size 0.4318 0.4318)
			(layers "F.Cu" "F.Mask" "F.Paste")
			(net "GND")
		)
		(pad "CP85" smd circle
			(at 36.392104 9.253474)
			(size 0.4318 0.4318)
			(layers "F.Cu" "F.Mask" "F.Paste")
			(net "M_D_DQS_DP<9>")
		)
		(pad "CR2" smd circle
			(at -36.392104 11.549126)
			(size 0.4318 0.4318)
			(layers "F.Cu" "F.Mask" "F.Paste")
			(net "P3E_CPU0_PE2_SS_TXP<2>")
		)
		(pad "CR4" smd circle
			(at -34.675064 11.549126)
			(size 0.4318 0.4318)
			(layers "F.Cu" "F.Mask" "F.Paste")
			(net "DMI_CPU0_PCH_TX_DP<3>")
		)
		(pad "CR6" smd circle
			(at -32.958024 11.549126)
			(size 0.4318 0.4318)
			(layers "F.Cu" "F.Mask" "F.Paste")
			(net "GND")
		)
		(pad "CR8" smd circle
			(at -31.240984 11.549126)
			(size 0.4318 0.4318)
			(layers "F.Cu" "F.Mask" "F.Paste")
			(net "P3E_CPU0_PE2_SS_RXP<0>")
		)
		(pad "CR10" smd circle
			(at -29.523944 11.549126)
			(size 0.4318 0.4318)
			(layers "F.Cu" "F.Mask" "F.Paste")
			(net "GND")
		)
		(pad "CR12" smd circle
			(at -27.806904 11.549126)
			(size 0.4318 0.4318)
			(layers "F.Cu" "F.Mask" "F.Paste")
			(net "DMI_CPU0_PCH_RX_C_DN<2>")
		)
		(pad "CR14" smd circle
			(at -26.090118 11.549126)
			(size 0.4318 0.4318)
			(layers "F.Cu" "F.Mask" "F.Paste")
			(net "TP_CPU0_UPI2_RSVD_DE16")
		)
		(pad "CR18" smd circle
			(at -22.656038 11.549126)
			(size 0.4318 0.4318)
			(layers "F.Cu" "F.Mask" "F.Paste")
			(net "GND")
		)
		(pad "CR20" smd circle
			(at -20.938998 11.549126)
			(size 0.4318 0.4318)
			(layers "F.Cu" "F.Mask" "F.Paste")
			(net "GND")
		)
		(pad "CR22" smd circle
			(at -19.221958 11.549126)
			(size 0.4318 0.4318)
			(layers "F.Cu" "F.Mask" "F.Paste")
			(net "GND")
		)
		(pad "CR24" smd circle
			(at -17.504918 11.549126)
			(size 0.4318 0.4318)
			(layers "F.Cu" "F.Mask" "F.Paste")
			(net "GND")
		)
		(pad "CR26" smd circle
			(at -15.787878 11.549126)
			(size 0.4318 0.4318)
			(layers "F.Cu" "F.Mask" "F.Paste")
			(net "CLK_100M_CPU0_BCLK1_DN")
		)
		(pad "CR28" smd circle
			(at -14.071092 11.549126)
			(size 0.4318 0.4318)
			(layers "F.Cu" "F.Mask" "F.Paste")
			(net "PWRGD_CPU0_DRAMPWROK_DEF_G")
		)
		(pad "CR30" smd circle
			(at -12.354052 11.549126)
			(size 0.4318 0.4318)
			(layers "F.Cu" "F.Mask" "F.Paste")
			(net "A_CPU0_PE3_RBIAS")
		)
		(pad "CR32" smd circle
			(at -10.637012 11.549126)
			(size 0.4318 0.4318)
			(layers "F.Cu" "F.Mask" "F.Paste")
			(net "GND")
		)
		(pad "CR34" smd circle
			(at -8.919972 11.549126)
			(size 0.4318 0.4318)
			(layers "F.Cu" "F.Mask" "F.Paste")
			(net "PVCCIN_CPU0")
		)
		(pad "CR54" smd circle
			(at 9.778492 9.749028)
			(size 0.508 0.508)
			(layers "F.Cu" "F.Mask" "F.Paste")
			(net "PVCCIN_CPU0")
		)
		(pad "CR56" smd circle
			(at 11.495532 9.749028)
			(size 0.4318 0.4318)
			(layers "F.Cu" "F.Mask" "F.Paste")
			(net "PVCCIN_CPU0")
		)
		(pad "CR58" smd circle
			(at 13.212572 9.749028)
			(size 0.4318 0.4318)
			(layers "F.Cu" "F.Mask" "F.Paste")
			(net "GND")
		)
		(pad "CR60" smd circle
			(at 14.929612 9.749028)
			(size 0.4318 0.4318)
			(layers "F.Cu" "F.Mask" "F.Paste")
			(net "TP_CPU0_RSVD_72")
		)
		(pad "CR62" smd circle
			(at 16.646398 9.749028)
			(size 0.4318 0.4318)
			(layers "F.Cu" "F.Mask" "F.Paste")
			(net "GND")
		)
		(pad "CR64" smd circle
			(at 18.363438 9.749028)
			(size 0.4318 0.4318)
			(layers "F.Cu" "F.Mask" "F.Paste")
			(net "GND")
		)
		(pad "CR66" smd circle
			(at 20.080478 9.749028)
			(size 0.4318 0.4318)
			(layers "F.Cu" "F.Mask" "F.Paste")
			(net "GND")
		)
		(pad "CR68" smd circle
			(at 21.797518 9.749028)
			(size 0.4318 0.4318)
			(layers "F.Cu" "F.Mask" "F.Paste")
			(net "GND")
		)
		(pad "CR74" smd circle
			(at 26.948384 9.749028)
			(size 0.4318 0.4318)
			(layers "F.Cu" "F.Mask" "F.Paste")
			(net "M_F_DQ<0>")
		)
		(pad "CR76" smd circle
			(at 28.665424 9.749028)
			(size 0.4318 0.4318)
			(layers "F.Cu" "F.Mask" "F.Paste")
			(net "M_F_DQS_DP<0>")
		)
		(pad "CR78" smd circle
			(at 30.382464 9.749028)
			(size 0.4318 0.4318)
			(layers "F.Cu" "F.Mask" "F.Paste")
			(net "GND")
		)
		(pad "CR80" smd circle
			(at 32.099504 9.749028)
			(size 0.4318 0.4318)
			(layers "F.Cu" "F.Mask" "F.Paste")
			(net "M_E_DQ<6>")
		)
		(pad "CR82" smd circle
			(at 33.816544 9.749028)
			(size 0.4318 0.4318)
			(layers "F.Cu" "F.Mask" "F.Paste")
			(net "M_E_DQ<3>")
		)
		(pad "CR84" smd circle
			(at 35.533584 9.749028)
			(size 0.4318 0.4318)
			(layers "F.Cu" "F.Mask" "F.Paste")
			(net "M_D_DQS_DN<9>")
		)
		(pad "CR86" smd custom
			(at 37.250624 9.749028 270)
			(size 0.10795 0.10795)
			(layers "F.Cu" "F.Mask" "F.Paste")
			(net "GND")
			(options
				(clearance outline)
				(anchor circle)
			)
			(primitives
				(gr_poly
					(pts
						(arc
							(start 0.2159 -0.0381)
							(mid 0 -0.254)
							(end -0.2159 -0.0381)
						)
						(arc
							(start -0.2159 0.0381)
							(mid 0 0.254)
							(end 0.2159 0.0381)
						)
					)
					(width 0)
					(fill yes)
				)
			)
		)
		(pad "CT1" smd custom
			(at -37.250624 12.044172 90)
			(size 0.10795 0.10795)
			(layers "F.Cu" "F.Mask" "F.Paste")
			(net "P3E_CPU0_PE2_SS_TXN<2>")
			(options
				(clearance outline)
				(anchor circle)
			)
			(primitives
				(gr_poly
					(pts
						(arc
							(start 0.2159 -0.0381)
							(mid 0 -0.254)
							(end -0.2159 -0.0381)
						)
						(arc
							(start -0.2159 0.0381)
							(mid 0 0.254)
							(end 0.2159 0.0381)
						)
					)
					(width 0)
					(fill yes)
				)
			)
		)
		(pad "CT3" smd circle
			(at -35.533584 12.044172)
			(size 0.4318 0.4318)
			(layers "F.Cu" "F.Mask" "F.Paste")
			(net "P3E_CPU0_PE2_SS_TXN<3>")
		)
		(pad "CT5" smd circle
			(at -33.816544 12.044172)
			(size 0.4318 0.4318)
			(layers "F.Cu" "F.Mask" "F.Paste")
			(net "TP_CPU0_RSVD_70")
		)
		(pad "CT7" smd circle
			(at -32.099504 12.044172)
			(size 0.4318 0.4318)
			(layers "F.Cu" "F.Mask" "F.Paste")
			(net "GND")
		)
		(pad "CT9" smd circle
			(at -30.382464 12.044172)
			(size 0.4318 0.4318)
			(layers "F.Cu" "F.Mask" "F.Paste")
			(net "P3E_CPU0_PE2_SS_RXN<0>")
		)
		(pad "CT11" smd circle
			(at -28.665424 12.044172)
			(size 0.4318 0.4318)
			(layers "F.Cu" "F.Mask" "F.Paste")
			(net "DMI_CPU0_PCH_RX_C_DN<3>")
		)
		(pad "CT13" smd circle
			(at -26.948384 12.044172)
			(size 0.4318 0.4318)
			(layers "F.Cu" "F.Mask" "F.Paste")
			(net "GND")
		)
		(pad "CT19" smd circle
			(at -21.797518 12.044172)
			(size 0.4318 0.4318)
			(layers "F.Cu" "F.Mask" "F.Paste")
			(net "GND")
		)
		(pad "CT21" smd circle
			(at -20.080478 12.044172)
			(size 0.4318 0.4318)
			(layers "F.Cu" "F.Mask" "F.Paste")
			(net "GND")
		)
		(pad "CT23" smd circle
			(at -18.363438 12.044172)
			(size 0.4318 0.4318)
			(layers "F.Cu" "F.Mask" "F.Paste")
			(net "PVCCMCP_CPU0")
		)
		(pad "CT25" smd circle
			(at -16.646398 12.044172)
			(size 0.4318 0.4318)
			(layers "F.Cu" "F.Mask" "F.Paste")
			(net "CLK_100M_CPU0_BCLK2_DN")
		)
		(pad "CT27" smd circle
			(at -14.929612 12.044172)
			(size 0.4318 0.4318)
			(layers "F.Cu" "F.Mask" "F.Paste")
			(net "GND")
		)
		(pad "CT29" smd circle
			(at -13.212572 12.044172)
			(size 0.4318 0.4318)
			(layers "F.Cu" "F.Mask" "F.Paste")
			(net "GND")
		)
		(pad "CT31" smd circle
			(at -11.495532 12.044172)
			(size 0.4318 0.4318)
			(layers "F.Cu" "F.Mask" "F.Paste")
			(net "A_CPU0_MCP01_RBIAS")
		)
		(pad "CT33" smd circle
			(at -9.778492 12.044172)
			(size 0.4318 0.4318)
			(layers "F.Cu" "F.Mask" "F.Paste")
			(net "GND")
		)
		(pad "CT35" smd circle
			(at -8.061452 12.044172)
			(size 0.4318 0.4318)
			(layers "F.Cu" "F.Mask" "F.Paste")
			(net "GND")
		)
		(pad "CT37" smd circle
			(at -6.344412 12.044172)
			(size 0.4318 0.4318)
			(layers "F.Cu" "F.Mask" "F.Paste")
			(net "PVCCIN_CPU0")
		)
		(pad "CT39" smd circle
			(at -4.627626 12.044172)
			(size 0.4318 0.4318)
			(layers "F.Cu" "F.Mask" "F.Paste")
			(net "PVCCIN_CPU0")
		)
		(pad "CT41" smd circle
			(at -2.910586 12.044172)
			(size 0.4318 0.4318)
			(layers "F.Cu" "F.Mask" "F.Paste")
			(net "PVCCIN_CPU0")
		)
		(pad "CT53" smd circle
			(at 8.919972 10.244074)
			(size 0.508 0.508)
			(layers "F.Cu" "F.Mask" "F.Paste")
			(net "PVCCIN_CPU0")
		)
		(pad "CT55" smd circle
			(at 10.637012 10.244074)
			(size 0.4318 0.4318)
			(layers "F.Cu" "F.Mask" "F.Paste")
			(net "PVCCIN_CPU0")
		)
		(pad "CT57" smd circle
			(at 12.354052 10.244074)
			(size 0.4318 0.4318)
			(layers "F.Cu" "F.Mask" "F.Paste")
			(net "GND")
		)
		(pad "CT59" smd circle
			(at 14.071092 10.244074)
			(size 0.4318 0.4318)
			(layers "F.Cu" "F.Mask" "F.Paste")
			(net "SMB_PIROM_CPU0_SCL")
		)
		(pad "CT61" smd circle
			(at 15.787878 10.244074)
			(size 0.4318 0.4318)
			(layers "F.Cu" "F.Mask" "F.Paste")
			(net "M_E_CPU_VREF")
		)
		(pad "CT63" smd circle
			(at 17.504918 10.244074)
			(size 0.4318 0.4318)
			(layers "F.Cu" "F.Mask" "F.Paste")
			(net "M_F_DQ<27>")
		)
		(pad "CT65" smd circle
			(at 19.221958 10.244074)
			(size 0.4318 0.4318)
			(layers "F.Cu" "F.Mask" "F.Paste")
			(net "M_F_DQS_DP<3>")
		)
		(pad "CT67" smd circle
			(at 20.938998 10.244074)
			(size 0.4318 0.4318)
			(layers "F.Cu" "F.Mask" "F.Paste")
			(net "M_F_DQ<29>")
		)
		(pad "CT69" smd circle
			(at 22.656038 10.244074)
			(size 0.4318 0.4318)
			(layers "F.Cu" "F.Mask" "F.Paste")
			(net "TP_CPU0_RSVD_69")
		)
		(pad "CT73" smd circle
			(at 26.090118 10.244074)
			(size 0.4318 0.4318)
			(layers "F.Cu" "F.Mask" "F.Paste")
			(net "GND")
		)
		(pad "CT75" smd circle
			(at 27.806904 10.244074)
			(size 0.4318 0.4318)
			(layers "F.Cu" "F.Mask" "F.Paste")
			(net "M_F_DQS_DN<9>")
		)
		(pad "CT77" smd circle
			(at 29.523944 10.244074)
			(size 0.4318 0.4318)
			(layers "F.Cu" "F.Mask" "F.Paste")
			(net "M_F_DQ<7>")
		)
		(pad "CT79" smd circle
			(at 31.240984 10.244074)
			(size 0.4318 0.4318)
			(layers "F.Cu" "F.Mask" "F.Paste")
			(net "GND")
		)
		(pad "CT81" smd circle
			(at 32.958024 10.244074)
			(size 0.4318 0.4318)
			(layers "F.Cu" "F.Mask" "F.Paste")
			(net "M_E_DQ<2>")
		)
		(pad "CT83" smd circle
			(at 34.675064 10.244074)
			(size 0.4318 0.4318)
			(layers "F.Cu" "F.Mask" "F.Paste")
			(net "GND")
		)
		(pad "CT85" smd circle
			(at 36.392104 10.244074)
			(size 0.4318 0.4318)
			(layers "F.Cu" "F.Mask" "F.Paste")
			(net "GND")
		)
		(pad "CU2" smd circle
			(at -36.392104 12.539726)
			(size 0.4318 0.4318)
			(layers "F.Cu" "F.Mask" "F.Paste")
			(net "P3E_CPU0_PE2_SS_TXP<1>")
		)
		(pad "CU4" smd circle
			(at -34.675064 12.539726)
			(size 0.4318 0.4318)
			(layers "F.Cu" "F.Mask" "F.Paste")
			(net "GND")
		)
		(pad "CU6" smd circle
			(at -32.958024 12.539726)
			(size 0.4318 0.4318)
			(layers "F.Cu" "F.Mask" "F.Paste")
			(net "TP_CPU0_RSVD_67")
		)
		(pad "CU8" smd circle
			(at -31.240984 12.539726)
			(size 0.4318 0.4318)
			(layers "F.Cu" "F.Mask" "F.Paste")
			(net "P3E_CPU0_PE1_SS_RXP<0>")
		)
		(pad "CU10" smd circle
			(at -29.523944 12.539726)
			(size 0.4318 0.4318)
			(layers "F.Cu" "F.Mask" "F.Paste")
			(net "P3E_CPU0_PE3_OCP_RXP<15>")
		)
		(pad "CU12" smd circle
			(at -27.806904 12.539726)
			(size 0.4318 0.4318)
			(layers "F.Cu" "F.Mask" "F.Paste")
			(net "PVCCIO_CPU0")
		)
		(pad "CU14" smd circle
			(at -26.090118 12.539726)
			(size 0.4318 0.4318)
			(layers "F.Cu" "F.Mask" "F.Paste")
			(net "TP_CPU0_UPI2_RSVD_DD17")
		)
		(pad "CU18" smd circle
			(at -22.656038 12.539726)
			(size 0.4318 0.4318)
			(layers "F.Cu" "F.Mask" "F.Paste")
			(net "PVCCIO_CPU0")
		)
		(pad "CU20" smd circle
			(at -20.938998 12.539726)
			(size 0.4318 0.4318)
			(layers "F.Cu" "F.Mask" "F.Paste")
			(net "GND")
		)
		(pad "CU22" smd circle
			(at -19.221958 12.539726)
			(size 0.4318 0.4318)
			(layers "F.Cu" "F.Mask" "F.Paste")
			(net "GND")
		)
		(pad "CU24" smd circle
			(at -17.504918 12.539726)
			(size 0.4318 0.4318)
			(layers "F.Cu" "F.Mask" "F.Paste")
			(net "PVCCMCP_CPU0")
		)
		(pad "CU26" smd circle
			(at -15.787878 12.539726)
			(size 0.4318 0.4318)
			(layers "F.Cu" "F.Mask" "F.Paste")
			(net "CLK_100M_CPU0_BCLK2_DP")
		)
		(pad "CU28" smd circle
			(at -14.071092 12.539726)
			(size 0.4318 0.4318)
			(layers "F.Cu" "F.Mask" "F.Paste")
			(net "GND")
		)
		(pad "CU30" smd circle
			(at -12.354052 12.539726)
			(size 0.4318 0.4318)
			(layers "F.Cu" "F.Mask" "F.Paste")
			(net "GND")
		)
		(pad "CU32" smd circle
			(at -10.637012 12.539726)
			(size 0.4318 0.4318)
			(layers "F.Cu" "F.Mask" "F.Paste")
			(net "A_CPU0_MCP01_RBIAS")
		)
		(pad "CU34" smd circle
			(at -8.919972 12.539726)
			(size 0.4318 0.4318)
			(layers "F.Cu" "F.Mask" "F.Paste")
			(net "GND")
		)
		(pad "CU36" smd circle
			(at -7.202932 12.539726)
			(size 0.4318 0.4318)
			(layers "F.Cu" "F.Mask" "F.Paste")
			(net "GND")
		)
		(pad "CU38" smd circle
			(at -5.485892 12.539726)
			(size 0.4318 0.4318)
			(layers "F.Cu" "F.Mask" "F.Paste")
			(net "PVCCIN_CPU0")
		)
		(pad "CU40" smd circle
			(at -3.769106 12.539726)
			(size 0.4318 0.4318)
			(layers "F.Cu" "F.Mask" "F.Paste")
			(net "PVCCIN_CPU0")
		)
		(pad "CU42" smd circle
			(at -2.052066 12.539726)
			(size 0.4318 0.4318)
			(layers "F.Cu" "F.Mask" "F.Paste")
			(net "PVCCIN_CPU0")
		)
		(pad "CU52" smd circle
			(at 8.061452 10.739628)
			(size 0.508 0.508)
			(layers "F.Cu" "F.Mask" "F.Paste")
			(net "PVCCIN_CPU0")
		)
		(pad "CU54" smd circle
			(at 9.778492 10.739628)
			(size 0.4318 0.4318)
			(layers "F.Cu" "F.Mask" "F.Paste")
			(net "PVCCIN_CPU0")
		)
		(pad "CU56" smd circle
			(at 11.495532 10.739628)
			(size 0.4318 0.4318)
			(layers "F.Cu" "F.Mask" "F.Paste")
			(net "GND")
		)
		(pad "CU58" smd circle
			(at 13.212572 10.739628)
			(size 0.4318 0.4318)
			(layers "F.Cu" "F.Mask" "F.Paste")
			(net "PD_PIROM_CPU0_ADDR0")
		)
		(pad "CU60" smd circle
			(at 14.929612 10.739628)
			(size 0.4318 0.4318)
			(layers "F.Cu" "F.Mask" "F.Paste")
			(net "TP_CPU0_RSVD_66")
		)
		(pad "CU62" smd circle
			(at 16.646398 10.739628)
			(size 0.4318 0.4318)
			(layers "F.Cu" "F.Mask" "F.Paste")
			(net "GND")
		)
		(pad "CU64" smd circle
			(at 18.363438 10.739628)
			(size 0.4318 0.4318)
			(layers "F.Cu" "F.Mask" "F.Paste")
			(net "M_F_DQ<31>")
		)
		(pad "CU66" smd circle
			(at 20.080478 10.739628)
			(size 0.4318 0.4318)
			(layers "F.Cu" "F.Mask" "F.Paste")
			(net "M_F_DQ<25>")
		)
		(pad "CU68" smd circle
			(at 21.797518 10.739628)
			(size 0.4318 0.4318)
			(layers "F.Cu" "F.Mask" "F.Paste")
			(net "GND")
		)
		(pad "CU74" smd circle
			(at 26.948384 10.739628)
			(size 0.4318 0.4318)
			(layers "F.Cu" "F.Mask" "F.Paste")
			(net "M_F_DQS_DP<9>")
		)
		(pad "CU76" smd circle
			(at 28.665424 10.739628)
			(size 0.4318 0.4318)
			(layers "F.Cu" "F.Mask" "F.Paste")
			(net "GND")
		)
		(pad "CU78" smd circle
			(at 30.382464 10.739628)
			(size 0.4318 0.4318)
			(layers "F.Cu" "F.Mask" "F.Paste")
			(net "GND")
		)
		(pad "CU80" smd circle
			(at 32.099504 10.739628)
			(size 0.4318 0.4318)
			(layers "F.Cu" "F.Mask" "F.Paste")
			(net "GND")
		)
		(pad "CU82" smd circle
			(at 33.816544 10.739628)
			(size 0.4318 0.4318)
			(layers "F.Cu" "F.Mask" "F.Paste")
			(net "GND")
		)
		(pad "CU84" smd circle
			(at 35.533584 10.739628)
			(size 0.4318 0.4318)
			(layers "F.Cu" "F.Mask" "F.Paste")
			(net "M_D_DQS_DN<0>")
		)
		(pad "CU86" smd custom
			(at 37.250624 10.739628 270)
			(size 0.10795 0.10795)
			(layers "F.Cu" "F.Mask" "F.Paste")
			(net "GND")
			(options
				(clearance outline)
				(anchor circle)
			)
			(primitives
				(gr_poly
					(pts
						(arc
							(start 0.2159 -0.0381)
							(mid 0 -0.254)
							(end -0.2159 -0.0381)
						)
						(arc
							(start -0.2159 0.0381)
							(mid 0 0.254)
							(end 0.2159 0.0381)
						)
					)
					(width 0)
					(fill yes)
				)
			)
		)
		(pad "CV1" smd custom
			(at -37.250624 13.034772 90)
			(size 0.10795 0.10795)
			(layers "F.Cu" "F.Mask" "F.Paste")
			(net "GND")
			(options
				(clearance outline)
				(anchor circle)
			)
			(primitives
				(gr_poly
					(pts
						(arc
							(start 0.2159 -0.0381)
							(mid 0 -0.254)
							(end -0.2159 -0.0381)
						)
						(arc
							(start -0.2159 0.0381)
							(mid 0 0.254)
							(end 0.2159 0.0381)
						)
					)
					(width 0)
					(fill yes)
				)
			)
		)
		(pad "CV3" smd circle
			(at -35.533584 13.034772)
			(size 0.4318 0.4318)
			(layers "F.Cu" "F.Mask" "F.Paste")
			(net "P3E_CPU0_PE2_SS_TXN<1>")
		)
		(pad "CV5" smd circle
			(at -33.816544 13.034772)
			(size 0.4318 0.4318)
			(layers "F.Cu" "F.Mask" "F.Paste")
			(net "P3E_CPU0_PE3_OCP_TXP<15>")
		)
		(pad "CV7" smd circle
			(at -32.099504 13.034772)
			(size 0.4318 0.4318)
			(layers "F.Cu" "F.Mask" "F.Paste")
			(net "PVCCIO_CPU0")
		)
		(pad "CV9" smd circle
			(at -30.382464 13.034772)
			(size 0.4318 0.4318)
			(layers "F.Cu" "F.Mask" "F.Paste")
			(net "P3E_CPU0_PE3_OCP_RXN<15>")
		)
		(pad "CV11" smd circle
			(at -28.665424 13.034772)
			(size 0.4318 0.4318)
			(layers "F.Cu" "F.Mask" "F.Paste")
			(net "DMI_CPU0_PCH_RX_C_DP<3>")
		)
		(pad "CV13" smd circle
			(at -26.948384 13.034772)
			(size 0.4318 0.4318)
			(layers "F.Cu" "F.Mask" "F.Paste")
			(net "TP_CPU0_UPI2_RSVD_DD15")
		)
		(pad "CV17" smd circle
			(at -23.514558 13.034772)
			(size 0.4318 0.4318)
			(layers "F.Cu" "F.Mask" "F.Paste")
			(net "GND")
		)
		(pad "CV19" smd circle
			(at -21.797518 13.034772)
			(size 0.4318 0.4318)
			(layers "F.Cu" "F.Mask" "F.Paste")
			(net "GND")
		)
		(pad "CV21" smd circle
			(at -20.080478 13.034772)
			(size 0.4318 0.4318)
			(layers "F.Cu" "F.Mask" "F.Paste")
			(net "PVCCIO_CPU0")
		)
		(pad "CV23" smd circle
			(at -18.363438 13.034772)
			(size 0.4318 0.4318)
			(layers "F.Cu" "F.Mask" "F.Paste")
			(net "PVCCMCP_CPU0")
		)
		(pad "CV25" smd circle
			(at -16.646398 13.034772)
			(size 0.4318 0.4318)
			(layers "F.Cu" "F.Mask" "F.Paste")
			(net "GND")
		)
		(pad "CV27" smd circle
			(at -14.929612 13.034772)
			(size 0.4318 0.4318)
			(layers "F.Cu" "F.Mask" "F.Paste")
			(net "GND")
		)
		(pad "CV29" smd circle
			(at -13.212572 13.034772)
			(size 0.4318 0.4318)
			(layers "F.Cu" "F.Mask" "F.Paste")
			(net "M_F_DQS_DP<16>")
		)
		(pad "CV31" smd circle
			(at -11.495532 13.034772)
			(size 0.4318 0.4318)
			(layers "F.Cu" "F.Mask" "F.Paste")
			(net "GND")
		)
		(pad "CV33" smd circle
			(at -9.778492 13.034772)
			(size 0.4318 0.4318)
			(layers "F.Cu" "F.Mask" "F.Paste")
			(net "GND")
		)
		(pad "CV35" smd circle
			(at -8.061452 13.034772)
			(size 0.4318 0.4318)
			(layers "F.Cu" "F.Mask" "F.Paste")
			(net "M_F_DQS_DP<15>")
		)
		(pad "CV37" smd circle
			(at -6.344412 13.034772)
			(size 0.4318 0.4318)
			(layers "F.Cu" "F.Mask" "F.Paste")
			(net "GND")
		)
		(pad "CV39" smd circle
			(at -4.627626 13.034772)
			(size 0.4318 0.4318)
			(layers "F.Cu" "F.Mask" "F.Paste")
			(net "GND")
		)
		(pad "CV41" smd circle
			(at -2.910586 13.034772)
			(size 0.4318 0.4318)
			(layers "F.Cu" "F.Mask" "F.Paste")
			(net "GND")
		)
		(pad "CV51" smd circle
			(at 7.202932 11.234674)
			(size 0.508 0.508)
			(layers "F.Cu" "F.Mask" "F.Paste")
			(net "PVCCIN_CPU0")
		)
		(pad "CV53" smd circle
			(at 8.919972 11.234674)
			(size 0.4318 0.4318)
			(layers "F.Cu" "F.Mask" "F.Paste")
			(net "GND")
		)
		(pad "CV55" smd circle
			(at 10.637012 11.234674)
			(size 0.4318 0.4318)
			(layers "F.Cu" "F.Mask" "F.Paste")
			(net "GND")
		)
		(pad "CV57" smd circle
			(at 12.354052 11.234674)
			(size 0.4318 0.4318)
			(layers "F.Cu" "F.Mask" "F.Paste")
			(net "PD_PIROM_CPU0_ADDR1")
		)
		(pad "CV59" smd circle
			(at 14.071092 11.234674)
			(size 0.4318 0.4318)
			(layers "F.Cu" "F.Mask" "F.Paste")
			(net "FM_CPU0_SM_WP")
		)
		(pad "CV61" smd circle
			(at 15.787878 11.234674)
			(size 0.4318 0.4318)
			(layers "F.Cu" "F.Mask" "F.Paste")
			(net "M_F_CPU_VREF")
		)
		(pad "CV63" smd circle
			(at 17.504918 11.234674)
			(size 0.4318 0.4318)
			(layers "F.Cu" "F.Mask" "F.Paste")
			(net "GND")
		)
		(pad "CV65" smd circle
			(at 19.221958 11.234674)
			(size 0.4318 0.4318)
			(layers "F.Cu" "F.Mask" "F.Paste")
			(net "M_F_DQS_DN<3>")
		)
		(pad "CV67" smd circle
			(at 20.938998 11.234674)
			(size 0.4318 0.4318)
			(layers "F.Cu" "F.Mask" "F.Paste")
			(net "GND")
		)
		(pad "CV69" smd circle
			(at 22.656038 11.234674)
			(size 0.4318 0.4318)
			(layers "F.Cu" "F.Mask" "F.Paste")
			(net "TP_CPU0_RSVD_64")
		)
		(pad "CV73" smd circle
			(at 26.090118 11.234674)
			(size 0.4318 0.4318)
			(layers "F.Cu" "F.Mask" "F.Paste")
			(net "GND")
		)
		(pad "CV75" smd circle
			(at 27.806904 11.234674)
			(size 0.4318 0.4318)
			(layers "F.Cu" "F.Mask" "F.Paste")
			(net "M_F_DQ<6>")
		)
		(pad "CV77" smd circle
			(at 29.523944 11.234674)
			(size 0.4318 0.4318)
			(layers "F.Cu" "F.Mask" "F.Paste")
			(net "M_F_DQ<3>")
		)
		(pad "CV79" smd circle
			(at 31.240984 11.234674)
			(size 0.4318 0.4318)
			(layers "F.Cu" "F.Mask" "F.Paste")
			(net "GND")
		)
		(pad "CV81" smd circle
			(at 32.958024 11.234674)
			(size 0.4318 0.4318)
			(layers "F.Cu" "F.Mask" "F.Paste")
			(net "GND")
		)
		(pad "CV83" smd circle
			(at 34.675064 11.234674)
			(size 0.4318 0.4318)
			(layers "F.Cu" "F.Mask" "F.Paste")
			(net "GND")
		)
		(pad "CV85" smd circle
			(at 36.392104 11.234674)
			(size 0.4318 0.4318)
			(layers "F.Cu" "F.Mask" "F.Paste")
			(net "M_D_DQS_DP<0>")
		)
		(pad "CW2" smd circle
			(at -36.392104 13.530326)
			(size 0.4318 0.4318)
			(layers "F.Cu" "F.Mask" "F.Paste")
			(net "P3E_CPU0_PE1_SS_TXP<0>")
		)
		(pad "CW4" smd circle
			(at -34.675064 13.530326)
			(size 0.4318 0.4318)
			(layers "F.Cu" "F.Mask" "F.Paste")
			(net "P3E_CPU0_PE2_SS_TXP<0>")
		)
		(pad "CW6" smd circle
			(at -32.958024 13.530326)
			(size 0.4318 0.4318)
			(layers "F.Cu" "F.Mask" "F.Paste")
			(net "GND")
		)
		(pad "CW8" smd circle
			(at -31.240984 13.530326)
			(size 0.4318 0.4318)
			(layers "F.Cu" "F.Mask" "F.Paste")
			(net "P3E_CPU0_PE1_SS_RXN<0>")
		)
		(pad "CW10" smd circle
			(at -29.523944 13.530326)
			(size 0.4318 0.4318)
			(layers "F.Cu" "F.Mask" "F.Paste")
			(net "P3E_CPU0_PE3_OCP_RXP<14>")
		)
		(pad "CW12" smd circle
			(at -27.806904 13.530326)
			(size 0.4318 0.4318)
			(layers "F.Cu" "F.Mask" "F.Paste")
			(net "GND")
		)
		(pad "CW14" smd circle
			(at -26.090118 13.530326)
			(size 0.4318 0.4318)
			(layers "F.Cu" "F.Mask" "F.Paste")
			(net "TP_CPU0_UPI2_RSVD_DF15")
		)
		(pad "CW16" smd circle
			(at -24.373078 13.530326)
			(size 0.4318 0.4318)
			(layers "F.Cu" "F.Mask" "F.Paste")
			(net "TP_CPU0_UPI2_RSVD_DB15")
		)
		(pad "CW18" smd circle
			(at -22.656038 13.530326)
			(size 0.4318 0.4318)
			(layers "F.Cu" "F.Mask" "F.Paste")
			(net "GND")
		)
		(pad "CW20" smd circle
			(at -20.938998 13.530326)
			(size 0.4318 0.4318)
			(layers "F.Cu" "F.Mask" "F.Paste")
			(net "GND")
		)
		(pad "CW22" smd circle
			(at -19.221958 13.530326)
			(size 0.4318 0.4318)
			(layers "F.Cu" "F.Mask" "F.Paste")
			(net "TP_CPU0_KTI2_DFX_DN")
		)
		(pad "CW24" smd circle
			(at -17.504918 13.530326)
			(size 0.4318 0.4318)
			(layers "F.Cu" "F.Mask" "F.Paste")
			(net "PVCCMCP_CPU0")
		)
		(pad "CW26" smd circle
			(at -15.787878 13.530326)
			(size 0.4318 0.4318)
			(layers "F.Cu" "F.Mask" "F.Paste")
			(net "GND")
		)
		(pad "CW28" smd circle
			(at -14.071092 13.530326)
			(size 0.4318 0.4318)
			(layers "F.Cu" "F.Mask" "F.Paste")
			(net "M_F_DQ<62>")
		)
		(pad "CW30" smd circle
			(at -12.354052 13.530326)
			(size 0.4318 0.4318)
			(layers "F.Cu" "F.Mask" "F.Paste")
			(net "M_F_DQ<56>")
		)
		(pad "CW32" smd circle
			(at -10.637012 13.530326)
			(size 0.4318 0.4318)
			(layers "F.Cu" "F.Mask" "F.Paste")
			(net "GND")
		)
		(pad "CW34" smd circle
			(at -8.919972 13.530326)
			(size 0.4318 0.4318)
			(layers "F.Cu" "F.Mask" "F.Paste")
			(net "M_F_DQ<54>")
		)
		(pad "CW36" smd circle
			(at -7.202932 13.530326)
			(size 0.4318 0.4318)
			(layers "F.Cu" "F.Mask" "F.Paste")
			(net "M_F_DQ<48>")
		)
		(pad "CW38" smd circle
			(at -5.485892 13.530326)
			(size 0.4318 0.4318)
			(layers "F.Cu" "F.Mask" "F.Paste")
			(net "GND")
		)
		(pad "CW40" smd circle
			(at -3.769106 13.530326)
			(size 0.4318 0.4318)
			(layers "F.Cu" "F.Mask" "F.Paste")
			(net "GND")
		)
		(pad "CW42" smd circle
			(at -2.052066 13.530326)
			(size 0.4318 0.4318)
			(layers "F.Cu" "F.Mask" "F.Paste")
			(net "GND")
		)
		(pad "CW46" smd circle
			(at 2.910586 11.730228)
			(size 0.508 0.508)
			(layers "F.Cu" "F.Mask" "F.Paste")
			(net "PVCCIN_CPU0")
		)
		(pad "CW48" smd circle
			(at 4.627626 11.730228)
			(size 0.508 0.508)
			(layers "F.Cu" "F.Mask" "F.Paste")
			(net "PVCCIN_CPU0")
		)
		(pad "CW50" smd circle
			(at 6.344412 11.730228)
			(size 0.508 0.508)
			(layers "F.Cu" "F.Mask" "F.Paste")
			(net "PVCCIN_CPU0")
		)
		(pad "CW52" smd circle
			(at 8.061452 11.730228)
			(size 0.4318 0.4318)
			(layers "F.Cu" "F.Mask" "F.Paste")
			(net "GND")
		)
		(pad "CW54" smd circle
			(at 9.778492 11.730228)
			(size 0.4318 0.4318)
			(layers "F.Cu" "F.Mask" "F.Paste")
			(net "GND")
		)
		(pad "CW56" smd circle
			(at 11.495532 11.730228)
			(size 0.4318 0.4318)
			(layers "F.Cu" "F.Mask" "F.Paste")
			(net "PD_PIROM_CPU0_ADDR2")
		)
		(pad "CW58" smd circle
			(at 13.212572 11.730228)
			(size 0.4318 0.4318)
			(layers "F.Cu" "F.Mask" "F.Paste")
			(net "SMB_PIROM_CPU0_SDA")
		)
		(pad "CW60" smd circle
			(at 14.929612 11.730228)
			(size 0.4318 0.4318)
			(layers "F.Cu" "F.Mask" "F.Paste")
			(net "TP_CPU0_RSVD_61")
		)
		(pad "CW62" smd circle
			(at 16.646398 11.730228)
			(size 0.4318 0.4318)
			(layers "F.Cu" "F.Mask" "F.Paste")
			(net "TP_CPU0_RSVD_60")
		)
		(pad "CW64" smd circle
			(at 18.363438 11.730228)
			(size 0.4318 0.4318)
			(layers "F.Cu" "F.Mask" "F.Paste")
			(net "GND")
		)
		(pad "CW66" smd circle
			(at 20.080478 11.730228)
			(size 0.4318 0.4318)
			(layers "F.Cu" "F.Mask" "F.Paste")
			(net "GND")
		)
		(pad "CW68" smd circle
			(at 21.797518 11.730228)
			(size 0.4318 0.4318)
			(layers "F.Cu" "F.Mask" "F.Paste")
			(net "GND")
		)
		(pad "CW72" smd circle
			(at 25.231598 11.730228)
			(size 0.4318 0.4318)
			(layers "F.Cu" "F.Mask" "F.Paste")
			(net "FM_CPU0_PKGID1")
		)
		(pad "CW74" smd circle
			(at 26.948384 11.730228)
			(size 0.4318 0.4318)
			(layers "F.Cu" "F.Mask" "F.Paste")
			(net "GND")
		)
		(pad "CW76" smd circle
			(at 28.665424 11.730228)
			(size 0.4318 0.4318)
			(layers "F.Cu" "F.Mask" "F.Paste")
			(net "M_F_DQ<2>")
		)
		(pad "CW78" smd circle
			(at 30.382464 11.730228)
			(size 0.4318 0.4318)
			(layers "F.Cu" "F.Mask" "F.Paste")
			(net "GND")
		)
		(pad "CW80" smd circle
			(at 32.099504 11.730228)
			(size 0.4318 0.4318)
			(layers "F.Cu" "F.Mask" "F.Paste")
			(net "M_E_DQ<13>")
		)
		(pad "CW82" smd circle
			(at 33.816544 11.730228)
			(size 0.4318 0.4318)
			(layers "F.Cu" "F.Mask" "F.Paste")
			(net "GND")
		)
		(pad "CW84" smd circle
			(at 35.533584 11.730228)
			(size 0.4318 0.4318)
			(layers "F.Cu" "F.Mask" "F.Paste")
			(net "M_D_DQ<7>")
		)
		(pad "CW86" smd custom
			(at 37.250624 11.730228 270)
			(size 0.10795 0.10795)
			(layers "F.Cu" "F.Mask" "F.Paste")
			(net "M_D_DQ<6>")
			(options
				(clearance outline)
				(anchor circle)
			)
			(primitives
				(gr_poly
					(pts
						(arc
							(start 0.2159 -0.0381)
							(mid 0 -0.254)
							(end -0.2159 -0.0381)
						)
						(arc
							(start -0.2159 0.0381)
							(mid 0 0.254)
							(end 0.2159 0.0381)
						)
					)
					(width 0)
					(fill yes)
				)
			)
		)
		(pad "CY1" smd custom
			(at -37.250624 14.025372 90)
			(size 0.10795 0.10795)
			(layers "F.Cu" "F.Mask" "F.Paste")
			(net "GND")
			(options
				(clearance outline)
				(anchor circle)
			)
			(primitives
				(gr_poly
					(pts
						(arc
							(start 0.2159 -0.0381)
							(mid 0 -0.254)
							(end -0.2159 -0.0381)
						)
						(arc
							(start -0.2159 0.0381)
							(mid 0 0.254)
							(end 0.2159 0.0381)
						)
					)
					(width 0)
					(fill yes)
				)
			)
		)
		(pad "CY3" smd circle
			(at -35.533584 14.025372)
			(size 0.4318 0.4318)
			(layers "F.Cu" "F.Mask" "F.Paste")
			(net "P3E_CPU0_PE2_SS_TXN<0>")
		)
		(pad "CY5" smd circle
			(at -33.816544 14.025372)
			(size 0.4318 0.4318)
			(layers "F.Cu" "F.Mask" "F.Paste")
			(net "P3E_CPU0_PE3_OCP_TXN<15>")
		)
		(pad "CY7" smd circle
			(at -32.099504 14.025372)
			(size 0.4318 0.4318)
			(layers "F.Cu" "F.Mask" "F.Paste")
			(net "P3E_CPU0_PE1_SS_RXP<1>")
		)
		(pad "CY9" smd circle
			(at -30.382464 14.025372)
			(size 0.4318 0.4318)
			(layers "F.Cu" "F.Mask" "F.Paste")
			(net "GND")
		)
		(pad "CY11" smd circle
			(at -28.665424 14.025372)
			(size 0.4318 0.4318)
			(layers "F.Cu" "F.Mask" "F.Paste")
			(net "P3E_CPU0_PE3_OCP_RXN<14>")
		)
		(pad "CY13" smd circle
			(at -26.948384 14.025372)
			(size 0.4318 0.4318)
			(layers "F.Cu" "F.Mask" "F.Paste")
			(net "GND")
		)
		(pad "CY15" smd circle
			(at -25.231598 14.025372)
			(size 0.4318 0.4318)
			(layers "F.Cu" "F.Mask" "F.Paste")
			(net "GND")
		)
		(pad "CY17" smd circle
			(at -23.514558 14.025372)
			(size 0.4318 0.4318)
			(layers "F.Cu" "F.Mask" "F.Paste")
			(net "PVCCIO_CPU0")
		)
		(pad "CY19" smd circle
			(at -21.797518 14.025372)
			(size 0.4318 0.4318)
			(layers "F.Cu" "F.Mask" "F.Paste")
			(net "GND")
		)
		(pad "CY21" smd circle
			(at -20.080478 14.025372)
			(size 0.4318 0.4318)
			(layers "F.Cu" "F.Mask" "F.Paste")
			(net "GND")
		)
		(pad "CY23" smd circle
			(at -18.363438 14.025372)
			(size 0.4318 0.4318)
			(layers "F.Cu" "F.Mask" "F.Paste")
			(net "TP_CPU0_RSVD_59")
		)
		(pad "CY25" smd circle
			(at -16.646398 14.025372)
			(size 0.4318 0.4318)
			(layers "F.Cu" "F.Mask" "F.Paste")
			(net "PVCCMCP_CPU0")
		)
		(pad "CY27" smd circle
			(at -14.929612 14.025372)
			(size 0.4318 0.4318)
			(layers "F.Cu" "F.Mask" "F.Paste")
			(net "M_F_DQ<58>")
		)
		(pad "CY29" smd circle
			(at -13.212572 14.025372)
			(size 0.4318 0.4318)
			(layers "F.Cu" "F.Mask" "F.Paste")
			(net "M_F_DQS_DN<16>")
		)
		(pad "CY31" smd circle
			(at -11.495532 14.025372)
			(size 0.4318 0.4318)
			(layers "F.Cu" "F.Mask" "F.Paste")
			(net "M_F_DQ<60>")
		)
		(pad "CY33" smd circle
			(at -9.778492 14.025372)
			(size 0.4318 0.4318)
			(layers "F.Cu" "F.Mask" "F.Paste")
			(net "M_F_DQ<50>")
		)
		(pad "CY35" smd circle
			(at -8.061452 14.025372)
			(size 0.4318 0.4318)
			(layers "F.Cu" "F.Mask" "F.Paste")
			(net "M_F_DQS_DN<15>")
		)
		(pad "CY37" smd circle
			(at -6.344412 14.025372)
			(size 0.4318 0.4318)
			(layers "F.Cu" "F.Mask" "F.Paste")
			(net "M_F_DQ<52>")
		)
		(pad "CY39" smd circle
			(at -4.627626 14.025372)
			(size 0.4318 0.4318)
			(layers "F.Cu" "F.Mask" "F.Paste")
			(net "TP_CPU0_RSVD_57")
		)
		(pad "CY41" smd circle
			(at -2.910586 14.025372)
			(size 0.4318 0.4318)
			(layers "F.Cu" "F.Mask" "F.Paste")
			(net "GND")
		)
		(pad "CY45" smd circle
			(at 2.052066 12.225274)
			(size 0.508 0.508)
			(layers "F.Cu" "F.Mask" "F.Paste")
			(net "GND")
		)
		(pad "CY47" smd circle
			(at 3.769106 12.225274)
			(size 0.4318 0.4318)
			(layers "F.Cu" "F.Mask" "F.Paste")
			(net "PVCCIN_CPU0")
		)
		(pad "CY49" smd circle
			(at 5.485892 12.225274)
			(size 0.4318 0.4318)
			(layers "F.Cu" "F.Mask" "F.Paste")
			(net "PVCCIN_CPU0")
		)
		(pad "CY51" smd circle
			(at 7.202932 12.225274)
			(size 0.4318 0.4318)
			(layers "F.Cu" "F.Mask" "F.Paste")
			(net "GND")
		)
		(pad "CY53" smd circle
			(at 8.919972 12.225274)
			(size 0.4318 0.4318)
			(layers "F.Cu" "F.Mask" "F.Paste")
			(net "TP_CPU0_RSVD_56")
		)
		(pad "CY55" smd circle
			(at 10.637012 12.225274)
			(size 0.4318 0.4318)
			(layers "F.Cu" "F.Mask" "F.Paste")
			(net "P3V3_STBY")
		)
		(pad "CY57" smd circle
			(at 12.354052 12.225274)
			(size 0.4318 0.4318)
			(layers "F.Cu" "F.Mask" "F.Paste")
			(net "TP_CPU0_RSVD_55")
		)
		(pad "CY59" smd circle
			(at 14.071092 12.225274)
			(size 0.4318 0.4318)
			(layers "F.Cu" "F.Mask" "F.Paste")
			(net "GND")
		)
		(pad "CY61" smd circle
			(at 15.787878 12.225274)
			(size 0.4318 0.4318)
			(layers "F.Cu" "F.Mask" "F.Paste")
			(net "GND")
		)
		(pad "CY63" smd circle
			(at 17.504918 12.225274)
			(size 0.4318 0.4318)
			(layers "F.Cu" "F.Mask" "F.Paste")
			(net "TP_CPU0_RSVD_54")
		)
		(pad "CY65" smd circle
			(at 19.221958 12.225274)
			(size 0.4318 0.4318)
			(layers "F.Cu" "F.Mask" "F.Paste")
			(net "GND")
		)
		(pad "CY67" smd circle
			(at 20.938998 12.225274)
			(size 0.4318 0.4318)
			(layers "F.Cu" "F.Mask" "F.Paste")
			(net "M_D_DQS_DP<17>")
		)
		(pad "CY69" smd circle
			(at 22.656038 12.225274)
			(size 0.4318 0.4318)
			(layers "F.Cu" "F.Mask" "F.Paste")
			(net "GND")
		)
		(pad "CY71" smd circle
			(at 24.373078 12.225274)
			(size 0.4318 0.4318)
			(layers "F.Cu" "F.Mask" "F.Paste")
			(net "FM_CPU0_PROC_ID0")
		)
		(pad "CY73" smd circle
			(at 26.090118 12.225274)
			(size 0.4318 0.4318)
			(layers "F.Cu" "F.Mask" "F.Paste")
			(net "TP_CPU0_RSVD_53")
		)
		(pad "CY75" smd circle
			(at 27.806904 12.225274)
			(size 0.4318 0.4318)
			(layers "F.Cu" "F.Mask" "F.Paste")
			(net "GND")
		)
		(pad "CY77" smd circle
			(at 29.523944 12.225274)
			(size 0.4318 0.4318)
			(layers "F.Cu" "F.Mask" "F.Paste")
			(net "GND")
		)
		(pad "CY79" smd circle
			(at 31.240984 12.225274)
			(size 0.4318 0.4318)
			(layers "F.Cu" "F.Mask" "F.Paste")
			(net "M_E_DQ<12>")
		)
		(pad "CY81" smd circle
			(at 32.958024 12.225274)
			(size 0.4318 0.4318)
			(layers "F.Cu" "F.Mask" "F.Paste")
			(net "M_E_DQ<9>")
		)
		(pad "CY83" smd circle
			(at 34.675064 12.225274)
			(size 0.4318 0.4318)
			(layers "F.Cu" "F.Mask" "F.Paste")
			(net "GND")
		)
		(pad "CY85" smd circle
			(at 36.392104 12.225274)
			(size 0.4318 0.4318)
			(layers "F.Cu" "F.Mask" "F.Paste")
			(net "GND")
		)
		(pad "D3" smd custom
			(at -35.533584 -23.617174 45)
			(size 0.10795 0.10795)
			(layers "F.Cu" "F.Mask" "F.Paste")
			(net "GND")
			(options
				(clearance outline)
				(anchor circle)
			)
			(primitives
				(gr_poly
					(pts
						(arc
							(start 0.2159 -0.0381)
							(mid 0 -0.254)
							(end -0.2159 -0.0381)
						)
						(arc
							(start -0.2159 0.0381)
							(mid 0 0.254)
							(end 0.2159 0.0381)
						)
					)
					(width 0)
					(fill yes)
				)
			)
		)
		(pad "D5" smd custom
			(at -33.816544 -23.617174 90)
			(size 0.10795 0.10795)
			(layers "F.Cu" "F.Mask" "F.Paste")
			(net "TP_CPU0_RSVD_287")
			(options
				(clearance outline)
				(anchor circle)
			)
			(primitives
				(gr_poly
					(pts
						(arc
							(start 0.2159 -0.0381)
							(mid 0 -0.254)
							(end -0.2159 -0.0381)
						)
						(arc
							(start -0.2159 0.0381)
							(mid 0 0.254)
							(end 0.2159 0.0381)
						)
					)
					(width 0)
					(fill yes)
				)
			)
		)
		(pad "D7" smd circle
			(at -32.099504 -23.617174)
			(size 0.4318 0.4318)
			(layers "F.Cu" "F.Mask" "F.Paste")
			(net "PVCCIO_CPU0")
		)
		(pad "D9" smd circle
			(at -30.382464 -23.617174)
			(size 0.4318 0.4318)
			(layers "F.Cu" "F.Mask" "F.Paste")
			(net "UPI_CPU0_CPU1_P1P1_DN<12>")
		)
		(pad "D11" smd circle
			(at -28.665424 -23.617174)
			(size 0.4318 0.4318)
			(layers "F.Cu" "F.Mask" "F.Paste")
			(net "GND")
		)
		(pad "D13" smd circle
			(at -26.948384 -23.617174)
			(size 0.4318 0.4318)
			(layers "F.Cu" "F.Mask" "F.Paste")
			(net "GND")
		)
		(pad "D15" smd circle
			(at -25.231598 -23.617174)
			(size 0.4318 0.4318)
			(layers "F.Cu" "F.Mask" "F.Paste")
			(net "UPI_CPU0_CPU1_P1P1_DN<7>")
		)
		(pad "D17" smd circle
			(at -23.514558 -23.617174)
			(size 0.4318 0.4318)
			(layers "F.Cu" "F.Mask" "F.Paste")
			(net "TP_CPU0_RSVD_286")
		)
		(pad "D25" smd circle
			(at -16.646398 -23.617174)
			(size 0.4318 0.4318)
			(layers "F.Cu" "F.Mask" "F.Paste")
			(net "GND")
		)
		(pad "D27" smd circle
			(at -14.929612 -23.617174)
			(size 0.4318 0.4318)
			(layers "F.Cu" "F.Mask" "F.Paste")
			(net "GND")
		)
		(pad "D29" smd circle
			(at -13.212572 -23.617174)
			(size 0.4318 0.4318)
			(layers "F.Cu" "F.Mask" "F.Paste")
			(net "GND")
		)
		(pad "D31" smd circle
			(at -11.495532 -23.617174)
			(size 0.4318 0.4318)
			(layers "F.Cu" "F.Mask" "F.Paste")
			(net "GND")
		)
		(pad "D33" smd circle
			(at -9.778492 -23.617174)
			(size 0.4318 0.4318)
			(layers "F.Cu" "F.Mask" "F.Paste")
			(net "GND")
		)
		(pad "D35" smd circle
			(at -8.061452 -23.617174)
			(size 0.4318 0.4318)
			(layers "F.Cu" "F.Mask" "F.Paste")
			(net "GND")
		)
		(pad "D37" smd circle
			(at -6.344412 -23.617174)
			(size 0.4318 0.4318)
			(layers "F.Cu" "F.Mask" "F.Paste")
			(net "GND")
		)
		(pad "D39" smd circle
			(at -4.627626 -23.617174)
			(size 0.4318 0.4318)
			(layers "F.Cu" "F.Mask" "F.Paste")
			(net "GND")
		)
		(pad "D41" smd circle
			(at -2.910586 -23.617174)
			(size 0.4318 0.4318)
			(layers "F.Cu" "F.Mask" "F.Paste")
			(net "GND")
		)
		(pad "D43" smd circle
			(at -1.193546 -23.617174)
			(size 0.4318 0.4318)
			(layers "F.Cu" "F.Mask" "F.Paste")
			(net "GND")
		)
		(pad "D45" smd custom
			(at 2.052066 -25.417526 45)
			(size 0.10795 0.10795)
			(layers "F.Cu" "F.Mask" "F.Paste")
			(net "PVDDQ_ABC")
			(options
				(clearance outline)
				(anchor circle)
			)
			(primitives
				(gr_poly
					(pts
						(arc
							(start 0.2159 -0.0381)
							(mid 0 -0.254)
							(end -0.2159 -0.0381)
						)
						(arc
							(start -0.2159 0.0381)
							(mid 0 0.254)
							(end 0.2159 0.0381)
						)
					)
					(width 0)
					(fill yes)
				)
			)
		)
		(pad "D47" smd circle
			(at 3.769106 -25.417526)
			(size 0.4318 0.4318)
			(layers "F.Cu" "F.Mask" "F.Paste")
			(net "M_A_CS_N<2>")
		)
		(pad "D49" smd circle
			(at 5.485892 -25.417526)
			(size 0.4318 0.4318)
			(layers "F.Cu" "F.Mask" "F.Paste")
			(net "M_A_CS_N<5>")
		)
		(pad "D51" smd circle
			(at 7.202932 -25.417526)
			(size 0.4318 0.4318)
			(layers "F.Cu" "F.Mask" "F.Paste")
			(net "M_A_MA<16>")
		)
		(pad "D53" smd circle
			(at 8.919972 -25.417526)
			(size 0.4318 0.4318)
			(layers "F.Cu" "F.Mask" "F.Paste")
			(net "M_A_PAR")
		)
		(pad "D55" smd circle
			(at 10.637012 -25.417526)
			(size 0.4318 0.4318)
			(layers "F.Cu" "F.Mask" "F.Paste")
			(net "M_A_CLK_DP<0>")
		)
		(pad "D57" smd circle
			(at 12.354052 -25.417526)
			(size 0.4318 0.4318)
			(layers "F.Cu" "F.Mask" "F.Paste")
			(net "M_A_MA<2>")
		)
		(pad "D59" smd circle
			(at 14.071092 -25.417526)
			(size 0.4318 0.4318)
			(layers "F.Cu" "F.Mask" "F.Paste")
			(net "M_A_MA<6>")
		)
		(pad "D61" smd circle
			(at 15.787878 -25.417526)
			(size 0.4318 0.4318)
			(layers "F.Cu" "F.Mask" "F.Paste")
			(net "M_A_BG<0>")
		)
		(pad "D63" smd circle
			(at 17.504918 -25.417526)
			(size 0.4318 0.4318)
			(layers "F.Cu" "F.Mask" "F.Paste")
			(net "M_A_CKE<3>")
		)
		(pad "D65" smd custom
			(at 19.221958 -25.417526)
			(size 0.10795 0.10795)
			(layers "F.Cu" "F.Mask" "F.Paste")
			(net "TP_CPU0_RSVD_285")
			(options
				(clearance outline)
				(anchor circle)
			)
			(primitives
				(gr_poly
					(pts
						(arc
							(start 0.2159 -0.0381)
							(mid 0 -0.254)
							(end -0.2159 -0.0381)
						)
						(arc
							(start -0.2159 0.0381)
							(mid 0 0.254)
							(end 0.2159 0.0381)
						)
					)
					(width 0)
					(fill yes)
				)
			)
		)
		(pad "D71" smd custom
			(at 24.373078 -25.417526)
			(size 0.10795 0.10795)
			(layers "F.Cu" "F.Mask" "F.Paste")
			(net "M_B_DQ<26>")
			(options
				(clearance outline)
				(anchor circle)
			)
			(primitives
				(gr_poly
					(pts
						(arc
							(start 0.2159 -0.0381)
							(mid 0 -0.254)
							(end -0.2159 -0.0381)
						)
						(arc
							(start -0.2159 0.0381)
							(mid 0 0.254)
							(end 0.2159 0.0381)
						)
					)
					(width 0)
					(fill yes)
				)
			)
		)
		(pad "D73" smd circle
			(at 26.090118 -25.417526)
			(size 0.4318 0.4318)
			(layers "F.Cu" "F.Mask" "F.Paste")
			(net "M_B_DQS_DP<12>")
		)
		(pad "D75" smd circle
			(at 27.806904 -25.417526)
			(size 0.4318 0.4318)
			(layers "F.Cu" "F.Mask" "F.Paste")
			(net "M_B_DQ<24>")
		)
		(pad "D77" smd circle
			(at 29.523944 -25.417526)
			(size 0.4318 0.4318)
			(layers "F.Cu" "F.Mask" "F.Paste")
			(net "GND")
		)
		(pad "D79" smd circle
			(at 31.240984 -25.417526)
			(size 0.4318 0.4318)
			(layers "F.Cu" "F.Mask" "F.Paste")
			(net "M_B_DQS_DN<11>")
		)
		(pad "D81" smd custom
			(at 32.958024 -25.417526 315)
			(size 0.10795 0.10795)
			(layers "F.Cu" "F.Mask" "F.Paste")
			(net "GND")
			(options
				(clearance outline)
				(anchor circle)
			)
			(primitives
				(gr_poly
					(pts
						(arc
							(start 0.2159 -0.0381)
							(mid 0 -0.254)
							(end -0.2159 -0.0381)
						)
						(arc
							(start -0.2159 0.0381)
							(mid 0 0.254)
							(end 0.2159 0.0381)
						)
					)
					(width 0)
					(fill yes)
				)
			)
		)
		(pad "D83" smd custom
			(at 34.675064 -25.417526 270)
			(size 0.10795 0.10795)
			(layers "F.Cu" "F.Mask" "F.Paste")
			(net "TP_CPU0_RSVD_284")
			(options
				(clearance outline)
				(anchor circle)
			)
			(primitives
				(gr_poly
					(pts
						(arc
							(start 0.2159 -0.0381)
							(mid 0 -0.254)
							(end -0.2159 -0.0381)
						)
						(arc
							(start -0.2159 0.0381)
							(mid 0 0.254)
							(end 0.2159 0.0381)
						)
					)
					(width 0)
					(fill yes)
				)
			)
		)
		(pad "DA2" smd circle
			(at -36.392104 14.520926)
			(size 0.4318 0.4318)
			(layers "F.Cu" "F.Mask" "F.Paste")
			(net "P3E_CPU0_PE1_SS_TXN<0>")
		)
		(pad "DA4" smd circle
			(at -34.675064 14.520926)
			(size 0.4318 0.4318)
			(layers "F.Cu" "F.Mask" "F.Paste")
			(net "P3E_CPU0_PE3_OCP_TXP<14>")
		)
		(pad "DA6" smd circle
			(at -32.958024 14.520926)
			(size 0.4318 0.4318)
			(layers "F.Cu" "F.Mask" "F.Paste")
			(net "GND")
		)
		(pad "DA8" smd circle
			(at -31.240984 14.520926)
			(size 0.4318 0.4318)
			(layers "F.Cu" "F.Mask" "F.Paste")
			(net "P3E_CPU0_PE1_SS_RXN<1>")
		)
		(pad "DA10" smd circle
			(at -29.523944 14.520926)
			(size 0.4318 0.4318)
			(layers "F.Cu" "F.Mask" "F.Paste")
			(net "P3E_CPU0_PE1_SS_RXP<3>")
		)
		(pad "DA12" smd circle
			(at -27.806904 14.520926)
			(size 0.4318 0.4318)
			(layers "F.Cu" "F.Mask" "F.Paste")
			(net "P3E_CPU0_PE3_OCP_RXP<13>")
		)
		(pad "DA14" smd circle
			(at -26.090118 14.520926)
			(size 0.4318 0.4318)
			(layers "F.Cu" "F.Mask" "F.Paste")
			(net "PVCCIO_CPU0")
		)
		(pad "DA16" smd circle
			(at -24.373078 14.520926)
			(size 0.4318 0.4318)
			(layers "F.Cu" "F.Mask" "F.Paste")
			(net "TP_CPU0_UPI2_RSVD_DC16")
		)
		(pad "DA18" smd circle
			(at -22.656038 14.520926)
			(size 0.4318 0.4318)
			(layers "F.Cu" "F.Mask" "F.Paste")
			(net "GND")
		)
		(pad "DA20" smd circle
			(at -20.938998 14.520926)
			(size 0.4318 0.4318)
			(layers "F.Cu" "F.Mask" "F.Paste")
			(net "GND")
		)
		(pad "DA22" smd circle
			(at -19.221958 14.520926)
			(size 0.4318 0.4318)
			(layers "F.Cu" "F.Mask" "F.Paste")
			(net "GND")
		)
		(pad "DA24" smd circle
			(at -17.504918 14.520926)
			(size 0.4318 0.4318)
			(layers "F.Cu" "F.Mask" "F.Paste")
			(net "PVCCMCP_CPU0")
		)
		(pad "DA26" smd circle
			(at -15.787878 14.520926)
			(size 0.4318 0.4318)
			(layers "F.Cu" "F.Mask" "F.Paste")
			(net "GND")
		)
		(pad "DA28" smd circle
			(at -14.071092 14.520926)
			(size 0.4318 0.4318)
			(layers "F.Cu" "F.Mask" "F.Paste")
			(net "GND")
		)
		(pad "DA30" smd circle
			(at -12.354052 14.520926)
			(size 0.4318 0.4318)
			(layers "F.Cu" "F.Mask" "F.Paste")
			(net "GND")
		)
		(pad "DA32" smd circle
			(at -10.637012 14.520926)
			(size 0.4318 0.4318)
			(layers "F.Cu" "F.Mask" "F.Paste")
			(net "GND")
		)
		(pad "DA34" smd circle
			(at -8.919972 14.520926)
			(size 0.4318 0.4318)
			(layers "F.Cu" "F.Mask" "F.Paste")
			(net "GND")
		)
		(pad "DA36" smd circle
			(at -7.202932 14.520926)
			(size 0.4318 0.4318)
			(layers "F.Cu" "F.Mask" "F.Paste")
			(net "GND")
		)
		(pad "DA38" smd circle
			(at -5.485892 14.520926)
			(size 0.4318 0.4318)
			(layers "F.Cu" "F.Mask" "F.Paste")
			(net "GND")
		)
		(pad "DA40" smd circle
			(at -3.769106 14.520926)
			(size 0.4318 0.4318)
			(layers "F.Cu" "F.Mask" "F.Paste")
			(net "TP_CPU0_RSVD_51")
		)
		(pad "DA42" smd circle
			(at -2.052066 14.520926)
			(size 0.4318 0.4318)
			(layers "F.Cu" "F.Mask" "F.Paste")
			(net "M_F_DQ<36>")
		)
		(pad "DA44" smd circle
			(at 1.193546 12.720828)
			(size 0.508 0.508)
			(layers "F.Cu" "F.Mask" "F.Paste")
			(net "GND")
		)
		(pad "DA46" smd circle
			(at 2.910586 12.720828)
			(size 0.4318 0.4318)
			(layers "F.Cu" "F.Mask" "F.Paste")
			(net "GND")
		)
		(pad "DA48" smd circle
			(at 4.627626 12.720828)
			(size 0.4318 0.4318)
			(layers "F.Cu" "F.Mask" "F.Paste")
			(net "GND")
		)
		(pad "DA50" smd circle
			(at 6.344412 12.720828)
			(size 0.4318 0.4318)
			(layers "F.Cu" "F.Mask" "F.Paste")
			(net "GND")
		)
		(pad "DA52" smd circle
			(at 8.061452 12.720828)
			(size 0.4318 0.4318)
			(layers "F.Cu" "F.Mask" "F.Paste")
			(net "TP_CPU0_RSVD_50")
		)
		(pad "DA54" smd circle
			(at 9.778492 12.720828)
			(size 0.4318 0.4318)
			(layers "F.Cu" "F.Mask" "F.Paste")
			(net "TP_CPU0_RSVD_49")
		)
		(pad "DA56" smd circle
			(at 11.495532 12.720828)
			(size 0.4318 0.4318)
			(layers "F.Cu" "F.Mask" "F.Paste")
			(net "TP_CPU0_RSVD_48")
		)
		(pad "DA58" smd circle
			(at 13.212572 12.720828)
			(size 0.4318 0.4318)
			(layers "F.Cu" "F.Mask" "F.Paste")
			(net "M_F_MA<9>")
		)
		(pad "DA60" smd circle
			(at 14.929612 12.720828)
			(size 0.4318 0.4318)
			(layers "F.Cu" "F.Mask" "F.Paste")
			(net "M_F_MA<11>")
		)
		(pad "DA62" smd circle
			(at 16.646398 12.720828)
			(size 0.4318 0.4318)
			(layers "F.Cu" "F.Mask" "F.Paste")
			(net "M_F_BG<0>")
		)
		(pad "DA64" smd circle
			(at 18.363438 12.720828)
			(size 0.4318 0.4318)
			(layers "F.Cu" "F.Mask" "F.Paste")
			(net "GND")
		)
		(pad "DA66" smd circle
			(at 20.080478 12.720828)
			(size 0.4318 0.4318)
			(layers "F.Cu" "F.Mask" "F.Paste")
			(net "M_D_ECC<6>")
		)
		(pad "DA68" smd circle
			(at 21.797518 12.720828)
			(size 0.4318 0.4318)
			(layers "F.Cu" "F.Mask" "F.Paste")
			(net "M_D_ECC<0>")
		)
		(pad "DA70" smd circle
			(at 23.514558 12.720828)
			(size 0.4318 0.4318)
			(layers "F.Cu" "F.Mask" "F.Paste")
			(net "GND")
		)
		(pad "DA72" smd circle
			(at 25.231598 12.720828)
			(size 0.4318 0.4318)
			(layers "F.Cu" "F.Mask" "F.Paste")
			(net "FM_CPU0_PKGID2")
		)
		(pad "DA74" smd circle
			(at 26.948384 12.720828)
			(size 0.4318 0.4318)
			(layers "F.Cu" "F.Mask" "F.Paste")
			(net "GND")
		)
		(pad "DA76" smd circle
			(at 28.665424 12.720828)
			(size 0.4318 0.4318)
			(layers "F.Cu" "F.Mask" "F.Paste")
			(net "GND")
		)
		(pad "DA78" smd circle
			(at 30.382464 12.720828)
			(size 0.4318 0.4318)
			(layers "F.Cu" "F.Mask" "F.Paste")
			(net "GND")
		)
		(pad "DA80" smd circle
			(at 32.099504 12.720828)
			(size 0.4318 0.4318)
			(layers "F.Cu" "F.Mask" "F.Paste")
			(net "GND")
		)
		(pad "DA82" smd circle
			(at 33.816544 12.720828)
			(size 0.4318 0.4318)
			(layers "F.Cu" "F.Mask" "F.Paste")
			(net "M_E_DQS_DN<1>")
		)
		(pad "DA84" smd circle
			(at 35.533584 12.720828)
			(size 0.4318 0.4318)
			(layers "F.Cu" "F.Mask" "F.Paste")
			(net "M_D_DQ<3>")
		)
		(pad "DA86" smd custom
			(at 37.250624 12.720828 270)
			(size 0.10795 0.10795)
			(layers "F.Cu" "F.Mask" "F.Paste")
			(net "M_D_DQ<2>")
			(options
				(clearance outline)
				(anchor circle)
			)
			(primitives
				(gr_poly
					(pts
						(arc
							(start 0.2159 -0.0381)
							(mid 0 -0.254)
							(end -0.2159 -0.0381)
						)
						(arc
							(start -0.2159 0.0381)
							(mid 0 0.254)
							(end 0.2159 0.0381)
						)
					)
					(width 0)
					(fill yes)
				)
			)
		)
		(pad "DB1" smd custom
			(at -37.250624 15.015972 90)
			(size 0.10795 0.10795)
			(layers "F.Cu" "F.Mask" "F.Paste")
			(net "P3E_CPU0_PE1_SS_TXP<1>")
			(options
				(clearance outline)
				(anchor circle)
			)
			(primitives
				(gr_poly
					(pts
						(arc
							(start 0.2159 -0.0381)
							(mid 0 -0.254)
							(end -0.2159 -0.0381)
						)
						(arc
							(start -0.2159 0.0381)
							(mid 0 0.254)
							(end 0.2159 0.0381)
						)
					)
					(width 0)
					(fill yes)
				)
			)
		)
		(pad "DB3" smd circle
			(at -35.533584 15.015972)
			(size 0.4318 0.4318)
			(layers "F.Cu" "F.Mask" "F.Paste")
			(net "GND")
		)
		(pad "DB5" smd circle
			(at -33.816544 15.015972)
			(size 0.4318 0.4318)
			(layers "F.Cu" "F.Mask" "F.Paste")
			(net "P3E_CPU0_PE3_OCP_TXN<14>")
		)
		(pad "DB7" smd circle
			(at -32.099504 15.015972)
			(size 0.4318 0.4318)
			(layers "F.Cu" "F.Mask" "F.Paste")
			(net "GND")
		)
		(pad "DB9" smd circle
			(at -30.382464 15.015972)
			(size 0.4318 0.4318)
			(layers "F.Cu" "F.Mask" "F.Paste")
			(net "P3E_CPU0_PE1_SS_RXP<2>")
		)
		(pad "DB11" smd circle
			(at -28.665424 15.015972)
			(size 0.4318 0.4318)
			(layers "F.Cu" "F.Mask" "F.Paste")
			(net "P3E_CPU0_PE3_OCP_RXN<13>")
		)
		(pad "DB13" smd circle
			(at -26.948384 15.015972)
			(size 0.4318 0.4318)
			(layers "F.Cu" "F.Mask" "F.Paste")
			(net "GND")
		)
		(pad "DB15" smd circle
			(at -25.231598 15.015972)
			(size 0.4318 0.4318)
			(layers "F.Cu" "F.Mask" "F.Paste")
			(net "TP_CPU0_UPI2_RSVD_CW16")
		)
		(pad "DB17" smd circle
			(at -23.514558 15.015972)
			(size 0.4318 0.4318)
			(layers "F.Cu" "F.Mask" "F.Paste")
			(net "GND")
		)
		(pad "DB19" smd circle
			(at -21.797518 15.015972)
			(size 0.4318 0.4318)
			(layers "F.Cu" "F.Mask" "F.Paste")
			(net "GND")
		)
		(pad "DB21" smd circle
			(at -20.080478 15.015972)
			(size 0.4318 0.4318)
			(layers "F.Cu" "F.Mask" "F.Paste")
			(net "GND")
		)
		(pad "DB23" smd circle
			(at -18.363438 15.015972)
			(size 0.4318 0.4318)
			(layers "F.Cu" "F.Mask" "F.Paste")
			(net "GND")
		)
		(pad "DB25" smd circle
			(at -16.646398 15.015972)
			(size 0.4318 0.4318)
			(layers "F.Cu" "F.Mask" "F.Paste")
			(net "GND")
		)
		(pad "DB27" smd circle
			(at -14.929612 15.015972)
			(size 0.4318 0.4318)
			(layers "F.Cu" "F.Mask" "F.Paste")
			(net "M_F_DQ<59>")
		)
		(pad "DB29" smd circle
			(at -13.212572 15.015972)
			(size 0.4318 0.4318)
			(layers "F.Cu" "F.Mask" "F.Paste")
			(net "M_F_DQS_DP<7>")
		)
		(pad "DB31" smd circle
			(at -11.495532 15.015972)
			(size 0.4318 0.4318)
			(layers "F.Cu" "F.Mask" "F.Paste")
			(net "M_F_DQ<61>")
		)
		(pad "DB33" smd circle
			(at -9.778492 15.015972)
			(size 0.4318 0.4318)
			(layers "F.Cu" "F.Mask" "F.Paste")
			(net "M_F_DQ<51>")
		)
		(pad "DB35" smd circle
			(at -8.061452 15.015972)
			(size 0.4318 0.4318)
			(layers "F.Cu" "F.Mask" "F.Paste")
			(net "M_F_DQS_DP<6>")
		)
		(pad "DB37" smd circle
			(at -6.344412 15.015972)
			(size 0.4318 0.4318)
			(layers "F.Cu" "F.Mask" "F.Paste")
			(net "M_F_DQ<53>")
		)
		(pad "DB39" smd circle
			(at -4.627626 15.015972)
			(size 0.4318 0.4318)
			(layers "F.Cu" "F.Mask" "F.Paste")
			(net "GND")
		)
		(pad "DB41" smd circle
			(at -2.910586 15.015972)
			(size 0.4318 0.4318)
			(layers "F.Cu" "F.Mask" "F.Paste")
			(net "GND")
		)
		(pad "DB45" smd circle
			(at 2.052066 13.215874)
			(size 0.4318 0.4318)
			(layers "F.Cu" "F.Mask" "F.Paste")
			(net "SVID_DIO0_CPU0")
		)
		(pad "DB47" smd circle
			(at 3.769106 13.215874)
			(size 0.4318 0.4318)
			(layers "F.Cu" "F.Mask" "F.Paste")
			(net "GND")
		)
		(pad "DB49" smd circle
			(at 5.485892 13.215874)
			(size 0.4318 0.4318)
			(layers "F.Cu" "F.Mask" "F.Paste")
			(net "GND")
		)
		(pad "DB51" smd circle
			(at 7.202932 13.215874)
			(size 0.4318 0.4318)
			(layers "F.Cu" "F.Mask" "F.Paste")
			(net "PD_CPU0_TEST13")
		)
		(pad "DB53" smd circle
			(at 8.919972 13.215874)
			(size 0.4318 0.4318)
			(layers "F.Cu" "F.Mask" "F.Paste")
			(net "PVDDQ_DEF")
		)
		(pad "DB55" smd circle
			(at 10.637012 13.215874)
			(size 0.4318 0.4318)
			(layers "F.Cu" "F.Mask" "F.Paste")
			(net "PVDDQ_DEF")
		)
		(pad "DB57" smd circle
			(at 12.354052 13.215874)
			(size 0.4318 0.4318)
			(layers "F.Cu" "F.Mask" "F.Paste")
			(net "PVDDQ_DEF")
		)
		(pad "DB59" smd circle
			(at 14.071092 13.215874)
			(size 0.4318 0.4318)
			(layers "F.Cu" "F.Mask" "F.Paste")
			(net "PVDDQ_DEF")
		)
		(pad "DB61" smd circle
			(at 15.787878 13.215874)
			(size 0.4318 0.4318)
			(layers "F.Cu" "F.Mask" "F.Paste")
			(net "PVDDQ_DEF")
		)
		(pad "DB63" smd circle
			(at 17.504918 13.215874)
			(size 0.4318 0.4318)
			(layers "F.Cu" "F.Mask" "F.Paste")
			(net "PVDDQ_DEF")
		)
		(pad "DB65" smd circle
			(at 19.221958 13.215874)
			(size 0.4318 0.4318)
			(layers "F.Cu" "F.Mask" "F.Paste")
			(net "M_D_ECC<2>")
		)
		(pad "DB67" smd circle
			(at 20.938998 13.215874)
			(size 0.4318 0.4318)
			(layers "F.Cu" "F.Mask" "F.Paste")
			(net "M_D_DQS_DN<17>")
		)
		(pad "DB69" smd circle
			(at 22.656038 13.215874)
			(size 0.4318 0.4318)
			(layers "F.Cu" "F.Mask" "F.Paste")
			(net "M_D_ECC<4>")
		)
		(pad "DB71" smd circle
			(at 24.373078 13.215874)
			(size 0.4318 0.4318)
			(layers "F.Cu" "F.Mask" "F.Paste")
			(net "FM_CPU0_PROC_ID1")
		)
		(pad "DB73" smd circle
			(at 26.090118 13.215874)
			(size 0.4318 0.4318)
			(layers "F.Cu" "F.Mask" "F.Paste")
			(net "GND")
		)
		(pad "DB75" smd circle
			(at 27.806904 13.215874)
			(size 0.4318 0.4318)
			(layers "F.Cu" "F.Mask" "F.Paste")
			(net "M_F_DQ<13>")
		)
		(pad "DB77" smd circle
			(at 29.523944 13.215874)
			(size 0.4318 0.4318)
			(layers "F.Cu" "F.Mask" "F.Paste")
			(net "GND")
		)
		(pad "DB79" smd circle
			(at 31.240984 13.215874)
			(size 0.4318 0.4318)
			(layers "F.Cu" "F.Mask" "F.Paste")
			(net "M_E_DQ<8>")
		)
		(pad "DB81" smd circle
			(at 32.958024 13.215874)
			(size 0.4318 0.4318)
			(layers "F.Cu" "F.Mask" "F.Paste")
			(net "M_E_DQS_DP<1>")
		)
		(pad "DB83" smd circle
			(at 34.675064 13.215874)
			(size 0.4318 0.4318)
			(layers "F.Cu" "F.Mask" "F.Paste")
			(net "GND")
		)
		(pad "DB85" smd circle
			(at 36.392104 13.215874)
			(size 0.4318 0.4318)
			(layers "F.Cu" "F.Mask" "F.Paste")
			(net "GND")
		)
		(pad "DC2" smd custom
			(at -36.392104 15.511526 90)
			(size 0.10795 0.10795)
			(layers "F.Cu" "F.Mask" "F.Paste")
			(net "P3E_CPU0_PE1_SS_TXN<1>")
			(options
				(clearance outline)
				(anchor circle)
			)
			(primitives
				(gr_poly
					(pts
						(arc
							(start 0.2159 -0.0381)
							(mid 0 -0.254)
							(end -0.2159 -0.0381)
						)
						(arc
							(start -0.2159 0.0381)
							(mid 0 0.254)
							(end 0.2159 0.0381)
						)
					)
					(width 0)
					(fill yes)
				)
			)
		)
		(pad "DC4" smd circle
			(at -34.675064 15.511526)
			(size 0.4318 0.4318)
			(layers "F.Cu" "F.Mask" "F.Paste")
			(net "P3E_CPU0_PE1_SS_TXP<3>")
		)
		(pad "DC6" smd circle
			(at -32.958024 15.511526)
			(size 0.4318 0.4318)
			(layers "F.Cu" "F.Mask" "F.Paste")
			(net "P3E_CPU0_PE3_OCP_TXP<13>")
		)
		(pad "DC8" smd circle
			(at -31.240984 15.511526)
			(size 0.4318 0.4318)
			(layers "F.Cu" "F.Mask" "F.Paste")
			(net "P3E_CPU0_PE1_SS_RXN<2>")
		)
		(pad "DC10" smd circle
			(at -29.523944 15.511526)
			(size 0.4318 0.4318)
			(layers "F.Cu" "F.Mask" "F.Paste")
			(net "P3E_CPU0_PE1_SS_RXN<3>")
		)
		(pad "DC12" smd circle
			(at -27.806904 15.511526)
			(size 0.4318 0.4318)
			(layers "F.Cu" "F.Mask" "F.Paste")
			(net "P3E_CPU0_PE3_OCP_RXP<12>")
		)
		(pad "DC14" smd circle
			(at -26.090118 15.511526)
			(size 0.4318 0.4318)
			(layers "F.Cu" "F.Mask" "F.Paste")
			(net "GND")
		)
		(pad "DC16" smd circle
			(at -24.373078 15.511526)
			(size 0.4318 0.4318)
			(layers "F.Cu" "F.Mask" "F.Paste")
			(net "TP_CPU0_UPI2_RSVD_DA16")
		)
		(pad "DC18" smd circle
			(at -22.656038 15.511526)
			(size 0.4318 0.4318)
			(layers "F.Cu" "F.Mask" "F.Paste")
			(net "PVCCIO_CPU0")
		)
		(pad "DC20" smd circle
			(at -20.938998 15.511526)
			(size 0.4318 0.4318)
			(layers "F.Cu" "F.Mask" "F.Paste")
			(net "GND")
		)
		(pad "DC22" smd circle
			(at -19.221958 15.511526)
			(size 0.4318 0.4318)
			(layers "F.Cu" "F.Mask" "F.Paste")
			(net "GND")
		)
		(pad "DC24" smd circle
			(at -17.504918 15.511526)
			(size 0.4318 0.4318)
			(layers "F.Cu" "F.Mask" "F.Paste")
			(net "GND")
		)
		(pad "DC26" smd circle
			(at -15.787878 15.511526)
			(size 0.4318 0.4318)
			(layers "F.Cu" "F.Mask" "F.Paste")
			(net "GND")
		)
		(pad "DC28" smd circle
			(at -14.071092 15.511526)
			(size 0.4318 0.4318)
			(layers "F.Cu" "F.Mask" "F.Paste")
			(net "M_F_DQ<63>")
		)
		(pad "DC30" smd circle
			(at -12.354052 15.511526)
			(size 0.4318 0.4318)
			(layers "F.Cu" "F.Mask" "F.Paste")
			(net "M_F_DQ<57>")
		)
		(pad "DC32" smd circle
			(at -10.637012 15.511526)
			(size 0.4318 0.4318)
			(layers "F.Cu" "F.Mask" "F.Paste")
			(net "GND")
		)
		(pad "DC34" smd circle
			(at -8.919972 15.511526)
			(size 0.4318 0.4318)
			(layers "F.Cu" "F.Mask" "F.Paste")
			(net "M_F_DQ<55>")
		)
		(pad "DC36" smd circle
			(at -7.202932 15.511526)
			(size 0.4318 0.4318)
			(layers "F.Cu" "F.Mask" "F.Paste")
			(net "M_F_DQ<49>")
		)
		(pad "DC38" smd circle
			(at -5.485892 15.511526)
			(size 0.4318 0.4318)
			(layers "F.Cu" "F.Mask" "F.Paste")
			(net "GND")
		)
		(pad "DC40" smd circle
			(at -3.769106 15.511526)
			(size 0.4318 0.4318)
			(layers "F.Cu" "F.Mask" "F.Paste")
			(net "M_F_DQS_DP<13>")
		)
		(pad "DC42" smd circle
			(at -2.052066 15.511526)
			(size 0.4318 0.4318)
			(layers "F.Cu" "F.Mask" "F.Paste")
			(net "GND")
		)
		(pad "DC44" smd circle
			(at 1.193546 13.711428)
			(size 0.508 0.508)
			(layers "F.Cu" "F.Mask" "F.Paste")
			(net "SVID_CLK0_CPU0")
		)
		(pad "DC46" smd circle
			(at 2.910586 13.711428)
			(size 0.4318 0.4318)
			(layers "F.Cu" "F.Mask" "F.Paste")
			(net "TP_CPU0_RSVD_47")
		)
		(pad "DC48" smd circle
			(at 4.627626 13.711428)
			(size 0.4318 0.4318)
			(layers "F.Cu" "F.Mask" "F.Paste")
			(net "A_CPU0_DEF_RCOMP0")
		)
		(pad "DC50" smd circle
			(at 6.344412 13.711428)
			(size 0.4318 0.4318)
			(layers "F.Cu" "F.Mask" "F.Paste")
			(net "PD_CPU0_TEST14")
		)
		(pad "DC52" smd circle
			(at 8.061452 13.711428)
			(size 0.4318 0.4318)
			(layers "F.Cu" "F.Mask" "F.Paste")
			(net "TP_CPU0_RSVD_46")
		)
		(pad "DC54" smd circle
			(at 9.778492 13.711428)
			(size 0.4318 0.4318)
			(layers "F.Cu" "F.Mask" "F.Paste")
			(net "M_F_MA<15>")
		)
		(pad "DC56" smd circle
			(at 11.495532 13.711428)
			(size 0.4318 0.4318)
			(layers "F.Cu" "F.Mask" "F.Paste")
			(net "M_F_BA<1>")
		)
		(pad "DC58" smd circle
			(at 13.212572 13.711428)
			(size 0.4318 0.4318)
			(layers "F.Cu" "F.Mask" "F.Paste")
			(net "M_F_MA<1>")
		)
		(pad "DC60" smd circle
			(at 14.929612 13.711428)
			(size 0.4318 0.4318)
			(layers "F.Cu" "F.Mask" "F.Paste")
			(net "M_F_MA<7>")
		)
		(pad "DC62" smd circle
			(at 16.646398 13.711428)
			(size 0.4318 0.4318)
			(layers "F.Cu" "F.Mask" "F.Paste")
			(net "M_F_ACT_N")
		)
		(pad "DC64" smd circle
			(at 18.363438 13.711428)
			(size 0.4318 0.4318)
			(layers "F.Cu" "F.Mask" "F.Paste")
			(net "GND")
		)
		(pad "DC66" smd circle
			(at 20.080478 13.711428)
			(size 0.4318 0.4318)
			(layers "F.Cu" "F.Mask" "F.Paste")
			(net "GND")
		)
		(pad "DC68" smd circle
			(at 21.797518 13.711428)
			(size 0.4318 0.4318)
			(layers "F.Cu" "F.Mask" "F.Paste")
			(net "GND")
		)
		(pad "DC70" smd circle
			(at 23.514558 13.711428)
			(size 0.4318 0.4318)
			(layers "F.Cu" "F.Mask" "F.Paste")
			(net "GND")
		)
		(pad "DC72" smd circle
			(at 25.231598 13.711428)
			(size 0.4318 0.4318)
			(layers "F.Cu" "F.Mask" "F.Paste")
			(net "FM_CPU0_PKGID0")
		)
		(pad "DC74" smd circle
			(at 26.948384 13.711428)
			(size 0.4318 0.4318)
			(layers "F.Cu" "F.Mask" "F.Paste")
			(net "M_F_DQ<12>")
		)
		(pad "DC76" smd circle
			(at 28.665424 13.711428)
			(size 0.4318 0.4318)
			(layers "F.Cu" "F.Mask" "F.Paste")
			(net "M_F_DQ<9>")
		)
		(pad "DC78" smd circle
			(at 30.382464 13.711428)
			(size 0.4318 0.4318)
			(layers "F.Cu" "F.Mask" "F.Paste")
			(net "GND")
		)
		(pad "DC80" smd circle
			(at 32.099504 13.711428)
			(size 0.4318 0.4318)
			(layers "F.Cu" "F.Mask" "F.Paste")
			(net "M_E_DQS_DN<10>")
		)
		(pad "DC82" smd circle
			(at 33.816544 13.711428)
			(size 0.4318 0.4318)
			(layers "F.Cu" "F.Mask" "F.Paste")
			(net "M_E_DQ<14>")
		)
		(pad "DC84" smd circle
			(at 35.533584 13.711428)
			(size 0.4318 0.4318)
			(layers "F.Cu" "F.Mask" "F.Paste")
			(net "GND")
		)
		(pad "DC86" smd custom
			(at 37.250624 13.711428 270)
			(size 0.10795 0.10795)
			(layers "F.Cu" "F.Mask" "F.Paste")
			(net "GND")
			(options
				(clearance outline)
				(anchor circle)
			)
			(primitives
				(gr_poly
					(pts
						(arc
							(start 0.2159 -0.0381)
							(mid 0 -0.254)
							(end -0.2159 -0.0381)
						)
						(arc
							(start -0.2159 0.0381)
							(mid 0 0.254)
							(end 0.2159 0.0381)
						)
					)
					(width 0)
					(fill yes)
				)
			)
		)
		(pad "DD3" smd circle
			(at -35.533584 16.006572)
			(size 0.4318 0.4318)
			(layers "F.Cu" "F.Mask" "F.Paste")
			(net "P3E_CPU0_PE1_SS_TXP<2>")
		)
		(pad "DD5" smd circle
			(at -33.816544 16.006572)
			(size 0.4318 0.4318)
			(layers "F.Cu" "F.Mask" "F.Paste")
			(net "P3E_CPU0_PE3_OCP_TXN<13>")
		)
		(pad "DD7" smd circle
			(at -32.099504 16.006572)
			(size 0.4318 0.4318)
			(layers "F.Cu" "F.Mask" "F.Paste")
			(net "PVCCIO_CPU0")
		)
		(pad "DD9" smd circle
			(at -30.382464 16.006572)
			(size 0.4318 0.4318)
			(layers "F.Cu" "F.Mask" "F.Paste")
			(net "P3E_CPU0_PE1_SS_RXP<4>")
		)
		(pad "DD11" smd circle
			(at -28.665424 16.006572)
			(size 0.4318 0.4318)
			(layers "F.Cu" "F.Mask" "F.Paste")
			(net "GND")
		)
		(pad "DD13" smd circle
			(at -26.948384 16.006572)
			(size 0.4318 0.4318)
			(layers "F.Cu" "F.Mask" "F.Paste")
			(net "P3E_CPU0_PE3_OCP_RXN<12>")
		)
		(pad "DD15" smd circle
			(at -25.231598 16.006572)
			(size 0.4318 0.4318)
			(layers "F.Cu" "F.Mask" "F.Paste")
			(net "TP_CPU0_UPI2_RSVD_CV13")
		)
		(pad "DD17" smd circle
			(at -23.514558 16.006572)
			(size 0.4318 0.4318)
			(layers "F.Cu" "F.Mask" "F.Paste")
			(net "TP_CPU0_UPI2_RSVD_CU14")
		)
		(pad "DD19" smd circle
			(at -21.797518 16.006572)
			(size 0.4318 0.4318)
			(layers "F.Cu" "F.Mask" "F.Paste")
			(net "GND")
		)
		(pad "DD21" smd circle
			(at -20.080478 16.006572)
			(size 0.4318 0.4318)
			(layers "F.Cu" "F.Mask" "F.Paste")
			(net "GND")
		)
		(pad "DD23" smd circle
			(at -18.363438 16.006572)
			(size 0.4318 0.4318)
			(layers "F.Cu" "F.Mask" "F.Paste")
			(net "GND")
		)
		(pad "DD25" smd circle
			(at -16.646398 16.006572)
			(size 0.4318 0.4318)
			(layers "F.Cu" "F.Mask" "F.Paste")
			(net "M_E_DQ<58>")
		)
		(pad "DD27" smd circle
			(at -14.929612 16.006572)
			(size 0.4318 0.4318)
			(layers "F.Cu" "F.Mask" "F.Paste")
			(net "GND")
		)
		(pad "DD29" smd circle
			(at -13.212572 16.006572)
			(size 0.4318 0.4318)
			(layers "F.Cu" "F.Mask" "F.Paste")
			(net "M_F_DQS_DN<7>")
		)
		(pad "DD31" smd circle
			(at -11.495532 16.006572)
			(size 0.4318 0.4318)
			(layers "F.Cu" "F.Mask" "F.Paste")
			(net "GND")
		)
		(pad "DD33" smd circle
			(at -9.778492 16.006572)
			(size 0.4318 0.4318)
			(layers "F.Cu" "F.Mask" "F.Paste")
			(net "GND")
		)
		(pad "DD35" smd circle
			(at -8.061452 16.006572)
			(size 0.4318 0.4318)
			(layers "F.Cu" "F.Mask" "F.Paste")
			(net "M_F_DQS_DN<6>")
		)
		(pad "DD37" smd circle
			(at -6.344412 16.006572)
			(size 0.4318 0.4318)
			(layers "F.Cu" "F.Mask" "F.Paste")
			(net "GND")
		)
		(pad "DD39" smd circle
			(at -4.627626 16.006572)
			(size 0.4318 0.4318)
			(layers "F.Cu" "F.Mask" "F.Paste")
			(net "M_F_DQ<38>")
		)
		(pad "DD41" smd circle
			(at -2.910586 16.006572)
			(size 0.4318 0.4318)
			(layers "F.Cu" "F.Mask" "F.Paste")
			(net "M_F_DQ<32>")
		)
		(pad "DD45" smd circle
			(at 2.052066 14.206474)
			(size 0.4318 0.4318)
			(layers "F.Cu" "F.Mask" "F.Paste")
			(net "PVDDQ_DEF")
		)
		(pad "DD47" smd circle
			(at 3.769106 14.206474)
			(size 0.4318 0.4318)
			(layers "F.Cu" "F.Mask" "F.Paste")
			(net "A_CPU0_DEF_RCOMP1")
		)
		(pad "DD49" smd circle
			(at 5.485892 14.206474)
			(size 0.4318 0.4318)
			(layers "F.Cu" "F.Mask" "F.Paste")
			(net "A_CPU0_DEF_RCOMP2")
		)
		(pad "DD51" smd circle
			(at 7.202932 14.206474)
			(size 0.4318 0.4318)
			(layers "F.Cu" "F.Mask" "F.Paste")
			(net "TP_CPU0_RSVD_45")
		)
		(pad "DD53" smd circle
			(at 8.919972 14.206474)
			(size 0.4318 0.4318)
			(layers "F.Cu" "F.Mask" "F.Paste")
			(net "M_F_MA<13>")
		)
		(pad "DD55" smd circle
			(at 10.637012 14.206474)
			(size 0.4318 0.4318)
			(layers "F.Cu" "F.Mask" "F.Paste")
			(net "M_F_MA<10>")
		)
		(pad "DD57" smd circle
			(at 12.354052 14.206474)
			(size 0.4318 0.4318)
			(layers "F.Cu" "F.Mask" "F.Paste")
			(net "M_F_MA<2>")
		)
		(pad "DD59" smd circle
			(at 14.071092 14.206474)
			(size 0.4318 0.4318)
			(layers "F.Cu" "F.Mask" "F.Paste")
			(net "M_F_MA<8>")
		)
		(pad "DD61" smd circle
			(at 15.787878 14.206474)
			(size 0.4318 0.4318)
			(layers "F.Cu" "F.Mask" "F.Paste")
			(net "M_F_ALERT_N")
		)
		(pad "DD63" smd circle
			(at 17.504918 14.206474)
			(size 0.4318 0.4318)
			(layers "F.Cu" "F.Mask" "F.Paste")
			(net "M_F_CKE<1>")
		)
		(pad "DD65" smd circle
			(at 19.221958 14.206474)
			(size 0.4318 0.4318)
			(layers "F.Cu" "F.Mask" "F.Paste")
			(net "M_D_ECC<3>")
		)
		(pad "DD67" smd circle
			(at 20.938998 14.206474)
			(size 0.4318 0.4318)
			(layers "F.Cu" "F.Mask" "F.Paste")
			(net "M_D_DQS_DP<8>")
		)
		(pad "DD69" smd circle
			(at 22.656038 14.206474)
			(size 0.4318 0.4318)
			(layers "F.Cu" "F.Mask" "F.Paste")
			(net "M_D_ECC<5>")
		)
		(pad "DD71" smd circle
			(at 24.373078 14.206474)
			(size 0.4318 0.4318)
			(layers "F.Cu" "F.Mask" "F.Paste")
			(net "GND")
		)
		(pad "DD73" smd circle
			(at 26.090118 14.206474)
			(size 0.4318 0.4318)
			(layers "F.Cu" "F.Mask" "F.Paste")
			(net "GND")
		)
		(pad "DD75" smd circle
			(at 27.806904 14.206474)
			(size 0.4318 0.4318)
			(layers "F.Cu" "F.Mask" "F.Paste")
			(net "GND")
		)
		(pad "DD77" smd circle
			(at 29.523944 14.206474)
			(size 0.4318 0.4318)
			(layers "F.Cu" "F.Mask" "F.Paste")
			(net "M_F_DQS_DN<1>")
		)
		(pad "DD79" smd circle
			(at 31.240984 14.206474)
			(size 0.4318 0.4318)
			(layers "F.Cu" "F.Mask" "F.Paste")
			(net "M_E_DQS_DP<10>")
		)
		(pad "DD81" smd circle
			(at 32.958024 14.206474)
			(size 0.4318 0.4318)
			(layers "F.Cu" "F.Mask" "F.Paste")
			(net "GND")
		)
		(pad "DD83" smd circle
			(at 34.675064 14.206474)
			(size 0.4318 0.4318)
			(layers "F.Cu" "F.Mask" "F.Paste")
			(net "GND")
		)
		(pad "DD85" smd custom
			(at 36.392104 14.206474 270)
			(size 0.10795 0.10795)
			(layers "F.Cu" "F.Mask" "F.Paste")
			(net "M_D_DQ<12>")
			(options
				(clearance outline)
				(anchor circle)
			)
			(primitives
				(gr_poly
					(pts
						(arc
							(start 0.2159 -0.0381)
							(mid 0 -0.254)
							(end -0.2159 -0.0381)
						)
						(arc
							(start -0.2159 0.0381)
							(mid 0 0.254)
							(end 0.2159 0.0381)
						)
					)
					(width 0)
					(fill yes)
				)
			)
		)
		(pad "DE2" smd custom
			(at -36.392104 16.502126 90)
			(size 0.10795 0.10795)
			(layers "F.Cu" "F.Mask" "F.Paste")
			(net "P3E_CPU0_PE1_SS_TXN<2>")
			(options
				(clearance outline)
				(anchor circle)
			)
			(primitives
				(gr_poly
					(pts
						(arc
							(start 0.2159 -0.0381)
							(mid 0 -0.254)
							(end -0.2159 -0.0381)
						)
						(arc
							(start -0.2159 0.0381)
							(mid 0 0.254)
							(end 0.2159 0.0381)
						)
					)
					(width 0)
					(fill yes)
				)
			)
		)
		(pad "DE4" smd circle
			(at -34.675064 16.502126)
			(size 0.4318 0.4318)
			(layers "F.Cu" "F.Mask" "F.Paste")
			(net "P3E_CPU0_PE1_SS_TXN<3>")
		)
		(pad "DE6" smd circle
			(at -32.958024 16.502126)
			(size 0.4318 0.4318)
			(layers "F.Cu" "F.Mask" "F.Paste")
			(net "GND")
		)
		(pad "DE8" smd circle
			(at -31.240984 16.502126)
			(size 0.4318 0.4318)
			(layers "F.Cu" "F.Mask" "F.Paste")
			(net "GND")
		)
		(pad "DE10" smd circle
			(at -29.523944 16.502126)
			(size 0.4318 0.4318)
			(layers "F.Cu" "F.Mask" "F.Paste")
			(net "P3E_CPU0_PE1_SS_RXN<4>")
		)
		(pad "DE12" smd circle
			(at -27.806904 16.502126)
			(size 0.4318 0.4318)
			(layers "F.Cu" "F.Mask" "F.Paste")
			(net "P3E_CPU0_PE3_OCP_RXP<10>")
		)
		(pad "DE14" smd circle
			(at -26.090118 16.502126)
			(size 0.4318 0.4318)
			(layers "F.Cu" "F.Mask" "F.Paste")
			(net "PVCCIO_CPU0")
		)
		(pad "DE16" smd circle
			(at -24.373078 16.502126)
			(size 0.4318 0.4318)
			(layers "F.Cu" "F.Mask" "F.Paste")
			(net "TP_CPU0_UPI2_RSVD_CR14")
		)
		(pad "DE18" smd circle
			(at -22.656038 16.502126)
			(size 0.4318 0.4318)
			(layers "F.Cu" "F.Mask" "F.Paste")
			(net "GND")
		)
		(pad "DE20" smd circle
			(at -20.938998 16.502126)
			(size 0.4318 0.4318)
			(layers "F.Cu" "F.Mask" "F.Paste")
			(net "GND")
		)
		(pad "DE22" smd circle
			(at -19.221958 16.502126)
			(size 0.4318 0.4318)
			(layers "F.Cu" "F.Mask" "F.Paste")
			(net "GND")
		)
		(pad "DE24" smd circle
			(at -17.504918 16.502126)
			(size 0.4318 0.4318)
			(layers "F.Cu" "F.Mask" "F.Paste")
			(net "GND")
		)
		(pad "DE26" smd circle
			(at -15.787878 16.502126)
			(size 0.4318 0.4318)
			(layers "F.Cu" "F.Mask" "F.Paste")
			(net "M_E_DQS_DP<16>")
		)
		(pad "DE28" smd circle
			(at -14.071092 16.502126)
			(size 0.4318 0.4318)
			(layers "F.Cu" "F.Mask" "F.Paste")
			(net "GND")
		)
		(pad "DE30" smd circle
			(at -12.354052 16.502126)
			(size 0.4318 0.4318)
			(layers "F.Cu" "F.Mask" "F.Paste")
			(net "GND")
		)
		(pad "DE32" smd circle
			(at -10.637012 16.502126)
			(size 0.4318 0.4318)
			(layers "F.Cu" "F.Mask" "F.Paste")
			(net "M_F_DQS_DP<14>")
		)
		(pad "DE34" smd circle
			(at -8.919972 16.502126)
			(size 0.4318 0.4318)
			(layers "F.Cu" "F.Mask" "F.Paste")
			(net "GND")
		)
		(pad "DE36" smd circle
			(at -7.202932 16.502126)
			(size 0.4318 0.4318)
			(layers "F.Cu" "F.Mask" "F.Paste")
			(net "GND")
		)
		(pad "DE38" smd circle
			(at -5.485892 16.502126)
			(size 0.4318 0.4318)
			(layers "F.Cu" "F.Mask" "F.Paste")
			(net "M_F_DQ<34>")
		)
		(pad "DE40" smd circle
			(at -3.769106 16.502126)
			(size 0.4318 0.4318)
			(layers "F.Cu" "F.Mask" "F.Paste")
			(net "M_F_DQS_DN<13>")
		)
		(pad "DE42" smd circle
			(at -2.052066 16.502126)
			(size 0.4318 0.4318)
			(layers "F.Cu" "F.Mask" "F.Paste")
			(net "M_F_DQ<37>")
		)
		(pad "DE44" smd circle
			(at 1.193546 14.702028)
			(size 0.508 0.508)
			(layers "F.Cu" "F.Mask" "F.Paste")
			(net "SVID_ALERT0_CPU0_N")
		)
		(pad "DE46" smd circle
			(at 2.910586 14.702028)
			(size 0.4318 0.4318)
			(layers "F.Cu" "F.Mask" "F.Paste")
			(net "M_F_MA<17>")
		)
		(pad "DE48" smd circle
			(at 4.627626 14.702028)
			(size 0.4318 0.4318)
			(layers "F.Cu" "F.Mask" "F.Paste")
			(net "GND")
		)
		(pad "DE50" smd circle
			(at 6.344412 14.702028)
			(size 0.4318 0.4318)
			(layers "F.Cu" "F.Mask" "F.Paste")
			(net "GND")
		)
		(pad "DE52" smd circle
			(at 8.061452 14.702028)
			(size 0.4318 0.4318)
			(layers "F.Cu" "F.Mask" "F.Paste")
			(net "GND")
		)
		(pad "DE54" smd circle
			(at 9.778492 14.702028)
			(size 0.4318 0.4318)
			(layers "F.Cu" "F.Mask" "F.Paste")
			(net "GND")
		)
		(pad "DE56" smd circle
			(at 11.495532 14.702028)
			(size 0.4318 0.4318)
			(layers "F.Cu" "F.Mask" "F.Paste")
			(net "GND")
		)
		(pad "DE58" smd circle
			(at 13.212572 14.702028)
			(size 0.4318 0.4318)
			(layers "F.Cu" "F.Mask" "F.Paste")
			(net "GND")
		)
		(pad "DE60" smd circle
			(at 14.929612 14.702028)
			(size 0.4318 0.4318)
			(layers "F.Cu" "F.Mask" "F.Paste")
			(net "GND")
		)
		(pad "DE62" smd circle
			(at 16.646398 14.702028)
			(size 0.4318 0.4318)
			(layers "F.Cu" "F.Mask" "F.Paste")
			(net "GND")
		)
		(pad "DE64" smd circle
			(at 18.363438 14.702028)
			(size 0.4318 0.4318)
			(layers "F.Cu" "F.Mask" "F.Paste")
			(net "GND")
		)
		(pad "DE66" smd circle
			(at 20.080478 14.702028)
			(size 0.4318 0.4318)
			(layers "F.Cu" "F.Mask" "F.Paste")
			(net "M_D_ECC<7>")
		)
		(pad "DE68" smd circle
			(at 21.797518 14.702028)
			(size 0.4318 0.4318)
			(layers "F.Cu" "F.Mask" "F.Paste")
			(net "M_D_ECC<1>")
		)
		(pad "DE70" smd circle
			(at 23.514558 14.702028)
			(size 0.4318 0.4318)
			(layers "F.Cu" "F.Mask" "F.Paste")
			(net "GND")
		)
		(pad "DE72" smd circle
			(at 25.231598 14.702028)
			(size 0.4318 0.4318)
			(layers "F.Cu" "F.Mask" "F.Paste")
			(net "GND")
		)
		(pad "DE74" smd circle
			(at 26.948384 14.702028)
			(size 0.4318 0.4318)
			(layers "F.Cu" "F.Mask" "F.Paste")
			(net "M_F_DQ<8>")
		)
		(pad "DE76" smd circle
			(at 28.665424 14.702028)
			(size 0.4318 0.4318)
			(layers "F.Cu" "F.Mask" "F.Paste")
			(net "M_F_DQS_DP<1>")
		)
		(pad "DE78" smd circle
			(at 30.382464 14.702028)
			(size 0.4318 0.4318)
			(layers "F.Cu" "F.Mask" "F.Paste")
			(net "GND")
		)
		(pad "DE80" smd circle
			(at 32.099504 14.702028)
			(size 0.4318 0.4318)
			(layers "F.Cu" "F.Mask" "F.Paste")
			(net "M_E_DQ<10>")
		)
		(pad "DE82" smd circle
			(at 33.816544 14.702028)
			(size 0.4318 0.4318)
			(layers "F.Cu" "F.Mask" "F.Paste")
			(net "M_E_DQ<15>")
		)
		(pad "DE84" smd circle
			(at 35.533584 14.702028)
			(size 0.4318 0.4318)
			(layers "F.Cu" "F.Mask" "F.Paste")
			(net "M_D_DQ<13>")
		)
		(pad "DF3" smd circle
			(at -35.533584 16.997172)
			(size 0.4318 0.4318)
			(layers "F.Cu" "F.Mask" "F.Paste")
			(net "P3E_CPU0_PE1_SS_TXP<4>")
		)
		(pad "DF5" smd circle
			(at -33.816544 16.997172)
			(size 0.4318 0.4318)
			(layers "F.Cu" "F.Mask" "F.Paste")
			(net "GND")
		)
		(pad "DF7" smd circle
			(at -32.099504 16.997172)
			(size 0.4318 0.4318)
			(layers "F.Cu" "F.Mask" "F.Paste")
			(net "GND")
		)
		(pad "DF9" smd circle
			(at -30.382464 16.997172)
			(size 0.4318 0.4318)
			(layers "F.Cu" "F.Mask" "F.Paste")
			(net "P3E_CPU0_PE1_SS_RXP<5>")
		)
		(pad "DF11" smd circle
			(at -28.665424 16.997172)
			(size 0.4318 0.4318)
			(layers "F.Cu" "F.Mask" "F.Paste")
			(net "P3E_CPU0_PE3_OCP_RXP<11>")
		)
		(pad "DF13" smd circle
			(at -26.948384 16.997172)
			(size 0.4318 0.4318)
			(layers "F.Cu" "F.Mask" "F.Paste")
			(net "PVCCIO_CPU0")
		)
		(pad "DF15" smd circle
			(at -25.231598 16.997172)
			(size 0.4318 0.4318)
			(layers "F.Cu" "F.Mask" "F.Paste")
			(net "TP_CPU0_UPI2_RSVD_CW14")
		)
		(pad "DF17" smd circle
			(at -23.514558 16.997172)
			(size 0.4318 0.4318)
			(layers "F.Cu" "F.Mask" "F.Paste")
			(net "TP_CPU0_UPI2_RSVD_CK13")
		)
		(pad "DF19" smd circle
			(at -21.797518 16.997172)
			(size 0.4318 0.4318)
			(layers "F.Cu" "F.Mask" "F.Paste")
			(net "GND")
		)
		(pad "DF21" smd circle
			(at -20.080478 16.997172)
			(size 0.4318 0.4318)
			(layers "F.Cu" "F.Mask" "F.Paste")
			(net "PVCCIO_CPU0")
		)
		(pad "DF23" smd circle
			(at -18.363438 16.997172)
			(size 0.4318 0.4318)
			(layers "F.Cu" "F.Mask" "F.Paste")
			(net "GND")
		)
		(pad "DF25" smd circle
			(at -16.646398 16.997172)
			(size 0.4318 0.4318)
			(layers "F.Cu" "F.Mask" "F.Paste")
			(net "M_E_DQ<62>")
		)
		(pad "DF27" smd circle
			(at -14.929612 16.997172)
			(size 0.4318 0.4318)
			(layers "F.Cu" "F.Mask" "F.Paste")
			(net "M_E_DQ<56>")
		)
		(pad "DF29" smd circle
			(at -13.212572 16.997172)
			(size 0.4318 0.4318)
			(layers "F.Cu" "F.Mask" "F.Paste")
			(net "GND")
		)
		(pad "DF31" smd circle
			(at -11.495532 16.997172)
			(size 0.4318 0.4318)
			(layers "F.Cu" "F.Mask" "F.Paste")
			(net "M_F_DQ<46>")
		)
		(pad "DF33" smd circle
			(at -9.778492 16.997172)
			(size 0.4318 0.4318)
			(layers "F.Cu" "F.Mask" "F.Paste")
			(net "M_F_DQ<40>")
		)
		(pad "DF35" smd circle
			(at -8.061452 16.997172)
			(size 0.4318 0.4318)
			(layers "F.Cu" "F.Mask" "F.Paste")
			(net "GND")
		)
		(pad "DF37" smd circle
			(at -6.344412 16.997172)
			(size 0.4318 0.4318)
			(layers "F.Cu" "F.Mask" "F.Paste")
			(net "GND")
		)
		(pad "DF39" smd circle
			(at -4.627626 16.997172)
			(size 0.4318 0.4318)
			(layers "F.Cu" "F.Mask" "F.Paste")
			(net "GND")
		)
		(pad "DF41" smd circle
			(at -2.910586 16.997172)
			(size 0.4318 0.4318)
			(layers "F.Cu" "F.Mask" "F.Paste")
			(net "GND")
		)
		(pad "DF45" smd circle
			(at 2.052066 15.197074)
			(size 0.4318 0.4318)
			(layers "F.Cu" "F.Mask" "F.Paste")
			(net "M_F_C<2>")
		)
		(pad "DF47" smd circle
			(at 3.769106 15.197074)
			(size 0.4318 0.4318)
			(layers "F.Cu" "F.Mask" "F.Paste")
			(net "M_F_ODT<3>")
		)
		(pad "DF49" smd circle
			(at 5.485892 15.197074)
			(size 0.4318 0.4318)
			(layers "F.Cu" "F.Mask" "F.Paste")
			(net "M_F_CS_N<1>")
		)
		(pad "DF51" smd circle
			(at 7.202932 15.197074)
			(size 0.4318 0.4318)
			(layers "F.Cu" "F.Mask" "F.Paste")
			(net "M_F_CS_N<4>")
		)
		(pad "DF53" smd circle
			(at 8.919972 15.197074)
			(size 0.4318 0.4318)
			(layers "F.Cu" "F.Mask" "F.Paste")
			(net "M_F_MA<0>")
		)
		(pad "DF55" smd circle
			(at 10.637012 15.197074)
			(size 0.4318 0.4318)
			(layers "F.Cu" "F.Mask" "F.Paste")
			(net "M_F_CLK_DN<1>")
		)
		(pad "DF57" smd circle
			(at 12.354052 15.197074)
			(size 0.4318 0.4318)
			(layers "F.Cu" "F.Mask" "F.Paste")
			(net "M_F_CLK_DN<3>")
		)
		(pad "DF59" smd circle
			(at 14.071092 15.197074)
			(size 0.4318 0.4318)
			(layers "F.Cu" "F.Mask" "F.Paste")
			(net "M_F_MA<5>")
		)
		(pad "DF61" smd circle
			(at 15.787878 15.197074)
			(size 0.4318 0.4318)
			(layers "F.Cu" "F.Mask" "F.Paste")
			(net "M_F_BG<1>")
		)
		(pad "DF63" smd circle
			(at 17.504918 15.197074)
			(size 0.4318 0.4318)
			(layers "F.Cu" "F.Mask" "F.Paste")
			(net "M_F_CKE<3>")
		)
		(pad "DF65" smd circle
			(at 19.221958 15.197074)
			(size 0.4318 0.4318)
			(layers "F.Cu" "F.Mask" "F.Paste")
			(net "GND")
		)
		(pad "DF67" smd circle
			(at 20.938998 15.197074)
			(size 0.4318 0.4318)
			(layers "F.Cu" "F.Mask" "F.Paste")
			(net "M_D_DQS_DN<8>")
		)
		(pad "DF69" smd circle
			(at 22.656038 15.197074)
			(size 0.4318 0.4318)
			(layers "F.Cu" "F.Mask" "F.Paste")
			(net "GND")
		)
		(pad "DF71" smd circle
			(at 24.373078 15.197074)
			(size 0.4318 0.4318)
			(layers "F.Cu" "F.Mask" "F.Paste")
			(net "M_F_DQ<20>")
		)
		(pad "DF73" smd circle
			(at 26.090118 15.197074)
			(size 0.4318 0.4318)
			(layers "F.Cu" "F.Mask" "F.Paste")
			(net "GND")
		)
		(pad "DF75" smd circle
			(at 27.806904 15.197074)
			(size 0.4318 0.4318)
			(layers "F.Cu" "F.Mask" "F.Paste")
			(net "M_F_DQS_DN<10>")
		)
		(pad "DF77" smd circle
			(at 29.523944 15.197074)
			(size 0.4318 0.4318)
			(layers "F.Cu" "F.Mask" "F.Paste")
			(net "M_F_DQ<14>")
		)
		(pad "DF79" smd circle
			(at 31.240984 15.197074)
			(size 0.4318 0.4318)
			(layers "F.Cu" "F.Mask" "F.Paste")
			(net "GND")
		)
		(pad "DF81" smd circle
			(at 32.958024 15.197074)
			(size 0.4318 0.4318)
			(layers "F.Cu" "F.Mask" "F.Paste")
			(net "M_E_DQ<11>")
		)
		(pad "DF83" smd circle
			(at 34.675064 15.197074)
			(size 0.4318 0.4318)
			(layers "F.Cu" "F.Mask" "F.Paste")
			(net "GND")
		)
		(pad "DF85" smd custom
			(at 36.392104 15.197074 270)
			(size 0.10795 0.10795)
			(layers "F.Cu" "F.Mask" "F.Paste")
			(net "GND")
			(options
				(clearance outline)
				(anchor circle)
			)
			(primitives
				(gr_poly
					(pts
						(arc
							(start 0.2159 -0.0381)
							(mid 0 -0.254)
							(end -0.2159 -0.0381)
						)
						(arc
							(start -0.2159 0.0381)
							(mid 0 0.254)
							(end 0.2159 0.0381)
						)
					)
					(width 0)
					(fill yes)
				)
			)
		)
		(pad "DG2" smd custom
			(at -36.392104 17.492726 90)
			(size 0.10795 0.10795)
			(layers "F.Cu" "F.Mask" "F.Paste")
			(net "GND")
			(options
				(clearance outline)
				(anchor circle)
			)
			(primitives
				(gr_poly
					(pts
						(arc
							(start 0.2159 -0.0381)
							(mid 0 -0.254)
							(end -0.2159 -0.0381)
						)
						(arc
							(start -0.2159 0.0381)
							(mid 0 0.254)
							(end 0.2159 0.0381)
						)
					)
					(width 0)
					(fill yes)
				)
			)
		)
		(pad "DG4" smd circle
			(at -34.675064 17.492726)
			(size 0.4318 0.4318)
			(layers "F.Cu" "F.Mask" "F.Paste")
			(net "P3E_CPU0_PE1_SS_TXN<4>")
		)
		(pad "DG6" smd circle
			(at -32.958024 17.492726)
			(size 0.4318 0.4318)
			(layers "F.Cu" "F.Mask" "F.Paste")
			(net "P3E_CPU0_PE3_OCP_TXP<12>")
		)
		(pad "DG8" smd circle
			(at -31.240984 17.492726)
			(size 0.4318 0.4318)
			(layers "F.Cu" "F.Mask" "F.Paste")
			(net "PVCCIO_CPU0")
		)
		(pad "DG10" smd circle
			(at -29.523944 17.492726)
			(size 0.4318 0.4318)
			(layers "F.Cu" "F.Mask" "F.Paste")
			(net "P3E_CPU0_PE3_OCP_RXN<11>")
		)
		(pad "DG12" smd circle
			(at -27.806904 17.492726)
			(size 0.4318 0.4318)
			(layers "F.Cu" "F.Mask" "F.Paste")
			(net "P3E_CPU0_PE3_OCP_RXN<10>")
		)
		(pad "DG14" smd circle
			(at -26.090118 17.492726)
			(size 0.4318 0.4318)
			(layers "F.Cu" "F.Mask" "F.Paste")
			(net "GND")
		)
		(pad "DG16" smd circle
			(at -24.373078 17.492726)
			(size 0.4318 0.4318)
			(layers "F.Cu" "F.Mask" "F.Paste")
			(net "GND")
		)
		(pad "DG18" smd circle
			(at -22.656038 17.492726)
			(size 0.4318 0.4318)
			(layers "F.Cu" "F.Mask" "F.Paste")
			(net "TP_CPU0_UPI2_RSVD_CM13")
		)
		(pad "DG20" smd circle
			(at -20.938998 17.492726)
			(size 0.4318 0.4318)
			(layers "F.Cu" "F.Mask" "F.Paste")
			(net "TP_CPU0_UPI2_RSVD_CH11")
		)
		(pad "DG22" smd circle
			(at -19.221958 17.492726)
			(size 0.4318 0.4318)
			(layers "F.Cu" "F.Mask" "F.Paste")
			(net "GND")
		)
		(pad "DG24" smd circle
			(at -17.504918 17.492726)
			(size 0.4318 0.4318)
			(layers "F.Cu" "F.Mask" "F.Paste")
			(net "GND")
		)
		(pad "DG26" smd circle
			(at -15.787878 17.492726)
			(size 0.4318 0.4318)
			(layers "F.Cu" "F.Mask" "F.Paste")
			(net "M_E_DQS_DN<16>")
		)
		(pad "DG28" smd circle
			(at -14.071092 17.492726)
			(size 0.4318 0.4318)
			(layers "F.Cu" "F.Mask" "F.Paste")
			(net "M_E_DQ<60>")
		)
		(pad "DG30" smd circle
			(at -12.354052 17.492726)
			(size 0.4318 0.4318)
			(layers "F.Cu" "F.Mask" "F.Paste")
			(net "M_F_DQ<42>")
		)
		(pad "DG32" smd circle
			(at -10.637012 17.492726)
			(size 0.4318 0.4318)
			(layers "F.Cu" "F.Mask" "F.Paste")
			(net "M_F_DQS_DN<14>")
		)
		(pad "DG34" smd circle
			(at -8.919972 17.492726)
			(size 0.4318 0.4318)
			(layers "F.Cu" "F.Mask" "F.Paste")
			(net "M_F_DQ<44>")
		)
		(pad "DG36" smd circle
			(at -7.202932 17.492726)
			(size 0.4318 0.4318)
			(layers "F.Cu" "F.Mask" "F.Paste")
			(net "TP_CPU0_RSVD_44")
		)
		(pad "DG38" smd circle
			(at -5.485892 17.492726)
			(size 0.4318 0.4318)
			(layers "F.Cu" "F.Mask" "F.Paste")
			(net "M_F_DQ<35>")
		)
		(pad "DG40" smd circle
			(at -3.769106 17.492726)
			(size 0.4318 0.4318)
			(layers "F.Cu" "F.Mask" "F.Paste")
			(net "M_F_DQS_DN<4>")
		)
		(pad "DG42" smd circle
			(at -2.052066 17.492726)
			(size 0.4318 0.4318)
			(layers "F.Cu" "F.Mask" "F.Paste")
			(net "M_F_DQ<33>")
		)
		(pad "DG44" smd circle
			(at 1.193546 15.692628)
			(size 0.508 0.508)
			(layers "F.Cu" "F.Mask" "F.Paste")
			(net "SVID_CLK1_CPU0")
		)
		(pad "DG46" smd circle
			(at 2.910586 15.692628)
			(size 0.4318 0.4318)
			(layers "F.Cu" "F.Mask" "F.Paste")
			(net "M_F_CS_N<3>")
		)
		(pad "DG48" smd circle
			(at 4.627626 15.692628)
			(size 0.4318 0.4318)
			(layers "F.Cu" "F.Mask" "F.Paste")
			(net "M_F_ODT<1>")
		)
		(pad "DG50" smd circle
			(at 6.344412 15.692628)
			(size 0.4318 0.4318)
			(layers "F.Cu" "F.Mask" "F.Paste")
			(net "M_F_ODT<0>")
		)
		(pad "DG52" smd circle
			(at 8.061452 15.692628)
			(size 0.4318 0.4318)
			(layers "F.Cu" "F.Mask" "F.Paste")
			(net "M_F_MA<16>")
		)
		(pad "DG54" smd circle
			(at 9.778492 15.692628)
			(size 0.4318 0.4318)
			(layers "F.Cu" "F.Mask" "F.Paste")
			(net "M_F_CLK_DP<1>")
		)
		(pad "DG56" smd circle
			(at 11.495532 15.692628)
			(size 0.4318 0.4318)
			(layers "F.Cu" "F.Mask" "F.Paste")
			(net "M_F_CLK_DP<3>")
		)
		(pad "DG58" smd circle
			(at 13.212572 15.692628)
			(size 0.4318 0.4318)
			(layers "F.Cu" "F.Mask" "F.Paste")
			(net "M_F_MA<3>")
		)
		(pad "DG60" smd circle
			(at 14.929612 15.692628)
			(size 0.4318 0.4318)
			(layers "F.Cu" "F.Mask" "F.Paste")
			(net "M_F_MA<12>")
		)
		(pad "DG62" smd circle
			(at 16.646398 15.692628)
			(size 0.4318 0.4318)
			(layers "F.Cu" "F.Mask" "F.Paste")
			(net "M_F_CKE<0>")
		)
		(pad "DG64" smd circle
			(at 18.363438 15.692628)
			(size 0.4318 0.4318)
			(layers "F.Cu" "F.Mask" "F.Paste")
			(net "TP_CPU0_RSVD_43")
		)
		(pad "DG66" smd circle
			(at 20.080478 15.692628)
			(size 0.4318 0.4318)
			(layers "F.Cu" "F.Mask" "F.Paste")
			(net "GND")
		)
		(pad "DG68" smd circle
			(at 21.797518 15.692628)
			(size 0.4318 0.4318)
			(layers "F.Cu" "F.Mask" "F.Paste")
			(net "GND")
		)
		(pad "DG70" smd circle
			(at 23.514558 15.692628)
			(size 0.4318 0.4318)
			(layers "F.Cu" "F.Mask" "F.Paste")
			(net "M_F_DQ<16>")
		)
		(pad "DG72" smd circle
			(at 25.231598 15.692628)
			(size 0.4318 0.4318)
			(layers "F.Cu" "F.Mask" "F.Paste")
			(net "M_F_DQ<21>")
		)
		(pad "DG74" smd circle
			(at 26.948384 15.692628)
			(size 0.4318 0.4318)
			(layers "F.Cu" "F.Mask" "F.Paste")
			(net "M_F_DQS_DP<10>")
		)
		(pad "DG76" smd circle
			(at 28.665424 15.692628)
			(size 0.4318 0.4318)
			(layers "F.Cu" "F.Mask" "F.Paste")
			(net "GND")
		)
		(pad "DG78" smd circle
			(at 30.382464 15.692628)
			(size 0.4318 0.4318)
			(layers "F.Cu" "F.Mask" "F.Paste")
			(net "GND")
		)
		(pad "DG80" smd circle
			(at 32.099504 15.692628)
			(size 0.4318 0.4318)
			(layers "F.Cu" "F.Mask" "F.Paste")
			(net "GND")
		)
		(pad "DG82" smd circle
			(at 33.816544 15.692628)
			(size 0.4318 0.4318)
			(layers "F.Cu" "F.Mask" "F.Paste")
			(net "GND")
		)
		(pad "DG84" smd circle
			(at 35.533584 15.692628)
			(size 0.4318 0.4318)
			(layers "F.Cu" "F.Mask" "F.Paste")
			(net "M_D_DQ<8>")
		)
		(pad "DH3" smd circle
			(at -35.533584 17.988026)
			(size 0.4318 0.4318)
			(layers "F.Cu" "F.Mask" "F.Paste")
			(net "P3E_CPU0_PE1_SS_TXP<5>")
		)
		(pad "DH5" smd circle
			(at -33.816544 17.988026)
			(size 0.4318 0.4318)
			(layers "F.Cu" "F.Mask" "F.Paste")
			(net "P3E_CPU0_PE3_OCP_TXP<11>")
		)
		(pad "DH7" smd circle
			(at -32.099504 17.988026)
			(size 0.4318 0.4318)
			(layers "F.Cu" "F.Mask" "F.Paste")
			(net "PVCCIO_CPU0")
		)
		(pad "DH9" smd circle
			(at -30.382464 17.988026)
			(size 0.4318 0.4318)
			(layers "F.Cu" "F.Mask" "F.Paste")
			(net "P3E_CPU0_PE1_SS_RXN<5>")
		)
		(pad "DH11" smd circle
			(at -28.665424 17.988026)
			(size 0.4318 0.4318)
			(layers "F.Cu" "F.Mask" "F.Paste")
			(net "P3E_CPU0_PE3_OCP_RXP<9>")
		)
		(pad "DH13" smd circle
			(at -26.948384 17.988026)
			(size 0.4318 0.4318)
			(layers "F.Cu" "F.Mask" "F.Paste")
			(net "GND")
		)
		(pad "DH15" smd circle
			(at -25.231598 17.988026)
			(size 0.4318 0.4318)
			(layers "F.Cu" "F.Mask" "F.Paste")
			(net "GND")
		)
		(pad "DH17" smd circle
			(at -23.514558 17.988026)
			(size 0.4318 0.4318)
			(layers "F.Cu" "F.Mask" "F.Paste")
			(net "TP_CPU0_UPI2_RSVD_CH13")
		)
		(pad "DH19" smd circle
			(at -21.797518 17.988026)
			(size 0.4318 0.4318)
			(layers "F.Cu" "F.Mask" "F.Paste")
			(net "TP_CPU0_UPI2_RSVD_CF13")
		)
		(pad "DH21" smd circle
			(at -20.080478 17.988026)
			(size 0.4318 0.4318)
			(layers "F.Cu" "F.Mask" "F.Paste")
			(net "GND")
		)
		(pad "DH23" smd circle
			(at -18.363438 17.988026)
			(size 0.4318 0.4318)
			(layers "F.Cu" "F.Mask" "F.Paste")
			(net "GND")
		)
		(pad "DH25" smd circle
			(at -16.646398 17.988026)
			(size 0.4318 0.4318)
			(layers "F.Cu" "F.Mask" "F.Paste")
			(net "GND")
		)
		(pad "DH27" smd circle
			(at -14.929612 17.988026)
			(size 0.4318 0.4318)
			(layers "F.Cu" "F.Mask" "F.Paste")
			(net "GND")
		)
		(pad "DH29" smd circle
			(at -13.212572 17.988026)
			(size 0.4318 0.4318)
			(layers "F.Cu" "F.Mask" "F.Paste")
			(net "GND")
		)
		(pad "DH31" smd circle
			(at -11.495532 17.988026)
			(size 0.4318 0.4318)
			(layers "F.Cu" "F.Mask" "F.Paste")
			(net "GND")
		)
		(pad "DH33" smd circle
			(at -9.778492 17.988026)
			(size 0.4318 0.4318)
			(layers "F.Cu" "F.Mask" "F.Paste")
			(net "GND")
		)
		(pad "DH35" smd circle
			(at -8.061452 17.988026)
			(size 0.4318 0.4318)
			(layers "F.Cu" "F.Mask" "F.Paste")
			(net "GND")
		)
		(pad "DH37" smd circle
			(at -6.344412 17.988026)
			(size 0.4318 0.4318)
			(layers "F.Cu" "F.Mask" "F.Paste")
			(net "GND")
		)
		(pad "DH39" smd circle
			(at -4.627626 17.988026)
			(size 0.4318 0.4318)
			(layers "F.Cu" "F.Mask" "F.Paste")
			(net "M_F_DQ<39>")
		)
		(pad "DH41" smd circle
			(at -2.910586 17.988026)
			(size 0.4318 0.4318)
			(layers "F.Cu" "F.Mask" "F.Paste")
			(net "GND")
		)
		(pad "DH45" smd circle
			(at 2.052066 16.187674)
			(size 0.4318 0.4318)
			(layers "F.Cu" "F.Mask" "F.Paste")
			(net "PVDDQ_DEF")
		)
		(pad "DH47" smd circle
			(at 3.769106 16.187674)
			(size 0.4318 0.4318)
			(layers "F.Cu" "F.Mask" "F.Paste")
			(net "PVDDQ_DEF")
		)
		(pad "DH49" smd circle
			(at 5.485892 16.187674)
			(size 0.4318 0.4318)
			(layers "F.Cu" "F.Mask" "F.Paste")
			(net "PVDDQ_DEF")
		)
		(pad "DH51" smd circle
			(at 7.202932 16.187674)
			(size 0.4318 0.4318)
			(layers "F.Cu" "F.Mask" "F.Paste")
			(net "PVDDQ_DEF")
		)
		(pad "DH53" smd circle
			(at 8.919972 16.187674)
			(size 0.4318 0.4318)
			(layers "F.Cu" "F.Mask" "F.Paste")
			(net "PVDDQ_DEF")
		)
		(pad "DH55" smd circle
			(at 10.637012 16.187674)
			(size 0.4318 0.4318)
			(layers "F.Cu" "F.Mask" "F.Paste")
			(net "PVDDQ_DEF")
		)
		(pad "DH57" smd circle
			(at 12.354052 16.187674)
			(size 0.4318 0.4318)
			(layers "F.Cu" "F.Mask" "F.Paste")
			(net "PVDDQ_DEF")
		)
		(pad "DH59" smd circle
			(at 14.071092 16.187674)
			(size 0.4318 0.4318)
			(layers "F.Cu" "F.Mask" "F.Paste")
			(net "PVDDQ_DEF")
		)
		(pad "DH61" smd circle
			(at 15.787878 16.187674)
			(size 0.4318 0.4318)
			(layers "F.Cu" "F.Mask" "F.Paste")
			(net "PVDDQ_DEF")
		)
		(pad "DH63" smd circle
			(at 17.504918 16.187674)
			(size 0.4318 0.4318)
			(layers "F.Cu" "F.Mask" "F.Paste")
			(net "PVDDQ_DEF")
		)
		(pad "DH65" smd circle
			(at 19.221958 16.187674)
			(size 0.4318 0.4318)
			(layers "F.Cu" "F.Mask" "F.Paste")
			(net "TP_CPU0_RSVD_42")
		)
		(pad "DH67" smd circle
			(at 20.938998 16.187674)
			(size 0.4318 0.4318)
			(layers "F.Cu" "F.Mask" "F.Paste")
			(net "GND")
		)
		(pad "DH69" smd circle
			(at 22.656038 16.187674)
			(size 0.4318 0.4318)
			(layers "F.Cu" "F.Mask" "F.Paste")
			(net "M_F_DQS_DP<11>")
		)
		(pad "DH71" smd circle
			(at 24.373078 16.187674)
			(size 0.4318 0.4318)
			(layers "F.Cu" "F.Mask" "F.Paste")
			(net "GND")
		)
		(pad "DH73" smd circle
			(at 26.090118 16.187674)
			(size 0.4318 0.4318)
			(layers "F.Cu" "F.Mask" "F.Paste")
			(net "GND")
		)
		(pad "DH75" smd circle
			(at 27.806904 16.187674)
			(size 0.4318 0.4318)
			(layers "F.Cu" "F.Mask" "F.Paste")
			(net "M_F_DQ<10>")
		)
		(pad "DH77" smd circle
			(at 29.523944 16.187674)
			(size 0.4318 0.4318)
			(layers "F.Cu" "F.Mask" "F.Paste")
			(net "M_F_DQ<15>")
		)
		(pad "DH79" smd circle
			(at 31.240984 16.187674)
			(size 0.4318 0.4318)
			(layers "F.Cu" "F.Mask" "F.Paste")
			(net "GND")
		)
		(pad "DH81" smd circle
			(at 32.958024 16.187674)
			(size 0.4318 0.4318)
			(layers "F.Cu" "F.Mask" "F.Paste")
			(net "GND")
		)
		(pad "DH83" smd circle
			(at 34.675064 16.187674)
			(size 0.4318 0.4318)
			(layers "F.Cu" "F.Mask" "F.Paste")
			(net "GND")
		)
		(pad "DH85" smd custom
			(at 36.392104 16.187674 270)
			(size 0.10795 0.10795)
			(layers "F.Cu" "F.Mask" "F.Paste")
			(net "M_D_DQ<9>")
			(options
				(clearance outline)
				(anchor circle)
			)
			(primitives
				(gr_poly
					(pts
						(arc
							(start 0.2159 -0.0381)
							(mid 0 -0.254)
							(end -0.2159 -0.0381)
						)
						(arc
							(start -0.2159 0.0381)
							(mid 0 0.254)
							(end 0.2159 0.0381)
						)
					)
					(width 0)
					(fill yes)
				)
			)
		)
		(pad "DJ2" smd custom
			(at -36.392104 18.483072 90)
			(size 0.10795 0.10795)
			(layers "F.Cu" "F.Mask" "F.Paste")
			(net "GND")
			(options
				(clearance outline)
				(anchor circle)
			)
			(primitives
				(gr_poly
					(pts
						(arc
							(start 0.2159 -0.0381)
							(mid 0 -0.254)
							(end -0.2159 -0.0381)
						)
						(arc
							(start -0.2159 0.0381)
							(mid 0 0.254)
							(end 0.2159 0.0381)
						)
					)
					(width 0)
					(fill yes)
				)
			)
		)
		(pad "DJ4" smd circle
			(at -34.675064 18.483072)
			(size 0.4318 0.4318)
			(layers "F.Cu" "F.Mask" "F.Paste")
			(net "P3E_CPU0_PE3_OCP_TXN<11>")
		)
		(pad "DJ6" smd circle
			(at -32.958024 18.483072)
			(size 0.4318 0.4318)
			(layers "F.Cu" "F.Mask" "F.Paste")
			(net "P3E_CPU0_PE3_OCP_TXN<12>")
		)
		(pad "DJ8" smd circle
			(at -31.240984 18.483072)
			(size 0.4318 0.4318)
			(layers "F.Cu" "F.Mask" "F.Paste")
			(net "P3E_CPU0_PE1_SS_RXP<6>")
		)
		(pad "DJ10" smd circle
			(at -29.523944 18.483072)
			(size 0.4318 0.4318)
			(layers "F.Cu" "F.Mask" "F.Paste")
			(net "GND")
		)
		(pad "DJ12" smd circle
			(at -27.806904 18.483072)
			(size 0.4318 0.4318)
			(layers "F.Cu" "F.Mask" "F.Paste")
			(net "P3E_CPU0_PE3_OCP_RXN<9>")
		)
		(pad "DJ14" smd circle
			(at -26.090118 18.483072)
			(size 0.4318 0.4318)
			(layers "F.Cu" "F.Mask" "F.Paste")
			(net "P3E_CPU0_PE3_OCP_RXP<7>")
		)
		(pad "DJ16" smd circle
			(at -24.373078 18.483072)
			(size 0.4318 0.4318)
			(layers "F.Cu" "F.Mask" "F.Paste")
			(net "PVCCIO_CPU0")
		)
		(pad "DJ18" smd circle
			(at -22.656038 18.483072)
			(size 0.4318 0.4318)
			(layers "F.Cu" "F.Mask" "F.Paste")
			(net "TP_CPU0_UPI2_RSVD_CG12")
		)
		(pad "DJ20" smd circle
			(at -20.938998 18.483072)
			(size 0.4318 0.4318)
			(layers "F.Cu" "F.Mask" "F.Paste")
			(net "TP_CPU0_UPI2_RSVD_CF11")
		)
		(pad "DJ22" smd circle
			(at -19.221958 18.483072)
			(size 0.4318 0.4318)
			(layers "F.Cu" "F.Mask" "F.Paste")
			(net "GND")
		)
		(pad "DJ24" smd circle
			(at -17.504918 18.483072)
			(size 0.4318 0.4318)
			(layers "F.Cu" "F.Mask" "F.Paste")
			(net "M_E_DQ<59>")
		)
		(pad "DJ26" smd circle
			(at -15.787878 18.483072)
			(size 0.4318 0.4318)
			(layers "F.Cu" "F.Mask" "F.Paste")
			(net "M_E_DQS_DP<7>")
		)
		(pad "DJ28" smd circle
			(at -14.071092 18.483072)
			(size 0.4318 0.4318)
			(layers "F.Cu" "F.Mask" "F.Paste")
			(net "M_E_DQ<61>")
		)
		(pad "DJ30" smd circle
			(at -12.354052 18.483072)
			(size 0.4318 0.4318)
			(layers "F.Cu" "F.Mask" "F.Paste")
			(net "M_F_DQ<43>")
		)
		(pad "DJ32" smd circle
			(at -10.637012 18.483072)
			(size 0.4318 0.4318)
			(layers "F.Cu" "F.Mask" "F.Paste")
			(net "M_F_DQS_DP<5>")
		)
		(pad "DJ34" smd circle
			(at -8.919972 18.483072)
			(size 0.4318 0.4318)
			(layers "F.Cu" "F.Mask" "F.Paste")
			(net "M_F_DQ<45>")
		)
		(pad "DJ36" smd circle
			(at -7.202932 18.483072)
			(size 0.4318 0.4318)
			(layers "F.Cu" "F.Mask" "F.Paste")
			(net "TP_CPU0_RSVD_41")
		)
		(pad "DJ38" smd circle
			(at -5.485892 18.483072)
			(size 0.4318 0.4318)
			(layers "F.Cu" "F.Mask" "F.Paste")
			(net "GND")
		)
		(pad "DJ40" smd circle
			(at -3.769106 18.483072)
			(size 0.4318 0.4318)
			(layers "F.Cu" "F.Mask" "F.Paste")
			(net "M_F_DQS_DP<4>")
		)
		(pad "DJ42" smd circle
			(at -2.052066 18.483072)
			(size 0.4318 0.4318)
			(layers "F.Cu" "F.Mask" "F.Paste")
			(net "GND")
		)
		(pad "DJ44" smd circle
			(at 1.193546 16.683228)
			(size 0.508 0.508)
			(layers "F.Cu" "F.Mask" "F.Paste")
			(net "SVID_DIO1_CPU0")
		)
		(pad "DJ46" smd circle
			(at 2.910586 16.683228)
			(size 0.4318 0.4318)
			(layers "F.Cu" "F.Mask" "F.Paste")
			(net "M_F_CS_N<2>")
		)
		(pad "DJ48" smd circle
			(at 4.627626 16.683228)
			(size 0.4318 0.4318)
			(layers "F.Cu" "F.Mask" "F.Paste")
			(net "M_F_CS_N<5>")
		)
		(pad "DJ50" smd circle
			(at 6.344412 16.683228)
			(size 0.4318 0.4318)
			(layers "F.Cu" "F.Mask" "F.Paste")
			(net "M_F_MA<14>")
		)
		(pad "DJ52" smd circle
			(at 8.061452 16.683228)
			(size 0.4318 0.4318)
			(layers "F.Cu" "F.Mask" "F.Paste")
			(net "M_F_BA<0>")
		)
		(pad "DJ54" smd circle
			(at 9.778492 16.683228)
			(size 0.4318 0.4318)
			(layers "F.Cu" "F.Mask" "F.Paste")
			(net "M_F_CLK_DP<0>")
		)
		(pad "DJ56" smd circle
			(at 11.495532 16.683228)
			(size 0.4318 0.4318)
			(layers "F.Cu" "F.Mask" "F.Paste")
			(net "M_F_CLK_DP<2>")
		)
		(pad "DJ58" smd circle
			(at 13.212572 16.683228)
			(size 0.4318 0.4318)
			(layers "F.Cu" "F.Mask" "F.Paste")
			(net "M_F_MA<4>")
		)
		(pad "DJ60" smd circle
			(at 14.929612 16.683228)
			(size 0.4318 0.4318)
			(layers "F.Cu" "F.Mask" "F.Paste")
			(net "M_E_MA<8>")
		)
		(pad "DJ62" smd circle
			(at 16.646398 16.683228)
			(size 0.4318 0.4318)
			(layers "F.Cu" "F.Mask" "F.Paste")
			(net "M_E_BG<0>")
		)
		(pad "DJ64" smd circle
			(at 18.363438 16.683228)
			(size 0.4318 0.4318)
			(layers "F.Cu" "F.Mask" "F.Paste")
			(net "PVDDQ_DEF")
		)
		(pad "DJ66" smd circle
			(at 20.080478 16.683228)
			(size 0.4318 0.4318)
			(layers "F.Cu" "F.Mask" "F.Paste")
			(net "TP_CPU0_RSVD_40")
		)
		(pad "DJ68" smd circle
			(at 21.797518 16.683228)
			(size 0.4318 0.4318)
			(layers "F.Cu" "F.Mask" "F.Paste")
			(net "GND")
		)
		(pad "DJ70" smd circle
			(at 23.514558 16.683228)
			(size 0.4318 0.4318)
			(layers "F.Cu" "F.Mask" "F.Paste")
			(net "M_F_DQS_DN<11>")
		)
		(pad "DJ72" smd circle
			(at 25.231598 16.683228)
			(size 0.4318 0.4318)
			(layers "F.Cu" "F.Mask" "F.Paste")
			(net "M_F_DQ<17>")
		)
		(pad "DJ74" smd circle
			(at 26.948384 16.683228)
			(size 0.4318 0.4318)
			(layers "F.Cu" "F.Mask" "F.Paste")
			(net "GND")
		)
		(pad "DJ76" smd circle
			(at 28.665424 16.683228)
			(size 0.4318 0.4318)
			(layers "F.Cu" "F.Mask" "F.Paste")
			(net "M_F_DQ<11>")
		)
		(pad "DJ78" smd circle
			(at 30.382464 16.683228)
			(size 0.4318 0.4318)
			(layers "F.Cu" "F.Mask" "F.Paste")
			(net "GND")
		)
		(pad "DJ80" smd circle
			(at 32.099504 16.683228)
			(size 0.4318 0.4318)
			(layers "F.Cu" "F.Mask" "F.Paste")
			(net "M_D_DQ<21>")
		)
		(pad "DJ82" smd circle
			(at 33.816544 16.683228)
			(size 0.4318 0.4318)
			(layers "F.Cu" "F.Mask" "F.Paste")
			(net "GND")
		)
		(pad "DJ84" smd circle
			(at 35.533584 16.683228)
			(size 0.4318 0.4318)
			(layers "F.Cu" "F.Mask" "F.Paste")
			(net "GND")
		)
		(pad "DK3" smd circle
			(at -35.533584 18.978372)
			(size 0.4318 0.4318)
			(layers "F.Cu" "F.Mask" "F.Paste")
			(net "P3E_CPU0_PE1_SS_TXN<5>")
		)
		(pad "DK5" smd circle
			(at -33.816544 18.978372)
			(size 0.4318 0.4318)
			(layers "F.Cu" "F.Mask" "F.Paste")
			(net "P3E_CPU0_PE3_OCP_TXP<10>")
		)
		(pad "DK7" smd circle
			(at -32.099504 18.978372)
			(size 0.4318 0.4318)
			(layers "F.Cu" "F.Mask" "F.Paste")
			(net "GND")
		)
		(pad "DK9" smd circle
			(at -30.382464 18.978372)
			(size 0.4318 0.4318)
			(layers "F.Cu" "F.Mask" "F.Paste")
			(net "P3E_CPU0_PE1_SS_RXN<6>")
		)
		(pad "DK11" smd circle
			(at -28.665424 18.978372)
			(size 0.4318 0.4318)
			(layers "F.Cu" "F.Mask" "F.Paste")
			(net "P3E_CPU0_PE1_PCH_RXP<8>")
		)
		(pad "DK13" smd circle
			(at -26.948384 18.978372)
			(size 0.4318 0.4318)
			(layers "F.Cu" "F.Mask" "F.Paste")
			(net "P3E_CPU0_PE3_OCP_RXP<8>")
		)
		(pad "DK15" smd circle
			(at -25.231598 18.978372)
			(size 0.4318 0.4318)
			(layers "F.Cu" "F.Mask" "F.Paste")
			(net "TP_CPU0_RSVD_39")
		)
		(pad "DK17" smd circle
			(at -23.514558 18.978372)
			(size 0.4318 0.4318)
			(layers "F.Cu" "F.Mask" "F.Paste")
			(net "TP_CPU0_UPI2_RSVD_CJ14")
		)
		(pad "DK19" smd circle
			(at -21.797518 18.978372)
			(size 0.4318 0.4318)
			(layers "F.Cu" "F.Mask" "F.Paste")
			(net "TP_CPU0_UPI2_RSVD_CD11")
		)
		(pad "DK21" smd circle
			(at -20.080478 18.978372)
			(size 0.4318 0.4318)
			(layers "F.Cu" "F.Mask" "F.Paste")
			(net "PVCCIO_CPU0")
		)
		(pad "DK23" smd circle
			(at -18.363438 18.978372)
			(size 0.4318 0.4318)
			(layers "F.Cu" "F.Mask" "F.Paste")
			(net "GND")
		)
		(pad "DK25" smd circle
			(at -16.646398 18.978372)
			(size 0.4318 0.4318)
			(layers "F.Cu" "F.Mask" "F.Paste")
			(net "M_E_DQ<63>")
		)
		(pad "DK27" smd circle
			(at -14.929612 18.978372)
			(size 0.4318 0.4318)
			(layers "F.Cu" "F.Mask" "F.Paste")
			(net "M_E_DQ<57>")
		)
		(pad "DK29" smd circle
			(at -13.212572 18.978372)
			(size 0.4318 0.4318)
			(layers "F.Cu" "F.Mask" "F.Paste")
			(net "GND")
		)
		(pad "DK31" smd circle
			(at -11.495532 18.978372)
			(size 0.4318 0.4318)
			(layers "F.Cu" "F.Mask" "F.Paste")
			(net "M_F_DQ<47>")
		)
		(pad "DK33" smd circle
			(at -9.778492 18.978372)
			(size 0.4318 0.4318)
			(layers "F.Cu" "F.Mask" "F.Paste")
			(net "M_F_DQ<41>")
		)
		(pad "DK35" smd circle
			(at -8.061452 18.978372)
			(size 0.4318 0.4318)
			(layers "F.Cu" "F.Mask" "F.Paste")
			(net "GND")
		)
		(pad "DK37" smd circle
			(at -6.344412 18.978372)
			(size 0.4318 0.4318)
			(layers "F.Cu" "F.Mask" "F.Paste")
			(net "TP_CPU0_RSVD_38")
		)
		(pad "DK39" smd circle
			(at -4.627626 18.978372)
			(size 0.4318 0.4318)
			(layers "F.Cu" "F.Mask" "F.Paste")
			(net "GND")
		)
		(pad "DK41" smd circle
			(at -2.910586 18.978372)
			(size 0.4318 0.4318)
			(layers "F.Cu" "F.Mask" "F.Paste")
			(net "GND")
		)
		(pad "DK45" smd circle
			(at 2.052066 17.178528)
			(size 0.4318 0.4318)
			(layers "F.Cu" "F.Mask" "F.Paste")
			(net "M_F_CS_N<7>")
		)
		(pad "DK47" smd circle
			(at 3.769106 17.178528)
			(size 0.4318 0.4318)
			(layers "F.Cu" "F.Mask" "F.Paste")
			(net "M_E_CS_N<3>")
		)
		(pad "DK49" smd circle
			(at 5.485892 17.178528)
			(size 0.4318 0.4318)
			(layers "F.Cu" "F.Mask" "F.Paste")
			(net "M_F_ODT<2>")
		)
		(pad "DK51" smd circle
			(at 7.202932 17.178528)
			(size 0.4318 0.4318)
			(layers "F.Cu" "F.Mask" "F.Paste")
			(net "M_F_CS_N<0>")
		)
		(pad "DK53" smd circle
			(at 8.919972 17.178528)
			(size 0.4318 0.4318)
			(layers "F.Cu" "F.Mask" "F.Paste")
			(net "M_F_PAR")
		)
		(pad "DK55" smd circle
			(at 10.637012 17.178528)
			(size 0.4318 0.4318)
			(layers "F.Cu" "F.Mask" "F.Paste")
			(net "M_F_CLK_DN<0>")
		)
		(pad "DK57" smd circle
			(at 12.354052 17.178528)
			(size 0.4318 0.4318)
			(layers "F.Cu" "F.Mask" "F.Paste")
			(net "M_F_CLK_DN<2>")
		)
		(pad "DK59" smd circle
			(at 14.071092 17.178528)
			(size 0.4318 0.4318)
			(layers "F.Cu" "F.Mask" "F.Paste")
			(net "M_F_MA<6>")
		)
		(pad "DK61" smd circle
			(at 15.787878 17.178528)
			(size 0.4318 0.4318)
			(layers "F.Cu" "F.Mask" "F.Paste")
			(net "M_E_MA<7>")
		)
		(pad "DK63" smd circle
			(at 17.504918 17.178528)
			(size 0.4318 0.4318)
			(layers "F.Cu" "F.Mask" "F.Paste")
			(net "M_F_CKE<2>")
		)
		(pad "DK65" smd circle
			(at 19.221958 17.178528)
			(size 0.4318 0.4318)
			(layers "F.Cu" "F.Mask" "F.Paste")
			(net "TP_CPU0_RSVD_37")
		)
		(pad "DK67" smd circle
			(at 20.938998 17.178528)
			(size 0.4318 0.4318)
			(layers "F.Cu" "F.Mask" "F.Paste")
			(net "TP_CPU0_RSVD_36")
		)
		(pad "DK69" smd circle
			(at 22.656038 17.178528)
			(size 0.4318 0.4318)
			(layers "F.Cu" "F.Mask" "F.Paste")
			(net "M_F_DQ<22>")
		)
		(pad "DK71" smd circle
			(at 24.373078 17.178528)
			(size 0.4318 0.4318)
			(layers "F.Cu" "F.Mask" "F.Paste")
			(net "M_F_DQS_DP<2>")
		)
		(pad "DK73" smd circle
			(at 26.090118 17.178528)
			(size 0.4318 0.4318)
			(layers "F.Cu" "F.Mask" "F.Paste")
			(net "GND")
		)
		(pad "DK75" smd circle
			(at 27.806904 17.178528)
			(size 0.4318 0.4318)
			(layers "F.Cu" "F.Mask" "F.Paste")
			(net "GND")
		)
		(pad "DK77" smd circle
			(at 29.523944 17.178528)
			(size 0.4318 0.4318)
			(layers "F.Cu" "F.Mask" "F.Paste")
			(net "GND")
		)
		(pad "DK79" smd circle
			(at 31.240984 17.178528)
			(size 0.4318 0.4318)
			(layers "F.Cu" "F.Mask" "F.Paste")
			(net "M_D_DQ<20>")
		)
		(pad "DK81" smd circle
			(at 32.958024 17.178528)
			(size 0.4318 0.4318)
			(layers "F.Cu" "F.Mask" "F.Paste")
			(net "M_D_DQ<17>")
		)
		(pad "DK83" smd circle
			(at 34.675064 17.178528)
			(size 0.4318 0.4318)
			(layers "F.Cu" "F.Mask" "F.Paste")
			(net "GND")
		)
		(pad "DK85" smd custom
			(at 36.392104 17.178528 270)
			(size 0.10795 0.10795)
			(layers "F.Cu" "F.Mask" "F.Paste")
			(net "GND")
			(options
				(clearance outline)
				(anchor circle)
			)
			(primitives
				(gr_poly
					(pts
						(arc
							(start 0.2159 -0.0381)
							(mid 0 -0.254)
							(end -0.2159 -0.0381)
						)
						(arc
							(start -0.2159 0.0381)
							(mid 0 0.254)
							(end 0.2159 0.0381)
						)
					)
					(width 0)
					(fill yes)
				)
			)
		)
		(pad "DL2" smd custom
			(at -36.392104 19.473926 90)
			(size 0.10795 0.10795)
			(layers "F.Cu" "F.Mask" "F.Paste")
			(net "P3E_CPU0_PE1_SS_TXP<6>")
			(options
				(clearance outline)
				(anchor circle)
			)
			(primitives
				(gr_poly
					(pts
						(arc
							(start 0.2159 -0.0381)
							(mid 0 -0.254)
							(end -0.2159 -0.0381)
						)
						(arc
							(start -0.2159 0.0381)
							(mid 0 0.254)
							(end 0.2159 0.0381)
						)
					)
					(width 0)
					(fill yes)
				)
			)
		)
		(pad "DL4" smd circle
			(at -34.675064 19.473926)
			(size 0.4318 0.4318)
			(layers "F.Cu" "F.Mask" "F.Paste")
			(net "GND")
		)
		(pad "DL6" smd circle
			(at -32.958024 19.473926)
			(size 0.4318 0.4318)
			(layers "F.Cu" "F.Mask" "F.Paste")
			(net "P3E_CPU0_PE3_OCP_TXN<10>")
		)
		(pad "DL8" smd circle
			(at -31.240984 19.473926)
			(size 0.4318 0.4318)
			(layers "F.Cu" "F.Mask" "F.Paste")
			(net "GND")
		)
		(pad "DL10" smd circle
			(at -29.523944 19.473926)
			(size 0.4318 0.4318)
			(layers "F.Cu" "F.Mask" "F.Paste")
			(net "P3E_CPU0_PE1_SS_RXP<7>")
		)
		(pad "DL12" smd circle
			(at -27.806904 19.473926)
			(size 0.4318 0.4318)
			(layers "F.Cu" "F.Mask" "F.Paste")
			(net "P3E_CPU0_PE3_OCP_RXN<8>")
		)
		(pad "DL14" smd circle
			(at -26.090118 19.473926)
			(size 0.4318 0.4318)
			(layers "F.Cu" "F.Mask" "F.Paste")
			(net "P3E_CPU0_PE3_OCP_RXN<7>")
		)
		(pad "DL16" smd circle
			(at -24.373078 19.473926)
			(size 0.4318 0.4318)
			(layers "F.Cu" "F.Mask" "F.Paste")
			(net "GND")
		)
		(pad "DL18" smd circle
			(at -22.656038 19.473926)
			(size 0.4318 0.4318)
			(layers "F.Cu" "F.Mask" "F.Paste")
			(net "GND")
		)
		(pad "DL20" smd circle
			(at -20.938998 19.473926)
			(size 0.4318 0.4318)
			(layers "F.Cu" "F.Mask" "F.Paste")
			(net "TP_CPU0_UPI2_RSVD_CE12")
		)
		(pad "DL22" smd circle
			(at -19.221958 19.473926)
			(size 0.4318 0.4318)
			(layers "F.Cu" "F.Mask" "F.Paste")
			(net "GND")
		)
		(pad "DL24" smd circle
			(at -17.504918 19.473926)
			(size 0.4318 0.4318)
			(layers "F.Cu" "F.Mask" "F.Paste")
			(net "GND")
		)
		(pad "DL26" smd circle
			(at -15.787878 19.473926)
			(size 0.4318 0.4318)
			(layers "F.Cu" "F.Mask" "F.Paste")
			(net "M_E_DQS_DN<7>")
		)
		(pad "DL28" smd circle
			(at -14.071092 19.473926)
			(size 0.4318 0.4318)
			(layers "F.Cu" "F.Mask" "F.Paste")
			(net "GND")
		)
		(pad "DL30" smd circle
			(at -12.354052 19.473926)
			(size 0.4318 0.4318)
			(layers "F.Cu" "F.Mask" "F.Paste")
			(net "GND")
		)
		(pad "DL32" smd circle
			(at -10.637012 19.473926)
			(size 0.4318 0.4318)
			(layers "F.Cu" "F.Mask" "F.Paste")
			(net "M_F_DQS_DN<5>")
		)
		(pad "DL34" smd circle
			(at -8.919972 19.473926)
			(size 0.4318 0.4318)
			(layers "F.Cu" "F.Mask" "F.Paste")
			(net "GND")
		)
		(pad "DL36" smd circle
			(at -7.202932 19.473926)
			(size 0.4318 0.4318)
			(layers "F.Cu" "F.Mask" "F.Paste")
			(net "GND")
		)
		(pad "DL38" smd circle
			(at -5.485892 19.473926)
			(size 0.4318 0.4318)
			(layers "F.Cu" "F.Mask" "F.Paste")
			(net "TP_CPU0_RSVD_35")
		)
		(pad "DL40" smd circle
			(at -3.769106 19.473926)
			(size 0.4318 0.4318)
			(layers "F.Cu" "F.Mask" "F.Paste")
			(net "GND")
		)
		(pad "DL42" smd circle
			(at -2.052066 19.473926)
			(size 0.4318 0.4318)
			(layers "F.Cu" "F.Mask" "F.Paste")
			(net "M_E_DQ<36>")
		)
		(pad "DL44" smd circle
			(at 1.193546 17.673574)
			(size 0.508 0.508)
			(layers "F.Cu" "F.Mask" "F.Paste")
			(net "SVID_ALERT1_CPU0_N")
		)
		(pad "DL46" smd circle
			(at 2.910586 17.673574)
			(size 0.4318 0.4318)
			(layers "F.Cu" "F.Mask" "F.Paste")
			(net "PVDDQ_DEF")
		)
		(pad "DL48" smd circle
			(at 4.627626 17.673574)
			(size 0.4318 0.4318)
			(layers "F.Cu" "F.Mask" "F.Paste")
			(net "PVDDQ_DEF")
		)
		(pad "DL50" smd circle
			(at 6.344412 17.673574)
			(size 0.4318 0.4318)
			(layers "F.Cu" "F.Mask" "F.Paste")
			(net "PVDDQ_DEF")
		)
		(pad "DL52" smd circle
			(at 8.061452 17.673574)
			(size 0.4318 0.4318)
			(layers "F.Cu" "F.Mask" "F.Paste")
			(net "PVDDQ_DEF")
		)
		(pad "DL54" smd circle
			(at 9.778492 17.673574)
			(size 0.4318 0.4318)
			(layers "F.Cu" "F.Mask" "F.Paste")
			(net "PVDDQ_DEF")
		)
		(pad "DL56" smd circle
			(at 11.495532 17.673574)
			(size 0.4318 0.4318)
			(layers "F.Cu" "F.Mask" "F.Paste")
			(net "PVDDQ_DEF")
		)
		(pad "DL58" smd circle
			(at 13.212572 17.673574)
			(size 0.4318 0.4318)
			(layers "F.Cu" "F.Mask" "F.Paste")
			(net "PVDDQ_DEF")
		)
		(pad "DL60" smd circle
			(at 14.929612 17.673574)
			(size 0.4318 0.4318)
			(layers "F.Cu" "F.Mask" "F.Paste")
			(net "PVDDQ_DEF")
		)
		(pad "DL62" smd circle
			(at 16.646398 17.673574)
			(size 0.4318 0.4318)
			(layers "F.Cu" "F.Mask" "F.Paste")
			(net "PVDDQ_DEF")
		)
		(pad "DL64" smd circle
			(at 18.363438 17.673574)
			(size 0.4318 0.4318)
			(layers "F.Cu" "F.Mask" "F.Paste")
			(net "M_E_CKE<2>")
		)
		(pad "DL66" smd circle
			(at 20.080478 17.673574)
			(size 0.4318 0.4318)
			(layers "F.Cu" "F.Mask" "F.Paste")
			(net "TP_CPU0_RSVD_34")
		)
		(pad "DL68" smd circle
			(at 21.797518 17.673574)
			(size 0.4318 0.4318)
			(layers "F.Cu" "F.Mask" "F.Paste")
			(net "GND")
		)
		(pad "DL70" smd circle
			(at 23.514558 17.673574)
			(size 0.4318 0.4318)
			(layers "F.Cu" "F.Mask" "F.Paste")
			(net "GND")
		)
		(pad "DL72" smd circle
			(at 25.231598 17.673574)
			(size 0.4318 0.4318)
			(layers "F.Cu" "F.Mask" "F.Paste")
			(net "M_F_DQS_DN<2>")
		)
		(pad "DL74" smd circle
			(at 26.948384 17.673574)
			(size 0.4318 0.4318)
			(layers "F.Cu" "F.Mask" "F.Paste")
			(net "GND")
		)
		(pad "DL76" smd circle
			(at 28.665424 17.673574)
			(size 0.4318 0.4318)
			(layers "F.Cu" "F.Mask" "F.Paste")
			(net "GND")
		)
		(pad "DL78" smd circle
			(at 30.382464 17.673574)
			(size 0.4318 0.4318)
			(layers "F.Cu" "F.Mask" "F.Paste")
			(net "GND")
		)
		(pad "DL80" smd circle
			(at 32.099504 17.673574)
			(size 0.4318 0.4318)
			(layers "F.Cu" "F.Mask" "F.Paste")
			(net "GND")
		)
		(pad "DL82" smd circle
			(at 33.816544 17.673574)
			(size 0.4318 0.4318)
			(layers "F.Cu" "F.Mask" "F.Paste")
			(net "M_D_DQS_DN<2>")
		)
		(pad "DL84" smd circle
			(at 35.533584 17.673574)
			(size 0.4318 0.4318)
			(layers "F.Cu" "F.Mask" "F.Paste")
			(net "M_D_DQS_DP<10>")
		)
		(pad "DM3" smd circle
			(at -35.533584 19.968972)
			(size 0.4318 0.4318)
			(layers "F.Cu" "F.Mask" "F.Paste")
			(net "P3E_CPU0_PE1_SS_TXN<6>")
		)
		(pad "DM5" smd circle
			(at -33.816544 19.968972)
			(size 0.4318 0.4318)
			(layers "F.Cu" "F.Mask" "F.Paste")
			(net "P3E_CPU0_PE3_OCP_TXP<9>")
		)
		(pad "DM7" smd circle
			(at -32.099504 19.968972)
			(size 0.4318 0.4318)
			(layers "F.Cu" "F.Mask" "F.Paste")
			(net "P3E_CPU0_PE3_OCP_TXN<8>")
		)
		(pad "DM9" smd circle
			(at -30.382464 19.968972)
			(size 0.4318 0.4318)
			(layers "F.Cu" "F.Mask" "F.Paste")
			(net "P3E_CPU0_PE1_SS_RXN<7>")
		)
		(pad "DM11" smd circle
			(at -28.665424 19.968972)
			(size 0.4318 0.4318)
			(layers "F.Cu" "F.Mask" "F.Paste")
			(net "P3E_CPU0_PE1_PCH_RXN<8>")
		)
		(pad "DM13" smd circle
			(at -26.948384 19.968972)
			(size 0.4318 0.4318)
			(layers "F.Cu" "F.Mask" "F.Paste")
			(net "P3E_CPU0_PE3_OCP_RXP<6>")
		)
		(pad "DM15" smd circle
			(at -25.231598 19.968972)
			(size 0.4318 0.4318)
			(layers "F.Cu" "F.Mask" "F.Paste")
			(net "GND")
		)
		(pad "DM17" smd circle
			(at -23.514558 19.968972)
			(size 0.4318 0.4318)
			(layers "F.Cu" "F.Mask" "F.Paste")
			(net "PVCCIO_CPU0")
		)
		(pad "DM19" smd circle
			(at -21.797518 19.968972)
			(size 0.4318 0.4318)
			(layers "F.Cu" "F.Mask" "F.Paste")
			(net "GND")
		)
		(pad "DM21" smd circle
			(at -20.080478 19.968972)
			(size 0.4318 0.4318)
			(layers "F.Cu" "F.Mask" "F.Paste")
			(net "TP_CPU0_UPI2_RSVD_CC10")
		)
		(pad "DM23" smd circle
			(at -18.363438 19.968972)
			(size 0.4318 0.4318)
			(layers "F.Cu" "F.Mask" "F.Paste")
			(net "M_D_DQS_DN<16>")
		)
		(pad "DM25" smd circle
			(at -16.646398 19.968972)
			(size 0.4318 0.4318)
			(layers "F.Cu" "F.Mask" "F.Paste")
			(net "GND")
		)
		(pad "DM27" smd circle
			(at -14.929612 19.968972)
			(size 0.4318 0.4318)
			(layers "F.Cu" "F.Mask" "F.Paste")
			(net "GND")
		)
		(pad "DM29" smd circle
			(at -13.212572 19.968972)
			(size 0.4318 0.4318)
			(layers "F.Cu" "F.Mask" "F.Paste")
			(net "M_D_DQS_DN<15>")
		)
		(pad "DM31" smd circle
			(at -11.495532 19.968972)
			(size 0.4318 0.4318)
			(layers "F.Cu" "F.Mask" "F.Paste")
			(net "GND")
		)
		(pad "DM33" smd circle
			(at -9.778492 19.968972)
			(size 0.4318 0.4318)
			(layers "F.Cu" "F.Mask" "F.Paste")
			(net "GND")
		)
		(pad "DM35" smd circle
			(at -8.061452 19.968972)
			(size 0.4318 0.4318)
			(layers "F.Cu" "F.Mask" "F.Paste")
			(net "M_D_DQS_DP<14>")
		)
		(pad "DM37" smd circle
			(at -6.344412 19.968972)
			(size 0.4318 0.4318)
			(layers "F.Cu" "F.Mask" "F.Paste")
			(net "GND")
		)
		(pad "DM39" smd circle
			(at -4.627626 19.968972)
			(size 0.4318 0.4318)
			(layers "F.Cu" "F.Mask" "F.Paste")
			(net "GND")
		)
		(pad "DM41" smd circle
			(at -2.910586 19.968972)
			(size 0.4318 0.4318)
			(layers "F.Cu" "F.Mask" "F.Paste")
			(net "M_E_DQS_DP<13>")
		)
		(pad "DM45" smd circle
			(at 2.052066 18.168874)
			(size 0.4318 0.4318)
			(layers "F.Cu" "F.Mask" "F.Paste")
			(net "M_F_CS_N<6>")
		)
		(pad "DM47" smd circle
			(at 3.769106 18.168874)
			(size 0.4318 0.4318)
			(layers "F.Cu" "F.Mask" "F.Paste")
			(net "M_E_ODT<3>")
		)
		(pad "DM49" smd circle
			(at 5.485892 18.168874)
			(size 0.4318 0.4318)
			(layers "F.Cu" "F.Mask" "F.Paste")
			(net "M_E_CS_N<5>")
		)
		(pad "DM51" smd circle
			(at 7.202932 18.168874)
			(size 0.4318 0.4318)
			(layers "F.Cu" "F.Mask" "F.Paste")
			(net "M_E_MA<14>")
		)
		(pad "DM53" smd circle
			(at 8.919972 18.168874)
			(size 0.4318 0.4318)
			(layers "F.Cu" "F.Mask" "F.Paste")
			(net "M_E_BA<0>")
		)
		(pad "DM55" smd circle
			(at 10.637012 18.168874)
			(size 0.4318 0.4318)
			(layers "F.Cu" "F.Mask" "F.Paste")
			(net "M_E_CLK_DN<0>")
		)
		(pad "DM57" smd circle
			(at 12.354052 18.168874)
			(size 0.4318 0.4318)
			(layers "F.Cu" "F.Mask" "F.Paste")
			(net "M_E_CLK_DN<2>")
		)
		(pad "DM59" smd circle
			(at 14.071092 18.168874)
			(size 0.4318 0.4318)
			(layers "F.Cu" "F.Mask" "F.Paste")
			(net "M_E_MA<6>")
		)
		(pad "DM61" smd circle
			(at 15.787878 18.168874)
			(size 0.4318 0.4318)
			(layers "F.Cu" "F.Mask" "F.Paste")
			(net "M_E_BG<1>")
		)
		(pad "DM63" smd circle
			(at 17.504918 18.168874)
			(size 0.4318 0.4318)
			(layers "F.Cu" "F.Mask" "F.Paste")
			(net "M_E_CKE<0>")
		)
		(pad "DM65" smd circle
			(at 19.221958 18.168874)
			(size 0.4318 0.4318)
			(layers "F.Cu" "F.Mask" "F.Paste")
			(net "GND")
		)
		(pad "DM67" smd circle
			(at 20.938998 18.168874)
			(size 0.4318 0.4318)
			(layers "F.Cu" "F.Mask" "F.Paste")
			(net "TP_CPU0_RSVD_33")
		)
		(pad "DM69" smd circle
			(at 22.656038 18.168874)
			(size 0.4318 0.4318)
			(layers "F.Cu" "F.Mask" "F.Paste")
			(net "M_F_DQ<18>")
		)
		(pad "DM71" smd circle
			(at 24.373078 18.168874)
			(size 0.4318 0.4318)
			(layers "F.Cu" "F.Mask" "F.Paste")
			(net "M_F_DQ<23>")
		)
		(pad "DM73" smd circle
			(at 26.090118 18.168874)
			(size 0.4318 0.4318)
			(layers "F.Cu" "F.Mask" "F.Paste")
			(net "GND")
		)
		(pad "DM75" smd circle
			(at 27.806904 18.168874)
			(size 0.4318 0.4318)
			(layers "F.Cu" "F.Mask" "F.Paste")
			(net "M_D_DQS_DP<12>")
		)
		(pad "DM77" smd circle
			(at 29.523944 18.168874)
			(size 0.4318 0.4318)
			(layers "F.Cu" "F.Mask" "F.Paste")
			(net "GND")
		)
		(pad "DM79" smd circle
			(at 31.240984 18.168874)
			(size 0.4318 0.4318)
			(layers "F.Cu" "F.Mask" "F.Paste")
			(net "M_D_DQ<16>")
		)
		(pad "DM81" smd circle
			(at 32.958024 18.168874)
			(size 0.4318 0.4318)
			(layers "F.Cu" "F.Mask" "F.Paste")
			(net "M_D_DQS_DP<2>")
		)
		(pad "DM83" smd circle
			(at 34.675064 18.168874)
			(size 0.4318 0.4318)
			(layers "F.Cu" "F.Mask" "F.Paste")
			(net "GND")
		)
		(pad "DM85" smd custom
			(at 36.392104 18.168874 270)
			(size 0.10795 0.10795)
			(layers "F.Cu" "F.Mask" "F.Paste")
			(net "M_D_DQS_DN<10>")
			(options
				(clearance outline)
				(anchor circle)
			)
			(primitives
				(gr_poly
					(pts
						(arc
							(start 0.2159 -0.0381)
							(mid 0 -0.254)
							(end -0.2159 -0.0381)
						)
						(arc
							(start -0.2159 0.0381)
							(mid 0 0.254)
							(end 0.2159 0.0381)
						)
					)
					(width 0)
					(fill yes)
				)
			)
		)
		(pad "DN2" smd custom
			(at -36.392104 20.464526 90)
			(size 0.10795 0.10795)
			(layers "F.Cu" "F.Mask" "F.Paste")
			(net "GND")
			(options
				(clearance outline)
				(anchor circle)
			)
			(primitives
				(gr_poly
					(pts
						(arc
							(start 0.2159 -0.0381)
							(mid 0 -0.254)
							(end -0.2159 -0.0381)
						)
						(arc
							(start -0.2159 0.0381)
							(mid 0 0.254)
							(end 0.2159 0.0381)
						)
					)
					(width 0)
					(fill yes)
				)
			)
		)
		(pad "DN4" smd circle
			(at -34.675064 20.464526)
			(size 0.4318 0.4318)
			(layers "F.Cu" "F.Mask" "F.Paste")
			(net "P3E_CPU0_PE1_SS_TXN<7>")
		)
		(pad "DN6" smd circle
			(at -32.958024 20.464526)
			(size 0.4318 0.4318)
			(layers "F.Cu" "F.Mask" "F.Paste")
			(net "P3E_CPU0_PE3_OCP_TXP<8>")
		)
		(pad "DN8" smd circle
			(at -31.240984 20.464526)
			(size 0.4318 0.4318)
			(layers "F.Cu" "F.Mask" "F.Paste")
			(net "PVCCIO_CPU0")
		)
		(pad "DN10" smd circle
			(at -29.523944 20.464526)
			(size 0.4318 0.4318)
			(layers "F.Cu" "F.Mask" "F.Paste")
			(net "P3E_CPU0_PE1_PCH_RXP<9>")
		)
		(pad "DN12" smd circle
			(at -27.806904 20.464526)
			(size 0.4318 0.4318)
			(layers "F.Cu" "F.Mask" "F.Paste")
			(net "GND")
		)
		(pad "DN14" smd circle
			(at -26.090118 20.464526)
			(size 0.4318 0.4318)
			(layers "F.Cu" "F.Mask" "F.Paste")
			(net "P3E_CPU0_PE3_OCP_RXN<6>")
		)
		(pad "DN16" smd circle
			(at -24.373078 20.464526)
			(size 0.4318 0.4318)
			(layers "F.Cu" "F.Mask" "F.Paste")
			(net "P3E_CPU0_PE3_OCP_RXP<4>")
		)
		(pad "DN18" smd circle
			(at -22.656038 20.464526)
			(size 0.4318 0.4318)
			(layers "F.Cu" "F.Mask" "F.Paste")
			(net "GND")
		)
		(pad "DN20" smd circle
			(at -20.938998 20.464526)
			(size 0.4318 0.4318)
			(layers "F.Cu" "F.Mask" "F.Paste")
			(net "TP_CPU0_UPI2_RSVD_CB11")
		)
		(pad "DN22" smd circle
			(at -19.221958 20.464526)
			(size 0.4318 0.4318)
			(layers "F.Cu" "F.Mask" "F.Paste")
			(net "GND")
		)
		(pad "DN24" smd circle
			(at -17.504918 20.464526)
			(size 0.4318 0.4318)
			(layers "F.Cu" "F.Mask" "F.Paste")
			(net "M_D_DQ<56>")
		)
		(pad "DN26" smd circle
			(at -15.787878 20.464526)
			(size 0.4318 0.4318)
			(layers "F.Cu" "F.Mask" "F.Paste")
			(net "GND")
		)
		(pad "DN28" smd circle
			(at -14.071092 20.464526)
			(size 0.4318 0.4318)
			(layers "F.Cu" "F.Mask" "F.Paste")
			(net "M_D_DQ<54>")
		)
		(pad "DN30" smd circle
			(at -12.354052 20.464526)
			(size 0.4318 0.4318)
			(layers "F.Cu" "F.Mask" "F.Paste")
			(net "M_D_DQ<48>")
		)
		(pad "DN32" smd circle
			(at -10.637012 20.464526)
			(size 0.4318 0.4318)
			(layers "F.Cu" "F.Mask" "F.Paste")
			(net "GND")
		)
		(pad "DN34" smd circle
			(at -8.919972 20.464526)
			(size 0.4318 0.4318)
			(layers "F.Cu" "F.Mask" "F.Paste")
			(net "M_D_DQ<46>")
		)
		(pad "DN36" smd circle
			(at -7.202932 20.464526)
			(size 0.4318 0.4318)
			(layers "F.Cu" "F.Mask" "F.Paste")
			(net "M_D_DQ<40>")
		)
		(pad "DN38" smd circle
			(at -5.485892 20.464526)
			(size 0.4318 0.4318)
			(layers "F.Cu" "F.Mask" "F.Paste")
			(net "GND")
		)
		(pad "DN40" smd circle
			(at -3.769106 20.464526)
			(size 0.4318 0.4318)
			(layers "F.Cu" "F.Mask" "F.Paste")
			(net "M_E_DQ<38>")
		)
		(pad "DN42" smd circle
			(at -2.052066 20.464526)
			(size 0.4318 0.4318)
			(layers "F.Cu" "F.Mask" "F.Paste")
			(net "M_E_DQ<37>")
		)
		(pad "DN44" smd circle
			(at 1.193546 18.664428)
			(size 0.508 0.508)
			(layers "F.Cu" "F.Mask" "F.Paste")
			(net "GND")
		)
		(pad "DN46" smd circle
			(at 2.910586 18.664428)
			(size 0.4318 0.4318)
			(layers "F.Cu" "F.Mask" "F.Paste")
			(net "M_E_CS_N<7>")
		)
		(pad "DN48" smd circle
			(at 4.627626 18.664428)
			(size 0.4318 0.4318)
			(layers "F.Cu" "F.Mask" "F.Paste")
			(net "M_E_ODT<1>")
		)
		(pad "DN50" smd circle
			(at 6.344412 18.664428)
			(size 0.4318 0.4318)
			(layers "F.Cu" "F.Mask" "F.Paste")
			(net "M_E_CS_N<1>")
		)
		(pad "DN52" smd circle
			(at 8.061452 18.664428)
			(size 0.4318 0.4318)
			(layers "F.Cu" "F.Mask" "F.Paste")
			(net "M_E_MA<16>")
		)
		(pad "DN54" smd circle
			(at 9.778492 18.664428)
			(size 0.4318 0.4318)
			(layers "F.Cu" "F.Mask" "F.Paste")
			(net "M_E_CLK_DP<0>")
		)
		(pad "DN56" smd circle
			(at 11.495532 18.664428)
			(size 0.4318 0.4318)
			(layers "F.Cu" "F.Mask" "F.Paste")
			(net "M_E_CLK_DP<2>")
		)
		(pad "DN58" smd circle
			(at 13.212572 18.664428)
			(size 0.4318 0.4318)
			(layers "F.Cu" "F.Mask" "F.Paste")
			(net "M_E_MA<5>")
		)
		(pad "DN60" smd circle
			(at 14.929612 18.664428)
			(size 0.4318 0.4318)
			(layers "F.Cu" "F.Mask" "F.Paste")
			(net "M_E_MA<12>")
		)
		(pad "DN62" smd circle
			(at 16.646398 18.664428)
			(size 0.4318 0.4318)
			(layers "F.Cu" "F.Mask" "F.Paste")
			(net "TP_CPU0_RSVD_32")
		)
		(pad "DN64" smd circle
			(at 18.363438 18.664428)
			(size 0.4318 0.4318)
			(layers "F.Cu" "F.Mask" "F.Paste")
			(net "M_E_CKE<1>")
		)
		(pad "DN66" smd circle
			(at 20.080478 18.664428)
			(size 0.4318 0.4318)
			(layers "F.Cu" "F.Mask" "F.Paste")
			(net "TP_CPU0_RSVD_31")
		)
		(pad "DN68" smd circle
			(at 21.797518 18.664428)
			(size 0.4318 0.4318)
			(layers "F.Cu" "F.Mask" "F.Paste")
			(net "GND")
		)
		(pad "DN70" smd circle
			(at 23.514558 18.664428)
			(size 0.4318 0.4318)
			(layers "F.Cu" "F.Mask" "F.Paste")
			(net "M_F_DQ<19>")
		)
		(pad "DN72" smd circle
			(at 25.231598 18.664428)
			(size 0.4318 0.4318)
			(layers "F.Cu" "F.Mask" "F.Paste")
			(net "GND")
		)
		(pad "DN74" smd circle
			(at 26.948384 18.664428)
			(size 0.4318 0.4318)
			(layers "F.Cu" "F.Mask" "F.Paste")
			(net "M_D_DQ<30>")
		)
		(pad "DN76" smd circle
			(at 28.665424 18.664428)
			(size 0.4318 0.4318)
			(layers "F.Cu" "F.Mask" "F.Paste")
			(net "M_D_DQ<24>")
		)
		(pad "DN78" smd circle
			(at 30.382464 18.664428)
			(size 0.4318 0.4318)
			(layers "F.Cu" "F.Mask" "F.Paste")
			(net "GND")
		)
		(pad "DN80" smd circle
			(at 32.099504 18.664428)
			(size 0.4318 0.4318)
			(layers "F.Cu" "F.Mask" "F.Paste")
			(net "M_D_DQS_DN<11>")
		)
		(pad "DN82" smd circle
			(at 33.816544 18.664428)
			(size 0.4318 0.4318)
			(layers "F.Cu" "F.Mask" "F.Paste")
			(net "M_D_DQ<23>")
		)
		(pad "DN84" smd circle
			(at 35.533584 18.664428)
			(size 0.4318 0.4318)
			(layers "F.Cu" "F.Mask" "F.Paste")
			(net "M_D_DQS_DN<1>")
		)
		(pad "DP3" smd circle
			(at -35.533584 20.959572)
			(size 0.4318 0.4318)
			(layers "F.Cu" "F.Mask" "F.Paste")
			(net "P3E_CPU0_PE1_SS_TXP<7>")
		)
		(pad "DP5" smd circle
			(at -33.816544 20.959572)
			(size 0.4318 0.4318)
			(layers "F.Cu" "F.Mask" "F.Paste")
			(net "P3E_CPU0_PE3_OCP_TXN<9>")
		)
		(pad "DP7" smd circle
			(at -32.099504 20.959572)
			(size 0.4318 0.4318)
			(layers "F.Cu" "F.Mask" "F.Paste")
			(net "P3E_CPU0_PE3_OCP_TXP<7>")
		)
		(pad "DP9" smd circle
			(at -30.382464 20.959572)
			(size 0.4318 0.4318)
			(layers "F.Cu" "F.Mask" "F.Paste")
			(net "GND")
		)
		(pad "DP11" smd circle
			(at -28.665424 20.959572)
			(size 0.4318 0.4318)
			(layers "F.Cu" "F.Mask" "F.Paste")
			(net "P3E_CPU0_PE1_PCH_RXN<9>")
		)
		(pad "DP13" smd circle
			(at -26.948384 20.959572)
			(size 0.4318 0.4318)
			(layers "F.Cu" "F.Mask" "F.Paste")
			(net "P3E_CPU0_PE1_PCH_RXP<11>")
		)
		(pad "DP15" smd circle
			(at -25.231598 20.959572)
			(size 0.4318 0.4318)
			(layers "F.Cu" "F.Mask" "F.Paste")
			(net "P3E_CPU0_PE3_OCP_RXP<5>")
		)
		(pad "DP17" smd circle
			(at -23.514558 20.959572)
			(size 0.4318 0.4318)
			(layers "F.Cu" "F.Mask" "F.Paste")
			(net "TP_CPU0_RSVD_30")
		)
		(pad "DP19" smd circle
			(at -21.797518 20.959572)
			(size 0.4318 0.4318)
			(layers "F.Cu" "F.Mask" "F.Paste")
			(net "PVCCIO_CPU0")
		)
		(pad "DP21" smd circle
			(at -20.080478 20.959572)
			(size 0.4318 0.4318)
			(layers "F.Cu" "F.Mask" "F.Paste")
			(net "TP_CPU0_UPI2_RSVD_CA12")
		)
		(pad "DP23" smd circle
			(at -18.363438 20.959572)
			(size 0.4318 0.4318)
			(layers "F.Cu" "F.Mask" "F.Paste")
			(net "M_D_DQS_DP<16>")
		)
		(pad "DP25" smd circle
			(at -16.646398 20.959572)
			(size 0.4318 0.4318)
			(layers "F.Cu" "F.Mask" "F.Paste")
			(net "M_D_DQ<60>")
		)
		(pad "DP27" smd circle
			(at -14.929612 20.959572)
			(size 0.4318 0.4318)
			(layers "F.Cu" "F.Mask" "F.Paste")
			(net "M_D_DQ<50>")
		)
		(pad "DP29" smd circle
			(at -13.212572 20.959572)
			(size 0.4318 0.4318)
			(layers "F.Cu" "F.Mask" "F.Paste")
			(net "M_D_DQS_DP<15>")
		)
		(pad "DP31" smd circle
			(at -11.495532 20.959572)
			(size 0.4318 0.4318)
			(layers "F.Cu" "F.Mask" "F.Paste")
			(net "M_D_DQ<52>")
		)
		(pad "DP33" smd circle
			(at -9.778492 20.959572)
			(size 0.4318 0.4318)
			(layers "F.Cu" "F.Mask" "F.Paste")
			(net "M_D_DQ<42>")
		)
		(pad "DP35" smd circle
			(at -8.061452 20.959572)
			(size 0.4318 0.4318)
			(layers "F.Cu" "F.Mask" "F.Paste")
			(net "M_D_DQS_DN<14>")
		)
		(pad "DP37" smd circle
			(at -6.344412 20.959572)
			(size 0.4318 0.4318)
			(layers "F.Cu" "F.Mask" "F.Paste")
			(net "M_D_DQ<44>")
		)
		(pad "DP39" smd circle
			(at -4.627626 20.959572)
			(size 0.4318 0.4318)
			(layers "F.Cu" "F.Mask" "F.Paste")
			(net "M_E_DQ<34>")
		)
		(pad "DP41" smd circle
			(at -2.910586 20.959572)
			(size 0.4318 0.4318)
			(layers "F.Cu" "F.Mask" "F.Paste")
			(net "M_E_DQS_DN<13>")
		)
		(pad "DP45" smd circle
			(at 2.052066 19.159474)
			(size 0.4318 0.4318)
			(layers "F.Cu" "F.Mask" "F.Paste")
			(net "GND")
		)
		(pad "DP47" smd circle
			(at 3.769106 19.159474)
			(size 0.4318 0.4318)
			(layers "F.Cu" "F.Mask" "F.Paste")
			(net "GND")
		)
		(pad "DP49" smd circle
			(at 5.485892 19.159474)
			(size 0.4318 0.4318)
			(layers "F.Cu" "F.Mask" "F.Paste")
			(net "GND")
		)
		(pad "DP51" smd circle
			(at 7.202932 19.159474)
			(size 0.4318 0.4318)
			(layers "F.Cu" "F.Mask" "F.Paste")
			(net "GND")
		)
		(pad "DP53" smd circle
			(at 8.919972 19.159474)
			(size 0.4318 0.4318)
			(layers "F.Cu" "F.Mask" "F.Paste")
			(net "GND")
		)
		(pad "DP55" smd circle
			(at 10.637012 19.159474)
			(size 0.4318 0.4318)
			(layers "F.Cu" "F.Mask" "F.Paste")
			(net "GND")
		)
		(pad "DP57" smd circle
			(at 12.354052 19.159474)
			(size 0.4318 0.4318)
			(layers "F.Cu" "F.Mask" "F.Paste")
			(net "GND")
		)
		(pad "DP59" smd circle
			(at 14.071092 19.159474)
			(size 0.4318 0.4318)
			(layers "F.Cu" "F.Mask" "F.Paste")
			(net "GND")
		)
		(pad "DP61" smd circle
			(at 15.787878 19.159474)
			(size 0.4318 0.4318)
			(layers "F.Cu" "F.Mask" "F.Paste")
			(net "GND")
		)
		(pad "DP63" smd circle
			(at 17.504918 19.159474)
			(size 0.4318 0.4318)
			(layers "F.Cu" "F.Mask" "F.Paste")
			(net "GND")
		)
		(pad "DP65" smd circle
			(at 19.221958 19.159474)
			(size 0.4318 0.4318)
			(layers "F.Cu" "F.Mask" "F.Paste")
			(net "TP_CPU0_RSVD_29")
		)
		(pad "DP67" smd circle
			(at 20.938998 19.159474)
			(size 0.4318 0.4318)
			(layers "F.Cu" "F.Mask" "F.Paste")
			(net "GND")
		)
		(pad "DP69" smd circle
			(at 22.656038 19.159474)
			(size 0.4318 0.4318)
			(layers "F.Cu" "F.Mask" "F.Paste")
			(net "GND")
		)
		(pad "DP71" smd circle
			(at 24.373078 19.159474)
			(size 0.4318 0.4318)
			(layers "F.Cu" "F.Mask" "F.Paste")
			(net "GND")
		)
		(pad "DP73" smd circle
			(at 26.090118 19.159474)
			(size 0.4318 0.4318)
			(layers "F.Cu" "F.Mask" "F.Paste")
			(net "M_D_DQ<26>")
		)
		(pad "DP75" smd circle
			(at 27.806904 19.159474)
			(size 0.4318 0.4318)
			(layers "F.Cu" "F.Mask" "F.Paste")
			(net "M_D_DQS_DN<12>")
		)
		(pad "DP77" smd circle
			(at 29.523944 19.159474)
			(size 0.4318 0.4318)
			(layers "F.Cu" "F.Mask" "F.Paste")
			(net "M_D_DQ<28>")
		)
		(pad "DP79" smd circle
			(at 31.240984 19.159474)
			(size 0.4318 0.4318)
			(layers "F.Cu" "F.Mask" "F.Paste")
			(net "M_D_DQS_DP<11>")
		)
		(pad "DP81" smd circle
			(at 32.958024 19.159474)
			(size 0.4318 0.4318)
			(layers "F.Cu" "F.Mask" "F.Paste")
			(net "GND")
		)
		(pad "DP83" smd circle
			(at 34.675064 19.159474)
			(size 0.4318 0.4318)
			(layers "F.Cu" "F.Mask" "F.Paste")
			(net "GND")
		)
		(pad "DP85" smd custom
			(at 36.392104 19.159474 270)
			(size 0.10795 0.10795)
			(layers "F.Cu" "F.Mask" "F.Paste")
			(net "M_D_DQS_DP<1>")
			(options
				(clearance outline)
				(anchor circle)
			)
			(primitives
				(gr_poly
					(pts
						(arc
							(start 0.2159 -0.0381)
							(mid 0 -0.254)
							(end -0.2159 -0.0381)
						)
						(arc
							(start -0.2159 0.0381)
							(mid 0 0.254)
							(end 0.2159 0.0381)
						)
					)
					(width 0)
					(fill yes)
				)
			)
		)
		(pad "DR2" smd custom
			(at -36.392104 21.455126 90)
			(size 0.10795 0.10795)
			(layers "F.Cu" "F.Mask" "F.Paste")
			(net "PVCCIO_CPU0")
			(options
				(clearance outline)
				(anchor circle)
			)
			(primitives
				(gr_poly
					(pts
						(arc
							(start 0.2159 -0.0381)
							(mid 0 -0.254)
							(end -0.2159 -0.0381)
						)
						(arc
							(start -0.2159 0.0381)
							(mid 0 0.254)
							(end 0.2159 0.0381)
						)
					)
					(width 0)
					(fill yes)
				)
			)
		)
		(pad "DR4" smd circle
			(at -34.675064 21.455126)
			(size 0.4318 0.4318)
			(layers "F.Cu" "F.Mask" "F.Paste")
			(net "P3E_CPU0_PE1_PCH_TXP<8>")
		)
		(pad "DR6" smd circle
			(at -32.958024 21.455126)
			(size 0.4318 0.4318)
			(layers "F.Cu" "F.Mask" "F.Paste")
			(net "GND")
		)
		(pad "DR8" smd circle
			(at -31.240984 21.455126)
			(size 0.4318 0.4318)
			(layers "F.Cu" "F.Mask" "F.Paste")
			(net "P3E_CPU0_PE3_OCP_TXN<7>")
		)
		(pad "DR10" smd circle
			(at -29.523944 21.455126)
			(size 0.4318 0.4318)
			(layers "F.Cu" "F.Mask" "F.Paste")
			(net "PVCCIO_CPU0")
		)
		(pad "DR12" smd circle
			(at -27.806904 21.455126)
			(size 0.4318 0.4318)
			(layers "F.Cu" "F.Mask" "F.Paste")
			(net "P3E_CPU0_PE1_PCH_RXP<10>")
		)
		(pad "DR14" smd circle
			(at -26.090118 21.455126)
			(size 0.4318 0.4318)
			(layers "F.Cu" "F.Mask" "F.Paste")
			(net "P3E_CPU0_PE3_OCP_RXN<5>")
		)
		(pad "DR16" smd circle
			(at -24.373078 21.455126)
			(size 0.4318 0.4318)
			(layers "F.Cu" "F.Mask" "F.Paste")
			(net "P3E_CPU0_PE3_OCP_RXN<4>")
		)
		(pad "DR18" smd circle
			(at -22.656038 21.455126)
			(size 0.4318 0.4318)
			(layers "F.Cu" "F.Mask" "F.Paste")
			(net "P3E_CPU0_PE3_OCP_RXP<3>")
		)
		(pad "DR20" smd circle
			(at -20.938998 21.455126)
			(size 0.4318 0.4318)
			(layers "F.Cu" "F.Mask" "F.Paste")
			(net "GND")
		)
		(pad "DR22" smd circle
			(at -19.221958 21.455126)
			(size 0.4318 0.4318)
			(layers "F.Cu" "F.Mask" "F.Paste")
			(net "GND")
		)
		(pad "DR24" smd circle
			(at -17.504918 21.455126)
			(size 0.4318 0.4318)
			(layers "F.Cu" "F.Mask" "F.Paste")
			(net "GND")
		)
		(pad "DR26" smd circle
			(at -15.787878 21.455126)
			(size 0.4318 0.4318)
			(layers "F.Cu" "F.Mask" "F.Paste")
			(net "GND")
		)
		(pad "DR28" smd circle
			(at -14.071092 21.455126)
			(size 0.4318 0.4318)
			(layers "F.Cu" "F.Mask" "F.Paste")
			(net "GND")
		)
		(pad "DR30" smd circle
			(at -12.354052 21.455126)
			(size 0.4318 0.4318)
			(layers "F.Cu" "F.Mask" "F.Paste")
			(net "GND")
		)
		(pad "DR32" smd circle
			(at -10.637012 21.455126)
			(size 0.4318 0.4318)
			(layers "F.Cu" "F.Mask" "F.Paste")
			(net "GND")
		)
		(pad "DR34" smd circle
			(at -8.919972 21.455126)
			(size 0.4318 0.4318)
			(layers "F.Cu" "F.Mask" "F.Paste")
			(net "GND")
		)
		(pad "DR36" smd circle
			(at -7.202932 21.455126)
			(size 0.4318 0.4318)
			(layers "F.Cu" "F.Mask" "F.Paste")
			(net "GND")
		)
		(pad "DR38" smd circle
			(at -5.485892 21.455126)
			(size 0.4318 0.4318)
			(layers "F.Cu" "F.Mask" "F.Paste")
			(net "GND")
		)
		(pad "DR40" smd circle
			(at -3.769106 21.455126)
			(size 0.4318 0.4318)
			(layers "F.Cu" "F.Mask" "F.Paste")
			(net "GND")
		)
		(pad "DR42" smd circle
			(at -2.052066 21.455126)
			(size 0.4318 0.4318)
			(layers "F.Cu" "F.Mask" "F.Paste")
			(net "GND")
		)
		(pad "DR44" smd circle
			(at 1.193546 19.655028)
			(size 0.508 0.508)
			(layers "F.Cu" "F.Mask" "F.Paste")
			(net "TP_CPU0_RSVD_28")
		)
		(pad "DR46" smd circle
			(at 2.910586 19.655028)
			(size 0.4318 0.4318)
			(layers "F.Cu" "F.Mask" "F.Paste")
			(net "M_E_CS_N<2>")
		)
		(pad "DR48" smd circle
			(at 4.627626 19.655028)
			(size 0.4318 0.4318)
			(layers "F.Cu" "F.Mask" "F.Paste")
			(net "M_E_MA<17>")
		)
		(pad "DR50" smd circle
			(at 6.344412 19.655028)
			(size 0.4318 0.4318)
			(layers "F.Cu" "F.Mask" "F.Paste")
			(net "M_E_ODT<0>")
		)
		(pad "DR52" smd circle
			(at 8.061452 19.655028)
			(size 0.4318 0.4318)
			(layers "F.Cu" "F.Mask" "F.Paste")
			(net "M_E_MA<15>")
		)
		(pad "DR54" smd circle
			(at 9.778492 19.655028)
			(size 0.4318 0.4318)
			(layers "F.Cu" "F.Mask" "F.Paste")
			(net "M_E_CLK_DN<1>")
		)
		(pad "DR56" smd circle
			(at 11.495532 19.655028)
			(size 0.4318 0.4318)
			(layers "F.Cu" "F.Mask" "F.Paste")
			(net "M_E_CLK_DP<3>")
		)
		(pad "DR58" smd circle
			(at 13.212572 19.655028)
			(size 0.4318 0.4318)
			(layers "F.Cu" "F.Mask" "F.Paste")
			(net "M_E_MA<3>")
		)
		(pad "DR60" smd circle
			(at 14.929612 19.655028)
			(size 0.4318 0.4318)
			(layers "F.Cu" "F.Mask" "F.Paste")
			(net "M_E_MA<11>")
		)
		(pad "DR62" smd circle
			(at 16.646398 19.655028)
			(size 0.4318 0.4318)
			(layers "F.Cu" "F.Mask" "F.Paste")
			(net "M_E_ACT_N")
		)
		(pad "DR64" smd circle
			(at 18.363438 19.655028)
			(size 0.4318 0.4318)
			(layers "F.Cu" "F.Mask" "F.Paste")
			(net "M_E_CKE<3>")
		)
		(pad "DR66" smd circle
			(at 20.080478 19.655028)
			(size 0.4318 0.4318)
			(layers "F.Cu" "F.Mask" "F.Paste")
			(net "GND")
		)
		(pad "DR68" smd circle
			(at 21.797518 19.655028)
			(size 0.4318 0.4318)
			(layers "F.Cu" "F.Mask" "F.Paste")
			(net "GND")
		)
		(pad "DR70" smd circle
			(at 23.514558 19.655028)
			(size 0.4318 0.4318)
			(layers "F.Cu" "F.Mask" "F.Paste")
			(net "GND")
		)
		(pad "DR72" smd circle
			(at 25.231598 19.655028)
			(size 0.4318 0.4318)
			(layers "F.Cu" "F.Mask" "F.Paste")
			(net "GND")
		)
		(pad "DR74" smd circle
			(at 26.948384 19.655028)
			(size 0.4318 0.4318)
			(layers "F.Cu" "F.Mask" "F.Paste")
			(net "GND")
		)
		(pad "DR76" smd circle
			(at 28.665424 19.655028)
			(size 0.4318 0.4318)
			(layers "F.Cu" "F.Mask" "F.Paste")
			(net "GND")
		)
		(pad "DR78" smd circle
			(at 30.382464 19.655028)
			(size 0.4318 0.4318)
			(layers "F.Cu" "F.Mask" "F.Paste")
			(net "GND")
		)
		(pad "DR80" smd circle
			(at 32.099504 19.655028)
			(size 0.4318 0.4318)
			(layers "F.Cu" "F.Mask" "F.Paste")
			(net "M_D_DQ<22>")
		)
		(pad "DR82" smd circle
			(at 33.816544 19.655028)
			(size 0.4318 0.4318)
			(layers "F.Cu" "F.Mask" "F.Paste")
			(net "M_D_DQ<19>")
		)
		(pad "DR84" smd circle
			(at 35.533584 19.655028)
			(size 0.4318 0.4318)
			(layers "F.Cu" "F.Mask" "F.Paste")
			(net "M_D_DQ<14>")
		)
		(pad "DT3" smd circle
			(at -35.533584 21.950172)
			(size 0.4318 0.4318)
			(layers "F.Cu" "F.Mask" "F.Paste")
			(net "GND")
		)
		(pad "DT5" smd circle
			(at -33.816544 21.950172)
			(size 0.4318 0.4318)
			(layers "F.Cu" "F.Mask" "F.Paste")
			(net "P3E_CPU0_PE1_PCH_TXN<8>")
		)
		(pad "DT7" smd circle
			(at -32.099504 21.950172)
			(size 0.4318 0.4318)
			(layers "F.Cu" "F.Mask" "F.Paste")
			(net "P3E_CPU0_PE1_PCH_TXP<12>")
		)
		(pad "DT9" smd circle
			(at -30.382464 21.950172)
			(size 0.4318 0.4318)
			(layers "F.Cu" "F.Mask" "F.Paste")
			(net "P3E_CPU0_PE3_OCP_TXP<6>")
		)
		(pad "DT11" smd circle
			(at -28.665424 21.950172)
			(size 0.4318 0.4318)
			(layers "F.Cu" "F.Mask" "F.Paste")
			(net "P3E_CPU0_PE1_PCH_RXN<10>")
		)
		(pad "DT13" smd circle
			(at -26.948384 21.950172)
			(size 0.4318 0.4318)
			(layers "F.Cu" "F.Mask" "F.Paste")
			(net "P3E_CPU0_PE1_PCH_RXN<11>")
		)
		(pad "DT15" smd circle
			(at -25.231598 21.950172)
			(size 0.4318 0.4318)
			(layers "F.Cu" "F.Mask" "F.Paste")
			(net "P3E_CPU0_PE1_PCH_RXP<15>")
		)
		(pad "DT17" smd circle
			(at -23.514558 21.950172)
			(size 0.4318 0.4318)
			(layers "F.Cu" "F.Mask" "F.Paste")
			(net "GND")
		)
		(pad "DT19" smd circle
			(at -21.797518 21.950172)
			(size 0.4318 0.4318)
			(layers "F.Cu" "F.Mask" "F.Paste")
			(net "P3E_CPU0_PE3_OCP_RXN<3>")
		)
		(pad "DT21" smd circle
			(at -20.080478 21.950172)
			(size 0.4318 0.4318)
			(layers "F.Cu" "F.Mask" "F.Paste")
			(net "TP_CPU0_UPI2_RSVD_CC12")
		)
		(pad "DT23" smd circle
			(at -18.363438 21.950172)
			(size 0.4318 0.4318)
			(layers "F.Cu" "F.Mask" "F.Paste")
			(net "M_D_DQS_DP<7>")
		)
		(pad "DT25" smd circle
			(at -16.646398 21.950172)
			(size 0.4318 0.4318)
			(layers "F.Cu" "F.Mask" "F.Paste")
			(net "M_D_DQ<61>")
		)
		(pad "DT27" smd circle
			(at -14.929612 21.950172)
			(size 0.4318 0.4318)
			(layers "F.Cu" "F.Mask" "F.Paste")
			(net "M_D_DQ<51>")
		)
		(pad "DT29" smd circle
			(at -13.212572 21.950172)
			(size 0.4318 0.4318)
			(layers "F.Cu" "F.Mask" "F.Paste")
			(net "M_D_DQS_DP<6>")
		)
		(pad "DT31" smd circle
			(at -11.495532 21.950172)
			(size 0.4318 0.4318)
			(layers "F.Cu" "F.Mask" "F.Paste")
			(net "M_D_DQ<53>")
		)
		(pad "DT33" smd circle
			(at -9.778492 21.950172)
			(size 0.4318 0.4318)
			(layers "F.Cu" "F.Mask" "F.Paste")
			(net "M_D_DQ<43>")
		)
		(pad "DT35" smd circle
			(at -8.061452 21.950172)
			(size 0.4318 0.4318)
			(layers "F.Cu" "F.Mask" "F.Paste")
			(net "M_D_DQS_DP<5>")
		)
		(pad "DT37" smd circle
			(at -6.344412 21.950172)
			(size 0.4318 0.4318)
			(layers "F.Cu" "F.Mask" "F.Paste")
			(net "M_D_DQ<45>")
		)
		(pad "DT39" smd circle
			(at -4.627626 21.950172)
			(size 0.4318 0.4318)
			(layers "F.Cu" "F.Mask" "F.Paste")
			(net "M_E_DQ<35>")
		)
		(pad "DT41" smd circle
			(at -2.910586 21.950172)
			(size 0.4318 0.4318)
			(layers "F.Cu" "F.Mask" "F.Paste")
			(net "M_E_DQS_DP<4>")
		)
		(pad "DT45" smd circle
			(at 2.052066 20.150074)
			(size 0.4318 0.4318)
			(layers "F.Cu" "F.Mask" "F.Paste")
			(net "M_E_CS_N<6>")
		)
		(pad "DT47" smd circle
			(at 3.769106 20.150074)
			(size 0.4318 0.4318)
			(layers "F.Cu" "F.Mask" "F.Paste")
			(net "M_E_C<2>")
		)
		(pad "DT49" smd circle
			(at 5.485892 20.150074)
			(size 0.4318 0.4318)
			(layers "F.Cu" "F.Mask" "F.Paste")
			(net "M_E_ODT<2>")
		)
		(pad "DT51" smd circle
			(at 7.202932 20.150074)
			(size 0.4318 0.4318)
			(layers "F.Cu" "F.Mask" "F.Paste")
			(net "M_E_MA<13>")
		)
		(pad "DT53" smd circle
			(at 8.919972 20.150074)
			(size 0.4318 0.4318)
			(layers "F.Cu" "F.Mask" "F.Paste")
			(net "M_E_CLK_DP<1>")
		)
		(pad "DT55" smd circle
			(at 10.637012 20.150074)
			(size 0.4318 0.4318)
			(layers "F.Cu" "F.Mask" "F.Paste")
			(net "M_E_MA<10>")
		)
		(pad "DT57" smd circle
			(at 12.354052 20.150074)
			(size 0.4318 0.4318)
			(layers "F.Cu" "F.Mask" "F.Paste")
			(net "M_E_CLK_DN<3>")
		)
		(pad "DT59" smd circle
			(at 14.071092 20.150074)
			(size 0.4318 0.4318)
			(layers "F.Cu" "F.Mask" "F.Paste")
			(net "M_E_MA<4>")
		)
		(pad "DT61" smd circle
			(at 15.787878 20.150074)
			(size 0.4318 0.4318)
			(layers "F.Cu" "F.Mask" "F.Paste")
			(net "M_E_ALERT_N")
		)
		(pad "DT63" smd circle
			(at 17.504918 20.150074)
			(size 0.4318 0.4318)
			(layers "F.Cu" "F.Mask" "F.Paste")
			(net "M_D_MA<12>")
		)
		(pad "DT65" smd circle
			(at 19.221958 20.150074)
			(size 0.4318 0.4318)
			(layers "F.Cu" "F.Mask" "F.Paste")
			(net "GND")
		)
		(pad "DT67" smd circle
			(at 20.938998 20.150074)
			(size 0.4318 0.4318)
			(layers "F.Cu" "F.Mask" "F.Paste")
			(net "M_E_DQS_DP<17>")
		)
		(pad "DT69" smd circle
			(at 22.656038 20.150074)
			(size 0.4318 0.4318)
			(layers "F.Cu" "F.Mask" "F.Paste")
			(net "GND")
		)
		(pad "DT71" smd circle
			(at 24.373078 20.150074)
			(size 0.4318 0.4318)
			(layers "F.Cu" "F.Mask" "F.Paste")
			(net "TP_CPU0_RSVD_27")
		)
		(pad "DT73" smd circle
			(at 26.090118 20.150074)
			(size 0.4318 0.4318)
			(layers "F.Cu" "F.Mask" "F.Paste")
			(net "M_D_DQ<27>")
		)
		(pad "DT75" smd circle
			(at 27.806904 20.150074)
			(size 0.4318 0.4318)
			(layers "F.Cu" "F.Mask" "F.Paste")
			(net "M_D_DQS_DP<3>")
		)
		(pad "DT77" smd circle
			(at 29.523944 20.150074)
			(size 0.4318 0.4318)
			(layers "F.Cu" "F.Mask" "F.Paste")
			(net "M_D_DQ<29>")
		)
		(pad "DT79" smd circle
			(at 31.240984 20.150074)
			(size 0.4318 0.4318)
			(layers "F.Cu" "F.Mask" "F.Paste")
			(net "GND")
		)
		(pad "DT81" smd circle
			(at 32.958024 20.150074)
			(size 0.4318 0.4318)
			(layers "F.Cu" "F.Mask" "F.Paste")
			(net "M_D_DQ<18>")
		)
		(pad "DT83" smd circle
			(at 34.675064 20.150074)
			(size 0.4318 0.4318)
			(layers "F.Cu" "F.Mask" "F.Paste")
			(net "GND")
		)
		(pad "DT85" smd custom
			(at 36.392104 20.150074 270)
			(size 0.10795 0.10795)
			(layers "F.Cu" "F.Mask" "F.Paste")
			(net "GND")
			(options
				(clearance outline)
				(anchor circle)
			)
			(primitives
				(gr_poly
					(pts
						(arc
							(start 0.2159 -0.0381)
							(mid 0 -0.254)
							(end -0.2159 -0.0381)
						)
						(arc
							(start -0.2159 0.0381)
							(mid 0 0.254)
							(end 0.2159 0.0381)
						)
					)
					(width 0)
					(fill yes)
				)
			)
		)
		(pad "DU2" smd custom
			(at -36.392104 22.445726 90)
			(size 0.10795 0.10795)
			(layers "F.Cu" "F.Mask" "F.Paste")
			(net "P3E_CPU0_PE1_PCH_TXP<9>")
			(options
				(clearance outline)
				(anchor circle)
			)
			(primitives
				(gr_poly
					(pts
						(arc
							(start 0.2159 -0.0381)
							(mid 0 -0.254)
							(end -0.2159 -0.0381)
						)
						(arc
							(start -0.2159 0.0381)
							(mid 0 0.254)
							(end 0.2159 0.0381)
						)
					)
					(width 0)
					(fill yes)
				)
			)
		)
		(pad "DU4" smd circle
			(at -34.675064 22.445726)
			(size 0.4318 0.4318)
			(layers "F.Cu" "F.Mask" "F.Paste")
			(net "P3E_CPU0_PE1_PCH_TXP<10>")
		)
		(pad "DU6" smd circle
			(at -32.958024 22.445726)
			(size 0.4318 0.4318)
			(layers "F.Cu" "F.Mask" "F.Paste")
			(net "P3E_CPU0_PE1_PCH_TXN<11>")
		)
		(pad "DU8" smd circle
			(at -31.240984 22.445726)
			(size 0.4318 0.4318)
			(layers "F.Cu" "F.Mask" "F.Paste")
			(net "P3E_CPU0_PE3_OCP_TXN<6>")
		)
		(pad "DU10" smd circle
			(at -29.523944 22.445726)
			(size 0.4318 0.4318)
			(layers "F.Cu" "F.Mask" "F.Paste")
			(net "GND")
		)
		(pad "DU12" smd circle
			(at -27.806904 22.445726)
			(size 0.4318 0.4318)
			(layers "F.Cu" "F.Mask" "F.Paste")
			(net "P3E_CPU0_PE1_PCH_RXP<12>")
		)
		(pad "DU14" smd circle
			(at -26.090118 22.445726)
			(size 0.4318 0.4318)
			(layers "F.Cu" "F.Mask" "F.Paste")
			(net "GND")
		)
		(pad "DU16" smd circle
			(at -24.373078 22.445726)
			(size 0.4318 0.4318)
			(layers "F.Cu" "F.Mask" "F.Paste")
			(net "P3E_CPU0_PE1_PCH_RXN<15>")
		)
		(pad "DU18" smd circle
			(at -22.656038 22.445726)
			(size 0.4318 0.4318)
			(layers "F.Cu" "F.Mask" "F.Paste")
			(net "P3E_CPU0_PE3_OCP_RXP<1>")
		)
		(pad "DU20" smd circle
			(at -20.938998 22.445726)
			(size 0.4318 0.4318)
			(layers "F.Cu" "F.Mask" "F.Paste")
			(net "PVCCIO_CPU0")
		)
		(pad "DU22" smd circle
			(at -19.221958 22.445726)
			(size 0.4318 0.4318)
			(layers "F.Cu" "F.Mask" "F.Paste")
			(net "GND")
		)
		(pad "DU24" smd circle
			(at -17.504918 22.445726)
			(size 0.4318 0.4318)
			(layers "F.Cu" "F.Mask" "F.Paste")
			(net "M_D_DQ<57>")
		)
		(pad "DU26" smd circle
			(at -15.787878 22.445726)
			(size 0.4318 0.4318)
			(layers "F.Cu" "F.Mask" "F.Paste")
			(net "GND")
		)
		(pad "DU28" smd circle
			(at -14.071092 22.445726)
			(size 0.4318 0.4318)
			(layers "F.Cu" "F.Mask" "F.Paste")
			(net "M_D_DQ<55>")
		)
		(pad "DU30" smd circle
			(at -12.354052 22.445726)
			(size 0.4318 0.4318)
			(layers "F.Cu" "F.Mask" "F.Paste")
			(net "M_D_DQ<49>")
		)
		(pad "DU32" smd circle
			(at -10.637012 22.445726)
			(size 0.4318 0.4318)
			(layers "F.Cu" "F.Mask" "F.Paste")
			(net "GND")
		)
		(pad "DU34" smd circle
			(at -8.919972 22.445726)
			(size 0.4318 0.4318)
			(layers "F.Cu" "F.Mask" "F.Paste")
			(net "M_D_DQ<47>")
		)
		(pad "DU36" smd circle
			(at -7.202932 22.445726)
			(size 0.4318 0.4318)
			(layers "F.Cu" "F.Mask" "F.Paste")
			(net "M_D_DQ<41>")
		)
		(pad "DU38" smd circle
			(at -5.485892 22.445726)
			(size 0.4318 0.4318)
			(layers "F.Cu" "F.Mask" "F.Paste")
			(net "GND")
		)
		(pad "DU40" smd circle
			(at -3.769106 22.445726)
			(size 0.4318 0.4318)
			(layers "F.Cu" "F.Mask" "F.Paste")
			(net "M_E_DQ<39>")
		)
		(pad "DU42" smd circle
			(at -2.052066 22.445726)
			(size 0.4318 0.4318)
			(layers "F.Cu" "F.Mask" "F.Paste")
			(net "M_E_DQ<32>")
		)
		(pad "DU44" smd circle
			(at 1.193546 20.645628)
			(size 0.508 0.508)
			(layers "F.Cu" "F.Mask" "F.Paste")
			(net "TP_CPU0_RSVD_26")
		)
		(pad "DU46" smd circle
			(at 2.910586 20.645628)
			(size 0.4318 0.4318)
			(layers "F.Cu" "F.Mask" "F.Paste")
			(net "PVDDQ_DEF")
		)
		(pad "DU48" smd circle
			(at 4.627626 20.645628)
			(size 0.4318 0.4318)
			(layers "F.Cu" "F.Mask" "F.Paste")
			(net "PVDDQ_DEF")
		)
		(pad "DU50" smd circle
			(at 6.344412 20.645628)
			(size 0.4318 0.4318)
			(layers "F.Cu" "F.Mask" "F.Paste")
			(net "PVDDQ_DEF")
		)
		(pad "DU52" smd circle
			(at 8.061452 20.645628)
			(size 0.4318 0.4318)
			(layers "F.Cu" "F.Mask" "F.Paste")
			(net "PVDDQ_DEF")
		)
		(pad "DU54" smd circle
			(at 9.778492 20.645628)
			(size 0.4318 0.4318)
			(layers "F.Cu" "F.Mask" "F.Paste")
			(net "PVDDQ_DEF")
		)
		(pad "DU56" smd circle
			(at 11.495532 20.645628)
			(size 0.4318 0.4318)
			(layers "F.Cu" "F.Mask" "F.Paste")
			(net "PVDDQ_DEF")
		)
		(pad "DU58" smd circle
			(at 13.212572 20.645628)
			(size 0.4318 0.4318)
			(layers "F.Cu" "F.Mask" "F.Paste")
			(net "PVDDQ_DEF")
		)
		(pad "DU60" smd circle
			(at 14.929612 20.645628)
			(size 0.4318 0.4318)
			(layers "F.Cu" "F.Mask" "F.Paste")
			(net "PVDDQ_DEF")
		)
		(pad "DU62" smd circle
			(at 16.646398 20.645628)
			(size 0.4318 0.4318)
			(layers "F.Cu" "F.Mask" "F.Paste")
			(net "PVDDQ_DEF")
		)
		(pad "DU64" smd circle
			(at 18.363438 20.645628)
			(size 0.4318 0.4318)
			(layers "F.Cu" "F.Mask" "F.Paste")
			(net "PVDDQ_DEF")
		)
		(pad "DU66" smd circle
			(at 20.080478 20.645628)
			(size 0.4318 0.4318)
			(layers "F.Cu" "F.Mask" "F.Paste")
			(net "M_E_ECC<6>")
		)
		(pad "DU68" smd circle
			(at 21.797518 20.645628)
			(size 0.4318 0.4318)
			(layers "F.Cu" "F.Mask" "F.Paste")
			(net "M_E_ECC<4>")
		)
		(pad "DU70" smd circle
			(at 23.514558 20.645628)
			(size 0.4318 0.4318)
			(layers "F.Cu" "F.Mask" "F.Paste")
			(net "GND")
		)
		(pad "DU72" smd circle
			(at 25.231598 20.645628)
			(size 0.4318 0.4318)
			(layers "F.Cu" "F.Mask" "F.Paste")
			(net "GND")
		)
		(pad "DU74" smd circle
			(at 26.948384 20.645628)
			(size 0.4318 0.4318)
			(layers "F.Cu" "F.Mask" "F.Paste")
			(net "M_D_DQ<31>")
		)
		(pad "DU76" smd circle
			(at 28.665424 20.645628)
			(size 0.4318 0.4318)
			(layers "F.Cu" "F.Mask" "F.Paste")
			(net "M_D_DQ<25>")
		)
		(pad "DU78" smd circle
			(at 30.382464 20.645628)
			(size 0.4318 0.4318)
			(layers "F.Cu" "F.Mask" "F.Paste")
			(net "GND")
		)
		(pad "DU80" smd circle
			(at 32.099504 20.645628)
			(size 0.4318 0.4318)
			(layers "F.Cu" "F.Mask" "F.Paste")
			(net "GND")
		)
		(pad "DU82" smd circle
			(at 33.816544 20.645628)
			(size 0.4318 0.4318)
			(layers "F.Cu" "F.Mask" "F.Paste")
			(net "GND")
		)
		(pad "DU84" smd circle
			(at 35.533584 20.645628)
			(size 0.4318 0.4318)
			(layers "F.Cu" "F.Mask" "F.Paste")
			(net "GND")
		)
		(pad "DV3" smd circle
			(at -35.533584 22.940772)
			(size 0.4318 0.4318)
			(layers "F.Cu" "F.Mask" "F.Paste")
			(net "P3E_CPU0_PE1_PCH_TXN<9>")
		)
		(pad "DV5" smd circle
			(at -33.816544 22.940772)
			(size 0.4318 0.4318)
			(layers "F.Cu" "F.Mask" "F.Paste")
			(net "P3E_CPU0_PE1_PCH_TXP<11>")
		)
		(pad "DV7" smd circle
			(at -32.099504 22.940772)
			(size 0.4318 0.4318)
			(layers "F.Cu" "F.Mask" "F.Paste")
			(net "P3E_CPU0_PE1_PCH_TXN<12>")
		)
		(pad "DV9" smd circle
			(at -30.382464 22.940772)
			(size 0.4318 0.4318)
			(layers "F.Cu" "F.Mask" "F.Paste")
			(net "P3E_CPU0_PE3_OCP_TXP<5>")
		)
		(pad "DV11" smd circle
			(at -28.665424 22.940772)
			(size 0.4318 0.4318)
			(layers "F.Cu" "F.Mask" "F.Paste")
			(net "PVCCIO_CPU0")
		)
		(pad "DV13" smd circle
			(at -26.948384 22.940772)
			(size 0.4318 0.4318)
			(layers "F.Cu" "F.Mask" "F.Paste")
			(net "P3E_CPU0_PE1_PCH_RXN<12>")
		)
		(pad "DV15" smd circle
			(at -25.231598 22.940772)
			(size 0.4318 0.4318)
			(layers "F.Cu" "F.Mask" "F.Paste")
			(net "P3E_CPU0_PE1_PCH_RXP<14>")
		)
		(pad "DV17" smd circle
			(at -23.514558 22.940772)
			(size 0.4318 0.4318)
			(layers "F.Cu" "F.Mask" "F.Paste")
			(net "P3E_CPU0_PE3_OCP_RXP<2>")
		)
		(pad "DV19" smd circle
			(at -21.797518 22.940772)
			(size 0.4318 0.4318)
			(layers "F.Cu" "F.Mask" "F.Paste")
			(net "GND")
		)
		(pad "DV21" smd circle
			(at -20.080478 22.940772)
			(size 0.4318 0.4318)
			(layers "F.Cu" "F.Mask" "F.Paste")
			(net "GND")
		)
		(pad "DV23" smd circle
			(at -18.363438 22.940772)
			(size 0.4318 0.4318)
			(layers "F.Cu" "F.Mask" "F.Paste")
			(net "M_D_DQS_DN<7>")
		)
		(pad "DV25" smd circle
			(at -16.646398 22.940772)
			(size 0.4318 0.4318)
			(layers "F.Cu" "F.Mask" "F.Paste")
			(net "GND")
		)
		(pad "DV27" smd circle
			(at -14.929612 22.940772)
			(size 0.4318 0.4318)
			(layers "F.Cu" "F.Mask" "F.Paste")
			(net "GND")
		)
		(pad "DV29" smd circle
			(at -13.212572 22.940772)
			(size 0.4318 0.4318)
			(layers "F.Cu" "F.Mask" "F.Paste")
			(net "M_D_DQS_DN<6>")
		)
		(pad "DV31" smd circle
			(at -11.495532 22.940772)
			(size 0.4318 0.4318)
			(layers "F.Cu" "F.Mask" "F.Paste")
			(net "GND")
		)
		(pad "DV33" smd circle
			(at -9.778492 22.940772)
			(size 0.4318 0.4318)
			(layers "F.Cu" "F.Mask" "F.Paste")
			(net "GND")
		)
		(pad "DV35" smd circle
			(at -8.061452 22.940772)
			(size 0.4318 0.4318)
			(layers "F.Cu" "F.Mask" "F.Paste")
			(net "M_D_DQS_DN<5>")
		)
		(pad "DV37" smd circle
			(at -6.344412 22.940772)
			(size 0.4318 0.4318)
			(layers "F.Cu" "F.Mask" "F.Paste")
			(net "GND")
		)
		(pad "DV39" smd circle
			(at -4.627626 22.940772)
			(size 0.4318 0.4318)
			(layers "F.Cu" "F.Mask" "F.Paste")
			(net "GND")
		)
		(pad "DV41" smd circle
			(at -2.910586 22.940772)
			(size 0.4318 0.4318)
			(layers "F.Cu" "F.Mask" "F.Paste")
			(net "M_E_DQS_DN<4>")
		)
		(pad "DV45" smd circle
			(at 2.052066 21.140674)
			(size 0.4318 0.4318)
			(layers "F.Cu" "F.Mask" "F.Paste")
			(net "M_D_CS_N<6>")
		)
		(pad "DV47" smd circle
			(at 3.769106 21.140674)
			(size 0.4318 0.4318)
			(layers "F.Cu" "F.Mask" "F.Paste")
			(net "M_D_C<2>")
		)
		(pad "DV49" smd circle
			(at 5.485892 21.140674)
			(size 0.4318 0.4318)
			(layers "F.Cu" "F.Mask" "F.Paste")
			(net "M_D_MA<15>")
		)
		(pad "DV51" smd circle
			(at 7.202932 21.140674)
			(size 0.4318 0.4318)
			(layers "F.Cu" "F.Mask" "F.Paste")
			(net "M_E_CS_N<0>")
		)
		(pad "DV53" smd circle
			(at 8.919972 21.140674)
			(size 0.4318 0.4318)
			(layers "F.Cu" "F.Mask" "F.Paste")
			(net "M_E_PAR")
		)
		(pad "DV55" smd circle
			(at 10.637012 21.140674)
			(size 0.4318 0.4318)
			(layers "F.Cu" "F.Mask" "F.Paste")
			(net "M_E_BA<1>")
		)
		(pad "DV57" smd circle
			(at 12.354052 21.140674)
			(size 0.4318 0.4318)
			(layers "F.Cu" "F.Mask" "F.Paste")
			(net "M_E_MA<2>")
		)
		(pad "DV59" smd circle
			(at 14.071092 21.140674)
			(size 0.4318 0.4318)
			(layers "F.Cu" "F.Mask" "F.Paste")
			(net "M_E_MA<9>")
		)
		(pad "DV61" smd circle
			(at 15.787878 21.140674)
			(size 0.4318 0.4318)
			(layers "F.Cu" "F.Mask" "F.Paste")
			(net "TP_CPU0_RSVD_25")
		)
		(pad "DV63" smd circle
			(at 17.504918 21.140674)
			(size 0.4318 0.4318)
			(layers "F.Cu" "F.Mask" "F.Paste")
			(net "M_DEF_RST_N")
		)
		(pad "DV65" smd circle
			(at 19.221958 21.140674)
			(size 0.4318 0.4318)
			(layers "F.Cu" "F.Mask" "F.Paste")
			(net "M_E_ECC<2>")
		)
		(pad "DV67" smd circle
			(at 20.938998 21.140674)
			(size 0.4318 0.4318)
			(layers "F.Cu" "F.Mask" "F.Paste")
			(net "M_E_DQS_DN<17>")
		)
		(pad "DV69" smd circle
			(at 22.656038 21.140674)
			(size 0.4318 0.4318)
			(layers "F.Cu" "F.Mask" "F.Paste")
			(net "M_E_ECC<5>")
		)
		(pad "DV71" smd circle
			(at 24.373078 21.140674)
			(size 0.4318 0.4318)
			(layers "F.Cu" "F.Mask" "F.Paste")
			(net "TP_CPU0_RSVD_24")
		)
		(pad "DV73" smd circle
			(at 26.090118 21.140674)
			(size 0.4318 0.4318)
			(layers "F.Cu" "F.Mask" "F.Paste")
			(net "GND")
		)
		(pad "DV75" smd circle
			(at 27.806904 21.140674)
			(size 0.4318 0.4318)
			(layers "F.Cu" "F.Mask" "F.Paste")
			(net "M_D_DQS_DN<3>")
		)
		(pad "DV77" smd circle
			(at 29.523944 21.140674)
			(size 0.4318 0.4318)
			(layers "F.Cu" "F.Mask" "F.Paste")
			(net "GND")
		)
		(pad "DV79" smd circle
			(at 31.240984 21.140674)
			(size 0.4318 0.4318)
			(layers "F.Cu" "F.Mask" "F.Paste")
			(net "M_E_DQS_DP<11>")
		)
		(pad "DV81" smd circle
			(at 32.958024 21.140674)
			(size 0.4318 0.4318)
			(layers "F.Cu" "F.Mask" "F.Paste")
			(net "GND")
		)
		(pad "DV83" smd circle
			(at 34.675064 21.140674)
			(size 0.4318 0.4318)
			(layers "F.Cu" "F.Mask" "F.Paste")
			(net "M_D_DQ<10>")
		)
		(pad "DV85" smd custom
			(at 36.392104 21.140674 270)
			(size 0.10795 0.10795)
			(layers "F.Cu" "F.Mask" "F.Paste")
			(net "M_D_DQ<15>")
			(options
				(clearance outline)
				(anchor circle)
			)
			(primitives
				(gr_poly
					(pts
						(arc
							(start 0.2159 -0.0381)
							(mid 0 -0.254)
							(end -0.2159 -0.0381)
						)
						(arc
							(start -0.2159 0.0381)
							(mid 0 0.254)
							(end 0.2159 0.0381)
						)
					)
					(width 0)
					(fill yes)
				)
			)
		)
		(pad "DW2" smd custom
			(at -36.392104 23.436326 90)
			(size 0.10795 0.10795)
			(layers "F.Cu" "F.Mask" "F.Paste")
			(net "GND")
			(options
				(clearance outline)
				(anchor circle)
			)
			(primitives
				(gr_poly
					(pts
						(arc
							(start 0.2159 -0.0381)
							(mid 0 -0.254)
							(end -0.2159 -0.0381)
						)
						(arc
							(start -0.2159 0.0381)
							(mid 0 0.254)
							(end 0.2159 0.0381)
						)
					)
					(width 0)
					(fill yes)
				)
			)
		)
		(pad "DW4" smd circle
			(at -34.675064 23.436326)
			(size 0.4318 0.4318)
			(layers "F.Cu" "F.Mask" "F.Paste")
			(net "P3E_CPU0_PE1_PCH_TXN<10>")
		)
		(pad "DW6" smd circle
			(at -32.958024 23.436326)
			(size 0.4318 0.4318)
			(layers "F.Cu" "F.Mask" "F.Paste")
			(net "P3E_CPU0_PE1_PCH_TXP<13>")
		)
		(pad "DW8" smd circle
			(at -31.240984 23.436326)
			(size 0.4318 0.4318)
			(layers "F.Cu" "F.Mask" "F.Paste")
			(net "GND")
		)
		(pad "DW10" smd circle
			(at -29.523944 23.436326)
			(size 0.4318 0.4318)
			(layers "F.Cu" "F.Mask" "F.Paste")
			(net "P3E_CPU0_PE3_OCP_TXN<5>")
		)
		(pad "DW12" smd circle
			(at -27.806904 23.436326)
			(size 0.4318 0.4318)
			(layers "F.Cu" "F.Mask" "F.Paste")
			(net "GND")
		)
		(pad "DW14" smd circle
			(at -26.090118 23.436326)
			(size 0.4318 0.4318)
			(layers "F.Cu" "F.Mask" "F.Paste")
			(net "P3E_CPU0_PE1_PCH_RXN<13>")
		)
		(pad "DW16" smd circle
			(at -24.373078 23.436326)
			(size 0.4318 0.4318)
			(layers "F.Cu" "F.Mask" "F.Paste")
			(net "P3E_CPU0_PE3_OCP_RXN<2>")
		)
		(pad "DW18" smd circle
			(at -22.656038 23.436326)
			(size 0.4318 0.4318)
			(layers "F.Cu" "F.Mask" "F.Paste")
			(net "P3E_CPU0_PE3_OCP_RXN<1>")
		)
		(pad "DW20" smd circle
			(at -20.938998 23.436326)
			(size 0.4318 0.4318)
			(layers "F.Cu" "F.Mask" "F.Paste")
			(net "GND")
		)
		(pad "DW22" smd circle
			(at -19.221958 23.436326)
			(size 0.4318 0.4318)
			(layers "F.Cu" "F.Mask" "F.Paste")
			(net "M_D_DQ<63>")
		)
		(pad "DW24" smd circle
			(at -17.504918 23.436326)
			(size 0.4318 0.4318)
			(layers "F.Cu" "F.Mask" "F.Paste")
			(net "GND")
		)
		(pad "DW26" smd circle
			(at -15.787878 23.436326)
			(size 0.4318 0.4318)
			(layers "F.Cu" "F.Mask" "F.Paste")
			(net "M_E_DQS_DP<15>")
		)
		(pad "DW28" smd circle
			(at -14.071092 23.436326)
			(size 0.4318 0.4318)
			(layers "F.Cu" "F.Mask" "F.Paste")
			(net "GND")
		)
		(pad "DW30" smd circle
			(at -12.354052 23.436326)
			(size 0.4318 0.4318)
			(layers "F.Cu" "F.Mask" "F.Paste")
			(net "GND")
		)
		(pad "DW32" smd circle
			(at -10.637012 23.436326)
			(size 0.4318 0.4318)
			(layers "F.Cu" "F.Mask" "F.Paste")
			(net "M_E_DQS_DP<14>")
		)
		(pad "DW34" smd circle
			(at -8.919972 23.436326)
			(size 0.4318 0.4318)
			(layers "F.Cu" "F.Mask" "F.Paste")
			(net "GND")
		)
		(pad "DW36" smd circle
			(at -7.202932 23.436326)
			(size 0.4318 0.4318)
			(layers "F.Cu" "F.Mask" "F.Paste")
			(net "GND")
		)
		(pad "DW38" smd circle
			(at -5.485892 23.436326)
			(size 0.4318 0.4318)
			(layers "F.Cu" "F.Mask" "F.Paste")
			(net "M_D_DQS_DP<13>")
		)
		(pad "DW40" smd circle
			(at -3.769106 23.436326)
			(size 0.4318 0.4318)
			(layers "F.Cu" "F.Mask" "F.Paste")
			(net "GND")
		)
		(pad "DW42" smd circle
			(at -2.052066 23.436326)
			(size 0.4318 0.4318)
			(layers "F.Cu" "F.Mask" "F.Paste")
			(net "M_E_DQ<33>")
		)
		(pad "DW44" smd circle
			(at 1.193546 21.636228)
			(size 0.508 0.508)
			(layers "F.Cu" "F.Mask" "F.Paste")
			(net "TP_CPU0_RSVD_23")
		)
		(pad "DW46" smd circle
			(at 2.910586 21.636228)
			(size 0.4318 0.4318)
			(layers "F.Cu" "F.Mask" "F.Paste")
			(net "TP_CPU0_RSVD_22")
		)
		(pad "DW48" smd circle
			(at 4.627626 21.636228)
			(size 0.4318 0.4318)
			(layers "F.Cu" "F.Mask" "F.Paste")
			(net "M_D_MA<13>")
		)
		(pad "DW50" smd circle
			(at 6.344412 21.636228)
			(size 0.4318 0.4318)
			(layers "F.Cu" "F.Mask" "F.Paste")
			(net "M_E_CS_N<4>")
		)
		(pad "DW52" smd circle
			(at 8.061452 21.636228)
			(size 0.4318 0.4318)
			(layers "F.Cu" "F.Mask" "F.Paste")
			(net "M_E_MA<0>")
		)
		(pad "DW54" smd circle
			(at 9.778492 21.636228)
			(size 0.4318 0.4318)
			(layers "F.Cu" "F.Mask" "F.Paste")
			(net "M_D_MA<10>")
		)
		(pad "DW56" smd circle
			(at 11.495532 21.636228)
			(size 0.4318 0.4318)
			(layers "F.Cu" "F.Mask" "F.Paste")
			(net "M_D_CLK_DN<2>")
		)
		(pad "DW58" smd circle
			(at 13.212572 21.636228)
			(size 0.4318 0.4318)
			(layers "F.Cu" "F.Mask" "F.Paste")
			(net "M_E_MA<1>")
		)
		(pad "DW60" smd circle
			(at 14.929612 21.636228)
			(size 0.4318 0.4318)
			(layers "F.Cu" "F.Mask" "F.Paste")
			(net "M_D_ACT_N")
		)
		(pad "DW62" smd circle
			(at 16.646398 21.636228)
			(size 0.4318 0.4318)
			(layers "F.Cu" "F.Mask" "F.Paste")
			(net "M_D_BG<1>")
		)
		(pad "DW64" smd circle
			(at 18.363438 21.636228)
			(size 0.4318 0.4318)
			(layers "F.Cu" "F.Mask" "F.Paste")
			(net "GND")
		)
		(pad "DW66" smd circle
			(at 20.080478 21.636228)
			(size 0.4318 0.4318)
			(layers "F.Cu" "F.Mask" "F.Paste")
			(net "GND")
		)
		(pad "DW68" smd circle
			(at 21.797518 21.636228)
			(size 0.4318 0.4318)
			(layers "F.Cu" "F.Mask" "F.Paste")
			(net "GND")
		)
		(pad "DW70" smd circle
			(at 23.514558 21.636228)
			(size 0.4318 0.4318)
			(layers "F.Cu" "F.Mask" "F.Paste")
			(net "GND")
		)
		(pad "DW72" smd circle
			(at 25.231598 21.636228)
			(size 0.4318 0.4318)
			(layers "F.Cu" "F.Mask" "F.Paste")
			(net "GND")
		)
		(pad "DW74" smd circle
			(at 26.948384 21.636228)
			(size 0.4318 0.4318)
			(layers "F.Cu" "F.Mask" "F.Paste")
			(net "GND")
		)
		(pad "DW76" smd circle
			(at 28.665424 21.636228)
			(size 0.4318 0.4318)
			(layers "F.Cu" "F.Mask" "F.Paste")
			(net "GND")
		)
		(pad "DW78" smd circle
			(at 30.382464 21.636228)
			(size 0.4318 0.4318)
			(layers "F.Cu" "F.Mask" "F.Paste")
			(net "M_E_DQ<22>")
		)
		(pad "DW80" smd circle
			(at 32.099504 21.636228)
			(size 0.4318 0.4318)
			(layers "F.Cu" "F.Mask" "F.Paste")
			(net "M_E_DQ<16>")
		)
		(pad "DW82" smd circle
			(at 33.816544 21.636228)
			(size 0.4318 0.4318)
			(layers "F.Cu" "F.Mask" "F.Paste")
			(net "GND")
		)
		(pad "DW84" smd circle
			(at 35.533584 21.636228)
			(size 0.4318 0.4318)
			(layers "F.Cu" "F.Mask" "F.Paste")
			(net "GND")
		)
		(pad "DY3" smd custom
			(at -35.533584 23.931626 135)
			(size 0.10795 0.10795)
			(layers "F.Cu" "F.Mask" "F.Paste")
			(net "TP_CPU0_RSVD_21")
			(options
				(clearance outline)
				(anchor circle)
			)
			(primitives
				(gr_poly
					(pts
						(arc
							(start 0.2159 -0.0381)
							(mid 0 -0.254)
							(end -0.2159 -0.0381)
						)
						(arc
							(start -0.2159 0.0381)
							(mid 0 0.254)
							(end 0.2159 0.0381)
						)
					)
					(width 0)
					(fill yes)
				)
			)
		)
		(pad "DY5" smd circle
			(at -33.816544 23.931626)
			(size 0.4318 0.4318)
			(layers "F.Cu" "F.Mask" "F.Paste")
			(net "GND")
		)
		(pad "DY7" smd circle
			(at -32.099504 23.931626)
			(size 0.4318 0.4318)
			(layers "F.Cu" "F.Mask" "F.Paste")
			(net "P3E_CPU0_PE1_PCH_TXN<13>")
		)
		(pad "DY9" smd circle
			(at -30.382464 23.931626)
			(size 0.4318 0.4318)
			(layers "F.Cu" "F.Mask" "F.Paste")
			(net "P3E_CPU0_PE3_OCP_TXP<4>")
		)
		(pad "DY11" smd circle
			(at -28.665424 23.931626)
			(size 0.4318 0.4318)
			(layers "F.Cu" "F.Mask" "F.Paste")
			(net "P3E_CPU0_PE3_OCP_TXN<3>")
		)
		(pad "DY13" smd circle
			(at -26.948384 23.931626)
			(size 0.4318 0.4318)
			(layers "F.Cu" "F.Mask" "F.Paste")
			(net "P3E_CPU0_PE1_PCH_RXP<13>")
		)
		(pad "DY15" smd circle
			(at -25.231598 23.931626)
			(size 0.4318 0.4318)
			(layers "F.Cu" "F.Mask" "F.Paste")
			(net "P3E_CPU0_PE1_PCH_RXN<14>")
		)
		(pad "DY17" smd circle
			(at -23.514558 23.931626)
			(size 0.4318 0.4318)
			(layers "F.Cu" "F.Mask" "F.Paste")
			(net "P3E_CPU0_PE3_OCP_RXP<0>")
		)
		(pad "DY19" smd circle
			(at -21.797518 23.931626)
			(size 0.4318 0.4318)
			(layers "F.Cu" "F.Mask" "F.Paste")
			(net "GND")
		)
		(pad "DY21" smd circle
			(at -20.080478 23.931626)
			(size 0.4318 0.4318)
			(layers "F.Cu" "F.Mask" "F.Paste")
			(net "M_D_DQ<58>")
		)
		(pad "DY23" smd circle
			(at -18.363438 23.931626)
			(size 0.4318 0.4318)
			(layers "F.Cu" "F.Mask" "F.Paste")
			(net "GND")
		)
		(pad "DY25" smd circle
			(at -16.646398 23.931626)
			(size 0.4318 0.4318)
			(layers "F.Cu" "F.Mask" "F.Paste")
			(net "M_E_DQ<54>")
		)
		(pad "DY27" smd circle
			(at -14.929612 23.931626)
			(size 0.4318 0.4318)
			(layers "F.Cu" "F.Mask" "F.Paste")
			(net "M_E_DQ<52>")
		)
		(pad "DY29" smd circle
			(at -13.212572 23.931626)
			(size 0.4318 0.4318)
			(layers "F.Cu" "F.Mask" "F.Paste")
			(net "GND")
		)
		(pad "DY31" smd circle
			(at -11.495532 23.931626)
			(size 0.4318 0.4318)
			(layers "F.Cu" "F.Mask" "F.Paste")
			(net "M_E_DQ<46>")
		)
		(pad "DY33" smd circle
			(at -9.778492 23.931626)
			(size 0.4318 0.4318)
			(layers "F.Cu" "F.Mask" "F.Paste")
			(net "M_E_DQ<44>")
		)
		(pad "DY35" smd circle
			(at -8.061452 23.931626)
			(size 0.4318 0.4318)
			(layers "F.Cu" "F.Mask" "F.Paste")
			(net "GND")
		)
		(pad "DY37" smd circle
			(at -6.344412 23.931626)
			(size 0.4318 0.4318)
			(layers "F.Cu" "F.Mask" "F.Paste")
			(net "M_D_DQ<38>")
		)
		(pad "DY39" smd circle
			(at -4.627626 23.931626)
			(size 0.4318 0.4318)
			(layers "F.Cu" "F.Mask" "F.Paste")
			(net "M_D_DQ<36>")
		)
		(pad "DY41" smd circle
			(at -2.910586 23.931626)
			(size 0.4318 0.4318)
			(layers "F.Cu" "F.Mask" "F.Paste")
			(net "GND")
		)
		(pad "DY45" smd circle
			(at 2.052066 22.131274)
			(size 0.4318 0.4318)
			(layers "F.Cu" "F.Mask" "F.Paste")
			(net "GND")
		)
		(pad "DY47" smd circle
			(at 3.769106 22.131274)
			(size 0.4318 0.4318)
			(layers "F.Cu" "F.Mask" "F.Paste")
			(net "GND")
		)
		(pad "DY49" smd circle
			(at 5.485892 22.131274)
			(size 0.4318 0.4318)
			(layers "F.Cu" "F.Mask" "F.Paste")
			(net "GND")
		)
		(pad "DY51" smd circle
			(at 7.202932 22.131274)
			(size 0.4318 0.4318)
			(layers "F.Cu" "F.Mask" "F.Paste")
			(net "GND")
		)
		(pad "DY53" smd circle
			(at 8.919972 22.131274)
			(size 0.4318 0.4318)
			(layers "F.Cu" "F.Mask" "F.Paste")
			(net "GND")
		)
		(pad "DY55" smd circle
			(at 10.637012 22.131274)
			(size 0.4318 0.4318)
			(layers "F.Cu" "F.Mask" "F.Paste")
			(net "GND")
		)
		(pad "DY57" smd circle
			(at 12.354052 22.131274)
			(size 0.4318 0.4318)
			(layers "F.Cu" "F.Mask" "F.Paste")
			(net "GND")
		)
		(pad "DY59" smd circle
			(at 14.071092 22.131274)
			(size 0.4318 0.4318)
			(layers "F.Cu" "F.Mask" "F.Paste")
			(net "GND")
		)
		(pad "DY61" smd circle
			(at 15.787878 22.131274)
			(size 0.4318 0.4318)
			(layers "F.Cu" "F.Mask" "F.Paste")
			(net "GND")
		)
		(pad "DY63" smd circle
			(at 17.504918 22.131274)
			(size 0.4318 0.4318)
			(layers "F.Cu" "F.Mask" "F.Paste")
			(net "GND")
		)
		(pad "DY65" smd circle
			(at 19.221958 22.131274)
			(size 0.4318 0.4318)
			(layers "F.Cu" "F.Mask" "F.Paste")
			(net "M_E_ECC<3>")
		)
		(pad "DY67" smd circle
			(at 20.938998 22.131274)
			(size 0.4318 0.4318)
			(layers "F.Cu" "F.Mask" "F.Paste")
			(net "M_E_DQS_DP<8>")
		)
		(pad "DY69" smd circle
			(at 22.656038 22.131274)
			(size 0.4318 0.4318)
			(layers "F.Cu" "F.Mask" "F.Paste")
			(net "M_E_ECC<0>")
		)
		(pad "DY71" smd circle
			(at 24.373078 22.131274)
			(size 0.4318 0.4318)
			(layers "F.Cu" "F.Mask" "F.Paste")
			(net "GND")
		)
		(pad "DY73" smd circle
			(at 26.090118 22.131274)
			(size 0.4318 0.4318)
			(layers "F.Cu" "F.Mask" "F.Paste")
			(net "M_E_DQS_DP<12>")
		)
		(pad "DY75" smd circle
			(at 27.806904 22.131274)
			(size 0.4318 0.4318)
			(layers "F.Cu" "F.Mask" "F.Paste")
			(net "GND")
		)
		(pad "DY77" smd circle
			(at 29.523944 22.131274)
			(size 0.4318 0.4318)
			(layers "F.Cu" "F.Mask" "F.Paste")
			(net "M_E_DQ<18>")
		)
		(pad "DY79" smd circle
			(at 31.240984 22.131274)
			(size 0.4318 0.4318)
			(layers "F.Cu" "F.Mask" "F.Paste")
			(net "M_E_DQS_DN<11>")
		)
		(pad "DY81" smd circle
			(at 32.958024 22.131274)
			(size 0.4318 0.4318)
			(layers "F.Cu" "F.Mask" "F.Paste")
			(net "M_E_DQ<20>")
		)
		(pad "DY83" smd circle
			(at 34.675064 22.131274)
			(size 0.4318 0.4318)
			(layers "F.Cu" "F.Mask" "F.Paste")
			(net "M_D_DQ<11>")
		)
		(pad "DY85" smd custom
			(at 36.392104 22.131274 225)
			(size 0.10795 0.10795)
			(layers "F.Cu" "F.Mask" "F.Paste")
			(net "GND")
			(options
				(clearance outline)
				(anchor circle)
			)
			(primitives
				(gr_poly
					(pts
						(arc
							(start 0.2159 -0.0381)
							(mid 0 -0.254)
							(end -0.2159 -0.0381)
						)
						(arc
							(start -0.2159 0.0381)
							(mid 0 0.254)
							(end 0.2159 0.0381)
						)
					)
					(width 0)
					(fill yes)
				)
			)
		)
		(pad "E2" smd custom
			(at -36.392104 -23.122128 45)
			(size 0.10795 0.10795)
			(layers "F.Cu" "F.Mask" "F.Paste")
			(net "TP_CPU0_RSVD_283")
			(options
				(clearance outline)
				(anchor circle)
			)
			(primitives
				(gr_poly
					(pts
						(arc
							(start 0.2159 -0.0381)
							(mid 0 -0.254)
							(end -0.2159 -0.0381)
						)
						(arc
							(start -0.2159 0.0381)
							(mid 0 0.254)
							(end 0.2159 0.0381)
						)
					)
					(width 0)
					(fill yes)
				)
			)
		)
		(pad "E4" smd custom
			(at -34.675064 -23.122128 45)
			(size 0.10795 0.10795)
			(layers "F.Cu" "F.Mask" "F.Paste")
			(net "TP_CPU0_RSVD_282")
			(options
				(clearance outline)
				(anchor circle)
			)
			(primitives
				(gr_poly
					(pts
						(arc
							(start 0.2159 -0.0381)
							(mid 0 -0.254)
							(end -0.2159 -0.0381)
						)
						(arc
							(start -0.2159 0.0381)
							(mid 0 0.254)
							(end 0.2159 0.0381)
						)
					)
					(width 0)
					(fill yes)
				)
			)
		)
		(pad "E6" smd circle
			(at -32.958024 -23.122128)
			(size 0.4318 0.4318)
			(layers "F.Cu" "F.Mask" "F.Paste")
			(net "GND")
		)
		(pad "E8" smd circle
			(at -31.240984 -23.122128)
			(size 0.4318 0.4318)
			(layers "F.Cu" "F.Mask" "F.Paste")
			(net "GND")
		)
		(pad "E10" smd circle
			(at -29.523944 -23.122128)
			(size 0.4318 0.4318)
			(layers "F.Cu" "F.Mask" "F.Paste")
			(net "UPI_CPU0_CPU1_P1P1_DP<11>")
		)
		(pad "E12" smd circle
			(at -27.806904 -23.122128)
			(size 0.4318 0.4318)
			(layers "F.Cu" "F.Mask" "F.Paste")
			(net "UPI_CPU0_CPU1_P1P1_DN<9>")
		)
		(pad "E14" smd circle
			(at -26.090118 -23.122128)
			(size 0.4318 0.4318)
			(layers "F.Cu" "F.Mask" "F.Paste")
			(net "UPI_CPU0_CPU1_P1P1_DP<7>")
		)
		(pad "E16" smd circle
			(at -24.373078 -23.122128)
			(size 0.4318 0.4318)
			(layers "F.Cu" "F.Mask" "F.Paste")
			(net "GND")
		)
		(pad "E18" smd custom
			(at -22.656038 -23.122128)
			(size 0.10795 0.10795)
			(layers "F.Cu" "F.Mask" "F.Paste")
			(net "GND")
			(options
				(clearance outline)
				(anchor circle)
			)
			(primitives
				(gr_poly
					(pts
						(arc
							(start 0.2159 -0.0381)
							(mid 0 -0.254)
							(end -0.2159 -0.0381)
						)
						(arc
							(start -0.2159 0.0381)
							(mid 0 0.254)
							(end 0.2159 0.0381)
						)
					)
					(width 0)
					(fill yes)
				)
			)
		)
		(pad "E20" smd custom
			(at -20.938998 -23.122128)
			(size 0.10795 0.10795)
			(layers "F.Cu" "F.Mask" "F.Paste")
			(net "GND")
			(options
				(clearance outline)
				(anchor circle)
			)
			(primitives
				(gr_poly
					(pts
						(arc
							(start 0.2159 -0.0381)
							(mid 0 -0.254)
							(end -0.2159 -0.0381)
						)
						(arc
							(start -0.2159 0.0381)
							(mid 0 0.254)
							(end 0.2159 0.0381)
						)
					)
					(width 0)
					(fill yes)
				)
			)
		)
		(pad "E22" smd custom
			(at -19.221958 -23.122128)
			(size 0.10795 0.10795)
			(layers "F.Cu" "F.Mask" "F.Paste")
			(net "GND")
			(options
				(clearance outline)
				(anchor circle)
			)
			(primitives
				(gr_poly
					(pts
						(arc
							(start 0.2159 -0.0381)
							(mid 0 -0.254)
							(end -0.2159 -0.0381)
						)
						(arc
							(start -0.2159 0.0381)
							(mid 0 0.254)
							(end 0.2159 0.0381)
						)
					)
					(width 0)
					(fill yes)
				)
			)
		)
		(pad "E24" smd custom
			(at -17.504918 -23.122128)
			(size 0.10795 0.10795)
			(layers "F.Cu" "F.Mask" "F.Paste")
			(net "TP_CPU0_RSVD_281")
			(options
				(clearance outline)
				(anchor circle)
			)
			(primitives
				(gr_poly
					(pts
						(arc
							(start 0.2159 -0.0381)
							(mid 0 -0.254)
							(end -0.2159 -0.0381)
						)
						(arc
							(start -0.2159 0.0381)
							(mid 0 0.254)
							(end 0.2159 0.0381)
						)
					)
					(width 0)
					(fill yes)
				)
			)
		)
		(pad "E26" smd circle
			(at -15.787878 -23.122128)
			(size 0.4318 0.4318)
			(layers "F.Cu" "F.Mask" "F.Paste")
			(net "M_B_DQ<51>")
		)
		(pad "E28" smd circle
			(at -14.071092 -23.122128)
			(size 0.4318 0.4318)
			(layers "F.Cu" "F.Mask" "F.Paste")
			(net "M_B_DQS_DP<6>")
		)
		(pad "E30" smd circle
			(at -12.354052 -23.122128)
			(size 0.4318 0.4318)
			(layers "F.Cu" "F.Mask" "F.Paste")
			(net "M_B_DQ<52>")
		)
		(pad "E32" smd circle
			(at -10.637012 -23.122128)
			(size 0.4318 0.4318)
			(layers "F.Cu" "F.Mask" "F.Paste")
			(net "M_B_DQ<43>")
		)
		(pad "E34" smd circle
			(at -8.919972 -23.122128)
			(size 0.4318 0.4318)
			(layers "F.Cu" "F.Mask" "F.Paste")
			(net "M_B_DQS_DP<5>")
		)
		(pad "E36" smd circle
			(at -7.202932 -23.122128)
			(size 0.4318 0.4318)
			(layers "F.Cu" "F.Mask" "F.Paste")
			(net "M_B_DQ<44>")
		)
		(pad "E38" smd circle
			(at -5.485892 -23.122128)
			(size 0.4318 0.4318)
			(layers "F.Cu" "F.Mask" "F.Paste")
			(net "M_A_DQ<35>")
		)
		(pad "E40" smd circle
			(at -3.769106 -23.122128)
			(size 0.4318 0.4318)
			(layers "F.Cu" "F.Mask" "F.Paste")
			(net "M_A_DQS_DP<4>")
		)
		(pad "E42" smd circle
			(at -2.052066 -23.122128)
			(size 0.4318 0.4318)
			(layers "F.Cu" "F.Mask" "F.Paste")
			(net "M_A_DQ<36>")
		)
		(pad "E46" smd circle
			(at 2.910586 -24.921972)
			(size 0.4318 0.4318)
			(layers "F.Cu" "F.Mask" "F.Paste")
			(net "PVDDQ_ABC")
		)
		(pad "E48" smd circle
			(at 4.627626 -24.921972)
			(size 0.4318 0.4318)
			(layers "F.Cu" "F.Mask" "F.Paste")
			(net "PVDDQ_ABC")
		)
		(pad "E50" smd circle
			(at 6.344412 -24.921972)
			(size 0.4318 0.4318)
			(layers "F.Cu" "F.Mask" "F.Paste")
			(net "PVDDQ_ABC")
		)
		(pad "E52" smd circle
			(at 8.061452 -24.921972)
			(size 0.4318 0.4318)
			(layers "F.Cu" "F.Mask" "F.Paste")
			(net "PVDDQ_ABC")
		)
		(pad "E54" smd circle
			(at 9.778492 -24.921972)
			(size 0.4318 0.4318)
			(layers "F.Cu" "F.Mask" "F.Paste")
			(net "PVDDQ_ABC")
		)
		(pad "E56" smd circle
			(at 11.495532 -24.921972)
			(size 0.4318 0.4318)
			(layers "F.Cu" "F.Mask" "F.Paste")
			(net "PVDDQ_ABC")
		)
		(pad "E58" smd circle
			(at 13.212572 -24.921972)
			(size 0.4318 0.4318)
			(layers "F.Cu" "F.Mask" "F.Paste")
			(net "PVDDQ_ABC")
		)
		(pad "E60" smd circle
			(at 14.929612 -24.921972)
			(size 0.4318 0.4318)
			(layers "F.Cu" "F.Mask" "F.Paste")
			(net "PVDDQ_ABC")
		)
		(pad "E62" smd circle
			(at 16.646398 -24.921972)
			(size 0.4318 0.4318)
			(layers "F.Cu" "F.Mask" "F.Paste")
			(net "PVDDQ_ABC")
		)
		(pad "E64" smd circle
			(at 18.363438 -24.921972)
			(size 0.4318 0.4318)
			(layers "F.Cu" "F.Mask" "F.Paste")
			(net "PVDDQ_ABC")
		)
		(pad "E66" smd custom
			(at 20.080478 -24.921972)
			(size 0.10795 0.10795)
			(layers "F.Cu" "F.Mask" "F.Paste")
			(net "GND")
			(options
				(clearance outline)
				(anchor circle)
			)
			(primitives
				(gr_poly
					(pts
						(arc
							(start 0.2159 -0.0381)
							(mid 0 -0.254)
							(end -0.2159 -0.0381)
						)
						(arc
							(start -0.2159 0.0381)
							(mid 0 0.254)
							(end 0.2159 0.0381)
						)
					)
					(width 0)
					(fill yes)
				)
			)
		)
		(pad "E72" smd circle
			(at 25.231598 -24.921972)
			(size 0.4318 0.4318)
			(layers "F.Cu" "F.Mask" "F.Paste")
			(net "GND")
		)
		(pad "E74" smd circle
			(at 26.948384 -24.921972)
			(size 0.4318 0.4318)
			(layers "F.Cu" "F.Mask" "F.Paste")
			(net "GND")
		)
		(pad "E76" smd circle
			(at 28.665424 -24.921972)
			(size 0.4318 0.4318)
			(layers "F.Cu" "F.Mask" "F.Paste")
			(net "GND")
		)
		(pad "E78" smd circle
			(at 30.382464 -24.921972)
			(size 0.4318 0.4318)
			(layers "F.Cu" "F.Mask" "F.Paste")
			(net "M_B_DQ<22>")
		)
		(pad "E80" smd circle
			(at 32.099504 -24.921972)
			(size 0.4318 0.4318)
			(layers "F.Cu" "F.Mask" "F.Paste")
			(net "M_B_DQ<16>")
		)
		(pad "E82" smd custom
			(at 33.816544 -24.921972 315)
			(size 0.10795 0.10795)
			(layers "F.Cu" "F.Mask" "F.Paste")
			(net "GND")
			(options
				(clearance outline)
				(anchor circle)
			)
			(primitives
				(gr_poly
					(pts
						(arc
							(start 0.2159 -0.0381)
							(mid 0 -0.254)
							(end -0.2159 -0.0381)
						)
						(arc
							(start -0.2159 0.0381)
							(mid 0 0.254)
							(end 0.2159 0.0381)
						)
					)
					(width 0)
					(fill yes)
				)
			)
		)
		(pad "E84" smd custom
			(at 35.533584 -24.921972 270)
			(size 0.10795 0.10795)
			(layers "F.Cu" "F.Mask" "F.Paste")
			(net "TP_CPU0_RSVD_280")
			(options
				(clearance outline)
				(anchor circle)
			)
			(primitives
				(gr_poly
					(pts
						(arc
							(start 0.2159 -0.0381)
							(mid 0 -0.254)
							(end -0.2159 -0.0381)
						)
						(arc
							(start -0.2159 0.0381)
							(mid 0 0.254)
							(end 0.2159 0.0381)
						)
					)
					(width 0)
					(fill yes)
				)
			)
		)
		(pad "EA4" smd custom
			(at -34.675064 24.426672 135)
			(size 0.10795 0.10795)
			(layers "F.Cu" "F.Mask" "F.Paste")
			(net "TP_CPU0_RSVD_20")
			(options
				(clearance outline)
				(anchor circle)
			)
			(primitives
				(gr_poly
					(pts
						(arc
							(start 0.2159 -0.0381)
							(mid 0 -0.254)
							(end -0.2159 -0.0381)
						)
						(arc
							(start -0.2159 0.0381)
							(mid 0 0.254)
							(end 0.2159 0.0381)
						)
					)
					(width 0)
					(fill yes)
				)
			)
		)
		(pad "EA6" smd circle
			(at -32.958024 24.426672)
			(size 0.4318 0.4318)
			(layers "F.Cu" "F.Mask" "F.Paste")
			(net "GND")
		)
		(pad "EA8" smd circle
			(at -31.240984 24.426672)
			(size 0.4318 0.4318)
			(layers "F.Cu" "F.Mask" "F.Paste")
			(net "P3E_CPU0_PE1_PCH_TXN<14>")
		)
		(pad "EA10" smd circle
			(at -29.523944 24.426672)
			(size 0.4318 0.4318)
			(layers "F.Cu" "F.Mask" "F.Paste")
			(net "P3E_CPU0_PE3_OCP_TXP<3>")
		)
		(pad "EA12" smd circle
			(at -27.806904 24.426672)
			(size 0.4318 0.4318)
			(layers "F.Cu" "F.Mask" "F.Paste")
			(net "PVCCIO_CPU0")
		)
		(pad "EA14" smd circle
			(at -26.090118 24.426672)
			(size 0.4318 0.4318)
			(layers "F.Cu" "F.Mask" "F.Paste")
			(net "GND")
		)
		(pad "EA16" smd custom
			(at -24.373078 24.426672 180)
			(size 0.10795 0.10795)
			(layers "F.Cu" "F.Mask" "F.Paste")
			(net "GND")
			(options
				(clearance outline)
				(anchor circle)
			)
			(primitives
				(gr_poly
					(pts
						(arc
							(start 0.2159 -0.0381)
							(mid 0 -0.254)
							(end -0.2159 -0.0381)
						)
						(arc
							(start -0.2159 0.0381)
							(mid 0 0.254)
							(end 0.2159 0.0381)
						)
					)
					(width 0)
					(fill yes)
				)
			)
		)
		(pad "EA18" smd custom
			(at -22.656038 24.426672 180)
			(size 0.10795 0.10795)
			(layers "F.Cu" "F.Mask" "F.Paste")
			(net "P3E_CPU0_PE3_OCP_RXN<0>")
			(options
				(clearance outline)
				(anchor circle)
			)
			(primitives
				(gr_poly
					(pts
						(arc
							(start 0.2159 -0.0381)
							(mid 0 -0.254)
							(end -0.2159 -0.0381)
						)
						(arc
							(start -0.2159 0.0381)
							(mid 0 0.254)
							(end 0.2159 0.0381)
						)
					)
					(width 0)
					(fill yes)
				)
			)
		)
		(pad "EA20" smd custom
			(at -20.938998 24.426672 120)
			(size 0.10795 0.10795)
			(layers "F.Cu" "F.Mask" "F.Paste")
			(net "GND")
			(options
				(clearance outline)
				(anchor circle)
			)
			(primitives
				(gr_poly
					(pts
						(arc
							(start 0.2159 -0.0381)
							(mid 0 -0.254)
							(end -0.2159 -0.0381)
						)
						(arc
							(start -0.2159 0.0381)
							(mid 0 0.254)
							(end 0.2159 0.0381)
						)
					)
					(width 0)
					(fill yes)
				)
			)
		)
		(pad "EA22" smd circle
			(at -19.221958 24.426672)
			(size 0.4318 0.4318)
			(layers "F.Cu" "F.Mask" "F.Paste")
			(net "GND")
		)
		(pad "EA24" smd circle
			(at -17.504918 24.426672)
			(size 0.4318 0.4318)
			(layers "F.Cu" "F.Mask" "F.Paste")
			(net "M_E_DQ<50>")
		)
		(pad "EA26" smd circle
			(at -15.787878 24.426672)
			(size 0.4318 0.4318)
			(layers "F.Cu" "F.Mask" "F.Paste")
			(net "M_E_DQS_DN<15>")
		)
		(pad "EA28" smd circle
			(at -14.071092 24.426672)
			(size 0.4318 0.4318)
			(layers "F.Cu" "F.Mask" "F.Paste")
			(net "M_E_DQ<53>")
		)
		(pad "EA30" smd circle
			(at -12.354052 24.426672)
			(size 0.4318 0.4318)
			(layers "F.Cu" "F.Mask" "F.Paste")
			(net "M_E_DQ<42>")
		)
		(pad "EA32" smd circle
			(at -10.637012 24.426672)
			(size 0.4318 0.4318)
			(layers "F.Cu" "F.Mask" "F.Paste")
			(net "M_E_DQS_DN<14>")
		)
		(pad "EA34" smd circle
			(at -8.919972 24.426672)
			(size 0.4318 0.4318)
			(layers "F.Cu" "F.Mask" "F.Paste")
			(net "M_E_DQ<45>")
		)
		(pad "EA36" smd circle
			(at -7.202932 24.426672)
			(size 0.4318 0.4318)
			(layers "F.Cu" "F.Mask" "F.Paste")
			(net "M_D_DQ<34>")
		)
		(pad "EA38" smd circle
			(at -5.485892 24.426672)
			(size 0.4318 0.4318)
			(layers "F.Cu" "F.Mask" "F.Paste")
			(net "M_D_DQS_DN<13>")
		)
		(pad "EA40" smd circle
			(at -3.769106 24.426672)
			(size 0.4318 0.4318)
			(layers "F.Cu" "F.Mask" "F.Paste")
			(net "M_D_DQ<37>")
		)
		(pad "EA42" smd circle
			(at -2.052066 24.426672)
			(size 0.4318 0.4318)
			(layers "F.Cu" "F.Mask" "F.Paste")
			(net "GND")
		)
		(pad "EA44" smd circle
			(at 1.193546 22.626828)
			(size 0.508 0.508)
			(layers "F.Cu" "F.Mask" "F.Paste")
			(net "TP_CPU0_RSVD_19")
		)
		(pad "EA46" smd circle
			(at 2.910586 22.626828)
			(size 0.4318 0.4318)
			(layers "F.Cu" "F.Mask" "F.Paste")
			(net "M_D_MA<17>")
		)
		(pad "EA48" smd circle
			(at 4.627626 22.626828)
			(size 0.4318 0.4318)
			(layers "F.Cu" "F.Mask" "F.Paste")
			(net "M_D_ODT<3>")
		)
		(pad "EA50" smd circle
			(at 6.344412 22.626828)
			(size 0.4318 0.4318)
			(layers "F.Cu" "F.Mask" "F.Paste")
			(net "M_D_ODT<2>")
		)
		(pad "EA52" smd circle
			(at 8.061452 22.626828)
			(size 0.4318 0.4318)
			(layers "F.Cu" "F.Mask" "F.Paste")
			(net "M_D_MA<16>")
		)
		(pad "EA54" smd circle
			(at 9.778492 22.626828)
			(size 0.4318 0.4318)
			(layers "F.Cu" "F.Mask" "F.Paste")
			(net "M_D_BA<1>")
		)
		(pad "EA56" smd circle
			(at 11.495532 22.626828)
			(size 0.4318 0.4318)
			(layers "F.Cu" "F.Mask" "F.Paste")
			(net "M_D_CLK_DP<2>")
		)
		(pad "EA58" smd circle
			(at 13.212572 22.626828)
			(size 0.4318 0.4318)
			(layers "F.Cu" "F.Mask" "F.Paste")
			(net "M_D_MA<5>")
		)
		(pad "EA60" smd circle
			(at 14.929612 22.626828)
			(size 0.4318 0.4318)
			(layers "F.Cu" "F.Mask" "F.Paste")
			(net "M_D_MA<7>")
		)
		(pad "EA62" smd circle
			(at 16.646398 22.626828)
			(size 0.4318 0.4318)
			(layers "F.Cu" "F.Mask" "F.Paste")
			(net "M_D_CKE<2>")
		)
		(pad "EA64" smd circle
			(at 18.363438 22.626828)
			(size 0.4318 0.4318)
			(layers "F.Cu" "F.Mask" "F.Paste")
			(net "GND")
		)
		(pad "EA66" smd circle
			(at 20.080478 22.626828)
			(size 0.4318 0.4318)
			(layers "F.Cu" "F.Mask" "F.Paste")
			(net "M_E_ECC<7>")
		)
		(pad "EA68" smd circle
			(at 21.797518 22.626828)
			(size 0.4318 0.4318)
			(layers "F.Cu" "F.Mask" "F.Paste")
			(net "M_E_ECC<1>")
		)
		(pad "EA70" smd circle
			(at 23.514558 22.626828)
			(size 0.4318 0.4318)
			(layers "F.Cu" "F.Mask" "F.Paste")
			(net "GND")
		)
		(pad "EA72" smd circle
			(at 25.231598 22.626828)
			(size 0.4318 0.4318)
			(layers "F.Cu" "F.Mask" "F.Paste")
			(net "M_E_DQ<30>")
		)
		(pad "EA74" smd circle
			(at 26.948384 22.626828)
			(size 0.4318 0.4318)
			(layers "F.Cu" "F.Mask" "F.Paste")
			(net "M_E_DQ<28>")
		)
		(pad "EA76" smd circle
			(at 28.665424 22.626828)
			(size 0.4318 0.4318)
			(layers "F.Cu" "F.Mask" "F.Paste")
			(net "GND")
		)
		(pad "EA78" smd circle
			(at 30.382464 22.626828)
			(size 0.4318 0.4318)
			(layers "F.Cu" "F.Mask" "F.Paste")
			(net "GND")
		)
		(pad "EA80" smd circle
			(at 32.099504 22.626828)
			(size 0.4318 0.4318)
			(layers "F.Cu" "F.Mask" "F.Paste")
			(net "GND")
		)
		(pad "EA82" smd circle
			(at 33.816544 22.626828)
			(size 0.4318 0.4318)
			(layers "F.Cu" "F.Mask" "F.Paste")
			(net "GND")
		)
		(pad "EA84" smd custom
			(at 35.533584 22.626828 225)
			(size 0.10795 0.10795)
			(layers "F.Cu" "F.Mask" "F.Paste")
			(net "GND")
			(options
				(clearance outline)
				(anchor circle)
			)
			(primitives
				(gr_poly
					(pts
						(arc
							(start 0.2159 -0.0381)
							(mid 0 -0.254)
							(end -0.2159 -0.0381)
						)
						(arc
							(start -0.2159 0.0381)
							(mid 0 0.254)
							(end 0.2159 0.0381)
						)
					)
					(width 0)
					(fill yes)
				)
			)
		)
		(pad "EB3" smd custom
			(at -35.533584 24.921972 135)
			(size 0.10795 0.10795)
			(layers "F.Cu" "F.Mask" "F.Paste")
			(net "TP_CPU0_RSVD_18")
			(options
				(clearance outline)
				(anchor circle)
			)
			(primitives
				(gr_poly
					(pts
						(arc
							(start 0.2159 -0.0381)
							(mid 0 -0.254)
							(end -0.2159 -0.0381)
						)
						(arc
							(start -0.2159 0.0381)
							(mid 0 0.254)
							(end 0.2159 0.0381)
						)
					)
					(width 0)
					(fill yes)
				)
			)
		)
		(pad "EB5" smd custom
			(at -33.816544 24.921972 135)
			(size 0.10795 0.10795)
			(layers "F.Cu" "F.Mask" "F.Paste")
			(net "TP_CPU0_RSVD_17")
			(options
				(clearance outline)
				(anchor circle)
			)
			(primitives
				(gr_poly
					(pts
						(arc
							(start 0.2159 -0.0381)
							(mid 0 -0.254)
							(end -0.2159 -0.0381)
						)
						(arc
							(start -0.2159 0.0381)
							(mid 0 0.254)
							(end 0.2159 0.0381)
						)
					)
					(width 0)
					(fill yes)
				)
			)
		)
		(pad "EB7" smd circle
			(at -32.099504 24.921972)
			(size 0.4318 0.4318)
			(layers "F.Cu" "F.Mask" "F.Paste")
			(net "P3E_CPU0_PE1_PCH_TXP<14>")
		)
		(pad "EB9" smd circle
			(at -30.382464 24.921972)
			(size 0.4318 0.4318)
			(layers "F.Cu" "F.Mask" "F.Paste")
			(net "P3E_CPU0_PE3_OCP_TXN<4>")
		)
		(pad "EB11" smd circle
			(at -28.665424 24.921972)
			(size 0.4318 0.4318)
			(layers "F.Cu" "F.Mask" "F.Paste")
			(net "P3E_CPU0_PE3_OCP_TXP<2>")
		)
		(pad "EB13" smd circle
			(at -26.948384 24.921972)
			(size 0.4318 0.4318)
			(layers "F.Cu" "F.Mask" "F.Paste")
			(net "GND")
		)
		(pad "EB15" smd circle
			(at -25.231598 24.921972)
			(size 0.4318 0.4318)
			(layers "F.Cu" "F.Mask" "F.Paste")
			(net "PVCCIO_CPU0")
		)
		(pad "EB21" smd custom
			(at -20.080478 24.921972 120)
			(size 0.10795 0.10795)
			(layers "F.Cu" "F.Mask" "F.Paste")
			(net "M_D_DQ<59>")
			(options
				(clearance outline)
				(anchor circle)
			)
			(primitives
				(gr_poly
					(pts
						(arc
							(start 0.2159 -0.0381)
							(mid 0 -0.254)
							(end -0.2159 -0.0381)
						)
						(arc
							(start -0.2159 0.0381)
							(mid 0 0.254)
							(end 0.2159 0.0381)
						)
					)
					(width 0)
					(fill yes)
				)
			)
		)
		(pad "EB23" smd circle
			(at -18.363438 24.921972)
			(size 0.4318 0.4318)
			(layers "F.Cu" "F.Mask" "F.Paste")
			(net "GND")
		)
		(pad "EB25" smd circle
			(at -16.646398 24.921972)
			(size 0.4318 0.4318)
			(layers "F.Cu" "F.Mask" "F.Paste")
			(net "GND")
		)
		(pad "EB27" smd circle
			(at -14.929612 24.921972)
			(size 0.4318 0.4318)
			(layers "F.Cu" "F.Mask" "F.Paste")
			(net "GND")
		)
		(pad "EB29" smd circle
			(at -13.212572 24.921972)
			(size 0.4318 0.4318)
			(layers "F.Cu" "F.Mask" "F.Paste")
			(net "GND")
		)
		(pad "EB31" smd circle
			(at -11.495532 24.921972)
			(size 0.4318 0.4318)
			(layers "F.Cu" "F.Mask" "F.Paste")
			(net "GND")
		)
		(pad "EB33" smd circle
			(at -9.778492 24.921972)
			(size 0.4318 0.4318)
			(layers "F.Cu" "F.Mask" "F.Paste")
			(net "GND")
		)
		(pad "EB35" smd circle
			(at -8.061452 24.921972)
			(size 0.4318 0.4318)
			(layers "F.Cu" "F.Mask" "F.Paste")
			(net "GND")
		)
		(pad "EB37" smd circle
			(at -6.344412 24.921972)
			(size 0.4318 0.4318)
			(layers "F.Cu" "F.Mask" "F.Paste")
			(net "GND")
		)
		(pad "EB39" smd circle
			(at -4.627626 24.921972)
			(size 0.4318 0.4318)
			(layers "F.Cu" "F.Mask" "F.Paste")
			(net "GND")
		)
		(pad "EB41" smd circle
			(at -2.910586 24.921972)
			(size 0.4318 0.4318)
			(layers "F.Cu" "F.Mask" "F.Paste")
			(net "GND")
		)
		(pad "EB45" smd circle
			(at 2.052066 23.122128)
			(size 0.4318 0.4318)
			(layers "F.Cu" "F.Mask" "F.Paste")
			(net "M_D_CS_N<7>")
		)
		(pad "EB47" smd circle
			(at 3.769106 23.122128)
			(size 0.4318 0.4318)
			(layers "F.Cu" "F.Mask" "F.Paste")
			(net "M_D_CS_N<3>")
		)
		(pad "EB49" smd circle
			(at 5.485892 23.122128)
			(size 0.4318 0.4318)
			(layers "F.Cu" "F.Mask" "F.Paste")
			(net "M_D_CS_N<5>")
		)
		(pad "EB51" smd circle
			(at 7.202932 23.122128)
			(size 0.4318 0.4318)
			(layers "F.Cu" "F.Mask" "F.Paste")
			(net "M_D_CS_N<4>")
		)
		(pad "EB53" smd circle
			(at 8.919972 23.122128)
			(size 0.4318 0.4318)
			(layers "F.Cu" "F.Mask" "F.Paste")
			(net "M_D_MA<0>")
		)
		(pad "EB55" smd circle
			(at 10.637012 23.122128)
			(size 0.4318 0.4318)
			(layers "F.Cu" "F.Mask" "F.Paste")
			(net "M_D_CLK_DP<0>")
		)
		(pad "EB57" smd circle
			(at 12.354052 23.122128)
			(size 0.4318 0.4318)
			(layers "F.Cu" "F.Mask" "F.Paste")
			(net "M_D_MA<3>")
		)
		(pad "EB59" smd circle
			(at 14.071092 23.122128)
			(size 0.4318 0.4318)
			(layers "F.Cu" "F.Mask" "F.Paste")
			(net "M_D_MA<8>")
		)
		(pad "EB61" smd circle
			(at 15.787878 23.122128)
			(size 0.4318 0.4318)
			(layers "F.Cu" "F.Mask" "F.Paste")
			(net "M_D_MA<11>")
		)
		(pad "EB63" smd custom
			(at 17.504918 23.122128 180)
			(size 0.10795 0.10795)
			(layers "F.Cu" "F.Mask" "F.Paste")
			(net "M_D_CKE<3>")
			(options
				(clearance outline)
				(anchor circle)
			)
			(primitives
				(gr_poly
					(pts
						(arc
							(start 0.2159 -0.0381)
							(mid 0 -0.254)
							(end -0.2159 -0.0381)
						)
						(arc
							(start -0.2159 0.0381)
							(mid 0 0.254)
							(end 0.2159 0.0381)
						)
					)
					(width 0)
					(fill yes)
				)
			)
		)
		(pad "EB65" smd custom
			(at 19.221958 23.122128 180)
			(size 0.10795 0.10795)
			(layers "F.Cu" "F.Mask" "F.Paste")
			(net "GND")
			(options
				(clearance outline)
				(anchor circle)
			)
			(primitives
				(gr_poly
					(pts
						(arc
							(start 0.2159 -0.0381)
							(mid 0 -0.254)
							(end -0.2159 -0.0381)
						)
						(arc
							(start -0.2159 0.0381)
							(mid 0 0.254)
							(end 0.2159 0.0381)
						)
					)
					(width 0)
					(fill yes)
				)
			)
		)
		(pad "EB67" smd custom
			(at 20.938998 23.122128 180)
			(size 0.10795 0.10795)
			(layers "F.Cu" "F.Mask" "F.Paste")
			(net "M_E_DQS_DN<8>")
			(options
				(clearance outline)
				(anchor circle)
			)
			(primitives
				(gr_poly
					(pts
						(arc
							(start 0.2159 -0.0381)
							(mid 0 -0.254)
							(end -0.2159 -0.0381)
						)
						(arc
							(start -0.2159 0.0381)
							(mid 0 0.254)
							(end 0.2159 0.0381)
						)
					)
					(width 0)
					(fill yes)
				)
			)
		)
		(pad "EB69" smd custom
			(at 22.656038 23.122128 180)
			(size 0.10795 0.10795)
			(layers "F.Cu" "F.Mask" "F.Paste")
			(net "GND")
			(options
				(clearance outline)
				(anchor circle)
			)
			(primitives
				(gr_poly
					(pts
						(arc
							(start 0.2159 -0.0381)
							(mid 0 -0.254)
							(end -0.2159 -0.0381)
						)
						(arc
							(start -0.2159 0.0381)
							(mid 0 0.254)
							(end 0.2159 0.0381)
						)
					)
					(width 0)
					(fill yes)
				)
			)
		)
		(pad "EB71" smd circle
			(at 24.373078 23.122128)
			(size 0.4318 0.4318)
			(layers "F.Cu" "F.Mask" "F.Paste")
			(net "M_E_DQ<26>")
		)
		(pad "EB73" smd circle
			(at 26.090118 23.122128)
			(size 0.4318 0.4318)
			(layers "F.Cu" "F.Mask" "F.Paste")
			(net "M_E_DQS_DN<12>")
		)
		(pad "EB75" smd circle
			(at 27.806904 23.122128)
			(size 0.4318 0.4318)
			(layers "F.Cu" "F.Mask" "F.Paste")
			(net "M_E_DQ<29>")
		)
		(pad "EB77" smd circle
			(at 29.523944 23.122128)
			(size 0.4318 0.4318)
			(layers "F.Cu" "F.Mask" "F.Paste")
			(net "M_E_DQ<19>")
		)
		(pad "EB79" smd circle
			(at 31.240984 23.122128)
			(size 0.4318 0.4318)
			(layers "F.Cu" "F.Mask" "F.Paste")
			(net "M_E_DQS_DP<2>")
		)
		(pad "EB81" smd circle
			(at 32.958024 23.122128)
			(size 0.4318 0.4318)
			(layers "F.Cu" "F.Mask" "F.Paste")
			(net "M_E_DQ<21>")
		)
		(pad "EB83" smd custom
			(at 34.675064 23.122128 225)
			(size 0.10795 0.10795)
			(layers "F.Cu" "F.Mask" "F.Paste")
			(net "GND")
			(options
				(clearance outline)
				(anchor circle)
			)
			(primitives
				(gr_poly
					(pts
						(arc
							(start 0.2159 -0.0381)
							(mid 0 -0.254)
							(end -0.2159 -0.0381)
						)
						(arc
							(start -0.2159 0.0381)
							(mid 0 0.254)
							(end 0.2159 0.0381)
						)
					)
					(width 0)
					(fill yes)
				)
			)
		)
		(pad "EB85" smd custom
			(at 36.392104 23.122128 270)
			(size 0.10795 0.10795)
			(layers "F.Cu" "F.Mask" "F.Paste")
			(net "TP_CPU0_RSVD_16")
			(options
				(clearance outline)
				(anchor circle)
			)
			(primitives
				(gr_poly
					(pts
						(arc
							(start 0.2159 -0.0381)
							(mid 0 -0.254)
							(end -0.2159 -0.0381)
						)
						(arc
							(start -0.2159 0.0381)
							(mid 0 0.254)
							(end 0.2159 0.0381)
						)
					)
					(width 0)
					(fill yes)
				)
			)
		)
		(pad "EC4" smd custom
			(at -34.675064 25.417526 135)
			(size 0.10795 0.10795)
			(layers "F.Cu" "F.Mask" "F.Paste")
			(net "TP_CPU0_RSVD_14")
			(options
				(clearance outline)
				(anchor circle)
			)
			(primitives
				(gr_poly
					(pts
						(arc
							(start 0.2159 -0.0381)
							(mid 0 -0.254)
							(end -0.2159 -0.0381)
						)
						(arc
							(start -0.2159 0.0381)
							(mid 0 0.254)
							(end 0.2159 0.0381)
						)
					)
					(width 0)
					(fill yes)
				)
			)
		)
		(pad "EC6" smd custom
			(at -32.958024 25.417526 135)
			(size 0.10795 0.10795)
			(layers "F.Cu" "F.Mask" "F.Paste")
			(net "GND")
			(options
				(clearance outline)
				(anchor circle)
			)
			(primitives
				(gr_poly
					(pts
						(arc
							(start 0.2159 -0.0381)
							(mid 0 -0.254)
							(end -0.2159 -0.0381)
						)
						(arc
							(start -0.2159 0.0381)
							(mid 0 0.254)
							(end 0.2159 0.0381)
						)
					)
					(width 0)
					(fill yes)
				)
			)
		)
		(pad "EC8" smd circle
			(at -31.240984 25.417526)
			(size 0.4318 0.4318)
			(layers "F.Cu" "F.Mask" "F.Paste")
			(net "P3E_CPU0_PE1_PCH_TXP<15>")
		)
		(pad "EC10" smd circle
			(at -29.523944 25.417526)
			(size 0.4318 0.4318)
			(layers "F.Cu" "F.Mask" "F.Paste")
			(net "GND")
		)
		(pad "EC12" smd circle
			(at -27.806904 25.417526)
			(size 0.4318 0.4318)
			(layers "F.Cu" "F.Mask" "F.Paste")
			(net "P3E_CPU0_PE3_OCP_TXN<2>")
		)
		(pad "EC14" smd circle
			(at -26.090118 25.417526)
			(size 0.4318 0.4318)
			(layers "F.Cu" "F.Mask" "F.Paste")
			(net "P3E_CPU0_PE3_OCP_TXP<0>")
		)
		(pad "EC16" smd custom
			(at -24.373078 25.417526 180)
			(size 0.10795 0.10795)
			(layers "F.Cu" "F.Mask" "F.Paste")
			(net "TP_CPU0_RSVD_15")
			(options
				(clearance outline)
				(anchor circle)
			)
			(primitives
				(gr_poly
					(pts
						(arc
							(start 0.2159 -0.0381)
							(mid 0 -0.254)
							(end -0.2159 -0.0381)
						)
						(arc
							(start -0.2159 0.0381)
							(mid 0 0.254)
							(end 0.2159 0.0381)
						)
					)
					(width 0)
					(fill yes)
				)
			)
		)
		(pad "EC22" smd custom
			(at -19.221958 25.417526 120)
			(size 0.10795 0.10795)
			(layers "F.Cu" "F.Mask" "F.Paste")
			(net "M_D_DQ<62>")
			(options
				(clearance outline)
				(anchor circle)
			)
			(primitives
				(gr_poly
					(pts
						(arc
							(start 0.2159 -0.0381)
							(mid 0 -0.254)
							(end -0.2159 -0.0381)
						)
						(arc
							(start -0.2159 0.0381)
							(mid 0 0.254)
							(end 0.2159 0.0381)
						)
					)
					(width 0)
					(fill yes)
				)
			)
		)
		(pad "EC24" smd circle
			(at -17.504918 25.417526)
			(size 0.4318 0.4318)
			(layers "F.Cu" "F.Mask" "F.Paste")
			(net "M_E_DQ<51>")
		)
		(pad "EC26" smd circle
			(at -15.787878 25.417526)
			(size 0.4318 0.4318)
			(layers "F.Cu" "F.Mask" "F.Paste")
			(net "M_E_DQS_DP<6>")
		)
		(pad "EC28" smd circle
			(at -14.071092 25.417526)
			(size 0.4318 0.4318)
			(layers "F.Cu" "F.Mask" "F.Paste")
			(net "M_E_DQ<48>")
		)
		(pad "EC30" smd circle
			(at -12.354052 25.417526)
			(size 0.4318 0.4318)
			(layers "F.Cu" "F.Mask" "F.Paste")
			(net "M_E_DQ<43>")
		)
		(pad "EC32" smd circle
			(at -10.637012 25.417526)
			(size 0.4318 0.4318)
			(layers "F.Cu" "F.Mask" "F.Paste")
			(net "M_E_DQS_DP<5>")
		)
		(pad "EC34" smd circle
			(at -8.919972 25.417526)
			(size 0.4318 0.4318)
			(layers "F.Cu" "F.Mask" "F.Paste")
			(net "M_E_DQ<40>")
		)
		(pad "EC36" smd circle
			(at -7.202932 25.417526)
			(size 0.4318 0.4318)
			(layers "F.Cu" "F.Mask" "F.Paste")
			(net "M_D_DQ<35>")
		)
		(pad "EC38" smd circle
			(at -5.485892 25.417526)
			(size 0.4318 0.4318)
			(layers "F.Cu" "F.Mask" "F.Paste")
			(net "M_D_DQS_DP<4>")
		)
		(pad "EC40" smd circle
			(at -3.769106 25.417526)
			(size 0.4318 0.4318)
			(layers "F.Cu" "F.Mask" "F.Paste")
			(net "M_D_DQ<32>")
		)
		(pad "EC42" smd custom
			(at -2.052066 25.417526 225)
			(size 0.10795 0.10795)
			(layers "F.Cu" "F.Mask" "F.Paste")
			(net "GND")
			(options
				(clearance outline)
				(anchor circle)
			)
			(primitives
				(gr_poly
					(pts
						(arc
							(start 0.2159 -0.0381)
							(mid 0 -0.254)
							(end -0.2159 -0.0381)
						)
						(arc
							(start -0.2159 0.0381)
							(mid 0 0.254)
							(end 0.2159 0.0381)
						)
					)
					(width 0)
					(fill yes)
				)
			)
		)
		(pad "EC44" smd circle
			(at 1.193546 23.617174)
			(size 0.508 0.508)
			(layers "F.Cu" "F.Mask" "F.Paste")
			(net "TP_CPU0_RSVD_13")
		)
		(pad "EC46" smd circle
			(at 2.910586 23.617174)
			(size 0.4318 0.4318)
			(layers "F.Cu" "F.Mask" "F.Paste")
			(net "PVDDQ_DEF")
		)
		(pad "EC48" smd circle
			(at 4.627626 23.617174)
			(size 0.4318 0.4318)
			(layers "F.Cu" "F.Mask" "F.Paste")
			(net "PVDDQ_DEF")
		)
		(pad "EC50" smd circle
			(at 6.344412 23.617174)
			(size 0.4318 0.4318)
			(layers "F.Cu" "F.Mask" "F.Paste")
			(net "PVDDQ_DEF")
		)
		(pad "EC52" smd circle
			(at 8.061452 23.617174)
			(size 0.4318 0.4318)
			(layers "F.Cu" "F.Mask" "F.Paste")
			(net "PVDDQ_DEF")
		)
		(pad "EC54" smd circle
			(at 9.778492 23.617174)
			(size 0.4318 0.4318)
			(layers "F.Cu" "F.Mask" "F.Paste")
			(net "PVDDQ_DEF")
		)
		(pad "EC56" smd circle
			(at 11.495532 23.617174)
			(size 0.4318 0.4318)
			(layers "F.Cu" "F.Mask" "F.Paste")
			(net "PVDDQ_DEF")
		)
		(pad "EC58" smd circle
			(at 13.212572 23.617174)
			(size 0.4318 0.4318)
			(layers "F.Cu" "F.Mask" "F.Paste")
			(net "PVDDQ_DEF")
		)
		(pad "EC60" smd circle
			(at 14.929612 23.617174)
			(size 0.4318 0.4318)
			(layers "F.Cu" "F.Mask" "F.Paste")
			(net "PVDDQ_DEF")
		)
		(pad "EC62" smd circle
			(at 16.646398 23.617174)
			(size 0.4318 0.4318)
			(layers "F.Cu" "F.Mask" "F.Paste")
			(net "PVDDQ_DEF")
		)
		(pad "EC70" smd circle
			(at 23.514558 23.617174)
			(size 0.4318 0.4318)
			(layers "F.Cu" "F.Mask" "F.Paste")
			(net "GND")
		)
		(pad "EC72" smd circle
			(at 25.231598 23.617174)
			(size 0.4318 0.4318)
			(layers "F.Cu" "F.Mask" "F.Paste")
			(net "GND")
		)
		(pad "EC74" smd circle
			(at 26.948384 23.617174)
			(size 0.4318 0.4318)
			(layers "F.Cu" "F.Mask" "F.Paste")
			(net "GND")
		)
		(pad "EC76" smd circle
			(at 28.665424 23.617174)
			(size 0.4318 0.4318)
			(layers "F.Cu" "F.Mask" "F.Paste")
			(net "GND")
		)
		(pad "EC78" smd circle
			(at 30.382464 23.617174)
			(size 0.4318 0.4318)
			(layers "F.Cu" "F.Mask" "F.Paste")
			(net "M_E_DQ<23>")
		)
		(pad "EC80" smd circle
			(at 32.099504 23.617174)
			(size 0.4318 0.4318)
			(layers "F.Cu" "F.Mask" "F.Paste")
			(net "M_E_DQ<17>")
		)
		(pad "EC82" smd custom
			(at 33.816544 23.617174 225)
			(size 0.10795 0.10795)
			(layers "F.Cu" "F.Mask" "F.Paste")
			(net "GND")
			(options
				(clearance outline)
				(anchor circle)
			)
			(primitives
				(gr_poly
					(pts
						(arc
							(start 0.2159 -0.0381)
							(mid 0 -0.254)
							(end -0.2159 -0.0381)
						)
						(arc
							(start -0.2159 0.0381)
							(mid 0 0.254)
							(end 0.2159 0.0381)
						)
					)
					(width 0)
					(fill yes)
				)
			)
		)
		(pad "EC84" smd custom
			(at 35.533584 23.617174 270)
			(size 0.10795 0.10795)
			(layers "F.Cu" "F.Mask" "F.Paste")
			(net "TP_CPU0_RSVD_12")
			(options
				(clearance outline)
				(anchor circle)
			)
			(primitives
				(gr_poly
					(pts
						(arc
							(start 0.2159 -0.0381)
							(mid 0 -0.254)
							(end -0.2159 -0.0381)
						)
						(arc
							(start -0.2159 0.0381)
							(mid 0 0.254)
							(end 0.2159 0.0381)
						)
					)
					(width 0)
					(fill yes)
				)
			)
		)
		(pad "ED5" smd custom
			(at -33.816544 25.912572 135)
			(size 0.10795 0.10795)
			(layers "F.Cu" "F.Mask" "F.Paste")
			(net "TP_CPU0_RSVD_10")
			(options
				(clearance outline)
				(anchor circle)
			)
			(primitives
				(gr_poly
					(pts
						(arc
							(start 0.2159 -0.0381)
							(mid 0 -0.254)
							(end -0.2159 -0.0381)
						)
						(arc
							(start -0.2159 0.0381)
							(mid 0 0.254)
							(end 0.2159 0.0381)
						)
					)
					(width 0)
					(fill yes)
				)
			)
		)
		(pad "ED7" smd custom
			(at -32.099504 25.912572 135)
			(size 0.10795 0.10795)
			(layers "F.Cu" "F.Mask" "F.Paste")
			(net "GND")
			(options
				(clearance outline)
				(anchor circle)
			)
			(primitives
				(gr_poly
					(pts
						(arc
							(start 0.2159 -0.0381)
							(mid 0 -0.254)
							(end -0.2159 -0.0381)
						)
						(arc
							(start -0.2159 0.0381)
							(mid 0 0.254)
							(end 0.2159 0.0381)
						)
					)
					(width 0)
					(fill yes)
				)
			)
		)
		(pad "ED9" smd circle
			(at -30.382464 25.912572)
			(size 0.4318 0.4318)
			(layers "F.Cu" "F.Mask" "F.Paste")
			(net "P3E_CPU0_PE1_PCH_TXN<15>")
		)
		(pad "ED11" smd circle
			(at -28.665424 25.912572)
			(size 0.4318 0.4318)
			(layers "F.Cu" "F.Mask" "F.Paste")
			(net "GND")
		)
		(pad "ED13" smd circle
			(at -26.948384 25.912572)
			(size 0.4318 0.4318)
			(layers "F.Cu" "F.Mask" "F.Paste")
			(net "P3E_CPU0_PE3_OCP_TXP<1>")
		)
		(pad "ED15" smd circle
			(at -25.231598 25.912572)
			(size 0.4318 0.4318)
			(layers "F.Cu" "F.Mask" "F.Paste")
			(net "GND")
		)
		(pad "ED23" smd custom
			(at -18.363438 25.912572 120)
			(size 0.10795 0.10795)
			(layers "F.Cu" "F.Mask" "F.Paste")
			(net "GND")
			(options
				(clearance outline)
				(anchor circle)
			)
			(primitives
				(gr_poly
					(pts
						(arc
							(start 0.2159 -0.0381)
							(mid 0 -0.254)
							(end -0.2159 -0.0381)
						)
						(arc
							(start -0.2159 0.0381)
							(mid 0 0.254)
							(end 0.2159 0.0381)
						)
					)
					(width 0)
					(fill yes)
				)
			)
		)
		(pad "ED25" smd circle
			(at -16.646398 25.912572)
			(size 0.4318 0.4318)
			(layers "F.Cu" "F.Mask" "F.Paste")
			(net "M_E_DQ<55>")
		)
		(pad "ED27" smd circle
			(at -14.929612 25.912572)
			(size 0.4318 0.4318)
			(layers "F.Cu" "F.Mask" "F.Paste")
			(net "M_E_DQ<49>")
		)
		(pad "ED29" smd circle
			(at -13.212572 25.912572)
			(size 0.4318 0.4318)
			(layers "F.Cu" "F.Mask" "F.Paste")
			(net "GND")
		)
		(pad "ED31" smd circle
			(at -11.495532 25.912572)
			(size 0.4318 0.4318)
			(layers "F.Cu" "F.Mask" "F.Paste")
			(net "M_E_DQ<47>")
		)
		(pad "ED33" smd circle
			(at -9.778492 25.912572)
			(size 0.4318 0.4318)
			(layers "F.Cu" "F.Mask" "F.Paste")
			(net "M_E_DQ<41>")
		)
		(pad "ED35" smd circle
			(at -8.061452 25.912572)
			(size 0.4318 0.4318)
			(layers "F.Cu" "F.Mask" "F.Paste")
			(net "GND")
		)
		(pad "ED37" smd circle
			(at -6.344412 25.912572)
			(size 0.4318 0.4318)
			(layers "F.Cu" "F.Mask" "F.Paste")
			(net "M_D_DQ<39>")
		)
		(pad "ED39" smd circle
			(at -4.627626 25.912572)
			(size 0.4318 0.4318)
			(layers "F.Cu" "F.Mask" "F.Paste")
			(net "M_D_DQ<33>")
		)
		(pad "ED41" smd custom
			(at -2.910586 25.912572 225)
			(size 0.10795 0.10795)
			(layers "F.Cu" "F.Mask" "F.Paste")
			(net "GND")
			(options
				(clearance outline)
				(anchor circle)
			)
			(primitives
				(gr_poly
					(pts
						(arc
							(start 0.2159 -0.0381)
							(mid 0 -0.254)
							(end -0.2159 -0.0381)
						)
						(arc
							(start -0.2159 0.0381)
							(mid 0 0.254)
							(end 0.2159 0.0381)
						)
					)
					(width 0)
					(fill yes)
				)
			)
		)
		(pad "ED45" smd circle
			(at 2.052066 24.112474)
			(size 0.4318 0.4318)
			(layers "F.Cu" "F.Mask" "F.Paste")
			(net "TP_CPU0_RSVD_11")
		)
		(pad "ED47" smd circle
			(at 3.769106 24.112474)
			(size 0.4318 0.4318)
			(layers "F.Cu" "F.Mask" "F.Paste")
			(net "M_D_CS_N<2>")
		)
		(pad "ED49" smd circle
			(at 5.485892 24.112474)
			(size 0.4318 0.4318)
			(layers "F.Cu" "F.Mask" "F.Paste")
			(net "M_D_CS_N<1>")
		)
		(pad "ED51" smd circle
			(at 7.202932 24.112474)
			(size 0.4318 0.4318)
			(layers "F.Cu" "F.Mask" "F.Paste")
			(net "M_D_MA<14>")
		)
		(pad "ED53" smd circle
			(at 8.919972 24.112474)
			(size 0.4318 0.4318)
			(layers "F.Cu" "F.Mask" "F.Paste")
			(net "M_D_PAR")
		)
		(pad "ED55" smd circle
			(at 10.637012 24.112474)
			(size 0.4318 0.4318)
			(layers "F.Cu" "F.Mask" "F.Paste")
			(net "M_D_CLK_DN<0>")
		)
		(pad "ED57" smd circle
			(at 12.354052 24.112474)
			(size 0.4318 0.4318)
			(layers "F.Cu" "F.Mask" "F.Paste")
			(net "M_D_MA<1>")
		)
		(pad "ED59" smd circle
			(at 14.071092 24.112474)
			(size 0.4318 0.4318)
			(layers "F.Cu" "F.Mask" "F.Paste")
			(net "M_D_MA<4>")
		)
		(pad "ED61" smd circle
			(at 15.787878 24.112474)
			(size 0.4318 0.4318)
			(layers "F.Cu" "F.Mask" "F.Paste")
			(net "M_D_BG<0>")
		)
		(pad "ED63" smd custom
			(at 17.504918 24.112474 180)
			(size 0.10795 0.10795)
			(layers "F.Cu" "F.Mask" "F.Paste")
			(net "M_D_ALERT_N")
			(options
				(clearance outline)
				(anchor circle)
			)
			(primitives
				(gr_poly
					(pts
						(arc
							(start 0.2159 -0.0381)
							(mid 0 -0.254)
							(end -0.2159 -0.0381)
						)
						(arc
							(start -0.2159 0.0381)
							(mid 0 0.254)
							(end 0.2159 0.0381)
						)
					)
					(width 0)
					(fill yes)
				)
			)
		)
		(pad "ED69" smd custom
			(at 22.656038 24.112474 180)
			(size 0.10795 0.10795)
			(layers "F.Cu" "F.Mask" "F.Paste")
			(net "GND")
			(options
				(clearance outline)
				(anchor circle)
			)
			(primitives
				(gr_poly
					(pts
						(arc
							(start 0.2159 -0.0381)
							(mid 0 -0.254)
							(end -0.2159 -0.0381)
						)
						(arc
							(start -0.2159 0.0381)
							(mid 0 0.254)
							(end 0.2159 0.0381)
						)
					)
					(width 0)
					(fill yes)
				)
			)
		)
		(pad "ED71" smd circle
			(at 24.373078 24.112474)
			(size 0.4318 0.4318)
			(layers "F.Cu" "F.Mask" "F.Paste")
			(net "M_E_DQ<27>")
		)
		(pad "ED73" smd circle
			(at 26.090118 24.112474)
			(size 0.4318 0.4318)
			(layers "F.Cu" "F.Mask" "F.Paste")
			(net "M_E_DQS_DP<3>")
		)
		(pad "ED75" smd circle
			(at 27.806904 24.112474)
			(size 0.4318 0.4318)
			(layers "F.Cu" "F.Mask" "F.Paste")
			(net "M_E_DQ<24>")
		)
		(pad "ED77" smd circle
			(at 29.523944 24.112474)
			(size 0.4318 0.4318)
			(layers "F.Cu" "F.Mask" "F.Paste")
			(net "GND")
		)
		(pad "ED79" smd circle
			(at 31.240984 24.112474)
			(size 0.4318 0.4318)
			(layers "F.Cu" "F.Mask" "F.Paste")
			(net "M_E_DQS_DN<2>")
		)
		(pad "ED81" smd custom
			(at 32.958024 24.112474 225)
			(size 0.10795 0.10795)
			(layers "F.Cu" "F.Mask" "F.Paste")
			(net "GND")
			(options
				(clearance outline)
				(anchor circle)
			)
			(primitives
				(gr_poly
					(pts
						(arc
							(start 0.2159 -0.0381)
							(mid 0 -0.254)
							(end -0.2159 -0.0381)
						)
						(arc
							(start -0.2159 0.0381)
							(mid 0 0.254)
							(end 0.2159 0.0381)
						)
					)
					(width 0)
					(fill yes)
				)
			)
		)
		(pad "ED83" smd custom
			(at 34.675064 24.112474 270)
			(size 0.10795 0.10795)
			(layers "F.Cu" "F.Mask" "F.Paste")
			(net "TP_CPU0_RSVD_9")
			(options
				(clearance outline)
				(anchor circle)
			)
			(primitives
				(gr_poly
					(pts
						(arc
							(start 0.2159 -0.0381)
							(mid 0 -0.254)
							(end -0.2159 -0.0381)
						)
						(arc
							(start -0.2159 0.0381)
							(mid 0 0.254)
							(end 0.2159 0.0381)
						)
					)
					(width 0)
					(fill yes)
				)
			)
		)
		(pad "EE6" smd custom
			(at -32.958024 26.408126 135)
			(size 0.10795 0.10795)
			(layers "F.Cu" "F.Mask" "F.Paste")
			(net "TP_CPU0_RSVD_6")
			(options
				(clearance outline)
				(anchor circle)
			)
			(primitives
				(gr_poly
					(pts
						(arc
							(start 0.2159 -0.0381)
							(mid 0 -0.254)
							(end -0.2159 -0.0381)
						)
						(arc
							(start -0.2159 0.0381)
							(mid 0 0.254)
							(end 0.2159 0.0381)
						)
					)
					(width 0)
					(fill yes)
				)
			)
		)
		(pad "EE8" smd custom
			(at -31.240984 26.408126 135)
			(size 0.10795 0.10795)
			(layers "F.Cu" "F.Mask" "F.Paste")
			(net "GND")
			(options
				(clearance outline)
				(anchor circle)
			)
			(primitives
				(gr_poly
					(pts
						(arc
							(start 0.2159 -0.0381)
							(mid 0 -0.254)
							(end -0.2159 -0.0381)
						)
						(arc
							(start -0.2159 0.0381)
							(mid 0 0.254)
							(end 0.2159 0.0381)
						)
					)
					(width 0)
					(fill yes)
				)
			)
		)
		(pad "EE10" smd custom
			(at -29.523944 26.408126 180)
			(size 0.10795 0.10795)
			(layers "F.Cu" "F.Mask" "F.Paste")
			(net "PVCCIO_CPU0")
			(options
				(clearance outline)
				(anchor circle)
			)
			(primitives
				(gr_poly
					(pts
						(arc
							(start 0.2159 -0.0381)
							(mid 0 -0.254)
							(end -0.2159 -0.0381)
						)
						(arc
							(start -0.2159 0.0381)
							(mid 0 0.254)
							(end 0.2159 0.0381)
						)
					)
					(width 0)
					(fill yes)
				)
			)
		)
		(pad "EE12" smd custom
			(at -27.806904 26.408126 180)
			(size 0.10795 0.10795)
			(layers "F.Cu" "F.Mask" "F.Paste")
			(net "P3E_CPU0_PE3_OCP_TXN<1>")
			(options
				(clearance outline)
				(anchor circle)
			)
			(primitives
				(gr_poly
					(pts
						(arc
							(start 0.2159 -0.0381)
							(mid 0 -0.254)
							(end -0.2159 -0.0381)
						)
						(arc
							(start -0.2159 0.0381)
							(mid 0 0.254)
							(end 0.2159 0.0381)
						)
					)
					(width 0)
					(fill yes)
				)
			)
		)
		(pad "EE14" smd custom
			(at -26.090118 26.408126 180)
			(size 0.10795 0.10795)
			(layers "F.Cu" "F.Mask" "F.Paste")
			(net "P3E_CPU0_PE3_OCP_TXN<0>")
			(options
				(clearance outline)
				(anchor circle)
			)
			(primitives
				(gr_poly
					(pts
						(arc
							(start 0.2159 -0.0381)
							(mid 0 -0.254)
							(end -0.2159 -0.0381)
						)
						(arc
							(start -0.2159 0.0381)
							(mid 0 0.254)
							(end 0.2159 0.0381)
						)
					)
					(width 0)
					(fill yes)
				)
			)
		)
		(pad "EE16" smd custom
			(at -24.373078 26.408126 180)
			(size 0.10795 0.10795)
			(layers "F.Cu" "F.Mask" "F.Paste")
			(net "TP_CPU0_RSVD_8")
			(options
				(clearance outline)
				(anchor circle)
			)
			(primitives
				(gr_poly
					(pts
						(arc
							(start 0.2159 -0.0381)
							(mid 0 -0.254)
							(end -0.2159 -0.0381)
						)
						(arc
							(start -0.2159 0.0381)
							(mid 0 0.254)
							(end 0.2159 0.0381)
						)
					)
					(width 0)
					(fill yes)
				)
			)
		)
		(pad "EE24" smd custom
			(at -17.504918 26.408126 120)
			(size 0.10795 0.10795)
			(layers "F.Cu" "F.Mask" "F.Paste")
			(net "GND")
			(options
				(clearance outline)
				(anchor circle)
			)
			(primitives
				(gr_poly
					(pts
						(arc
							(start 0.2159 -0.0381)
							(mid 0 -0.254)
							(end -0.2159 -0.0381)
						)
						(arc
							(start -0.2159 0.0381)
							(mid 0 0.254)
							(end 0.2159 0.0381)
						)
					)
					(width 0)
					(fill yes)
				)
			)
		)
		(pad "EE26" smd custom
			(at -15.787878 26.408126 180)
			(size 0.10795 0.10795)
			(layers "F.Cu" "F.Mask" "F.Paste")
			(net "M_E_DQS_DN<6>")
			(options
				(clearance outline)
				(anchor circle)
			)
			(primitives
				(gr_poly
					(pts
						(arc
							(start 0.2159 -0.0381)
							(mid 0 -0.254)
							(end -0.2159 -0.0381)
						)
						(arc
							(start -0.2159 0.0381)
							(mid 0 0.254)
							(end 0.2159 0.0381)
						)
					)
					(width 0)
					(fill yes)
				)
			)
		)
		(pad "EE28" smd custom
			(at -14.071092 26.408126 180)
			(size 0.10795 0.10795)
			(layers "F.Cu" "F.Mask" "F.Paste")
			(net "GND")
			(options
				(clearance outline)
				(anchor circle)
			)
			(primitives
				(gr_poly
					(pts
						(arc
							(start 0.2159 -0.0381)
							(mid 0 -0.254)
							(end -0.2159 -0.0381)
						)
						(arc
							(start -0.2159 0.0381)
							(mid 0 0.254)
							(end 0.2159 0.0381)
						)
					)
					(width 0)
					(fill yes)
				)
			)
		)
		(pad "EE30" smd custom
			(at -12.354052 26.408126 180)
			(size 0.10795 0.10795)
			(layers "F.Cu" "F.Mask" "F.Paste")
			(net "GND")
			(options
				(clearance outline)
				(anchor circle)
			)
			(primitives
				(gr_poly
					(pts
						(arc
							(start 0.2159 -0.0381)
							(mid 0 -0.254)
							(end -0.2159 -0.0381)
						)
						(arc
							(start -0.2159 0.0381)
							(mid 0 0.254)
							(end 0.2159 0.0381)
						)
					)
					(width 0)
					(fill yes)
				)
			)
		)
		(pad "EE32" smd custom
			(at -10.637012 26.408126 180)
			(size 0.10795 0.10795)
			(layers "F.Cu" "F.Mask" "F.Paste")
			(net "M_E_DQS_DN<5>")
			(options
				(clearance outline)
				(anchor circle)
			)
			(primitives
				(gr_poly
					(pts
						(arc
							(start 0.2159 -0.0381)
							(mid 0 -0.254)
							(end -0.2159 -0.0381)
						)
						(arc
							(start -0.2159 0.0381)
							(mid 0 0.254)
							(end 0.2159 0.0381)
						)
					)
					(width 0)
					(fill yes)
				)
			)
		)
		(pad "EE34" smd custom
			(at -8.919972 26.408126 180)
			(size 0.10795 0.10795)
			(layers "F.Cu" "F.Mask" "F.Paste")
			(net "GND")
			(options
				(clearance outline)
				(anchor circle)
			)
			(primitives
				(gr_poly
					(pts
						(arc
							(start 0.2159 -0.0381)
							(mid 0 -0.254)
							(end -0.2159 -0.0381)
						)
						(arc
							(start -0.2159 0.0381)
							(mid 0 0.254)
							(end 0.2159 0.0381)
						)
					)
					(width 0)
					(fill yes)
				)
			)
		)
		(pad "EE36" smd custom
			(at -7.202932 26.408126 180)
			(size 0.10795 0.10795)
			(layers "F.Cu" "F.Mask" "F.Paste")
			(net "GND")
			(options
				(clearance outline)
				(anchor circle)
			)
			(primitives
				(gr_poly
					(pts
						(arc
							(start 0.2159 -0.0381)
							(mid 0 -0.254)
							(end -0.2159 -0.0381)
						)
						(arc
							(start -0.2159 0.0381)
							(mid 0 0.254)
							(end 0.2159 0.0381)
						)
					)
					(width 0)
					(fill yes)
				)
			)
		)
		(pad "EE38" smd custom
			(at -5.485892 26.408126 180)
			(size 0.10795 0.10795)
			(layers "F.Cu" "F.Mask" "F.Paste")
			(net "M_D_DQS_DN<4>")
			(options
				(clearance outline)
				(anchor circle)
			)
			(primitives
				(gr_poly
					(pts
						(arc
							(start 0.2159 -0.0381)
							(mid 0 -0.254)
							(end -0.2159 -0.0381)
						)
						(arc
							(start -0.2159 0.0381)
							(mid 0 0.254)
							(end 0.2159 0.0381)
						)
					)
					(width 0)
					(fill yes)
				)
			)
		)
		(pad "EE40" smd custom
			(at -3.769106 26.408126 225)
			(size 0.10795 0.10795)
			(layers "F.Cu" "F.Mask" "F.Paste")
			(net "GND")
			(options
				(clearance outline)
				(anchor circle)
			)
			(primitives
				(gr_poly
					(pts
						(arc
							(start 0.2159 -0.0381)
							(mid 0 -0.254)
							(end -0.2159 -0.0381)
						)
						(arc
							(start -0.2159 0.0381)
							(mid 0 0.254)
							(end 0.2159 0.0381)
						)
					)
					(width 0)
					(fill yes)
				)
			)
		)
		(pad "EE44" smd custom
			(at 1.193546 24.608028 135)
			(size 0.10795 0.10795)
			(layers "F.Cu" "F.Mask" "F.Paste")
			(net "PVDDQ_DEF")
			(options
				(clearance outline)
				(anchor circle)
			)
			(primitives
				(gr_poly
					(pts
						(arc
							(start 0.2159 -0.0381)
							(mid 0 -0.254)
							(end -0.2159 -0.0381)
						)
						(arc
							(start -0.2159 0.0381)
							(mid 0 0.254)
							(end 0.2159 0.0381)
						)
					)
					(width 0)
					(fill yes)
				)
			)
		)
		(pad "EE46" smd circle
			(at 2.910586 24.608028)
			(size 0.4318 0.4318)
			(layers "F.Cu" "F.Mask" "F.Paste")
			(net "TP_CPU0_RSVD_7")
		)
		(pad "EE48" smd circle
			(at 4.627626 24.608028)
			(size 0.4318 0.4318)
			(layers "F.Cu" "F.Mask" "F.Paste")
			(net "M_D_ODT<1>")
		)
		(pad "EE50" smd circle
			(at 6.344412 24.608028)
			(size 0.4318 0.4318)
			(layers "F.Cu" "F.Mask" "F.Paste")
			(net "M_D_ODT<0>")
		)
		(pad "EE52" smd circle
			(at 8.061452 24.608028)
			(size 0.4318 0.4318)
			(layers "F.Cu" "F.Mask" "F.Paste")
			(net "M_D_BA<0>")
		)
		(pad "EE54" smd circle
			(at 9.778492 24.608028)
			(size 0.4318 0.4318)
			(layers "F.Cu" "F.Mask" "F.Paste")
			(net "M_D_CLK_DP<1>")
		)
		(pad "EE56" smd circle
			(at 11.495532 24.608028)
			(size 0.4318 0.4318)
			(layers "F.Cu" "F.Mask" "F.Paste")
			(net "M_D_CLK_DP<3>")
		)
		(pad "EE58" smd circle
			(at 13.212572 24.608028)
			(size 0.4318 0.4318)
			(layers "F.Cu" "F.Mask" "F.Paste")
			(net "M_D_MA<2>")
		)
		(pad "EE60" smd circle
			(at 14.929612 24.608028)
			(size 0.4318 0.4318)
			(layers "F.Cu" "F.Mask" "F.Paste")
			(net "M_D_MA<6>")
		)
		(pad "EE62" smd circle
			(at 16.646398 24.608028)
			(size 0.4318 0.4318)
			(layers "F.Cu" "F.Mask" "F.Paste")
			(net "M_D_CKE<0>")
		)
		(pad "EE70" smd custom
			(at 23.514558 24.608028 180)
			(size 0.10795 0.10795)
			(layers "F.Cu" "F.Mask" "F.Paste")
			(net "GND")
			(options
				(clearance outline)
				(anchor circle)
			)
			(primitives
				(gr_poly
					(pts
						(arc
							(start 0.2159 -0.0381)
							(mid 0 -0.254)
							(end -0.2159 -0.0381)
						)
						(arc
							(start -0.2159 0.0381)
							(mid 0 0.254)
							(end 0.2159 0.0381)
						)
					)
					(width 0)
					(fill yes)
				)
			)
		)
		(pad "EE72" smd circle
			(at 25.231598 24.608028)
			(size 0.4318 0.4318)
			(layers "F.Cu" "F.Mask" "F.Paste")
			(net "M_E_DQ<31>")
		)
		(pad "EE74" smd circle
			(at 26.948384 24.608028)
			(size 0.4318 0.4318)
			(layers "F.Cu" "F.Mask" "F.Paste")
			(net "M_E_DQ<25>")
		)
		(pad "EE76" smd circle
			(at 28.665424 24.608028)
			(size 0.4318 0.4318)
			(layers "F.Cu" "F.Mask" "F.Paste")
			(net "GND")
		)
		(pad "EE78" smd circle
			(at 30.382464 24.608028)
			(size 0.4318 0.4318)
			(layers "F.Cu" "F.Mask" "F.Paste")
			(net "GND")
		)
		(pad "EE80" smd custom
			(at 32.099504 24.608028 225)
			(size 0.10795 0.10795)
			(layers "F.Cu" "F.Mask" "F.Paste")
			(net "GND")
			(options
				(clearance outline)
				(anchor circle)
			)
			(primitives
				(gr_poly
					(pts
						(arc
							(start 0.2159 -0.0381)
							(mid 0 -0.254)
							(end -0.2159 -0.0381)
						)
						(arc
							(start -0.2159 0.0381)
							(mid 0 0.254)
							(end 0.2159 0.0381)
						)
					)
					(width 0)
					(fill yes)
				)
			)
		)
		(pad "EE82" smd custom
			(at 33.816544 24.608028 270)
			(size 0.10795 0.10795)
			(layers "F.Cu" "F.Mask" "F.Paste")
			(net "TP_CPU0_RSVD_5")
			(options
				(clearance outline)
				(anchor circle)
			)
			(primitives
				(gr_poly
					(pts
						(arc
							(start 0.2159 -0.0381)
							(mid 0 -0.254)
							(end -0.2159 -0.0381)
						)
						(arc
							(start -0.2159 0.0381)
							(mid 0 0.254)
							(end 0.2159 0.0381)
						)
					)
					(width 0)
					(fill yes)
				)
			)
		)
		(pad "EE84" smd custom
			(at 35.533584 24.608028 270)
			(size 0.10795 0.10795)
			(layers "F.Cu" "F.Mask" "F.Paste")
			(net "TP_CPU0_RSVD_4")
			(options
				(clearance outline)
				(anchor circle)
			)
			(primitives
				(gr_poly
					(pts
						(arc
							(start 0.2159 -0.0381)
							(mid 0 -0.254)
							(end -0.2159 -0.0381)
						)
						(arc
							(start -0.2159 0.0381)
							(mid 0 0.254)
							(end 0.2159 0.0381)
						)
					)
					(width 0)
					(fill yes)
				)
			)
		)
		(pad "EF45" smd custom
			(at 2.052066 25.103074 135)
			(size 0.10795 0.10795)
			(layers "F.Cu" "F.Mask" "F.Paste")
			(net "PVDDQ_DEF")
			(options
				(clearance outline)
				(anchor circle)
			)
			(primitives
				(gr_poly
					(pts
						(arc
							(start 0.2159 -0.0381)
							(mid 0 -0.254)
							(end -0.2159 -0.0381)
						)
						(arc
							(start -0.2159 0.0381)
							(mid 0 0.254)
							(end 0.2159 0.0381)
						)
					)
					(width 0)
					(fill yes)
				)
			)
		)
		(pad "EF47" smd custom
			(at 3.769106 25.103074 180)
			(size 0.10795 0.10795)
			(layers "F.Cu" "F.Mask" "F.Paste")
			(net "TP_CPU0_RSVD_3")
			(options
				(clearance outline)
				(anchor circle)
			)
			(primitives
				(gr_poly
					(pts
						(arc
							(start 0.2159 -0.0381)
							(mid 0 -0.254)
							(end -0.2159 -0.0381)
						)
						(arc
							(start -0.2159 0.0381)
							(mid 0 0.254)
							(end 0.2159 0.0381)
						)
					)
					(width 0)
					(fill yes)
				)
			)
		)
		(pad "EF49" smd custom
			(at 5.485892 25.103074 180)
			(size 0.10795 0.10795)
			(layers "F.Cu" "F.Mask" "F.Paste")
			(net "PVDDQ_DEF")
			(options
				(clearance outline)
				(anchor circle)
			)
			(primitives
				(gr_poly
					(pts
						(arc
							(start 0.2159 -0.0381)
							(mid 0 -0.254)
							(end -0.2159 -0.0381)
						)
						(arc
							(start -0.2159 0.0381)
							(mid 0 0.254)
							(end 0.2159 0.0381)
						)
					)
					(width 0)
					(fill yes)
				)
			)
		)
		(pad "EF51" smd custom
			(at 7.202932 25.103074 180)
			(size 0.10795 0.10795)
			(layers "F.Cu" "F.Mask" "F.Paste")
			(net "M_D_CS_N<0>")
			(options
				(clearance outline)
				(anchor circle)
			)
			(primitives
				(gr_poly
					(pts
						(arc
							(start 0.2159 -0.0381)
							(mid 0 -0.254)
							(end -0.2159 -0.0381)
						)
						(arc
							(start -0.2159 0.0381)
							(mid 0 0.254)
							(end 0.2159 0.0381)
						)
					)
					(width 0)
					(fill yes)
				)
			)
		)
		(pad "EF53" smd custom
			(at 8.919972 25.103074 180)
			(size 0.10795 0.10795)
			(layers "F.Cu" "F.Mask" "F.Paste")
			(net "PVDDQ_DEF")
			(options
				(clearance outline)
				(anchor circle)
			)
			(primitives
				(gr_poly
					(pts
						(arc
							(start 0.2159 -0.0381)
							(mid 0 -0.254)
							(end -0.2159 -0.0381)
						)
						(arc
							(start -0.2159 0.0381)
							(mid 0 0.254)
							(end 0.2159 0.0381)
						)
					)
					(width 0)
					(fill yes)
				)
			)
		)
		(pad "EF55" smd custom
			(at 10.637012 25.103074 180)
			(size 0.10795 0.10795)
			(layers "F.Cu" "F.Mask" "F.Paste")
			(net "M_D_CLK_DN<1>")
			(options
				(clearance outline)
				(anchor circle)
			)
			(primitives
				(gr_poly
					(pts
						(arc
							(start 0.2159 -0.0381)
							(mid 0 -0.254)
							(end -0.2159 -0.0381)
						)
						(arc
							(start -0.2159 0.0381)
							(mid 0 0.254)
							(end 0.2159 0.0381)
						)
					)
					(width 0)
					(fill yes)
				)
			)
		)
		(pad "EF57" smd custom
			(at 12.354052 25.103074 180)
			(size 0.10795 0.10795)
			(layers "F.Cu" "F.Mask" "F.Paste")
			(net "M_D_CLK_DN<3>")
			(options
				(clearance outline)
				(anchor circle)
			)
			(primitives
				(gr_poly
					(pts
						(arc
							(start 0.2159 -0.0381)
							(mid 0 -0.254)
							(end -0.2159 -0.0381)
						)
						(arc
							(start -0.2159 0.0381)
							(mid 0 0.254)
							(end 0.2159 0.0381)
						)
					)
					(width 0)
					(fill yes)
				)
			)
		)
		(pad "EF59" smd custom
			(at 14.071092 25.103074 180)
			(size 0.10795 0.10795)
			(layers "F.Cu" "F.Mask" "F.Paste")
			(net "PVDDQ_DEF")
			(options
				(clearance outline)
				(anchor circle)
			)
			(primitives
				(gr_poly
					(pts
						(arc
							(start 0.2159 -0.0381)
							(mid 0 -0.254)
							(end -0.2159 -0.0381)
						)
						(arc
							(start -0.2159 0.0381)
							(mid 0 0.254)
							(end 0.2159 0.0381)
						)
					)
					(width 0)
					(fill yes)
				)
			)
		)
		(pad "EF61" smd custom
			(at 15.787878 25.103074 180)
			(size 0.10795 0.10795)
			(layers "F.Cu" "F.Mask" "F.Paste")
			(net "M_D_MA<9>")
			(options
				(clearance outline)
				(anchor circle)
			)
			(primitives
				(gr_poly
					(pts
						(arc
							(start 0.2159 -0.0381)
							(mid 0 -0.254)
							(end -0.2159 -0.0381)
						)
						(arc
							(start -0.2159 0.0381)
							(mid 0 0.254)
							(end 0.2159 0.0381)
						)
					)
					(width 0)
					(fill yes)
				)
			)
		)
		(pad "EF63" smd custom
			(at 17.504918 25.103074 180)
			(size 0.10795 0.10795)
			(layers "F.Cu" "F.Mask" "F.Paste")
			(net "M_D_CKE<1>")
			(options
				(clearance outline)
				(anchor circle)
			)
			(primitives
				(gr_poly
					(pts
						(arc
							(start 0.2159 -0.0381)
							(mid 0 -0.254)
							(end -0.2159 -0.0381)
						)
						(arc
							(start -0.2159 0.0381)
							(mid 0 0.254)
							(end 0.2159 0.0381)
						)
					)
					(width 0)
					(fill yes)
				)
			)
		)
		(pad "EF71" smd custom
			(at 24.373078 25.103074 180)
			(size 0.10795 0.10795)
			(layers "F.Cu" "F.Mask" "F.Paste")
			(net "GND")
			(options
				(clearance outline)
				(anchor circle)
			)
			(primitives
				(gr_poly
					(pts
						(arc
							(start 0.2159 -0.0381)
							(mid 0 -0.254)
							(end -0.2159 -0.0381)
						)
						(arc
							(start -0.2159 0.0381)
							(mid 0 0.254)
							(end 0.2159 0.0381)
						)
					)
					(width 0)
					(fill yes)
				)
			)
		)
		(pad "EF73" smd custom
			(at 26.090118 25.103074 180)
			(size 0.10795 0.10795)
			(layers "F.Cu" "F.Mask" "F.Paste")
			(net "M_E_DQS_DN<3>")
			(options
				(clearance outline)
				(anchor circle)
			)
			(primitives
				(gr_poly
					(pts
						(arc
							(start 0.2159 -0.0381)
							(mid 0 -0.254)
							(end -0.2159 -0.0381)
						)
						(arc
							(start -0.2159 0.0381)
							(mid 0 0.254)
							(end 0.2159 0.0381)
						)
					)
					(width 0)
					(fill yes)
				)
			)
		)
		(pad "EF75" smd custom
			(at 27.806904 25.103074 180)
			(size 0.10795 0.10795)
			(layers "F.Cu" "F.Mask" "F.Paste")
			(net "GND")
			(options
				(clearance outline)
				(anchor circle)
			)
			(primitives
				(gr_poly
					(pts
						(arc
							(start 0.2159 -0.0381)
							(mid 0 -0.254)
							(end -0.2159 -0.0381)
						)
						(arc
							(start -0.2159 0.0381)
							(mid 0 0.254)
							(end 0.2159 0.0381)
						)
					)
					(width 0)
					(fill yes)
				)
			)
		)
		(pad "EF77" smd custom
			(at 29.523944 25.103074 180)
			(size 0.10795 0.10795)
			(layers "F.Cu" "F.Mask" "F.Paste")
			(net "TP_CPU0_RSVD_2")
			(options
				(clearance outline)
				(anchor circle)
			)
			(primitives
				(gr_poly
					(pts
						(arc
							(start 0.2159 -0.0381)
							(mid 0 -0.254)
							(end -0.2159 -0.0381)
						)
						(arc
							(start -0.2159 0.0381)
							(mid 0 0.254)
							(end 0.2159 0.0381)
						)
					)
					(width 0)
					(fill yes)
				)
			)
		)
		(pad "EF79" smd custom
			(at 31.240984 25.103074 180)
			(size 0.10795 0.10795)
			(layers "F.Cu" "F.Mask" "F.Paste")
			(net "GND")
			(options
				(clearance outline)
				(anchor circle)
			)
			(primitives
				(gr_poly
					(pts
						(arc
							(start 0.2159 -0.0381)
							(mid 0 -0.254)
							(end -0.2159 -0.0381)
						)
						(arc
							(start -0.2159 0.0381)
							(mid 0 0.254)
							(end 0.2159 0.0381)
						)
					)
					(width 0)
					(fill yes)
				)
			)
		)
		(pad "EF81" smd custom
			(at 32.958024 25.103074 225)
			(size 0.10795 0.10795)
			(layers "F.Cu" "F.Mask" "F.Paste")
			(net "TP_CPU0_RSVD_1")
			(options
				(clearance outline)
				(anchor circle)
			)
			(primitives
				(gr_poly
					(pts
						(arc
							(start 0.2159 -0.0381)
							(mid 0 -0.254)
							(end -0.2159 -0.0381)
						)
						(arc
							(start -0.2159 0.0381)
							(mid 0 0.254)
							(end 0.2159 0.0381)
						)
					)
					(width 0)
					(fill yes)
				)
			)
		)
		(pad "EF83" smd custom
			(at 34.675064 25.103074 225)
			(size 0.10795 0.10795)
			(layers "F.Cu" "F.Mask" "F.Paste")
			(net "TP_CPU0_RSVD_0")
			(options
				(clearance outline)
				(anchor circle)
			)
			(primitives
				(gr_poly
					(pts
						(arc
							(start 0.2159 -0.0381)
							(mid 0 -0.254)
							(end -0.2159 -0.0381)
						)
						(arc
							(start -0.2159 0.0381)
							(mid 0 0.254)
							(end 0.2159 0.0381)
						)
					)
					(width 0)
					(fill yes)
				)
			)
		)
		(pad "F3" smd custom
			(at -35.533584 -22.626828 45)
			(size 0.10795 0.10795)
			(layers "F.Cu" "F.Mask" "F.Paste")
			(net "TP_CPU0_RSVD_279")
			(options
				(clearance outline)
				(anchor circle)
			)
			(primitives
				(gr_poly
					(pts
						(arc
							(start 0.2159 -0.0381)
							(mid 0 -0.254)
							(end -0.2159 -0.0381)
						)
						(arc
							(start -0.2159 0.0381)
							(mid 0 0.254)
							(end 0.2159 0.0381)
						)
					)
					(width 0)
					(fill yes)
				)
			)
		)
		(pad "F5" smd circle
			(at -33.816544 -22.626828)
			(size 0.4318 0.4318)
			(layers "F.Cu" "F.Mask" "F.Paste")
			(net "GND")
		)
		(pad "F7" smd circle
			(at -32.099504 -22.626828)
			(size 0.4318 0.4318)
			(layers "F.Cu" "F.Mask" "F.Paste")
			(net "UPI_CPU0_CPU1_P1P1_DP<15>")
		)
		(pad "F9" smd circle
			(at -30.382464 -22.626828)
			(size 0.4318 0.4318)
			(layers "F.Cu" "F.Mask" "F.Paste")
			(net "UPI_CPU0_CPU1_P1P1_DP<12>")
		)
		(pad "F11" smd circle
			(at -28.665424 -22.626828)
			(size 0.4318 0.4318)
			(layers "F.Cu" "F.Mask" "F.Paste")
			(net "UPI_CPU0_CPU1_P1P1_DN<11>")
		)
		(pad "F13" smd circle
			(at -26.948384 -22.626828)
			(size 0.4318 0.4318)
			(layers "F.Cu" "F.Mask" "F.Paste")
			(net "UPI_CPU0_CPU1_P1P1_DP<8>")
		)
		(pad "F15" smd circle
			(at -25.231598 -22.626828)
			(size 0.4318 0.4318)
			(layers "F.Cu" "F.Mask" "F.Paste")
			(net "UPI_CPU0_CPU1_P1P1_DN<6>")
		)
		(pad "F17" smd circle
			(at -23.514558 -22.626828)
			(size 0.4318 0.4318)
			(layers "F.Cu" "F.Mask" "F.Paste")
			(net "GND")
		)
		(pad "F19" smd circle
			(at -21.797518 -22.626828)
			(size 0.4318 0.4318)
			(layers "F.Cu" "F.Mask" "F.Paste")
			(net "GND")
		)
		(pad "F21" smd circle
			(at -20.080478 -22.626828)
			(size 0.4318 0.4318)
			(layers "F.Cu" "F.Mask" "F.Paste")
			(net "UPI_CPU0_CPU1_P1P1_DN<1>")
		)
		(pad "F23" smd circle
			(at -18.363438 -22.626828)
			(size 0.4318 0.4318)
			(layers "F.Cu" "F.Mask" "F.Paste")
			(net "TP_CPU0_RSVD_278")
		)
		(pad "F25" smd circle
			(at -16.646398 -22.626828)
			(size 0.4318 0.4318)
			(layers "F.Cu" "F.Mask" "F.Paste")
			(net "GND")
		)
		(pad "F27" smd circle
			(at -14.929612 -22.626828)
			(size 0.4318 0.4318)
			(layers "F.Cu" "F.Mask" "F.Paste")
			(net "M_B_DQ<55>")
		)
		(pad "F29" smd circle
			(at -13.212572 -22.626828)
			(size 0.4318 0.4318)
			(layers "F.Cu" "F.Mask" "F.Paste")
			(net "M_B_DQ<53>")
		)
		(pad "F31" smd circle
			(at -11.495532 -22.626828)
			(size 0.4318 0.4318)
			(layers "F.Cu" "F.Mask" "F.Paste")
			(net "GND")
		)
		(pad "F33" smd circle
			(at -9.778492 -22.626828)
			(size 0.4318 0.4318)
			(layers "F.Cu" "F.Mask" "F.Paste")
			(net "M_B_DQ<47>")
		)
		(pad "F35" smd circle
			(at -8.061452 -22.626828)
			(size 0.4318 0.4318)
			(layers "F.Cu" "F.Mask" "F.Paste")
			(net "M_B_DQ<45>")
		)
		(pad "F37" smd circle
			(at -6.344412 -22.626828)
			(size 0.4318 0.4318)
			(layers "F.Cu" "F.Mask" "F.Paste")
			(net "GND")
		)
		(pad "F39" smd circle
			(at -4.627626 -22.626828)
			(size 0.4318 0.4318)
			(layers "F.Cu" "F.Mask" "F.Paste")
			(net "M_A_DQ<39>")
		)
		(pad "F41" smd circle
			(at -2.910586 -22.626828)
			(size 0.4318 0.4318)
			(layers "F.Cu" "F.Mask" "F.Paste")
			(net "M_A_DQ<37>")
		)
		(pad "F43" smd circle
			(at -1.193546 -22.626828)
			(size 0.4318 0.4318)
			(layers "F.Cu" "F.Mask" "F.Paste")
			(net "GND")
		)
		(pad "F45" smd circle
			(at 2.052066 -24.426672)
			(size 0.508 0.508)
			(layers "F.Cu" "F.Mask" "F.Paste")
			(net "M_A_CS_N<6>")
		)
		(pad "F47" smd circle
			(at 3.769106 -24.426672)
			(size 0.4318 0.4318)
			(layers "F.Cu" "F.Mask" "F.Paste")
			(net "M_A_CS_N<3>")
		)
		(pad "F49" smd circle
			(at 5.485892 -24.426672)
			(size 0.4318 0.4318)
			(layers "F.Cu" "F.Mask" "F.Paste")
			(net "M_A_CS_N<1>")
		)
		(pad "F51" smd circle
			(at 7.202932 -24.426672)
			(size 0.4318 0.4318)
			(layers "F.Cu" "F.Mask" "F.Paste")
			(net "M_A_MA<14>")
		)
		(pad "F53" smd circle
			(at 8.919972 -24.426672)
			(size 0.4318 0.4318)
			(layers "F.Cu" "F.Mask" "F.Paste")
			(net "M_A_MA<0>")
		)
		(pad "F55" smd circle
			(at 10.637012 -24.426672)
			(size 0.4318 0.4318)
			(layers "F.Cu" "F.Mask" "F.Paste")
			(net "M_A_CLK_DN<0>")
		)
		(pad "F57" smd circle
			(at 12.354052 -24.426672)
			(size 0.4318 0.4318)
			(layers "F.Cu" "F.Mask" "F.Paste")
			(net "M_A_MA<1>")
		)
		(pad "F59" smd circle
			(at 14.071092 -24.426672)
			(size 0.4318 0.4318)
			(layers "F.Cu" "F.Mask" "F.Paste")
			(net "M_A_MA<5>")
		)
		(pad "F61" smd circle
			(at 15.787878 -24.426672)
			(size 0.4318 0.4318)
			(layers "F.Cu" "F.Mask" "F.Paste")
			(net "M_A_MA<9>")
		)
		(pad "F63" smd circle
			(at 17.504918 -24.426672)
			(size 0.4318 0.4318)
			(layers "F.Cu" "F.Mask" "F.Paste")
			(net "M_A_BG<1>")
		)
		(pad "F65" smd circle
			(at 19.221958 -24.426672)
			(size 0.4318 0.4318)
			(layers "F.Cu" "F.Mask" "F.Paste")
			(net "TP_CPU0_RSVD_277")
		)
		(pad "F67" smd custom
			(at 20.938998 -24.426672)
			(size 0.10795 0.10795)
			(layers "F.Cu" "F.Mask" "F.Paste")
			(net "GND")
			(options
				(clearance outline)
				(anchor circle)
			)
			(primitives
				(gr_poly
					(pts
						(arc
							(start 0.2159 -0.0381)
							(mid 0 -0.254)
							(end -0.2159 -0.0381)
						)
						(arc
							(start -0.2159 0.0381)
							(mid 0 0.254)
							(end 0.2159 0.0381)
						)
					)
					(width 0)
					(fill yes)
				)
			)
		)
		(pad "F69" smd custom
			(at 22.656038 -24.426672)
			(size 0.10795 0.10795)
			(layers "F.Cu" "F.Mask" "F.Paste")
			(net "GND")
			(options
				(clearance outline)
				(anchor circle)
			)
			(primitives
				(gr_poly
					(pts
						(arc
							(start 0.2159 -0.0381)
							(mid 0 -0.254)
							(end -0.2159 -0.0381)
						)
						(arc
							(start -0.2159 0.0381)
							(mid 0 0.254)
							(end 0.2159 0.0381)
						)
					)
					(width 0)
					(fill yes)
				)
			)
		)
		(pad "F71" smd custom
			(at 24.373078 -24.426672)
			(size 0.10795 0.10795)
			(layers "F.Cu" "F.Mask" "F.Paste")
			(net "M_B_DQ<27>")
			(options
				(clearance outline)
				(anchor circle)
			)
			(primitives
				(gr_poly
					(pts
						(arc
							(start 0.2159 -0.0381)
							(mid 0 -0.254)
							(end -0.2159 -0.0381)
						)
						(arc
							(start -0.2159 0.0381)
							(mid 0 0.254)
							(end 0.2159 0.0381)
						)
					)
					(width 0)
					(fill yes)
				)
			)
		)
		(pad "F73" smd circle
			(at 26.090118 -24.426672)
			(size 0.4318 0.4318)
			(layers "F.Cu" "F.Mask" "F.Paste")
			(net "M_B_DQS_DP<3>")
		)
		(pad "F75" smd circle
			(at 27.806904 -24.426672)
			(size 0.4318 0.4318)
			(layers "F.Cu" "F.Mask" "F.Paste")
			(net "M_B_DQ<28>")
		)
		(pad "F77" smd circle
			(at 29.523944 -24.426672)
			(size 0.4318 0.4318)
			(layers "F.Cu" "F.Mask" "F.Paste")
			(net "M_B_DQ<18>")
		)
		(pad "F79" smd circle
			(at 31.240984 -24.426672)
			(size 0.4318 0.4318)
			(layers "F.Cu" "F.Mask" "F.Paste")
			(net "M_B_DQS_DP<11>")
		)
		(pad "F81" smd circle
			(at 32.958024 -24.426672)
			(size 0.4318 0.4318)
			(layers "F.Cu" "F.Mask" "F.Paste")
			(net "M_B_DQ<20>")
		)
		(pad "F83" smd custom
			(at 34.675064 -24.426672 270)
			(size 0.10795 0.10795)
			(layers "F.Cu" "F.Mask" "F.Paste")
			(net "TP_CPU0_RSVD_276")
			(options
				(clearance outline)
				(anchor circle)
			)
			(primitives
				(gr_poly
					(pts
						(arc
							(start 0.2159 -0.0381)
							(mid 0 -0.254)
							(end -0.2159 -0.0381)
						)
						(arc
							(start -0.2159 0.0381)
							(mid 0 0.254)
							(end 0.2159 0.0381)
						)
					)
					(width 0)
					(fill yes)
				)
			)
		)
		(pad "G2" smd custom
			(at -36.392104 -22.131274 90)
			(size 0.10795 0.10795)
			(layers "F.Cu" "F.Mask" "F.Paste")
			(net "TP_CPU0_RSVD_275")
			(options
				(clearance outline)
				(anchor circle)
			)
			(primitives
				(gr_poly
					(pts
						(arc
							(start 0.2159 -0.0381)
							(mid 0 -0.254)
							(end -0.2159 -0.0381)
						)
						(arc
							(start -0.2159 0.0381)
							(mid 0 0.254)
							(end 0.2159 0.0381)
						)
					)
					(width 0)
					(fill yes)
				)
			)
		)
		(pad "G4" smd circle
			(at -34.675064 -22.131274)
			(size 0.4318 0.4318)
			(layers "F.Cu" "F.Mask" "F.Paste")
			(net "GND")
		)
		(pad "G6" smd circle
			(at -32.958024 -22.131274)
			(size 0.4318 0.4318)
			(layers "F.Cu" "F.Mask" "F.Paste")
			(net "UPI_CPU0_CPU1_P1P1_DN<15>")
		)
		(pad "G8" smd circle
			(at -31.240984 -22.131274)
			(size 0.4318 0.4318)
			(layers "F.Cu" "F.Mask" "F.Paste")
			(net "GND")
		)
		(pad "G10" smd circle
			(at -29.523944 -22.131274)
			(size 0.4318 0.4318)
			(layers "F.Cu" "F.Mask" "F.Paste")
			(net "UPI_CPU0_CPU1_P1P1_DN<10>")
		)
		(pad "G12" smd circle
			(at -27.806904 -22.131274)
			(size 0.4318 0.4318)
			(layers "F.Cu" "F.Mask" "F.Paste")
			(net "UPI_CPU0_CPU1_P1P1_DP<9>")
		)
		(pad "G14" smd circle
			(at -26.090118 -22.131274)
			(size 0.4318 0.4318)
			(layers "F.Cu" "F.Mask" "F.Paste")
			(net "UPI_CPU0_CPU1_P1P1_DN<8>")
		)
		(pad "G16" smd circle
			(at -24.373078 -22.131274)
			(size 0.4318 0.4318)
			(layers "F.Cu" "F.Mask" "F.Paste")
			(net "UPI_CPU0_CPU1_P1P1_DP<5>")
		)
		(pad "G18" smd circle
			(at -22.656038 -22.131274)
			(size 0.4318 0.4318)
			(layers "F.Cu" "F.Mask" "F.Paste")
			(net "UPI_CPU0_CPU1_P1P1_DN<3>")
		)
		(pad "G20" smd circle
			(at -20.938998 -22.131274)
			(size 0.4318 0.4318)
			(layers "F.Cu" "F.Mask" "F.Paste")
			(net "UPI_CPU0_CPU1_P1P1_DP<1>")
		)
		(pad "G22" smd circle
			(at -19.221958 -22.131274)
			(size 0.4318 0.4318)
			(layers "F.Cu" "F.Mask" "F.Paste")
			(net "GND")
		)
		(pad "G24" smd circle
			(at -17.504918 -22.131274)
			(size 0.4318 0.4318)
			(layers "F.Cu" "F.Mask" "F.Paste")
			(net "GND")
		)
		(pad "G26" smd circle
			(at -15.787878 -22.131274)
			(size 0.4318 0.4318)
			(layers "F.Cu" "F.Mask" "F.Paste")
			(net "GND")
		)
		(pad "G28" smd circle
			(at -14.071092 -22.131274)
			(size 0.4318 0.4318)
			(layers "F.Cu" "F.Mask" "F.Paste")
			(net "M_B_DQS_DN<6>")
		)
		(pad "G30" smd circle
			(at -12.354052 -22.131274)
			(size 0.4318 0.4318)
			(layers "F.Cu" "F.Mask" "F.Paste")
			(net "GND")
		)
		(pad "G32" smd circle
			(at -10.637012 -22.131274)
			(size 0.4318 0.4318)
			(layers "F.Cu" "F.Mask" "F.Paste")
			(net "GND")
		)
		(pad "G34" smd circle
			(at -8.919972 -22.131274)
			(size 0.4318 0.4318)
			(layers "F.Cu" "F.Mask" "F.Paste")
			(net "M_B_DQS_DN<5>")
		)
		(pad "G36" smd circle
			(at -7.202932 -22.131274)
			(size 0.4318 0.4318)
			(layers "F.Cu" "F.Mask" "F.Paste")
			(net "GND")
		)
		(pad "G38" smd circle
			(at -5.485892 -22.131274)
			(size 0.4318 0.4318)
			(layers "F.Cu" "F.Mask" "F.Paste")
			(net "GND")
		)
		(pad "G40" smd circle
			(at -3.769106 -22.131274)
			(size 0.4318 0.4318)
			(layers "F.Cu" "F.Mask" "F.Paste")
			(net "M_A_DQS_DN<4>")
		)
		(pad "G42" smd circle
			(at -2.052066 -22.131274)
			(size 0.4318 0.4318)
			(layers "F.Cu" "F.Mask" "F.Paste")
			(net "GND")
		)
		(pad "G46" smd circle
			(at 2.910586 -23.931626)
			(size 0.4318 0.4318)
			(layers "F.Cu" "F.Mask" "F.Paste")
			(net "M_A_C<2>")
		)
		(pad "G48" smd circle
			(at 4.627626 -23.931626)
			(size 0.4318 0.4318)
			(layers "F.Cu" "F.Mask" "F.Paste")
			(net "M_A_ODT<3>")
		)
		(pad "G50" smd circle
			(at 6.344412 -23.931626)
			(size 0.4318 0.4318)
			(layers "F.Cu" "F.Mask" "F.Paste")
			(net "M_A_ODT<2>")
		)
		(pad "G52" smd circle
			(at 8.061452 -23.931626)
			(size 0.4318 0.4318)
			(layers "F.Cu" "F.Mask" "F.Paste")
			(net "M_A_CS_N<0>")
		)
		(pad "G54" smd circle
			(at 9.778492 -23.931626)
			(size 0.4318 0.4318)
			(layers "F.Cu" "F.Mask" "F.Paste")
			(net "M_A_BA<1>")
		)
		(pad "G56" smd circle
			(at 11.495532 -23.931626)
			(size 0.4318 0.4318)
			(layers "F.Cu" "F.Mask" "F.Paste")
			(net "M_A_CLK_DP<2>")
		)
		(pad "G58" smd circle
			(at 13.212572 -23.931626)
			(size 0.4318 0.4318)
			(layers "F.Cu" "F.Mask" "F.Paste")
			(net "M_A_MA<4>")
		)
		(pad "G60" smd circle
			(at 14.929612 -23.931626)
			(size 0.4318 0.4318)
			(layers "F.Cu" "F.Mask" "F.Paste")
			(net "M_A_MA<7>")
		)
		(pad "G62" smd circle
			(at 16.646398 -23.931626)
			(size 0.4318 0.4318)
			(layers "F.Cu" "F.Mask" "F.Paste")
			(net "M_A_MA<11>")
		)
		(pad "G64" smd circle
			(at 18.363438 -23.931626)
			(size 0.4318 0.4318)
			(layers "F.Cu" "F.Mask" "F.Paste")
			(net "TP_CPU0_RSVD_274")
		)
		(pad "G66" smd circle
			(at 20.080478 -23.931626)
			(size 0.4318 0.4318)
			(layers "F.Cu" "F.Mask" "F.Paste")
			(net "GND")
		)
		(pad "G68" smd circle
			(at 21.797518 -23.931626)
			(size 0.4318 0.4318)
			(layers "F.Cu" "F.Mask" "F.Paste")
			(net "M_B_DQS_DN<17>")
		)
		(pad "G70" smd circle
			(at 23.514558 -23.931626)
			(size 0.4318 0.4318)
			(layers "F.Cu" "F.Mask" "F.Paste")
			(net "GND")
		)
		(pad "G72" smd circle
			(at 25.231598 -23.931626)
			(size 0.4318 0.4318)
			(layers "F.Cu" "F.Mask" "F.Paste")
			(net "M_B_DQ<31>")
		)
		(pad "G74" smd circle
			(at 26.948384 -23.931626)
			(size 0.4318 0.4318)
			(layers "F.Cu" "F.Mask" "F.Paste")
			(net "M_B_DQ<29>")
		)
		(pad "G76" smd circle
			(at 28.665424 -23.931626)
			(size 0.4318 0.4318)
			(layers "F.Cu" "F.Mask" "F.Paste")
			(net "GND")
		)
		(pad "G78" smd circle
			(at 30.382464 -23.931626)
			(size 0.4318 0.4318)
			(layers "F.Cu" "F.Mask" "F.Paste")
			(net "GND")
		)
		(pad "G80" smd circle
			(at 32.099504 -23.931626)
			(size 0.4318 0.4318)
			(layers "F.Cu" "F.Mask" "F.Paste")
			(net "GND")
		)
		(pad "G82" smd circle
			(at 33.816544 -23.931626)
			(size 0.4318 0.4318)
			(layers "F.Cu" "F.Mask" "F.Paste")
			(net "GND")
		)
		(pad "G84" smd custom
			(at 35.533584 -23.931626 270)
			(size 0.10795 0.10795)
			(layers "F.Cu" "F.Mask" "F.Paste")
			(net "TP_CPU0_RSVD_273")
			(options
				(clearance outline)
				(anchor circle)
			)
			(primitives
				(gr_poly
					(pts
						(arc
							(start 0.2159 -0.0381)
							(mid 0 -0.254)
							(end -0.2159 -0.0381)
						)
						(arc
							(start -0.2159 0.0381)
							(mid 0 0.254)
							(end 0.2159 0.0381)
						)
					)
					(width 0)
					(fill yes)
				)
			)
		)
		(pad "H1" smd custom
			(at -37.250624 -21.636228 90)
			(size 0.10795 0.10795)
			(layers "F.Cu" "F.Mask" "F.Paste")
			(net "TP_CPU0_RSVD_272")
			(options
				(clearance outline)
				(anchor circle)
			)
			(primitives
				(gr_poly
					(pts
						(arc
							(start 0.2159 -0.0381)
							(mid 0 -0.254)
							(end -0.2159 -0.0381)
						)
						(arc
							(start -0.2159 0.0381)
							(mid 0 0.254)
							(end 0.2159 0.0381)
						)
					)
					(width 0)
					(fill yes)
				)
			)
		)
		(pad "H3" smd circle
			(at -35.533584 -21.636228)
			(size 0.4318 0.4318)
			(layers "F.Cu" "F.Mask" "F.Paste")
			(net "GND")
		)
		(pad "H5" smd circle
			(at -33.816544 -21.636228)
			(size 0.4318 0.4318)
			(layers "F.Cu" "F.Mask" "F.Paste")
			(net "UPI_CPU0_CPU1_P1P1_DP<16>")
		)
		(pad "H7" smd circle
			(at -32.099504 -21.636228)
			(size 0.4318 0.4318)
			(layers "F.Cu" "F.Mask" "F.Paste")
			(net "UPI_CPU0_CPU1_P1P1_DN<14>")
		)
		(pad "H9" smd circle
			(at -30.382464 -21.636228)
			(size 0.4318 0.4318)
			(layers "F.Cu" "F.Mask" "F.Paste")
			(net "UPI_CPU0_CPU1_P1P1_DP<10>")
		)
		(pad "H11" smd circle
			(at -28.665424 -21.636228)
			(size 0.4318 0.4318)
			(layers "F.Cu" "F.Mask" "F.Paste")
			(net "GND")
		)
		(pad "H13" smd circle
			(at -26.948384 -21.636228)
			(size 0.4318 0.4318)
			(layers "F.Cu" "F.Mask" "F.Paste")
			(net "PVCCIO_CPU0")
		)
		(pad "H15" smd circle
			(at -25.231598 -21.636228)
			(size 0.4318 0.4318)
			(layers "F.Cu" "F.Mask" "F.Paste")
			(net "UPI_CPU0_CPU1_P1P1_DP<6>")
		)
		(pad "H17" smd circle
			(at -23.514558 -21.636228)
			(size 0.4318 0.4318)
			(layers "F.Cu" "F.Mask" "F.Paste")
			(net "UPI_CPU0_CPU1_P1P1_DN<5>")
		)
		(pad "H19" smd circle
			(at -21.797518 -21.636228)
			(size 0.4318 0.4318)
			(layers "F.Cu" "F.Mask" "F.Paste")
			(net "UPI_CPU0_CPU1_P1P1_DP<2>")
		)
		(pad "H21" smd circle
			(at -20.080478 -21.636228)
			(size 0.4318 0.4318)
			(layers "F.Cu" "F.Mask" "F.Paste")
			(net "UPI_CPU0_CPU1_P1P1_DN<0>")
		)
		(pad "H23" smd circle
			(at -18.363438 -21.636228)
			(size 0.4318 0.4318)
			(layers "F.Cu" "F.Mask" "F.Paste")
			(net "M_A_DQ<62>")
		)
		(pad "H25" smd circle
			(at -16.646398 -21.636228)
			(size 0.4318 0.4318)
			(layers "F.Cu" "F.Mask" "F.Paste")
			(net "GND")
		)
		(pad "H27" smd circle
			(at -14.929612 -21.636228)
			(size 0.4318 0.4318)
			(layers "F.Cu" "F.Mask" "F.Paste")
			(net "GND")
		)
		(pad "H29" smd circle
			(at -13.212572 -21.636228)
			(size 0.4318 0.4318)
			(layers "F.Cu" "F.Mask" "F.Paste")
			(net "GND")
		)
		(pad "H31" smd circle
			(at -11.495532 -21.636228)
			(size 0.4318 0.4318)
			(layers "F.Cu" "F.Mask" "F.Paste")
			(net "GND")
		)
		(pad "H33" smd circle
			(at -9.778492 -21.636228)
			(size 0.4318 0.4318)
			(layers "F.Cu" "F.Mask" "F.Paste")
			(net "GND")
		)
		(pad "H35" smd circle
			(at -8.061452 -21.636228)
			(size 0.4318 0.4318)
			(layers "F.Cu" "F.Mask" "F.Paste")
			(net "GND")
		)
		(pad "H37" smd circle
			(at -6.344412 -21.636228)
			(size 0.4318 0.4318)
			(layers "F.Cu" "F.Mask" "F.Paste")
			(net "GND")
		)
		(pad "H39" smd circle
			(at -4.627626 -21.636228)
			(size 0.4318 0.4318)
			(layers "F.Cu" "F.Mask" "F.Paste")
			(net "GND")
		)
		(pad "H41" smd circle
			(at -2.910586 -21.636228)
			(size 0.4318 0.4318)
			(layers "F.Cu" "F.Mask" "F.Paste")
			(net "GND")
		)
		(pad "H43" smd circle
			(at -1.193546 -21.636228)
			(size 0.4318 0.4318)
			(layers "F.Cu" "F.Mask" "F.Paste")
			(net "M_B_DQ<33>")
		)
		(pad "H45" smd circle
			(at 2.052066 -23.436326)
			(size 0.508 0.508)
			(layers "F.Cu" "F.Mask" "F.Paste")
			(net "GND")
		)
		(pad "H47" smd circle
			(at 3.769106 -23.436326)
			(size 0.4318 0.4318)
			(layers "F.Cu" "F.Mask" "F.Paste")
			(net "GND")
		)
		(pad "H49" smd circle
			(at 5.485892 -23.436326)
			(size 0.4318 0.4318)
			(layers "F.Cu" "F.Mask" "F.Paste")
			(net "GND")
		)
		(pad "H51" smd circle
			(at 7.202932 -23.436326)
			(size 0.4318 0.4318)
			(layers "F.Cu" "F.Mask" "F.Paste")
			(net "GND")
		)
		(pad "H53" smd circle
			(at 8.919972 -23.436326)
			(size 0.4318 0.4318)
			(layers "F.Cu" "F.Mask" "F.Paste")
			(net "GND")
		)
		(pad "H55" smd circle
			(at 10.637012 -23.436326)
			(size 0.4318 0.4318)
			(layers "F.Cu" "F.Mask" "F.Paste")
			(net "GND")
		)
		(pad "H57" smd circle
			(at 12.354052 -23.436326)
			(size 0.4318 0.4318)
			(layers "F.Cu" "F.Mask" "F.Paste")
			(net "GND")
		)
		(pad "H59" smd circle
			(at 14.071092 -23.436326)
			(size 0.4318 0.4318)
			(layers "F.Cu" "F.Mask" "F.Paste")
			(net "GND")
		)
		(pad "H61" smd circle
			(at 15.787878 -23.436326)
			(size 0.4318 0.4318)
			(layers "F.Cu" "F.Mask" "F.Paste")
			(net "GND")
		)
		(pad "H63" smd circle
			(at 17.504918 -23.436326)
			(size 0.4318 0.4318)
			(layers "F.Cu" "F.Mask" "F.Paste")
			(net "GND")
		)
		(pad "H65" smd circle
			(at 19.221958 -23.436326)
			(size 0.4318 0.4318)
			(layers "F.Cu" "F.Mask" "F.Paste")
			(net "GND")
		)
		(pad "H67" smd circle
			(at 20.938998 -23.436326)
			(size 0.4318 0.4318)
			(layers "F.Cu" "F.Mask" "F.Paste")
			(net "M_B_ECC<6>")
		)
		(pad "H69" smd circle
			(at 22.656038 -23.436326)
			(size 0.4318 0.4318)
			(layers "F.Cu" "F.Mask" "F.Paste")
			(net "M_B_ECC<1>")
		)
		(pad "H71" smd circle
			(at 24.373078 -23.436326)
			(size 0.4318 0.4318)
			(layers "F.Cu" "F.Mask" "F.Paste")
			(net "GND")
		)
		(pad "H73" smd circle
			(at 26.090118 -23.436326)
			(size 0.4318 0.4318)
			(layers "F.Cu" "F.Mask" "F.Paste")
			(net "M_B_DQS_DN<3>")
		)
		(pad "H75" smd circle
			(at 27.806904 -23.436326)
			(size 0.4318 0.4318)
			(layers "F.Cu" "F.Mask" "F.Paste")
			(net "GND")
		)
		(pad "H77" smd circle
			(at 29.523944 -23.436326)
			(size 0.4318 0.4318)
			(layers "F.Cu" "F.Mask" "F.Paste")
			(net "M_B_DQ<19>")
		)
		(pad "H79" smd circle
			(at 31.240984 -23.436326)
			(size 0.4318 0.4318)
			(layers "F.Cu" "F.Mask" "F.Paste")
			(net "M_B_DQS_DP<2>")
		)
		(pad "H81" smd circle
			(at 32.958024 -23.436326)
			(size 0.4318 0.4318)
			(layers "F.Cu" "F.Mask" "F.Paste")
			(net "M_B_DQ<21>")
		)
		(pad "H83" smd circle
			(at 34.675064 -23.436326)
			(size 0.4318 0.4318)
			(layers "F.Cu" "F.Mask" "F.Paste")
			(net "TP_CPU0_RSVD_271")
		)
		(pad "H85" smd custom
			(at 36.392104 -23.436326 270)
			(size 0.10795 0.10795)
			(layers "F.Cu" "F.Mask" "F.Paste")
			(net "TP_CPU0_RSVD_270")
			(options
				(clearance outline)
				(anchor circle)
			)
			(primitives
				(gr_poly
					(pts
						(arc
							(start 0.2159 -0.0381)
							(mid 0 -0.254)
							(end -0.2159 -0.0381)
						)
						(arc
							(start -0.2159 0.0381)
							(mid 0 0.254)
							(end 0.2159 0.0381)
						)
					)
					(width 0)
					(fill yes)
				)
			)
		)
		(pad "J2" smd circle
			(at -36.392104 -21.140674)
			(size 0.4318 0.4318)
			(layers "F.Cu" "F.Mask" "F.Paste")
			(net "PVCCIO_CPU0")
		)
		(pad "J4" smd circle
			(at -34.675064 -21.140674)
			(size 0.4318 0.4318)
			(layers "F.Cu" "F.Mask" "F.Paste")
			(net "GND")
		)
		(pad "J6" smd circle
			(at -32.958024 -21.140674)
			(size 0.4318 0.4318)
			(layers "F.Cu" "F.Mask" "F.Paste")
			(net "UPI_CPU0_CPU1_P1P1_DN<16>")
		)
		(pad "J8" smd circle
			(at -31.240984 -21.140674)
			(size 0.4318 0.4318)
			(layers "F.Cu" "F.Mask" "F.Paste")
			(net "UPI_CPU0_CPU1_P1P1_DP<13>")
		)
		(pad "J10" smd circle
			(at -29.523944 -21.140674)
			(size 0.4318 0.4318)
			(layers "F.Cu" "F.Mask" "F.Paste")
			(net "PVCCIO_CPU0")
		)
		(pad "J12" smd circle
			(at -27.806904 -21.140674)
			(size 0.4318 0.4318)
			(layers "F.Cu" "F.Mask" "F.Paste")
			(net "GND")
		)
		(pad "J14" smd circle
			(at -26.090118 -21.140674)
			(size 0.4318 0.4318)
			(layers "F.Cu" "F.Mask" "F.Paste")
			(net "GND")
		)
		(pad "J16" smd circle
			(at -24.373078 -21.140674)
			(size 0.4318 0.4318)
			(layers "F.Cu" "F.Mask" "F.Paste")
			(net "GND")
		)
		(pad "J18" smd circle
			(at -22.656038 -21.140674)
			(size 0.4318 0.4318)
			(layers "F.Cu" "F.Mask" "F.Paste")
			(net "UPI_CPU0_CPU1_P1P1_DP<3>")
		)
		(pad "J20" smd circle
			(at -20.938998 -21.140674)
			(size 0.4318 0.4318)
			(layers "F.Cu" "F.Mask" "F.Paste")
			(net "UPI_CPU0_CPU1_P1P1_DN<2>")
		)
		(pad "J22" smd circle
			(at -19.221958 -21.140674)
			(size 0.4318 0.4318)
			(layers "F.Cu" "F.Mask" "F.Paste")
			(net "GND")
		)
		(pad "J24" smd circle
			(at -17.504918 -21.140674)
			(size 0.4318 0.4318)
			(layers "F.Cu" "F.Mask" "F.Paste")
			(net "M_A_DQS_DN<16>")
		)
		(pad "J26" smd circle
			(at -15.787878 -21.140674)
			(size 0.4318 0.4318)
			(layers "F.Cu" "F.Mask" "F.Paste")
			(net "GND")
		)
		(pad "J28" smd circle
			(at -14.071092 -21.140674)
			(size 0.4318 0.4318)
			(layers "F.Cu" "F.Mask" "F.Paste")
			(net "GND")
		)
		(pad "J30" smd circle
			(at -12.354052 -21.140674)
			(size 0.4318 0.4318)
			(layers "F.Cu" "F.Mask" "F.Paste")
			(net "M_A_DQS_DN<15>")
		)
		(pad "J32" smd circle
			(at -10.637012 -21.140674)
			(size 0.4318 0.4318)
			(layers "F.Cu" "F.Mask" "F.Paste")
			(net "GND")
		)
		(pad "J34" smd circle
			(at -8.919972 -21.140674)
			(size 0.4318 0.4318)
			(layers "F.Cu" "F.Mask" "F.Paste")
			(net "GND")
		)
		(pad "J36" smd circle
			(at -7.202932 -21.140674)
			(size 0.4318 0.4318)
			(layers "F.Cu" "F.Mask" "F.Paste")
			(net "M_A_DQS_DN<14>")
		)
		(pad "J38" smd circle
			(at -5.485892 -21.140674)
			(size 0.4318 0.4318)
			(layers "F.Cu" "F.Mask" "F.Paste")
			(net "GND")
		)
		(pad "J40" smd circle
			(at -3.769106 -21.140674)
			(size 0.4318 0.4318)
			(layers "F.Cu" "F.Mask" "F.Paste")
			(net "GND")
		)
		(pad "J42" smd circle
			(at -2.052066 -21.140674)
			(size 0.4318 0.4318)
			(layers "F.Cu" "F.Mask" "F.Paste")
			(net "M_B_DQS_DN<13>")
		)
		(pad "J46" smd circle
			(at 2.910586 -22.940772)
			(size 0.4318 0.4318)
			(layers "F.Cu" "F.Mask" "F.Paste")
			(net "TP_CPU0_RSVD_269")
		)
		(pad "J48" smd circle
			(at 4.627626 -22.940772)
			(size 0.4318 0.4318)
			(layers "F.Cu" "F.Mask" "F.Paste")
			(net "M_A_MA<13>")
		)
		(pad "J50" smd circle
			(at 6.344412 -22.940772)
			(size 0.4318 0.4318)
			(layers "F.Cu" "F.Mask" "F.Paste")
			(net "M_B_CS_N<4>")
		)
		(pad "J52" smd circle
			(at 8.061452 -22.940772)
			(size 0.4318 0.4318)
			(layers "F.Cu" "F.Mask" "F.Paste")
			(net "M_B_MA<0>")
		)
		(pad "J54" smd circle
			(at 9.778492 -22.940772)
			(size 0.4318 0.4318)
			(layers "F.Cu" "F.Mask" "F.Paste")
			(net "M_A_MA<10>")
		)
		(pad "J56" smd circle
			(at 11.495532 -22.940772)
			(size 0.4318 0.4318)
			(layers "F.Cu" "F.Mask" "F.Paste")
			(net "M_A_CLK_DN<2>")
		)
		(pad "J58" smd circle
			(at 13.212572 -22.940772)
			(size 0.4318 0.4318)
			(layers "F.Cu" "F.Mask" "F.Paste")
			(net "M_B_MA<1>")
		)
		(pad "J60" smd circle
			(at 14.929612 -22.940772)
			(size 0.4318 0.4318)
			(layers "F.Cu" "F.Mask" "F.Paste")
			(net "M_A_ACT_N")
		)
		(pad "J62" smd circle
			(at 16.646398 -22.940772)
			(size 0.4318 0.4318)
			(layers "F.Cu" "F.Mask" "F.Paste")
			(net "TP_CPU0_RSVD_268")
		)
		(pad "J64" smd circle
			(at 18.363438 -22.940772)
			(size 0.4318 0.4318)
			(layers "F.Cu" "F.Mask" "F.Paste")
			(net "M_A_MA<12>")
		)
		(pad "J66" smd circle
			(at 20.080478 -22.940772)
			(size 0.4318 0.4318)
			(layers "F.Cu" "F.Mask" "F.Paste")
			(net "M_B_ECC<2>")
		)
		(pad "J68" smd circle
			(at 21.797518 -22.940772)
			(size 0.4318 0.4318)
			(layers "F.Cu" "F.Mask" "F.Paste")
			(net "M_B_DQS_DP<17>")
		)
		(pad "J70" smd circle
			(at 23.514558 -22.940772)
			(size 0.4318 0.4318)
			(layers "F.Cu" "F.Mask" "F.Paste")
			(net "M_B_ECC<0>")
		)
		(pad "J72" smd circle
			(at 25.231598 -22.940772)
			(size 0.4318 0.4318)
			(layers "F.Cu" "F.Mask" "F.Paste")
			(net "GND")
		)
		(pad "J74" smd circle
			(at 26.948384 -22.940772)
			(size 0.4318 0.4318)
			(layers "F.Cu" "F.Mask" "F.Paste")
			(net "GND")
		)
		(pad "J76" smd circle
			(at 28.665424 -22.940772)
			(size 0.4318 0.4318)
			(layers "F.Cu" "F.Mask" "F.Paste")
			(net "GND")
		)
		(pad "J78" smd circle
			(at 30.382464 -22.940772)
			(size 0.4318 0.4318)
			(layers "F.Cu" "F.Mask" "F.Paste")
			(net "M_B_DQ<23>")
		)
		(pad "J80" smd circle
			(at 32.099504 -22.940772)
			(size 0.4318 0.4318)
			(layers "F.Cu" "F.Mask" "F.Paste")
			(net "M_B_DQ<17>")
		)
		(pad "J82" smd circle
			(at 33.816544 -22.940772)
			(size 0.4318 0.4318)
			(layers "F.Cu" "F.Mask" "F.Paste")
			(net "GND")
		)
		(pad "J84" smd circle
			(at 35.533584 -22.940772)
			(size 0.4318 0.4318)
			(layers "F.Cu" "F.Mask" "F.Paste")
			(net "GND")
		)
		(pad "J86" smd custom
			(at 37.250624 -22.940772 270)
			(size 0.10795 0.10795)
			(layers "F.Cu" "F.Mask" "F.Paste")
			(net "GND")
			(options
				(clearance outline)
				(anchor circle)
			)
			(primitives
				(gr_poly
					(pts
						(arc
							(start 0.2159 -0.0381)
							(mid 0 -0.254)
							(end -0.2159 -0.0381)
						)
						(arc
							(start -0.2159 0.0381)
							(mid 0 0.254)
							(end 0.2159 0.0381)
						)
					)
					(width 0)
					(fill yes)
				)
			)
		)
		(pad "K1" smd custom
			(at -37.250624 -20.645628 90)
			(size 0.10795 0.10795)
			(layers "F.Cu" "F.Mask" "F.Paste")
			(net "GND")
			(options
				(clearance outline)
				(anchor circle)
			)
			(primitives
				(gr_poly
					(pts
						(arc
							(start 0.2159 -0.0381)
							(mid 0 -0.254)
							(end -0.2159 -0.0381)
						)
						(arc
							(start -0.2159 0.0381)
							(mid 0 0.254)
							(end 0.2159 0.0381)
						)
					)
					(width 0)
					(fill yes)
				)
			)
		)
		(pad "K3" smd circle
			(at -35.533584 -20.645628)
			(size 0.4318 0.4318)
			(layers "F.Cu" "F.Mask" "F.Paste")
			(net "UPI_CPU0_CPU1_P1P1_DP<18>")
		)
		(pad "K5" smd circle
			(at -33.816544 -20.645628)
			(size 0.4318 0.4318)
			(layers "F.Cu" "F.Mask" "F.Paste")
			(net "UPI_CPU0_CPU1_P1P1_DN<17>")
		)
		(pad "K7" smd circle
			(at -32.099504 -20.645628)
			(size 0.4318 0.4318)
			(layers "F.Cu" "F.Mask" "F.Paste")
			(net "UPI_CPU0_CPU1_P1P1_DP<14>")
		)
		(pad "K9" smd circle
			(at -30.382464 -20.645628)
			(size 0.4318 0.4318)
			(layers "F.Cu" "F.Mask" "F.Paste")
			(net "UPI_CPU0_CPU1_P1P1_DN<13>")
		)
		(pad "K11" smd circle
			(at -28.665424 -20.645628)
			(size 0.4318 0.4318)
			(layers "F.Cu" "F.Mask" "F.Paste")
			(net "GND")
		)
		(pad "K13" smd circle
			(at -26.948384 -20.645628)
			(size 0.4318 0.4318)
			(layers "F.Cu" "F.Mask" "F.Paste")
			(net "GND")
		)
		(pad "K15" smd circle
			(at -25.231598 -20.645628)
			(size 0.4318 0.4318)
			(layers "F.Cu" "F.Mask" "F.Paste")
			(net "PVCCIO_CPU0")
		)
		(pad "K17" smd circle
			(at -23.514558 -20.645628)
			(size 0.4318 0.4318)
			(layers "F.Cu" "F.Mask" "F.Paste")
			(net "GND")
		)
		(pad "K19" smd circle
			(at -21.797518 -20.645628)
			(size 0.4318 0.4318)
			(layers "F.Cu" "F.Mask" "F.Paste")
			(net "UPI_CPU0_CPU1_P1P1_DN<4>")
		)
		(pad "K21" smd circle
			(at -20.080478 -20.645628)
			(size 0.4318 0.4318)
			(layers "F.Cu" "F.Mask" "F.Paste")
			(net "UPI_CPU0_CPU1_P1P1_DP<0>")
		)
		(pad "K23" smd circle
			(at -18.363438 -20.645628)
			(size 0.4318 0.4318)
			(layers "F.Cu" "F.Mask" "F.Paste")
			(net "M_A_DQ<63>")
		)
		(pad "K25" smd circle
			(at -16.646398 -20.645628)
			(size 0.4318 0.4318)
			(layers "F.Cu" "F.Mask" "F.Paste")
			(net "M_A_DQ<56>")
		)
		(pad "K27" smd circle
			(at -14.929612 -20.645628)
			(size 0.4318 0.4318)
			(layers "F.Cu" "F.Mask" "F.Paste")
			(net "GND")
		)
		(pad "K29" smd circle
			(at -13.212572 -20.645628)
			(size 0.4318 0.4318)
			(layers "F.Cu" "F.Mask" "F.Paste")
			(net "M_A_DQ<54>")
		)
		(pad "K31" smd circle
			(at -11.495532 -20.645628)
			(size 0.4318 0.4318)
			(layers "F.Cu" "F.Mask" "F.Paste")
			(net "M_A_DQ<48>")
		)
		(pad "K33" smd circle
			(at -9.778492 -20.645628)
			(size 0.4318 0.4318)
			(layers "F.Cu" "F.Mask" "F.Paste")
			(net "GND")
		)
		(pad "K35" smd circle
			(at -8.061452 -20.645628)
			(size 0.4318 0.4318)
			(layers "F.Cu" "F.Mask" "F.Paste")
			(net "M_A_DQ<46>")
		)
		(pad "K37" smd circle
			(at -6.344412 -20.645628)
			(size 0.4318 0.4318)
			(layers "F.Cu" "F.Mask" "F.Paste")
			(net "M_A_DQ<40>")
		)
		(pad "K39" smd circle
			(at -4.627626 -20.645628)
			(size 0.4318 0.4318)
			(layers "F.Cu" "F.Mask" "F.Paste")
			(net "GND")
		)
		(pad "K41" smd circle
			(at -2.910586 -20.645628)
			(size 0.4318 0.4318)
			(layers "F.Cu" "F.Mask" "F.Paste")
			(net "M_B_DQ<38>")
		)
		(pad "K43" smd circle
			(at -1.193546 -20.645628)
			(size 0.4318 0.4318)
			(layers "F.Cu" "F.Mask" "F.Paste")
			(net "M_B_DQ<32>")
		)
		(pad "K45" smd circle
			(at 2.052066 -22.445726)
			(size 0.508 0.508)
			(layers "F.Cu" "F.Mask" "F.Paste")
			(net "M_A_CS_N<7>")
		)
		(pad "K47" smd circle
			(at 3.769106 -22.445726)
			(size 0.4318 0.4318)
			(layers "F.Cu" "F.Mask" "F.Paste")
			(net "M_A_MA<17>")
		)
		(pad "K49" smd circle
			(at 5.485892 -22.445726)
			(size 0.4318 0.4318)
			(layers "F.Cu" "F.Mask" "F.Paste")
			(net "M_A_MA<15>")
		)
		(pad "K51" smd circle
			(at 7.202932 -22.445726)
			(size 0.4318 0.4318)
			(layers "F.Cu" "F.Mask" "F.Paste")
			(net "M_B_CS_N<0>")
		)
		(pad "K53" smd circle
			(at 8.919972 -22.445726)
			(size 0.4318 0.4318)
			(layers "F.Cu" "F.Mask" "F.Paste")
			(net "M_B_PAR")
		)
		(pad "K55" smd circle
			(at 10.637012 -22.445726)
			(size 0.4318 0.4318)
			(layers "F.Cu" "F.Mask" "F.Paste")
			(net "M_B_BA<1>")
		)
		(pad "K57" smd circle
			(at 12.354052 -22.445726)
			(size 0.4318 0.4318)
			(layers "F.Cu" "F.Mask" "F.Paste")
			(net "M_B_MA<2>")
		)
		(pad "K59" smd circle
			(at 14.071092 -22.445726)
			(size 0.4318 0.4318)
			(layers "F.Cu" "F.Mask" "F.Paste")
			(net "M_B_MA<9>")
		)
		(pad "K61" smd circle
			(at 15.787878 -22.445726)
			(size 0.4318 0.4318)
			(layers "F.Cu" "F.Mask" "F.Paste")
			(net "TP_CPU0_RSVD_267")
		)
		(pad "K63" smd circle
			(at 17.504918 -22.445726)
			(size 0.4318 0.4318)
			(layers "F.Cu" "F.Mask" "F.Paste")
			(net "M_B_CKE<2>")
		)
		(pad "K65" smd circle
			(at 19.221958 -22.445726)
			(size 0.4318 0.4318)
			(layers "F.Cu" "F.Mask" "F.Paste")
			(net "GND")
		)
		(pad "K67" smd circle
			(at 20.938998 -22.445726)
			(size 0.4318 0.4318)
			(layers "F.Cu" "F.Mask" "F.Paste")
			(net "GND")
		)
		(pad "K69" smd circle
			(at 22.656038 -22.445726)
			(size 0.4318 0.4318)
			(layers "F.Cu" "F.Mask" "F.Paste")
			(net "GND")
		)
		(pad "K71" smd circle
			(at 24.373078 -22.445726)
			(size 0.4318 0.4318)
			(layers "F.Cu" "F.Mask" "F.Paste")
			(net "GND")
		)
		(pad "K73" smd circle
			(at 26.090118 -22.445726)
			(size 0.4318 0.4318)
			(layers "F.Cu" "F.Mask" "F.Paste")
			(net "GND")
		)
		(pad "K75" smd circle
			(at 27.806904 -22.445726)
			(size 0.4318 0.4318)
			(layers "F.Cu" "F.Mask" "F.Paste")
			(net "M_A_DQS_DN<12>")
		)
		(pad "K77" smd circle
			(at 29.523944 -22.445726)
			(size 0.4318 0.4318)
			(layers "F.Cu" "F.Mask" "F.Paste")
			(net "GND")
		)
		(pad "K79" smd circle
			(at 31.240984 -22.445726)
			(size 0.4318 0.4318)
			(layers "F.Cu" "F.Mask" "F.Paste")
			(net "M_B_DQS_DN<2>")
		)
		(pad "K81" smd circle
			(at 32.958024 -22.445726)
			(size 0.4318 0.4318)
			(layers "F.Cu" "F.Mask" "F.Paste")
			(net "GND")
		)
		(pad "K83" smd circle
			(at 34.675064 -22.445726)
			(size 0.4318 0.4318)
			(layers "F.Cu" "F.Mask" "F.Paste")
			(net "GND")
		)
		(pad "K85" smd circle
			(at 36.392104 -22.445726)
			(size 0.4318 0.4318)
			(layers "F.Cu" "F.Mask" "F.Paste")
			(net "GND")
		)
		(pad "L2" smd circle
			(at -36.392104 -20.150074)
			(size 0.4318 0.4318)
			(layers "F.Cu" "F.Mask" "F.Paste")
			(net "GND")
		)
		(pad "L4" smd circle
			(at -34.675064 -20.150074)
			(size 0.4318 0.4318)
			(layers "F.Cu" "F.Mask" "F.Paste")
			(net "UPI_CPU0_CPU1_P1P1_DN<18>")
		)
		(pad "L6" smd circle
			(at -32.958024 -20.150074)
			(size 0.4318 0.4318)
			(layers "F.Cu" "F.Mask" "F.Paste")
			(net "GND")
		)
		(pad "L8" smd circle
			(at -31.240984 -20.150074)
			(size 0.4318 0.4318)
			(layers "F.Cu" "F.Mask" "F.Paste")
			(net "GND")
		)
		(pad "L10" smd circle
			(at -29.523944 -20.150074)
			(size 0.4318 0.4318)
			(layers "F.Cu" "F.Mask" "F.Paste")
			(net "GND")
		)
		(pad "L12" smd circle
			(at -27.806904 -20.150074)
			(size 0.4318 0.4318)
			(layers "F.Cu" "F.Mask" "F.Paste")
			(net "UPI_CPU1_CPU0_P1P1_DN<12>")
		)
		(pad "L14" smd circle
			(at -26.090118 -20.150074)
			(size 0.4318 0.4318)
			(layers "F.Cu" "F.Mask" "F.Paste")
			(net "PVCCIO_CPU0")
		)
		(pad "L16" smd circle
			(at -24.373078 -20.150074)
			(size 0.4318 0.4318)
			(layers "F.Cu" "F.Mask" "F.Paste")
			(net "PVCCIO_CPU0")
		)
		(pad "L18" smd circle
			(at -22.656038 -20.150074)
			(size 0.4318 0.4318)
			(layers "F.Cu" "F.Mask" "F.Paste")
			(net "UPI_CPU0_CPU1_P1P1_DP<4>")
		)
		(pad "L20" smd circle
			(at -20.938998 -20.150074)
			(size 0.4318 0.4318)
			(layers "F.Cu" "F.Mask" "F.Paste")
			(net "GND")
		)
		(pad "L22" smd circle
			(at -19.221958 -20.150074)
			(size 0.4318 0.4318)
			(layers "F.Cu" "F.Mask" "F.Paste")
			(net "GND")
		)
		(pad "L24" smd circle
			(at -17.504918 -20.150074)
			(size 0.4318 0.4318)
			(layers "F.Cu" "F.Mask" "F.Paste")
			(net "M_A_DQS_DP<16>")
		)
		(pad "L26" smd circle
			(at -15.787878 -20.150074)
			(size 0.4318 0.4318)
			(layers "F.Cu" "F.Mask" "F.Paste")
			(net "M_A_DQ<60>")
		)
		(pad "L28" smd circle
			(at -14.071092 -20.150074)
			(size 0.4318 0.4318)
			(layers "F.Cu" "F.Mask" "F.Paste")
			(net "M_A_DQ<50>")
		)
		(pad "L30" smd circle
			(at -12.354052 -20.150074)
			(size 0.4318 0.4318)
			(layers "F.Cu" "F.Mask" "F.Paste")
			(net "M_A_DQS_DP<15>")
		)
		(pad "L32" smd circle
			(at -10.637012 -20.150074)
			(size 0.4318 0.4318)
			(layers "F.Cu" "F.Mask" "F.Paste")
			(net "M_A_DQ<52>")
		)
		(pad "L34" smd circle
			(at -8.919972 -20.150074)
			(size 0.4318 0.4318)
			(layers "F.Cu" "F.Mask" "F.Paste")
			(net "M_A_DQ<42>")
		)
		(pad "L36" smd circle
			(at -7.202932 -20.150074)
			(size 0.4318 0.4318)
			(layers "F.Cu" "F.Mask" "F.Paste")
			(net "M_A_DQS_DP<14>")
		)
		(pad "L38" smd circle
			(at -5.485892 -20.150074)
			(size 0.4318 0.4318)
			(layers "F.Cu" "F.Mask" "F.Paste")
			(net "M_A_DQ<44>")
		)
		(pad "L40" smd circle
			(at -3.769106 -20.150074)
			(size 0.4318 0.4318)
			(layers "F.Cu" "F.Mask" "F.Paste")
			(net "M_B_DQ<34>")
		)
		(pad "L42" smd circle
			(at -2.052066 -20.150074)
			(size 0.4318 0.4318)
			(layers "F.Cu" "F.Mask" "F.Paste")
			(net "M_B_DQS_DP<13>")
		)
		(pad "L46" smd circle
			(at 2.910586 -21.950172)
			(size 0.4318 0.4318)
			(layers "F.Cu" "F.Mask" "F.Paste")
			(net "PVDDQ_ABC")
		)
		(pad "L48" smd circle
			(at 4.627626 -21.950172)
			(size 0.4318 0.4318)
			(layers "F.Cu" "F.Mask" "F.Paste")
			(net "PVDDQ_ABC")
		)
		(pad "L50" smd circle
			(at 6.344412 -21.950172)
			(size 0.4318 0.4318)
			(layers "F.Cu" "F.Mask" "F.Paste")
			(net "PVDDQ_ABC")
		)
		(pad "L52" smd circle
			(at 8.061452 -21.950172)
			(size 0.4318 0.4318)
			(layers "F.Cu" "F.Mask" "F.Paste")
			(net "PVDDQ_ABC")
		)
		(pad "L54" smd circle
			(at 9.778492 -21.950172)
			(size 0.4318 0.4318)
			(layers "F.Cu" "F.Mask" "F.Paste")
			(net "PVDDQ_ABC")
		)
		(pad "L56" smd circle
			(at 11.495532 -21.950172)
			(size 0.4318 0.4318)
			(layers "F.Cu" "F.Mask" "F.Paste")
			(net "PVDDQ_ABC")
		)
		(pad "L58" smd circle
			(at 13.212572 -21.950172)
			(size 0.4318 0.4318)
			(layers "F.Cu" "F.Mask" "F.Paste")
			(net "PVDDQ_ABC")
		)
		(pad "L60" smd circle
			(at 14.929612 -21.950172)
			(size 0.4318 0.4318)
			(layers "F.Cu" "F.Mask" "F.Paste")
			(net "PVDDQ_ABC")
		)
		(pad "L62" smd circle
			(at 16.646398 -21.950172)
			(size 0.4318 0.4318)
			(layers "F.Cu" "F.Mask" "F.Paste")
			(net "PVDDQ_ABC")
		)
		(pad "L64" smd circle
			(at 18.363438 -21.950172)
			(size 0.4318 0.4318)
			(layers "F.Cu" "F.Mask" "F.Paste")
			(net "M_B_CKE<3>")
		)
		(pad "L66" smd circle
			(at 20.080478 -21.950172)
			(size 0.4318 0.4318)
			(layers "F.Cu" "F.Mask" "F.Paste")
			(net "M_B_ECC<3>")
		)
		(pad "L68" smd circle
			(at 21.797518 -21.950172)
			(size 0.4318 0.4318)
			(layers "F.Cu" "F.Mask" "F.Paste")
			(net "M_B_DQS_DP<8>")
		)
		(pad "L70" smd circle
			(at 23.514558 -21.950172)
			(size 0.4318 0.4318)
			(layers "F.Cu" "F.Mask" "F.Paste")
			(net "M_B_ECC<4>")
		)
		(pad "L72" smd circle
			(at 25.231598 -21.950172)
			(size 0.4318 0.4318)
			(layers "F.Cu" "F.Mask" "F.Paste")
			(net "GND")
		)
		(pad "L74" smd circle
			(at 26.948384 -21.950172)
			(size 0.4318 0.4318)
			(layers "F.Cu" "F.Mask" "F.Paste")
			(net "M_A_DQ<30>")
		)
		(pad "L76" smd circle
			(at 28.665424 -21.950172)
			(size 0.4318 0.4318)
			(layers "F.Cu" "F.Mask" "F.Paste")
			(net "M_A_DQ<24>")
		)
		(pad "L78" smd circle
			(at 30.382464 -21.950172)
			(size 0.4318 0.4318)
			(layers "F.Cu" "F.Mask" "F.Paste")
			(net "GND")
		)
		(pad "L80" smd circle
			(at 32.099504 -21.950172)
			(size 0.4318 0.4318)
			(layers "F.Cu" "F.Mask" "F.Paste")
			(net "GND")
		)
		(pad "L82" smd circle
			(at 33.816544 -21.950172)
			(size 0.4318 0.4318)
			(layers "F.Cu" "F.Mask" "F.Paste")
			(net "GND")
		)
		(pad "L84" smd circle
			(at 35.533584 -21.950172)
			(size 0.4318 0.4318)
			(layers "F.Cu" "F.Mask" "F.Paste")
			(net "M_A_DQ<11>")
		)
		(pad "L86" smd custom
			(at 37.250624 -21.950172 270)
			(size 0.10795 0.10795)
			(layers "F.Cu" "F.Mask" "F.Paste")
			(net "M_A_DQ<10>")
			(options
				(clearance outline)
				(anchor circle)
			)
			(primitives
				(gr_poly
					(pts
						(arc
							(start 0.2159 -0.0381)
							(mid 0 -0.254)
							(end -0.2159 -0.0381)
						)
						(arc
							(start -0.2159 0.0381)
							(mid 0 0.254)
							(end 0.2159 0.0381)
						)
					)
					(width 0)
					(fill yes)
				)
			)
		)
		(pad "M1" smd custom
			(at -37.250624 -19.655028 90)
			(size 0.10795 0.10795)
			(layers "F.Cu" "F.Mask" "F.Paste")
			(net "UPI_CPU0_CPU1_P0P0_DP<19>")
			(options
				(clearance outline)
				(anchor circle)
			)
			(primitives
				(gr_poly
					(pts
						(arc
							(start 0.2159 -0.0381)
							(mid 0 -0.254)
							(end -0.2159 -0.0381)
						)
						(arc
							(start -0.2159 0.0381)
							(mid 0 0.254)
							(end 0.2159 0.0381)
						)
					)
					(width 0)
					(fill yes)
				)
			)
		)
		(pad "M3" smd circle
			(at -35.533584 -19.655028)
			(size 0.4318 0.4318)
			(layers "F.Cu" "F.Mask" "F.Paste")
			(net "UPI_CPU0_CPU1_P1P1_DN<19>")
		)
		(pad "M5" smd circle
			(at -33.816544 -19.655028)
			(size 0.4318 0.4318)
			(layers "F.Cu" "F.Mask" "F.Paste")
			(net "UPI_CPU0_CPU1_P1P1_DP<17>")
		)
		(pad "M7" smd circle
			(at -32.099504 -19.655028)
			(size 0.4318 0.4318)
			(layers "F.Cu" "F.Mask" "F.Paste")
			(net "PVCCIO_CPU0")
		)
		(pad "M9" smd circle
			(at -30.382464 -19.655028)
			(size 0.4318 0.4318)
			(layers "F.Cu" "F.Mask" "F.Paste")
			(net "PVCCIO_CPU0")
		)
		(pad "M11" smd circle
			(at -28.665424 -19.655028)
			(size 0.4318 0.4318)
			(layers "F.Cu" "F.Mask" "F.Paste")
			(net "PVCCIO_CPU0")
		)
		(pad "M13" smd circle
			(at -26.948384 -19.655028)
			(size 0.4318 0.4318)
			(layers "F.Cu" "F.Mask" "F.Paste")
			(net "UPI_CPU1_CPU0_P1P1_DP<11>")
		)
		(pad "M15" smd circle
			(at -25.231598 -19.655028)
			(size 0.4318 0.4318)
			(layers "F.Cu" "F.Mask" "F.Paste")
			(net "GND")
		)
		(pad "M17" smd circle
			(at -23.514558 -19.655028)
			(size 0.4318 0.4318)
			(layers "F.Cu" "F.Mask" "F.Paste")
			(net "GND")
		)
		(pad "M19" smd circle
			(at -21.797518 -19.655028)
			(size 0.4318 0.4318)
			(layers "F.Cu" "F.Mask" "F.Paste")
			(net "GND")
		)
		(pad "M21" smd circle
			(at -20.080478 -19.655028)
			(size 0.4318 0.4318)
			(layers "F.Cu" "F.Mask" "F.Paste")
			(net "PVCCIO_CPU0")
		)
		(pad "M23" smd circle
			(at -18.363438 -19.655028)
			(size 0.4318 0.4318)
			(layers "F.Cu" "F.Mask" "F.Paste")
			(net "GND")
		)
		(pad "M25" smd circle
			(at -16.646398 -19.655028)
			(size 0.4318 0.4318)
			(layers "F.Cu" "F.Mask" "F.Paste")
			(net "GND")
		)
		(pad "M27" smd circle
			(at -14.929612 -19.655028)
			(size 0.4318 0.4318)
			(layers "F.Cu" "F.Mask" "F.Paste")
			(net "GND")
		)
		(pad "M29" smd circle
			(at -13.212572 -19.655028)
			(size 0.4318 0.4318)
			(layers "F.Cu" "F.Mask" "F.Paste")
			(net "GND")
		)
		(pad "M31" smd circle
			(at -11.495532 -19.655028)
			(size 0.4318 0.4318)
			(layers "F.Cu" "F.Mask" "F.Paste")
			(net "GND")
		)
		(pad "M33" smd circle
			(at -9.778492 -19.655028)
			(size 0.4318 0.4318)
			(layers "F.Cu" "F.Mask" "F.Paste")
			(net "GND")
		)
		(pad "M35" smd circle
			(at -8.061452 -19.655028)
			(size 0.4318 0.4318)
			(layers "F.Cu" "F.Mask" "F.Paste")
			(net "GND")
		)
		(pad "M37" smd circle
			(at -6.344412 -19.655028)
			(size 0.4318 0.4318)
			(layers "F.Cu" "F.Mask" "F.Paste")
			(net "GND")
		)
		(pad "M39" smd circle
			(at -4.627626 -19.655028)
			(size 0.4318 0.4318)
			(layers "F.Cu" "F.Mask" "F.Paste")
			(net "GND")
		)
		(pad "M41" smd circle
			(at -2.910586 -19.655028)
			(size 0.4318 0.4318)
			(layers "F.Cu" "F.Mask" "F.Paste")
			(net "GND")
		)
		(pad "M43" smd circle
			(at -1.193546 -19.655028)
			(size 0.4318 0.4318)
			(layers "F.Cu" "F.Mask" "F.Paste")
			(net "GND")
		)
		(pad "M45" smd circle
			(at 2.052066 -21.455126)
			(size 0.508 0.508)
			(layers "F.Cu" "F.Mask" "F.Paste")
			(net "M_B_CS_N<6>")
		)
		(pad "M47" smd circle
			(at 3.769106 -21.455126)
			(size 0.4318 0.4318)
			(layers "F.Cu" "F.Mask" "F.Paste")
			(net "M_B_C<2>")
		)
		(pad "M49" smd circle
			(at 5.485892 -21.455126)
			(size 0.4318 0.4318)
			(layers "F.Cu" "F.Mask" "F.Paste")
			(net "M_B_ODT<2>")
		)
		(pad "M51" smd circle
			(at 7.202932 -21.455126)
			(size 0.4318 0.4318)
			(layers "F.Cu" "F.Mask" "F.Paste")
			(net "M_B_MA<13>")
		)
		(pad "M53" smd circle
			(at 8.919972 -21.455126)
			(size 0.4318 0.4318)
			(layers "F.Cu" "F.Mask" "F.Paste")
			(net "M_B_CLK_DN<0>")
		)
		(pad "M55" smd circle
			(at 10.637012 -21.455126)
			(size 0.4318 0.4318)
			(layers "F.Cu" "F.Mask" "F.Paste")
			(net "M_B_MA<10>")
		)
		(pad "M57" smd circle
			(at 12.354052 -21.455126)
			(size 0.4318 0.4318)
			(layers "F.Cu" "F.Mask" "F.Paste")
			(net "M_B_CLK_DP<2>")
		)
		(pad "M59" smd circle
			(at 14.071092 -21.455126)
			(size 0.4318 0.4318)
			(layers "F.Cu" "F.Mask" "F.Paste")
			(net "M_B_MA<4>")
		)
		(pad "M61" smd circle
			(at 15.787878 -21.455126)
			(size 0.4318 0.4318)
			(layers "F.Cu" "F.Mask" "F.Paste")
			(net "M_B_BG<0>")
		)
		(pad "M63" smd circle
			(at 17.504918 -21.455126)
			(size 0.4318 0.4318)
			(layers "F.Cu" "F.Mask" "F.Paste")
			(net "TP_CPU0_RSVD_266")
		)
		(pad "M65" smd circle
			(at 19.221958 -21.455126)
			(size 0.4318 0.4318)
			(layers "F.Cu" "F.Mask" "F.Paste")
			(net "GND")
		)
		(pad "M67" smd circle
			(at 20.938998 -21.455126)
			(size 0.4318 0.4318)
			(layers "F.Cu" "F.Mask" "F.Paste")
			(net "M_B_ECC<7>")
		)
		(pad "M69" smd circle
			(at 22.656038 -21.455126)
			(size 0.4318 0.4318)
			(layers "F.Cu" "F.Mask" "F.Paste")
			(net "M_B_ECC<5>")
		)
		(pad "M71" smd circle
			(at 24.373078 -21.455126)
			(size 0.4318 0.4318)
			(layers "F.Cu" "F.Mask" "F.Paste")
			(net "GND")
		)
		(pad "M73" smd circle
			(at 26.090118 -21.455126)
			(size 0.4318 0.4318)
			(layers "F.Cu" "F.Mask" "F.Paste")
			(net "M_A_DQ<26>")
		)
		(pad "M75" smd circle
			(at 27.806904 -21.455126)
			(size 0.4318 0.4318)
			(layers "F.Cu" "F.Mask" "F.Paste")
			(net "M_A_DQS_DP<12>")
		)
		(pad "M77" smd circle
			(at 29.523944 -21.455126)
			(size 0.4318 0.4318)
			(layers "F.Cu" "F.Mask" "F.Paste")
			(net "M_A_DQ<28>")
		)
		(pad "M79" smd circle
			(at 31.240984 -21.455126)
			(size 0.4318 0.4318)
			(layers "F.Cu" "F.Mask" "F.Paste")
			(net "GND")
		)
		(pad "M81" smd circle
			(at 32.958024 -21.455126)
			(size 0.4318 0.4318)
			(layers "F.Cu" "F.Mask" "F.Paste")
			(net "M_A_DQ<19>")
		)
		(pad "M83" smd circle
			(at 34.675064 -21.455126)
			(size 0.4318 0.4318)
			(layers "F.Cu" "F.Mask" "F.Paste")
			(net "GND")
		)
		(pad "M85" smd circle
			(at 36.392104 -21.455126)
			(size 0.4318 0.4318)
			(layers "F.Cu" "F.Mask" "F.Paste")
			(net "GND")
		)
		(pad "N2" smd circle
			(at -36.392104 -19.159474)
			(size 0.4318 0.4318)
			(layers "F.Cu" "F.Mask" "F.Paste")
			(net "UPI_CPU0_CPU1_P0P0_DN<19>")
		)
		(pad "N4" smd circle
			(at -34.675064 -19.159474)
			(size 0.4318 0.4318)
			(layers "F.Cu" "F.Mask" "F.Paste")
			(net "GND")
		)
		(pad "N6" smd circle
			(at -32.958024 -19.159474)
			(size 0.4318 0.4318)
			(layers "F.Cu" "F.Mask" "F.Paste")
			(net "GND")
		)
		(pad "N8" smd circle
			(at -31.240984 -19.159474)
			(size 0.4318 0.4318)
			(layers "F.Cu" "F.Mask" "F.Paste")
			(net "GND")
		)
		(pad "N10" smd circle
			(at -29.523944 -19.159474)
			(size 0.4318 0.4318)
			(layers "F.Cu" "F.Mask" "F.Paste")
			(net "UPI_CPU1_CPU0_P1P1_DP<15>")
		)
		(pad "N12" smd circle
			(at -27.806904 -19.159474)
			(size 0.4318 0.4318)
			(layers "F.Cu" "F.Mask" "F.Paste")
			(net "UPI_CPU1_CPU0_P1P1_DP<12>")
		)
		(pad "N14" smd circle
			(at -26.090118 -19.159474)
			(size 0.4318 0.4318)
			(layers "F.Cu" "F.Mask" "F.Paste")
			(net "UPI_CPU1_CPU0_P1P1_DN<11>")
		)
		(pad "N16" smd circle
			(at -24.373078 -19.159474)
			(size 0.4318 0.4318)
			(layers "F.Cu" "F.Mask" "F.Paste")
			(net "UPI_CPU1_CPU0_P1P1_DP<8>")
		)
		(pad "N18" smd circle
			(at -22.656038 -19.159474)
			(size 0.4318 0.4318)
			(layers "F.Cu" "F.Mask" "F.Paste")
			(net "PVCCIO_CPU0")
		)
		(pad "N20" smd circle
			(at -20.938998 -19.159474)
			(size 0.4318 0.4318)
			(layers "F.Cu" "F.Mask" "F.Paste")
			(net "GND")
		)
		(pad "N22" smd circle
			(at -19.221958 -19.159474)
			(size 0.4318 0.4318)
			(layers "F.Cu" "F.Mask" "F.Paste")
			(net "GND")
		)
		(pad "N24" smd circle
			(at -17.504918 -19.159474)
			(size 0.4318 0.4318)
			(layers "F.Cu" "F.Mask" "F.Paste")
			(net "M_A_DQS_DN<7>")
		)
		(pad "N26" smd circle
			(at -15.787878 -19.159474)
			(size 0.4318 0.4318)
			(layers "F.Cu" "F.Mask" "F.Paste")
			(net "M_A_DQ<61>")
		)
		(pad "N28" smd circle
			(at -14.071092 -19.159474)
			(size 0.4318 0.4318)
			(layers "F.Cu" "F.Mask" "F.Paste")
			(net "M_A_DQ<51>")
		)
		(pad "N30" smd circle
			(at -12.354052 -19.159474)
			(size 0.4318 0.4318)
			(layers "F.Cu" "F.Mask" "F.Paste")
			(net "M_A_DQS_DP<6>")
		)
		(pad "N32" smd circle
			(at -10.637012 -19.159474)
			(size 0.4318 0.4318)
			(layers "F.Cu" "F.Mask" "F.Paste")
			(net "M_A_DQ<53>")
		)
		(pad "N34" smd circle
			(at -8.919972 -19.159474)
			(size 0.4318 0.4318)
			(layers "F.Cu" "F.Mask" "F.Paste")
			(net "M_A_DQ<43>")
		)
		(pad "N36" smd circle
			(at -7.202932 -19.159474)
			(size 0.4318 0.4318)
			(layers "F.Cu" "F.Mask" "F.Paste")
			(net "M_A_DQS_DP<5>")
		)
		(pad "N38" smd circle
			(at -5.485892 -19.159474)
			(size 0.4318 0.4318)
			(layers "F.Cu" "F.Mask" "F.Paste")
			(net "M_A_DQ<45>")
		)
		(pad "N40" smd circle
			(at -3.769106 -19.159474)
			(size 0.4318 0.4318)
			(layers "F.Cu" "F.Mask" "F.Paste")
			(net "M_B_DQ<35>")
		)
		(pad "N42" smd circle
			(at -2.052066 -19.159474)
			(size 0.4318 0.4318)
			(layers "F.Cu" "F.Mask" "F.Paste")
			(net "M_B_DQS_DN<4>")
		)
		(pad "N46" smd circle
			(at 2.910586 -20.959572)
			(size 0.4318 0.4318)
			(layers "F.Cu" "F.Mask" "F.Paste")
			(net "M_B_CS_N<2>")
		)
		(pad "N48" smd circle
			(at 4.627626 -20.959572)
			(size 0.4318 0.4318)
			(layers "F.Cu" "F.Mask" "F.Paste")
			(net "M_B_MA<17>")
		)
		(pad "N50" smd circle
			(at 6.344412 -20.959572)
			(size 0.4318 0.4318)
			(layers "F.Cu" "F.Mask" "F.Paste")
			(net "M_B_ODT<0>")
		)
		(pad "N52" smd circle
			(at 8.061452 -20.959572)
			(size 0.4318 0.4318)
			(layers "F.Cu" "F.Mask" "F.Paste")
			(net "M_B_MA<15>")
		)
		(pad "N54" smd circle
			(at 9.778492 -20.959572)
			(size 0.4318 0.4318)
			(layers "F.Cu" "F.Mask" "F.Paste")
			(net "M_B_CLK_DP<0>")
		)
		(pad "N56" smd circle
			(at 11.495532 -20.959572)
			(size 0.4318 0.4318)
			(layers "F.Cu" "F.Mask" "F.Paste")
			(net "M_B_CLK_DN<2>")
		)
		(pad "N58" smd circle
			(at 13.212572 -20.959572)
			(size 0.4318 0.4318)
			(layers "F.Cu" "F.Mask" "F.Paste")
			(net "M_B_MA<3>")
		)
		(pad "N60" smd circle
			(at 14.929612 -20.959572)
			(size 0.4318 0.4318)
			(layers "F.Cu" "F.Mask" "F.Paste")
			(net "M_B_BG<1>")
		)
		(pad "N62" smd circle
			(at 16.646398 -20.959572)
			(size 0.4318 0.4318)
			(layers "F.Cu" "F.Mask" "F.Paste")
			(net "M_B_CKE<0>")
		)
		(pad "N64" smd circle
			(at 18.363438 -20.959572)
			(size 0.4318 0.4318)
			(layers "F.Cu" "F.Mask" "F.Paste")
			(net "PVDDQ_ABC")
		)
		(pad "N66" smd circle
			(at 20.080478 -20.959572)
			(size 0.4318 0.4318)
			(layers "F.Cu" "F.Mask" "F.Paste")
			(net "GND")
		)
		(pad "N68" smd circle
			(at 21.797518 -20.959572)
			(size 0.4318 0.4318)
			(layers "F.Cu" "F.Mask" "F.Paste")
			(net "M_B_DQS_DN<8>")
		)
		(pad "N70" smd circle
			(at 23.514558 -20.959572)
			(size 0.4318 0.4318)
			(layers "F.Cu" "F.Mask" "F.Paste")
			(net "GND")
		)
		(pad "N72" smd circle
			(at 25.231598 -20.959572)
			(size 0.4318 0.4318)
			(layers "F.Cu" "F.Mask" "F.Paste")
			(net "GND")
		)
		(pad "N74" smd circle
			(at 26.948384 -20.959572)
			(size 0.4318 0.4318)
			(layers "F.Cu" "F.Mask" "F.Paste")
			(net "GND")
		)
		(pad "N76" smd circle
			(at 28.665424 -20.959572)
			(size 0.4318 0.4318)
			(layers "F.Cu" "F.Mask" "F.Paste")
			(net "GND")
		)
		(pad "N78" smd circle
			(at 30.382464 -20.959572)
			(size 0.4318 0.4318)
			(layers "F.Cu" "F.Mask" "F.Paste")
			(net "GND")
		)
		(pad "N80" smd circle
			(at 32.099504 -20.959572)
			(size 0.4318 0.4318)
			(layers "F.Cu" "F.Mask" "F.Paste")
			(net "M_A_DQ<23>")
		)
		(pad "N82" smd circle
			(at 33.816544 -20.959572)
			(size 0.4318 0.4318)
			(layers "F.Cu" "F.Mask" "F.Paste")
			(net "M_A_DQ<18>")
		)
		(pad "N84" smd circle
			(at 35.533584 -20.959572)
			(size 0.4318 0.4318)
			(layers "F.Cu" "F.Mask" "F.Paste")
			(net "M_A_DQ<15>")
		)
		(pad "N86" smd custom
			(at 37.250624 -20.959572 270)
			(size 0.10795 0.10795)
			(layers "F.Cu" "F.Mask" "F.Paste")
			(net "M_A_DQ<14>")
			(options
				(clearance outline)
				(anchor circle)
			)
			(primitives
				(gr_poly
					(pts
						(arc
							(start 0.2159 -0.0381)
							(mid 0 -0.254)
							(end -0.2159 -0.0381)
						)
						(arc
							(start -0.2159 0.0381)
							(mid 0 0.254)
							(end 0.2159 0.0381)
						)
					)
					(width 0)
					(fill yes)
				)
			)
		)
		(pad "P1" smd custom
			(at -37.250624 -18.664428 90)
			(size 0.10795 0.10795)
			(layers "F.Cu" "F.Mask" "F.Paste")
			(net "UPI_CPU0_CPU1_P0P0_DN<18>")
			(options
				(clearance outline)
				(anchor circle)
			)
			(primitives
				(gr_poly
					(pts
						(arc
							(start 0.2159 -0.0381)
							(mid 0 -0.254)
							(end -0.2159 -0.0381)
						)
						(arc
							(start -0.2159 0.0381)
							(mid 0 0.254)
							(end 0.2159 0.0381)
						)
					)
					(width 0)
					(fill yes)
				)
			)
		)
		(pad "P3" smd circle
			(at -35.533584 -18.664428)
			(size 0.4318 0.4318)
			(layers "F.Cu" "F.Mask" "F.Paste")
			(net "UPI_CPU0_CPU1_P1P1_DP<19>")
		)
		(pad "P5" smd circle
			(at -33.816544 -18.664428)
			(size 0.4318 0.4318)
			(layers "F.Cu" "F.Mask" "F.Paste")
			(net "PVCCIO_CPU0")
		)
		(pad "P7" smd circle
			(at -32.099504 -18.664428)
			(size 0.4318 0.4318)
			(layers "F.Cu" "F.Mask" "F.Paste")
			(net "UPI_CPU1_CPU0_P1P1_DN<18>")
		)
		(pad "P9" smd circle
			(at -30.382464 -18.664428)
			(size 0.4318 0.4318)
			(layers "F.Cu" "F.Mask" "F.Paste")
			(net "UPI_CPU1_CPU0_P1P1_DN<15>")
		)
		(pad "P11" smd circle
			(at -28.665424 -18.664428)
			(size 0.4318 0.4318)
			(layers "F.Cu" "F.Mask" "F.Paste")
			(net "GND")
		)
		(pad "P13" smd circle
			(at -26.948384 -18.664428)
			(size 0.4318 0.4318)
			(layers "F.Cu" "F.Mask" "F.Paste")
			(net "UPI_CPU1_CPU0_P1P1_DP<10>")
		)
		(pad "P15" smd circle
			(at -25.231598 -18.664428)
			(size 0.4318 0.4318)
			(layers "F.Cu" "F.Mask" "F.Paste")
			(net "GND")
		)
		(pad "P17" smd circle
			(at -23.514558 -18.664428)
			(size 0.4318 0.4318)
			(layers "F.Cu" "F.Mask" "F.Paste")
			(net "UPI_CPU1_CPU0_P1P1_DN<8>")
		)
		(pad "P19" smd circle
			(at -21.797518 -18.664428)
			(size 0.4318 0.4318)
			(layers "F.Cu" "F.Mask" "F.Paste")
			(net "UPI_CPU1_CPU0_P1P1_DP<5>")
		)
		(pad "P21" smd circle
			(at -20.080478 -18.664428)
			(size 0.4318 0.4318)
			(layers "F.Cu" "F.Mask" "F.Paste")
			(net "UPI_CPU1_CPU0_P1P1_DN<3>")
		)
		(pad "P23" smd circle
			(at -18.363438 -18.664428)
			(size 0.4318 0.4318)
			(layers "F.Cu" "F.Mask" "F.Paste")
			(net "M_A_DQ<58>")
		)
		(pad "P25" smd circle
			(at -16.646398 -18.664428)
			(size 0.4318 0.4318)
			(layers "F.Cu" "F.Mask" "F.Paste")
			(net "M_A_DQ<57>")
		)
		(pad "P27" smd circle
			(at -14.929612 -18.664428)
			(size 0.4318 0.4318)
			(layers "F.Cu" "F.Mask" "F.Paste")
			(net "GND")
		)
		(pad "P29" smd circle
			(at -13.212572 -18.664428)
			(size 0.4318 0.4318)
			(layers "F.Cu" "F.Mask" "F.Paste")
			(net "M_A_DQ<55>")
		)
		(pad "P31" smd circle
			(at -11.495532 -18.664428)
			(size 0.4318 0.4318)
			(layers "F.Cu" "F.Mask" "F.Paste")
			(net "M_A_DQ<49>")
		)
		(pad "P33" smd circle
			(at -9.778492 -18.664428)
			(size 0.4318 0.4318)
			(layers "F.Cu" "F.Mask" "F.Paste")
			(net "GND")
		)
		(pad "P35" smd circle
			(at -8.061452 -18.664428)
			(size 0.4318 0.4318)
			(layers "F.Cu" "F.Mask" "F.Paste")
			(net "M_A_DQ<47>")
		)
		(pad "P37" smd circle
			(at -6.344412 -18.664428)
			(size 0.4318 0.4318)
			(layers "F.Cu" "F.Mask" "F.Paste")
			(net "M_A_DQ<41>")
		)
		(pad "P39" smd circle
			(at -4.627626 -18.664428)
			(size 0.4318 0.4318)
			(layers "F.Cu" "F.Mask" "F.Paste")
			(net "GND")
		)
		(pad "P41" smd circle
			(at -2.910586 -18.664428)
			(size 0.4318 0.4318)
			(layers "F.Cu" "F.Mask" "F.Paste")
			(net "M_B_DQ<39>")
		)
		(pad "P43" smd circle
			(at -1.193546 -18.664428)
			(size 0.4318 0.4318)
			(layers "F.Cu" "F.Mask" "F.Paste")
			(net "M_B_DQ<36>")
		)
		(pad "P45" smd circle
			(at 2.052066 -20.464526)
			(size 0.508 0.508)
			(layers "F.Cu" "F.Mask" "F.Paste")
			(net "GND")
		)
		(pad "P47" smd circle
			(at 3.769106 -20.464526)
			(size 0.4318 0.4318)
			(layers "F.Cu" "F.Mask" "F.Paste")
			(net "GND")
		)
		(pad "P49" smd circle
			(at 5.485892 -20.464526)
			(size 0.4318 0.4318)
			(layers "F.Cu" "F.Mask" "F.Paste")
			(net "GND")
		)
		(pad "P51" smd circle
			(at 7.202932 -20.464526)
			(size 0.4318 0.4318)
			(layers "F.Cu" "F.Mask" "F.Paste")
			(net "GND")
		)
		(pad "P53" smd circle
			(at 8.919972 -20.464526)
			(size 0.4318 0.4318)
			(layers "F.Cu" "F.Mask" "F.Paste")
			(net "GND")
		)
		(pad "P55" smd circle
			(at 10.637012 -20.464526)
			(size 0.4318 0.4318)
			(layers "F.Cu" "F.Mask" "F.Paste")
			(net "GND")
		)
		(pad "P57" smd circle
			(at 12.354052 -20.464526)
			(size 0.4318 0.4318)
			(layers "F.Cu" "F.Mask" "F.Paste")
			(net "GND")
		)
		(pad "P59" smd circle
			(at 14.071092 -20.464526)
			(size 0.4318 0.4318)
			(layers "F.Cu" "F.Mask" "F.Paste")
			(net "GND")
		)
		(pad "P61" smd circle
			(at 15.787878 -20.464526)
			(size 0.4318 0.4318)
			(layers "F.Cu" "F.Mask" "F.Paste")
			(net "GND")
		)
		(pad "P63" smd circle
			(at 17.504918 -20.464526)
			(size 0.4318 0.4318)
			(layers "F.Cu" "F.Mask" "F.Paste")
			(net "GND")
		)
		(pad "P65" smd circle
			(at 19.221958 -20.464526)
			(size 0.4318 0.4318)
			(layers "F.Cu" "F.Mask" "F.Paste")
			(net "TP_CPU0_RSVD_265")
		)
		(pad "P67" smd circle
			(at 20.938998 -20.464526)
			(size 0.4318 0.4318)
			(layers "F.Cu" "F.Mask" "F.Paste")
			(net "GND")
		)
		(pad "P69" smd circle
			(at 22.656038 -20.464526)
			(size 0.4318 0.4318)
			(layers "F.Cu" "F.Mask" "F.Paste")
			(net "GND")
		)
		(pad "P71" smd circle
			(at 24.373078 -20.464526)
			(size 0.4318 0.4318)
			(layers "F.Cu" "F.Mask" "F.Paste")
			(net "GND")
		)
		(pad "P73" smd circle
			(at 26.090118 -20.464526)
			(size 0.4318 0.4318)
			(layers "F.Cu" "F.Mask" "F.Paste")
			(net "M_A_DQ<27>")
		)
		(pad "P75" smd circle
			(at 27.806904 -20.464526)
			(size 0.4318 0.4318)
			(layers "F.Cu" "F.Mask" "F.Paste")
			(net "M_A_DQS_DP<3>")
		)
		(pad "P77" smd circle
			(at 29.523944 -20.464526)
			(size 0.4318 0.4318)
			(layers "F.Cu" "F.Mask" "F.Paste")
			(net "M_A_DQ<29>")
		)
		(pad "P79" smd circle
			(at 31.240984 -20.464526)
			(size 0.4318 0.4318)
			(layers "F.Cu" "F.Mask" "F.Paste")
			(net "M_A_DQS_DN<2>")
		)
		(pad "P81" smd circle
			(at 32.958024 -20.464526)
			(size 0.4318 0.4318)
			(layers "F.Cu" "F.Mask" "F.Paste")
			(net "GND")
		)
		(pad "P83" smd circle
			(at 34.675064 -20.464526)
			(size 0.4318 0.4318)
			(layers "F.Cu" "F.Mask" "F.Paste")
			(net "GND")
		)
		(pad "P85" smd circle
			(at 36.392104 -20.464526)
			(size 0.4318 0.4318)
			(layers "F.Cu" "F.Mask" "F.Paste")
			(net "M_A_DQS_DP<1>")
		)
		(pad "R2" smd circle
			(at -36.392104 -18.168874)
			(size 0.4318 0.4318)
			(layers "F.Cu" "F.Mask" "F.Paste")
			(net "GND")
		)
		(pad "R4" smd circle
			(at -34.675064 -18.168874)
			(size 0.4318 0.4318)
			(layers "F.Cu" "F.Mask" "F.Paste")
			(net "GND")
		)
		(pad "R6" smd circle
			(at -32.958024 -18.168874)
			(size 0.4318 0.4318)
			(layers "F.Cu" "F.Mask" "F.Paste")
			(net "UPI_CPU1_CPU0_P1P1_DP<19>")
		)
		(pad "R8" smd circle
			(at -31.240984 -18.168874)
			(size 0.4318 0.4318)
			(layers "F.Cu" "F.Mask" "F.Paste")
			(net "UPI_CPU1_CPU0_P1P1_DP<16>")
		)
		(pad "R10" smd circle
			(at -29.523944 -18.168874)
			(size 0.4318 0.4318)
			(layers "F.Cu" "F.Mask" "F.Paste")
			(net "UPI_CPU1_CPU0_P1P1_DN<14>")
		)
		(pad "R12" smd circle
			(at -27.806904 -18.168874)
			(size 0.4318 0.4318)
			(layers "F.Cu" "F.Mask" "F.Paste")
			(net "UPI_CPU1_CPU0_P1P1_DN<10>")
		)
		(pad "R14" smd circle
			(at -26.090118 -18.168874)
			(size 0.4318 0.4318)
			(layers "F.Cu" "F.Mask" "F.Paste")
			(net "GND")
		)
		(pad "R16" smd circle
			(at -24.373078 -18.168874)
			(size 0.4318 0.4318)
			(layers "F.Cu" "F.Mask" "F.Paste")
			(net "UPI_CPU1_CPU0_P1P1_DN<9>")
		)
		(pad "R18" smd circle
			(at -22.656038 -18.168874)
			(size 0.4318 0.4318)
			(layers "F.Cu" "F.Mask" "F.Paste")
			(net "GND")
		)
		(pad "R20" smd circle
			(at -20.938998 -18.168874)
			(size 0.4318 0.4318)
			(layers "F.Cu" "F.Mask" "F.Paste")
			(net "UPI_CPU1_CPU0_P1P1_DN<5>")
		)
		(pad "R22" smd circle
			(at -19.221958 -18.168874)
			(size 0.4318 0.4318)
			(layers "F.Cu" "F.Mask" "F.Paste")
			(net "GND")
		)
		(pad "R24" smd circle
			(at -17.504918 -18.168874)
			(size 0.4318 0.4318)
			(layers "F.Cu" "F.Mask" "F.Paste")
			(net "M_A_DQS_DP<7>")
		)
		(pad "R26" smd circle
			(at -15.787878 -18.168874)
			(size 0.4318 0.4318)
			(layers "F.Cu" "F.Mask" "F.Paste")
			(net "GND")
		)
		(pad "R28" smd circle
			(at -14.071092 -18.168874)
			(size 0.4318 0.4318)
			(layers "F.Cu" "F.Mask" "F.Paste")
			(net "GND")
		)
		(pad "R30" smd circle
			(at -12.354052 -18.168874)
			(size 0.4318 0.4318)
			(layers "F.Cu" "F.Mask" "F.Paste")
			(net "M_A_DQS_DN<6>")
		)
		(pad "R32" smd circle
			(at -10.637012 -18.168874)
			(size 0.4318 0.4318)
			(layers "F.Cu" "F.Mask" "F.Paste")
			(net "GND")
		)
		(pad "R34" smd circle
			(at -8.919972 -18.168874)
			(size 0.4318 0.4318)
			(layers "F.Cu" "F.Mask" "F.Paste")
			(net "GND")
		)
		(pad "R36" smd circle
			(at -7.202932 -18.168874)
			(size 0.4318 0.4318)
			(layers "F.Cu" "F.Mask" "F.Paste")
			(net "M_A_DQS_DN<5>")
		)
		(pad "R38" smd circle
			(at -5.485892 -18.168874)
			(size 0.4318 0.4318)
			(layers "F.Cu" "F.Mask" "F.Paste")
			(net "GND")
		)
		(pad "R40" smd circle
			(at -3.769106 -18.168874)
			(size 0.4318 0.4318)
			(layers "F.Cu" "F.Mask" "F.Paste")
			(net "GND")
		)
		(pad "R42" smd circle
			(at -2.052066 -18.168874)
			(size 0.4318 0.4318)
			(layers "F.Cu" "F.Mask" "F.Paste")
			(net "M_B_DQS_DP<4>")
		)
		(pad "R46" smd circle
			(at 2.910586 -19.968972)
			(size 0.4318 0.4318)
			(layers "F.Cu" "F.Mask" "F.Paste")
			(net "M_B_CS_N<7>")
		)
		(pad "R48" smd circle
			(at 4.627626 -19.968972)
			(size 0.4318 0.4318)
			(layers "F.Cu" "F.Mask" "F.Paste")
			(net "M_B_ODT<1>")
		)
		(pad "R50" smd circle
			(at 6.344412 -19.968972)
			(size 0.4318 0.4318)
			(layers "F.Cu" "F.Mask" "F.Paste")
			(net "M_B_CS_N<1>")
		)
		(pad "R52" smd circle
			(at 8.061452 -19.968972)
			(size 0.4318 0.4318)
			(layers "F.Cu" "F.Mask" "F.Paste")
			(net "M_B_MA<16>")
		)
		(pad "R54" smd circle
			(at 9.778492 -19.968972)
			(size 0.4318 0.4318)
			(layers "F.Cu" "F.Mask" "F.Paste")
			(net "M_B_CLK_DN<1>")
		)
		(pad "R56" smd circle
			(at 11.495532 -19.968972)
			(size 0.4318 0.4318)
			(layers "F.Cu" "F.Mask" "F.Paste")
			(net "M_B_CLK_DN<3>")
		)
		(pad "R58" smd circle
			(at 13.212572 -19.968972)
			(size 0.4318 0.4318)
			(layers "F.Cu" "F.Mask" "F.Paste")
			(net "M_B_MA<5>")
		)
		(pad "R60" smd circle
			(at 14.929612 -19.968972)
			(size 0.4318 0.4318)
			(layers "F.Cu" "F.Mask" "F.Paste")
			(net "M_B_MA<11>")
		)
		(pad "R62" smd circle
			(at 16.646398 -19.968972)
			(size 0.4318 0.4318)
			(layers "F.Cu" "F.Mask" "F.Paste")
			(net "TP_CPU0_RSVD_264")
		)
		(pad "R64" smd circle
			(at 18.363438 -19.968972)
			(size 0.4318 0.4318)
			(layers "F.Cu" "F.Mask" "F.Paste")
			(net "M_B_CKE<1>")
		)
		(pad "R66" smd circle
			(at 20.080478 -19.968972)
			(size 0.4318 0.4318)
			(layers "F.Cu" "F.Mask" "F.Paste")
			(net "TP_CPU0_RSVD_263")
		)
		(pad "R68" smd circle
			(at 21.797518 -19.968972)
			(size 0.4318 0.4318)
			(layers "F.Cu" "F.Mask" "F.Paste")
			(net "GND")
		)
		(pad "R70" smd circle
			(at 23.514558 -19.968972)
			(size 0.4318 0.4318)
			(layers "F.Cu" "F.Mask" "F.Paste")
			(net "M_C_DQ<18>")
		)
		(pad "R72" smd circle
			(at 25.231598 -19.968972)
			(size 0.4318 0.4318)
			(layers "F.Cu" "F.Mask" "F.Paste")
			(net "GND")
		)
		(pad "R74" smd circle
			(at 26.948384 -19.968972)
			(size 0.4318 0.4318)
			(layers "F.Cu" "F.Mask" "F.Paste")
			(net "M_A_DQ<31>")
		)
		(pad "R76" smd circle
			(at 28.665424 -19.968972)
			(size 0.4318 0.4318)
			(layers "F.Cu" "F.Mask" "F.Paste")
			(net "M_A_DQ<25>")
		)
		(pad "R78" smd circle
			(at 30.382464 -19.968972)
			(size 0.4318 0.4318)
			(layers "F.Cu" "F.Mask" "F.Paste")
			(net "GND")
		)
		(pad "R80" smd circle
			(at 32.099504 -19.968972)
			(size 0.4318 0.4318)
			(layers "F.Cu" "F.Mask" "F.Paste")
			(net "M_A_DQS_DP<2>")
		)
		(pad "R82" smd circle
			(at 33.816544 -19.968972)
			(size 0.4318 0.4318)
			(layers "F.Cu" "F.Mask" "F.Paste")
			(net "M_A_DQ<22>")
		)
		(pad "R84" smd circle
			(at 35.533584 -19.968972)
			(size 0.4318 0.4318)
			(layers "F.Cu" "F.Mask" "F.Paste")
			(net "M_A_DQS_DN<1>")
		)
		(pad "R86" smd custom
			(at 37.250624 -19.968972 270)
			(size 0.10795 0.10795)
			(layers "F.Cu" "F.Mask" "F.Paste")
			(net "GND")
			(options
				(clearance outline)
				(anchor circle)
			)
			(primitives
				(gr_poly
					(pts
						(arc
							(start 0.2159 -0.0381)
							(mid 0 -0.254)
							(end -0.2159 -0.0381)
						)
						(arc
							(start -0.2159 0.0381)
							(mid 0 0.254)
							(end 0.2159 0.0381)
						)
					)
					(width 0)
					(fill yes)
				)
			)
		)
		(pad "T1" smd custom
			(at -37.250624 -17.673574 90)
			(size 0.10795 0.10795)
			(layers "F.Cu" "F.Mask" "F.Paste")
			(net "UPI_CPU0_CPU1_P0P0_DP<18>")
			(options
				(clearance outline)
				(anchor circle)
			)
			(primitives
				(gr_poly
					(pts
						(arc
							(start 0.2159 -0.0381)
							(mid 0 -0.254)
							(end -0.2159 -0.0381)
						)
						(arc
							(start -0.2159 0.0381)
							(mid 0 0.254)
							(end 0.2159 0.0381)
						)
					)
					(width 0)
					(fill yes)
				)
			)
		)
		(pad "T3" smd circle
			(at -35.533584 -17.673574)
			(size 0.4318 0.4318)
			(layers "F.Cu" "F.Mask" "F.Paste")
			(net "PVCCIO_CPU0")
		)
		(pad "T5" smd circle
			(at -33.816544 -17.673574)
			(size 0.4318 0.4318)
			(layers "F.Cu" "F.Mask" "F.Paste")
			(net "UPI_CPU1_CPU0_P1P1_DN<19>")
		)
		(pad "T7" smd circle
			(at -32.099504 -17.673574)
			(size 0.4318 0.4318)
			(layers "F.Cu" "F.Mask" "F.Paste")
			(net "UPI_CPU1_CPU0_P1P1_DP<18>")
		)
		(pad "T9" smd circle
			(at -30.382464 -17.673574)
			(size 0.4318 0.4318)
			(layers "F.Cu" "F.Mask" "F.Paste")
			(net "UPI_CPU1_CPU0_P1P1_DN<16>")
		)
		(pad "T11" smd circle
			(at -28.665424 -17.673574)
			(size 0.4318 0.4318)
			(layers "F.Cu" "F.Mask" "F.Paste")
			(net "UPI_CPU1_CPU0_P1P1_DP<13>")
		)
		(pad "T13" smd circle
			(at -26.948384 -17.673574)
			(size 0.4318 0.4318)
			(layers "F.Cu" "F.Mask" "F.Paste")
			(net "GND")
		)
		(pad "T15" smd circle
			(at -25.231598 -17.673574)
			(size 0.4318 0.4318)
			(layers "F.Cu" "F.Mask" "F.Paste")
			(net "UPI_CPU1_CPU0_P1P1_DP<9>")
		)
		(pad "T17" smd circle
			(at -23.514558 -17.673574)
			(size 0.4318 0.4318)
			(layers "F.Cu" "F.Mask" "F.Paste")
			(net "GND")
		)
		(pad "T19" smd circle
			(at -21.797518 -17.673574)
			(size 0.4318 0.4318)
			(layers "F.Cu" "F.Mask" "F.Paste")
			(net "UPI_CPU1_CPU0_P1P1_DP<4>")
		)
		(pad "T21" smd circle
			(at -20.080478 -17.673574)
			(size 0.4318 0.4318)
			(layers "F.Cu" "F.Mask" "F.Paste")
			(net "UPI_CPU1_CPU0_P1P1_DP<3>")
		)
		(pad "T23" smd circle
			(at -18.363438 -17.673574)
			(size 0.4318 0.4318)
			(layers "F.Cu" "F.Mask" "F.Paste")
			(net "M_A_DQ<59>")
		)
		(pad "T25" smd circle
			(at -16.646398 -17.673574)
			(size 0.4318 0.4318)
			(layers "F.Cu" "F.Mask" "F.Paste")
			(net "GND")
		)
		(pad "T27" smd circle
			(at -14.929612 -17.673574)
			(size 0.4318 0.4318)
			(layers "F.Cu" "F.Mask" "F.Paste")
			(net "M_B_DQS_DN<16>")
		)
		(pad "T29" smd circle
			(at -13.212572 -17.673574)
			(size 0.4318 0.4318)
			(layers "F.Cu" "F.Mask" "F.Paste")
			(net "GND")
		)
		(pad "T31" smd circle
			(at -11.495532 -17.673574)
			(size 0.4318 0.4318)
			(layers "F.Cu" "F.Mask" "F.Paste")
			(net "GND")
		)
		(pad "T33" smd circle
			(at -9.778492 -17.673574)
			(size 0.4318 0.4318)
			(layers "F.Cu" "F.Mask" "F.Paste")
			(net "M_C_DQS_DN<14>")
		)
		(pad "T35" smd circle
			(at -8.061452 -17.673574)
			(size 0.4318 0.4318)
			(layers "F.Cu" "F.Mask" "F.Paste")
			(net "GND")
		)
		(pad "T37" smd circle
			(at -6.344412 -17.673574)
			(size 0.4318 0.4318)
			(layers "F.Cu" "F.Mask" "F.Paste")
			(net "GND")
		)
		(pad "T39" smd circle
			(at -4.627626 -17.673574)
			(size 0.4318 0.4318)
			(layers "F.Cu" "F.Mask" "F.Paste")
			(net "M_C_DQS_DN<13>")
		)
		(pad "T41" smd circle
			(at -2.910586 -17.673574)
			(size 0.4318 0.4318)
			(layers "F.Cu" "F.Mask" "F.Paste")
			(net "GND")
		)
		(pad "T43" smd circle
			(at -1.193546 -17.673574)
			(size 0.4318 0.4318)
			(layers "F.Cu" "F.Mask" "F.Paste")
			(net "M_B_DQ<37>")
		)
		(pad "T45" smd circle
			(at 2.052066 -19.473926)
			(size 0.508 0.508)
			(layers "F.Cu" "F.Mask" "F.Paste")
			(net "M_C_CS_N<6>")
		)
		(pad "T47" smd circle
			(at 3.769106 -19.473926)
			(size 0.4318 0.4318)
			(layers "F.Cu" "F.Mask" "F.Paste")
			(net "M_B_ODT<3>")
		)
		(pad "T49" smd circle
			(at 5.485892 -19.473926)
			(size 0.4318 0.4318)
			(layers "F.Cu" "F.Mask" "F.Paste")
			(net "M_B_CS_N<5>")
		)
		(pad "T51" smd circle
			(at 7.202932 -19.473926)
			(size 0.4318 0.4318)
			(layers "F.Cu" "F.Mask" "F.Paste")
			(net "M_B_MA<14>")
		)
		(pad "T53" smd circle
			(at 8.919972 -19.473926)
			(size 0.4318 0.4318)
			(layers "F.Cu" "F.Mask" "F.Paste")
			(net "M_B_BA<0>")
		)
		(pad "T55" smd circle
			(at 10.637012 -19.473926)
			(size 0.4318 0.4318)
			(layers "F.Cu" "F.Mask" "F.Paste")
			(net "M_B_CLK_DP<1>")
		)
		(pad "T57" smd circle
			(at 12.354052 -19.473926)
			(size 0.4318 0.4318)
			(layers "F.Cu" "F.Mask" "F.Paste")
			(net "M_B_CLK_DP<3>")
		)
		(pad "T59" smd circle
			(at 14.071092 -19.473926)
			(size 0.4318 0.4318)
			(layers "F.Cu" "F.Mask" "F.Paste")
			(net "M_B_MA<6>")
		)
		(pad "T61" smd circle
			(at 15.787878 -19.473926)
			(size 0.4318 0.4318)
			(layers "F.Cu" "F.Mask" "F.Paste")
			(net "M_B_MA<12>")
		)
		(pad "T63" smd circle
			(at 17.504918 -19.473926)
			(size 0.4318 0.4318)
			(layers "F.Cu" "F.Mask" "F.Paste")
			(net "M_B_ACT_N")
		)
		(pad "T65" smd circle
			(at 19.221958 -19.473926)
			(size 0.4318 0.4318)
			(layers "F.Cu" "F.Mask" "F.Paste")
			(net "GND")
		)
		(pad "T67" smd circle
			(at 20.938998 -19.473926)
			(size 0.4318 0.4318)
			(layers "F.Cu" "F.Mask" "F.Paste")
			(net "TP_CPU0_RSVD_262")
		)
		(pad "T69" smd circle
			(at 22.656038 -19.473926)
			(size 0.4318 0.4318)
			(layers "F.Cu" "F.Mask" "F.Paste")
			(net "M_C_DQ<19>")
		)
		(pad "T71" smd circle
			(at 24.373078 -19.473926)
			(size 0.4318 0.4318)
			(layers "F.Cu" "F.Mask" "F.Paste")
			(net "M_C_DQ<22>")
		)
		(pad "T73" smd circle
			(at 26.090118 -19.473926)
			(size 0.4318 0.4318)
			(layers "F.Cu" "F.Mask" "F.Paste")
			(net "GND")
		)
		(pad "T75" smd circle
			(at 27.806904 -19.473926)
			(size 0.4318 0.4318)
			(layers "F.Cu" "F.Mask" "F.Paste")
			(net "M_A_DQS_DN<3>")
		)
		(pad "T77" smd circle
			(at 29.523944 -19.473926)
			(size 0.4318 0.4318)
			(layers "F.Cu" "F.Mask" "F.Paste")
			(net "GND")
		)
		(pad "T79" smd circle
			(at 31.240984 -19.473926)
			(size 0.4318 0.4318)
			(layers "F.Cu" "F.Mask" "F.Paste")
			(net "M_A_DQ<17>")
		)
		(pad "T81" smd circle
			(at 32.958024 -19.473926)
			(size 0.4318 0.4318)
			(layers "F.Cu" "F.Mask" "F.Paste")
			(net "M_A_DQS_DP<11>")
		)
		(pad "T83" smd circle
			(at 34.675064 -19.473926)
			(size 0.4318 0.4318)
			(layers "F.Cu" "F.Mask" "F.Paste")
			(net "GND")
		)
		(pad "T85" smd circle
			(at 36.392104 -19.473926)
			(size 0.4318 0.4318)
			(layers "F.Cu" "F.Mask" "F.Paste")
			(net "GND")
		)
		(pad "U2" smd circle
			(at -36.392104 -17.178528)
			(size 0.4318 0.4318)
			(layers "F.Cu" "F.Mask" "F.Paste")
			(net "GND")
		)
		(pad "U4" smd circle
			(at -34.675064 -17.178528)
			(size 0.4318 0.4318)
			(layers "F.Cu" "F.Mask" "F.Paste")
			(net "GND")
		)
		(pad "U6" smd circle
			(at -32.958024 -17.178528)
			(size 0.4318 0.4318)
			(layers "F.Cu" "F.Mask" "F.Paste")
			(net "GND")
		)
		(pad "U8" smd circle
			(at -31.240984 -17.178528)
			(size 0.4318 0.4318)
			(layers "F.Cu" "F.Mask" "F.Paste")
			(net "UPI_CPU1_CPU0_P1P1_DP<17>")
		)
		(pad "U10" smd circle
			(at -29.523944 -17.178528)
			(size 0.4318 0.4318)
			(layers "F.Cu" "F.Mask" "F.Paste")
			(net "UPI_CPU1_CPU0_P1P1_DP<14>")
		)
		(pad "U12" smd circle
			(at -27.806904 -17.178528)
			(size 0.4318 0.4318)
			(layers "F.Cu" "F.Mask" "F.Paste")
			(net "UPI_CPU1_CPU0_P1P1_DN<13>")
		)
		(pad "U14" smd circle
			(at -26.090118 -17.178528)
			(size 0.4318 0.4318)
			(layers "F.Cu" "F.Mask" "F.Paste")
			(net "PVCCIO_CPU0")
		)
		(pad "U16" smd circle
			(at -24.373078 -17.178528)
			(size 0.4318 0.4318)
			(layers "F.Cu" "F.Mask" "F.Paste")
			(net "UPI_CPU1_CPU0_P1P1_DN<7>")
		)
		(pad "U18" smd circle
			(at -22.656038 -17.178528)
			(size 0.4318 0.4318)
			(layers "F.Cu" "F.Mask" "F.Paste")
			(net "UPI_CPU1_CPU0_P1P1_DN<4>")
		)
		(pad "U20" smd circle
			(at -20.938998 -17.178528)
			(size 0.4318 0.4318)
			(layers "F.Cu" "F.Mask" "F.Paste")
			(net "GND")
		)
		(pad "U22" smd circle
			(at -19.221958 -17.178528)
			(size 0.4318 0.4318)
			(layers "F.Cu" "F.Mask" "F.Paste")
			(net "GND")
		)
		(pad "U24" smd circle
			(at -17.504918 -17.178528)
			(size 0.4318 0.4318)
			(layers "F.Cu" "F.Mask" "F.Paste")
			(net "GND")
		)
		(pad "U26" smd circle
			(at -15.787878 -17.178528)
			(size 0.4318 0.4318)
			(layers "F.Cu" "F.Mask" "F.Paste")
			(net "M_B_DQ<62>")
		)
		(pad "U28" smd circle
			(at -14.071092 -17.178528)
			(size 0.4318 0.4318)
			(layers "F.Cu" "F.Mask" "F.Paste")
			(net "M_B_DQ<56>")
		)
		(pad "U30" smd circle
			(at -12.354052 -17.178528)
			(size 0.4318 0.4318)
			(layers "F.Cu" "F.Mask" "F.Paste")
			(net "GND")
		)
		(pad "U32" smd circle
			(at -10.637012 -17.178528)
			(size 0.4318 0.4318)
			(layers "F.Cu" "F.Mask" "F.Paste")
			(net "M_C_DQ<46>")
		)
		(pad "U34" smd circle
			(at -8.919972 -17.178528)
			(size 0.4318 0.4318)
			(layers "F.Cu" "F.Mask" "F.Paste")
			(net "M_C_DQ<40>")
		)
		(pad "U36" smd circle
			(at -7.202932 -17.178528)
			(size 0.4318 0.4318)
			(layers "F.Cu" "F.Mask" "F.Paste")
			(net "GND")
		)
		(pad "U38" smd circle
			(at -5.485892 -17.178528)
			(size 0.4318 0.4318)
			(layers "F.Cu" "F.Mask" "F.Paste")
			(net "M_C_DQ<38>")
		)
		(pad "U40" smd circle
			(at -3.769106 -17.178528)
			(size 0.4318 0.4318)
			(layers "F.Cu" "F.Mask" "F.Paste")
			(net "M_C_DQ<32>")
		)
		(pad "U42" smd circle
			(at -2.052066 -17.178528)
			(size 0.4318 0.4318)
			(layers "F.Cu" "F.Mask" "F.Paste")
			(net "GND")
		)
		(pad "U46" smd circle
			(at 2.910586 -18.978372)
			(size 0.4318 0.4318)
			(layers "F.Cu" "F.Mask" "F.Paste")
			(net "PVDDQ_ABC")
		)
		(pad "U48" smd circle
			(at 4.627626 -18.978372)
			(size 0.4318 0.4318)
			(layers "F.Cu" "F.Mask" "F.Paste")
			(net "PVDDQ_ABC")
		)
		(pad "U50" smd circle
			(at 6.344412 -18.978372)
			(size 0.4318 0.4318)
			(layers "F.Cu" "F.Mask" "F.Paste")
			(net "PVDDQ_ABC")
		)
		(pad "U52" smd circle
			(at 8.061452 -18.978372)
			(size 0.4318 0.4318)
			(layers "F.Cu" "F.Mask" "F.Paste")
			(net "PVDDQ_ABC")
		)
		(pad "U54" smd circle
			(at 9.778492 -18.978372)
			(size 0.4318 0.4318)
			(layers "F.Cu" "F.Mask" "F.Paste")
			(net "PVDDQ_ABC")
		)
		(pad "U56" smd circle
			(at 11.495532 -18.978372)
			(size 0.4318 0.4318)
			(layers "F.Cu" "F.Mask" "F.Paste")
			(net "PVDDQ_ABC")
		)
		(pad "U58" smd circle
			(at 13.212572 -18.978372)
			(size 0.4318 0.4318)
			(layers "F.Cu" "F.Mask" "F.Paste")
			(net "PVDDQ_ABC")
		)
		(pad "U60" smd circle
			(at 14.929612 -18.978372)
			(size 0.4318 0.4318)
			(layers "F.Cu" "F.Mask" "F.Paste")
			(net "PVDDQ_ABC")
		)
		(pad "U62" smd circle
			(at 16.646398 -18.978372)
			(size 0.4318 0.4318)
			(layers "F.Cu" "F.Mask" "F.Paste")
			(net "PVDDQ_ABC")
		)
		(pad "U64" smd circle
			(at 18.363438 -18.978372)
			(size 0.4318 0.4318)
			(layers "F.Cu" "F.Mask" "F.Paste")
			(net "M_ABC_RST_N")
		)
		(pad "U66" smd circle
			(at 20.080478 -18.978372)
			(size 0.4318 0.4318)
			(layers "F.Cu" "F.Mask" "F.Paste")
			(net "TP_CPU0_RSVD_261")
		)
		(pad "U68" smd circle
			(at 21.797518 -18.978372)
			(size 0.4318 0.4318)
			(layers "F.Cu" "F.Mask" "F.Paste")
			(net "GND")
		)
		(pad "U70" smd circle
			(at 23.514558 -18.978372)
			(size 0.4318 0.4318)
			(layers "F.Cu" "F.Mask" "F.Paste")
			(net "GND")
		)
		(pad "U72" smd circle
			(at 25.231598 -18.978372)
			(size 0.4318 0.4318)
			(layers "F.Cu" "F.Mask" "F.Paste")
			(net "M_C_DQS_DN<11>")
		)
		(pad "U74" smd circle
			(at 26.948384 -18.978372)
			(size 0.4318 0.4318)
			(layers "F.Cu" "F.Mask" "F.Paste")
			(net "GND")
		)
		(pad "U76" smd circle
			(at 28.665424 -18.978372)
			(size 0.4318 0.4318)
			(layers "F.Cu" "F.Mask" "F.Paste")
			(net "GND")
		)
		(pad "U78" smd circle
			(at 30.382464 -18.978372)
			(size 0.4318 0.4318)
			(layers "F.Cu" "F.Mask" "F.Paste")
			(net "GND")
		)
		(pad "U80" smd circle
			(at 32.099504 -18.978372)
			(size 0.4318 0.4318)
			(layers "F.Cu" "F.Mask" "F.Paste")
			(net "GND")
		)
		(pad "U82" smd circle
			(at 33.816544 -18.978372)
			(size 0.4318 0.4318)
			(layers "F.Cu" "F.Mask" "F.Paste")
			(net "M_A_DQS_DN<11>")
		)
		(pad "U84" smd circle
			(at 35.533584 -18.978372)
			(size 0.4318 0.4318)
			(layers "F.Cu" "F.Mask" "F.Paste")
			(net "M_A_DQS_DN<10>")
		)
		(pad "U86" smd custom
			(at 37.250624 -18.978372 270)
			(size 0.10795 0.10795)
			(layers "F.Cu" "F.Mask" "F.Paste")
			(net "GND")
			(options
				(clearance outline)
				(anchor circle)
			)
			(primitives
				(gr_poly
					(pts
						(arc
							(start 0.2159 -0.0381)
							(mid 0 -0.254)
							(end -0.2159 -0.0381)
						)
						(arc
							(start -0.2159 0.0381)
							(mid 0 0.254)
							(end 0.2159 0.0381)
						)
					)
					(width 0)
					(fill yes)
				)
			)
		)
		(pad "V1" smd custom
			(at -37.250624 -16.683228 90)
			(size 0.10795 0.10795)
			(layers "F.Cu" "F.Mask" "F.Paste")
			(net "GND")
			(options
				(clearance outline)
				(anchor circle)
			)
			(primitives
				(gr_poly
					(pts
						(arc
							(start 0.2159 -0.0381)
							(mid 0 -0.254)
							(end -0.2159 -0.0381)
						)
						(arc
							(start -0.2159 0.0381)
							(mid 0 0.254)
							(end 0.2159 0.0381)
						)
					)
					(width 0)
					(fill yes)
				)
			)
		)
		(pad "V3" smd circle
			(at -35.533584 -16.683228)
			(size 0.4318 0.4318)
			(layers "F.Cu" "F.Mask" "F.Paste")
			(net "UPI_CPU0_CPU1_P0P0_DN<17>")
		)
		(pad "V5" smd circle
			(at -33.816544 -16.683228)
			(size 0.4318 0.4318)
			(layers "F.Cu" "F.Mask" "F.Paste")
			(net "GND")
		)
		(pad "V7" smd circle
			(at -32.099504 -16.683228)
			(size 0.4318 0.4318)
			(layers "F.Cu" "F.Mask" "F.Paste")
			(net "UPI_CPU1_CPU0_P1P1_DN<17>")
		)
		(pad "V9" smd circle
			(at -30.382464 -16.683228)
			(size 0.4318 0.4318)
			(layers "F.Cu" "F.Mask" "F.Paste")
			(net "GND")
		)
		(pad "V11" smd circle
			(at -28.665424 -16.683228)
			(size 0.4318 0.4318)
			(layers "F.Cu" "F.Mask" "F.Paste")
			(net "GND")
		)
		(pad "V13" smd circle
			(at -26.948384 -16.683228)
			(size 0.4318 0.4318)
			(layers "F.Cu" "F.Mask" "F.Paste")
			(net "GND")
		)
		(pad "V15" smd circle
			(at -25.231598 -16.683228)
			(size 0.4318 0.4318)
			(layers "F.Cu" "F.Mask" "F.Paste")
			(net "GND")
		)
		(pad "V17" smd circle
			(at -23.514558 -16.683228)
			(size 0.4318 0.4318)
			(layers "F.Cu" "F.Mask" "F.Paste")
			(net "UPI_CPU1_CPU0_P1P1_DP<6>")
		)
		(pad "V19" smd circle
			(at -21.797518 -16.683228)
			(size 0.4318 0.4318)
			(layers "F.Cu" "F.Mask" "F.Paste")
			(net "UPI_CPU1_CPU0_P1P1_DN<2>")
		)
		(pad "V21" smd circle
			(at -20.080478 -16.683228)
			(size 0.4318 0.4318)
			(layers "F.Cu" "F.Mask" "F.Paste")
			(net "GND")
		)
		(pad "V23" smd circle
			(at -18.363438 -16.683228)
			(size 0.4318 0.4318)
			(layers "F.Cu" "F.Mask" "F.Paste")
			(net "GND")
		)
		(pad "V25" smd circle
			(at -16.646398 -16.683228)
			(size 0.4318 0.4318)
			(layers "F.Cu" "F.Mask" "F.Paste")
			(net "M_B_DQ<58>")
		)
		(pad "V27" smd circle
			(at -14.929612 -16.683228)
			(size 0.4318 0.4318)
			(layers "F.Cu" "F.Mask" "F.Paste")
			(net "M_B_DQS_DP<16>")
		)
		(pad "V29" smd circle
			(at -13.212572 -16.683228)
			(size 0.4318 0.4318)
			(layers "F.Cu" "F.Mask" "F.Paste")
			(net "M_B_DQ<60>")
		)
		(pad "V31" smd circle
			(at -11.495532 -16.683228)
			(size 0.4318 0.4318)
			(layers "F.Cu" "F.Mask" "F.Paste")
			(net "M_C_DQ<42>")
		)
		(pad "V33" smd circle
			(at -9.778492 -16.683228)
			(size 0.4318 0.4318)
			(layers "F.Cu" "F.Mask" "F.Paste")
			(net "M_C_DQS_DP<14>")
		)
		(pad "V35" smd circle
			(at -8.061452 -16.683228)
			(size 0.4318 0.4318)
			(layers "F.Cu" "F.Mask" "F.Paste")
			(net "M_C_DQ<44>")
		)
		(pad "V37" smd circle
			(at -6.344412 -16.683228)
			(size 0.4318 0.4318)
			(layers "F.Cu" "F.Mask" "F.Paste")
			(net "M_C_DQ<34>")
		)
		(pad "V39" smd circle
			(at -4.627626 -16.683228)
			(size 0.4318 0.4318)
			(layers "F.Cu" "F.Mask" "F.Paste")
			(net "M_C_DQS_DP<13>")
		)
		(pad "V41" smd circle
			(at -2.910586 -16.683228)
			(size 0.4318 0.4318)
			(layers "F.Cu" "F.Mask" "F.Paste")
			(net "M_C_DQ<36>")
		)
		(pad "V43" smd circle
			(at -1.193546 -16.683228)
			(size 0.4318 0.4318)
			(layers "F.Cu" "F.Mask" "F.Paste")
			(net "GND")
		)
		(pad "V45" smd circle
			(at 2.052066 -18.483072)
			(size 0.508 0.508)
			(layers "F.Cu" "F.Mask" "F.Paste")
			(net "M_C_CS_N<7>")
		)
		(pad "V47" smd circle
			(at 3.769106 -18.483072)
			(size 0.4318 0.4318)
			(layers "F.Cu" "F.Mask" "F.Paste")
			(net "M_B_CS_N<3>")
		)
		(pad "V49" smd circle
			(at 5.485892 -18.483072)
			(size 0.4318 0.4318)
			(layers "F.Cu" "F.Mask" "F.Paste")
			(net "M_C_ODT<2>")
		)
		(pad "V51" smd circle
			(at 7.202932 -18.483072)
			(size 0.4318 0.4318)
			(layers "F.Cu" "F.Mask" "F.Paste")
			(net "M_C_CS_N<0>")
		)
		(pad "V53" smd circle
			(at 8.919972 -18.483072)
			(size 0.4318 0.4318)
			(layers "F.Cu" "F.Mask" "F.Paste")
			(net "M_C_PAR")
		)
		(pad "V55" smd circle
			(at 10.637012 -18.483072)
			(size 0.4318 0.4318)
			(layers "F.Cu" "F.Mask" "F.Paste")
			(net "M_C_CLK_DP<1>")
		)
		(pad "V57" smd circle
			(at 12.354052 -18.483072)
			(size 0.4318 0.4318)
			(layers "F.Cu" "F.Mask" "F.Paste")
			(net "M_C_CLK_DP<3>")
		)
		(pad "V59" smd circle
			(at 14.071092 -18.483072)
			(size 0.4318 0.4318)
			(layers "F.Cu" "F.Mask" "F.Paste")
			(net "M_C_MA<5>")
		)
		(pad "V61" smd circle
			(at 15.787878 -18.483072)
			(size 0.4318 0.4318)
			(layers "F.Cu" "F.Mask" "F.Paste")
			(net "M_B_MA<7>")
		)
		(pad "V63" smd circle
			(at 17.504918 -18.483072)
			(size 0.4318 0.4318)
			(layers "F.Cu" "F.Mask" "F.Paste")
			(net "M_C_CKE<2>")
		)
		(pad "V65" smd circle
			(at 19.221958 -18.483072)
			(size 0.4318 0.4318)
			(layers "F.Cu" "F.Mask" "F.Paste")
			(net "TP_CPU0_RSVD_260")
		)
		(pad "V67" smd circle
			(at 20.938998 -18.483072)
			(size 0.4318 0.4318)
			(layers "F.Cu" "F.Mask" "F.Paste")
			(net "TP_CPU0_RSVD_259")
		)
		(pad "V69" smd circle
			(at 22.656038 -18.483072)
			(size 0.4318 0.4318)
			(layers "F.Cu" "F.Mask" "F.Paste")
			(net "M_C_DQ<23>")
		)
		(pad "V71" smd circle
			(at 24.373078 -18.483072)
			(size 0.4318 0.4318)
			(layers "F.Cu" "F.Mask" "F.Paste")
			(net "M_C_DQS_DP<11>")
		)
		(pad "V73" smd circle
			(at 26.090118 -18.483072)
			(size 0.4318 0.4318)
			(layers "F.Cu" "F.Mask" "F.Paste")
			(net "GND")
		)
		(pad "V75" smd circle
			(at 27.806904 -18.483072)
			(size 0.4318 0.4318)
			(layers "F.Cu" "F.Mask" "F.Paste")
			(net "GND")
		)
		(pad "V77" smd circle
			(at 29.523944 -18.483072)
			(size 0.4318 0.4318)
			(layers "F.Cu" "F.Mask" "F.Paste")
			(net "GND")
		)
		(pad "V79" smd circle
			(at 31.240984 -18.483072)
			(size 0.4318 0.4318)
			(layers "F.Cu" "F.Mask" "F.Paste")
			(net "M_A_DQ<21>")
		)
		(pad "V81" smd circle
			(at 32.958024 -18.483072)
			(size 0.4318 0.4318)
			(layers "F.Cu" "F.Mask" "F.Paste")
			(net "M_A_DQ<16>")
		)
		(pad "V83" smd circle
			(at 34.675064 -18.483072)
			(size 0.4318 0.4318)
			(layers "F.Cu" "F.Mask" "F.Paste")
			(net "GND")
		)
		(pad "V85" smd circle
			(at 36.392104 -18.483072)
			(size 0.4318 0.4318)
			(layers "F.Cu" "F.Mask" "F.Paste")
			(net "M_A_DQS_DP<10>")
		)
		(pad "W2" smd circle
			(at -36.392104 -16.187674)
			(size 0.4318 0.4318)
			(layers "F.Cu" "F.Mask" "F.Paste")
			(net "UPI_CPU0_CPU1_P0P0_DP<16>")
		)
		(pad "W4" smd circle
			(at -34.675064 -16.187674)
			(size 0.4318 0.4318)
			(layers "F.Cu" "F.Mask" "F.Paste")
			(net "PVCCIO_CPU0")
		)
		(pad "W6" smd circle
			(at -32.958024 -16.187674)
			(size 0.4318 0.4318)
			(layers "F.Cu" "F.Mask" "F.Paste")
			(net "PVCCIO_CPU0")
		)
		(pad "W8" smd circle
			(at -31.240984 -16.187674)
			(size 0.4318 0.4318)
			(layers "F.Cu" "F.Mask" "F.Paste")
			(net "GND")
		)
		(pad "W10" smd circle
			(at -29.523944 -16.187674)
			(size 0.4318 0.4318)
			(layers "F.Cu" "F.Mask" "F.Paste")
			(net "PVCCIO_CPU0")
		)
		(pad "W12" smd circle
			(at -27.806904 -16.187674)
			(size 0.4318 0.4318)
			(layers "F.Cu" "F.Mask" "F.Paste")
			(net "GND")
		)
		(pad "W14" smd circle
			(at -26.090118 -16.187674)
			(size 0.4318 0.4318)
			(layers "F.Cu" "F.Mask" "F.Paste")
			(net "XDP_CPU_TMS")
		)
		(pad "W16" smd circle
			(at -24.373078 -16.187674)
			(size 0.4318 0.4318)
			(layers "F.Cu" "F.Mask" "F.Paste")
			(net "UPI_CPU1_CPU0_P1P1_DP<7>")
		)
		(pad "W18" smd circle
			(at -22.656038 -16.187674)
			(size 0.4318 0.4318)
			(layers "F.Cu" "F.Mask" "F.Paste")
			(net "UPI_CPU1_CPU0_P1P1_DN<6>")
		)
		(pad "W20" smd circle
			(at -20.938998 -16.187674)
			(size 0.4318 0.4318)
			(layers "F.Cu" "F.Mask" "F.Paste")
			(net "UPI_CPU1_CPU0_P1P1_DP<1>")
		)
		(pad "W22" smd circle
			(at -19.221958 -16.187674)
			(size 0.4318 0.4318)
			(layers "F.Cu" "F.Mask" "F.Paste")
			(net "GND")
		)
		(pad "W24" smd circle
			(at -17.504918 -16.187674)
			(size 0.4318 0.4318)
			(layers "F.Cu" "F.Mask" "F.Paste")
			(net "GND")
		)
		(pad "W26" smd circle
			(at -15.787878 -16.187674)
			(size 0.4318 0.4318)
			(layers "F.Cu" "F.Mask" "F.Paste")
			(net "GND")
		)
		(pad "W28" smd circle
			(at -14.071092 -16.187674)
			(size 0.4318 0.4318)
			(layers "F.Cu" "F.Mask" "F.Paste")
			(net "GND")
		)
		(pad "W30" smd circle
			(at -12.354052 -16.187674)
			(size 0.4318 0.4318)
			(layers "F.Cu" "F.Mask" "F.Paste")
			(net "GND")
		)
		(pad "W32" smd circle
			(at -10.637012 -16.187674)
			(size 0.4318 0.4318)
			(layers "F.Cu" "F.Mask" "F.Paste")
			(net "GND")
		)
		(pad "W34" smd circle
			(at -8.919972 -16.187674)
			(size 0.4318 0.4318)
			(layers "F.Cu" "F.Mask" "F.Paste")
			(net "GND")
		)
		(pad "W36" smd circle
			(at -7.202932 -16.187674)
			(size 0.4318 0.4318)
			(layers "F.Cu" "F.Mask" "F.Paste")
			(net "GND")
		)
		(pad "W38" smd circle
			(at -5.485892 -16.187674)
			(size 0.4318 0.4318)
			(layers "F.Cu" "F.Mask" "F.Paste")
			(net "GND")
		)
		(pad "W40" smd circle
			(at -3.769106 -16.187674)
			(size 0.4318 0.4318)
			(layers "F.Cu" "F.Mask" "F.Paste")
			(net "GND")
		)
		(pad "W42" smd circle
			(at -2.052066 -16.187674)
			(size 0.4318 0.4318)
			(layers "F.Cu" "F.Mask" "F.Paste")
			(net "GND")
		)
		(pad "W46" smd circle
			(at 2.910586 -17.988026)
			(size 0.4318 0.4318)
			(layers "F.Cu" "F.Mask" "F.Paste")
			(net "M_C_CS_N<2>")
		)
		(pad "W48" smd circle
			(at 4.627626 -17.988026)
			(size 0.4318 0.4318)
			(layers "F.Cu" "F.Mask" "F.Paste")
			(net "M_C_CS_N<5>")
		)
		(pad "W50" smd circle
			(at 6.344412 -17.988026)
			(size 0.4318 0.4318)
			(layers "F.Cu" "F.Mask" "F.Paste")
			(net "M_C_MA<14>")
		)
		(pad "W52" smd circle
			(at 8.061452 -17.988026)
			(size 0.4318 0.4318)
			(layers "F.Cu" "F.Mask" "F.Paste")
			(net "M_C_BA<0>")
		)
		(pad "W54" smd circle
			(at 9.778492 -17.988026)
			(size 0.4318 0.4318)
			(layers "F.Cu" "F.Mask" "F.Paste")
			(net "M_C_CLK_DN<1>")
		)
		(pad "W56" smd circle
			(at 11.495532 -17.988026)
			(size 0.4318 0.4318)
			(layers "F.Cu" "F.Mask" "F.Paste")
			(net "M_C_CLK_DN<3>")
		)
		(pad "W58" smd circle
			(at 13.212572 -17.988026)
			(size 0.4318 0.4318)
			(layers "F.Cu" "F.Mask" "F.Paste")
			(net "M_C_MA<3>")
		)
		(pad "W60" smd circle
			(at 14.929612 -17.988026)
			(size 0.4318 0.4318)
			(layers "F.Cu" "F.Mask" "F.Paste")
			(net "M_B_MA<8>")
		)
		(pad "W62" smd circle
			(at 16.646398 -17.988026)
			(size 0.4318 0.4318)
			(layers "F.Cu" "F.Mask" "F.Paste")
			(net "M_B_ALERT_N")
		)
		(pad "W64" smd circle
			(at 18.363438 -17.988026)
			(size 0.4318 0.4318)
			(layers "F.Cu" "F.Mask" "F.Paste")
			(net "PVDDQ_ABC")
		)
		(pad "W66" smd circle
			(at 20.080478 -17.988026)
			(size 0.4318 0.4318)
			(layers "F.Cu" "F.Mask" "F.Paste")
			(net "TP_CPU0_RSVD_258")
		)
		(pad "W68" smd circle
			(at 21.797518 -17.988026)
			(size 0.4318 0.4318)
			(layers "F.Cu" "F.Mask" "F.Paste")
			(net "GND")
		)
		(pad "W70" smd circle
			(at 23.514558 -17.988026)
			(size 0.4318 0.4318)
			(layers "F.Cu" "F.Mask" "F.Paste")
			(net "M_C_DQS_DP<2>")
		)
		(pad "W72" smd circle
			(at 25.231598 -17.988026)
			(size 0.4318 0.4318)
			(layers "F.Cu" "F.Mask" "F.Paste")
			(net "M_C_DQ<16>")
		)
		(pad "W74" smd circle
			(at 26.948384 -17.988026)
			(size 0.4318 0.4318)
			(layers "F.Cu" "F.Mask" "F.Paste")
			(net "GND")
		)
		(pad "W76" smd circle
			(at 28.665424 -17.988026)
			(size 0.4318 0.4318)
			(layers "F.Cu" "F.Mask" "F.Paste")
			(net "M_C_DQ<11>")
		)
		(pad "W78" smd circle
			(at 30.382464 -17.988026)
			(size 0.4318 0.4318)
			(layers "F.Cu" "F.Mask" "F.Paste")
			(net "GND")
		)
		(pad "W80" smd circle
			(at 32.099504 -17.988026)
			(size 0.4318 0.4318)
			(layers "F.Cu" "F.Mask" "F.Paste")
			(net "M_A_DQ<20>")
		)
		(pad "W82" smd circle
			(at 33.816544 -17.988026)
			(size 0.4318 0.4318)
			(layers "F.Cu" "F.Mask" "F.Paste")
			(net "GND")
		)
		(pad "W84" smd circle
			(at 35.533584 -17.988026)
			(size 0.4318 0.4318)
			(layers "F.Cu" "F.Mask" "F.Paste")
			(net "M_A_DQ<9>")
		)
		(pad "W86" smd custom
			(at 37.250624 -17.988026 270)
			(size 0.10795 0.10795)
			(layers "F.Cu" "F.Mask" "F.Paste")
			(net "M_A_DQ<8>")
			(options
				(clearance outline)
				(anchor circle)
			)
			(primitives
				(gr_poly
					(pts
						(arc
							(start 0.2159 -0.0381)
							(mid 0 -0.254)
							(end -0.2159 -0.0381)
						)
						(arc
							(start -0.2159 0.0381)
							(mid 0 0.254)
							(end 0.2159 0.0381)
						)
					)
					(width 0)
					(fill yes)
				)
			)
		)
		(pad "Y1" smd custom
			(at -37.250624 -15.692628 90)
			(size 0.10795 0.10795)
			(layers "F.Cu" "F.Mask" "F.Paste")
			(net "UPI_CPU0_CPU1_P0P0_DN<16>")
			(options
				(clearance outline)
				(anchor circle)
			)
			(primitives
				(gr_poly
					(pts
						(arc
							(start 0.2159 -0.0381)
							(mid 0 -0.254)
							(end -0.2159 -0.0381)
						)
						(arc
							(start -0.2159 0.0381)
							(mid 0 0.254)
							(end 0.2159 0.0381)
						)
					)
					(width 0)
					(fill yes)
				)
			)
		)
		(pad "Y3" smd circle
			(at -35.533584 -15.692628)
			(size 0.4318 0.4318)
			(layers "F.Cu" "F.Mask" "F.Paste")
			(net "UPI_CPU0_CPU1_P0P0_DP<17>")
		)
		(pad "Y5" smd circle
			(at -33.816544 -15.692628)
			(size 0.4318 0.4318)
			(layers "F.Cu" "F.Mask" "F.Paste")
			(net "GND")
		)
		(pad "Y7" smd circle
			(at -32.099504 -15.692628)
			(size 0.4318 0.4318)
			(layers "F.Cu" "F.Mask" "F.Paste")
			(net "GND")
		)
		(pad "Y9" smd circle
			(at -30.382464 -15.692628)
			(size 0.4318 0.4318)
			(layers "F.Cu" "F.Mask" "F.Paste")
			(net "GND")
		)
		(pad "Y11" smd circle
			(at -28.665424 -15.692628)
			(size 0.4318 0.4318)
			(layers "F.Cu" "F.Mask" "F.Paste")
			(net "TP_XDP_CPU0_OBSDATA_A3_MBP5_N")
		)
		(pad "Y13" smd circle
			(at -26.948384 -15.692628)
			(size 0.4318 0.4318)
			(layers "F.Cu" "F.Mask" "F.Paste")
			(net "XDP_CPU_TRST_N")
		)
		(pad "Y15" smd circle
			(at -25.231598 -15.692628)
			(size 0.4318 0.4318)
			(layers "F.Cu" "F.Mask" "F.Paste")
			(net "GND")
		)
		(pad "Y17" smd circle
			(at -23.514558 -15.692628)
			(size 0.4318 0.4318)
			(layers "F.Cu" "F.Mask" "F.Paste")
			(net "GND")
		)
		(pad "Y19" smd circle
			(at -21.797518 -15.692628)
			(size 0.4318 0.4318)
			(layers "F.Cu" "F.Mask" "F.Paste")
			(net "UPI_CPU1_CPU0_P1P1_DP<2>")
		)
		(pad "Y21" smd circle
			(at -20.080478 -15.692628)
			(size 0.4318 0.4318)
			(layers "F.Cu" "F.Mask" "F.Paste")
			(net "UPI_CPU1_CPU0_P1P1_DN<1>")
		)
		(pad "Y23" smd circle
			(at -18.363438 -15.692628)
			(size 0.4318 0.4318)
			(layers "F.Cu" "F.Mask" "F.Paste")
			(net "FM_CPU0_RC_ERROR_N")
		)
		(pad "Y25" smd circle
			(at -16.646398 -15.692628)
			(size 0.4318 0.4318)
			(layers "F.Cu" "F.Mask" "F.Paste")
			(net "M_B_DQ<59>")
		)
		(pad "Y27" smd circle
			(at -14.929612 -15.692628)
			(size 0.4318 0.4318)
			(layers "F.Cu" "F.Mask" "F.Paste")
			(net "M_B_DQS_DP<7>")
		)
		(pad "Y29" smd circle
			(at -13.212572 -15.692628)
			(size 0.4318 0.4318)
			(layers "F.Cu" "F.Mask" "F.Paste")
			(net "M_B_DQ<61>")
		)
		(pad "Y31" smd circle
			(at -11.495532 -15.692628)
			(size 0.4318 0.4318)
			(layers "F.Cu" "F.Mask" "F.Paste")
			(net "M_C_DQ<43>")
		)
		(pad "Y33" smd circle
			(at -9.778492 -15.692628)
			(size 0.4318 0.4318)
			(layers "F.Cu" "F.Mask" "F.Paste")
			(net "M_C_DQS_DP<5>")
		)
		(pad "Y35" smd circle
			(at -8.061452 -15.692628)
			(size 0.4318 0.4318)
			(layers "F.Cu" "F.Mask" "F.Paste")
			(net "M_C_DQ<45>")
		)
		(pad "Y37" smd circle
			(at -6.344412 -15.692628)
			(size 0.4318 0.4318)
			(layers "F.Cu" "F.Mask" "F.Paste")
			(net "M_C_DQ<35>")
		)
		(pad "Y39" smd circle
			(at -4.627626 -15.692628)
			(size 0.4318 0.4318)
			(layers "F.Cu" "F.Mask" "F.Paste")
			(net "M_C_DQS_DP<4>")
		)
		(pad "Y41" smd circle
			(at -2.910586 -15.692628)
			(size 0.4318 0.4318)
			(layers "F.Cu" "F.Mask" "F.Paste")
			(net "M_C_DQ<37>")
		)
		(pad "Y43" smd circle
			(at -1.193546 -15.692628)
			(size 0.4318 0.4318)
			(layers "F.Cu" "F.Mask" "F.Paste")
			(net "A_CPU0_ABC_RCOMP0")
		)
		(pad "Y45" smd circle
			(at 2.052066 -17.492726)
			(size 0.508 0.508)
			(layers "F.Cu" "F.Mask" "F.Paste")
			(net "PVDDQ_ABC")
		)
		(pad "Y47" smd circle
			(at 3.769106 -17.492726)
			(size 0.4318 0.4318)
			(layers "F.Cu" "F.Mask" "F.Paste")
			(net "PVDDQ_ABC")
		)
		(pad "Y49" smd circle
			(at 5.485892 -17.492726)
			(size 0.4318 0.4318)
			(layers "F.Cu" "F.Mask" "F.Paste")
			(net "PVDDQ_ABC")
		)
		(pad "Y51" smd circle
			(at 7.202932 -17.492726)
			(size 0.4318 0.4318)
			(layers "F.Cu" "F.Mask" "F.Paste")
			(net "PVDDQ_ABC")
		)
		(pad "Y53" smd circle
			(at 8.919972 -17.492726)
			(size 0.4318 0.4318)
			(layers "F.Cu" "F.Mask" "F.Paste")
			(net "PVDDQ_ABC")
		)
		(pad "Y55" smd circle
			(at 10.637012 -17.492726)
			(size 0.4318 0.4318)
			(layers "F.Cu" "F.Mask" "F.Paste")
			(net "PVDDQ_ABC")
		)
		(pad "Y57" smd circle
			(at 12.354052 -17.492726)
			(size 0.4318 0.4318)
			(layers "F.Cu" "F.Mask" "F.Paste")
			(net "PVDDQ_ABC")
		)
		(pad "Y59" smd circle
			(at 14.071092 -17.492726)
			(size 0.4318 0.4318)
			(layers "F.Cu" "F.Mask" "F.Paste")
			(net "PVDDQ_ABC")
		)
		(pad "Y61" smd circle
			(at 15.787878 -17.492726)
			(size 0.4318 0.4318)
			(layers "F.Cu" "F.Mask" "F.Paste")
			(net "PVDDQ_ABC")
		)
		(pad "Y63" smd circle
			(at 17.504918 -17.492726)
			(size 0.4318 0.4318)
			(layers "F.Cu" "F.Mask" "F.Paste")
			(net "PVDDQ_ABC")
		)
		(pad "Y65" smd circle
			(at 19.221958 -17.492726)
			(size 0.4318 0.4318)
			(layers "F.Cu" "F.Mask" "F.Paste")
			(net "TP_CPU0_RSVD_256")
		)
		(pad "Y67" smd circle
			(at 20.938998 -17.492726)
			(size 0.4318 0.4318)
			(layers "F.Cu" "F.Mask" "F.Paste")
			(net "GND")
		)
		(pad "Y69" smd circle
			(at 22.656038 -17.492726)
			(size 0.4318 0.4318)
			(layers "F.Cu" "F.Mask" "F.Paste")
			(net "M_C_DQS_DN<2>")
		)
		(pad "Y71" smd circle
			(at 24.373078 -17.492726)
			(size 0.4318 0.4318)
			(layers "F.Cu" "F.Mask" "F.Paste")
			(net "GND")
		)
		(pad "Y73" smd circle
			(at 26.090118 -17.492726)
			(size 0.4318 0.4318)
			(layers "F.Cu" "F.Mask" "F.Paste")
			(net "GND")
		)
		(pad "Y75" smd circle
			(at 27.806904 -17.492726)
			(size 0.4318 0.4318)
			(layers "F.Cu" "F.Mask" "F.Paste")
			(net "M_C_DQ<15>")
		)
		(pad "Y77" smd circle
			(at 29.523944 -17.492726)
			(size 0.4318 0.4318)
			(layers "F.Cu" "F.Mask" "F.Paste")
			(net "M_C_DQ<10>")
		)
		(pad "Y79" smd circle
			(at 31.240984 -17.492726)
			(size 0.4318 0.4318)
			(layers "F.Cu" "F.Mask" "F.Paste")
			(net "GND")
		)
		(pad "Y81" smd circle
			(at 32.958024 -17.492726)
			(size 0.4318 0.4318)
			(layers "F.Cu" "F.Mask" "F.Paste")
			(net "GND")
		)
		(pad "Y83" smd circle
			(at 34.675064 -17.492726)
			(size 0.4318 0.4318)
			(layers "F.Cu" "F.Mask" "F.Paste")
			(net "GND")
		)
		(pad "Y85" smd circle
			(at 36.392104 -17.492726)
			(size 0.4318 0.4318)
			(layers "F.Cu" "F.Mask" "F.Paste")
			(net "GND")
		)
		(zone
			(layer "F.Cu")
			(hatch none 0.5)
			(connect_pads
				(clearance 0)
			)
			(min_thickness 0.25)
			(keepout
				(tracks not_allowed)
				(vias allowed)
				(pads allowed)
				(copperpour not_allowed)
				(footprints allowed)
			)
			(placement
				(enabled no)
				(sheetname "")
			)
			(fill
				(thermal_gap 0.5)
				(thermal_bridge_width 0.5)
				(island_removal_mode 0)
			)
			(polygon
				(pts
					(arc
						(start 268.26591 -57.076086)
						(mid 267.630402 -57.076086)
						(end 268.26591 -57.076086)
					)
				)
			)
		)
		(zone
			(layer "F.Cu")
			(hatch none 0.5)
			(connect_pads
				(clearance 0)
			)
			(min_thickness 0.25)
			(keepout
				(tracks not_allowed)
				(vias allowed)
				(pads allowed)
				(copperpour not_allowed)
				(footprints allowed)
			)
			(placement
				(enabled no)
				(sheetname "")
			)
			(fill
				(thermal_gap 0.5)
				(thermal_bridge_width 0.5)
				(island_removal_mode 0)
			)
			(polygon
				(pts
					(arc
						(start 269.124176 -94.223586)
						(mid 268.489176 -94.223586)
						(end 269.124176 -94.223586)
					)
				)
			)
		)
		(zone
			(layer "F.Cu")
			(hatch none 0.5)
			(connect_pads
				(clearance 0)
			)
			(min_thickness 0.25)
			(keepout
				(tracks not_allowed)
				(vias allowed)
				(pads allowed)
				(copperpour not_allowed)
				(footprints allowed)
			)
			(placement
				(enabled no)
				(sheetname "")
			)
			(fill
				(thermal_gap 0.5)
				(thermal_bridge_width 0.5)
				(island_removal_mode 0)
			)
			(polygon
				(pts
					(arc
						(start 255.426464 -83.32724)
						(mid 254.714756 -83.32724)
						(end 255.426464 -83.32724)
					)
				)
			)
		)
		(zone
			(layer "F.Cu")
			(hatch none 0.5)
			(connect_pads
				(clearance 0)
			)
			(min_thickness 0.25)
			(keepout
				(tracks not_allowed)
				(vias allowed)
				(pads allowed)
				(copperpour not_allowed)
				(footprints allowed)
			)
			(placement
				(enabled no)
				(sheetname "")
			)
			(fill
				(thermal_gap 0.5)
				(thermal_bridge_width 0.5)
				(island_removal_mode 0)
			)
			(polygon
				(pts
					(arc
						(start 255.426464 -82.33664)
						(mid 254.714756 -82.33664)
						(end 255.426464 -82.33664)
					)
				)
			)
		)
		(zone
			(layer "F.Cu")
			(hatch none 0.5)
			(connect_pads
				(clearance 0)
			)
			(min_thickness 0.25)
			(keepout
				(tracks not_allowed)
				(vias allowed)
				(pads allowed)
				(copperpour not_allowed)
				(footprints allowed)
			)
			(placement
				(enabled no)
				(sheetname "")
			)
			(fill
				(thermal_gap 0.5)
				(thermal_bridge_width 0.5)
				(island_removal_mode 0)
			)
			(polygon
				(pts
					(arc
						(start 255.426464 -81.346294)
						(mid 254.714756 -81.346294)
						(end 255.426464 -81.346294)
					)
				)
			)
		)
		(zone
			(layer "F.Cu")
			(hatch none 0.5)
			(connect_pads
				(clearance 0)
			)
			(min_thickness 0.25)
			(keepout
				(tracks not_allowed)
				(vias allowed)
				(pads allowed)
				(copperpour not_allowed)
				(footprints allowed)
			)
			(placement
				(enabled no)
				(sheetname "")
			)
			(fill
				(thermal_gap 0.5)
				(thermal_bridge_width 0.5)
				(island_removal_mode 0)
			)
			(polygon
				(pts
					(arc
						(start 255.426464 -80.355694)
						(mid 254.714756 -80.355694)
						(end 255.426464 -80.355694)
					)
				)
			)
		)
		(zone
			(layer "F.Cu")
			(hatch none 0.5)
			(connect_pads
				(clearance 0)
			)
			(min_thickness 0.25)
			(keepout
				(tracks not_allowed)
				(vias allowed)
				(pads allowed)
				(copperpour not_allowed)
				(footprints allowed)
			)
			(placement
				(enabled no)
				(sheetname "")
			)
			(fill
				(thermal_gap 0.5)
				(thermal_bridge_width 0.5)
				(island_removal_mode 0)
			)
			(polygon
				(pts
					(arc
						(start 255.426464 -79.365094)
						(mid 254.714756 -79.365094)
						(end 255.426464 -79.365094)
					)
				)
			)
		)
		(zone
			(layer "F.Cu")
			(hatch none 0.5)
			(connect_pads
				(clearance 0)
			)
			(min_thickness 0.25)
			(keepout
				(tracks not_allowed)
				(vias allowed)
				(pads allowed)
				(copperpour not_allowed)
				(footprints allowed)
			)
			(placement
				(enabled no)
				(sheetname "")
			)
			(fill
				(thermal_gap 0.5)
				(thermal_bridge_width 0.5)
				(island_removal_mode 0)
			)
			(polygon
				(pts
					(arc
						(start 255.426464 -78.374748)
						(mid 254.714756 -78.374748)
						(end 255.426464 -78.374748)
					)
				)
			)
		)
		(zone
			(layer "F.Cu")
			(hatch none 0.5)
			(connect_pads
				(clearance 0)
			)
			(min_thickness 0.25)
			(keepout
				(tracks not_allowed)
				(vias allowed)
				(pads allowed)
				(copperpour not_allowed)
				(footprints allowed)
			)
			(placement
				(enabled no)
				(sheetname "")
			)
			(fill
				(thermal_gap 0.5)
				(thermal_bridge_width 0.5)
				(island_removal_mode 0)
			)
			(polygon
				(pts
					(arc
						(start 255.426464 -77.384148)
						(mid 254.714756 -77.384148)
						(end 255.426464 -77.384148)
					)
				)
			)
		)
		(zone
			(layer "F.Cu")
			(hatch none 0.5)
			(connect_pads
				(clearance 0)
			)
			(min_thickness 0.25)
			(keepout
				(tracks not_allowed)
				(vias allowed)
				(pads allowed)
				(copperpour not_allowed)
				(footprints allowed)
			)
			(placement
				(enabled no)
				(sheetname "")
			)
			(fill
				(thermal_gap 0.5)
				(thermal_bridge_width 0.5)
				(island_removal_mode 0)
			)
			(polygon
				(pts
					(arc
						(start 255.426464 -76.393802)
						(mid 254.714756 -76.393802)
						(end 255.426464 -76.393802)
					)
				)
			)
		)
		(zone
			(layer "F.Cu")
			(hatch none 0.5)
			(connect_pads
				(clearance 0)
			)
			(min_thickness 0.25)
			(keepout
				(tracks not_allowed)
				(vias allowed)
				(pads allowed)
				(copperpour not_allowed)
				(footprints allowed)
			)
			(placement
				(enabled no)
				(sheetname "")
			)
			(fill
				(thermal_gap 0.5)
				(thermal_bridge_width 0.5)
				(island_removal_mode 0)
			)
			(polygon
				(pts
					(arc
						(start 255.426464 -75.403202)
						(mid 254.714756 -75.403202)
						(end 255.426464 -75.403202)
					)
				)
			)
		)
		(zone
			(layer "F.Cu")
			(hatch none 0.5)
			(connect_pads
				(clearance 0)
			)
			(min_thickness 0.25)
			(keepout
				(tracks not_allowed)
				(vias allowed)
				(pads allowed)
				(copperpour not_allowed)
				(footprints allowed)
			)
			(placement
				(enabled no)
				(sheetname "")
			)
			(fill
				(thermal_gap 0.5)
				(thermal_bridge_width 0.5)
				(island_removal_mode 0)
			)
			(polygon
				(pts
					(arc
						(start 255.426464 -74.412602)
						(mid 254.714756 -74.412602)
						(end 255.426464 -74.412602)
					)
				)
			)
		)
		(zone
			(layer "F.Cu")
			(hatch none 0.5)
			(connect_pads
				(clearance 0)
			)
			(min_thickness 0.25)
			(keepout
				(tracks not_allowed)
				(vias allowed)
				(pads allowed)
				(copperpour not_allowed)
				(footprints allowed)
			)
			(placement
				(enabled no)
				(sheetname "")
			)
			(fill
				(thermal_gap 0.5)
				(thermal_bridge_width 0.5)
				(island_removal_mode 0)
			)
			(polygon
				(pts
					(arc
						(start 255.426464 -73.422256)
						(mid 254.714756 -73.422256)
						(end 255.426464 -73.422256)
					)
				)
			)
		)
		(zone
			(layer "F.Cu")
			(hatch none 0.5)
			(connect_pads
				(clearance 0)
			)
			(min_thickness 0.25)
			(keepout
				(tracks not_allowed)
				(vias allowed)
				(pads allowed)
				(copperpour not_allowed)
				(footprints allowed)
			)
			(placement
				(enabled no)
				(sheetname "")
			)
			(fill
				(thermal_gap 0.5)
				(thermal_bridge_width 0.5)
				(island_removal_mode 0)
			)
			(polygon
				(pts
					(arc
						(start 255.426464 -72.431656)
						(mid 254.714756 -72.431656)
						(end 255.426464 -72.431656)
					)
				)
			)
		)
		(zone
			(layer "F.Cu")
			(hatch none 0.5)
			(connect_pads
				(clearance 0)
			)
			(min_thickness 0.25)
			(keepout
				(tracks not_allowed)
				(vias allowed)
				(pads allowed)
				(copperpour not_allowed)
				(footprints allowed)
			)
			(placement
				(enabled no)
				(sheetname "")
			)
			(fill
				(thermal_gap 0.5)
				(thermal_bridge_width 0.5)
				(island_removal_mode 0)
			)
			(polygon
				(pts
					(arc
						(start 255.426464 -71.44131)
						(mid 254.714756 -71.44131)
						(end 255.426464 -71.44131)
					)
				)
			)
		)
		(zone
			(layer "F.Cu")
			(hatch none 0.5)
			(connect_pads
				(clearance 0)
			)
			(min_thickness 0.25)
			(keepout
				(tracks not_allowed)
				(vias allowed)
				(pads allowed)
				(copperpour not_allowed)
				(footprints allowed)
			)
			(placement
				(enabled no)
				(sheetname "")
			)
			(fill
				(thermal_gap 0.5)
				(thermal_bridge_width 0.5)
				(island_removal_mode 0)
			)
			(polygon
				(pts
					(arc
						(start 255.426464 -70.45071)
						(mid 254.714756 -70.45071)
						(end 255.426464 -70.45071)
					)
				)
			)
		)
		(zone
			(layer "F.Cu")
			(hatch none 0.5)
			(connect_pads
				(clearance 0)
			)
			(min_thickness 0.25)
			(keepout
				(tracks not_allowed)
				(vias allowed)
				(pads allowed)
				(copperpour not_allowed)
				(footprints allowed)
			)
			(placement
				(enabled no)
				(sheetname "")
			)
			(fill
				(thermal_gap 0.5)
				(thermal_bridge_width 0.5)
				(island_removal_mode 0)
			)
			(polygon
				(pts
					(arc
						(start 255.426464 -69.46011)
						(mid 254.714756 -69.46011)
						(end 255.426464 -69.46011)
					)
				)
			)
		)
		(zone
			(layer "F.Cu")
			(hatch none 0.5)
			(connect_pads
				(clearance 0)
			)
			(min_thickness 0.25)
			(keepout
				(tracks not_allowed)
				(vias allowed)
				(pads allowed)
				(copperpour not_allowed)
				(footprints allowed)
			)
			(placement
				(enabled no)
				(sheetname "")
			)
			(fill
				(thermal_gap 0.5)
				(thermal_bridge_width 0.5)
				(island_removal_mode 0)
			)
			(polygon
				(pts
					(arc
						(start 255.426464 -68.469764)
						(mid 254.714756 -68.469764)
						(end 255.426464 -68.469764)
					)
				)
			)
		)
		(zone
			(layer "F.Cu")
			(hatch none 0.5)
			(connect_pads
				(clearance 0)
			)
			(min_thickness 0.25)
			(keepout
				(tracks not_allowed)
				(vias allowed)
				(pads allowed)
				(copperpour not_allowed)
				(footprints allowed)
			)
			(placement
				(enabled no)
				(sheetname "")
			)
			(fill
				(thermal_gap 0.5)
				(thermal_bridge_width 0.5)
				(island_removal_mode 0)
			)
			(polygon
				(pts
					(arc
						(start 256.284984 -83.822286)
						(mid 255.573276 -83.822286)
						(end 256.284984 -83.822286)
					)
				)
			)
		)
		(zone
			(layer "F.Cu")
			(hatch none 0.5)
			(connect_pads
				(clearance 0)
			)
			(min_thickness 0.25)
			(keepout
				(tracks not_allowed)
				(vias allowed)
				(pads allowed)
				(copperpour not_allowed)
				(footprints allowed)
			)
			(placement
				(enabled no)
				(sheetname "")
			)
			(fill
				(thermal_gap 0.5)
				(thermal_bridge_width 0.5)
				(island_removal_mode 0)
			)
			(polygon
				(pts
					(arc
						(start 256.284984 -67.972686)
						(mid 255.573276 -67.972686)
						(end 256.284984 -67.972686)
					)
				)
			)
		)
		(zone
			(layer "F.Cu")
			(hatch none 0.5)
			(connect_pads
				(clearance 0)
			)
			(min_thickness 0.25)
			(keepout
				(tracks not_allowed)
				(vias allowed)
				(pads allowed)
				(copperpour not_allowed)
				(footprints allowed)
			)
			(placement
				(enabled no)
				(sheetname "")
			)
			(fill
				(thermal_gap 0.5)
				(thermal_bridge_width 0.5)
				(island_removal_mode 0)
			)
			(polygon
				(pts
					(arc
						(start 257.143504 -84.31784)
						(mid 256.431796 -84.31784)
						(end 257.143504 -84.31784)
					)
				)
			)
		)
		(zone
			(layer "F.Cu")
			(hatch none 0.5)
			(connect_pads
				(clearance 0)
			)
			(min_thickness 0.25)
			(keepout
				(tracks not_allowed)
				(vias allowed)
				(pads allowed)
				(copperpour not_allowed)
				(footprints allowed)
			)
			(placement
				(enabled no)
				(sheetname "")
			)
			(fill
				(thermal_gap 0.5)
				(thermal_bridge_width 0.5)
				(island_removal_mode 0)
			)
			(polygon
				(pts
					(arc
						(start 257.143504 -67.47764)
						(mid 256.431796 -67.47764)
						(end 257.143504 -67.47764)
					)
				)
			)
		)
		(zone
			(layer "F.Cu")
			(hatch none 0.5)
			(connect_pads
				(clearance 0)
			)
			(min_thickness 0.25)
			(keepout
				(tracks not_allowed)
				(vias allowed)
				(pads allowed)
				(copperpour not_allowed)
				(footprints allowed)
			)
			(placement
				(enabled no)
				(sheetname "")
			)
			(fill
				(thermal_gap 0.5)
				(thermal_bridge_width 0.5)
				(island_removal_mode 0)
			)
			(polygon
				(pts
					(arc
						(start 258.00177 -84.812886)
						(mid 257.29057 -84.812886)
						(end 258.00177 -84.812886)
					)
				)
			)
		)
		(zone
			(layer "F.Cu")
			(hatch none 0.5)
			(connect_pads
				(clearance 0)
			)
			(min_thickness 0.25)
			(keepout
				(tracks not_allowed)
				(vias allowed)
				(pads allowed)
				(copperpour not_allowed)
				(footprints allowed)
			)
			(placement
				(enabled no)
				(sheetname "")
			)
			(fill
				(thermal_gap 0.5)
				(thermal_bridge_width 0.5)
				(island_removal_mode 0)
			)
			(polygon
				(pts
					(arc
						(start 258.00177 -66.982086)
						(mid 257.29057 -66.982086)
						(end 258.00177 -66.982086)
					)
				)
			)
		)
		(zone
			(layer "F.Cu")
			(hatch none 0.5)
			(connect_pads
				(clearance 0)
			)
			(min_thickness 0.25)
			(keepout
				(tracks not_allowed)
				(vias allowed)
				(pads allowed)
				(copperpour not_allowed)
				(footprints allowed)
			)
			(placement
				(enabled no)
				(sheetname "")
			)
			(fill
				(thermal_gap 0.5)
				(thermal_bridge_width 0.5)
				(island_removal_mode 0)
			)
			(polygon
				(pts
					(arc
						(start 258.86029 -85.30844)
						(mid 258.14909 -85.30844)
						(end 258.86029 -85.30844)
					)
				)
			)
		)
		(zone
			(layer "F.Cu")
			(hatch none 0.5)
			(connect_pads
				(clearance 0)
			)
			(min_thickness 0.25)
			(keepout
				(tracks not_allowed)
				(vias allowed)
				(pads allowed)
				(copperpour not_allowed)
				(footprints allowed)
			)
			(placement
				(enabled no)
				(sheetname "")
			)
			(fill
				(thermal_gap 0.5)
				(thermal_bridge_width 0.5)
				(island_removal_mode 0)
			)
			(polygon
				(pts
					(arc
						(start 258.86029 -66.48704)
						(mid 258.14909 -66.48704)
						(end 258.86029 -66.48704)
					)
				)
			)
		)
		(zone
			(layer "F.Cu")
			(hatch none 0.5)
			(connect_pads
				(clearance 0)
			)
			(min_thickness 0.25)
			(keepout
				(tracks not_allowed)
				(vias allowed)
				(pads allowed)
				(copperpour not_allowed)
				(footprints allowed)
			)
			(placement
				(enabled no)
				(sheetname "")
			)
			(fill
				(thermal_gap 0.5)
				(thermal_bridge_width 0.5)
				(island_removal_mode 0)
			)
			(polygon
				(pts
					(arc
						(start 259.71881 -85.803486)
						(mid 259.00761 -85.803486)
						(end 259.71881 -85.803486)
					)
				)
			)
		)
		(zone
			(layer "F.Cu")
			(hatch none 0.5)
			(connect_pads
				(clearance 0)
			)
			(min_thickness 0.25)
			(keepout
				(tracks not_allowed)
				(vias allowed)
				(pads allowed)
				(copperpour not_allowed)
				(footprints allowed)
			)
			(placement
				(enabled no)
				(sheetname "")
			)
			(fill
				(thermal_gap 0.5)
				(thermal_bridge_width 0.5)
				(island_removal_mode 0)
			)
			(polygon
				(pts
					(arc
						(start 259.71881 -65.991486)
						(mid 259.00761 -65.991486)
						(end 259.71881 -65.991486)
					)
				)
			)
		)
		(zone
			(layer "F.Cu")
			(hatch none 0.5)
			(connect_pads
				(clearance 0)
			)
			(min_thickness 0.25)
			(keepout
				(tracks not_allowed)
				(vias allowed)
				(pads allowed)
				(copperpour not_allowed)
				(footprints allowed)
			)
			(placement
				(enabled no)
				(sheetname "")
			)
			(fill
				(thermal_gap 0.5)
				(thermal_bridge_width 0.5)
				(island_removal_mode 0)
			)
			(polygon
				(pts
					(arc
						(start 260.57733 -86.29904)
						(mid 259.86613 -86.29904)
						(end 260.57733 -86.29904)
					)
				)
			)
		)
		(zone
			(layer "F.Cu")
			(hatch none 0.5)
			(connect_pads
				(clearance 0)
			)
			(min_thickness 0.25)
			(keepout
				(tracks not_allowed)
				(vias allowed)
				(pads allowed)
				(copperpour not_allowed)
				(footprints allowed)
			)
			(placement
				(enabled no)
				(sheetname "")
			)
			(fill
				(thermal_gap 0.5)
				(thermal_bridge_width 0.5)
				(island_removal_mode 0)
			)
			(polygon
				(pts
					(arc
						(start 260.57733 -65.49644)
						(mid 259.86613 -65.49644)
						(end 260.57733 -65.49644)
					)
				)
			)
		)
		(zone
			(layer "F.Cu")
			(hatch none 0.5)
			(connect_pads
				(clearance 0)
			)
			(min_thickness 0.25)
			(keepout
				(tracks not_allowed)
				(vias allowed)
				(pads allowed)
				(copperpour not_allowed)
				(footprints allowed)
			)
			(placement
				(enabled no)
				(sheetname "")
			)
			(fill
				(thermal_gap 0.5)
				(thermal_bridge_width 0.5)
				(island_removal_mode 0)
			)
			(polygon
				(pts
					(arc
						(start 261.43585 -86.794086)
						(mid 260.72465 -86.794086)
						(end 261.43585 -86.794086)
					)
				)
			)
		)
		(zone
			(layer "F.Cu")
			(hatch none 0.5)
			(connect_pads
				(clearance 0)
			)
			(min_thickness 0.25)
			(keepout
				(tracks not_allowed)
				(vias allowed)
				(pads allowed)
				(copperpour not_allowed)
				(footprints allowed)
			)
			(placement
				(enabled no)
				(sheetname "")
			)
			(fill
				(thermal_gap 0.5)
				(thermal_bridge_width 0.5)
				(island_removal_mode 0)
			)
			(polygon
				(pts
					(arc
						(start 261.43585 -65.000886)
						(mid 260.72465 -65.000886)
						(end 261.43585 -65.000886)
					)
				)
			)
		)
		(zone
			(layer "F.Cu")
			(hatch none 0.5)
			(connect_pads
				(clearance 0)
			)
			(min_thickness 0.25)
			(keepout
				(tracks not_allowed)
				(vias allowed)
				(pads allowed)
				(copperpour not_allowed)
				(footprints allowed)
			)
			(placement
				(enabled no)
				(sheetname "")
			)
			(fill
				(thermal_gap 0.5)
				(thermal_bridge_width 0.5)
				(island_removal_mode 0)
			)
			(polygon
				(pts
					(arc
						(start 262.29437 -87.28964)
						(mid 261.58317 -87.28964)
						(end 262.29437 -87.28964)
					)
				)
			)
		)
		(zone
			(layer "F.Cu")
			(hatch none 0.5)
			(connect_pads
				(clearance 0)
			)
			(min_thickness 0.25)
			(keepout
				(tracks not_allowed)
				(vias allowed)
				(pads allowed)
				(copperpour not_allowed)
				(footprints allowed)
			)
			(placement
				(enabled no)
				(sheetname "")
			)
			(fill
				(thermal_gap 0.5)
				(thermal_bridge_width 0.5)
				(island_removal_mode 0)
			)
			(polygon
				(pts
					(arc
						(start 262.29437 -64.50584)
						(mid 261.58317 -64.50584)
						(end 262.29437 -64.50584)
					)
				)
			)
		)
		(zone
			(layer "F.Cu")
			(hatch none 0.5)
			(connect_pads
				(clearance 0)
			)
			(min_thickness 0.25)
			(keepout
				(tracks not_allowed)
				(vias allowed)
				(pads allowed)
				(copperpour not_allowed)
				(footprints allowed)
			)
			(placement
				(enabled no)
				(sheetname "")
			)
			(fill
				(thermal_gap 0.5)
				(thermal_bridge_width 0.5)
				(island_removal_mode 0)
			)
			(polygon
				(pts
					(arc
						(start 263.152636 -87.784686)
						(mid 262.441944 -87.784686)
						(end 263.152636 -87.784686)
					)
				)
			)
		)
		(zone
			(layer "F.Cu")
			(hatch none 0.5)
			(connect_pads
				(clearance 0)
			)
			(min_thickness 0.25)
			(keepout
				(tracks not_allowed)
				(vias allowed)
				(pads allowed)
				(copperpour not_allowed)
				(footprints allowed)
			)
			(placement
				(enabled no)
				(sheetname "")
			)
			(fill
				(thermal_gap 0.5)
				(thermal_bridge_width 0.5)
				(island_removal_mode 0)
			)
			(polygon
				(pts
					(arc
						(start 264.011156 -88.28024)
						(mid 263.300464 -88.28024)
						(end 264.011156 -88.28024)
					)
				)
			)
		)
		(zone
			(layer "F.Cu")
			(hatch none 0.5)
			(connect_pads
				(clearance 0)
			)
			(min_thickness 0.25)
			(keepout
				(tracks not_allowed)
				(vias allowed)
				(pads allowed)
				(copperpour not_allowed)
				(footprints allowed)
			)
			(placement
				(enabled no)
				(sheetname "")
			)
			(fill
				(thermal_gap 0.5)
				(thermal_bridge_width 0.5)
				(island_removal_mode 0)
			)
			(polygon
				(pts
					(arc
						(start 264.011156 -64.50584)
						(mid 263.300464 -64.50584)
						(end 264.011156 -64.50584)
					)
				)
			)
		)
		(zone
			(layer "F.Cu")
			(hatch none 0.5)
			(connect_pads
				(clearance 0)
			)
			(min_thickness 0.25)
			(keepout
				(tracks not_allowed)
				(vias allowed)
				(pads allowed)
				(copperpour not_allowed)
				(footprints allowed)
			)
			(placement
				(enabled no)
				(sheetname "")
			)
			(fill
				(thermal_gap 0.5)
				(thermal_bridge_width 0.5)
				(island_removal_mode 0)
			)
			(polygon
				(pts
					(arc
						(start 265.72845 -88.28024)
						(mid 265.016742 -88.28024)
						(end 265.72845 -88.28024)
					)
				)
			)
		)
		(zone
			(layer "F.Cu")
			(hatch none 0.5)
			(connect_pads
				(clearance 0)
			)
			(min_thickness 0.25)
			(keepout
				(tracks not_allowed)
				(vias allowed)
				(pads allowed)
				(copperpour not_allowed)
				(footprints allowed)
			)
			(placement
				(enabled no)
				(sheetname "")
			)
			(fill
				(thermal_gap 0.5)
				(thermal_bridge_width 0.5)
				(island_removal_mode 0)
			)
			(polygon
				(pts
					(arc
						(start 265.72845 -64.50584)
						(mid 265.016742 -64.50584)
						(end 265.72845 -64.50584)
					)
				)
			)
		)
		(zone
			(layer "F.Cu")
			(hatch none 0.5)
			(connect_pads
				(clearance 0)
			)
			(min_thickness 0.25)
			(keepout
				(tracks not_allowed)
				(vias allowed)
				(pads allowed)
				(copperpour not_allowed)
				(footprints allowed)
			)
			(placement
				(enabled no)
				(sheetname "")
			)
			(fill
				(thermal_gap 0.5)
				(thermal_bridge_width 0.5)
				(island_removal_mode 0)
			)
			(polygon
				(pts
					(arc
						(start 267.44549 -88.28024)
						(mid 266.733782 -88.28024)
						(end 267.44549 -88.28024)
					)
				)
			)
		)
		(zone
			(layer "F.Cu")
			(hatch none 0.5)
			(connect_pads
				(clearance 0)
			)
			(min_thickness 0.25)
			(keepout
				(tracks not_allowed)
				(vias allowed)
				(pads allowed)
				(copperpour not_allowed)
				(footprints allowed)
			)
			(placement
				(enabled no)
				(sheetname "")
			)
			(fill
				(thermal_gap 0.5)
				(thermal_bridge_width 0.5)
				(island_removal_mode 0)
			)
			(polygon
				(pts
					(arc
						(start 267.44549 -64.50584)
						(mid 266.733782 -64.50584)
						(end 267.44549 -64.50584)
					)
				)
			)
		)
		(zone
			(layer "F.Cu")
			(hatch none 0.5)
			(connect_pads
				(clearance 0)
			)
			(min_thickness 0.25)
			(keepout
				(tracks not_allowed)
				(vias allowed)
				(pads allowed)
				(copperpour not_allowed)
				(footprints allowed)
			)
			(placement
				(enabled no)
				(sheetname "")
			)
			(fill
				(thermal_gap 0.5)
				(thermal_bridge_width 0.5)
				(island_removal_mode 0)
			)
			(polygon
				(pts
					(arc
						(start 268.30401 -88.775286)
						(mid 267.592302 -88.775286)
						(end 268.30401 -88.775286)
					)
				)
			)
		)
		(zone
			(layer "F.Cu")
			(hatch none 0.5)
			(connect_pads
				(clearance 0)
			)
			(min_thickness 0.25)
			(keepout
				(tracks not_allowed)
				(vias allowed)
				(pads allowed)
				(copperpour not_allowed)
				(footprints allowed)
			)
			(placement
				(enabled no)
				(sheetname "")
			)
			(fill
				(thermal_gap 0.5)
				(thermal_bridge_width 0.5)
				(island_removal_mode 0)
			)
			(polygon
				(pts
					(arc
						(start 268.30401 -64.010286)
						(mid 267.592302 -64.010286)
						(end 268.30401 -64.010286)
					)
				)
			)
		)
		(zone
			(layer "F.Cu")
			(hatch none 0.5)
			(connect_pads
				(clearance 0)
			)
			(min_thickness 0.25)
			(keepout
				(tracks not_allowed)
				(vias allowed)
				(pads allowed)
				(copperpour not_allowed)
				(footprints allowed)
			)
			(placement
				(enabled no)
				(sheetname "")
			)
			(fill
				(thermal_gap 0.5)
				(thermal_bridge_width 0.5)
				(island_removal_mode 0)
			)
			(polygon
				(pts
					(arc
						(start 268.30401 -63.01994)
						(mid 267.592302 -63.01994)
						(end 268.30401 -63.01994)
					)
				)
			)
		)
		(zone
			(layer "F.Cu")
			(hatch none 0.5)
			(connect_pads
				(clearance 0)
			)
			(min_thickness 0.25)
			(keepout
				(tracks not_allowed)
				(vias allowed)
				(pads allowed)
				(copperpour not_allowed)
				(footprints allowed)
			)
			(placement
				(enabled no)
				(sheetname "")
			)
			(fill
				(thermal_gap 0.5)
				(thermal_bridge_width 0.5)
				(island_removal_mode 0)
			)
			(polygon
				(pts
					(arc
						(start 268.30401 -62.02934)
						(mid 267.592302 -62.02934)
						(end 268.30401 -62.02934)
					)
				)
			)
		)
		(zone
			(layer "F.Cu")
			(hatch none 0.5)
			(connect_pads
				(clearance 0)
			)
			(min_thickness 0.25)
			(keepout
				(tracks not_allowed)
				(vias allowed)
				(pads allowed)
				(copperpour not_allowed)
				(footprints allowed)
			)
			(placement
				(enabled no)
				(sheetname "")
			)
			(fill
				(thermal_gap 0.5)
				(thermal_bridge_width 0.5)
				(island_removal_mode 0)
			)
			(polygon
				(pts
					(arc
						(start 268.30401 -61.038994)
						(mid 267.592302 -61.038994)
						(end 268.30401 -61.038994)
					)
				)
			)
		)
		(zone
			(layer "F.Cu")
			(hatch none 0.5)
			(connect_pads
				(clearance 0)
			)
			(min_thickness 0.25)
			(keepout
				(tracks not_allowed)
				(vias allowed)
				(pads allowed)
				(copperpour not_allowed)
				(footprints allowed)
			)
			(placement
				(enabled no)
				(sheetname "")
			)
			(fill
				(thermal_gap 0.5)
				(thermal_bridge_width 0.5)
				(island_removal_mode 0)
			)
			(polygon
				(pts
					(arc
						(start 268.30401 -60.048394)
						(mid 267.592302 -60.048394)
						(end 268.30401 -60.048394)
					)
				)
			)
		)
		(zone
			(layer "F.Cu")
			(hatch none 0.5)
			(connect_pads
				(clearance 0)
			)
			(min_thickness 0.25)
			(keepout
				(tracks not_allowed)
				(vias allowed)
				(pads allowed)
				(copperpour not_allowed)
				(footprints allowed)
			)
			(placement
				(enabled no)
				(sheetname "")
			)
			(fill
				(thermal_gap 0.5)
				(thermal_bridge_width 0.5)
				(island_removal_mode 0)
			)
			(polygon
				(pts
					(arc
						(start 268.30401 -59.057794)
						(mid 267.592302 -59.057794)
						(end 268.30401 -59.057794)
					)
				)
			)
		)
		(zone
			(layer "F.Cu")
			(hatch none 0.5)
			(connect_pads
				(clearance 0)
			)
			(min_thickness 0.25)
			(keepout
				(tracks not_allowed)
				(vias allowed)
				(pads allowed)
				(copperpour not_allowed)
				(footprints allowed)
			)
			(placement
				(enabled no)
				(sheetname "")
			)
			(fill
				(thermal_gap 0.5)
				(thermal_bridge_width 0.5)
				(island_removal_mode 0)
			)
			(polygon
				(pts
					(arc
						(start 268.30401 -58.067448)
						(mid 267.592302 -58.067448)
						(end 268.30401 -58.067448)
					)
				)
			)
		)
		(zone
			(layer "F.Cu")
			(hatch none 0.5)
			(connect_pads
				(clearance 0)
			)
			(min_thickness 0.25)
			(keepout
				(tracks not_allowed)
				(vias allowed)
				(pads allowed)
				(copperpour not_allowed)
				(footprints allowed)
			)
			(placement
				(enabled no)
				(sheetname "")
			)
			(fill
				(thermal_gap 0.5)
				(thermal_bridge_width 0.5)
				(island_removal_mode 0)
			)
			(polygon
				(pts
					(arc
						(start 268.30401 -56.086502)
						(mid 267.592302 -56.086502)
						(end 268.30401 -56.086502)
					)
				)
			)
		)
		(zone
			(layer "F.Cu")
			(hatch none 0.5)
			(connect_pads
				(clearance 0)
			)
			(min_thickness 0.25)
			(keepout
				(tracks not_allowed)
				(vias allowed)
				(pads allowed)
				(copperpour not_allowed)
				(footprints allowed)
			)
			(placement
				(enabled no)
				(sheetname "")
			)
			(fill
				(thermal_gap 0.5)
				(thermal_bridge_width 0.5)
				(island_removal_mode 0)
			)
			(polygon
				(pts
					(arc
						(start 268.30401 -55.095902)
						(mid 267.592302 -55.095902)
						(end 268.30401 -55.095902)
					)
				)
			)
		)
		(zone
			(layer "F.Cu")
			(hatch none 0.5)
			(connect_pads
				(clearance 0)
			)
			(min_thickness 0.25)
			(keepout
				(tracks not_allowed)
				(vias allowed)
				(pads allowed)
				(copperpour not_allowed)
				(footprints allowed)
			)
			(placement
				(enabled no)
				(sheetname "")
			)
			(fill
				(thermal_gap 0.5)
				(thermal_bridge_width 0.5)
				(island_removal_mode 0)
			)
			(polygon
				(pts
					(arc
						(start 268.30401 -54.105302)
						(mid 267.592302 -54.105302)
						(end 268.30401 -54.105302)
					)
				)
			)
		)
		(zone
			(layer "F.Cu")
			(hatch none 0.5)
			(connect_pads
				(clearance 0)
			)
			(min_thickness 0.25)
			(keepout
				(tracks not_allowed)
				(vias allowed)
				(pads allowed)
				(copperpour not_allowed)
				(footprints allowed)
			)
			(placement
				(enabled no)
				(sheetname "")
			)
			(fill
				(thermal_gap 0.5)
				(thermal_bridge_width 0.5)
				(island_removal_mode 0)
			)
			(polygon
				(pts
					(arc
						(start 268.30401 -53.114956)
						(mid 267.592302 -53.114956)
						(end 268.30401 -53.114956)
					)
				)
			)
		)
		(zone
			(layer "F.Cu")
			(hatch none 0.5)
			(connect_pads
				(clearance 0)
			)
			(min_thickness 0.25)
			(keepout
				(tracks not_allowed)
				(vias allowed)
				(pads allowed)
				(copperpour not_allowed)
				(footprints allowed)
			)
			(placement
				(enabled no)
				(sheetname "")
			)
			(fill
				(thermal_gap 0.5)
				(thermal_bridge_width 0.5)
				(island_removal_mode 0)
			)
			(polygon
				(pts
					(arc
						(start 268.30401 -52.124356)
						(mid 267.592302 -52.124356)
						(end 268.30401 -52.124356)
					)
				)
			)
		)
		(zone
			(layer "F.Cu")
			(hatch none 0.5)
			(connect_pads
				(clearance 0)
			)
			(min_thickness 0.25)
			(keepout
				(tracks not_allowed)
				(vias allowed)
				(pads allowed)
				(copperpour not_allowed)
				(footprints allowed)
			)
			(placement
				(enabled no)
				(sheetname "")
			)
			(fill
				(thermal_gap 0.5)
				(thermal_bridge_width 0.5)
				(island_removal_mode 0)
			)
			(polygon
				(pts
					(arc
						(start 269.162276 -100.167186)
						(mid 268.451076 -100.167186)
						(end 269.162276 -100.167186)
					)
				)
			)
		)
		(zone
			(layer "F.Cu")
			(hatch none 0.5)
			(connect_pads
				(clearance 0)
			)
			(min_thickness 0.25)
			(keepout
				(tracks not_allowed)
				(vias allowed)
				(pads allowed)
				(copperpour not_allowed)
				(footprints allowed)
			)
			(placement
				(enabled no)
				(sheetname "")
			)
			(fill
				(thermal_gap 0.5)
				(thermal_bridge_width 0.5)
				(island_removal_mode 0)
			)
			(polygon
				(pts
					(arc
						(start 269.162276 -99.17684)
						(mid 268.451076 -99.17684)
						(end 269.162276 -99.17684)
					)
				)
			)
		)
		(zone
			(layer "F.Cu")
			(hatch none 0.5)
			(connect_pads
				(clearance 0)
			)
			(min_thickness 0.25)
			(keepout
				(tracks not_allowed)
				(vias allowed)
				(pads allowed)
				(copperpour not_allowed)
				(footprints allowed)
			)
			(placement
				(enabled no)
				(sheetname "")
			)
			(fill
				(thermal_gap 0.5)
				(thermal_bridge_width 0.5)
				(island_removal_mode 0)
			)
			(polygon
				(pts
					(arc
						(start 269.162276 -98.18624)
						(mid 268.451076 -98.18624)
						(end 269.162276 -98.18624)
					)
				)
			)
		)
		(zone
			(layer "F.Cu")
			(hatch none 0.5)
			(connect_pads
				(clearance 0)
			)
			(min_thickness 0.25)
			(keepout
				(tracks not_allowed)
				(vias allowed)
				(pads allowed)
				(copperpour not_allowed)
				(footprints allowed)
			)
			(placement
				(enabled no)
				(sheetname "")
			)
			(fill
				(thermal_gap 0.5)
				(thermal_bridge_width 0.5)
				(island_removal_mode 0)
			)
			(polygon
				(pts
					(arc
						(start 269.162276 -97.195894)
						(mid 268.451076 -97.195894)
						(end 269.162276 -97.195894)
					)
				)
			)
		)
		(zone
			(layer "F.Cu")
			(hatch none 0.5)
			(connect_pads
				(clearance 0)
			)
			(min_thickness 0.25)
			(keepout
				(tracks not_allowed)
				(vias allowed)
				(pads allowed)
				(copperpour not_allowed)
				(footprints allowed)
			)
			(placement
				(enabled no)
				(sheetname "")
			)
			(fill
				(thermal_gap 0.5)
				(thermal_bridge_width 0.5)
				(island_removal_mode 0)
			)
			(polygon
				(pts
					(arc
						(start 269.162276 -96.205294)
						(mid 268.451076 -96.205294)
						(end 269.162276 -96.205294)
					)
				)
			)
		)
		(zone
			(layer "F.Cu")
			(hatch none 0.5)
			(connect_pads
				(clearance 0)
			)
			(min_thickness 0.25)
			(keepout
				(tracks not_allowed)
				(vias allowed)
				(pads allowed)
				(copperpour not_allowed)
				(footprints allowed)
			)
			(placement
				(enabled no)
				(sheetname "")
			)
			(fill
				(thermal_gap 0.5)
				(thermal_bridge_width 0.5)
				(island_removal_mode 0)
			)
			(polygon
				(pts
					(arc
						(start 269.162276 -95.214694)
						(mid 268.451076 -95.214694)
						(end 269.162276 -95.214694)
					)
				)
			)
		)
		(zone
			(layer "F.Cu")
			(hatch none 0.5)
			(connect_pads
				(clearance 0)
			)
			(min_thickness 0.25)
			(keepout
				(tracks not_allowed)
				(vias allowed)
				(pads allowed)
				(copperpour not_allowed)
				(footprints allowed)
			)
			(placement
				(enabled no)
				(sheetname "")
			)
			(fill
				(thermal_gap 0.5)
				(thermal_bridge_width 0.5)
				(island_removal_mode 0)
			)
			(polygon
				(pts
					(arc
						(start 269.162276 -93.233748)
						(mid 268.451076 -93.233748)
						(end 269.162276 -93.233748)
					)
				)
			)
		)
		(zone
			(layer "F.Cu")
			(hatch none 0.5)
			(connect_pads
				(clearance 0)
			)
			(min_thickness 0.25)
			(keepout
				(tracks not_allowed)
				(vias allowed)
				(pads allowed)
				(copperpour not_allowed)
				(footprints allowed)
			)
			(placement
				(enabled no)
				(sheetname "")
			)
			(fill
				(thermal_gap 0.5)
				(thermal_bridge_width 0.5)
				(island_removal_mode 0)
			)
			(polygon
				(pts
					(arc
						(start 269.162276 -92.243402)
						(mid 268.451076 -92.243402)
						(end 269.162276 -92.243402)
					)
				)
			)
		)
		(zone
			(layer "F.Cu")
			(hatch none 0.5)
			(connect_pads
				(clearance 0)
			)
			(min_thickness 0.25)
			(keepout
				(tracks not_allowed)
				(vias allowed)
				(pads allowed)
				(copperpour not_allowed)
				(footprints allowed)
			)
			(placement
				(enabled no)
				(sheetname "")
			)
			(fill
				(thermal_gap 0.5)
				(thermal_bridge_width 0.5)
				(island_removal_mode 0)
			)
			(polygon
				(pts
					(arc
						(start 269.162276 -91.252802)
						(mid 268.451076 -91.252802)
						(end 269.162276 -91.252802)
					)
				)
			)
		)
		(zone
			(layer "F.Cu")
			(hatch none 0.5)
			(connect_pads
				(clearance 0)
			)
			(min_thickness 0.25)
			(keepout
				(tracks not_allowed)
				(vias allowed)
				(pads allowed)
				(copperpour not_allowed)
				(footprints allowed)
			)
			(placement
				(enabled no)
				(sheetname "")
			)
			(fill
				(thermal_gap 0.5)
				(thermal_bridge_width 0.5)
				(island_removal_mode 0)
			)
			(polygon
				(pts
					(arc
						(start 269.162276 -90.262202)
						(mid 268.451076 -90.262202)
						(end 269.162276 -90.262202)
					)
				)
			)
		)
		(zone
			(layer "F.Cu")
			(hatch none 0.5)
			(connect_pads
				(clearance 0)
			)
			(min_thickness 0.25)
			(keepout
				(tracks not_allowed)
				(vias allowed)
				(pads allowed)
				(copperpour not_allowed)
				(footprints allowed)
			)
			(placement
				(enabled no)
				(sheetname "")
			)
			(fill
				(thermal_gap 0.5)
				(thermal_bridge_width 0.5)
				(island_removal_mode 0)
			)
			(polygon
				(pts
					(arc
						(start 269.162276 -89.271856)
						(mid 268.451076 -89.271856)
						(end 269.162276 -89.271856)
					)
				)
			)
		)
		(zone
			(layer "F.Cu")
			(hatch none 0.5)
			(connect_pads
				(clearance 0)
			)
			(min_thickness 0.25)
			(keepout
				(tracks not_allowed)
				(vias allowed)
				(pads allowed)
				(copperpour not_allowed)
				(footprints allowed)
			)
			(placement
				(enabled no)
				(sheetname "")
			)
			(fill
				(thermal_gap 0.5)
				(thermal_bridge_width 0.5)
				(island_removal_mode 0)
			)
			(polygon
				(pts
					(arc
						(start 271.549368 -63.828168)
						(mid 270.838168 -63.828168)
						(end 271.549368 -63.828168)
					)
				)
			)
		)
		(zone
			(layer "F.Cu")
			(hatch none 0.5)
			(connect_pads
				(clearance 0)
			)
			(min_thickness 0.25)
			(keepout
				(tracks not_allowed)
				(vias allowed)
				(pads allowed)
				(copperpour not_allowed)
				(footprints allowed)
			)
			(placement
				(enabled no)
				(sheetname "")
			)
			(fill
				(thermal_gap 0.5)
				(thermal_bridge_width 0.5)
				(island_removal_mode 0)
			)
			(polygon
				(pts
					(arc
						(start 271.549368 -62.837822)
						(mid 270.838168 -62.837822)
						(end 271.549368 -62.837822)
					)
				)
			)
		)
		(zone
			(layer "F.Cu")
			(hatch none 0.5)
			(connect_pads
				(clearance 0)
			)
			(min_thickness 0.25)
			(keepout
				(tracks not_allowed)
				(vias allowed)
				(pads allowed)
				(copperpour not_allowed)
				(footprints allowed)
			)
			(placement
				(enabled no)
				(sheetname "")
			)
			(fill
				(thermal_gap 0.5)
				(thermal_bridge_width 0.5)
				(island_removal_mode 0)
			)
			(polygon
				(pts
					(arc
						(start 271.549368 -61.847222)
						(mid 270.838168 -61.847222)
						(end 271.549368 -61.847222)
					)
				)
			)
		)
		(zone
			(layer "F.Cu")
			(hatch none 0.5)
			(connect_pads
				(clearance 0)
			)
			(min_thickness 0.25)
			(keepout
				(tracks not_allowed)
				(vias allowed)
				(pads allowed)
				(copperpour not_allowed)
				(footprints allowed)
			)
			(placement
				(enabled no)
				(sheetname "")
			)
			(fill
				(thermal_gap 0.5)
				(thermal_bridge_width 0.5)
				(island_removal_mode 0)
			)
			(polygon
				(pts
					(arc
						(start 271.549368 -60.856622)
						(mid 270.838168 -60.856622)
						(end 271.549368 -60.856622)
					)
				)
			)
		)
		(zone
			(layer "F.Cu")
			(hatch none 0.5)
			(connect_pads
				(clearance 0)
			)
			(min_thickness 0.25)
			(keepout
				(tracks not_allowed)
				(vias allowed)
				(pads allowed)
				(copperpour not_allowed)
				(footprints allowed)
			)
			(placement
				(enabled no)
				(sheetname "")
			)
			(fill
				(thermal_gap 0.5)
				(thermal_bridge_width 0.5)
				(island_removal_mode 0)
			)
			(polygon
				(pts
					(arc
						(start 271.549368 -59.866276)
						(mid 270.838168 -59.866276)
						(end 271.549368 -59.866276)
					)
				)
			)
		)
		(zone
			(layer "F.Cu")
			(hatch none 0.5)
			(connect_pads
				(clearance 0)
			)
			(min_thickness 0.25)
			(keepout
				(tracks not_allowed)
				(vias allowed)
				(pads allowed)
				(copperpour not_allowed)
				(footprints allowed)
			)
			(placement
				(enabled no)
				(sheetname "")
			)
			(fill
				(thermal_gap 0.5)
				(thermal_bridge_width 0.5)
				(island_removal_mode 0)
			)
			(polygon
				(pts
					(arc
						(start 271.549368 -58.875676)
						(mid 270.838168 -58.875676)
						(end 271.549368 -58.875676)
					)
				)
			)
		)
		(zone
			(layer "F.Cu")
			(hatch none 0.5)
			(connect_pads
				(clearance 0)
			)
			(min_thickness 0.25)
			(keepout
				(tracks not_allowed)
				(vias allowed)
				(pads allowed)
				(copperpour not_allowed)
				(footprints allowed)
			)
			(placement
				(enabled no)
				(sheetname "")
			)
			(fill
				(thermal_gap 0.5)
				(thermal_bridge_width 0.5)
				(island_removal_mode 0)
			)
			(polygon
				(pts
					(arc
						(start 271.549368 -57.88533)
						(mid 270.838168 -57.88533)
						(end 271.549368 -57.88533)
					)
				)
			)
		)
		(zone
			(layer "F.Cu")
			(hatch none 0.5)
			(connect_pads
				(clearance 0)
			)
			(min_thickness 0.25)
			(keepout
				(tracks not_allowed)
				(vias allowed)
				(pads allowed)
				(copperpour not_allowed)
				(footprints allowed)
			)
			(placement
				(enabled no)
				(sheetname "")
			)
			(fill
				(thermal_gap 0.5)
				(thermal_bridge_width 0.5)
				(island_removal_mode 0)
			)
			(polygon
				(pts
					(arc
						(start 271.549368 -56.89473)
						(mid 270.838168 -56.89473)
						(end 271.549368 -56.89473)
					)
				)
			)
		)
		(zone
			(layer "F.Cu")
			(hatch none 0.5)
			(connect_pads
				(clearance 0)
			)
			(min_thickness 0.25)
			(keepout
				(tracks not_allowed)
				(vias allowed)
				(pads allowed)
				(copperpour not_allowed)
				(footprints allowed)
			)
			(placement
				(enabled no)
				(sheetname "")
			)
			(fill
				(thermal_gap 0.5)
				(thermal_bridge_width 0.5)
				(island_removal_mode 0)
			)
			(polygon
				(pts
					(arc
						(start 271.549368 -55.90413)
						(mid 270.838168 -55.90413)
						(end 271.549368 -55.90413)
					)
				)
			)
		)
		(zone
			(layer "F.Cu")
			(hatch none 0.5)
			(connect_pads
				(clearance 0)
			)
			(min_thickness 0.25)
			(keepout
				(tracks not_allowed)
				(vias allowed)
				(pads allowed)
				(copperpour not_allowed)
				(footprints allowed)
			)
			(placement
				(enabled no)
				(sheetname "")
			)
			(fill
				(thermal_gap 0.5)
				(thermal_bridge_width 0.5)
				(island_removal_mode 0)
			)
			(polygon
				(pts
					(arc
						(start 271.549368 -54.913784)
						(mid 270.838168 -54.913784)
						(end 271.549368 -54.913784)
					)
				)
			)
		)
		(zone
			(layer "F.Cu")
			(hatch none 0.5)
			(connect_pads
				(clearance 0)
			)
			(min_thickness 0.25)
			(keepout
				(tracks not_allowed)
				(vias allowed)
				(pads allowed)
				(copperpour not_allowed)
				(footprints allowed)
			)
			(placement
				(enabled no)
				(sheetname "")
			)
			(fill
				(thermal_gap 0.5)
				(thermal_bridge_width 0.5)
				(island_removal_mode 0)
			)
			(polygon
				(pts
					(arc
						(start 271.549368 -53.923184)
						(mid 270.838168 -53.923184)
						(end 271.549368 -53.923184)
					)
				)
			)
		)
		(zone
			(layer "F.Cu")
			(hatch none 0.5)
			(connect_pads
				(clearance 0)
			)
			(min_thickness 0.25)
			(keepout
				(tracks not_allowed)
				(vias allowed)
				(pads allowed)
				(copperpour not_allowed)
				(footprints allowed)
			)
			(placement
				(enabled no)
				(sheetname "")
			)
			(fill
				(thermal_gap 0.5)
				(thermal_bridge_width 0.5)
				(island_removal_mode 0)
			)
			(polygon
				(pts
					(arc
						(start 271.549368 -52.932838)
						(mid 270.838168 -52.932838)
						(end 271.549368 -52.932838)
					)
				)
			)
		)
		(zone
			(layer "F.Cu")
			(hatch none 0.5)
			(connect_pads
				(clearance 0)
			)
			(min_thickness 0.25)
			(keepout
				(tracks not_allowed)
				(vias allowed)
				(pads allowed)
				(copperpour not_allowed)
				(footprints allowed)
			)
			(placement
				(enabled no)
				(sheetname "")
			)
			(fill
				(thermal_gap 0.5)
				(thermal_bridge_width 0.5)
				(island_removal_mode 0)
			)
			(polygon
				(pts
					(arc
						(start 272.407634 -100.975668)
						(mid 271.696942 -100.975668)
						(end 272.407634 -100.975668)
					)
				)
			)
		)
		(zone
			(layer "F.Cu")
			(hatch none 0.5)
			(connect_pads
				(clearance 0)
			)
			(min_thickness 0.25)
			(keepout
				(tracks not_allowed)
				(vias allowed)
				(pads allowed)
				(copperpour not_allowed)
				(footprints allowed)
			)
			(placement
				(enabled no)
				(sheetname "")
			)
			(fill
				(thermal_gap 0.5)
				(thermal_bridge_width 0.5)
				(island_removal_mode 0)
			)
			(polygon
				(pts
					(arc
						(start 272.407634 -99.985068)
						(mid 271.696942 -99.985068)
						(end 272.407634 -99.985068)
					)
				)
			)
		)
		(zone
			(layer "F.Cu")
			(hatch none 0.5)
			(connect_pads
				(clearance 0)
			)
			(min_thickness 0.25)
			(keepout
				(tracks not_allowed)
				(vias allowed)
				(pads allowed)
				(copperpour not_allowed)
				(footprints allowed)
			)
			(placement
				(enabled no)
				(sheetname "")
			)
			(fill
				(thermal_gap 0.5)
				(thermal_bridge_width 0.5)
				(island_removal_mode 0)
			)
			(polygon
				(pts
					(arc
						(start 272.407634 -98.994722)
						(mid 271.696942 -98.994722)
						(end 272.407634 -98.994722)
					)
				)
			)
		)
		(zone
			(layer "F.Cu")
			(hatch none 0.5)
			(connect_pads
				(clearance 0)
			)
			(min_thickness 0.25)
			(keepout
				(tracks not_allowed)
				(vias allowed)
				(pads allowed)
				(copperpour not_allowed)
				(footprints allowed)
			)
			(placement
				(enabled no)
				(sheetname "")
			)
			(fill
				(thermal_gap 0.5)
				(thermal_bridge_width 0.5)
				(island_removal_mode 0)
			)
			(polygon
				(pts
					(arc
						(start 272.407634 -98.004122)
						(mid 271.696942 -98.004122)
						(end 272.407634 -98.004122)
					)
				)
			)
		)
		(zone
			(layer "F.Cu")
			(hatch none 0.5)
			(connect_pads
				(clearance 0)
			)
			(min_thickness 0.25)
			(keepout
				(tracks not_allowed)
				(vias allowed)
				(pads allowed)
				(copperpour not_allowed)
				(footprints allowed)
			)
			(placement
				(enabled no)
				(sheetname "")
			)
			(fill
				(thermal_gap 0.5)
				(thermal_bridge_width 0.5)
				(island_removal_mode 0)
			)
			(polygon
				(pts
					(arc
						(start 272.407634 -97.013522)
						(mid 271.696942 -97.013522)
						(end 272.407634 -97.013522)
					)
				)
			)
		)
		(zone
			(layer "F.Cu")
			(hatch none 0.5)
			(connect_pads
				(clearance 0)
			)
			(min_thickness 0.25)
			(keepout
				(tracks not_allowed)
				(vias allowed)
				(pads allowed)
				(copperpour not_allowed)
				(footprints allowed)
			)
			(placement
				(enabled no)
				(sheetname "")
			)
			(fill
				(thermal_gap 0.5)
				(thermal_bridge_width 0.5)
				(island_removal_mode 0)
			)
			(polygon
				(pts
					(arc
						(start 272.407634 -96.023176)
						(mid 271.696942 -96.023176)
						(end 272.407634 -96.023176)
					)
				)
			)
		)
		(zone
			(layer "F.Cu")
			(hatch none 0.5)
			(connect_pads
				(clearance 0)
			)
			(min_thickness 0.25)
			(keepout
				(tracks not_allowed)
				(vias allowed)
				(pads allowed)
				(copperpour not_allowed)
				(footprints allowed)
			)
			(placement
				(enabled no)
				(sheetname "")
			)
			(fill
				(thermal_gap 0.5)
				(thermal_bridge_width 0.5)
				(island_removal_mode 0)
			)
			(polygon
				(pts
					(arc
						(start 272.407634 -95.032576)
						(mid 271.696942 -95.032576)
						(end 272.407634 -95.032576)
					)
				)
			)
		)
		(zone
			(layer "F.Cu")
			(hatch none 0.5)
			(connect_pads
				(clearance 0)
			)
			(min_thickness 0.25)
			(keepout
				(tracks not_allowed)
				(vias allowed)
				(pads allowed)
				(copperpour not_allowed)
				(footprints allowed)
			)
			(placement
				(enabled no)
				(sheetname "")
			)
			(fill
				(thermal_gap 0.5)
				(thermal_bridge_width 0.5)
				(island_removal_mode 0)
			)
			(polygon
				(pts
					(arc
						(start 272.407634 -94.04223)
						(mid 271.696942 -94.04223)
						(end 272.407634 -94.04223)
					)
				)
			)
		)
		(zone
			(layer "F.Cu")
			(hatch none 0.5)
			(connect_pads
				(clearance 0)
			)
			(min_thickness 0.25)
			(keepout
				(tracks not_allowed)
				(vias allowed)
				(pads allowed)
				(copperpour not_allowed)
				(footprints allowed)
			)
			(placement
				(enabled no)
				(sheetname "")
			)
			(fill
				(thermal_gap 0.5)
				(thermal_bridge_width 0.5)
				(island_removal_mode 0)
			)
			(polygon
				(pts
					(arc
						(start 272.407634 -93.05163)
						(mid 271.696942 -93.05163)
						(end 272.407634 -93.05163)
					)
				)
			)
		)
		(zone
			(layer "F.Cu")
			(hatch none 0.5)
			(connect_pads
				(clearance 0)
			)
			(min_thickness 0.25)
			(keepout
				(tracks not_allowed)
				(vias allowed)
				(pads allowed)
				(copperpour not_allowed)
				(footprints allowed)
			)
			(placement
				(enabled no)
				(sheetname "")
			)
			(fill
				(thermal_gap 0.5)
				(thermal_bridge_width 0.5)
				(island_removal_mode 0)
			)
			(polygon
				(pts
					(arc
						(start 272.407634 -92.06103)
						(mid 271.696942 -92.06103)
						(end 272.407634 -92.06103)
					)
				)
			)
		)
		(zone
			(layer "F.Cu")
			(hatch none 0.5)
			(connect_pads
				(clearance 0)
			)
			(min_thickness 0.25)
			(keepout
				(tracks not_allowed)
				(vias allowed)
				(pads allowed)
				(copperpour not_allowed)
				(footprints allowed)
			)
			(placement
				(enabled no)
				(sheetname "")
			)
			(fill
				(thermal_gap 0.5)
				(thermal_bridge_width 0.5)
				(island_removal_mode 0)
			)
			(polygon
				(pts
					(arc
						(start 272.407634 -91.070684)
						(mid 271.696942 -91.070684)
						(end 272.407634 -91.070684)
					)
				)
			)
		)
		(zone
			(layer "F.Cu")
			(hatch none 0.5)
			(connect_pads
				(clearance 0)
			)
			(min_thickness 0.25)
			(keepout
				(tracks not_allowed)
				(vias allowed)
				(pads allowed)
				(copperpour not_allowed)
				(footprints allowed)
			)
			(placement
				(enabled no)
				(sheetname "")
			)
			(fill
				(thermal_gap 0.5)
				(thermal_bridge_width 0.5)
				(island_removal_mode 0)
			)
			(polygon
				(pts
					(arc
						(start 272.407634 -90.080084)
						(mid 271.696942 -90.080084)
						(end 272.407634 -90.080084)
					)
				)
			)
		)
		(zone
			(layer "F.Cu")
			(hatch none 0.5)
			(connect_pads
				(clearance 0)
			)
			(min_thickness 0.25)
			(keepout
				(tracks not_allowed)
				(vias allowed)
				(pads allowed)
				(copperpour not_allowed)
				(footprints allowed)
			)
			(placement
				(enabled no)
				(sheetname "")
			)
			(fill
				(thermal_gap 0.5)
				(thermal_bridge_width 0.5)
				(island_removal_mode 0)
			)
			(polygon
				(pts
					(arc
						(start 272.407634 -89.089738)
						(mid 271.696942 -89.089738)
						(end 272.407634 -89.089738)
					)
				)
			)
		)
		(zone
			(layer "F.Cu")
			(hatch none 0.5)
			(connect_pads
				(clearance 0)
			)
			(min_thickness 0.25)
			(keepout
				(tracks not_allowed)
				(vias allowed)
				(pads allowed)
				(copperpour not_allowed)
				(footprints allowed)
			)
			(placement
				(enabled no)
				(sheetname "")
			)
			(fill
				(thermal_gap 0.5)
				(thermal_bridge_width 0.5)
				(island_removal_mode 0)
			)
			(polygon
				(pts
					(arc
						(start 272.407634 -64.324738)
						(mid 271.696942 -64.324738)
						(end 272.407634 -64.324738)
					)
				)
			)
		)
		(zone
			(layer "F.Cu")
			(hatch none 0.5)
			(connect_pads
				(clearance 0)
			)
			(min_thickness 0.25)
			(keepout
				(tracks not_allowed)
				(vias allowed)
				(pads allowed)
				(copperpour not_allowed)
				(footprints allowed)
			)
			(placement
				(enabled no)
				(sheetname "")
			)
			(fill
				(thermal_gap 0.5)
				(thermal_bridge_width 0.5)
				(island_removal_mode 0)
			)
			(polygon
				(pts
					(arc
						(start 273.266154 -88.594184)
						(mid 272.555462 -88.594184)
						(end 273.266154 -88.594184)
					)
				)
			)
		)
		(zone
			(layer "F.Cu")
			(hatch none 0.5)
			(connect_pads
				(clearance 0)
			)
			(min_thickness 0.25)
			(keepout
				(tracks not_allowed)
				(vias allowed)
				(pads allowed)
				(copperpour not_allowed)
				(footprints allowed)
			)
			(placement
				(enabled no)
				(sheetname "")
			)
			(fill
				(thermal_gap 0.5)
				(thermal_bridge_width 0.5)
				(island_removal_mode 0)
			)
			(polygon
				(pts
					(arc
						(start 273.266154 -64.819784)
						(mid 272.555462 -64.819784)
						(end 273.266154 -64.819784)
					)
				)
			)
		)
		(zone
			(layer "F.Cu")
			(hatch none 0.5)
			(connect_pads
				(clearance 0)
			)
			(min_thickness 0.25)
			(keepout
				(tracks not_allowed)
				(vias allowed)
				(pads allowed)
				(copperpour not_allowed)
				(footprints allowed)
			)
			(placement
				(enabled no)
				(sheetname "")
			)
			(fill
				(thermal_gap 0.5)
				(thermal_bridge_width 0.5)
				(island_removal_mode 0)
			)
			(polygon
				(pts
					(arc
						(start 274.983194 -88.594184)
						(mid 274.272502 -88.594184)
						(end 274.983194 -88.594184)
					)
				)
			)
		)
		(zone
			(layer "F.Cu")
			(hatch none 0.5)
			(connect_pads
				(clearance 0)
			)
			(min_thickness 0.25)
			(keepout
				(tracks not_allowed)
				(vias allowed)
				(pads allowed)
				(copperpour not_allowed)
				(footprints allowed)
			)
			(placement
				(enabled no)
				(sheetname "")
			)
			(fill
				(thermal_gap 0.5)
				(thermal_bridge_width 0.5)
				(island_removal_mode 0)
			)
			(polygon
				(pts
					(arc
						(start 274.983194 -64.819784)
						(mid 274.272502 -64.819784)
						(end 274.983194 -64.819784)
					)
				)
			)
		)
		(zone
			(layer "F.Cu")
			(hatch none 0.5)
			(connect_pads
				(clearance 0)
			)
			(min_thickness 0.25)
			(keepout
				(tracks not_allowed)
				(vias allowed)
				(pads allowed)
				(copperpour not_allowed)
				(footprints allowed)
			)
			(placement
				(enabled no)
				(sheetname "")
			)
			(fill
				(thermal_gap 0.5)
				(thermal_bridge_width 0.5)
				(island_removal_mode 0)
			)
			(polygon
				(pts
					(arc
						(start 276.700488 -88.594184)
						(mid 275.98878 -88.594184)
						(end 276.700488 -88.594184)
					)
				)
			)
		)
		(zone
			(layer "F.Cu")
			(hatch none 0.5)
			(connect_pads
				(clearance 0)
			)
			(min_thickness 0.25)
			(keepout
				(tracks not_allowed)
				(vias allowed)
				(pads allowed)
				(copperpour not_allowed)
				(footprints allowed)
			)
			(placement
				(enabled no)
				(sheetname "")
			)
			(fill
				(thermal_gap 0.5)
				(thermal_bridge_width 0.5)
				(island_removal_mode 0)
			)
			(polygon
				(pts
					(arc
						(start 276.700488 -64.819784)
						(mid 275.98878 -64.819784)
						(end 276.700488 -64.819784)
					)
				)
			)
		)
		(zone
			(layer "F.Cu")
			(hatch none 0.5)
			(connect_pads
				(clearance 0)
			)
			(min_thickness 0.25)
			(keepout
				(tracks not_allowed)
				(vias allowed)
				(pads allowed)
				(copperpour not_allowed)
				(footprints allowed)
			)
			(placement
				(enabled no)
				(sheetname "")
			)
			(fill
				(thermal_gap 0.5)
				(thermal_bridge_width 0.5)
				(island_removal_mode 0)
			)
			(polygon
				(pts
					(arc
						(start 277.559008 -65.315338)
						(mid 276.8473 -65.315338)
						(end 277.559008 -65.315338)
					)
				)
			)
		)
		(zone
			(layer "F.Cu")
			(hatch none 0.5)
			(connect_pads
				(clearance 0)
			)
			(min_thickness 0.25)
			(keepout
				(tracks not_allowed)
				(vias allowed)
				(pads allowed)
				(copperpour not_allowed)
				(footprints allowed)
			)
			(placement
				(enabled no)
				(sheetname "")
			)
			(fill
				(thermal_gap 0.5)
				(thermal_bridge_width 0.5)
				(island_removal_mode 0)
			)
			(polygon
				(pts
					(arc
						(start 278.417274 -88.594184)
						(mid 277.706074 -88.594184)
						(end 278.417274 -88.594184)
					)
				)
			)
		)
		(zone
			(layer "F.Cu")
			(hatch none 0.5)
			(connect_pads
				(clearance 0)
			)
			(min_thickness 0.25)
			(keepout
				(tracks not_allowed)
				(vias allowed)
				(pads allowed)
				(copperpour not_allowed)
				(footprints allowed)
			)
			(placement
				(enabled no)
				(sheetname "")
			)
			(fill
				(thermal_gap 0.5)
				(thermal_bridge_width 0.5)
				(island_removal_mode 0)
			)
			(polygon
				(pts
					(arc
						(start 278.417274 -65.810384)
						(mid 277.706074 -65.810384)
						(end 278.417274 -65.810384)
					)
				)
			)
		)
		(zone
			(layer "F.Cu")
			(hatch none 0.5)
			(connect_pads
				(clearance 0)
			)
			(min_thickness 0.25)
			(keepout
				(tracks not_allowed)
				(vias allowed)
				(pads allowed)
				(copperpour not_allowed)
				(footprints allowed)
			)
			(placement
				(enabled no)
				(sheetname "")
			)
			(fill
				(thermal_gap 0.5)
				(thermal_bridge_width 0.5)
				(island_removal_mode 0)
			)
			(polygon
				(pts
					(arc
						(start 279.275794 -88.099138)
						(mid 278.564594 -88.099138)
						(end 279.275794 -88.099138)
					)
				)
			)
		)
		(zone
			(layer "F.Cu")
			(hatch none 0.5)
			(connect_pads
				(clearance 0)
			)
			(min_thickness 0.25)
			(keepout
				(tracks not_allowed)
				(vias allowed)
				(pads allowed)
				(copperpour not_allowed)
				(footprints allowed)
			)
			(placement
				(enabled no)
				(sheetname "")
			)
			(fill
				(thermal_gap 0.5)
				(thermal_bridge_width 0.5)
				(island_removal_mode 0)
			)
			(polygon
				(pts
					(arc
						(start 279.275794 -66.305938)
						(mid 278.564594 -66.305938)
						(end 279.275794 -66.305938)
					)
				)
			)
		)
		(zone
			(layer "F.Cu")
			(hatch none 0.5)
			(connect_pads
				(clearance 0)
			)
			(min_thickness 0.25)
			(keepout
				(tracks not_allowed)
				(vias allowed)
				(pads allowed)
				(copperpour not_allowed)
				(footprints allowed)
			)
			(placement
				(enabled no)
				(sheetname "")
			)
			(fill
				(thermal_gap 0.5)
				(thermal_bridge_width 0.5)
				(island_removal_mode 0)
			)
			(polygon
				(pts
					(arc
						(start 280.134314 -87.603584)
						(mid 279.423114 -87.603584)
						(end 280.134314 -87.603584)
					)
				)
			)
		)
		(zone
			(layer "F.Cu")
			(hatch none 0.5)
			(connect_pads
				(clearance 0)
			)
			(min_thickness 0.25)
			(keepout
				(tracks not_allowed)
				(vias allowed)
				(pads allowed)
				(copperpour not_allowed)
				(footprints allowed)
			)
			(placement
				(enabled no)
				(sheetname "")
			)
			(fill
				(thermal_gap 0.5)
				(thermal_bridge_width 0.5)
				(island_removal_mode 0)
			)
			(polygon
				(pts
					(arc
						(start 280.134314 -66.800984)
						(mid 279.423114 -66.800984)
						(end 280.134314 -66.800984)
					)
				)
			)
		)
		(zone
			(layer "F.Cu")
			(hatch none 0.5)
			(connect_pads
				(clearance 0)
			)
			(min_thickness 0.25)
			(keepout
				(tracks not_allowed)
				(vias allowed)
				(pads allowed)
				(copperpour not_allowed)
				(footprints allowed)
			)
			(placement
				(enabled no)
				(sheetname "")
			)
			(fill
				(thermal_gap 0.5)
				(thermal_bridge_width 0.5)
				(island_removal_mode 0)
			)
			(polygon
				(pts
					(arc
						(start 280.992834 -87.108538)
						(mid 280.281634 -87.108538)
						(end 280.992834 -87.108538)
					)
				)
			)
		)
		(zone
			(layer "F.Cu")
			(hatch none 0.5)
			(connect_pads
				(clearance 0)
			)
			(min_thickness 0.25)
			(keepout
				(tracks not_allowed)
				(vias allowed)
				(pads allowed)
				(copperpour not_allowed)
				(footprints allowed)
			)
			(placement
				(enabled no)
				(sheetname "")
			)
			(fill
				(thermal_gap 0.5)
				(thermal_bridge_width 0.5)
				(island_removal_mode 0)
			)
			(polygon
				(pts
					(arc
						(start 280.992834 -67.296538)
						(mid 280.281634 -67.296538)
						(end 280.992834 -67.296538)
					)
				)
			)
		)
		(zone
			(layer "F.Cu")
			(hatch none 0.5)
			(connect_pads
				(clearance 0)
			)
			(min_thickness 0.25)
			(keepout
				(tracks not_allowed)
				(vias allowed)
				(pads allowed)
				(copperpour not_allowed)
				(footprints allowed)
			)
			(placement
				(enabled no)
				(sheetname "")
			)
			(fill
				(thermal_gap 0.5)
				(thermal_bridge_width 0.5)
				(island_removal_mode 0)
			)
			(polygon
				(pts
					(arc
						(start 281.851354 -86.612984)
						(mid 281.140154 -86.612984)
						(end 281.851354 -86.612984)
					)
				)
			)
		)
		(zone
			(layer "F.Cu")
			(hatch none 0.5)
			(connect_pads
				(clearance 0)
			)
			(min_thickness 0.25)
			(keepout
				(tracks not_allowed)
				(vias allowed)
				(pads allowed)
				(copperpour not_allowed)
				(footprints allowed)
			)
			(placement
				(enabled no)
				(sheetname "")
			)
			(fill
				(thermal_gap 0.5)
				(thermal_bridge_width 0.5)
				(island_removal_mode 0)
			)
			(polygon
				(pts
					(arc
						(start 281.851354 -67.791584)
						(mid 281.140154 -67.791584)
						(end 281.851354 -67.791584)
					)
				)
			)
		)
		(zone
			(layer "F.Cu")
			(hatch none 0.5)
			(connect_pads
				(clearance 0)
			)
			(min_thickness 0.25)
			(keepout
				(tracks not_allowed)
				(vias allowed)
				(pads allowed)
				(copperpour not_allowed)
				(footprints allowed)
			)
			(placement
				(enabled no)
				(sheetname "")
			)
			(fill
				(thermal_gap 0.5)
				(thermal_bridge_width 0.5)
				(island_removal_mode 0)
			)
			(polygon
				(pts
					(arc
						(start 282.709874 -86.117938)
						(mid 281.998674 -86.117938)
						(end 282.709874 -86.117938)
					)
				)
			)
		)
		(zone
			(layer "F.Cu")
			(hatch none 0.5)
			(connect_pads
				(clearance 0)
			)
			(min_thickness 0.25)
			(keepout
				(tracks not_allowed)
				(vias allowed)
				(pads allowed)
				(copperpour not_allowed)
				(footprints allowed)
			)
			(placement
				(enabled no)
				(sheetname "")
			)
			(fill
				(thermal_gap 0.5)
				(thermal_bridge_width 0.5)
				(island_removal_mode 0)
			)
			(polygon
				(pts
					(arc
						(start 282.709874 -68.287138)
						(mid 281.998674 -68.287138)
						(end 282.709874 -68.287138)
					)
				)
			)
		)
		(zone
			(layer "F.Cu")
			(hatch none 0.5)
			(connect_pads
				(clearance 0)
			)
			(min_thickness 0.25)
			(keepout
				(tracks not_allowed)
				(vias allowed)
				(pads allowed)
				(copperpour not_allowed)
				(footprints allowed)
			)
			(placement
				(enabled no)
				(sheetname "")
			)
			(fill
				(thermal_gap 0.5)
				(thermal_bridge_width 0.5)
				(island_removal_mode 0)
			)
			(polygon
				(pts
					(arc
						(start 283.56814 -85.622384)
						(mid 282.857448 -85.622384)
						(end 283.56814 -85.622384)
					)
				)
			)
		)
		(zone
			(layer "F.Cu")
			(hatch none 0.5)
			(connect_pads
				(clearance 0)
			)
			(min_thickness 0.25)
			(keepout
				(tracks not_allowed)
				(vias allowed)
				(pads allowed)
				(copperpour not_allowed)
				(footprints allowed)
			)
			(placement
				(enabled no)
				(sheetname "")
			)
			(fill
				(thermal_gap 0.5)
				(thermal_bridge_width 0.5)
				(island_removal_mode 0)
			)
			(polygon
				(pts
					(arc
						(start 283.56814 -68.782184)
						(mid 282.857448 -68.782184)
						(end 283.56814 -68.782184)
					)
				)
			)
		)
		(zone
			(layer "F.Cu")
			(hatch none 0.5)
			(connect_pads
				(clearance 0)
			)
			(min_thickness 0.25)
			(keepout
				(tracks not_allowed)
				(vias allowed)
				(pads allowed)
				(copperpour not_allowed)
				(footprints allowed)
			)
			(placement
				(enabled no)
				(sheetname "")
			)
			(fill
				(thermal_gap 0.5)
				(thermal_bridge_width 0.5)
				(island_removal_mode 0)
			)
			(polygon
				(pts
					(arc
						(start 284.42666 -85.127338)
						(mid 283.715968 -85.127338)
						(end 284.42666 -85.127338)
					)
				)
			)
		)
		(zone
			(layer "F.Cu")
			(hatch none 0.5)
			(connect_pads
				(clearance 0)
			)
			(min_thickness 0.25)
			(keepout
				(tracks not_allowed)
				(vias allowed)
				(pads allowed)
				(copperpour not_allowed)
				(footprints allowed)
			)
			(placement
				(enabled no)
				(sheetname "")
			)
			(fill
				(thermal_gap 0.5)
				(thermal_bridge_width 0.5)
				(island_removal_mode 0)
			)
			(polygon
				(pts
					(arc
						(start 284.42666 -69.277738)
						(mid 283.715968 -69.277738)
						(end 284.42666 -69.277738)
					)
				)
			)
		)
		(zone
			(layer "F.Cu")
			(hatch none 0.5)
			(connect_pads
				(clearance 0)
			)
			(min_thickness 0.25)
			(keepout
				(tracks not_allowed)
				(vias allowed)
				(pads allowed)
				(copperpour not_allowed)
				(footprints allowed)
			)
			(placement
				(enabled no)
				(sheetname "")
			)
			(fill
				(thermal_gap 0.5)
				(thermal_bridge_width 0.5)
				(island_removal_mode 0)
			)
			(polygon
				(pts
					(arc
						(start 285.28518 -84.63026)
						(mid 284.574488 -84.63026)
						(end 285.28518 -84.63026)
					)
				)
			)
		)
		(zone
			(layer "F.Cu")
			(hatch none 0.5)
			(connect_pads
				(clearance 0)
			)
			(min_thickness 0.25)
			(keepout
				(tracks not_allowed)
				(vias allowed)
				(pads allowed)
				(copperpour not_allowed)
				(footprints allowed)
			)
			(placement
				(enabled no)
				(sheetname "")
			)
			(fill
				(thermal_gap 0.5)
				(thermal_bridge_width 0.5)
				(island_removal_mode 0)
			)
			(polygon
				(pts
					(arc
						(start 285.28518 -83.639914)
						(mid 284.574488 -83.639914)
						(end 285.28518 -83.639914)
					)
				)
			)
		)
		(zone
			(layer "F.Cu")
			(hatch none 0.5)
			(connect_pads
				(clearance 0)
			)
			(min_thickness 0.25)
			(keepout
				(tracks not_allowed)
				(vias allowed)
				(pads allowed)
				(copperpour not_allowed)
				(footprints allowed)
			)
			(placement
				(enabled no)
				(sheetname "")
			)
			(fill
				(thermal_gap 0.5)
				(thermal_bridge_width 0.5)
				(island_removal_mode 0)
			)
			(polygon
				(pts
					(arc
						(start 285.28518 -82.649314)
						(mid 284.574488 -82.649314)
						(end 285.28518 -82.649314)
					)
				)
			)
		)
		(zone
			(layer "F.Cu")
			(hatch none 0.5)
			(connect_pads
				(clearance 0)
			)
			(min_thickness 0.25)
			(keepout
				(tracks not_allowed)
				(vias allowed)
				(pads allowed)
				(copperpour not_allowed)
				(footprints allowed)
			)
			(placement
				(enabled no)
				(sheetname "")
			)
			(fill
				(thermal_gap 0.5)
				(thermal_bridge_width 0.5)
				(island_removal_mode 0)
			)
			(polygon
				(pts
					(arc
						(start 285.28518 -81.658714)
						(mid 284.574488 -81.658714)
						(end 285.28518 -81.658714)
					)
				)
			)
		)
		(zone
			(layer "F.Cu")
			(hatch none 0.5)
			(connect_pads
				(clearance 0)
			)
			(min_thickness 0.25)
			(keepout
				(tracks not_allowed)
				(vias allowed)
				(pads allowed)
				(copperpour not_allowed)
				(footprints allowed)
			)
			(placement
				(enabled no)
				(sheetname "")
			)
			(fill
				(thermal_gap 0.5)
				(thermal_bridge_width 0.5)
				(island_removal_mode 0)
			)
			(polygon
				(pts
					(arc
						(start 285.28518 -80.668368)
						(mid 284.574488 -80.668368)
						(end 285.28518 -80.668368)
					)
				)
			)
		)
		(zone
			(layer "F.Cu")
			(hatch none 0.5)
			(connect_pads
				(clearance 0)
			)
			(min_thickness 0.25)
			(keepout
				(tracks not_allowed)
				(vias allowed)
				(pads allowed)
				(copperpour not_allowed)
				(footprints allowed)
			)
			(placement
				(enabled no)
				(sheetname "")
			)
			(fill
				(thermal_gap 0.5)
				(thermal_bridge_width 0.5)
				(island_removal_mode 0)
			)
			(polygon
				(pts
					(arc
						(start 285.28518 -79.677768)
						(mid 284.574488 -79.677768)
						(end 285.28518 -79.677768)
					)
				)
			)
		)
		(zone
			(layer "F.Cu")
			(hatch none 0.5)
			(connect_pads
				(clearance 0)
			)
			(min_thickness 0.25)
			(keepout
				(tracks not_allowed)
				(vias allowed)
				(pads allowed)
				(copperpour not_allowed)
				(footprints allowed)
			)
			(placement
				(enabled no)
				(sheetname "")
			)
			(fill
				(thermal_gap 0.5)
				(thermal_bridge_width 0.5)
				(island_removal_mode 0)
			)
			(polygon
				(pts
					(arc
						(start 285.28518 -78.687422)
						(mid 284.574488 -78.687422)
						(end 285.28518 -78.687422)
					)
				)
			)
		)
		(zone
			(layer "F.Cu")
			(hatch none 0.5)
			(connect_pads
				(clearance 0)
			)
			(min_thickness 0.25)
			(keepout
				(tracks not_allowed)
				(vias allowed)
				(pads allowed)
				(copperpour not_allowed)
				(footprints allowed)
			)
			(placement
				(enabled no)
				(sheetname "")
			)
			(fill
				(thermal_gap 0.5)
				(thermal_bridge_width 0.5)
				(island_removal_mode 0)
			)
			(polygon
				(pts
					(arc
						(start 285.28518 -77.696822)
						(mid 284.574488 -77.696822)
						(end 285.28518 -77.696822)
					)
				)
			)
		)
		(zone
			(layer "F.Cu")
			(hatch none 0.5)
			(connect_pads
				(clearance 0)
			)
			(min_thickness 0.25)
			(keepout
				(tracks not_allowed)
				(vias allowed)
				(pads allowed)
				(copperpour not_allowed)
				(footprints allowed)
			)
			(placement
				(enabled no)
				(sheetname "")
			)
			(fill
				(thermal_gap 0.5)
				(thermal_bridge_width 0.5)
				(island_removal_mode 0)
			)
			(polygon
				(pts
					(arc
						(start 285.28518 -76.706222)
						(mid 284.574488 -76.706222)
						(end 285.28518 -76.706222)
					)
				)
			)
		)
		(zone
			(layer "F.Cu")
			(hatch none 0.5)
			(connect_pads
				(clearance 0)
			)
			(min_thickness 0.25)
			(keepout
				(tracks not_allowed)
				(vias allowed)
				(pads allowed)
				(copperpour not_allowed)
				(footprints allowed)
			)
			(placement
				(enabled no)
				(sheetname "")
			)
			(fill
				(thermal_gap 0.5)
				(thermal_bridge_width 0.5)
				(island_removal_mode 0)
			)
			(polygon
				(pts
					(arc
						(start 285.28518 -75.715876)
						(mid 284.574488 -75.715876)
						(end 285.28518 -75.715876)
					)
				)
			)
		)
		(zone
			(layer "F.Cu")
			(hatch none 0.5)
			(connect_pads
				(clearance 0)
			)
			(min_thickness 0.25)
			(keepout
				(tracks not_allowed)
				(vias allowed)
				(pads allowed)
				(copperpour not_allowed)
				(footprints allowed)
			)
			(placement
				(enabled no)
				(sheetname "")
			)
			(fill
				(thermal_gap 0.5)
				(thermal_bridge_width 0.5)
				(island_removal_mode 0)
			)
			(polygon
				(pts
					(arc
						(start 285.28518 -74.725276)
						(mid 284.574488 -74.725276)
						(end 285.28518 -74.725276)
					)
				)
			)
		)
		(zone
			(layer "F.Cu")
			(hatch none 0.5)
			(connect_pads
				(clearance 0)
			)
			(min_thickness 0.25)
			(keepout
				(tracks not_allowed)
				(vias allowed)
				(pads allowed)
				(copperpour not_allowed)
				(footprints allowed)
			)
			(placement
				(enabled no)
				(sheetname "")
			)
			(fill
				(thermal_gap 0.5)
				(thermal_bridge_width 0.5)
				(island_removal_mode 0)
			)
			(polygon
				(pts
					(arc
						(start 285.28518 -73.73493)
						(mid 284.574488 -73.73493)
						(end 285.28518 -73.73493)
					)
				)
			)
		)
		(zone
			(layer "F.Cu")
			(hatch none 0.5)
			(connect_pads
				(clearance 0)
			)
			(min_thickness 0.25)
			(keepout
				(tracks not_allowed)
				(vias allowed)
				(pads allowed)
				(copperpour not_allowed)
				(footprints allowed)
			)
			(placement
				(enabled no)
				(sheetname "")
			)
			(fill
				(thermal_gap 0.5)
				(thermal_bridge_width 0.5)
				(island_removal_mode 0)
			)
			(polygon
				(pts
					(arc
						(start 285.28518 -72.74433)
						(mid 284.574488 -72.74433)
						(end 285.28518 -72.74433)
					)
				)
			)
		)
		(zone
			(layer "F.Cu")
			(hatch none 0.5)
			(connect_pads
				(clearance 0)
			)
			(min_thickness 0.25)
			(keepout
				(tracks not_allowed)
				(vias allowed)
				(pads allowed)
				(copperpour not_allowed)
				(footprints allowed)
			)
			(placement
				(enabled no)
				(sheetname "")
			)
			(fill
				(thermal_gap 0.5)
				(thermal_bridge_width 0.5)
				(island_removal_mode 0)
			)
			(polygon
				(pts
					(arc
						(start 285.28518 -71.75373)
						(mid 284.574488 -71.75373)
						(end 285.28518 -71.75373)
					)
				)
			)
		)
		(zone
			(layer "F.Cu")
			(hatch none 0.5)
			(connect_pads
				(clearance 0)
			)
			(min_thickness 0.25)
			(keepout
				(tracks not_allowed)
				(vias allowed)
				(pads allowed)
				(copperpour not_allowed)
				(footprints allowed)
			)
			(placement
				(enabled no)
				(sheetname "")
			)
			(fill
				(thermal_gap 0.5)
				(thermal_bridge_width 0.5)
				(island_removal_mode 0)
			)
			(polygon
				(pts
					(arc
						(start 285.28518 -70.763384)
						(mid 284.574488 -70.763384)
						(end 285.28518 -70.763384)
					)
				)
			)
		)
		(zone
			(layer "F.Cu")
			(hatch none 0.5)
			(connect_pads
				(clearance 0)
			)
			(min_thickness 0.25)
			(keepout
				(tracks not_allowed)
				(vias allowed)
				(pads allowed)
				(copperpour not_allowed)
				(footprints allowed)
			)
			(placement
				(enabled no)
				(sheetname "")
			)
			(fill
				(thermal_gap 0.5)
				(thermal_bridge_width 0.5)
				(island_removal_mode 0)
			)
			(polygon
				(pts
					(arc
						(start 285.28518 -69.772784)
						(mid 284.574488 -69.772784)
						(end 285.28518 -69.772784)
					)
				)
			)
		)
		(zone
			(layer "F.Cu")
			(hatch none 0.5)
			(connect_pads
				(clearance 0)
			)
			(min_thickness 0.25)
			(keepout
				(tracks not_allowed)
				(vias allowed)
				(pads allowed)
				(copperpour not_allowed)
				(footprints allowed)
			)
			(placement
				(enabled no)
				(sheetname "")
			)
			(fill
				(thermal_gap 0.5)
				(thermal_bridge_width 0.5)
				(island_removal_mode 0)
			)
			(polygon
				(pts
					(xy 299.307504 -51.46929) (xy 299.306996 -51.45913) (xy 299.306742 -51.447192) (xy 299.297852 -51.447192)
					(arc
						(start 299.265086 -51.447192)
						(mid 299.256645 -51.447535)
						(end 299.248322 -51.44897)
					)
					(arc
						(start 299.248322 -51.44897)
						(mid 299.233754 -51.455209)
						(end 299.221906 -51.465734)
					)
					(arc
						(start 299.217334 -51.472338)
						(mid 299.211564 -51.485872)
						(end 299.210222 -51.500532)
					)
					(arc
						(start 299.210222 -51.500532)
						(mid 299.523685 -51.764978)
						(end 299.83557 -51.4985)
					)
					(xy 299.835062 -51.491642) (xy 299.834554 -51.487832) (xy 299.833538 -51.48453) (xy 299.832014 -51.479196)
					(xy 299.829982 -51.475132) (xy 299.824648 -51.467004) (xy 299.822108 -51.46421) (xy 299.81652 -51.458622)
					(xy 299.814742 -51.457352) (xy 299.811694 -51.454812) (xy 299.809662 -51.453796) (xy 299.808138 -51.453034)
					(xy 299.807122 -51.452526) (xy 299.80509 -51.45151) (xy 299.803058 -51.451002) (xy 299.798232 -51.449224)
					(xy 299.791882 -51.4477) (xy 299.78858 -51.447192) (xy 299.782484 -51.447192) (xy 299.777404 -51.447192)
					(xy 299.75302 -51.447192) (xy 299.738796 -51.447192)
					(arc
						(start 299.737018 -51.473354)
						(mid 299.73315 -51.496306)
						(end 299.72635 -51.518566)
					)
					(arc
						(start 299.721016 -51.533044)
						(mid 299.709795 -51.555503)
						(end 299.695616 -51.576224)
					)
					(xy 299.682408 -51.592226)
					(arc
						(start 299.655484 -51.617118)
						(mid 299.642493 -51.625458)
						(end 299.630084 -51.634644)
					)
					(arc
						(start 299.630084 -51.634644)
						(mid 299.601 -51.648273)
						(end 299.570394 -51.658012)
					)
					(arc
						(start 299.570394 -51.658012)
						(mid 299.547464 -51.662214)
						(end 299.524166 -51.663092)
					)
					(arc
						(start 299.490638 -51.660806)
						(mid 299.458801 -51.652931)
						(end 299.428154 -51.641248)
					)
					(arc
						(start 299.428154 -51.641248)
						(mid 299.405064 -51.628376)
						(end 299.383704 -51.6128)
					)
					(arc
						(start 299.383704 -51.6128)
						(mid 299.362064 -51.591248)
						(end 299.343064 -51.567334)
					)
					(arc
						(start 299.343064 -51.567334)
						(mid 299.330075 -51.544227)
						(end 299.319696 -51.519836)
					)
					(arc
						(start 299.319696 -51.519836)
						(mid 299.313776 -51.500753)
						(end 299.309536 -51.481228)
					)
					(xy 299.308774 -51.47691)
				)
			)
		)
		(zone
			(layer "F.Cu")
			(hatch none 0.5)
			(connect_pads
				(clearance 0)
			)
			(min_thickness 0.25)
			(keepout
				(tracks not_allowed)
				(vias allowed)
				(pads allowed)
				(copperpour not_allowed)
				(footprints allowed)
			)
			(placement
				(enabled no)
				(sheetname "")
			)
			(fill
				(thermal_gap 0.5)
				(thermal_bridge_width 0.5)
				(island_removal_mode 0)
			)
			(polygon
				(pts
					(xy 233.629454 -82.056478) (xy 233.619548 -82.056986) (xy 233.60761 -82.056986) (xy 233.60761 -82.06613)
					(arc
						(start 233.60761 -82.098896)
						(mid 233.607855 -82.107324)
						(end 233.609134 -82.11566)
					)
					(arc
						(start 233.609134 -82.11566)
						(mid 233.615349 -82.130251)
						(end 233.625898 -82.142076)
					)
					(arc
						(start 233.632502 -82.146648)
						(mid 233.646036 -82.152418)
						(end 233.660696 -82.15376)
					)
					(arc
						(start 233.660696 -82.15376)
						(mid 233.925142 -81.840422)
						(end 233.658918 -81.528412)
					)
					(xy 233.651806 -81.52892) (xy 233.64825 -81.529428) (xy 233.644948 -81.530444) (xy 233.639614 -81.531968)
					(xy 233.635296 -81.534) (xy 233.627422 -81.539334) (xy 233.624374 -81.541874) (xy 233.61904 -81.547208)
					(xy 233.61777 -81.54924) (xy 233.61523 -81.552288) (xy 233.614214 -81.55432) (xy 233.613198 -81.55559)
					(xy 233.612944 -81.556606) (xy 233.61269 -81.55686) (xy 233.611928 -81.558892) (xy 233.611166 -81.560924)
					(xy 233.609642 -81.565496) (xy 233.608118 -81.5721) (xy 233.60761 -81.575402) (xy 233.60761 -81.581498)
					(xy 233.60761 -81.586578) (xy 233.60761 -81.610708) (xy 233.60761 -81.625186)
					(arc
						(start 233.633518 -81.626964)
						(mid 233.656595 -81.630828)
						(end 233.678984 -81.637632)
					)
					(arc
						(start 233.693462 -81.642966)
						(mid 233.715921 -81.654187)
						(end 233.736642 -81.668366)
					)
					(xy 233.75239 -81.681574)
					(arc
						(start 233.777536 -81.708498)
						(mid 233.785752 -81.721483)
						(end 233.794808 -81.733898)
					)
					(arc
						(start 233.794808 -81.733898)
						(mid 233.80856 -81.762975)
						(end 233.81843 -81.793588)
					)
					(arc
						(start 233.81843 -81.793588)
						(mid 233.822632 -81.816518)
						(end 233.82351 -81.839816)
					)
					(arc
						(start 233.821224 -81.873344)
						(mid 233.813241 -81.905196)
						(end 233.801412 -81.935828)
					)
					(arc
						(start 233.801412 -81.935828)
						(mid 233.788674 -81.958915)
						(end 233.773218 -81.980278)
					)
					(arc
						(start 233.773218 -81.980278)
						(mid 233.751666 -82.001918)
						(end 233.727752 -82.020918)
					)
					(arc
						(start 233.727752 -82.020918)
						(mid 233.704523 -82.033924)
						(end 233.68 -82.044286)
					)
					(arc
						(start 233.68 -82.044286)
						(mid 233.660917 -82.050206)
						(end 233.641392 -82.054446)
					)
					(xy 233.637328 -82.055208)
				)
			)
		)
		(zone
			(layer "F.Cu")
			(hatch none 0.5)
			(connect_pads
				(clearance 0)
			)
			(min_thickness 0.25)
			(keepout
				(tracks not_allowed)
				(vias allowed)
				(pads allowed)
				(copperpour not_allowed)
				(footprints allowed)
			)
			(placement
				(enabled no)
				(sheetname "")
			)
			(fill
				(thermal_gap 0.5)
				(thermal_bridge_width 0.5)
				(island_removal_mode 0)
			)
			(polygon
				(pts
					(xy 233.630216 -81.065878) (xy 233.620056 -81.066386) (xy 233.608118 -81.066386) (xy 233.608372 -81.07553)
					(arc
						(start 233.608372 -81.108296)
						(mid 233.608617 -81.116724)
						(end 233.609896 -81.12506)
					)
					(arc
						(start 233.609896 -81.12506)
						(mid 233.616111 -81.139651)
						(end 233.62666 -81.151476)
					)
					(arc
						(start 233.633264 -81.156048)
						(mid 233.646798 -81.161818)
						(end 233.661458 -81.16316)
					)
					(arc
						(start 233.661458 -81.16316)
						(mid 233.925904 -80.849822)
						(end 233.65968 -80.537812)
					)
					(xy 233.652568 -80.53832) (xy 233.649012 -80.538828) (xy 233.64571 -80.539844) (xy 233.640122 -80.541368)
					(xy 233.636058 -80.5434) (xy 233.62793 -80.548734) (xy 233.625136 -80.551274) (xy 233.619548 -80.556608)
					(xy 233.618532 -80.55864) (xy 233.615992 -80.561688) (xy 233.614976 -80.56372) (xy 233.61396 -80.56499)
					(xy 233.613706 -80.566006) (xy 233.613452 -80.56626) (xy 233.612436 -80.568292) (xy 233.611928 -80.570324)
					(xy 233.61015 -80.574896) (xy 233.608626 -80.5815) (xy 233.608372 -80.584802) (xy 233.608118 -80.590898)
					(xy 233.608118 -80.595978) (xy 233.608372 -80.620108) (xy 233.608118 -80.634586)
					(arc
						(start 233.63428 -80.636364)
						(mid 233.657357 -80.640228)
						(end 233.679746 -80.647032)
					)
					(arc
						(start 233.694224 -80.652366)
						(mid 233.716683 -80.663587)
						(end 233.737404 -80.677766)
					)
					(xy 233.753152 -80.690974)
					(arc
						(start 233.778044 -80.717898)
						(mid 233.786384 -80.730889)
						(end 233.79557 -80.743298)
					)
					(arc
						(start 233.79557 -80.743298)
						(mid 233.809199 -80.772382)
						(end 233.818938 -80.802988)
					)
					(arc
						(start 233.818938 -80.802988)
						(mid 233.823292 -80.825908)
						(end 233.824272 -80.849216)
					)
					(arc
						(start 233.821732 -80.882744)
						(mid 233.813885 -80.914592)
						(end 233.802174 -80.945228)
					)
					(arc
						(start 233.802174 -80.945228)
						(mid 233.789302 -80.968318)
						(end 233.773726 -80.989678)
					)
					(arc
						(start 233.773726 -80.989678)
						(mid 233.752304 -81.011315)
						(end 233.728514 -81.030318)
					)
					(arc
						(start 233.728514 -81.030318)
						(mid 233.705285 -81.043324)
						(end 233.680762 -81.053686)
					)
					(arc
						(start 233.680762 -81.053686)
						(mid 233.661679 -81.059606)
						(end 233.642154 -81.063846)
					)
					(xy 233.63809 -81.064608)
				)
			)
		)
		(zone
			(layer "F.Cu")
			(hatch none 0.5)
			(connect_pads
				(clearance 0)
			)
			(min_thickness 0.25)
			(keepout
				(tracks not_allowed)
				(vias allowed)
				(pads allowed)
				(copperpour not_allowed)
				(footprints allowed)
			)
			(placement
				(enabled no)
				(sheetname "")
			)
			(fill
				(thermal_gap 0.5)
				(thermal_bridge_width 0.5)
				(island_removal_mode 0)
			)
			(polygon
				(pts
					(xy 233.630216 -72.149716) (xy 233.62031 -72.150224) (xy 233.608372 -72.150478) (xy 233.608372 -72.159368)
					(arc
						(start 233.608372 -72.192134)
						(mid 233.608617 -72.200562)
						(end 233.609896 -72.208898)
					)
					(arc
						(start 233.609896 -72.208898)
						(mid 233.616111 -72.223489)
						(end 233.62666 -72.235314)
					)
					(arc
						(start 233.633264 -72.239886)
						(mid 233.646914 -72.245762)
						(end 233.661712 -72.246998)
					)
					(arc
						(start 233.661712 -72.246998)
						(mid 233.926158 -71.933535)
						(end 233.65968 -71.62165)
					)
					(xy 233.652822 -71.622158) (xy 233.649012 -71.622666) (xy 233.64571 -71.623936) (xy 233.640376 -71.625206)
					(xy 233.636058 -71.627238) (xy 233.628184 -71.632572) (xy 233.625136 -71.635112) (xy 233.619802 -71.6407)
					(xy 233.618532 -71.642478) (xy 233.615992 -71.645526) (xy 233.614976 -71.647558) (xy 233.614214 -71.649082)
					(xy 233.613706 -71.650098) (xy 233.613452 -71.650098) (xy 233.61269 -71.65213) (xy 233.611928 -71.654162)
					(xy 233.610404 -71.658988) (xy 233.60888 -71.665338) (xy 233.608372 -71.66864) (xy 233.608372 -71.674736)
					(xy 233.608372 -71.679816) (xy 233.608372 -71.7042) (xy 233.608372 -71.718424)
					(arc
						(start 233.634534 -71.720202)
						(mid 233.657486 -71.72407)
						(end 233.679746 -71.73087)
					)
					(arc
						(start 233.694224 -71.736204)
						(mid 233.716683 -71.747425)
						(end 233.737404 -71.761604)
					)
					(xy 233.753152 -71.774812)
					(arc
						(start 233.778298 -71.801736)
						(mid 233.786638 -71.814727)
						(end 233.795824 -71.827136)
					)
					(arc
						(start 233.795824 -71.827136)
						(mid 233.809453 -71.85622)
						(end 233.819192 -71.886826)
					)
					(arc
						(start 233.819192 -71.886826)
						(mid 233.823394 -71.909756)
						(end 233.824272 -71.933054)
					)
					(arc
						(start 233.821986 -71.966836)
						(mid 233.814117 -71.998552)
						(end 233.802428 -72.029066)
					)
					(arc
						(start 233.802428 -72.029066)
						(mid 233.789556 -72.052156)
						(end 233.77398 -72.073516)
					)
					(arc
						(start 233.77398 -72.073516)
						(mid 233.752428 -72.095156)
						(end 233.728514 -72.114156)
					)
					(arc
						(start 233.728514 -72.114156)
						(mid 233.705285 -72.127162)
						(end 233.680762 -72.137524)
					)
					(arc
						(start 233.680762 -72.137524)
						(mid 233.661679 -72.143444)
						(end 233.642154 -72.147684)
					)
					(xy 233.63809 -72.148446)
				)
			)
		)
		(zone
			(layer "F.Cu")
			(hatch none 0.5)
			(connect_pads
				(clearance 0)
			)
			(min_thickness 0.25)
			(keepout
				(tracks not_allowed)
				(vias allowed)
				(pads allowed)
				(copperpour not_allowed)
				(footprints allowed)
			)
			(placement
				(enabled no)
				(sheetname "")
			)
			(fill
				(thermal_gap 0.5)
				(thermal_bridge_width 0.5)
				(island_removal_mode 0)
			)
			(polygon
				(pts
					(xy 233.630216 -71.16064) (xy 233.620056 -71.161148) (xy 233.608118 -71.161402) (xy 233.608118 -71.170292)
					(arc
						(start 233.608118 -71.203058)
						(mid 233.608461 -71.211499)
						(end 233.609896 -71.219822)
					)
					(arc
						(start 233.609896 -71.219822)
						(mid 233.616002 -71.234379)
						(end 233.626406 -71.246238)
					)
					(arc
						(start 233.63301 -71.25081)
						(mid 233.646641 -71.25679)
						(end 233.661458 -71.258176)
					)
					(arc
						(start 233.661458 -71.258176)
						(mid 233.926366 -70.944479)
						(end 233.659426 -70.632574)
					)
					(xy 233.652568 -70.633082) (xy 233.648758 -70.63359) (xy 233.645456 -70.63486) (xy 233.640122 -70.636384)
					(xy 233.635804 -70.638416) (xy 233.62793 -70.643496) (xy 233.625136 -70.64629) (xy 233.619548 -70.651624)
					(xy 233.618278 -70.653402) (xy 233.615738 -70.65645) (xy 233.614722 -70.658482) (xy 233.61396 -70.660006)
					(xy 233.613452 -70.661022) (xy 233.613198 -70.661276) (xy 233.612436 -70.663054) (xy 233.611928 -70.665086)
					(xy 233.61015 -70.669912) (xy 233.608626 -70.676262) (xy 233.608118 -70.679564) (xy 233.608118 -70.685914)
					(xy 233.608118 -70.69074) (xy 233.608118 -70.715124) (xy 233.608118 -70.729348)
					(arc
						(start 233.63428 -70.731126)
						(mid 233.657234 -70.734988)
						(end 233.679492 -70.741794)
					)
					(arc
						(start 233.69397 -70.747128)
						(mid 233.716453 -70.758454)
						(end 233.73715 -70.772782)
					)
					(xy 233.752898 -70.785736)
					(arc
						(start 233.778044 -70.812914)
						(mid 233.786384 -70.825905)
						(end 233.79557 -70.838314)
					)
					(arc
						(start 233.79557 -70.838314)
						(mid 233.809182 -70.867274)
						(end 233.818938 -70.89775)
					)
					(arc
						(start 233.818938 -70.89775)
						(mid 233.823191 -70.920805)
						(end 233.824018 -70.944232)
					)
					(arc
						(start 233.821732 -70.97776)
						(mid 233.813863 -71.009476)
						(end 233.802174 -71.03999)
					)
					(arc
						(start 233.802174 -71.03999)
						(mid 233.789328 -71.063219)
						(end 233.773726 -71.084694)
					)
					(arc
						(start 233.773726 -71.084694)
						(mid 233.752176 -71.10622)
						(end 233.72826 -71.12508)
					)
					(arc
						(start 233.72826 -71.12508)
						(mid 233.705042 -71.138221)
						(end 233.680508 -71.148702)
					)
					(arc
						(start 233.680508 -71.148702)
						(mid 233.661421 -71.154499)
						(end 233.6419 -71.158608)
					)
					(xy 233.637836 -71.15937)
				)
			)
		)
		(zone
			(layer "F.Cu")
			(hatch none 0.5)
			(connect_pads
				(clearance 0)
			)
			(min_thickness 0.25)
			(keepout
				(tracks not_allowed)
				(vias allowed)
				(pads allowed)
				(copperpour not_allowed)
				(footprints allowed)
			)
			(placement
				(enabled no)
				(sheetname "")
			)
			(fill
				(thermal_gap 0.5)
				(thermal_bridge_width 0.5)
				(island_removal_mode 0)
			)
			(polygon
				(pts
					(xy 233.630216 -70.168516) (xy 233.620056 -70.169024) (xy 233.608118 -70.169024) (xy 233.608372 -70.177914)
					(arc
						(start 233.608372 -70.210934)
						(mid 233.608617 -70.219362)
						(end 233.609896 -70.227698)
					)
					(arc
						(start 233.609896 -70.227698)
						(mid 233.616111 -70.242289)
						(end 233.62666 -70.254114)
					)
					(arc
						(start 233.633264 -70.258686)
						(mid 233.646798 -70.264456)
						(end 233.661458 -70.265798)
					)
					(arc
						(start 233.661458 -70.265798)
						(mid 233.926367 -69.952226)
						(end 233.65968 -69.640196)
					)
					(xy 233.652568 -69.640704) (xy 233.649012 -69.641212) (xy 233.64571 -69.642482) (xy 233.640122 -69.644006)
					(xy 233.636058 -69.646038) (xy 233.62793 -69.651372) (xy 233.625136 -69.653912) (xy 233.619548 -69.659246)
					(xy 233.618532 -69.661278) (xy 233.615992 -69.664326) (xy 233.614976 -69.666104) (xy 233.61396 -69.667628)
					(xy 233.613706 -69.668644) (xy 233.613452 -69.668898) (xy 233.612436 -69.67093) (xy 233.611928 -69.672708)
					(xy 233.61015 -69.677534) (xy 233.608626 -69.684138) (xy 233.608372 -69.687186) (xy 233.608118 -69.693536)
					(xy 233.608118 -69.698616) (xy 233.608372 -69.722746) (xy 233.608118 -69.737224)
					(arc
						(start 233.63428 -69.739002)
						(mid 233.657357 -69.742866)
						(end 233.679746 -69.74967)
					)
					(arc
						(start 233.694224 -69.755004)
						(mid 233.716683 -69.766225)
						(end 233.737404 -69.780404)
					)
					(xy 233.753152 -69.793612)
					(arc
						(start 233.778044 -69.820536)
						(mid 233.786384 -69.833527)
						(end 233.79557 -69.845936)
					)
					(arc
						(start 233.79557 -69.845936)
						(mid 233.809199 -69.87502)
						(end 233.818938 -69.905626)
					)
					(arc
						(start 233.818938 -69.905626)
						(mid 233.823292 -69.928546)
						(end 233.824272 -69.951854)
					)
					(arc
						(start 233.821732 -69.985382)
						(mid 233.813885 -70.01723)
						(end 233.802174 -70.047866)
					)
					(arc
						(start 233.802174 -70.047866)
						(mid 233.789302 -70.070956)
						(end 233.773726 -70.092316)
					)
					(arc
						(start 233.773726 -70.092316)
						(mid 233.752293 -70.113822)
						(end 233.728514 -70.132702)
					)
					(arc
						(start 233.728514 -70.132702)
						(mid 233.705296 -70.145843)
						(end 233.680762 -70.156324)
					)
					(arc
						(start 233.680762 -70.156324)
						(mid 233.661682 -70.162258)
						(end 233.642154 -70.166484)
					)
					(xy 233.63809 -70.166992)
				)
			)
		)
		(zone
			(layer "F.Cu")
			(hatch none 0.5)
			(connect_pads
				(clearance 0)
			)
			(min_thickness 0.25)
			(keepout
				(tracks not_allowed)
				(vias allowed)
				(pads allowed)
				(copperpour not_allowed)
				(footprints allowed)
			)
			(placement
				(enabled no)
				(sheetname "")
			)
			(fill
				(thermal_gap 0.5)
				(thermal_bridge_width 0.5)
				(island_removal_mode 0)
			)
			(polygon
				(pts
					(xy 233.63174 -83.04657) (xy 233.62158 -83.047078) (xy 233.609642 -83.047332) (xy 233.609642 -83.056222)
					(arc
						(start 233.609642 -83.088988)
						(mid 233.609985 -83.097429)
						(end 233.61142 -83.105752)
					)
					(arc
						(start 233.61142 -83.105752)
						(mid 233.617526 -83.120309)
						(end 233.62793 -83.132168)
					)
					(arc
						(start 233.634534 -83.13674)
						(mid 233.648184 -83.142616)
						(end 233.662982 -83.143852)
					)
					(arc
						(start 233.662982 -83.143852)
						(mid 233.927428 -82.830389)
						(end 233.66095 -82.518504)
					)
					(xy 233.654092 -82.519012) (xy 233.650282 -82.51952) (xy 233.64698 -82.520536) (xy 233.641646 -82.52206)
					(xy 233.637328 -82.524092) (xy 233.629454 -82.529426) (xy 233.626406 -82.531966) (xy 233.621072 -82.5373)
					(xy 233.619802 -82.539332) (xy 233.617262 -82.54238) (xy 233.616246 -82.544412) (xy 233.615484 -82.545936)
					(xy 233.614976 -82.546698) (xy 233.614722 -82.546952) (xy 233.61396 -82.548984) (xy 233.613198 -82.551016)
					(xy 233.611674 -82.555588) (xy 233.61015 -82.562192) (xy 233.609642 -82.565494) (xy 233.609642 -82.57159)
					(xy 233.609642 -82.57667) (xy 233.609642 -82.6008) (xy 233.609642 -82.615278)
					(arc
						(start 233.635804 -82.617056)
						(mid 233.658756 -82.620924)
						(end 233.681016 -82.627724)
					)
					(arc
						(start 233.695494 -82.633058)
						(mid 233.717953 -82.644279)
						(end 233.738674 -82.658458)
					)
					(xy 233.754422 -82.671666)
					(arc
						(start 233.779568 -82.69859)
						(mid 233.787908 -82.711581)
						(end 233.797094 -82.72399)
					)
					(arc
						(start 233.797094 -82.72399)
						(mid 233.810723 -82.753074)
						(end 233.820462 -82.78368)
					)
					(arc
						(start 233.820462 -82.78368)
						(mid 233.824664 -82.80661)
						(end 233.825542 -82.829908)
					)
					(arc
						(start 233.823256 -82.863436)
						(mid 233.815381 -82.895273)
						(end 233.803698 -82.92592)
					)
					(arc
						(start 233.803698 -82.92592)
						(mid 233.790826 -82.94901)
						(end 233.77525 -82.97037)
					)
					(arc
						(start 233.77525 -82.97037)
						(mid 233.753698 -82.99201)
						(end 233.729784 -83.01101)
					)
					(arc
						(start 233.729784 -83.01101)
						(mid 233.706555 -83.024016)
						(end 233.682032 -83.034378)
					)
					(arc
						(start 233.682032 -83.034378)
						(mid 233.662949 -83.040298)
						(end 233.643424 -83.044538)
					)
					(xy 233.63936 -83.0453)
				)
			)
		)
		(zone
			(layer "F.Cu")
			(hatch none 0.5)
			(connect_pads
				(clearance 0)
			)
			(min_thickness 0.25)
			(keepout
				(tracks not_allowed)
				(vias allowed)
				(pads allowed)
				(copperpour not_allowed)
				(footprints allowed)
			)
			(placement
				(enabled no)
				(sheetname "")
			)
			(fill
				(thermal_gap 0.5)
				(thermal_bridge_width 0.5)
				(island_removal_mode 0)
			)
			(polygon
				(pts
					(xy 234.488736 -80.570324) (xy 234.478576 -80.570832) (xy 234.466638 -80.570832) (xy 234.466892 -80.579722)
					(arc
						(start 234.466892 -80.612488)
						(mid 234.467116 -80.621045)
						(end 234.468416 -80.629506)
					)
					(arc
						(start 234.468416 -80.629506)
						(mid 234.474631 -80.644097)
						(end 234.48518 -80.655922)
					)
					(arc
						(start 234.491784 -80.660494)
						(mid 234.505318 -80.666264)
						(end 234.519978 -80.667606)
					)
					(arc
						(start 234.519978 -80.667606)
						(mid 234.784887 -80.354034)
						(end 234.5182 -80.042004)
					)
					(xy 234.511088 -80.042512) (xy 234.507532 -80.04302) (xy 234.50423 -80.04429) (xy 234.498642 -80.045814)
					(xy 234.494578 -80.047846) (xy 234.48645 -80.05318) (xy 234.483656 -80.05572) (xy 234.478068 -80.061054)
					(xy 234.476798 -80.063086) (xy 234.474512 -80.066134) (xy 234.473496 -80.067912) (xy 234.47248 -80.069436)
					(xy 234.472226 -80.070452) (xy 234.471972 -80.070706) (xy 234.470956 -80.072738) (xy 234.470448 -80.074516)
					(xy 234.46867 -80.079342) (xy 234.467146 -80.085692) (xy 234.466892 -80.088994) (xy 234.466638 -80.095344)
					(xy 234.466638 -80.100424) (xy 234.466892 -80.124554) (xy 234.466638 -80.139032)
					(arc
						(start 234.4928 -80.14081)
						(mid 234.515752 -80.144678)
						(end 234.538012 -80.151478)
					)
					(arc
						(start 234.552744 -80.156812)
						(mid 234.575203 -80.168033)
						(end 234.595924 -80.182212)
					)
					(xy 234.611672 -80.19542)
					(arc
						(start 234.636564 -80.222344)
						(mid 234.644904 -80.235335)
						(end 234.65409 -80.247744)
					)
					(arc
						(start 234.65409 -80.247744)
						(mid 234.667719 -80.276828)
						(end 234.677458 -80.307434)
					)
					(arc
						(start 234.677458 -80.307434)
						(mid 234.681812 -80.330354)
						(end 234.682792 -80.353662)
					)
					(arc
						(start 234.680252 -80.38719)
						(mid 234.672377 -80.419027)
						(end 234.660694 -80.449674)
					)
					(arc
						(start 234.660694 -80.449674)
						(mid 234.647822 -80.472764)
						(end 234.632246 -80.494124)
					)
					(arc
						(start 234.632246 -80.494124)
						(mid 234.610813 -80.51563)
						(end 234.587034 -80.53451)
					)
					(arc
						(start 234.587034 -80.53451)
						(mid 234.563816 -80.547651)
						(end 234.539282 -80.558132)
					)
					(arc
						(start 234.539282 -80.558132)
						(mid 234.520202 -80.564066)
						(end 234.500674 -80.568292)
					)
					(xy 234.49661 -80.5688)
				)
			)
		)
		(zone
			(layer "F.Cu")
			(hatch none 0.5)
			(connect_pads
				(clearance 0)
			)
			(min_thickness 0.25)
			(keepout
				(tracks not_allowed)
				(vias allowed)
				(pads allowed)
				(copperpour not_allowed)
				(footprints allowed)
			)
			(placement
				(enabled no)
				(sheetname "")
			)
			(fill
				(thermal_gap 0.5)
				(thermal_bridge_width 0.5)
				(island_removal_mode 0)
			)
			(polygon
				(pts
					(xy 234.488736 -79.579724) (xy 234.47883 -79.580232) (xy 234.466892 -79.580486) (xy 234.466892 -79.589376)
					(arc
						(start 234.466892 -79.622142)
						(mid 234.467137 -79.63057)
						(end 234.468416 -79.638906)
					)
					(arc
						(start 234.468416 -79.638906)
						(mid 234.474631 -79.653497)
						(end 234.48518 -79.665322)
					)
					(arc
						(start 234.491784 -79.669894)
						(mid 234.505415 -79.675874)
						(end 234.520232 -79.67726)
					)
					(arc
						(start 234.520232 -79.67726)
						(mid 234.78514 -79.363563)
						(end 234.5182 -79.051658)
					)
					(xy 234.511342 -79.052166) (xy 234.507532 -79.052674) (xy 234.50423 -79.053944) (xy 234.498896 -79.055468)
					(xy 234.494578 -79.0575) (xy 234.486704 -79.062834) (xy 234.483656 -79.065374) (xy 234.478322 -79.070708)
					(xy 234.477052 -79.072486) (xy 234.474512 -79.075534) (xy 234.473496 -79.077566) (xy 234.472734 -79.07909)
					(xy 234.472226 -79.080106) (xy 234.471972 -79.08036) (xy 234.47121 -79.082138) (xy 234.470448 -79.08417)
					(xy 234.468924 -79.088996) (xy 234.4674 -79.095346) (xy 234.466892 -79.098648) (xy 234.466892 -79.104998)
					(xy 234.466892 -79.109824) (xy 234.466892 -79.134208) (xy 234.466892 -79.148432)
					(arc
						(start 234.4928 -79.15021)
						(mid 234.515892 -79.154178)
						(end 234.538266 -79.161132)
					)
					(arc
						(start 234.552744 -79.166212)
						(mid 234.575227 -79.177538)
						(end 234.595924 -79.191866)
					)
					(xy 234.611672 -79.20482)
					(arc
						(start 234.636818 -79.231998)
						(mid 234.645158 -79.244989)
						(end 234.654344 -79.257398)
					)
					(arc
						(start 234.654344 -79.257398)
						(mid 234.667956 -79.286358)
						(end 234.677712 -79.316834)
					)
					(arc
						(start 234.677712 -79.316834)
						(mid 234.681965 -79.339889)
						(end 234.682792 -79.363316)
					)
					(arc
						(start 234.680506 -79.396844)
						(mid 234.672631 -79.428681)
						(end 234.660948 -79.459328)
					)
					(arc
						(start 234.660948 -79.459328)
						(mid 234.648076 -79.482418)
						(end 234.6325 -79.503778)
					)
					(arc
						(start 234.6325 -79.503778)
						(mid 234.61095 -79.525304)
						(end 234.587034 -79.544164)
					)
					(arc
						(start 234.587034 -79.544164)
						(mid 234.563816 -79.557305)
						(end 234.539282 -79.567786)
					)
					(arc
						(start 234.539282 -79.567786)
						(mid 234.520195 -79.573583)
						(end 234.500674 -79.577692)
					)
					(xy 234.49661 -79.578454)
				)
			)
		)
		(zone
			(layer "F.Cu")
			(hatch none 0.5)
			(connect_pads
				(clearance 0)
			)
			(min_thickness 0.25)
			(keepout
				(tracks not_allowed)
				(vias allowed)
				(pads allowed)
				(copperpour not_allowed)
				(footprints allowed)
			)
			(placement
				(enabled no)
				(sheetname "")
			)
			(fill
				(thermal_gap 0.5)
				(thermal_bridge_width 0.5)
				(island_removal_mode 0)
			)
			(polygon
				(pts
					(xy 234.488736 -78.589632) (xy 234.478576 -78.589886) (xy 234.466638 -78.59014) (xy 234.466892 -78.59903)
					(arc
						(start 234.466892 -78.631796)
						(mid 234.467116 -78.640353)
						(end 234.468416 -78.648814)
					)
					(arc
						(start 234.468416 -78.648814)
						(mid 234.474631 -78.663405)
						(end 234.48518 -78.67523)
					)
					(arc
						(start 234.491784 -78.679802)
						(mid 234.505318 -78.685572)
						(end 234.519978 -78.686914)
					)
					(arc
						(start 234.519978 -78.686914)
						(mid 234.784887 -78.373342)
						(end 234.5182 -78.061312)
					)
					(xy 234.511088 -78.06182) (xy 234.507532 -78.062328) (xy 234.50423 -78.063598) (xy 234.498642 -78.065122)
					(xy 234.494578 -78.067154) (xy 234.48645 -78.072488) (xy 234.483656 -78.075028) (xy 234.478068 -78.080362)
					(xy 234.476798 -78.082394) (xy 234.474512 -78.085188) (xy 234.473496 -78.08722) (xy 234.47248 -78.088744)
					(xy 234.472226 -78.08976) (xy 234.471972 -78.090014) (xy 234.470956 -78.091792) (xy 234.470448 -78.093824)
					(xy 234.46867 -78.09865) (xy 234.467146 -78.105) (xy 234.466892 -78.108302) (xy 234.466638 -78.114652)
					(xy 234.466638 -78.119732) (xy 234.466892 -78.143862) (xy 234.466638 -78.158086)
					(arc
						(start 234.4928 -78.160118)
						(mid 234.515752 -78.163986)
						(end 234.538012 -78.170786)
					)
					(arc
						(start 234.552744 -78.17612)
						(mid 234.575203 -78.187341)
						(end 234.595924 -78.20152)
					)
					(xy 234.611672 -78.214728)
					(arc
						(start 234.636564 -78.241652)
						(mid 234.644904 -78.254643)
						(end 234.65409 -78.267052)
					)
					(arc
						(start 234.65409 -78.267052)
						(mid 234.667702 -78.296012)
						(end 234.677458 -78.326488)
					)
					(arc
						(start 234.677458 -78.326488)
						(mid 234.681826 -78.349534)
						(end 234.682792 -78.37297)
					)
					(arc
						(start 234.680252 -78.406498)
						(mid 234.672377 -78.438335)
						(end 234.660694 -78.468982)
					)
					(arc
						(start 234.660694 -78.468982)
						(mid 234.647822 -78.492072)
						(end 234.632246 -78.513432)
					)
					(arc
						(start 234.632246 -78.513432)
						(mid 234.610826 -78.534954)
						(end 234.587034 -78.553818)
					)
					(arc
						(start 234.587034 -78.553818)
						(mid 234.563816 -78.566959)
						(end 234.539282 -78.57744)
					)
					(arc
						(start 234.539282 -78.57744)
						(mid 234.520202 -78.583374)
						(end 234.500674 -78.5876)
					)
					(xy 234.49661 -78.588108)
				)
			)
		)
		(zone
			(layer "F.Cu")
			(hatch none 0.5)
			(connect_pads
				(clearance 0)
			)
			(min_thickness 0.25)
			(keepout
				(tracks not_allowed)
				(vias allowed)
				(pads allowed)
				(copperpour not_allowed)
				(footprints allowed)
			)
			(placement
				(enabled no)
				(sheetname "")
			)
			(fill
				(thermal_gap 0.5)
				(thermal_bridge_width 0.5)
				(island_removal_mode 0)
			)
			(polygon
				(pts
					(xy 234.488736 -77.598778) (xy 234.478576 -77.599286) (xy 234.466638 -77.599286) (xy 234.466892 -77.60843)
					(arc
						(start 234.466892 -77.641196)
						(mid 234.467137 -77.649624)
						(end 234.468416 -77.65796)
					)
					(arc
						(start 234.468416 -77.65796)
						(mid 234.474631 -77.672551)
						(end 234.48518 -77.684376)
					)
					(arc
						(start 234.491784 -77.688948)
						(mid 234.505318 -77.694718)
						(end 234.519978 -77.69606)
					)
					(arc
						(start 234.519978 -77.69606)
						(mid 234.784424 -77.382722)
						(end 234.5182 -77.070712)
					)
					(xy 234.511088 -77.07122) (xy 234.507532 -77.071728) (xy 234.50423 -77.072744) (xy 234.498642 -77.074268)
					(xy 234.494578 -77.0763) (xy 234.48645 -77.081634) (xy 234.483656 -77.084174) (xy 234.478068 -77.089508)
					(xy 234.476798 -77.09154) (xy 234.474512 -77.094588) (xy 234.473496 -77.09662) (xy 234.47248 -77.09789)
					(xy 234.472226 -77.098906) (xy 234.471972 -77.09916) (xy 234.470956 -77.101192) (xy 234.470448 -77.103224)
					(xy 234.46867 -77.107796) (xy 234.467146 -77.1144) (xy 234.466892 -77.117702) (xy 234.466638 -77.123798)
					(xy 234.466638 -77.128878) (xy 234.466892 -77.153008) (xy 234.466638 -77.167486)
					(arc
						(start 234.4928 -77.169264)
						(mid 234.515752 -77.173132)
						(end 234.538012 -77.179932)
					)
					(arc
						(start 234.552744 -77.185266)
						(mid 234.575203 -77.196487)
						(end 234.595924 -77.210666)
					)
					(xy 234.611672 -77.223874)
					(arc
						(start 234.636564 -77.250798)
						(mid 234.644904 -77.263789)
						(end 234.65409 -77.276198)
					)
					(arc
						(start 234.65409 -77.276198)
						(mid 234.667719 -77.305282)
						(end 234.677458 -77.335888)
					)
					(arc
						(start 234.677458 -77.335888)
						(mid 234.681812 -77.358808)
						(end 234.682792 -77.382116)
					)
					(arc
						(start 234.680252 -77.415644)
						(mid 234.672377 -77.447481)
						(end 234.660694 -77.478128)
					)
					(arc
						(start 234.660694 -77.478128)
						(mid 234.647822 -77.501218)
						(end 234.632246 -77.522578)
					)
					(arc
						(start 234.632246 -77.522578)
						(mid 234.610824 -77.544215)
						(end 234.587034 -77.563218)
					)
					(arc
						(start 234.587034 -77.563218)
						(mid 234.563805 -77.576224)
						(end 234.539282 -77.586586)
					)
					(arc
						(start 234.539282 -77.586586)
						(mid 234.520199 -77.592506)
						(end 234.500674 -77.596746)
					)
					(xy 234.49661 -77.597508)
				)
			)
		)
		(zone
			(layer "F.Cu")
			(hatch none 0.5)
			(connect_pads
				(clearance 0)
			)
			(min_thickness 0.25)
			(keepout
				(tracks not_allowed)
				(vias allowed)
				(pads allowed)
				(copperpour not_allowed)
				(footprints allowed)
			)
			(placement
				(enabled no)
				(sheetname "")
			)
			(fill
				(thermal_gap 0.5)
				(thermal_bridge_width 0.5)
				(island_removal_mode 0)
			)
			(polygon
				(pts
					(xy 234.488736 -76.605638) (xy 234.47883 -76.605892) (xy 234.466892 -76.606146) (xy 234.466892 -76.615036)
					(arc
						(start 234.466892 -76.647802)
						(mid 234.467116 -76.656359)
						(end 234.468416 -76.66482)
					)
					(arc
						(start 234.468416 -76.66482)
						(mid 234.474631 -76.679411)
						(end 234.48518 -76.691236)
					)
					(arc
						(start 234.491784 -76.695808)
						(mid 234.505434 -76.701684)
						(end 234.520232 -76.70292)
					)
					(arc
						(start 234.520232 -76.70292)
						(mid 234.78514 -76.389223)
						(end 234.5182 -76.077318)
					)
					(xy 234.511342 -76.077826) (xy 234.507532 -76.078334) (xy 234.50423 -76.079604) (xy 234.498896 -76.081128)
					(xy 234.494578 -76.08316) (xy 234.486704 -76.088494) (xy 234.483656 -76.091034) (xy 234.478322 -76.096368)
					(xy 234.477052 -76.0984) (xy 234.474512 -76.101194) (xy 234.473496 -76.103226) (xy 234.472734 -76.10475)
					(xy 234.472226 -76.105766) (xy 234.471972 -76.10602) (xy 234.47121 -76.107798) (xy 234.470448 -76.10983)
					(xy 234.468924 -76.114656) (xy 234.4674 -76.121006) (xy 234.466892 -76.124308) (xy 234.466892 -76.130658)
					(xy 234.466892 -76.135738) (xy 234.466892 -76.159868) (xy 234.466892 -76.174092)
					(arc
						(start 234.4928 -76.176124)
						(mid 234.515877 -76.179988)
						(end 234.538266 -76.186792)
					)
					(arc
						(start 234.552744 -76.192126)
						(mid 234.575221 -76.203321)
						(end 234.595924 -76.217526)
					)
					(xy 234.611672 -76.230734)
					(arc
						(start 234.636818 -76.257658)
						(mid 234.645158 -76.270649)
						(end 234.654344 -76.283058)
					)
					(arc
						(start 234.654344 -76.283058)
						(mid 234.667956 -76.312018)
						(end 234.677712 -76.342494)
					)
					(arc
						(start 234.677712 -76.342494)
						(mid 234.681965 -76.365549)
						(end 234.682792 -76.388976)
					)
					(arc
						(start 234.680506 -76.422504)
						(mid 234.672631 -76.454341)
						(end 234.660948 -76.484988)
					)
					(arc
						(start 234.660948 -76.484988)
						(mid 234.648076 -76.508078)
						(end 234.6325 -76.529438)
					)
					(arc
						(start 234.6325 -76.529438)
						(mid 234.61095 -76.550964)
						(end 234.587034 -76.569824)
					)
					(arc
						(start 234.587034 -76.569824)
						(mid 234.563816 -76.582965)
						(end 234.539282 -76.593446)
					)
					(arc
						(start 234.539282 -76.593446)
						(mid 234.520202 -76.59938)
						(end 234.500674 -76.603606)
					)
					(xy 234.49661 -76.604114)
				)
			)
		)
		(zone
			(layer "F.Cu")
			(hatch none 0.5)
			(connect_pads
				(clearance 0)
			)
			(min_thickness 0.25)
			(keepout
				(tracks not_allowed)
				(vias allowed)
				(pads allowed)
				(copperpour not_allowed)
				(footprints allowed)
			)
			(placement
				(enabled no)
				(sheetname "")
			)
			(fill
				(thermal_gap 0.5)
				(thermal_bridge_width 0.5)
				(island_removal_mode 0)
			)
			(polygon
				(pts
					(xy 234.488736 -75.617324) (xy 234.478576 -75.617832) (xy 234.466638 -75.618086) (xy 234.466892 -75.626976)
					(arc
						(start 234.466892 -75.659742)
						(mid 234.467137 -75.66817)
						(end 234.468416 -75.676506)
					)
					(arc
						(start 234.468416 -75.676506)
						(mid 234.474655 -75.691074)
						(end 234.48518 -75.702922)
					)
					(arc
						(start 234.491784 -75.707494)
						(mid 234.505292 -75.713442)
						(end 234.519978 -75.71486)
					)
					(arc
						(start 234.519978 -75.71486)
						(mid 234.784887 -75.401288)
						(end 234.5182 -75.089258)
					)
					(xy 234.511088 -75.089766) (xy 234.507532 -75.090274) (xy 234.50423 -75.091544) (xy 234.498642 -75.093068)
					(xy 234.494578 -75.0951) (xy 234.48645 -75.100434) (xy 234.483656 -75.102974) (xy 234.478068 -75.108308)
					(xy 234.476798 -75.110086) (xy 234.474512 -75.113134) (xy 234.473496 -75.115166) (xy 234.47248 -75.11669)
					(xy 234.472226 -75.117706) (xy 234.471972 -75.11796) (xy 234.470956 -75.119738) (xy 234.470448 -75.12177)
					(xy 234.46867 -75.126596) (xy 234.467146 -75.132946) (xy 234.466892 -75.136248) (xy 234.466638 -75.142598)
					(xy 234.466638 -75.147424) (xy 234.466892 -75.171808) (xy 234.466638 -75.186032)
					(arc
						(start 234.4928 -75.18781)
						(mid 234.515758 -75.191813)
						(end 234.538012 -75.198732)
					)
					(arc
						(start 234.552744 -75.203812)
						(mid 234.575227 -75.215138)
						(end 234.595924 -75.229466)
					)
					(xy 234.611672 -75.24242)
					(arc
						(start 234.636564 -75.269598)
						(mid 234.644904 -75.282589)
						(end 234.65409 -75.294998)
					)
					(arc
						(start 234.65409 -75.294998)
						(mid 234.667702 -75.323958)
						(end 234.677458 -75.354434)
					)
					(arc
						(start 234.677458 -75.354434)
						(mid 234.681826 -75.37748)
						(end 234.682792 -75.400916)
					)
					(arc
						(start 234.680252 -75.434444)
						(mid 234.672377 -75.466281)
						(end 234.660694 -75.496928)
					)
					(arc
						(start 234.660694 -75.496928)
						(mid 234.647822 -75.520018)
						(end 234.632246 -75.541378)
					)
					(arc
						(start 234.632246 -75.541378)
						(mid 234.610826 -75.5629)
						(end 234.587034 -75.581764)
					)
					(arc
						(start 234.587034 -75.581764)
						(mid 234.563816 -75.594905)
						(end 234.539282 -75.605386)
					)
					(arc
						(start 234.539282 -75.605386)
						(mid 234.520195 -75.611183)
						(end 234.500674 -75.615292)
					)
					(xy 234.49661 -75.616054)
				)
			)
		)
		(zone
			(layer "F.Cu")
			(hatch none 0.5)
			(connect_pads
				(clearance 0)
			)
			(min_thickness 0.25)
			(keepout
				(tracks not_allowed)
				(vias allowed)
				(pads allowed)
				(copperpour not_allowed)
				(footprints allowed)
			)
			(placement
				(enabled no)
				(sheetname "")
			)
			(fill
				(thermal_gap 0.5)
				(thermal_bridge_width 0.5)
				(island_removal_mode 0)
			)
			(polygon
				(pts
					(xy 234.488736 -74.629772) (xy 234.478576 -74.63028) (xy 234.466638 -74.630534) (xy 234.466638 -74.639424)
					(arc
						(start 234.466638 -74.67219)
						(mid 234.466981 -74.680631)
						(end 234.468416 -74.688954)
					)
					(arc
						(start 234.468416 -74.688954)
						(mid 234.474522 -74.703511)
						(end 234.484926 -74.71537)
					)
					(arc
						(start 234.49153 -74.719942)
						(mid 234.505166 -74.72589)
						(end 234.519978 -74.727308)
					)
					(arc
						(start 234.519978 -74.727308)
						(mid 234.784886 -74.413611)
						(end 234.517946 -74.101706)
					)
					(xy 234.511088 -74.102214) (xy 234.507278 -74.102722) (xy 234.503976 -74.103992) (xy 234.498642 -74.105516)
					(xy 234.494324 -74.107294) (xy 234.48645 -74.112628) (xy 234.483402 -74.115422) (xy 234.478068 -74.120756)
					(xy 234.476798 -74.122534) (xy 234.474258 -74.125582) (xy 234.473242 -74.127614) (xy 234.47248 -74.129138)
					(xy 234.471972 -74.130154) (xy 234.471718 -74.130408) (xy 234.470956 -74.132186) (xy 234.470448 -74.134218)
					(xy 234.46867 -74.139044) (xy 234.467146 -74.145394) (xy 234.466638 -74.148696) (xy 234.466638 -74.154792)
					(xy 234.466638 -74.159872) (xy 234.466638 -74.184256) (xy 234.466638 -74.19848)
					(arc
						(start 234.4928 -74.200258)
						(mid 234.515752 -74.204126)
						(end 234.538012 -74.210926)
					)
					(arc
						(start 234.55249 -74.21626)
						(mid 234.574973 -74.227586)
						(end 234.59567 -74.241914)
					)
					(xy 234.611418 -74.254868)
					(arc
						(start 234.636564 -74.281792)
						(mid 234.644904 -74.294783)
						(end 234.65409 -74.307192)
					)
					(arc
						(start 234.65409 -74.307192)
						(mid 234.667719 -74.336276)
						(end 234.677458 -74.366882)
					)
					(arc
						(start 234.677458 -74.366882)
						(mid 234.68166 -74.389812)
						(end 234.682538 -74.41311)
					)
					(arc
						(start 234.680252 -74.446892)
						(mid 234.672383 -74.478608)
						(end 234.660694 -74.509122)
					)
					(arc
						(start 234.660694 -74.509122)
						(mid 234.647848 -74.532351)
						(end 234.632246 -74.553826)
					)
					(arc
						(start 234.632246 -74.553826)
						(mid 234.610696 -74.575352)
						(end 234.58678 -74.594212)
					)
					(arc
						(start 234.58678 -74.594212)
						(mid 234.563562 -74.607353)
						(end 234.539028 -74.617834)
					)
					(arc
						(start 234.539028 -74.617834)
						(mid 234.519941 -74.623631)
						(end 234.50042 -74.62774)
					)
					(xy 234.496356 -74.628502)
				)
			)
		)
		(zone
			(layer "F.Cu")
			(hatch none 0.5)
			(connect_pads
				(clearance 0)
			)
			(min_thickness 0.25)
			(keepout
				(tracks not_allowed)
				(vias allowed)
				(pads allowed)
				(copperpour not_allowed)
				(footprints allowed)
			)
			(placement
				(enabled no)
				(sheetname "")
			)
			(fill
				(thermal_gap 0.5)
				(thermal_bridge_width 0.5)
				(island_removal_mode 0)
			)
			(polygon
				(pts
					(xy 234.488736 -73.635616) (xy 234.478576 -73.636124) (xy 234.466638 -73.636124) (xy 234.466892 -73.645014)
					(arc
						(start 234.466892 -73.678034)
						(mid 234.467137 -73.686462)
						(end 234.468416 -73.694798)
					)
					(arc
						(start 234.468416 -73.694798)
						(mid 234.474631 -73.709389)
						(end 234.48518 -73.721214)
					)
					(arc
						(start 234.491784 -73.725786)
						(mid 234.505318 -73.731556)
						(end 234.519978 -73.732898)
					)
					(arc
						(start 234.519978 -73.732898)
						(mid 234.784887 -73.419326)
						(end 234.5182 -73.107296)
					)
					(xy 234.511088 -73.107804) (xy 234.507532 -73.108312) (xy 234.50423 -73.109582) (xy 234.498642 -73.111106)
					(xy 234.494578 -73.113138) (xy 234.48645 -73.118472) (xy 234.483656 -73.121012) (xy 234.478068 -73.126346)
					(xy 234.476798 -73.128378) (xy 234.474512 -73.131426) (xy 234.473496 -73.133204) (xy 234.47248 -73.134728)
					(xy 234.472226 -73.135744) (xy 234.471972 -73.135998) (xy 234.470956 -73.13803) (xy 234.470448 -73.139808)
					(xy 234.46867 -73.144634) (xy 234.467146 -73.151238) (xy 234.466892 -73.154286) (xy 234.466638 -73.160636)
					(xy 234.466638 -73.165716) (xy 234.466892 -73.189846) (xy 234.466638 -73.204324)
					(arc
						(start 234.4928 -73.206102)
						(mid 234.515752 -73.20997)
						(end 234.538012 -73.21677)
					)
					(arc
						(start 234.552744 -73.222104)
						(mid 234.575203 -73.233325)
						(end 234.595924 -73.247504)
					)
					(xy 234.611672 -73.260712)
					(arc
						(start 234.636564 -73.287636)
						(mid 234.644904 -73.300627)
						(end 234.65409 -73.313036)
					)
					(arc
						(start 234.65409 -73.313036)
						(mid 234.667719 -73.34212)
						(end 234.677458 -73.372726)
					)
					(arc
						(start 234.677458 -73.372726)
						(mid 234.681812 -73.395646)
						(end 234.682792 -73.418954)
					)
					(arc
						(start 234.680252 -73.452482)
						(mid 234.672377 -73.484319)
						(end 234.660694 -73.514966)
					)
					(arc
						(start 234.660694 -73.514966)
						(mid 234.647822 -73.538056)
						(end 234.632246 -73.559416)
					)
					(arc
						(start 234.632246 -73.559416)
						(mid 234.610813 -73.580922)
						(end 234.587034 -73.599802)
					)
					(arc
						(start 234.587034 -73.599802)
						(mid 234.563816 -73.612943)
						(end 234.539282 -73.623424)
					)
					(arc
						(start 234.539282 -73.623424)
						(mid 234.520202 -73.629358)
						(end 234.500674 -73.633584)
					)
					(xy 234.49661 -73.634092)
				)
			)
		)
		(zone
			(layer "F.Cu")
			(hatch none 0.5)
			(connect_pads
				(clearance 0)
			)
			(min_thickness 0.25)
			(keepout
				(tracks not_allowed)
				(vias allowed)
				(pads allowed)
				(copperpour not_allowed)
				(footprints allowed)
			)
			(placement
				(enabled no)
				(sheetname "")
			)
			(fill
				(thermal_gap 0.5)
				(thermal_bridge_width 0.5)
				(island_removal_mode 0)
			)
			(polygon
				(pts
					(xy 234.488736 -72.646286) (xy 234.47883 -72.646794) (xy 234.466892 -72.647048) (xy 234.466892 -72.655938)
					(arc
						(start 234.466892 -72.688704)
						(mid 234.467137 -72.697132)
						(end 234.468416 -72.705468)
					)
					(arc
						(start 234.468416 -72.705468)
						(mid 234.474631 -72.720059)
						(end 234.48518 -72.731884)
					)
					(arc
						(start 234.491784 -72.736456)
						(mid 234.50542 -72.742404)
						(end 234.520232 -72.743822)
					)
					(arc
						(start 234.520232 -72.743822)
						(mid 234.78514 -72.430125)
						(end 234.5182 -72.11822)
					)
					(xy 234.511342 -72.118728) (xy 234.507532 -72.119236) (xy 234.50423 -72.120506) (xy 234.498896 -72.12203)
					(xy 234.494578 -72.123808) (xy 234.486704 -72.129142) (xy 234.483656 -72.131936) (xy 234.478322 -72.13727)
					(xy 234.477052 -72.139048) (xy 234.474512 -72.142096) (xy 234.473496 -72.144128) (xy 234.472734 -72.145652)
					(xy 234.472226 -72.146668) (xy 234.471972 -72.146922) (xy 234.47121 -72.1487) (xy 234.470448 -72.150732)
					(xy 234.468924 -72.155558) (xy 234.4674 -72.161908) (xy 234.466892 -72.16521) (xy 234.466892 -72.171306)
					(xy 234.466892 -72.176386) (xy 234.466892 -72.20077) (xy 234.466892 -72.214994)
					(arc
						(start 234.4928 -72.216772)
						(mid 234.515879 -72.22063)
						(end 234.538266 -72.22744)
					)
					(arc
						(start 234.552744 -72.232774)
						(mid 234.575227 -72.2441)
						(end 234.595924 -72.258428)
					)
					(xy 234.611672 -72.271382)
					(arc
						(start 234.636818 -72.298306)
						(mid 234.645147 -72.311306)
						(end 234.654344 -72.323706)
					)
					(arc
						(start 234.654344 -72.323706)
						(mid 234.667959 -72.352794)
						(end 234.677712 -72.383396)
					)
					(arc
						(start 234.677712 -72.383396)
						(mid 234.681914 -72.406326)
						(end 234.682792 -72.429624)
					)
					(arc
						(start 234.680506 -72.463406)
						(mid 234.672637 -72.495122)
						(end 234.660948 -72.525636)
					)
					(arc
						(start 234.660948 -72.525636)
						(mid 234.648076 -72.548726)
						(end 234.6325 -72.570086)
					)
					(arc
						(start 234.6325 -72.570086)
						(mid 234.610948 -72.591726)
						(end 234.587034 -72.610726)
					)
					(arc
						(start 234.587034 -72.610726)
						(mid 234.563805 -72.623732)
						(end 234.539282 -72.634094)
					)
					(arc
						(start 234.539282 -72.634094)
						(mid 234.520199 -72.640014)
						(end 234.500674 -72.644254)
					)
					(xy 234.49661 -72.645016)
				)
			)
		)
		(zone
			(layer "F.Cu")
			(hatch none 0.5)
			(connect_pads
				(clearance 0)
			)
			(min_thickness 0.25)
			(keepout
				(tracks not_allowed)
				(vias allowed)
				(pads allowed)
				(copperpour not_allowed)
				(footprints allowed)
			)
			(placement
				(enabled no)
				(sheetname "")
			)
			(fill
				(thermal_gap 0.5)
				(thermal_bridge_width 0.5)
				(island_removal_mode 0)
			)
			(polygon
				(pts
					(xy 297.590464 -51.46929) (xy 297.589956 -51.45913) (xy 297.589702 -51.447192) (xy 297.580812 -51.447192)
					(arc
						(start 297.548046 -51.447192)
						(mid 297.539605 -51.447535)
						(end 297.531282 -51.44897)
					)
					(arc
						(start 297.531282 -51.44897)
						(mid 297.516714 -51.455209)
						(end 297.504866 -51.465734)
					)
					(arc
						(start 297.500294 -51.472338)
						(mid 297.494524 -51.485872)
						(end 297.493182 -51.500532)
					)
					(arc
						(start 297.493182 -51.500532)
						(mid 297.806645 -51.764978)
						(end 298.11853 -51.4985)
					)
					(xy 298.118022 -51.491642) (xy 298.117514 -51.487832) (xy 298.116498 -51.48453) (xy 298.114974 -51.479196)
					(xy 298.112942 -51.475132) (xy 298.107608 -51.467004) (xy 298.105068 -51.46421) (xy 298.099734 -51.458622)
					(xy 298.097702 -51.457352) (xy 298.094654 -51.454812) (xy 298.092622 -51.453796) (xy 298.091098 -51.453034)
					(xy 298.090336 -51.452526) (xy 298.090082 -51.452526) (xy 298.08805 -51.45151) (xy 298.086018 -51.451002)
					(xy 298.081446 -51.449224) (xy 298.074842 -51.4477) (xy 298.07154 -51.447192) (xy 298.065444 -51.447192)
					(xy 298.060364 -51.447192) (xy 298.036234 -51.447192) (xy 298.021756 -51.447192)
					(arc
						(start 298.019978 -51.473354)
						(mid 298.01611 -51.496306)
						(end 298.00931 -51.518566)
					)
					(arc
						(start 298.003976 -51.533044)
						(mid 297.992755 -51.555503)
						(end 297.978576 -51.576224)
					)
					(xy 297.965368 -51.592226)
					(arc
						(start 297.938444 -51.617118)
						(mid 297.925453 -51.625458)
						(end 297.913044 -51.634644)
					)
					(arc
						(start 297.913044 -51.634644)
						(mid 297.88396 -51.648273)
						(end 297.853354 -51.658012)
					)
					(arc
						(start 297.853354 -51.658012)
						(mid 297.830424 -51.662214)
						(end 297.807126 -51.663092)
					)
					(arc
						(start 297.773598 -51.660806)
						(mid 297.741761 -51.652931)
						(end 297.711114 -51.641248)
					)
					(arc
						(start 297.711114 -51.641248)
						(mid 297.688024 -51.628376)
						(end 297.666664 -51.6128)
					)
					(arc
						(start 297.666664 -51.6128)
						(mid 297.645024 -51.591248)
						(end 297.626024 -51.567334)
					)
					(arc
						(start 297.626024 -51.567334)
						(mid 297.613035 -51.544227)
						(end 297.602656 -51.519836)
					)
					(arc
						(start 297.602656 -51.519836)
						(mid 297.596736 -51.500753)
						(end 297.592496 -51.481228)
					)
					(xy 297.591734 -51.47691)
				)
			)
		)
		(zone
			(layer "F.Cu")
			(hatch none 0.5)
			(connect_pads
				(clearance 0)
			)
			(min_thickness 0.25)
			(keepout
				(tracks not_allowed)
				(vias allowed)
				(pads allowed)
				(copperpour not_allowed)
				(footprints allowed)
			)
			(placement
				(enabled no)
				(sheetname "")
			)
			(fill
				(thermal_gap 0.5)
				(thermal_bridge_width 0.5)
				(island_removal_mode 0)
			)
			(polygon
				(pts
					(xy 301.024544 -51.46929) (xy 301.024036 -51.45913) (xy 301.023782 -51.447192) (xy 301.014892 -51.447192)
					(arc
						(start 300.982126 -51.447192)
						(mid 300.973685 -51.447535)
						(end 300.965362 -51.44897)
					)
					(arc
						(start 300.965362 -51.44897)
						(mid 300.950794 -51.455209)
						(end 300.938946 -51.465734)
					)
					(arc
						(start 300.934374 -51.472338)
						(mid 300.928426 -51.485846)
						(end 300.927008 -51.500532)
					)
					(arc
						(start 300.927008 -51.500532)
						(mid 301.240705 -51.76544)
						(end 301.55261 -51.4985)
					)
					(xy 301.552102 -51.491642) (xy 301.551594 -51.487832) (xy 301.550324 -51.48453) (xy 301.5488 -51.479196)
					(xy 301.547022 -51.475132) (xy 301.541688 -51.467004) (xy 301.539148 -51.46421) (xy 301.53356 -51.458622)
					(xy 301.531782 -51.457352) (xy 301.528734 -51.454812) (xy 301.526702 -51.453796) (xy 301.525178 -51.453034)
					(xy 301.524162 -51.452526) (xy 301.523908 -51.452526) (xy 301.52213 -51.45151) (xy 301.520098 -51.451002)
					(xy 301.515272 -51.449224) (xy 301.508922 -51.4477) (xy 301.50562 -51.447192) (xy 301.499524 -51.447192)
					(xy 301.494444 -51.447192) (xy 301.47006 -51.447192) (xy 301.455836 -51.447192)
					(arc
						(start 301.454058 -51.473354)
						(mid 301.45019 -51.496306)
						(end 301.44339 -51.518566)
					)
					(arc
						(start 301.438056 -51.533044)
						(mid 301.42673 -51.555527)
						(end 301.412402 -51.576224)
					)
					(xy 301.399448 -51.592226)
					(arc
						(start 301.372524 -51.617118)
						(mid 301.359533 -51.625458)
						(end 301.347124 -51.634644)
					)
					(arc
						(start 301.347124 -51.634644)
						(mid 301.31804 -51.648273)
						(end 301.287434 -51.658012)
					)
					(arc
						(start 301.287434 -51.658012)
						(mid 301.264504 -51.662214)
						(end 301.241206 -51.663092)
					)
					(arc
						(start 301.207424 -51.660806)
						(mid 301.175708 -51.652937)
						(end 301.145194 -51.641248)
					)
					(arc
						(start 301.145194 -51.641248)
						(mid 301.122104 -51.628376)
						(end 301.100744 -51.6128)
					)
					(arc
						(start 301.100744 -51.6128)
						(mid 301.079087 -51.591261)
						(end 301.060104 -51.567334)
					)
					(arc
						(start 301.060104 -51.567334)
						(mid 301.047115 -51.544227)
						(end 301.036736 -51.519836)
					)
					(arc
						(start 301.036736 -51.519836)
						(mid 301.030816 -51.500753)
						(end 301.026576 -51.481228)
					)
					(xy 301.025814 -51.47691)
				)
			)
		)
	)
	(footprint ""
		(layer "F.Cu")
		(at -0.2794 -18.2118 90)
		(property "Reference" "RT21"
			(at 1.01473 0.656336 0)
			(unlocked yes)
			(layer "F.SilkS")
			(effects
				(font
					(size 0.4064 0.254)
					(thickness 0.1524)
				)
			)
		)
		(property "Value" ""
			(at 0 0 90)
			(layer "F.Fab")
			(effects
				(font
					(size 1.27 1.27)
				)
			)
		)
		(duplicate_pad_numbers_are_jumpers no)
		(fp_poly
			(pts
				(xy -0.4953 -0.2032) (xy 0.4953 -0.2032) (xy 0.4953 1.6002) (xy -0.4953 1.6002)
			)
			(stroke
				(width 0)
				(type default)
			)
			(fill no)
			(layer "F.CrtYd")
		)
		(fp_line
			(start 0.4953 -0.2032)
			(end 0.4953 1.6002)
			(stroke
				(width 0.1)
				(type default)
			)
			(layer "F.Fab")
		)
		(fp_line
			(start -0.4953 -0.2032)
			(end 0.4953 -0.2032)
			(stroke
				(width 0.1)
				(type default)
			)
			(layer "F.Fab")
		)
		(fp_line
			(start 0.4953 1.6002)
			(end -0.4953 1.6002)
			(stroke
				(width 0.1)
				(type default)
			)
			(layer "F.Fab")
		)
		(fp_line
			(start -0.4953 1.6002)
			(end -0.4953 -0.2032)
			(stroke
				(width 0.1)
				(type default)
			)
			(layer "F.Fab")
		)
		(pad "1" smd rect
			(at 0 0 90)
			(size 0.762 0.889)
			(layers "F.Cu" "F.Mask" "F.Paste")
			(net "VR_PVDDQ_GHJ_PH2_BOOT")
		)
		(pad "2" smd rect
			(at 0 1.397 90)
			(size 0.762 0.889)
			(layers "F.Cu" "F.Mask" "F.Paste")
			(net "VR_PVDDQ_GHJ_PH2_BOOT_R")
		)
		(zone
			(layer "F.Cu")
			(hatch none 0.5)
			(connect_pads
				(clearance 0)
			)
			(min_thickness 0.25)
			(keepout
				(tracks allowed)
				(vias not_allowed)
				(pads allowed)
				(copperpour not_allowed)
				(footprints allowed)
			)
			(placement
				(enabled no)
				(sheetname "")
			)
			(fill
				(thermal_gap 0.5)
				(thermal_bridge_width 0.5)
				(island_removal_mode 0)
			)
			(polygon
				(pts
					(xy 0.6731 -18.5928) (xy 0.1651 -18.5928) (xy 0.1651 -17.8308) (xy 0.6731 -17.8308)
				)
			)
		)
		(zone
			(layer "F.Cu")
			(hatch none 0.5)
			(connect_pads
				(clearance 0)
			)
			(min_thickness 0.25)
			(keepout
				(tracks not_allowed)
				(vias allowed)
				(pads allowed)
				(copperpour not_allowed)
				(footprints allowed)
			)
			(placement
				(enabled no)
				(sheetname "")
			)
			(fill
				(thermal_gap 0.5)
				(thermal_bridge_width 0.5)
				(island_removal_mode 0)
			)
			(polygon
				(pts
					(xy 0.6731 -17.8308) (xy 0.6731 -18.5928) (xy 0.1651 -18.5928) (xy 0.1651 -17.8308)
				)
			)
		)
	)
	(footprint ""
		(layer "F.Cu")
		(at 419.435026 -54.027832 90)
		(property "Reference" "R1W7"
			(at -0.8382 -0.67818 90)
			(unlocked yes)
			(layer "F.SilkS")
			(effects
				(font
					(size 0.4064 0.254)
					(thickness 0.1524)
				)
				(justify left)
			)
		)
		(property "Value" ""
			(at 0 0 90)
			(layer "F.Fab")
			(effects
				(font
					(size 1.27 1.27)
				)
			)
		)
		(duplicate_pad_numbers_are_jumpers no)
		(fp_poly
			(pts
				(xy -0.2794 -0.1016) (xy 0.2794 -0.1016) (xy 0.2794 0.9906) (xy -0.2794 0.9906)
			)
			(stroke
				(width 0)
				(type default)
			)
			(fill no)
			(layer "F.CrtYd")
		)
		(fp_line
			(start 0.2794 -0.1016)
			(end -0.2794 -0.1016)
			(stroke
				(width 0.1)
				(type default)
			)
			(layer "F.Fab")
		)
		(fp_line
			(start -0.2794 -0.1016)
			(end -0.2794 0.9906)
			(stroke
				(width 0.1)
				(type default)
			)
			(layer "F.Fab")
		)
		(fp_line
			(start 0.2794 0.9906)
			(end 0.2794 -0.1016)
			(stroke
				(width 0.1)
				(type default)
			)
			(layer "F.Fab")
		)
		(fp_line
			(start -0.2794 0.9906)
			(end 0.2794 0.9906)
			(stroke
				(width 0.1)
				(type default)
			)
			(layer "F.Fab")
		)
		(pad "1" smd rect
			(at 0 0 90)
			(size 0.508 0.508)
			(layers "F.Cu" "F.Mask" "F.Paste")
			(net "FM_OCP_MEZZC_PRES_LVT3_BMC")
		)
		(pad "2" smd rect
			(at 0 0.889 90)
			(size 0.508 0.508)
			(layers "F.Cu" "F.Mask" "F.Paste")
			(net "P3V3_STBY")
		)
		(zone
			(layer "F.Cu")
			(hatch none 0.5)
			(connect_pads
				(clearance 0)
			)
			(min_thickness 0.25)
			(keepout
				(tracks allowed)
				(vias not_allowed)
				(pads allowed)
				(copperpour not_allowed)
				(footprints allowed)
			)
			(placement
				(enabled no)
				(sheetname "")
			)
			(fill
				(thermal_gap 0.5)
				(thermal_bridge_width 0.5)
				(island_removal_mode 0)
			)
			(polygon
				(pts
					(xy 419.689026 -53.773832) (xy 419.689026 -54.281832) (xy 420.070026 -54.281832) (xy 420.070026 -53.773832)
				)
			)
		)
		(zone
			(layer "F.Cu")
			(hatch none 0.5)
			(connect_pads
				(clearance 0)
			)
			(min_thickness 0.25)
			(keepout
				(tracks not_allowed)
				(vias allowed)
				(pads allowed)
				(copperpour not_allowed)
				(footprints allowed)
			)
			(placement
				(enabled no)
				(sheetname "")
			)
			(fill
				(thermal_gap 0.5)
				(thermal_bridge_width 0.5)
				(island_removal_mode 0)
			)
			(polygon
				(pts
					(xy 420.070026 -53.773832) (xy 420.070026 -54.281832) (xy 419.689026 -54.281832) (xy 419.689026 -53.773832)
				)
			)
		)
	)
	(footprint ""
		(layer "F.Cu")
		(at 472.313 -29.845 90)
		(property "Reference" "R1W23"
			(at -0.8382 -0.67818 90)
			(unlocked yes)
			(layer "F.SilkS")
			(effects
				(font
					(size 0.4064 0.254)
					(thickness 0.1524)
				)
				(justify left)
			)
		)
		(property "Value" ""
			(at 0 0 90)
			(layer "F.Fab")
			(effects
				(font
					(size 1.27 1.27)
				)
			)
		)
		(duplicate_pad_numbers_are_jumpers no)
		(fp_poly
			(pts
				(xy -0.2794 -0.1016) (xy 0.2794 -0.1016) (xy 0.2794 0.9906) (xy -0.2794 0.9906)
			)
			(stroke
				(width 0)
				(type default)
			)
			(fill no)
			(layer "F.CrtYd")
		)
		(fp_line
			(start 0.2794 -0.1016)
			(end -0.2794 -0.1016)
			(stroke
				(width 0.1)
				(type default)
			)
			(layer "F.Fab")
		)
		(fp_line
			(start -0.2794 -0.1016)
			(end -0.2794 0.9906)
			(stroke
				(width 0.1)
				(type default)
			)
			(layer "F.Fab")
		)
		(fp_line
			(start 0.2794 0.9906)
			(end 0.2794 -0.1016)
			(stroke
				(width 0.1)
				(type default)
			)
			(layer "F.Fab")
		)
		(fp_line
			(start -0.2794 0.9906)
			(end 0.2794 0.9906)
			(stroke
				(width 0.1)
				(type default)
			)
			(layer "F.Fab")
		)
		(pad "1" smd rect
			(at 0 0 90)
			(size 0.508 0.508)
			(layers "F.Cu" "F.Mask" "F.Paste")
			(net "SMB_HOST_STBY_LVC3_SDA")
		)
		(pad "2" smd rect
			(at 0 0.889 90)
			(size 0.508 0.508)
			(layers "F.Cu" "F.Mask" "F.Paste")
			(net "SMB_HOST_STBY_LVC3_SDA_R4")
		)
		(zone
			(layer "F.Cu")
			(hatch none 0.5)
			(connect_pads
				(clearance 0)
			)
			(min_thickness 0.25)
			(keepout
				(tracks allowed)
				(vias not_allowed)
				(pads allowed)
				(copperpour not_allowed)
				(footprints allowed)
			)
			(placement
				(enabled no)
				(sheetname "")
			)
			(fill
				(thermal_gap 0.5)
				(thermal_bridge_width 0.5)
				(island_removal_mode 0)
			)
			(polygon
				(pts
					(xy 472.567 -29.591) (xy 472.567 -30.099) (xy 472.948 -30.099) (xy 472.948 -29.591)
				)
			)
		)
		(zone
			(layer "F.Cu")
			(hatch none 0.5)
			(connect_pads
				(clearance 0)
			)
			(min_thickness 0.25)
			(keepout
				(tracks not_allowed)
				(vias allowed)
				(pads allowed)
				(copperpour not_allowed)
				(footprints allowed)
			)
			(placement
				(enabled no)
				(sheetname "")
			)
			(fill
				(thermal_gap 0.5)
				(thermal_bridge_width 0.5)
				(island_removal_mode 0)
			)
			(polygon
				(pts
					(xy 472.948 -29.591) (xy 472.948 -30.099) (xy 472.567 -30.099) (xy 472.567 -29.591)
				)
			)
		)
	)
	(footprint ""
		(layer "F.Cu")
		(at 104.5591 -149.8092 90)
		(property "Reference" "C2A7"
			(at 1.848866 0.752348 90)
			(unlocked yes)
			(layer "F.SilkS")
			(effects
				(font
					(size 1.27 0.9652)
					(thickness 0.1524)
				)
			)
		)
		(property "Value" ""
			(at 0 0 90)
			(layer "F.Fab")
			(effects
				(font
					(size 1.27 1.27)
				)
			)
		)
		(duplicate_pad_numbers_are_jumpers no)
		(fp_rect
			(start -0.500126 1.598422)
			(end 0.500126 -0.201422)
			(stroke
				(width 0)
				(type default)
			)
			(fill no)
			(layer "F.CrtYd")
		)
		(fp_line
			(start 0.500126 -0.201422)
			(end 0.500126 1.598422)
			(stroke
				(width 0.1)
				(type default)
			)
			(layer "F.Fab")
		)
		(fp_line
			(start -0.500126 -0.201422)
			(end 0.500126 -0.201422)
			(stroke
				(width 0.1)
				(type default)
			)
			(layer "F.Fab")
		)
		(fp_line
			(start 0.500126 1.598422)
			(end -0.500126 1.598422)
			(stroke
				(width 0.1)
				(type default)
			)
			(layer "F.Fab")
		)
		(fp_line
			(start -0.500126 1.598422)
			(end -0.500126 -0.201422)
			(stroke
				(width 0.1)
				(type default)
			)
			(layer "F.Fab")
		)
		(pad "1" smd rect
			(at 0 0)
			(size 0.889 0.9906)
			(layers "F.Cu" "F.Mask" "F.Paste")
			(net "PVDDQ_KLM")
		)
		(pad "2" smd rect
			(at 0 1.397)
			(size 0.889 0.9906)
			(layers "F.Cu" "F.Mask" "F.Paste")
			(net "GND")
		)
		(zone
			(layer "F.Cu")
			(hatch none 0.5)
			(connect_pads
				(clearance 0)
			)
			(min_thickness 0.25)
			(keepout
				(tracks not_allowed)
				(vias allowed)
				(pads allowed)
				(copperpour not_allowed)
				(footprints allowed)
			)
			(placement
				(enabled no)
				(sheetname "")
			)
			(fill
				(thermal_gap 0.5)
				(thermal_bridge_width 0.5)
				(island_removal_mode 0)
			)
			(polygon
				(pts
					(xy 105.5116 -149.3139) (xy 105.5116 -150.3045) (xy 105.0036 -150.3045) (xy 105.0036 -149.3139)
				)
			)
		)
		(zone
			(layer "F.Cu")
			(hatch none 0.5)
			(connect_pads
				(clearance 0)
			)
			(min_thickness 0.25)
			(keepout
				(tracks allowed)
				(vias not_allowed)
				(pads allowed)
				(copperpour not_allowed)
				(footprints allowed)
			)
			(placement
				(enabled no)
				(sheetname "")
			)
			(fill
				(thermal_gap 0.5)
				(thermal_bridge_width 0.5)
				(island_removal_mode 0)
			)
			(polygon
				(pts
					(xy 105.5116 -149.3139) (xy 105.5116 -150.3045) (xy 105.0036 -150.3045) (xy 105.0036 -149.3139)
				)
			)
		)
	)
	(footprint ""
		(layer "F.Cu")
		(at 270.7132 -79.6036 180)
		(property "Reference" "C5D20"
			(at 0 0 180)
			(layer "F.SilkS")
			(hide yes)
			(effects
				(font
					(size 1.27 1.27)
				)
			)
		)
		(property "Value" ""
			(at 0 0 180)
			(layer "F.Fab")
			(effects
				(font
					(size 1.27 1.27)
				)
			)
		)
		(duplicate_pad_numbers_are_jumpers no)
		(fp_poly
			(pts
				(xy -0.4953 -0.2032) (xy 0.4953 -0.2032) (xy 0.4953 1.6002) (xy -0.4953 1.6002)
			)
			(stroke
				(width 0)
				(type default)
			)
			(fill no)
			(layer "F.CrtYd")
		)
		(fp_line
			(start 0.4953 1.6002)
			(end -0.4953 1.6002)
			(stroke
				(width 0.1)
				(type default)
			)
			(layer "F.Fab")
		)
		(fp_line
			(start 0.4953 -0.2032)
			(end 0.4953 1.6002)
			(stroke
				(width 0.1)
				(type default)
			)
			(layer "F.Fab")
		)
		(fp_line
			(start -0.4953 1.6002)
			(end -0.4953 -0.2032)
			(stroke
				(width 0.1)
				(type default)
			)
			(layer "F.Fab")
		)
		(fp_line
			(start -0.4953 -0.2032)
			(end 0.4953 -0.2032)
			(stroke
				(width 0.1)
				(type default)
			)
			(layer "F.Fab")
		)
		(pad "1" smd rect
			(at 0 0 180)
			(size 0.762 0.889)
			(layers "F.Cu" "F.Mask" "F.Paste")
			(net "PVCCMCP_CPU0")
		)
		(pad "2" smd rect
			(at 0 1.397 180)
			(size 0.762 0.889)
			(layers "F.Cu" "F.Mask" "F.Paste")
			(net "GND")
		)
		(zone
			(layer "F.Cu")
			(hatch none 0.5)
			(connect_pads
				(clearance 0)
			)
			(min_thickness 0.25)
			(keepout
				(tracks not_allowed)
				(vias allowed)
				(pads allowed)
				(copperpour not_allowed)
				(footprints allowed)
			)
			(placement
				(enabled no)
				(sheetname "")
			)
			(fill
				(thermal_gap 0.5)
				(thermal_bridge_width 0.5)
				(island_removal_mode 0)
			)
			(polygon
				(pts
					(xy 271.0942 -80.0481) (xy 270.3322 -80.0481) (xy 270.3322 -80.5561) (xy 271.0942 -80.5561)
				)
			)
		)
	)
	(footprint ""
		(layer "F.Cu")
		(at 376.879866 -17.869662 180)
		(property "Reference" "UN8F2"
			(at 3.446272 -4.713986 180)
			(unlocked yes)
			(layer "F.SilkS")
			(effects
				(font
					(size 1.27 0.964946)
					(thickness 0.000001)
				)
				(justify left)
			)
		)
		(property "Value" ""
			(at 0 0 180)
			(layer "F.Fab")
			(effects
				(font
					(size 1.27 1.27)
				)
			)
		)
		(duplicate_pad_numbers_are_jumpers no)
		(fp_line
			(start 11.645392 10.819892)
			(end -2.094738 10.819892)
			(stroke
				(width 0.1524)
				(type default)
			)
			(layer "F.SilkS")
		)
		(fp_line
			(start 11.645392 -1.929892)
			(end 11.645392 10.819892)
			(stroke
				(width 0.1524)
				(type default)
			)
			(layer "F.SilkS")
		)
		(fp_line
			(start -2.094738 10.819892)
			(end -2.094738 -1.929892)
			(stroke
				(width 0.1524)
				(type default)
			)
			(layer "F.SilkS")
		)
		(fp_line
			(start -2.094738 -1.929892)
			(end 11.645392 -1.929892)
			(stroke
				(width 0.1524)
				(type default)
			)
			(layer "F.SilkS")
		)
		(fp_circle
			(center -2.69621 -0.952754)
			(end -2.82321 -0.952754)
			(stroke
				(width 0.762)
				(type default)
			)
			(fill no)
			(layer "F.SilkS")
		)
		(fp_rect
			(start 15.404846 -3.284474)
			(end 11.645392 12.260326)
			(stroke
				(width 0)
				(type default)
			)
			(fill no)
			(layer "F.CrtYd")
		)
		(fp_rect
			(start 11.645392 -1.929892)
			(end -2.094738 10.819892)
			(stroke
				(width 0)
				(type default)
			)
			(fill no)
			(layer "F.CrtYd")
		)
		(fp_rect
			(start -2.094738 -3.284474)
			(end -5.600954 12.260326)
			(stroke
				(width 0)
				(type default)
			)
			(fill no)
			(layer "F.CrtYd")
		)
		(fp_poly
			(pts
				(xy 7.569962 10.819892) (xy 6.970014 12.21994) (xy 2.629916 12.21994) (xy 2.029968 10.819892)
			)
			(stroke
				(width 0)
				(type default)
			)
			(fill no)
			(layer "F.CrtYd")
		)
		(fp_poly
			(pts
				(xy 2.029968 -1.929892) (xy 2.629916 -3.32994) (xy 6.970014 -3.32994) (xy 7.569962 -1.929892)
			)
			(stroke
				(width 0)
				(type default)
			)
			(fill no)
			(layer "F.CrtYd")
		)
		(fp_line
			(start 11.645392 10.819892)
			(end -2.094738 10.819892)
			(stroke
				(width 0.1)
				(type default)
			)
			(layer "F.Fab")
		)
		(fp_line
			(start 11.645392 -1.929892)
			(end 11.645392 10.819892)
			(stroke
				(width 0.1)
				(type default)
			)
			(layer "F.Fab")
		)
		(fp_line
			(start 7.569962 10.819892)
			(end 6.970014 12.21994)
			(stroke
				(width 0.1)
				(type default)
			)
			(layer "F.Fab")
		)
		(fp_line
			(start 6.970014 12.21994)
			(end 2.629916 12.21994)
			(stroke
				(width 0.1)
				(type default)
			)
			(layer "F.Fab")
		)
		(fp_line
			(start 6.970014 -3.32994)
			(end 7.569962 -1.929892)
			(stroke
				(width 0.1)
				(type default)
			)
			(layer "F.Fab")
		)
		(fp_line
			(start 2.629916 12.21994)
			(end 2.029968 10.819892)
			(stroke
				(width 0.1)
				(type default)
			)
			(layer "F.Fab")
		)
		(fp_line
			(start 2.629916 -3.32994)
			(end 6.970014 -3.32994)
			(stroke
				(width 0.1)
				(type default)
			)
			(layer "F.Fab")
		)
		(fp_line
			(start 2.029968 -1.929892)
			(end 2.629916 -3.32994)
			(stroke
				(width 0.1)
				(type default)
			)
			(layer "F.Fab")
		)
		(fp_line
			(start -2.094738 10.819892)
			(end -2.094738 -1.929892)
			(stroke
				(width 0.1)
				(type default)
			)
			(layer "F.Fab")
		)
		(fp_line
			(start -2.094738 -1.929892)
			(end 11.645392 -1.929892)
			(stroke
				(width 0.1)
				(type default)
			)
			(layer "F.Fab")
		)
		(pad "1" smd rect
			(at 0 0 180)
			(size 1.9304 0.635)
			(layers "F.Cu" "F.Mask" "F.Paste")
			(net "PU_TPM_SPI_BMC_HOLD_N")
		)
		(pad "2" smd rect
			(at 0 1.27 180)
			(size 1.9304 0.635)
			(layers "F.Cu" "F.Mask" "F.Paste")
			(net "P3V3_STBY")
		)
		(pad "3" smd rect
			(at 0 2.54 180)
			(size 1.9304 0.635)
			(layers "F.Cu" "F.Mask" "F.Paste")
			(net "PU_TPM_SPI_FLASH_RESET_2_N")
		)
		(pad "4" smd rect
			(at 0 3.81 180)
			(size 1.9304 0.635)
			(layers "F.Cu" "F.Mask" "F.Paste")
			(net "TP_TPM_SPI_6")
		)
		(pad "5" smd rect
			(at 0 5.08 180)
			(size 1.9304 0.635)
			(layers "F.Cu" "F.Mask" "F.Paste")
			(net "TP_TPM_SPI_5")
		)
		(pad "6" smd rect
			(at 0 6.35 180)
			(size 1.9304 0.635)
			(layers "F.Cu" "F.Mask" "F.Paste")
			(net "TP_TPM_SPI_4")
		)
		(pad "7" smd rect
			(at 0 7.62 180)
			(size 1.9304 0.635)
			(layers "F.Cu" "F.Mask" "F.Paste")
			(net "SPI_BMC_BT_CS0_N")
		)
		(pad "8" smd rect
			(at 0 8.89 180)
			(size 1.9304 0.635)
			(layers "F.Cu" "F.Mask" "F.Paste")
			(net "SPI_TPM_BMC_DI_R")
		)
		(pad "9" smd rect
			(at 9.5504 8.89 180)
			(size 1.9304 0.635)
			(layers "F.Cu" "F.Mask" "F.Paste")
			(net "TPM_SPI_BMC_WP_N")
		)
		(pad "10" smd rect
			(at 9.5504 7.62 180)
			(size 1.9304 0.635)
			(layers "F.Cu" "F.Mask" "F.Paste")
			(net "GND")
		)
		(pad "11" smd rect
			(at 9.5504 6.35 180)
			(size 1.9304 0.635)
			(layers "F.Cu" "F.Mask" "F.Paste")
			(net "TP_TPM_SPI_3")
		)
		(pad "12" smd rect
			(at 9.5504 5.08 180)
			(size 1.9304 0.635)
			(layers "F.Cu" "F.Mask" "F.Paste")
			(net "TP_TPM_SPI_2")
		)
		(pad "13" smd rect
			(at 9.5504 3.81 180)
			(size 1.9304 0.635)
			(layers "F.Cu" "F.Mask" "F.Paste")
			(net "TP_TPM_SPI_1")
		)
		(pad "14" smd rect
			(at 9.5504 2.54 180)
			(size 1.9304 0.635)
			(layers "F.Cu" "F.Mask" "F.Paste")
			(net "TP_TPM_SPI_0")
		)
		(pad "15" smd rect
			(at 9.5504 1.27 180)
			(size 1.9304 0.635)
			(layers "F.Cu" "F.Mask" "F.Paste")
			(net "SPI_BMC_BT_DO")
		)
		(pad "16" smd rect
			(at 9.5504 0 180)
			(size 1.9304 0.635)
			(layers "F.Cu" "F.Mask" "F.Paste")
			(net "SPI_BMC_BT_CLK")
		)
	)
	(footprint ""
		(layer "F.Cu")
		(at 0.315468 -68.586858 90)
		(property "Reference" "C1E19"
			(at 0 0 90)
			(layer "F.SilkS")
			(hide yes)
			(effects
				(font
					(size 1.27 1.27)
				)
			)
		)
		(property "Value" ""
			(at 0 0 90)
			(layer "F.Fab")
			(effects
				(font
					(size 1.27 1.27)
				)
			)
		)
		(duplicate_pad_numbers_are_jumpers no)
		(fp_poly
			(pts
				(xy 0.3048 -0.1016) (xy 0.3048 0.9906) (xy -0.3048 0.9906) (xy -0.3048 -0.1016)
			)
			(stroke
				(width 0)
				(type default)
			)
			(fill no)
			(layer "F.CrtYd")
		)
		(fp_line
			(start 0.3048 -0.1016)
			(end -0.3048 -0.1016)
			(stroke
				(width 0.1)
				(type default)
			)
			(layer "F.Fab")
		)
		(fp_line
			(start -0.3048 -0.1016)
			(end -0.3048 0.9906)
			(stroke
				(width 0.1)
				(type default)
			)
			(layer "F.Fab")
		)
		(fp_line
			(start 0.3048 0.9906)
			(end 0.3048 -0.1016)
			(stroke
				(width 0.1)
				(type default)
			)
			(layer "F.Fab")
		)
		(fp_line
			(start -0.3048 0.9906)
			(end 0.3048 0.9906)
			(stroke
				(width 0.1)
				(type default)
			)
			(layer "F.Fab")
		)
		(pad "1" smd rect
			(at 0 0 90)
			(size 0.508 0.508)
			(layers "F.Cu" "F.Mask" "F.Paste")
			(net "ISENSE_TMP421_2_DXP")
		)
		(pad "2" smd rect
			(at 0 0.889 90)
			(size 0.508 0.508)
			(layers "F.Cu" "F.Mask" "F.Paste")
			(net "ISENSE_TMP421_2_DXN")
		)
		(zone
			(layer "F.Cu")
			(hatch none 0.5)
			(connect_pads
				(clearance 0)
			)
			(min_thickness 0.25)
			(keepout
				(tracks allowed)
				(vias not_allowed)
				(pads allowed)
				(copperpour not_allowed)
				(footprints allowed)
			)
			(placement
				(enabled no)
				(sheetname "")
			)
			(fill
				(thermal_gap 0.5)
				(thermal_bridge_width 0.5)
				(island_removal_mode 0)
			)
			(polygon
				(pts
					(xy 0.569468 -68.332858) (xy 0.569468 -68.840858) (xy 0.950468 -68.840858) (xy 0.950468 -68.332858)
				)
			)
		)
		(zone
			(layer "F.Cu")
			(hatch none 0.5)
			(connect_pads
				(clearance 0)
			)
			(min_thickness 0.25)
			(keepout
				(tracks not_allowed)
				(vias allowed)
				(pads allowed)
				(copperpour not_allowed)
				(footprints allowed)
			)
			(placement
				(enabled no)
				(sheetname "")
			)
			(fill
				(thermal_gap 0.5)
				(thermal_bridge_width 0.5)
				(island_removal_mode 0)
			)
			(polygon
				(pts
					(xy 0.950468 -68.332858) (xy 0.950468 -68.840858) (xy 0.569468 -68.840858) (xy 0.569468 -68.332858)
				)
			)
		)
	)
	(footprint ""
		(layer "F.Cu")
		(at 473.827094 -141.608048 -90)
		(property "Reference" "C1L16"
			(at 0 0 270)
			(layer "F.SilkS")
			(hide yes)
			(effects
				(font
					(size 1.27 1.27)
				)
			)
		)
		(property "Value" ""
			(at 0 0 270)
			(layer "F.Fab")
			(effects
				(font
					(size 1.27 1.27)
				)
			)
		)
		(duplicate_pad_numbers_are_jumpers no)
		(fp_poly
			(pts
				(xy 0.3048 -0.1016) (xy 0.3048 0.9906) (xy -0.3048 0.9906) (xy -0.3048 -0.1016)
			)
			(stroke
				(width 0)
				(type default)
			)
			(fill no)
			(layer "F.CrtYd")
		)
		(fp_line
			(start -0.3048 0.9906)
			(end 0.3048 0.9906)
			(stroke
				(width 0.1)
				(type default)
			)
			(layer "F.Fab")
		)
		(fp_line
			(start 0.3048 0.9906)
			(end 0.3048 -0.1016)
			(stroke
				(width 0.1)
				(type default)
			)
			(layer "F.Fab")
		)
		(fp_line
			(start -0.3048 -0.1016)
			(end -0.3048 0.9906)
			(stroke
				(width 0.1)
				(type default)
			)
			(layer "F.Fab")
		)
		(fp_line
			(start 0.3048 -0.1016)
			(end -0.3048 -0.1016)
			(stroke
				(width 0.1)
				(type default)
			)
			(layer "F.Fab")
		)
		(pad "1" smd rect
			(at 0 0 270)
			(size 0.508 0.508)
			(layers "F.Cu" "F.Mask" "F.Paste")
			(net "P3V3")
		)
		(pad "2" smd rect
			(at 0 0.889 270)
			(size 0.508 0.508)
			(layers "F.Cu" "F.Mask" "F.Paste")
			(net "GND")
		)
		(zone
			(layer "F.Cu")
			(hatch none 0.5)
			(connect_pads
				(clearance 0)
			)
			(min_thickness 0.25)
			(keepout
				(tracks not_allowed)
				(vias allowed)
				(pads allowed)
				(copperpour not_allowed)
				(footprints allowed)
			)
			(placement
				(enabled no)
				(sheetname "")
			)
			(fill
				(thermal_gap 0.5)
				(thermal_bridge_width 0.5)
				(island_removal_mode 0)
			)
			(polygon
				(pts
					(xy 473.192094 -141.862048) (xy 473.192094 -141.354048) (xy 473.573094 -141.354048) (xy 473.573094 -141.862048)
				)
			)
		)
		(zone
			(layer "F.Cu")
			(hatch none 0.5)
			(connect_pads
				(clearance 0)
			)
			(min_thickness 0.25)
			(keepout
				(tracks allowed)
				(vias not_allowed)
				(pads allowed)
				(copperpour not_allowed)
				(footprints allowed)
			)
			(placement
				(enabled no)
				(sheetname "")
			)
			(fill
				(thermal_gap 0.5)
				(thermal_bridge_width 0.5)
				(island_removal_mode 0)
			)
			(polygon
				(pts
					(xy 473.573094 -141.862048) (xy 473.573094 -141.354048) (xy 473.192094 -141.354048) (xy 473.192094 -141.862048)
				)
			)
		)
	)
	(footprint ""
		(layer "F.Cu")
		(at 426.4279 -124.0536 -90)
		(property "Reference" "R8B17"
			(at 0 0 270)
			(layer "F.SilkS")
			(hide yes)
			(effects
				(font
					(size 1.27 1.27)
				)
			)
		)
		(property "Value" ""
			(at 0 0 270)
			(layer "F.Fab")
			(effects
				(font
					(size 1.27 1.27)
				)
			)
		)
		(duplicate_pad_numbers_are_jumpers no)
		(fp_poly
			(pts
				(xy -0.2794 -0.1016) (xy 0.2794 -0.1016) (xy 0.2794 0.9906) (xy -0.2794 0.9906)
			)
			(stroke
				(width 0)
				(type default)
			)
			(fill no)
			(layer "F.CrtYd")
		)
		(fp_line
			(start -0.2794 0.9906)
			(end 0.2794 0.9906)
			(stroke
				(width 0.1)
				(type default)
			)
			(layer "F.Fab")
		)
		(fp_line
			(start 0.2794 0.9906)
			(end 0.2794 -0.1016)
			(stroke
				(width 0.1)
				(type default)
			)
			(layer "F.Fab")
		)
		(fp_line
			(start -0.2794 -0.1016)
			(end -0.2794 0.9906)
			(stroke
				(width 0.1)
				(type default)
			)
			(layer "F.Fab")
		)
		(fp_line
			(start 0.2794 -0.1016)
			(end -0.2794 -0.1016)
			(stroke
				(width 0.1)
				(type default)
			)
			(layer "F.Fab")
		)
		(pad "1" smd rect
			(at 0 0 270)
			(size 0.508 0.508)
			(layers "F.Cu" "F.Mask" "F.Paste")
			(net "PVPP_ABC")
		)
		(pad "2" smd rect
			(at 0 0.889 270)
			(size 0.508 0.508)
			(layers "F.Cu" "F.Mask" "F.Paste")
			(net "IRQ_HFI1_CPU0_LVT2_N")
		)
		(zone
			(layer "F.Cu")
			(hatch none 0.5)
			(connect_pads
				(clearance 0)
			)
			(min_thickness 0.25)
			(keepout
				(tracks not_allowed)
				(vias allowed)
				(pads allowed)
				(copperpour not_allowed)
				(footprints allowed)
			)
			(placement
				(enabled no)
				(sheetname "")
			)
			(fill
				(thermal_gap 0.5)
				(thermal_bridge_width 0.5)
				(island_removal_mode 0)
			)
			(polygon
				(pts
					(xy 425.7929 -124.3076) (xy 425.7929 -123.7996) (xy 426.1739 -123.7996) (xy 426.1739 -124.3076)
				)
			)
		)
		(zone
			(layer "F.Cu")
			(hatch none 0.5)
			(connect_pads
				(clearance 0)
			)
			(min_thickness 0.25)
			(keepout
				(tracks allowed)
				(vias not_allowed)
				(pads allowed)
				(copperpour not_allowed)
				(footprints allowed)
			)
			(placement
				(enabled no)
				(sheetname "")
			)
			(fill
				(thermal_gap 0.5)
				(thermal_bridge_width 0.5)
				(island_removal_mode 0)
			)
			(polygon
				(pts
					(xy 426.1739 -124.3076) (xy 426.1739 -123.7996) (xy 425.7929 -123.7996) (xy 425.7929 -124.3076)
				)
			)
		)
	)
	(footprint ""
		(layer "F.Cu")
		(at 180.594 -64.135 180)
		(property "Reference" "R4E4"
			(at 0 0 180)
			(layer "F.SilkS")
			(hide yes)
			(effects
				(font
					(size 1.27 1.27)
				)
			)
		)
		(property "Value" ""
			(at 0 0 180)
			(layer "F.Fab")
			(effects
				(font
					(size 1.27 1.27)
				)
			)
		)
		(duplicate_pad_numbers_are_jumpers no)
		(fp_rect
			(start -0.2794 0.9906)
			(end 0.2794 -0.1016)
			(stroke
				(width 0)
				(type default)
			)
			(fill no)
			(layer "F.CrtYd")
		)
		(fp_line
			(start 0.2794 0.9906)
			(end 0.2794 -0.1016)
			(stroke
				(width 0.1)
				(type default)
			)
			(layer "F.Fab")
		)
		(fp_line
			(start 0.2794 -0.1016)
			(end -0.2794 -0.1016)
			(stroke
				(width 0.1)
				(type default)
			)
			(layer "F.Fab")
		)
		(fp_line
			(start -0.2794 0.9906)
			(end 0.2794 0.9906)
			(stroke
				(width 0.1)
				(type default)
			)
			(layer "F.Fab")
		)
		(fp_line
			(start -0.2794 -0.1016)
			(end -0.2794 0.9906)
			(stroke
				(width 0.1)
				(type default)
			)
			(layer "F.Fab")
		)
		(pad "1" smd rect
			(at 0 0 180)
			(size 0.508 0.508)
			(layers "F.Cu" "F.Mask" "F.Paste")
			(net "P3V3_STBY")
		)
		(pad "2" smd rect
			(at 0 0.889 180)
			(size 0.508 0.508)
			(layers "F.Cu" "F.Mask" "F.Paste")
			(net "FM_PVCCIN_CPU0_PWR_IN_ALERT_N")
		)
		(zone
			(layer "F.Cu")
			(hatch none 0.5)
			(connect_pads
				(clearance 0)
			)
			(min_thickness 0.25)
			(keepout
				(tracks allowed)
				(vias not_allowed)
				(pads allowed)
				(copperpour not_allowed)
				(footprints allowed)
			)
			(placement
				(enabled no)
				(sheetname "")
			)
			(fill
				(thermal_gap 0.5)
				(thermal_bridge_width 0.5)
				(island_removal_mode 0)
			)
			(polygon
				(pts
					(xy 180.848 -64.77) (xy 180.34 -64.77) (xy 180.34 -64.389) (xy 180.848 -64.389)
				)
			)
		)
		(zone
			(layer "F.Cu")
			(hatch none 0.5)
			(connect_pads
				(clearance 0)
			)
			(min_thickness 0.25)
			(keepout
				(tracks not_allowed)
				(vias allowed)
				(pads allowed)
				(copperpour not_allowed)
				(footprints allowed)
			)
			(placement
				(enabled no)
				(sheetname "")
			)
			(fill
				(thermal_gap 0.5)
				(thermal_bridge_width 0.5)
				(island_removal_mode 0)
			)
			(polygon
				(pts
					(xy 180.848 -64.77) (xy 180.34 -64.77) (xy 180.34 -64.389) (xy 180.848 -64.389)
				)
			)
		)
	)
	(footprint ""
		(layer "F.Cu")
		(at 26.489406 -31.738316 180)
		(property "Reference" "C1F9"
			(at 0 0 180)
			(layer "F.SilkS")
			(hide yes)
			(effects
				(font
					(size 1.27 1.27)
				)
			)
		)
		(property "Value" ""
			(at 0 0 180)
			(layer "F.Fab")
			(effects
				(font
					(size 1.27 1.27)
				)
			)
		)
		(duplicate_pad_numbers_are_jumpers no)
		(fp_rect
			(start 0.3048 -0.1016)
			(end -0.3048 0.9906)
			(stroke
				(width 0)
				(type default)
			)
			(fill no)
			(layer "F.CrtYd")
		)
		(fp_line
			(start 0.3048 0.9906)
			(end 0.3048 -0.1016)
			(stroke
				(width 0.1)
				(type default)
			)
			(layer "F.Fab")
		)
		(fp_line
			(start 0.3048 -0.1016)
			(end -0.3048 -0.1016)
			(stroke
				(width 0.1)
				(type default)
			)
			(layer "F.Fab")
		)
		(fp_line
			(start -0.3048 0.9906)
			(end 0.3048 0.9906)
			(stroke
				(width 0.1)
				(type default)
			)
			(layer "F.Fab")
		)
		(fp_line
			(start -0.3048 -0.1016)
			(end -0.3048 0.9906)
			(stroke
				(width 0.1)
				(type default)
			)
			(layer "F.Fab")
		)
		(pad "1" smd rect
			(at 0 0 180)
			(size 0.508 0.508)
			(layers "F.Cu" "F.Mask" "F.Paste")
			(net "FAN_TACH0")
		)
		(pad "2" smd rect
			(at 0 0.889 180)
			(size 0.508 0.508)
			(layers "F.Cu" "F.Mask" "F.Paste")
			(net "GND")
		)
		(zone
			(layer "F.Cu")
			(hatch none 0.5)
			(connect_pads
				(clearance 0)
			)
			(min_thickness 0.25)
			(keepout
				(tracks allowed)
				(vias not_allowed)
				(pads allowed)
				(copperpour not_allowed)
				(footprints allowed)
			)
			(placement
				(enabled no)
				(sheetname "")
			)
			(fill
				(thermal_gap 0.5)
				(thermal_bridge_width 0.5)
				(island_removal_mode 0)
			)
			(polygon
				(pts
					(xy 26.235406 -31.992316) (xy 26.743406 -31.992316) (xy 26.743406 -32.373316) (xy 26.235406 -32.373316)
				)
			)
		)
		(zone
			(layer "F.Cu")
			(hatch none 0.5)
			(connect_pads
				(clearance 0)
			)
			(min_thickness 0.25)
			(keepout
				(tracks not_allowed)
				(vias allowed)
				(pads allowed)
				(copperpour not_allowed)
				(footprints allowed)
			)
			(placement
				(enabled no)
				(sheetname "")
			)
			(fill
				(thermal_gap 0.5)
				(thermal_bridge_width 0.5)
				(island_removal_mode 0)
			)
			(polygon
				(pts
					(xy 26.235406 -31.992316) (xy 26.743406 -31.992316) (xy 26.743406 -32.373316) (xy 26.235406 -32.373316)
				)
			)
		)
	)
	(footprint ""
		(layer "F.Cu")
		(at 190.7286 -66.6242 180)
		(property "Reference" "CF2"
			(at 0 0 180)
			(layer "F.SilkS")
			(hide yes)
			(effects
				(font
					(size 1.27 1.27)
				)
			)
		)
		(property "Value" "*"
			(at 1.1811 -2.8194 180)
			(unlocked yes)
			(layer "F.Fab")
			(hide yes)
			(effects
				(font
					(size 1.27 1.016)
					(thickness 0.1524)
				)
			)
		)
		(property "Device Type" "SC22P50V2JN-4GP_SMD-BCG-SC22P5A"
			(at 1.1811 -4.3434 180)
			(unlocked yes)
			(layer "F.Fab")
			(hide yes)
			(effects
				(font
					(size 1.27 1.016)
					(thickness 0.1524)
				)
			)
		)
		(duplicate_pad_numbers_are_jumpers no)
		(fp_rect
			(start -0.4318 0.9525)
			(end 0.4318 -0.9525)
			(stroke
				(width 0)
				(type default)
			)
			(fill no)
			(layer "F.CrtYd")
		)
		(fp_rect
			(start -0.4318 0.9525)
			(end 0.4318 -0.9525)
			(stroke
				(width 0)
				(type default)
			)
			(fill no)
			(layer "F.Fab")
		)
		(pad "1" smd custom
			(at 0 -0.4445 180)
			(size 0.1524 0.1524)
			(layers "F.Cu" "F.Mask" "F.Paste")
			(net "VR_PVCCIN_CPU0_AIREF2")
			(options
				(clearance outline)
				(anchor circle)
			)
			(primitives
				(gr_poly
					(pts
						(arc
							(start 0.3048 -0.2032)
							(mid 0.275042 -0.275042)
							(end 0.2032 -0.3048)
						)
						(arc
							(start -0.2032 -0.3048)
							(mid -0.275042 -0.275042)
							(end -0.3048 -0.2032)
						)
						(arc
							(start -0.3048 0.2032)
							(mid -0.275042 0.275042)
							(end -0.2032 0.3048)
						)
						(arc
							(start 0.2032 0.3048)
							(mid 0.275042 0.275042)
							(end 0.3048 0.2032)
						)
					)
					(width 0)
					(fill yes)
				)
			)
		)
		(pad "2" smd custom
			(at 0 0.4445 180)
			(size 0.1524 0.1524)
			(layers "F.Cu" "F.Mask" "F.Paste")
			(net "ISENSE_PVCCIN_CPU0_PH2_IMON")
			(options
				(clearance outline)
				(anchor circle)
			)
			(primitives
				(gr_poly
					(pts
						(arc
							(start 0.3048 -0.2032)
							(mid 0.275042 -0.275042)
							(end 0.2032 -0.3048)
						)
						(arc
							(start -0.2032 -0.3048)
							(mid -0.275042 -0.275042)
							(end -0.3048 -0.2032)
						)
						(arc
							(start -0.3048 0.2032)
							(mid -0.275042 0.275042)
							(end -0.2032 0.3048)
						)
						(arc
							(start 0.2032 0.3048)
							(mid 0.275042 0.275042)
							(end 0.3048 0.2032)
						)
					)
					(width 0)
					(fill yes)
				)
			)
		)
	)
	(footprint ""
		(layer "F.Cu")
		(at -3.901694 -148.286978 90)
		(property "Reference" "RT8"
			(at 1.01473 0.656336 0)
			(unlocked yes)
			(layer "F.SilkS")
			(effects
				(font
					(size 0.4064 0.254)
					(thickness 0.1524)
				)
			)
		)
		(property "Value" ""
			(at 0 0 90)
			(layer "F.Fab")
			(effects
				(font
					(size 1.27 1.27)
				)
			)
		)
		(duplicate_pad_numbers_are_jumpers no)
		(fp_poly
			(pts
				(xy -0.4953 -0.2032) (xy 0.4953 -0.2032) (xy 0.4953 1.6002) (xy -0.4953 1.6002)
			)
			(stroke
				(width 0)
				(type default)
			)
			(fill no)
			(layer "F.CrtYd")
		)
		(fp_line
			(start 0.4953 -0.2032)
			(end 0.4953 1.6002)
			(stroke
				(width 0.1)
				(type default)
			)
			(layer "F.Fab")
		)
		(fp_line
			(start -0.4953 -0.2032)
			(end 0.4953 -0.2032)
			(stroke
				(width 0.1)
				(type default)
			)
			(layer "F.Fab")
		)
		(fp_line
			(start 0.4953 1.6002)
			(end -0.4953 1.6002)
			(stroke
				(width 0.1)
				(type default)
			)
			(layer "F.Fab")
		)
		(fp_line
			(start -0.4953 1.6002)
			(end -0.4953 -0.2032)
			(stroke
				(width 0.1)
				(type default)
			)
			(layer "F.Fab")
		)
		(pad "1" smd rect
			(at 0 0 90)
			(size 0.762 0.889)
			(layers "F.Cu" "F.Mask" "F.Paste")
			(net "VR_PVDDQ_KLM_PH2_BOOT")
		)
		(pad "2" smd rect
			(at 0 1.397 90)
			(size 0.762 0.889)
			(layers "F.Cu" "F.Mask" "F.Paste")
			(net "VR_PVDDQ_KLM_PH2_BOOT_R")
		)
		(zone
			(layer "F.Cu")
			(hatch none 0.5)
			(connect_pads
				(clearance 0)
			)
			(min_thickness 0.25)
			(keepout
				(tracks allowed)
				(vias not_allowed)
				(pads allowed)
				(copperpour not_allowed)
				(footprints allowed)
			)
			(placement
				(enabled no)
				(sheetname "")
			)
			(fill
				(thermal_gap 0.5)
				(thermal_bridge_width 0.5)
				(island_removal_mode 0)
			)
			(polygon
				(pts
					(xy -2.949194 -148.667978) (xy -3.457194 -148.667978) (xy -3.457194 -147.905978) (xy -2.949194 -147.905978)
				)
			)
		)
		(zone
			(layer "F.Cu")
			(hatch none 0.5)
			(connect_pads
				(clearance 0)
			)
			(min_thickness 0.25)
			(keepout
				(tracks not_allowed)
				(vias allowed)
				(pads allowed)
				(copperpour not_allowed)
				(footprints allowed)
			)
			(placement
				(enabled no)
				(sheetname "")
			)
			(fill
				(thermal_gap 0.5)
				(thermal_bridge_width 0.5)
				(island_removal_mode 0)
			)
			(polygon
				(pts
					(xy -2.949194 -147.905978) (xy -2.949194 -148.667978) (xy -3.457194 -148.667978) (xy -3.457194 -147.905978)
				)
			)
		)
	)
	(footprint ""
		(layer "F.Cu")
		(at 465.328 -0.254 -90)
		(property "Reference" "R9G26"
			(at 0 0 270)
			(layer "F.SilkS")
			(hide yes)
			(effects
				(font
					(size 1.27 1.27)
				)
			)
		)
		(property "Value" ""
			(at 0 0 270)
			(layer "F.Fab")
			(effects
				(font
					(size 1.27 1.27)
				)
			)
		)
		(duplicate_pad_numbers_are_jumpers no)
		(fp_poly
			(pts
				(xy -0.2794 -0.1016) (xy 0.2794 -0.1016) (xy 0.2794 0.9906) (xy -0.2794 0.9906)
			)
			(stroke
				(width 0)
				(type default)
			)
			(fill no)
			(layer "F.CrtYd")
		)
		(fp_line
			(start -0.2794 0.9906)
			(end 0.2794 0.9906)
			(stroke
				(width 0.1)
				(type default)
			)
			(layer "F.Fab")
		)
		(fp_line
			(start 0.2794 0.9906)
			(end 0.2794 -0.1016)
			(stroke
				(width 0.1)
				(type default)
			)
			(layer "F.Fab")
		)
		(fp_line
			(start -0.2794 -0.1016)
			(end -0.2794 0.9906)
			(stroke
				(width 0.1)
				(type default)
			)
			(layer "F.Fab")
		)
		(fp_line
			(start 0.2794 -0.1016)
			(end -0.2794 -0.1016)
			(stroke
				(width 0.1)
				(type default)
			)
			(layer "F.Fab")
		)
		(pad "1" smd rect
			(at 0 0 270)
			(size 0.508 0.508)
			(layers "F.Cu" "F.Mask" "F.Paste")
			(net "A_P3V_BAT_SCALED")
		)
		(pad "2" smd rect
			(at 0 0.889 270)
			(size 0.508 0.508)
			(layers "F.Cu" "F.Mask" "F.Paste")
			(net "GND")
		)
		(zone
			(layer "F.Cu")
			(hatch none 0.5)
			(connect_pads
				(clearance 0)
			)
			(min_thickness 0.25)
			(keepout
				(tracks not_allowed)
				(vias allowed)
				(pads allowed)
				(copperpour not_allowed)
				(footprints allowed)
			)
			(placement
				(enabled no)
				(sheetname "")
			)
			(fill
				(thermal_gap 0.5)
				(thermal_bridge_width 0.5)
				(island_removal_mode 0)
			)
			(polygon
				(pts
					(xy 464.693 -0.508) (xy 464.693 0) (xy 465.074 0) (xy 465.074 -0.508)
				)
			)
		)
		(zone
			(layer "F.Cu")
			(hatch none 0.5)
			(connect_pads
				(clearance 0)
			)
			(min_thickness 0.25)
			(keepout
				(tracks allowed)
				(vias not_allowed)
				(pads allowed)
				(copperpour not_allowed)
				(footprints allowed)
			)
			(placement
				(enabled no)
				(sheetname "")
			)
			(fill
				(thermal_gap 0.5)
				(thermal_bridge_width 0.5)
				(island_removal_mode 0)
			)
			(polygon
				(pts
					(xy 465.074 -0.508) (xy 465.074 0) (xy 464.693 0) (xy 464.693 -0.508)
				)
			)
		)
	)
	(footprint ""
		(layer "F.Cu")
		(at 178.943 -131.7625)
		(property "Reference" "C4B8"
			(at 0 0 0)
			(layer "F.SilkS")
			(hide yes)
			(effects
				(font
					(size 1.27 1.27)
				)
			)
		)
		(property "Value" ""
			(at 0 0 0)
			(layer "F.Fab")
			(effects
				(font
					(size 1.27 1.27)
				)
			)
		)
		(duplicate_pad_numbers_are_jumpers no)
		(fp_poly
			(pts
				(xy 0.3048 -0.1016) (xy 0.3048 0.9906) (xy -0.3048 0.9906) (xy -0.3048 -0.1016)
			)
			(stroke
				(width 0)
				(type default)
			)
			(fill no)
			(layer "F.CrtYd")
		)
		(fp_line
			(start -0.3048 -0.1016)
			(end -0.3048 0.9906)
			(stroke
				(width 0.1)
				(type default)
			)
			(layer "F.Fab")
		)
		(fp_line
			(start -0.3048 0.9906)
			(end 0.3048 0.9906)
			(stroke
				(width 0.1)
				(type default)
			)
			(layer "F.Fab")
		)
		(fp_line
			(start 0.3048 -0.1016)
			(end -0.3048 -0.1016)
			(stroke
				(width 0.1)
				(type default)
			)
			(layer "F.Fab")
		)
		(fp_line
			(start 0.3048 0.9906)
			(end 0.3048 -0.1016)
			(stroke
				(width 0.1)
				(type default)
			)
			(layer "F.Fab")
		)
		(pad "1" smd rect
			(at 0 0)
			(size 0.508 0.508)
			(layers "F.Cu" "F.Mask" "F.Paste")
			(net "PWRGD_PVPP_KLM_R")
		)
		(pad "2" smd rect
			(at 0 0.889)
			(size 0.508 0.508)
			(layers "F.Cu" "F.Mask" "F.Paste")
			(net "GND")
		)
		(zone
			(layer "F.Cu")
			(hatch none 0.5)
			(connect_pads
				(clearance 0)
			)
			(min_thickness 0.25)
			(keepout
				(tracks allowed)
				(vias not_allowed)
				(pads allowed)
				(copperpour not_allowed)
				(footprints allowed)
			)
			(placement
				(enabled no)
				(sheetname "")
			)
			(fill
				(thermal_gap 0.5)
				(thermal_bridge_width 0.5)
				(island_removal_mode 0)
			)
			(polygon
				(pts
					(xy 178.689 -131.5085) (xy 179.197 -131.5085) (xy 179.197 -131.1275) (xy 178.689 -131.1275)
				)
			)
		)
		(zone
			(layer "F.Cu")
			(hatch none 0.5)
			(connect_pads
				(clearance 0)
			)
			(min_thickness 0.25)
			(keepout
				(tracks not_allowed)
				(vias allowed)
				(pads allowed)
				(copperpour not_allowed)
				(footprints allowed)
			)
			(placement
				(enabled no)
				(sheetname "")
			)
			(fill
				(thermal_gap 0.5)
				(thermal_bridge_width 0.5)
				(island_removal_mode 0)
			)
			(polygon
				(pts
					(xy 178.689 -131.1275) (xy 179.197 -131.1275) (xy 179.197 -131.5085) (xy 178.689 -131.5085)
				)
			)
		)
	)
	(footprint ""
		(layer "F.Cu")
		(at 476.4659 -147.4089 -90)
		(property "Reference" "C1L9"
			(at 0 0 270)
			(layer "F.SilkS")
			(hide yes)
			(effects
				(font
					(size 1.27 1.27)
				)
			)
		)
		(property "Value" ""
			(at 0 0 270)
			(layer "F.Fab")
			(effects
				(font
					(size 1.27 1.27)
				)
			)
		)
		(duplicate_pad_numbers_are_jumpers no)
		(fp_poly
			(pts
				(xy 0.3048 -0.1016) (xy 0.3048 0.9906) (xy -0.3048 0.9906) (xy -0.3048 -0.1016)
			)
			(stroke
				(width 0)
				(type default)
			)
			(fill no)
			(layer "F.CrtYd")
		)
		(fp_line
			(start -0.3048 0.9906)
			(end 0.3048 0.9906)
			(stroke
				(width 0.1)
				(type default)
			)
			(layer "F.Fab")
		)
		(fp_line
			(start 0.3048 0.9906)
			(end 0.3048 -0.1016)
			(stroke
				(width 0.1)
				(type default)
			)
			(layer "F.Fab")
		)
		(fp_line
			(start -0.3048 -0.1016)
			(end -0.3048 0.9906)
			(stroke
				(width 0.1)
				(type default)
			)
			(layer "F.Fab")
		)
		(fp_line
			(start 0.3048 -0.1016)
			(end -0.3048 -0.1016)
			(stroke
				(width 0.1)
				(type default)
			)
			(layer "F.Fab")
		)
		(pad "1" smd rect
			(at 0 0 270)
			(size 0.508 0.508)
			(layers "F.Cu" "F.Mask" "F.Paste")
			(net "P3V3_STBY")
		)
		(pad "2" smd rect
			(at 0 0.889 270)
			(size 0.508 0.508)
			(layers "F.Cu" "F.Mask" "F.Paste")
			(net "GND")
		)
		(zone
			(layer "F.Cu")
			(hatch none 0.5)
			(connect_pads
				(clearance 0)
			)
			(min_thickness 0.25)
			(keepout
				(tracks not_allowed)
				(vias allowed)
				(pads allowed)
				(copperpour not_allowed)
				(footprints allowed)
			)
			(placement
				(enabled no)
				(sheetname "")
			)
			(fill
				(thermal_gap 0.5)
				(thermal_bridge_width 0.5)
				(island_removal_mode 0)
			)
			(polygon
				(pts
					(xy 475.8309 -147.6629) (xy 475.8309 -147.1549) (xy 476.2119 -147.1549) (xy 476.2119 -147.6629)
				)
			)
		)
		(zone
			(layer "F.Cu")
			(hatch none 0.5)
			(connect_pads
				(clearance 0)
			)
			(min_thickness 0.25)
			(keepout
				(tracks allowed)
				(vias not_allowed)
				(pads allowed)
				(copperpour not_allowed)
				(footprints allowed)
			)
			(placement
				(enabled no)
				(sheetname "")
			)
			(fill
				(thermal_gap 0.5)
				(thermal_bridge_width 0.5)
				(island_removal_mode 0)
			)
			(polygon
				(pts
					(xy 476.2119 -147.6629) (xy 476.2119 -147.1549) (xy 475.8309 -147.1549) (xy 475.8309 -147.6629)
				)
			)
		)
	)
	(footprint ""
		(layer "F.Cu")
		(at 351.731834 -21.284438)
		(property "Reference" "R12W2"
			(at 0 0 0)
			(layer "F.SilkS")
			(hide yes)
			(effects
				(font
					(size 1.27 1.27)
				)
			)
		)
		(property "Value" "*"
			(at 0 -8.9535 0)
			(unlocked yes)
			(layer "F.Fab")
			(hide yes)
			(effects
				(font
					(size 1.27 1.016)
					(thickness 0.1524)
				)
			)
		)
		(property "Device Type" "665KR5B-1-GP_SMD-RG3-665KR5B-1A"
			(at 0 -10.6299 0)
			(unlocked yes)
			(layer "F.Fab")
			(hide yes)
			(effects
				(font
					(size 1.27 1.016)
					(thickness 0.1524)
				)
			)
		)
		(duplicate_pad_numbers_are_jumpers no)
		(fp_line
			(start -0.889 -1.7018)
			(end -0.889 0.2794)
			(stroke
				(width 0.1524)
				(type default)
			)
			(layer "F.SilkS")
		)
		(fp_line
			(start -0.889 0.0762)
			(end -0.889 1.7018)
			(stroke
				(width 0.1524)
				(type default)
			)
			(layer "F.SilkS")
		)
		(fp_line
			(start -0.889 1.7018)
			(end 0.889 1.7018)
			(stroke
				(width 0.1524)
				(type default)
			)
			(layer "F.SilkS")
		)
		(fp_line
			(start 0.889 -1.7018)
			(end -0.889 -1.7018)
			(stroke
				(width 0.1524)
				(type default)
			)
			(layer "F.SilkS")
		)
		(fp_line
			(start 0.889 -1.7018)
			(end 0.889 -0.381)
			(stroke
				(width 0.1524)
				(type default)
			)
			(layer "F.SilkS")
		)
		(fp_line
			(start 0.889 1.7018)
			(end 0.889 -0.508)
			(stroke
				(width 0.1524)
				(type default)
			)
			(layer "F.SilkS")
		)
		(fp_poly
			(pts
				(xy 0.9652 -1.778) (xy 0.9652 1.778) (xy -0.9652 1.778) (xy -0.9652 -1.778)
			)
			(stroke
				(width 0)
				(type default)
			)
			(fill no)
			(layer "F.CrtYd")
		)
		(fp_rect
			(start -0.9652 1.778)
			(end 0.9652 -1.778)
			(stroke
				(width 0)
				(type default)
			)
			(fill no)
			(layer "F.Fab")
		)
		(pad "1" smd rect
			(at 0 -0.9652)
			(size 1.397 1.143)
			(layers "F.Cu" "F.Mask" "F.Paste")
			(net "P12V_NVDIMM_ABC_D")
		)
		(pad "2" smd rect
			(at 0 0.9652)
			(size 1.397 1.143)
			(layers "F.Cu" "F.Mask" "F.Paste")
			(net "VR_PVDDQ_ABC_VINSEN")
		)
	)
	(footprint ""
		(layer "F.Cu")
		(at 450.215 -21.209 -90)
		(property "Reference" "R9W32"
			(at -0.8382 -0.67818 270)
			(unlocked yes)
			(layer "F.SilkS")
			(effects
				(font
					(size 0.4064 0.254)
					(thickness 0.1524)
				)
				(justify left)
			)
		)
		(property "Value" ""
			(at 0 0 270)
			(layer "F.Fab")
			(effects
				(font
					(size 1.27 1.27)
				)
			)
		)
		(duplicate_pad_numbers_are_jumpers no)
		(fp_poly
			(pts
				(xy -0.2794 -0.1016) (xy 0.2794 -0.1016) (xy 0.2794 0.9906) (xy -0.2794 0.9906)
			)
			(stroke
				(width 0)
				(type default)
			)
			(fill no)
			(layer "F.CrtYd")
		)
		(fp_line
			(start -0.2794 0.9906)
			(end 0.2794 0.9906)
			(stroke
				(width 0.1)
				(type default)
			)
			(layer "F.Fab")
		)
		(fp_line
			(start 0.2794 0.9906)
			(end 0.2794 -0.1016)
			(stroke
				(width 0.1)
				(type default)
			)
			(layer "F.Fab")
		)
		(fp_line
			(start -0.2794 -0.1016)
			(end -0.2794 0.9906)
			(stroke
				(width 0.1)
				(type default)
			)
			(layer "F.Fab")
		)
		(fp_line
			(start 0.2794 -0.1016)
			(end -0.2794 -0.1016)
			(stroke
				(width 0.1)
				(type default)
			)
			(layer "F.Fab")
		)
		(pad "1" smd rect
			(at 0 0 270)
			(size 0.508 0.508)
			(layers "F.Cu" "F.Mask" "F.Paste")
			(net "VR_P2V5_BMC_STBY_FB")
		)
		(pad "2" smd rect
			(at 0 0.889 270)
			(size 0.508 0.508)
			(layers "F.Cu" "F.Mask" "F.Paste")
			(net "GND")
		)
		(zone
			(layer "F.Cu")
			(hatch none 0.5)
			(connect_pads
				(clearance 0)
			)
			(min_thickness 0.25)
			(keepout
				(tracks not_allowed)
				(vias allowed)
				(pads allowed)
				(copperpour not_allowed)
				(footprints allowed)
			)
			(placement
				(enabled no)
				(sheetname "")
			)
			(fill
				(thermal_gap 0.5)
				(thermal_bridge_width 0.5)
				(island_removal_mode 0)
			)
			(polygon
				(pts
					(xy 449.58 -21.463) (xy 449.58 -20.955) (xy 449.961 -20.955) (xy 449.961 -21.463)
				)
			)
		)
		(zone
			(layer "F.Cu")
			(hatch none 0.5)
			(connect_pads
				(clearance 0)
			)
			(min_thickness 0.25)
			(keepout
				(tracks allowed)
				(vias not_allowed)
				(pads allowed)
				(copperpour not_allowed)
				(footprints allowed)
			)
			(placement
				(enabled no)
				(sheetname "")
			)
			(fill
				(thermal_gap 0.5)
				(thermal_bridge_width 0.5)
				(island_removal_mode 0)
			)
			(polygon
				(pts
					(xy 449.961 -21.463) (xy 449.961 -20.955) (xy 449.58 -20.955) (xy 449.58 -21.463)
				)
			)
		)
	)
	(footprint ""
		(layer "F.Cu")
		(at 332.90002 -118.5164 90)
		(property "Reference" "C6B19"
			(at -0.8382 -0.67818 90)
			(unlocked yes)
			(layer "F.SilkS")
			(effects
				(font
					(size 0.4064 0.254)
					(thickness 0.1524)
				)
				(justify left)
			)
		)
		(property "Value" ""
			(at 0 0 90)
			(layer "F.Fab")
			(effects
				(font
					(size 1.27 1.27)
				)
			)
		)
		(duplicate_pad_numbers_are_jumpers no)
		(fp_poly
			(pts
				(xy 0.3048 -0.1016) (xy 0.3048 0.9906) (xy -0.3048 0.9906) (xy -0.3048 -0.1016)
			)
			(stroke
				(width 0)
				(type default)
			)
			(fill no)
			(layer "F.CrtYd")
		)
		(fp_line
			(start 0.3048 -0.1016)
			(end -0.3048 -0.1016)
			(stroke
				(width 0.1)
				(type default)
			)
			(layer "F.Fab")
		)
		(fp_line
			(start -0.3048 -0.1016)
			(end -0.3048 0.9906)
			(stroke
				(width 0.1)
				(type default)
			)
			(layer "F.Fab")
		)
		(fp_line
			(start 0.3048 0.9906)
			(end 0.3048 -0.1016)
			(stroke
				(width 0.1)
				(type default)
			)
			(layer "F.Fab")
		)
		(fp_line
			(start -0.3048 0.9906)
			(end 0.3048 0.9906)
			(stroke
				(width 0.1)
				(type default)
			)
			(layer "F.Fab")
		)
		(pad "1" smd rect
			(at 0 0 90)
			(size 0.508 0.508)
			(layers "F.Cu" "F.Mask" "F.Paste")
			(net "P3E_CPU0_PE1_PCH_TXN<8>")
		)
		(pad "2" smd rect
			(at 0 0.889 90)
			(size 0.508 0.508)
			(layers "F.Cu" "F.Mask" "F.Paste")
			(net "P3E_CPU0_PE1_PCH_C_TXN<8>")
		)
		(zone
			(layer "F.Cu")
			(hatch none 0.5)
			(connect_pads
				(clearance 0)
			)
			(min_thickness 0.25)
			(keepout
				(tracks allowed)
				(vias not_allowed)
				(pads allowed)
				(copperpour not_allowed)
				(footprints allowed)
			)
			(placement
				(enabled no)
				(sheetname "")
			)
			(fill
				(thermal_gap 0.5)
				(thermal_bridge_width 0.5)
				(island_removal_mode 0)
			)
			(polygon
				(pts
					(xy 333.15402 -118.2624) (xy 333.15402 -118.7704) (xy 333.53502 -118.7704) (xy 333.53502 -118.2624)
				)
			)
		)
		(zone
			(layer "F.Cu")
			(hatch none 0.5)
			(connect_pads
				(clearance 0)
			)
			(min_thickness 0.25)
			(keepout
				(tracks not_allowed)
				(vias allowed)
				(pads allowed)
				(copperpour not_allowed)
				(footprints allowed)
			)
			(placement
				(enabled no)
				(sheetname "")
			)
			(fill
				(thermal_gap 0.5)
				(thermal_bridge_width 0.5)
				(island_removal_mode 0)
			)
			(polygon
				(pts
					(xy 333.53502 -118.2624) (xy 333.53502 -118.7704) (xy 333.15402 -118.7704) (xy 333.15402 -118.2624)
				)
			)
		)
	)
	(footprint ""
		(layer "F.Cu")
		(at 157.988 -120.080786 90)
		(property "Reference" "R3B2"
			(at 0 0 90)
			(layer "F.SilkS")
			(hide yes)
			(effects
				(font
					(size 1.27 1.27)
				)
			)
		)
		(property "Value" ""
			(at 0 0 90)
			(layer "F.Fab")
			(effects
				(font
					(size 1.27 1.27)
				)
			)
		)
		(duplicate_pad_numbers_are_jumpers no)
		(fp_poly
			(pts
				(xy -0.2794 -0.1016) (xy 0.2794 -0.1016) (xy 0.2794 0.9906) (xy -0.2794 0.9906)
			)
			(stroke
				(width 0)
				(type default)
			)
			(fill no)
			(layer "F.CrtYd")
		)
		(fp_line
			(start 0.2794 -0.1016)
			(end -0.2794 -0.1016)
			(stroke
				(width 0.1)
				(type default)
			)
			(layer "F.Fab")
		)
		(fp_line
			(start -0.2794 -0.1016)
			(end -0.2794 0.9906)
			(stroke
				(width 0.1)
				(type default)
			)
			(layer "F.Fab")
		)
		(fp_line
			(start 0.2794 0.9906)
			(end 0.2794 -0.1016)
			(stroke
				(width 0.1)
				(type default)
			)
			(layer "F.Fab")
		)
		(fp_line
			(start -0.2794 0.9906)
			(end 0.2794 0.9906)
			(stroke
				(width 0.1)
				(type default)
			)
			(layer "F.Fab")
		)
		(pad "1" smd rect
			(at 0 0 90)
			(size 0.508 0.508)
			(layers "F.Cu" "F.Mask" "F.Paste")
			(net "SVID_ALERT0_CPU1_R_N")
		)
		(pad "2" smd rect
			(at 0 0.889 90)
			(size 0.508 0.508)
			(layers "F.Cu" "F.Mask" "F.Paste")
			(net "PVCCIO_CPU1")
		)
		(zone
			(layer "F.Cu")
			(hatch none 0.5)
			(connect_pads
				(clearance 0)
			)
			(min_thickness 0.25)
			(keepout
				(tracks allowed)
				(vias not_allowed)
				(pads allowed)
				(copperpour not_allowed)
				(footprints allowed)
			)
			(placement
				(enabled no)
				(sheetname "")
			)
			(fill
				(thermal_gap 0.5)
				(thermal_bridge_width 0.5)
				(island_removal_mode 0)
			)
			(polygon
				(pts
					(xy 158.242 -119.826786) (xy 158.242 -120.334786) (xy 158.623 -120.334786) (xy 158.623 -119.826786)
				)
			)
		)
		(zone
			(layer "F.Cu")
			(hatch none 0.5)
			(connect_pads
				(clearance 0)
			)
			(min_thickness 0.25)
			(keepout
				(tracks not_allowed)
				(vias allowed)
				(pads allowed)
				(copperpour not_allowed)
				(footprints allowed)
			)
			(placement
				(enabled no)
				(sheetname "")
			)
			(fill
				(thermal_gap 0.5)
				(thermal_bridge_width 0.5)
				(island_removal_mode 0)
			)
			(polygon
				(pts
					(xy 158.623 -119.826786) (xy 158.623 -120.334786) (xy 158.242 -120.334786) (xy 158.242 -119.826786)
				)
			)
		)
	)
	(footprint ""
		(layer "F.Cu")
		(at 274.5232 -79.6036 180)
		(property "Reference" "C5D22"
			(at 0 0 180)
			(layer "F.SilkS")
			(hide yes)
			(effects
				(font
					(size 1.27 1.27)
				)
			)
		)
		(property "Value" ""
			(at 0 0 180)
			(layer "F.Fab")
			(effects
				(font
					(size 1.27 1.27)
				)
			)
		)
		(duplicate_pad_numbers_are_jumpers no)
		(fp_poly
			(pts
				(xy -0.4953 -0.2032) (xy 0.4953 -0.2032) (xy 0.4953 1.6002) (xy -0.4953 1.6002)
			)
			(stroke
				(width 0)
				(type default)
			)
			(fill no)
			(layer "F.CrtYd")
		)
		(fp_line
			(start 0.4953 1.6002)
			(end -0.4953 1.6002)
			(stroke
				(width 0.1)
				(type default)
			)
			(layer "F.Fab")
		)
		(fp_line
			(start 0.4953 -0.2032)
			(end 0.4953 1.6002)
			(stroke
				(width 0.1)
				(type default)
			)
			(layer "F.Fab")
		)
		(fp_line
			(start -0.4953 1.6002)
			(end -0.4953 -0.2032)
			(stroke
				(width 0.1)
				(type default)
			)
			(layer "F.Fab")
		)
		(fp_line
			(start -0.4953 -0.2032)
			(end 0.4953 -0.2032)
			(stroke
				(width 0.1)
				(type default)
			)
			(layer "F.Fab")
		)
		(pad "1" smd rect
			(at 0 0 180)
			(size 0.762 0.889)
			(layers "F.Cu" "F.Mask" "F.Paste")
			(net "PVCCMCP_CPU0")
		)
		(pad "2" smd rect
			(at 0 1.397 180)
			(size 0.762 0.889)
			(layers "F.Cu" "F.Mask" "F.Paste")
			(net "GND")
		)
		(zone
			(layer "F.Cu")
			(hatch none 0.5)
			(connect_pads
				(clearance 0)
			)
			(min_thickness 0.25)
			(keepout
				(tracks not_allowed)
				(vias allowed)
				(pads allowed)
				(copperpour not_allowed)
				(footprints allowed)
			)
			(placement
				(enabled no)
				(sheetname "")
			)
			(fill
				(thermal_gap 0.5)
				(thermal_bridge_width 0.5)
				(island_removal_mode 0)
			)
			(polygon
				(pts
					(xy 274.9042 -80.0481) (xy 274.1422 -80.0481) (xy 274.1422 -80.5561) (xy 274.9042 -80.5561)
				)
			)
		)
	)
	(footprint ""
		(layer "F.Cu")
		(at 458.431392 -39.480998 90)
		(property "Reference" "R9F6"
			(at 0 0 90)
			(layer "F.SilkS")
			(hide yes)
			(effects
				(font
					(size 1.27 1.27)
				)
			)
		)
		(property "Value" "*"
			(at 0.064008 -4.108196 90)
			(unlocked yes)
			(layer "F.Fab")
			(hide yes)
			(effects
				(font
					(size 1.27 1.016)
					(thickness 0.1524)
				)
			)
		)
		(property "Device Type" "4K42R2F-GP_SMD-RG-4K42R2F-GP,6A"
			(at 0.064008 -5.632196 90)
			(unlocked yes)
			(layer "F.Fab")
			(hide yes)
			(effects
				(font
					(size 1.27 1.016)
					(thickness 0.1524)
				)
			)
		)
		(duplicate_pad_numbers_are_jumpers no)
		(fp_line
			(start 0.508 -0.9398)
			(end -0.508 -0.9398)
			(stroke
				(width 0.1524)
				(type default)
			)
			(layer "F.SilkS")
		)
		(fp_line
			(start -0.508 -0.9398)
			(end -0.508 0.9398)
			(stroke
				(width 0.1524)
				(type default)
			)
			(layer "F.SilkS")
		)
		(fp_rect
			(start -0.508 0.9398)
			(end 0.508 -0.9398)
			(stroke
				(width 0)
				(type default)
			)
			(fill no)
			(layer "F.CrtYd")
		)
		(fp_rect
			(start -0.508 0.9398)
			(end 0.508 -0.9398)
			(stroke
				(width 0)
				(type default)
			)
			(fill no)
			(layer "F.Fab")
		)
		(pad "1" smd custom
			(at 0 -0.4445 90)
			(size 0.1397 0.1397)
			(layers "F.Cu" "F.Mask" "F.Paste")
			(net "P1V15_AUX_BMC")
			(options
				(clearance outline)
				(anchor circle)
			)
			(primitives
				(gr_poly
					(pts
						(arc
							(start -0.1778 -0.2794)
							(mid -0.249642 -0.249642)
							(end -0.2794 -0.1778)
						)
						(arc
							(start -0.2794 0.1778)
							(mid -0.249642 0.249642)
							(end -0.1778 0.2794)
						)
						(arc
							(start 0.1778 0.2794)
							(mid 0.249642 0.249642)
							(end 0.2794 0.1778)
						)
						(arc
							(start 0.2794 -0.1778)
							(mid 0.249642 -0.249642)
							(end 0.1778 -0.2794)
						)
					)
					(width 0)
					(fill yes)
				)
			)
		)
		(pad "2" smd custom
			(at 0 0.4445 90)
			(size 0.1397 0.1397)
			(layers "F.Cu" "F.Mask" "F.Paste")
			(net "VR_P1V15_BMC_STBY_FB")
			(options
				(clearance outline)
				(anchor circle)
			)
			(primitives
				(gr_poly
					(pts
						(arc
							(start -0.1778 -0.2794)
							(mid -0.249642 -0.249642)
							(end -0.2794 -0.1778)
						)
						(arc
							(start -0.2794 0.1778)
							(mid -0.249642 0.249642)
							(end -0.1778 0.2794)
						)
						(arc
							(start 0.1778 0.2794)
							(mid 0.249642 0.249642)
							(end 0.2794 0.1778)
						)
						(arc
							(start 0.2794 -0.1778)
							(mid 0.249642 -0.249642)
							(end 0.1778 -0.2794)
						)
					)
					(width 0)
					(fill yes)
				)
			)
		)
	)
	(footprint ""
		(layer "F.Cu")
		(at 6.35 -126.111 90)
		(property "Reference" "C1B11"
			(at 0 0 90)
			(layer "F.SilkS")
			(hide yes)
			(effects
				(font
					(size 1.27 1.27)
				)
			)
		)
		(property "Value" ""
			(at 0 0 90)
			(layer "F.Fab")
			(effects
				(font
					(size 1.27 1.27)
				)
			)
		)
		(duplicate_pad_numbers_are_jumpers no)
		(fp_rect
			(start -0.3048 -0.1016)
			(end 0.3048 0.9906)
			(stroke
				(width 0)
				(type default)
			)
			(fill no)
			(layer "F.CrtYd")
		)
		(fp_line
			(start 0.3048 -0.1016)
			(end -0.3048 -0.1016)
			(stroke
				(width 0.1)
				(type default)
			)
			(layer "F.Fab")
		)
		(fp_line
			(start -0.3048 -0.1016)
			(end -0.3048 0.9906)
			(stroke
				(width 0.1)
				(type default)
			)
			(layer "F.Fab")
		)
		(fp_line
			(start 0.3048 0.9906)
			(end 0.3048 -0.1016)
			(stroke
				(width 0.1)
				(type default)
			)
			(layer "F.Fab")
		)
		(fp_line
			(start -0.3048 0.9906)
			(end 0.3048 0.9906)
			(stroke
				(width 0.1)
				(type default)
			)
			(layer "F.Fab")
		)
		(pad "1" smd rect
			(at 0 0 90)
			(size 0.508 0.508)
			(layers "F.Cu" "F.Mask" "F.Paste")
			(net "A_TSENSE_PVDDQ_KLM")
		)
		(pad "2" smd rect
			(at 0 0.889 90)
			(size 0.508 0.508)
			(layers "F.Cu" "F.Mask" "F.Paste")
			(net "GND")
		)
		(zone
			(layer "F.Cu")
			(hatch none 0.5)
			(connect_pads
				(clearance 0)
			)
			(min_thickness 0.25)
			(keepout
				(tracks allowed)
				(vias not_allowed)
				(pads allowed)
				(copperpour not_allowed)
				(footprints allowed)
			)
			(placement
				(enabled no)
				(sheetname "")
			)
			(fill
				(thermal_gap 0.5)
				(thermal_bridge_width 0.5)
				(island_removal_mode 0)
			)
			(polygon
				(pts
					(xy 6.604 -125.857) (xy 6.985 -125.857) (xy 6.985 -126.365) (xy 6.604 -126.365)
				)
			)
		)
		(zone
			(layer "F.Cu")
			(hatch none 0.5)
			(connect_pads
				(clearance 0)
			)
			(min_thickness 0.25)
			(keepout
				(tracks not_allowed)
				(vias allowed)
				(pads allowed)
				(copperpour not_allowed)
				(footprints allowed)
			)
			(placement
				(enabled no)
				(sheetname "")
			)
			(fill
				(thermal_gap 0.5)
				(thermal_bridge_width 0.5)
				(island_removal_mode 0)
			)
			(polygon
				(pts
					(xy 6.604 -125.857) (xy 6.985 -125.857) (xy 6.985 -126.365) (xy 6.604 -126.365)
				)
			)
		)
	)
	(footprint ""
		(layer "F.Cu")
		(at 447.4718 -129.5146 180)
		(property "Reference" "C9B1"
			(at 0 0 180)
			(layer "F.SilkS")
			(hide yes)
			(effects
				(font
					(size 1.27 1.27)
				)
			)
		)
		(property "Value" ""
			(at 0 0 180)
			(layer "F.Fab")
			(effects
				(font
					(size 1.27 1.27)
				)
			)
		)
		(duplicate_pad_numbers_are_jumpers no)
		(fp_poly
			(pts
				(xy -0.7239 -0.2159) (xy 0.7239 -0.2159) (xy 0.7239 1.9939) (xy -0.7239 1.9939)
			)
			(stroke
				(width 0)
				(type default)
			)
			(fill no)
			(layer "F.CrtYd")
		)
		(fp_line
			(start 0.7239 1.9939)
			(end 0.7239 -0.2159)
			(stroke
				(width 0.1)
				(type default)
			)
			(layer "F.Fab")
		)
		(fp_line
			(start 0.7239 -0.2159)
			(end -0.7239 -0.2159)
			(stroke
				(width 0.1)
				(type default)
			)
			(layer "F.Fab")
		)
		(fp_line
			(start -0.7239 1.9939)
			(end 0.7239 1.9939)
			(stroke
				(width 0.1)
				(type default)
			)
			(layer "F.Fab")
		)
		(fp_line
			(start -0.7239 -0.2159)
			(end -0.7239 1.9939)
			(stroke
				(width 0.1)
				(type default)
			)
			(layer "F.Fab")
		)
		(pad "1" smd rect
			(at 0 0 180)
			(size 1.27 1.016)
			(layers "F.Cu" "F.Mask" "F.Paste")
			(net "P5V_HDD_SATA")
		)
		(pad "2" smd rect
			(at 0 1.778 180)
			(size 1.27 1.016)
			(layers "F.Cu" "F.Mask" "F.Paste")
			(net "GND")
		)
		(zone
			(layer "F.Cu")
			(hatch none 0.5)
			(connect_pads
				(clearance 0)
			)
			(min_thickness 0.25)
			(keepout
				(tracks not_allowed)
				(vias allowed)
				(pads allowed)
				(copperpour not_allowed)
				(footprints allowed)
			)
			(placement
				(enabled no)
				(sheetname "")
			)
			(fill
				(thermal_gap 0.5)
				(thermal_bridge_width 0.5)
				(island_removal_mode 0)
			)
			(polygon
				(pts
					(xy 448.1068 -130.0226) (xy 446.8368 -130.0226) (xy 446.8368 -130.7846) (xy 448.1068 -130.7846)
				)
			)
		)
	)
	(footprint ""
		(layer "F.Cu")
		(at 5.923788 -3.00101 -90)
		(property "Reference" "CF19"
			(at 0 0 270)
			(layer "F.SilkS")
			(hide yes)
			(effects
				(font
					(size 1.27 1.27)
				)
			)
		)
		(property "Value" "*"
			(at 1.1811 -2.8194 270)
			(unlocked yes)
			(layer "F.Fab")
			(hide yes)
			(effects
				(font
					(size 1.27 1.016)
					(thickness 0.1524)
				)
			)
		)
		(property "Device Type" "SC22P50V2JN-4GP_SMD-BCG-SC22P5A"
			(at 1.1811 -4.3434 270)
			(unlocked yes)
			(layer "F.Fab")
			(hide yes)
			(effects
				(font
					(size 1.27 1.016)
					(thickness 0.1524)
				)
			)
		)
		(duplicate_pad_numbers_are_jumpers no)
		(fp_rect
			(start -0.4318 0.9525)
			(end 0.4318 -0.9525)
			(stroke
				(width 0)
				(type default)
			)
			(fill no)
			(layer "F.CrtYd")
		)
		(fp_rect
			(start -0.4318 0.9525)
			(end 0.4318 -0.9525)
			(stroke
				(width 0)
				(type default)
			)
			(fill no)
			(layer "F.Fab")
		)
		(pad "1" smd custom
			(at 0 -0.4445 270)
			(size 0.1524 0.1524)
			(layers "F.Cu" "F.Mask" "F.Paste")
			(net "VR_PVDDQ_GHJ_AIREF1")
			(options
				(clearance outline)
				(anchor circle)
			)
			(primitives
				(gr_poly
					(pts
						(arc
							(start 0.3048 -0.2032)
							(mid 0.275042 -0.275042)
							(end 0.2032 -0.3048)
						)
						(arc
							(start -0.2032 -0.3048)
							(mid -0.275042 -0.275042)
							(end -0.3048 -0.2032)
						)
						(arc
							(start -0.3048 0.2032)
							(mid -0.275042 0.275042)
							(end -0.2032 0.3048)
						)
						(arc
							(start 0.2032 0.3048)
							(mid 0.275042 0.275042)
							(end 0.3048 0.2032)
						)
					)
					(width 0)
					(fill yes)
				)
			)
		)
		(pad "2" smd custom
			(at 0 0.4445 270)
			(size 0.1524 0.1524)
			(layers "F.Cu" "F.Mask" "F.Paste")
			(net "ISENSE_PVDDQ_GHJ_PH1_IMON")
			(options
				(clearance outline)
				(anchor circle)
			)
			(primitives
				(gr_poly
					(pts
						(arc
							(start 0.3048 -0.2032)
							(mid 0.275042 -0.275042)
							(end 0.2032 -0.3048)
						)
						(arc
							(start -0.2032 -0.3048)
							(mid -0.275042 -0.275042)
							(end -0.3048 -0.2032)
						)
						(arc
							(start -0.3048 0.2032)
							(mid -0.275042 0.275042)
							(end -0.2032 0.3048)
						)
						(arc
							(start 0.2032 0.3048)
							(mid 0.275042 0.275042)
							(end 0.3048 0.2032)
						)
					)
					(width 0)
					(fill yes)
				)
			)
		)
	)
	(footprint ""
		(layer "F.Cu")
		(at 20.2946 -41.402 180)
		(property "Reference" "U1E2"
			(at 2.2606 2.25933 0)
			(unlocked yes)
			(layer "F.SilkS")
			(effects
				(font
					(size 0.7874 0.5842)
					(thickness 0.1524)
				)
				(justify left)
			)
		)
		(property "Value" ""
			(at 0 0 180)
			(layer "F.Fab")
			(effects
				(font
					(size 1.27 1.27)
				)
			)
		)
		(duplicate_pad_numbers_are_jumpers no)
		(fp_circle
			(center -1.2192 -0.35814)
			(end -1.3462 -0.35814)
			(stroke
				(width 0.254)
				(type default)
			)
			(fill no)
			(layer "F.SilkS")
		)
		(fp_poly
			(pts
				(xy 0.21463 -0.450088) (xy 1.56337 -0.450088) (xy 1.56337 1.75006) (xy 0.21463 1.75006)
			)
			(stroke
				(width 0)
				(type default)
			)
			(fill no)
			(layer "F.CrtYd")
		)
		(fp_line
			(start 1.56337 1.75006)
			(end 0.21463 1.75006)
			(stroke
				(width 0.1)
				(type default)
			)
			(layer "F.Fab")
		)
		(fp_line
			(start 1.56337 -0.450088)
			(end 1.56337 1.75006)
			(stroke
				(width 0.1)
				(type default)
			)
			(layer "F.Fab")
		)
		(fp_line
			(start 0.21463 1.75006)
			(end 0.21463 -0.450088)
			(stroke
				(width 0.1)
				(type default)
			)
			(layer "F.Fab")
		)
		(fp_line
			(start 0.21463 -0.450088)
			(end 1.56337 -0.450088)
			(stroke
				(width 0.1)
				(type default)
			)
			(layer "F.Fab")
		)
		(fp_circle
			(center -0.4699 -0.8382)
			(end -0.5969 -0.8382)
			(stroke
				(width 0.254)
				(type default)
			)
			(fill no)
			(layer "F.Fab")
		)
		(pad "1" smd rect
			(at 0 0 180)
			(size 1.016 0.381)
			(layers "F.Cu" "F.Mask" "F.Paste")
			(net "FM_CTNR_PS_ON")
		)
		(pad "2" smd rect
			(at 0 0.649986 180)
			(size 1.016 0.381)
			(layers "F.Cu" "F.Mask" "F.Paste")
			(net "FM_DISABLE_FAN_N")
		)
		(pad "3" smd rect
			(at 0 1.299972 180)
			(size 1.016 0.381)
			(layers "F.Cu" "F.Mask" "F.Paste")
			(net "GND")
		)
		(pad "4" smd rect
			(at 1.778 1.299972 180)
			(size 1.016 0.381)
			(layers "F.Cu" "F.Mask" "F.Paste")
			(net "FM_ENABLE_FAN_POWER")
		)
		(pad "5" smd rect
			(at 1.778 0 180)
			(size 1.016 0.381)
			(layers "F.Cu" "F.Mask" "F.Paste")
			(net "P3V3_STBY")
		)
	)
	(footprint ""
		(layer "F.Cu")
		(at 281.178 -73.152 90)
		(property "Reference" "R6D9"
			(at 0 0 90)
			(layer "F.SilkS")
			(hide yes)
			(effects
				(font
					(size 1.27 1.27)
				)
			)
		)
		(property "Value" ""
			(at 0 0 90)
			(layer "F.Fab")
			(effects
				(font
					(size 1.27 1.27)
				)
			)
		)
		(duplicate_pad_numbers_are_jumpers no)
		(fp_rect
			(start -0.2794 -0.1016)
			(end 0.2794 0.9906)
			(stroke
				(width 0)
				(type default)
			)
			(fill no)
			(layer "F.CrtYd")
		)
		(fp_line
			(start 0.2794 -0.1016)
			(end -0.2794 -0.1016)
			(stroke
				(width 0.1)
				(type default)
			)
			(layer "F.Fab")
		)
		(fp_line
			(start -0.2794 -0.1016)
			(end -0.2794 0.9906)
			(stroke
				(width 0.1)
				(type default)
			)
			(layer "F.Fab")
		)
		(fp_line
			(start 0.2794 0.9906)
			(end 0.2794 -0.1016)
			(stroke
				(width 0.1)
				(type default)
			)
			(layer "F.Fab")
		)
		(fp_line
			(start -0.2794 0.9906)
			(end 0.2794 0.9906)
			(stroke
				(width 0.1)
				(type default)
			)
			(layer "F.Fab")
		)
		(pad "1" smd rect
			(at 0 0 90)
			(size 0.508 0.508)
			(layers "F.Cu" "F.Mask" "F.Paste")
			(net "PVCCIO_CPU0")
		)
		(pad "2" smd rect
			(at 0 0.889 90)
			(size 0.508 0.508)
			(layers "F.Cu" "F.Mask" "F.Paste")
			(net "H_CPU0_MSMI_G_N")
		)
		(zone
			(layer "F.Cu")
			(hatch none 0.5)
			(connect_pads
				(clearance 0)
			)
			(min_thickness 0.25)
			(keepout
				(tracks allowed)
				(vias not_allowed)
				(pads allowed)
				(copperpour not_allowed)
				(footprints allowed)
			)
			(placement
				(enabled no)
				(sheetname "")
			)
			(fill
				(thermal_gap 0.5)
				(thermal_bridge_width 0.5)
				(island_removal_mode 0)
			)
			(polygon
				(pts
					(xy 281.432 -72.898) (xy 281.813 -72.898) (xy 281.813 -73.406) (xy 281.432 -73.406)
				)
			)
		)
		(zone
			(layer "F.Cu")
			(hatch none 0.5)
			(connect_pads
				(clearance 0)
			)
			(min_thickness 0.25)
			(keepout
				(tracks not_allowed)
				(vias allowed)
				(pads allowed)
				(copperpour not_allowed)
				(footprints allowed)
			)
			(placement
				(enabled no)
				(sheetname "")
			)
			(fill
				(thermal_gap 0.5)
				(thermal_bridge_width 0.5)
				(island_removal_mode 0)
			)
			(polygon
				(pts
					(xy 281.432 -72.898) (xy 281.813 -72.898) (xy 281.813 -73.406) (xy 281.432 -73.406)
				)
			)
		)
	)
	(footprint ""
		(layer "F.Cu")
		(at 4.295394 -12.815824 90)
		(property "Reference" "C1G14"
			(at 0 0 90)
			(layer "F.SilkS")
			(hide yes)
			(effects
				(font
					(size 1.27 1.27)
				)
			)
		)
		(property "Value" ""
			(at 0 0 90)
			(layer "F.Fab")
			(effects
				(font
					(size 1.27 1.27)
				)
			)
		)
		(duplicate_pad_numbers_are_jumpers no)
		(fp_rect
			(start 0.3048 -0.1016)
			(end -0.3048 0.9906)
			(stroke
				(width 0)
				(type default)
			)
			(fill no)
			(layer "F.CrtYd")
		)
		(fp_line
			(start 0.3048 -0.1016)
			(end -0.3048 -0.1016)
			(stroke
				(width 0.1)
				(type default)
			)
			(layer "F.Fab")
		)
		(fp_line
			(start -0.3048 -0.1016)
			(end -0.3048 0.9906)
			(stroke
				(width 0.1)
				(type default)
			)
			(layer "F.Fab")
		)
		(fp_line
			(start 0.3048 0.9906)
			(end 0.3048 -0.1016)
			(stroke
				(width 0.1)
				(type default)
			)
			(layer "F.Fab")
		)
		(fp_line
			(start -0.3048 0.9906)
			(end 0.3048 0.9906)
			(stroke
				(width 0.1)
				(type default)
			)
			(layer "F.Fab")
		)
		(pad "1" smd rect
			(at 0 0 90)
			(size 0.508 0.508)
			(layers "F.Cu" "F.Mask" "F.Paste")
			(net "VR_FET_SW_P12V_STBY_PVDDQ_GHJ")
		)
		(pad "2" smd rect
			(at 0 0.889 90)
			(size 0.508 0.508)
			(layers "F.Cu" "F.Mask" "F.Paste")
			(net "GND")
		)
		(zone
			(layer "F.Cu")
			(hatch none 0.5)
			(connect_pads
				(clearance 0)
			)
			(min_thickness 0.25)
			(keepout
				(tracks not_allowed)
				(vias allowed)
				(pads allowed)
				(copperpour not_allowed)
				(footprints allowed)
			)
			(placement
				(enabled no)
				(sheetname "")
			)
			(fill
				(thermal_gap 0.5)
				(thermal_bridge_width 0.5)
				(island_removal_mode 0)
			)
			(polygon
				(pts
					(xy 4.549394 -13.069824) (xy 4.549394 -12.561824) (xy 4.930394 -12.561824) (xy 4.930394 -13.069824)
				)
			)
		)
		(zone
			(layer "F.Cu")
			(hatch none 0.5)
			(connect_pads
				(clearance 0)
			)
			(min_thickness 0.25)
			(keepout
				(tracks allowed)
				(vias not_allowed)
				(pads allowed)
				(copperpour not_allowed)
				(footprints allowed)
			)
			(placement
				(enabled no)
				(sheetname "")
			)
			(fill
				(thermal_gap 0.5)
				(thermal_bridge_width 0.5)
				(island_removal_mode 0)
			)
			(polygon
				(pts
					(xy 4.549394 -13.069824) (xy 4.549394 -12.561824) (xy 4.930394 -12.561824) (xy 4.930394 -13.069824)
				)
			)
		)
	)
	(footprint ""
		(layer "F.Cu")
		(at 164.973 -60.9346 90)
		(property "Reference" "C4E7"
			(at 0.2794 -2.76733 90)
			(unlocked yes)
			(layer "F.SilkS")
			(effects
				(font
					(size 0.7874 0.5842)
					(thickness 0.1524)
				)
			)
		)
		(property "Value" ""
			(at 0 0 90)
			(layer "F.Fab")
			(effects
				(font
					(size 1.27 1.27)
				)
			)
		)
		(duplicate_pad_numbers_are_jumpers no)
		(fp_line
			(start 2.504948 -1.616456)
			(end 2.504948 1.633728)
			(stroke
				(width 0.1524)
				(type default)
			)
			(layer "F.SilkS")
		)
		(fp_line
			(start 1.6002 -1.616456)
			(end 2.504948 -1.616456)
			(stroke
				(width 0.1524)
				(type default)
			)
			(layer "F.SilkS")
		)
		(fp_line
			(start -1.6002 -1.616456)
			(end -2.563114 -1.616456)
			(stroke
				(width 0.1524)
				(type default)
			)
			(layer "F.SilkS")
		)
		(fp_line
			(start -2.563114 -1.616456)
			(end -2.563114 1.633728)
			(stroke
				(width 0.1524)
				(type default)
			)
			(layer "F.SilkS")
		)
		(fp_line
			(start 2.504948 1.633728)
			(end 1.6002 1.633728)
			(stroke
				(width 0.1524)
				(type default)
			)
			(layer "F.SilkS")
		)
		(fp_line
			(start -2.563114 1.633728)
			(end -1.6002 1.633728)
			(stroke
				(width 0.1524)
				(type default)
			)
			(layer "F.SilkS")
		)
		(fp_line
			(start 2.286 7.366)
			(end 2.286 1.63195)
			(stroke
				(width 0.1524)
				(type default)
			)
			(layer "F.SilkS")
		)
		(fp_line
			(start 2.286 7.366)
			(end 1.600708 7.366)
			(stroke
				(width 0.1524)
				(type default)
			)
			(layer "F.SilkS")
		)
		(fp_line
			(start -2.286 7.366)
			(end -2.286 1.632712)
			(stroke
				(width 0.1524)
				(type default)
			)
			(layer "F.SilkS")
		)
		(fp_line
			(start -2.286 7.366)
			(end -1.60147 7.366)
			(stroke
				(width 0.1524)
				(type default)
			)
			(layer "F.SilkS")
		)
		(fp_rect
			(start -2.286 7.366)
			(end 2.286 -0.254)
			(stroke
				(width 0)
				(type default)
			)
			(fill no)
			(layer "F.CrtYd")
		)
		(fp_line
			(start 2.286 -0.254)
			(end 2.286 7.366)
			(stroke
				(width 0.1)
				(type default)
			)
			(layer "F.Fab")
		)
		(fp_line
			(start -2.286 -0.254)
			(end 2.286 -0.254)
			(stroke
				(width 0.1)
				(type default)
			)
			(layer "F.Fab")
		)
		(fp_line
			(start 2.286 7.366)
			(end -2.286 7.366)
			(stroke
				(width 0.1)
				(type default)
			)
			(layer "F.Fab")
		)
		(fp_line
			(start -2.286 7.366)
			(end -2.286 -0.254)
			(stroke
				(width 0.1)
				(type default)
			)
			(layer "F.Fab")
		)
		(pad "1" smd rect
			(at 0 0 90)
			(size 2.54 3.048)
			(layers "F.Cu" "F.Mask" "F.Paste")
			(net "PVCCIO_CPU1")
		)
		(pad "2" smd rect
			(at 0 7.112 90)
			(size 2.54 3.048)
			(layers "F.Cu" "F.Mask" "F.Paste")
			(net "GND")
		)
	)
	(footprint ""
		(layer "F.Cu")
		(at 248.8565 -149.8092 -90)
		(property "Reference" "C5A2"
			(at 1.848866 0.752348 270)
			(unlocked yes)
			(layer "F.SilkS")
			(effects
				(font
					(size 1.27 0.9652)
					(thickness 0.1524)
				)
			)
		)
		(property "Value" ""
			(at 0 0 270)
			(layer "F.Fab")
			(effects
				(font
					(size 1.27 1.27)
				)
			)
		)
		(duplicate_pad_numbers_are_jumpers no)
		(fp_rect
			(start -0.500126 1.598422)
			(end 0.500126 -0.201422)
			(stroke
				(width 0)
				(type default)
			)
			(fill no)
			(layer "F.CrtYd")
		)
		(fp_line
			(start -0.500126 1.598422)
			(end -0.500126 -0.201422)
			(stroke
				(width 0.1)
				(type default)
			)
			(layer "F.Fab")
		)
		(fp_line
			(start 0.500126 1.598422)
			(end -0.500126 1.598422)
			(stroke
				(width 0.1)
				(type default)
			)
			(layer "F.Fab")
		)
		(fp_line
			(start -0.500126 -0.201422)
			(end 0.500126 -0.201422)
			(stroke
				(width 0.1)
				(type default)
			)
			(layer "F.Fab")
		)
		(fp_line
			(start 0.500126 -0.201422)
			(end 0.500126 1.598422)
			(stroke
				(width 0.1)
				(type default)
			)
			(layer "F.Fab")
		)
		(pad "1" smd rect
			(at 0 0 180)
			(size 0.889 0.9906)
			(layers "F.Cu" "F.Mask" "F.Paste")
			(net "PVDDQ_DEF")
		)
		(pad "2" smd rect
			(at 0 1.397 180)
			(size 0.889 0.9906)
			(layers "F.Cu" "F.Mask" "F.Paste")
			(net "GND")
		)
		(zone
			(layer "F.Cu")
			(hatch none 0.5)
			(connect_pads
				(clearance 0)
			)
			(min_thickness 0.25)
			(keepout
				(tracks allowed)
				(vias not_allowed)
				(pads allowed)
				(copperpour not_allowed)
				(footprints allowed)
			)
			(placement
				(enabled no)
				(sheetname "")
			)
			(fill
				(thermal_gap 0.5)
				(thermal_bridge_width 0.5)
				(island_removal_mode 0)
			)
			(polygon
				(pts
					(xy 247.904 -150.3045) (xy 247.904 -149.3139) (xy 248.412 -149.3139) (xy 248.412 -150.3045)
				)
			)
		)
		(zone
			(layer "F.Cu")
			(hatch none 0.5)
			(connect_pads
				(clearance 0)
			)
			(min_thickness 0.25)
			(keepout
				(tracks not_allowed)
				(vias allowed)
				(pads allowed)
				(copperpour not_allowed)
				(footprints allowed)
			)
			(placement
				(enabled no)
				(sheetname "")
			)
			(fill
				(thermal_gap 0.5)
				(thermal_bridge_width 0.5)
				(island_removal_mode 0)
			)
			(polygon
				(pts
					(xy 247.904 -150.3045) (xy 247.904 -149.3139) (xy 248.412 -149.3139) (xy 248.412 -150.3045)
				)
			)
		)
	)
	(footprint ""
		(layer "F.Cu")
		(at 94.308168 -149.778212 90)
		(property "Reference" "C2A8"
			(at 0 0 90)
			(layer "F.SilkS")
			(hide yes)
			(effects
				(font
					(size 1.27 1.27)
				)
			)
		)
		(property "Value" ""
			(at 0 0 90)
			(layer "F.Fab")
			(effects
				(font
					(size 1.27 1.27)
				)
			)
		)
		(duplicate_pad_numbers_are_jumpers no)
		(fp_poly
			(pts
				(xy -0.7239 -0.2159) (xy 0.7239 -0.2159) (xy 0.7239 1.9939) (xy -0.7239 1.9939)
			)
			(stroke
				(width 0)
				(type default)
			)
			(fill no)
			(layer "F.CrtYd")
		)
		(fp_line
			(start 0.7239 -0.2159)
			(end -0.7239 -0.2159)
			(stroke
				(width 0.1)
				(type default)
			)
			(layer "F.Fab")
		)
		(fp_line
			(start -0.7239 -0.2159)
			(end -0.7239 1.9939)
			(stroke
				(width 0.1)
				(type default)
			)
			(layer "F.Fab")
		)
		(fp_line
			(start 0.7239 1.9939)
			(end 0.7239 -0.2159)
			(stroke
				(width 0.1)
				(type default)
			)
			(layer "F.Fab")
		)
		(fp_line
			(start -0.7239 1.9939)
			(end 0.7239 1.9939)
			(stroke
				(width 0.1)
				(type default)
			)
			(layer "F.Fab")
		)
		(pad "1" smd rect
			(at 0 0 90)
			(size 1.27 1.016)
			(layers "F.Cu" "F.Mask" "F.Paste")
			(net "PVDDQ_KLM")
		)
		(pad "2" smd rect
			(at 0 1.778 90)
			(size 1.27 1.016)
			(layers "F.Cu" "F.Mask" "F.Paste")
			(net "GND")
		)
		(zone
			(layer "F.Cu")
			(hatch none 0.5)
			(connect_pads
				(clearance 0)
			)
			(min_thickness 0.25)
			(keepout
				(tracks not_allowed)
				(vias allowed)
				(pads allowed)
				(copperpour not_allowed)
				(footprints allowed)
			)
			(placement
				(enabled no)
				(sheetname "")
			)
			(fill
				(thermal_gap 0.5)
				(thermal_bridge_width 0.5)
				(island_removal_mode 0)
			)
			(polygon
				(pts
					(xy 94.816168 -149.143212) (xy 94.816168 -150.413212) (xy 95.578168 -150.413212) (xy 95.578168 -149.143212)
				)
			)
		)
	)
	(footprint ""
		(layer "F.Cu")
		(at 499.872 -144.399)
		(property "Reference" "DS9A3"
			(at -1.33477 0.11684 90)
			(unlocked yes)
			(layer "F.SilkS")
			(effects
				(font
					(size 0.7874 0.5842)
					(thickness 0.1524)
				)
			)
		)
		(property "Value" ""
			(at 0 0 0)
			(layer "F.Fab")
			(effects
				(font
					(size 1.27 1.27)
				)
			)
		)
		(duplicate_pad_numbers_are_jumpers no)
		(fp_line
			(start -1.826006 1.143254)
			(end -1.345184 0.310388)
			(stroke
				(width 0.1524)
				(type default)
			)
			(layer "F.SilkS")
		)
		(fp_line
			(start -1.345184 -0.813054)
			(end -1.345184 0.310388)
			(stroke
				(width 0.1524)
				(type default)
			)
			(layer "F.SilkS")
		)
		(fp_line
			(start -1.345184 0.310388)
			(end -0.864362 1.143254)
			(stroke
				(width 0.1524)
				(type default)
			)
			(layer "F.SilkS")
		)
		(fp_line
			(start -1.345184 1.143254)
			(end -1.826006 1.143254)
			(stroke
				(width 0.1524)
				(type default)
			)
			(layer "F.SilkS")
		)
		(fp_line
			(start -1.345184 2.05486)
			(end -1.345184 1.143254)
			(stroke
				(width 0.1524)
				(type default)
			)
			(layer "F.SilkS")
		)
		(fp_line
			(start -0.864362 0.310388)
			(end -1.826006 0.310388)
			(stroke
				(width 0.1524)
				(type default)
			)
			(layer "F.SilkS")
		)
		(fp_line
			(start -0.864362 1.143254)
			(end -1.345184 1.143254)
			(stroke
				(width 0.1524)
				(type default)
			)
			(layer "F.SilkS")
		)
		(fp_poly
			(pts
				(xy -0.5715 2.2098) (xy -0.5715 0.2032) (xy 0.5715 0.2032) (xy 0.5715 0.6985)
				(arc
					(start 0.726948 0.6985)
					(mid 1.29058 0.932279)
					(end 1.524 1.49606)
				)
				(arc
					(start 1.524 2.05994)
					(mid 1.2904 2.6239)
					(end 0.72644 2.8575)
				)
				(xy 0.5715 2.8575) (xy 0.5715 3.3528) (xy -0.5715 3.3528)
			)
			(stroke
				(width 0)
				(type default)
			)
			(fill no)
			(layer "F.CrtYd")
		)
		(fp_line
			(start -1.837182 1.132078)
			(end -1.35636 0.299212)
			(stroke
				(width 0.1)
				(type default)
			)
			(layer "F.Fab")
		)
		(fp_line
			(start -1.35636 0.299212)
			(end -1.35636 -0.82423)
			(stroke
				(width 0.1)
				(type default)
			)
			(layer "F.Fab")
		)
		(fp_line
			(start -1.35636 0.299212)
			(end -0.875538 1.132078)
			(stroke
				(width 0.1)
				(type default)
			)
			(layer "F.Fab")
		)
		(fp_line
			(start -1.35636 1.132078)
			(end -1.35636 2.043684)
			(stroke
				(width 0.1)
				(type default)
			)
			(layer "F.Fab")
		)
		(fp_line
			(start -0.875538 0.299212)
			(end -1.837182 0.299212)
			(stroke
				(width 0.1)
				(type default)
			)
			(layer "F.Fab")
		)
		(fp_line
			(start -0.875538 1.132078)
			(end -1.837182 1.132078)
			(stroke
				(width 0.1)
				(type default)
			)
			(layer "F.Fab")
		)
		(fp_line
			(start -0.5715 0.2032)
			(end 0.5715 0.2032)
			(stroke
				(width 0.1)
				(type default)
			)
			(layer "F.Fab")
		)
		(fp_line
			(start -0.5715 0.7112)
			(end 0.5715 0.7112)
			(stroke
				(width 0.1)
				(type default)
			)
			(layer "F.Fab")
		)
		(fp_line
			(start -0.5715 2.8448)
			(end 0.5715 2.8448)
			(stroke
				(width 0.1)
				(type default)
			)
			(layer "F.Fab")
		)
		(fp_line
			(start -0.5715 3.3528)
			(end -0.5715 0.2032)
			(stroke
				(width 0.1)
				(type default)
			)
			(layer "F.Fab")
		)
		(fp_line
			(start 0.5715 0.2032)
			(end 0.5715 3.3528)
			(stroke
				(width 0.1)
				(type default)
			)
			(layer "F.Fab")
		)
		(fp_line
			(start 0.5715 2.8575)
			(end 0.72644 2.8575)
			(stroke
				(width 0.1)
				(type default)
			)
			(layer "F.Fab")
		)
		(fp_line
			(start 0.5715 3.3528)
			(end -0.5715 3.3528)
			(stroke
				(width 0.1)
				(type default)
			)
			(layer "F.Fab")
		)
		(fp_line
			(start 0.72644 0.6985)
			(end 0.5715 0.6985)
			(stroke
				(width 0.1)
				(type default)
			)
			(layer "F.Fab")
		)
		(fp_line
			(start 1.524 2.05994)
			(end 1.524 1.49606)
			(stroke
				(width 0.1)
				(type default)
			)
			(layer "F.Fab")
		)
		(fp_arc
			(start 0.72644 0.6985)
			(mid 1.290388 0.932112)
			(end 1.524 1.49606)
			(stroke
				(width 0.1)
				(type default)
			)
			(layer "F.Fab")
		)
		(fp_arc
			(start 1.524 2.05994)
			(mid 1.290388 2.623888)
			(end 0.72644 2.8575)
			(stroke
				(width 0.1)
				(type default)
			)
			(layer "F.Fab")
		)
		(pad "1" smd rect
			(at 0 0)
			(size 1.524 1.524)
			(layers "F.Cu" "F.Mask" "F.Paste")
			(net "FM_SPEAKER_PCH_N")
		)
		(pad "2" smd rect
			(at 0 3.556)
			(size 1.524 1.524)
			(layers "F.Cu" "F.Mask" "F.Paste")
			(net "FM_BEEP_LED_P")
		)
		(pad "3" smd rect
			(at -0.762 1.778)
			(size 0.889 0.889)
			(layers "F.Cu" "F.Mask" "F.Paste")
			(net "Net_6473")
		)
		(zone
			(layer "F.Cu")
			(hatch none 0.5)
			(connect_pads
				(clearance 0)
			)
			(min_thickness 0.25)
			(keepout
				(tracks allowed)
				(vias not_allowed)
				(pads allowed)
				(copperpour not_allowed)
				(footprints allowed)
			)
			(placement
				(enabled no)
				(sheetname "")
			)
			(fill
				(thermal_gap 0.5)
				(thermal_bridge_width 0.5)
				(island_removal_mode 0)
			)
			(polygon
				(pts
					(xy 500.4435 -143.5862) (xy 500.4435 -141.6558) (xy 499.3005 -141.6558) (xy 499.3005 -143.5862)
				)
			)
		)
	)
	(footprint ""
		(layer "F.Cu")
		(at 321.16522 -120.53316 90)
		(property "Reference" "C6B11"
			(at -0.8382 -0.67818 90)
			(unlocked yes)
			(layer "F.SilkS")
			(effects
				(font
					(size 0.4064 0.254)
					(thickness 0.1524)
				)
				(justify left)
			)
		)
		(property "Value" ""
			(at 0 0 90)
			(layer "F.Fab")
			(effects
				(font
					(size 1.27 1.27)
				)
			)
		)
		(duplicate_pad_numbers_are_jumpers no)
		(fp_poly
			(pts
				(xy 0.3048 -0.1016) (xy 0.3048 0.9906) (xy -0.3048 0.9906) (xy -0.3048 -0.1016)
			)
			(stroke
				(width 0)
				(type default)
			)
			(fill no)
			(layer "F.CrtYd")
		)
		(fp_line
			(start 0.3048 -0.1016)
			(end -0.3048 -0.1016)
			(stroke
				(width 0.1)
				(type default)
			)
			(layer "F.Fab")
		)
		(fp_line
			(start -0.3048 -0.1016)
			(end -0.3048 0.9906)
			(stroke
				(width 0.1)
				(type default)
			)
			(layer "F.Fab")
		)
		(fp_line
			(start 0.3048 0.9906)
			(end 0.3048 -0.1016)
			(stroke
				(width 0.1)
				(type default)
			)
			(layer "F.Fab")
		)
		(fp_line
			(start -0.3048 0.9906)
			(end 0.3048 0.9906)
			(stroke
				(width 0.1)
				(type default)
			)
			(layer "F.Fab")
		)
		(pad "1" smd rect
			(at 0 0 90)
			(size 0.508 0.508)
			(layers "F.Cu" "F.Mask" "F.Paste")
			(net "P3E_CPU0_PE1_PCH_TXN<12>")
		)
		(pad "2" smd rect
			(at 0 0.889 90)
			(size 0.508 0.508)
			(layers "F.Cu" "F.Mask" "F.Paste")
			(net "P3E_CPU0_PE1_PCH_C_TXN<12>")
		)
		(zone
			(layer "F.Cu")
			(hatch none 0.5)
			(connect_pads
				(clearance 0)
			)
			(min_thickness 0.25)
			(keepout
				(tracks allowed)
				(vias not_allowed)
				(pads allowed)
				(copperpour not_allowed)
				(footprints allowed)
			)
			(placement
				(enabled no)
				(sheetname "")
			)
			(fill
				(thermal_gap 0.5)
				(thermal_bridge_width 0.5)
				(island_removal_mode 0)
			)
			(polygon
				(pts
					(xy 321.41922 -120.27916) (xy 321.41922 -120.78716) (xy 321.80022 -120.78716) (xy 321.80022 -120.27916)
				)
			)
		)
		(zone
			(layer "F.Cu")
			(hatch none 0.5)
			(connect_pads
				(clearance 0)
			)
			(min_thickness 0.25)
			(keepout
				(tracks not_allowed)
				(vias allowed)
				(pads allowed)
				(copperpour not_allowed)
				(footprints allowed)
			)
			(placement
				(enabled no)
				(sheetname "")
			)
			(fill
				(thermal_gap 0.5)
				(thermal_bridge_width 0.5)
				(island_removal_mode 0)
			)
			(polygon
				(pts
					(xy 321.80022 -120.27916) (xy 321.80022 -120.78716) (xy 321.41922 -120.78716) (xy 321.41922 -120.27916)
				)
			)
		)
	)
	(footprint ""
		(layer "F.Cu")
		(at 376.3772 -147.8788 -90)
		(property "Reference" "L7A2"
			(at 3.378708 -4.251706 270)
			(unlocked yes)
			(layer "F.SilkS")
			(effects
				(font
					(size 0.4064 0.254)
					(thickness 0.1524)
				)
			)
		)
		(property "Value" ""
			(at 0 0 270)
			(layer "F.Fab")
			(effects
				(font
					(size 1.27 1.27)
				)
			)
		)
		(duplicate_pad_numbers_are_jumpers no)
		(fp_line
			(start -1.1303 3.199892)
			(end -1.1303 1.6637)
			(stroke
				(width 0.1524)
				(type default)
			)
			(layer "F.SilkS")
		)
		(fp_line
			(start 8.3693 3.199892)
			(end -1.1303 3.199892)
			(stroke
				(width 0.1524)
				(type default)
			)
			(layer "F.SilkS")
		)
		(fp_line
			(start 8.3693 1.6637)
			(end 8.3693 3.199892)
			(stroke
				(width 0.1524)
				(type default)
			)
			(layer "F.SilkS")
		)
		(fp_line
			(start -1.1303 -1.6637)
			(end -1.1303 -3.199892)
			(stroke
				(width 0.1524)
				(type default)
			)
			(layer "F.SilkS")
		)
		(fp_line
			(start -1.1303 -3.199892)
			(end 8.3693 -3.199892)
			(stroke
				(width 0.1524)
				(type default)
			)
			(layer "F.SilkS")
		)
		(fp_line
			(start 8.3693 -3.199892)
			(end 8.3693 -1.6637)
			(stroke
				(width 0.1524)
				(type default)
			)
			(layer "F.SilkS")
		)
		(fp_rect
			(start -1.1303 3.199892)
			(end 8.3693 -3.199892)
			(stroke
				(width 0)
				(type default)
			)
			(fill no)
			(layer "F.CrtYd")
		)
		(fp_line
			(start -1.1303 3.199892)
			(end -1.1303 -3.199892)
			(stroke
				(width 0.1)
				(type default)
			)
			(layer "F.Fab")
		)
		(fp_line
			(start 8.3693 3.199892)
			(end -1.1303 3.199892)
			(stroke
				(width 0.1)
				(type default)
			)
			(layer "F.Fab")
		)
		(fp_line
			(start -1.1303 -3.199892)
			(end 8.3693 -3.199892)
			(stroke
				(width 0.1)
				(type default)
			)
			(layer "F.Fab")
		)
		(fp_line
			(start 8.3693 -3.199892)
			(end 8.3693 3.199892)
			(stroke
				(width 0.1)
				(type default)
			)
			(layer "F.Fab")
		)
		(pad "1" smd rect
			(at 0 0 270)
			(size 3.683 2.667)
			(layers "F.Cu" "F.Mask" "F.Paste")
			(net "VR_PVNN_PCH_PH1_PHASE_SW")
		)
		(pad "2" smd rect
			(at 7.239 0 270)
			(size 3.683 2.667)
			(layers "F.Cu" "F.Mask" "F.Paste")
			(net "PVNN_PCH_STBY")
		)
	)
	(footprint ""
		(layer "F.Cu")
		(at 380.746 -88.2015)
		(property "Reference" "R25W68"
			(at -0.8382 -0.67818 0)
			(unlocked yes)
			(layer "F.SilkS")
			(effects
				(font
					(size 0.4064 0.254)
					(thickness 0.1524)
				)
				(justify left)
			)
		)
		(property "Value" ""
			(at 0 0 0)
			(layer "F.Fab")
			(effects
				(font
					(size 1.27 1.27)
				)
			)
		)
		(duplicate_pad_numbers_are_jumpers no)
		(fp_poly
			(pts
				(xy -0.2794 -0.1016) (xy 0.2794 -0.1016) (xy 0.2794 0.9906) (xy -0.2794 0.9906)
			)
			(stroke
				(width 0)
				(type default)
			)
			(fill no)
			(layer "F.CrtYd")
		)
		(fp_line
			(start -0.2794 -0.1016)
			(end -0.2794 0.9906)
			(stroke
				(width 0.1)
				(type default)
			)
			(layer "F.Fab")
		)
		(fp_line
			(start -0.2794 0.9906)
			(end 0.2794 0.9906)
			(stroke
				(width 0.1)
				(type default)
			)
			(layer "F.Fab")
		)
		(fp_line
			(start 0.2794 -0.1016)
			(end -0.2794 -0.1016)
			(stroke
				(width 0.1)
				(type default)
			)
			(layer "F.Fab")
		)
		(fp_line
			(start 0.2794 0.9906)
			(end 0.2794 -0.1016)
			(stroke
				(width 0.1)
				(type default)
			)
			(layer "F.Fab")
		)
		(pad "1" smd rect
			(at 0 0)
			(size 0.508 0.508)
			(layers "F.Cu" "F.Mask" "F.Paste")
			(net "LPC_LAD3_IO3")
		)
		(pad "2" smd rect
			(at 0 0.889)
			(size 0.508 0.508)
			(layers "F.Cu" "F.Mask" "F.Paste")
			(net "LPC_LAD3_IO3_R")
		)
		(zone
			(layer "F.Cu")
			(hatch none 0.5)
			(connect_pads
				(clearance 0)
			)
			(min_thickness 0.25)
			(keepout
				(tracks allowed)
				(vias not_allowed)
				(pads allowed)
				(copperpour not_allowed)
				(footprints allowed)
			)
			(placement
				(enabled no)
				(sheetname "")
			)
			(fill
				(thermal_gap 0.5)
				(thermal_bridge_width 0.5)
				(island_removal_mode 0)
			)
			(polygon
				(pts
					(xy 380.492 -87.9475) (xy 381 -87.9475) (xy 381 -87.5665) (xy 380.492 -87.5665)
				)
			)
		)
		(zone
			(layer "F.Cu")
			(hatch none 0.5)
			(connect_pads
				(clearance 0)
			)
			(min_thickness 0.25)
			(keepout
				(tracks not_allowed)
				(vias allowed)
				(pads allowed)
				(copperpour not_allowed)
				(footprints allowed)
			)
			(placement
				(enabled no)
				(sheetname "")
			)
			(fill
				(thermal_gap 0.5)
				(thermal_bridge_width 0.5)
				(island_removal_mode 0)
			)
			(polygon
				(pts
					(xy 380.492 -87.5665) (xy 381 -87.5665) (xy 381 -87.9475) (xy 380.492 -87.9475)
				)
			)
		)
	)
	(footprint ""
		(layer "F.Cu")
		(at 320.194432 -22.740112 90)
		(property "Reference" "C6F6"
			(at 0 0 90)
			(layer "F.SilkS")
			(hide yes)
			(effects
				(font
					(size 1.27 1.27)
				)
			)
		)
		(property "Value" ""
			(at 0 0 90)
			(layer "F.Fab")
			(effects
				(font
					(size 1.27 1.27)
				)
			)
		)
		(duplicate_pad_numbers_are_jumpers no)
		(fp_poly
			(pts
				(xy -0.4953 -0.2032) (xy 0.4953 -0.2032) (xy 0.4953 1.6002) (xy -0.4953 1.6002)
			)
			(stroke
				(width 0)
				(type default)
			)
			(fill no)
			(layer "F.CrtYd")
		)
		(fp_line
			(start 0.4953 -0.2032)
			(end 0.4953 1.6002)
			(stroke
				(width 0.1)
				(type default)
			)
			(layer "F.Fab")
		)
		(fp_line
			(start -0.4953 -0.2032)
			(end 0.4953 -0.2032)
			(stroke
				(width 0.1)
				(type default)
			)
			(layer "F.Fab")
		)
		(fp_line
			(start 0.4953 1.6002)
			(end -0.4953 1.6002)
			(stroke
				(width 0.1)
				(type default)
			)
			(layer "F.Fab")
		)
		(fp_line
			(start -0.4953 1.6002)
			(end -0.4953 -0.2032)
			(stroke
				(width 0.1)
				(type default)
			)
			(layer "F.Fab")
		)
		(pad "1" smd rect
			(at 0 0 90)
			(size 0.762 0.889)
			(layers "F.Cu" "F.Mask" "F.Paste")
			(net "PVPP_ABC")
		)
		(pad "2" smd rect
			(at 0 1.397 90)
			(size 0.762 0.889)
			(layers "F.Cu" "F.Mask" "F.Paste")
			(net "GND")
		)
		(zone
			(layer "F.Cu")
			(hatch none 0.5)
			(connect_pads
				(clearance 0)
			)
			(min_thickness 0.25)
			(keepout
				(tracks not_allowed)
				(vias allowed)
				(pads allowed)
				(copperpour not_allowed)
				(footprints allowed)
			)
			(placement
				(enabled no)
				(sheetname "")
			)
			(fill
				(thermal_gap 0.5)
				(thermal_bridge_width 0.5)
				(island_removal_mode 0)
			)
			(polygon
				(pts
					(xy 320.638932 -22.359112) (xy 320.638932 -23.121112) (xy 321.146932 -23.121112) (xy 321.146932 -22.359112)
				)
			)
		)
	)
	(footprint ""
		(layer "F.Cu")
		(at 111.000032 -3.3528 90)
		(property "Reference" "C3G6"
			(at 1.848866 0.752348 90)
			(unlocked yes)
			(layer "F.SilkS")
			(effects
				(font
					(size 1.27 0.9652)
					(thickness 0.1524)
				)
			)
		)
		(property "Value" ""
			(at 0 0 90)
			(layer "F.Fab")
			(effects
				(font
					(size 1.27 1.27)
				)
			)
		)
		(duplicate_pad_numbers_are_jumpers no)
		(fp_rect
			(start -0.500126 1.598422)
			(end 0.500126 -0.201422)
			(stroke
				(width 0)
				(type default)
			)
			(fill no)
			(layer "F.CrtYd")
		)
		(fp_line
			(start 0.500126 -0.201422)
			(end 0.500126 1.598422)
			(stroke
				(width 0.1)
				(type default)
			)
			(layer "F.Fab")
		)
		(fp_line
			(start -0.500126 -0.201422)
			(end 0.500126 -0.201422)
			(stroke
				(width 0.1)
				(type default)
			)
			(layer "F.Fab")
		)
		(fp_line
			(start 0.500126 1.598422)
			(end -0.500126 1.598422)
			(stroke
				(width 0.1)
				(type default)
			)
			(layer "F.Fab")
		)
		(fp_line
			(start -0.500126 1.598422)
			(end -0.500126 -0.201422)
			(stroke
				(width 0.1)
				(type default)
			)
			(layer "F.Fab")
		)
		(pad "1" smd rect
			(at 0 0)
			(size 0.889 0.9906)
			(layers "F.Cu" "F.Mask" "F.Paste")
			(net "PVDDQ_GHJ")
		)
		(pad "2" smd rect
			(at 0 1.397)
			(size 0.889 0.9906)
			(layers "F.Cu" "F.Mask" "F.Paste")
			(net "GND")
		)
		(zone
			(layer "F.Cu")
			(hatch none 0.5)
			(connect_pads
				(clearance 0)
			)
			(min_thickness 0.25)
			(keepout
				(tracks allowed)
				(vias not_allowed)
				(pads allowed)
				(copperpour not_allowed)
				(footprints allowed)
			)
			(placement
				(enabled no)
				(sheetname "")
			)
			(fill
				(thermal_gap 0.5)
				(thermal_bridge_width 0.5)
				(island_removal_mode 0)
			)
			(polygon
				(pts
					(xy 111.952532 -2.8575) (xy 111.952532 -3.8481) (xy 111.444532 -3.8481) (xy 111.444532 -2.8575)
				)
			)
		)
		(zone
			(layer "F.Cu")
			(hatch none 0.5)
			(connect_pads
				(clearance 0)
			)
			(min_thickness 0.25)
			(keepout
				(tracks not_allowed)
				(vias allowed)
				(pads allowed)
				(copperpour not_allowed)
				(footprints allowed)
			)
			(placement
				(enabled no)
				(sheetname "")
			)
			(fill
				(thermal_gap 0.5)
				(thermal_bridge_width 0.5)
				(island_removal_mode 0)
			)
			(polygon
				(pts
					(xy 111.952532 -2.8575) (xy 111.952532 -3.8481) (xy 111.444532 -3.8481) (xy 111.444532 -2.8575)
				)
			)
		)
	)
	(footprint ""
		(layer "F.Cu")
		(at 347.032072 -97.54489 -90)
		(property "Reference" "EU7C1"
			(at 4.64566 -1.565148 0)
			(unlocked yes)
			(layer "F.SilkS")
			(effects
				(font
					(size 0.7874 0.5842)
					(thickness 0.1524)
				)
			)
		)
		(property "Value" ""
			(at 0 0 270)
			(layer "F.Fab")
			(effects
				(font
					(size 1.27 1.27)
				)
			)
		)
		(duplicate_pad_numbers_are_jumpers no)
		(fp_line
			(start -3.0099 3.429)
			(end -3.0099 -3.5052)
			(stroke
				(width 0.1524)
				(type default)
			)
			(layer "F.SilkS")
		)
		(fp_line
			(start 2.9718 3.429)
			(end -3.0099 3.429)
			(stroke
				(width 0.1524)
				(type default)
			)
			(layer "F.SilkS")
		)
		(fp_line
			(start -3.0099 -3.5052)
			(end 2.9718 -3.5052)
			(stroke
				(width 0.1524)
				(type default)
			)
			(layer "F.SilkS")
		)
		(fp_line
			(start 2.9718 -3.5052)
			(end 2.9718 3.429)
			(stroke
				(width 0.1524)
				(type default)
			)
			(layer "F.SilkS")
		)
		(fp_circle
			(center -3.057398 -2.678684)
			(end -3.057398 -2.805684)
			(stroke
				(width 0.254)
				(type default)
			)
			(fill no)
			(layer "F.SilkS")
		)
		(fp_poly
			(pts
				(xy -2.9972 -3.4925) (xy -2.9972 -2.6924) (xy -2.1971 -3.4925)
			)
			(stroke
				(width 0)
				(type default)
			)
			(fill yes)
			(layer "F.SilkS")
		)
		(fp_poly
			(pts
				(xy -2.549906 -3.050032) (xy -2.549906 3.050032) (xy 2.549906 3.050032) (xy 2.549906 -3.050032)
			)
			(stroke
				(width 0)
				(type default)
			)
			(fill no)
			(layer "F.CrtYd")
		)
		(fp_line
			(start -2.549906 3.050032)
			(end -2.549906 -3.050032)
			(stroke
				(width 0.1)
				(type default)
			)
			(layer "F.Fab")
		)
		(fp_line
			(start 2.549906 3.050032)
			(end -2.549906 3.050032)
			(stroke
				(width 0.1)
				(type default)
			)
			(layer "F.Fab")
		)
		(fp_line
			(start -2.549906 -3.050032)
			(end 2.549906 -3.050032)
			(stroke
				(width 0.1)
				(type default)
			)
			(layer "F.Fab")
		)
		(fp_line
			(start 2.549906 -3.050032)
			(end 2.549906 3.050032)
			(stroke
				(width 0.1)
				(type default)
			)
			(layer "F.Fab")
		)
		(fp_circle
			(center -3.057398 -2.678684)
			(end -3.057398 -2.805684)
			(stroke
				(width 0.254)
				(type default)
			)
			(fill no)
			(layer "F.Fab")
		)
		(pad "1" smd rect
			(at -2.39522 -2.279904 270)
			(size 0.7112 0.254)
			(layers "F.Cu" "F.Mask" "F.Paste")
			(net "PVCCIO_CPU0")
		)
		(pad "2" smd rect
			(at -2.39522 -1.83007 270)
			(size 0.7112 0.254)
			(layers "F.Cu" "F.Mask" "F.Paste")
			(net "GND")
		)
		(pad "3" smd rect
			(at -2.39522 -1.379982 270)
			(size 0.7112 0.254)
			(layers "F.Cu" "F.Mask" "F.Paste")
			(net "VR_PVCCIO_CPU0_PH1_VCIN")
		)
		(pad "4" smd rect
			(at -2.39522 -0.929894 270)
			(size 0.7112 0.254)
			(layers "F.Cu" "F.Mask" "F.Paste")
			(net "P5V_STBY")
		)
		(pad "5" smd rect
			(at -2.39522 -0.48006 270)
			(size 0.7112 0.254)
			(layers "F.Cu" "F.Mask" "F.Paste")
			(net "GND")
		)
		(pad "6" smd rect
			(at -2.39522 -0.029972 270)
			(size 0.7112 0.254)
			(layers "F.Cu" "F.Mask" "F.Paste")
			(net "TP_PVCCIO_CPU0_GL_0")
		)
		(pad "7" smd custom
			(at 0.016764 1.145032 270)
			(size 0.53975 0.53975)
			(layers "F.Cu" "F.Mask" "F.Paste")
			(net "GND")
			(options
				(clearance outline)
				(anchor circle)
			)
			(primitives
				(gr_poly
					(pts
						(xy -2.7051 1.0795) (xy -2.7051 -0.3683) (xy -0.9271 -0.3683) (xy -0.9271 -1.0795) (xy 2.7051 -1.0795)
						(xy 2.7051 1.0795)
					)
					(width 0)
					(fill yes)
				)
			)
		)
		(pad "10" smd rect
			(at -0.008382 2.874772 270)
			(size 4.3434 0.6096)
			(layers "F.Cu" "F.Mask" "F.Paste")
			(net "VR_PVCCIO_CPU0_PH1_SW")
		)
		(pad "25" smd rect
			(at 1.548384 -1.283208 270)
			(size 2.3368 2.0066)
			(layers "F.Cu" "F.Mask" "F.Paste")
			(net "VR_FET_SW_P12V_STBY_PVCCIO_CPU0")
		)
		(pad "30" smd rect
			(at 2.050034 -2.895092 270)
			(size 0.254 0.7112)
			(layers "F.Cu" "F.Mask" "F.Paste")
			(net "VR_FET_SW_P12V_STBY_PVCCIO_CPU0")
		)
		(pad "31" smd rect
			(at 1.599946 -2.895092 270)
			(size 0.254 0.7112)
			(layers "F.Cu" "F.Mask" "F.Paste")
			(net "Net_366")
		)
		(pad "32" smd rect
			(at 1.150112 -2.895092 270)
			(size 0.254 0.7112)
			(layers "F.Cu" "F.Mask" "F.Paste")
			(net "VR_PVCCIO_CPU0_PH1_PHASE")
		)
		(pad "33" smd rect
			(at 0.700024 -2.895092 270)
			(size 0.254 0.7112)
			(layers "F.Cu" "F.Mask" "F.Paste")
			(net "VR_PVCCIO_CPU0_PH1_BOOT_R")
		)
		(pad "34" smd rect
			(at 0.249936 -2.895092 270)
			(size 0.254 0.7112)
			(layers "F.Cu" "F.Mask" "F.Paste")
			(net "VR_PVCCIO_CPU0_PWM1")
		)
		(pad "35" smd rect
			(at -0.199898 -2.895092 270)
			(size 0.254 0.7112)
			(layers "F.Cu" "F.Mask" "F.Paste")
			(net "P5V_STBY")
		)
		(pad "36" smd rect
			(at -0.649986 -2.895092 270)
			(size 0.254 0.7112)
			(layers "F.Cu" "F.Mask" "F.Paste")
			(net "A_TSENSE_PVCCIO_CPU0")
		)
		(pad "37" smd rect
			(at -1.100074 -2.895092 270)
			(size 0.254 0.7112)
			(layers "F.Cu" "F.Mask" "F.Paste")
			(net "VR_PVCCIO_CPU0_OCSET")
		)
		(pad "38" smd rect
			(at -1.549908 -2.895092 270)
			(size 0.254 0.7112)
			(layers "F.Cu" "F.Mask" "F.Paste")
			(net "ISENSE_PVCCIO_CPU0_PH1_IMON")
		)
		(pad "39" smd rect
			(at -1.999996 -2.895092 270)
			(size 0.254 0.7112)
			(layers "F.Cu" "F.Mask" "F.Paste")
			(net "VR_PVCCIO_CPU0_AIREF1")
		)
		(pad "40" smd rect
			(at -0.871728 -1.283208 270)
			(size 1.8034 2.0066)
			(layers "F.Cu" "F.Mask" "F.Paste")
			(net "GND")
		)
		(pad "41" smd rect
			(at -1.533906 0.247904 270)
			(size 0.508 0.3556)
			(layers "F.Cu" "F.Mask" "F.Paste")
			(net "TP_PVCCIO_CPU0_GL_1")
		)
	)
	(footprint ""
		(layer "F.Cu")
		(at 372.6053 -137.0457)
		(property "Reference" "C7A32"
			(at 0 0 0)
			(layer "F.SilkS")
			(hide yes)
			(effects
				(font
					(size 1.27 1.27)
				)
			)
		)
		(property "Value" ""
			(at 0 0 0)
			(layer "F.Fab")
			(effects
				(font
					(size 1.27 1.27)
				)
			)
		)
		(duplicate_pad_numbers_are_jumpers no)
		(fp_rect
			(start -0.7239 1.9939)
			(end 0.7239 -0.2159)
			(stroke
				(width 0)
				(type default)
			)
			(fill no)
			(layer "F.CrtYd")
		)
		(fp_line
			(start -0.7239 -0.2159)
			(end -0.7239 1.9939)
			(stroke
				(width 0.1)
				(type default)
			)
			(layer "F.Fab")
		)
		(fp_line
			(start -0.7239 1.9939)
			(end 0.7239 1.9939)
			(stroke
				(width 0.1)
				(type default)
			)
			(layer "F.Fab")
		)
		(fp_line
			(start 0.7239 -0.2159)
			(end -0.7239 -0.2159)
			(stroke
				(width 0.1)
				(type default)
			)
			(layer "F.Fab")
		)
		(fp_line
			(start 0.7239 1.9939)
			(end 0.7239 -0.2159)
			(stroke
				(width 0.1)
				(type default)
			)
			(layer "F.Fab")
		)
		(pad "1" smd rect
			(at 0 0)
			(size 1.27 1.016)
			(layers "F.Cu" "F.Mask" "F.Paste")
			(net "PVNN_PCH_STBY")
		)
		(pad "2" smd rect
			(at 0 1.778)
			(size 1.27 1.016)
			(layers "F.Cu" "F.Mask" "F.Paste")
			(net "GND")
		)
		(zone
			(layer "F.Cu")
			(hatch none 0.5)
			(connect_pads
				(clearance 0)
			)
			(min_thickness 0.25)
			(keepout
				(tracks not_allowed)
				(vias allowed)
				(pads allowed)
				(copperpour not_allowed)
				(footprints allowed)
			)
			(placement
				(enabled no)
				(sheetname "")
			)
			(fill
				(thermal_gap 0.5)
				(thermal_bridge_width 0.5)
				(island_removal_mode 0)
			)
			(polygon
				(pts
					(xy 371.9703 -135.7757) (xy 373.2403 -135.7757) (xy 373.2403 -136.5377) (xy 371.9703 -136.5377)
				)
			)
		)
	)
	(footprint ""
		(layer "F.Cu")
		(at 186.309 -64.77 90)
		(property "Reference" "C4D45"
			(at 0 0 90)
			(layer "F.SilkS")
			(hide yes)
			(effects
				(font
					(size 1.27 1.27)
				)
			)
		)
		(property "Value" ""
			(at 0 0 90)
			(layer "F.Fab")
			(effects
				(font
					(size 1.27 1.27)
				)
			)
		)
		(duplicate_pad_numbers_are_jumpers no)
		(fp_rect
			(start -0.3048 -0.1016)
			(end 0.3048 0.9906)
			(stroke
				(width 0)
				(type default)
			)
			(fill no)
			(layer "F.CrtYd")
		)
		(fp_line
			(start 0.3048 -0.1016)
			(end -0.3048 -0.1016)
			(stroke
				(width 0.1)
				(type default)
			)
			(layer "F.Fab")
		)
		(fp_line
			(start -0.3048 -0.1016)
			(end -0.3048 0.9906)
			(stroke
				(width 0.1)
				(type default)
			)
			(layer "F.Fab")
		)
		(fp_line
			(start 0.3048 0.9906)
			(end 0.3048 -0.1016)
			(stroke
				(width 0.1)
				(type default)
			)
			(layer "F.Fab")
		)
		(fp_line
			(start -0.3048 0.9906)
			(end 0.3048 0.9906)
			(stroke
				(width 0.1)
				(type default)
			)
			(layer "F.Fab")
		)
		(pad "1" smd rect
			(at 0 0 90)
			(size 0.508 0.508)
			(layers "F.Cu" "F.Mask" "F.Paste")
			(net "VSENSE_PVCCIN_CPU0_AVSP")
		)
		(pad "2" smd rect
			(at 0 0.889 90)
			(size 0.508 0.508)
			(layers "F.Cu" "F.Mask" "F.Paste")
			(net "VSENSE_PVCCIN_CPU0_N")
		)
		(zone
			(layer "F.Cu")
			(hatch none 0.5)
			(connect_pads
				(clearance 0)
			)
			(min_thickness 0.25)
			(keepout
				(tracks not_allowed)
				(vias allowed)
				(pads allowed)
				(copperpour not_allowed)
				(footprints allowed)
			)
			(placement
				(enabled no)
				(sheetname "")
			)
			(fill
				(thermal_gap 0.5)
				(thermal_bridge_width 0.5)
				(island_removal_mode 0)
			)
			(polygon
				(pts
					(xy 186.563 -64.516) (xy 186.944 -64.516) (xy 186.944 -65.024) (xy 186.563 -65.024)
				)
			)
		)
		(zone
			(layer "F.Cu")
			(hatch none 0.5)
			(connect_pads
				(clearance 0)
			)
			(min_thickness 0.25)
			(keepout
				(tracks allowed)
				(vias not_allowed)
				(pads allowed)
				(copperpour not_allowed)
				(footprints allowed)
			)
			(placement
				(enabled no)
				(sheetname "")
			)
			(fill
				(thermal_gap 0.5)
				(thermal_bridge_width 0.5)
				(island_removal_mode 0)
			)
			(polygon
				(pts
					(xy 186.563 -64.516) (xy 186.944 -64.516) (xy 186.944 -65.024) (xy 186.563 -65.024)
				)
			)
		)
	)
	(footprint ""
		(layer "F.Cu")
		(at 323.723 -35.814 90)
		(property "Reference" "R6F1"
			(at 0 0 90)
			(layer "F.SilkS")
			(hide yes)
			(effects
				(font
					(size 1.27 1.27)
				)
			)
		)
		(property "Value" ""
			(at 0 0 90)
			(layer "F.Fab")
			(effects
				(font
					(size 1.27 1.27)
				)
			)
		)
		(duplicate_pad_numbers_are_jumpers no)
		(fp_poly
			(pts
				(xy -0.2794 -0.1016) (xy 0.2794 -0.1016) (xy 0.2794 0.9906) (xy -0.2794 0.9906)
			)
			(stroke
				(width 0)
				(type default)
			)
			(fill no)
			(layer "F.CrtYd")
		)
		(fp_line
			(start 0.2794 -0.1016)
			(end -0.2794 -0.1016)
			(stroke
				(width 0.1)
				(type default)
			)
			(layer "F.Fab")
		)
		(fp_line
			(start -0.2794 -0.1016)
			(end -0.2794 0.9906)
			(stroke
				(width 0.1)
				(type default)
			)
			(layer "F.Fab")
		)
		(fp_line
			(start 0.2794 0.9906)
			(end 0.2794 -0.1016)
			(stroke
				(width 0.1)
				(type default)
			)
			(layer "F.Fab")
		)
		(fp_line
			(start -0.2794 0.9906)
			(end 0.2794 0.9906)
			(stroke
				(width 0.1)
				(type default)
			)
			(layer "F.Fab")
		)
		(pad "1" smd rect
			(at 0 0 90)
			(size 0.508 0.508)
			(layers "F.Cu" "F.Mask" "F.Paste")
			(net "IRQ_DIMM_SAVE_N")
		)
		(pad "2" smd rect
			(at 0 0.889 90)
			(size 0.508 0.508)
			(layers "F.Cu" "F.Mask" "F.Paste")
			(net "FM_ADR_COMPLETE_DEF_N")
		)
		(zone
			(layer "F.Cu")
			(hatch none 0.5)
			(connect_pads
				(clearance 0)
			)
			(min_thickness 0.25)
			(keepout
				(tracks allowed)
				(vias not_allowed)
				(pads allowed)
				(copperpour not_allowed)
				(footprints allowed)
			)
			(placement
				(enabled no)
				(sheetname "")
			)
			(fill
				(thermal_gap 0.5)
				(thermal_bridge_width 0.5)
				(island_removal_mode 0)
			)
			(polygon
				(pts
					(xy 323.977 -35.56) (xy 323.977 -36.068) (xy 324.358 -36.068) (xy 324.358 -35.56)
				)
			)
		)
		(zone
			(layer "F.Cu")
			(hatch none 0.5)
			(connect_pads
				(clearance 0)
			)
			(min_thickness 0.25)
			(keepout
				(tracks not_allowed)
				(vias allowed)
				(pads allowed)
				(copperpour not_allowed)
				(footprints allowed)
			)
			(placement
				(enabled no)
				(sheetname "")
			)
			(fill
				(thermal_gap 0.5)
				(thermal_bridge_width 0.5)
				(island_removal_mode 0)
			)
			(polygon
				(pts
					(xy 324.358 -35.56) (xy 324.358 -36.068) (xy 323.977 -36.068) (xy 323.977 -35.56)
				)
			)
		)
	)
	(footprint ""
		(layer "F.Cu")
		(at 469.077802 -38.188392 90)
		(property "Reference" "EU9F2"
			(at -0.6096 -1.21793 90)
			(unlocked yes)
			(layer "F.SilkS")
			(effects
				(font
					(size 0.7874 0.5842)
					(thickness 0.1524)
				)
				(justify left)
			)
		)
		(property "Value" ""
			(at 0 0 90)
			(layer "F.Fab")
			(effects
				(font
					(size 1.27 1.27)
				)
			)
		)
		(duplicate_pad_numbers_are_jumpers no)
		(fp_circle
			(center -0.570484 -0.440944)
			(end -0.570484 -0.314198)
			(stroke
				(width 0.254)
				(type default)
			)
			(fill no)
			(layer "F.SilkS")
		)
		(fp_poly
			(pts
				(xy -0.064516 -1.0922) (xy -0.064516 -0.3302) (xy 0.697484 -1.0922)
			)
			(stroke
				(width 0)
				(type default)
			)
			(fill yes)
			(layer "F.SilkS")
		)
		(fp_rect
			(start 0.597408 2.295398)
			(end 2.273808 -0.295402)
			(stroke
				(width 0)
				(type default)
			)
			(fill yes)
			(layer "F.Paste")
		)
		(fp_rect
			(start -0.064516 2.500122)
			(end 2.935478 -0.500126)
			(stroke
				(width 0)
				(type default)
			)
			(fill no)
			(layer "F.CrtYd")
		)
		(fp_line
			(start 2.935478 -0.500126)
			(end 2.935478 2.500122)
			(stroke
				(width 0.1)
				(type default)
			)
			(layer "F.Fab")
		)
		(fp_line
			(start -0.064516 -0.500126)
			(end 2.935478 -0.500126)
			(stroke
				(width 0.1)
				(type default)
			)
			(layer "F.Fab")
		)
		(fp_line
			(start 2.935478 2.500122)
			(end -0.064516 2.500122)
			(stroke
				(width 0.1)
				(type default)
			)
			(layer "F.Fab")
		)
		(fp_line
			(start -0.064516 2.500122)
			(end -0.064516 -0.500126)
			(stroke
				(width 0.1)
				(type default)
			)
			(layer "F.Fab")
		)
		(fp_circle
			(center -0.835152 -0.417322)
			(end -0.835152 -0.290576)
			(stroke
				(width 0.254)
				(type default)
			)
			(fill no)
			(layer "F.Fab")
		)
		(pad "1" smd rect
			(at 0 0 90)
			(size 0.6858 0.3048)
			(layers "F.Cu" "F.Mask" "F.Paste")
			(net "P1V2_AUX_BMC")
		)
		(pad "2" smd rect
			(at 0 0.500126 90)
			(size 0.6858 0.3048)
			(layers "F.Cu" "F.Mask" "F.Paste")
			(net "P1V2_AUX_BMC")
		)
		(pad "3" smd rect
			(at 0 0.999998 90)
			(size 0.6858 0.3048)
			(layers "F.Cu" "F.Mask" "F.Paste")
			(net "P1V2_AUX_BMC")
		)
		(pad "4" smd rect
			(at 0 1.500124 90)
			(size 0.6858 0.3048)
			(layers "F.Cu" "F.Mask" "F.Paste")
			(net "VR_P1V2_BMC_STBY_FB")
		)
		(pad "5" smd rect
			(at 0 1.999996 90)
			(size 0.6858 0.3048)
			(layers "F.Cu" "F.Mask" "F.Paste")
			(net "PWRGD_P1V2_BMC_STBY_R")
		)
		(pad "6" smd rect
			(at 2.871216 1.999996 90)
			(size 0.6858 0.3048)
			(layers "F.Cu" "F.Mask" "F.Paste")
			(net "PWRGD_P2V5_BMC_STBY")
		)
		(pad "7" smd rect
			(at 2.871216 1.500124 90)
			(size 0.6858 0.3048)
			(layers "F.Cu" "F.Mask" "F.Paste")
			(net "P3V3_STBY")
		)
		(pad "8" smd rect
			(at 2.871216 0.999998 90)
			(size 0.6858 0.3048)
			(layers "F.Cu" "F.Mask" "F.Paste")
			(net "P3V3_STBY")
		)
		(pad "9" smd rect
			(at 2.871216 0.500126 90)
			(size 0.6858 0.3048)
			(layers "F.Cu" "F.Mask" "F.Paste")
			(net "P3V3_STBY")
		)
		(pad "10" smd rect
			(at 2.871216 0 90)
			(size 0.6858 0.3048)
			(layers "F.Cu" "F.Mask" "F.Paste")
			(net "P3V3_STBY")
		)
		(pad "11" smd rect
			(at 1.435608 0.999998 90)
			(size 1.6764 2.5908)
			(layers "F.Cu" "F.Mask" "F.Paste")
			(net "GND")
		)
	)
	(footprint ""
		(layer "F.Cu")
		(at 464.7057 -23.0759 90)
		(property "Reference" "R8F2"
			(at 0 0 90)
			(layer "F.SilkS")
			(hide yes)
			(effects
				(font
					(size 1.27 1.27)
				)
			)
		)
		(property "Value" ""
			(at 0 0 90)
			(layer "F.Fab")
			(effects
				(font
					(size 1.27 1.27)
				)
			)
		)
		(duplicate_pad_numbers_are_jumpers no)
		(fp_poly
			(pts
				(xy -0.2794 -0.1016) (xy 0.2794 -0.1016) (xy 0.2794 0.9906) (xy -0.2794 0.9906)
			)
			(stroke
				(width 0)
				(type default)
			)
			(fill no)
			(layer "F.CrtYd")
		)
		(fp_line
			(start 0.2794 -0.1016)
			(end -0.2794 -0.1016)
			(stroke
				(width 0.1)
				(type default)
			)
			(layer "F.Fab")
		)
		(fp_line
			(start -0.2794 -0.1016)
			(end -0.2794 0.9906)
			(stroke
				(width 0.1)
				(type default)
			)
			(layer "F.Fab")
		)
		(fp_line
			(start 0.2794 0.9906)
			(end 0.2794 -0.1016)
			(stroke
				(width 0.1)
				(type default)
			)
			(layer "F.Fab")
		)
		(fp_line
			(start -0.2794 0.9906)
			(end 0.2794 0.9906)
			(stroke
				(width 0.1)
				(type default)
			)
			(layer "F.Fab")
		)
		(pad "1" smd rect
			(at 0 0 90)
			(size 0.508 0.508)
			(layers "F.Cu" "F.Mask" "F.Paste")
			(net "PWRGD_P5V_STBY")
		)
		(pad "2" smd rect
			(at 0 0.889 90)
			(size 0.508 0.508)
			(layers "F.Cu" "F.Mask" "F.Paste")
			(net "VR_P3V3_STBY_EN")
		)
		(zone
			(layer "F.Cu")
			(hatch none 0.5)
			(connect_pads
				(clearance 0)
			)
			(min_thickness 0.25)
			(keepout
				(tracks allowed)
				(vias not_allowed)
				(pads allowed)
				(copperpour not_allowed)
				(footprints allowed)
			)
			(placement
				(enabled no)
				(sheetname "")
			)
			(fill
				(thermal_gap 0.5)
				(thermal_bridge_width 0.5)
				(island_removal_mode 0)
			)
			(polygon
				(pts
					(xy 464.9597 -22.8219) (xy 464.9597 -23.3299) (xy 465.3407 -23.3299) (xy 465.3407 -22.8219)
				)
			)
		)
		(zone
			(layer "F.Cu")
			(hatch none 0.5)
			(connect_pads
				(clearance 0)
			)
			(min_thickness 0.25)
			(keepout
				(tracks not_allowed)
				(vias allowed)
				(pads allowed)
				(copperpour not_allowed)
				(footprints allowed)
			)
			(placement
				(enabled no)
				(sheetname "")
			)
			(fill
				(thermal_gap 0.5)
				(thermal_bridge_width 0.5)
				(island_removal_mode 0)
			)
			(polygon
				(pts
					(xy 465.3407 -22.8219) (xy 465.3407 -23.3299) (xy 464.9597 -23.3299) (xy 464.9597 -22.8219)
				)
			)
		)
	)
	(footprint ""
		(layer "F.Cu")
		(at 405.8285 -105.664 90)
		(property "Reference" "R8C21"
			(at 0 0 90)
			(layer "F.SilkS")
			(hide yes)
			(effects
				(font
					(size 1.27 1.27)
				)
			)
		)
		(property "Value" ""
			(at 0 0 90)
			(layer "F.Fab")
			(effects
				(font
					(size 1.27 1.27)
				)
			)
		)
		(duplicate_pad_numbers_are_jumpers no)
		(fp_poly
			(pts
				(xy -0.2794 -0.1016) (xy 0.2794 -0.1016) (xy 0.2794 0.9906) (xy -0.2794 0.9906)
			)
			(stroke
				(width 0)
				(type default)
			)
			(fill no)
			(layer "F.CrtYd")
		)
		(fp_line
			(start 0.2794 -0.1016)
			(end -0.2794 -0.1016)
			(stroke
				(width 0.1)
				(type default)
			)
			(layer "F.Fab")
		)
		(fp_line
			(start -0.2794 -0.1016)
			(end -0.2794 0.9906)
			(stroke
				(width 0.1)
				(type default)
			)
			(layer "F.Fab")
		)
		(fp_line
			(start 0.2794 0.9906)
			(end 0.2794 -0.1016)
			(stroke
				(width 0.1)
				(type default)
			)
			(layer "F.Fab")
		)
		(fp_line
			(start -0.2794 0.9906)
			(end 0.2794 0.9906)
			(stroke
				(width 0.1)
				(type default)
			)
			(layer "F.Fab")
		)
		(pad "1" smd rect
			(at 0 0 90)
			(size 0.508 0.508)
			(layers "F.Cu" "F.Mask" "F.Paste")
			(net "A_RCOMP_3P3")
		)
		(pad "2" smd rect
			(at 0 0.889 90)
			(size 0.508 0.508)
			(layers "F.Cu" "F.Mask" "F.Paste")
			(net "GND")
		)
		(zone
			(layer "F.Cu")
			(hatch none 0.5)
			(connect_pads
				(clearance 0)
			)
			(min_thickness 0.25)
			(keepout
				(tracks allowed)
				(vias not_allowed)
				(pads allowed)
				(copperpour not_allowed)
				(footprints allowed)
			)
			(placement
				(enabled no)
				(sheetname "")
			)
			(fill
				(thermal_gap 0.5)
				(thermal_bridge_width 0.5)
				(island_removal_mode 0)
			)
			(polygon
				(pts
					(xy 406.0825 -105.41) (xy 406.0825 -105.918) (xy 406.4635 -105.918) (xy 406.4635 -105.41)
				)
			)
		)
		(zone
			(layer "F.Cu")
			(hatch none 0.5)
			(connect_pads
				(clearance 0)
			)
			(min_thickness 0.25)
			(keepout
				(tracks not_allowed)
				(vias allowed)
				(pads allowed)
				(copperpour not_allowed)
				(footprints allowed)
			)
			(placement
				(enabled no)
				(sheetname "")
			)
			(fill
				(thermal_gap 0.5)
				(thermal_bridge_width 0.5)
				(island_removal_mode 0)
			)
			(polygon
				(pts
					(xy 406.4635 -105.41) (xy 406.4635 -105.918) (xy 406.0825 -105.918) (xy 406.0825 -105.41)
				)
			)
		)
	)
	(footprint ""
		(layer "F.Cu")
		(at 198.178928 -53.221382 90)
		(property "Reference" "C4E5"
			(at 0 0 90)
			(layer "F.SilkS")
			(hide yes)
			(effects
				(font
					(size 1.27 1.27)
				)
			)
		)
		(property "Value" ""
			(at 0 0 90)
			(layer "F.Fab")
			(effects
				(font
					(size 1.27 1.27)
				)
			)
		)
		(duplicate_pad_numbers_are_jumpers no)
		(fp_rect
			(start 0.3048 0.9906)
			(end -0.3048 -0.1016)
			(stroke
				(width 0)
				(type default)
			)
			(fill no)
			(layer "F.CrtYd")
		)
		(fp_line
			(start 0.3048 -0.1016)
			(end -0.3048 -0.1016)
			(stroke
				(width 0.1)
				(type default)
			)
			(layer "F.Fab")
		)
		(fp_line
			(start -0.3048 -0.1016)
			(end -0.3048 0.9906)
			(stroke
				(width 0.1)
				(type default)
			)
			(layer "F.Fab")
		)
		(fp_line
			(start 0.3048 0.9906)
			(end 0.3048 -0.1016)
			(stroke
				(width 0.1)
				(type default)
			)
			(layer "F.Fab")
		)
		(fp_line
			(start -0.3048 0.9906)
			(end 0.3048 0.9906)
			(stroke
				(width 0.1)
				(type default)
			)
			(layer "F.Fab")
		)
		(pad "1" smd rect
			(at 0 0 90)
			(size 0.508 0.508)
			(layers "F.Cu" "F.Mask" "F.Paste")
			(net "P5V_STBY")
		)
		(pad "2" smd rect
			(at 0 0.889 90)
			(size 0.508 0.508)
			(layers "F.Cu" "F.Mask" "F.Paste")
			(net "GND")
		)
		(zone
			(layer "F.Cu")
			(hatch none 0.5)
			(connect_pads
				(clearance 0)
			)
			(min_thickness 0.25)
			(keepout
				(tracks allowed)
				(vias not_allowed)
				(pads allowed)
				(copperpour not_allowed)
				(footprints allowed)
			)
			(placement
				(enabled no)
				(sheetname "")
			)
			(fill
				(thermal_gap 0.5)
				(thermal_bridge_width 0.5)
				(island_removal_mode 0)
			)
			(polygon
				(pts
					(xy 198.813928 -53.475382) (xy 198.432928 -53.475382) (xy 198.432928 -52.967382) (xy 198.813928 -52.967382)
				)
			)
		)
		(zone
			(layer "F.Cu")
			(hatch none 0.5)
			(connect_pads
				(clearance 0)
			)
			(min_thickness 0.25)
			(keepout
				(tracks not_allowed)
				(vias allowed)
				(pads allowed)
				(copperpour not_allowed)
				(footprints allowed)
			)
			(placement
				(enabled no)
				(sheetname "")
			)
			(fill
				(thermal_gap 0.5)
				(thermal_bridge_width 0.5)
				(island_removal_mode 0)
			)
			(polygon
				(pts
					(xy 198.813928 -53.475382) (xy 198.432928 -53.475382) (xy 198.432928 -52.967382) (xy 198.813928 -52.967382)
				)
			)
		)
	)
	(footprint ""
		(layer "F.Cu")
		(at 171.989496 -74.972672 90)
		(property "Reference" "R4W3"
			(at -0.8382 -0.67818 90)
			(unlocked yes)
			(layer "F.SilkS")
			(effects
				(font
					(size 0.4064 0.254)
					(thickness 0.1524)
				)
				(justify left)
			)
		)
		(property "Value" ""
			(at 0 0 90)
			(layer "F.Fab")
			(effects
				(font
					(size 1.27 1.27)
				)
			)
		)
		(duplicate_pad_numbers_are_jumpers no)
		(fp_poly
			(pts
				(xy -0.2794 -0.1016) (xy 0.2794 -0.1016) (xy 0.2794 0.9906) (xy -0.2794 0.9906)
			)
			(stroke
				(width 0)
				(type default)
			)
			(fill no)
			(layer "F.CrtYd")
		)
		(fp_line
			(start 0.2794 -0.1016)
			(end -0.2794 -0.1016)
			(stroke
				(width 0.1)
				(type default)
			)
			(layer "F.Fab")
		)
		(fp_line
			(start -0.2794 -0.1016)
			(end -0.2794 0.9906)
			(stroke
				(width 0.1)
				(type default)
			)
			(layer "F.Fab")
		)
		(fp_line
			(start 0.2794 0.9906)
			(end 0.2794 -0.1016)
			(stroke
				(width 0.1)
				(type default)
			)
			(layer "F.Fab")
		)
		(fp_line
			(start -0.2794 0.9906)
			(end 0.2794 0.9906)
			(stroke
				(width 0.1)
				(type default)
			)
			(layer "F.Fab")
		)
		(pad "1" smd rect
			(at 0 0 90)
			(size 0.508 0.508)
			(layers "F.Cu" "F.Mask" "F.Paste")
			(net "P3V3_DB1200")
		)
		(pad "2" smd rect
			(at 0 0.889 90)
			(size 0.508 0.508)
			(layers "F.Cu" "F.Mask" "F.Paste")
			(net "SMB_HOST_STBY_LVC3_SDA_R2")
		)
		(zone
			(layer "F.Cu")
			(hatch none 0.5)
			(connect_pads
				(clearance 0)
			)
			(min_thickness 0.25)
			(keepout
				(tracks allowed)
				(vias not_allowed)
				(pads allowed)
				(copperpour not_allowed)
				(footprints allowed)
			)
			(placement
				(enabled no)
				(sheetname "")
			)
			(fill
				(thermal_gap 0.5)
				(thermal_bridge_width 0.5)
				(island_removal_mode 0)
			)
			(polygon
				(pts
					(xy 172.243496 -74.718672) (xy 172.243496 -75.226672) (xy 172.624496 -75.226672) (xy 172.624496 -74.718672)
				)
			)
		)
		(zone
			(layer "F.Cu")
			(hatch none 0.5)
			(connect_pads
				(clearance 0)
			)
			(min_thickness 0.25)
			(keepout
				(tracks not_allowed)
				(vias allowed)
				(pads allowed)
				(copperpour not_allowed)
				(footprints allowed)
			)
			(placement
				(enabled no)
				(sheetname "")
			)
			(fill
				(thermal_gap 0.5)
				(thermal_bridge_width 0.5)
				(island_removal_mode 0)
			)
			(polygon
				(pts
					(xy 172.624496 -74.718672) (xy 172.624496 -75.226672) (xy 172.243496 -75.226672) (xy 172.243496 -74.718672)
				)
			)
		)
	)
	(footprint ""
		(layer "F.Cu")
		(at 452.628 -148.59 180)
		(property "Reference" "R25W164"
			(at -0.8382 -0.67818 180)
			(unlocked yes)
			(layer "F.SilkS")
			(effects
				(font
					(size 0.4064 0.254)
					(thickness 0.1524)
				)
				(justify left)
			)
		)
		(property "Value" ""
			(at 0 0 180)
			(layer "F.Fab")
			(effects
				(font
					(size 1.27 1.27)
				)
			)
		)
		(duplicate_pad_numbers_are_jumpers no)
		(fp_poly
			(pts
				(xy -0.2794 -0.1016) (xy 0.2794 -0.1016) (xy 0.2794 0.9906) (xy -0.2794 0.9906)
			)
			(stroke
				(width 0)
				(type default)
			)
			(fill no)
			(layer "F.CrtYd")
		)
		(fp_line
			(start 0.2794 0.9906)
			(end 0.2794 -0.1016)
			(stroke
				(width 0.1)
				(type default)
			)
			(layer "F.Fab")
		)
		(fp_line
			(start 0.2794 -0.1016)
			(end -0.2794 -0.1016)
			(stroke
				(width 0.1)
				(type default)
			)
			(layer "F.Fab")
		)
		(fp_line
			(start -0.2794 0.9906)
			(end 0.2794 0.9906)
			(stroke
				(width 0.1)
				(type default)
			)
			(layer "F.Fab")
		)
		(fp_line
			(start -0.2794 -0.1016)
			(end -0.2794 0.9906)
			(stroke
				(width 0.1)
				(type default)
			)
			(layer "F.Fab")
		)
		(pad "1" smd rect
			(at 0 0 180)
			(size 0.508 0.508)
			(layers "F.Cu" "F.Mask" "F.Paste")
			(net "P1V05_PCH_STBY")
		)
		(pad "2" smd rect
			(at 0 0.889 180)
			(size 0.508 0.508)
			(layers "F.Cu" "F.Mask" "F.Paste")
			(net "P0V7_GTL2014_VREF_6")
		)
		(zone
			(layer "F.Cu")
			(hatch none 0.5)
			(connect_pads
				(clearance 0)
			)
			(min_thickness 0.25)
			(keepout
				(tracks not_allowed)
				(vias allowed)
				(pads allowed)
				(copperpour not_allowed)
				(footprints allowed)
			)
			(placement
				(enabled no)
				(sheetname "")
			)
			(fill
				(thermal_gap 0.5)
				(thermal_bridge_width 0.5)
				(island_removal_mode 0)
			)
			(polygon
				(pts
					(xy 452.882 -149.225) (xy 452.374 -149.225) (xy 452.374 -148.844) (xy 452.882 -148.844)
				)
			)
		)
		(zone
			(layer "F.Cu")
			(hatch none 0.5)
			(connect_pads
				(clearance 0)
			)
			(min_thickness 0.25)
			(keepout
				(tracks allowed)
				(vias not_allowed)
				(pads allowed)
				(copperpour not_allowed)
				(footprints allowed)
			)
			(placement
				(enabled no)
				(sheetname "")
			)
			(fill
				(thermal_gap 0.5)
				(thermal_bridge_width 0.5)
				(island_removal_mode 0)
			)
			(polygon
				(pts
					(xy 452.882 -148.844) (xy 452.374 -148.844) (xy 452.374 -149.225) (xy 452.882 -149.225)
				)
			)
		)
	)
	(footprint ""
		(layer "F.Cu")
		(at 403.733 -22.098 180)
		(property "Reference" "R25W150"
			(at -0.8382 -0.67818 180)
			(unlocked yes)
			(layer "F.SilkS")
			(effects
				(font
					(size 0.4064 0.254)
					(thickness 0.1524)
				)
				(justify left)
			)
		)
		(property "Value" ""
			(at 0 0 180)
			(layer "F.Fab")
			(effects
				(font
					(size 1.27 1.27)
				)
			)
		)
		(duplicate_pad_numbers_are_jumpers no)
		(fp_poly
			(pts
				(xy -0.2794 -0.1016) (xy 0.2794 -0.1016) (xy 0.2794 0.9906) (xy -0.2794 0.9906)
			)
			(stroke
				(width 0)
				(type default)
			)
			(fill no)
			(layer "F.CrtYd")
		)
		(fp_line
			(start 0.2794 0.9906)
			(end 0.2794 -0.1016)
			(stroke
				(width 0.1)
				(type default)
			)
			(layer "F.Fab")
		)
		(fp_line
			(start 0.2794 -0.1016)
			(end -0.2794 -0.1016)
			(stroke
				(width 0.1)
				(type default)
			)
			(layer "F.Fab")
		)
		(fp_line
			(start -0.2794 0.9906)
			(end 0.2794 0.9906)
			(stroke
				(width 0.1)
				(type default)
			)
			(layer "F.Fab")
		)
		(fp_line
			(start -0.2794 -0.1016)
			(end -0.2794 0.9906)
			(stroke
				(width 0.1)
				(type default)
			)
			(layer "F.Fab")
		)
		(pad "1" smd rect
			(at 0 0 180)
			(size 0.508 0.508)
			(layers "F.Cu" "F.Mask" "F.Paste")
			(net "GND")
		)
		(pad "2" smd rect
			(at 0 0.889 180)
			(size 0.508 0.508)
			(layers "F.Cu" "F.Mask" "F.Paste")
			(net "RMII_BMC_PCH_SPRNGVLLE_TXD0_R")
		)
		(zone
			(layer "F.Cu")
			(hatch none 0.5)
			(connect_pads
				(clearance 0)
			)
			(min_thickness 0.25)
			(keepout
				(tracks not_allowed)
				(vias allowed)
				(pads allowed)
				(copperpour not_allowed)
				(footprints allowed)
			)
			(placement
				(enabled no)
				(sheetname "")
			)
			(fill
				(thermal_gap 0.5)
				(thermal_bridge_width 0.5)
				(island_removal_mode 0)
			)
			(polygon
				(pts
					(xy 403.987 -22.733) (xy 403.479 -22.733) (xy 403.479 -22.352) (xy 403.987 -22.352)
				)
			)
		)
		(zone
			(layer "F.Cu")
			(hatch none 0.5)
			(connect_pads
				(clearance 0)
			)
			(min_thickness 0.25)
			(keepout
				(tracks allowed)
				(vias not_allowed)
				(pads allowed)
				(copperpour not_allowed)
				(footprints allowed)
			)
			(placement
				(enabled no)
				(sheetname "")
			)
			(fill
				(thermal_gap 0.5)
				(thermal_bridge_width 0.5)
				(island_removal_mode 0)
			)
			(polygon
				(pts
					(xy 403.987 -22.352) (xy 403.479 -22.352) (xy 403.479 -22.733) (xy 403.987 -22.733)
				)
			)
		)
	)
	(footprint ""
		(layer "F.Cu")
		(at 404.158196 -58.694828)
		(property "Reference" "R8E18"
			(at 0 0 0)
			(layer "F.SilkS")
			(hide yes)
			(effects
				(font
					(size 1.27 1.27)
				)
			)
		)
		(property "Value" ""
			(at 0 0 0)
			(layer "F.Fab")
			(effects
				(font
					(size 1.27 1.27)
				)
			)
		)
		(duplicate_pad_numbers_are_jumpers no)
		(fp_poly
			(pts
				(xy -0.2794 -0.1016) (xy 0.2794 -0.1016) (xy 0.2794 0.9906) (xy -0.2794 0.9906)
			)
			(stroke
				(width 0)
				(type default)
			)
			(fill no)
			(layer "F.CrtYd")
		)
		(fp_line
			(start -0.2794 -0.1016)
			(end -0.2794 0.9906)
			(stroke
				(width 0.1)
				(type default)
			)
			(layer "F.Fab")
		)
		(fp_line
			(start -0.2794 0.9906)
			(end 0.2794 0.9906)
			(stroke
				(width 0.1)
				(type default)
			)
			(layer "F.Fab")
		)
		(fp_line
			(start 0.2794 -0.1016)
			(end -0.2794 -0.1016)
			(stroke
				(width 0.1)
				(type default)
			)
			(layer "F.Fab")
		)
		(fp_line
			(start 0.2794 0.9906)
			(end 0.2794 -0.1016)
			(stroke
				(width 0.1)
				(type default)
			)
			(layer "F.Fab")
		)
		(pad "1" smd rect
			(at 0 0)
			(size 0.508 0.508)
			(layers "F.Cu" "F.Mask" "F.Paste")
			(net "P5V_STBY")
		)
		(pad "2" smd rect
			(at 0 0.889)
			(size 0.508 0.508)
			(layers "F.Cu" "F.Mask" "F.Paste")
			(net "GND")
		)
		(zone
			(layer "F.Cu")
			(hatch none 0.5)
			(connect_pads
				(clearance 0)
			)
			(min_thickness 0.25)
			(keepout
				(tracks allowed)
				(vias not_allowed)
				(pads allowed)
				(copperpour not_allowed)
				(footprints allowed)
			)
			(placement
				(enabled no)
				(sheetname "")
			)
			(fill
				(thermal_gap 0.5)
				(thermal_bridge_width 0.5)
				(island_removal_mode 0)
			)
			(polygon
				(pts
					(xy 403.904196 -58.440828) (xy 404.412196 -58.440828) (xy 404.412196 -58.059828) (xy 403.904196 -58.059828)
				)
			)
		)
		(zone
			(layer "F.Cu")
			(hatch none 0.5)
			(connect_pads
				(clearance 0)
			)
			(min_thickness 0.25)
			(keepout
				(tracks not_allowed)
				(vias allowed)
				(pads allowed)
				(copperpour not_allowed)
				(footprints allowed)
			)
			(placement
				(enabled no)
				(sheetname "")
			)
			(fill
				(thermal_gap 0.5)
				(thermal_bridge_width 0.5)
				(island_removal_mode 0)
			)
			(polygon
				(pts
					(xy 403.904196 -58.059828) (xy 404.412196 -58.059828) (xy 404.412196 -58.440828) (xy 403.904196 -58.440828)
				)
			)
		)
	)
	(footprint ""
		(layer "F.Cu")
		(at 161.798 -63.373)
		(property "Reference" "C7R1"
			(at 0 0 0)
			(layer "F.SilkS")
			(hide yes)
			(effects
				(font
					(size 1.27 1.27)
				)
			)
		)
		(property "Value" ""
			(at 0 0 0)
			(layer "F.Fab")
			(effects
				(font
					(size 1.27 1.27)
				)
			)
		)
		(duplicate_pad_numbers_are_jumpers no)
		(fp_poly
			(pts
				(xy -0.4953 -0.2032) (xy 0.4953 -0.2032) (xy 0.4953 1.6002) (xy -0.4953 1.6002)
			)
			(stroke
				(width 0)
				(type default)
			)
			(fill no)
			(layer "F.CrtYd")
		)
		(fp_line
			(start -0.4953 -0.2032)
			(end 0.4953 -0.2032)
			(stroke
				(width 0.1)
				(type default)
			)
			(layer "F.Fab")
		)
		(fp_line
			(start -0.4953 1.6002)
			(end -0.4953 -0.2032)
			(stroke
				(width 0.1)
				(type default)
			)
			(layer "F.Fab")
		)
		(fp_line
			(start 0.4953 -0.2032)
			(end 0.4953 1.6002)
			(stroke
				(width 0.1)
				(type default)
			)
			(layer "F.Fab")
		)
		(fp_line
			(start 0.4953 1.6002)
			(end -0.4953 1.6002)
			(stroke
				(width 0.1)
				(type default)
			)
			(layer "F.Fab")
		)
		(pad "1" smd rect
			(at 0 0)
			(size 0.762 0.889)
			(layers "F.Cu" "F.Mask" "F.Paste")
			(net "PVCCIO_CPU1")
		)
		(pad "2" smd rect
			(at 0 1.397)
			(size 0.762 0.889)
			(layers "F.Cu" "F.Mask" "F.Paste")
			(net "GND")
		)
		(zone
			(layer "F.Cu")
			(hatch none 0.5)
			(connect_pads
				(clearance 0)
			)
			(min_thickness 0.25)
			(keepout
				(tracks not_allowed)
				(vias allowed)
				(pads allowed)
				(copperpour not_allowed)
				(footprints allowed)
			)
			(placement
				(enabled no)
				(sheetname "")
			)
			(fill
				(thermal_gap 0.5)
				(thermal_bridge_width 0.5)
				(island_removal_mode 0)
			)
			(polygon
				(pts
					(xy 161.417 -62.9285) (xy 162.179 -62.9285) (xy 162.179 -62.4205) (xy 161.417 -62.4205)
				)
			)
		)
	)
	(footprint ""
		(layer "F.Cu")
		(at 116.369592 -81.366614)
		(property "Reference" "C3D3"
			(at 0 0 0)
			(layer "F.SilkS")
			(hide yes)
			(effects
				(font
					(size 1.27 1.27)
				)
			)
		)
		(property "Value" ""
			(at 0 0 0)
			(layer "F.Fab")
			(effects
				(font
					(size 1.27 1.27)
				)
			)
		)
		(duplicate_pad_numbers_are_jumpers no)
		(fp_poly
			(pts
				(xy -0.4953 -0.2032) (xy 0.4953 -0.2032) (xy 0.4953 1.6002) (xy -0.4953 1.6002)
			)
			(stroke
				(width 0)
				(type default)
			)
			(fill no)
			(layer "F.CrtYd")
		)
		(fp_line
			(start -0.4953 -0.2032)
			(end 0.4953 -0.2032)
			(stroke
				(width 0.1)
				(type default)
			)
			(layer "F.Fab")
		)
		(fp_line
			(start -0.4953 1.6002)
			(end -0.4953 -0.2032)
			(stroke
				(width 0.1)
				(type default)
			)
			(layer "F.Fab")
		)
		(fp_line
			(start 0.4953 -0.2032)
			(end 0.4953 1.6002)
			(stroke
				(width 0.1)
				(type default)
			)
			(layer "F.Fab")
		)
		(fp_line
			(start 0.4953 1.6002)
			(end -0.4953 1.6002)
			(stroke
				(width 0.1)
				(type default)
			)
			(layer "F.Fab")
		)
		(pad "1" smd rect
			(at 0 0)
			(size 0.762 0.889)
			(layers "F.Cu" "F.Mask" "F.Paste")
			(net "P1V8_MCP_CPU1")
		)
		(pad "2" smd rect
			(at 0 1.397)
			(size 0.762 0.889)
			(layers "F.Cu" "F.Mask" "F.Paste")
			(net "GND")
		)
		(zone
			(layer "F.Cu")
			(hatch none 0.5)
			(connect_pads
				(clearance 0)
			)
			(min_thickness 0.25)
			(keepout
				(tracks not_allowed)
				(vias allowed)
				(pads allowed)
				(copperpour not_allowed)
				(footprints allowed)
			)
			(placement
				(enabled no)
				(sheetname "")
			)
			(fill
				(thermal_gap 0.5)
				(thermal_bridge_width 0.5)
				(island_removal_mode 0)
			)
			(polygon
				(pts
					(xy 115.988592 -80.922114) (xy 116.750592 -80.922114) (xy 116.750592 -80.414114) (xy 115.988592 -80.414114)
				)
			)
		)
	)
	(footprint ""
		(layer "F.Cu")
		(at 474.091 -35.7505 180)
		(property "Reference" "R2T42"
			(at 0 0 180)
			(layer "F.SilkS")
			(hide yes)
			(effects
				(font
					(size 1.27 1.27)
				)
			)
		)
		(property "Value" ""
			(at 0 0 180)
			(layer "F.Fab")
			(effects
				(font
					(size 1.27 1.27)
				)
			)
		)
		(duplicate_pad_numbers_are_jumpers no)
		(fp_poly
			(pts
				(xy -0.2794 -0.1016) (xy 0.2794 -0.1016) (xy 0.2794 0.9906) (xy -0.2794 0.9906)
			)
			(stroke
				(width 0)
				(type default)
			)
			(fill no)
			(layer "F.CrtYd")
		)
		(fp_line
			(start 0.2794 0.9906)
			(end 0.2794 -0.1016)
			(stroke
				(width 0.1)
				(type default)
			)
			(layer "F.Fab")
		)
		(fp_line
			(start 0.2794 -0.1016)
			(end -0.2794 -0.1016)
			(stroke
				(width 0.1)
				(type default)
			)
			(layer "F.Fab")
		)
		(fp_line
			(start -0.2794 0.9906)
			(end 0.2794 0.9906)
			(stroke
				(width 0.1)
				(type default)
			)
			(layer "F.Fab")
		)
		(fp_line
			(start -0.2794 -0.1016)
			(end -0.2794 0.9906)
			(stroke
				(width 0.1)
				(type default)
			)
			(layer "F.Fab")
		)
		(pad "1" smd rect
			(at 0 0 180)
			(size 0.508 0.508)
			(layers "F.Cu" "F.Mask" "F.Paste")
			(net "CLK_50M_CKMNG_OCP_R")
		)
		(pad "2" smd rect
			(at 0 0.889 180)
			(size 0.508 0.508)
			(layers "F.Cu" "F.Mask" "F.Paste")
			(net "CLK_50M_CKMNG_OCP")
		)
		(zone
			(layer "F.Cu")
			(hatch none 0.5)
			(connect_pads
				(clearance 0)
			)
			(min_thickness 0.25)
			(keepout
				(tracks not_allowed)
				(vias allowed)
				(pads allowed)
				(copperpour not_allowed)
				(footprints allowed)
			)
			(placement
				(enabled no)
				(sheetname "")
			)
			(fill
				(thermal_gap 0.5)
				(thermal_bridge_width 0.5)
				(island_removal_mode 0)
			)
			(polygon
				(pts
					(xy 474.345 -36.3855) (xy 473.837 -36.3855) (xy 473.837 -36.0045) (xy 474.345 -36.0045)
				)
			)
		)
		(zone
			(layer "F.Cu")
			(hatch none 0.5)
			(connect_pads
				(clearance 0)
			)
			(min_thickness 0.25)
			(keepout
				(tracks allowed)
				(vias not_allowed)
				(pads allowed)
				(copperpour not_allowed)
				(footprints allowed)
			)
			(placement
				(enabled no)
				(sheetname "")
			)
			(fill
				(thermal_gap 0.5)
				(thermal_bridge_width 0.5)
				(island_removal_mode 0)
			)
			(polygon
				(pts
					(xy 474.345 -36.0045) (xy 473.837 -36.0045) (xy 473.837 -36.3855) (xy 474.345 -36.3855)
				)
			)
		)
	)
	(footprint ""
		(layer "F.Cu")
		(at 173.1264 -57.9374 90)
		(property "Reference" "RT42"
			(at 0 0 90)
			(layer "F.SilkS")
			(hide yes)
			(effects
				(font
					(size 1.27 1.27)
				)
			)
		)
		(property "Value" "*"
			(at -0.0254 -2.6289 90)
			(unlocked yes)
			(layer "F.Fab")
			(hide yes)
			(effects
				(font
					(size 1.27 1.016)
					(thickness 0.1524)
				)
			)
		)
		(property "Device Type" "1R3F-GP_RCL_GP-1R3F-GP,64.1R00A"
			(at -0.0254 -4.1529 90)
			(unlocked yes)
			(layer "F.Fab")
			(hide yes)
			(effects
				(font
					(size 1.27 1.016)
					(thickness 0.1524)
				)
			)
		)
		(duplicate_pad_numbers_are_jumpers no)
		(fp_line
			(start 0.2032 0)
			(end 0.4826 0)
			(stroke
				(width 0.2032)
				(type default)
			)
			(layer "F.SilkS")
		)
		(fp_line
			(start -0.4826 0)
			(end -0.2032 0)
			(stroke
				(width 0.2032)
				(type default)
			)
			(layer "F.SilkS")
		)
		(fp_rect
			(start -0.5842 1.3335)
			(end 0.5842 -1.3335)
			(stroke
				(width 0)
				(type default)
			)
			(fill no)
			(layer "F.CrtYd")
		)
		(fp_rect
			(start -0.5842 1.3335)
			(end 0.5842 -1.3335)
			(stroke
				(width 0)
				(type default)
			)
			(fill no)
			(layer "F.Fab")
		)
		(pad "1" smd custom
			(at 0 -0.762 90)
			(size 0.2159 0.2159)
			(layers "F.Cu" "F.Mask" "F.Paste")
			(net "VR_PVCCIO_CPU1_PH1_SW_RC")
			(options
				(clearance outline)
				(anchor circle)
			)
			(primitives
				(gr_poly
					(pts
						(arc
							(start -0.3302 -0.4318)
							(mid -0.402042 -0.402042)
							(end -0.4318 -0.3302)
						)
						(arc
							(start -0.4318 0.3302)
							(mid -0.402042 0.402042)
							(end -0.3302 0.4318)
						)
						(arc
							(start 0.3302 0.4318)
							(mid 0.402042 0.402042)
							(end 0.4318 0.3302)
						)
						(arc
							(start 0.4318 -0.3302)
							(mid 0.402042 -0.402042)
							(end 0.3302 -0.4318)
						)
					)
					(width 0)
					(fill yes)
				)
			)
		)
		(pad "2" smd custom
			(at 0 0.762 90)
			(size 0.2159 0.2159)
			(layers "F.Cu" "F.Mask" "F.Paste")
			(net "GND")
			(options
				(clearance outline)
				(anchor circle)
			)
			(primitives
				(gr_poly
					(pts
						(arc
							(start -0.3302 -0.4318)
							(mid -0.402042 -0.402042)
							(end -0.4318 -0.3302)
						)
						(arc
							(start -0.4318 0.3302)
							(mid -0.402042 0.402042)
							(end -0.3302 0.4318)
						)
						(arc
							(start 0.3302 0.4318)
							(mid 0.402042 0.402042)
							(end 0.4318 0.3302)
						)
						(arc
							(start 0.4318 -0.3302)
							(mid 0.402042 -0.402042)
							(end 0.3302 -0.4318)
						)
					)
					(width 0)
					(fill yes)
				)
			)
		)
	)
	(footprint ""
		(layer "F.Cu")
		(at 184.428384 -21.34362 -90)
		(property "Reference" "R12W4"
			(at 1.01473 0.656336 180)
			(unlocked yes)
			(layer "F.SilkS")
			(effects
				(font
					(size 0.4064 0.254)
					(thickness 0.1524)
				)
			)
		)
		(property "Value" ""
			(at 0 0 270)
			(layer "F.Fab")
			(effects
				(font
					(size 1.27 1.27)
				)
			)
		)
		(duplicate_pad_numbers_are_jumpers no)
		(fp_poly
			(pts
				(xy -0.4953 -0.2032) (xy 0.4953 -0.2032) (xy 0.4953 1.6002) (xy -0.4953 1.6002)
			)
			(stroke
				(width 0)
				(type default)
			)
			(fill no)
			(layer "F.CrtYd")
		)
		(fp_line
			(start -0.4953 1.6002)
			(end -0.4953 -0.2032)
			(stroke
				(width 0.1)
				(type default)
			)
			(layer "F.Fab")
		)
		(fp_line
			(start 0.4953 1.6002)
			(end -0.4953 1.6002)
			(stroke
				(width 0.1)
				(type default)
			)
			(layer "F.Fab")
		)
		(fp_line
			(start -0.4953 -0.2032)
			(end 0.4953 -0.2032)
			(stroke
				(width 0.1)
				(type default)
			)
			(layer "F.Fab")
		)
		(fp_line
			(start 0.4953 -0.2032)
			(end 0.4953 1.6002)
			(stroke
				(width 0.1)
				(type default)
			)
			(layer "F.Fab")
		)
		(pad "1" smd rect
			(at 0 0 270)
			(size 0.762 0.889)
			(layers "F.Cu" "F.Mask" "F.Paste")
			(net "P12V_NVDIMM_ABC")
		)
		(pad "2" smd rect
			(at 0 1.397 270)
			(size 0.762 0.889)
			(layers "F.Cu" "F.Mask" "F.Paste")
			(net "PWRGD_PVDDQ_ABC_N")
		)
		(zone
			(layer "F.Cu")
			(hatch none 0.5)
			(connect_pads
				(clearance 0)
			)
			(min_thickness 0.25)
			(keepout
				(tracks not_allowed)
				(vias allowed)
				(pads allowed)
				(copperpour not_allowed)
				(footprints allowed)
			)
			(placement
				(enabled no)
				(sheetname "")
			)
			(fill
				(thermal_gap 0.5)
				(thermal_bridge_width 0.5)
				(island_removal_mode 0)
			)
			(polygon
				(pts
					(xy 183.475884 -21.72462) (xy 183.475884 -20.96262) (xy 183.983884 -20.96262) (xy 183.983884 -21.72462)
				)
			)
		)
		(zone
			(layer "F.Cu")
			(hatch none 0.5)
			(connect_pads
				(clearance 0)
			)
			(min_thickness 0.25)
			(keepout
				(tracks allowed)
				(vias not_allowed)
				(pads allowed)
				(copperpour not_allowed)
				(footprints allowed)
			)
			(placement
				(enabled no)
				(sheetname "")
			)
			(fill
				(thermal_gap 0.5)
				(thermal_bridge_width 0.5)
				(island_removal_mode 0)
			)
			(polygon
				(pts
					(xy 183.475884 -20.96262) (xy 183.983884 -20.96262) (xy 183.983884 -21.72462) (xy 183.475884 -21.72462)
				)
			)
		)
	)
	(footprint ""
		(layer "F.Cu")
		(at 347.08719 -2.954782 -90)
		(property "Reference" "C7G29"
			(at 0 0 270)
			(layer "F.SilkS")
			(hide yes)
			(effects
				(font
					(size 1.27 1.27)
				)
			)
		)
		(property "Value" ""
			(at 0 0 270)
			(layer "F.Fab")
			(effects
				(font
					(size 1.27 1.27)
				)
			)
		)
		(duplicate_pad_numbers_are_jumpers no)
		(fp_rect
			(start -0.3048 0.9906)
			(end 0.3048 -0.1016)
			(stroke
				(width 0)
				(type default)
			)
			(fill no)
			(layer "F.CrtYd")
		)
		(fp_line
			(start -0.3048 0.9906)
			(end 0.3048 0.9906)
			(stroke
				(width 0.1)
				(type default)
			)
			(layer "F.Fab")
		)
		(fp_line
			(start 0.3048 0.9906)
			(end 0.3048 -0.1016)
			(stroke
				(width 0.1)
				(type default)
			)
			(layer "F.Fab")
		)
		(fp_line
			(start -0.3048 -0.1016)
			(end -0.3048 0.9906)
			(stroke
				(width 0.1)
				(type default)
			)
			(layer "F.Fab")
		)
		(fp_line
			(start 0.3048 -0.1016)
			(end -0.3048 -0.1016)
			(stroke
				(width 0.1)
				(type default)
			)
			(layer "F.Fab")
		)
		(pad "1" smd rect
			(at 0 0 270)
			(size 0.508 0.508)
			(layers "F.Cu" "F.Mask" "F.Paste")
			(net "VR_FET_SW_P12V_STBY_PVDDQ_ABC")
		)
		(pad "2" smd rect
			(at 0 0.889 270)
			(size 0.508 0.508)
			(layers "F.Cu" "F.Mask" "F.Paste")
			(net "GND")
		)
		(zone
			(layer "F.Cu")
			(hatch none 0.5)
			(connect_pads
				(clearance 0)
			)
			(min_thickness 0.25)
			(keepout
				(tracks allowed)
				(vias not_allowed)
				(pads allowed)
				(copperpour not_allowed)
				(footprints allowed)
			)
			(placement
				(enabled no)
				(sheetname "")
			)
			(fill
				(thermal_gap 0.5)
				(thermal_bridge_width 0.5)
				(island_removal_mode 0)
			)
			(polygon
				(pts
					(xy 346.45219 -3.208782) (xy 346.45219 -2.700782) (xy 346.83319 -2.700782) (xy 346.83319 -3.208782)
				)
			)
		)
		(zone
			(layer "F.Cu")
			(hatch none 0.5)
			(connect_pads
				(clearance 0)
			)
			(min_thickness 0.25)
			(keepout
				(tracks not_allowed)
				(vias allowed)
				(pads allowed)
				(copperpour not_allowed)
				(footprints allowed)
			)
			(placement
				(enabled no)
				(sheetname "")
			)
			(fill
				(thermal_gap 0.5)
				(thermal_bridge_width 0.5)
				(island_removal_mode 0)
			)
			(polygon
				(pts
					(xy 346.45219 -3.208782) (xy 346.45219 -2.700782) (xy 346.83319 -2.700782) (xy 346.83319 -3.208782)
				)
			)
		)
	)
	(footprint ""
		(layer "F.Cu")
		(at 417.9951 -88.5825)
		(property "Reference" "R2P4"
			(at 0 0 0)
			(layer "F.SilkS")
			(hide yes)
			(effects
				(font
					(size 1.27 1.27)
				)
			)
		)
		(property "Value" ""
			(at 0 0 0)
			(layer "F.Fab")
			(effects
				(font
					(size 1.27 1.27)
				)
			)
		)
		(duplicate_pad_numbers_are_jumpers no)
		(fp_poly
			(pts
				(xy -0.2794 -0.1016) (xy 0.2794 -0.1016) (xy 0.2794 0.9906) (xy -0.2794 0.9906)
			)
			(stroke
				(width 0)
				(type default)
			)
			(fill no)
			(layer "F.CrtYd")
		)
		(fp_line
			(start -0.2794 -0.1016)
			(end -0.2794 0.9906)
			(stroke
				(width 0.1)
				(type default)
			)
			(layer "F.Fab")
		)
		(fp_line
			(start -0.2794 0.9906)
			(end 0.2794 0.9906)
			(stroke
				(width 0.1)
				(type default)
			)
			(layer "F.Fab")
		)
		(fp_line
			(start 0.2794 -0.1016)
			(end -0.2794 -0.1016)
			(stroke
				(width 0.1)
				(type default)
			)
			(layer "F.Fab")
		)
		(fp_line
			(start 0.2794 0.9906)
			(end 0.2794 -0.1016)
			(stroke
				(width 0.1)
				(type default)
			)
			(layer "F.Fab")
		)
		(pad "1" smd rect
			(at 0 0)
			(size 0.508 0.508)
			(layers "F.Cu" "F.Mask" "F.Paste")
			(net "IRQ_FORCE_NM_THROTTLE_R_N")
		)
		(pad "2" smd rect
			(at 0 0.889)
			(size 0.508 0.508)
			(layers "F.Cu" "F.Mask" "F.Paste")
			(net "IRQ_FORCE_NM_THROTTLE_N")
		)
		(zone
			(layer "F.Cu")
			(hatch none 0.5)
			(connect_pads
				(clearance 0)
			)
			(min_thickness 0.25)
			(keepout
				(tracks allowed)
				(vias not_allowed)
				(pads allowed)
				(copperpour not_allowed)
				(footprints allowed)
			)
			(placement
				(enabled no)
				(sheetname "")
			)
			(fill
				(thermal_gap 0.5)
				(thermal_bridge_width 0.5)
				(island_removal_mode 0)
			)
			(polygon
				(pts
					(xy 417.7411 -88.3285) (xy 418.2491 -88.3285) (xy 418.2491 -87.9475) (xy 417.7411 -87.9475)
				)
			)
		)
		(zone
			(layer "F.Cu")
			(hatch none 0.5)
			(connect_pads
				(clearance 0)
			)
			(min_thickness 0.25)
			(keepout
				(tracks not_allowed)
				(vias allowed)
				(pads allowed)
				(copperpour not_allowed)
				(footprints allowed)
			)
			(placement
				(enabled no)
				(sheetname "")
			)
			(fill
				(thermal_gap 0.5)
				(thermal_bridge_width 0.5)
				(island_removal_mode 0)
			)
			(polygon
				(pts
					(xy 417.7411 -87.9475) (xy 418.2491 -87.9475) (xy 418.2491 -88.3285) (xy 417.7411 -88.3285)
				)
			)
		)
	)
	(footprint ""
		(layer "F.Cu")
		(at 110.7694 -83.8962)
		(property "Reference" "R3D2"
			(at 0 0 0)
			(layer "F.SilkS")
			(hide yes)
			(effects
				(font
					(size 1.27 1.27)
				)
			)
		)
		(property "Value" ""
			(at 0 0 0)
			(layer "F.Fab")
			(effects
				(font
					(size 1.27 1.27)
				)
			)
		)
		(duplicate_pad_numbers_are_jumpers no)
		(fp_poly
			(pts
				(xy -0.2794 -0.1016) (xy 0.2794 -0.1016) (xy 0.2794 0.9906) (xy -0.2794 0.9906)
			)
			(stroke
				(width 0)
				(type default)
			)
			(fill no)
			(layer "F.CrtYd")
		)
		(fp_line
			(start -0.2794 -0.1016)
			(end -0.2794 0.9906)
			(stroke
				(width 0.1)
				(type default)
			)
			(layer "F.Fab")
		)
		(fp_line
			(start -0.2794 0.9906)
			(end 0.2794 0.9906)
			(stroke
				(width 0.1)
				(type default)
			)
			(layer "F.Fab")
		)
		(fp_line
			(start 0.2794 -0.1016)
			(end -0.2794 -0.1016)
			(stroke
				(width 0.1)
				(type default)
			)
			(layer "F.Fab")
		)
		(fp_line
			(start 0.2794 0.9906)
			(end 0.2794 -0.1016)
			(stroke
				(width 0.1)
				(type default)
			)
			(layer "F.Fab")
		)
		(pad "1" smd rect
			(at 0 0)
			(size 0.508 0.508)
			(layers "F.Cu" "F.Mask" "F.Paste")
			(net "A_CPU1_KLM_RCOMP1")
		)
		(pad "2" smd rect
			(at 0 0.889)
			(size 0.508 0.508)
			(layers "F.Cu" "F.Mask" "F.Paste")
			(net "GND")
		)
		(zone
			(layer "F.Cu")
			(hatch none 0.5)
			(connect_pads
				(clearance 0)
			)
			(min_thickness 0.25)
			(keepout
				(tracks allowed)
				(vias not_allowed)
				(pads allowed)
				(copperpour not_allowed)
				(footprints allowed)
			)
			(placement
				(enabled no)
				(sheetname "")
			)
			(fill
				(thermal_gap 0.5)
				(thermal_bridge_width 0.5)
				(island_removal_mode 0)
			)
			(polygon
				(pts
					(xy 110.5154 -83.6422) (xy 111.0234 -83.6422) (xy 111.0234 -83.2612) (xy 110.5154 -83.2612)
				)
			)
		)
		(zone
			(layer "F.Cu")
			(hatch none 0.5)
			(connect_pads
				(clearance 0)
			)
			(min_thickness 0.25)
			(keepout
				(tracks not_allowed)
				(vias allowed)
				(pads allowed)
				(copperpour not_allowed)
				(footprints allowed)
			)
			(placement
				(enabled no)
				(sheetname "")
			)
			(fill
				(thermal_gap 0.5)
				(thermal_bridge_width 0.5)
				(island_removal_mode 0)
			)
			(polygon
				(pts
					(xy 110.5154 -83.2612) (xy 111.0234 -83.2612) (xy 111.0234 -83.6422) (xy 110.5154 -83.6422)
				)
			)
		)
	)
	(footprint ""
		(layer "F.Cu")
		(at 401.701 -34.426652 90)
		(property "Reference" "R8C15"
			(at 0 0 90)
			(layer "F.SilkS")
			(hide yes)
			(effects
				(font
					(size 1.27 1.27)
				)
			)
		)
		(property "Value" ""
			(at 0 0 90)
			(layer "F.Fab")
			(effects
				(font
					(size 1.27 1.27)
				)
			)
		)
		(duplicate_pad_numbers_are_jumpers no)
		(fp_poly
			(pts
				(xy -0.2794 -0.1016) (xy 0.2794 -0.1016) (xy 0.2794 0.9906) (xy -0.2794 0.9906)
			)
			(stroke
				(width 0)
				(type default)
			)
			(fill no)
			(layer "F.CrtYd")
		)
		(fp_line
			(start 0.2794 -0.1016)
			(end -0.2794 -0.1016)
			(stroke
				(width 0.1)
				(type default)
			)
			(layer "F.Fab")
		)
		(fp_line
			(start -0.2794 -0.1016)
			(end -0.2794 0.9906)
			(stroke
				(width 0.1)
				(type default)
			)
			(layer "F.Fab")
		)
		(fp_line
			(start 0.2794 0.9906)
			(end 0.2794 -0.1016)
			(stroke
				(width 0.1)
				(type default)
			)
			(layer "F.Fab")
		)
		(fp_line
			(start -0.2794 0.9906)
			(end 0.2794 0.9906)
			(stroke
				(width 0.1)
				(type default)
			)
			(layer "F.Fab")
		)
		(pad "1" smd rect
			(at 0 0 90)
			(size 0.508 0.508)
			(layers "F.Cu" "F.Mask" "F.Paste")
			(net "P3V3_STBY")
		)
		(pad "2" smd rect
			(at 0 0.889 90)
			(size 0.508 0.508)
			(layers "F.Cu" "F.Mask" "F.Paste")
			(net "SMB_HOST_STBY_LVC3_SCL_R")
		)
		(zone
			(layer "F.Cu")
			(hatch none 0.5)
			(connect_pads
				(clearance 0)
			)
			(min_thickness 0.25)
			(keepout
				(tracks allowed)
				(vias not_allowed)
				(pads allowed)
				(copperpour not_allowed)
				(footprints allowed)
			)
			(placement
				(enabled no)
				(sheetname "")
			)
			(fill
				(thermal_gap 0.5)
				(thermal_bridge_width 0.5)
				(island_removal_mode 0)
			)
			(polygon
				(pts
					(xy 401.955 -34.172652) (xy 401.955 -34.680652) (xy 402.336 -34.680652) (xy 402.336 -34.172652)
				)
			)
		)
		(zone
			(layer "F.Cu")
			(hatch none 0.5)
			(connect_pads
				(clearance 0)
			)
			(min_thickness 0.25)
			(keepout
				(tracks not_allowed)
				(vias allowed)
				(pads allowed)
				(copperpour not_allowed)
				(footprints allowed)
			)
			(placement
				(enabled no)
				(sheetname "")
			)
			(fill
				(thermal_gap 0.5)
				(thermal_bridge_width 0.5)
				(island_removal_mode 0)
			)
			(polygon
				(pts
					(xy 402.336 -34.172652) (xy 402.336 -34.680652) (xy 401.955 -34.680652) (xy 401.955 -34.172652)
				)
			)
		)
	)
	(footprint ""
		(layer "F.Cu")
		(at 171.242736 -54.10073 180)
		(property "Reference" "L4E2"
			(at 3.378708 -4.251706 180)
			(unlocked yes)
			(layer "F.SilkS")
			(effects
				(font
					(size 0.4064 0.254)
					(thickness 0.1524)
				)
			)
		)
		(property "Value" ""
			(at 0 0 180)
			(layer "F.Fab")
			(effects
				(font
					(size 1.27 1.27)
				)
			)
		)
		(duplicate_pad_numbers_are_jumpers no)
		(fp_line
			(start 8.3693 3.199892)
			(end -1.1303 3.199892)
			(stroke
				(width 0.1524)
				(type default)
			)
			(layer "F.SilkS")
		)
		(fp_line
			(start 8.3693 1.6637)
			(end 8.3693 3.199892)
			(stroke
				(width 0.1524)
				(type default)
			)
			(layer "F.SilkS")
		)
		(fp_line
			(start 8.3693 -3.199892)
			(end 8.3693 -1.6637)
			(stroke
				(width 0.1524)
				(type default)
			)
			(layer "F.SilkS")
		)
		(fp_line
			(start -1.1303 3.199892)
			(end -1.1303 1.6637)
			(stroke
				(width 0.1524)
				(type default)
			)
			(layer "F.SilkS")
		)
		(fp_line
			(start -1.1303 -1.6637)
			(end -1.1303 -3.199892)
			(stroke
				(width 0.1524)
				(type default)
			)
			(layer "F.SilkS")
		)
		(fp_line
			(start -1.1303 -3.199892)
			(end 8.3693 -3.199892)
			(stroke
				(width 0.1524)
				(type default)
			)
			(layer "F.SilkS")
		)
		(fp_rect
			(start -1.1303 3.199892)
			(end 8.3693 -3.199892)
			(stroke
				(width 0)
				(type default)
			)
			(fill no)
			(layer "F.CrtYd")
		)
		(fp_line
			(start 8.3693 3.199892)
			(end -1.1303 3.199892)
			(stroke
				(width 0.1)
				(type default)
			)
			(layer "F.Fab")
		)
		(fp_line
			(start 8.3693 -3.199892)
			(end 8.3693 3.199892)
			(stroke
				(width 0.1)
				(type default)
			)
			(layer "F.Fab")
		)
		(fp_line
			(start -1.1303 3.199892)
			(end -1.1303 -3.199892)
			(stroke
				(width 0.1)
				(type default)
			)
			(layer "F.Fab")
		)
		(fp_line
			(start -1.1303 -3.199892)
			(end 8.3693 -3.199892)
			(stroke
				(width 0.1)
				(type default)
			)
			(layer "F.Fab")
		)
		(pad "1" smd rect
			(at 0 0 180)
			(size 3.683 2.667)
			(layers "F.Cu" "F.Mask" "F.Paste")
			(net "VR_PVCCIO_CPU1_PH1_SW")
		)
		(pad "2" smd rect
			(at 7.239 0 180)
			(size 3.683 2.667)
			(layers "F.Cu" "F.Mask" "F.Paste")
			(net "PVCCIO_CPU1")
		)
	)
	(footprint ""
		(layer "F.Cu")
		(at 87.158068 -149.8092 -90)
		(property "Reference" "C2A3"
			(at 1.848866 0.752348 270)
			(unlocked yes)
			(layer "F.SilkS")
			(effects
				(font
					(size 1.27 0.9652)
					(thickness 0.1524)
				)
			)
		)
		(property "Value" ""
			(at 0 0 270)
			(layer "F.Fab")
			(effects
				(font
					(size 1.27 1.27)
				)
			)
		)
		(duplicate_pad_numbers_are_jumpers no)
		(fp_rect
			(start -0.500126 1.598422)
			(end 0.500126 -0.201422)
			(stroke
				(width 0)
				(type default)
			)
			(fill no)
			(layer "F.CrtYd")
		)
		(fp_line
			(start -0.500126 1.598422)
			(end -0.500126 -0.201422)
			(stroke
				(width 0.1)
				(type default)
			)
			(layer "F.Fab")
		)
		(fp_line
			(start 0.500126 1.598422)
			(end -0.500126 1.598422)
			(stroke
				(width 0.1)
				(type default)
			)
			(layer "F.Fab")
		)
		(fp_line
			(start -0.500126 -0.201422)
			(end 0.500126 -0.201422)
			(stroke
				(width 0.1)
				(type default)
			)
			(layer "F.Fab")
		)
		(fp_line
			(start 0.500126 -0.201422)
			(end 0.500126 1.598422)
			(stroke
				(width 0.1)
				(type default)
			)
			(layer "F.Fab")
		)
		(pad "1" smd rect
			(at 0 0 180)
			(size 0.889 0.9906)
			(layers "F.Cu" "F.Mask" "F.Paste")
			(net "PVDDQ_KLM")
		)
		(pad "2" smd rect
			(at 0 1.397 180)
			(size 0.889 0.9906)
			(layers "F.Cu" "F.Mask" "F.Paste")
			(net "GND")
		)
		(zone
			(layer "F.Cu")
			(hatch none 0.5)
			(connect_pads
				(clearance 0)
			)
			(min_thickness 0.25)
			(keepout
				(tracks not_allowed)
				(vias allowed)
				(pads allowed)
				(copperpour not_allowed)
				(footprints allowed)
			)
			(placement
				(enabled no)
				(sheetname "")
			)
			(fill
				(thermal_gap 0.5)
				(thermal_bridge_width 0.5)
				(island_removal_mode 0)
			)
			(polygon
				(pts
					(xy 86.205568 -150.3045) (xy 86.205568 -149.3139) (xy 86.713568 -149.3139) (xy 86.713568 -150.3045)
				)
			)
		)
		(zone
			(layer "F.Cu")
			(hatch none 0.5)
			(connect_pads
				(clearance 0)
			)
			(min_thickness 0.25)
			(keepout
				(tracks allowed)
				(vias not_allowed)
				(pads allowed)
				(copperpour not_allowed)
				(footprints allowed)
			)
			(placement
				(enabled no)
				(sheetname "")
			)
			(fill
				(thermal_gap 0.5)
				(thermal_bridge_width 0.5)
				(island_removal_mode 0)
			)
			(polygon
				(pts
					(xy 86.205568 -150.3045) (xy 86.205568 -149.3139) (xy 86.713568 -149.3139) (xy 86.713568 -150.3045)
				)
			)
		)
	)
	(footprint ""
		(layer "F.Cu")
		(at 22.225 -77.724 90)
		(property "Reference" "R1D30"
			(at 0 0 90)
			(layer "F.SilkS")
			(hide yes)
			(effects
				(font
					(size 1.27 1.27)
				)
			)
		)
		(property "Value" ""
			(at 0 0 90)
			(layer "F.Fab")
			(effects
				(font
					(size 1.27 1.27)
				)
			)
		)
		(duplicate_pad_numbers_are_jumpers no)
		(fp_poly
			(pts
				(xy -0.2794 -0.1016) (xy 0.2794 -0.1016) (xy 0.2794 0.9906) (xy -0.2794 0.9906)
			)
			(stroke
				(width 0)
				(type default)
			)
			(fill no)
			(layer "F.CrtYd")
		)
		(fp_line
			(start 0.2794 -0.1016)
			(end -0.2794 -0.1016)
			(stroke
				(width 0.1)
				(type default)
			)
			(layer "F.Fab")
		)
		(fp_line
			(start -0.2794 -0.1016)
			(end -0.2794 0.9906)
			(stroke
				(width 0.1)
				(type default)
			)
			(layer "F.Fab")
		)
		(fp_line
			(start 0.2794 0.9906)
			(end 0.2794 -0.1016)
			(stroke
				(width 0.1)
				(type default)
			)
			(layer "F.Fab")
		)
		(fp_line
			(start -0.2794 0.9906)
			(end 0.2794 0.9906)
			(stroke
				(width 0.1)
				(type default)
			)
			(layer "F.Fab")
		)
		(pad "1" smd rect
			(at 0 0 90)
			(size 0.508 0.508)
			(layers "F.Cu" "F.Mask" "F.Paste")
			(net "IRQ_HSC_FAULT_R_N")
		)
		(pad "2" smd rect
			(at 0 0.889 90)
			(size 0.508 0.508)
			(layers "F.Cu" "F.Mask" "F.Paste")
			(net "IRQ_HSC_FAULT_N")
		)
		(zone
			(layer "F.Cu")
			(hatch none 0.5)
			(connect_pads
				(clearance 0)
			)
			(min_thickness 0.25)
			(keepout
				(tracks allowed)
				(vias not_allowed)
				(pads allowed)
				(copperpour not_allowed)
				(footprints allowed)
			)
			(placement
				(enabled no)
				(sheetname "")
			)
			(fill
				(thermal_gap 0.5)
				(thermal_bridge_width 0.5)
				(island_removal_mode 0)
			)
			(polygon
				(pts
					(xy 22.479 -77.47) (xy 22.479 -77.978) (xy 22.86 -77.978) (xy 22.86 -77.47)
				)
			)
		)
		(zone
			(layer "F.Cu")
			(hatch none 0.5)
			(connect_pads
				(clearance 0)
			)
			(min_thickness 0.25)
			(keepout
				(tracks not_allowed)
				(vias allowed)
				(pads allowed)
				(copperpour not_allowed)
				(footprints allowed)
			)
			(placement
				(enabled no)
				(sheetname "")
			)
			(fill
				(thermal_gap 0.5)
				(thermal_bridge_width 0.5)
				(island_removal_mode 0)
			)
			(polygon
				(pts
					(xy 22.86 -77.47) (xy 22.86 -77.978) (xy 22.479 -77.978) (xy 22.479 -77.47)
				)
			)
		)
	)
	(footprint ""
		(layer "F.Cu")
		(at 189.2808 -68.2498 180)
		(property "Reference" "CF3"
			(at 0 0 180)
			(layer "F.SilkS")
			(hide yes)
			(effects
				(font
					(size 1.27 1.27)
				)
			)
		)
		(property "Value" "*"
			(at 1.1811 -2.8194 180)
			(unlocked yes)
			(layer "F.Fab")
			(hide yes)
			(effects
				(font
					(size 1.27 1.016)
					(thickness 0.1524)
				)
			)
		)
		(property "Device Type" "SC22P50V2JN-4GP_SMD-BCG-SC22P5A"
			(at 1.1811 -4.3434 180)
			(unlocked yes)
			(layer "F.Fab")
			(hide yes)
			(effects
				(font
					(size 1.27 1.016)
					(thickness 0.1524)
				)
			)
		)
		(duplicate_pad_numbers_are_jumpers no)
		(fp_rect
			(start -0.4318 0.9525)
			(end 0.4318 -0.9525)
			(stroke
				(width 0)
				(type default)
			)
			(fill no)
			(layer "F.CrtYd")
		)
		(fp_rect
			(start -0.4318 0.9525)
			(end 0.4318 -0.9525)
			(stroke
				(width 0)
				(type default)
			)
			(fill no)
			(layer "F.Fab")
		)
		(pad "1" smd custom
			(at 0 -0.4445 180)
			(size 0.1524 0.1524)
			(layers "F.Cu" "F.Mask" "F.Paste")
			(net "VR_PVCCIN_CPU0_AIREF3")
			(options
				(clearance outline)
				(anchor circle)
			)
			(primitives
				(gr_poly
					(pts
						(arc
							(start 0.3048 -0.2032)
							(mid 0.275042 -0.275042)
							(end 0.2032 -0.3048)
						)
						(arc
							(start -0.2032 -0.3048)
							(mid -0.275042 -0.275042)
							(end -0.3048 -0.2032)
						)
						(arc
							(start -0.3048 0.2032)
							(mid -0.275042 0.275042)
							(end -0.2032 0.3048)
						)
						(arc
							(start 0.2032 0.3048)
							(mid 0.275042 0.275042)
							(end 0.3048 0.2032)
						)
					)
					(width 0)
					(fill yes)
				)
			)
		)
		(pad "2" smd custom
			(at 0 0.4445 180)
			(size 0.1524 0.1524)
			(layers "F.Cu" "F.Mask" "F.Paste")
			(net "ISENSE_PVCCIN_CPU0_PH3_IMON")
			(options
				(clearance outline)
				(anchor circle)
			)
			(primitives
				(gr_poly
					(pts
						(arc
							(start 0.3048 -0.2032)
							(mid 0.275042 -0.275042)
							(end 0.2032 -0.3048)
						)
						(arc
							(start -0.2032 -0.3048)
							(mid -0.275042 -0.275042)
							(end -0.3048 -0.2032)
						)
						(arc
							(start -0.3048 0.2032)
							(mid -0.275042 0.275042)
							(end -0.2032 0.3048)
						)
						(arc
							(start 0.2032 0.3048)
							(mid 0.275042 0.275042)
							(end 0.3048 0.2032)
						)
					)
					(width 0)
					(fill yes)
				)
			)
		)
	)
	(footprint ""
		(layer "F.Cu")
		(at 156.539692 -164.904674 -90)
		(property "Reference" "T1D13"
			(at 0 0 270)
			(layer "F.SilkS")
			(hide yes)
			(effects
				(font
					(size 1.27 1.27)
				)
			)
		)
		(property "Value" "*"
			(at -3.4036 -4.46405 270)
			(unlocked yes)
			(layer "F.Fab")
			(hide yes)
			(effects
				(font
					(size 0.889 0.889)
					(thickness 0.1524)
				)
			)
		)
		(property "Device Type" "TEST-PAD-12P-1-GP-U_DISCRET-GBA"
			(at -3.4036 -5.98805 270)
			(unlocked yes)
			(layer "F.Fab")
			(hide yes)
			(effects
				(font
					(size 0.889 0.889)
					(thickness 0.1524)
				)
			)
		)
		(duplicate_pad_numbers_are_jumpers no)
		(fp_line
			(start -2.3876 3.4798)
			(end -2.3876 -4.826)
			(stroke
				(width 0.1524)
				(type default)
			)
			(layer "F.SilkS")
		)
		(fp_line
			(start 2.3622 3.4798)
			(end -2.3876 3.4798)
			(stroke
				(width 0.1524)
				(type default)
			)
			(layer "F.SilkS")
		)
		(fp_line
			(start -2.3876 -4.826)
			(end 2.3622 -4.826)
			(stroke
				(width 0.1524)
				(type default)
			)
			(layer "F.SilkS")
		)
		(fp_line
			(start 2.3622 -4.826)
			(end 2.3622 3.4798)
			(stroke
				(width 0.1524)
				(type default)
			)
			(layer "F.SilkS")
		)
		(fp_rect
			(start -2.6416 3.7338)
			(end 2.6162 -5.08)
			(stroke
				(width 0)
				(type default)
			)
			(fill no)
			(layer "F.CrtYd")
		)
		(fp_rect
			(start -2.6416 3.7338)
			(end 2.6162 -5.08)
			(stroke
				(width 0)
				(type default)
			)
			(fill no)
			(layer "F.Fab")
		)
		(pad "1" smd circle
			(at 0.496824 -1.301496 270)
			(size 0.6604 0.6604)
			(layers "F.Cu" "F.Mask" "F.Paste")
			(net "L1_85OHM_10INCH_DP")
		)
		(pad "2" smd circle
			(at -0.503936 -1.301496 270)
			(size 0.6604 0.6604)
			(layers "F.Cu" "F.Mask" "F.Paste")
			(net "L1_85OHM_10INCH_DN")
		)
		(pad "3" smd custom
			(at -0.00889 0.370078 270)
			(size 0.74295 0.74295)
			(layers "F.Cu" "F.Mask" "F.Paste")
			(net "GND")
			(options
				(clearance outline)
				(anchor circle)
			)
			(primitives
				(gr_poly
					(pts
						(xy -2.1209 1.4859) (xy 2.1209 1.4859) (xy 2.1209 -1.4859) (xy 1.08585 -1.4859) (xy 1.08585 -0.4699)
						(xy -1.08585 -0.4699) (xy -1.08585 -1.4859) (xy -2.1209 -1.4859)
					)
					(width 0)
					(fill yes)
				)
			)
		)
		(pad "4" thru_hole circle
			(at 1.266444 -3.851656 270)
			(size 1.4478 1.4478)
			(drill 1.0414)
			(layers "*.Cu" "*.Mask")
			(remove_unused_layers no)
			(net "GND")
			(clearance 0.1524)
			(thermal_gap 0.1524)
		)
		(pad "5" thru_hole circle
			(at -1.273556 -3.851656 270)
			(size 1.4478 1.4478)
			(drill 1.0414)
			(layers "*.Cu" "*.Mask")
			(remove_unused_layers no)
			(net "GND")
			(clearance 0.1524)
			(thermal_gap 0.1524)
		)
		(pad "6" thru_hole circle
			(at 1.266444 2.498344 270)
			(size 1.4478 1.4478)
			(drill 1.0414)
			(layers "*.Cu" "*.Mask")
			(remove_unused_layers no)
			(net "GND")
			(clearance 0.1524)
			(thermal_gap 0.1524)
		)
		(pad "7" thru_hole circle
			(at -1.273556 2.498344 270)
			(size 1.4478 1.4478)
			(drill 1.0414)
			(layers "*.Cu" "*.Mask")
			(remove_unused_layers no)
			(net "GND")
			(clearance 0.1524)
			(thermal_gap 0.1524)
		)
		(pad "8" thru_hole circle
			(at 1.27 -0.4572 270)
			(size 0.7112 0.7112)
			(drill 0.4064)
			(layers "*.Cu" "*.Mask")
			(remove_unused_layers no)
			(net "GND")
			(clearance 0.1016)
			(thermal_gap 0.1016)
		)
		(pad "9" thru_hole circle
			(at 1.27 0.762 270)
			(size 0.7112 0.7112)
			(drill 0.4064)
			(layers "*.Cu" "*.Mask")
			(remove_unused_layers no)
			(net "GND")
			(clearance 0.1016)
			(thermal_gap 0.1016)
		)
		(pad "10" thru_hole circle
			(at -0.0254 0.762 270)
			(size 0.7112 0.7112)
			(drill 0.4064)
			(layers "*.Cu" "*.Mask")
			(remove_unused_layers no)
			(net "GND")
			(clearance 0.1016)
			(thermal_gap 0.1016)
		)
		(pad "11" thru_hole circle
			(at -1.27 0.762 270)
			(size 0.7112 0.7112)
			(drill 0.4064)
			(layers "*.Cu" "*.Mask")
			(remove_unused_layers no)
			(net "GND")
			(clearance 0.1016)
			(thermal_gap 0.1016)
		)
		(pad "12" thru_hole circle
			(at -1.27 -0.4572 270)
			(size 0.7112 0.7112)
			(drill 0.4064)
			(layers "*.Cu" "*.Mask")
			(remove_unused_layers no)
			(net "GND")
			(clearance 0.1016)
			(thermal_gap 0.1016)
		)
	)
	(footprint ""
		(layer "F.Cu")
		(at 435.727094 -150.043642)
		(property "Reference" "R25W170"
			(at -0.8382 -0.677926 0)
			(unlocked yes)
			(layer "F.SilkS")
			(effects
				(font
					(size 0.4064 0.254)
					(thickness 0.1524)
				)
				(justify left)
			)
		)
		(property "Value" ""
			(at 0 0 0)
			(layer "F.Fab")
			(effects
				(font
					(size 1.27 1.27)
				)
			)
		)
		(duplicate_pad_numbers_are_jumpers no)
		(fp_poly
			(pts
				(xy -0.2794 -0.1016) (xy 0.2794 -0.1016) (xy 0.2794 0.9906) (xy -0.2794 0.9906)
			)
			(stroke
				(width 0)
				(type default)
			)
			(fill no)
			(layer "F.CrtYd")
		)
		(fp_line
			(start -0.2794 -0.1016)
			(end -0.2794 0.9906)
			(stroke
				(width 0.1)
				(type default)
			)
			(layer "F.Fab")
		)
		(fp_line
			(start -0.2794 0.9906)
			(end 0.2794 0.9906)
			(stroke
				(width 0.1)
				(type default)
			)
			(layer "F.Fab")
		)
		(fp_line
			(start 0.2794 -0.1016)
			(end -0.2794 -0.1016)
			(stroke
				(width 0.1)
				(type default)
			)
			(layer "F.Fab")
		)
		(fp_line
			(start 0.2794 0.9906)
			(end 0.2794 -0.1016)
			(stroke
				(width 0.1)
				(type default)
			)
			(layer "F.Fab")
		)
		(pad "1" smd rect
			(at 0 0)
			(size 0.508 0.508)
			(layers "F.Cu" "F.Mask" "F.Paste")
			(net "JTAG_BMC_TRST_BUF_N")
		)
		(pad "2" smd rect
			(at 0 0.889)
			(size 0.508 0.508)
			(layers "F.Cu" "F.Mask" "F.Paste")
			(net "GND")
		)
		(zone
			(layer "F.Cu")
			(hatch none 0.5)
			(connect_pads
				(clearance 0)
			)
			(min_thickness 0.25)
			(keepout
				(tracks allowed)
				(vias not_allowed)
				(pads allowed)
				(copperpour not_allowed)
				(footprints allowed)
			)
			(placement
				(enabled no)
				(sheetname "")
			)
			(fill
				(thermal_gap 0.5)
				(thermal_bridge_width 0.5)
				(island_removal_mode 0)
			)
			(polygon
				(pts
					(xy 435.473094 -149.789642) (xy 435.981094 -149.789642) (xy 435.981094 -149.408642) (xy 435.473094 -149.408642)
				)
			)
		)
		(zone
			(layer "F.Cu")
			(hatch none 0.5)
			(connect_pads
				(clearance 0)
			)
			(min_thickness 0.25)
			(keepout
				(tracks not_allowed)
				(vias allowed)
				(pads allowed)
				(copperpour not_allowed)
				(footprints allowed)
			)
			(placement
				(enabled no)
				(sheetname "")
			)
			(fill
				(thermal_gap 0.5)
				(thermal_bridge_width 0.5)
				(island_removal_mode 0)
			)
			(polygon
				(pts
					(xy 435.473094 -149.408642) (xy 435.981094 -149.408642) (xy 435.981094 -149.789642) (xy 435.473094 -149.789642)
				)
			)
		)
	)
	(footprint ""
		(layer "F.Cu")
		(at 175.387 -77.597 90)
		(property "Reference" "R4D25"
			(at 0 0 90)
			(layer "F.SilkS")
			(hide yes)
			(effects
				(font
					(size 1.27 1.27)
				)
			)
		)
		(property "Value" ""
			(at 0 0 90)
			(layer "F.Fab")
			(effects
				(font
					(size 1.27 1.27)
				)
			)
		)
		(duplicate_pad_numbers_are_jumpers no)
		(fp_poly
			(pts
				(xy -0.2794 -0.1016) (xy 0.2794 -0.1016) (xy 0.2794 0.9906) (xy -0.2794 0.9906)
			)
			(stroke
				(width 0)
				(type default)
			)
			(fill no)
			(layer "F.CrtYd")
		)
		(fp_line
			(start 0.2794 -0.1016)
			(end -0.2794 -0.1016)
			(stroke
				(width 0.1)
				(type default)
			)
			(layer "F.Fab")
		)
		(fp_line
			(start -0.2794 -0.1016)
			(end -0.2794 0.9906)
			(stroke
				(width 0.1)
				(type default)
			)
			(layer "F.Fab")
		)
		(fp_line
			(start 0.2794 0.9906)
			(end 0.2794 -0.1016)
			(stroke
				(width 0.1)
				(type default)
			)
			(layer "F.Fab")
		)
		(fp_line
			(start -0.2794 0.9906)
			(end 0.2794 0.9906)
			(stroke
				(width 0.1)
				(type default)
			)
			(layer "F.Fab")
		)
		(pad "1" smd rect
			(at 0 0 90)
			(size 0.508 0.508)
			(layers "F.Cu" "F.Mask" "F.Paste")
			(net "CLK_100M_CPU0_BCLK0_R_DN")
		)
		(pad "2" smd rect
			(at 0 0.889 90)
			(size 0.508 0.508)
			(layers "F.Cu" "F.Mask" "F.Paste")
			(net "CLK_100M_CPU0_BCLK0_DN")
		)
		(zone
			(layer "F.Cu")
			(hatch none 0.5)
			(connect_pads
				(clearance 0)
			)
			(min_thickness 0.25)
			(keepout
				(tracks allowed)
				(vias not_allowed)
				(pads allowed)
				(copperpour not_allowed)
				(footprints allowed)
			)
			(placement
				(enabled no)
				(sheetname "")
			)
			(fill
				(thermal_gap 0.5)
				(thermal_bridge_width 0.5)
				(island_removal_mode 0)
			)
			(polygon
				(pts
					(xy 175.641 -77.343) (xy 175.641 -77.851) (xy 176.022 -77.851) (xy 176.022 -77.343)
				)
			)
		)
		(zone
			(layer "F.Cu")
			(hatch none 0.5)
			(connect_pads
				(clearance 0)
			)
			(min_thickness 0.25)
			(keepout
				(tracks not_allowed)
				(vias allowed)
				(pads allowed)
				(copperpour not_allowed)
				(footprints allowed)
			)
			(placement
				(enabled no)
				(sheetname "")
			)
			(fill
				(thermal_gap 0.5)
				(thermal_bridge_width 0.5)
				(island_removal_mode 0)
			)
			(polygon
				(pts
					(xy 176.022 -77.343) (xy 176.022 -77.851) (xy 175.641 -77.851) (xy 175.641 -77.343)
				)
			)
		)
	)
	(footprint ""
		(layer "F.Cu")
		(at 349.735648 -21.279612)
		(property "Reference" "R12W1"
			(at 0 0 0)
			(layer "F.SilkS")
			(hide yes)
			(effects
				(font
					(size 1.27 1.27)
				)
			)
		)
		(property "Value" "*"
			(at 0 -8.9535 0)
			(unlocked yes)
			(layer "F.Fab")
			(hide yes)
			(effects
				(font
					(size 1.27 1.016)
					(thickness 0.1524)
				)
			)
		)
		(property "Device Type" "665KR5B-1-GP_SMD-RG3-665KR5B-1A"
			(at 0 -10.6299 0)
			(unlocked yes)
			(layer "F.Fab")
			(hide yes)
			(effects
				(font
					(size 1.27 1.016)
					(thickness 0.1524)
				)
			)
		)
		(duplicate_pad_numbers_are_jumpers no)
		(fp_line
			(start -0.889 -1.7018)
			(end -0.889 0.2794)
			(stroke
				(width 0.1524)
				(type default)
			)
			(layer "F.SilkS")
		)
		(fp_line
			(start -0.889 0.0762)
			(end -0.889 1.7018)
			(stroke
				(width 0.1524)
				(type default)
			)
			(layer "F.SilkS")
		)
		(fp_line
			(start -0.889 1.7018)
			(end 0.889 1.7018)
			(stroke
				(width 0.1524)
				(type default)
			)
			(layer "F.SilkS")
		)
		(fp_line
			(start 0.889 -1.7018)
			(end -0.889 -1.7018)
			(stroke
				(width 0.1524)
				(type default)
			)
			(layer "F.SilkS")
		)
		(fp_line
			(start 0.889 -1.7018)
			(end 0.889 -0.381)
			(stroke
				(width 0.1524)
				(type default)
			)
			(layer "F.SilkS")
		)
		(fp_line
			(start 0.889 1.7018)
			(end 0.889 -0.508)
			(stroke
				(width 0.1524)
				(type default)
			)
			(layer "F.SilkS")
		)
		(fp_poly
			(pts
				(xy 0.9652 -1.778) (xy 0.9652 1.778) (xy -0.9652 1.778) (xy -0.9652 -1.778)
			)
			(stroke
				(width 0)
				(type default)
			)
			(fill no)
			(layer "F.CrtYd")
		)
		(fp_rect
			(start -0.9652 1.778)
			(end 0.9652 -1.778)
			(stroke
				(width 0)
				(type default)
			)
			(fill no)
			(layer "F.Fab")
		)
		(pad "1" smd rect
			(at 0 -0.9652)
			(size 1.397 1.143)
			(layers "F.Cu" "F.Mask" "F.Paste")
			(net "P12V_STBY")
		)
		(pad "2" smd rect
			(at 0 0.9652)
			(size 1.397 1.143)
			(layers "F.Cu" "F.Mask" "F.Paste")
			(net "VR_PVDDQ_ABC_AIINSEN")
		)
	)
	(footprint ""
		(layer "F.Cu")
		(at 4.31546 -132.49402 180)
		(property "Reference" "C1B2"
			(at -0.8382 -0.67818 180)
			(unlocked yes)
			(layer "F.SilkS")
			(effects
				(font
					(size 0.4064 0.254)
					(thickness 0.1524)
				)
				(justify left)
			)
		)
		(property "Value" ""
			(at 0 0 180)
			(layer "F.Fab")
			(effects
				(font
					(size 1.27 1.27)
				)
			)
		)
		(duplicate_pad_numbers_are_jumpers no)
		(fp_poly
			(pts
				(xy 0.3048 -0.1016) (xy 0.3048 0.9906) (xy -0.3048 0.9906) (xy -0.3048 -0.1016)
			)
			(stroke
				(width 0)
				(type default)
			)
			(fill no)
			(layer "F.CrtYd")
		)
		(fp_line
			(start 0.3048 0.9906)
			(end 0.3048 -0.1016)
			(stroke
				(width 0.1)
				(type default)
			)
			(layer "F.Fab")
		)
		(fp_line
			(start 0.3048 -0.1016)
			(end -0.3048 -0.1016)
			(stroke
				(width 0.1)
				(type default)
			)
			(layer "F.Fab")
		)
		(fp_line
			(start -0.3048 0.9906)
			(end 0.3048 0.9906)
			(stroke
				(width 0.1)
				(type default)
			)
			(layer "F.Fab")
		)
		(fp_line
			(start -0.3048 -0.1016)
			(end -0.3048 0.9906)
			(stroke
				(width 0.1)
				(type default)
			)
			(layer "F.Fab")
		)
		(pad "1" smd rect
			(at 0 0 180)
			(size 0.508 0.508)
			(layers "F.Cu" "F.Mask" "F.Paste")
			(net "VR_PVDDQ_KLM_VD12")
		)
		(pad "2" smd rect
			(at 0 0.889 180)
			(size 0.508 0.508)
			(layers "F.Cu" "F.Mask" "F.Paste")
			(net "GND")
		)
		(zone
			(layer "F.Cu")
			(hatch none 0.5)
			(connect_pads
				(clearance 0)
			)
			(min_thickness 0.25)
			(keepout
				(tracks not_allowed)
				(vias allowed)
				(pads allowed)
				(copperpour not_allowed)
				(footprints allowed)
			)
			(placement
				(enabled no)
				(sheetname "")
			)
			(fill
				(thermal_gap 0.5)
				(thermal_bridge_width 0.5)
				(island_removal_mode 0)
			)
			(polygon
				(pts
					(xy 4.56946 -133.12902) (xy 4.06146 -133.12902) (xy 4.06146 -132.74802) (xy 4.56946 -132.74802)
				)
			)
		)
		(zone
			(layer "F.Cu")
			(hatch none 0.5)
			(connect_pads
				(clearance 0)
			)
			(min_thickness 0.25)
			(keepout
				(tracks allowed)
				(vias not_allowed)
				(pads allowed)
				(copperpour not_allowed)
				(footprints allowed)
			)
			(placement
				(enabled no)
				(sheetname "")
			)
			(fill
				(thermal_gap 0.5)
				(thermal_bridge_width 0.5)
				(island_removal_mode 0)
			)
			(polygon
				(pts
					(xy 4.56946 -132.74802) (xy 4.06146 -132.74802) (xy 4.06146 -133.12902) (xy 4.56946 -133.12902)
				)
			)
		)
	)
	(footprint ""
		(layer "F.Cu")
		(at 20.5232 -97.310956 180)
		(property "Reference" "C1C11"
			(at 0 0 180)
			(layer "F.SilkS")
			(hide yes)
			(effects
				(font
					(size 1.27 1.27)
				)
			)
		)
		(property "Value" ""
			(at 0 0 180)
			(layer "F.Fab")
			(effects
				(font
					(size 1.27 1.27)
				)
			)
		)
		(duplicate_pad_numbers_are_jumpers no)
		(fp_rect
			(start 0.3048 -0.1016)
			(end -0.3048 0.9906)
			(stroke
				(width 0)
				(type default)
			)
			(fill no)
			(layer "F.CrtYd")
		)
		(fp_line
			(start 0.3048 0.9906)
			(end 0.3048 -0.1016)
			(stroke
				(width 0.1)
				(type default)
			)
			(layer "F.Fab")
		)
		(fp_line
			(start 0.3048 -0.1016)
			(end -0.3048 -0.1016)
			(stroke
				(width 0.1)
				(type default)
			)
			(layer "F.Fab")
		)
		(fp_line
			(start -0.3048 0.9906)
			(end 0.3048 0.9906)
			(stroke
				(width 0.1)
				(type default)
			)
			(layer "F.Fab")
		)
		(fp_line
			(start -0.3048 -0.1016)
			(end -0.3048 0.9906)
			(stroke
				(width 0.1)
				(type default)
			)
			(layer "F.Fab")
		)
		(pad "1" smd rect
			(at 0 0 180)
			(size 0.508 0.508)
			(layers "F.Cu" "F.Mask" "F.Paste")
			(net "A_TSENSE_PVSA_CPU1")
		)
		(pad "2" smd rect
			(at 0 0.889 180)
			(size 0.508 0.508)
			(layers "F.Cu" "F.Mask" "F.Paste")
			(net "GND")
		)
		(zone
			(layer "F.Cu")
			(hatch none 0.5)
			(connect_pads
				(clearance 0)
			)
			(min_thickness 0.25)
			(keepout
				(tracks allowed)
				(vias not_allowed)
				(pads allowed)
				(copperpour not_allowed)
				(footprints allowed)
			)
			(placement
				(enabled no)
				(sheetname "")
			)
			(fill
				(thermal_gap 0.5)
				(thermal_bridge_width 0.5)
				(island_removal_mode 0)
			)
			(polygon
				(pts
					(xy 20.2692 -97.564956) (xy 20.7772 -97.564956) (xy 20.7772 -97.945956) (xy 20.2692 -97.945956)
				)
			)
		)
		(zone
			(layer "F.Cu")
			(hatch none 0.5)
			(connect_pads
				(clearance 0)
			)
			(min_thickness 0.25)
			(keepout
				(tracks not_allowed)
				(vias allowed)
				(pads allowed)
				(copperpour not_allowed)
				(footprints allowed)
			)
			(placement
				(enabled no)
				(sheetname "")
			)
			(fill
				(thermal_gap 0.5)
				(thermal_bridge_width 0.5)
				(island_removal_mode 0)
			)
			(polygon
				(pts
					(xy 20.2692 -97.564956) (xy 20.7772 -97.564956) (xy 20.7772 -97.945956) (xy 20.2692 -97.945956)
				)
			)
		)
	)
	(footprint ""
		(layer "F.Cu")
		(at 332.172818 -129.921)
		(property "Reference" "C6B3"
			(at 0 0 0)
			(layer "F.SilkS")
			(hide yes)
			(effects
				(font
					(size 1.27 1.27)
				)
			)
		)
		(property "Value" ""
			(at 0 0 0)
			(layer "F.Fab")
			(effects
				(font
					(size 1.27 1.27)
				)
			)
		)
		(duplicate_pad_numbers_are_jumpers no)
		(fp_poly
			(pts
				(xy -0.7239 -0.2159) (xy 0.7239 -0.2159) (xy 0.7239 1.9939) (xy -0.7239 1.9939)
			)
			(stroke
				(width 0)
				(type default)
			)
			(fill no)
			(layer "F.CrtYd")
		)
		(fp_line
			(start -0.7239 -0.2159)
			(end -0.7239 1.9939)
			(stroke
				(width 0.1)
				(type default)
			)
			(layer "F.Fab")
		)
		(fp_line
			(start -0.7239 1.9939)
			(end 0.7239 1.9939)
			(stroke
				(width 0.1)
				(type default)
			)
			(layer "F.Fab")
		)
		(fp_line
			(start 0.7239 -0.2159)
			(end -0.7239 -0.2159)
			(stroke
				(width 0.1)
				(type default)
			)
			(layer "F.Fab")
		)
		(fp_line
			(start 0.7239 1.9939)
			(end 0.7239 -0.2159)
			(stroke
				(width 0.1)
				(type default)
			)
			(layer "F.Fab")
		)
		(pad "1" smd rect
			(at 0 0)
			(size 1.27 1.016)
			(layers "F.Cu" "F.Mask" "F.Paste")
			(net "PVPP_DEF")
		)
		(pad "2" smd rect
			(at 0 1.778)
			(size 1.27 1.016)
			(layers "F.Cu" "F.Mask" "F.Paste")
			(net "GND")
		)
		(zone
			(layer "F.Cu")
			(hatch none 0.5)
			(connect_pads
				(clearance 0)
			)
			(min_thickness 0.25)
			(keepout
				(tracks not_allowed)
				(vias allowed)
				(pads allowed)
				(copperpour not_allowed)
				(footprints allowed)
			)
			(placement
				(enabled no)
				(sheetname "")
			)
			(fill
				(thermal_gap 0.5)
				(thermal_bridge_width 0.5)
				(island_removal_mode 0)
			)
			(polygon
				(pts
					(xy 331.537818 -129.413) (xy 332.807818 -129.413) (xy 332.807818 -128.651) (xy 331.537818 -128.651)
				)
			)
		)
	)
	(footprint ""
		(layer "F.Cu")
		(at 177.165 -78.867 90)
		(property "Reference" "R4D22"
			(at 0 0 90)
			(layer "F.SilkS")
			(hide yes)
			(effects
				(font
					(size 1.27 1.27)
				)
			)
		)
		(property "Value" ""
			(at 0 0 90)
			(layer "F.Fab")
			(effects
				(font
					(size 1.27 1.27)
				)
			)
		)
		(duplicate_pad_numbers_are_jumpers no)
		(fp_poly
			(pts
				(xy -0.2794 -0.1016) (xy 0.2794 -0.1016) (xy 0.2794 0.9906) (xy -0.2794 0.9906)
			)
			(stroke
				(width 0)
				(type default)
			)
			(fill no)
			(layer "F.CrtYd")
		)
		(fp_line
			(start 0.2794 -0.1016)
			(end -0.2794 -0.1016)
			(stroke
				(width 0.1)
				(type default)
			)
			(layer "F.Fab")
		)
		(fp_line
			(start -0.2794 -0.1016)
			(end -0.2794 0.9906)
			(stroke
				(width 0.1)
				(type default)
			)
			(layer "F.Fab")
		)
		(fp_line
			(start 0.2794 0.9906)
			(end 0.2794 -0.1016)
			(stroke
				(width 0.1)
				(type default)
			)
			(layer "F.Fab")
		)
		(fp_line
			(start -0.2794 0.9906)
			(end 0.2794 0.9906)
			(stroke
				(width 0.1)
				(type default)
			)
			(layer "F.Fab")
		)
		(pad "1" smd rect
			(at 0 0 90)
			(size 0.508 0.508)
			(layers "F.Cu" "F.Mask" "F.Paste")
			(net "CLK_100M_CPU0_BCLK1_R_DP")
		)
		(pad "2" smd rect
			(at 0 0.889 90)
			(size 0.508 0.508)
			(layers "F.Cu" "F.Mask" "F.Paste")
			(net "CLK_100M_CPU0_BCLK1_DP")
		)
		(zone
			(layer "F.Cu")
			(hatch none 0.5)
			(connect_pads
				(clearance 0)
			)
			(min_thickness 0.25)
			(keepout
				(tracks allowed)
				(vias not_allowed)
				(pads allowed)
				(copperpour not_allowed)
				(footprints allowed)
			)
			(placement
				(enabled no)
				(sheetname "")
			)
			(fill
				(thermal_gap 0.5)
				(thermal_bridge_width 0.5)
				(island_removal_mode 0)
			)
			(polygon
				(pts
					(xy 177.419 -78.613) (xy 177.419 -79.121) (xy 177.8 -79.121) (xy 177.8 -78.613)
				)
			)
		)
		(zone
			(layer "F.Cu")
			(hatch none 0.5)
			(connect_pads
				(clearance 0)
			)
			(min_thickness 0.25)
			(keepout
				(tracks not_allowed)
				(vias allowed)
				(pads allowed)
				(copperpour not_allowed)
				(footprints allowed)
			)
			(placement
				(enabled no)
				(sheetname "")
			)
			(fill
				(thermal_gap 0.5)
				(thermal_bridge_width 0.5)
				(island_removal_mode 0)
			)
			(polygon
				(pts
					(xy 177.8 -78.613) (xy 177.8 -79.121) (xy 177.419 -79.121) (xy 177.419 -78.613)
				)
			)
		)
	)
	(footprint ""
		(layer "F.Cu")
		(at 87.158068 -3.3528 -90)
		(property "Reference" "C2G11"
			(at 1.848866 0.752348 270)
			(unlocked yes)
			(layer "F.SilkS")
			(effects
				(font
					(size 1.27 0.9652)
					(thickness 0.1524)
				)
			)
		)
		(property "Value" ""
			(at 0 0 270)
			(layer "F.Fab")
			(effects
				(font
					(size 1.27 1.27)
				)
			)
		)
		(duplicate_pad_numbers_are_jumpers no)
		(fp_rect
			(start -0.500126 1.598422)
			(end 0.500126 -0.201422)
			(stroke
				(width 0)
				(type default)
			)
			(fill no)
			(layer "F.CrtYd")
		)
		(fp_line
			(start -0.500126 1.598422)
			(end -0.500126 -0.201422)
			(stroke
				(width 0.1)
				(type default)
			)
			(layer "F.Fab")
		)
		(fp_line
			(start 0.500126 1.598422)
			(end -0.500126 1.598422)
			(stroke
				(width 0.1)
				(type default)
			)
			(layer "F.Fab")
		)
		(fp_line
			(start -0.500126 -0.201422)
			(end 0.500126 -0.201422)
			(stroke
				(width 0.1)
				(type default)
			)
			(layer "F.Fab")
		)
		(fp_line
			(start 0.500126 -0.201422)
			(end 0.500126 1.598422)
			(stroke
				(width 0.1)
				(type default)
			)
			(layer "F.Fab")
		)
		(pad "1" smd rect
			(at 0 0 180)
			(size 0.889 0.9906)
			(layers "F.Cu" "F.Mask" "F.Paste")
			(net "PVDDQ_GHJ")
		)
		(pad "2" smd rect
			(at 0 1.397 180)
			(size 0.889 0.9906)
			(layers "F.Cu" "F.Mask" "F.Paste")
			(net "GND")
		)
		(zone
			(layer "F.Cu")
			(hatch none 0.5)
			(connect_pads
				(clearance 0)
			)
			(min_thickness 0.25)
			(keepout
				(tracks allowed)
				(vias not_allowed)
				(pads allowed)
				(copperpour not_allowed)
				(footprints allowed)
			)
			(placement
				(enabled no)
				(sheetname "")
			)
			(fill
				(thermal_gap 0.5)
				(thermal_bridge_width 0.5)
				(island_removal_mode 0)
			)
			(polygon
				(pts
					(xy 86.205568 -3.8481) (xy 86.205568 -2.8575) (xy 86.713568 -2.8575) (xy 86.713568 -3.8481)
				)
			)
		)
		(zone
			(layer "F.Cu")
			(hatch none 0.5)
			(connect_pads
				(clearance 0)
			)
			(min_thickness 0.25)
			(keepout
				(tracks not_allowed)
				(vias allowed)
				(pads allowed)
				(copperpour not_allowed)
				(footprints allowed)
			)
			(placement
				(enabled no)
				(sheetname "")
			)
			(fill
				(thermal_gap 0.5)
				(thermal_bridge_width 0.5)
				(island_removal_mode 0)
			)
			(polygon
				(pts
					(xy 86.205568 -3.8481) (xy 86.205568 -2.8575) (xy 86.713568 -2.8575) (xy 86.713568 -3.8481)
				)
			)
		)
	)
	(footprint ""
		(layer "F.Cu")
		(at -1.999996 -54.909974 -90)
		(property "Reference" "J1E1"
			(at 0 0 270)
			(layer "F.SilkS")
			(hide yes)
			(effects
				(font
					(size 1.27 1.27)
				)
			)
		)
		(property "Value" "*"
			(at -18.3388 15.2273 270)
			(unlocked yes)
			(layer "F.Fab")
			(hide yes)
			(effects
				(font
					(size 1.27 1.016)
					(thickness 0.1524)
				)
			)
		)
		(property "Device Type" "FCI-CONN12-2R-GP_CONN-G5-FCI-CA"
			(at -18.3388 13.7033 270)
			(unlocked yes)
			(layer "F.Fab")
			(hide yes)
			(effects
				(font
					(size 1.27 1.016)
					(thickness 0.1524)
				)
			)
		)
		(duplicate_pad_numbers_are_jumpers no)
		(fp_line
			(start -6.1849 3.999992)
			(end 6.1849 3.999992)
			(stroke
				(width 0.1524)
				(type default)
			)
			(layer "F.SilkS")
		)
		(fp_line
			(start 6.1849 3.999992)
			(end 6.1849 -14.8971)
			(stroke
				(width 0.1524)
				(type default)
			)
			(layer "F.SilkS")
		)
		(fp_line
			(start -6.1849 -14.8971)
			(end -6.1849 3.999992)
			(stroke
				(width 0.1524)
				(type default)
			)
			(layer "F.SilkS")
		)
		(fp_line
			(start 6.1849 -14.8971)
			(end -6.1849 -14.8971)
			(stroke
				(width 0.1524)
				(type default)
			)
			(layer "F.SilkS")
		)
		(fp_poly
			(pts
				(xy -6.1849 3.999992) (xy 6.1849 3.999992) (xy 6.1849 -14.8971) (xy -6.1849 -14.8971)
			)
			(stroke
				(width 0)
				(type default)
			)
			(fill yes)
			(layer "F.SilkS")
		)
		(fp_poly
			(pts
				(arc
					(start -4.064 1.331976)
					(mid -4.318 1.585976)
					(end -4.572 1.331976)
				)
				(arc
					(start -4.572 0.569976)
					(mid -4.318 0.315976)
					(end -4.064 0.569976)
				)
			)
			(stroke
				(width 0)
				(type default)
			)
			(fill yes)
			(layer "F.SilkS")
		)
		(fp_poly
			(pts
				(arc
					(start -4.064 -0.66802)
					(mid -4.318 -0.41402)
					(end -4.572 -0.66802)
				)
				(arc
					(start -4.572 -1.43002)
					(mid -4.318 -1.68402)
					(end -4.064 -1.43002)
				)
			)
			(stroke
				(width 0)
				(type default)
			)
			(fill yes)
			(layer "F.SilkS")
		)
		(fp_poly
			(pts
				(arc
					(start -4.064 -2.668016)
					(mid -4.318 -2.414016)
					(end -4.572 -2.668016)
				)
				(arc
					(start -4.572 -3.430016)
					(mid -4.318 -3.684016)
					(end -4.064 -3.430016)
				)
			)
			(stroke
				(width 0)
				(type default)
			)
			(fill yes)
			(layer "F.SilkS")
		)
		(fp_poly
			(pts
				(arc
					(start -4.064 -6.668008)
					(mid -4.318 -6.414008)
					(end -4.572 -6.668008)
				)
				(arc
					(start -4.572 -7.430008)
					(mid -4.318 -7.684008)
					(end -4.064 -7.430008)
				)
			)
			(stroke
				(width 0)
				(type default)
			)
			(fill yes)
			(layer "F.SilkS")
		)
		(fp_poly
			(pts
				(arc
					(start -4.064 -8.668004)
					(mid -4.318 -8.414004)
					(end -4.572 -8.668004)
				)
				(arc
					(start -4.572 -9.430004)
					(mid -4.318 -9.684004)
					(end -4.064 -9.430004)
				)
			)
			(stroke
				(width 0)
				(type default)
			)
			(fill yes)
			(layer "F.SilkS")
		)
		(fp_poly
			(pts
				(arc
					(start -4.064 -10.668)
					(mid -4.318 -10.414)
					(end -4.572 -10.668)
				)
				(arc
					(start -4.572 -11.43)
					(mid -4.318 -11.684)
					(end -4.064 -11.43)
				)
			)
			(stroke
				(width 0)
				(type default)
			)
			(fill yes)
			(layer "F.SilkS")
		)
		(fp_rect
			(start -8.5598 6.5532)
			(end 8.5598 -16.5608)
			(stroke
				(width 0)
				(type default)
			)
			(fill no)
			(layer "B.CrtYd")
		)
		(fp_rect
			(start -5.9309 16.3449)
			(end 5.9309 -14.6431)
			(stroke
				(width 0)
				(type default)
			)
			(fill no)
			(layer "F.CrtYd")
		)
		(fp_poly
			(pts
				(xy -10.9347 21.3487) (xy -10.9347 -19.6469) (xy 10.9347 -19.6469) (xy 10.9347 -0.00635) (xy 6.4389 -0.00635)
				(xy 6.4389 -15.1511) (xy -6.4389 -15.1511) (xy -6.4389 16.8529) (xy 6.4389 16.8529) (xy 6.4389 0.00635)
				(xy 10.9347 0.00635) (xy 10.9347 21.3487)
			)
			(stroke
				(width 0)
				(type default)
			)
			(fill no)
			(layer "F.CrtYd")
		)
		(fp_poly
			(pts
				(xy -6.4389 16.8529) (xy -6.4389 -15.1511) (xy 6.4389 -15.1511) (xy 6.4389 -0.00635) (xy 5.9309 -0.00635)
				(xy 5.9309 -14.6431) (xy -5.9309 -14.6431) (xy -5.9309 16.3449) (xy 5.9309 16.3449) (xy 5.9309 0.00635)
				(xy 6.4389 0.00635) (xy 6.4389 16.8529)
			)
			(stroke
				(width 0)
				(type default)
			)
			(fill no)
			(layer "F.CrtYd")
		)
		(fp_rect
			(start -13.5636 11.557)
			(end 13.5636 -21.5646)
			(stroke
				(width 0)
				(type default)
			)
			(fill no)
			(layer "B.Fab")
		)
		(fp_rect
			(start -8.5598 6.5532)
			(end 8.5598 -16.5608)
			(stroke
				(width 0)
				(type default)
			)
			(fill no)
			(layer "B.Fab")
		)
		(fp_rect
			(start -15.9385 26.3525)
			(end 15.9385 -24.6507)
			(stroke
				(width 0)
				(type default)
			)
			(fill no)
			(layer "F.Fab")
		)
		(fp_rect
			(start -10.9347 21.3487)
			(end 10.9347 -19.6469)
			(stroke
				(width 0)
				(type default)
			)
			(fill no)
			(layer "F.Fab")
		)
		(fp_rect
			(start -6.4389 16.8529)
			(end 6.4389 -15.1511)
			(stroke
				(width 0)
				(type default)
			)
			(fill no)
			(layer "F.Fab")
		)
		(fp_text user "Slit"
			(at -2.31521 6.78307 270)
			(unlocked yes)
			(layer "F.SilkS")
			(effects
				(font
					(size 1.27 1.016)
					(thickness 0.1524)
				)
				(justify left)
			)
		)
		(fp_text user "Press Fit"
			(at -5.1054 -12.6111 270)
			(unlocked yes)
			(layer "F.SilkS")
			(effects
				(font
					(size 1.27 1.016)
					(thickness 0.1524)
				)
				(justify left)
			)
		)
		(fp_text user "Can not place BGA,CSP,Wave Solder Component"
			(at -25.73655 8.95604 270)
			(unlocked yes)
			(layer "B.Fab")
			(effects
				(font
					(size 1.27 1.016)
					(thickness 0.1524)
				)
				(justify left)
			)
		)
		(fp_text user "Can not place BGA,CSP,Wave Solder Component"
			(at -25.82926 18.53946 270)
			(unlocked yes)
			(layer "F.Fab")
			(effects
				(font
					(size 1.27 1.016)
					(thickness 0.1524)
				)
				(justify left)
			)
		)
		(fp_text user "High Limit 2mm"
			(at -8.4963 13.35786 270)
			(unlocked yes)
			(layer "F.Fab")
			(effects
				(font
					(size 1.27 1.016)
					(thickness 0.1524)
				)
				(justify left)
			)
		)
		(pad "" np_thru_hole circle
			(at 0 0 270)
			(size 0.254 0.254)
			(drill 2.1336)
			(layers "*.Cu" "*.Mask")
			(clearance 1.2954)
			(thermal_gap 1.2954)
		)
		(pad "1_1" thru_hole circle
			(at 2.999994 -6.999986 270)
			(size 1.1176 1.1176)
			(drill 0.749808)
			(layers "*.Cu" "*.Mask")
			(remove_unused_layers no)
			(net "P12V_PSU")
			(clearance 0.1778)
			(thermal_gap 0.1778)
		)
		(pad "1_2" thru_hole circle
			(at 2.999994 -8.999982 270)
			(size 1.1176 1.1176)
			(drill 0.749808)
			(layers "*.Cu" "*.Mask")
			(remove_unused_layers no)
			(net "P12V_PSU")
			(clearance 0.1778)
			(thermal_gap 0.1778)
		)
		(pad "1_3" thru_hole circle
			(at 2.999994 -10.999978 270)
			(size 1.1176 1.1176)
			(drill 0.749808)
			(layers "*.Cu" "*.Mask")
			(remove_unused_layers no)
			(net "P12V_PSU")
			(clearance 0.1778)
			(thermal_gap 0.1778)
		)
		(pad "2_1" thru_hole circle
			(at -2.999994 -6.999986 270)
			(size 1.1176 1.1176)
			(drill 0.749808)
			(layers "*.Cu" "*.Mask")
			(remove_unused_layers no)
			(net "P12V_PSU")
			(clearance 0.1778)
			(thermal_gap 0.1778)
		)
		(pad "2_2" thru_hole circle
			(at -2.999994 -8.999982 270)
			(size 1.1176 1.1176)
			(drill 0.749808)
			(layers "*.Cu" "*.Mask")
			(remove_unused_layers no)
			(net "P12V_PSU")
			(clearance 0.1778)
			(thermal_gap 0.1778)
		)
		(pad "2_3" thru_hole circle
			(at -2.999994 -10.999978 270)
			(size 1.1176 1.1176)
			(drill 0.749808)
			(layers "*.Cu" "*.Mask")
			(remove_unused_layers no)
			(net "P12V_PSU")
			(clearance 0.1778)
			(thermal_gap 0.1778)
		)
		(pad "3_1" thru_hole circle
			(at -2.999994 0.999998 270)
			(size 1.1176 1.1176)
			(drill 0.749808)
			(layers "*.Cu" "*.Mask")
			(remove_unused_layers no)
			(net "GND")
			(clearance 0.1778)
			(thermal_gap 0.1778)
		)
		(pad "3_2" thru_hole circle
			(at -2.999994 -0.999998 270)
			(size 1.1176 1.1176)
			(drill 0.749808)
			(layers "*.Cu" "*.Mask")
			(remove_unused_layers no)
			(net "GND")
			(clearance 0.1778)
			(thermal_gap 0.1778)
		)
		(pad "3_3" thru_hole circle
			(at -2.999994 -2.999994 270)
			(size 1.1176 1.1176)
			(drill 0.749808)
			(layers "*.Cu" "*.Mask")
			(remove_unused_layers no)
			(net "GND")
			(clearance 0.1778)
			(thermal_gap 0.1778)
		)
		(pad "4_1" thru_hole circle
			(at 2.999994 0.999998 270)
			(size 1.1176 1.1176)
			(drill 0.749808)
			(layers "*.Cu" "*.Mask")
			(remove_unused_layers no)
			(net "GND")
			(clearance 0.1778)
			(thermal_gap 0.1778)
		)
		(pad "4_2" thru_hole circle
			(at 2.999994 -0.999998 270)
			(size 1.1176 1.1176)
			(drill 0.749808)
			(layers "*.Cu" "*.Mask")
			(remove_unused_layers no)
			(net "GND")
			(clearance 0.1778)
			(thermal_gap 0.1778)
		)
		(pad "4_3" thru_hole circle
			(at 2.999994 -2.999994 270)
			(size 1.1176 1.1176)
			(drill 0.749808)
			(layers "*.Cu" "*.Mask")
			(remove_unused_layers no)
			(net "GND")
			(clearance 0.1778)
			(thermal_gap 0.1778)
		)
		(zone
			(layers "F.Cu" "B.Cu" "In1.Cu" "In2.Cu" "In3.Cu" "In4.Cu" "In5.Cu" "In6.Cu"
				"In7.Cu" "In8.Cu" "In9.Cu" "In10.Cu" "In11.Cu" "In12.Cu"
			)
			(hatch none 0.5)
			(connect_pads
				(clearance 0)
			)
			(min_thickness 0.25)
			(keepout
				(tracks not_allowed)
				(vias allowed)
				(pads allowed)
				(copperpour not_allowed)
				(footprints allowed)
			)
			(placement
				(enabled no)
				(sheetname "")
			)
			(fill
				(thermal_gap 0.5)
				(thermal_bridge_width 0.5)
				(island_removal_mode 0)
			)
			(polygon
				(pts
					(arc
						(start -0.628396 -54.909974)
						(mid -3.371596 -54.909974)
						(end -0.628396 -54.909974)
					)
				)
			)
		)
	)
	(footprint ""
		(layer "F.Cu")
		(at 336.677 -22.352 180)
		(property "Reference" "C7F13"
			(at 0 0 180)
			(layer "F.SilkS")
			(hide yes)
			(effects
				(font
					(size 1.27 1.27)
				)
			)
		)
		(property "Value" ""
			(at 0 0 180)
			(layer "F.Fab")
			(effects
				(font
					(size 1.27 1.27)
				)
			)
		)
		(duplicate_pad_numbers_are_jumpers no)
		(fp_poly
			(pts
				(xy 0.3048 -0.1016) (xy 0.3048 0.9906) (xy -0.3048 0.9906) (xy -0.3048 -0.1016)
			)
			(stroke
				(width 0)
				(type default)
			)
			(fill no)
			(layer "F.CrtYd")
		)
		(fp_line
			(start 0.3048 0.9906)
			(end 0.3048 -0.1016)
			(stroke
				(width 0.1)
				(type default)
			)
			(layer "F.Fab")
		)
		(fp_line
			(start 0.3048 -0.1016)
			(end -0.3048 -0.1016)
			(stroke
				(width 0.1)
				(type default)
			)
			(layer "F.Fab")
		)
		(fp_line
			(start -0.3048 0.9906)
			(end 0.3048 0.9906)
			(stroke
				(width 0.1)
				(type default)
			)
			(layer "F.Fab")
		)
		(fp_line
			(start -0.3048 -0.1016)
			(end -0.3048 0.9906)
			(stroke
				(width 0.1)
				(type default)
			)
			(layer "F.Fab")
		)
		(pad "1" smd rect
			(at 0 0 180)
			(size 0.508 0.508)
			(layers "F.Cu" "F.Mask" "F.Paste")
			(net "VR_COMP_PVPP_ABC")
		)
		(pad "2" smd rect
			(at 0 0.889 180)
			(size 0.508 0.508)
			(layers "F.Cu" "F.Mask" "F.Paste")
			(net "VR_FB_PVPP_ABC")
		)
		(zone
			(layer "F.Cu")
			(hatch none 0.5)
			(connect_pads
				(clearance 0)
			)
			(min_thickness 0.25)
			(keepout
				(tracks not_allowed)
				(vias allowed)
				(pads allowed)
				(copperpour not_allowed)
				(footprints allowed)
			)
			(placement
				(enabled no)
				(sheetname "")
			)
			(fill
				(thermal_gap 0.5)
				(thermal_bridge_width 0.5)
				(island_removal_mode 0)
			)
			(polygon
				(pts
					(xy 336.931 -22.987) (xy 336.423 -22.987) (xy 336.423 -22.606) (xy 336.931 -22.606)
				)
			)
		)
		(zone
			(layer "F.Cu")
			(hatch none 0.5)
			(connect_pads
				(clearance 0)
			)
			(min_thickness 0.25)
			(keepout
				(tracks allowed)
				(vias not_allowed)
				(pads allowed)
				(copperpour not_allowed)
				(footprints allowed)
			)
			(placement
				(enabled no)
				(sheetname "")
			)
			(fill
				(thermal_gap 0.5)
				(thermal_bridge_width 0.5)
				(island_removal_mode 0)
			)
			(polygon
				(pts
					(xy 336.931 -22.606) (xy 336.423 -22.606) (xy 336.423 -22.987) (xy 336.931 -22.987)
				)
			)
		)
	)
	(footprint ""
		(layer "F.Cu")
		(at 25.035002 -88.130634 180)
		(property "Reference" "CF8"
			(at 0 0 180)
			(layer "F.SilkS")
			(hide yes)
			(effects
				(font
					(size 1.27 1.27)
				)
			)
		)
		(property "Value" "*"
			(at 1.1811 -2.8194 180)
			(unlocked yes)
			(layer "F.Fab")
			(hide yes)
			(effects
				(font
					(size 1.27 1.016)
					(thickness 0.1524)
				)
			)
		)
		(property "Device Type" "SC22P50V2JN-4GP_SMD-BCG-SC22P5A"
			(at 1.1811 -4.3434 180)
			(unlocked yes)
			(layer "F.Fab")
			(hide yes)
			(effects
				(font
					(size 1.27 1.016)
					(thickness 0.1524)
				)
			)
		)
		(duplicate_pad_numbers_are_jumpers no)
		(fp_rect
			(start -0.4318 0.9525)
			(end 0.4318 -0.9525)
			(stroke
				(width 0)
				(type default)
			)
			(fill no)
			(layer "F.CrtYd")
		)
		(fp_rect
			(start -0.4318 0.9525)
			(end 0.4318 -0.9525)
			(stroke
				(width 0)
				(type default)
			)
			(fill no)
			(layer "F.Fab")
		)
		(pad "1" smd custom
			(at 0 -0.4445 180)
			(size 0.1524 0.1524)
			(layers "F.Cu" "F.Mask" "F.Paste")
			(net "VR_PVCCIN_CPU1_AIREF2")
			(options
				(clearance outline)
				(anchor circle)
			)
			(primitives
				(gr_poly
					(pts
						(arc
							(start 0.3048 -0.2032)
							(mid 0.275042 -0.275042)
							(end 0.2032 -0.3048)
						)
						(arc
							(start -0.2032 -0.3048)
							(mid -0.275042 -0.275042)
							(end -0.3048 -0.2032)
						)
						(arc
							(start -0.3048 0.2032)
							(mid -0.275042 0.275042)
							(end -0.2032 0.3048)
						)
						(arc
							(start 0.2032 0.3048)
							(mid 0.275042 0.275042)
							(end 0.3048 0.2032)
						)
					)
					(width 0)
					(fill yes)
				)
			)
		)
		(pad "2" smd custom
			(at 0 0.4445 180)
			(size 0.1524 0.1524)
			(layers "F.Cu" "F.Mask" "F.Paste")
			(net "ISENSE_PVCCIN_CPU1_PH2_IMON")
			(options
				(clearance outline)
				(anchor circle)
			)
			(primitives
				(gr_poly
					(pts
						(arc
							(start 0.3048 -0.2032)
							(mid 0.275042 -0.275042)
							(end 0.2032 -0.3048)
						)
						(arc
							(start -0.2032 -0.3048)
							(mid -0.275042 -0.275042)
							(end -0.3048 -0.2032)
						)
						(arc
							(start -0.3048 0.2032)
							(mid -0.275042 0.275042)
							(end -0.2032 0.3048)
						)
						(arc
							(start 0.2032 0.3048)
							(mid 0.275042 0.275042)
							(end 0.3048 0.2032)
						)
					)
					(width 0)
					(fill yes)
				)
			)
		)
	)
	(footprint ""
		(layer "F.Cu")
		(at 388.992618 -156.591 90)
		(property "Reference" "C7A9"
			(at 0 0 90)
			(layer "F.SilkS")
			(hide yes)
			(effects
				(font
					(size 1.27 1.27)
				)
			)
		)
		(property "Value" ""
			(at 0 0 90)
			(layer "F.Fab")
			(effects
				(font
					(size 1.27 1.27)
				)
			)
		)
		(duplicate_pad_numbers_are_jumpers no)
		(fp_poly
			(pts
				(xy 0.3048 -0.1016) (xy 0.3048 0.9906) (xy -0.3048 0.9906) (xy -0.3048 -0.1016)
			)
			(stroke
				(width 0)
				(type default)
			)
			(fill no)
			(layer "F.CrtYd")
		)
		(fp_line
			(start 0.3048 -0.1016)
			(end -0.3048 -0.1016)
			(stroke
				(width 0.1)
				(type default)
			)
			(layer "F.Fab")
		)
		(fp_line
			(start -0.3048 -0.1016)
			(end -0.3048 0.9906)
			(stroke
				(width 0.1)
				(type default)
			)
			(layer "F.Fab")
		)
		(fp_line
			(start 0.3048 0.9906)
			(end 0.3048 -0.1016)
			(stroke
				(width 0.1)
				(type default)
			)
			(layer "F.Fab")
		)
		(fp_line
			(start -0.3048 0.9906)
			(end 0.3048 0.9906)
			(stroke
				(width 0.1)
				(type default)
			)
			(layer "F.Fab")
		)
		(pad "1" smd rect
			(at 0 0 90)
			(size 0.508 0.508)
			(layers "F.Cu" "F.Mask" "F.Paste")
			(net "VR_FET_SW_P12V_STBY_PVDDQ_DEF")
		)
		(pad "2" smd rect
			(at 0 0.889 90)
			(size 0.508 0.508)
			(layers "F.Cu" "F.Mask" "F.Paste")
			(net "GND")
		)
		(zone
			(layer "F.Cu")
			(hatch none 0.5)
			(connect_pads
				(clearance 0)
			)
			(min_thickness 0.25)
			(keepout
				(tracks allowed)
				(vias not_allowed)
				(pads allowed)
				(copperpour not_allowed)
				(footprints allowed)
			)
			(placement
				(enabled no)
				(sheetname "")
			)
			(fill
				(thermal_gap 0.5)
				(thermal_bridge_width 0.5)
				(island_removal_mode 0)
			)
			(polygon
				(pts
					(xy 389.246618 -156.337) (xy 389.246618 -156.845) (xy 389.627618 -156.845) (xy 389.627618 -156.337)
				)
			)
		)
		(zone
			(layer "F.Cu")
			(hatch none 0.5)
			(connect_pads
				(clearance 0)
			)
			(min_thickness 0.25)
			(keepout
				(tracks not_allowed)
				(vias allowed)
				(pads allowed)
				(copperpour not_allowed)
				(footprints allowed)
			)
			(placement
				(enabled no)
				(sheetname "")
			)
			(fill
				(thermal_gap 0.5)
				(thermal_bridge_width 0.5)
				(island_removal_mode 0)
			)
			(polygon
				(pts
					(xy 389.627618 -156.337) (xy 389.627618 -156.845) (xy 389.246618 -156.845) (xy 389.246618 -156.337)
				)
			)
		)
	)
	(footprint ""
		(layer "F.Cu")
		(at 375.158 -88.2015)
		(property "Reference" "R7C15"
			(at 0 0 0)
			(layer "F.SilkS")
			(hide yes)
			(effects
				(font
					(size 1.27 1.27)
				)
			)
		)
		(property "Value" ""
			(at 0 0 0)
			(layer "F.Fab")
			(effects
				(font
					(size 1.27 1.27)
				)
			)
		)
		(duplicate_pad_numbers_are_jumpers no)
		(fp_rect
			(start -0.2794 -0.1016)
			(end 0.2794 0.9906)
			(stroke
				(width 0)
				(type default)
			)
			(fill no)
			(layer "F.CrtYd")
		)
		(fp_line
			(start -0.2794 -0.1016)
			(end -0.2794 0.9906)
			(stroke
				(width 0.1)
				(type default)
			)
			(layer "F.Fab")
		)
		(fp_line
			(start -0.2794 0.9906)
			(end 0.2794 0.9906)
			(stroke
				(width 0.1)
				(type default)
			)
			(layer "F.Fab")
		)
		(fp_line
			(start 0.2794 -0.1016)
			(end -0.2794 -0.1016)
			(stroke
				(width 0.1)
				(type default)
			)
			(layer "F.Fab")
		)
		(fp_line
			(start 0.2794 0.9906)
			(end 0.2794 -0.1016)
			(stroke
				(width 0.1)
				(type default)
			)
			(layer "F.Fab")
		)
		(pad "1" smd rect
			(at 0 0)
			(size 0.508 0.508)
			(layers "F.Cu" "F.Mask" "F.Paste")
			(net "SPI_PCH_MOSI_R")
		)
		(pad "2" smd rect
			(at 0 0.889)
			(size 0.508 0.508)
			(layers "F.Cu" "F.Mask" "F.Paste")
			(net "SPI_PCH_MOSI")
		)
		(zone
			(layer "F.Cu")
			(hatch none 0.5)
			(connect_pads
				(clearance 0)
			)
			(min_thickness 0.25)
			(keepout
				(tracks allowed)
				(vias not_allowed)
				(pads allowed)
				(copperpour not_allowed)
				(footprints allowed)
			)
			(placement
				(enabled no)
				(sheetname "")
			)
			(fill
				(thermal_gap 0.5)
				(thermal_bridge_width 0.5)
				(island_removal_mode 0)
			)
			(polygon
				(pts
					(xy 374.904 -87.9475) (xy 374.904 -87.5665) (xy 375.412 -87.5665) (xy 375.412 -87.9475)
				)
			)
		)
		(zone
			(layer "F.Cu")
			(hatch none 0.5)
			(connect_pads
				(clearance 0)
			)
			(min_thickness 0.25)
			(keepout
				(tracks not_allowed)
				(vias allowed)
				(pads allowed)
				(copperpour not_allowed)
				(footprints allowed)
			)
			(placement
				(enabled no)
				(sheetname "")
			)
			(fill
				(thermal_gap 0.5)
				(thermal_bridge_width 0.5)
				(island_removal_mode 0)
			)
			(polygon
				(pts
					(xy 374.904 -87.9475) (xy 374.904 -87.5665) (xy 375.412 -87.5665) (xy 375.412 -87.9475)
				)
			)
		)
	)
	(footprint ""
		(layer "F.Cu")
		(at 405.283416 -150.468584 90)
		(property "Reference" "C8A10"
			(at 0 0 90)
			(layer "F.SilkS")
			(hide yes)
			(effects
				(font
					(size 1.27 1.27)
				)
			)
		)
		(property "Value" ""
			(at 0 0 90)
			(layer "F.Fab")
			(effects
				(font
					(size 1.27 1.27)
				)
			)
		)
		(duplicate_pad_numbers_are_jumpers no)
		(fp_poly
			(pts
				(xy 0.3048 -0.1016) (xy 0.3048 0.9906) (xy -0.3048 0.9906) (xy -0.3048 -0.1016)
			)
			(stroke
				(width 0)
				(type default)
			)
			(fill no)
			(layer "F.CrtYd")
		)
		(fp_line
			(start 0.3048 -0.1016)
			(end -0.3048 -0.1016)
			(stroke
				(width 0.1)
				(type default)
			)
			(layer "F.Fab")
		)
		(fp_line
			(start -0.3048 -0.1016)
			(end -0.3048 0.9906)
			(stroke
				(width 0.1)
				(type default)
			)
			(layer "F.Fab")
		)
		(fp_line
			(start 0.3048 0.9906)
			(end 0.3048 -0.1016)
			(stroke
				(width 0.1)
				(type default)
			)
			(layer "F.Fab")
		)
		(fp_line
			(start -0.3048 0.9906)
			(end 0.3048 0.9906)
			(stroke
				(width 0.1)
				(type default)
			)
			(layer "F.Fab")
		)
		(pad "1" smd rect
			(at 0 0 90)
			(size 0.508 0.508)
			(layers "F.Cu" "F.Mask" "F.Paste")
			(net "PWRGD_P3V3_STBY")
		)
		(pad "2" smd rect
			(at 0 0.889 90)
			(size 0.508 0.508)
			(layers "F.Cu" "F.Mask" "F.Paste")
			(net "GND")
		)
		(zone
			(layer "F.Cu")
			(hatch none 0.5)
			(connect_pads
				(clearance 0)
			)
			(min_thickness 0.25)
			(keepout
				(tracks allowed)
				(vias not_allowed)
				(pads allowed)
				(copperpour not_allowed)
				(footprints allowed)
			)
			(placement
				(enabled no)
				(sheetname "")
			)
			(fill
				(thermal_gap 0.5)
				(thermal_bridge_width 0.5)
				(island_removal_mode 0)
			)
			(polygon
				(pts
					(xy 405.537416 -150.214584) (xy 405.537416 -150.722584) (xy 405.918416 -150.722584) (xy 405.918416 -150.214584)
				)
			)
		)
		(zone
			(layer "F.Cu")
			(hatch none 0.5)
			(connect_pads
				(clearance 0)
			)
			(min_thickness 0.25)
			(keepout
				(tracks not_allowed)
				(vias allowed)
				(pads allowed)
				(copperpour not_allowed)
				(footprints allowed)
			)
			(placement
				(enabled no)
				(sheetname "")
			)
			(fill
				(thermal_gap 0.5)
				(thermal_bridge_width 0.5)
				(island_removal_mode 0)
			)
			(polygon
				(pts
					(xy 405.918416 -150.214584) (xy 405.918416 -150.722584) (xy 405.537416 -150.722584) (xy 405.537416 -150.214584)
				)
			)
		)
	)
	(footprint ""
		(layer "F.Cu")
		(at 263.186672 -73.318116)
		(property "Reference" "C5D43"
			(at 0 0 0)
			(layer "F.SilkS")
			(hide yes)
			(effects
				(font
					(size 1.27 1.27)
				)
			)
		)
		(property "Value" ""
			(at 0 0 0)
			(layer "F.Fab")
			(effects
				(font
					(size 1.27 1.27)
				)
			)
		)
		(duplicate_pad_numbers_are_jumpers no)
		(fp_poly
			(pts
				(xy -0.4953 -0.2032) (xy 0.4953 -0.2032) (xy 0.4953 1.6002) (xy -0.4953 1.6002)
			)
			(stroke
				(width 0)
				(type default)
			)
			(fill no)
			(layer "F.CrtYd")
		)
		(fp_line
			(start -0.4953 -0.2032)
			(end 0.4953 -0.2032)
			(stroke
				(width 0.1)
				(type default)
			)
			(layer "F.Fab")
		)
		(fp_line
			(start -0.4953 1.6002)
			(end -0.4953 -0.2032)
			(stroke
				(width 0.1)
				(type default)
			)
			(layer "F.Fab")
		)
		(fp_line
			(start 0.4953 -0.2032)
			(end 0.4953 1.6002)
			(stroke
				(width 0.1)
				(type default)
			)
			(layer "F.Fab")
		)
		(fp_line
			(start 0.4953 1.6002)
			(end -0.4953 1.6002)
			(stroke
				(width 0.1)
				(type default)
			)
			(layer "F.Fab")
		)
		(pad "1" smd rect
			(at 0 0)
			(size 0.762 0.889)
			(layers "F.Cu" "F.Mask" "F.Paste")
			(net "PVCCIN_CPU0")
		)
		(pad "2" smd rect
			(at 0 1.397)
			(size 0.762 0.889)
			(layers "F.Cu" "F.Mask" "F.Paste")
			(net "GND")
		)
		(zone
			(layer "F.Cu")
			(hatch none 0.5)
			(connect_pads
				(clearance 0)
			)
			(min_thickness 0.25)
			(keepout
				(tracks not_allowed)
				(vias allowed)
				(pads allowed)
				(copperpour not_allowed)
				(footprints allowed)
			)
			(placement
				(enabled no)
				(sheetname "")
			)
			(fill
				(thermal_gap 0.5)
				(thermal_bridge_width 0.5)
				(island_removal_mode 0)
			)
			(polygon
				(pts
					(xy 262.805672 -72.873616) (xy 263.567672 -72.873616) (xy 263.567672 -72.365616) (xy 262.805672 -72.365616)
				)
			)
		)
	)
	(footprint ""
		(layer "F.Cu")
		(at 166.271448 -10.0711 90)
		(property "Reference" "R4G6"
			(at 0 0 90)
			(layer "F.SilkS")
			(hide yes)
			(effects
				(font
					(size 1.27 1.27)
				)
			)
		)
		(property "Value" ""
			(at 0 0 90)
			(layer "F.Fab")
			(effects
				(font
					(size 1.27 1.27)
				)
			)
		)
		(duplicate_pad_numbers_are_jumpers no)
		(fp_poly
			(pts
				(xy -0.4953 -0.2032) (xy 0.4953 -0.2032) (xy 0.4953 1.6002) (xy -0.4953 1.6002)
			)
			(stroke
				(width 0)
				(type default)
			)
			(fill no)
			(layer "F.CrtYd")
		)
		(fp_line
			(start 0.4953 -0.2032)
			(end 0.4953 1.6002)
			(stroke
				(width 0.1)
				(type default)
			)
			(layer "F.Fab")
		)
		(fp_line
			(start -0.4953 -0.2032)
			(end 0.4953 -0.2032)
			(stroke
				(width 0.1)
				(type default)
			)
			(layer "F.Fab")
		)
		(fp_line
			(start 0.4953 1.6002)
			(end -0.4953 1.6002)
			(stroke
				(width 0.1)
				(type default)
			)
			(layer "F.Fab")
		)
		(fp_line
			(start -0.4953 1.6002)
			(end -0.4953 -0.2032)
			(stroke
				(width 0.1)
				(type default)
			)
			(layer "F.Fab")
		)
		(pad "1" smd rect
			(at 0 0 90)
			(size 0.762 0.889)
			(layers "F.Cu" "F.Mask" "F.Paste")
			(net "PVPP_GHJ")
		)
		(pad "2" smd rect
			(at 0 1.397 90)
			(size 0.762 0.889)
			(layers "F.Cu" "F.Mask" "F.Paste")
			(net "GND")
		)
		(zone
			(layer "F.Cu")
			(hatch none 0.5)
			(connect_pads
				(clearance 0)
			)
			(min_thickness 0.25)
			(keepout
				(tracks allowed)
				(vias not_allowed)
				(pads allowed)
				(copperpour not_allowed)
				(footprints allowed)
			)
			(placement
				(enabled no)
				(sheetname "")
			)
			(fill
				(thermal_gap 0.5)
				(thermal_bridge_width 0.5)
				(island_removal_mode 0)
			)
			(polygon
				(pts
					(xy 167.223948 -10.4521) (xy 166.715948 -10.4521) (xy 166.715948 -9.6901) (xy 167.223948 -9.6901)
				)
			)
		)
		(zone
			(layer "F.Cu")
			(hatch none 0.5)
			(connect_pads
				(clearance 0)
			)
			(min_thickness 0.25)
			(keepout
				(tracks not_allowed)
				(vias allowed)
				(pads allowed)
				(copperpour not_allowed)
				(footprints allowed)
			)
			(placement
				(enabled no)
				(sheetname "")
			)
			(fill
				(thermal_gap 0.5)
				(thermal_bridge_width 0.5)
				(island_removal_mode 0)
			)
			(polygon
				(pts
					(xy 167.223948 -9.6901) (xy 167.223948 -10.4521) (xy 166.715948 -10.4521) (xy 166.715948 -9.6901)
				)
			)
		)
	)
	(footprint ""
		(layer "B.Cu")
		(at 488.244896 -55.856378)
		(property "Reference" "C30W8"
			(at 0 0 0)
			(layer "B.SilkS")
			(hide yes)
			(effects
				(font
					(size 1.27 1.27)
				)
				(justify mirror)
			)
		)
		(property "Value" "*"
			(at 0.0762 -6.2357 0)
			(unlocked yes)
			(layer "B.Fab")
			(hide yes)
			(effects
				(font
					(size 1.27 1.016)
					(thickness 0.1524)
				)
				(justify mirror)
			)
		)
		(property "Device Type" "SC22U16V5MX-4-GP_SMD-BCG5-SC22A"
			(at 0.0762 -8.2677 0)
			(unlocked yes)
			(layer "B.Fab")
			(hide yes)
			(effects
				(font
					(size 1.27 1.016)
					(thickness 0.1524)
				)
				(justify mirror)
			)
		)
		(duplicate_pad_numbers_are_jumpers no)
		(fp_line
			(start -0.635 0)
			(end 0.635 0)
			(stroke
				(width 0.508)
				(type default)
			)
			(layer "B.SilkS")
		)
		(fp_rect
			(start 0.9652 1.778)
			(end -0.9652 -1.778)
			(stroke
				(width 0)
				(type default)
			)
			(fill no)
			(layer "B.CrtYd")
		)
		(fp_poly
			(pts
				(xy 0.9652 -1.778) (xy -0.9652 -1.778) (xy -0.9652 1.778) (xy 0.9652 1.778)
			)
			(stroke
				(width 0)
				(type default)
			)
			(fill no)
			(layer "B.Fab")
		)
		(pad "1" smd rect
			(at 0 -0.9652 180)
			(size 1.397 1.143)
			(layers "B.Cu" "B.Mask" "B.Paste")
			(net "P5V_STBY_USBC")
		)
		(pad "2" smd rect
			(at 0 0.9652 180)
			(size 1.397 1.143)
			(layers "B.Cu" "B.Mask" "B.Paste")
			(net "GND")
		)
	)
	(footprint ""
		(layer "B.Cu")
		(at 406.892506 -32.6644 -90)
		(property "Reference" "R1T26"
			(at 0 0 90)
			(layer "B.SilkS")
			(hide yes)
			(effects
				(font
					(size 1.27 1.27)
				)
				(justify mirror)
			)
		)
		(property "Value" ""
			(at 0 0 90)
			(layer "B.Fab")
			(effects
				(font
					(size 1.27 1.27)
				)
				(justify mirror)
			)
		)
		(duplicate_pad_numbers_are_jumpers no)
		(fp_poly
			(pts
				(xy 0.2794 -0.1016) (xy -0.2794 -0.1016) (xy -0.2794 0.9906) (xy 0.2794 0.9906)
			)
			(stroke
				(width 0)
				(type default)
			)
			(fill no)
			(layer "B.CrtYd")
		)
		(fp_line
			(start -0.2794 0.9906)
			(end -0.2794 -0.1016)
			(stroke
				(width 0.1)
				(type default)
			)
			(layer "B.Fab")
		)
		(fp_line
			(start 0.2794 0.9906)
			(end -0.2794 0.9906)
			(stroke
				(width 0.1)
				(type default)
			)
			(layer "B.Fab")
		)
		(fp_line
			(start -0.2794 -0.1016)
			(end 0.2794 -0.1016)
			(stroke
				(width 0.1)
				(type default)
			)
			(layer "B.Fab")
		)
		(fp_line
			(start 0.2794 -0.1016)
			(end 0.2794 0.9906)
			(stroke
				(width 0.1)
				(type default)
			)
			(layer "B.Fab")
		)
		(pad "1" smd rect
			(at 0 0 90)
			(size 0.508 0.508)
			(layers "B.Cu" "B.Mask" "B.Paste")
			(net "A_USB2AVRES")
		)
		(pad "2" smd rect
			(at 0 0.889 90)
			(size 0.508 0.508)
			(layers "B.Cu" "B.Mask" "B.Paste")
			(net "GND")
		)
		(zone
			(layer "B.Cu")
			(hatch none 0.5)
			(connect_pads
				(clearance 0)
			)
			(min_thickness 0.25)
			(keepout
				(tracks not_allowed)
				(vias allowed)
				(pads allowed)
				(copperpour not_allowed)
				(footprints allowed)
			)
			(placement
				(enabled no)
				(sheetname "")
			)
			(fill
				(thermal_gap 0.5)
				(thermal_bridge_width 0.5)
				(island_removal_mode 0)
			)
			(polygon
				(pts
					(xy 406.257506 -32.4104) (xy 406.257506 -32.9184) (xy 406.638506 -32.9184) (xy 406.638506 -32.4104)
				)
			)
		)
		(zone
			(layer "B.Cu")
			(hatch none 0.5)
			(connect_pads
				(clearance 0)
			)
			(min_thickness 0.25)
			(keepout
				(tracks allowed)
				(vias not_allowed)
				(pads allowed)
				(copperpour not_allowed)
				(footprints allowed)
			)
			(placement
				(enabled no)
				(sheetname "")
			)
			(fill
				(thermal_gap 0.5)
				(thermal_bridge_width 0.5)
				(island_removal_mode 0)
			)
			(polygon
				(pts
					(xy 406.638506 -32.4104) (xy 406.638506 -32.9184) (xy 406.257506 -32.9184) (xy 406.257506 -32.4104)
				)
			)
		)
	)
	(footprint ""
		(layer "B.Cu")
		(at 388.154672 -154.721306)
		(property "Reference" "C3L10"
			(at 0 0 0)
			(layer "B.SilkS")
			(hide yes)
			(effects
				(font
					(size 1.27 1.27)
				)
				(justify mirror)
			)
		)
		(property "Value" ""
			(at 0 0 0)
			(layer "B.Fab")
			(effects
				(font
					(size 1.27 1.27)
				)
				(justify mirror)
			)
		)
		(duplicate_pad_numbers_are_jumpers no)
		(fp_poly
			(pts
				(xy 0.7239 -0.2159) (xy -0.7239 -0.2159) (xy -0.7239 1.9939) (xy 0.7239 1.9939)
			)
			(stroke
				(width 0)
				(type default)
			)
			(fill no)
			(layer "B.CrtYd")
		)
		(fp_line
			(start -0.7239 -0.2159)
			(end 0.7239 -0.2159)
			(stroke
				(width 0.1)
				(type default)
			)
			(layer "B.Fab")
		)
		(fp_line
			(start -0.7239 1.9939)
			(end -0.7239 -0.2159)
			(stroke
				(width 0.1)
				(type default)
			)
			(layer "B.Fab")
		)
		(fp_line
			(start 0.7239 -0.2159)
			(end 0.7239 1.9939)
			(stroke
				(width 0.1)
				(type default)
			)
			(layer "B.Fab")
		)
		(fp_line
			(start 0.7239 1.9939)
			(end -0.7239 1.9939)
			(stroke
				(width 0.1)
				(type default)
			)
			(layer "B.Fab")
		)
		(pad "1" smd rect
			(at 0 0 180)
			(size 1.27 1.016)
			(layers "B.Cu" "B.Mask" "B.Paste")
			(net "VR_FET_SW_P12V_STBY_PVDDQ_DEF")
		)
		(pad "2" smd rect
			(at 0 1.778 180)
			(size 1.27 1.016)
			(layers "B.Cu" "B.Mask" "B.Paste")
			(net "GND")
		)
		(zone
			(layer "B.Cu")
			(hatch none 0.5)
			(connect_pads
				(clearance 0)
			)
			(min_thickness 0.25)
			(keepout
				(tracks not_allowed)
				(vias allowed)
				(pads allowed)
				(copperpour not_allowed)
				(footprints allowed)
			)
			(placement
				(enabled no)
				(sheetname "")
			)
			(fill
				(thermal_gap 0.5)
				(thermal_bridge_width 0.5)
				(island_removal_mode 0)
			)
			(polygon
				(pts
					(xy 388.789672 -154.213306) (xy 387.519672 -154.213306) (xy 387.519672 -153.451306) (xy 388.789672 -153.451306)
				)
			)
		)
	)
	(footprint ""
		(layer "B.Cu")
		(at 262.206486 -73.51014)
		(property "Reference" "C5P35"
			(at 0 0 0)
			(layer "B.SilkS")
			(hide yes)
			(effects
				(font
					(size 1.27 1.27)
				)
				(justify mirror)
			)
		)
		(property "Value" ""
			(at 0 0 0)
			(layer "B.Fab")
			(effects
				(font
					(size 1.27 1.27)
				)
				(justify mirror)
			)
		)
		(duplicate_pad_numbers_are_jumpers no)
		(fp_poly
			(pts
				(xy 0.7239 -0.2159) (xy -0.7239 -0.2159) (xy -0.7239 1.9939) (xy 0.7239 1.9939)
			)
			(stroke
				(width 0)
				(type default)
			)
			(fill no)
			(layer "B.CrtYd")
		)
		(fp_line
			(start -0.7239 -0.2159)
			(end 0.7239 -0.2159)
			(stroke
				(width 0.1)
				(type default)
			)
			(layer "B.Fab")
		)
		(fp_line
			(start -0.7239 1.9939)
			(end -0.7239 -0.2159)
			(stroke
				(width 0.1)
				(type default)
			)
			(layer "B.Fab")
		)
		(fp_line
			(start 0.7239 -0.2159)
			(end 0.7239 1.9939)
			(stroke
				(width 0.1)
				(type default)
			)
			(layer "B.Fab")
		)
		(fp_line
			(start 0.7239 1.9939)
			(end -0.7239 1.9939)
			(stroke
				(width 0.1)
				(type default)
			)
			(layer "B.Fab")
		)
		(pad "1" smd rect
			(at 0 0 180)
			(size 1.27 1.016)
			(layers "B.Cu" "B.Mask" "B.Paste")
			(net "PVCCIN_CPU0")
		)
		(pad "2" smd rect
			(at 0 1.778 180)
			(size 1.27 1.016)
			(layers "B.Cu" "B.Mask" "B.Paste")
			(net "GND")
		)
		(zone
			(layer "B.Cu")
			(hatch none 0.5)
			(connect_pads
				(clearance 0)
			)
			(min_thickness 0.25)
			(keepout
				(tracks not_allowed)
				(vias allowed)
				(pads allowed)
				(copperpour not_allowed)
				(footprints allowed)
			)
			(placement
				(enabled no)
				(sheetname "")
			)
			(fill
				(thermal_gap 0.5)
				(thermal_bridge_width 0.5)
				(island_removal_mode 0)
			)
			(polygon
				(pts
					(xy 262.841486 -73.00214) (xy 261.571486 -73.00214) (xy 261.571486 -72.24014) (xy 262.841486 -72.24014)
				)
			)
		)
	)
	(footprint ""
		(layer "B.Cu")
		(at 409.6004 -147.955 -90)
		(property "Reference" "C2L21"
			(at 0 0 90)
			(layer "B.SilkS")
			(hide yes)
			(effects
				(font
					(size 1.27 1.27)
				)
				(justify mirror)
			)
		)
		(property "Value" ""
			(at 0 0 90)
			(layer "B.Fab")
			(effects
				(font
					(size 1.27 1.27)
				)
				(justify mirror)
			)
		)
		(duplicate_pad_numbers_are_jumpers no)
		(fp_poly
			(pts
				(xy -0.3048 -0.1016) (xy -0.3048 0.9906) (xy 0.3048 0.9906) (xy 0.3048 -0.1016)
			)
			(stroke
				(width 0)
				(type default)
			)
			(fill no)
			(layer "B.CrtYd")
		)
		(fp_line
			(start -0.3048 0.9906)
			(end -0.3048 -0.1016)
			(stroke
				(width 0.1)
				(type default)
			)
			(layer "B.Fab")
		)
		(fp_line
			(start 0.3048 0.9906)
			(end -0.3048 0.9906)
			(stroke
				(width 0.1)
				(type default)
			)
			(layer "B.Fab")
		)
		(fp_line
			(start -0.3048 -0.1016)
			(end 0.3048 -0.1016)
			(stroke
				(width 0.1)
				(type default)
			)
			(layer "B.Fab")
		)
		(fp_line
			(start 0.3048 -0.1016)
			(end 0.3048 0.9906)
			(stroke
				(width 0.1)
				(type default)
			)
			(layer "B.Fab")
		)
		(pad "1" smd rect
			(at 0 0 90)
			(size 0.508 0.508)
			(layers "B.Cu" "B.Mask" "B.Paste")
			(net "SATA6G_P7_TX_C_DN")
		)
		(pad "2" smd rect
			(at 0 0.889 90)
			(size 0.508 0.508)
			(layers "B.Cu" "B.Mask" "B.Paste")
			(net "SATA6G_PCH_PCIE_UP_SATA_TXN<7>")
		)
		(zone
			(layer "B.Cu")
			(hatch none 0.5)
			(connect_pads
				(clearance 0)
			)
			(min_thickness 0.25)
			(keepout
				(tracks not_allowed)
				(vias allowed)
				(pads allowed)
				(copperpour not_allowed)
				(footprints allowed)
			)
			(placement
				(enabled no)
				(sheetname "")
			)
			(fill
				(thermal_gap 0.5)
				(thermal_bridge_width 0.5)
				(island_removal_mode 0)
			)
			(polygon
				(pts
					(xy 408.9654 -147.701) (xy 408.9654 -148.209) (xy 409.3464 -148.209) (xy 409.3464 -147.701)
				)
			)
		)
		(zone
			(layer "B.Cu")
			(hatch none 0.5)
			(connect_pads
				(clearance 0)
			)
			(min_thickness 0.25)
			(keepout
				(tracks allowed)
				(vias not_allowed)
				(pads allowed)
				(copperpour not_allowed)
				(footprints allowed)
			)
			(placement
				(enabled no)
				(sheetname "")
			)
			(fill
				(thermal_gap 0.5)
				(thermal_bridge_width 0.5)
				(island_removal_mode 0)
			)
			(polygon
				(pts
					(xy 409.3464 -147.701) (xy 409.3464 -148.209) (xy 408.9654 -148.209) (xy 408.9654 -147.701)
				)
			)
		)
	)
	(footprint ""
		(layer "B.Cu")
		(at 221.488 -28.194)
		(property "Reference" ""
			(at 0 0 0)
			(layer "B.SilkS")
			(hide yes)
			(effects
				(font
					(size 1.27 1.27)
				)
				(justify mirror)
			)
		)
		(property "Value" ""
			(at 0 0 0)
			(layer "B.Fab")
			(effects
				(font
					(size 1.27 1.27)
				)
				(justify mirror)
			)
		)
		(duplicate_pad_numbers_are_jumpers no)
		(fp_poly
			(pts
				(arc
					(start 2.032 0)
					(mid -2.032 0)
					(end 2.032 0)
				)
			)
			(stroke
				(width 0)
				(type default)
			)
			(fill no)
			(layer "B.CrtYd")
		)
		(pad "1" smd circle
			(at 0 0 180)
			(size 1.016 1.016)
			(layers "B.Cu" "B.Mask" "B.Paste")
			(net "Net_396")
		)
		(zone
			(layers "F.Cu" "B.Cu" "In1.Cu" "In2.Cu" "In3.Cu" "In4.Cu" "In5.Cu" "In6.Cu"
				"In7.Cu" "In8.Cu" "In9.Cu" "In10.Cu" "In11.Cu" "In12.Cu"
			)
			(hatch none 0.5)
			(connect_pads
				(clearance 0)
			)
			(min_thickness 0.25)
			(keepout
				(tracks allowed)
				(vias not_allowed)
				(pads allowed)
				(copperpour not_allowed)
				(footprints allowed)
			)
			(placement
				(enabled no)
				(sheetname "")
			)
			(fill
				(thermal_gap 0.5)
				(thermal_bridge_width 0.5)
				(island_removal_mode 0)
			)
			(polygon
				(pts
					(arc
						(start 223.012 -28.194)
						(mid 219.964 -28.194)
						(end 223.012 -28.194)
					)
				)
			)
		)
		(zone
			(layer "B.Cu")
			(hatch none 0.5)
			(connect_pads
				(clearance 0)
			)
			(min_thickness 0.25)
			(keepout
				(tracks not_allowed)
				(vias allowed)
				(pads allowed)
				(copperpour not_allowed)
				(footprints allowed)
			)
			(placement
				(enabled no)
				(sheetname "")
			)
			(fill
				(thermal_gap 0.5)
				(thermal_bridge_width 0.5)
				(island_removal_mode 0)
			)
			(polygon
				(pts
					(arc
						(start 223.012 -28.194)
						(mid 219.964 -28.194)
						(end 223.012 -28.194)
					)
				)
			)
		)
	)
	(footprint ""
		(layer "B.Cu")
		(at 116.332 -74.93 90)
		(property "Reference" "R7P15"
			(at 0 0 90)
			(layer "B.SilkS")
			(hide yes)
			(effects
				(font
					(size 1.27 1.27)
				)
				(justify mirror)
			)
		)
		(property "Value" ""
			(at 0 0 90)
			(layer "B.Fab")
			(effects
				(font
					(size 1.27 1.27)
				)
				(justify mirror)
			)
		)
		(duplicate_pad_numbers_are_jumpers no)
		(fp_poly
			(pts
				(xy 0.2794 -0.1016) (xy -0.2794 -0.1016) (xy -0.2794 0.9906) (xy 0.2794 0.9906)
			)
			(stroke
				(width 0)
				(type default)
			)
			(fill no)
			(layer "B.CrtYd")
		)
		(fp_line
			(start 0.2794 -0.1016)
			(end 0.2794 0.9906)
			(stroke
				(width 0.1)
				(type default)
			)
			(layer "B.Fab")
		)
		(fp_line
			(start -0.2794 -0.1016)
			(end 0.2794 -0.1016)
			(stroke
				(width 0.1)
				(type default)
			)
			(layer "B.Fab")
		)
		(fp_line
			(start 0.2794 0.9906)
			(end -0.2794 0.9906)
			(stroke
				(width 0.1)
				(type default)
			)
			(layer "B.Fab")
		)
		(fp_line
			(start -0.2794 0.9906)
			(end -0.2794 -0.1016)
			(stroke
				(width 0.1)
				(type default)
			)
			(layer "B.Fab")
		)
		(pad "1" smd rect
			(at 0 0 270)
			(size 0.508 0.508)
			(layers "B.Cu" "B.Mask" "B.Paste")
			(net "GND")
		)
		(pad "2" smd rect
			(at 0 0.889 270)
			(size 0.508 0.508)
			(layers "B.Cu" "B.Mask" "B.Paste")
			(net "PD_CPU1_KSFC_DIS")
		)
		(zone
			(layer "B.Cu")
			(hatch none 0.5)
			(connect_pads
				(clearance 0)
			)
			(min_thickness 0.25)
			(keepout
				(tracks allowed)
				(vias not_allowed)
				(pads allowed)
				(copperpour not_allowed)
				(footprints allowed)
			)
			(placement
				(enabled no)
				(sheetname "")
			)
			(fill
				(thermal_gap 0.5)
				(thermal_bridge_width 0.5)
				(island_removal_mode 0)
			)
			(polygon
				(pts
					(xy 116.586 -75.184) (xy 116.586 -74.676) (xy 116.967 -74.676) (xy 116.967 -75.184)
				)
			)
		)
		(zone
			(layer "B.Cu")
			(hatch none 0.5)
			(connect_pads
				(clearance 0)
			)
			(min_thickness 0.25)
			(keepout
				(tracks not_allowed)
				(vias allowed)
				(pads allowed)
				(copperpour not_allowed)
				(footprints allowed)
			)
			(placement
				(enabled no)
				(sheetname "")
			)
			(fill
				(thermal_gap 0.5)
				(thermal_bridge_width 0.5)
				(island_removal_mode 0)
			)
			(polygon
				(pts
					(xy 116.967 -75.184) (xy 116.967 -74.676) (xy 116.586 -74.676) (xy 116.586 -75.184)
				)
			)
		)
	)
	(footprint ""
		(layer "B.Cu")
		(at 492.4044 -116.082318)
		(property "Reference" "R9B7"
			(at 0 0 0)
			(layer "B.SilkS")
			(hide yes)
			(effects
				(font
					(size 1.27 1.27)
				)
				(justify mirror)
			)
		)
		(property "Value" "*"
			(at -0.064008 -4.108196 0)
			(unlocked yes)
			(layer "B.Fab")
			(hide yes)
			(effects
				(font
					(size 1.27 1.016)
					(thickness 0.1524)
				)
				(justify mirror)
			)
		)
		(property "Device Type" "887R2F-L-GP_SMD-RG-887R2F-L-GPA"
			(at -0.064008 -5.632196 0)
			(unlocked yes)
			(layer "B.Fab")
			(hide yes)
			(effects
				(font
					(size 1.27 1.016)
					(thickness 0.1524)
				)
				(justify mirror)
			)
		)
		(duplicate_pad_numbers_are_jumpers no)
		(fp_line
			(start -0.508 -0.9398)
			(end 0.508 -0.9398)
			(stroke
				(width 0.1524)
				(type default)
			)
			(layer "B.SilkS")
		)
		(fp_line
			(start 0.508 -0.9398)
			(end 0.508 0.9398)
			(stroke
				(width 0.1524)
				(type default)
			)
			(layer "B.SilkS")
		)
		(fp_rect
			(start 0.508 0.9398)
			(end -0.508 -0.9398)
			(stroke
				(width 0)
				(type default)
			)
			(fill no)
			(layer "B.CrtYd")
		)
		(fp_rect
			(start 0.508 0.9398)
			(end -0.508 -0.9398)
			(stroke
				(width 0)
				(type default)
			)
			(fill no)
			(layer "B.Fab")
		)
		(pad "1" smd custom
			(at 0 -0.4445 180)
			(size 0.1397 0.1397)
			(layers "B.Cu" "B.Mask" "B.Paste")
			(net "FM_MEZZA_PRSNT1_N")
			(options
				(clearance outline)
				(anchor circle)
			)
			(primitives
				(gr_poly
					(pts
						(arc
							(start -0.1778 0.2794)
							(mid -0.249642 0.249642)
							(end -0.2794 0.1778)
						)
						(arc
							(start -0.2794 -0.1778)
							(mid -0.249642 -0.249642)
							(end -0.1778 -0.2794)
						)
						(arc
							(start 0.1778 -0.2794)
							(mid 0.249642 -0.249642)
							(end 0.2794 -0.1778)
						)
						(arc
							(start 0.2794 0.1778)
							(mid 0.249642 0.249642)
							(end 0.1778 0.2794)
						)
					)
					(width 0)
					(fill yes)
				)
			)
		)
		(pad "2" smd custom
			(at 0 0.4445 180)
			(size 0.1397 0.1397)
			(layers "B.Cu" "B.Mask" "B.Paste")
			(net "GND")
			(options
				(clearance outline)
				(anchor circle)
			)
			(primitives
				(gr_poly
					(pts
						(arc
							(start -0.1778 0.2794)
							(mid -0.249642 0.249642)
							(end -0.2794 0.1778)
						)
						(arc
							(start -0.2794 -0.1778)
							(mid -0.249642 -0.249642)
							(end -0.1778 -0.2794)
						)
						(arc
							(start 0.1778 -0.2794)
							(mid 0.249642 -0.249642)
							(end 0.2794 -0.1778)
						)
						(arc
							(start 0.2794 0.1778)
							(mid 0.249642 0.249642)
							(end 0.1778 0.2794)
						)
					)
					(width 0)
					(fill yes)
				)
			)
		)
	)
	(footprint ""
		(layer "B.Cu")
		(at 487.045 -140.8176 90)
		(property "Reference" "R1L36"
			(at 0 0 90)
			(layer "B.SilkS")
			(hide yes)
			(effects
				(font
					(size 1.27 1.27)
				)
				(justify mirror)
			)
		)
		(property "Value" ""
			(at 0 0 90)
			(layer "B.Fab")
			(effects
				(font
					(size 1.27 1.27)
				)
				(justify mirror)
			)
		)
		(duplicate_pad_numbers_are_jumpers no)
		(fp_poly
			(pts
				(xy 0.2794 -0.1016) (xy -0.2794 -0.1016) (xy -0.2794 0.9906) (xy 0.2794 0.9906)
			)
			(stroke
				(width 0)
				(type default)
			)
			(fill no)
			(layer "B.CrtYd")
		)
		(fp_line
			(start 0.2794 -0.1016)
			(end 0.2794 0.9906)
			(stroke
				(width 0.1)
				(type default)
			)
			(layer "B.Fab")
		)
		(fp_line
			(start -0.2794 -0.1016)
			(end 0.2794 -0.1016)
			(stroke
				(width 0.1)
				(type default)
			)
			(layer "B.Fab")
		)
		(fp_line
			(start 0.2794 0.9906)
			(end -0.2794 0.9906)
			(stroke
				(width 0.1)
				(type default)
			)
			(layer "B.Fab")
		)
		(fp_line
			(start -0.2794 0.9906)
			(end -0.2794 -0.1016)
			(stroke
				(width 0.1)
				(type default)
			)
			(layer "B.Fab")
		)
		(pad "1" smd rect
			(at 0 0 270)
			(size 0.508 0.508)
			(layers "B.Cu" "B.Mask" "B.Paste")
			(net "P3V3_STBY")
		)
		(pad "2" smd rect
			(at 0 0.889 270)
			(size 0.508 0.508)
			(layers "B.Cu" "B.Mask" "B.Paste")
			(net "FM_DB_PRESENT")
		)
		(zone
			(layer "B.Cu")
			(hatch none 0.5)
			(connect_pads
				(clearance 0)
			)
			(min_thickness 0.25)
			(keepout
				(tracks allowed)
				(vias not_allowed)
				(pads allowed)
				(copperpour not_allowed)
				(footprints allowed)
			)
			(placement
				(enabled no)
				(sheetname "")
			)
			(fill
				(thermal_gap 0.5)
				(thermal_bridge_width 0.5)
				(island_removal_mode 0)
			)
			(polygon
				(pts
					(xy 487.299 -141.0716) (xy 487.299 -140.5636) (xy 487.68 -140.5636) (xy 487.68 -141.0716)
				)
			)
		)
		(zone
			(layer "B.Cu")
			(hatch none 0.5)
			(connect_pads
				(clearance 0)
			)
			(min_thickness 0.25)
			(keepout
				(tracks not_allowed)
				(vias allowed)
				(pads allowed)
				(copperpour not_allowed)
				(footprints allowed)
			)
			(placement
				(enabled no)
				(sheetname "")
			)
			(fill
				(thermal_gap 0.5)
				(thermal_bridge_width 0.5)
				(island_removal_mode 0)
			)
			(polygon
				(pts
					(xy 487.68 -141.0716) (xy 487.68 -140.5636) (xy 487.299 -140.5636) (xy 487.299 -141.0716)
				)
			)
		)
	)
	(footprint ""
		(layer "B.Cu")
		(at 389.33755 -106.25455 180)
		(property "Reference" "C2N16"
			(at 0 0 0)
			(layer "B.SilkS")
			(hide yes)
			(effects
				(font
					(size 1.27 1.27)
				)
				(justify mirror)
			)
		)
		(property "Value" ""
			(at 0 0 0)
			(layer "B.Fab")
			(effects
				(font
					(size 1.27 1.27)
				)
				(justify mirror)
			)
		)
		(duplicate_pad_numbers_are_jumpers no)
		(fp_rect
			(start 0.2794 0.9144)
			(end -0.2794 -0.1143)
			(stroke
				(width 0)
				(type default)
			)
			(fill no)
			(layer "B.CrtYd")
		)
		(fp_line
			(start 0.2794 0.9144)
			(end 0.2794 -0.1143)
			(stroke
				(width 0.1)
				(type default)
			)
			(layer "B.Fab")
		)
		(fp_line
			(start 0.2794 -0.1143)
			(end -0.2794 -0.1143)
			(stroke
				(width 0.1)
				(type default)
			)
			(layer "B.Fab")
		)
		(fp_line
			(start -0.2794 0.9144)
			(end 0.2794 0.9144)
			(stroke
				(width 0.1)
				(type default)
			)
			(layer "B.Fab")
		)
		(fp_line
			(start -0.2794 -0.1143)
			(end -0.2794 0.9144)
			(stroke
				(width 0.1)
				(type default)
			)
			(layer "B.Fab")
		)
		(pad "1" smd custom
			(at 0 0 90)
			(size 0.10414 0.10414)
			(layers "B.Cu" "B.Mask" "B.Paste")
			(net "P1V8_PCH_STBY")
			(options
				(clearance outline)
				(anchor circle)
			)
			(primitives
				(gr_poly
					(pts
						(xy -0.20828 -0.08636) (xy -0.20828 0.08636) (xy -0.08636 0.20828) (xy 0.086614 0.20828) (xy 0.20828 0.086614)
						(xy 0.20828 -0.08636) (xy 0.08636 -0.20828) (xy -0.08636 -0.20828)
					)
					(width 0)
					(fill yes)
				)
			)
		)
		(pad "2" smd custom
			(at 0 0.8001 90)
			(size 0.10414 0.10414)
			(layers "B.Cu" "B.Mask" "B.Paste")
			(net "GND")
			(options
				(clearance outline)
				(anchor circle)
			)
			(primitives
				(gr_poly
					(pts
						(xy -0.20828 -0.08636) (xy -0.20828 0.08636) (xy -0.08636 0.20828) (xy 0.086614 0.20828) (xy 0.20828 0.086614)
						(xy 0.20828 -0.08636) (xy 0.08636 -0.20828) (xy -0.08636 -0.20828)
					)
					(width 0)
					(fill yes)
				)
			)
		)
		(zone
			(layer "B.Cu")
			(hatch none 0.5)
			(connect_pads
				(clearance 0)
			)
			(min_thickness 0.25)
			(keepout
				(tracks allowed)
				(vias not_allowed)
				(pads allowed)
				(copperpour not_allowed)
				(footprints allowed)
			)
			(placement
				(enabled no)
				(sheetname "")
			)
			(fill
				(thermal_gap 0.5)
				(thermal_bridge_width 0.5)
				(island_removal_mode 0)
			)
			(polygon
				(pts
					(xy 389.24992 -106.4641) (xy 389.24992 -106.8451) (xy 389.42518 -106.8451) (xy 389.425434 -106.4641)
				)
			)
		)
		(zone
			(layer "B.Cu")
			(hatch none 0.5)
			(connect_pads
				(clearance 0)
			)
			(min_thickness 0.25)
			(keepout
				(tracks not_allowed)
				(vias allowed)
				(pads allowed)
				(copperpour not_allowed)
				(footprints allowed)
			)
			(placement
				(enabled no)
				(sheetname "")
			)
			(fill
				(thermal_gap 0.5)
				(thermal_bridge_width 0.5)
				(island_removal_mode 0)
			)
			(polygon
				(pts
					(xy 389.24992 -106.4641) (xy 389.24992 -106.8451) (xy 389.42518 -106.8451) (xy 389.425434 -106.4641)
				)
			)
		)
	)
	(footprint ""
		(layer "B.Cu")
		(at 416.30092 -37.20338 -90)
		(property "Reference" "C25W26"
			(at 0.8382 -0.67818 270)
			(unlocked yes)
			(layer "B.SilkS")
			(effects
				(font
					(size 0.4064 0.254)
					(thickness 0.1524)
				)
				(justify left mirror)
			)
		)
		(property "Value" ""
			(at 0 0 90)
			(layer "B.Fab")
			(effects
				(font
					(size 1.27 1.27)
				)
				(justify mirror)
			)
		)
		(duplicate_pad_numbers_are_jumpers no)
		(fp_poly
			(pts
				(xy -0.3048 -0.1016) (xy -0.3048 0.9906) (xy 0.3048 0.9906) (xy 0.3048 -0.1016)
			)
			(stroke
				(width 0)
				(type default)
			)
			(fill no)
			(layer "B.CrtYd")
		)
		(fp_line
			(start -0.3048 0.9906)
			(end -0.3048 -0.1016)
			(stroke
				(width 0.1)
				(type default)
			)
			(layer "B.Fab")
		)
		(fp_line
			(start 0.3048 0.9906)
			(end -0.3048 0.9906)
			(stroke
				(width 0.1)
				(type default)
			)
			(layer "B.Fab")
		)
		(fp_line
			(start -0.3048 -0.1016)
			(end 0.3048 -0.1016)
			(stroke
				(width 0.1)
				(type default)
			)
			(layer "B.Fab")
		)
		(fp_line
			(start 0.3048 -0.1016)
			(end 0.3048 0.9906)
			(stroke
				(width 0.1)
				(type default)
			)
			(layer "B.Fab")
		)
		(pad "1" smd rect
			(at 0 0 90)
			(size 0.508 0.508)
			(layers "B.Cu" "B.Mask" "B.Paste")
			(net "P1V15_AUX_BMC")
		)
		(pad "2" smd rect
			(at 0 0.889 90)
			(size 0.508 0.508)
			(layers "B.Cu" "B.Mask" "B.Paste")
			(net "GND")
		)
		(zone
			(layer "B.Cu")
			(hatch none 0.5)
			(connect_pads
				(clearance 0)
			)
			(min_thickness 0.25)
			(keepout
				(tracks not_allowed)
				(vias allowed)
				(pads allowed)
				(copperpour not_allowed)
				(footprints allowed)
			)
			(placement
				(enabled no)
				(sheetname "")
			)
			(fill
				(thermal_gap 0.5)
				(thermal_bridge_width 0.5)
				(island_removal_mode 0)
			)
			(polygon
				(pts
					(xy 415.66592 -36.94938) (xy 415.66592 -37.45738) (xy 416.04692 -37.45738) (xy 416.04692 -36.94938)
				)
			)
		)
		(zone
			(layer "B.Cu")
			(hatch none 0.5)
			(connect_pads
				(clearance 0)
			)
			(min_thickness 0.25)
			(keepout
				(tracks allowed)
				(vias not_allowed)
				(pads allowed)
				(copperpour not_allowed)
				(footprints allowed)
			)
			(placement
				(enabled no)
				(sheetname "")
			)
			(fill
				(thermal_gap 0.5)
				(thermal_bridge_width 0.5)
				(island_removal_mode 0)
			)
			(polygon
				(pts
					(xy 416.04692 -36.94938) (xy 416.04692 -37.45738) (xy 415.66592 -37.45738) (xy 415.66592 -36.94938)
				)
			)
		)
	)
	(footprint ""
		(layer "B.Cu")
		(at 193.8528 -102.6668 180)
		(property "Reference" "R6N14"
			(at 0 0 0)
			(layer "B.SilkS")
			(hide yes)
			(effects
				(font
					(size 1.27 1.27)
				)
				(justify mirror)
			)
		)
		(property "Value" ""
			(at 0 0 0)
			(layer "B.Fab")
			(effects
				(font
					(size 1.27 1.27)
				)
				(justify mirror)
			)
		)
		(duplicate_pad_numbers_are_jumpers no)
		(fp_poly
			(pts
				(xy 0.2794 -0.1016) (xy -0.2794 -0.1016) (xy -0.2794 0.9906) (xy 0.2794 0.9906)
			)
			(stroke
				(width 0)
				(type default)
			)
			(fill no)
			(layer "B.CrtYd")
		)
		(fp_line
			(start 0.2794 0.9906)
			(end -0.2794 0.9906)
			(stroke
				(width 0.1)
				(type default)
			)
			(layer "B.Fab")
		)
		(fp_line
			(start 0.2794 -0.1016)
			(end 0.2794 0.9906)
			(stroke
				(width 0.1)
				(type default)
			)
			(layer "B.Fab")
		)
		(fp_line
			(start -0.2794 0.9906)
			(end -0.2794 -0.1016)
			(stroke
				(width 0.1)
				(type default)
			)
			(layer "B.Fab")
		)
		(fp_line
			(start -0.2794 -0.1016)
			(end 0.2794 -0.1016)
			(stroke
				(width 0.1)
				(type default)
			)
			(layer "B.Fab")
		)
		(pad "1" smd rect
			(at 0 0)
			(size 0.508 0.508)
			(layers "B.Cu" "B.Mask" "B.Paste")
			(net "GND")
		)
		(pad "2" smd rect
			(at 0 0.889)
			(size 0.508 0.508)
			(layers "B.Cu" "B.Mask" "B.Paste")
			(net "PD_PIROM_CPU0_ADDR0")
		)
		(zone
			(layer "B.Cu")
			(hatch none 0.5)
			(connect_pads
				(clearance 0)
			)
			(min_thickness 0.25)
			(keepout
				(tracks not_allowed)
				(vias allowed)
				(pads allowed)
				(copperpour not_allowed)
				(footprints allowed)
			)
			(placement
				(enabled no)
				(sheetname "")
			)
			(fill
				(thermal_gap 0.5)
				(thermal_bridge_width 0.5)
				(island_removal_mode 0)
			)
			(polygon
				(pts
					(xy 193.5988 -103.3018) (xy 194.1068 -103.3018) (xy 194.1068 -102.9208) (xy 193.5988 -102.9208)
				)
			)
		)
		(zone
			(layer "B.Cu")
			(hatch none 0.5)
			(connect_pads
				(clearance 0)
			)
			(min_thickness 0.25)
			(keepout
				(tracks allowed)
				(vias not_allowed)
				(pads allowed)
				(copperpour not_allowed)
				(footprints allowed)
			)
			(placement
				(enabled no)
				(sheetname "")
			)
			(fill
				(thermal_gap 0.5)
				(thermal_bridge_width 0.5)
				(island_removal_mode 0)
			)
			(polygon
				(pts
					(xy 193.5988 -102.9208) (xy 194.1068 -102.9208) (xy 194.1068 -103.3018) (xy 193.5988 -103.3018)
				)
			)
		)
	)
	(footprint ""
		(layer "B.Cu")
		(at 446.381632 -34.7345 90)
		(property "Reference" "R25W22"
			(at 0 0 90)
			(layer "B.SilkS")
			(hide yes)
			(effects
				(font
					(size 1.27 1.27)
				)
				(justify mirror)
			)
		)
		(property "Value" "*"
			(at -0.064008 -4.108196 90)
			(unlocked yes)
			(layer "B.Fab")
			(hide yes)
			(effects
				(font
					(size 1.27 1.016)
					(thickness 0.1524)
				)
				(justify mirror)
			)
		)
		(property "Device Type" "120R2F-GP_RCL_GP-120R2F-GP,64.A"
			(at -0.064008 -5.632196 90)
			(unlocked yes)
			(layer "B.Fab")
			(hide yes)
			(effects
				(font
					(size 1.27 1.016)
					(thickness 0.1524)
				)
				(justify mirror)
			)
		)
		(duplicate_pad_numbers_are_jumpers no)
		(fp_line
			(start 0.508 -0.9398)
			(end 0.508 0.9398)
			(stroke
				(width 0.1524)
				(type default)
			)
			(layer "B.SilkS")
		)
		(fp_line
			(start -0.508 -0.9398)
			(end 0.508 -0.9398)
			(stroke
				(width 0.1524)
				(type default)
			)
			(layer "B.SilkS")
		)
		(fp_rect
			(start 0.508 0.9398)
			(end -0.508 -0.9398)
			(stroke
				(width 0)
				(type default)
			)
			(fill no)
			(layer "B.CrtYd")
		)
		(fp_rect
			(start 0.508 0.9398)
			(end -0.508 -0.9398)
			(stroke
				(width 0)
				(type default)
			)
			(fill no)
			(layer "B.Fab")
		)
		(pad "1" smd custom
			(at 0 -0.4445 270)
			(size 0.1397 0.1397)
			(layers "B.Cu" "B.Mask" "B.Paste")
			(net "GND")
			(options
				(clearance outline)
				(anchor circle)
			)
			(primitives
				(gr_poly
					(pts
						(arc
							(start -0.1778 0.2794)
							(mid -0.249642 0.249642)
							(end -0.2794 0.1778)
						)
						(arc
							(start -0.2794 -0.1778)
							(mid -0.249642 -0.249642)
							(end -0.1778 -0.2794)
						)
						(arc
							(start 0.1778 -0.2794)
							(mid 0.249642 -0.249642)
							(end 0.2794 -0.1778)
						)
						(arc
							(start 0.2794 0.1778)
							(mid 0.249642 0.249642)
							(end 0.1778 0.2794)
						)
					)
					(width 0)
					(fill yes)
				)
			)
		)
		(pad "2" smd custom
			(at 0 0.4445 270)
			(size 0.1397 0.1397)
			(layers "B.Cu" "B.Mask" "B.Paste")
			(net "BMC_M_A10")
			(options
				(clearance outline)
				(anchor circle)
			)
			(primitives
				(gr_poly
					(pts
						(arc
							(start -0.1778 0.2794)
							(mid -0.249642 0.249642)
							(end -0.2794 0.1778)
						)
						(arc
							(start -0.2794 -0.1778)
							(mid -0.249642 -0.249642)
							(end -0.1778 -0.2794)
						)
						(arc
							(start 0.1778 -0.2794)
							(mid 0.249642 -0.249642)
							(end 0.2794 -0.1778)
						)
						(arc
							(start 0.2794 0.1778)
							(mid 0.249642 0.249642)
							(end 0.1778 0.2794)
						)
					)
					(width 0)
					(fill yes)
				)
			)
		)
	)
	(footprint ""
		(layer "B.Cu")
		(at 412.186882 -106.565192 90)
		(property "Reference" "R7W22"
			(at 0.8382 -0.67818 90)
			(unlocked yes)
			(layer "B.SilkS")
			(effects
				(font
					(size 0.4064 0.254)
					(thickness 0.1524)
				)
				(justify left mirror)
			)
		)
		(property "Value" ""
			(at 0 0 90)
			(layer "B.Fab")
			(effects
				(font
					(size 1.27 1.27)
				)
				(justify mirror)
			)
		)
		(duplicate_pad_numbers_are_jumpers no)
		(fp_poly
			(pts
				(xy 0.2794 -0.1016) (xy -0.2794 -0.1016) (xy -0.2794 0.9906) (xy 0.2794 0.9906)
			)
			(stroke
				(width 0)
				(type default)
			)
			(fill no)
			(layer "B.CrtYd")
		)
		(fp_line
			(start 0.2794 -0.1016)
			(end 0.2794 0.9906)
			(stroke
				(width 0.1)
				(type default)
			)
			(layer "B.Fab")
		)
		(fp_line
			(start -0.2794 -0.1016)
			(end 0.2794 -0.1016)
			(stroke
				(width 0.1)
				(type default)
			)
			(layer "B.Fab")
		)
		(fp_line
			(start 0.2794 0.9906)
			(end -0.2794 0.9906)
			(stroke
				(width 0.1)
				(type default)
			)
			(layer "B.Fab")
		)
		(fp_line
			(start -0.2794 0.9906)
			(end -0.2794 -0.1016)
			(stroke
				(width 0.1)
				(type default)
			)
			(layer "B.Fab")
		)
		(pad "1" smd rect
			(at 0 0 270)
			(size 0.508 0.508)
			(layers "B.Cu" "B.Mask" "B.Paste")
			(net "P3V3_STBY")
		)
		(pad "2" smd rect
			(at 0 0.889 270)
			(size 0.508 0.508)
			(layers "B.Cu" "B.Mask" "B.Paste")
			(net "FM_BMC_ENABLE_N")
		)
		(zone
			(layer "B.Cu")
			(hatch none 0.5)
			(connect_pads
				(clearance 0)
			)
			(min_thickness 0.25)
			(keepout
				(tracks allowed)
				(vias not_allowed)
				(pads allowed)
				(copperpour not_allowed)
				(footprints allowed)
			)
			(placement
				(enabled no)
				(sheetname "")
			)
			(fill
				(thermal_gap 0.5)
				(thermal_bridge_width 0.5)
				(island_removal_mode 0)
			)
			(polygon
				(pts
					(xy 412.440882 -106.819192) (xy 412.440882 -106.311192) (xy 412.821882 -106.311192) (xy 412.821882 -106.819192)
				)
			)
		)
		(zone
			(layer "B.Cu")
			(hatch none 0.5)
			(connect_pads
				(clearance 0)
			)
			(min_thickness 0.25)
			(keepout
				(tracks not_allowed)
				(vias allowed)
				(pads allowed)
				(copperpour not_allowed)
				(footprints allowed)
			)
			(placement
				(enabled no)
				(sheetname "")
			)
			(fill
				(thermal_gap 0.5)
				(thermal_bridge_width 0.5)
				(island_removal_mode 0)
			)
			(polygon
				(pts
					(xy 412.821882 -106.819192) (xy 412.821882 -106.311192) (xy 412.440882 -106.311192) (xy 412.440882 -106.819192)
				)
			)
		)
	)
	(footprint ""
		(layer "B.Cu")
		(at 407.5176 -29.4132 180)
		(property "Reference" "R25W149"
			(at 0.8382 -0.67818 180)
			(unlocked yes)
			(layer "B.SilkS")
			(effects
				(font
					(size 0.4064 0.254)
					(thickness 0.1524)
				)
				(justify left mirror)
			)
		)
		(property "Value" ""
			(at 0 0 0)
			(layer "B.Fab")
			(effects
				(font
					(size 1.27 1.27)
				)
				(justify mirror)
			)
		)
		(duplicate_pad_numbers_are_jumpers no)
		(fp_poly
			(pts
				(xy 0.2794 -0.1016) (xy -0.2794 -0.1016) (xy -0.2794 0.9906) (xy 0.2794 0.9906)
			)
			(stroke
				(width 0)
				(type default)
			)
			(fill no)
			(layer "B.CrtYd")
		)
		(fp_line
			(start 0.2794 0.9906)
			(end -0.2794 0.9906)
			(stroke
				(width 0.1)
				(type default)
			)
			(layer "B.Fab")
		)
		(fp_line
			(start 0.2794 -0.1016)
			(end 0.2794 0.9906)
			(stroke
				(width 0.1)
				(type default)
			)
			(layer "B.Fab")
		)
		(fp_line
			(start -0.2794 0.9906)
			(end -0.2794 -0.1016)
			(stroke
				(width 0.1)
				(type default)
			)
			(layer "B.Fab")
		)
		(fp_line
			(start -0.2794 -0.1016)
			(end 0.2794 -0.1016)
			(stroke
				(width 0.1)
				(type default)
			)
			(layer "B.Fab")
		)
		(pad "1" smd rect
			(at 0 0)
			(size 0.508 0.508)
			(layers "B.Cu" "B.Mask" "B.Paste")
			(net "GND")
		)
		(pad "2" smd rect
			(at 0 0.889)
			(size 0.508 0.508)
			(layers "B.Cu" "B.Mask" "B.Paste")
			(net "TP_RGMII1TXD2_GPIOT4")
		)
		(zone
			(layer "B.Cu")
			(hatch none 0.5)
			(connect_pads
				(clearance 0)
			)
			(min_thickness 0.25)
			(keepout
				(tracks not_allowed)
				(vias allowed)
				(pads allowed)
				(copperpour not_allowed)
				(footprints allowed)
			)
			(placement
				(enabled no)
				(sheetname "")
			)
			(fill
				(thermal_gap 0.5)
				(thermal_bridge_width 0.5)
				(island_removal_mode 0)
			)
			(polygon
				(pts
					(xy 407.2636 -30.0482) (xy 407.7716 -30.0482) (xy 407.7716 -29.6672) (xy 407.2636 -29.6672)
				)
			)
		)
		(zone
			(layer "B.Cu")
			(hatch none 0.5)
			(connect_pads
				(clearance 0)
			)
			(min_thickness 0.25)
			(keepout
				(tracks allowed)
				(vias not_allowed)
				(pads allowed)
				(copperpour not_allowed)
				(footprints allowed)
			)
			(placement
				(enabled no)
				(sheetname "")
			)
			(fill
				(thermal_gap 0.5)
				(thermal_bridge_width 0.5)
				(island_removal_mode 0)
			)
			(polygon
				(pts
					(xy 407.2636 -29.6672) (xy 407.7716 -29.6672) (xy 407.7716 -30.0482) (xy 407.2636 -30.0482)
				)
			)
		)
	)
	(footprint ""
		(layer "B.Cu")
		(at 88.392 -8.1534 90)
		(property "Reference" "C8U4"
			(at -1.848866 0.752348 90)
			(unlocked yes)
			(layer "B.SilkS")
			(effects
				(font
					(size 1.27 0.9652)
					(thickness 0.1524)
				)
				(justify mirror)
			)
		)
		(property "Value" ""
			(at 0 0 90)
			(layer "B.Fab")
			(effects
				(font
					(size 1.27 1.27)
				)
				(justify mirror)
			)
		)
		(duplicate_pad_numbers_are_jumpers no)
		(fp_rect
			(start 0.500126 1.598422)
			(end -0.500126 -0.201422)
			(stroke
				(width 0)
				(type default)
			)
			(fill no)
			(layer "B.CrtYd")
		)
		(fp_line
			(start 0.500126 -0.201422)
			(end -0.500126 -0.201422)
			(stroke
				(width 0.1)
				(type default)
			)
			(layer "B.Fab")
		)
		(fp_line
			(start -0.500126 -0.201422)
			(end -0.500126 1.598422)
			(stroke
				(width 0.1)
				(type default)
			)
			(layer "B.Fab")
		)
		(fp_line
			(start 0.500126 1.598422)
			(end 0.500126 -0.201422)
			(stroke
				(width 0.1)
				(type default)
			)
			(layer "B.Fab")
		)
		(fp_line
			(start -0.500126 1.598422)
			(end 0.500126 1.598422)
			(stroke
				(width 0.1)
				(type default)
			)
			(layer "B.Fab")
		)
		(pad "1" smd rect
			(at 0 0)
			(size 0.889 0.9906)
			(layers "B.Cu" "B.Mask" "B.Paste")
			(net "PVDDQ_GHJ")
		)
		(pad "2" smd rect
			(at 0 1.397)
			(size 0.889 0.9906)
			(layers "B.Cu" "B.Mask" "B.Paste")
			(net "GND")
		)
		(zone
			(layer "B.Cu")
			(hatch none 0.5)
			(connect_pads
				(clearance 0)
			)
			(min_thickness 0.25)
			(keepout
				(tracks allowed)
				(vias not_allowed)
				(pads allowed)
				(copperpour not_allowed)
				(footprints allowed)
			)
			(placement
				(enabled no)
				(sheetname "")
			)
			(fill
				(thermal_gap 0.5)
				(thermal_bridge_width 0.5)
				(island_removal_mode 0)
			)
			(polygon
				(pts
					(xy 89.3445 -8.6487) (xy 88.8365 -8.6487) (xy 88.8365 -7.6581) (xy 89.3445 -7.6581)
				)
			)
		)
		(zone
			(layer "B.Cu")
			(hatch none 0.5)
			(connect_pads
				(clearance 0)
			)
			(min_thickness 0.25)
			(keepout
				(tracks not_allowed)
				(vias allowed)
				(pads allowed)
				(copperpour not_allowed)
				(footprints allowed)
			)
			(placement
				(enabled no)
				(sheetname "")
			)
			(fill
				(thermal_gap 0.5)
				(thermal_bridge_width 0.5)
				(island_removal_mode 0)
			)
			(polygon
				(pts
					(xy 89.3445 -8.6487) (xy 88.8365 -8.6487) (xy 88.8365 -7.6581) (xy 89.3445 -7.6581)
				)
			)
		)
	)
	(footprint ""
		(layer "B.Cu")
		(at 330.091288 -63.38824 90)
		(property "Reference" "R3R14"
			(at 0 0 90)
			(layer "B.SilkS")
			(hide yes)
			(effects
				(font
					(size 1.27 1.27)
				)
				(justify mirror)
			)
		)
		(property "Value" ""
			(at 0 0 90)
			(layer "B.Fab")
			(effects
				(font
					(size 1.27 1.27)
				)
				(justify mirror)
			)
		)
		(duplicate_pad_numbers_are_jumpers no)
		(fp_poly
			(pts
				(xy 0.2794 -0.1016) (xy -0.2794 -0.1016) (xy -0.2794 0.9906) (xy 0.2794 0.9906)
			)
			(stroke
				(width 0)
				(type default)
			)
			(fill no)
			(layer "B.CrtYd")
		)
		(fp_line
			(start 0.2794 -0.1016)
			(end 0.2794 0.9906)
			(stroke
				(width 0.1)
				(type default)
			)
			(layer "B.Fab")
		)
		(fp_line
			(start -0.2794 -0.1016)
			(end 0.2794 -0.1016)
			(stroke
				(width 0.1)
				(type default)
			)
			(layer "B.Fab")
		)
		(fp_line
			(start 0.2794 0.9906)
			(end -0.2794 0.9906)
			(stroke
				(width 0.1)
				(type default)
			)
			(layer "B.Fab")
		)
		(fp_line
			(start -0.2794 0.9906)
			(end -0.2794 -0.1016)
			(stroke
				(width 0.1)
				(type default)
			)
			(layer "B.Fab")
		)
		(pad "1" smd rect
			(at 0 0 270)
			(size 0.508 0.508)
			(layers "B.Cu" "B.Mask" "B.Paste")
			(net "SMB_DDR_DEF_SDA_G_R")
		)
		(pad "2" smd rect
			(at 0 0.889 270)
			(size 0.508 0.508)
			(layers "B.Cu" "B.Mask" "B.Paste")
			(net "SMB_DDR_DEF_SDA_G")
		)
		(zone
			(layer "B.Cu")
			(hatch none 0.5)
			(connect_pads
				(clearance 0)
			)
			(min_thickness 0.25)
			(keepout
				(tracks allowed)
				(vias not_allowed)
				(pads allowed)
				(copperpour not_allowed)
				(footprints allowed)
			)
			(placement
				(enabled no)
				(sheetname "")
			)
			(fill
				(thermal_gap 0.5)
				(thermal_bridge_width 0.5)
				(island_removal_mode 0)
			)
			(polygon
				(pts
					(xy 330.345288 -63.64224) (xy 330.345288 -63.13424) (xy 330.726288 -63.13424) (xy 330.726288 -63.64224)
				)
			)
		)
		(zone
			(layer "B.Cu")
			(hatch none 0.5)
			(connect_pads
				(clearance 0)
			)
			(min_thickness 0.25)
			(keepout
				(tracks not_allowed)
				(vias allowed)
				(pads allowed)
				(copperpour not_allowed)
				(footprints allowed)
			)
			(placement
				(enabled no)
				(sheetname "")
			)
			(fill
				(thermal_gap 0.5)
				(thermal_bridge_width 0.5)
				(island_removal_mode 0)
			)
			(polygon
				(pts
					(xy 330.726288 -63.64224) (xy 330.726288 -63.13424) (xy 330.345288 -63.13424) (xy 330.345288 -63.64224)
				)
			)
		)
	)
	(footprint ""
		(layer "B.Cu")
		(at 194.691 -135.763)
		(property "Reference" "R6L16"
			(at 0 0 0)
			(layer "B.SilkS")
			(hide yes)
			(effects
				(font
					(size 1.27 1.27)
				)
				(justify mirror)
			)
		)
		(property "Value" ""
			(at 0 0 0)
			(layer "B.Fab")
			(effects
				(font
					(size 1.27 1.27)
				)
				(justify mirror)
			)
		)
		(duplicate_pad_numbers_are_jumpers no)
		(fp_poly
			(pts
				(xy 0.2794 -0.1016) (xy -0.2794 -0.1016) (xy -0.2794 0.9906) (xy 0.2794 0.9906)
			)
			(stroke
				(width 0)
				(type default)
			)
			(fill no)
			(layer "B.CrtYd")
		)
		(fp_line
			(start -0.2794 -0.1016)
			(end 0.2794 -0.1016)
			(stroke
				(width 0.1)
				(type default)
			)
			(layer "B.Fab")
		)
		(fp_line
			(start -0.2794 0.9906)
			(end -0.2794 -0.1016)
			(stroke
				(width 0.1)
				(type default)
			)
			(layer "B.Fab")
		)
		(fp_line
			(start 0.2794 -0.1016)
			(end 0.2794 0.9906)
			(stroke
				(width 0.1)
				(type default)
			)
			(layer "B.Fab")
		)
		(fp_line
			(start 0.2794 0.9906)
			(end -0.2794 0.9906)
			(stroke
				(width 0.1)
				(type default)
			)
			(layer "B.Fab")
		)
		(pad "1" smd rect
			(at 0 0 180)
			(size 0.508 0.508)
			(layers "B.Cu" "B.Mask" "B.Paste")
			(net "M_D_VREF")
		)
		(pad "2" smd rect
			(at 0 0.889 180)
			(size 0.508 0.508)
			(layers "B.Cu" "B.Mask" "B.Paste")
			(net "GND")
		)
		(zone
			(layer "B.Cu")
			(hatch none 0.5)
			(connect_pads
				(clearance 0)
			)
			(min_thickness 0.25)
			(keepout
				(tracks allowed)
				(vias not_allowed)
				(pads allowed)
				(copperpour not_allowed)
				(footprints allowed)
			)
			(placement
				(enabled no)
				(sheetname "")
			)
			(fill
				(thermal_gap 0.5)
				(thermal_bridge_width 0.5)
				(island_removal_mode 0)
			)
			(polygon
				(pts
					(xy 194.945 -135.509) (xy 194.437 -135.509) (xy 194.437 -135.128) (xy 194.945 -135.128)
				)
			)
		)
		(zone
			(layer "B.Cu")
			(hatch none 0.5)
			(connect_pads
				(clearance 0)
			)
			(min_thickness 0.25)
			(keepout
				(tracks not_allowed)
				(vias allowed)
				(pads allowed)
				(copperpour not_allowed)
				(footprints allowed)
			)
			(placement
				(enabled no)
				(sheetname "")
			)
			(fill
				(thermal_gap 0.5)
				(thermal_bridge_width 0.5)
				(island_removal_mode 0)
			)
			(polygon
				(pts
					(xy 194.945 -135.128) (xy 194.437 -135.128) (xy 194.437 -135.509) (xy 194.945 -135.509)
				)
			)
		)
	)
	(footprint ""
		(layer "B.Cu")
		(at 353.654614 -123.780042 -90)
		(property "Reference" "R775"
			(at 0.8382 -0.67818 270)
			(unlocked yes)
			(layer "B.SilkS")
			(effects
				(font
					(size 0.4064 0.254)
					(thickness 0.1524)
				)
				(justify left mirror)
			)
		)
		(property "Value" ""
			(at 0 0 90)
			(layer "B.Fab")
			(effects
				(font
					(size 1.27 1.27)
				)
				(justify mirror)
			)
		)
		(duplicate_pad_numbers_are_jumpers no)
		(fp_poly
			(pts
				(xy 0.2794 -0.1016) (xy -0.2794 -0.1016) (xy -0.2794 0.9906) (xy 0.2794 0.9906)
			)
			(stroke
				(width 0)
				(type default)
			)
			(fill no)
			(layer "B.CrtYd")
		)
		(fp_line
			(start -0.2794 0.9906)
			(end -0.2794 -0.1016)
			(stroke
				(width 0.1)
				(type default)
			)
			(layer "B.Fab")
		)
		(fp_line
			(start 0.2794 0.9906)
			(end -0.2794 0.9906)
			(stroke
				(width 0.1)
				(type default)
			)
			(layer "B.Fab")
		)
		(fp_line
			(start -0.2794 -0.1016)
			(end 0.2794 -0.1016)
			(stroke
				(width 0.1)
				(type default)
			)
			(layer "B.Fab")
		)
		(fp_line
			(start 0.2794 -0.1016)
			(end 0.2794 0.9906)
			(stroke
				(width 0.1)
				(type default)
			)
			(layer "B.Fab")
		)
		(pad "1" smd rect
			(at 0 0 90)
			(size 0.508 0.508)
			(layers "B.Cu" "B.Mask" "B.Paste")
			(net "P3E_CPU0_PE1_PCH_RXN<12>")
		)
		(pad "2" smd rect
			(at 0 0.889 90)
			(size 0.508 0.508)
			(layers "B.Cu" "B.Mask" "B.Paste")
			(net "P3E_CPU0_PE1_PCH_CON_RXN<12>")
		)
		(zone
			(layer "B.Cu")
			(hatch none 0.5)
			(connect_pads
				(clearance 0)
			)
			(min_thickness 0.25)
			(keepout
				(tracks not_allowed)
				(vias allowed)
				(pads allowed)
				(copperpour not_allowed)
				(footprints allowed)
			)
			(placement
				(enabled no)
				(sheetname "")
			)
			(fill
				(thermal_gap 0.5)
				(thermal_bridge_width 0.5)
				(island_removal_mode 0)
			)
			(polygon
				(pts
					(xy 353.019614 -123.526042) (xy 353.019614 -124.034042) (xy 353.400614 -124.034042) (xy 353.400614 -123.526042)
				)
			)
		)
		(zone
			(layer "B.Cu")
			(hatch none 0.5)
			(connect_pads
				(clearance 0)
			)
			(min_thickness 0.25)
			(keepout
				(tracks allowed)
				(vias not_allowed)
				(pads allowed)
				(copperpour not_allowed)
				(footprints allowed)
			)
			(placement
				(enabled no)
				(sheetname "")
			)
			(fill
				(thermal_gap 0.5)
				(thermal_bridge_width 0.5)
				(island_removal_mode 0)
			)
			(polygon
				(pts
					(xy 353.400614 -123.526042) (xy 353.400614 -124.034042) (xy 353.019614 -124.034042) (xy 353.019614 -123.526042)
				)
			)
		)
	)
	(footprint ""
		(layer "B.Cu")
		(at 388.892542 -12.473432)
		(property "Reference" "U32W2"
			(at 0 0 0)
			(layer "B.SilkS")
			(hide yes)
			(effects
				(font
					(size 1.27 1.27)
				)
				(justify mirror)
			)
		)
		(property "Value" "*"
			(at 0.1143 -9.3091 0)
			(unlocked yes)
			(layer "B.Fab")
			(hide yes)
			(effects
				(font
					(size 1.27 1.016)
					(thickness 0.1524)
				)
				(justify mirror)
			)
		)
		(property "Device Type" "TCA9517DGKR-GP_DISCRET-G8-TCA9A"
			(at 0.1143 -10.9093 0)
			(unlocked yes)
			(layer "B.Fab")
			(hide yes)
			(effects
				(font
					(size 1.27 1.016)
					(thickness 0.1524)
				)
				(justify mirror)
			)
		)
		(duplicate_pad_numbers_are_jumpers no)
		(fp_line
			(start -1.0795 -1.016)
			(end 1.9558 -1.016)
			(stroke
				(width 0.1524)
				(type default)
			)
			(layer "B.SilkS")
		)
		(fp_line
			(start -1.0795 1.016)
			(end -1.0795 -1.016)
			(stroke
				(width 0.1524)
				(type default)
			)
			(layer "B.SilkS")
		)
		(fp_line
			(start 1.4478 -0.0381)
			(end 1.9558 0.4699)
			(stroke
				(width 0.1524)
				(type default)
			)
			(layer "B.SilkS")
		)
		(fp_line
			(start 1.778 1.0922)
			(end 1.778 3.048)
			(stroke
				(width 0.508)
				(type default)
			)
			(layer "B.SilkS")
		)
		(fp_line
			(start 1.9558 -1.016)
			(end 1.9558 1.016)
			(stroke
				(width 0.1524)
				(type default)
			)
			(layer "B.SilkS")
		)
		(fp_line
			(start 1.9558 -0.5461)
			(end 1.4478 -0.0381)
			(stroke
				(width 0.1524)
				(type default)
			)
			(layer "B.SilkS")
		)
		(fp_line
			(start 1.9558 1.016)
			(end -1.0795 1.016)
			(stroke
				(width 0.1524)
				(type default)
			)
			(layer "B.SilkS")
		)
		(fp_poly
			(pts
				(xy 1.1557 -1.016) (xy 1.1557 1.016) (xy -1.1557 1.016) (xy -1.1557 -1.016)
			)
			(stroke
				(width 0)
				(type default)
			)
			(fill yes)
			(layer "B.SilkS")
		)
		(fp_rect
			(start 1.4986 2.4511)
			(end -1.4986 -2.4511)
			(stroke
				(width 0)
				(type default)
			)
			(fill no)
			(layer "B.CrtYd")
		)
		(fp_poly
			(pts
				(xy 2.032 3.302) (xy 2.032 -3.302) (xy -2.032 -3.302) (xy -2.032 -2.1209) (xy -1.4986 -2.1209) (xy -1.4986 -2.4511)
				(xy 1.4986 -2.4511) (xy 1.4986 2.4511) (xy -1.4986 2.4511) (xy -1.4986 -2.1082) (xy -2.032 -2.1082)
				(xy -2.032 3.302)
			)
			(stroke
				(width 0)
				(type default)
			)
			(fill no)
			(layer "B.CrtYd")
		)
		(fp_rect
			(start 2.032 3.302)
			(end -2.032 -3.302)
			(stroke
				(width 0)
				(type default)
			)
			(fill no)
			(layer "B.Fab")
		)
		(pad "1" smd rect
			(at 0.97536 2.05486 180)
			(size 0.3556 1.524)
			(layers "B.Cu" "B.Mask" "B.Paste")
			(net "P1V8_M2")
		)
		(pad "2" smd rect
			(at 0.32512 2.05486 180)
			(size 0.3556 1.524)
			(layers "B.Cu" "B.Mask" "B.Paste")
			(net "SMB_M2_ALT_R_N")
		)
		(pad "3" smd rect
			(at -0.32512 2.05486 180)
			(size 0.3556 1.524)
			(layers "B.Cu" "B.Mask" "B.Paste")
			(net "Net_6507")
		)
		(pad "4" smd rect
			(at -0.97536 2.05486 180)
			(size 0.3556 1.524)
			(layers "B.Cu" "B.Mask" "B.Paste")
			(net "GND")
		)
		(pad "5" smd rect
			(at -0.97536 -2.05486 180)
			(size 0.3556 1.524)
			(layers "B.Cu" "B.Mask" "B.Paste")
			(net "PD_SMB_M2_EN")
		)
		(pad "6" smd rect
			(at -0.32512 -2.05486 180)
			(size 0.3556 1.524)
			(layers "B.Cu" "B.Mask" "B.Paste")
			(net "Net_6506")
		)
		(pad "7" smd rect
			(at 0.32512 -2.05486 180)
			(size 0.3556 1.524)
			(layers "B.Cu" "B.Mask" "B.Paste")
			(net "IRQ_MEZZ_LAN_ALERT_N")
		)
		(pad "8" smd rect
			(at 0.97536 -2.05486 180)
			(size 0.3556 1.524)
			(layers "B.Cu" "B.Mask" "B.Paste")
			(net "P3V3_STBY")
		)
	)
	(footprint ""
		(layer "B.Cu")
		(at 26.896568 -154.559 180)
		(property "Reference" "C9L3"
			(at 0 0 0)
			(layer "B.SilkS")
			(hide yes)
			(effects
				(font
					(size 1.27 1.27)
				)
				(justify mirror)
			)
		)
		(property "Value" ""
			(at 0 0 0)
			(layer "B.Fab")
			(effects
				(font
					(size 1.27 1.27)
				)
				(justify mirror)
			)
		)
		(duplicate_pad_numbers_are_jumpers no)
		(fp_poly
			(pts
				(xy -0.3048 -0.1016) (xy -0.3048 0.9906) (xy 0.3048 0.9906) (xy 0.3048 -0.1016)
			)
			(stroke
				(width 0)
				(type default)
			)
			(fill no)
			(layer "B.CrtYd")
		)
		(fp_line
			(start 0.3048 0.9906)
			(end -0.3048 0.9906)
			(stroke
				(width 0.1)
				(type default)
			)
			(layer "B.Fab")
		)
		(fp_line
			(start 0.3048 -0.1016)
			(end 0.3048 0.9906)
			(stroke
				(width 0.1)
				(type default)
			)
			(layer "B.Fab")
		)
		(fp_line
			(start -0.3048 0.9906)
			(end -0.3048 -0.1016)
			(stroke
				(width 0.1)
				(type default)
			)
			(layer "B.Fab")
		)
		(fp_line
			(start -0.3048 -0.1016)
			(end 0.3048 -0.1016)
			(stroke
				(width 0.1)
				(type default)
			)
			(layer "B.Fab")
		)
		(pad "1" smd rect
			(at 0 0)
			(size 0.508 0.508)
			(layers "B.Cu" "B.Mask" "B.Paste")
			(net "M_M_CPU_VREF")
		)
		(pad "2" smd rect
			(at 0 0.889)
			(size 0.508 0.508)
			(layers "B.Cu" "B.Mask" "B.Paste")
			(net "GND")
		)
		(zone
			(layer "B.Cu")
			(hatch none 0.5)
			(connect_pads
				(clearance 0)
			)
			(min_thickness 0.25)
			(keepout
				(tracks not_allowed)
				(vias allowed)
				(pads allowed)
				(copperpour not_allowed)
				(footprints allowed)
			)
			(placement
				(enabled no)
				(sheetname "")
			)
			(fill
				(thermal_gap 0.5)
				(thermal_bridge_width 0.5)
				(island_removal_mode 0)
			)
			(polygon
				(pts
					(xy 26.642568 -155.194) (xy 27.150568 -155.194) (xy 27.150568 -154.813) (xy 26.642568 -154.813)
				)
			)
		)
		(zone
			(layer "B.Cu")
			(hatch none 0.5)
			(connect_pads
				(clearance 0)
			)
			(min_thickness 0.25)
			(keepout
				(tracks allowed)
				(vias not_allowed)
				(pads allowed)
				(copperpour not_allowed)
				(footprints allowed)
			)
			(placement
				(enabled no)
				(sheetname "")
			)
			(fill
				(thermal_gap 0.5)
				(thermal_bridge_width 0.5)
				(island_removal_mode 0)
			)
			(polygon
				(pts
					(xy 26.642568 -154.813) (xy 27.150568 -154.813) (xy 27.150568 -155.194) (xy 26.642568 -155.194)
				)
			)
		)
	)
	(footprint ""
		(layer "B.Cu")
		(at 377.8758 -135.1788 -90)
		(property "Reference" "FB3M1"
			(at 0 0 90)
			(layer "B.SilkS")
			(hide yes)
			(effects
				(font
					(size 1.27 1.27)
				)
				(justify mirror)
			)
		)
		(property "Value" ""
			(at 0 0 90)
			(layer "B.Fab")
			(effects
				(font
					(size 1.27 1.27)
				)
				(justify mirror)
			)
		)
		(duplicate_pad_numbers_are_jumpers no)
		(fp_poly
			(pts
				(xy 0.15113 -0.47498) (xy -1.59893 -0.47498) (xy -1.59893 0.47498) (xy 0.15113 0.47498)
			)
			(stroke
				(width 0)
				(type default)
			)
			(fill no)
			(layer "B.CrtYd")
		)
		(fp_line
			(start -1.59893 0.47498)
			(end 0.15113 0.47498)
			(stroke
				(width 0.1)
				(type default)
			)
			(layer "B.Fab")
		)
		(fp_line
			(start 0.15113 0.47498)
			(end 0.15113 -0.47498)
			(stroke
				(width 0.1)
				(type default)
			)
			(layer "B.Fab")
		)
		(fp_line
			(start -1.59893 -0.47498)
			(end -1.59893 0.47498)
			(stroke
				(width 0.1)
				(type default)
			)
			(layer "B.Fab")
		)
		(fp_line
			(start 0.15113 -0.47498)
			(end -1.59893 -0.47498)
			(stroke
				(width 0.1)
				(type default)
			)
			(layer "B.Fab")
		)
		(pad "1" smd rect
			(at 0 0 90)
			(size 0.9398 0.9398)
			(layers "B.Cu" "B.Mask" "B.Paste")
			(net "P1V05_PCH_STBY")
		)
		(pad "2" smd rect
			(at -1.4478 0 90)
			(size 0.9398 0.9398)
			(layers "B.Cu" "B.Mask" "B.Paste")
			(net "P1V05_PCH_STBY_VCCA_PLL1")
		)
		(zone
			(layer "B.Cu")
			(hatch none 0.5)
			(connect_pads
				(clearance 0)
			)
			(min_thickness 0.25)
			(keepout
				(tracks not_allowed)
				(vias allowed)
				(pads allowed)
				(copperpour not_allowed)
				(footprints allowed)
			)
			(placement
				(enabled no)
				(sheetname "")
			)
			(fill
				(thermal_gap 0.5)
				(thermal_bridge_width 0.5)
				(island_removal_mode 0)
			)
			(polygon
				(pts
					(xy 377.4059 -135.6487) (xy 378.3457 -135.6487) (xy 378.3457 -136.1567) (xy 377.4059 -136.1567)
				)
			)
		)
		(zone
			(layer "B.Cu")
			(hatch none 0.5)
			(connect_pads
				(clearance 0)
			)
			(min_thickness 0.25)
			(keepout
				(tracks allowed)
				(vias not_allowed)
				(pads allowed)
				(copperpour not_allowed)
				(footprints allowed)
			)
			(placement
				(enabled no)
				(sheetname "")
			)
			(fill
				(thermal_gap 0.5)
				(thermal_bridge_width 0.5)
				(island_removal_mode 0)
			)
			(polygon
				(pts
					(xy 377.4059 -135.6487) (xy 378.3457 -135.6487) (xy 378.3457 -136.1567) (xy 377.4059 -136.1567)
				)
			)
		)
	)
	(footprint ""
		(layer "B.Cu")
		(at 425.203874 -40.931846 180)
		(property "Reference" "C25W59"
			(at -0.97536 0.76708 270)
			(unlocked yes)
			(layer "B.SilkS")
			(effects
				(font
					(size 0.4064 0.254)
					(thickness 0.1524)
				)
				(justify mirror)
			)
		)
		(property "Value" ""
			(at 0 0 0)
			(layer "B.Fab")
			(effects
				(font
					(size 1.27 1.27)
				)
				(justify mirror)
			)
		)
		(duplicate_pad_numbers_are_jumpers no)
		(fp_poly
			(pts
				(xy 0.4953 -0.2032) (xy -0.4953 -0.2032) (xy -0.4953 1.6002) (xy 0.4953 1.6002)
			)
			(stroke
				(width 0)
				(type default)
			)
			(fill no)
			(layer "B.CrtYd")
		)
		(fp_line
			(start 0.4953 1.6002)
			(end 0.4953 -0.2032)
			(stroke
				(width 0.1)
				(type default)
			)
			(layer "B.Fab")
		)
		(fp_line
			(start 0.4953 -0.2032)
			(end -0.4953 -0.2032)
			(stroke
				(width 0.1)
				(type default)
			)
			(layer "B.Fab")
		)
		(fp_line
			(start -0.4953 1.6002)
			(end 0.4953 1.6002)
			(stroke
				(width 0.1)
				(type default)
			)
			(layer "B.Fab")
		)
		(fp_line
			(start -0.4953 -0.2032)
			(end -0.4953 1.6002)
			(stroke
				(width 0.1)
				(type default)
			)
			(layer "B.Fab")
		)
		(pad "1" smd rect
			(at 0 0)
			(size 0.762 0.889)
			(layers "B.Cu" "B.Mask" "B.Paste")
			(net "VCC_PA_3V3")
		)
		(pad "2" smd rect
			(at 0 1.397)
			(size 0.762 0.889)
			(layers "B.Cu" "B.Mask" "B.Paste")
			(net "GND")
		)
		(zone
			(layer "B.Cu")
			(hatch none 0.5)
			(connect_pads
				(clearance 0)
			)
			(min_thickness 0.25)
			(keepout
				(tracks not_allowed)
				(vias allowed)
				(pads allowed)
				(copperpour not_allowed)
				(footprints allowed)
			)
			(placement
				(enabled no)
				(sheetname "")
			)
			(fill
				(thermal_gap 0.5)
				(thermal_bridge_width 0.5)
				(island_removal_mode 0)
			)
			(polygon
				(pts
					(xy 424.822874 -41.376346) (xy 425.584874 -41.376346) (xy 425.584874 -41.884346) (xy 424.822874 -41.884346)
				)
			)
		)
	)
	(footprint ""
		(layer "B.Cu")
		(at 244.5512 -125.55601 -90)
		(property "Reference" "C5M10"
			(at 0 0 90)
			(layer "B.SilkS")
			(hide yes)
			(effects
				(font
					(size 1.27 1.27)
				)
				(justify mirror)
			)
		)
		(property "Value" ""
			(at 0 0 90)
			(layer "B.Fab")
			(effects
				(font
					(size 1.27 1.27)
				)
				(justify mirror)
			)
		)
		(duplicate_pad_numbers_are_jumpers no)
		(fp_rect
			(start 0.500126 1.598422)
			(end -0.500126 -0.201422)
			(stroke
				(width 0)
				(type default)
			)
			(fill no)
			(layer "B.CrtYd")
		)
		(fp_line
			(start -0.500126 1.598422)
			(end 0.500126 1.598422)
			(stroke
				(width 0.1)
				(type default)
			)
			(layer "B.Fab")
		)
		(fp_line
			(start 0.500126 1.598422)
			(end 0.500126 -0.201422)
			(stroke
				(width 0.1)
				(type default)
			)
			(layer "B.Fab")
		)
		(fp_line
			(start -0.500126 -0.201422)
			(end -0.500126 1.598422)
			(stroke
				(width 0.1)
				(type default)
			)
			(layer "B.Fab")
		)
		(fp_line
			(start 0.500126 -0.201422)
			(end -0.500126 -0.201422)
			(stroke
				(width 0.1)
				(type default)
			)
			(layer "B.Fab")
		)
		(pad "1" smd rect
			(at 0 0 180)
			(size 0.889 0.9906)
			(layers "B.Cu" "B.Mask" "B.Paste")
			(net "PVDDQ_DEF")
		)
		(pad "2" smd rect
			(at 0 1.397 180)
			(size 0.889 0.9906)
			(layers "B.Cu" "B.Mask" "B.Paste")
			(net "GND")
		)
		(zone
			(layer "B.Cu")
			(hatch none 0.5)
			(connect_pads
				(clearance 0)
			)
			(min_thickness 0.25)
			(keepout
				(tracks allowed)
				(vias not_allowed)
				(pads allowed)
				(copperpour not_allowed)
				(footprints allowed)
			)
			(placement
				(enabled no)
				(sheetname "")
			)
			(fill
				(thermal_gap 0.5)
				(thermal_bridge_width 0.5)
				(island_removal_mode 0)
			)
			(polygon
				(pts
					(xy 243.5987 -125.06071) (xy 244.1067 -125.06071) (xy 244.1067 -126.05131) (xy 243.5987 -126.05131)
				)
			)
		)
		(zone
			(layer "B.Cu")
			(hatch none 0.5)
			(connect_pads
				(clearance 0)
			)
			(min_thickness 0.25)
			(keepout
				(tracks not_allowed)
				(vias allowed)
				(pads allowed)
				(copperpour not_allowed)
				(footprints allowed)
			)
			(placement
				(enabled no)
				(sheetname "")
			)
			(fill
				(thermal_gap 0.5)
				(thermal_bridge_width 0.5)
				(island_removal_mode 0)
			)
			(polygon
				(pts
					(xy 243.5987 -125.06071) (xy 244.1067 -125.06071) (xy 244.1067 -126.05131) (xy 243.5987 -126.05131)
				)
			)
		)
	)
	(footprint ""
		(layer "B.Cu")
		(at 182.736998 -5.321808)
		(property "Reference" "R6U5"
			(at 0 0 0)
			(layer "B.SilkS")
			(hide yes)
			(effects
				(font
					(size 1.27 1.27)
				)
				(justify mirror)
			)
		)
		(property "Value" ""
			(at 0 0 0)
			(layer "B.Fab")
			(effects
				(font
					(size 1.27 1.27)
				)
				(justify mirror)
			)
		)
		(duplicate_pad_numbers_are_jumpers no)
		(fp_rect
			(start 0.2794 0.9906)
			(end -0.2794 -0.1016)
			(stroke
				(width 0)
				(type default)
			)
			(fill no)
			(layer "B.CrtYd")
		)
		(fp_line
			(start -0.2794 -0.1016)
			(end 0.2794 -0.1016)
			(stroke
				(width 0.1)
				(type default)
			)
			(layer "B.Fab")
		)
		(fp_line
			(start -0.2794 0.9906)
			(end -0.2794 -0.1016)
			(stroke
				(width 0.1)
				(type default)
			)
			(layer "B.Fab")
		)
		(fp_line
			(start 0.2794 -0.1016)
			(end 0.2794 0.9906)
			(stroke
				(width 0.1)
				(type default)
			)
			(layer "B.Fab")
		)
		(fp_line
			(start 0.2794 0.9906)
			(end -0.2794 0.9906)
			(stroke
				(width 0.1)
				(type default)
			)
			(layer "B.Fab")
		)
		(pad "1" smd rect
			(at 0 0 180)
			(size 0.508 0.508)
			(layers "B.Cu" "B.Mask" "B.Paste")
			(net "PVDDQ_ABC")
		)
		(pad "2" smd rect
			(at 0 0.889 180)
			(size 0.508 0.508)
			(layers "B.Cu" "B.Mask" "B.Paste")
			(net "VSENSE_PVDDQ_ABC_VTT")
		)
		(zone
			(layer "B.Cu")
			(hatch none 0.5)
			(connect_pads
				(clearance 0)
			)
			(min_thickness 0.25)
			(keepout
				(tracks allowed)
				(vias not_allowed)
				(pads allowed)
				(copperpour not_allowed)
				(footprints allowed)
			)
			(placement
				(enabled no)
				(sheetname "")
			)
			(fill
				(thermal_gap 0.5)
				(thermal_bridge_width 0.5)
				(island_removal_mode 0)
			)
			(polygon
				(pts
					(xy 182.990998 -4.686808) (xy 182.990998 -5.067808) (xy 182.482998 -5.067808) (xy 182.482998 -4.686808)
				)
			)
		)
	)
	(footprint ""
		(layer "B.Cu")
		(at 259.09778 -149.7711 90)
		(property "Reference" "C5G77"
			(at -1.64973 0.78994 180)
			(unlocked yes)
			(layer "B.SilkS")
			(effects
				(font
					(size 0.7874 0.5842)
					(thickness 0.1524)
				)
				(justify mirror)
			)
		)
		(property "Value" ""
			(at 0 0 90)
			(layer "B.Fab")
			(effects
				(font
					(size 1.27 1.27)
				)
				(justify mirror)
			)
		)
		(duplicate_pad_numbers_are_jumpers no)
		(fp_rect
			(start -0.7239 -0.2159)
			(end 0.7239 1.9939)
			(stroke
				(width 0)
				(type default)
			)
			(fill no)
			(layer "B.CrtYd")
		)
		(fp_line
			(start 0.7239 -0.2159)
			(end 0.7239 1.9939)
			(stroke
				(width 0.1)
				(type default)
			)
			(layer "B.Fab")
		)
		(fp_line
			(start -0.7239 -0.2159)
			(end 0.7239 -0.2159)
			(stroke
				(width 0.1)
				(type default)
			)
			(layer "B.Fab")
		)
		(fp_line
			(start 0.7239 1.9939)
			(end -0.7239 1.9939)
			(stroke
				(width 0.1)
				(type default)
			)
			(layer "B.Fab")
		)
		(fp_line
			(start -0.7239 1.9939)
			(end -0.7239 -0.2159)
			(stroke
				(width 0.1)
				(type default)
			)
			(layer "B.Fab")
		)
		(pad "1" smd rect
			(at 0 0 270)
			(size 1.27 1.016)
			(layers "B.Cu" "B.Mask" "B.Paste")
			(net "PVDDQ_DEF")
		)
		(pad "2" smd rect
			(at 0 1.778 270)
			(size 1.27 1.016)
			(layers "B.Cu" "B.Mask" "B.Paste")
			(net "GND")
		)
		(zone
			(layer "B.Cu")
			(hatch none 0.5)
			(connect_pads
				(clearance 0)
			)
			(min_thickness 0.25)
			(keepout
				(tracks not_allowed)
				(vias allowed)
				(pads allowed)
				(copperpour not_allowed)
				(footprints allowed)
			)
			(placement
				(enabled no)
				(sheetname "")
			)
			(fill
				(thermal_gap 0.5)
				(thermal_bridge_width 0.5)
				(island_removal_mode 0)
			)
			(polygon
				(pts
					(xy 259.60578 -149.1361) (xy 260.36778 -149.1361) (xy 260.36778 -150.4061) (xy 259.60578 -150.4061)
				)
			)
		)
	)
	(footprint ""
		(layer "B.Cu")
		(at 470.027 -56.388 -90)
		(property "Reference" "R1R22"
			(at 0 0 90)
			(layer "B.SilkS")
			(hide yes)
			(effects
				(font
					(size 1.27 1.27)
				)
				(justify mirror)
			)
		)
		(property "Value" ""
			(at 0 0 90)
			(layer "B.Fab")
			(effects
				(font
					(size 1.27 1.27)
				)
				(justify mirror)
			)
		)
		(duplicate_pad_numbers_are_jumpers no)
		(fp_poly
			(pts
				(xy 0.2794 -0.1016) (xy -0.2794 -0.1016) (xy -0.2794 0.9906) (xy 0.2794 0.9906)
			)
			(stroke
				(width 0)
				(type default)
			)
			(fill no)
			(layer "B.CrtYd")
		)
		(fp_line
			(start -0.2794 0.9906)
			(end -0.2794 -0.1016)
			(stroke
				(width 0.1)
				(type default)
			)
			(layer "B.Fab")
		)
		(fp_line
			(start 0.2794 0.9906)
			(end -0.2794 0.9906)
			(stroke
				(width 0.1)
				(type default)
			)
			(layer "B.Fab")
		)
		(fp_line
			(start -0.2794 -0.1016)
			(end 0.2794 -0.1016)
			(stroke
				(width 0.1)
				(type default)
			)
			(layer "B.Fab")
		)
		(fp_line
			(start 0.2794 -0.1016)
			(end 0.2794 0.9906)
			(stroke
				(width 0.1)
				(type default)
			)
			(layer "B.Fab")
		)
		(pad "1" smd rect
			(at 0 0 90)
			(size 0.508 0.508)
			(layers "B.Cu" "B.Mask" "B.Paste")
			(net "P3V3_STBY")
		)
		(pad "2" smd rect
			(at 0 0.889 90)
			(size 0.508 0.508)
			(layers "B.Cu" "B.Mask" "B.Paste")
			(net "SMB_PCH_MEZZ_LOM3_SDA")
		)
		(zone
			(layer "B.Cu")
			(hatch none 0.5)
			(connect_pads
				(clearance 0)
			)
			(min_thickness 0.25)
			(keepout
				(tracks not_allowed)
				(vias allowed)
				(pads allowed)
				(copperpour not_allowed)
				(footprints allowed)
			)
			(placement
				(enabled no)
				(sheetname "")
			)
			(fill
				(thermal_gap 0.5)
				(thermal_bridge_width 0.5)
				(island_removal_mode 0)
			)
			(polygon
				(pts
					(xy 469.392 -56.134) (xy 469.392 -56.642) (xy 469.773 -56.642) (xy 469.773 -56.134)
				)
			)
		)
		(zone
			(layer "B.Cu")
			(hatch none 0.5)
			(connect_pads
				(clearance 0)
			)
			(min_thickness 0.25)
			(keepout
				(tracks allowed)
				(vias not_allowed)
				(pads allowed)
				(copperpour not_allowed)
				(footprints allowed)
			)
			(placement
				(enabled no)
				(sheetname "")
			)
			(fill
				(thermal_gap 0.5)
				(thermal_bridge_width 0.5)
				(island_removal_mode 0)
			)
			(polygon
				(pts
					(xy 469.773 -56.134) (xy 469.773 -56.642) (xy 469.392 -56.642) (xy 469.392 -56.134)
				)
			)
		)
	)
	(footprint ""
		(layer "B.Cu")
		(at 443.1538 -142.0368 -90)
		(property "Reference" "R25W178"
			(at 0.8382 -0.67818 270)
			(unlocked yes)
			(layer "B.SilkS")
			(effects
				(font
					(size 0.4064 0.254)
					(thickness 0.1524)
				)
				(justify left mirror)
			)
		)
		(property "Value" ""
			(at 0 0 90)
			(layer "B.Fab")
			(effects
				(font
					(size 1.27 1.27)
				)
				(justify mirror)
			)
		)
		(duplicate_pad_numbers_are_jumpers no)
		(fp_poly
			(pts
				(xy 0.2794 -0.1016) (xy -0.2794 -0.1016) (xy -0.2794 0.9906) (xy 0.2794 0.9906)
			)
			(stroke
				(width 0)
				(type default)
			)
			(fill no)
			(layer "B.CrtYd")
		)
		(fp_line
			(start -0.2794 0.9906)
			(end -0.2794 -0.1016)
			(stroke
				(width 0.1)
				(type default)
			)
			(layer "B.Fab")
		)
		(fp_line
			(start 0.2794 0.9906)
			(end -0.2794 0.9906)
			(stroke
				(width 0.1)
				(type default)
			)
			(layer "B.Fab")
		)
		(fp_line
			(start -0.2794 -0.1016)
			(end 0.2794 -0.1016)
			(stroke
				(width 0.1)
				(type default)
			)
			(layer "B.Fab")
		)
		(fp_line
			(start 0.2794 -0.1016)
			(end 0.2794 0.9906)
			(stroke
				(width 0.1)
				(type default)
			)
			(layer "B.Fab")
		)
		(pad "1" smd rect
			(at 0 0 90)
			(size 0.508 0.508)
			(layers "B.Cu" "B.Mask" "B.Paste")
			(net "P3V3_STBY")
		)
		(pad "2" smd rect
			(at 0 0.889 90)
			(size 0.508 0.508)
			(layers "B.Cu" "B.Mask" "B.Paste")
			(net "BMC_PWR_DEBUG_BUF_N")
		)
		(zone
			(layer "B.Cu")
			(hatch none 0.5)
			(connect_pads
				(clearance 0)
			)
			(min_thickness 0.25)
			(keepout
				(tracks not_allowed)
				(vias allowed)
				(pads allowed)
				(copperpour not_allowed)
				(footprints allowed)
			)
			(placement
				(enabled no)
				(sheetname "")
			)
			(fill
				(thermal_gap 0.5)
				(thermal_bridge_width 0.5)
				(island_removal_mode 0)
			)
			(polygon
				(pts
					(xy 442.5188 -141.7828) (xy 442.5188 -142.2908) (xy 442.8998 -142.2908) (xy 442.8998 -141.7828)
				)
			)
		)
		(zone
			(layer "B.Cu")
			(hatch none 0.5)
			(connect_pads
				(clearance 0)
			)
			(min_thickness 0.25)
			(keepout
				(tracks allowed)
				(vias not_allowed)
				(pads allowed)
				(copperpour not_allowed)
				(footprints allowed)
			)
			(placement
				(enabled no)
				(sheetname "")
			)
			(fill
				(thermal_gap 0.5)
				(thermal_bridge_width 0.5)
				(island_removal_mode 0)
			)
			(polygon
				(pts
					(xy 442.8998 -141.7828) (xy 442.8998 -142.2908) (xy 442.5188 -142.2908) (xy 442.5188 -141.7828)
				)
			)
		)
	)
	(footprint ""
		(layer "B.Cu")
		(at 393.362688 -153.552144 90)
		(property "Reference" "R2L9"
			(at 0 0 90)
			(layer "B.SilkS")
			(hide yes)
			(effects
				(font
					(size 1.27 1.27)
				)
				(justify mirror)
			)
		)
		(property "Value" ""
			(at 0 0 90)
			(layer "B.Fab")
			(effects
				(font
					(size 1.27 1.27)
				)
				(justify mirror)
			)
		)
		(duplicate_pad_numbers_are_jumpers no)
		(fp_poly
			(pts
				(xy 0.2794 -0.1016) (xy -0.2794 -0.1016) (xy -0.2794 0.9906) (xy 0.2794 0.9906)
			)
			(stroke
				(width 0)
				(type default)
			)
			(fill no)
			(layer "B.CrtYd")
		)
		(fp_line
			(start 0.2794 -0.1016)
			(end 0.2794 0.9906)
			(stroke
				(width 0.1)
				(type default)
			)
			(layer "B.Fab")
		)
		(fp_line
			(start -0.2794 -0.1016)
			(end 0.2794 -0.1016)
			(stroke
				(width 0.1)
				(type default)
			)
			(layer "B.Fab")
		)
		(fp_line
			(start 0.2794 0.9906)
			(end -0.2794 0.9906)
			(stroke
				(width 0.1)
				(type default)
			)
			(layer "B.Fab")
		)
		(fp_line
			(start -0.2794 0.9906)
			(end -0.2794 -0.1016)
			(stroke
				(width 0.1)
				(type default)
			)
			(layer "B.Fab")
		)
		(pad "1" smd rect
			(at 0 0 270)
			(size 0.508 0.508)
			(layers "B.Cu" "B.Mask" "B.Paste")
			(net "VR_PVNN_PCH_XADDR1")
		)
		(pad "2" smd rect
			(at 0 0.889 270)
			(size 0.508 0.508)
			(layers "B.Cu" "B.Mask" "B.Paste")
			(net "GND")
		)
		(zone
			(layer "B.Cu")
			(hatch none 0.5)
			(connect_pads
				(clearance 0)
			)
			(min_thickness 0.25)
			(keepout
				(tracks allowed)
				(vias not_allowed)
				(pads allowed)
				(copperpour not_allowed)
				(footprints allowed)
			)
			(placement
				(enabled no)
				(sheetname "")
			)
			(fill
				(thermal_gap 0.5)
				(thermal_bridge_width 0.5)
				(island_removal_mode 0)
			)
			(polygon
				(pts
					(xy 393.616688 -153.806144) (xy 393.616688 -153.298144) (xy 393.997688 -153.298144) (xy 393.997688 -153.806144)
				)
			)
		)
		(zone
			(layer "B.Cu")
			(hatch none 0.5)
			(connect_pads
				(clearance 0)
			)
			(min_thickness 0.25)
			(keepout
				(tracks not_allowed)
				(vias allowed)
				(pads allowed)
				(copperpour not_allowed)
				(footprints allowed)
			)
			(placement
				(enabled no)
				(sheetname "")
			)
			(fill
				(thermal_gap 0.5)
				(thermal_bridge_width 0.5)
				(island_removal_mode 0)
			)
			(polygon
				(pts
					(xy 393.997688 -153.806144) (xy 393.997688 -153.298144) (xy 393.616688 -153.298144) (xy 393.616688 -153.806144)
				)
			)
		)
	)
	(footprint ""
		(layer "B.Cu")
		(at 101.3968 -12.954 90)
		(property "Reference" "C5G93"
			(at -1.14681 0.76708 180)
			(unlocked yes)
			(layer "B.SilkS")
			(effects
				(font
					(size 0.7874 0.5842)
					(thickness 0.1524)
				)
				(justify mirror)
			)
		)
		(property "Value" ""
			(at 0 0 90)
			(layer "B.Fab")
			(effects
				(font
					(size 1.27 1.27)
				)
				(justify mirror)
			)
		)
		(duplicate_pad_numbers_are_jumpers no)
		(fp_rect
			(start -0.4953 -0.2032)
			(end 0.4953 1.6002)
			(stroke
				(width 0)
				(type default)
			)
			(fill no)
			(layer "B.CrtYd")
		)
		(fp_line
			(start 0.4953 -0.2032)
			(end -0.4953 -0.2032)
			(stroke
				(width 0.1)
				(type default)
			)
			(layer "B.Fab")
		)
		(fp_line
			(start -0.4953 -0.2032)
			(end -0.4953 1.6002)
			(stroke
				(width 0.1)
				(type default)
			)
			(layer "B.Fab")
		)
		(fp_line
			(start 0.4953 1.6002)
			(end 0.4953 -0.2032)
			(stroke
				(width 0.1)
				(type default)
			)
			(layer "B.Fab")
		)
		(fp_line
			(start -0.4953 1.6002)
			(end 0.4953 1.6002)
			(stroke
				(width 0.1)
				(type default)
			)
			(layer "B.Fab")
		)
		(pad "1" smd rect
			(at 0 0 270)
			(size 0.762 0.889)
			(layers "B.Cu" "B.Mask" "B.Paste")
			(net "PVDDQ_GHJ")
		)
		(pad "2" smd rect
			(at 0 1.397 270)
			(size 0.762 0.889)
			(layers "B.Cu" "B.Mask" "B.Paste")
			(net "GND")
		)
		(zone
			(layer "B.Cu")
			(hatch none 0.5)
			(connect_pads
				(clearance 0)
			)
			(min_thickness 0.25)
			(keepout
				(tracks not_allowed)
				(vias allowed)
				(pads allowed)
				(copperpour not_allowed)
				(footprints allowed)
			)
			(placement
				(enabled no)
				(sheetname "")
			)
			(fill
				(thermal_gap 0.5)
				(thermal_bridge_width 0.5)
				(island_removal_mode 0)
			)
			(polygon
				(pts
					(xy 101.8413 -12.573) (xy 102.3493 -12.573) (xy 102.3493 -13.335) (xy 101.8413 -13.335)
				)
			)
		)
	)
	(footprint ""
		(layer "B.Cu")
		(at 390.906 -87.4395)
		(property "Reference" "R2N19"
			(at 0.8382 -0.67818 0)
			(unlocked yes)
			(layer "B.SilkS")
			(effects
				(font
					(size 0.4064 0.254)
					(thickness 0.1524)
				)
				(justify left mirror)
			)
		)
		(property "Value" ""
			(at 0 0 0)
			(layer "B.Fab")
			(effects
				(font
					(size 1.27 1.27)
				)
				(justify mirror)
			)
		)
		(duplicate_pad_numbers_are_jumpers no)
		(fp_poly
			(pts
				(xy 0.2794 -0.1016) (xy -0.2794 -0.1016) (xy -0.2794 0.9906) (xy 0.2794 0.9906)
			)
			(stroke
				(width 0)
				(type default)
			)
			(fill no)
			(layer "B.CrtYd")
		)
		(fp_line
			(start -0.2794 -0.1016)
			(end 0.2794 -0.1016)
			(stroke
				(width 0.1)
				(type default)
			)
			(layer "B.Fab")
		)
		(fp_line
			(start -0.2794 0.9906)
			(end -0.2794 -0.1016)
			(stroke
				(width 0.1)
				(type default)
			)
			(layer "B.Fab")
		)
		(fp_line
			(start 0.2794 -0.1016)
			(end 0.2794 0.9906)
			(stroke
				(width 0.1)
				(type default)
			)
			(layer "B.Fab")
		)
		(fp_line
			(start 0.2794 0.9906)
			(end -0.2794 0.9906)
			(stroke
				(width 0.1)
				(type default)
			)
			(layer "B.Fab")
		)
		(pad "1" smd rect
			(at 0 0 180)
			(size 0.508 0.508)
			(layers "B.Cu" "B.Mask" "B.Paste")
			(net "SGPIO_PCH_SSATA_LOAD")
		)
		(pad "2" smd rect
			(at 0 0.889 180)
			(size 0.508 0.508)
			(layers "B.Cu" "B.Mask" "B.Paste")
			(net "SGPIO_PCH_SSATA_LOAD_R")
		)
		(zone
			(layer "B.Cu")
			(hatch none 0.5)
			(connect_pads
				(clearance 0)
			)
			(min_thickness 0.25)
			(keepout
				(tracks allowed)
				(vias not_allowed)
				(pads allowed)
				(copperpour not_allowed)
				(footprints allowed)
			)
			(placement
				(enabled no)
				(sheetname "")
			)
			(fill
				(thermal_gap 0.5)
				(thermal_bridge_width 0.5)
				(island_removal_mode 0)
			)
			(polygon
				(pts
					(xy 391.16 -87.1855) (xy 390.652 -87.1855) (xy 390.652 -86.8045) (xy 391.16 -86.8045)
				)
			)
		)
		(zone
			(layer "B.Cu")
			(hatch none 0.5)
			(connect_pads
				(clearance 0)
			)
			(min_thickness 0.25)
			(keepout
				(tracks not_allowed)
				(vias allowed)
				(pads allowed)
				(copperpour not_allowed)
				(footprints allowed)
			)
			(placement
				(enabled no)
				(sheetname "")
			)
			(fill
				(thermal_gap 0.5)
				(thermal_bridge_width 0.5)
				(island_removal_mode 0)
			)
			(polygon
				(pts
					(xy 391.16 -86.8045) (xy 390.652 -86.8045) (xy 390.652 -87.1855) (xy 391.16 -87.1855)
				)
			)
		)
	)
	(footprint ""
		(layer "B.Cu")
		(at 410.7307 -8.8138 -90)
		(property "Reference" "R8D42"
			(at 0 0 90)
			(layer "B.SilkS")
			(hide yes)
			(effects
				(font
					(size 1.27 1.27)
				)
				(justify mirror)
			)
		)
		(property "Value" ""
			(at 0 0 90)
			(layer "B.Fab")
			(effects
				(font
					(size 1.27 1.27)
				)
				(justify mirror)
			)
		)
		(duplicate_pad_numbers_are_jumpers no)
		(fp_poly
			(pts
				(xy 0.2794 -0.1016) (xy -0.2794 -0.1016) (xy -0.2794 0.9906) (xy 0.2794 0.9906)
			)
			(stroke
				(width 0)
				(type default)
			)
			(fill no)
			(layer "B.CrtYd")
		)
		(fp_line
			(start -0.2794 0.9906)
			(end -0.2794 -0.1016)
			(stroke
				(width 0.1)
				(type default)
			)
			(layer "B.Fab")
		)
		(fp_line
			(start 0.2794 0.9906)
			(end -0.2794 0.9906)
			(stroke
				(width 0.1)
				(type default)
			)
			(layer "B.Fab")
		)
		(fp_line
			(start -0.2794 -0.1016)
			(end 0.2794 -0.1016)
			(stroke
				(width 0.1)
				(type default)
			)
			(layer "B.Fab")
		)
		(fp_line
			(start 0.2794 -0.1016)
			(end 0.2794 0.9906)
			(stroke
				(width 0.1)
				(type default)
			)
			(layer "B.Fab")
		)
		(pad "1" smd rect
			(at 0 0 90)
			(size 0.508 0.508)
			(layers "B.Cu" "B.Mask" "B.Paste")
			(net "PWRGD_P12V_MAIN_R")
		)
		(pad "2" smd rect
			(at 0 0.889 90)
			(size 0.508 0.508)
			(layers "B.Cu" "B.Mask" "B.Paste")
			(net "PWRGD_P12V_MAIN")
		)
		(zone
			(layer "B.Cu")
			(hatch none 0.5)
			(connect_pads
				(clearance 0)
			)
			(min_thickness 0.25)
			(keepout
				(tracks not_allowed)
				(vias allowed)
				(pads allowed)
				(copperpour not_allowed)
				(footprints allowed)
			)
			(placement
				(enabled no)
				(sheetname "")
			)
			(fill
				(thermal_gap 0.5)
				(thermal_bridge_width 0.5)
				(island_removal_mode 0)
			)
			(polygon
				(pts
					(xy 410.0957 -8.5598) (xy 410.0957 -9.0678) (xy 410.4767 -9.0678) (xy 410.4767 -8.5598)
				)
			)
		)
		(zone
			(layer "B.Cu")
			(hatch none 0.5)
			(connect_pads
				(clearance 0)
			)
			(min_thickness 0.25)
			(keepout
				(tracks allowed)
				(vias not_allowed)
				(pads allowed)
				(copperpour not_allowed)
				(footprints allowed)
			)
			(placement
				(enabled no)
				(sheetname "")
			)
			(fill
				(thermal_gap 0.5)
				(thermal_bridge_width 0.5)
				(island_removal_mode 0)
			)
			(polygon
				(pts
					(xy 410.4767 -8.5598) (xy 410.4767 -9.0678) (xy 410.0957 -9.0678) (xy 410.0957 -8.5598)
				)
			)
		)
	)
	(footprint ""
		(layer "B.Cu")
		(at 258.1656 -3.321812 -90)
		(property "Reference" "C5G54"
			(at -1.14681 0.76708 0)
			(unlocked yes)
			(layer "B.SilkS")
			(effects
				(font
					(size 0.7874 0.5842)
					(thickness 0.1524)
				)
				(justify mirror)
			)
		)
		(property "Value" ""
			(at 0 0 90)
			(layer "B.Fab")
			(effects
				(font
					(size 1.27 1.27)
				)
				(justify mirror)
			)
		)
		(duplicate_pad_numbers_are_jumpers no)
		(fp_rect
			(start 0.4953 1.6002)
			(end -0.4953 -0.2032)
			(stroke
				(width 0)
				(type default)
			)
			(fill no)
			(layer "B.CrtYd")
		)
		(fp_line
			(start -0.4953 1.6002)
			(end 0.4953 1.6002)
			(stroke
				(width 0.1)
				(type default)
			)
			(layer "B.Fab")
		)
		(fp_line
			(start 0.4953 1.6002)
			(end 0.4953 -0.2032)
			(stroke
				(width 0.1)
				(type default)
			)
			(layer "B.Fab")
		)
		(fp_line
			(start -0.4953 -0.2032)
			(end -0.4953 1.6002)
			(stroke
				(width 0.1)
				(type default)
			)
			(layer "B.Fab")
		)
		(fp_line
			(start 0.4953 -0.2032)
			(end -0.4953 -0.2032)
			(stroke
				(width 0.1)
				(type default)
			)
			(layer "B.Fab")
		)
		(pad "1" smd rect
			(at 0 0 90)
			(size 0.762 0.889)
			(layers "B.Cu" "B.Mask" "B.Paste")
			(net "PVDDQ_ABC")
		)
		(pad "2" smd rect
			(at 0 1.397 90)
			(size 0.762 0.889)
			(layers "B.Cu" "B.Mask" "B.Paste")
			(net "GND")
		)
		(zone
			(layer "B.Cu")
			(hatch none 0.5)
			(connect_pads
				(clearance 0)
			)
			(min_thickness 0.25)
			(keepout
				(tracks not_allowed)
				(vias allowed)
				(pads allowed)
				(copperpour not_allowed)
				(footprints allowed)
			)
			(placement
				(enabled no)
				(sheetname "")
			)
			(fill
				(thermal_gap 0.5)
				(thermal_bridge_width 0.5)
				(island_removal_mode 0)
			)
			(polygon
				(pts
					(xy 257.2131 -2.940812) (xy 257.7211 -2.940812) (xy 257.7211 -3.702812) (xy 257.2131 -3.702812)
				)
			)
		)
	)
	(footprint ""
		(layer "B.Cu")
		(at 258.548886 -77.82814)
		(property "Reference" "C5P27"
			(at 0 0 0)
			(layer "B.SilkS")
			(hide yes)
			(effects
				(font
					(size 1.27 1.27)
				)
				(justify mirror)
			)
		)
		(property "Value" ""
			(at 0 0 0)
			(layer "B.Fab")
			(effects
				(font
					(size 1.27 1.27)
				)
				(justify mirror)
			)
		)
		(duplicate_pad_numbers_are_jumpers no)
		(fp_poly
			(pts
				(xy 0.7239 -0.2159) (xy -0.7239 -0.2159) (xy -0.7239 1.9939) (xy 0.7239 1.9939)
			)
			(stroke
				(width 0)
				(type default)
			)
			(fill no)
			(layer "B.CrtYd")
		)
		(fp_line
			(start -0.7239 -0.2159)
			(end 0.7239 -0.2159)
			(stroke
				(width 0.1)
				(type default)
			)
			(layer "B.Fab")
		)
		(fp_line
			(start -0.7239 1.9939)
			(end -0.7239 -0.2159)
			(stroke
				(width 0.1)
				(type default)
			)
			(layer "B.Fab")
		)
		(fp_line
			(start 0.7239 -0.2159)
			(end 0.7239 1.9939)
			(stroke
				(width 0.1)
				(type default)
			)
			(layer "B.Fab")
		)
		(fp_line
			(start 0.7239 1.9939)
			(end -0.7239 1.9939)
			(stroke
				(width 0.1)
				(type default)
			)
			(layer "B.Fab")
		)
		(pad "1" smd rect
			(at 0 0 180)
			(size 1.27 1.016)
			(layers "B.Cu" "B.Mask" "B.Paste")
			(net "PVCCIN_CPU0")
		)
		(pad "2" smd rect
			(at 0 1.778 180)
			(size 1.27 1.016)
			(layers "B.Cu" "B.Mask" "B.Paste")
			(net "GND")
		)
		(zone
			(layer "B.Cu")
			(hatch none 0.5)
			(connect_pads
				(clearance 0)
			)
			(min_thickness 0.25)
			(keepout
				(tracks not_allowed)
				(vias allowed)
				(pads allowed)
				(copperpour not_allowed)
				(footprints allowed)
			)
			(placement
				(enabled no)
				(sheetname "")
			)
			(fill
				(thermal_gap 0.5)
				(thermal_bridge_width 0.5)
				(island_removal_mode 0)
			)
			(polygon
				(pts
					(xy 259.183886 -77.32014) (xy 257.913886 -77.32014) (xy 257.913886 -76.55814) (xy 259.183886 -76.55814)
				)
			)
		)
	)
	(footprint ""
		(layer "B.Cu")
		(at 110.318296 -156.910024 -90)
		(property "Reference" "C7L1"
			(at 0 0 90)
			(layer "B.SilkS")
			(hide yes)
			(effects
				(font
					(size 1.27 1.27)
				)
				(justify mirror)
			)
		)
		(property "Value" ""
			(at 0 0 90)
			(layer "B.Fab")
			(effects
				(font
					(size 1.27 1.27)
				)
				(justify mirror)
			)
		)
		(duplicate_pad_numbers_are_jumpers no)
		(fp_poly
			(pts
				(xy 0.7239 -0.2159) (xy -0.7239 -0.2159) (xy -0.7239 1.9939) (xy 0.7239 1.9939)
			)
			(stroke
				(width 0)
				(type default)
			)
			(fill no)
			(layer "B.CrtYd")
		)
		(fp_line
			(start -0.7239 1.9939)
			(end -0.7239 -0.2159)
			(stroke
				(width 0.1)
				(type default)
			)
			(layer "B.Fab")
		)
		(fp_line
			(start 0.7239 1.9939)
			(end -0.7239 1.9939)
			(stroke
				(width 0.1)
				(type default)
			)
			(layer "B.Fab")
		)
		(fp_line
			(start -0.7239 -0.2159)
			(end 0.7239 -0.2159)
			(stroke
				(width 0.1)
				(type default)
			)
			(layer "B.Fab")
		)
		(fp_line
			(start 0.7239 -0.2159)
			(end 0.7239 1.9939)
			(stroke
				(width 0.1)
				(type default)
			)
			(layer "B.Fab")
		)
		(pad "1" smd rect
			(at 0 0 90)
			(size 1.27 1.016)
			(layers "B.Cu" "B.Mask" "B.Paste")
			(net "PVDDQ_KLM")
		)
		(pad "2" smd rect
			(at 0 1.778 90)
			(size 1.27 1.016)
			(layers "B.Cu" "B.Mask" "B.Paste")
			(net "GND")
		)
		(zone
			(layer "B.Cu")
			(hatch none 0.5)
			(connect_pads
				(clearance 0)
			)
			(min_thickness 0.25)
			(keepout
				(tracks not_allowed)
				(vias allowed)
				(pads allowed)
				(copperpour not_allowed)
				(footprints allowed)
			)
			(placement
				(enabled no)
				(sheetname "")
			)
			(fill
				(thermal_gap 0.5)
				(thermal_bridge_width 0.5)
				(island_removal_mode 0)
			)
			(polygon
				(pts
					(xy 109.810296 -156.275024) (xy 109.810296 -157.545024) (xy 109.048296 -157.545024) (xy 109.048296 -156.275024)
				)
			)
		)
	)
	(footprint ""
		(layer "B.Cu")
		(at 14.66723 -122.874278 180)
		(property "Reference" "C10W1"
			(at -1.47828 0.78994 270)
			(unlocked yes)
			(layer "B.SilkS")
			(effects
				(font
					(size 0.4064 0.254)
					(thickness 0.1524)
				)
				(justify mirror)
			)
		)
		(property "Value" ""
			(at 0 0 0)
			(layer "B.Fab")
			(effects
				(font
					(size 1.27 1.27)
				)
				(justify mirror)
			)
		)
		(duplicate_pad_numbers_are_jumpers no)
		(fp_poly
			(pts
				(xy 0.7239 -0.2159) (xy -0.7239 -0.2159) (xy -0.7239 1.9939) (xy 0.7239 1.9939)
			)
			(stroke
				(width 0)
				(type default)
			)
			(fill no)
			(layer "B.CrtYd")
		)
		(fp_line
			(start 0.7239 1.9939)
			(end -0.7239 1.9939)
			(stroke
				(width 0.1)
				(type default)
			)
			(layer "B.Fab")
		)
		(fp_line
			(start 0.7239 -0.2159)
			(end 0.7239 1.9939)
			(stroke
				(width 0.1)
				(type default)
			)
			(layer "B.Fab")
		)
		(fp_line
			(start -0.7239 1.9939)
			(end -0.7239 -0.2159)
			(stroke
				(width 0.1)
				(type default)
			)
			(layer "B.Fab")
		)
		(fp_line
			(start -0.7239 -0.2159)
			(end 0.7239 -0.2159)
			(stroke
				(width 0.1)
				(type default)
			)
			(layer "B.Fab")
		)
		(pad "1" smd rect
			(at 0 0)
			(size 1.27 1.016)
			(layers "B.Cu" "B.Mask" "B.Paste")
			(net "P12V_PUMP")
		)
		(pad "2" smd rect
			(at 0 1.778)
			(size 1.27 1.016)
			(layers "B.Cu" "B.Mask" "B.Paste")
			(net "GND")
		)
		(zone
			(layer "B.Cu")
			(hatch none 0.5)
			(connect_pads
				(clearance 0)
			)
			(min_thickness 0.25)
			(keepout
				(tracks not_allowed)
				(vias allowed)
				(pads allowed)
				(copperpour not_allowed)
				(footprints allowed)
			)
			(placement
				(enabled no)
				(sheetname "")
			)
			(fill
				(thermal_gap 0.5)
				(thermal_bridge_width 0.5)
				(island_removal_mode 0)
			)
			(polygon
				(pts
					(xy 14.03223 -123.382278) (xy 15.30223 -123.382278) (xy 15.30223 -124.144278) (xy 14.03223 -124.144278)
				)
			)
		)
	)
	(footprint ""
		(layer "B.Cu")
		(at 410.464 -149.95652 90)
		(property "Reference" "C2L18"
			(at 0 0 90)
			(layer "B.SilkS")
			(hide yes)
			(effects
				(font
					(size 1.27 1.27)
				)
				(justify mirror)
			)
		)
		(property "Value" ""
			(at 0 0 90)
			(layer "B.Fab")
			(effects
				(font
					(size 1.27 1.27)
				)
				(justify mirror)
			)
		)
		(duplicate_pad_numbers_are_jumpers no)
		(fp_poly
			(pts
				(xy -0.3048 -0.1016) (xy -0.3048 0.9906) (xy 0.3048 0.9906) (xy 0.3048 -0.1016)
			)
			(stroke
				(width 0)
				(type default)
			)
			(fill no)
			(layer "B.CrtYd")
		)
		(fp_line
			(start 0.3048 -0.1016)
			(end 0.3048 0.9906)
			(stroke
				(width 0.1)
				(type default)
			)
			(layer "B.Fab")
		)
		(fp_line
			(start -0.3048 -0.1016)
			(end 0.3048 -0.1016)
			(stroke
				(width 0.1)
				(type default)
			)
			(layer "B.Fab")
		)
		(fp_line
			(start 0.3048 0.9906)
			(end -0.3048 0.9906)
			(stroke
				(width 0.1)
				(type default)
			)
			(layer "B.Fab")
		)
		(fp_line
			(start -0.3048 0.9906)
			(end -0.3048 -0.1016)
			(stroke
				(width 0.1)
				(type default)
			)
			(layer "B.Fab")
		)
		(pad "1" smd rect
			(at 0 0 270)
			(size 0.508 0.508)
			(layers "B.Cu" "B.Mask" "B.Paste")
			(net "SATA6G_PCH_PCIE_UP_SATA_RXN<4>")
		)
		(pad "2" smd rect
			(at 0 0.889 270)
			(size 0.508 0.508)
			(layers "B.Cu" "B.Mask" "B.Paste")
			(net "SATA6G_P4_RX_C_DN")
		)
		(zone
			(layer "B.Cu")
			(hatch none 0.5)
			(connect_pads
				(clearance 0)
			)
			(min_thickness 0.25)
			(keepout
				(tracks allowed)
				(vias not_allowed)
				(pads allowed)
				(copperpour not_allowed)
				(footprints allowed)
			)
			(placement
				(enabled no)
				(sheetname "")
			)
			(fill
				(thermal_gap 0.5)
				(thermal_bridge_width 0.5)
				(island_removal_mode 0)
			)
			(polygon
				(pts
					(xy 410.718 -150.21052) (xy 410.718 -149.70252) (xy 411.099 -149.70252) (xy 411.099 -150.21052)
				)
			)
		)
		(zone
			(layer "B.Cu")
			(hatch none 0.5)
			(connect_pads
				(clearance 0)
			)
			(min_thickness 0.25)
			(keepout
				(tracks not_allowed)
				(vias allowed)
				(pads allowed)
				(copperpour not_allowed)
				(footprints allowed)
			)
			(placement
				(enabled no)
				(sheetname "")
			)
			(fill
				(thermal_gap 0.5)
				(thermal_bridge_width 0.5)
				(island_removal_mode 0)
			)
			(polygon
				(pts
					(xy 411.099 -150.21052) (xy 411.099 -149.70252) (xy 410.718 -149.70252) (xy 410.718 -150.21052)
				)
			)
		)
	)
	(footprint ""
		(layer "B.Cu")
		(at 110.388654 -79.60614 180)
		(property "Reference" "C7P6"
			(at 0 0 0)
			(layer "B.SilkS")
			(hide yes)
			(effects
				(font
					(size 1.27 1.27)
				)
				(justify mirror)
			)
		)
		(property "Value" ""
			(at 0 0 0)
			(layer "B.Fab")
			(effects
				(font
					(size 1.27 1.27)
				)
				(justify mirror)
			)
		)
		(duplicate_pad_numbers_are_jumpers no)
		(fp_poly
			(pts
				(xy 0.7239 -0.2159) (xy -0.7239 -0.2159) (xy -0.7239 1.9939) (xy 0.7239 1.9939)
			)
			(stroke
				(width 0)
				(type default)
			)
			(fill no)
			(layer "B.CrtYd")
		)
		(fp_line
			(start 0.7239 1.9939)
			(end -0.7239 1.9939)
			(stroke
				(width 0.1)
				(type default)
			)
			(layer "B.Fab")
		)
		(fp_line
			(start 0.7239 -0.2159)
			(end 0.7239 1.9939)
			(stroke
				(width 0.1)
				(type default)
			)
			(layer "B.Fab")
		)
		(fp_line
			(start -0.7239 1.9939)
			(end -0.7239 -0.2159)
			(stroke
				(width 0.1)
				(type default)
			)
			(layer "B.Fab")
		)
		(fp_line
			(start -0.7239 -0.2159)
			(end 0.7239 -0.2159)
			(stroke
				(width 0.1)
				(type default)
			)
			(layer "B.Fab")
		)
		(pad "1" smd rect
			(at 0 0)
			(size 1.27 1.016)
			(layers "B.Cu" "B.Mask" "B.Paste")
			(net "PVCCMCP_CPU1")
		)
		(pad "2" smd rect
			(at 0 1.778)
			(size 1.27 1.016)
			(layers "B.Cu" "B.Mask" "B.Paste")
			(net "GND")
		)
		(zone
			(layer "B.Cu")
			(hatch none 0.5)
			(connect_pads
				(clearance 0)
			)
			(min_thickness 0.25)
			(keepout
				(tracks not_allowed)
				(vias allowed)
				(pads allowed)
				(copperpour not_allowed)
				(footprints allowed)
			)
			(placement
				(enabled no)
				(sheetname "")
			)
			(fill
				(thermal_gap 0.5)
				(thermal_bridge_width 0.5)
				(island_removal_mode 0)
			)
			(polygon
				(pts
					(xy 109.753654 -80.11414) (xy 111.023654 -80.11414) (xy 111.023654 -80.87614) (xy 109.753654 -80.87614)
				)
			)
		)
	)
	(footprint ""
		(layer "B.Cu")
		(at 375.062242 -40.662352 -90)
		(property "Reference" "R2T20"
			(at 0 0 90)
			(layer "B.SilkS")
			(hide yes)
			(effects
				(font
					(size 1.27 1.27)
				)
				(justify mirror)
			)
		)
		(property "Value" ""
			(at 0 0 90)
			(layer "B.Fab")
			(effects
				(font
					(size 1.27 1.27)
				)
				(justify mirror)
			)
		)
		(duplicate_pad_numbers_are_jumpers no)
		(fp_poly
			(pts
				(xy 0.2794 -0.1016) (xy -0.2794 -0.1016) (xy -0.2794 0.9906) (xy 0.2794 0.9906)
			)
			(stroke
				(width 0)
				(type default)
			)
			(fill no)
			(layer "B.CrtYd")
		)
		(fp_line
			(start -0.2794 0.9906)
			(end -0.2794 -0.1016)
			(stroke
				(width 0.1)
				(type default)
			)
			(layer "B.Fab")
		)
		(fp_line
			(start 0.2794 0.9906)
			(end -0.2794 0.9906)
			(stroke
				(width 0.1)
				(type default)
			)
			(layer "B.Fab")
		)
		(fp_line
			(start -0.2794 -0.1016)
			(end 0.2794 -0.1016)
			(stroke
				(width 0.1)
				(type default)
			)
			(layer "B.Fab")
		)
		(fp_line
			(start 0.2794 -0.1016)
			(end 0.2794 0.9906)
			(stroke
				(width 0.1)
				(type default)
			)
			(layer "B.Fab")
		)
		(pad "1" smd rect
			(at 0 0 90)
			(size 0.508 0.508)
			(layers "B.Cu" "B.Mask" "B.Paste")
			(net "H_CPU1_ERR0_G_N")
		)
		(pad "2" smd rect
			(at 0 0.889 90)
			(size 0.508 0.508)
			(layers "B.Cu" "B.Mask" "B.Paste")
			(net "H_CPU_ERR0_GTL_R_N")
		)
		(zone
			(layer "B.Cu")
			(hatch none 0.5)
			(connect_pads
				(clearance 0)
			)
			(min_thickness 0.25)
			(keepout
				(tracks not_allowed)
				(vias allowed)
				(pads allowed)
				(copperpour not_allowed)
				(footprints allowed)
			)
			(placement
				(enabled no)
				(sheetname "")
			)
			(fill
				(thermal_gap 0.5)
				(thermal_bridge_width 0.5)
				(island_removal_mode 0)
			)
			(polygon
				(pts
					(xy 374.427242 -40.408352) (xy 374.427242 -40.916352) (xy 374.808242 -40.916352) (xy 374.808242 -40.408352)
				)
			)
		)
		(zone
			(layer "B.Cu")
			(hatch none 0.5)
			(connect_pads
				(clearance 0)
			)
			(min_thickness 0.25)
			(keepout
				(tracks allowed)
				(vias not_allowed)
				(pads allowed)
				(copperpour not_allowed)
				(footprints allowed)
			)
			(placement
				(enabled no)
				(sheetname "")
			)
			(fill
				(thermal_gap 0.5)
				(thermal_bridge_width 0.5)
				(island_removal_mode 0)
			)
			(polygon
				(pts
					(xy 374.808242 -40.408352) (xy 374.808242 -40.916352) (xy 374.427242 -40.916352) (xy 374.427242 -40.408352)
				)
			)
		)
	)
	(footprint ""
		(layer "B.Cu")
		(at 412.75 -46.052232)
		(property "Reference" "R25W74"
			(at 0.8382 -0.67818 0)
			(unlocked yes)
			(layer "B.SilkS")
			(effects
				(font
					(size 0.4064 0.254)
					(thickness 0.1524)
				)
				(justify left mirror)
			)
		)
		(property "Value" ""
			(at 0 0 0)
			(layer "B.Fab")
			(effects
				(font
					(size 1.27 1.27)
				)
				(justify mirror)
			)
		)
		(duplicate_pad_numbers_are_jumpers no)
		(fp_poly
			(pts
				(xy 0.2794 -0.1016) (xy -0.2794 -0.1016) (xy -0.2794 0.9906) (xy 0.2794 0.9906)
			)
			(stroke
				(width 0)
				(type default)
			)
			(fill no)
			(layer "B.CrtYd")
		)
		(fp_line
			(start -0.2794 -0.1016)
			(end 0.2794 -0.1016)
			(stroke
				(width 0.1)
				(type default)
			)
			(layer "B.Fab")
		)
		(fp_line
			(start -0.2794 0.9906)
			(end -0.2794 -0.1016)
			(stroke
				(width 0.1)
				(type default)
			)
			(layer "B.Fab")
		)
		(fp_line
			(start 0.2794 -0.1016)
			(end 0.2794 0.9906)
			(stroke
				(width 0.1)
				(type default)
			)
			(layer "B.Fab")
		)
		(fp_line
			(start 0.2794 0.9906)
			(end -0.2794 0.9906)
			(stroke
				(width 0.1)
				(type default)
			)
			(layer "B.Fab")
		)
		(pad "1" smd rect
			(at 0 0 180)
			(size 0.508 0.508)
			(layers "B.Cu" "B.Mask" "B.Paste")
			(net "RST_PLTRST_BUF_N")
		)
		(pad "2" smd rect
			(at 0 0.889 180)
			(size 0.508 0.508)
			(layers "B.Cu" "B.Mask" "B.Paste")
			(net "RST_BMC_LVC3_N")
		)
		(zone
			(layer "B.Cu")
			(hatch none 0.5)
			(connect_pads
				(clearance 0)
			)
			(min_thickness 0.25)
			(keepout
				(tracks allowed)
				(vias not_allowed)
				(pads allowed)
				(copperpour not_allowed)
				(footprints allowed)
			)
			(placement
				(enabled no)
				(sheetname "")
			)
			(fill
				(thermal_gap 0.5)
				(thermal_bridge_width 0.5)
				(island_removal_mode 0)
			)
			(polygon
				(pts
					(xy 413.004 -45.798232) (xy 412.496 -45.798232) (xy 412.496 -45.417232) (xy 413.004 -45.417232)
				)
			)
		)
		(zone
			(layer "B.Cu")
			(hatch none 0.5)
			(connect_pads
				(clearance 0)
			)
			(min_thickness 0.25)
			(keepout
				(tracks not_allowed)
				(vias allowed)
				(pads allowed)
				(copperpour not_allowed)
				(footprints allowed)
			)
			(placement
				(enabled no)
				(sheetname "")
			)
			(fill
				(thermal_gap 0.5)
				(thermal_bridge_width 0.5)
				(island_removal_mode 0)
			)
			(polygon
				(pts
					(xy 413.004 -45.417232) (xy 412.496 -45.417232) (xy 412.496 -45.798232) (xy 413.004 -45.798232)
				)
			)
		)
	)
	(footprint ""
		(layer "B.Cu")
		(at 20.447 -69.85 180)
		(property "Reference" "R9P29"
			(at 0 0 0)
			(layer "B.SilkS")
			(hide yes)
			(effects
				(font
					(size 1.27 1.27)
				)
				(justify mirror)
			)
		)
		(property "Value" ""
			(at 0 0 0)
			(layer "B.Fab")
			(effects
				(font
					(size 1.27 1.27)
				)
				(justify mirror)
			)
		)
		(duplicate_pad_numbers_are_jumpers no)
		(fp_poly
			(pts
				(xy 0.2794 -0.1016) (xy -0.2794 -0.1016) (xy -0.2794 0.9906) (xy 0.2794 0.9906)
			)
			(stroke
				(width 0)
				(type default)
			)
			(fill no)
			(layer "B.CrtYd")
		)
		(fp_line
			(start 0.2794 0.9906)
			(end -0.2794 0.9906)
			(stroke
				(width 0.1)
				(type default)
			)
			(layer "B.Fab")
		)
		(fp_line
			(start 0.2794 -0.1016)
			(end 0.2794 0.9906)
			(stroke
				(width 0.1)
				(type default)
			)
			(layer "B.Fab")
		)
		(fp_line
			(start -0.2794 0.9906)
			(end -0.2794 -0.1016)
			(stroke
				(width 0.1)
				(type default)
			)
			(layer "B.Fab")
		)
		(fp_line
			(start -0.2794 -0.1016)
			(end 0.2794 -0.1016)
			(stroke
				(width 0.1)
				(type default)
			)
			(layer "B.Fab")
		)
		(pad "1" smd rect
			(at 0 0)
			(size 0.508 0.508)
			(layers "B.Cu" "B.Mask" "B.Paste")
			(net "P12V_PSU")
		)
		(pad "2" smd rect
			(at 0 0.889)
			(size 0.508 0.508)
			(layers "B.Cu" "B.Mask" "B.Paste")
			(net "A_HSC_UV")
		)
		(zone
			(layer "B.Cu")
			(hatch none 0.5)
			(connect_pads
				(clearance 0)
			)
			(min_thickness 0.25)
			(keepout
				(tracks not_allowed)
				(vias allowed)
				(pads allowed)
				(copperpour not_allowed)
				(footprints allowed)
			)
			(placement
				(enabled no)
				(sheetname "")
			)
			(fill
				(thermal_gap 0.5)
				(thermal_bridge_width 0.5)
				(island_removal_mode 0)
			)
			(polygon
				(pts
					(xy 20.193 -70.485) (xy 20.701 -70.485) (xy 20.701 -70.104) (xy 20.193 -70.104)
				)
			)
		)
		(zone
			(layer "B.Cu")
			(hatch none 0.5)
			(connect_pads
				(clearance 0)
			)
			(min_thickness 0.25)
			(keepout
				(tracks allowed)
				(vias not_allowed)
				(pads allowed)
				(copperpour not_allowed)
				(footprints allowed)
			)
			(placement
				(enabled no)
				(sheetname "")
			)
			(fill
				(thermal_gap 0.5)
				(thermal_bridge_width 0.5)
				(island_removal_mode 0)
			)
			(polygon
				(pts
					(xy 20.193 -70.104) (xy 20.701 -70.104) (xy 20.701 -70.485) (xy 20.193 -70.485)
				)
			)
		)
	)
	(footprint ""
		(layer "B.Cu")
		(at 385.217924 -24.885904 90)
		(property "Reference" "C2T20"
			(at 0 0 90)
			(layer "B.SilkS")
			(hide yes)
			(effects
				(font
					(size 1.27 1.27)
				)
				(justify mirror)
			)
		)
		(property "Value" ""
			(at 0 0 90)
			(layer "B.Fab")
			(effects
				(font
					(size 1.27 1.27)
				)
				(justify mirror)
			)
		)
		(duplicate_pad_numbers_are_jumpers no)
		(fp_poly
			(pts
				(xy -0.3048 -0.1016) (xy -0.3048 0.9906) (xy 0.3048 0.9906) (xy 0.3048 -0.1016)
			)
			(stroke
				(width 0)
				(type default)
			)
			(fill no)
			(layer "B.CrtYd")
		)
		(fp_line
			(start 0.3048 -0.1016)
			(end 0.3048 0.9906)
			(stroke
				(width 0.1)
				(type default)
			)
			(layer "B.Fab")
		)
		(fp_line
			(start -0.3048 -0.1016)
			(end 0.3048 -0.1016)
			(stroke
				(width 0.1)
				(type default)
			)
			(layer "B.Fab")
		)
		(fp_line
			(start 0.3048 0.9906)
			(end -0.3048 0.9906)
			(stroke
				(width 0.1)
				(type default)
			)
			(layer "B.Fab")
		)
		(fp_line
			(start -0.3048 0.9906)
			(end -0.3048 -0.1016)
			(stroke
				(width 0.1)
				(type default)
			)
			(layer "B.Fab")
		)
		(pad "1" smd rect
			(at 0 0 270)
			(size 0.508 0.508)
			(layers "B.Cu" "B.Mask" "B.Paste")
			(net "P3E_PCH_M2_TX_C_DP<3>")
		)
		(pad "2" smd rect
			(at 0 0.889 270)
			(size 0.508 0.508)
			(layers "B.Cu" "B.Mask" "B.Paste")
			(net "P3E_PCH_M2_TX_DP<3>")
		)
		(zone
			(layer "B.Cu")
			(hatch none 0.5)
			(connect_pads
				(clearance 0)
			)
			(min_thickness 0.25)
			(keepout
				(tracks allowed)
				(vias not_allowed)
				(pads allowed)
				(copperpour not_allowed)
				(footprints allowed)
			)
			(placement
				(enabled no)
				(sheetname "")
			)
			(fill
				(thermal_gap 0.5)
				(thermal_bridge_width 0.5)
				(island_removal_mode 0)
			)
			(polygon
				(pts
					(xy 385.471924 -25.139904) (xy 385.471924 -24.631904) (xy 385.852924 -24.631904) (xy 385.852924 -25.139904)
				)
			)
		)
		(zone
			(layer "B.Cu")
			(hatch none 0.5)
			(connect_pads
				(clearance 0)
			)
			(min_thickness 0.25)
			(keepout
				(tracks not_allowed)
				(vias allowed)
				(pads allowed)
				(copperpour not_allowed)
				(footprints allowed)
			)
			(placement
				(enabled no)
				(sheetname "")
			)
			(fill
				(thermal_gap 0.5)
				(thermal_bridge_width 0.5)
				(island_removal_mode 0)
			)
			(polygon
				(pts
					(xy 385.852924 -25.139904) (xy 385.852924 -24.631904) (xy 385.471924 -24.631904) (xy 385.471924 -25.139904)
				)
			)
		)
	)
	(footprint ""
		(layer "B.Cu")
		(at 371.05209 -65.411604 180)
		(property "Reference" "R3R15"
			(at 0 0 0)
			(layer "B.SilkS")
			(hide yes)
			(effects
				(font
					(size 1.27 1.27)
				)
				(justify mirror)
			)
		)
		(property "Value" ""
			(at 0 0 0)
			(layer "B.Fab")
			(effects
				(font
					(size 1.27 1.27)
				)
				(justify mirror)
			)
		)
		(duplicate_pad_numbers_are_jumpers no)
		(fp_poly
			(pts
				(xy 0.2794 -0.1016) (xy -0.2794 -0.1016) (xy -0.2794 0.9906) (xy 0.2794 0.9906)
			)
			(stroke
				(width 0)
				(type default)
			)
			(fill no)
			(layer "B.CrtYd")
		)
		(fp_line
			(start 0.2794 0.9906)
			(end -0.2794 0.9906)
			(stroke
				(width 0.1)
				(type default)
			)
			(layer "B.Fab")
		)
		(fp_line
			(start 0.2794 -0.1016)
			(end 0.2794 0.9906)
			(stroke
				(width 0.1)
				(type default)
			)
			(layer "B.Fab")
		)
		(fp_line
			(start -0.2794 0.9906)
			(end -0.2794 -0.1016)
			(stroke
				(width 0.1)
				(type default)
			)
			(layer "B.Fab")
		)
		(fp_line
			(start -0.2794 -0.1016)
			(end 0.2794 -0.1016)
			(stroke
				(width 0.1)
				(type default)
			)
			(layer "B.Fab")
		)
		(pad "1" smd rect
			(at 0 0)
			(size 0.508 0.508)
			(layers "B.Cu" "B.Mask" "B.Paste")
			(net "P3V3_STBY")
		)
		(pad "2" smd rect
			(at 0 0.889)
			(size 0.508 0.508)
			(layers "B.Cu" "B.Mask" "B.Paste")
			(net "FM_JTAG_PLD_EN_DEBUG")
		)
		(zone
			(layer "B.Cu")
			(hatch none 0.5)
			(connect_pads
				(clearance 0)
			)
			(min_thickness 0.25)
			(keepout
				(tracks not_allowed)
				(vias allowed)
				(pads allowed)
				(copperpour not_allowed)
				(footprints allowed)
			)
			(placement
				(enabled no)
				(sheetname "")
			)
			(fill
				(thermal_gap 0.5)
				(thermal_bridge_width 0.5)
				(island_removal_mode 0)
			)
			(polygon
				(pts
					(xy 370.79809 -66.046604) (xy 371.30609 -66.046604) (xy 371.30609 -65.665604) (xy 370.79809 -65.665604)
				)
			)
		)
		(zone
			(layer "B.Cu")
			(hatch none 0.5)
			(connect_pads
				(clearance 0)
			)
			(min_thickness 0.25)
			(keepout
				(tracks allowed)
				(vias not_allowed)
				(pads allowed)
				(copperpour not_allowed)
				(footprints allowed)
			)
			(placement
				(enabled no)
				(sheetname "")
			)
			(fill
				(thermal_gap 0.5)
				(thermal_bridge_width 0.5)
				(island_removal_mode 0)
			)
			(polygon
				(pts
					(xy 370.79809 -65.665604) (xy 371.30609 -65.665604) (xy 371.30609 -66.046604) (xy 370.79809 -66.046604)
				)
			)
		)
	)
	(footprint ""
		(layer "B.Cu")
		(at 276.9362 -29.337 90)
		(property "Reference" "R4U6"
			(at 0 0 90)
			(layer "B.SilkS")
			(hide yes)
			(effects
				(font
					(size 1.27 1.27)
				)
				(justify mirror)
			)
		)
		(property "Value" ""
			(at 0 0 90)
			(layer "B.Fab")
			(effects
				(font
					(size 1.27 1.27)
				)
				(justify mirror)
			)
		)
		(duplicate_pad_numbers_are_jumpers no)
		(fp_rect
			(start -0.2794 0.9906)
			(end 0.2794 -0.1016)
			(stroke
				(width 0)
				(type default)
			)
			(fill no)
			(layer "B.CrtYd")
		)
		(fp_line
			(start 0.2794 -0.1016)
			(end 0.2794 0.9906)
			(stroke
				(width 0.1)
				(type default)
			)
			(layer "B.Fab")
		)
		(fp_line
			(start -0.2794 -0.1016)
			(end 0.2794 -0.1016)
			(stroke
				(width 0.1)
				(type default)
			)
			(layer "B.Fab")
		)
		(fp_line
			(start 0.2794 0.9906)
			(end -0.2794 0.9906)
			(stroke
				(width 0.1)
				(type default)
			)
			(layer "B.Fab")
		)
		(fp_line
			(start -0.2794 0.9906)
			(end -0.2794 -0.1016)
			(stroke
				(width 0.1)
				(type default)
			)
			(layer "B.Fab")
		)
		(pad "1" smd rect
			(at 0 0 270)
			(size 0.508 0.508)
			(layers "B.Cu" "B.Mask" "B.Paste")
			(net "VSENSE_PVDDQ_ABC_P")
		)
		(pad "2" smd rect
			(at 0 0.889 270)
			(size 0.508 0.508)
			(layers "B.Cu" "B.Mask" "B.Paste")
			(net "VSENSE_PVDDQ_ABC_N")
		)
		(zone
			(layer "B.Cu")
			(hatch none 0.5)
			(connect_pads
				(clearance 0)
			)
			(min_thickness 0.25)
			(keepout
				(tracks allowed)
				(vias not_allowed)
				(pads allowed)
				(copperpour not_allowed)
				(footprints allowed)
			)
			(placement
				(enabled no)
				(sheetname "")
			)
			(fill
				(thermal_gap 0.5)
				(thermal_bridge_width 0.5)
				(island_removal_mode 0)
			)
			(polygon
				(pts
					(xy 277.5712 -29.083) (xy 277.5712 -29.591) (xy 277.1902 -29.591) (xy 277.1902 -29.083)
				)
			)
		)
	)
	(footprint ""
		(layer "B.Cu")
		(at 392.382756 -19.68119 180)
		(property "Reference" "R32W7"
			(at 0.8382 -0.67818 180)
			(unlocked yes)
			(layer "B.SilkS")
			(effects
				(font
					(size 0.4064 0.254)
					(thickness 0.1524)
				)
				(justify left mirror)
			)
		)
		(property "Value" ""
			(at 0 0 0)
			(layer "B.Fab")
			(effects
				(font
					(size 1.27 1.27)
				)
				(justify mirror)
			)
		)
		(duplicate_pad_numbers_are_jumpers no)
		(fp_poly
			(pts
				(xy 0.2794 -0.1016) (xy -0.2794 -0.1016) (xy -0.2794 0.9906) (xy 0.2794 0.9906)
			)
			(stroke
				(width 0)
				(type default)
			)
			(fill no)
			(layer "B.CrtYd")
		)
		(fp_line
			(start 0.2794 0.9906)
			(end -0.2794 0.9906)
			(stroke
				(width 0.1)
				(type default)
			)
			(layer "B.Fab")
		)
		(fp_line
			(start 0.2794 -0.1016)
			(end 0.2794 0.9906)
			(stroke
				(width 0.1)
				(type default)
			)
			(layer "B.Fab")
		)
		(fp_line
			(start -0.2794 0.9906)
			(end -0.2794 -0.1016)
			(stroke
				(width 0.1)
				(type default)
			)
			(layer "B.Fab")
		)
		(fp_line
			(start -0.2794 -0.1016)
			(end 0.2794 -0.1016)
			(stroke
				(width 0.1)
				(type default)
			)
			(layer "B.Fab")
		)
		(pad "1" smd rect
			(at 0 0)
			(size 0.508 0.508)
			(layers "B.Cu" "B.Mask" "B.Paste")
			(net "P1V8_M2")
		)
		(pad "2" smd rect
			(at 0 0.889)
			(size 0.508 0.508)
			(layers "B.Cu" "B.Mask" "B.Paste")
			(net "SMB_M2_ALT_N")
		)
		(zone
			(layer "B.Cu")
			(hatch none 0.5)
			(connect_pads
				(clearance 0)
			)
			(min_thickness 0.25)
			(keepout
				(tracks not_allowed)
				(vias allowed)
				(pads allowed)
				(copperpour not_allowed)
				(footprints allowed)
			)
			(placement
				(enabled no)
				(sheetname "")
			)
			(fill
				(thermal_gap 0.5)
				(thermal_bridge_width 0.5)
				(island_removal_mode 0)
			)
			(polygon
				(pts
					(xy 392.128756 -20.31619) (xy 392.636756 -20.31619) (xy 392.636756 -19.93519) (xy 392.128756 -19.93519)
				)
			)
		)
		(zone
			(layer "B.Cu")
			(hatch none 0.5)
			(connect_pads
				(clearance 0)
			)
			(min_thickness 0.25)
			(keepout
				(tracks allowed)
				(vias not_allowed)
				(pads allowed)
				(copperpour not_allowed)
				(footprints allowed)
			)
			(placement
				(enabled no)
				(sheetname "")
			)
			(fill
				(thermal_gap 0.5)
				(thermal_bridge_width 0.5)
				(island_removal_mode 0)
			)
			(polygon
				(pts
					(xy 392.128756 -19.93519) (xy 392.636756 -19.93519) (xy 392.636756 -20.31619) (xy 392.128756 -20.31619)
				)
			)
		)
	)
	(footprint ""
		(layer "B.Cu")
		(at 419.220142 -82.042)
		(property "Reference" "R2P5"
			(at 0 0 0)
			(layer "B.SilkS")
			(hide yes)
			(effects
				(font
					(size 1.27 1.27)
				)
				(justify mirror)
			)
		)
		(property "Value" ""
			(at 0 0 0)
			(layer "B.Fab")
			(effects
				(font
					(size 1.27 1.27)
				)
				(justify mirror)
			)
		)
		(duplicate_pad_numbers_are_jumpers no)
		(fp_poly
			(pts
				(xy 0.2794 -0.1016) (xy -0.2794 -0.1016) (xy -0.2794 0.9906) (xy 0.2794 0.9906)
			)
			(stroke
				(width 0)
				(type default)
			)
			(fill no)
			(layer "B.CrtYd")
		)
		(fp_line
			(start -0.2794 -0.1016)
			(end 0.2794 -0.1016)
			(stroke
				(width 0.1)
				(type default)
			)
			(layer "B.Fab")
		)
		(fp_line
			(start -0.2794 0.9906)
			(end -0.2794 -0.1016)
			(stroke
				(width 0.1)
				(type default)
			)
			(layer "B.Fab")
		)
		(fp_line
			(start 0.2794 -0.1016)
			(end 0.2794 0.9906)
			(stroke
				(width 0.1)
				(type default)
			)
			(layer "B.Fab")
		)
		(fp_line
			(start 0.2794 0.9906)
			(end -0.2794 0.9906)
			(stroke
				(width 0.1)
				(type default)
			)
			(layer "B.Fab")
		)
		(pad "1" smd rect
			(at 0 0 180)
			(size 0.508 0.508)
			(layers "B.Cu" "B.Mask" "B.Paste")
			(net "P3V3_STBY")
		)
		(pad "2" smd rect
			(at 0 0.889 180)
			(size 0.508 0.508)
			(layers "B.Cu" "B.Mask" "B.Paste")
			(net "FM_PMBUS_ALERT_BUF_EN")
		)
		(zone
			(layer "B.Cu")
			(hatch none 0.5)
			(connect_pads
				(clearance 0)
			)
			(min_thickness 0.25)
			(keepout
				(tracks allowed)
				(vias not_allowed)
				(pads allowed)
				(copperpour not_allowed)
				(footprints allowed)
			)
			(placement
				(enabled no)
				(sheetname "")
			)
			(fill
				(thermal_gap 0.5)
				(thermal_bridge_width 0.5)
				(island_removal_mode 0)
			)
			(polygon
				(pts
					(xy 419.474142 -81.788) (xy 418.966142 -81.788) (xy 418.966142 -81.407) (xy 419.474142 -81.407)
				)
			)
		)
		(zone
			(layer "B.Cu")
			(hatch none 0.5)
			(connect_pads
				(clearance 0)
			)
			(min_thickness 0.25)
			(keepout
				(tracks not_allowed)
				(vias allowed)
				(pads allowed)
				(copperpour not_allowed)
				(footprints allowed)
			)
			(placement
				(enabled no)
				(sheetname "")
			)
			(fill
				(thermal_gap 0.5)
				(thermal_bridge_width 0.5)
				(island_removal_mode 0)
			)
			(polygon
				(pts
					(xy 419.474142 -81.407) (xy 418.966142 -81.407) (xy 418.966142 -81.788) (xy 419.474142 -81.788)
				)
			)
		)
	)
	(footprint ""
		(layer "B.Cu")
		(at 193.802 -134.874 180)
		(property "Reference" "R6M1"
			(at 0 0 0)
			(layer "B.SilkS")
			(hide yes)
			(effects
				(font
					(size 1.27 1.27)
				)
				(justify mirror)
			)
		)
		(property "Value" ""
			(at 0 0 0)
			(layer "B.Fab")
			(effects
				(font
					(size 1.27 1.27)
				)
				(justify mirror)
			)
		)
		(duplicate_pad_numbers_are_jumpers no)
		(fp_poly
			(pts
				(xy 0.2794 -0.1016) (xy -0.2794 -0.1016) (xy -0.2794 0.9906) (xy 0.2794 0.9906)
			)
			(stroke
				(width 0)
				(type default)
			)
			(fill no)
			(layer "B.CrtYd")
		)
		(fp_line
			(start 0.2794 0.9906)
			(end -0.2794 0.9906)
			(stroke
				(width 0.1)
				(type default)
			)
			(layer "B.Fab")
		)
		(fp_line
			(start 0.2794 -0.1016)
			(end 0.2794 0.9906)
			(stroke
				(width 0.1)
				(type default)
			)
			(layer "B.Fab")
		)
		(fp_line
			(start -0.2794 0.9906)
			(end -0.2794 -0.1016)
			(stroke
				(width 0.1)
				(type default)
			)
			(layer "B.Fab")
		)
		(fp_line
			(start -0.2794 -0.1016)
			(end 0.2794 -0.1016)
			(stroke
				(width 0.1)
				(type default)
			)
			(layer "B.Fab")
		)
		(pad "1" smd rect
			(at 0 0)
			(size 0.508 0.508)
			(layers "B.Cu" "B.Mask" "B.Paste")
			(net "PVDDQ_DEF")
		)
		(pad "2" smd rect
			(at 0 0.889)
			(size 0.508 0.508)
			(layers "B.Cu" "B.Mask" "B.Paste")
			(net "M_D_VREF")
		)
		(zone
			(layer "B.Cu")
			(hatch none 0.5)
			(connect_pads
				(clearance 0)
			)
			(min_thickness 0.25)
			(keepout
				(tracks not_allowed)
				(vias allowed)
				(pads allowed)
				(copperpour not_allowed)
				(footprints allowed)
			)
			(placement
				(enabled no)
				(sheetname "")
			)
			(fill
				(thermal_gap 0.5)
				(thermal_bridge_width 0.5)
				(island_removal_mode 0)
			)
			(polygon
				(pts
					(xy 193.548 -135.509) (xy 194.056 -135.509) (xy 194.056 -135.128) (xy 193.548 -135.128)
				)
			)
		)
		(zone
			(layer "B.Cu")
			(hatch none 0.5)
			(connect_pads
				(clearance 0)
			)
			(min_thickness 0.25)
			(keepout
				(tracks allowed)
				(vias not_allowed)
				(pads allowed)
				(copperpour not_allowed)
				(footprints allowed)
			)
			(placement
				(enabled no)
				(sheetname "")
			)
			(fill
				(thermal_gap 0.5)
				(thermal_bridge_width 0.5)
				(island_removal_mode 0)
			)
			(polygon
				(pts
					(xy 193.548 -135.128) (xy 194.056 -135.128) (xy 194.056 -135.509) (xy 193.548 -135.509)
				)
			)
		)
	)
	(footprint ""
		(layer "B.Cu")
		(at 493.06734 -123.06808 90)
		(property "Reference" "C9B7"
			(at 0 0 90)
			(layer "B.SilkS")
			(hide yes)
			(effects
				(font
					(size 1.27 1.27)
				)
				(justify mirror)
			)
		)
		(property "Value" ""
			(at 0 0 90)
			(layer "B.Fab")
			(effects
				(font
					(size 1.27 1.27)
				)
				(justify mirror)
			)
		)
		(duplicate_pad_numbers_are_jumpers no)
		(fp_poly
			(pts
				(xy -0.3048 -0.1016) (xy -0.3048 0.9906) (xy 0.3048 0.9906) (xy 0.3048 -0.1016)
			)
			(stroke
				(width 0)
				(type default)
			)
			(fill no)
			(layer "B.CrtYd")
		)
		(fp_line
			(start 0.3048 -0.1016)
			(end 0.3048 0.9906)
			(stroke
				(width 0.1)
				(type default)
			)
			(layer "B.Fab")
		)
		(fp_line
			(start -0.3048 -0.1016)
			(end 0.3048 -0.1016)
			(stroke
				(width 0.1)
				(type default)
			)
			(layer "B.Fab")
		)
		(fp_line
			(start 0.3048 0.9906)
			(end -0.3048 0.9906)
			(stroke
				(width 0.1)
				(type default)
			)
			(layer "B.Fab")
		)
		(fp_line
			(start -0.3048 0.9906)
			(end -0.3048 -0.1016)
			(stroke
				(width 0.1)
				(type default)
			)
			(layer "B.Fab")
		)
		(pad "1" smd rect
			(at 0 0 270)
			(size 0.508 0.508)
			(layers "B.Cu" "B.Mask" "B.Paste")
			(net "P3V3_STBY")
		)
		(pad "2" smd rect
			(at 0 0.889 270)
			(size 0.508 0.508)
			(layers "B.Cu" "B.Mask" "B.Paste")
			(net "GND")
		)
		(zone
			(layer "B.Cu")
			(hatch none 0.5)
			(connect_pads
				(clearance 0)
			)
			(min_thickness 0.25)
			(keepout
				(tracks allowed)
				(vias not_allowed)
				(pads allowed)
				(copperpour not_allowed)
				(footprints allowed)
			)
			(placement
				(enabled no)
				(sheetname "")
			)
			(fill
				(thermal_gap 0.5)
				(thermal_bridge_width 0.5)
				(island_removal_mode 0)
			)
			(polygon
				(pts
					(xy 493.32134 -123.32208) (xy 493.32134 -122.81408) (xy 493.70234 -122.81408) (xy 493.70234 -123.32208)
				)
			)
		)
		(zone
			(layer "B.Cu")
			(hatch none 0.5)
			(connect_pads
				(clearance 0)
			)
			(min_thickness 0.25)
			(keepout
				(tracks not_allowed)
				(vias allowed)
				(pads allowed)
				(copperpour not_allowed)
				(footprints allowed)
			)
			(placement
				(enabled no)
				(sheetname "")
			)
			(fill
				(thermal_gap 0.5)
				(thermal_bridge_width 0.5)
				(island_removal_mode 0)
			)
			(polygon
				(pts
					(xy 493.70234 -123.32208) (xy 493.70234 -122.81408) (xy 493.32134 -122.81408) (xy 493.32134 -123.32208)
				)
			)
		)
	)
	(footprint ""
		(layer "B.Cu")
		(at 107.8611 -149.8092 90)
		(property "Reference" "C5G104"
			(at -1.14681 0.76708 180)
			(unlocked yes)
			(layer "B.SilkS")
			(effects
				(font
					(size 0.7874 0.5842)
					(thickness 0.1524)
				)
				(justify mirror)
			)
		)
		(property "Value" ""
			(at 0 0 90)
			(layer "B.Fab")
			(effects
				(font
					(size 1.27 1.27)
				)
				(justify mirror)
			)
		)
		(duplicate_pad_numbers_are_jumpers no)
		(fp_rect
			(start -0.4953 -0.2032)
			(end 0.4953 1.6002)
			(stroke
				(width 0)
				(type default)
			)
			(fill no)
			(layer "B.CrtYd")
		)
		(fp_line
			(start 0.4953 -0.2032)
			(end -0.4953 -0.2032)
			(stroke
				(width 0.1)
				(type default)
			)
			(layer "B.Fab")
		)
		(fp_line
			(start -0.4953 -0.2032)
			(end -0.4953 1.6002)
			(stroke
				(width 0.1)
				(type default)
			)
			(layer "B.Fab")
		)
		(fp_line
			(start 0.4953 1.6002)
			(end 0.4953 -0.2032)
			(stroke
				(width 0.1)
				(type default)
			)
			(layer "B.Fab")
		)
		(fp_line
			(start -0.4953 1.6002)
			(end 0.4953 1.6002)
			(stroke
				(width 0.1)
				(type default)
			)
			(layer "B.Fab")
		)
		(pad "1" smd rect
			(at 0 0 270)
			(size 0.762 0.889)
			(layers "B.Cu" "B.Mask" "B.Paste")
			(net "PVDDQ_KLM")
		)
		(pad "2" smd rect
			(at 0 1.397 270)
			(size 0.762 0.889)
			(layers "B.Cu" "B.Mask" "B.Paste")
			(net "GND")
		)
		(zone
			(layer "B.Cu")
			(hatch none 0.5)
			(connect_pads
				(clearance 0)
			)
			(min_thickness 0.25)
			(keepout
				(tracks not_allowed)
				(vias allowed)
				(pads allowed)
				(copperpour not_allowed)
				(footprints allowed)
			)
			(placement
				(enabled no)
				(sheetname "")
			)
			(fill
				(thermal_gap 0.5)
				(thermal_bridge_width 0.5)
				(island_removal_mode 0)
			)
			(polygon
				(pts
					(xy 108.3056 -149.4282) (xy 108.8136 -149.4282) (xy 108.8136 -150.1902) (xy 108.3056 -150.1902)
				)
			)
		)
	)
	(footprint ""
		(layer "B.Cu")
		(at 375.519696 -62.277752)
		(property "Reference" "C2T1"
			(at 0 0 0)
			(layer "B.SilkS")
			(hide yes)
			(effects
				(font
					(size 1.27 1.27)
				)
				(justify mirror)
			)
		)
		(property "Value" ""
			(at 0 0 0)
			(layer "B.Fab")
			(effects
				(font
					(size 1.27 1.27)
				)
				(justify mirror)
			)
		)
		(duplicate_pad_numbers_are_jumpers no)
		(fp_poly
			(pts
				(xy -0.3048 -0.1016) (xy -0.3048 0.9906) (xy 0.3048 0.9906) (xy 0.3048 -0.1016)
			)
			(stroke
				(width 0)
				(type default)
			)
			(fill no)
			(layer "B.CrtYd")
		)
		(fp_line
			(start -0.3048 -0.1016)
			(end 0.3048 -0.1016)
			(stroke
				(width 0.1)
				(type default)
			)
			(layer "B.Fab")
		)
		(fp_line
			(start -0.3048 0.9906)
			(end -0.3048 -0.1016)
			(stroke
				(width 0.1)
				(type default)
			)
			(layer "B.Fab")
		)
		(fp_line
			(start 0.3048 -0.1016)
			(end 0.3048 0.9906)
			(stroke
				(width 0.1)
				(type default)
			)
			(layer "B.Fab")
		)
		(fp_line
			(start 0.3048 0.9906)
			(end -0.3048 0.9906)
			(stroke
				(width 0.1)
				(type default)
			)
			(layer "B.Fab")
		)
		(pad "1" smd rect
			(at 0 0 180)
			(size 0.508 0.508)
			(layers "B.Cu" "B.Mask" "B.Paste")
			(net "P3V3_STBY")
		)
		(pad "2" smd rect
			(at 0 0.889 180)
			(size 0.508 0.508)
			(layers "B.Cu" "B.Mask" "B.Paste")
			(net "GND")
		)
		(zone
			(layer "B.Cu")
			(hatch none 0.5)
			(connect_pads
				(clearance 0)
			)
			(min_thickness 0.25)
			(keepout
				(tracks allowed)
				(vias not_allowed)
				(pads allowed)
				(copperpour not_allowed)
				(footprints allowed)
			)
			(placement
				(enabled no)
				(sheetname "")
			)
			(fill
				(thermal_gap 0.5)
				(thermal_bridge_width 0.5)
				(island_removal_mode 0)
			)
			(polygon
				(pts
					(xy 375.773696 -62.023752) (xy 375.265696 -62.023752) (xy 375.265696 -61.642752) (xy 375.773696 -61.642752)
				)
			)
		)
		(zone
			(layer "B.Cu")
			(hatch none 0.5)
			(connect_pads
				(clearance 0)
			)
			(min_thickness 0.25)
			(keepout
				(tracks not_allowed)
				(vias allowed)
				(pads allowed)
				(copperpour not_allowed)
				(footprints allowed)
			)
			(placement
				(enabled no)
				(sheetname "")
			)
			(fill
				(thermal_gap 0.5)
				(thermal_bridge_width 0.5)
				(island_removal_mode 0)
			)
			(polygon
				(pts
					(xy 375.773696 -61.642752) (xy 375.265696 -61.642752) (xy 375.265696 -62.023752) (xy 375.773696 -62.023752)
				)
			)
		)
	)
	(footprint ""
		(layer "B.Cu")
		(at 379.476 -20.193 90)
		(property "Reference" "CN8F1"
			(at 0.8382 -0.67818 90)
			(unlocked yes)
			(layer "B.SilkS")
			(effects
				(font
					(size 0.4064 0.254)
					(thickness 0.1524)
				)
				(justify left mirror)
			)
		)
		(property "Value" ""
			(at 0 0 90)
			(layer "B.Fab")
			(effects
				(font
					(size 1.27 1.27)
				)
				(justify mirror)
			)
		)
		(duplicate_pad_numbers_are_jumpers no)
		(fp_poly
			(pts
				(xy -0.3048 -0.1016) (xy -0.3048 0.9906) (xy 0.3048 0.9906) (xy 0.3048 -0.1016)
			)
			(stroke
				(width 0)
				(type default)
			)
			(fill no)
			(layer "B.CrtYd")
		)
		(fp_line
			(start 0.3048 -0.1016)
			(end 0.3048 0.9906)
			(stroke
				(width 0.1)
				(type default)
			)
			(layer "B.Fab")
		)
		(fp_line
			(start -0.3048 -0.1016)
			(end 0.3048 -0.1016)
			(stroke
				(width 0.1)
				(type default)
			)
			(layer "B.Fab")
		)
		(fp_line
			(start 0.3048 0.9906)
			(end -0.3048 0.9906)
			(stroke
				(width 0.1)
				(type default)
			)
			(layer "B.Fab")
		)
		(fp_line
			(start -0.3048 0.9906)
			(end -0.3048 -0.1016)
			(stroke
				(width 0.1)
				(type default)
			)
			(layer "B.Fab")
		)
		(pad "1" smd rect
			(at 0 0 270)
			(size 0.508 0.508)
			(layers "B.Cu" "B.Mask" "B.Paste")
			(net "P3V3_STBY")
		)
		(pad "2" smd rect
			(at 0 0.889 270)
			(size 0.508 0.508)
			(layers "B.Cu" "B.Mask" "B.Paste")
			(net "GND")
		)
		(zone
			(layer "B.Cu")
			(hatch none 0.5)
			(connect_pads
				(clearance 0)
			)
			(min_thickness 0.25)
			(keepout
				(tracks allowed)
				(vias not_allowed)
				(pads allowed)
				(copperpour not_allowed)
				(footprints allowed)
			)
			(placement
				(enabled no)
				(sheetname "")
			)
			(fill
				(thermal_gap 0.5)
				(thermal_bridge_width 0.5)
				(island_removal_mode 0)
			)
			(polygon
				(pts
					(xy 379.73 -20.447) (xy 379.73 -19.939) (xy 380.111 -19.939) (xy 380.111 -20.447)
				)
			)
		)
		(zone
			(layer "B.Cu")
			(hatch none 0.5)
			(connect_pads
				(clearance 0)
			)
			(min_thickness 0.25)
			(keepout
				(tracks not_allowed)
				(vias allowed)
				(pads allowed)
				(copperpour not_allowed)
				(footprints allowed)
			)
			(placement
				(enabled no)
				(sheetname "")
			)
			(fill
				(thermal_gap 0.5)
				(thermal_bridge_width 0.5)
				(island_removal_mode 0)
			)
			(polygon
				(pts
					(xy 380.111 -20.447) (xy 380.111 -19.939) (xy 379.73 -19.939) (xy 379.73 -20.447)
				)
			)
		)
	)
	(footprint ""
		(layer "B.Cu")
		(at 351.507806 -60.368434)
		(property "Reference" "R2U27"
			(at 0 0 0)
			(layer "B.SilkS")
			(hide yes)
			(effects
				(font
					(size 1.27 1.27)
				)
				(justify mirror)
			)
		)
		(property "Value" ""
			(at 0 0 0)
			(layer "B.Fab")
			(effects
				(font
					(size 1.27 1.27)
				)
				(justify mirror)
			)
		)
		(duplicate_pad_numbers_are_jumpers no)
		(fp_poly
			(pts
				(xy 0.2794 -0.1016) (xy -0.2794 -0.1016) (xy -0.2794 0.9906) (xy 0.2794 0.9906)
			)
			(stroke
				(width 0)
				(type default)
			)
			(fill no)
			(layer "B.CrtYd")
		)
		(fp_line
			(start -0.2794 -0.1016)
			(end 0.2794 -0.1016)
			(stroke
				(width 0.1)
				(type default)
			)
			(layer "B.Fab")
		)
		(fp_line
			(start -0.2794 0.9906)
			(end -0.2794 -0.1016)
			(stroke
				(width 0.1)
				(type default)
			)
			(layer "B.Fab")
		)
		(fp_line
			(start 0.2794 -0.1016)
			(end 0.2794 0.9906)
			(stroke
				(width 0.1)
				(type default)
			)
			(layer "B.Fab")
		)
		(fp_line
			(start 0.2794 0.9906)
			(end -0.2794 0.9906)
			(stroke
				(width 0.1)
				(type default)
			)
			(layer "B.Fab")
		)
		(pad "1" smd rect
			(at 0 0 180)
			(size 0.508 0.508)
			(layers "B.Cu" "B.Mask" "B.Paste")
			(net "P3E_CPU0_PE1_SS_RXN<6>")
		)
		(pad "2" smd rect
			(at 0 0.889 180)
			(size 0.508 0.508)
			(layers "B.Cu" "B.Mask" "B.Paste")
			(net "P3E_CPU0_PE1_SS_R_RXN<6>")
		)
		(zone
			(layer "B.Cu")
			(hatch none 0.5)
			(connect_pads
				(clearance 0)
			)
			(min_thickness 0.25)
			(keepout
				(tracks allowed)
				(vias not_allowed)
				(pads allowed)
				(copperpour not_allowed)
				(footprints allowed)
			)
			(placement
				(enabled no)
				(sheetname "")
			)
			(fill
				(thermal_gap 0.5)
				(thermal_bridge_width 0.5)
				(island_removal_mode 0)
			)
			(polygon
				(pts
					(xy 351.761806 -60.114434) (xy 351.253806 -60.114434) (xy 351.253806 -59.733434) (xy 351.761806 -59.733434)
				)
			)
		)
		(zone
			(layer "B.Cu")
			(hatch none 0.5)
			(connect_pads
				(clearance 0)
			)
			(min_thickness 0.25)
			(keepout
				(tracks not_allowed)
				(vias allowed)
				(pads allowed)
				(copperpour not_allowed)
				(footprints allowed)
			)
			(placement
				(enabled no)
				(sheetname "")
			)
			(fill
				(thermal_gap 0.5)
				(thermal_bridge_width 0.5)
				(island_removal_mode 0)
			)
			(polygon
				(pts
					(xy 351.761806 -59.733434) (xy 351.253806 -59.733434) (xy 351.253806 -60.114434) (xy 351.761806 -60.114434)
				)
			)
		)
	)
	(footprint ""
		(layer "B.Cu")
		(at 470.8144 -15.3162)
		(property "Reference" "C2U19"
			(at 0 0 0)
			(layer "B.SilkS")
			(hide yes)
			(effects
				(font
					(size 1.27 1.27)
				)
				(justify mirror)
			)
		)
		(property "Value" ""
			(at 0 0 0)
			(layer "B.Fab")
			(effects
				(font
					(size 1.27 1.27)
				)
				(justify mirror)
			)
		)
		(duplicate_pad_numbers_are_jumpers no)
		(fp_rect
			(start 0.3048 -0.1016)
			(end -0.3048 0.9906)
			(stroke
				(width 0)
				(type default)
			)
			(fill no)
			(layer "B.CrtYd")
		)
		(fp_line
			(start -0.3048 -0.1016)
			(end 0.3048 -0.1016)
			(stroke
				(width 0.1)
				(type default)
			)
			(layer "B.Fab")
		)
		(fp_line
			(start -0.3048 0.9906)
			(end -0.3048 -0.1016)
			(stroke
				(width 0.1)
				(type default)
			)
			(layer "B.Fab")
		)
		(fp_line
			(start 0.3048 -0.1016)
			(end 0.3048 0.9906)
			(stroke
				(width 0.1)
				(type default)
			)
			(layer "B.Fab")
		)
		(fp_line
			(start 0.3048 0.9906)
			(end -0.3048 0.9906)
			(stroke
				(width 0.1)
				(type default)
			)
			(layer "B.Fab")
		)
		(pad "1" smd rect
			(at 0 0 180)
			(size 0.508 0.508)
			(layers "B.Cu" "B.Mask" "B.Paste")
			(net "P3V3")
		)
		(pad "2" smd rect
			(at 0 0.889 180)
			(size 0.508 0.508)
			(layers "B.Cu" "B.Mask" "B.Paste")
			(net "GND")
		)
		(zone
			(layer "B.Cu")
			(hatch none 0.5)
			(connect_pads
				(clearance 0)
			)
			(min_thickness 0.25)
			(keepout
				(tracks not_allowed)
				(vias allowed)
				(pads allowed)
				(copperpour not_allowed)
				(footprints allowed)
			)
			(placement
				(enabled no)
				(sheetname "")
			)
			(fill
				(thermal_gap 0.5)
				(thermal_bridge_width 0.5)
				(island_removal_mode 0)
			)
			(polygon
				(pts
					(xy 471.0684 -15.0622) (xy 470.5604 -15.0622) (xy 470.5604 -14.6812) (xy 471.0684 -14.6812)
				)
			)
		)
		(zone
			(layer "B.Cu")
			(hatch none 0.5)
			(connect_pads
				(clearance 0)
			)
			(min_thickness 0.25)
			(keepout
				(tracks allowed)
				(vias not_allowed)
				(pads allowed)
				(copperpour not_allowed)
				(footprints allowed)
			)
			(placement
				(enabled no)
				(sheetname "")
			)
			(fill
				(thermal_gap 0.5)
				(thermal_bridge_width 0.5)
				(island_removal_mode 0)
			)
			(polygon
				(pts
					(xy 471.0684 -15.0622) (xy 470.5604 -15.0622) (xy 470.5604 -14.6812) (xy 471.0684 -14.6812)
				)
			)
		)
	)
	(footprint ""
		(layer "B.Cu")
		(at 389.90651 -44.874688)
		(property "Reference" "Q2U1"
			(at 1.51765 0.54864 90)
			(unlocked yes)
			(layer "B.SilkS")
			(effects
				(font
					(size 0.7874 0.5842)
					(thickness 0.1524)
				)
				(justify left mirror)
			)
		)
		(property "Value" ""
			(at 0 0 0)
			(layer "B.Fab")
			(effects
				(font
					(size 1.27 1.27)
				)
				(justify mirror)
			)
		)
		(duplicate_pad_numbers_are_jumpers no)
		(fp_circle
			(center 0.508 -0.7874)
			(end 0.635 -0.7874)
			(stroke
				(width 0.254)
				(type default)
			)
			(fill no)
			(layer "B.SilkS")
		)
		(fp_poly
			(pts
				(xy -0.2159 1.7526) (xy -1.5621 1.7526) (xy -1.5621 -0.4572) (xy -0.2159 -0.4572)
			)
			(stroke
				(width 0)
				(type default)
			)
			(fill no)
			(layer "B.CrtYd")
		)
		(fp_line
			(start -1.5621 -0.45466)
			(end -0.2159 -0.45466)
			(stroke
				(width 0.1)
				(type default)
			)
			(layer "B.Fab")
		)
		(fp_line
			(start -1.5621 1.75514)
			(end -1.5621 -0.45466)
			(stroke
				(width 0.1)
				(type default)
			)
			(layer "B.Fab")
		)
		(fp_line
			(start -0.2159 -0.45466)
			(end -0.2159 1.75514)
			(stroke
				(width 0.1)
				(type default)
			)
			(layer "B.Fab")
		)
		(fp_line
			(start -0.2159 1.75514)
			(end -1.5621 1.75514)
			(stroke
				(width 0.1)
				(type default)
			)
			(layer "B.Fab")
		)
		(fp_circle
			(center 0.508 -0.7874)
			(end 0.635 -0.7874)
			(stroke
				(width 0.254)
				(type default)
			)
			(fill no)
			(layer "B.Fab")
		)
		(pad "1" smd rect
			(at 0 0 180)
			(size 1.016 0.381)
			(layers "B.Cu" "B.Mask" "B.Paste")
			(net "GND")
		)
		(pad "2" smd rect
			(at 0 0.65024 180)
			(size 1.016 0.381)
			(layers "B.Cu" "B.Mask" "B.Paste")
			(net "FM_SYS_THROTTLE_LVC3")
		)
		(pad "3" smd rect
			(at 0 1.30048 180)
			(size 1.016 0.381)
			(layers "B.Cu" "B.Mask" "B.Paste")
			(net "H_CPU0_MEMDEF_MEMHOT_G_N")
		)
		(pad "4" smd rect
			(at -1.778 1.30048 180)
			(size 1.016 0.381)
			(layers "B.Cu" "B.Mask" "B.Paste")
			(net "GND")
		)
		(pad "5" smd rect
			(at -1.778 0.65024 180)
			(size 1.016 0.381)
			(layers "B.Cu" "B.Mask" "B.Paste")
			(net "FM_SYS_THROTTLE_LVC3")
		)
		(pad "6" smd rect
			(at -1.778 0 180)
			(size 1.016 0.381)
			(layers "B.Cu" "B.Mask" "B.Paste")
			(net "H_CPU0_MEMABC_MEMHOT_G_N")
		)
		(zone
			(layer "B.Cu")
			(hatch none 0.5)
			(connect_pads
				(clearance 0)
			)
			(min_thickness 0.25)
			(keepout
				(tracks allowed)
				(vias not_allowed)
				(pads allowed)
				(copperpour not_allowed)
				(footprints allowed)
			)
			(placement
				(enabled no)
				(sheetname "")
			)
			(fill
				(thermal_gap 0.5)
				(thermal_bridge_width 0.5)
				(island_removal_mode 0)
			)
			(polygon
				(pts
					(xy 388.63651 -45.065188) (xy 387.62051 -45.065188) (xy 387.62051 -43.376088) (xy 388.63651 -43.376088)
				)
			)
		)
		(zone
			(layer "B.Cu")
			(hatch none 0.5)
			(connect_pads
				(clearance 0)
			)
			(min_thickness 0.25)
			(keepout
				(tracks allowed)
				(vias not_allowed)
				(pads allowed)
				(copperpour not_allowed)
				(footprints allowed)
			)
			(placement
				(enabled no)
				(sheetname "")
			)
			(fill
				(thermal_gap 0.5)
				(thermal_bridge_width 0.5)
				(island_removal_mode 0)
			)
			(polygon
				(pts
					(xy 390.41451 -45.065188) (xy 389.39851 -45.065188) (xy 389.39851 -43.376088) (xy 390.41451 -43.376088)
				)
			)
		)
	)
	(footprint ""
		(layer "B.Cu")
		(at 9.398 -130.9624 90)
		(property "Reference" "R9M4"
			(at -1.59893 2.286 180)
			(unlocked yes)
			(layer "B.SilkS")
			(effects
				(font
					(size 0.7874 0.5842)
					(thickness 0.1524)
				)
				(justify mirror)
			)
		)
		(property "Value" ""
			(at 0 0 90)
			(layer "B.Fab")
			(effects
				(font
					(size 1.27 1.27)
				)
				(justify mirror)
			)
		)
		(duplicate_pad_numbers_are_jumpers no)
		(fp_line
			(start 0.9017 1.951736)
			(end 0.9017 0.823468)
			(stroke
				(width 0.1524)
				(type default)
			)
			(layer "B.SilkS")
		)
		(fp_line
			(start -0.9017 1.952498)
			(end -0.9017 0.853948)
			(stroke
				(width 0.1524)
				(type default)
			)
			(layer "B.SilkS")
		)
		(fp_poly
			(pts
				(xy 0.9017 -0.3048) (xy -0.9017 -0.3048) (xy -0.9017 3.0988) (xy 0.9017 3.0988)
			)
			(stroke
				(width 0)
				(type default)
			)
			(fill no)
			(layer "B.CrtYd")
		)
		(fp_line
			(start 0.9017 -0.3048)
			(end 0.9017 3.0988)
			(stroke
				(width 0.1)
				(type default)
			)
			(layer "B.Fab")
		)
		(fp_line
			(start -0.9017 -0.3048)
			(end 0.9017 -0.3048)
			(stroke
				(width 0.1)
				(type default)
			)
			(layer "B.Fab")
		)
		(fp_line
			(start 0.9017 3.0988)
			(end -0.9017 3.0988)
			(stroke
				(width 0.1)
				(type default)
			)
			(layer "B.Fab")
		)
		(fp_line
			(start -0.9017 3.0988)
			(end -0.9017 -0.3048)
			(stroke
				(width 0.1)
				(type default)
			)
			(layer "B.Fab")
		)
		(pad "1" smd rect
			(at 0 0 270)
			(size 1.524 1.016)
			(layers "B.Cu" "B.Mask" "B.Paste")
			(net "P12V_STBY")
		)
		(pad "2" smd rect
			(at 0 2.794 270)
			(size 1.524 1.016)
			(layers "B.Cu" "B.Mask" "B.Paste")
			(net "P12V_NVDIMM_KLM")
		)
		(zone
			(layer "B.Cu")
			(hatch none 0.5)
			(connect_pads
				(clearance 0)
			)
			(min_thickness 0.25)
			(keepout
				(tracks allowed)
				(vias not_allowed)
				(pads allowed)
				(copperpour not_allowed)
				(footprints allowed)
			)
			(placement
				(enabled no)
				(sheetname "")
			)
			(fill
				(thermal_gap 0.5)
				(thermal_bridge_width 0.5)
				(island_removal_mode 0)
			)
			(polygon
				(pts
					(xy 9.906 -130.2004) (xy 11.684 -130.2004) (xy 11.684 -131.7244) (xy 9.906 -131.7244)
				)
			)
		)
	)
	(footprint ""
		(layer "B.Cu")
		(at 113.702592 -77.810614)
		(property "Reference" "C7P11"
			(at 0 0 0)
			(layer "B.SilkS")
			(hide yes)
			(effects
				(font
					(size 1.27 1.27)
				)
				(justify mirror)
			)
		)
		(property "Value" ""
			(at 0 0 0)
			(layer "B.Fab")
			(effects
				(font
					(size 1.27 1.27)
				)
				(justify mirror)
			)
		)
		(duplicate_pad_numbers_are_jumpers no)
		(fp_poly
			(pts
				(xy 0.7239 -0.2159) (xy -0.7239 -0.2159) (xy -0.7239 1.9939) (xy 0.7239 1.9939)
			)
			(stroke
				(width 0)
				(type default)
			)
			(fill no)
			(layer "B.CrtYd")
		)
		(fp_line
			(start -0.7239 -0.2159)
			(end 0.7239 -0.2159)
			(stroke
				(width 0.1)
				(type default)
			)
			(layer "B.Fab")
		)
		(fp_line
			(start -0.7239 1.9939)
			(end -0.7239 -0.2159)
			(stroke
				(width 0.1)
				(type default)
			)
			(layer "B.Fab")
		)
		(fp_line
			(start 0.7239 -0.2159)
			(end 0.7239 1.9939)
			(stroke
				(width 0.1)
				(type default)
			)
			(layer "B.Fab")
		)
		(fp_line
			(start 0.7239 1.9939)
			(end -0.7239 1.9939)
			(stroke
				(width 0.1)
				(type default)
			)
			(layer "B.Fab")
		)
		(pad "1" smd rect
			(at 0 0 180)
			(size 1.27 1.016)
			(layers "B.Cu" "B.Mask" "B.Paste")
			(net "PVCCMCP_CPU1")
		)
		(pad "2" smd rect
			(at 0 1.778 180)
			(size 1.27 1.016)
			(layers "B.Cu" "B.Mask" "B.Paste")
			(net "GND")
		)
		(zone
			(layer "B.Cu")
			(hatch none 0.5)
			(connect_pads
				(clearance 0)
			)
			(min_thickness 0.25)
			(keepout
				(tracks not_allowed)
				(vias allowed)
				(pads allowed)
				(copperpour not_allowed)
				(footprints allowed)
			)
			(placement
				(enabled no)
				(sheetname "")
			)
			(fill
				(thermal_gap 0.5)
				(thermal_bridge_width 0.5)
				(island_removal_mode 0)
			)
			(polygon
				(pts
					(xy 114.337592 -77.302614) (xy 113.067592 -77.302614) (xy 113.067592 -76.540614) (xy 114.337592 -76.540614)
				)
			)
		)
	)
	(footprint ""
		(layer "B.Cu")
		(at 20.153884 -134.189978 -90)
		(property "Reference" "R9M21"
			(at 0 0 90)
			(layer "B.SilkS")
			(hide yes)
			(effects
				(font
					(size 1.27 1.27)
				)
				(justify mirror)
			)
		)
		(property "Value" ""
			(at 0 0 90)
			(layer "B.Fab")
			(effects
				(font
					(size 1.27 1.27)
				)
				(justify mirror)
			)
		)
		(duplicate_pad_numbers_are_jumpers no)
		(fp_poly
			(pts
				(xy 0.2794 -0.1016) (xy -0.2794 -0.1016) (xy -0.2794 0.9906) (xy 0.2794 0.9906)
			)
			(stroke
				(width 0)
				(type default)
			)
			(fill no)
			(layer "B.CrtYd")
		)
		(fp_line
			(start -0.2794 0.9906)
			(end -0.2794 -0.1016)
			(stroke
				(width 0.1)
				(type default)
			)
			(layer "B.Fab")
		)
		(fp_line
			(start 0.2794 0.9906)
			(end -0.2794 0.9906)
			(stroke
				(width 0.1)
				(type default)
			)
			(layer "B.Fab")
		)
		(fp_line
			(start -0.2794 -0.1016)
			(end 0.2794 -0.1016)
			(stroke
				(width 0.1)
				(type default)
			)
			(layer "B.Fab")
		)
		(fp_line
			(start 0.2794 -0.1016)
			(end 0.2794 0.9906)
			(stroke
				(width 0.1)
				(type default)
			)
			(layer "B.Fab")
		)
		(pad "1" smd rect
			(at 0 0 90)
			(size 0.508 0.508)
			(layers "B.Cu" "B.Mask" "B.Paste")
			(net "SMB_LAN_STBY_LVC3_SDA")
		)
		(pad "2" smd rect
			(at 0 0.889 90)
			(size 0.508 0.508)
			(layers "B.Cu" "B.Mask" "B.Paste")
			(net "SMB_PIROM_CPU1_SDA")
		)
		(zone
			(layer "B.Cu")
			(hatch none 0.5)
			(connect_pads
				(clearance 0)
			)
			(min_thickness 0.25)
			(keepout
				(tracks not_allowed)
				(vias allowed)
				(pads allowed)
				(copperpour not_allowed)
				(footprints allowed)
			)
			(placement
				(enabled no)
				(sheetname "")
			)
			(fill
				(thermal_gap 0.5)
				(thermal_bridge_width 0.5)
				(island_removal_mode 0)
			)
			(polygon
				(pts
					(xy 19.518884 -133.935978) (xy 19.518884 -134.443978) (xy 19.899884 -134.443978) (xy 19.899884 -133.935978)
				)
			)
		)
		(zone
			(layer "B.Cu")
			(hatch none 0.5)
			(connect_pads
				(clearance 0)
			)
			(min_thickness 0.25)
			(keepout
				(tracks allowed)
				(vias not_allowed)
				(pads allowed)
				(copperpour not_allowed)
				(footprints allowed)
			)
			(placement
				(enabled no)
				(sheetname "")
			)
			(fill
				(thermal_gap 0.5)
				(thermal_bridge_width 0.5)
				(island_removal_mode 0)
			)
			(polygon
				(pts
					(xy 19.899884 -133.935978) (xy 19.899884 -134.443978) (xy 19.518884 -134.443978) (xy 19.518884 -133.935978)
				)
			)
		)
	)
	(footprint ""
		(layer "B.Cu")
		(at 29.436568 -145.3642)
		(property "Reference" "R9L6"
			(at 0 0 0)
			(layer "B.SilkS")
			(hide yes)
			(effects
				(font
					(size 1.27 1.27)
				)
				(justify mirror)
			)
		)
		(property "Value" ""
			(at 0 0 0)
			(layer "B.Fab")
			(effects
				(font
					(size 1.27 1.27)
				)
				(justify mirror)
			)
		)
		(duplicate_pad_numbers_are_jumpers no)
		(fp_poly
			(pts
				(xy 0.2794 -0.1016) (xy -0.2794 -0.1016) (xy -0.2794 0.9906) (xy 0.2794 0.9906)
			)
			(stroke
				(width 0)
				(type default)
			)
			(fill no)
			(layer "B.CrtYd")
		)
		(fp_line
			(start -0.2794 -0.1016)
			(end 0.2794 -0.1016)
			(stroke
				(width 0.1)
				(type default)
			)
			(layer "B.Fab")
		)
		(fp_line
			(start -0.2794 0.9906)
			(end -0.2794 -0.1016)
			(stroke
				(width 0.1)
				(type default)
			)
			(layer "B.Fab")
		)
		(fp_line
			(start 0.2794 -0.1016)
			(end 0.2794 0.9906)
			(stroke
				(width 0.1)
				(type default)
			)
			(layer "B.Fab")
		)
		(fp_line
			(start 0.2794 0.9906)
			(end -0.2794 0.9906)
			(stroke
				(width 0.1)
				(type default)
			)
			(layer "B.Fab")
		)
		(pad "1" smd rect
			(at 0 0 180)
			(size 0.508 0.508)
			(layers "B.Cu" "B.Mask" "B.Paste")
			(net "M_L_VREF")
		)
		(pad "2" smd rect
			(at 0 0.889 180)
			(size 0.508 0.508)
			(layers "B.Cu" "B.Mask" "B.Paste")
			(net "GND")
		)
		(zone
			(layer "B.Cu")
			(hatch none 0.5)
			(connect_pads
				(clearance 0)
			)
			(min_thickness 0.25)
			(keepout
				(tracks allowed)
				(vias not_allowed)
				(pads allowed)
				(copperpour not_allowed)
				(footprints allowed)
			)
			(placement
				(enabled no)
				(sheetname "")
			)
			(fill
				(thermal_gap 0.5)
				(thermal_bridge_width 0.5)
				(island_removal_mode 0)
			)
			(polygon
				(pts
					(xy 29.690568 -145.1102) (xy 29.182568 -145.1102) (xy 29.182568 -144.7292) (xy 29.690568 -144.7292)
				)
			)
		)
		(zone
			(layer "B.Cu")
			(hatch none 0.5)
			(connect_pads
				(clearance 0)
			)
			(min_thickness 0.25)
			(keepout
				(tracks not_allowed)
				(vias allowed)
				(pads allowed)
				(copperpour not_allowed)
				(footprints allowed)
			)
			(placement
				(enabled no)
				(sheetname "")
			)
			(fill
				(thermal_gap 0.5)
				(thermal_bridge_width 0.5)
				(island_removal_mode 0)
			)
			(polygon
				(pts
					(xy 29.690568 -144.7292) (xy 29.182568 -144.7292) (xy 29.182568 -145.1102) (xy 29.690568 -145.1102)
				)
			)
		)
	)
	(footprint ""
		(layer "B.Cu")
		(at 482.5238 -151.0284)
		(property "Reference" "R1L9"
			(at 0 0 0)
			(layer "B.SilkS")
			(hide yes)
			(effects
				(font
					(size 1.27 1.27)
				)
				(justify mirror)
			)
		)
		(property "Value" ""
			(at 0 0 0)
			(layer "B.Fab")
			(effects
				(font
					(size 1.27 1.27)
				)
				(justify mirror)
			)
		)
		(duplicate_pad_numbers_are_jumpers no)
		(fp_poly
			(pts
				(xy 0.2794 -0.1016) (xy -0.2794 -0.1016) (xy -0.2794 0.9906) (xy 0.2794 0.9906)
			)
			(stroke
				(width 0)
				(type default)
			)
			(fill no)
			(layer "B.CrtYd")
		)
		(fp_line
			(start -0.2794 -0.1016)
			(end 0.2794 -0.1016)
			(stroke
				(width 0.1)
				(type default)
			)
			(layer "B.Fab")
		)
		(fp_line
			(start -0.2794 0.9906)
			(end -0.2794 -0.1016)
			(stroke
				(width 0.1)
				(type default)
			)
			(layer "B.Fab")
		)
		(fp_line
			(start 0.2794 -0.1016)
			(end 0.2794 0.9906)
			(stroke
				(width 0.1)
				(type default)
			)
			(layer "B.Fab")
		)
		(fp_line
			(start 0.2794 0.9906)
			(end -0.2794 0.9906)
			(stroke
				(width 0.1)
				(type default)
			)
			(layer "B.Fab")
		)
		(pad "1" smd rect
			(at 0 0 180)
			(size 0.508 0.508)
			(layers "B.Cu" "B.Mask" "B.Paste")
			(net "P12V_STBY")
		)
		(pad "2" smd rect
			(at 0 0.889 180)
			(size 0.508 0.508)
			(layers "B.Cu" "B.Mask" "B.Paste")
			(net "FM_CPLD_DBG_PWR_EN")
		)
		(zone
			(layer "B.Cu")
			(hatch none 0.5)
			(connect_pads
				(clearance 0)
			)
			(min_thickness 0.25)
			(keepout
				(tracks allowed)
				(vias not_allowed)
				(pads allowed)
				(copperpour not_allowed)
				(footprints allowed)
			)
			(placement
				(enabled no)
				(sheetname "")
			)
			(fill
				(thermal_gap 0.5)
				(thermal_bridge_width 0.5)
				(island_removal_mode 0)
			)
			(polygon
				(pts
					(xy 482.7778 -150.7744) (xy 482.2698 -150.7744) (xy 482.2698 -150.3934) (xy 482.7778 -150.3934)
				)
			)
		)
		(zone
			(layer "B.Cu")
			(hatch none 0.5)
			(connect_pads
				(clearance 0)
			)
			(min_thickness 0.25)
			(keepout
				(tracks not_allowed)
				(vias allowed)
				(pads allowed)
				(copperpour not_allowed)
				(footprints allowed)
			)
			(placement
				(enabled no)
				(sheetname "")
			)
			(fill
				(thermal_gap 0.5)
				(thermal_bridge_width 0.5)
				(island_removal_mode 0)
			)
			(polygon
				(pts
					(xy 482.7778 -150.3934) (xy 482.2698 -150.3934) (xy 482.2698 -150.7744) (xy 482.7778 -150.7744)
				)
			)
		)
	)
	(footprint ""
		(layer "B.Cu")
		(at 440.67222 -58.02376 90)
		(property "Reference" "R1W40"
			(at 0.8382 -0.67818 90)
			(unlocked yes)
			(layer "B.SilkS")
			(effects
				(font
					(size 0.4064 0.254)
					(thickness 0.1524)
				)
				(justify left mirror)
			)
		)
		(property "Value" ""
			(at 0 0 90)
			(layer "B.Fab")
			(effects
				(font
					(size 1.27 1.27)
				)
				(justify mirror)
			)
		)
		(duplicate_pad_numbers_are_jumpers no)
		(fp_poly
			(pts
				(xy 0.2794 -0.1016) (xy -0.2794 -0.1016) (xy -0.2794 0.9906) (xy 0.2794 0.9906)
			)
			(stroke
				(width 0)
				(type default)
			)
			(fill no)
			(layer "B.CrtYd")
		)
		(fp_line
			(start 0.2794 -0.1016)
			(end 0.2794 0.9906)
			(stroke
				(width 0.1)
				(type default)
			)
			(layer "B.Fab")
		)
		(fp_line
			(start -0.2794 -0.1016)
			(end 0.2794 -0.1016)
			(stroke
				(width 0.1)
				(type default)
			)
			(layer "B.Fab")
		)
		(fp_line
			(start 0.2794 0.9906)
			(end -0.2794 0.9906)
			(stroke
				(width 0.1)
				(type default)
			)
			(layer "B.Fab")
		)
		(fp_line
			(start -0.2794 0.9906)
			(end -0.2794 -0.1016)
			(stroke
				(width 0.1)
				(type default)
			)
			(layer "B.Fab")
		)
		(pad "1" smd rect
			(at 0 0 270)
			(size 0.508 0.508)
			(layers "B.Cu" "B.Mask" "B.Paste")
			(net "P3V3_STBY")
		)
		(pad "2" smd rect
			(at 0 0.889 270)
			(size 0.508 0.508)
			(layers "B.Cu" "B.Mask" "B.Paste")
			(net "EXT_MDIO_I2C_SEL")
		)
		(zone
			(layer "B.Cu")
			(hatch none 0.5)
			(connect_pads
				(clearance 0)
			)
			(min_thickness 0.25)
			(keepout
				(tracks allowed)
				(vias not_allowed)
				(pads allowed)
				(copperpour not_allowed)
				(footprints allowed)
			)
			(placement
				(enabled no)
				(sheetname "")
			)
			(fill
				(thermal_gap 0.5)
				(thermal_bridge_width 0.5)
				(island_removal_mode 0)
			)
			(polygon
				(pts
					(xy 440.92622 -58.27776) (xy 440.92622 -57.76976) (xy 441.30722 -57.76976) (xy 441.30722 -58.27776)
				)
			)
		)
		(zone
			(layer "B.Cu")
			(hatch none 0.5)
			(connect_pads
				(clearance 0)
			)
			(min_thickness 0.25)
			(keepout
				(tracks not_allowed)
				(vias allowed)
				(pads allowed)
				(copperpour not_allowed)
				(footprints allowed)
			)
			(placement
				(enabled no)
				(sheetname "")
			)
			(fill
				(thermal_gap 0.5)
				(thermal_bridge_width 0.5)
				(island_removal_mode 0)
			)
			(polygon
				(pts
					(xy 441.30722 -58.27776) (xy 441.30722 -57.76976) (xy 440.92622 -57.76976) (xy 440.92622 -58.27776)
				)
			)
		)
	)
	(footprint ""
		(layer "B.Cu")
		(at 470.662 -116.84 180)
		(property "Reference" "R1M16"
			(at 0 0 0)
			(layer "B.SilkS")
			(hide yes)
			(effects
				(font
					(size 1.27 1.27)
				)
				(justify mirror)
			)
		)
		(property "Value" ""
			(at 0 0 0)
			(layer "B.Fab")
			(effects
				(font
					(size 1.27 1.27)
				)
				(justify mirror)
			)
		)
		(duplicate_pad_numbers_are_jumpers no)
		(fp_poly
			(pts
				(xy 0.2794 -0.1016) (xy -0.2794 -0.1016) (xy -0.2794 0.9906) (xy 0.2794 0.9906)
			)
			(stroke
				(width 0)
				(type default)
			)
			(fill no)
			(layer "B.CrtYd")
		)
		(fp_line
			(start 0.2794 0.9906)
			(end -0.2794 0.9906)
			(stroke
				(width 0.1)
				(type default)
			)
			(layer "B.Fab")
		)
		(fp_line
			(start 0.2794 -0.1016)
			(end 0.2794 0.9906)
			(stroke
				(width 0.1)
				(type default)
			)
			(layer "B.Fab")
		)
		(fp_line
			(start -0.2794 0.9906)
			(end -0.2794 -0.1016)
			(stroke
				(width 0.1)
				(type default)
			)
			(layer "B.Fab")
		)
		(fp_line
			(start -0.2794 -0.1016)
			(end 0.2794 -0.1016)
			(stroke
				(width 0.1)
				(type default)
			)
			(layer "B.Fab")
		)
		(pad "1" smd rect
			(at 0 0)
			(size 0.508 0.508)
			(layers "B.Cu" "B.Mask" "B.Paste")
			(net "RMII_BMC_OCP_RXD1")
		)
		(pad "2" smd rect
			(at 0 0.889)
			(size 0.508 0.508)
			(layers "B.Cu" "B.Mask" "B.Paste")
			(net "RMII_BMC_OCP_RXD1_R")
		)
		(zone
			(layer "B.Cu")
			(hatch none 0.5)
			(connect_pads
				(clearance 0)
			)
			(min_thickness 0.25)
			(keepout
				(tracks not_allowed)
				(vias allowed)
				(pads allowed)
				(copperpour not_allowed)
				(footprints allowed)
			)
			(placement
				(enabled no)
				(sheetname "")
			)
			(fill
				(thermal_gap 0.5)
				(thermal_bridge_width 0.5)
				(island_removal_mode 0)
			)
			(polygon
				(pts
					(xy 470.408 -117.475) (xy 470.916 -117.475) (xy 470.916 -117.094) (xy 470.408 -117.094)
				)
			)
		)
		(zone
			(layer "B.Cu")
			(hatch none 0.5)
			(connect_pads
				(clearance 0)
			)
			(min_thickness 0.25)
			(keepout
				(tracks allowed)
				(vias not_allowed)
				(pads allowed)
				(copperpour not_allowed)
				(footprints allowed)
			)
			(placement
				(enabled no)
				(sheetname "")
			)
			(fill
				(thermal_gap 0.5)
				(thermal_bridge_width 0.5)
				(island_removal_mode 0)
			)
			(polygon
				(pts
					(xy 470.408 -117.094) (xy 470.916 -117.094) (xy 470.916 -117.475) (xy 470.408 -117.475)
				)
			)
		)
	)
	(footprint ""
		(layer "B.Cu")
		(at 410.097986 -11.857736 -90)
		(property "Reference" "C2R12"
			(at 0 0 90)
			(layer "B.SilkS")
			(hide yes)
			(effects
				(font
					(size 1.27 1.27)
				)
				(justify mirror)
			)
		)
		(property "Value" ""
			(at 0 0 90)
			(layer "B.Fab")
			(effects
				(font
					(size 1.27 1.27)
				)
				(justify mirror)
			)
		)
		(duplicate_pad_numbers_are_jumpers no)
		(fp_poly
			(pts
				(xy -0.3048 -0.1016) (xy -0.3048 0.9906) (xy 0.3048 0.9906) (xy 0.3048 -0.1016)
			)
			(stroke
				(width 0)
				(type default)
			)
			(fill no)
			(layer "B.CrtYd")
		)
		(fp_line
			(start -0.3048 0.9906)
			(end -0.3048 -0.1016)
			(stroke
				(width 0.1)
				(type default)
			)
			(layer "B.Fab")
		)
		(fp_line
			(start 0.3048 0.9906)
			(end -0.3048 0.9906)
			(stroke
				(width 0.1)
				(type default)
			)
			(layer "B.Fab")
		)
		(fp_line
			(start -0.3048 -0.1016)
			(end 0.3048 -0.1016)
			(stroke
				(width 0.1)
				(type default)
			)
			(layer "B.Fab")
		)
		(fp_line
			(start 0.3048 -0.1016)
			(end 0.3048 0.9906)
			(stroke
				(width 0.1)
				(type default)
			)
			(layer "B.Fab")
		)
		(pad "1" smd rect
			(at 0 0 90)
			(size 0.508 0.508)
			(layers "B.Cu" "B.Mask" "B.Paste")
			(net "FP_NMI_BTN_OUT_N")
		)
		(pad "2" smd rect
			(at 0 0.889 90)
			(size 0.508 0.508)
			(layers "B.Cu" "B.Mask" "B.Paste")
			(net "GND")
		)
		(zone
			(layer "B.Cu")
			(hatch none 0.5)
			(connect_pads
				(clearance 0)
			)
			(min_thickness 0.25)
			(keepout
				(tracks not_allowed)
				(vias allowed)
				(pads allowed)
				(copperpour not_allowed)
				(footprints allowed)
			)
			(placement
				(enabled no)
				(sheetname "")
			)
			(fill
				(thermal_gap 0.5)
				(thermal_bridge_width 0.5)
				(island_removal_mode 0)
			)
			(polygon
				(pts
					(xy 409.462986 -11.603736) (xy 409.462986 -12.111736) (xy 409.843986 -12.111736) (xy 409.843986 -11.603736)
				)
			)
		)
		(zone
			(layer "B.Cu")
			(hatch none 0.5)
			(connect_pads
				(clearance 0)
			)
			(min_thickness 0.25)
			(keepout
				(tracks allowed)
				(vias not_allowed)
				(pads allowed)
				(copperpour not_allowed)
				(footprints allowed)
			)
			(placement
				(enabled no)
				(sheetname "")
			)
			(fill
				(thermal_gap 0.5)
				(thermal_bridge_width 0.5)
				(island_removal_mode 0)
			)
			(polygon
				(pts
					(xy 409.843986 -11.603736) (xy 409.843986 -12.111736) (xy 409.462986 -12.111736) (xy 409.462986 -11.603736)
				)
			)
		)
	)
	(footprint ""
		(layer "B.Cu")
		(at 446.381632 -33.5915 90)
		(property "Reference" "R25W2"
			(at 0 0 90)
			(layer "B.SilkS")
			(hide yes)
			(effects
				(font
					(size 1.27 1.27)
				)
				(justify mirror)
			)
		)
		(property "Value" "*"
			(at -0.064008 -4.108196 90)
			(unlocked yes)
			(layer "B.Fab")
			(hide yes)
			(effects
				(font
					(size 1.27 1.016)
					(thickness 0.1524)
				)
				(justify mirror)
			)
		)
		(property "Device Type" "120R2F-GP_RCL_GP-120R2F-GP,64.A"
			(at -0.064008 -5.632196 90)
			(unlocked yes)
			(layer "B.Fab")
			(hide yes)
			(effects
				(font
					(size 1.27 1.016)
					(thickness 0.1524)
				)
				(justify mirror)
			)
		)
		(duplicate_pad_numbers_are_jumpers no)
		(fp_line
			(start 0.508 -0.9398)
			(end 0.508 0.9398)
			(stroke
				(width 0.1524)
				(type default)
			)
			(layer "B.SilkS")
		)
		(fp_line
			(start -0.508 -0.9398)
			(end 0.508 -0.9398)
			(stroke
				(width 0.1524)
				(type default)
			)
			(layer "B.SilkS")
		)
		(fp_rect
			(start 0.508 0.9398)
			(end -0.508 -0.9398)
			(stroke
				(width 0)
				(type default)
			)
			(fill no)
			(layer "B.CrtYd")
		)
		(fp_rect
			(start 0.508 0.9398)
			(end -0.508 -0.9398)
			(stroke
				(width 0)
				(type default)
			)
			(fill no)
			(layer "B.Fab")
		)
		(pad "1" smd custom
			(at 0 -0.4445 270)
			(size 0.1397 0.1397)
			(layers "B.Cu" "B.Mask" "B.Paste")
			(net "GND")
			(options
				(clearance outline)
				(anchor circle)
			)
			(primitives
				(gr_poly
					(pts
						(arc
							(start -0.1778 0.2794)
							(mid -0.249642 0.249642)
							(end -0.2794 0.1778)
						)
						(arc
							(start -0.2794 -0.1778)
							(mid -0.249642 -0.249642)
							(end -0.1778 -0.2794)
						)
						(arc
							(start 0.1778 -0.2794)
							(mid 0.249642 -0.249642)
							(end 0.2794 -0.1778)
						)
						(arc
							(start 0.2794 0.1778)
							(mid 0.249642 0.249642)
							(end 0.1778 0.2794)
						)
					)
					(width 0)
					(fill yes)
				)
			)
		)
		(pad "2" smd custom
			(at 0 0.4445 270)
			(size 0.1397 0.1397)
			(layers "B.Cu" "B.Mask" "B.Paste")
			(net "BMC_M_ODT")
			(options
				(clearance outline)
				(anchor circle)
			)
			(primitives
				(gr_poly
					(pts
						(arc
							(start -0.1778 0.2794)
							(mid -0.249642 0.249642)
							(end -0.2794 0.1778)
						)
						(arc
							(start -0.2794 -0.1778)
							(mid -0.249642 -0.249642)
							(end -0.1778 -0.2794)
						)
						(arc
							(start 0.1778 -0.2794)
							(mid 0.249642 -0.249642)
							(end 0.2794 -0.1778)
						)
						(arc
							(start 0.2794 0.1778)
							(mid 0.249642 0.249642)
							(end 0.1778 0.2794)
						)
					)
					(width 0)
					(fill yes)
				)
			)
		)
	)
	(footprint ""
		(layer "B.Cu")
		(at 32.832802 -82.681064 90)
		(property "Reference" "C9P1"
			(at 0 0 90)
			(layer "B.SilkS")
			(hide yes)
			(effects
				(font
					(size 1.27 1.27)
				)
				(justify mirror)
			)
		)
		(property "Value" ""
			(at 0 0 90)
			(layer "B.Fab")
			(effects
				(font
					(size 1.27 1.27)
				)
				(justify mirror)
			)
		)
		(duplicate_pad_numbers_are_jumpers no)
		(fp_poly
			(pts
				(xy 0.7239 -0.2159) (xy -0.7239 -0.2159) (xy -0.7239 1.9939) (xy 0.7239 1.9939)
			)
			(stroke
				(width 0)
				(type default)
			)
			(fill no)
			(layer "B.CrtYd")
		)
		(fp_line
			(start 0.7239 -0.2159)
			(end 0.7239 1.9939)
			(stroke
				(width 0.1)
				(type default)
			)
			(layer "B.Fab")
		)
		(fp_line
			(start -0.7239 -0.2159)
			(end 0.7239 -0.2159)
			(stroke
				(width 0.1)
				(type default)
			)
			(layer "B.Fab")
		)
		(fp_line
			(start 0.7239 1.9939)
			(end -0.7239 1.9939)
			(stroke
				(width 0.1)
				(type default)
			)
			(layer "B.Fab")
		)
		(fp_line
			(start -0.7239 1.9939)
			(end -0.7239 -0.2159)
			(stroke
				(width 0.1)
				(type default)
			)
			(layer "B.Fab")
		)
		(pad "1" smd rect
			(at 0 0 270)
			(size 1.27 1.016)
			(layers "B.Cu" "B.Mask" "B.Paste")
			(net "VR_FET_SW_P12V_STBY_PVCCIN_CPU1")
		)
		(pad "2" smd rect
			(at 0 1.778 270)
			(size 1.27 1.016)
			(layers "B.Cu" "B.Mask" "B.Paste")
			(net "GND")
		)
		(zone
			(layer "B.Cu")
			(hatch none 0.5)
			(connect_pads
				(clearance 0)
			)
			(min_thickness 0.25)
			(keepout
				(tracks not_allowed)
				(vias allowed)
				(pads allowed)
				(copperpour not_allowed)
				(footprints allowed)
			)
			(placement
				(enabled no)
				(sheetname "")
			)
			(fill
				(thermal_gap 0.5)
				(thermal_bridge_width 0.5)
				(island_removal_mode 0)
			)
			(polygon
				(pts
					(xy 33.340802 -83.316064) (xy 33.340802 -82.046064) (xy 34.102802 -82.046064) (xy 34.102802 -83.316064)
				)
			)
		)
	)
	(footprint ""
		(layer "B.Cu")
		(at 104.5591 -3.3528 90)
		(property "Reference" "C5G90"
			(at -1.14681 0.76708 180)
			(unlocked yes)
			(layer "B.SilkS")
			(effects
				(font
					(size 0.7874 0.5842)
					(thickness 0.1524)
				)
				(justify mirror)
			)
		)
		(property "Value" ""
			(at 0 0 90)
			(layer "B.Fab")
			(effects
				(font
					(size 1.27 1.27)
				)
				(justify mirror)
			)
		)
		(duplicate_pad_numbers_are_jumpers no)
		(fp_rect
			(start -0.4953 -0.2032)
			(end 0.4953 1.6002)
			(stroke
				(width 0)
				(type default)
			)
			(fill no)
			(layer "B.CrtYd")
		)
		(fp_line
			(start 0.4953 -0.2032)
			(end -0.4953 -0.2032)
			(stroke
				(width 0.1)
				(type default)
			)
			(layer "B.Fab")
		)
		(fp_line
			(start -0.4953 -0.2032)
			(end -0.4953 1.6002)
			(stroke
				(width 0.1)
				(type default)
			)
			(layer "B.Fab")
		)
		(fp_line
			(start 0.4953 1.6002)
			(end 0.4953 -0.2032)
			(stroke
				(width 0.1)
				(type default)
			)
			(layer "B.Fab")
		)
		(fp_line
			(start -0.4953 1.6002)
			(end 0.4953 1.6002)
			(stroke
				(width 0.1)
				(type default)
			)
			(layer "B.Fab")
		)
		(pad "1" smd rect
			(at 0 0 270)
			(size 0.762 0.889)
			(layers "B.Cu" "B.Mask" "B.Paste")
			(net "PVDDQ_GHJ")
		)
		(pad "2" smd rect
			(at 0 1.397 270)
			(size 0.762 0.889)
			(layers "B.Cu" "B.Mask" "B.Paste")
			(net "GND")
		)
		(zone
			(layer "B.Cu")
			(hatch none 0.5)
			(connect_pads
				(clearance 0)
			)
			(min_thickness 0.25)
			(keepout
				(tracks not_allowed)
				(vias allowed)
				(pads allowed)
				(copperpour not_allowed)
				(footprints allowed)
			)
			(placement
				(enabled no)
				(sheetname "")
			)
			(fill
				(thermal_gap 0.5)
				(thermal_bridge_width 0.5)
				(island_removal_mode 0)
			)
			(polygon
				(pts
					(xy 105.0036 -2.9718) (xy 105.5116 -2.9718) (xy 105.5116 -3.7338) (xy 105.0036 -3.7338)
				)
			)
		)
	)
	(footprint ""
		(layer "B.Cu")
		(at 97.206054 -73.51014)
		(property "Reference" "C8P27"
			(at 0 0 0)
			(layer "B.SilkS")
			(hide yes)
			(effects
				(font
					(size 1.27 1.27)
				)
				(justify mirror)
			)
		)
		(property "Value" ""
			(at 0 0 0)
			(layer "B.Fab")
			(effects
				(font
					(size 1.27 1.27)
				)
				(justify mirror)
			)
		)
		(duplicate_pad_numbers_are_jumpers no)
		(fp_poly
			(pts
				(xy 0.7239 -0.2159) (xy -0.7239 -0.2159) (xy -0.7239 1.9939) (xy 0.7239 1.9939)
			)
			(stroke
				(width 0)
				(type default)
			)
			(fill no)
			(layer "B.CrtYd")
		)
		(fp_line
			(start -0.7239 -0.2159)
			(end 0.7239 -0.2159)
			(stroke
				(width 0.1)
				(type default)
			)
			(layer "B.Fab")
		)
		(fp_line
			(start -0.7239 1.9939)
			(end -0.7239 -0.2159)
			(stroke
				(width 0.1)
				(type default)
			)
			(layer "B.Fab")
		)
		(fp_line
			(start 0.7239 -0.2159)
			(end 0.7239 1.9939)
			(stroke
				(width 0.1)
				(type default)
			)
			(layer "B.Fab")
		)
		(fp_line
			(start 0.7239 1.9939)
			(end -0.7239 1.9939)
			(stroke
				(width 0.1)
				(type default)
			)
			(layer "B.Fab")
		)
		(pad "1" smd rect
			(at 0 0 180)
			(size 1.27 1.016)
			(layers "B.Cu" "B.Mask" "B.Paste")
			(net "PVCCIN_CPU1")
		)
		(pad "2" smd rect
			(at 0 1.778 180)
			(size 1.27 1.016)
			(layers "B.Cu" "B.Mask" "B.Paste")
			(net "GND")
		)
		(zone
			(layer "B.Cu")
			(hatch none 0.5)
			(connect_pads
				(clearance 0)
			)
			(min_thickness 0.25)
			(keepout
				(tracks not_allowed)
				(vias allowed)
				(pads allowed)
				(copperpour not_allowed)
				(footprints allowed)
			)
			(placement
				(enabled no)
				(sheetname "")
			)
			(fill
				(thermal_gap 0.5)
				(thermal_bridge_width 0.5)
				(island_removal_mode 0)
			)
			(polygon
				(pts
					(xy 97.841054 -73.00214) (xy 96.571054 -73.00214) (xy 96.571054 -72.24014) (xy 97.841054 -72.24014)
				)
			)
		)
	)
	(footprint ""
		(layer "B.Cu")
		(at 482.854 -32.512 180)
		(property "Reference" "C2T28"
			(at 0 0 0)
			(layer "B.SilkS")
			(hide yes)
			(effects
				(font
					(size 1.27 1.27)
				)
				(justify mirror)
			)
		)
		(property "Value" ""
			(at 0 0 0)
			(layer "B.Fab")
			(effects
				(font
					(size 1.27 1.27)
				)
				(justify mirror)
			)
		)
		(duplicate_pad_numbers_are_jumpers no)
		(fp_poly
			(pts
				(xy -0.3048 -0.1016) (xy -0.3048 0.9906) (xy 0.3048 0.9906) (xy 0.3048 -0.1016)
			)
			(stroke
				(width 0)
				(type default)
			)
			(fill no)
			(layer "B.CrtYd")
		)
		(fp_line
			(start 0.3048 0.9906)
			(end -0.3048 0.9906)
			(stroke
				(width 0.1)
				(type default)
			)
			(layer "B.Fab")
		)
		(fp_line
			(start 0.3048 -0.1016)
			(end 0.3048 0.9906)
			(stroke
				(width 0.1)
				(type default)
			)
			(layer "B.Fab")
		)
		(fp_line
			(start -0.3048 0.9906)
			(end -0.3048 -0.1016)
			(stroke
				(width 0.1)
				(type default)
			)
			(layer "B.Fab")
		)
		(fp_line
			(start -0.3048 -0.1016)
			(end 0.3048 -0.1016)
			(stroke
				(width 0.1)
				(type default)
			)
			(layer "B.Fab")
		)
		(pad "1" smd rect
			(at 0 0)
			(size 0.508 0.508)
			(layers "B.Cu" "B.Mask" "B.Paste")
			(net "P3V3_STBY")
		)
		(pad "2" smd rect
			(at 0 0.889)
			(size 0.508 0.508)
			(layers "B.Cu" "B.Mask" "B.Paste")
			(net "GND")
		)
		(zone
			(layer "B.Cu")
			(hatch none 0.5)
			(connect_pads
				(clearance 0)
			)
			(min_thickness 0.25)
			(keepout
				(tracks not_allowed)
				(vias allowed)
				(pads allowed)
				(copperpour not_allowed)
				(footprints allowed)
			)
			(placement
				(enabled no)
				(sheetname "")
			)
			(fill
				(thermal_gap 0.5)
				(thermal_bridge_width 0.5)
				(island_removal_mode 0)
			)
			(polygon
				(pts
					(xy 482.6 -33.147) (xy 483.108 -33.147) (xy 483.108 -32.766) (xy 482.6 -32.766)
				)
			)
		)
		(zone
			(layer "B.Cu")
			(hatch none 0.5)
			(connect_pads
				(clearance 0)
			)
			(min_thickness 0.25)
			(keepout
				(tracks allowed)
				(vias not_allowed)
				(pads allowed)
				(copperpour not_allowed)
				(footprints allowed)
			)
			(placement
				(enabled no)
				(sheetname "")
			)
			(fill
				(thermal_gap 0.5)
				(thermal_bridge_width 0.5)
				(island_removal_mode 0)
			)
			(polygon
				(pts
					(xy 482.6 -32.766) (xy 483.108 -32.766) (xy 483.108 -33.147) (xy 482.6 -33.147)
				)
			)
		)
	)
	(footprint ""
		(layer "B.Cu")
		(at 27.0764 -77.089 180)
		(property "Reference" "R9P20"
			(at 0 0 0)
			(layer "B.SilkS")
			(hide yes)
			(effects
				(font
					(size 1.27 1.27)
				)
				(justify mirror)
			)
		)
		(property "Value" ""
			(at 0 0 0)
			(layer "B.Fab")
			(effects
				(font
					(size 1.27 1.27)
				)
				(justify mirror)
			)
		)
		(duplicate_pad_numbers_are_jumpers no)
		(fp_poly
			(pts
				(xy 0.2794 -0.1016) (xy -0.2794 -0.1016) (xy -0.2794 0.9906) (xy 0.2794 0.9906)
			)
			(stroke
				(width 0)
				(type default)
			)
			(fill no)
			(layer "B.CrtYd")
		)
		(fp_line
			(start 0.2794 0.9906)
			(end -0.2794 0.9906)
			(stroke
				(width 0.1)
				(type default)
			)
			(layer "B.Fab")
		)
		(fp_line
			(start 0.2794 -0.1016)
			(end 0.2794 0.9906)
			(stroke
				(width 0.1)
				(type default)
			)
			(layer "B.Fab")
		)
		(fp_line
			(start -0.2794 0.9906)
			(end -0.2794 -0.1016)
			(stroke
				(width 0.1)
				(type default)
			)
			(layer "B.Fab")
		)
		(fp_line
			(start -0.2794 -0.1016)
			(end 0.2794 -0.1016)
			(stroke
				(width 0.1)
				(type default)
			)
			(layer "B.Fab")
		)
		(pad "1" smd rect
			(at 0 0)
			(size 0.508 0.508)
			(layers "B.Cu" "B.Mask" "B.Paste")
			(net "P3V3_STBY")
		)
		(pad "2" smd rect
			(at 0 0.889)
			(size 0.508 0.508)
			(layers "B.Cu" "B.Mask" "B.Paste")
			(net "FM_HSC_TIMER_EXP_N")
		)
		(zone
			(layer "B.Cu")
			(hatch none 0.5)
			(connect_pads
				(clearance 0)
			)
			(min_thickness 0.25)
			(keepout
				(tracks not_allowed)
				(vias allowed)
				(pads allowed)
				(copperpour not_allowed)
				(footprints allowed)
			)
			(placement
				(enabled no)
				(sheetname "")
			)
			(fill
				(thermal_gap 0.5)
				(thermal_bridge_width 0.5)
				(island_removal_mode 0)
			)
			(polygon
				(pts
					(xy 26.8224 -77.724) (xy 27.3304 -77.724) (xy 27.3304 -77.343) (xy 26.8224 -77.343)
				)
			)
		)
		(zone
			(layer "B.Cu")
			(hatch none 0.5)
			(connect_pads
				(clearance 0)
			)
			(min_thickness 0.25)
			(keepout
				(tracks allowed)
				(vias not_allowed)
				(pads allowed)
				(copperpour not_allowed)
				(footprints allowed)
			)
			(placement
				(enabled no)
				(sheetname "")
			)
			(fill
				(thermal_gap 0.5)
				(thermal_bridge_width 0.5)
				(island_removal_mode 0)
			)
			(polygon
				(pts
					(xy 26.8224 -77.343) (xy 27.3304 -77.343) (xy 27.3304 -77.724) (xy 26.8224 -77.724)
				)
			)
		)
	)
	(footprint ""
		(layer "B.Cu")
		(at 453.6948 -147.5486 90)
		(property "Reference" "R9A11"
			(at 0 0 90)
			(layer "B.SilkS")
			(hide yes)
			(effects
				(font
					(size 1.27 1.27)
				)
				(justify mirror)
			)
		)
		(property "Value" ""
			(at 0 0 90)
			(layer "B.Fab")
			(effects
				(font
					(size 1.27 1.27)
				)
				(justify mirror)
			)
		)
		(duplicate_pad_numbers_are_jumpers no)
		(fp_poly
			(pts
				(xy 0.2794 -0.1016) (xy -0.2794 -0.1016) (xy -0.2794 0.9906) (xy 0.2794 0.9906)
			)
			(stroke
				(width 0)
				(type default)
			)
			(fill no)
			(layer "B.CrtYd")
		)
		(fp_line
			(start 0.2794 -0.1016)
			(end 0.2794 0.9906)
			(stroke
				(width 0.1)
				(type default)
			)
			(layer "B.Fab")
		)
		(fp_line
			(start -0.2794 -0.1016)
			(end 0.2794 -0.1016)
			(stroke
				(width 0.1)
				(type default)
			)
			(layer "B.Fab")
		)
		(fp_line
			(start 0.2794 0.9906)
			(end -0.2794 0.9906)
			(stroke
				(width 0.1)
				(type default)
			)
			(layer "B.Fab")
		)
		(fp_line
			(start -0.2794 0.9906)
			(end -0.2794 -0.1016)
			(stroke
				(width 0.1)
				(type default)
			)
			(layer "B.Fab")
		)
		(pad "1" smd rect
			(at 0 0 270)
			(size 0.508 0.508)
			(layers "B.Cu" "B.Mask" "B.Paste")
			(net "P1V05_PCH_STBY")
		)
		(pad "2" smd rect
			(at 0 0.889 270)
			(size 0.508 0.508)
			(layers "B.Cu" "B.Mask" "B.Paste")
			(net "XDP_TDO")
		)
		(zone
			(layer "B.Cu")
			(hatch none 0.5)
			(connect_pads
				(clearance 0)
			)
			(min_thickness 0.25)
			(keepout
				(tracks allowed)
				(vias not_allowed)
				(pads allowed)
				(copperpour not_allowed)
				(footprints allowed)
			)
			(placement
				(enabled no)
				(sheetname "")
			)
			(fill
				(thermal_gap 0.5)
				(thermal_bridge_width 0.5)
				(island_removal_mode 0)
			)
			(polygon
				(pts
					(xy 453.9488 -147.8026) (xy 453.9488 -147.2946) (xy 454.3298 -147.2946) (xy 454.3298 -147.8026)
				)
			)
		)
		(zone
			(layer "B.Cu")
			(hatch none 0.5)
			(connect_pads
				(clearance 0)
			)
			(min_thickness 0.25)
			(keepout
				(tracks not_allowed)
				(vias allowed)
				(pads allowed)
				(copperpour not_allowed)
				(footprints allowed)
			)
			(placement
				(enabled no)
				(sheetname "")
			)
			(fill
				(thermal_gap 0.5)
				(thermal_bridge_width 0.5)
				(island_removal_mode 0)
			)
			(polygon
				(pts
					(xy 454.3298 -147.8026) (xy 454.3298 -147.2946) (xy 453.9488 -147.2946) (xy 453.9488 -147.8026)
				)
			)
		)
	)
	(footprint ""
		(layer "B.Cu")
		(at 367.646712 -37.856922)
		(property "Reference" "R8F13"
			(at 0 0 0)
			(layer "B.SilkS")
			(hide yes)
			(effects
				(font
					(size 1.27 1.27)
				)
				(justify mirror)
			)
		)
		(property "Value" ""
			(at 0 0 0)
			(layer "B.Fab")
			(effects
				(font
					(size 1.27 1.27)
				)
				(justify mirror)
			)
		)
		(duplicate_pad_numbers_are_jumpers no)
		(fp_poly
			(pts
				(xy 0.2794 -0.1016) (xy -0.2794 -0.1016) (xy -0.2794 0.9906) (xy 0.2794 0.9906)
			)
			(stroke
				(width 0)
				(type default)
			)
			(fill no)
			(layer "B.CrtYd")
		)
		(fp_line
			(start -0.2794 -0.1016)
			(end 0.2794 -0.1016)
			(stroke
				(width 0.1)
				(type default)
			)
			(layer "B.Fab")
		)
		(fp_line
			(start -0.2794 0.9906)
			(end -0.2794 -0.1016)
			(stroke
				(width 0.1)
				(type default)
			)
			(layer "B.Fab")
		)
		(fp_line
			(start 0.2794 -0.1016)
			(end 0.2794 0.9906)
			(stroke
				(width 0.1)
				(type default)
			)
			(layer "B.Fab")
		)
		(fp_line
			(start 0.2794 0.9906)
			(end -0.2794 0.9906)
			(stroke
				(width 0.1)
				(type default)
			)
			(layer "B.Fab")
		)
		(pad "1" smd rect
			(at 0 0 180)
			(size 0.508 0.508)
			(layers "B.Cu" "B.Mask" "B.Paste")
			(net "P3V3_STBY")
		)
		(pad "2" smd rect
			(at 0 0.889 180)
			(size 0.508 0.508)
			(layers "B.Cu" "B.Mask" "B.Paste")
			(net "SPI_BMC_BT_CS_N")
		)
		(zone
			(layer "B.Cu")
			(hatch none 0.5)
			(connect_pads
				(clearance 0)
			)
			(min_thickness 0.25)
			(keepout
				(tracks allowed)
				(vias not_allowed)
				(pads allowed)
				(copperpour not_allowed)
				(footprints allowed)
			)
			(placement
				(enabled no)
				(sheetname "")
			)
			(fill
				(thermal_gap 0.5)
				(thermal_bridge_width 0.5)
				(island_removal_mode 0)
			)
			(polygon
				(pts
					(xy 367.900712 -37.602922) (xy 367.392712 -37.602922) (xy 367.392712 -37.221922) (xy 367.900712 -37.221922)
				)
			)
		)
		(zone
			(layer "B.Cu")
			(hatch none 0.5)
			(connect_pads
				(clearance 0)
			)
			(min_thickness 0.25)
			(keepout
				(tracks not_allowed)
				(vias allowed)
				(pads allowed)
				(copperpour not_allowed)
				(footprints allowed)
			)
			(placement
				(enabled no)
				(sheetname "")
			)
			(fill
				(thermal_gap 0.5)
				(thermal_bridge_width 0.5)
				(island_removal_mode 0)
			)
			(polygon
				(pts
					(xy 367.900712 -37.221922) (xy 367.392712 -37.221922) (xy 367.392712 -37.602922) (xy 367.900712 -37.602922)
				)
			)
		)
	)
	(footprint ""
		(layer "B.Cu")
		(at 454.453752 -144.455896)
		(property "Reference" "R9A17"
			(at 0 0 0)
			(layer "B.SilkS")
			(hide yes)
			(effects
				(font
					(size 1.27 1.27)
				)
				(justify mirror)
			)
		)
		(property "Value" ""
			(at 0 0 0)
			(layer "B.Fab")
			(effects
				(font
					(size 1.27 1.27)
				)
				(justify mirror)
			)
		)
		(duplicate_pad_numbers_are_jumpers no)
		(fp_poly
			(pts
				(xy 0.2794 -0.1016) (xy -0.2794 -0.1016) (xy -0.2794 0.9906) (xy 0.2794 0.9906)
			)
			(stroke
				(width 0)
				(type default)
			)
			(fill no)
			(layer "B.CrtYd")
		)
		(fp_line
			(start -0.2794 -0.1016)
			(end 0.2794 -0.1016)
			(stroke
				(width 0.1)
				(type default)
			)
			(layer "B.Fab")
		)
		(fp_line
			(start -0.2794 0.9906)
			(end -0.2794 -0.1016)
			(stroke
				(width 0.1)
				(type default)
			)
			(layer "B.Fab")
		)
		(fp_line
			(start 0.2794 -0.1016)
			(end 0.2794 0.9906)
			(stroke
				(width 0.1)
				(type default)
			)
			(layer "B.Fab")
		)
		(fp_line
			(start 0.2794 0.9906)
			(end -0.2794 0.9906)
			(stroke
				(width 0.1)
				(type default)
			)
			(layer "B.Fab")
		)
		(pad "1" smd rect
			(at 0 0 180)
			(size 0.508 0.508)
			(layers "B.Cu" "B.Mask" "B.Paste")
			(net "XDP_ITP_PMODE")
		)
		(pad "2" smd rect
			(at 0 0.889 180)
			(size 0.508 0.508)
			(layers "B.Cu" "B.Mask" "B.Paste")
			(net "P1V05_PCH_STBY")
		)
		(zone
			(layer "B.Cu")
			(hatch none 0.5)
			(connect_pads
				(clearance 0)
			)
			(min_thickness 0.25)
			(keepout
				(tracks allowed)
				(vias not_allowed)
				(pads allowed)
				(copperpour not_allowed)
				(footprints allowed)
			)
			(placement
				(enabled no)
				(sheetname "")
			)
			(fill
				(thermal_gap 0.5)
				(thermal_bridge_width 0.5)
				(island_removal_mode 0)
			)
			(polygon
				(pts
					(xy 454.707752 -144.201896) (xy 454.199752 -144.201896) (xy 454.199752 -143.820896) (xy 454.707752 -143.820896)
				)
			)
		)
		(zone
			(layer "B.Cu")
			(hatch none 0.5)
			(connect_pads
				(clearance 0)
			)
			(min_thickness 0.25)
			(keepout
				(tracks not_allowed)
				(vias allowed)
				(pads allowed)
				(copperpour not_allowed)
				(footprints allowed)
			)
			(placement
				(enabled no)
				(sheetname "")
			)
			(fill
				(thermal_gap 0.5)
				(thermal_bridge_width 0.5)
				(island_removal_mode 0)
			)
			(polygon
				(pts
					(xy 454.707752 -143.820896) (xy 454.199752 -143.820896) (xy 454.199752 -144.201896) (xy 454.707752 -144.201896)
				)
			)
		)
	)
	(footprint ""
		(layer "B.Cu")
		(at 385.572 -49.403 90)
		(property "Reference" "R3U1"
			(at 0 0 90)
			(layer "B.SilkS")
			(hide yes)
			(effects
				(font
					(size 1.27 1.27)
				)
				(justify mirror)
			)
		)
		(property "Value" ""
			(at 0 0 90)
			(layer "B.Fab")
			(effects
				(font
					(size 1.27 1.27)
				)
				(justify mirror)
			)
		)
		(duplicate_pad_numbers_are_jumpers no)
		(fp_poly
			(pts
				(xy 0.2794 -0.1016) (xy -0.2794 -0.1016) (xy -0.2794 0.9906) (xy 0.2794 0.9906)
			)
			(stroke
				(width 0)
				(type default)
			)
			(fill no)
			(layer "B.CrtYd")
		)
		(fp_line
			(start 0.2794 -0.1016)
			(end 0.2794 0.9906)
			(stroke
				(width 0.1)
				(type default)
			)
			(layer "B.Fab")
		)
		(fp_line
			(start -0.2794 -0.1016)
			(end 0.2794 -0.1016)
			(stroke
				(width 0.1)
				(type default)
			)
			(layer "B.Fab")
		)
		(fp_line
			(start 0.2794 0.9906)
			(end -0.2794 0.9906)
			(stroke
				(width 0.1)
				(type default)
			)
			(layer "B.Fab")
		)
		(fp_line
			(start -0.2794 0.9906)
			(end -0.2794 -0.1016)
			(stroke
				(width 0.1)
				(type default)
			)
			(layer "B.Fab")
		)
		(pad "1" smd rect
			(at 0 0 270)
			(size 0.508 0.508)
			(layers "B.Cu" "B.Mask" "B.Paste")
			(net "SPI_BIOS_SOCKET_IO2")
		)
		(pad "2" smd rect
			(at 0 0.889 270)
			(size 0.508 0.508)
			(layers "B.Cu" "B.Mask" "B.Paste")
			(net "PU_BIOS_SPI_WP1_N")
		)
		(zone
			(layer "B.Cu")
			(hatch none 0.5)
			(connect_pads
				(clearance 0)
			)
			(min_thickness 0.25)
			(keepout
				(tracks allowed)
				(vias not_allowed)
				(pads allowed)
				(copperpour not_allowed)
				(footprints allowed)
			)
			(placement
				(enabled no)
				(sheetname "")
			)
			(fill
				(thermal_gap 0.5)
				(thermal_bridge_width 0.5)
				(island_removal_mode 0)
			)
			(polygon
				(pts
					(xy 385.826 -49.657) (xy 385.826 -49.149) (xy 386.207 -49.149) (xy 386.207 -49.657)
				)
			)
		)
		(zone
			(layer "B.Cu")
			(hatch none 0.5)
			(connect_pads
				(clearance 0)
			)
			(min_thickness 0.25)
			(keepout
				(tracks not_allowed)
				(vias allowed)
				(pads allowed)
				(copperpour not_allowed)
				(footprints allowed)
			)
			(placement
				(enabled no)
				(sheetname "")
			)
			(fill
				(thermal_gap 0.5)
				(thermal_bridge_width 0.5)
				(island_removal_mode 0)
			)
			(polygon
				(pts
					(xy 386.207 -49.657) (xy 386.207 -49.149) (xy 385.826 -49.149) (xy 385.826 -49.657)
				)
			)
		)
	)
	(footprint ""
		(layer "B.Cu")
		(at 205.74 -104.775 -90)
		(property "Reference" "R6N12"
			(at 0 0 90)
			(layer "B.SilkS")
			(hide yes)
			(effects
				(font
					(size 1.27 1.27)
				)
				(justify mirror)
			)
		)
		(property "Value" ""
			(at 0 0 90)
			(layer "B.Fab")
			(effects
				(font
					(size 1.27 1.27)
				)
				(justify mirror)
			)
		)
		(duplicate_pad_numbers_are_jumpers no)
		(fp_poly
			(pts
				(xy 0.2794 -0.1016) (xy -0.2794 -0.1016) (xy -0.2794 0.9906) (xy 0.2794 0.9906)
			)
			(stroke
				(width 0)
				(type default)
			)
			(fill no)
			(layer "B.CrtYd")
		)
		(fp_line
			(start -0.2794 0.9906)
			(end -0.2794 -0.1016)
			(stroke
				(width 0.1)
				(type default)
			)
			(layer "B.Fab")
		)
		(fp_line
			(start 0.2794 0.9906)
			(end -0.2794 0.9906)
			(stroke
				(width 0.1)
				(type default)
			)
			(layer "B.Fab")
		)
		(fp_line
			(start -0.2794 -0.1016)
			(end 0.2794 -0.1016)
			(stroke
				(width 0.1)
				(type default)
			)
			(layer "B.Fab")
		)
		(fp_line
			(start 0.2794 -0.1016)
			(end 0.2794 0.9906)
			(stroke
				(width 0.1)
				(type default)
			)
			(layer "B.Fab")
		)
		(pad "1" smd rect
			(at 0 0 90)
			(size 0.508 0.508)
			(layers "B.Cu" "B.Mask" "B.Paste")
			(net "SVID_CLK0_CPU0")
		)
		(pad "2" smd rect
			(at 0 0.889 90)
			(size 0.508 0.508)
			(layers "B.Cu" "B.Mask" "B.Paste")
			(net "SVID_CLK0_CPU0_R")
		)
		(zone
			(layer "B.Cu")
			(hatch none 0.5)
			(connect_pads
				(clearance 0)
			)
			(min_thickness 0.25)
			(keepout
				(tracks not_allowed)
				(vias allowed)
				(pads allowed)
				(copperpour not_allowed)
				(footprints allowed)
			)
			(placement
				(enabled no)
				(sheetname "")
			)
			(fill
				(thermal_gap 0.5)
				(thermal_bridge_width 0.5)
				(island_removal_mode 0)
			)
			(polygon
				(pts
					(xy 205.105 -104.521) (xy 205.105 -105.029) (xy 205.486 -105.029) (xy 205.486 -104.521)
				)
			)
		)
		(zone
			(layer "B.Cu")
			(hatch none 0.5)
			(connect_pads
				(clearance 0)
			)
			(min_thickness 0.25)
			(keepout
				(tracks allowed)
				(vias not_allowed)
				(pads allowed)
				(copperpour not_allowed)
				(footprints allowed)
			)
			(placement
				(enabled no)
				(sheetname "")
			)
			(fill
				(thermal_gap 0.5)
				(thermal_bridge_width 0.5)
				(island_removal_mode 0)
			)
			(polygon
				(pts
					(xy 205.486 -104.521) (xy 205.486 -105.029) (xy 205.105 -105.029) (xy 205.105 -104.521)
				)
			)
		)
	)
	(footprint ""
		(layer "B.Cu")
		(at 83.856068 -145.0086 -90)
		(property "Reference" "C8L9"
			(at -1.848866 0.752348 270)
			(unlocked yes)
			(layer "B.SilkS")
			(effects
				(font
					(size 1.27 0.9652)
					(thickness 0.1524)
				)
				(justify mirror)
			)
		)
		(property "Value" ""
			(at 0 0 90)
			(layer "B.Fab")
			(effects
				(font
					(size 1.27 1.27)
				)
				(justify mirror)
			)
		)
		(duplicate_pad_numbers_are_jumpers no)
		(fp_rect
			(start 0.500126 1.598422)
			(end -0.500126 -0.201422)
			(stroke
				(width 0)
				(type default)
			)
			(fill no)
			(layer "B.CrtYd")
		)
		(fp_line
			(start -0.500126 1.598422)
			(end 0.500126 1.598422)
			(stroke
				(width 0.1)
				(type default)
			)
			(layer "B.Fab")
		)
		(fp_line
			(start 0.500126 1.598422)
			(end 0.500126 -0.201422)
			(stroke
				(width 0.1)
				(type default)
			)
			(layer "B.Fab")
		)
		(fp_line
			(start -0.500126 -0.201422)
			(end -0.500126 1.598422)
			(stroke
				(width 0.1)
				(type default)
			)
			(layer "B.Fab")
		)
		(fp_line
			(start 0.500126 -0.201422)
			(end -0.500126 -0.201422)
			(stroke
				(width 0.1)
				(type default)
			)
			(layer "B.Fab")
		)
		(pad "1" smd rect
			(at 0 0 180)
			(size 0.889 0.9906)
			(layers "B.Cu" "B.Mask" "B.Paste")
			(net "PVDDQ_KLM")
		)
		(pad "2" smd rect
			(at 0 1.397 180)
			(size 0.889 0.9906)
			(layers "B.Cu" "B.Mask" "B.Paste")
			(net "GND")
		)
		(zone
			(layer "B.Cu")
			(hatch none 0.5)
			(connect_pads
				(clearance 0)
			)
			(min_thickness 0.25)
			(keepout
				(tracks allowed)
				(vias not_allowed)
				(pads allowed)
				(copperpour not_allowed)
				(footprints allowed)
			)
			(placement
				(enabled no)
				(sheetname "")
			)
			(fill
				(thermal_gap 0.5)
				(thermal_bridge_width 0.5)
				(island_removal_mode 0)
			)
			(polygon
				(pts
					(xy 82.903568 -144.5133) (xy 83.411568 -144.5133) (xy 83.411568 -145.5039) (xy 82.903568 -145.5039)
				)
			)
		)
		(zone
			(layer "B.Cu")
			(hatch none 0.5)
			(connect_pads
				(clearance 0)
			)
			(min_thickness 0.25)
			(keepout
				(tracks not_allowed)
				(vias allowed)
				(pads allowed)
				(copperpour not_allowed)
				(footprints allowed)
			)
			(placement
				(enabled no)
				(sheetname "")
			)
			(fill
				(thermal_gap 0.5)
				(thermal_bridge_width 0.5)
				(island_removal_mode 0)
			)
			(polygon
				(pts
					(xy 82.903568 -144.5133) (xy 83.411568 -144.5133) (xy 83.411568 -145.5039) (xy 82.903568 -145.5039)
				)
			)
		)
	)
	(footprint ""
		(layer "B.Cu")
		(at 400.756628 -117.179344)
		(property "Reference" "R7W8"
			(at 0.8382 -0.67818 0)
			(unlocked yes)
			(layer "B.SilkS")
			(effects
				(font
					(size 0.4064 0.254)
					(thickness 0.1524)
				)
				(justify left mirror)
			)
		)
		(property "Value" ""
			(at 0 0 0)
			(layer "B.Fab")
			(effects
				(font
					(size 1.27 1.27)
				)
				(justify mirror)
			)
		)
		(duplicate_pad_numbers_are_jumpers no)
		(fp_poly
			(pts
				(xy 0.2794 -0.1016) (xy -0.2794 -0.1016) (xy -0.2794 0.9906) (xy 0.2794 0.9906)
			)
			(stroke
				(width 0)
				(type default)
			)
			(fill no)
			(layer "B.CrtYd")
		)
		(fp_line
			(start -0.2794 -0.1016)
			(end 0.2794 -0.1016)
			(stroke
				(width 0.1)
				(type default)
			)
			(layer "B.Fab")
		)
		(fp_line
			(start -0.2794 0.9906)
			(end -0.2794 -0.1016)
			(stroke
				(width 0.1)
				(type default)
			)
			(layer "B.Fab")
		)
		(fp_line
			(start 0.2794 -0.1016)
			(end 0.2794 0.9906)
			(stroke
				(width 0.1)
				(type default)
			)
			(layer "B.Fab")
		)
		(fp_line
			(start 0.2794 0.9906)
			(end -0.2794 0.9906)
			(stroke
				(width 0.1)
				(type default)
			)
			(layer "B.Fab")
		)
		(pad "1" smd rect
			(at 0 0 180)
			(size 0.508 0.508)
			(layers "B.Cu" "B.Mask" "B.Paste")
			(net "FM_POST_CARD_PRES_BMC_N")
		)
		(pad "2" smd rect
			(at 0 0.889 180)
			(size 0.508 0.508)
			(layers "B.Cu" "B.Mask" "B.Paste")
			(net "FM_POST_CARD_PRES_BMC_R1_N")
		)
		(zone
			(layer "B.Cu")
			(hatch none 0.5)
			(connect_pads
				(clearance 0)
			)
			(min_thickness 0.25)
			(keepout
				(tracks allowed)
				(vias not_allowed)
				(pads allowed)
				(copperpour not_allowed)
				(footprints allowed)
			)
			(placement
				(enabled no)
				(sheetname "")
			)
			(fill
				(thermal_gap 0.5)
				(thermal_bridge_width 0.5)
				(island_removal_mode 0)
			)
			(polygon
				(pts
					(xy 401.010628 -116.925344) (xy 400.502628 -116.925344) (xy 400.502628 -116.544344) (xy 401.010628 -116.544344)
				)
			)
		)
		(zone
			(layer "B.Cu")
			(hatch none 0.5)
			(connect_pads
				(clearance 0)
			)
			(min_thickness 0.25)
			(keepout
				(tracks not_allowed)
				(vias allowed)
				(pads allowed)
				(copperpour not_allowed)
				(footprints allowed)
			)
			(placement
				(enabled no)
				(sheetname "")
			)
			(fill
				(thermal_gap 0.5)
				(thermal_bridge_width 0.5)
				(island_removal_mode 0)
			)
			(polygon
				(pts
					(xy 401.010628 -116.544344) (xy 400.502628 -116.544344) (xy 400.502628 -116.925344) (xy 401.010628 -116.925344)
				)
			)
		)
	)
	(footprint ""
		(layer "B.Cu")
		(at 165.9001 4.445 180)
		(property "Reference" "R6U18"
			(at 0 0 0)
			(layer "B.SilkS")
			(hide yes)
			(effects
				(font
					(size 1.27 1.27)
				)
				(justify mirror)
			)
		)
		(property "Value" ""
			(at 0 0 0)
			(layer "B.Fab")
			(effects
				(font
					(size 1.27 1.27)
				)
				(justify mirror)
			)
		)
		(duplicate_pad_numbers_are_jumpers no)
		(fp_poly
			(pts
				(xy 0.2794 -0.1016) (xy -0.2794 -0.1016) (xy -0.2794 0.9906) (xy 0.2794 0.9906)
			)
			(stroke
				(width 0)
				(type default)
			)
			(fill no)
			(layer "B.CrtYd")
		)
		(fp_line
			(start 0.2794 0.9906)
			(end -0.2794 0.9906)
			(stroke
				(width 0.1)
				(type default)
			)
			(layer "B.Fab")
		)
		(fp_line
			(start 0.2794 -0.1016)
			(end 0.2794 0.9906)
			(stroke
				(width 0.1)
				(type default)
			)
			(layer "B.Fab")
		)
		(fp_line
			(start -0.2794 0.9906)
			(end -0.2794 -0.1016)
			(stroke
				(width 0.1)
				(type default)
			)
			(layer "B.Fab")
		)
		(fp_line
			(start -0.2794 -0.1016)
			(end 0.2794 -0.1016)
			(stroke
				(width 0.1)
				(type default)
			)
			(layer "B.Fab")
		)
		(pad "1" smd rect
			(at 0 0)
			(size 0.508 0.508)
			(layers "B.Cu" "B.Mask" "B.Paste")
			(net "PVPP_GHJ")
		)
		(pad "2" smd rect
			(at 0 0.889)
			(size 0.508 0.508)
			(layers "B.Cu" "B.Mask" "B.Paste")
			(net "SMB_DDR_GHJ_VPP_SDA_R")
		)
		(zone
			(layer "B.Cu")
			(hatch none 0.5)
			(connect_pads
				(clearance 0)
			)
			(min_thickness 0.25)
			(keepout
				(tracks not_allowed)
				(vias allowed)
				(pads allowed)
				(copperpour not_allowed)
				(footprints allowed)
			)
			(placement
				(enabled no)
				(sheetname "")
			)
			(fill
				(thermal_gap 0.5)
				(thermal_bridge_width 0.5)
				(island_removal_mode 0)
			)
			(polygon
				(pts
					(xy 165.6461 3.81) (xy 166.1541 3.81) (xy 166.1541 4.191) (xy 165.6461 4.191)
				)
			)
		)
		(zone
			(layer "B.Cu")
			(hatch none 0.5)
			(connect_pads
				(clearance 0)
			)
			(min_thickness 0.25)
			(keepout
				(tracks allowed)
				(vias not_allowed)
				(pads allowed)
				(copperpour not_allowed)
				(footprints allowed)
			)
			(placement
				(enabled no)
				(sheetname "")
			)
			(fill
				(thermal_gap 0.5)
				(thermal_bridge_width 0.5)
				(island_removal_mode 0)
			)
			(polygon
				(pts
					(xy 165.6461 4.191) (xy 166.1541 4.191) (xy 166.1541 3.81) (xy 165.6461 3.81)
				)
			)
		)
	)
	(footprint ""
		(layer "B.Cu")
		(at 368.709956 -121.443242 -90)
		(property "Reference" "C3M34"
			(at 0 0 90)
			(layer "B.SilkS")
			(hide yes)
			(effects
				(font
					(size 1.27 1.27)
				)
				(justify mirror)
			)
		)
		(property "Value" ""
			(at 0 0 90)
			(layer "B.Fab")
			(effects
				(font
					(size 1.27 1.27)
				)
				(justify mirror)
			)
		)
		(duplicate_pad_numbers_are_jumpers no)
		(fp_poly
			(pts
				(xy -0.3048 -0.1016) (xy -0.3048 0.9906) (xy 0.3048 0.9906) (xy 0.3048 -0.1016)
			)
			(stroke
				(width 0)
				(type default)
			)
			(fill no)
			(layer "B.CrtYd")
		)
		(fp_line
			(start -0.3048 0.9906)
			(end -0.3048 -0.1016)
			(stroke
				(width 0.1)
				(type default)
			)
			(layer "B.Fab")
		)
		(fp_line
			(start 0.3048 0.9906)
			(end -0.3048 0.9906)
			(stroke
				(width 0.1)
				(type default)
			)
			(layer "B.Fab")
		)
		(fp_line
			(start -0.3048 -0.1016)
			(end 0.3048 -0.1016)
			(stroke
				(width 0.1)
				(type default)
			)
			(layer "B.Fab")
		)
		(fp_line
			(start 0.3048 -0.1016)
			(end 0.3048 0.9906)
			(stroke
				(width 0.1)
				(type default)
			)
			(layer "B.Fab")
		)
		(pad "1" smd rect
			(at 0 0 90)
			(size 0.508 0.508)
			(layers "B.Cu" "B.Mask" "B.Paste")
			(net "P3E_CPU0_PE1_PCH_R_RXP<8>")
		)
		(pad "2" smd rect
			(at 0 0.889 90)
			(size 0.508 0.508)
			(layers "B.Cu" "B.Mask" "B.Paste")
			(net "P3E_CPU0_PE1_PCH_RXP<8>")
		)
		(zone
			(layer "B.Cu")
			(hatch none 0.5)
			(connect_pads
				(clearance 0)
			)
			(min_thickness 0.25)
			(keepout
				(tracks not_allowed)
				(vias allowed)
				(pads allowed)
				(copperpour not_allowed)
				(footprints allowed)
			)
			(placement
				(enabled no)
				(sheetname "")
			)
			(fill
				(thermal_gap 0.5)
				(thermal_bridge_width 0.5)
				(island_removal_mode 0)
			)
			(polygon
				(pts
					(xy 368.074956 -121.189242) (xy 368.074956 -121.697242) (xy 368.455956 -121.697242) (xy 368.455956 -121.189242)
				)
			)
		)
		(zone
			(layer "B.Cu")
			(hatch none 0.5)
			(connect_pads
				(clearance 0)
			)
			(min_thickness 0.25)
			(keepout
				(tracks allowed)
				(vias not_allowed)
				(pads allowed)
				(copperpour not_allowed)
				(footprints allowed)
			)
			(placement
				(enabled no)
				(sheetname "")
			)
			(fill
				(thermal_gap 0.5)
				(thermal_bridge_width 0.5)
				(island_removal_mode 0)
			)
			(polygon
				(pts
					(xy 368.455956 -121.189242) (xy 368.455956 -121.697242) (xy 368.074956 -121.697242) (xy 368.074956 -121.189242)
				)
			)
		)
	)
	(footprint ""
		(layer "B.Cu")
		(at 32.832802 -72.902064 90)
		(property "Reference" "C9P7"
			(at 0 0 90)
			(layer "B.SilkS")
			(hide yes)
			(effects
				(font
					(size 1.27 1.27)
				)
				(justify mirror)
			)
		)
		(property "Value" ""
			(at 0 0 90)
			(layer "B.Fab")
			(effects
				(font
					(size 1.27 1.27)
				)
				(justify mirror)
			)
		)
		(duplicate_pad_numbers_are_jumpers no)
		(fp_poly
			(pts
				(xy 0.7239 -0.2159) (xy -0.7239 -0.2159) (xy -0.7239 1.9939) (xy 0.7239 1.9939)
			)
			(stroke
				(width 0)
				(type default)
			)
			(fill no)
			(layer "B.CrtYd")
		)
		(fp_line
			(start 0.7239 -0.2159)
			(end 0.7239 1.9939)
			(stroke
				(width 0.1)
				(type default)
			)
			(layer "B.Fab")
		)
		(fp_line
			(start -0.7239 -0.2159)
			(end 0.7239 -0.2159)
			(stroke
				(width 0.1)
				(type default)
			)
			(layer "B.Fab")
		)
		(fp_line
			(start 0.7239 1.9939)
			(end -0.7239 1.9939)
			(stroke
				(width 0.1)
				(type default)
			)
			(layer "B.Fab")
		)
		(fp_line
			(start -0.7239 1.9939)
			(end -0.7239 -0.2159)
			(stroke
				(width 0.1)
				(type default)
			)
			(layer "B.Fab")
		)
		(pad "1" smd rect
			(at 0 0 270)
			(size 1.27 1.016)
			(layers "B.Cu" "B.Mask" "B.Paste")
			(net "VR_FET_SW_P12V_STBY_PVCCIN_CPU1")
		)
		(pad "2" smd rect
			(at 0 1.778 270)
			(size 1.27 1.016)
			(layers "B.Cu" "B.Mask" "B.Paste")
			(net "GND")
		)
		(zone
			(layer "B.Cu")
			(hatch none 0.5)
			(connect_pads
				(clearance 0)
			)
			(min_thickness 0.25)
			(keepout
				(tracks not_allowed)
				(vias allowed)
				(pads allowed)
				(copperpour not_allowed)
				(footprints allowed)
			)
			(placement
				(enabled no)
				(sheetname "")
			)
			(fill
				(thermal_gap 0.5)
				(thermal_bridge_width 0.5)
				(island_removal_mode 0)
			)
			(polygon
				(pts
					(xy 33.340802 -73.537064) (xy 33.340802 -72.267064) (xy 34.102802 -72.267064) (xy 34.102802 -73.537064)
				)
			)
		)
	)
	(footprint ""
		(layer "B.Cu")
		(at 369.5954 -5.3467 180)
		(property "Reference" "R7G28"
			(at 0 0 0)
			(layer "B.SilkS")
			(hide yes)
			(effects
				(font
					(size 1.27 1.27)
				)
				(justify mirror)
			)
		)
		(property "Value" ""
			(at 0 0 0)
			(layer "B.Fab")
			(effects
				(font
					(size 1.27 1.27)
				)
				(justify mirror)
			)
		)
		(duplicate_pad_numbers_are_jumpers no)
		(fp_poly
			(pts
				(xy 0.2794 -0.1016) (xy -0.2794 -0.1016) (xy -0.2794 0.9906) (xy 0.2794 0.9906)
			)
			(stroke
				(width 0)
				(type default)
			)
			(fill no)
			(layer "B.CrtYd")
		)
		(fp_line
			(start 0.2794 0.9906)
			(end -0.2794 0.9906)
			(stroke
				(width 0.1)
				(type default)
			)
			(layer "B.Fab")
		)
		(fp_line
			(start 0.2794 -0.1016)
			(end 0.2794 0.9906)
			(stroke
				(width 0.1)
				(type default)
			)
			(layer "B.Fab")
		)
		(fp_line
			(start -0.2794 0.9906)
			(end -0.2794 -0.1016)
			(stroke
				(width 0.1)
				(type default)
			)
			(layer "B.Fab")
		)
		(fp_line
			(start -0.2794 -0.1016)
			(end 0.2794 -0.1016)
			(stroke
				(width 0.1)
				(type default)
			)
			(layer "B.Fab")
		)
		(pad "1" smd rect
			(at 0 0)
			(size 0.508 0.508)
			(layers "B.Cu" "B.Mask" "B.Paste")
			(net "PD_ME_RCVR_N")
		)
		(pad "2" smd rect
			(at 0 0.889)
			(size 0.508 0.508)
			(layers "B.Cu" "B.Mask" "B.Paste")
			(net "GND")
		)
		(zone
			(layer "B.Cu")
			(hatch none 0.5)
			(connect_pads
				(clearance 0)
			)
			(min_thickness 0.25)
			(keepout
				(tracks not_allowed)
				(vias allowed)
				(pads allowed)
				(copperpour not_allowed)
				(footprints allowed)
			)
			(placement
				(enabled no)
				(sheetname "")
			)
			(fill
				(thermal_gap 0.5)
				(thermal_bridge_width 0.5)
				(island_removal_mode 0)
			)
			(polygon
				(pts
					(xy 369.3414 -5.9817) (xy 369.8494 -5.9817) (xy 369.8494 -5.6007) (xy 369.3414 -5.6007)
				)
			)
		)
		(zone
			(layer "B.Cu")
			(hatch none 0.5)
			(connect_pads
				(clearance 0)
			)
			(min_thickness 0.25)
			(keepout
				(tracks allowed)
				(vias not_allowed)
				(pads allowed)
				(copperpour not_allowed)
				(footprints allowed)
			)
			(placement
				(enabled no)
				(sheetname "")
			)
			(fill
				(thermal_gap 0.5)
				(thermal_bridge_width 0.5)
				(island_removal_mode 0)
			)
			(polygon
				(pts
					(xy 369.3414 -5.6007) (xy 369.8494 -5.6007) (xy 369.8494 -5.9817) (xy 369.3414 -5.9817)
				)
			)
		)
	)
	(footprint ""
		(layer "B.Cu")
		(at 393.03325 -110.0328 -90)
		(property "Reference" "C2N8"
			(at 0 0 90)
			(layer "B.SilkS")
			(hide yes)
			(effects
				(font
					(size 1.27 1.27)
				)
				(justify mirror)
			)
		)
		(property "Value" ""
			(at 0 0 90)
			(layer "B.Fab")
			(effects
				(font
					(size 1.27 1.27)
				)
				(justify mirror)
			)
		)
		(duplicate_pad_numbers_are_jumpers no)
		(fp_rect
			(start 0.2794 0.9144)
			(end -0.2794 -0.1143)
			(stroke
				(width 0)
				(type default)
			)
			(fill no)
			(layer "B.CrtYd")
		)
		(fp_line
			(start -0.2794 0.9144)
			(end 0.2794 0.9144)
			(stroke
				(width 0.1)
				(type default)
			)
			(layer "B.Fab")
		)
		(fp_line
			(start 0.2794 0.9144)
			(end 0.2794 -0.1143)
			(stroke
				(width 0.1)
				(type default)
			)
			(layer "B.Fab")
		)
		(fp_line
			(start -0.2794 -0.1143)
			(end -0.2794 0.9144)
			(stroke
				(width 0.1)
				(type default)
			)
			(layer "B.Fab")
		)
		(fp_line
			(start 0.2794 -0.1143)
			(end -0.2794 -0.1143)
			(stroke
				(width 0.1)
				(type default)
			)
			(layer "B.Fab")
		)
		(pad "1" smd custom
			(at 0 0 180)
			(size 0.10414 0.10414)
			(layers "B.Cu" "B.Mask" "B.Paste")
			(net "P1V05_PCH_STBY")
			(options
				(clearance outline)
				(anchor circle)
			)
			(primitives
				(gr_poly
					(pts
						(xy -0.20828 -0.08636) (xy -0.20828 0.08636) (xy -0.08636 0.20828) (xy 0.086614 0.20828) (xy 0.20828 0.086614)
						(xy 0.20828 -0.08636) (xy 0.08636 -0.20828) (xy -0.08636 -0.20828)
					)
					(width 0)
					(fill yes)
				)
			)
		)
		(pad "2" smd custom
			(at 0 0.8001 180)
			(size 0.10414 0.10414)
			(layers "B.Cu" "B.Mask" "B.Paste")
			(net "GND")
			(options
				(clearance outline)
				(anchor circle)
			)
			(primitives
				(gr_poly
					(pts
						(xy -0.20828 -0.08636) (xy -0.20828 0.08636) (xy -0.08636 0.20828) (xy 0.086614 0.20828) (xy 0.20828 0.086614)
						(xy 0.20828 -0.08636) (xy 0.08636 -0.20828) (xy -0.08636 -0.20828)
					)
					(width 0)
					(fill yes)
				)
			)
		)
		(zone
			(layer "B.Cu")
			(hatch none 0.5)
			(connect_pads
				(clearance 0)
			)
			(min_thickness 0.25)
			(keepout
				(tracks not_allowed)
				(vias allowed)
				(pads allowed)
				(copperpour not_allowed)
				(footprints allowed)
			)
			(placement
				(enabled no)
				(sheetname "")
			)
			(fill
				(thermal_gap 0.5)
				(thermal_bridge_width 0.5)
				(island_removal_mode 0)
			)
			(polygon
				(pts
					(xy 392.8237 -109.94517) (xy 392.4427 -109.94517) (xy 392.4427 -110.12043) (xy 392.8237 -110.120684)
				)
			)
		)
		(zone
			(layer "B.Cu")
			(hatch none 0.5)
			(connect_pads
				(clearance 0)
			)
			(min_thickness 0.25)
			(keepout
				(tracks allowed)
				(vias not_allowed)
				(pads allowed)
				(copperpour not_allowed)
				(footprints allowed)
			)
			(placement
				(enabled no)
				(sheetname "")
			)
			(fill
				(thermal_gap 0.5)
				(thermal_bridge_width 0.5)
				(island_removal_mode 0)
			)
			(polygon
				(pts
					(xy 392.8237 -109.94517) (xy 392.4427 -109.94517) (xy 392.4427 -110.12043) (xy 392.8237 -110.120684)
				)
			)
		)
	)
	(footprint ""
		(layer "B.Cu")
		(at 373.9642 -155.432506)
		(property "Reference" "R3L1"
			(at 0 0 0)
			(layer "B.SilkS")
			(hide yes)
			(effects
				(font
					(size 1.27 1.27)
				)
				(justify mirror)
			)
		)
		(property "Value" ""
			(at 0 0 0)
			(layer "B.Fab")
			(effects
				(font
					(size 1.27 1.27)
				)
				(justify mirror)
			)
		)
		(duplicate_pad_numbers_are_jumpers no)
		(fp_poly
			(pts
				(xy 0.2794 -0.1016) (xy -0.2794 -0.1016) (xy -0.2794 0.9906) (xy 0.2794 0.9906)
			)
			(stroke
				(width 0)
				(type default)
			)
			(fill no)
			(layer "B.CrtYd")
		)
		(fp_line
			(start -0.2794 -0.1016)
			(end 0.2794 -0.1016)
			(stroke
				(width 0.1)
				(type default)
			)
			(layer "B.Fab")
		)
		(fp_line
			(start -0.2794 0.9906)
			(end -0.2794 -0.1016)
			(stroke
				(width 0.1)
				(type default)
			)
			(layer "B.Fab")
		)
		(fp_line
			(start 0.2794 -0.1016)
			(end 0.2794 0.9906)
			(stroke
				(width 0.1)
				(type default)
			)
			(layer "B.Fab")
		)
		(fp_line
			(start 0.2794 0.9906)
			(end -0.2794 0.9906)
			(stroke
				(width 0.1)
				(type default)
			)
			(layer "B.Fab")
		)
		(pad "1" smd rect
			(at 0 0 180)
			(size 0.508 0.508)
			(layers "B.Cu" "B.Mask" "B.Paste")
			(net "VR_PVNN_PCH_PH1_VCIN")
		)
		(pad "2" smd rect
			(at 0 0.889 180)
			(size 0.508 0.508)
			(layers "B.Cu" "B.Mask" "B.Paste")
			(net "P5V_STBY")
		)
		(zone
			(layer "B.Cu")
			(hatch none 0.5)
			(connect_pads
				(clearance 0)
			)
			(min_thickness 0.25)
			(keepout
				(tracks allowed)
				(vias not_allowed)
				(pads allowed)
				(copperpour not_allowed)
				(footprints allowed)
			)
			(placement
				(enabled no)
				(sheetname "")
			)
			(fill
				(thermal_gap 0.5)
				(thermal_bridge_width 0.5)
				(island_removal_mode 0)
			)
			(polygon
				(pts
					(xy 374.2182 -155.178506) (xy 373.7102 -155.178506) (xy 373.7102 -154.797506) (xy 374.2182 -154.797506)
				)
			)
		)
		(zone
			(layer "B.Cu")
			(hatch none 0.5)
			(connect_pads
				(clearance 0)
			)
			(min_thickness 0.25)
			(keepout
				(tracks not_allowed)
				(vias allowed)
				(pads allowed)
				(copperpour not_allowed)
				(footprints allowed)
			)
			(placement
				(enabled no)
				(sheetname "")
			)
			(fill
				(thermal_gap 0.5)
				(thermal_bridge_width 0.5)
				(island_removal_mode 0)
			)
			(polygon
				(pts
					(xy 374.2182 -154.797506) (xy 373.7102 -154.797506) (xy 373.7102 -155.178506) (xy 374.2182 -155.178506)
				)
			)
		)
	)
	(footprint ""
		(layer "B.Cu")
		(at 60.28182 -103.87584)
		(property "Reference" ""
			(at 0 0 0)
			(layer "B.SilkS")
			(hide yes)
			(effects
				(font
					(size 1.27 1.27)
				)
				(justify mirror)
			)
		)
		(property "Value" ""
			(at 0 0 0)
			(layer "B.Fab")
			(effects
				(font
					(size 1.27 1.27)
				)
				(justify mirror)
			)
		)
		(duplicate_pad_numbers_are_jumpers no)
		(fp_poly
			(pts
				(arc
					(start 2.032 0)
					(mid -2.032 0)
					(end 2.032 0)
				)
			)
			(stroke
				(width 0)
				(type default)
			)
			(fill no)
			(layer "B.CrtYd")
		)
		(pad "1" smd circle
			(at 0 0 180)
			(size 1.016 1.016)
			(layers "B.Cu" "B.Mask" "B.Paste")
			(net "Net_387")
		)
		(zone
			(layers "F.Cu" "B.Cu" "In1.Cu" "In2.Cu" "In3.Cu" "In4.Cu" "In5.Cu" "In6.Cu"
				"In7.Cu" "In8.Cu" "In9.Cu" "In10.Cu" "In11.Cu" "In12.Cu"
			)
			(hatch none 0.5)
			(connect_pads
				(clearance 0)
			)
			(min_thickness 0.25)
			(keepout
				(tracks allowed)
				(vias not_allowed)
				(pads allowed)
				(copperpour not_allowed)
				(footprints allowed)
			)
			(placement
				(enabled no)
				(sheetname "")
			)
			(fill
				(thermal_gap 0.5)
				(thermal_bridge_width 0.5)
				(island_removal_mode 0)
			)
			(polygon
				(pts
					(arc
						(start 61.80582 -103.87584)
						(mid 58.75782 -103.87584)
						(end 61.80582 -103.87584)
					)
				)
			)
		)
		(zone
			(layer "B.Cu")
			(hatch none 0.5)
			(connect_pads
				(clearance 0)
			)
			(min_thickness 0.25)
			(keepout
				(tracks not_allowed)
				(vias allowed)
				(pads allowed)
				(copperpour not_allowed)
				(footprints allowed)
			)
			(placement
				(enabled no)
				(sheetname "")
			)
			(fill
				(thermal_gap 0.5)
				(thermal_bridge_width 0.5)
				(island_removal_mode 0)
			)
			(polygon
				(pts
					(arc
						(start 61.80582 -103.87584)
						(mid 58.75782 -103.87584)
						(end 61.80582 -103.87584)
					)
				)
			)
		)
	)
	(footprint ""
		(layer "B.Cu")
		(at 128.8796 -66.292984 180)
		(property "Reference" "R7P27"
			(at 0 0 0)
			(layer "B.SilkS")
			(hide yes)
			(effects
				(font
					(size 1.27 1.27)
				)
				(justify mirror)
			)
		)
		(property "Value" ""
			(at 0 0 0)
			(layer "B.Fab")
			(effects
				(font
					(size 1.27 1.27)
				)
				(justify mirror)
			)
		)
		(duplicate_pad_numbers_are_jumpers no)
		(fp_poly
			(pts
				(xy 0.2794 -0.1016) (xy -0.2794 -0.1016) (xy -0.2794 0.9906) (xy 0.2794 0.9906)
			)
			(stroke
				(width 0)
				(type default)
			)
			(fill no)
			(layer "B.CrtYd")
		)
		(fp_line
			(start 0.2794 0.9906)
			(end -0.2794 0.9906)
			(stroke
				(width 0.1)
				(type default)
			)
			(layer "B.Fab")
		)
		(fp_line
			(start 0.2794 -0.1016)
			(end 0.2794 0.9906)
			(stroke
				(width 0.1)
				(type default)
			)
			(layer "B.Fab")
		)
		(fp_line
			(start -0.2794 0.9906)
			(end -0.2794 -0.1016)
			(stroke
				(width 0.1)
				(type default)
			)
			(layer "B.Fab")
		)
		(fp_line
			(start -0.2794 -0.1016)
			(end 0.2794 -0.1016)
			(stroke
				(width 0.1)
				(type default)
			)
			(layer "B.Fab")
		)
		(pad "1" smd rect
			(at 0 0)
			(size 0.508 0.508)
			(layers "B.Cu" "B.Mask" "B.Paste")
			(net "PVCCIO_CPU0")
		)
		(pad "2" smd rect
			(at 0 0.889)
			(size 0.508 0.508)
			(layers "B.Cu" "B.Mask" "B.Paste")
			(net "H_CPU1_MSMI_G_N")
		)
		(zone
			(layer "B.Cu")
			(hatch none 0.5)
			(connect_pads
				(clearance 0)
			)
			(min_thickness 0.25)
			(keepout
				(tracks not_allowed)
				(vias allowed)
				(pads allowed)
				(copperpour not_allowed)
				(footprints allowed)
			)
			(placement
				(enabled no)
				(sheetname "")
			)
			(fill
				(thermal_gap 0.5)
				(thermal_bridge_width 0.5)
				(island_removal_mode 0)
			)
			(polygon
				(pts
					(xy 128.6256 -66.927984) (xy 129.1336 -66.927984) (xy 129.1336 -66.546984) (xy 128.6256 -66.546984)
				)
			)
		)
		(zone
			(layer "B.Cu")
			(hatch none 0.5)
			(connect_pads
				(clearance 0)
			)
			(min_thickness 0.25)
			(keepout
				(tracks allowed)
				(vias not_allowed)
				(pads allowed)
				(copperpour not_allowed)
				(footprints allowed)
			)
			(placement
				(enabled no)
				(sheetname "")
			)
			(fill
				(thermal_gap 0.5)
				(thermal_bridge_width 0.5)
				(island_removal_mode 0)
			)
			(polygon
				(pts
					(xy 128.6256 -66.546984) (xy 129.1336 -66.546984) (xy 129.1336 -66.927984) (xy 128.6256 -66.927984)
				)
			)
		)
	)
	(footprint ""
		(layer "B.Cu")
		(at 282.259024 -78.039214 -90)
		(property "Reference" "R4P3"
			(at 0 0 90)
			(layer "B.SilkS")
			(hide yes)
			(effects
				(font
					(size 1.27 1.27)
				)
				(justify mirror)
			)
		)
		(property "Value" ""
			(at 0 0 90)
			(layer "B.Fab")
			(effects
				(font
					(size 1.27 1.27)
				)
				(justify mirror)
			)
		)
		(duplicate_pad_numbers_are_jumpers no)
		(fp_rect
			(start 0.2794 0.9906)
			(end -0.2794 -0.1016)
			(stroke
				(width 0)
				(type default)
			)
			(fill no)
			(layer "B.CrtYd")
		)
		(fp_line
			(start -0.2794 0.9906)
			(end -0.2794 -0.1016)
			(stroke
				(width 0.1)
				(type default)
			)
			(layer "B.Fab")
		)
		(fp_line
			(start 0.2794 0.9906)
			(end -0.2794 0.9906)
			(stroke
				(width 0.1)
				(type default)
			)
			(layer "B.Fab")
		)
		(fp_line
			(start -0.2794 -0.1016)
			(end 0.2794 -0.1016)
			(stroke
				(width 0.1)
				(type default)
			)
			(layer "B.Fab")
		)
		(fp_line
			(start 0.2794 -0.1016)
			(end 0.2794 0.9906)
			(stroke
				(width 0.1)
				(type default)
			)
			(layer "B.Fab")
		)
		(pad "1" smd rect
			(at 0 0 90)
			(size 0.508 0.508)
			(layers "B.Cu" "B.Mask" "B.Paste")
			(net "A_CPU0_PE012_RBIAS")
		)
		(pad "2" smd rect
			(at 0 0.889 90)
			(size 0.508 0.508)
			(layers "B.Cu" "B.Mask" "B.Paste")
			(net "GND")
		)
		(zone
			(layer "B.Cu")
			(hatch none 0.5)
			(connect_pads
				(clearance 0)
			)
			(min_thickness 0.25)
			(keepout
				(tracks allowed)
				(vias not_allowed)
				(pads allowed)
				(copperpour not_allowed)
				(footprints allowed)
			)
			(placement
				(enabled no)
				(sheetname "")
			)
			(fill
				(thermal_gap 0.5)
				(thermal_bridge_width 0.5)
				(island_removal_mode 0)
			)
			(polygon
				(pts
					(xy 281.624024 -77.785214) (xy 282.005024 -77.785214) (xy 282.005024 -78.293214) (xy 281.624024 -78.293214)
				)
			)
		)
		(zone
			(layer "B.Cu")
			(hatch none 0.5)
			(connect_pads
				(clearance 0)
			)
			(min_thickness 0.25)
			(keepout
				(tracks not_allowed)
				(vias allowed)
				(pads allowed)
				(copperpour not_allowed)
				(footprints allowed)
			)
			(placement
				(enabled no)
				(sheetname "")
			)
			(fill
				(thermal_gap 0.5)
				(thermal_bridge_width 0.5)
				(island_removal_mode 0)
			)
			(polygon
				(pts
					(xy 281.624024 -77.785214) (xy 282.005024 -77.785214) (xy 282.005024 -78.293214) (xy 281.624024 -78.293214)
				)
			)
		)
	)
	(footprint ""
		(layer "B.Cu")
		(at 345.832176 -77.694536)
		(property "Reference" "C3P21"
			(at 0 0 0)
			(layer "B.SilkS")
			(hide yes)
			(effects
				(font
					(size 1.27 1.27)
				)
				(justify mirror)
			)
		)
		(property "Value" ""
			(at 0 0 0)
			(layer "B.Fab")
			(effects
				(font
					(size 1.27 1.27)
				)
				(justify mirror)
			)
		)
		(duplicate_pad_numbers_are_jumpers no)
		(fp_poly
			(pts
				(xy -0.3048 -0.1016) (xy -0.3048 0.9906) (xy 0.3048 0.9906) (xy 0.3048 -0.1016)
			)
			(stroke
				(width 0)
				(type default)
			)
			(fill no)
			(layer "B.CrtYd")
		)
		(fp_line
			(start -0.3048 -0.1016)
			(end 0.3048 -0.1016)
			(stroke
				(width 0.1)
				(type default)
			)
			(layer "B.Fab")
		)
		(fp_line
			(start -0.3048 0.9906)
			(end -0.3048 -0.1016)
			(stroke
				(width 0.1)
				(type default)
			)
			(layer "B.Fab")
		)
		(fp_line
			(start 0.3048 -0.1016)
			(end 0.3048 0.9906)
			(stroke
				(width 0.1)
				(type default)
			)
			(layer "B.Fab")
		)
		(fp_line
			(start 0.3048 0.9906)
			(end -0.3048 0.9906)
			(stroke
				(width 0.1)
				(type default)
			)
			(layer "B.Fab")
		)
		(pad "1" smd rect
			(at 0 0 180)
			(size 0.508 0.508)
			(layers "B.Cu" "B.Mask" "B.Paste")
			(net "P3E_CPU0_PE1_SS_TXN<2>")
		)
		(pad "2" smd rect
			(at 0 0.889 180)
			(size 0.508 0.508)
			(layers "B.Cu" "B.Mask" "B.Paste")
			(net "P3E_CPU0_PE1_SS_C_TXN<2>")
		)
		(zone
			(layer "B.Cu")
			(hatch none 0.5)
			(connect_pads
				(clearance 0)
			)
			(min_thickness 0.25)
			(keepout
				(tracks allowed)
				(vias not_allowed)
				(pads allowed)
				(copperpour not_allowed)
				(footprints allowed)
			)
			(placement
				(enabled no)
				(sheetname "")
			)
			(fill
				(thermal_gap 0.5)
				(thermal_bridge_width 0.5)
				(island_removal_mode 0)
			)
			(polygon
				(pts
					(xy 346.086176 -77.440536) (xy 345.578176 -77.440536) (xy 345.578176 -77.059536) (xy 346.086176 -77.059536)
				)
			)
		)
	)
	(footprint ""
		(layer "B.Cu")
		(at 244.5004 -27.813 -90)
		(property "Reference" "C5T1"
			(at 0 0 90)
			(layer "B.SilkS")
			(hide yes)
			(effects
				(font
					(size 1.27 1.27)
				)
				(justify mirror)
			)
		)
		(property "Value" ""
			(at 0 0 90)
			(layer "B.Fab")
			(effects
				(font
					(size 1.27 1.27)
				)
				(justify mirror)
			)
		)
		(duplicate_pad_numbers_are_jumpers no)
		(fp_rect
			(start 0.500126 1.598422)
			(end -0.500126 -0.201422)
			(stroke
				(width 0)
				(type default)
			)
			(fill no)
			(layer "B.CrtYd")
		)
		(fp_line
			(start -0.500126 1.598422)
			(end 0.500126 1.598422)
			(stroke
				(width 0.1)
				(type default)
			)
			(layer "B.Fab")
		)
		(fp_line
			(start 0.500126 1.598422)
			(end 0.500126 -0.201422)
			(stroke
				(width 0.1)
				(type default)
			)
			(layer "B.Fab")
		)
		(fp_line
			(start -0.500126 -0.201422)
			(end -0.500126 1.598422)
			(stroke
				(width 0.1)
				(type default)
			)
			(layer "B.Fab")
		)
		(fp_line
			(start 0.500126 -0.201422)
			(end -0.500126 -0.201422)
			(stroke
				(width 0.1)
				(type default)
			)
			(layer "B.Fab")
		)
		(pad "1" smd rect
			(at 0 0 180)
			(size 0.889 0.9906)
			(layers "B.Cu" "B.Mask" "B.Paste")
			(net "PVDDQ_ABC")
		)
		(pad "2" smd rect
			(at 0 1.397 180)
			(size 0.889 0.9906)
			(layers "B.Cu" "B.Mask" "B.Paste")
			(net "GND")
		)
		(zone
			(layer "B.Cu")
			(hatch none 0.5)
			(connect_pads
				(clearance 0)
			)
			(min_thickness 0.25)
			(keepout
				(tracks not_allowed)
				(vias allowed)
				(pads allowed)
				(copperpour not_allowed)
				(footprints allowed)
			)
			(placement
				(enabled no)
				(sheetname "")
			)
			(fill
				(thermal_gap 0.5)
				(thermal_bridge_width 0.5)
				(island_removal_mode 0)
			)
			(polygon
				(pts
					(xy 243.5479 -27.3177) (xy 244.0559 -27.3177) (xy 244.0559 -28.3083) (xy 243.5479 -28.3083)
				)
			)
		)
		(zone
			(layer "B.Cu")
			(hatch none 0.5)
			(connect_pads
				(clearance 0)
			)
			(min_thickness 0.25)
			(keepout
				(tracks allowed)
				(vias not_allowed)
				(pads allowed)
				(copperpour not_allowed)
				(footprints allowed)
			)
			(placement
				(enabled no)
				(sheetname "")
			)
			(fill
				(thermal_gap 0.5)
				(thermal_bridge_width 0.5)
				(island_removal_mode 0)
			)
			(polygon
				(pts
					(xy 243.5479 -27.3177) (xy 244.0559 -27.3177) (xy 244.0559 -28.3083) (xy 243.5479 -28.3083)
				)
			)
		)
	)
	(footprint ""
		(layer "B.Cu")
		(at 189.992 -54.229 90)
		(property "Reference" "C22W17"
			(at 0 0 90)
			(layer "B.SilkS")
			(hide yes)
			(effects
				(font
					(size 1.27 1.27)
				)
				(justify mirror)
			)
		)
		(property "Value" "*"
			(at 0.0762 -6.2357 90)
			(unlocked yes)
			(layer "B.Fab")
			(hide yes)
			(effects
				(font
					(size 1.27 1.016)
					(thickness 0.1524)
				)
				(justify mirror)
			)
		)
		(property "Device Type" "SC22U16V5MX-4-GP_SMD-BCG5-SC22A"
			(at 0.0762 -8.2677 90)
			(unlocked yes)
			(layer "B.Fab")
			(hide yes)
			(effects
				(font
					(size 1.27 1.016)
					(thickness 0.1524)
				)
				(justify mirror)
			)
		)
		(duplicate_pad_numbers_are_jumpers no)
		(fp_line
			(start -0.635 0)
			(end 0.635 0)
			(stroke
				(width 0.508)
				(type default)
			)
			(layer "B.SilkS")
		)
		(fp_rect
			(start 0.9652 1.778)
			(end -0.9652 -1.778)
			(stroke
				(width 0)
				(type default)
			)
			(fill no)
			(layer "B.CrtYd")
		)
		(fp_poly
			(pts
				(xy 0.9652 -1.778) (xy -0.9652 -1.778) (xy -0.9652 1.778) (xy 0.9652 1.778)
			)
			(stroke
				(width 0)
				(type default)
			)
			(fill no)
			(layer "B.Fab")
		)
		(pad "1" smd rect
			(at 0 -0.9652 270)
			(size 1.397 1.143)
			(layers "B.Cu" "B.Mask" "B.Paste")
			(net "VR_FET_SW_P12V_STBY_PVCCIN_CPU0")
		)
		(pad "2" smd rect
			(at 0 0.9652 270)
			(size 1.397 1.143)
			(layers "B.Cu" "B.Mask" "B.Paste")
			(net "GND")
		)
	)
	(footprint ""
		(layer "B.Cu")
		(at 267.552424 -85.075014)
		(property "Reference" "C5P1"
			(at 0 0 0)
			(layer "B.SilkS")
			(hide yes)
			(effects
				(font
					(size 1.27 1.27)
				)
				(justify mirror)
			)
		)
		(property "Value" ""
			(at 0 0 0)
			(layer "B.Fab")
			(effects
				(font
					(size 1.27 1.27)
				)
				(justify mirror)
			)
		)
		(duplicate_pad_numbers_are_jumpers no)
		(fp_poly
			(pts
				(xy 0.7239 -0.2159) (xy -0.7239 -0.2159) (xy -0.7239 1.9939) (xy 0.7239 1.9939)
			)
			(stroke
				(width 0)
				(type default)
			)
			(fill no)
			(layer "B.CrtYd")
		)
		(fp_line
			(start -0.7239 -0.2159)
			(end 0.7239 -0.2159)
			(stroke
				(width 0.1)
				(type default)
			)
			(layer "B.Fab")
		)
		(fp_line
			(start -0.7239 1.9939)
			(end -0.7239 -0.2159)
			(stroke
				(width 0.1)
				(type default)
			)
			(layer "B.Fab")
		)
		(fp_line
			(start 0.7239 -0.2159)
			(end 0.7239 1.9939)
			(stroke
				(width 0.1)
				(type default)
			)
			(layer "B.Fab")
		)
		(fp_line
			(start 0.7239 1.9939)
			(end -0.7239 1.9939)
			(stroke
				(width 0.1)
				(type default)
			)
			(layer "B.Fab")
		)
		(pad "1" smd rect
			(at 0 0 180)
			(size 1.27 1.016)
			(layers "B.Cu" "B.Mask" "B.Paste")
			(net "PVDDQ_DEF")
		)
		(pad "2" smd rect
			(at 0 1.778 180)
			(size 1.27 1.016)
			(layers "B.Cu" "B.Mask" "B.Paste")
			(net "GND")
		)
		(zone
			(layer "B.Cu")
			(hatch none 0.5)
			(connect_pads
				(clearance 0)
			)
			(min_thickness 0.25)
			(keepout
				(tracks not_allowed)
				(vias allowed)
				(pads allowed)
				(copperpour not_allowed)
				(footprints allowed)
			)
			(placement
				(enabled no)
				(sheetname "")
			)
			(fill
				(thermal_gap 0.5)
				(thermal_bridge_width 0.5)
				(island_removal_mode 0)
			)
			(polygon
				(pts
					(xy 268.187424 -84.567014) (xy 266.917424 -84.567014) (xy 266.917424 -83.805014) (xy 268.187424 -83.805014)
				)
			)
		)
	)
	(footprint ""
		(layer "B.Cu")
		(at 481.203 -114.554 90)
		(property "Reference" "C1M21"
			(at 0 0 90)
			(layer "B.SilkS")
			(hide yes)
			(effects
				(font
					(size 1.27 1.27)
				)
				(justify mirror)
			)
		)
		(property "Value" ""
			(at 0 0 90)
			(layer "B.Fab")
			(effects
				(font
					(size 1.27 1.27)
				)
				(justify mirror)
			)
		)
		(duplicate_pad_numbers_are_jumpers no)
		(fp_rect
			(start 0.3048 -0.1016)
			(end -0.3048 0.9906)
			(stroke
				(width 0)
				(type default)
			)
			(fill no)
			(layer "B.CrtYd")
		)
		(fp_line
			(start 0.3048 -0.1016)
			(end 0.3048 0.9906)
			(stroke
				(width 0.1)
				(type default)
			)
			(layer "B.Fab")
		)
		(fp_line
			(start -0.3048 -0.1016)
			(end 0.3048 -0.1016)
			(stroke
				(width 0.1)
				(type default)
			)
			(layer "B.Fab")
		)
		(fp_line
			(start 0.3048 0.9906)
			(end -0.3048 0.9906)
			(stroke
				(width 0.1)
				(type default)
			)
			(layer "B.Fab")
		)
		(fp_line
			(start -0.3048 0.9906)
			(end -0.3048 -0.1016)
			(stroke
				(width 0.1)
				(type default)
			)
			(layer "B.Fab")
		)
		(pad "1" smd rect
			(at 0 0 270)
			(size 0.508 0.508)
			(layers "B.Cu" "B.Mask" "B.Paste")
			(net "P3V3")
		)
		(pad "2" smd rect
			(at 0 0.889 270)
			(size 0.508 0.508)
			(layers "B.Cu" "B.Mask" "B.Paste")
			(net "GND")
		)
		(zone
			(layer "B.Cu")
			(hatch none 0.5)
			(connect_pads
				(clearance 0)
			)
			(min_thickness 0.25)
			(keepout
				(tracks allowed)
				(vias not_allowed)
				(pads allowed)
				(copperpour not_allowed)
				(footprints allowed)
			)
			(placement
				(enabled no)
				(sheetname "")
			)
			(fill
				(thermal_gap 0.5)
				(thermal_bridge_width 0.5)
				(island_removal_mode 0)
			)
			(polygon
				(pts
					(xy 481.457 -114.808) (xy 481.457 -114.3) (xy 481.838 -114.3) (xy 481.838 -114.808)
				)
			)
		)
		(zone
			(layer "B.Cu")
			(hatch none 0.5)
			(connect_pads
				(clearance 0)
			)
			(min_thickness 0.25)
			(keepout
				(tracks not_allowed)
				(vias allowed)
				(pads allowed)
				(copperpour not_allowed)
				(footprints allowed)
			)
			(placement
				(enabled no)
				(sheetname "")
			)
			(fill
				(thermal_gap 0.5)
				(thermal_bridge_width 0.5)
				(island_removal_mode 0)
			)
			(polygon
				(pts
					(xy 481.457 -114.808) (xy 481.457 -114.3) (xy 481.838 -114.3) (xy 481.838 -114.808)
				)
			)
		)
	)
	(footprint ""
		(layer "B.Cu")
		(at 410.464 -149.06752 90)
		(property "Reference" "C2L20"
			(at 0 0 90)
			(layer "B.SilkS")
			(hide yes)
			(effects
				(font
					(size 1.27 1.27)
				)
				(justify mirror)
			)
		)
		(property "Value" ""
			(at 0 0 90)
			(layer "B.Fab")
			(effects
				(font
					(size 1.27 1.27)
				)
				(justify mirror)
			)
		)
		(duplicate_pad_numbers_are_jumpers no)
		(fp_poly
			(pts
				(xy -0.3048 -0.1016) (xy -0.3048 0.9906) (xy 0.3048 0.9906) (xy 0.3048 -0.1016)
			)
			(stroke
				(width 0)
				(type default)
			)
			(fill no)
			(layer "B.CrtYd")
		)
		(fp_line
			(start 0.3048 -0.1016)
			(end 0.3048 0.9906)
			(stroke
				(width 0.1)
				(type default)
			)
			(layer "B.Fab")
		)
		(fp_line
			(start -0.3048 -0.1016)
			(end 0.3048 -0.1016)
			(stroke
				(width 0.1)
				(type default)
			)
			(layer "B.Fab")
		)
		(fp_line
			(start 0.3048 0.9906)
			(end -0.3048 0.9906)
			(stroke
				(width 0.1)
				(type default)
			)
			(layer "B.Fab")
		)
		(fp_line
			(start -0.3048 0.9906)
			(end -0.3048 -0.1016)
			(stroke
				(width 0.1)
				(type default)
			)
			(layer "B.Fab")
		)
		(pad "1" smd rect
			(at 0 0 270)
			(size 0.508 0.508)
			(layers "B.Cu" "B.Mask" "B.Paste")
			(net "SATA6G_PCH_PCIE_UP_SATA_RXP<4>")
		)
		(pad "2" smd rect
			(at 0 0.889 270)
			(size 0.508 0.508)
			(layers "B.Cu" "B.Mask" "B.Paste")
			(net "SATA6G_P4_RX_C_DP")
		)
		(zone
			(layer "B.Cu")
			(hatch none 0.5)
			(connect_pads
				(clearance 0)
			)
			(min_thickness 0.25)
			(keepout
				(tracks allowed)
				(vias not_allowed)
				(pads allowed)
				(copperpour not_allowed)
				(footprints allowed)
			)
			(placement
				(enabled no)
				(sheetname "")
			)
			(fill
				(thermal_gap 0.5)
				(thermal_bridge_width 0.5)
				(island_removal_mode 0)
			)
			(polygon
				(pts
					(xy 410.718 -149.32152) (xy 410.718 -148.81352) (xy 411.099 -148.81352) (xy 411.099 -149.32152)
				)
			)
		)
		(zone
			(layer "B.Cu")
			(hatch none 0.5)
			(connect_pads
				(clearance 0)
			)
			(min_thickness 0.25)
			(keepout
				(tracks not_allowed)
				(vias allowed)
				(pads allowed)
				(copperpour not_allowed)
				(footprints allowed)
			)
			(placement
				(enabled no)
				(sheetname "")
			)
			(fill
				(thermal_gap 0.5)
				(thermal_bridge_width 0.5)
				(island_removal_mode 0)
			)
			(polygon
				(pts
					(xy 411.099 -149.32152) (xy 411.099 -148.81352) (xy 410.718 -148.81352) (xy 410.718 -149.32152)
				)
			)
		)
	)
	(footprint ""
		(layer "B.Cu")
		(at 409.884118 -92.860114 180)
		(property "Reference" "Q3U1"
			(at -2.737104 -0.459232 90)
			(unlocked yes)
			(layer "B.SilkS")
			(effects
				(font
					(size 0.7874 0.5842)
					(thickness 0.1524)
				)
				(justify left mirror)
			)
		)
		(property "Value" ""
			(at 0 0 0)
			(layer "B.Fab")
			(effects
				(font
					(size 1.27 1.27)
				)
				(justify mirror)
			)
		)
		(duplicate_pad_numbers_are_jumpers no)
		(fp_circle
			(center 0.508 -0.7874)
			(end 0.381 -0.7874)
			(stroke
				(width 0.254)
				(type default)
			)
			(fill no)
			(layer "B.SilkS")
		)
		(fp_poly
			(pts
				(xy -0.2159 1.7526) (xy -1.5621 1.7526) (xy -1.5621 -0.4572) (xy -0.2159 -0.4572)
			)
			(stroke
				(width 0)
				(type default)
			)
			(fill no)
			(layer "B.CrtYd")
		)
		(fp_line
			(start -0.2159 1.75514)
			(end -1.5621 1.75514)
			(stroke
				(width 0.1)
				(type default)
			)
			(layer "B.Fab")
		)
		(fp_line
			(start -0.2159 -0.45466)
			(end -0.2159 1.75514)
			(stroke
				(width 0.1)
				(type default)
			)
			(layer "B.Fab")
		)
		(fp_line
			(start -1.5621 1.75514)
			(end -1.5621 -0.45466)
			(stroke
				(width 0.1)
				(type default)
			)
			(layer "B.Fab")
		)
		(fp_line
			(start -1.5621 -0.45466)
			(end -0.2159 -0.45466)
			(stroke
				(width 0.1)
				(type default)
			)
			(layer "B.Fab")
		)
		(fp_circle
			(center 0.508 -0.7874)
			(end 0.381 -0.7874)
			(stroke
				(width 0.254)
				(type default)
			)
			(fill no)
			(layer "B.Fab")
		)
		(pad "1" smd rect
			(at 0 0)
			(size 1.016 0.381)
			(layers "B.Cu" "B.Mask" "B.Paste")
			(net "GND")
		)
		(pad "2" smd rect
			(at 0 0.65024)
			(size 1.016 0.381)
			(layers "B.Cu" "B.Mask" "B.Paste")
			(net "IRQ_PVDDQ_ABC_VRHOT_LVT3_N")
		)
		(pad "3" smd rect
			(at 0 1.30048)
			(size 1.016 0.381)
			(layers "B.Cu" "B.Mask" "B.Paste")
			(net "H_CPU0_MEMABC_MEMHOT_G_N")
		)
		(pad "4" smd rect
			(at -1.778 1.30048)
			(size 1.016 0.381)
			(layers "B.Cu" "B.Mask" "B.Paste")
			(net "GND")
		)
		(pad "5" smd rect
			(at -1.778 0.65024)
			(size 1.016 0.381)
			(layers "B.Cu" "B.Mask" "B.Paste")
			(net "H_CPU0_MEMABC_MEMHOT")
		)
		(pad "6" smd rect
			(at -1.778 0)
			(size 1.016 0.381)
			(layers "B.Cu" "B.Mask" "B.Paste")
			(net "H_CPU0_MEMABC_MEMHOT")
		)
		(zone
			(layer "B.Cu")
			(hatch none 0.5)
			(connect_pads
				(clearance 0)
			)
			(min_thickness 0.25)
			(keepout
				(tracks allowed)
				(vias not_allowed)
				(pads allowed)
				(copperpour not_allowed)
				(footprints allowed)
			)
			(placement
				(enabled no)
				(sheetname "")
			)
			(fill
				(thermal_gap 0.5)
				(thermal_bridge_width 0.5)
				(island_removal_mode 0)
			)
			(polygon
				(pts
					(xy 409.376118 -92.669614) (xy 410.392118 -92.669614) (xy 410.392118 -94.358714) (xy 409.376118 -94.358714)
				)
			)
		)
		(zone
			(layer "B.Cu")
			(hatch none 0.5)
			(connect_pads
				(clearance 0)
			)
			(min_thickness 0.25)
			(keepout
				(tracks allowed)
				(vias not_allowed)
				(pads allowed)
				(copperpour not_allowed)
				(footprints allowed)
			)
			(placement
				(enabled no)
				(sheetname "")
			)
			(fill
				(thermal_gap 0.5)
				(thermal_bridge_width 0.5)
				(island_removal_mode 0)
			)
			(polygon
				(pts
					(xy 411.154118 -92.669614) (xy 412.170118 -92.669614) (xy 412.170118 -94.358714) (xy 411.154118 -94.358714)
				)
			)
		)
	)
	(footprint ""
		(layer "B.Cu")
		(at 93.086428 -144.89684 -90)
		(property "Reference" "C8L12"
			(at 0 0 90)
			(layer "B.SilkS")
			(hide yes)
			(effects
				(font
					(size 1.27 1.27)
				)
				(justify mirror)
			)
		)
		(property "Value" ""
			(at 0 0 90)
			(layer "B.Fab")
			(effects
				(font
					(size 1.27 1.27)
				)
				(justify mirror)
			)
		)
		(duplicate_pad_numbers_are_jumpers no)
		(fp_rect
			(start 0.500126 1.598422)
			(end -0.500126 -0.201422)
			(stroke
				(width 0)
				(type default)
			)
			(fill no)
			(layer "B.CrtYd")
		)
		(fp_line
			(start -0.500126 1.598422)
			(end 0.500126 1.598422)
			(stroke
				(width 0.1)
				(type default)
			)
			(layer "B.Fab")
		)
		(fp_line
			(start 0.500126 1.598422)
			(end 0.500126 -0.201422)
			(stroke
				(width 0.1)
				(type default)
			)
			(layer "B.Fab")
		)
		(fp_line
			(start -0.500126 -0.201422)
			(end -0.500126 1.598422)
			(stroke
				(width 0.1)
				(type default)
			)
			(layer "B.Fab")
		)
		(fp_line
			(start 0.500126 -0.201422)
			(end -0.500126 -0.201422)
			(stroke
				(width 0.1)
				(type default)
			)
			(layer "B.Fab")
		)
		(pad "1" smd rect
			(at 0 0 180)
			(size 0.889 0.9906)
			(layers "B.Cu" "B.Mask" "B.Paste")
			(net "PVDDQ_KLM")
		)
		(pad "2" smd rect
			(at 0 1.397 180)
			(size 0.889 0.9906)
			(layers "B.Cu" "B.Mask" "B.Paste")
			(net "GND")
		)
		(zone
			(layer "B.Cu")
			(hatch none 0.5)
			(connect_pads
				(clearance 0)
			)
			(min_thickness 0.25)
			(keepout
				(tracks not_allowed)
				(vias allowed)
				(pads allowed)
				(copperpour not_allowed)
				(footprints allowed)
			)
			(placement
				(enabled no)
				(sheetname "")
			)
			(fill
				(thermal_gap 0.5)
				(thermal_bridge_width 0.5)
				(island_removal_mode 0)
			)
			(polygon
				(pts
					(xy 92.133928 -144.40154) (xy 92.641928 -144.40154) (xy 92.641928 -145.39214) (xy 92.133928 -145.39214)
				)
			)
		)
		(zone
			(layer "B.Cu")
			(hatch none 0.5)
			(connect_pads
				(clearance 0)
			)
			(min_thickness 0.25)
			(keepout
				(tracks allowed)
				(vias not_allowed)
				(pads allowed)
				(copperpour not_allowed)
				(footprints allowed)
			)
			(placement
				(enabled no)
				(sheetname "")
			)
			(fill
				(thermal_gap 0.5)
				(thermal_bridge_width 0.5)
				(island_removal_mode 0)
			)
			(polygon
				(pts
					(xy 92.133928 -144.40154) (xy 92.641928 -144.40154) (xy 92.641928 -145.39214) (xy 92.133928 -145.39214)
				)
			)
		)
	)
	(footprint ""
		(layer "B.Cu")
		(at 45.611796 -100.676202 -90)
		(property "Reference" "C9N11"
			(at -0.008128 -3.664204 0)
			(unlocked yes)
			(layer "B.SilkS")
			(effects
				(font
					(size 0.7874 0.5842)
					(thickness 0.1524)
				)
				(justify mirror)
			)
		)
		(property "Value" ""
			(at 0 0 90)
			(layer "B.Fab")
			(effects
				(font
					(size 1.27 1.27)
				)
				(justify mirror)
			)
		)
		(duplicate_pad_numbers_are_jumpers no)
		(fp_line
			(start -2.286 7.366)
			(end -1.600708 7.366)
			(stroke
				(width 0.1524)
				(type default)
			)
			(layer "B.SilkS")
		)
		(fp_line
			(start -2.286 7.366)
			(end -2.286 1.63195)
			(stroke
				(width 0.1524)
				(type default)
			)
			(layer "B.SilkS")
		)
		(fp_line
			(start 2.286 7.366)
			(end 1.60147 7.366)
			(stroke
				(width 0.1524)
				(type default)
			)
			(layer "B.SilkS")
		)
		(fp_line
			(start 2.286 7.366)
			(end 2.286 1.632712)
			(stroke
				(width 0.1524)
				(type default)
			)
			(layer "B.SilkS")
		)
		(fp_line
			(start -2.504948 1.633728)
			(end -1.6002 1.633728)
			(stroke
				(width 0.1524)
				(type default)
			)
			(layer "B.SilkS")
		)
		(fp_line
			(start 2.563114 1.633728)
			(end 1.6002 1.633728)
			(stroke
				(width 0.1524)
				(type default)
			)
			(layer "B.SilkS")
		)
		(fp_line
			(start -2.504948 -1.616456)
			(end -2.504948 1.633728)
			(stroke
				(width 0.1524)
				(type default)
			)
			(layer "B.SilkS")
		)
		(fp_line
			(start -1.6002 -1.616456)
			(end -2.504948 -1.616456)
			(stroke
				(width 0.1524)
				(type default)
			)
			(layer "B.SilkS")
		)
		(fp_line
			(start 1.6002 -1.616456)
			(end 2.563114 -1.616456)
			(stroke
				(width 0.1524)
				(type default)
			)
			(layer "B.SilkS")
		)
		(fp_line
			(start 2.563114 -1.616456)
			(end 2.563114 1.633728)
			(stroke
				(width 0.1524)
				(type default)
			)
			(layer "B.SilkS")
		)
		(fp_rect
			(start 2.286 7.366)
			(end -2.286 -0.254)
			(stroke
				(width 0)
				(type default)
			)
			(fill no)
			(layer "B.CrtYd")
		)
		(fp_line
			(start -2.286 7.366)
			(end 2.286 7.366)
			(stroke
				(width 0.1)
				(type default)
			)
			(layer "B.Fab")
		)
		(fp_line
			(start 2.286 7.366)
			(end 2.286 -0.254)
			(stroke
				(width 0.1)
				(type default)
			)
			(layer "B.Fab")
		)
		(fp_line
			(start -2.286 -0.254)
			(end -2.286 7.366)
			(stroke
				(width 0.1)
				(type default)
			)
			(layer "B.Fab")
		)
		(fp_line
			(start 2.286 -0.254)
			(end -2.286 -0.254)
			(stroke
				(width 0.1)
				(type default)
			)
			(layer "B.Fab")
		)
		(pad "1" smd rect
			(at 0 0 90)
			(size 2.54 3.048)
			(layers "B.Cu" "B.Mask" "B.Paste")
			(net "PVSA_CPU1")
		)
		(pad "2" smd rect
			(at 0 7.112 90)
			(size 2.54 3.048)
			(layers "B.Cu" "B.Mask" "B.Paste")
			(net "GND")
		)
	)
	(footprint ""
		(layer "B.Cu")
		(at 388.1374 -109.7534)
		(property "Reference" "C3N12"
			(at 0 0 0)
			(layer "B.SilkS")
			(hide yes)
			(effects
				(font
					(size 1.27 1.27)
				)
				(justify mirror)
			)
		)
		(property "Value" ""
			(at 0 0 0)
			(layer "B.Fab")
			(effects
				(font
					(size 1.27 1.27)
				)
				(justify mirror)
			)
		)
		(duplicate_pad_numbers_are_jumpers no)
		(fp_poly
			(pts
				(xy 0.4953 -0.2032) (xy -0.4953 -0.2032) (xy -0.4953 1.6002) (xy 0.4953 1.6002)
			)
			(stroke
				(width 0)
				(type default)
			)
			(fill no)
			(layer "B.CrtYd")
		)
		(fp_line
			(start -0.4953 -0.2032)
			(end -0.4953 1.6002)
			(stroke
				(width 0.1)
				(type default)
			)
			(layer "B.Fab")
		)
		(fp_line
			(start -0.4953 1.6002)
			(end 0.4953 1.6002)
			(stroke
				(width 0.1)
				(type default)
			)
			(layer "B.Fab")
		)
		(fp_line
			(start 0.4953 -0.2032)
			(end -0.4953 -0.2032)
			(stroke
				(width 0.1)
				(type default)
			)
			(layer "B.Fab")
		)
		(fp_line
			(start 0.4953 1.6002)
			(end 0.4953 -0.2032)
			(stroke
				(width 0.1)
				(type default)
			)
			(layer "B.Fab")
		)
		(pad "1" smd rect
			(at 0 0 180)
			(size 0.762 0.889)
			(layers "B.Cu" "B.Mask" "B.Paste")
			(net "PVNN_PCH_STBY")
		)
		(pad "2" smd rect
			(at 0 1.397 180)
			(size 0.762 0.889)
			(layers "B.Cu" "B.Mask" "B.Paste")
			(net "GND")
		)
		(zone
			(layer "B.Cu")
			(hatch none 0.5)
			(connect_pads
				(clearance 0)
			)
			(min_thickness 0.25)
			(keepout
				(tracks not_allowed)
				(vias allowed)
				(pads allowed)
				(copperpour not_allowed)
				(footprints allowed)
			)
			(placement
				(enabled no)
				(sheetname "")
			)
			(fill
				(thermal_gap 0.5)
				(thermal_bridge_width 0.5)
				(island_removal_mode 0)
			)
			(polygon
				(pts
					(xy 388.5184 -109.3089) (xy 387.7564 -109.3089) (xy 387.7564 -108.8009) (xy 388.5184 -108.8009)
				)
			)
		)
	)
	(footprint ""
		(layer "B.Cu")
		(at 336.140806 -61.257434)
		(property "Reference" "C2U5"
			(at 0 0 0)
			(layer "B.SilkS")
			(hide yes)
			(effects
				(font
					(size 1.27 1.27)
				)
				(justify mirror)
			)
		)
		(property "Value" ""
			(at 0 0 0)
			(layer "B.Fab")
			(effects
				(font
					(size 1.27 1.27)
				)
				(justify mirror)
			)
		)
		(duplicate_pad_numbers_are_jumpers no)
		(fp_poly
			(pts
				(xy -0.3048 -0.1016) (xy -0.3048 0.9906) (xy 0.3048 0.9906) (xy 0.3048 -0.1016)
			)
			(stroke
				(width 0)
				(type default)
			)
			(fill no)
			(layer "B.CrtYd")
		)
		(fp_line
			(start -0.3048 -0.1016)
			(end 0.3048 -0.1016)
			(stroke
				(width 0.1)
				(type default)
			)
			(layer "B.Fab")
		)
		(fp_line
			(start -0.3048 0.9906)
			(end -0.3048 -0.1016)
			(stroke
				(width 0.1)
				(type default)
			)
			(layer "B.Fab")
		)
		(fp_line
			(start 0.3048 -0.1016)
			(end 0.3048 0.9906)
			(stroke
				(width 0.1)
				(type default)
			)
			(layer "B.Fab")
		)
		(fp_line
			(start 0.3048 0.9906)
			(end -0.3048 0.9906)
			(stroke
				(width 0.1)
				(type default)
			)
			(layer "B.Fab")
		)
		(pad "1" smd rect
			(at 0 0 180)
			(size 0.508 0.508)
			(layers "B.Cu" "B.Mask" "B.Paste")
			(net "P3E_CPU0_PE1_PCH_RXP<1>")
		)
		(pad "2" smd rect
			(at 0 0.889 180)
			(size 0.508 0.508)
			(layers "B.Cu" "B.Mask" "B.Paste")
			(net "P3E_CPU0_PE1_SS_RXP<1>")
		)
		(zone
			(layer "B.Cu")
			(hatch none 0.5)
			(connect_pads
				(clearance 0)
			)
			(min_thickness 0.25)
			(keepout
				(tracks allowed)
				(vias not_allowed)
				(pads allowed)
				(copperpour not_allowed)
				(footprints allowed)
			)
			(placement
				(enabled no)
				(sheetname "")
			)
			(fill
				(thermal_gap 0.5)
				(thermal_bridge_width 0.5)
				(island_removal_mode 0)
			)
			(polygon
				(pts
					(xy 336.394806 -61.003434) (xy 335.886806 -61.003434) (xy 335.886806 -60.622434) (xy 336.394806 -60.622434)
				)
			)
		)
		(zone
			(layer "B.Cu")
			(hatch none 0.5)
			(connect_pads
				(clearance 0)
			)
			(min_thickness 0.25)
			(keepout
				(tracks not_allowed)
				(vias allowed)
				(pads allowed)
				(copperpour not_allowed)
				(footprints allowed)
			)
			(placement
				(enabled no)
				(sheetname "")
			)
			(fill
				(thermal_gap 0.5)
				(thermal_bridge_width 0.5)
				(island_removal_mode 0)
			)
			(polygon
				(pts
					(xy 336.394806 -60.622434) (xy 335.886806 -60.622434) (xy 335.886806 -61.003434) (xy 336.394806 -61.003434)
				)
			)
		)
	)
	(footprint ""
		(layer "B.Cu")
		(at 481.0379 -147.977098)
		(property "Reference" "Q6W2"
			(at 0.229362 -1.2065 0)
			(unlocked yes)
			(layer "B.SilkS")
			(effects
				(font
					(size 0.4064 0.254)
					(thickness 0.1524)
				)
				(justify left mirror)
			)
		)
		(property "Value" ""
			(at 0 0 0)
			(layer "B.Fab")
			(effects
				(font
					(size 1.27 1.27)
				)
				(justify mirror)
			)
		)
		(duplicate_pad_numbers_are_jumpers no)
		(fp_line
			(start -1.778 -0.5715)
			(end -1.778 0.3175)
			(stroke
				(width 0.1524)
				(type default)
			)
			(layer "B.SilkS")
		)
		(fp_line
			(start -1.778 2.4765)
			(end -1.778 1.5875)
			(stroke
				(width 0.1524)
				(type default)
			)
			(layer "B.SilkS")
		)
		(fp_line
			(start -0.9525 -0.5715)
			(end -1.778 -0.5715)
			(stroke
				(width 0.1524)
				(type default)
			)
			(layer "B.SilkS")
		)
		(fp_line
			(start -0.9525 2.4765)
			(end -1.778 2.4765)
			(stroke
				(width 0.1524)
				(type default)
			)
			(layer "B.SilkS")
		)
		(fp_line
			(start -0.381 0.635)
			(end -0.381 1.27)
			(stroke
				(width 0.1524)
				(type default)
			)
			(layer "B.SilkS")
		)
		(fp_circle
			(center 0.758952 -0.88773)
			(end 0.885952 -0.88773)
			(stroke
				(width 0.254)
				(type default)
			)
			(fill no)
			(layer "B.SilkS")
		)
		(fp_poly
			(pts
				(xy -1.778 2.4765) (xy -0.381 2.4765) (xy -0.381 -0.5715) (xy -1.778 -0.5715)
			)
			(stroke
				(width 0)
				(type default)
			)
			(fill no)
			(layer "B.CrtYd")
		)
		(fp_line
			(start -1.778 -0.5715)
			(end -0.381 -0.5715)
			(stroke
				(width 0.1)
				(type default)
			)
			(layer "B.Fab")
		)
		(fp_line
			(start -1.778 2.4765)
			(end -1.778 -0.5715)
			(stroke
				(width 0.1)
				(type default)
			)
			(layer "B.Fab")
		)
		(fp_line
			(start -0.381 -0.5715)
			(end -0.381 2.4765)
			(stroke
				(width 0.1)
				(type default)
			)
			(layer "B.Fab")
		)
		(fp_line
			(start -0.381 2.4765)
			(end -1.778 2.4765)
			(stroke
				(width 0.1)
				(type default)
			)
			(layer "B.Fab")
		)
		(fp_circle
			(center 0.9525 -0.9271)
			(end 1.0795 -0.9271)
			(stroke
				(width 0.254)
				(type default)
			)
			(fill no)
			(layer "B.Fab")
		)
		(pad "1" smd rect
			(at 0 0 180)
			(size 1.143 0.508)
			(layers "B.Cu" "B.Mask" "B.Paste")
			(net "FM_UART_SEL_N")
		)
		(pad "2" smd rect
			(at 0 1.905 180)
			(size 1.143 0.508)
			(layers "B.Cu" "B.Mask" "B.Paste")
			(net "GND")
		)
		(pad "3" smd rect
			(at -2.159 0.9525 180)
			(size 1.143 0.508)
			(layers "B.Cu" "B.Mask" "B.Paste")
			(net "FM_SOL_UART_CH_SEL")
		)
	)
	(footprint ""
		(layer "B.Cu")
		(at 447.04 -19.939 -90)
		(property "Reference" "Q9W4"
			(at 0 0 90)
			(layer "B.SilkS")
			(hide yes)
			(effects
				(font
					(size 1.27 1.27)
				)
				(justify mirror)
			)
		)
		(property "Value" "*"
			(at 2.3368 -8.8011 270)
			(unlocked yes)
			(layer "B.Fab")
			(hide yes)
			(effects
				(font
					(size 1.27 1.016)
					(thickness 0.1524)
				)
				(justify mirror)
			)
		)
		(property "Device Type" "LMV331IDCKRG4-GP_DISCRET-G-LMVA"
			(at 2.3114 -10.5283 270)
			(unlocked yes)
			(layer "B.Fab")
			(hide yes)
			(effects
				(font
					(size 1.27 1.016)
					(thickness 0.1524)
				)
				(justify mirror)
			)
		)
		(duplicate_pad_numbers_are_jumpers no)
		(fp_line
			(start -1.27 1.7018)
			(end 1.27 1.7018)
			(stroke
				(width 0.1524)
				(type default)
			)
			(layer "B.SilkS")
		)
		(fp_line
			(start 1.27 1.7018)
			(end 1.27 -1.7018)
			(stroke
				(width 0.1524)
				(type default)
			)
			(layer "B.SilkS")
		)
		(fp_line
			(start -1.27 -1.7018)
			(end -1.27 1.7018)
			(stroke
				(width 0.1524)
				(type default)
			)
			(layer "B.SilkS")
		)
		(fp_line
			(start 1.27 -1.7018)
			(end -1.27 -1.7018)
			(stroke
				(width 0.1524)
				(type default)
			)
			(layer "B.SilkS")
		)
		(fp_line
			(start -1.3843 -1.8034)
			(end -1.3843 -1.1176)
			(stroke
				(width 0.3302)
				(type default)
			)
			(layer "B.SilkS")
		)
		(fp_line
			(start -0.6604 -1.8034)
			(end -1.3843 -1.8034)
			(stroke
				(width 0.3302)
				(type default)
			)
			(layer "B.SilkS")
		)
		(fp_rect
			(start 1.524 1.9558)
			(end -1.524 -1.9558)
			(stroke
				(width 0)
				(type default)
			)
			(fill no)
			(layer "B.CrtYd")
		)
		(fp_poly
			(pts
				(xy 1.524 -1.9558) (xy -1.524 -1.9558) (xy -1.524 1.9558) (xy 1.524 1.9558)
			)
			(stroke
				(width 0)
				(type default)
			)
			(fill no)
			(layer "B.Fab")
		)
		(pad "1" smd rect
			(at -0.65024 -0.8255 90)
			(size 0.4064 1.2192)
			(layers "B.Cu" "B.Mask" "B.Paste")
			(net "FM_TPM_PRES_RST_N")
		)
		(pad "2" smd rect
			(at 0 -0.8255 90)
			(size 0.4064 1.2192)
			(layers "B.Cu" "B.Mask" "B.Paste")
			(net "GND")
		)
		(pad "3" smd rect
			(at 0.65024 -0.8255 90)
			(size 0.4064 1.2192)
			(layers "B.Cu" "B.Mask" "B.Paste")
			(net "VREF_2V2")
		)
		(pad "4" smd rect
			(at 0.65024 0.8255 90)
			(size 0.4064 1.2192)
			(layers "B.Cu" "B.Mask" "B.Paste")
			(net "FM_TPM_PRES_N")
		)
		(pad "5" smd rect
			(at -0.65024 0.8255 90)
			(size 0.4064 1.2192)
			(layers "B.Cu" "B.Mask" "B.Paste")
			(net "P5V_STBY")
		)
	)
	(footprint ""
		(layer "B.Cu")
		(at 376.418348 -47.007018 180)
		(property "Reference" "U7E3"
			(at -2.286 -1.281684 0)
			(unlocked yes)
			(layer "B.SilkS")
			(effects
				(font
					(size 0.7874 0.5842)
					(thickness 0.1524)
				)
				(justify left mirror)
			)
		)
		(property "Value" ""
			(at 0 0 0)
			(layer "B.Fab")
			(effects
				(font
					(size 1.27 1.27)
				)
				(justify mirror)
			)
		)
		(duplicate_pad_numbers_are_jumpers no)
		(fp_circle
			(center 0.402844 -0.6604)
			(end 0.275844 -0.6604)
			(stroke
				(width 0.254)
				(type default)
			)
			(fill no)
			(layer "B.SilkS")
		)
		(fp_poly
			(pts
				(xy -0.21463 -0.450088) (xy -1.56337 -0.450088) (xy -1.56337 1.75006) (xy -0.21463 1.75006)
			)
			(stroke
				(width 0)
				(type default)
			)
			(fill no)
			(layer "B.CrtYd")
		)
		(fp_line
			(start -0.21463 1.75006)
			(end -0.21463 -0.450088)
			(stroke
				(width 0.1)
				(type default)
			)
			(layer "B.Fab")
		)
		(fp_line
			(start -0.21463 -0.450088)
			(end -1.56337 -0.450088)
			(stroke
				(width 0.1)
				(type default)
			)
			(layer "B.Fab")
		)
		(fp_line
			(start -1.56337 1.75006)
			(end -0.21463 1.75006)
			(stroke
				(width 0.1)
				(type default)
			)
			(layer "B.Fab")
		)
		(fp_line
			(start -1.56337 -0.450088)
			(end -1.56337 1.75006)
			(stroke
				(width 0.1)
				(type default)
			)
			(layer "B.Fab")
		)
		(fp_circle
			(center 0.4699 -0.8382)
			(end 0.3429 -0.8382)
			(stroke
				(width 0.254)
				(type default)
			)
			(fill no)
			(layer "B.Fab")
		)
		(pad "1" smd rect
			(at 0 0)
			(size 1.016 0.381)
			(layers "B.Cu" "B.Mask" "B.Paste")
			(net "FM_PVCCIN_CPU1_PWR_IN_ALERT_N")
		)
		(pad "2" smd rect
			(at 0 0.649986)
			(size 1.016 0.381)
			(layers "B.Cu" "B.Mask" "B.Paste")
			(net "IRQ_PVCCIN_CPU1_VRHOT_LVC3_N")
		)
		(pad "3" smd rect
			(at 0 1.299972)
			(size 1.016 0.381)
			(layers "B.Cu" "B.Mask" "B.Paste")
			(net "GND")
		)
		(pad "4" smd rect
			(at -1.778 1.299972)
			(size 1.016 0.381)
			(layers "B.Cu" "B.Mask" "B.Paste")
			(net "IRQ_CPU1_PROCHOT_G_N")
		)
		(pad "5" smd rect
			(at -1.778 0)
			(size 1.016 0.381)
			(layers "B.Cu" "B.Mask" "B.Paste")
			(net "P3V3_STBY")
		)
	)
	(footprint ""
		(layer "B.Cu")
		(at 345.919806 -61.257434)
		(property "Reference" "C2U12"
			(at 0 0 0)
			(layer "B.SilkS")
			(hide yes)
			(effects
				(font
					(size 1.27 1.27)
				)
				(justify mirror)
			)
		)
		(property "Value" ""
			(at 0 0 0)
			(layer "B.Fab")
			(effects
				(font
					(size 1.27 1.27)
				)
				(justify mirror)
			)
		)
		(duplicate_pad_numbers_are_jumpers no)
		(fp_poly
			(pts
				(xy -0.3048 -0.1016) (xy -0.3048 0.9906) (xy 0.3048 0.9906) (xy 0.3048 -0.1016)
			)
			(stroke
				(width 0)
				(type default)
			)
			(fill no)
			(layer "B.CrtYd")
		)
		(fp_line
			(start -0.3048 -0.1016)
			(end 0.3048 -0.1016)
			(stroke
				(width 0.1)
				(type default)
			)
			(layer "B.Fab")
		)
		(fp_line
			(start -0.3048 0.9906)
			(end -0.3048 -0.1016)
			(stroke
				(width 0.1)
				(type default)
			)
			(layer "B.Fab")
		)
		(fp_line
			(start 0.3048 -0.1016)
			(end 0.3048 0.9906)
			(stroke
				(width 0.1)
				(type default)
			)
			(layer "B.Fab")
		)
		(fp_line
			(start 0.3048 0.9906)
			(end -0.3048 0.9906)
			(stroke
				(width 0.1)
				(type default)
			)
			(layer "B.Fab")
		)
		(pad "1" smd rect
			(at 0 0 180)
			(size 0.508 0.508)
			(layers "B.Cu" "B.Mask" "B.Paste")
			(net "P3E_CPU0_PE1_PCH_RXN<4>")
		)
		(pad "2" smd rect
			(at 0 0.889 180)
			(size 0.508 0.508)
			(layers "B.Cu" "B.Mask" "B.Paste")
			(net "P3E_CPU0_PE1_SS_RXN<4>")
		)
		(zone
			(layer "B.Cu")
			(hatch none 0.5)
			(connect_pads
				(clearance 0)
			)
			(min_thickness 0.25)
			(keepout
				(tracks allowed)
				(vias not_allowed)
				(pads allowed)
				(copperpour not_allowed)
				(footprints allowed)
			)
			(placement
				(enabled no)
				(sheetname "")
			)
			(fill
				(thermal_gap 0.5)
				(thermal_bridge_width 0.5)
				(island_removal_mode 0)
			)
			(polygon
				(pts
					(xy 346.173806 -61.003434) (xy 345.665806 -61.003434) (xy 345.665806 -60.622434) (xy 346.173806 -60.622434)
				)
			)
		)
	)
	(footprint ""
		(layer "B.Cu")
		(at 171.1706 -147.8026 90)
		(property "Reference" "R6L6"
			(at 0 0 90)
			(layer "B.SilkS")
			(hide yes)
			(effects
				(font
					(size 1.27 1.27)
				)
				(justify mirror)
			)
		)
		(property "Value" ""
			(at 0 0 90)
			(layer "B.Fab")
			(effects
				(font
					(size 1.27 1.27)
				)
				(justify mirror)
			)
		)
		(duplicate_pad_numbers_are_jumpers no)
		(fp_rect
			(start 0.2794 0.9906)
			(end -0.2794 -0.1016)
			(stroke
				(width 0)
				(type default)
			)
			(fill no)
			(layer "B.CrtYd")
		)
		(fp_line
			(start 0.2794 -0.1016)
			(end 0.2794 0.9906)
			(stroke
				(width 0.1)
				(type default)
			)
			(layer "B.Fab")
		)
		(fp_line
			(start -0.2794 -0.1016)
			(end 0.2794 -0.1016)
			(stroke
				(width 0.1)
				(type default)
			)
			(layer "B.Fab")
		)
		(fp_line
			(start 0.2794 0.9906)
			(end -0.2794 0.9906)
			(stroke
				(width 0.1)
				(type default)
			)
			(layer "B.Fab")
		)
		(fp_line
			(start -0.2794 0.9906)
			(end -0.2794 -0.1016)
			(stroke
				(width 0.1)
				(type default)
			)
			(layer "B.Fab")
		)
		(pad "1" smd rect
			(at 0 0 270)
			(size 0.508 0.508)
			(layers "B.Cu" "B.Mask" "B.Paste")
			(net "PVDDQ_KLM")
		)
		(pad "2" smd rect
			(at 0 0.889 270)
			(size 0.508 0.508)
			(layers "B.Cu" "B.Mask" "B.Paste")
			(net "VSENSE_PVDDQ_KLM_VTT")
		)
		(zone
			(layer "B.Cu")
			(hatch none 0.5)
			(connect_pads
				(clearance 0)
			)
			(min_thickness 0.25)
			(keepout
				(tracks not_allowed)
				(vias allowed)
				(pads allowed)
				(copperpour not_allowed)
				(footprints allowed)
			)
			(placement
				(enabled no)
				(sheetname "")
			)
			(fill
				(thermal_gap 0.5)
				(thermal_bridge_width 0.5)
				(island_removal_mode 0)
			)
			(polygon
				(pts
					(xy 171.8056 -148.0566) (xy 171.4246 -148.0566) (xy 171.4246 -147.5486) (xy 171.8056 -147.5486)
				)
			)
		)
		(zone
			(layer "B.Cu")
			(hatch none 0.5)
			(connect_pads
				(clearance 0)
			)
			(min_thickness 0.25)
			(keepout
				(tracks allowed)
				(vias not_allowed)
				(pads allowed)
				(copperpour not_allowed)
				(footprints allowed)
			)
			(placement
				(enabled no)
				(sheetname "")
			)
			(fill
				(thermal_gap 0.5)
				(thermal_bridge_width 0.5)
				(island_removal_mode 0)
			)
			(polygon
				(pts
					(xy 171.8056 -148.0566) (xy 171.4246 -148.0566) (xy 171.4246 -147.5486) (xy 171.8056 -147.5486)
				)
			)
		)
	)
	(footprint ""
		(layer "B.Cu")
		(at 414.5534 -141.0208 -90)
		(property "Reference" "C2L47"
			(at 0 0 90)
			(layer "B.SilkS")
			(hide yes)
			(effects
				(font
					(size 1.27 1.27)
				)
				(justify mirror)
			)
		)
		(property "Value" ""
			(at 0 0 90)
			(layer "B.Fab")
			(effects
				(font
					(size 1.27 1.27)
				)
				(justify mirror)
			)
		)
		(duplicate_pad_numbers_are_jumpers no)
		(fp_poly
			(pts
				(xy -0.3048 -0.1016) (xy -0.3048 0.9906) (xy 0.3048 0.9906) (xy 0.3048 -0.1016)
			)
			(stroke
				(width 0)
				(type default)
			)
			(fill no)
			(layer "B.CrtYd")
		)
		(fp_line
			(start -0.3048 0.9906)
			(end -0.3048 -0.1016)
			(stroke
				(width 0.1)
				(type default)
			)
			(layer "B.Fab")
		)
		(fp_line
			(start 0.3048 0.9906)
			(end -0.3048 0.9906)
			(stroke
				(width 0.1)
				(type default)
			)
			(layer "B.Fab")
		)
		(fp_line
			(start -0.3048 -0.1016)
			(end 0.3048 -0.1016)
			(stroke
				(width 0.1)
				(type default)
			)
			(layer "B.Fab")
		)
		(fp_line
			(start 0.3048 -0.1016)
			(end 0.3048 0.9906)
			(stroke
				(width 0.1)
				(type default)
			)
			(layer "B.Fab")
		)
		(pad "1" smd rect
			(at 0 0 90)
			(size 0.508 0.508)
			(layers "B.Cu" "B.Mask" "B.Paste")
			(net "SATA6G_P4_TX_C_DP")
		)
		(pad "2" smd rect
			(at 0 0.889 90)
			(size 0.508 0.508)
			(layers "B.Cu" "B.Mask" "B.Paste")
			(net "SATA6G_PCH_PCIE_UP_SATA_TXP<4>")
		)
		(zone
			(layer "B.Cu")
			(hatch none 0.5)
			(connect_pads
				(clearance 0)
			)
			(min_thickness 0.25)
			(keepout
				(tracks not_allowed)
				(vias allowed)
				(pads allowed)
				(copperpour not_allowed)
				(footprints allowed)
			)
			(placement
				(enabled no)
				(sheetname "")
			)
			(fill
				(thermal_gap 0.5)
				(thermal_bridge_width 0.5)
				(island_removal_mode 0)
			)
			(polygon
				(pts
					(xy 413.9184 -140.7668) (xy 413.9184 -141.2748) (xy 414.2994 -141.2748) (xy 414.2994 -140.7668)
				)
			)
		)
		(zone
			(layer "B.Cu")
			(hatch none 0.5)
			(connect_pads
				(clearance 0)
			)
			(min_thickness 0.25)
			(keepout
				(tracks allowed)
				(vias not_allowed)
				(pads allowed)
				(copperpour not_allowed)
				(footprints allowed)
			)
			(placement
				(enabled no)
				(sheetname "")
			)
			(fill
				(thermal_gap 0.5)
				(thermal_bridge_width 0.5)
				(island_removal_mode 0)
			)
			(polygon
				(pts
					(xy 414.2994 -140.7668) (xy 414.2994 -141.2748) (xy 413.9184 -141.2748) (xy 413.9184 -140.7668)
				)
			)
		)
	)
	(footprint ""
		(layer "B.Cu")
		(at 63.246 -64.7954 180)
		(property "Reference" "R1E4"
			(at 0 0 0)
			(layer "B.SilkS")
			(hide yes)
			(effects
				(font
					(size 1.27 1.27)
				)
				(justify mirror)
			)
		)
		(property "Value" ""
			(at 0 0 0)
			(layer "B.Fab")
			(effects
				(font
					(size 1.27 1.27)
				)
				(justify mirror)
			)
		)
		(duplicate_pad_numbers_are_jumpers no)
		(fp_poly
			(pts
				(xy 0.2794 -0.1016) (xy -0.2794 -0.1016) (xy -0.2794 0.9906) (xy 0.2794 0.9906)
			)
			(stroke
				(width 0)
				(type default)
			)
			(fill no)
			(layer "B.CrtYd")
		)
		(fp_line
			(start 0.2794 0.9906)
			(end -0.2794 0.9906)
			(stroke
				(width 0.1)
				(type default)
			)
			(layer "B.Fab")
		)
		(fp_line
			(start 0.2794 -0.1016)
			(end 0.2794 0.9906)
			(stroke
				(width 0.1)
				(type default)
			)
			(layer "B.Fab")
		)
		(fp_line
			(start -0.2794 0.9906)
			(end -0.2794 -0.1016)
			(stroke
				(width 0.1)
				(type default)
			)
			(layer "B.Fab")
		)
		(fp_line
			(start -0.2794 -0.1016)
			(end 0.2794 -0.1016)
			(stroke
				(width 0.1)
				(type default)
			)
			(layer "B.Fab")
		)
		(pad "1" smd rect
			(at 0 0)
			(size 0.508 0.508)
			(layers "B.Cu" "B.Mask" "B.Paste")
			(net "VSENSE_PVCCIN_CPU1_P")
		)
		(pad "2" smd rect
			(at 0 0.889)
			(size 0.508 0.508)
			(layers "B.Cu" "B.Mask" "B.Paste")
			(net "PVCCIN_CPU1")
		)
		(zone
			(layer "B.Cu")
			(hatch none 0.5)
			(connect_pads
				(clearance 0)
			)
			(min_thickness 0.25)
			(keepout
				(tracks not_allowed)
				(vias allowed)
				(pads allowed)
				(copperpour not_allowed)
				(footprints allowed)
			)
			(placement
				(enabled no)
				(sheetname "")
			)
			(fill
				(thermal_gap 0.5)
				(thermal_bridge_width 0.5)
				(island_removal_mode 0)
			)
			(polygon
				(pts
					(xy 62.992 -65.4304) (xy 63.5 -65.4304) (xy 63.5 -65.0494) (xy 62.992 -65.0494)
				)
			)
		)
		(zone
			(layer "B.Cu")
			(hatch none 0.5)
			(connect_pads
				(clearance 0)
			)
			(min_thickness 0.25)
			(keepout
				(tracks allowed)
				(vias not_allowed)
				(pads allowed)
				(copperpour not_allowed)
				(footprints allowed)
			)
			(placement
				(enabled no)
				(sheetname "")
			)
			(fill
				(thermal_gap 0.5)
				(thermal_bridge_width 0.5)
				(island_removal_mode 0)
			)
			(polygon
				(pts
					(xy 62.992 -65.0494) (xy 63.5 -65.0494) (xy 63.5 -65.4304) (xy 62.992 -65.4304)
				)
			)
		)
	)
	(footprint ""
		(layer "B.Cu")
		(at 350.022414 -126.345442 -90)
		(property "Reference" "C3M11"
			(at 0 0 90)
			(layer "B.SilkS")
			(hide yes)
			(effects
				(font
					(size 1.27 1.27)
				)
				(justify mirror)
			)
		)
		(property "Value" ""
			(at 0 0 90)
			(layer "B.Fab")
			(effects
				(font
					(size 1.27 1.27)
				)
				(justify mirror)
			)
		)
		(duplicate_pad_numbers_are_jumpers no)
		(fp_poly
			(pts
				(xy -0.3048 -0.1016) (xy -0.3048 0.9906) (xy 0.3048 0.9906) (xy 0.3048 -0.1016)
			)
			(stroke
				(width 0)
				(type default)
			)
			(fill no)
			(layer "B.CrtYd")
		)
		(fp_line
			(start -0.3048 0.9906)
			(end -0.3048 -0.1016)
			(stroke
				(width 0.1)
				(type default)
			)
			(layer "B.Fab")
		)
		(fp_line
			(start 0.3048 0.9906)
			(end -0.3048 0.9906)
			(stroke
				(width 0.1)
				(type default)
			)
			(layer "B.Fab")
		)
		(fp_line
			(start -0.3048 -0.1016)
			(end 0.3048 -0.1016)
			(stroke
				(width 0.1)
				(type default)
			)
			(layer "B.Fab")
		)
		(fp_line
			(start 0.3048 -0.1016)
			(end 0.3048 0.9906)
			(stroke
				(width 0.1)
				(type default)
			)
			(layer "B.Fab")
		)
		(pad "1" smd rect
			(at 0 0 90)
			(size 0.508 0.508)
			(layers "B.Cu" "B.Mask" "B.Paste")
			(net "P3E_CPU0_PE1_PCH_R_RXP<14>")
		)
		(pad "2" smd rect
			(at 0 0.889 90)
			(size 0.508 0.508)
			(layers "B.Cu" "B.Mask" "B.Paste")
			(net "P3E_CPU0_PE1_PCH_RXP<14>")
		)
		(zone
			(layer "B.Cu")
			(hatch none 0.5)
			(connect_pads
				(clearance 0)
			)
			(min_thickness 0.25)
			(keepout
				(tracks not_allowed)
				(vias allowed)
				(pads allowed)
				(copperpour not_allowed)
				(footprints allowed)
			)
			(placement
				(enabled no)
				(sheetname "")
			)
			(fill
				(thermal_gap 0.5)
				(thermal_bridge_width 0.5)
				(island_removal_mode 0)
			)
			(polygon
				(pts
					(xy 349.387414 -126.091442) (xy 349.387414 -126.599442) (xy 349.768414 -126.599442) (xy 349.768414 -126.091442)
				)
			)
		)
		(zone
			(layer "B.Cu")
			(hatch none 0.5)
			(connect_pads
				(clearance 0)
			)
			(min_thickness 0.25)
			(keepout
				(tracks allowed)
				(vias not_allowed)
				(pads allowed)
				(copperpour not_allowed)
				(footprints allowed)
			)
			(placement
				(enabled no)
				(sheetname "")
			)
			(fill
				(thermal_gap 0.5)
				(thermal_bridge_width 0.5)
				(island_removal_mode 0)
			)
			(polygon
				(pts
					(xy 349.768414 -126.091442) (xy 349.768414 -126.599442) (xy 349.387414 -126.599442) (xy 349.387414 -126.091442)
				)
			)
		)
	)
	(footprint ""
		(layer "B.Cu")
		(at 112.378236 -68.603114 -90)
		(property "Reference" "R7P22"
			(at 0 0 90)
			(layer "B.SilkS")
			(hide yes)
			(effects
				(font
					(size 1.27 1.27)
				)
				(justify mirror)
			)
		)
		(property "Value" ""
			(at 0 0 90)
			(layer "B.Fab")
			(effects
				(font
					(size 1.27 1.27)
				)
				(justify mirror)
			)
		)
		(duplicate_pad_numbers_are_jumpers no)
		(fp_poly
			(pts
				(xy 0.2794 -0.1016) (xy -0.2794 -0.1016) (xy -0.2794 0.9906) (xy 0.2794 0.9906)
			)
			(stroke
				(width 0)
				(type default)
			)
			(fill no)
			(layer "B.CrtYd")
		)
		(fp_line
			(start -0.2794 0.9906)
			(end -0.2794 -0.1016)
			(stroke
				(width 0.1)
				(type default)
			)
			(layer "B.Fab")
		)
		(fp_line
			(start 0.2794 0.9906)
			(end -0.2794 0.9906)
			(stroke
				(width 0.1)
				(type default)
			)
			(layer "B.Fab")
		)
		(fp_line
			(start -0.2794 -0.1016)
			(end 0.2794 -0.1016)
			(stroke
				(width 0.1)
				(type default)
			)
			(layer "B.Fab")
		)
		(fp_line
			(start 0.2794 -0.1016)
			(end 0.2794 0.9906)
			(stroke
				(width 0.1)
				(type default)
			)
			(layer "B.Fab")
		)
		(pad "1" smd rect
			(at 0 0 90)
			(size 0.508 0.508)
			(layers "B.Cu" "B.Mask" "B.Paste")
			(net "PVCCIO_CPU1")
		)
		(pad "2" smd rect
			(at 0 0.889 90)
			(size 0.508 0.508)
			(layers "B.Cu" "B.Mask" "B.Paste")
			(net "PU_CPU1_LEGACY_SKT")
		)
		(zone
			(layer "B.Cu")
			(hatch none 0.5)
			(connect_pads
				(clearance 0)
			)
			(min_thickness 0.25)
			(keepout
				(tracks not_allowed)
				(vias allowed)
				(pads allowed)
				(copperpour not_allowed)
				(footprints allowed)
			)
			(placement
				(enabled no)
				(sheetname "")
			)
			(fill
				(thermal_gap 0.5)
				(thermal_bridge_width 0.5)
				(island_removal_mode 0)
			)
			(polygon
				(pts
					(xy 111.743236 -68.349114) (xy 111.743236 -68.857114) (xy 112.124236 -68.857114) (xy 112.124236 -68.349114)
				)
			)
		)
		(zone
			(layer "B.Cu")
			(hatch none 0.5)
			(connect_pads
				(clearance 0)
			)
			(min_thickness 0.25)
			(keepout
				(tracks allowed)
				(vias not_allowed)
				(pads allowed)
				(copperpour not_allowed)
				(footprints allowed)
			)
			(placement
				(enabled no)
				(sheetname "")
			)
			(fill
				(thermal_gap 0.5)
				(thermal_bridge_width 0.5)
				(island_removal_mode 0)
			)
			(polygon
				(pts
					(xy 112.124236 -68.349114) (xy 112.124236 -68.857114) (xy 111.743236 -68.857114) (xy 111.743236 -68.349114)
				)
			)
		)
	)
	(footprint ""
		(layer "B.Cu")
		(at 406.4 -105.8545 180)
		(property "Reference" "C2N21"
			(at 0 0 0)
			(layer "B.SilkS")
			(hide yes)
			(effects
				(font
					(size 1.27 1.27)
				)
				(justify mirror)
			)
		)
		(property "Value" ""
			(at 0 0 0)
			(layer "B.Fab")
			(effects
				(font
					(size 1.27 1.27)
				)
				(justify mirror)
			)
		)
		(duplicate_pad_numbers_are_jumpers no)
		(fp_poly
			(pts
				(xy 0.4953 -0.2032) (xy -0.4953 -0.2032) (xy -0.4953 1.6002) (xy 0.4953 1.6002)
			)
			(stroke
				(width 0)
				(type default)
			)
			(fill no)
			(layer "B.CrtYd")
		)
		(fp_line
			(start 0.4953 1.6002)
			(end 0.4953 -0.2032)
			(stroke
				(width 0.1)
				(type default)
			)
			(layer "B.Fab")
		)
		(fp_line
			(start 0.4953 -0.2032)
			(end -0.4953 -0.2032)
			(stroke
				(width 0.1)
				(type default)
			)
			(layer "B.Fab")
		)
		(fp_line
			(start -0.4953 1.6002)
			(end 0.4953 1.6002)
			(stroke
				(width 0.1)
				(type default)
			)
			(layer "B.Fab")
		)
		(fp_line
			(start -0.4953 -0.2032)
			(end -0.4953 1.6002)
			(stroke
				(width 0.1)
				(type default)
			)
			(layer "B.Fab")
		)
		(pad "1" smd rect
			(at 0 0)
			(size 0.762 0.889)
			(layers "B.Cu" "B.Mask" "B.Paste")
			(net "P3V3_STBY")
		)
		(pad "2" smd rect
			(at 0 1.397)
			(size 0.762 0.889)
			(layers "B.Cu" "B.Mask" "B.Paste")
			(net "GND")
		)
		(zone
			(layer "B.Cu")
			(hatch none 0.5)
			(connect_pads
				(clearance 0)
			)
			(min_thickness 0.25)
			(keepout
				(tracks not_allowed)
				(vias allowed)
				(pads allowed)
				(copperpour not_allowed)
				(footprints allowed)
			)
			(placement
				(enabled no)
				(sheetname "")
			)
			(fill
				(thermal_gap 0.5)
				(thermal_bridge_width 0.5)
				(island_removal_mode 0)
			)
			(polygon
				(pts
					(xy 406.019 -106.299) (xy 406.781 -106.299) (xy 406.781 -106.807) (xy 406.019 -106.807)
				)
			)
		)
	)
	(footprint ""
		(layer "B.Cu")
		(at 267.946886 -68.17614 180)
		(property "Reference" "C5P44"
			(at 0 0 0)
			(layer "B.SilkS")
			(hide yes)
			(effects
				(font
					(size 1.27 1.27)
				)
				(justify mirror)
			)
		)
		(property "Value" ""
			(at 0 0 0)
			(layer "B.Fab")
			(effects
				(font
					(size 1.27 1.27)
				)
				(justify mirror)
			)
		)
		(duplicate_pad_numbers_are_jumpers no)
		(fp_poly
			(pts
				(xy 0.7239 -0.2159) (xy -0.7239 -0.2159) (xy -0.7239 1.9939) (xy 0.7239 1.9939)
			)
			(stroke
				(width 0)
				(type default)
			)
			(fill no)
			(layer "B.CrtYd")
		)
		(fp_line
			(start 0.7239 1.9939)
			(end -0.7239 1.9939)
			(stroke
				(width 0.1)
				(type default)
			)
			(layer "B.Fab")
		)
		(fp_line
			(start 0.7239 -0.2159)
			(end 0.7239 1.9939)
			(stroke
				(width 0.1)
				(type default)
			)
			(layer "B.Fab")
		)
		(fp_line
			(start -0.7239 1.9939)
			(end -0.7239 -0.2159)
			(stroke
				(width 0.1)
				(type default)
			)
			(layer "B.Fab")
		)
		(fp_line
			(start -0.7239 -0.2159)
			(end 0.7239 -0.2159)
			(stroke
				(width 0.1)
				(type default)
			)
			(layer "B.Fab")
		)
		(pad "1" smd rect
			(at 0 0)
			(size 1.27 1.016)
			(layers "B.Cu" "B.Mask" "B.Paste")
			(net "PVDDQ_ABC")
		)
		(pad "2" smd rect
			(at 0 1.778)
			(size 1.27 1.016)
			(layers "B.Cu" "B.Mask" "B.Paste")
			(net "GND")
		)
		(zone
			(layer "B.Cu")
			(hatch none 0.5)
			(connect_pads
				(clearance 0)
			)
			(min_thickness 0.25)
			(keepout
				(tracks not_allowed)
				(vias allowed)
				(pads allowed)
				(copperpour not_allowed)
				(footprints allowed)
			)
			(placement
				(enabled no)
				(sheetname "")
			)
			(fill
				(thermal_gap 0.5)
				(thermal_bridge_width 0.5)
				(island_removal_mode 0)
			)
			(polygon
				(pts
					(xy 267.311886 -68.68414) (xy 268.581886 -68.68414) (xy 268.581886 -69.44614) (xy 267.311886 -69.44614)
				)
			)
		)
	)
	(footprint ""
		(layer "B.Cu")
		(at 110.007654 -77.82814)
		(property "Reference" "C7P9"
			(at 0 0 0)
			(layer "B.SilkS")
			(hide yes)
			(effects
				(font
					(size 1.27 1.27)
				)
				(justify mirror)
			)
		)
		(property "Value" ""
			(at 0 0 0)
			(layer "B.Fab")
			(effects
				(font
					(size 1.27 1.27)
				)
				(justify mirror)
			)
		)
		(duplicate_pad_numbers_are_jumpers no)
		(fp_poly
			(pts
				(xy 0.7239 -0.2159) (xy -0.7239 -0.2159) (xy -0.7239 1.9939) (xy 0.7239 1.9939)
			)
			(stroke
				(width 0)
				(type default)
			)
			(fill no)
			(layer "B.CrtYd")
		)
		(fp_line
			(start -0.7239 -0.2159)
			(end 0.7239 -0.2159)
			(stroke
				(width 0.1)
				(type default)
			)
			(layer "B.Fab")
		)
		(fp_line
			(start -0.7239 1.9939)
			(end -0.7239 -0.2159)
			(stroke
				(width 0.1)
				(type default)
			)
			(layer "B.Fab")
		)
		(fp_line
			(start 0.7239 -0.2159)
			(end 0.7239 1.9939)
			(stroke
				(width 0.1)
				(type default)
			)
			(layer "B.Fab")
		)
		(fp_line
			(start 0.7239 1.9939)
			(end -0.7239 1.9939)
			(stroke
				(width 0.1)
				(type default)
			)
			(layer "B.Fab")
		)
		(pad "1" smd rect
			(at 0 0 180)
			(size 1.27 1.016)
			(layers "B.Cu" "B.Mask" "B.Paste")
			(net "PVCCMCP_CPU1")
		)
		(pad "2" smd rect
			(at 0 1.778 180)
			(size 1.27 1.016)
			(layers "B.Cu" "B.Mask" "B.Paste")
			(net "GND")
		)
		(zone
			(layer "B.Cu")
			(hatch none 0.5)
			(connect_pads
				(clearance 0)
			)
			(min_thickness 0.25)
			(keepout
				(tracks not_allowed)
				(vias allowed)
				(pads allowed)
				(copperpour not_allowed)
				(footprints allowed)
			)
			(placement
				(enabled no)
				(sheetname "")
			)
			(fill
				(thermal_gap 0.5)
				(thermal_bridge_width 0.5)
				(island_removal_mode 0)
			)
			(polygon
				(pts
					(xy 110.642654 -77.32014) (xy 109.372654 -77.32014) (xy 109.372654 -76.55814) (xy 110.642654 -76.55814)
				)
			)
		)
	)
	(footprint ""
		(layer "B.Cu")
		(at 408.1272 -122.0216 90)
		(property "Reference" "FB2M2"
			(at 0 0 90)
			(layer "B.SilkS")
			(hide yes)
			(effects
				(font
					(size 1.27 1.27)
				)
				(justify mirror)
			)
		)
		(property "Value" ""
			(at 0 0 90)
			(layer "B.Fab")
			(effects
				(font
					(size 1.27 1.27)
				)
				(justify mirror)
			)
		)
		(duplicate_pad_numbers_are_jumpers no)
		(fp_poly
			(pts
				(xy 0.15113 -0.47498) (xy -1.59893 -0.47498) (xy -1.59893 0.47498) (xy 0.15113 0.47498)
			)
			(stroke
				(width 0)
				(type default)
			)
			(fill no)
			(layer "B.CrtYd")
		)
		(fp_line
			(start 0.15113 -0.47498)
			(end -1.59893 -0.47498)
			(stroke
				(width 0.1)
				(type default)
			)
			(layer "B.Fab")
		)
		(fp_line
			(start -1.59893 -0.47498)
			(end -1.59893 0.47498)
			(stroke
				(width 0.1)
				(type default)
			)
			(layer "B.Fab")
		)
		(fp_line
			(start 0.15113 0.47498)
			(end 0.15113 -0.47498)
			(stroke
				(width 0.1)
				(type default)
			)
			(layer "B.Fab")
		)
		(fp_line
			(start -1.59893 0.47498)
			(end 0.15113 0.47498)
			(stroke
				(width 0.1)
				(type default)
			)
			(layer "B.Fab")
		)
		(pad "1" smd rect
			(at 0 0 270)
			(size 0.9398 0.9398)
			(layers "B.Cu" "B.Mask" "B.Paste")
			(net "P1V05_PCH_STBY")
		)
		(pad "2" smd rect
			(at -1.4478 0 270)
			(size 0.9398 0.9398)
			(layers "B.Cu" "B.Mask" "B.Paste")
			(net "P1V05_PCH_STBY_WM26_PLL")
		)
		(zone
			(layer "B.Cu")
			(hatch none 0.5)
			(connect_pads
				(clearance 0)
			)
			(min_thickness 0.25)
			(keepout
				(tracks not_allowed)
				(vias allowed)
				(pads allowed)
				(copperpour not_allowed)
				(footprints allowed)
			)
			(placement
				(enabled no)
				(sheetname "")
			)
			(fill
				(thermal_gap 0.5)
				(thermal_bridge_width 0.5)
				(island_removal_mode 0)
			)
			(polygon
				(pts
					(xy 408.5971 -121.5517) (xy 407.6573 -121.5517) (xy 407.6573 -121.0437) (xy 408.5971 -121.0437)
				)
			)
		)
		(zone
			(layer "B.Cu")
			(hatch none 0.5)
			(connect_pads
				(clearance 0)
			)
			(min_thickness 0.25)
			(keepout
				(tracks allowed)
				(vias not_allowed)
				(pads allowed)
				(copperpour not_allowed)
				(footprints allowed)
			)
			(placement
				(enabled no)
				(sheetname "")
			)
			(fill
				(thermal_gap 0.5)
				(thermal_bridge_width 0.5)
				(island_removal_mode 0)
			)
			(polygon
				(pts
					(xy 408.5971 -121.5517) (xy 407.6573 -121.5517) (xy 407.6573 -121.0437) (xy 408.5971 -121.0437)
				)
			)
		)
	)
	(footprint ""
		(layer "B.Cu")
		(at 473.91574 -135.41756 90)
		(property "Reference" "R1W36"
			(at 0.8382 -0.67818 90)
			(unlocked yes)
			(layer "B.SilkS")
			(effects
				(font
					(size 0.4064 0.254)
					(thickness 0.1524)
				)
				(justify left mirror)
			)
		)
		(property "Value" ""
			(at 0 0 90)
			(layer "B.Fab")
			(effects
				(font
					(size 1.27 1.27)
				)
				(justify mirror)
			)
		)
		(duplicate_pad_numbers_are_jumpers no)
		(fp_poly
			(pts
				(xy 0.2794 -0.1016) (xy -0.2794 -0.1016) (xy -0.2794 0.9906) (xy 0.2794 0.9906)
			)
			(stroke
				(width 0)
				(type default)
			)
			(fill no)
			(layer "B.CrtYd")
		)
		(fp_line
			(start 0.2794 -0.1016)
			(end 0.2794 0.9906)
			(stroke
				(width 0.1)
				(type default)
			)
			(layer "B.Fab")
		)
		(fp_line
			(start -0.2794 -0.1016)
			(end 0.2794 -0.1016)
			(stroke
				(width 0.1)
				(type default)
			)
			(layer "B.Fab")
		)
		(fp_line
			(start 0.2794 0.9906)
			(end -0.2794 0.9906)
			(stroke
				(width 0.1)
				(type default)
			)
			(layer "B.Fab")
		)
		(fp_line
			(start -0.2794 0.9906)
			(end -0.2794 -0.1016)
			(stroke
				(width 0.1)
				(type default)
			)
			(layer "B.Fab")
		)
		(pad "1" smd rect
			(at 0 0 270)
			(size 0.508 0.508)
			(layers "B.Cu" "B.Mask" "B.Paste")
			(net "P3V3_STBY")
		)
		(pad "2" smd rect
			(at 0 0.889 270)
			(size 0.508 0.508)
			(layers "B.Cu" "B.Mask" "B.Paste")
			(net "SMB_DEBUG_STBY_LVC3_SCL_CONN")
		)
		(zone
			(layer "B.Cu")
			(hatch none 0.5)
			(connect_pads
				(clearance 0)
			)
			(min_thickness 0.25)
			(keepout
				(tracks allowed)
				(vias not_allowed)
				(pads allowed)
				(copperpour not_allowed)
				(footprints allowed)
			)
			(placement
				(enabled no)
				(sheetname "")
			)
			(fill
				(thermal_gap 0.5)
				(thermal_bridge_width 0.5)
				(island_removal_mode 0)
			)
			(polygon
				(pts
					(xy 474.16974 -135.67156) (xy 474.16974 -135.16356) (xy 474.55074 -135.16356) (xy 474.55074 -135.67156)
				)
			)
		)
		(zone
			(layer "B.Cu")
			(hatch none 0.5)
			(connect_pads
				(clearance 0)
			)
			(min_thickness 0.25)
			(keepout
				(tracks not_allowed)
				(vias allowed)
				(pads allowed)
				(copperpour not_allowed)
				(footprints allowed)
			)
			(placement
				(enabled no)
				(sheetname "")
			)
			(fill
				(thermal_gap 0.5)
				(thermal_bridge_width 0.5)
				(island_removal_mode 0)
			)
			(polygon
				(pts
					(xy 474.55074 -135.67156) (xy 474.55074 -135.16356) (xy 474.16974 -135.16356) (xy 474.16974 -135.67156)
				)
			)
		)
	)
	(footprint ""
		(layer "B.Cu")
		(at 474.938344 -4.82092 90)
		(property "Reference" "R2U38"
			(at 0 0 90)
			(layer "B.SilkS")
			(hide yes)
			(effects
				(font
					(size 1.27 1.27)
				)
				(justify mirror)
			)
		)
		(property "Value" ""
			(at 0 0 90)
			(layer "B.Fab")
			(effects
				(font
					(size 1.27 1.27)
				)
				(justify mirror)
			)
		)
		(duplicate_pad_numbers_are_jumpers no)
		(fp_poly
			(pts
				(xy 0.2794 -0.1016) (xy -0.2794 -0.1016) (xy -0.2794 0.9906) (xy 0.2794 0.9906)
			)
			(stroke
				(width 0)
				(type default)
			)
			(fill no)
			(layer "B.CrtYd")
		)
		(fp_line
			(start 0.2794 -0.1016)
			(end 0.2794 0.9906)
			(stroke
				(width 0.1)
				(type default)
			)
			(layer "B.Fab")
		)
		(fp_line
			(start -0.2794 -0.1016)
			(end 0.2794 -0.1016)
			(stroke
				(width 0.1)
				(type default)
			)
			(layer "B.Fab")
		)
		(fp_line
			(start 0.2794 0.9906)
			(end -0.2794 0.9906)
			(stroke
				(width 0.1)
				(type default)
			)
			(layer "B.Fab")
		)
		(fp_line
			(start -0.2794 0.9906)
			(end -0.2794 -0.1016)
			(stroke
				(width 0.1)
				(type default)
			)
			(layer "B.Fab")
		)
		(pad "1" smd rect
			(at 0 0 270)
			(size 0.508 0.508)
			(layers "B.Cu" "B.Mask" "B.Paste")
			(net "P3V3_STBY")
		)
		(pad "2" smd rect
			(at 0 0.889 270)
			(size 0.508 0.508)
			(layers "B.Cu" "B.Mask" "B.Paste")
			(net "SMB_SENSOR_STBY_LVC3_SCL")
		)
		(zone
			(layer "B.Cu")
			(hatch none 0.5)
			(connect_pads
				(clearance 0)
			)
			(min_thickness 0.25)
			(keepout
				(tracks allowed)
				(vias not_allowed)
				(pads allowed)
				(copperpour not_allowed)
				(footprints allowed)
			)
			(placement
				(enabled no)
				(sheetname "")
			)
			(fill
				(thermal_gap 0.5)
				(thermal_bridge_width 0.5)
				(island_removal_mode 0)
			)
			(polygon
				(pts
					(xy 475.192344 -5.07492) (xy 475.192344 -4.56692) (xy 475.573344 -4.56692) (xy 475.573344 -5.07492)
				)
			)
		)
		(zone
			(layer "B.Cu")
			(hatch none 0.5)
			(connect_pads
				(clearance 0)
			)
			(min_thickness 0.25)
			(keepout
				(tracks not_allowed)
				(vias allowed)
				(pads allowed)
				(copperpour not_allowed)
				(footprints allowed)
			)
			(placement
				(enabled no)
				(sheetname "")
			)
			(fill
				(thermal_gap 0.5)
				(thermal_bridge_width 0.5)
				(island_removal_mode 0)
			)
			(polygon
				(pts
					(xy 475.573344 -5.07492) (xy 475.573344 -4.56692) (xy 475.192344 -4.56692) (xy 475.192344 -5.07492)
				)
			)
		)
	)
	(footprint ""
		(layer "B.Cu")
		(at 373.8372 -46.0756 -90)
		(property "Reference" "R2T60"
			(at 0 0 90)
			(layer "B.SilkS")
			(hide yes)
			(effects
				(font
					(size 1.27 1.27)
				)
				(justify mirror)
			)
		)
		(property "Value" ""
			(at 0 0 90)
			(layer "B.Fab")
			(effects
				(font
					(size 1.27 1.27)
				)
				(justify mirror)
			)
		)
		(duplicate_pad_numbers_are_jumpers no)
		(fp_poly
			(pts
				(xy 0.2794 -0.1016) (xy -0.2794 -0.1016) (xy -0.2794 0.9906) (xy 0.2794 0.9906)
			)
			(stroke
				(width 0)
				(type default)
			)
			(fill no)
			(layer "B.CrtYd")
		)
		(fp_line
			(start -0.2794 0.9906)
			(end -0.2794 -0.1016)
			(stroke
				(width 0.1)
				(type default)
			)
			(layer "B.Fab")
		)
		(fp_line
			(start 0.2794 0.9906)
			(end -0.2794 0.9906)
			(stroke
				(width 0.1)
				(type default)
			)
			(layer "B.Fab")
		)
		(fp_line
			(start -0.2794 -0.1016)
			(end 0.2794 -0.1016)
			(stroke
				(width 0.1)
				(type default)
			)
			(layer "B.Fab")
		)
		(fp_line
			(start 0.2794 -0.1016)
			(end 0.2794 0.9906)
			(stroke
				(width 0.1)
				(type default)
			)
			(layer "B.Fab")
		)
		(pad "1" smd rect
			(at 0 0 90)
			(size 0.508 0.508)
			(layers "B.Cu" "B.Mask" "B.Paste")
			(net "H_CPU0_PROCHOT_G_N")
		)
		(pad "2" smd rect
			(at 0 0.889 90)
			(size 0.508 0.508)
			(layers "B.Cu" "B.Mask" "B.Paste")
			(net "H_CPU0_PROCHOT_G_R_N")
		)
		(zone
			(layer "B.Cu")
			(hatch none 0.5)
			(connect_pads
				(clearance 0)
			)
			(min_thickness 0.25)
			(keepout
				(tracks not_allowed)
				(vias allowed)
				(pads allowed)
				(copperpour not_allowed)
				(footprints allowed)
			)
			(placement
				(enabled no)
				(sheetname "")
			)
			(fill
				(thermal_gap 0.5)
				(thermal_bridge_width 0.5)
				(island_removal_mode 0)
			)
			(polygon
				(pts
					(xy 373.2022 -45.8216) (xy 373.2022 -46.3296) (xy 373.5832 -46.3296) (xy 373.5832 -45.8216)
				)
			)
		)
		(zone
			(layer "B.Cu")
			(hatch none 0.5)
			(connect_pads
				(clearance 0)
			)
			(min_thickness 0.25)
			(keepout
				(tracks allowed)
				(vias not_allowed)
				(pads allowed)
				(copperpour not_allowed)
				(footprints allowed)
			)
			(placement
				(enabled no)
				(sheetname "")
			)
			(fill
				(thermal_gap 0.5)
				(thermal_bridge_width 0.5)
				(island_removal_mode 0)
			)
			(polygon
				(pts
					(xy 373.5832 -45.8216) (xy 373.5832 -46.3296) (xy 373.2022 -46.3296) (xy 373.2022 -45.8216)
				)
			)
		)
	)
	(footprint ""
		(layer "B.Cu")
		(at 29.699458 -132.876036 90)
		(property "Reference" "J9M1"
			(at 2.352548 37.991542 0)
			(unlocked yes)
			(layer "B.SilkS")
			(effects
				(font
					(size 0.7874 0.5842)
					(thickness 0.1524)
				)
				(justify left mirror)
			)
		)
		(property "Value" ""
			(at 0 0 90)
			(layer "B.Fab")
			(effects
				(font
					(size 1.27 1.27)
				)
				(justify mirror)
			)
		)
		(duplicate_pad_numbers_are_jumpers no)
		(fp_line
			(start 0.94996 -7.675118)
			(end -5.5499 -7.675118)
			(stroke
				(width 0.1524)
				(type default)
			)
			(layer "B.SilkS")
		)
		(fp_line
			(start -5.5499 -7.675118)
			(end -5.5499 -1.480058)
			(stroke
				(width 0.1524)
				(type default)
			)
			(layer "B.SilkS")
		)
		(fp_line
			(start 0.94996 -1.480058)
			(end 0.94996 -7.675118)
			(stroke
				(width 0.1524)
				(type default)
			)
			(layer "B.SilkS")
		)
		(fp_line
			(start -5.5499 128.130046)
			(end -5.5499 134.325106)
			(stroke
				(width 0.1524)
				(type default)
			)
			(layer "B.SilkS")
		)
		(fp_line
			(start 0.94996 134.325106)
			(end 0.94996 128.130046)
			(stroke
				(width 0.1524)
				(type default)
			)
			(layer "B.SilkS")
		)
		(fp_line
			(start -5.5499 134.325106)
			(end 0.94996 134.325106)
			(stroke
				(width 0.1524)
				(type default)
			)
			(layer "B.SilkS")
		)
		(fp_poly
			(pts
				(xy 2.99212 -4.10845) (xy 2.99212 -3.09245) (xy 1.72212 -3.60045)
			)
			(stroke
				(width 0)
				(type default)
			)
			(fill yes)
			(layer "B.SilkS")
		)
		(fp_poly
			(pts
				(xy 0.94996 -7.675118) (xy 0.94996 134.325106) (xy -5.5499 134.325106) (xy -5.5499 -7.675118)
			)
			(stroke
				(width 0)
				(type default)
			)
			(fill no)
			(layer "B.CrtYd")
		)
		(fp_line
			(start 0.94996 -7.675118)
			(end -5.5499 -7.675118)
			(stroke
				(width 0.1)
				(type default)
			)
			(layer "B.Fab")
		)
		(fp_line
			(start -5.5499 -7.675118)
			(end -5.5499 134.325106)
			(stroke
				(width 0.1)
				(type default)
			)
			(layer "B.Fab")
		)
		(fp_line
			(start 0.94996 134.325106)
			(end 0.94996 -7.675118)
			(stroke
				(width 0.1)
				(type default)
			)
			(layer "B.Fab")
		)
		(fp_line
			(start -5.5499 134.325106)
			(end 0.94996 134.325106)
			(stroke
				(width 0.1)
				(type default)
			)
			(layer "B.Fab")
		)
		(fp_poly
			(pts
				(xy 2.984246 -0.461264) (xy 2.984246 0.554736) (xy 1.714246 0.046736)
			)
			(stroke
				(width 0)
				(type default)
			)
			(fill yes)
			(layer "B.Fab")
		)
		(fp_text user "145"
			(at -6.156452 0.780542 0)
			(unlocked yes)
			(layer "B.SilkS")
			(effects
				(font
					(size 0.7874 0.5842)
					(thickness 0.1524)
				)
				(justify left mirror)
			)
		)
		(fp_text user "221"
			(at -6.546088 62.947042 0)
			(unlocked yes)
			(layer "B.SilkS")
			(effects
				(font
					(size 0.7874 0.5842)
					(thickness 0.1524)
				)
				(justify left mirror)
			)
		)
		(fp_text user "77"
			(at 1.082548 66.439542 0)
			(unlocked yes)
			(layer "B.SilkS")
			(effects
				(font
					(size 0.7874 0.5842)
					(thickness 0.1524)
				)
				(justify left mirror)
			)
		)
		(fp_text user "222"
			(at -6.156452 70.884542 0)
			(unlocked yes)
			(layer "B.SilkS")
			(effects
				(font
					(size 0.7874 0.5842)
					(thickness 0.1524)
				)
				(justify left mirror)
			)
		)
		(fp_text user "78"
			(at 1.463548 71.265542 0)
			(unlocked yes)
			(layer "B.SilkS")
			(effects
				(font
					(size 0.7874 0.5842)
					(thickness 0.1524)
				)
				(justify left mirror)
			)
		)
		(fp_text user "288"
			(at -6.283452 129.812542 0)
			(unlocked yes)
			(layer "B.SilkS")
			(effects
				(font
					(size 0.7874 0.5842)
					(thickness 0.1524)
				)
				(justify left mirror)
			)
		)
		(fp_text user "144"
			(at -2.600452 136.924542 0)
			(unlocked yes)
			(layer "B.SilkS")
			(effects
				(font
					(size 0.7874 0.5842)
					(thickness 0.1524)
				)
				(justify left mirror)
			)
		)
		(fp_text user "145"
			(at -3.335782 -0.843788 90)
			(unlocked yes)
			(layer "B.Fab")
			(effects
				(font
					(size 0.7874 0.5842)
					(thickness 0.1524)
				)
				(justify left mirror)
			)
		)
		(fp_text user "77"
			(at 0.474218 65.831212 90)
			(unlocked yes)
			(layer "B.Fab")
			(effects
				(font
					(size 0.7874 0.5842)
					(thickness 0.1524)
				)
				(justify left mirror)
			)
		)
		(fp_text user "221"
			(at -3.335782 65.831212 90)
			(unlocked yes)
			(layer "B.Fab")
			(effects
				(font
					(size 0.7874 0.5842)
					(thickness 0.1524)
				)
				(justify left mirror)
			)
		)
		(fp_text user "222"
			(at -3.335782 69.006212 90)
			(unlocked yes)
			(layer "B.Fab")
			(effects
				(font
					(size 0.7874 0.5842)
					(thickness 0.1524)
				)
				(justify left mirror)
			)
		)
		(fp_text user "78"
			(at 0.474218 69.641212 90)
			(unlocked yes)
			(layer "B.Fab")
			(effects
				(font
					(size 0.7874 0.5842)
					(thickness 0.1524)
				)
				(justify left mirror)
			)
		)
		(fp_text user "144"
			(at 0.474218 128.061212 90)
			(unlocked yes)
			(layer "B.Fab")
			(effects
				(font
					(size 0.7874 0.5842)
					(thickness 0.1524)
				)
				(justify left mirror)
			)
		)
		(fp_text user "288"
			(at -2.700782 128.061212 90)
			(unlocked yes)
			(layer "B.Fab")
			(effects
				(font
					(size 0.7874 0.5842)
					(thickness 0.1524)
				)
				(justify left mirror)
			)
		)
		(pad "" thru_hole circle
			(at -2.29997 -5.649976 270)
			(size 2.8194 2.8194)
			(drill 2.4384)
			(layers "*.Cu" "*.Mask")
			(remove_unused_layers no)
			(clearance 0.127)
			(thermal_gap 0.127)
		)
		(pad "" thru_hole oval
			(at -2.29997 68.90004 270)
			(size 2.8194 1.5748)
			(drill oval 2.4384 1.1938)
			(layers "*.Cu" "*.Mask")
			(remove_unused_layers no)
			(clearance 0.127)
			(thermal_gap 0.127)
		)
		(pad "" thru_hole circle
			(at -2.29997 132.299964 270)
			(size 2.8194 2.8194)
			(drill 2.4384)
			(layers "*.Cu" "*.Mask")
			(remove_unused_layers no)
			(clearance 0.127)
			(thermal_gap 0.127)
		)
		(pad "1" smd rect
			(at 0 0 270)
			(size 1.8034 0.508)
			(layers "B.Cu" "B.Mask" "B.Paste")
			(net "P12V_NVDIMM_KLM")
		)
		(pad "2" smd rect
			(at 0 0.849884 270)
			(size 1.8034 0.508)
			(layers "B.Cu" "B.Mask" "B.Paste")
			(net "GND")
		)
		(pad "3" smd rect
			(at 0 1.700022 270)
			(size 1.8034 0.508)
			(layers "B.Cu" "B.Mask" "B.Paste")
			(net "M_K_DQ<4>")
		)
		(pad "4" smd rect
			(at 0 2.549906 270)
			(size 1.8034 0.508)
			(layers "B.Cu" "B.Mask" "B.Paste")
			(net "GND")
		)
		(pad "5" smd rect
			(at 0 3.400044 270)
			(size 1.8034 0.508)
			(layers "B.Cu" "B.Mask" "B.Paste")
			(net "M_K_DQ<0>")
		)
		(pad "6" smd rect
			(at 0 4.249928 270)
			(size 1.8034 0.508)
			(layers "B.Cu" "B.Mask" "B.Paste")
			(net "GND")
		)
		(pad "7" smd rect
			(at 0 5.100066 270)
			(size 1.8034 0.508)
			(layers "B.Cu" "B.Mask" "B.Paste")
			(net "M_K_DQS_DP<9>")
		)
		(pad "8" smd rect
			(at 0 5.94995 270)
			(size 1.8034 0.508)
			(layers "B.Cu" "B.Mask" "B.Paste")
			(net "M_K_DQS_DN<9>")
		)
		(pad "9" smd rect
			(at 0 6.800088 270)
			(size 1.8034 0.508)
			(layers "B.Cu" "B.Mask" "B.Paste")
			(net "GND")
		)
		(pad "10" smd rect
			(at 0 7.649972 270)
			(size 1.8034 0.508)
			(layers "B.Cu" "B.Mask" "B.Paste")
			(net "M_K_DQ<6>")
		)
		(pad "11" smd rect
			(at 0 8.50011 270)
			(size 1.8034 0.508)
			(layers "B.Cu" "B.Mask" "B.Paste")
			(net "GND")
		)
		(pad "12" smd rect
			(at 0 9.349994 270)
			(size 1.8034 0.508)
			(layers "B.Cu" "B.Mask" "B.Paste")
			(net "M_K_DQ<2>")
		)
		(pad "13" smd rect
			(at 0 10.199878 270)
			(size 1.8034 0.508)
			(layers "B.Cu" "B.Mask" "B.Paste")
			(net "GND")
		)
		(pad "14" smd rect
			(at 0 11.050016 270)
			(size 1.8034 0.508)
			(layers "B.Cu" "B.Mask" "B.Paste")
			(net "M_K_DQ<12>")
		)
		(pad "15" smd rect
			(at 0 11.8999 270)
			(size 1.8034 0.508)
			(layers "B.Cu" "B.Mask" "B.Paste")
			(net "GND")
		)
		(pad "16" smd rect
			(at 0 12.750038 270)
			(size 1.8034 0.508)
			(layers "B.Cu" "B.Mask" "B.Paste")
			(net "M_K_DQ<8>")
		)
		(pad "17" smd rect
			(at 0 13.599922 270)
			(size 1.8034 0.508)
			(layers "B.Cu" "B.Mask" "B.Paste")
			(net "GND")
		)
		(pad "18" smd rect
			(at 0 14.45006 270)
			(size 1.8034 0.508)
			(layers "B.Cu" "B.Mask" "B.Paste")
			(net "M_K_DQS_DP<10>")
		)
		(pad "19" smd rect
			(at 0 15.299944 270)
			(size 1.8034 0.508)
			(layers "B.Cu" "B.Mask" "B.Paste")
			(net "M_K_DQS_DN<10>")
		)
		(pad "20" smd rect
			(at 0 16.150082 270)
			(size 1.8034 0.508)
			(layers "B.Cu" "B.Mask" "B.Paste")
			(net "GND")
		)
		(pad "21" smd rect
			(at 0 16.999966 270)
			(size 1.8034 0.508)
			(layers "B.Cu" "B.Mask" "B.Paste")
			(net "M_K_DQ<14>")
		)
		(pad "22" smd rect
			(at 0 17.850104 270)
			(size 1.8034 0.508)
			(layers "B.Cu" "B.Mask" "B.Paste")
			(net "GND")
		)
		(pad "23" smd rect
			(at 0 18.699988 270)
			(size 1.8034 0.508)
			(layers "B.Cu" "B.Mask" "B.Paste")
			(net "M_K_DQ<10>")
		)
		(pad "24" smd rect
			(at 0 19.550126 270)
			(size 1.8034 0.508)
			(layers "B.Cu" "B.Mask" "B.Paste")
			(net "GND")
		)
		(pad "25" smd rect
			(at 0 20.40001 270)
			(size 1.8034 0.508)
			(layers "B.Cu" "B.Mask" "B.Paste")
			(net "M_K_DQ<20>")
		)
		(pad "26" smd rect
			(at 0 21.249894 270)
			(size 1.8034 0.508)
			(layers "B.Cu" "B.Mask" "B.Paste")
			(net "GND")
		)
		(pad "27" smd rect
			(at 0 22.100032 270)
			(size 1.8034 0.508)
			(layers "B.Cu" "B.Mask" "B.Paste")
			(net "M_K_DQ<16>")
		)
		(pad "28" smd rect
			(at 0 22.949916 270)
			(size 1.8034 0.508)
			(layers "B.Cu" "B.Mask" "B.Paste")
			(net "GND")
		)
		(pad "29" smd rect
			(at 0 23.800054 270)
			(size 1.8034 0.508)
			(layers "B.Cu" "B.Mask" "B.Paste")
			(net "M_K_DQS_DP<11>")
		)
		(pad "30" smd rect
			(at 0 24.649938 270)
			(size 1.8034 0.508)
			(layers "B.Cu" "B.Mask" "B.Paste")
			(net "M_K_DQS_DN<11>")
		)
		(pad "31" smd rect
			(at 0 25.500076 270)
			(size 1.8034 0.508)
			(layers "B.Cu" "B.Mask" "B.Paste")
			(net "GND")
		)
		(pad "32" smd rect
			(at 0 26.34996 270)
			(size 1.8034 0.508)
			(layers "B.Cu" "B.Mask" "B.Paste")
			(net "M_K_DQ<22>")
		)
		(pad "33" smd rect
			(at 0 27.200098 270)
			(size 1.8034 0.508)
			(layers "B.Cu" "B.Mask" "B.Paste")
			(net "GND")
		)
		(pad "34" smd rect
			(at 0 28.049982 270)
			(size 1.8034 0.508)
			(layers "B.Cu" "B.Mask" "B.Paste")
			(net "M_K_DQ<18>")
		)
		(pad "35" smd rect
			(at 0 28.90012 270)
			(size 1.8034 0.508)
			(layers "B.Cu" "B.Mask" "B.Paste")
			(net "GND")
		)
		(pad "36" smd rect
			(at 0 29.750004 270)
			(size 1.8034 0.508)
			(layers "B.Cu" "B.Mask" "B.Paste")
			(net "M_K_DQ<28>")
		)
		(pad "37" smd rect
			(at 0 30.599888 270)
			(size 1.8034 0.508)
			(layers "B.Cu" "B.Mask" "B.Paste")
			(net "GND")
		)
		(pad "38" smd rect
			(at 0 31.450026 270)
			(size 1.8034 0.508)
			(layers "B.Cu" "B.Mask" "B.Paste")
			(net "M_K_DQ<24>")
		)
		(pad "39" smd rect
			(at 0 32.29991 270)
			(size 1.8034 0.508)
			(layers "B.Cu" "B.Mask" "B.Paste")
			(net "GND")
		)
		(pad "40" smd rect
			(at 0 33.150048 270)
			(size 1.8034 0.508)
			(layers "B.Cu" "B.Mask" "B.Paste")
			(net "M_K_DQS_DP<12>")
		)
		(pad "41" smd rect
			(at 0 33.999932 270)
			(size 1.8034 0.508)
			(layers "B.Cu" "B.Mask" "B.Paste")
			(net "M_K_DQS_DN<12>")
		)
		(pad "42" smd rect
			(at 0 34.85007 270)
			(size 1.8034 0.508)
			(layers "B.Cu" "B.Mask" "B.Paste")
			(net "GND")
		)
		(pad "43" smd rect
			(at 0 35.699954 270)
			(size 1.8034 0.508)
			(layers "B.Cu" "B.Mask" "B.Paste")
			(net "M_K_DQ<30>")
		)
		(pad "44" smd rect
			(at 0 36.550092 270)
			(size 1.8034 0.508)
			(layers "B.Cu" "B.Mask" "B.Paste")
			(net "GND")
		)
		(pad "45" smd rect
			(at 0 37.399976 270)
			(size 1.8034 0.508)
			(layers "B.Cu" "B.Mask" "B.Paste")
			(net "M_K_DQ<26>")
		)
		(pad "46" smd rect
			(at 0 38.250114 270)
			(size 1.8034 0.508)
			(layers "B.Cu" "B.Mask" "B.Paste")
			(net "GND")
		)
		(pad "47" smd rect
			(at 0 39.099998 270)
			(size 1.8034 0.508)
			(layers "B.Cu" "B.Mask" "B.Paste")
			(net "M_K_ECC<4>")
		)
		(pad "48" smd rect
			(at 0 39.949882 270)
			(size 1.8034 0.508)
			(layers "B.Cu" "B.Mask" "B.Paste")
			(net "GND")
		)
		(pad "49" smd rect
			(at 0 40.80002 270)
			(size 1.8034 0.508)
			(layers "B.Cu" "B.Mask" "B.Paste")
			(net "M_K_ECC<0>")
		)
		(pad "50" smd rect
			(at 0 41.649904 270)
			(size 1.8034 0.508)
			(layers "B.Cu" "B.Mask" "B.Paste")
			(net "GND")
		)
		(pad "51" smd rect
			(at 0 42.500042 270)
			(size 1.8034 0.508)
			(layers "B.Cu" "B.Mask" "B.Paste")
			(net "M_K_DQS_DP<17>")
		)
		(pad "52" smd rect
			(at 0 43.349926 270)
			(size 1.8034 0.508)
			(layers "B.Cu" "B.Mask" "B.Paste")
			(net "M_K_DQS_DN<17>")
		)
		(pad "53" smd rect
			(at 0 44.200064 270)
			(size 1.8034 0.508)
			(layers "B.Cu" "B.Mask" "B.Paste")
			(net "GND")
		)
		(pad "54" smd rect
			(at 0 45.049948 270)
			(size 1.8034 0.508)
			(layers "B.Cu" "B.Mask" "B.Paste")
			(net "M_K_ECC<6>")
		)
		(pad "55" smd rect
			(at 0 45.900086 270)
			(size 1.8034 0.508)
			(layers "B.Cu" "B.Mask" "B.Paste")
			(net "GND")
		)
		(pad "56" smd rect
			(at 0 46.74997 270)
			(size 1.8034 0.508)
			(layers "B.Cu" "B.Mask" "B.Paste")
			(net "M_K_ECC<2>")
		)
		(pad "57" smd rect
			(at 0 47.600108 270)
			(size 1.8034 0.508)
			(layers "B.Cu" "B.Mask" "B.Paste")
			(net "GND")
		)
		(pad "58" smd rect
			(at 0 48.449992 270)
			(size 1.8034 0.508)
			(layers "B.Cu" "B.Mask" "B.Paste")
			(net "M_KLM_RST_N")
		)
		(pad "59" smd rect
			(at 0 49.299876 270)
			(size 1.8034 0.508)
			(layers "B.Cu" "B.Mask" "B.Paste")
			(net "PVDDQ_KLM")
		)
		(pad "60" smd rect
			(at 0 50.150014 270)
			(size 1.8034 0.508)
			(layers "B.Cu" "B.Mask" "B.Paste")
			(net "M_K_CKE<2>")
		)
		(pad "61" smd rect
			(at 0 50.999898 270)
			(size 1.8034 0.508)
			(layers "B.Cu" "B.Mask" "B.Paste")
			(net "PVDDQ_KLM")
		)
		(pad "62" smd rect
			(at 0 51.850036 270)
			(size 1.8034 0.508)
			(layers "B.Cu" "B.Mask" "B.Paste")
			(net "M_K_ACT_N")
		)
		(pad "63" smd rect
			(at 0 52.69992 270)
			(size 1.8034 0.508)
			(layers "B.Cu" "B.Mask" "B.Paste")
			(net "M_K_BG<0>")
		)
		(pad "64" smd rect
			(at 0 53.550058 270)
			(size 1.8034 0.508)
			(layers "B.Cu" "B.Mask" "B.Paste")
			(net "PVDDQ_KLM")
		)
		(pad "65" smd rect
			(at 0 54.399942 270)
			(size 1.8034 0.508)
			(layers "B.Cu" "B.Mask" "B.Paste")
			(net "M_K_MA<12>")
		)
		(pad "66" smd rect
			(at 0 55.25008 270)
			(size 1.8034 0.508)
			(layers "B.Cu" "B.Mask" "B.Paste")
			(net "M_K_MA<9>")
		)
		(pad "67" smd rect
			(at 0 56.099964 270)
			(size 1.8034 0.508)
			(layers "B.Cu" "B.Mask" "B.Paste")
			(net "PVDDQ_KLM")
		)
		(pad "68" smd rect
			(at 0 56.950102 270)
			(size 1.8034 0.508)
			(layers "B.Cu" "B.Mask" "B.Paste")
			(net "M_K_MA<8>")
		)
		(pad "69" smd rect
			(at 0 57.799986 270)
			(size 1.8034 0.508)
			(layers "B.Cu" "B.Mask" "B.Paste")
			(net "M_K_MA<6>")
		)
		(pad "70" smd rect
			(at 0 58.650124 270)
			(size 1.8034 0.508)
			(layers "B.Cu" "B.Mask" "B.Paste")
			(net "PVDDQ_KLM")
		)
		(pad "71" smd rect
			(at 0 59.500008 270)
			(size 1.8034 0.508)
			(layers "B.Cu" "B.Mask" "B.Paste")
			(net "M_K_MA<3>")
		)
		(pad "72" smd rect
			(at 0 60.349892 270)
			(size 1.8034 0.508)
			(layers "B.Cu" "B.Mask" "B.Paste")
			(net "M_K_MA<1>")
		)
		(pad "73" smd rect
			(at 0 61.20003 270)
			(size 1.8034 0.508)
			(layers "B.Cu" "B.Mask" "B.Paste")
			(net "PVDDQ_KLM")
		)
		(pad "74" smd rect
			(at 0 62.049914 270)
			(size 1.8034 0.508)
			(layers "B.Cu" "B.Mask" "B.Paste")
			(net "M_K_CLK_DP<2>")
		)
		(pad "75" smd rect
			(at 0 62.900052 270)
			(size 1.8034 0.508)
			(layers "B.Cu" "B.Mask" "B.Paste")
			(net "M_K_CLK_DN<2>")
		)
		(pad "76" smd rect
			(at 0 63.749936 270)
			(size 1.8034 0.508)
			(layers "B.Cu" "B.Mask" "B.Paste")
			(net "PVDDQ_KLM")
		)
		(pad "77" smd rect
			(at 0 64.600074 270)
			(size 1.8034 0.508)
			(layers "B.Cu" "B.Mask" "B.Paste")
			(net "PVTT_KLM")
		)
		(pad "78" smd rect
			(at 0 70.550024 270)
			(size 1.8034 0.508)
			(layers "B.Cu" "B.Mask" "B.Paste")
			(net "FM_DIMM_EVENT_COD_N")
		)
		(pad "79" smd rect
			(at 0 71.399908 270)
			(size 1.8034 0.508)
			(layers "B.Cu" "B.Mask" "B.Paste")
			(net "M_K_MA<0>")
		)
		(pad "80" smd rect
			(at 0 72.250046 270)
			(size 1.8034 0.508)
			(layers "B.Cu" "B.Mask" "B.Paste")
			(net "PVDDQ_KLM")
		)
		(pad "81" smd rect
			(at 0 73.09993 270)
			(size 1.8034 0.508)
			(layers "B.Cu" "B.Mask" "B.Paste")
			(net "M_K_BA<0>")
		)
		(pad "82" smd rect
			(at 0 73.950068 270)
			(size 1.8034 0.508)
			(layers "B.Cu" "B.Mask" "B.Paste")
			(net "M_K_MA<16>")
		)
		(pad "83" smd rect
			(at 0 74.799952 270)
			(size 1.8034 0.508)
			(layers "B.Cu" "B.Mask" "B.Paste")
			(net "PVDDQ_KLM")
		)
		(pad "84" smd rect
			(at 0 75.65009 270)
			(size 1.8034 0.508)
			(layers "B.Cu" "B.Mask" "B.Paste")
			(net "M_K_CS_N<4>")
		)
		(pad "85" smd rect
			(at 0 76.499974 270)
			(size 1.8034 0.508)
			(layers "B.Cu" "B.Mask" "B.Paste")
			(net "PVDDQ_KLM")
		)
		(pad "86" smd rect
			(at 0 77.350112 270)
			(size 1.8034 0.508)
			(layers "B.Cu" "B.Mask" "B.Paste")
			(net "M_K_MA<15>")
		)
		(pad "87" smd rect
			(at 0 78.199996 270)
			(size 1.8034 0.508)
			(layers "B.Cu" "B.Mask" "B.Paste")
			(net "M_K_ODT<2>")
		)
		(pad "88" smd rect
			(at 0 79.04988 270)
			(size 1.8034 0.508)
			(layers "B.Cu" "B.Mask" "B.Paste")
			(net "PVDDQ_KLM")
		)
		(pad "89" smd rect
			(at 0 79.900018 270)
			(size 1.8034 0.508)
			(layers "B.Cu" "B.Mask" "B.Paste")
			(net "M_K_CS_N<5>")
		)
		(pad "90" smd rect
			(at 0 80.749902 270)
			(size 1.8034 0.508)
			(layers "B.Cu" "B.Mask" "B.Paste")
			(net "PVDDQ_KLM")
		)
		(pad "91" smd rect
			(at 0 81.60004 270)
			(size 1.8034 0.508)
			(layers "B.Cu" "B.Mask" "B.Paste")
			(net "M_K_ODT<3>")
		)
		(pad "92" smd rect
			(at 0 82.449924 270)
			(size 1.8034 0.508)
			(layers "B.Cu" "B.Mask" "B.Paste")
			(net "PVDDQ_KLM")
		)
		(pad "93" smd rect
			(at 0 83.300062 270)
			(size 1.8034 0.508)
			(layers "B.Cu" "B.Mask" "B.Paste")
			(net "M_K_CS_N<6>")
		)
		(pad "94" smd rect
			(at 0 84.149946 270)
			(size 1.8034 0.508)
			(layers "B.Cu" "B.Mask" "B.Paste")
			(net "GND")
		)
		(pad "95" smd rect
			(at 0 85.000084 270)
			(size 1.8034 0.508)
			(layers "B.Cu" "B.Mask" "B.Paste")
			(net "M_K_DQ<36>")
		)
		(pad "96" smd rect
			(at 0 85.849968 270)
			(size 1.8034 0.508)
			(layers "B.Cu" "B.Mask" "B.Paste")
			(net "GND")
		)
		(pad "97" smd rect
			(at 0 86.700106 270)
			(size 1.8034 0.508)
			(layers "B.Cu" "B.Mask" "B.Paste")
			(net "M_K_DQ<32>")
		)
		(pad "98" smd rect
			(at 0 87.54999 270)
			(size 1.8034 0.508)
			(layers "B.Cu" "B.Mask" "B.Paste")
			(net "GND")
		)
		(pad "99" smd rect
			(at 0 88.399874 270)
			(size 1.8034 0.508)
			(layers "B.Cu" "B.Mask" "B.Paste")
			(net "M_K_DQS_DP<13>")
		)
		(pad "100" smd rect
			(at 0 89.250012 270)
			(size 1.8034 0.508)
			(layers "B.Cu" "B.Mask" "B.Paste")
			(net "M_K_DQS_DN<13>")
		)
		(pad "101" smd rect
			(at 0 90.099896 270)
			(size 1.8034 0.508)
			(layers "B.Cu" "B.Mask" "B.Paste")
			(net "GND")
		)
		(pad "102" smd rect
			(at 0 90.950034 270)
			(size 1.8034 0.508)
			(layers "B.Cu" "B.Mask" "B.Paste")
			(net "M_K_DQ<38>")
		)
		(pad "103" smd rect
			(at 0 91.799918 270)
			(size 1.8034 0.508)
			(layers "B.Cu" "B.Mask" "B.Paste")
			(net "GND")
		)
		(pad "104" smd rect
			(at 0 92.650056 270)
			(size 1.8034 0.508)
			(layers "B.Cu" "B.Mask" "B.Paste")
			(net "M_K_DQ<34>")
		)
		(pad "105" smd rect
			(at 0 93.49994 270)
			(size 1.8034 0.508)
			(layers "B.Cu" "B.Mask" "B.Paste")
			(net "GND")
		)
		(pad "106" smd rect
			(at 0 94.350078 270)
			(size 1.8034 0.508)
			(layers "B.Cu" "B.Mask" "B.Paste")
			(net "M_K_DQ<44>")
		)
		(pad "107" smd rect
			(at 0 95.199962 270)
			(size 1.8034 0.508)
			(layers "B.Cu" "B.Mask" "B.Paste")
			(net "GND")
		)
		(pad "108" smd rect
			(at 0 96.0501 270)
			(size 1.8034 0.508)
			(layers "B.Cu" "B.Mask" "B.Paste")
			(net "M_K_DQ<40>")
		)
		(pad "109" smd rect
			(at 0 96.899984 270)
			(size 1.8034 0.508)
			(layers "B.Cu" "B.Mask" "B.Paste")
			(net "GND")
		)
		(pad "110" smd rect
			(at 0 97.750122 270)
			(size 1.8034 0.508)
			(layers "B.Cu" "B.Mask" "B.Paste")
			(net "M_K_DQS_DP<14>")
		)
		(pad "111" smd rect
			(at 0 98.600006 270)
			(size 1.8034 0.508)
			(layers "B.Cu" "B.Mask" "B.Paste")
			(net "M_K_DQS_DN<14>")
		)
		(pad "112" smd rect
			(at 0 99.44989 270)
			(size 1.8034 0.508)
			(layers "B.Cu" "B.Mask" "B.Paste")
			(net "GND")
		)
		(pad "113" smd rect
			(at 0 100.300028 270)
			(size 1.8034 0.508)
			(layers "B.Cu" "B.Mask" "B.Paste")
			(net "M_K_DQ<46>")
		)
		(pad "114" smd rect
			(at 0 101.149912 270)
			(size 1.8034 0.508)
			(layers "B.Cu" "B.Mask" "B.Paste")
			(net "GND")
		)
		(pad "115" smd rect
			(at 0 102.00005 270)
			(size 1.8034 0.508)
			(layers "B.Cu" "B.Mask" "B.Paste")
			(net "M_K_DQ<42>")
		)
		(pad "116" smd rect
			(at 0 102.849934 270)
			(size 1.8034 0.508)
			(layers "B.Cu" "B.Mask" "B.Paste")
			(net "GND")
		)
		(pad "117" smd rect
			(at 0 103.700072 270)
			(size 1.8034 0.508)
			(layers "B.Cu" "B.Mask" "B.Paste")
			(net "M_K_DQ<52>")
		)
		(pad "118" smd rect
			(at 0 104.549956 270)
			(size 1.8034 0.508)
			(layers "B.Cu" "B.Mask" "B.Paste")
			(net "GND")
		)
		(pad "119" smd rect
			(at 0 105.400094 270)
			(size 1.8034 0.508)
			(layers "B.Cu" "B.Mask" "B.Paste")
			(net "M_K_DQ<48>")
		)
		(pad "120" smd rect
			(at 0 106.249978 270)
			(size 1.8034 0.508)
			(layers "B.Cu" "B.Mask" "B.Paste")
			(net "GND")
		)
		(pad "121" smd rect
			(at 0 107.100116 270)
			(size 1.8034 0.508)
			(layers "B.Cu" "B.Mask" "B.Paste")
			(net "M_K_DQS_DP<15>")
		)
		(pad "122" smd rect
			(at 0 107.95 270)
			(size 1.8034 0.508)
			(layers "B.Cu" "B.Mask" "B.Paste")
			(net "M_K_DQS_DN<15>")
		)
		(pad "123" smd rect
			(at 0 108.799884 270)
			(size 1.8034 0.508)
			(layers "B.Cu" "B.Mask" "B.Paste")
			(net "GND")
		)
		(pad "124" smd rect
			(at 0 109.650022 270)
			(size 1.8034 0.508)
			(layers "B.Cu" "B.Mask" "B.Paste")
			(net "M_K_DQ<54>")
		)
		(pad "125" smd rect
			(at 0 110.499906 270)
			(size 1.8034 0.508)
			(layers "B.Cu" "B.Mask" "B.Paste")
			(net "GND")
		)
		(pad "126" smd rect
			(at 0 111.350044 270)
			(size 1.8034 0.508)
			(layers "B.Cu" "B.Mask" "B.Paste")
			(net "M_K_DQ<50>")
		)
		(pad "127" smd rect
			(at 0 112.199928 270)
			(size 1.8034 0.508)
			(layers "B.Cu" "B.Mask" "B.Paste")
			(net "GND")
		)
		(pad "128" smd rect
			(at 0 113.050066 270)
			(size 1.8034 0.508)
			(layers "B.Cu" "B.Mask" "B.Paste")
			(net "M_K_DQ<60>")
		)
		(pad "129" smd rect
			(at 0 113.89995 270)
			(size 1.8034 0.508)
			(layers "B.Cu" "B.Mask" "B.Paste")
			(net "GND")
		)
		(pad "130" smd rect
			(at 0 114.750088 270)
			(size 1.8034 0.508)
			(layers "B.Cu" "B.Mask" "B.Paste")
			(net "M_K_DQ<56>")
		)
		(pad "131" smd rect
			(at 0 115.599972 270)
			(size 1.8034 0.508)
			(layers "B.Cu" "B.Mask" "B.Paste")
			(net "GND")
		)
		(pad "132" smd rect
			(at 0 116.45011 270)
			(size 1.8034 0.508)
			(layers "B.Cu" "B.Mask" "B.Paste")
			(net "M_K_DQS_DP<16>")
		)
		(pad "133" smd rect
			(at 0 117.299994 270)
			(size 1.8034 0.508)
			(layers "B.Cu" "B.Mask" "B.Paste")
			(net "M_K_DQS_DN<16>")
		)
		(pad "134" smd rect
			(at 0 118.149878 270)
			(size 1.8034 0.508)
			(layers "B.Cu" "B.Mask" "B.Paste")
			(net "GND")
		)
		(pad "135" smd rect
			(at 0 119.000016 270)
			(size 1.8034 0.508)
			(layers "B.Cu" "B.Mask" "B.Paste")
			(net "M_K_DQ<62>")
		)
		(pad "136" smd rect
			(at 0 119.8499 270)
			(size 1.8034 0.508)
			(layers "B.Cu" "B.Mask" "B.Paste")
			(net "GND")
		)
		(pad "137" smd rect
			(at 0 120.700038 270)
			(size 1.8034 0.508)
			(layers "B.Cu" "B.Mask" "B.Paste")
			(net "M_K_DQ<58>")
		)
		(pad "138" smd rect
			(at 0 121.549922 270)
			(size 1.8034 0.508)
			(layers "B.Cu" "B.Mask" "B.Paste")
			(net "GND")
		)
		(pad "139" smd rect
			(at 0 122.40006 270)
			(size 1.8034 0.508)
			(layers "B.Cu" "B.Mask" "B.Paste")
			(net "PVPP_KLM")
		)
		(pad "140" smd rect
			(at 0 123.249944 270)
			(size 1.8034 0.508)
			(layers "B.Cu" "B.Mask" "B.Paste")
			(net "GND")
		)
		(pad "141" smd rect
			(at 0 124.100082 270)
			(size 1.8034 0.508)
			(layers "B.Cu" "B.Mask" "B.Paste")
			(net "SMB_DDR_KLM_VPP_SCL")
		)
		(pad "142" smd rect
			(at 0 124.949966 270)
			(size 1.8034 0.508)
			(layers "B.Cu" "B.Mask" "B.Paste")
			(net "PVPP_KLM")
		)
		(pad "143" smd rect
			(at 0 125.800104 270)
			(size 1.8034 0.508)
			(layers "B.Cu" "B.Mask" "B.Paste")
			(net "PVPP_KLM")
		)
		(pad "144" smd rect
			(at 0 126.649988 270)
			(size 1.8034 0.508)
			(layers "B.Cu" "B.Mask" "B.Paste")
			(net "TP_CH_K_DIMM0_RFU_2")
		)
		(pad "145" smd rect
			(at -4.59994 0 270)
			(size 1.8034 0.508)
			(layers "B.Cu" "B.Mask" "B.Paste")
			(net "P12V_NVDIMM_KLM")
		)
		(pad "146" smd rect
			(at -4.59994 0.849884 270)
			(size 1.8034 0.508)
			(layers "B.Cu" "B.Mask" "B.Paste")
			(net "M_K_VREF")
		)
		(pad "147" smd rect
			(at -4.59994 1.700022 270)
			(size 1.8034 0.508)
			(layers "B.Cu" "B.Mask" "B.Paste")
			(net "GND")
		)
		(pad "148" smd rect
			(at -4.59994 2.549906 270)
			(size 1.8034 0.508)
			(layers "B.Cu" "B.Mask" "B.Paste")
			(net "M_K_DQ<5>")
		)
		(pad "149" smd rect
			(at -4.59994 3.400044 270)
			(size 1.8034 0.508)
			(layers "B.Cu" "B.Mask" "B.Paste")
			(net "GND")
		)
		(pad "150" smd rect
			(at -4.59994 4.249928 270)
			(size 1.8034 0.508)
			(layers "B.Cu" "B.Mask" "B.Paste")
			(net "M_K_DQ<1>")
		)
		(pad "151" smd rect
			(at -4.59994 5.100066 270)
			(size 1.8034 0.508)
			(layers "B.Cu" "B.Mask" "B.Paste")
			(net "GND")
		)
		(pad "152" smd rect
			(at -4.59994 5.94995 270)
			(size 1.8034 0.508)
			(layers "B.Cu" "B.Mask" "B.Paste")
			(net "M_K_DQS_DN<0>")
		)
		(pad "153" smd rect
			(at -4.59994 6.800088 270)
			(size 1.8034 0.508)
			(layers "B.Cu" "B.Mask" "B.Paste")
			(net "M_K_DQS_DP<0>")
		)
		(pad "154" smd rect
			(at -4.59994 7.649972 270)
			(size 1.8034 0.508)
			(layers "B.Cu" "B.Mask" "B.Paste")
			(net "GND")
		)
		(pad "155" smd rect
			(at -4.59994 8.50011 270)
			(size 1.8034 0.508)
			(layers "B.Cu" "B.Mask" "B.Paste")
			(net "M_K_DQ<7>")
		)
		(pad "156" smd rect
			(at -4.59994 9.349994 270)
			(size 1.8034 0.508)
			(layers "B.Cu" "B.Mask" "B.Paste")
			(net "GND")
		)
		(pad "157" smd rect
			(at -4.59994 10.199878 270)
			(size 1.8034 0.508)
			(layers "B.Cu" "B.Mask" "B.Paste")
			(net "M_K_DQ<3>")
		)
		(pad "158" smd rect
			(at -4.59994 11.050016 270)
			(size 1.8034 0.508)
			(layers "B.Cu" "B.Mask" "B.Paste")
			(net "GND")
		)
		(pad "159" smd rect
			(at -4.59994 11.8999 270)
			(size 1.8034 0.508)
			(layers "B.Cu" "B.Mask" "B.Paste")
			(net "M_K_DQ<13>")
		)
		(pad "160" smd rect
			(at -4.59994 12.750038 270)
			(size 1.8034 0.508)
			(layers "B.Cu" "B.Mask" "B.Paste")
			(net "GND")
		)
		(pad "161" smd rect
			(at -4.59994 13.599922 270)
			(size 1.8034 0.508)
			(layers "B.Cu" "B.Mask" "B.Paste")
			(net "M_K_DQ<9>")
		)
		(pad "162" smd rect
			(at -4.59994 14.45006 270)
			(size 1.8034 0.508)
			(layers "B.Cu" "B.Mask" "B.Paste")
			(net "GND")
		)
		(pad "163" smd rect
			(at -4.59994 15.299944 270)
			(size 1.8034 0.508)
			(layers "B.Cu" "B.Mask" "B.Paste")
			(net "M_K_DQS_DN<1>")
		)
		(pad "164" smd rect
			(at -4.59994 16.150082 270)
			(size 1.8034 0.508)
			(layers "B.Cu" "B.Mask" "B.Paste")
			(net "M_K_DQS_DP<1>")
		)
		(pad "165" smd rect
			(at -4.59994 16.999966 270)
			(size 1.8034 0.508)
			(layers "B.Cu" "B.Mask" "B.Paste")
			(net "GND")
		)
		(pad "166" smd rect
			(at -4.59994 17.850104 270)
			(size 1.8034 0.508)
			(layers "B.Cu" "B.Mask" "B.Paste")
			(net "M_K_DQ<15>")
		)
		(pad "167" smd rect
			(at -4.59994 18.699988 270)
			(size 1.8034 0.508)
			(layers "B.Cu" "B.Mask" "B.Paste")
			(net "GND")
		)
		(pad "168" smd rect
			(at -4.59994 19.550126 270)
			(size 1.8034 0.508)
			(layers "B.Cu" "B.Mask" "B.Paste")
			(net "M_K_DQ<11>")
		)
		(pad "169" smd rect
			(at -4.59994 20.40001 270)
			(size 1.8034 0.508)
			(layers "B.Cu" "B.Mask" "B.Paste")
			(net "GND")
		)
		(pad "170" smd rect
			(at -4.59994 21.249894 270)
			(size 1.8034 0.508)
			(layers "B.Cu" "B.Mask" "B.Paste")
			(net "M_K_DQ<21>")
		)
		(pad "171" smd rect
			(at -4.59994 22.100032 270)
			(size 1.8034 0.508)
			(layers "B.Cu" "B.Mask" "B.Paste")
			(net "GND")
		)
		(pad "172" smd rect
			(at -4.59994 22.949916 270)
			(size 1.8034 0.508)
			(layers "B.Cu" "B.Mask" "B.Paste")
			(net "M_K_DQ<17>")
		)
		(pad "173" smd rect
			(at -4.59994 23.800054 270)
			(size 1.8034 0.508)
			(layers "B.Cu" "B.Mask" "B.Paste")
			(net "GND")
		)
		(pad "174" smd rect
			(at -4.59994 24.649938 270)
			(size 1.8034 0.508)
			(layers "B.Cu" "B.Mask" "B.Paste")
			(net "M_K_DQS_DN<2>")
		)
		(pad "175" smd rect
			(at -4.59994 25.500076 270)
			(size 1.8034 0.508)
			(layers "B.Cu" "B.Mask" "B.Paste")
			(net "M_K_DQS_DP<2>")
		)
		(pad "176" smd rect
			(at -4.59994 26.34996 270)
			(size 1.8034 0.508)
			(layers "B.Cu" "B.Mask" "B.Paste")
			(net "GND")
		)
		(pad "177" smd rect
			(at -4.59994 27.200098 270)
			(size 1.8034 0.508)
			(layers "B.Cu" "B.Mask" "B.Paste")
			(net "M_K_DQ<23>")
		)
		(pad "178" smd rect
			(at -4.59994 28.049982 270)
			(size 1.8034 0.508)
			(layers "B.Cu" "B.Mask" "B.Paste")
			(net "GND")
		)
		(pad "179" smd rect
			(at -4.59994 28.90012 270)
			(size 1.8034 0.508)
			(layers "B.Cu" "B.Mask" "B.Paste")
			(net "M_K_DQ<19>")
		)
		(pad "180" smd rect
			(at -4.59994 29.750004 270)
			(size 1.8034 0.508)
			(layers "B.Cu" "B.Mask" "B.Paste")
			(net "GND")
		)
		(pad "181" smd rect
			(at -4.59994 30.599888 270)
			(size 1.8034 0.508)
			(layers "B.Cu" "B.Mask" "B.Paste")
			(net "M_K_DQ<29>")
		)
		(pad "182" smd rect
			(at -4.59994 31.450026 270)
			(size 1.8034 0.508)
			(layers "B.Cu" "B.Mask" "B.Paste")
			(net "GND")
		)
		(pad "183" smd rect
			(at -4.59994 32.29991 270)
			(size 1.8034 0.508)
			(layers "B.Cu" "B.Mask" "B.Paste")
			(net "M_K_DQ<25>")
		)
		(pad "184" smd rect
			(at -4.59994 33.150048 270)
			(size 1.8034 0.508)
			(layers "B.Cu" "B.Mask" "B.Paste")
			(net "GND")
		)
		(pad "185" smd rect
			(at -4.59994 33.999932 270)
			(size 1.8034 0.508)
			(layers "B.Cu" "B.Mask" "B.Paste")
			(net "M_K_DQS_DN<3>")
		)
		(pad "186" smd rect
			(at -4.59994 34.85007 270)
			(size 1.8034 0.508)
			(layers "B.Cu" "B.Mask" "B.Paste")
			(net "M_K_DQS_DP<3>")
		)
		(pad "187" smd rect
			(at -4.59994 35.699954 270)
			(size 1.8034 0.508)
			(layers "B.Cu" "B.Mask" "B.Paste")
			(net "GND")
		)
		(pad "188" smd rect
			(at -4.59994 36.550092 270)
			(size 1.8034 0.508)
			(layers "B.Cu" "B.Mask" "B.Paste")
			(net "M_K_DQ<31>")
		)
		(pad "189" smd rect
			(at -4.59994 37.399976 270)
			(size 1.8034 0.508)
			(layers "B.Cu" "B.Mask" "B.Paste")
			(net "GND")
		)
		(pad "190" smd rect
			(at -4.59994 38.250114 270)
			(size 1.8034 0.508)
			(layers "B.Cu" "B.Mask" "B.Paste")
			(net "M_K_DQ<27>")
		)
		(pad "191" smd rect
			(at -4.59994 39.099998 270)
			(size 1.8034 0.508)
			(layers "B.Cu" "B.Mask" "B.Paste")
			(net "GND")
		)
		(pad "192" smd rect
			(at -4.59994 39.949882 270)
			(size 1.8034 0.508)
			(layers "B.Cu" "B.Mask" "B.Paste")
			(net "M_K_ECC<5>")
		)
		(pad "193" smd rect
			(at -4.59994 40.80002 270)
			(size 1.8034 0.508)
			(layers "B.Cu" "B.Mask" "B.Paste")
			(net "GND")
		)
		(pad "194" smd rect
			(at -4.59994 41.649904 270)
			(size 1.8034 0.508)
			(layers "B.Cu" "B.Mask" "B.Paste")
			(net "M_K_ECC<1>")
		)
		(pad "195" smd rect
			(at -4.59994 42.500042 270)
			(size 1.8034 0.508)
			(layers "B.Cu" "B.Mask" "B.Paste")
			(net "GND")
		)
		(pad "196" smd rect
			(at -4.59994 43.349926 270)
			(size 1.8034 0.508)
			(layers "B.Cu" "B.Mask" "B.Paste")
			(net "M_K_DQS_DN<8>")
		)
		(pad "197" smd rect
			(at -4.59994 44.200064 270)
			(size 1.8034 0.508)
			(layers "B.Cu" "B.Mask" "B.Paste")
			(net "M_K_DQS_DP<8>")
		)
		(pad "198" smd rect
			(at -4.59994 45.049948 270)
			(size 1.8034 0.508)
			(layers "B.Cu" "B.Mask" "B.Paste")
			(net "GND")
		)
		(pad "199" smd rect
			(at -4.59994 45.900086 270)
			(size 1.8034 0.508)
			(layers "B.Cu" "B.Mask" "B.Paste")
			(net "M_K_ECC<7>")
		)
		(pad "200" smd rect
			(at -4.59994 46.74997 270)
			(size 1.8034 0.508)
			(layers "B.Cu" "B.Mask" "B.Paste")
			(net "GND")
		)
		(pad "201" smd rect
			(at -4.59994 47.600108 270)
			(size 1.8034 0.508)
			(layers "B.Cu" "B.Mask" "B.Paste")
			(net "M_K_ECC<3>")
		)
		(pad "202" smd rect
			(at -4.59994 48.449992 270)
			(size 1.8034 0.508)
			(layers "B.Cu" "B.Mask" "B.Paste")
			(net "GND")
		)
		(pad "203" smd rect
			(at -4.59994 49.299876 270)
			(size 1.8034 0.508)
			(layers "B.Cu" "B.Mask" "B.Paste")
			(net "M_K_CKE<3>")
		)
		(pad "204" smd rect
			(at -4.59994 50.150014 270)
			(size 1.8034 0.508)
			(layers "B.Cu" "B.Mask" "B.Paste")
			(net "PVDDQ_KLM")
		)
		(pad "205" smd rect
			(at -4.59994 50.999898 270)
			(size 1.8034 0.508)
			(layers "B.Cu" "B.Mask" "B.Paste")
			(net "TP_CH_K_DIMM0_RFU_0")
		)
		(pad "206" smd rect
			(at -4.59994 51.850036 270)
			(size 1.8034 0.508)
			(layers "B.Cu" "B.Mask" "B.Paste")
			(net "PVDDQ_KLM")
		)
		(pad "207" smd rect
			(at -4.59994 52.69992 270)
			(size 1.8034 0.508)
			(layers "B.Cu" "B.Mask" "B.Paste")
			(net "M_K_BG<1>")
		)
		(pad "208" smd rect
			(at -4.59994 53.550058 270)
			(size 1.8034 0.508)
			(layers "B.Cu" "B.Mask" "B.Paste")
			(net "M_K_ALERT_N")
		)
		(pad "209" smd rect
			(at -4.59994 54.399942 270)
			(size 1.8034 0.508)
			(layers "B.Cu" "B.Mask" "B.Paste")
			(net "PVDDQ_KLM")
		)
		(pad "210" smd rect
			(at -4.59994 55.25008 270)
			(size 1.8034 0.508)
			(layers "B.Cu" "B.Mask" "B.Paste")
			(net "M_K_MA<11>")
		)
		(pad "211" smd rect
			(at -4.59994 56.099964 270)
			(size 1.8034 0.508)
			(layers "B.Cu" "B.Mask" "B.Paste")
			(net "M_K_MA<7>")
		)
		(pad "212" smd rect
			(at -4.59994 56.950102 270)
			(size 1.8034 0.508)
			(layers "B.Cu" "B.Mask" "B.Paste")
			(net "PVDDQ_KLM")
		)
		(pad "213" smd rect
			(at -4.59994 57.799986 270)
			(size 1.8034 0.508)
			(layers "B.Cu" "B.Mask" "B.Paste")
			(net "M_K_MA<5>")
		)
		(pad "214" smd rect
			(at -4.59994 58.650124 270)
			(size 1.8034 0.508)
			(layers "B.Cu" "B.Mask" "B.Paste")
			(net "M_K_MA<4>")
		)
		(pad "215" smd rect
			(at -4.59994 59.500008 270)
			(size 1.8034 0.508)
			(layers "B.Cu" "B.Mask" "B.Paste")
			(net "PVDDQ_KLM")
		)
		(pad "216" smd rect
			(at -4.59994 60.349892 270)
			(size 1.8034 0.508)
			(layers "B.Cu" "B.Mask" "B.Paste")
			(net "M_K_MA<2>")
		)
		(pad "217" smd rect
			(at -4.59994 61.20003 270)
			(size 1.8034 0.508)
			(layers "B.Cu" "B.Mask" "B.Paste")
			(net "PVDDQ_KLM")
		)
		(pad "218" smd rect
			(at -4.59994 62.049914 270)
			(size 1.8034 0.508)
			(layers "B.Cu" "B.Mask" "B.Paste")
			(net "M_K_CLK_DP<3>")
		)
		(pad "219" smd rect
			(at -4.59994 62.900052 270)
			(size 1.8034 0.508)
			(layers "B.Cu" "B.Mask" "B.Paste")
			(net "M_K_CLK_DN<3>")
		)
		(pad "220" smd rect
			(at -4.59994 63.749936 270)
			(size 1.8034 0.508)
			(layers "B.Cu" "B.Mask" "B.Paste")
			(net "PVDDQ_KLM")
		)
		(pad "221" smd rect
			(at -4.59994 64.600074 270)
			(size 1.8034 0.508)
			(layers "B.Cu" "B.Mask" "B.Paste")
			(net "PVTT_KLM")
		)
		(pad "222" smd rect
			(at -4.59994 70.550024 270)
			(size 1.8034 0.508)
			(layers "B.Cu" "B.Mask" "B.Paste")
			(net "M_K_PAR")
		)
		(pad "223" smd rect
			(at -4.59994 71.399908 270)
			(size 1.8034 0.508)
			(layers "B.Cu" "B.Mask" "B.Paste")
			(net "PVDDQ_KLM")
		)
		(pad "224" smd rect
			(at -4.59994 72.250046 270)
			(size 1.8034 0.508)
			(layers "B.Cu" "B.Mask" "B.Paste")
			(net "M_K_BA<1>")
		)
		(pad "225" smd rect
			(at -4.59994 73.09993 270)
			(size 1.8034 0.508)
			(layers "B.Cu" "B.Mask" "B.Paste")
			(net "M_K_MA<10>")
		)
		(pad "226" smd rect
			(at -4.59994 73.950068 270)
			(size 1.8034 0.508)
			(layers "B.Cu" "B.Mask" "B.Paste")
			(net "PVDDQ_KLM")
		)
		(pad "227" smd rect
			(at -4.59994 74.799952 270)
			(size 1.8034 0.508)
			(layers "B.Cu" "B.Mask" "B.Paste")
			(net "TP_CH_K_DIMM0_RFU_1")
		)
		(pad "228" smd rect
			(at -4.59994 75.65009 270)
			(size 1.8034 0.508)
			(layers "B.Cu" "B.Mask" "B.Paste")
			(net "M_K_MA<14>")
		)
		(pad "229" smd rect
			(at -4.59994 76.499974 270)
			(size 1.8034 0.508)
			(layers "B.Cu" "B.Mask" "B.Paste")
			(net "PVDDQ_KLM")
		)
		(pad "230" smd rect
			(at -4.59994 77.350112 270)
			(size 1.8034 0.508)
			(layers "B.Cu" "B.Mask" "B.Paste")
			(net "FM_ADR_COMPLETE_KLM_N")
		)
		(pad "231" smd rect
			(at -4.59994 78.199996 270)
			(size 1.8034 0.508)
			(layers "B.Cu" "B.Mask" "B.Paste")
			(net "PVDDQ_KLM")
		)
		(pad "232" smd rect
			(at -4.59994 79.04988 270)
			(size 1.8034 0.508)
			(layers "B.Cu" "B.Mask" "B.Paste")
			(net "M_K_MA<13>")
		)
		(pad "233" smd rect
			(at -4.59994 79.900018 270)
			(size 1.8034 0.508)
			(layers "B.Cu" "B.Mask" "B.Paste")
			(net "PVDDQ_KLM")
		)
		(pad "234" smd rect
			(at -4.59994 80.749902 270)
			(size 1.8034 0.508)
			(layers "B.Cu" "B.Mask" "B.Paste")
			(net "M_K_MA<17>")
		)
		(pad "235" smd rect
			(at -4.59994 81.60004 270)
			(size 1.8034 0.508)
			(layers "B.Cu" "B.Mask" "B.Paste")
			(net "M_K_C<2>")
		)
		(pad "236" smd rect
			(at -4.59994 82.449924 270)
			(size 1.8034 0.508)
			(layers "B.Cu" "B.Mask" "B.Paste")
			(net "PVDDQ_KLM")
		)
		(pad "237" smd rect
			(at -4.59994 83.300062 270)
			(size 1.8034 0.508)
			(layers "B.Cu" "B.Mask" "B.Paste")
			(net "M_K_CS_N<7>")
		)
		(pad "238" smd rect
			(at -4.59994 84.149946 270)
			(size 1.8034 0.508)
			(layers "B.Cu" "B.Mask" "B.Paste")
			(net "GND")
		)
		(pad "239" smd rect
			(at -4.59994 85.000084 270)
			(size 1.8034 0.508)
			(layers "B.Cu" "B.Mask" "B.Paste")
			(net "GND")
		)
		(pad "240" smd rect
			(at -4.59994 85.849968 270)
			(size 1.8034 0.508)
			(layers "B.Cu" "B.Mask" "B.Paste")
			(net "M_K_DQ<37>")
		)
		(pad "241" smd rect
			(at -4.59994 86.700106 270)
			(size 1.8034 0.508)
			(layers "B.Cu" "B.Mask" "B.Paste")
			(net "GND")
		)
		(pad "242" smd rect
			(at -4.59994 87.54999 270)
			(size 1.8034 0.508)
			(layers "B.Cu" "B.Mask" "B.Paste")
			(net "M_K_DQ<33>")
		)
		(pad "243" smd rect
			(at -4.59994 88.399874 270)
			(size 1.8034 0.508)
			(layers "B.Cu" "B.Mask" "B.Paste")
			(net "GND")
		)
		(pad "244" smd rect
			(at -4.59994 89.250012 270)
			(size 1.8034 0.508)
			(layers "B.Cu" "B.Mask" "B.Paste")
			(net "M_K_DQS_DN<4>")
		)
		(pad "245" smd rect
			(at -4.59994 90.099896 270)
			(size 1.8034 0.508)
			(layers "B.Cu" "B.Mask" "B.Paste")
			(net "M_K_DQS_DP<4>")
		)
		(pad "246" smd rect
			(at -4.59994 90.950034 270)
			(size 1.8034 0.508)
			(layers "B.Cu" "B.Mask" "B.Paste")
			(net "GND")
		)
		(pad "247" smd rect
			(at -4.59994 91.799918 270)
			(size 1.8034 0.508)
			(layers "B.Cu" "B.Mask" "B.Paste")
			(net "M_K_DQ<39>")
		)
		(pad "248" smd rect
			(at -4.59994 92.650056 270)
			(size 1.8034 0.508)
			(layers "B.Cu" "B.Mask" "B.Paste")
			(net "GND")
		)
		(pad "249" smd rect
			(at -4.59994 93.49994 270)
			(size 1.8034 0.508)
			(layers "B.Cu" "B.Mask" "B.Paste")
			(net "M_K_DQ<35>")
		)
		(pad "250" smd rect
			(at -4.59994 94.350078 270)
			(size 1.8034 0.508)
			(layers "B.Cu" "B.Mask" "B.Paste")
			(net "GND")
		)
		(pad "251" smd rect
			(at -4.59994 95.199962 270)
			(size 1.8034 0.508)
			(layers "B.Cu" "B.Mask" "B.Paste")
			(net "M_K_DQ<45>")
		)
		(pad "252" smd rect
			(at -4.59994 96.0501 270)
			(size 1.8034 0.508)
			(layers "B.Cu" "B.Mask" "B.Paste")
			(net "GND")
		)
		(pad "253" smd rect
			(at -4.59994 96.899984 270)
			(size 1.8034 0.508)
			(layers "B.Cu" "B.Mask" "B.Paste")
			(net "M_K_DQ<41>")
		)
		(pad "254" smd rect
			(at -4.59994 97.750122 270)
			(size 1.8034 0.508)
			(layers "B.Cu" "B.Mask" "B.Paste")
			(net "GND")
		)
		(pad "255" smd rect
			(at -4.59994 98.600006 270)
			(size 1.8034 0.508)
			(layers "B.Cu" "B.Mask" "B.Paste")
			(net "M_K_DQS_DN<5>")
		)
		(pad "256" smd rect
			(at -4.59994 99.44989 270)
			(size 1.8034 0.508)
			(layers "B.Cu" "B.Mask" "B.Paste")
			(net "M_K_DQS_DP<5>")
		)
		(pad "257" smd rect
			(at -4.59994 100.300028 270)
			(size 1.8034 0.508)
			(layers "B.Cu" "B.Mask" "B.Paste")
			(net "GND")
		)
		(pad "258" smd rect
			(at -4.59994 101.149912 270)
			(size 1.8034 0.508)
			(layers "B.Cu" "B.Mask" "B.Paste")
			(net "M_K_DQ<47>")
		)
		(pad "259" smd rect
			(at -4.59994 102.00005 270)
			(size 1.8034 0.508)
			(layers "B.Cu" "B.Mask" "B.Paste")
			(net "GND")
		)
		(pad "260" smd rect
			(at -4.59994 102.849934 270)
			(size 1.8034 0.508)
			(layers "B.Cu" "B.Mask" "B.Paste")
			(net "M_K_DQ<43>")
		)
		(pad "261" smd rect
			(at -4.59994 103.700072 270)
			(size 1.8034 0.508)
			(layers "B.Cu" "B.Mask" "B.Paste")
			(net "GND")
		)
		(pad "262" smd rect
			(at -4.59994 104.549956 270)
			(size 1.8034 0.508)
			(layers "B.Cu" "B.Mask" "B.Paste")
			(net "M_K_DQ<53>")
		)
		(pad "263" smd rect
			(at -4.59994 105.400094 270)
			(size 1.8034 0.508)
			(layers "B.Cu" "B.Mask" "B.Paste")
			(net "GND")
		)
		(pad "264" smd rect
			(at -4.59994 106.249978 270)
			(size 1.8034 0.508)
			(layers "B.Cu" "B.Mask" "B.Paste")
			(net "M_K_DQ<49>")
		)
		(pad "265" smd rect
			(at -4.59994 107.100116 270)
			(size 1.8034 0.508)
			(layers "B.Cu" "B.Mask" "B.Paste")
			(net "GND")
		)
		(pad "266" smd rect
			(at -4.59994 107.95 270)
			(size 1.8034 0.508)
			(layers "B.Cu" "B.Mask" "B.Paste")
			(net "M_K_DQS_DN<6>")
		)
		(pad "267" smd rect
			(at -4.59994 108.799884 270)
			(size 1.8034 0.508)
			(layers "B.Cu" "B.Mask" "B.Paste")
			(net "M_K_DQS_DP<6>")
		)
		(pad "268" smd rect
			(at -4.59994 109.650022 270)
			(size 1.8034 0.508)
			(layers "B.Cu" "B.Mask" "B.Paste")
			(net "GND")
		)
		(pad "269" smd rect
			(at -4.59994 110.499906 270)
			(size 1.8034 0.508)
			(layers "B.Cu" "B.Mask" "B.Paste")
			(net "M_K_DQ<55>")
		)
		(pad "270" smd rect
			(at -4.59994 111.350044 270)
			(size 1.8034 0.508)
			(layers "B.Cu" "B.Mask" "B.Paste")
			(net "GND")
		)
		(pad "271" smd rect
			(at -4.59994 112.199928 270)
			(size 1.8034 0.508)
			(layers "B.Cu" "B.Mask" "B.Paste")
			(net "M_K_DQ<51>")
		)
		(pad "272" smd rect
			(at -4.59994 113.050066 270)
			(size 1.8034 0.508)
			(layers "B.Cu" "B.Mask" "B.Paste")
			(net "GND")
		)
		(pad "273" smd rect
			(at -4.59994 113.89995 270)
			(size 1.8034 0.508)
			(layers "B.Cu" "B.Mask" "B.Paste")
			(net "M_K_DQ<61>")
		)
		(pad "274" smd rect
			(at -4.59994 114.750088 270)
			(size 1.8034 0.508)
			(layers "B.Cu" "B.Mask" "B.Paste")
			(net "GND")
		)
		(pad "275" smd rect
			(at -4.59994 115.599972 270)
			(size 1.8034 0.508)
			(layers "B.Cu" "B.Mask" "B.Paste")
			(net "M_K_DQ<57>")
		)
		(pad "276" smd rect
			(at -4.59994 116.45011 270)
			(size 1.8034 0.508)
			(layers "B.Cu" "B.Mask" "B.Paste")
			(net "GND")
		)
		(pad "277" smd rect
			(at -4.59994 117.299994 270)
			(size 1.8034 0.508)
			(layers "B.Cu" "B.Mask" "B.Paste")
			(net "M_K_DQS_DN<7>")
		)
		(pad "278" smd rect
			(at -4.59994 118.149878 270)
			(size 1.8034 0.508)
			(layers "B.Cu" "B.Mask" "B.Paste")
			(net "M_K_DQS_DP<7>")
		)
		(pad "279" smd rect
			(at -4.59994 119.000016 270)
			(size 1.8034 0.508)
			(layers "B.Cu" "B.Mask" "B.Paste")
			(net "GND")
		)
		(pad "280" smd rect
			(at -4.59994 119.8499 270)
			(size 1.8034 0.508)
			(layers "B.Cu" "B.Mask" "B.Paste")
			(net "M_K_DQ<63>")
		)
		(pad "281" smd rect
			(at -4.59994 120.700038 270)
			(size 1.8034 0.508)
			(layers "B.Cu" "B.Mask" "B.Paste")
			(net "GND")
		)
		(pad "282" smd rect
			(at -4.59994 121.549922 270)
			(size 1.8034 0.508)
			(layers "B.Cu" "B.Mask" "B.Paste")
			(net "M_K_DQ<59>")
		)
		(pad "283" smd rect
			(at -4.59994 122.40006 270)
			(size 1.8034 0.508)
			(layers "B.Cu" "B.Mask" "B.Paste")
			(net "GND")
		)
		(pad "284" smd rect
			(at -4.59994 123.249944 270)
			(size 1.8034 0.508)
			(layers "B.Cu" "B.Mask" "B.Paste")
			(net "PVPP_KLM")
		)
		(pad "285" smd rect
			(at -4.59994 124.100082 270)
			(size 1.8034 0.508)
			(layers "B.Cu" "B.Mask" "B.Paste")
			(net "SMB_DDR_KLM_VPP_SDA")
		)
		(pad "286" smd rect
			(at -4.59994 124.949966 270)
			(size 1.8034 0.508)
			(layers "B.Cu" "B.Mask" "B.Paste")
			(net "PVPP_KLM")
		)
		(pad "287" smd rect
			(at -4.59994 125.800104 270)
			(size 1.8034 0.508)
			(layers "B.Cu" "B.Mask" "B.Paste")
			(net "PVPP_KLM")
		)
		(pad "288" smd rect
			(at -4.59994 126.649988 270)
			(size 1.8034 0.508)
			(layers "B.Cu" "B.Mask" "B.Paste")
			(net "PVPP_KLM")
		)
	)
	(footprint ""
		(layer "B.Cu")
		(at 421.812466 -44.647612 -90)
		(property "Reference" "R25W82"
			(at 0.8382 -0.67818 270)
			(unlocked yes)
			(layer "B.SilkS")
			(effects
				(font
					(size 0.4064 0.254)
					(thickness 0.1524)
				)
				(justify left mirror)
			)
		)
		(property "Value" ""
			(at 0 0 90)
			(layer "B.Fab")
			(effects
				(font
					(size 1.27 1.27)
				)
				(justify mirror)
			)
		)
		(duplicate_pad_numbers_are_jumpers no)
		(fp_poly
			(pts
				(xy 0.2794 -0.1016) (xy -0.2794 -0.1016) (xy -0.2794 0.9906) (xy 0.2794 0.9906)
			)
			(stroke
				(width 0)
				(type default)
			)
			(fill no)
			(layer "B.CrtYd")
		)
		(fp_line
			(start -0.2794 0.9906)
			(end -0.2794 -0.1016)
			(stroke
				(width 0.1)
				(type default)
			)
			(layer "B.Fab")
		)
		(fp_line
			(start 0.2794 0.9906)
			(end -0.2794 0.9906)
			(stroke
				(width 0.1)
				(type default)
			)
			(layer "B.Fab")
		)
		(fp_line
			(start -0.2794 -0.1016)
			(end 0.2794 -0.1016)
			(stroke
				(width 0.1)
				(type default)
			)
			(layer "B.Fab")
		)
		(fp_line
			(start 0.2794 -0.1016)
			(end 0.2794 0.9906)
			(stroke
				(width 0.1)
				(type default)
			)
			(layer "B.Fab")
		)
		(pad "1" smd rect
			(at 0 0 90)
			(size 0.508 0.508)
			(layers "B.Cu" "B.Mask" "B.Paste")
			(net "SPI_BMC_BT_DO")
		)
		(pad "2" smd rect
			(at 0 0.889 90)
			(size 0.508 0.508)
			(layers "B.Cu" "B.Mask" "B.Paste")
			(net "SPI_BMC_BT_DO_R")
		)
		(zone
			(layer "B.Cu")
			(hatch none 0.5)
			(connect_pads
				(clearance 0)
			)
			(min_thickness 0.25)
			(keepout
				(tracks not_allowed)
				(vias allowed)
				(pads allowed)
				(copperpour not_allowed)
				(footprints allowed)
			)
			(placement
				(enabled no)
				(sheetname "")
			)
			(fill
				(thermal_gap 0.5)
				(thermal_bridge_width 0.5)
				(island_removal_mode 0)
			)
			(polygon
				(pts
					(xy 421.177466 -44.393612) (xy 421.177466 -44.901612) (xy 421.558466 -44.901612) (xy 421.558466 -44.393612)
				)
			)
		)
		(zone
			(layer "B.Cu")
			(hatch none 0.5)
			(connect_pads
				(clearance 0)
			)
			(min_thickness 0.25)
			(keepout
				(tracks allowed)
				(vias not_allowed)
				(pads allowed)
				(copperpour not_allowed)
				(footprints allowed)
			)
			(placement
				(enabled no)
				(sheetname "")
			)
			(fill
				(thermal_gap 0.5)
				(thermal_bridge_width 0.5)
				(island_removal_mode 0)
			)
			(polygon
				(pts
					(xy 421.558466 -44.393612) (xy 421.558466 -44.901612) (xy 421.177466 -44.901612) (xy 421.177466 -44.393612)
				)
			)
		)
	)
	(footprint ""
		(layer "B.Cu")
		(at 169.037 -3.4544 90)
		(property "Reference" "C6U14"
			(at 0 0 90)
			(layer "B.SilkS")
			(hide yes)
			(effects
				(font
					(size 1.27 1.27)
				)
				(justify mirror)
			)
		)
		(property "Value" ""
			(at 0 0 90)
			(layer "B.Fab")
			(effects
				(font
					(size 1.27 1.27)
				)
				(justify mirror)
			)
		)
		(duplicate_pad_numbers_are_jumpers no)
		(fp_rect
			(start -0.4953 1.6002)
			(end 0.4953 -0.2032)
			(stroke
				(width 0)
				(type default)
			)
			(fill no)
			(layer "B.CrtYd")
		)
		(fp_line
			(start 0.4953 -0.2032)
			(end -0.4953 -0.2032)
			(stroke
				(width 0.1)
				(type default)
			)
			(layer "B.Fab")
		)
		(fp_line
			(start -0.4953 -0.2032)
			(end -0.4953 1.6002)
			(stroke
				(width 0.1)
				(type default)
			)
			(layer "B.Fab")
		)
		(fp_line
			(start 0.4953 1.6002)
			(end 0.4953 -0.2032)
			(stroke
				(width 0.1)
				(type default)
			)
			(layer "B.Fab")
		)
		(fp_line
			(start -0.4953 1.6002)
			(end 0.4953 1.6002)
			(stroke
				(width 0.1)
				(type default)
			)
			(layer "B.Fab")
		)
		(pad "1" smd rect
			(at 0 0 270)
			(size 0.762 0.889)
			(layers "B.Cu" "B.Mask" "B.Paste")
			(net "PVDDQ_GHJ")
		)
		(pad "2" smd rect
			(at 0 1.397 270)
			(size 0.762 0.889)
			(layers "B.Cu" "B.Mask" "B.Paste")
			(net "GND")
		)
		(zone
			(layer "B.Cu")
			(hatch none 0.5)
			(connect_pads
				(clearance 0)
			)
			(min_thickness 0.25)
			(keepout
				(tracks not_allowed)
				(vias allowed)
				(pads allowed)
				(copperpour not_allowed)
				(footprints allowed)
			)
			(placement
				(enabled no)
				(sheetname "")
			)
			(fill
				(thermal_gap 0.5)
				(thermal_bridge_width 0.5)
				(island_removal_mode 0)
			)
			(polygon
				(pts
					(xy 169.9895 -3.0734) (xy 169.9895 -3.8354) (xy 169.4815 -3.8354) (xy 169.4815 -3.0734)
				)
			)
		)
	)
	(footprint ""
		(layer "B.Cu")
		(at 273.433286 -68.17614 180)
		(property "Reference" "C5P41"
			(at 0 0 0)
			(layer "B.SilkS")
			(hide yes)
			(effects
				(font
					(size 1.27 1.27)
				)
				(justify mirror)
			)
		)
		(property "Value" ""
			(at 0 0 0)
			(layer "B.Fab")
			(effects
				(font
					(size 1.27 1.27)
				)
				(justify mirror)
			)
		)
		(duplicate_pad_numbers_are_jumpers no)
		(fp_poly
			(pts
				(xy 0.7239 -0.2159) (xy -0.7239 -0.2159) (xy -0.7239 1.9939) (xy 0.7239 1.9939)
			)
			(stroke
				(width 0)
				(type default)
			)
			(fill no)
			(layer "B.CrtYd")
		)
		(fp_line
			(start 0.7239 1.9939)
			(end -0.7239 1.9939)
			(stroke
				(width 0.1)
				(type default)
			)
			(layer "B.Fab")
		)
		(fp_line
			(start 0.7239 -0.2159)
			(end 0.7239 1.9939)
			(stroke
				(width 0.1)
				(type default)
			)
			(layer "B.Fab")
		)
		(fp_line
			(start -0.7239 1.9939)
			(end -0.7239 -0.2159)
			(stroke
				(width 0.1)
				(type default)
			)
			(layer "B.Fab")
		)
		(fp_line
			(start -0.7239 -0.2159)
			(end 0.7239 -0.2159)
			(stroke
				(width 0.1)
				(type default)
			)
			(layer "B.Fab")
		)
		(pad "1" smd rect
			(at 0 0)
			(size 1.27 1.016)
			(layers "B.Cu" "B.Mask" "B.Paste")
			(net "PVDDQ_ABC")
		)
		(pad "2" smd rect
			(at 0 1.778)
			(size 1.27 1.016)
			(layers "B.Cu" "B.Mask" "B.Paste")
			(net "GND")
		)
		(zone
			(layer "B.Cu")
			(hatch none 0.5)
			(connect_pads
				(clearance 0)
			)
			(min_thickness 0.25)
			(keepout
				(tracks not_allowed)
				(vias allowed)
				(pads allowed)
				(copperpour not_allowed)
				(footprints allowed)
			)
			(placement
				(enabled no)
				(sheetname "")
			)
			(fill
				(thermal_gap 0.5)
				(thermal_bridge_width 0.5)
				(island_removal_mode 0)
			)
			(polygon
				(pts
					(xy 272.798286 -68.68414) (xy 274.068286 -68.68414) (xy 274.068286 -69.44614) (xy 272.798286 -69.44614)
				)
			)
		)
	)
	(footprint ""
		(layer "B.Cu")
		(at 101.3968 -17.7546 90)
		(property "Reference" "C8T6"
			(at -1.848866 0.752348 90)
			(unlocked yes)
			(layer "B.SilkS")
			(effects
				(font
					(size 1.27 0.9652)
					(thickness 0.1524)
				)
				(justify mirror)
			)
		)
		(property "Value" ""
			(at 0 0 90)
			(layer "B.Fab")
			(effects
				(font
					(size 1.27 1.27)
				)
				(justify mirror)
			)
		)
		(duplicate_pad_numbers_are_jumpers no)
		(fp_rect
			(start 0.500126 1.598422)
			(end -0.500126 -0.201422)
			(stroke
				(width 0)
				(type default)
			)
			(fill no)
			(layer "B.CrtYd")
		)
		(fp_line
			(start 0.500126 -0.201422)
			(end -0.500126 -0.201422)
			(stroke
				(width 0.1)
				(type default)
			)
			(layer "B.Fab")
		)
		(fp_line
			(start -0.500126 -0.201422)
			(end -0.500126 1.598422)
			(stroke
				(width 0.1)
				(type default)
			)
			(layer "B.Fab")
		)
		(fp_line
			(start 0.500126 1.598422)
			(end 0.500126 -0.201422)
			(stroke
				(width 0.1)
				(type default)
			)
			(layer "B.Fab")
		)
		(fp_line
			(start -0.500126 1.598422)
			(end 0.500126 1.598422)
			(stroke
				(width 0.1)
				(type default)
			)
			(layer "B.Fab")
		)
		(pad "1" smd rect
			(at 0 0)
			(size 0.889 0.9906)
			(layers "B.Cu" "B.Mask" "B.Paste")
			(net "PVDDQ_GHJ")
		)
		(pad "2" smd rect
			(at 0 1.397)
			(size 0.889 0.9906)
			(layers "B.Cu" "B.Mask" "B.Paste")
			(net "GND")
		)
		(zone
			(layer "B.Cu")
			(hatch none 0.5)
			(connect_pads
				(clearance 0)
			)
			(min_thickness 0.25)
			(keepout
				(tracks not_allowed)
				(vias allowed)
				(pads allowed)
				(copperpour not_allowed)
				(footprints allowed)
			)
			(placement
				(enabled no)
				(sheetname "")
			)
			(fill
				(thermal_gap 0.5)
				(thermal_bridge_width 0.5)
				(island_removal_mode 0)
			)
			(polygon
				(pts
					(xy 102.3493 -18.2499) (xy 101.8413 -18.2499) (xy 101.8413 -17.2593) (xy 102.3493 -17.2593)
				)
			)
		)
		(zone
			(layer "B.Cu")
			(hatch none 0.5)
			(connect_pads
				(clearance 0)
			)
			(min_thickness 0.25)
			(keepout
				(tracks allowed)
				(vias not_allowed)
				(pads allowed)
				(copperpour not_allowed)
				(footprints allowed)
			)
			(placement
				(enabled no)
				(sheetname "")
			)
			(fill
				(thermal_gap 0.5)
				(thermal_bridge_width 0.5)
				(island_removal_mode 0)
			)
			(polygon
				(pts
					(xy 102.3493 -18.2499) (xy 101.8413 -18.2499) (xy 101.8413 -17.2593) (xy 102.3493 -17.2593)
				)
			)
		)
	)
	(footprint ""
		(layer "B.Cu")
		(at 484.124 -143.4084 90)
		(property "Reference" "CR1L4"
			(at 0 0 90)
			(layer "B.SilkS")
			(hide yes)
			(effects
				(font
					(size 1.27 1.27)
				)
				(justify mirror)
			)
		)
		(property "Value" ""
			(at 0 0 90)
			(layer "B.Fab")
			(effects
				(font
					(size 1.27 1.27)
				)
				(justify mirror)
			)
		)
		(duplicate_pad_numbers_are_jumpers no)
		(fp_line
			(start 0.9144 0.1016)
			(end 0.9144 2.9464)
			(stroke
				(width 0.1524)
				(type default)
			)
			(layer "B.SilkS")
		)
		(fp_line
			(start 0.8382 0.1016)
			(end 0.9144 0.1016)
			(stroke
				(width 0.1524)
				(type default)
			)
			(layer "B.SilkS")
		)
		(fp_line
			(start -0.8382 0.1016)
			(end -0.9144 0.1016)
			(stroke
				(width 0.1524)
				(type default)
			)
			(layer "B.SilkS")
		)
		(fp_line
			(start -0.9144 0.1016)
			(end -0.9144 2.9464)
			(stroke
				(width 0.1524)
				(type default)
			)
			(layer "B.SilkS")
		)
		(fp_line
			(start 0.9144 2.9464)
			(end 0.8382 2.9464)
			(stroke
				(width 0.1524)
				(type default)
			)
			(layer "B.SilkS")
		)
		(fp_line
			(start -0.9144 2.9464)
			(end -0.8382 2.9464)
			(stroke
				(width 0.1524)
				(type default)
			)
			(layer "B.SilkS")
		)
		(fp_circle
			(center -1.128776 -0.907288)
			(end -1.128776 -0.780288)
			(stroke
				(width 0.254)
				(type default)
			)
			(fill no)
			(layer "B.SilkS")
		)
		(fp_poly
			(pts
				(xy 0 0.1016) (xy -0.5334 0.1016) (xy -0.7366 0.1016) (xy -0.9144 0.1016) (xy -0.9144 2.9464) (xy -0.8382 2.9464)
				(xy -0.762 2.9464) (xy 0.9144 2.9464) (xy 0.9144 2.7686) (xy 0.9144 2.159) (xy 0.9144 0.1016) (xy 0.7366 0.1016)
				(xy 0.5842 0.1016)
			)
			(stroke
				(width 0)
				(type default)
			)
			(fill no)
			(layer "B.CrtYd")
		)
		(fp_line
			(start 0.9144 0.1016)
			(end 0.9144 2.9464)
			(stroke
				(width 0.1)
				(type default)
			)
			(layer "B.Fab")
		)
		(fp_line
			(start -0.9144 0.1016)
			(end 0.9144 0.1016)
			(stroke
				(width 0.1)
				(type default)
			)
			(layer "B.Fab")
		)
		(fp_line
			(start 0.9144 2.9464)
			(end -0.9144 2.9464)
			(stroke
				(width 0.1)
				(type default)
			)
			(layer "B.Fab")
		)
		(fp_line
			(start -0.9144 2.9464)
			(end -0.9144 0.1016)
			(stroke
				(width 0.1)
				(type default)
			)
			(layer "B.Fab")
		)
		(fp_circle
			(center -1.128776 -0.907288)
			(end -1.128776 -0.780288)
			(stroke
				(width 0.254)
				(type default)
			)
			(fill no)
			(layer "B.Fab")
		)
		(pad "1" smd rect
			(at 0 0)
			(size 1.524 0.762)
			(layers "B.Cu" "B.Mask" "B.Paste")
			(net "FM_DB_UART_SEL4_N")
		)
		(pad "2" smd rect
			(at 0 3.048 180)
			(size 1.524 0.762)
			(layers "B.Cu" "B.Mask" "B.Paste")
			(net "FM_DB_UART_SEL3_N")
		)
	)
	(footprint ""
		(layer "B.Cu")
		(at 18.5674 -84.3026 90)
		(property "Reference" "R9P7"
			(at 0 0 90)
			(layer "B.SilkS")
			(hide yes)
			(effects
				(font
					(size 1.27 1.27)
				)
				(justify mirror)
			)
		)
		(property "Value" ""
			(at 0 0 90)
			(layer "B.Fab")
			(effects
				(font
					(size 1.27 1.27)
				)
				(justify mirror)
			)
		)
		(duplicate_pad_numbers_are_jumpers no)
		(fp_poly
			(pts
				(xy 0.2794 -0.1016) (xy -0.2794 -0.1016) (xy -0.2794 0.9906) (xy 0.2794 0.9906)
			)
			(stroke
				(width 0)
				(type default)
			)
			(fill no)
			(layer "B.CrtYd")
		)
		(fp_line
			(start 0.2794 -0.1016)
			(end 0.2794 0.9906)
			(stroke
				(width 0.1)
				(type default)
			)
			(layer "B.Fab")
		)
		(fp_line
			(start -0.2794 -0.1016)
			(end 0.2794 -0.1016)
			(stroke
				(width 0.1)
				(type default)
			)
			(layer "B.Fab")
		)
		(fp_line
			(start 0.2794 0.9906)
			(end -0.2794 0.9906)
			(stroke
				(width 0.1)
				(type default)
			)
			(layer "B.Fab")
		)
		(fp_line
			(start -0.2794 0.9906)
			(end -0.2794 -0.1016)
			(stroke
				(width 0.1)
				(type default)
			)
			(layer "B.Fab")
		)
		(pad "1" smd rect
			(at 0 0 270)
			(size 0.508 0.508)
			(layers "B.Cu" "B.Mask" "B.Paste")
			(net "P12V_STBY")
		)
		(pad "2" smd rect
			(at 0 0.889 270)
			(size 0.508 0.508)
			(layers "B.Cu" "B.Mask" "B.Paste")
			(net "A_P12V_STBY_ADR_TRIGGER")
		)
		(zone
			(layer "B.Cu")
			(hatch none 0.5)
			(connect_pads
				(clearance 0)
			)
			(min_thickness 0.25)
			(keepout
				(tracks allowed)
				(vias not_allowed)
				(pads allowed)
				(copperpour not_allowed)
				(footprints allowed)
			)
			(placement
				(enabled no)
				(sheetname "")
			)
			(fill
				(thermal_gap 0.5)
				(thermal_bridge_width 0.5)
				(island_removal_mode 0)
			)
			(polygon
				(pts
					(xy 18.8214 -84.5566) (xy 18.8214 -84.0486) (xy 19.2024 -84.0486) (xy 19.2024 -84.5566)
				)
			)
		)
		(zone
			(layer "B.Cu")
			(hatch none 0.5)
			(connect_pads
				(clearance 0)
			)
			(min_thickness 0.25)
			(keepout
				(tracks not_allowed)
				(vias allowed)
				(pads allowed)
				(copperpour not_allowed)
				(footprints allowed)
			)
			(placement
				(enabled no)
				(sheetname "")
			)
			(fill
				(thermal_gap 0.5)
				(thermal_bridge_width 0.5)
				(island_removal_mode 0)
			)
			(polygon
				(pts
					(xy 19.2024 -84.5566) (xy 19.2024 -84.0486) (xy 18.8214 -84.0486) (xy 18.8214 -84.5566)
				)
			)
		)
	)
	(footprint ""
		(layer "B.Cu")
		(at 325.5264 -122.81916)
		(property "Reference" "U7E1"
			(at 0.64262 2.90957 0)
			(unlocked yes)
			(layer "B.SilkS")
			(effects
				(font
					(size 0.7874 0.5842)
					(thickness 0.1524)
				)
				(justify mirror)
			)
		)
		(property "Value" ""
			(at 0 0 0)
			(layer "B.Fab")
			(effects
				(font
					(size 1.27 1.27)
				)
				(justify mirror)
			)
		)
		(duplicate_pad_numbers_are_jumpers no)
		(fp_line
			(start -3.225292 -0.57404)
			(end -1.352804 -0.57404)
			(stroke
				(width 0.1524)
				(type default)
			)
			(layer "B.SilkS")
		)
		(fp_line
			(start -3.225038 2.52476)
			(end -1.348486 2.52476)
			(stroke
				(width 0.1524)
				(type default)
			)
			(layer "B.SilkS")
		)
		(fp_circle
			(center 1.454404 -0.556514)
			(end 1.581404 -0.556514)
			(stroke
				(width 0.254)
				(type default)
			)
			(fill no)
			(layer "B.SilkS")
		)
		(fp_poly
			(pts
				(xy -0.7366 -0.57404) (xy -3.8354 -0.57404) (xy -3.8354 2.52476) (xy -0.7366 2.52476)
			)
			(stroke
				(width 0)
				(type default)
			)
			(fill no)
			(layer "B.CrtYd")
		)
		(fp_line
			(start -3.8354 -0.57404)
			(end -3.8354 2.52476)
			(stroke
				(width 0.1)
				(type default)
			)
			(layer "B.Fab")
		)
		(fp_line
			(start -3.8354 2.52476)
			(end -0.7366 2.52476)
			(stroke
				(width 0.1)
				(type default)
			)
			(layer "B.Fab")
		)
		(fp_line
			(start -0.7366 -0.57404)
			(end -3.8354 -0.57404)
			(stroke
				(width 0.1)
				(type default)
			)
			(layer "B.Fab")
		)
		(fp_line
			(start -0.7366 2.52476)
			(end -0.7366 -0.57404)
			(stroke
				(width 0.1)
				(type default)
			)
			(layer "B.Fab")
		)
		(fp_circle
			(center 1.454404 -0.556514)
			(end 1.581404 -0.556514)
			(stroke
				(width 0.254)
				(type default)
			)
			(fill no)
			(layer "B.Fab")
		)
		(pad "1" smd rect
			(at 0 0 180)
			(size 1.778 0.4572)
			(layers "B.Cu" "B.Mask" "B.Paste")
			(net "PVCCIO_CPU0")
		)
		(pad "2" smd rect
			(at 0 0.65024 180)
			(size 1.778 0.4572)
			(layers "B.Cu" "B.Mask" "B.Paste")
			(net "SMB_DDR_DEF_SCL_G")
		)
		(pad "3" smd rect
			(at 0 1.30048 180)
			(size 1.778 0.4572)
			(layers "B.Cu" "B.Mask" "B.Paste")
			(net "SMB_DDR_DEF_SDA_G")
		)
		(pad "4" smd rect
			(at 0 1.95072 180)
			(size 1.778 0.4572)
			(layers "B.Cu" "B.Mask" "B.Paste")
			(net "GND")
		)
		(pad "5" smd rect
			(at -4.572 1.95072 180)
			(size 1.778 0.4572)
			(layers "B.Cu" "B.Mask" "B.Paste")
			(net "TP_SMB_DDR_DEF_EN")
		)
		(pad "6" smd rect
			(at -4.572 1.30048 180)
			(size 1.778 0.4572)
			(layers "B.Cu" "B.Mask" "B.Paste")
			(net "SMB_DDR_DEF_VPP_SDA_R")
		)
		(pad "7" smd rect
			(at -4.572 0.65024 180)
			(size 1.778 0.4572)
			(layers "B.Cu" "B.Mask" "B.Paste")
			(net "SMB_DDR_DEF_VPP_SCL_R")
		)
		(pad "8" smd rect
			(at -4.572 0 180)
			(size 1.778 0.4572)
			(layers "B.Cu" "B.Mask" "B.Paste")
			(net "PVPP_DEF")
		)
	)
	(footprint ""
		(layer "B.Cu")
		(at 390.906 -84.709 180)
		(property "Reference" "R2L5"
			(at 0 0 0)
			(layer "B.SilkS")
			(hide yes)
			(effects
				(font
					(size 1.27 1.27)
				)
				(justify mirror)
			)
		)
		(property "Value" ""
			(at 0 0 0)
			(layer "B.Fab")
			(effects
				(font
					(size 1.27 1.27)
				)
				(justify mirror)
			)
		)
		(duplicate_pad_numbers_are_jumpers no)
		(fp_poly
			(pts
				(xy 0.2794 -0.1016) (xy -0.2794 -0.1016) (xy -0.2794 0.9906) (xy 0.2794 0.9906)
			)
			(stroke
				(width 0)
				(type default)
			)
			(fill no)
			(layer "B.CrtYd")
		)
		(fp_line
			(start 0.2794 0.9906)
			(end -0.2794 0.9906)
			(stroke
				(width 0.1)
				(type default)
			)
			(layer "B.Fab")
		)
		(fp_line
			(start 0.2794 -0.1016)
			(end 0.2794 0.9906)
			(stroke
				(width 0.1)
				(type default)
			)
			(layer "B.Fab")
		)
		(fp_line
			(start -0.2794 0.9906)
			(end -0.2794 -0.1016)
			(stroke
				(width 0.1)
				(type default)
			)
			(layer "B.Fab")
		)
		(fp_line
			(start -0.2794 -0.1016)
			(end 0.2794 -0.1016)
			(stroke
				(width 0.1)
				(type default)
			)
			(layer "B.Fab")
		)
		(pad "1" smd rect
			(at 0 0)
			(size 0.508 0.508)
			(layers "B.Cu" "B.Mask" "B.Paste")
			(net "P3V3_STBY")
		)
		(pad "2" smd rect
			(at 0 0.889)
			(size 0.508 0.508)
			(layers "B.Cu" "B.Mask" "B.Paste")
			(net "SGPIO_PCH_SSATA_LOAD_R")
		)
		(zone
			(layer "B.Cu")
			(hatch none 0.5)
			(connect_pads
				(clearance 0)
			)
			(min_thickness 0.25)
			(keepout
				(tracks not_allowed)
				(vias allowed)
				(pads allowed)
				(copperpour not_allowed)
				(footprints allowed)
			)
			(placement
				(enabled no)
				(sheetname "")
			)
			(fill
				(thermal_gap 0.5)
				(thermal_bridge_width 0.5)
				(island_removal_mode 0)
			)
			(polygon
				(pts
					(xy 390.652 -85.344) (xy 391.16 -85.344) (xy 391.16 -84.963) (xy 390.652 -84.963)
				)
			)
		)
		(zone
			(layer "B.Cu")
			(hatch none 0.5)
			(connect_pads
				(clearance 0)
			)
			(min_thickness 0.25)
			(keepout
				(tracks allowed)
				(vias not_allowed)
				(pads allowed)
				(copperpour not_allowed)
				(footprints allowed)
			)
			(placement
				(enabled no)
				(sheetname "")
			)
			(fill
				(thermal_gap 0.5)
				(thermal_bridge_width 0.5)
				(island_removal_mode 0)
			)
			(polygon
				(pts
					(xy 390.652 -84.963) (xy 391.16 -84.963) (xy 391.16 -85.344) (xy 390.652 -85.344)
				)
			)
		)
	)
	(footprint ""
		(layer "B.Cu")
		(at 463.55 -127.9398 180)
		(property "Reference" "R1M24"
			(at 0 0 0)
			(layer "B.SilkS")
			(hide yes)
			(effects
				(font
					(size 1.27 1.27)
				)
				(justify mirror)
			)
		)
		(property "Value" ""
			(at 0 0 0)
			(layer "B.Fab")
			(effects
				(font
					(size 1.27 1.27)
				)
				(justify mirror)
			)
		)
		(duplicate_pad_numbers_are_jumpers no)
		(fp_poly
			(pts
				(xy 0.2794 -0.1016) (xy -0.2794 -0.1016) (xy -0.2794 0.9906) (xy 0.2794 0.9906)
			)
			(stroke
				(width 0)
				(type default)
			)
			(fill no)
			(layer "B.CrtYd")
		)
		(fp_line
			(start 0.2794 0.9906)
			(end -0.2794 0.9906)
			(stroke
				(width 0.1)
				(type default)
			)
			(layer "B.Fab")
		)
		(fp_line
			(start 0.2794 -0.1016)
			(end 0.2794 0.9906)
			(stroke
				(width 0.1)
				(type default)
			)
			(layer "B.Fab")
		)
		(fp_line
			(start -0.2794 0.9906)
			(end -0.2794 -0.1016)
			(stroke
				(width 0.1)
				(type default)
			)
			(layer "B.Fab")
		)
		(fp_line
			(start -0.2794 -0.1016)
			(end 0.2794 -0.1016)
			(stroke
				(width 0.1)
				(type default)
			)
			(layer "B.Fab")
		)
		(pad "1" smd rect
			(at 0 0)
			(size 0.508 0.508)
			(layers "B.Cu" "B.Mask" "B.Paste")
			(net "P3V3_STBY")
		)
		(pad "2" smd rect
			(at 0 0.889)
			(size 0.508 0.508)
			(layers "B.Cu" "B.Mask" "B.Paste")
			(net "FM_OC0_USB_N")
		)
		(zone
			(layer "B.Cu")
			(hatch none 0.5)
			(connect_pads
				(clearance 0)
			)
			(min_thickness 0.25)
			(keepout
				(tracks not_allowed)
				(vias allowed)
				(pads allowed)
				(copperpour not_allowed)
				(footprints allowed)
			)
			(placement
				(enabled no)
				(sheetname "")
			)
			(fill
				(thermal_gap 0.5)
				(thermal_bridge_width 0.5)
				(island_removal_mode 0)
			)
			(polygon
				(pts
					(xy 463.296 -128.5748) (xy 463.804 -128.5748) (xy 463.804 -128.1938) (xy 463.296 -128.1938)
				)
			)
		)
		(zone
			(layer "B.Cu")
			(hatch none 0.5)
			(connect_pads
				(clearance 0)
			)
			(min_thickness 0.25)
			(keepout
				(tracks allowed)
				(vias not_allowed)
				(pads allowed)
				(copperpour not_allowed)
				(footprints allowed)
			)
			(placement
				(enabled no)
				(sheetname "")
			)
			(fill
				(thermal_gap 0.5)
				(thermal_bridge_width 0.5)
				(island_removal_mode 0)
			)
			(polygon
				(pts
					(xy 463.296 -128.1938) (xy 463.804 -128.1938) (xy 463.804 -128.5748) (xy 463.296 -128.5748)
				)
			)
		)
	)
	(footprint ""
		(layer "B.Cu")
		(at 419.6715 -71.9455)
		(property "Reference" "Q8F2"
			(at 1.16967 4.13004 270)
			(unlocked yes)
			(layer "B.SilkS")
			(effects
				(font
					(size 0.7874 0.5842)
					(thickness 0.1524)
				)
				(justify left mirror)
			)
		)
		(property "Value" ""
			(at 0 0 0)
			(layer "B.Fab")
			(effects
				(font
					(size 1.27 1.27)
				)
				(justify mirror)
			)
		)
		(duplicate_pad_numbers_are_jumpers no)
		(fp_line
			(start -1.778 -0.5715)
			(end -1.778 0.3175)
			(stroke
				(width 0.1524)
				(type default)
			)
			(layer "B.SilkS")
		)
		(fp_line
			(start -1.778 2.4765)
			(end -1.778 1.5875)
			(stroke
				(width 0.1524)
				(type default)
			)
			(layer "B.SilkS")
		)
		(fp_line
			(start -0.9525 -0.5715)
			(end -1.778 -0.5715)
			(stroke
				(width 0.1524)
				(type default)
			)
			(layer "B.SilkS")
		)
		(fp_line
			(start -0.9525 2.4765)
			(end -1.778 2.4765)
			(stroke
				(width 0.1524)
				(type default)
			)
			(layer "B.SilkS")
		)
		(fp_line
			(start -0.381 0.635)
			(end -0.381 1.27)
			(stroke
				(width 0.1524)
				(type default)
			)
			(layer "B.SilkS")
		)
		(fp_circle
			(center 0.9525 -0.9271)
			(end 1.0795 -0.9271)
			(stroke
				(width 0.254)
				(type default)
			)
			(fill no)
			(layer "B.SilkS")
		)
		(fp_poly
			(pts
				(xy -1.778 2.4765) (xy -0.381 2.4765) (xy -0.381 -0.5715) (xy -1.778 -0.5715)
			)
			(stroke
				(width 0)
				(type default)
			)
			(fill no)
			(layer "B.CrtYd")
		)
		(fp_line
			(start -1.778 -0.5715)
			(end -0.381 -0.5715)
			(stroke
				(width 0.1)
				(type default)
			)
			(layer "B.Fab")
		)
		(fp_line
			(start -1.778 2.4765)
			(end -1.778 -0.5715)
			(stroke
				(width 0.1)
				(type default)
			)
			(layer "B.Fab")
		)
		(fp_line
			(start -0.381 -0.5715)
			(end -0.381 2.4765)
			(stroke
				(width 0.1)
				(type default)
			)
			(layer "B.Fab")
		)
		(fp_line
			(start -0.381 2.4765)
			(end -1.778 2.4765)
			(stroke
				(width 0.1)
				(type default)
			)
			(layer "B.Fab")
		)
		(fp_circle
			(center 0.9525 -0.9271)
			(end 1.0795 -0.9271)
			(stroke
				(width 0.254)
				(type default)
			)
			(fill no)
			(layer "B.Fab")
		)
		(pad "1" smd rect
			(at 0 0 180)
			(size 1.143 0.508)
			(layers "B.Cu" "B.Mask" "B.Paste")
			(net "FM_FAST_PROCHOT_EN_N")
		)
		(pad "2" smd rect
			(at 0 1.905 180)
			(size 1.143 0.508)
			(layers "B.Cu" "B.Mask" "B.Paste")
			(net "GND")
		)
		(pad "3" smd rect
			(at -2.159 0.9525 180)
			(size 1.143 0.508)
			(layers "B.Cu" "B.Mask" "B.Paste")
			(net "FM_FAST_PROCHOT_EN")
		)
	)
	(footprint ""
		(layer "B.Cu")
		(at 20.3454 -78.0542 -90)
		(property "Reference" "R9P16"
			(at 0 0 90)
			(layer "B.SilkS")
			(hide yes)
			(effects
				(font
					(size 1.27 1.27)
				)
				(justify mirror)
			)
		)
		(property "Value" ""
			(at 0 0 90)
			(layer "B.Fab")
			(effects
				(font
					(size 1.27 1.27)
				)
				(justify mirror)
			)
		)
		(duplicate_pad_numbers_are_jumpers no)
		(fp_rect
			(start 0.2794 -0.1016)
			(end -0.2794 0.9906)
			(stroke
				(width 0)
				(type default)
			)
			(fill no)
			(layer "B.CrtYd")
		)
		(fp_line
			(start -0.2794 0.9906)
			(end -0.2794 -0.1016)
			(stroke
				(width 0.1)
				(type default)
			)
			(layer "B.Fab")
		)
		(fp_line
			(start 0.2794 0.9906)
			(end -0.2794 0.9906)
			(stroke
				(width 0.1)
				(type default)
			)
			(layer "B.Fab")
		)
		(fp_line
			(start -0.2794 -0.1016)
			(end 0.2794 -0.1016)
			(stroke
				(width 0.1)
				(type default)
			)
			(layer "B.Fab")
		)
		(fp_line
			(start 0.2794 -0.1016)
			(end 0.2794 0.9906)
			(stroke
				(width 0.1)
				(type default)
			)
			(layer "B.Fab")
		)
		(pad "1" smd rect
			(at 0 0 90)
			(size 0.508 0.508)
			(layers "B.Cu" "B.Mask" "B.Paste")
			(net "FM_P12V_HSC_ADR2")
		)
		(pad "2" smd rect
			(at 0 0.889 90)
			(size 0.508 0.508)
			(layers "B.Cu" "B.Mask" "B.Paste")
			(net "AGND_HSC")
		)
		(zone
			(layer "B.Cu")
			(hatch none 0.5)
			(connect_pads
				(clearance 0)
			)
			(min_thickness 0.25)
			(keepout
				(tracks not_allowed)
				(vias allowed)
				(pads allowed)
				(copperpour not_allowed)
				(footprints allowed)
			)
			(placement
				(enabled no)
				(sheetname "")
			)
			(fill
				(thermal_gap 0.5)
				(thermal_bridge_width 0.5)
				(island_removal_mode 0)
			)
			(polygon
				(pts
					(xy 20.0914 -77.8002) (xy 20.0914 -78.3082) (xy 19.7104 -78.3082) (xy 19.7104 -77.8002)
				)
			)
		)
		(zone
			(layer "B.Cu")
			(hatch none 0.5)
			(connect_pads
				(clearance 0)
			)
			(min_thickness 0.25)
			(keepout
				(tracks allowed)
				(vias not_allowed)
				(pads allowed)
				(copperpour not_allowed)
				(footprints allowed)
			)
			(placement
				(enabled no)
				(sheetname "")
			)
			(fill
				(thermal_gap 0.5)
				(thermal_bridge_width 0.5)
				(island_removal_mode 0)
			)
			(polygon
				(pts
					(xy 20.0914 -77.8002) (xy 20.0914 -78.3082) (xy 19.7104 -78.3082) (xy 19.7104 -77.8002)
				)
			)
		)
	)
	(footprint ""
		(layer "B.Cu")
		(at 416.3695 -30.988 90)
		(property "Reference" "C25W39"
			(at -0.97536 0.76708 180)
			(unlocked yes)
			(layer "B.SilkS")
			(effects
				(font
					(size 0.4064 0.254)
					(thickness 0.1524)
				)
				(justify mirror)
			)
		)
		(property "Value" ""
			(at 0 0 90)
			(layer "B.Fab")
			(effects
				(font
					(size 1.27 1.27)
				)
				(justify mirror)
			)
		)
		(duplicate_pad_numbers_are_jumpers no)
		(fp_poly
			(pts
				(xy 0.4953 -0.2032) (xy -0.4953 -0.2032) (xy -0.4953 1.6002) (xy 0.4953 1.6002)
			)
			(stroke
				(width 0)
				(type default)
			)
			(fill no)
			(layer "B.CrtYd")
		)
		(fp_line
			(start 0.4953 -0.2032)
			(end -0.4953 -0.2032)
			(stroke
				(width 0.1)
				(type default)
			)
			(layer "B.Fab")
		)
		(fp_line
			(start -0.4953 -0.2032)
			(end -0.4953 1.6002)
			(stroke
				(width 0.1)
				(type default)
			)
			(layer "B.Fab")
		)
		(fp_line
			(start 0.4953 1.6002)
			(end 0.4953 -0.2032)
			(stroke
				(width 0.1)
				(type default)
			)
			(layer "B.Fab")
		)
		(fp_line
			(start -0.4953 1.6002)
			(end 0.4953 1.6002)
			(stroke
				(width 0.1)
				(type default)
			)
			(layer "B.Fab")
		)
		(pad "1" smd rect
			(at 0 0 270)
			(size 0.762 0.889)
			(layers "B.Cu" "B.Mask" "B.Paste")
			(net "VCC_A_1V1")
		)
		(pad "2" smd rect
			(at 0 1.397 270)
			(size 0.762 0.889)
			(layers "B.Cu" "B.Mask" "B.Paste")
			(net "GND")
		)
		(zone
			(layer "B.Cu")
			(hatch none 0.5)
			(connect_pads
				(clearance 0)
			)
			(min_thickness 0.25)
			(keepout
				(tracks not_allowed)
				(vias allowed)
				(pads allowed)
				(copperpour not_allowed)
				(footprints allowed)
			)
			(placement
				(enabled no)
				(sheetname "")
			)
			(fill
				(thermal_gap 0.5)
				(thermal_bridge_width 0.5)
				(island_removal_mode 0)
			)
			(polygon
				(pts
					(xy 416.814 -31.369) (xy 416.814 -30.607) (xy 417.322 -30.607) (xy 417.322 -31.369)
				)
			)
		)
	)
	(footprint ""
		(layer "B.Cu")
		(at 458.851 -116.49202)
		(property "Reference" "C1M11"
			(at 0 0 0)
			(layer "B.SilkS")
			(hide yes)
			(effects
				(font
					(size 1.27 1.27)
				)
				(justify mirror)
			)
		)
		(property "Value" ""
			(at 0 0 0)
			(layer "B.Fab")
			(effects
				(font
					(size 1.27 1.27)
				)
				(justify mirror)
			)
		)
		(duplicate_pad_numbers_are_jumpers no)
		(fp_rect
			(start -0.3048 0.9906)
			(end 0.3048 -0.1016)
			(stroke
				(width 0)
				(type default)
			)
			(fill no)
			(layer "B.CrtYd")
		)
		(fp_line
			(start -0.3048 -0.1016)
			(end 0.3048 -0.1016)
			(stroke
				(width 0.1)
				(type default)
			)
			(layer "B.Fab")
		)
		(fp_line
			(start -0.3048 0.9906)
			(end -0.3048 -0.1016)
			(stroke
				(width 0.1)
				(type default)
			)
			(layer "B.Fab")
		)
		(fp_line
			(start 0.3048 -0.1016)
			(end 0.3048 0.9906)
			(stroke
				(width 0.1)
				(type default)
			)
			(layer "B.Fab")
		)
		(fp_line
			(start 0.3048 0.9906)
			(end -0.3048 0.9906)
			(stroke
				(width 0.1)
				(type default)
			)
			(layer "B.Fab")
		)
		(pad "1" smd rect
			(at 0 0 180)
			(size 0.508 0.508)
			(layers "B.Cu" "B.Mask" "B.Paste")
			(net "P3E_CPU0_PE3_OCP_TXN<13>")
		)
		(pad "2" smd rect
			(at 0 0.889 180)
			(size 0.508 0.508)
			(layers "B.Cu" "B.Mask" "B.Paste")
			(net "P3E_OCP_CPU0_PE3_C_TXN<13>")
		)
		(zone
			(layer "B.Cu")
			(hatch none 0.5)
			(connect_pads
				(clearance 0)
			)
			(min_thickness 0.25)
			(keepout
				(tracks not_allowed)
				(vias allowed)
				(pads allowed)
				(copperpour not_allowed)
				(footprints allowed)
			)
			(placement
				(enabled no)
				(sheetname "")
			)
			(fill
				(thermal_gap 0.5)
				(thermal_bridge_width 0.5)
				(island_removal_mode 0)
			)
			(polygon
				(pts
					(xy 458.597 -115.85702) (xy 459.105 -115.85702) (xy 459.105 -116.23802) (xy 458.597 -116.23802)
				)
			)
		)
		(zone
			(layer "B.Cu")
			(hatch none 0.5)
			(connect_pads
				(clearance 0)
			)
			(min_thickness 0.25)
			(keepout
				(tracks allowed)
				(vias not_allowed)
				(pads allowed)
				(copperpour not_allowed)
				(footprints allowed)
			)
			(placement
				(enabled no)
				(sheetname "")
			)
			(fill
				(thermal_gap 0.5)
				(thermal_bridge_width 0.5)
				(island_removal_mode 0)
			)
			(polygon
				(pts
					(xy 458.597 -115.85702) (xy 459.105 -115.85702) (xy 459.105 -116.23802) (xy 458.597 -116.23802)
				)
			)
		)
	)
	(footprint ""
		(layer "B.Cu")
		(at 475.361 -34.29)
		(property "Reference" "C1W17"
			(at -1.47828 0.78994 90)
			(unlocked yes)
			(layer "B.SilkS")
			(effects
				(font
					(size 0.4064 0.254)
					(thickness 0.1524)
				)
				(justify mirror)
			)
		)
		(property "Value" ""
			(at 0 0 0)
			(layer "B.Fab")
			(effects
				(font
					(size 1.27 1.27)
				)
				(justify mirror)
			)
		)
		(duplicate_pad_numbers_are_jumpers no)
		(fp_poly
			(pts
				(xy 0.7239 -0.2159) (xy -0.7239 -0.2159) (xy -0.7239 1.9939) (xy 0.7239 1.9939)
			)
			(stroke
				(width 0)
				(type default)
			)
			(fill no)
			(layer "B.CrtYd")
		)
		(fp_line
			(start -0.7239 -0.2159)
			(end 0.7239 -0.2159)
			(stroke
				(width 0.1)
				(type default)
			)
			(layer "B.Fab")
		)
		(fp_line
			(start -0.7239 1.9939)
			(end -0.7239 -0.2159)
			(stroke
				(width 0.1)
				(type default)
			)
			(layer "B.Fab")
		)
		(fp_line
			(start 0.7239 -0.2159)
			(end 0.7239 1.9939)
			(stroke
				(width 0.1)
				(type default)
			)
			(layer "B.Fab")
		)
		(fp_line
			(start 0.7239 1.9939)
			(end -0.7239 1.9939)
			(stroke
				(width 0.1)
				(type default)
			)
			(layer "B.Fab")
		)
		(pad "1" smd rect
			(at 0 0 180)
			(size 1.27 1.016)
			(layers "B.Cu" "B.Mask" "B.Paste")
			(net "P3V3_STBY_MNG_RMII")
		)
		(pad "2" smd rect
			(at 0 1.778 180)
			(size 1.27 1.016)
			(layers "B.Cu" "B.Mask" "B.Paste")
			(net "GND")
		)
		(zone
			(layer "B.Cu")
			(hatch none 0.5)
			(connect_pads
				(clearance 0)
			)
			(min_thickness 0.25)
			(keepout
				(tracks not_allowed)
				(vias allowed)
				(pads allowed)
				(copperpour not_allowed)
				(footprints allowed)
			)
			(placement
				(enabled no)
				(sheetname "")
			)
			(fill
				(thermal_gap 0.5)
				(thermal_bridge_width 0.5)
				(island_removal_mode 0)
			)
			(polygon
				(pts
					(xy 475.996 -33.782) (xy 474.726 -33.782) (xy 474.726 -33.02) (xy 475.996 -33.02)
				)
			)
		)
	)
	(footprint ""
		(layer "B.Cu")
		(at 489.08589 -33.674812 180)
		(property "Reference" "C1T11"
			(at 0 0 0)
			(layer "B.SilkS")
			(hide yes)
			(effects
				(font
					(size 1.27 1.27)
				)
				(justify mirror)
			)
		)
		(property "Value" ""
			(at 0 0 0)
			(layer "B.Fab")
			(effects
				(font
					(size 1.27 1.27)
				)
				(justify mirror)
			)
		)
		(duplicate_pad_numbers_are_jumpers no)
		(fp_poly
			(pts
				(xy -0.3048 -0.1016) (xy -0.3048 0.9906) (xy 0.3048 0.9906) (xy 0.3048 -0.1016)
			)
			(stroke
				(width 0)
				(type default)
			)
			(fill no)
			(layer "B.CrtYd")
		)
		(fp_line
			(start 0.3048 0.9906)
			(end -0.3048 0.9906)
			(stroke
				(width 0.1)
				(type default)
			)
			(layer "B.Fab")
		)
		(fp_line
			(start 0.3048 -0.1016)
			(end 0.3048 0.9906)
			(stroke
				(width 0.1)
				(type default)
			)
			(layer "B.Fab")
		)
		(fp_line
			(start -0.3048 0.9906)
			(end -0.3048 -0.1016)
			(stroke
				(width 0.1)
				(type default)
			)
			(layer "B.Fab")
		)
		(fp_line
			(start -0.3048 -0.1016)
			(end 0.3048 -0.1016)
			(stroke
				(width 0.1)
				(type default)
			)
			(layer "B.Fab")
		)
		(pad "1" smd rect
			(at 0 0)
			(size 0.508 0.508)
			(layers "B.Cu" "B.Mask" "B.Paste")
			(net "P3V3_STBY")
		)
		(pad "2" smd rect
			(at 0 0.889)
			(size 0.508 0.508)
			(layers "B.Cu" "B.Mask" "B.Paste")
			(net "GND")
		)
		(zone
			(layer "B.Cu")
			(hatch none 0.5)
			(connect_pads
				(clearance 0)
			)
			(min_thickness 0.25)
			(keepout
				(tracks not_allowed)
				(vias allowed)
				(pads allowed)
				(copperpour not_allowed)
				(footprints allowed)
			)
			(placement
				(enabled no)
				(sheetname "")
			)
			(fill
				(thermal_gap 0.5)
				(thermal_bridge_width 0.5)
				(island_removal_mode 0)
			)
			(polygon
				(pts
					(xy 488.83189 -34.309812) (xy 489.33989 -34.309812) (xy 489.33989 -33.928812) (xy 488.83189 -33.928812)
				)
			)
		)
		(zone
			(layer "B.Cu")
			(hatch none 0.5)
			(connect_pads
				(clearance 0)
			)
			(min_thickness 0.25)
			(keepout
				(tracks allowed)
				(vias not_allowed)
				(pads allowed)
				(copperpour not_allowed)
				(footprints allowed)
			)
			(placement
				(enabled no)
				(sheetname "")
			)
			(fill
				(thermal_gap 0.5)
				(thermal_bridge_width 0.5)
				(island_removal_mode 0)
			)
			(polygon
				(pts
					(xy 488.83189 -33.928812) (xy 489.33989 -33.928812) (xy 489.33989 -34.309812) (xy 488.83189 -34.309812)
				)
			)
		)
	)
	(footprint ""
		(layer "B.Cu")
		(at 408.333956 -114.984784 180)
		(property "Reference" "C2M11"
			(at 0 0 0)
			(layer "B.SilkS")
			(hide yes)
			(effects
				(font
					(size 1.27 1.27)
				)
				(justify mirror)
			)
		)
		(property "Value" ""
			(at 0 0 0)
			(layer "B.Fab")
			(effects
				(font
					(size 1.27 1.27)
				)
				(justify mirror)
			)
		)
		(duplicate_pad_numbers_are_jumpers no)
		(fp_poly
			(pts
				(xy 0.7239 -0.2159) (xy -0.7239 -0.2159) (xy -0.7239 1.9939) (xy 0.7239 1.9939)
			)
			(stroke
				(width 0)
				(type default)
			)
			(fill no)
			(layer "B.CrtYd")
		)
		(fp_line
			(start 0.7239 1.9939)
			(end -0.7239 1.9939)
			(stroke
				(width 0.1)
				(type default)
			)
			(layer "B.Fab")
		)
		(fp_line
			(start 0.7239 -0.2159)
			(end 0.7239 1.9939)
			(stroke
				(width 0.1)
				(type default)
			)
			(layer "B.Fab")
		)
		(fp_line
			(start -0.7239 1.9939)
			(end -0.7239 -0.2159)
			(stroke
				(width 0.1)
				(type default)
			)
			(layer "B.Fab")
		)
		(fp_line
			(start -0.7239 -0.2159)
			(end 0.7239 -0.2159)
			(stroke
				(width 0.1)
				(type default)
			)
			(layer "B.Fab")
		)
		(pad "1" smd rect
			(at 0 0)
			(size 1.27 1.016)
			(layers "B.Cu" "B.Mask" "B.Paste")
			(net "P1V05_PCH_STBY")
		)
		(pad "2" smd rect
			(at 0 1.778)
			(size 1.27 1.016)
			(layers "B.Cu" "B.Mask" "B.Paste")
			(net "GND")
		)
		(zone
			(layer "B.Cu")
			(hatch none 0.5)
			(connect_pads
				(clearance 0)
			)
			(min_thickness 0.25)
			(keepout
				(tracks not_allowed)
				(vias allowed)
				(pads allowed)
				(copperpour not_allowed)
				(footprints allowed)
			)
			(placement
				(enabled no)
				(sheetname "")
			)
			(fill
				(thermal_gap 0.5)
				(thermal_bridge_width 0.5)
				(island_removal_mode 0)
			)
			(polygon
				(pts
					(xy 407.698956 -115.492784) (xy 408.968956 -115.492784) (xy 408.968956 -116.254784) (xy 407.698956 -116.254784)
				)
			)
		)
	)
	(footprint ""
		(layer "B.Cu")
		(at 390.13765 -113.45545)
		(property "Reference" "C2M22"
			(at 0 0 0)
			(layer "B.SilkS")
			(hide yes)
			(effects
				(font
					(size 1.27 1.27)
				)
				(justify mirror)
			)
		)
		(property "Value" ""
			(at 0 0 0)
			(layer "B.Fab")
			(effects
				(font
					(size 1.27 1.27)
				)
				(justify mirror)
			)
		)
		(duplicate_pad_numbers_are_jumpers no)
		(fp_rect
			(start 0.2794 0.9144)
			(end -0.2794 -0.1143)
			(stroke
				(width 0)
				(type default)
			)
			(fill no)
			(layer "B.CrtYd")
		)
		(fp_line
			(start -0.2794 -0.1143)
			(end -0.2794 0.9144)
			(stroke
				(width 0.1)
				(type default)
			)
			(layer "B.Fab")
		)
		(fp_line
			(start -0.2794 0.9144)
			(end 0.2794 0.9144)
			(stroke
				(width 0.1)
				(type default)
			)
			(layer "B.Fab")
		)
		(fp_line
			(start 0.2794 -0.1143)
			(end -0.2794 -0.1143)
			(stroke
				(width 0.1)
				(type default)
			)
			(layer "B.Fab")
		)
		(fp_line
			(start 0.2794 0.9144)
			(end 0.2794 -0.1143)
			(stroke
				(width 0.1)
				(type default)
			)
			(layer "B.Fab")
		)
		(pad "1" smd custom
			(at 0 0 270)
			(size 0.10414 0.10414)
			(layers "B.Cu" "B.Mask" "B.Paste")
			(net "P1V05_PCH_STBY")
			(options
				(clearance outline)
				(anchor circle)
			)
			(primitives
				(gr_poly
					(pts
						(xy -0.20828 -0.08636) (xy -0.20828 0.08636) (xy -0.08636 0.20828) (xy 0.086614 0.20828) (xy 0.20828 0.086614)
						(xy 0.20828 -0.08636) (xy 0.08636 -0.20828) (xy -0.08636 -0.20828)
					)
					(width 0)
					(fill yes)
				)
			)
		)
		(pad "2" smd custom
			(at 0 0.8001 270)
			(size 0.10414 0.10414)
			(layers "B.Cu" "B.Mask" "B.Paste")
			(net "GND")
			(options
				(clearance outline)
				(anchor circle)
			)
			(primitives
				(gr_poly
					(pts
						(xy -0.20828 -0.08636) (xy -0.20828 0.08636) (xy -0.08636 0.20828) (xy 0.086614 0.20828) (xy 0.20828 0.086614)
						(xy 0.20828 -0.08636) (xy 0.08636 -0.20828) (xy -0.08636 -0.20828)
					)
					(width 0)
					(fill yes)
				)
			)
		)
		(zone
			(layer "B.Cu")
			(hatch none 0.5)
			(connect_pads
				(clearance 0)
			)
			(min_thickness 0.25)
			(keepout
				(tracks allowed)
				(vias not_allowed)
				(pads allowed)
				(copperpour not_allowed)
				(footprints allowed)
			)
			(placement
				(enabled no)
				(sheetname "")
			)
			(fill
				(thermal_gap 0.5)
				(thermal_bridge_width 0.5)
				(island_removal_mode 0)
			)
			(polygon
				(pts
					(xy 390.22528 -113.2459) (xy 390.22528 -112.8649) (xy 390.05002 -112.8649) (xy 390.049766 -113.2459)
				)
			)
		)
		(zone
			(layer "B.Cu")
			(hatch none 0.5)
			(connect_pads
				(clearance 0)
			)
			(min_thickness 0.25)
			(keepout
				(tracks not_allowed)
				(vias allowed)
				(pads allowed)
				(copperpour not_allowed)
				(footprints allowed)
			)
			(placement
				(enabled no)
				(sheetname "")
			)
			(fill
				(thermal_gap 0.5)
				(thermal_bridge_width 0.5)
				(island_removal_mode 0)
			)
			(polygon
				(pts
					(xy 390.22528 -113.2459) (xy 390.22528 -112.8649) (xy 390.05002 -112.8649) (xy 390.049766 -113.2459)
				)
			)
		)
	)
	(footprint ""
		(layer "B.Cu")
		(at 351.93732 -83.510628 -90)
		(property "Reference" "R3P22"
			(at 0 0 90)
			(layer "B.SilkS")
			(hide yes)
			(effects
				(font
					(size 1.27 1.27)
				)
				(justify mirror)
			)
		)
		(property "Value" ""
			(at 0 0 90)
			(layer "B.Fab")
			(effects
				(font
					(size 1.27 1.27)
				)
				(justify mirror)
			)
		)
		(duplicate_pad_numbers_are_jumpers no)
		(fp_poly
			(pts
				(xy 0.2794 -0.1016) (xy -0.2794 -0.1016) (xy -0.2794 0.9906) (xy 0.2794 0.9906)
			)
			(stroke
				(width 0)
				(type default)
			)
			(fill no)
			(layer "B.CrtYd")
		)
		(fp_line
			(start -0.2794 0.9906)
			(end -0.2794 -0.1016)
			(stroke
				(width 0.1)
				(type default)
			)
			(layer "B.Fab")
		)
		(fp_line
			(start 0.2794 0.9906)
			(end -0.2794 0.9906)
			(stroke
				(width 0.1)
				(type default)
			)
			(layer "B.Fab")
		)
		(fp_line
			(start -0.2794 -0.1016)
			(end 0.2794 -0.1016)
			(stroke
				(width 0.1)
				(type default)
			)
			(layer "B.Fab")
		)
		(fp_line
			(start 0.2794 -0.1016)
			(end 0.2794 0.9906)
			(stroke
				(width 0.1)
				(type default)
			)
			(layer "B.Fab")
		)
		(pad "1" smd rect
			(at 0 0 90)
			(size 0.508 0.508)
			(layers "B.Cu" "B.Mask" "B.Paste")
			(net "P3V3_STBY")
		)
		(pad "2" smd rect
			(at 0 0.889 90)
			(size 0.508 0.508)
			(layers "B.Cu" "B.Mask" "B.Paste")
			(net "VR_PVCCIO_CPU0_VDD")
		)
		(zone
			(layer "B.Cu")
			(hatch none 0.5)
			(connect_pads
				(clearance 0)
			)
			(min_thickness 0.25)
			(keepout
				(tracks not_allowed)
				(vias allowed)
				(pads allowed)
				(copperpour not_allowed)
				(footprints allowed)
			)
			(placement
				(enabled no)
				(sheetname "")
			)
			(fill
				(thermal_gap 0.5)
				(thermal_bridge_width 0.5)
				(island_removal_mode 0)
			)
			(polygon
				(pts
					(xy 351.30232 -83.256628) (xy 351.30232 -83.764628) (xy 351.68332 -83.764628) (xy 351.68332 -83.256628)
				)
			)
		)
		(zone
			(layer "B.Cu")
			(hatch none 0.5)
			(connect_pads
				(clearance 0)
			)
			(min_thickness 0.25)
			(keepout
				(tracks allowed)
				(vias not_allowed)
				(pads allowed)
				(copperpour not_allowed)
				(footprints allowed)
			)
			(placement
				(enabled no)
				(sheetname "")
			)
			(fill
				(thermal_gap 0.5)
				(thermal_bridge_width 0.5)
				(island_removal_mode 0)
			)
			(polygon
				(pts
					(xy 351.68332 -83.256628) (xy 351.68332 -83.764628) (xy 351.30232 -83.764628) (xy 351.30232 -83.256628)
				)
			)
		)
	)
	(footprint ""
		(layer "B.Cu")
		(at 453.8218 -19.7993 180)
		(property "Reference" "C3W2"
			(at 0.8382 -0.67818 180)
			(unlocked yes)
			(layer "B.SilkS")
			(effects
				(font
					(size 0.4064 0.254)
					(thickness 0.1524)
				)
				(justify left mirror)
			)
		)
		(property "Value" ""
			(at 0 0 0)
			(layer "B.Fab")
			(effects
				(font
					(size 1.27 1.27)
				)
				(justify mirror)
			)
		)
		(duplicate_pad_numbers_are_jumpers no)
		(fp_poly
			(pts
				(xy -0.3048 -0.1016) (xy -0.3048 0.9906) (xy 0.3048 0.9906) (xy 0.3048 -0.1016)
			)
			(stroke
				(width 0)
				(type default)
			)
			(fill no)
			(layer "B.CrtYd")
		)
		(fp_line
			(start 0.3048 0.9906)
			(end -0.3048 0.9906)
			(stroke
				(width 0.1)
				(type default)
			)
			(layer "B.Fab")
		)
		(fp_line
			(start 0.3048 -0.1016)
			(end 0.3048 0.9906)
			(stroke
				(width 0.1)
				(type default)
			)
			(layer "B.Fab")
		)
		(fp_line
			(start -0.3048 0.9906)
			(end -0.3048 -0.1016)
			(stroke
				(width 0.1)
				(type default)
			)
			(layer "B.Fab")
		)
		(fp_line
			(start -0.3048 -0.1016)
			(end 0.3048 -0.1016)
			(stroke
				(width 0.1)
				(type default)
			)
			(layer "B.Fab")
		)
		(pad "1" smd rect
			(at 0 0)
			(size 0.508 0.508)
			(layers "B.Cu" "B.Mask" "B.Paste")
			(net "BMC_TPM_HW_C_RST")
		)
		(pad "2" smd rect
			(at 0 0.889)
			(size 0.508 0.508)
			(layers "B.Cu" "B.Mask" "B.Paste")
			(net "GND")
		)
		(zone
			(layer "B.Cu")
			(hatch none 0.5)
			(connect_pads
				(clearance 0)
			)
			(min_thickness 0.25)
			(keepout
				(tracks not_allowed)
				(vias allowed)
				(pads allowed)
				(copperpour not_allowed)
				(footprints allowed)
			)
			(placement
				(enabled no)
				(sheetname "")
			)
			(fill
				(thermal_gap 0.5)
				(thermal_bridge_width 0.5)
				(island_removal_mode 0)
			)
			(polygon
				(pts
					(xy 453.5678 -20.4343) (xy 454.0758 -20.4343) (xy 454.0758 -20.0533) (xy 453.5678 -20.0533)
				)
			)
		)
		(zone
			(layer "B.Cu")
			(hatch none 0.5)
			(connect_pads
				(clearance 0)
			)
			(min_thickness 0.25)
			(keepout
				(tracks allowed)
				(vias not_allowed)
				(pads allowed)
				(copperpour not_allowed)
				(footprints allowed)
			)
			(placement
				(enabled no)
				(sheetname "")
			)
			(fill
				(thermal_gap 0.5)
				(thermal_bridge_width 0.5)
				(island_removal_mode 0)
			)
			(polygon
				(pts
					(xy 453.5678 -20.0533) (xy 454.0758 -20.0533) (xy 454.0758 -20.4343) (xy 453.5678 -20.4343)
				)
			)
		)
	)
	(footprint ""
		(layer "B.Cu")
		(at 416.9664 -22.225)
		(property "Reference" "R25W123"
			(at 0.8382 -0.67818 0)
			(unlocked yes)
			(layer "B.SilkS")
			(effects
				(font
					(size 0.4064 0.254)
					(thickness 0.1524)
				)
				(justify left mirror)
			)
		)
		(property "Value" ""
			(at 0 0 0)
			(layer "B.Fab")
			(effects
				(font
					(size 1.27 1.27)
				)
				(justify mirror)
			)
		)
		(duplicate_pad_numbers_are_jumpers no)
		(fp_poly
			(pts
				(xy 0.2794 -0.1016) (xy -0.2794 -0.1016) (xy -0.2794 0.9906) (xy 0.2794 0.9906)
			)
			(stroke
				(width 0)
				(type default)
			)
			(fill no)
			(layer "B.CrtYd")
		)
		(fp_line
			(start -0.2794 -0.1016)
			(end 0.2794 -0.1016)
			(stroke
				(width 0.1)
				(type default)
			)
			(layer "B.Fab")
		)
		(fp_line
			(start -0.2794 0.9906)
			(end -0.2794 -0.1016)
			(stroke
				(width 0.1)
				(type default)
			)
			(layer "B.Fab")
		)
		(fp_line
			(start 0.2794 -0.1016)
			(end 0.2794 0.9906)
			(stroke
				(width 0.1)
				(type default)
			)
			(layer "B.Fab")
		)
		(fp_line
			(start 0.2794 0.9906)
			(end -0.2794 0.9906)
			(stroke
				(width 0.1)
				(type default)
			)
			(layer "B.Fab")
		)
		(pad "1" smd rect
			(at 0 0 180)
			(size 0.508 0.508)
			(layers "B.Cu" "B.Mask" "B.Paste")
			(net "BMC_VGA_BLUE")
		)
		(pad "2" smd rect
			(at 0 0.889 180)
			(size 0.508 0.508)
			(layers "B.Cu" "B.Mask" "B.Paste")
			(net "GND")
		)
		(zone
			(layer "B.Cu")
			(hatch none 0.5)
			(connect_pads
				(clearance 0)
			)
			(min_thickness 0.25)
			(keepout
				(tracks allowed)
				(vias not_allowed)
				(pads allowed)
				(copperpour not_allowed)
				(footprints allowed)
			)
			(placement
				(enabled no)
				(sheetname "")
			)
			(fill
				(thermal_gap 0.5)
				(thermal_bridge_width 0.5)
				(island_removal_mode 0)
			)
			(polygon
				(pts
					(xy 417.2204 -21.971) (xy 416.7124 -21.971) (xy 416.7124 -21.59) (xy 417.2204 -21.59)
				)
			)
		)
		(zone
			(layer "B.Cu")
			(hatch none 0.5)
			(connect_pads
				(clearance 0)
			)
			(min_thickness 0.25)
			(keepout
				(tracks not_allowed)
				(vias allowed)
				(pads allowed)
				(copperpour not_allowed)
				(footprints allowed)
			)
			(placement
				(enabled no)
				(sheetname "")
			)
			(fill
				(thermal_gap 0.5)
				(thermal_bridge_width 0.5)
				(island_removal_mode 0)
			)
			(polygon
				(pts
					(xy 417.2204 -21.59) (xy 416.7124 -21.59) (xy 416.7124 -21.971) (xy 417.2204 -21.971)
				)
			)
		)
	)
	(footprint ""
		(layer "B.Cu")
		(at 416.179 -26.035)
		(property "Reference" "C25W74"
			(at 0.8382 -0.67818 0)
			(unlocked yes)
			(layer "B.SilkS")
			(effects
				(font
					(size 0.4064 0.254)
					(thickness 0.1524)
				)
				(justify left mirror)
			)
		)
		(property "Value" ""
			(at 0 0 0)
			(layer "B.Fab")
			(effects
				(font
					(size 1.27 1.27)
				)
				(justify mirror)
			)
		)
		(duplicate_pad_numbers_are_jumpers no)
		(fp_poly
			(pts
				(xy -0.3048 -0.1016) (xy -0.3048 0.9906) (xy 0.3048 0.9906) (xy 0.3048 -0.1016)
			)
			(stroke
				(width 0)
				(type default)
			)
			(fill no)
			(layer "B.CrtYd")
		)
		(fp_line
			(start -0.3048 -0.1016)
			(end 0.3048 -0.1016)
			(stroke
				(width 0.1)
				(type default)
			)
			(layer "B.Fab")
		)
		(fp_line
			(start -0.3048 0.9906)
			(end -0.3048 -0.1016)
			(stroke
				(width 0.1)
				(type default)
			)
			(layer "B.Fab")
		)
		(fp_line
			(start 0.3048 -0.1016)
			(end 0.3048 0.9906)
			(stroke
				(width 0.1)
				(type default)
			)
			(layer "B.Fab")
		)
		(fp_line
			(start 0.3048 0.9906)
			(end -0.3048 0.9906)
			(stroke
				(width 0.1)
				(type default)
			)
			(layer "B.Fab")
		)
		(pad "1" smd rect
			(at 0 0 180)
			(size 0.508 0.508)
			(layers "B.Cu" "B.Mask" "B.Paste")
			(net "BMC_VGA_RED")
		)
		(pad "2" smd rect
			(at 0 0.889 180)
			(size 0.508 0.508)
			(layers "B.Cu" "B.Mask" "B.Paste")
			(net "GND")
		)
		(zone
			(layer "B.Cu")
			(hatch none 0.5)
			(connect_pads
				(clearance 0)
			)
			(min_thickness 0.25)
			(keepout
				(tracks allowed)
				(vias not_allowed)
				(pads allowed)
				(copperpour not_allowed)
				(footprints allowed)
			)
			(placement
				(enabled no)
				(sheetname "")
			)
			(fill
				(thermal_gap 0.5)
				(thermal_bridge_width 0.5)
				(island_removal_mode 0)
			)
			(polygon
				(pts
					(xy 416.433 -25.781) (xy 415.925 -25.781) (xy 415.925 -25.4) (xy 416.433 -25.4)
				)
			)
		)
		(zone
			(layer "B.Cu")
			(hatch none 0.5)
			(connect_pads
				(clearance 0)
			)
			(min_thickness 0.25)
			(keepout
				(tracks not_allowed)
				(vias allowed)
				(pads allowed)
				(copperpour not_allowed)
				(footprints allowed)
			)
			(placement
				(enabled no)
				(sheetname "")
			)
			(fill
				(thermal_gap 0.5)
				(thermal_bridge_width 0.5)
				(island_removal_mode 0)
			)
			(polygon
				(pts
					(xy 416.433 -25.4) (xy 415.925 -25.4) (xy 415.925 -25.781) (xy 416.433 -25.781)
				)
			)
		)
	)
	(footprint ""
		(layer "B.Cu")
		(at 463.8294 -52.432458)
		(property "Reference" "C1R1"
			(at 0 0 0)
			(layer "B.SilkS")
			(hide yes)
			(effects
				(font
					(size 1.27 1.27)
				)
				(justify mirror)
			)
		)
		(property "Value" ""
			(at 0 0 0)
			(layer "B.Fab")
			(effects
				(font
					(size 1.27 1.27)
				)
				(justify mirror)
			)
		)
		(duplicate_pad_numbers_are_jumpers no)
		(fp_poly
			(pts
				(xy -0.3048 -0.1016) (xy -0.3048 0.9906) (xy 0.3048 0.9906) (xy 0.3048 -0.1016)
			)
			(stroke
				(width 0)
				(type default)
			)
			(fill no)
			(layer "B.CrtYd")
		)
		(fp_line
			(start -0.3048 -0.1016)
			(end 0.3048 -0.1016)
			(stroke
				(width 0.1)
				(type default)
			)
			(layer "B.Fab")
		)
		(fp_line
			(start -0.3048 0.9906)
			(end -0.3048 -0.1016)
			(stroke
				(width 0.1)
				(type default)
			)
			(layer "B.Fab")
		)
		(fp_line
			(start 0.3048 -0.1016)
			(end 0.3048 0.9906)
			(stroke
				(width 0.1)
				(type default)
			)
			(layer "B.Fab")
		)
		(fp_line
			(start 0.3048 0.9906)
			(end -0.3048 0.9906)
			(stroke
				(width 0.1)
				(type default)
			)
			(layer "B.Fab")
		)
		(pad "1" smd rect
			(at 0 0 180)
			(size 0.508 0.508)
			(layers "B.Cu" "B.Mask" "B.Paste")
			(net "P3E_CPU0_PE3_OCP_TXN<0>")
		)
		(pad "2" smd rect
			(at 0 0.889 180)
			(size 0.508 0.508)
			(layers "B.Cu" "B.Mask" "B.Paste")
			(net "P3E_OCP_CPU0_PE3_C_TXN<0>")
		)
		(zone
			(layer "B.Cu")
			(hatch none 0.5)
			(connect_pads
				(clearance 0)
			)
			(min_thickness 0.25)
			(keepout
				(tracks allowed)
				(vias not_allowed)
				(pads allowed)
				(copperpour not_allowed)
				(footprints allowed)
			)
			(placement
				(enabled no)
				(sheetname "")
			)
			(fill
				(thermal_gap 0.5)
				(thermal_bridge_width 0.5)
				(island_removal_mode 0)
			)
			(polygon
				(pts
					(xy 464.0834 -52.178458) (xy 463.5754 -52.178458) (xy 463.5754 -51.797458) (xy 464.0834 -51.797458)
				)
			)
		)
		(zone
			(layer "B.Cu")
			(hatch none 0.5)
			(connect_pads
				(clearance 0)
			)
			(min_thickness 0.25)
			(keepout
				(tracks not_allowed)
				(vias allowed)
				(pads allowed)
				(copperpour not_allowed)
				(footprints allowed)
			)
			(placement
				(enabled no)
				(sheetname "")
			)
			(fill
				(thermal_gap 0.5)
				(thermal_bridge_width 0.5)
				(island_removal_mode 0)
			)
			(polygon
				(pts
					(xy 464.0834 -51.797458) (xy 463.5754 -51.797458) (xy 463.5754 -52.178458) (xy 464.0834 -52.178458)
				)
			)
		)
	)
	(footprint ""
		(layer "B.Cu")
		(at 377.2281 -36.83 180)
		(property "Reference" "R7E10"
			(at 0 0 0)
			(layer "B.SilkS")
			(hide yes)
			(effects
				(font
					(size 1.27 1.27)
				)
				(justify mirror)
			)
		)
		(property "Value" ""
			(at 0 0 0)
			(layer "B.Fab")
			(effects
				(font
					(size 1.27 1.27)
				)
				(justify mirror)
			)
		)
		(duplicate_pad_numbers_are_jumpers no)
		(fp_poly
			(pts
				(xy 0.2794 -0.1016) (xy -0.2794 -0.1016) (xy -0.2794 0.9906) (xy 0.2794 0.9906)
			)
			(stroke
				(width 0)
				(type default)
			)
			(fill no)
			(layer "B.CrtYd")
		)
		(fp_line
			(start 0.2794 0.9906)
			(end -0.2794 0.9906)
			(stroke
				(width 0.1)
				(type default)
			)
			(layer "B.Fab")
		)
		(fp_line
			(start 0.2794 -0.1016)
			(end 0.2794 0.9906)
			(stroke
				(width 0.1)
				(type default)
			)
			(layer "B.Fab")
		)
		(fp_line
			(start -0.2794 0.9906)
			(end -0.2794 -0.1016)
			(stroke
				(width 0.1)
				(type default)
			)
			(layer "B.Fab")
		)
		(fp_line
			(start -0.2794 -0.1016)
			(end 0.2794 -0.1016)
			(stroke
				(width 0.1)
				(type default)
			)
			(layer "B.Fab")
		)
		(pad "1" smd rect
			(at 0 0)
			(size 0.508 0.508)
			(layers "B.Cu" "B.Mask" "B.Paste")
			(net "P3V3")
		)
		(pad "2" smd rect
			(at 0 0.889)
			(size 0.508 0.508)
			(layers "B.Cu" "B.Mask" "B.Paste")
			(net "IRQ_CPU0_VRHOT")
		)
		(zone
			(layer "B.Cu")
			(hatch none 0.5)
			(connect_pads
				(clearance 0)
			)
			(min_thickness 0.25)
			(keepout
				(tracks not_allowed)
				(vias allowed)
				(pads allowed)
				(copperpour not_allowed)
				(footprints allowed)
			)
			(placement
				(enabled no)
				(sheetname "")
			)
			(fill
				(thermal_gap 0.5)
				(thermal_bridge_width 0.5)
				(island_removal_mode 0)
			)
			(polygon
				(pts
					(xy 376.9741 -37.465) (xy 377.4821 -37.465) (xy 377.4821 -37.084) (xy 376.9741 -37.084)
				)
			)
		)
		(zone
			(layer "B.Cu")
			(hatch none 0.5)
			(connect_pads
				(clearance 0)
			)
			(min_thickness 0.25)
			(keepout
				(tracks allowed)
				(vias not_allowed)
				(pads allowed)
				(copperpour not_allowed)
				(footprints allowed)
			)
			(placement
				(enabled no)
				(sheetname "")
			)
			(fill
				(thermal_gap 0.5)
				(thermal_bridge_width 0.5)
				(island_removal_mode 0)
			)
			(polygon
				(pts
					(xy 376.9741 -37.084) (xy 377.4821 -37.084) (xy 377.4821 -37.465) (xy 376.9741 -37.465)
				)
			)
		)
	)
	(footprint ""
		(layer "B.Cu")
		(at 377.7488 -154.457146)
		(property "Reference" "C3L11"
			(at 0 0 0)
			(layer "B.SilkS")
			(hide yes)
			(effects
				(font
					(size 1.27 1.27)
				)
				(justify mirror)
			)
		)
		(property "Value" ""
			(at 0 0 0)
			(layer "B.Fab")
			(effects
				(font
					(size 1.27 1.27)
				)
				(justify mirror)
			)
		)
		(duplicate_pad_numbers_are_jumpers no)
		(fp_poly
			(pts
				(xy 0.7239 -0.2159) (xy -0.7239 -0.2159) (xy -0.7239 1.9939) (xy 0.7239 1.9939)
			)
			(stroke
				(width 0)
				(type default)
			)
			(fill no)
			(layer "B.CrtYd")
		)
		(fp_line
			(start -0.7239 -0.2159)
			(end 0.7239 -0.2159)
			(stroke
				(width 0.1)
				(type default)
			)
			(layer "B.Fab")
		)
		(fp_line
			(start -0.7239 1.9939)
			(end -0.7239 -0.2159)
			(stroke
				(width 0.1)
				(type default)
			)
			(layer "B.Fab")
		)
		(fp_line
			(start 0.7239 -0.2159)
			(end 0.7239 1.9939)
			(stroke
				(width 0.1)
				(type default)
			)
			(layer "B.Fab")
		)
		(fp_line
			(start 0.7239 1.9939)
			(end -0.7239 1.9939)
			(stroke
				(width 0.1)
				(type default)
			)
			(layer "B.Fab")
		)
		(pad "1" smd rect
			(at 0 0 180)
			(size 1.27 1.016)
			(layers "B.Cu" "B.Mask" "B.Paste")
			(net "VR_FET_SW_P12V_STBY_PVDDQ_DEF")
		)
		(pad "2" smd rect
			(at 0 1.778 180)
			(size 1.27 1.016)
			(layers "B.Cu" "B.Mask" "B.Paste")
			(net "GND")
		)
		(zone
			(layer "B.Cu")
			(hatch none 0.5)
			(connect_pads
				(clearance 0)
			)
			(min_thickness 0.25)
			(keepout
				(tracks not_allowed)
				(vias allowed)
				(pads allowed)
				(copperpour not_allowed)
				(footprints allowed)
			)
			(placement
				(enabled no)
				(sheetname "")
			)
			(fill
				(thermal_gap 0.5)
				(thermal_bridge_width 0.5)
				(island_removal_mode 0)
			)
			(polygon
				(pts
					(xy 378.3838 -153.949146) (xy 377.1138 -153.949146) (xy 377.1138 -153.187146) (xy 378.3838 -153.187146)
				)
			)
		)
	)
	(footprint ""
		(layer "B.Cu")
		(at 402.2344 -23.114 90)
		(property "Reference" "R1U27"
			(at 0 0 90)
			(layer "B.SilkS")
			(hide yes)
			(effects
				(font
					(size 1.27 1.27)
				)
				(justify mirror)
			)
		)
		(property "Value" ""
			(at 0 0 90)
			(layer "B.Fab")
			(effects
				(font
					(size 1.27 1.27)
				)
				(justify mirror)
			)
		)
		(duplicate_pad_numbers_are_jumpers no)
		(fp_poly
			(pts
				(xy 0.2794 -0.1016) (xy -0.2794 -0.1016) (xy -0.2794 0.9906) (xy 0.2794 0.9906)
			)
			(stroke
				(width 0)
				(type default)
			)
			(fill no)
			(layer "B.CrtYd")
		)
		(fp_line
			(start 0.2794 -0.1016)
			(end 0.2794 0.9906)
			(stroke
				(width 0.1)
				(type default)
			)
			(layer "B.Fab")
		)
		(fp_line
			(start -0.2794 -0.1016)
			(end 0.2794 -0.1016)
			(stroke
				(width 0.1)
				(type default)
			)
			(layer "B.Fab")
		)
		(fp_line
			(start 0.2794 0.9906)
			(end -0.2794 0.9906)
			(stroke
				(width 0.1)
				(type default)
			)
			(layer "B.Fab")
		)
		(fp_line
			(start -0.2794 0.9906)
			(end -0.2794 -0.1016)
			(stroke
				(width 0.1)
				(type default)
			)
			(layer "B.Fab")
		)
		(pad "1" smd rect
			(at 0 0 270)
			(size 0.508 0.508)
			(layers "B.Cu" "B.Mask" "B.Paste")
			(net "A_P3V3_SCALED")
		)
		(pad "2" smd rect
			(at 0 0.889 270)
			(size 0.508 0.508)
			(layers "B.Cu" "B.Mask" "B.Paste")
			(net "GND")
		)
		(zone
			(layer "B.Cu")
			(hatch none 0.5)
			(connect_pads
				(clearance 0)
			)
			(min_thickness 0.25)
			(keepout
				(tracks allowed)
				(vias not_allowed)
				(pads allowed)
				(copperpour not_allowed)
				(footprints allowed)
			)
			(placement
				(enabled no)
				(sheetname "")
			)
			(fill
				(thermal_gap 0.5)
				(thermal_bridge_width 0.5)
				(island_removal_mode 0)
			)
			(polygon
				(pts
					(xy 402.4884 -23.368) (xy 402.4884 -22.86) (xy 402.8694 -22.86) (xy 402.8694 -23.368)
				)
			)
		)
		(zone
			(layer "B.Cu")
			(hatch none 0.5)
			(connect_pads
				(clearance 0)
			)
			(min_thickness 0.25)
			(keepout
				(tracks not_allowed)
				(vias allowed)
				(pads allowed)
				(copperpour not_allowed)
				(footprints allowed)
			)
			(placement
				(enabled no)
				(sheetname "")
			)
			(fill
				(thermal_gap 0.5)
				(thermal_bridge_width 0.5)
				(island_removal_mode 0)
			)
			(polygon
				(pts
					(xy 402.8694 -23.368) (xy 402.8694 -22.86) (xy 402.4884 -22.86) (xy 402.4884 -23.368)
				)
			)
		)
	)
	(footprint ""
		(layer "B.Cu")
		(at 406.680924 -114.9858 180)
		(property "Reference" "C2M17"
			(at 0 0 0)
			(layer "B.SilkS")
			(hide yes)
			(effects
				(font
					(size 1.27 1.27)
				)
				(justify mirror)
			)
		)
		(property "Value" ""
			(at 0 0 0)
			(layer "B.Fab")
			(effects
				(font
					(size 1.27 1.27)
				)
				(justify mirror)
			)
		)
		(duplicate_pad_numbers_are_jumpers no)
		(fp_poly
			(pts
				(xy 0.7239 -0.2159) (xy -0.7239 -0.2159) (xy -0.7239 1.9939) (xy 0.7239 1.9939)
			)
			(stroke
				(width 0)
				(type default)
			)
			(fill no)
			(layer "B.CrtYd")
		)
		(fp_line
			(start 0.7239 1.9939)
			(end -0.7239 1.9939)
			(stroke
				(width 0.1)
				(type default)
			)
			(layer "B.Fab")
		)
		(fp_line
			(start 0.7239 -0.2159)
			(end 0.7239 1.9939)
			(stroke
				(width 0.1)
				(type default)
			)
			(layer "B.Fab")
		)
		(fp_line
			(start -0.7239 1.9939)
			(end -0.7239 -0.2159)
			(stroke
				(width 0.1)
				(type default)
			)
			(layer "B.Fab")
		)
		(fp_line
			(start -0.7239 -0.2159)
			(end 0.7239 -0.2159)
			(stroke
				(width 0.1)
				(type default)
			)
			(layer "B.Fab")
		)
		(pad "1" smd rect
			(at 0 0)
			(size 1.27 1.016)
			(layers "B.Cu" "B.Mask" "B.Paste")
			(net "P1V05_PCH_STBY")
		)
		(pad "2" smd rect
			(at 0 1.778)
			(size 1.27 1.016)
			(layers "B.Cu" "B.Mask" "B.Paste")
			(net "GND")
		)
		(zone
			(layer "B.Cu")
			(hatch none 0.5)
			(connect_pads
				(clearance 0)
			)
			(min_thickness 0.25)
			(keepout
				(tracks not_allowed)
				(vias allowed)
				(pads allowed)
				(copperpour not_allowed)
				(footprints allowed)
			)
			(placement
				(enabled no)
				(sheetname "")
			)
			(fill
				(thermal_gap 0.5)
				(thermal_bridge_width 0.5)
				(island_removal_mode 0)
			)
			(polygon
				(pts
					(xy 406.045924 -115.4938) (xy 407.315924 -115.4938) (xy 407.315924 -116.2558) (xy 406.045924 -116.2558)
				)
			)
		)
	)
	(footprint ""
		(layer "B.Cu")
		(at 370.459 -62.357 180)
		(property "Reference" "R3R2"
			(at 0 0 0)
			(layer "B.SilkS")
			(hide yes)
			(effects
				(font
					(size 1.27 1.27)
				)
				(justify mirror)
			)
		)
		(property "Value" ""
			(at 0 0 0)
			(layer "B.Fab")
			(effects
				(font
					(size 1.27 1.27)
				)
				(justify mirror)
			)
		)
		(duplicate_pad_numbers_are_jumpers no)
		(fp_poly
			(pts
				(xy 0.2794 -0.1016) (xy -0.2794 -0.1016) (xy -0.2794 0.9906) (xy 0.2794 0.9906)
			)
			(stroke
				(width 0)
				(type default)
			)
			(fill no)
			(layer "B.CrtYd")
		)
		(fp_line
			(start 0.2794 0.9906)
			(end -0.2794 0.9906)
			(stroke
				(width 0.1)
				(type default)
			)
			(layer "B.Fab")
		)
		(fp_line
			(start 0.2794 -0.1016)
			(end 0.2794 0.9906)
			(stroke
				(width 0.1)
				(type default)
			)
			(layer "B.Fab")
		)
		(fp_line
			(start -0.2794 0.9906)
			(end -0.2794 -0.1016)
			(stroke
				(width 0.1)
				(type default)
			)
			(layer "B.Fab")
		)
		(fp_line
			(start -0.2794 -0.1016)
			(end 0.2794 -0.1016)
			(stroke
				(width 0.1)
				(type default)
			)
			(layer "B.Fab")
		)
		(pad "1" smd rect
			(at 0 0)
			(size 0.508 0.508)
			(layers "B.Cu" "B.Mask" "B.Paste")
			(net "H_CPU1_FIVR_FAULT_G")
		)
		(pad "2" smd rect
			(at 0 0.889)
			(size 0.508 0.508)
			(layers "B.Cu" "B.Mask" "B.Paste")
			(net "GND")
		)
		(zone
			(layer "B.Cu")
			(hatch none 0.5)
			(connect_pads
				(clearance 0)
			)
			(min_thickness 0.25)
			(keepout
				(tracks not_allowed)
				(vias allowed)
				(pads allowed)
				(copperpour not_allowed)
				(footprints allowed)
			)
			(placement
				(enabled no)
				(sheetname "")
			)
			(fill
				(thermal_gap 0.5)
				(thermal_bridge_width 0.5)
				(island_removal_mode 0)
			)
			(polygon
				(pts
					(xy 370.205 -62.992) (xy 370.713 -62.992) (xy 370.713 -62.611) (xy 370.205 -62.611)
				)
			)
		)
		(zone
			(layer "B.Cu")
			(hatch none 0.5)
			(connect_pads
				(clearance 0)
			)
			(min_thickness 0.25)
			(keepout
				(tracks allowed)
				(vias not_allowed)
				(pads allowed)
				(copperpour not_allowed)
				(footprints allowed)
			)
			(placement
				(enabled no)
				(sheetname "")
			)
			(fill
				(thermal_gap 0.5)
				(thermal_bridge_width 0.5)
				(island_removal_mode 0)
			)
			(polygon
				(pts
					(xy 370.205 -62.611) (xy 370.713 -62.611) (xy 370.713 -62.992) (xy 370.205 -62.992)
				)
			)
		)
	)
	(footprint ""
		(layer "B.Cu")
		(at 272.861532 -135.4074 90)
		(property "Reference" "C5M1"
			(at -1.848866 0.752348 90)
			(unlocked yes)
			(layer "B.SilkS")
			(effects
				(font
					(size 1.27 0.9652)
					(thickness 0.1524)
				)
				(justify mirror)
			)
		)
		(property "Value" ""
			(at 0 0 90)
			(layer "B.Fab")
			(effects
				(font
					(size 1.27 1.27)
				)
				(justify mirror)
			)
		)
		(duplicate_pad_numbers_are_jumpers no)
		(fp_rect
			(start 0.500126 1.598422)
			(end -0.500126 -0.201422)
			(stroke
				(width 0)
				(type default)
			)
			(fill no)
			(layer "B.CrtYd")
		)
		(fp_line
			(start 0.500126 -0.201422)
			(end -0.500126 -0.201422)
			(stroke
				(width 0.1)
				(type default)
			)
			(layer "B.Fab")
		)
		(fp_line
			(start -0.500126 -0.201422)
			(end -0.500126 1.598422)
			(stroke
				(width 0.1)
				(type default)
			)
			(layer "B.Fab")
		)
		(fp_line
			(start 0.500126 1.598422)
			(end 0.500126 -0.201422)
			(stroke
				(width 0.1)
				(type default)
			)
			(layer "B.Fab")
		)
		(fp_line
			(start -0.500126 1.598422)
			(end 0.500126 1.598422)
			(stroke
				(width 0.1)
				(type default)
			)
			(layer "B.Fab")
		)
		(pad "1" smd rect
			(at 0 0)
			(size 0.889 0.9906)
			(layers "B.Cu" "B.Mask" "B.Paste")
			(net "PVDDQ_DEF")
		)
		(pad "2" smd rect
			(at 0 1.397)
			(size 0.889 0.9906)
			(layers "B.Cu" "B.Mask" "B.Paste")
			(net "GND")
		)
		(zone
			(layer "B.Cu")
			(hatch none 0.5)
			(connect_pads
				(clearance 0)
			)
			(min_thickness 0.25)
			(keepout
				(tracks not_allowed)
				(vias allowed)
				(pads allowed)
				(copperpour not_allowed)
				(footprints allowed)
			)
			(placement
				(enabled no)
				(sheetname "")
			)
			(fill
				(thermal_gap 0.5)
				(thermal_bridge_width 0.5)
				(island_removal_mode 0)
			)
			(polygon
				(pts
					(xy 273.814032 -135.9027) (xy 273.306032 -135.9027) (xy 273.306032 -134.9121) (xy 273.814032 -134.9121)
				)
			)
		)
		(zone
			(layer "B.Cu")
			(hatch none 0.5)
			(connect_pads
				(clearance 0)
			)
			(min_thickness 0.25)
			(keepout
				(tracks allowed)
				(vias not_allowed)
				(pads allowed)
				(copperpour not_allowed)
				(footprints allowed)
			)
			(placement
				(enabled no)
				(sheetname "")
			)
			(fill
				(thermal_gap 0.5)
				(thermal_bridge_width 0.5)
				(island_removal_mode 0)
			)
			(polygon
				(pts
					(xy 273.814032 -135.9027) (xy 273.306032 -135.9027) (xy 273.306032 -134.9121) (xy 273.814032 -134.9121)
				)
			)
		)
	)
	(footprint ""
		(layer "B.Cu")
		(at 181.991 -12.7 180)
		(property "Reference" "C6U5"
			(at 0 0 0)
			(layer "B.SilkS")
			(hide yes)
			(effects
				(font
					(size 1.27 1.27)
				)
				(justify mirror)
			)
		)
		(property "Value" ""
			(at 0 0 0)
			(layer "B.Fab")
			(effects
				(font
					(size 1.27 1.27)
				)
				(justify mirror)
			)
		)
		(duplicate_pad_numbers_are_jumpers no)
		(fp_rect
			(start 0.3048 -0.1016)
			(end -0.3048 0.9906)
			(stroke
				(width 0)
				(type default)
			)
			(fill no)
			(layer "B.CrtYd")
		)
		(fp_line
			(start 0.3048 0.9906)
			(end -0.3048 0.9906)
			(stroke
				(width 0.1)
				(type default)
			)
			(layer "B.Fab")
		)
		(fp_line
			(start 0.3048 -0.1016)
			(end 0.3048 0.9906)
			(stroke
				(width 0.1)
				(type default)
			)
			(layer "B.Fab")
		)
		(fp_line
			(start -0.3048 0.9906)
			(end -0.3048 -0.1016)
			(stroke
				(width 0.1)
				(type default)
			)
			(layer "B.Fab")
		)
		(fp_line
			(start -0.3048 -0.1016)
			(end 0.3048 -0.1016)
			(stroke
				(width 0.1)
				(type default)
			)
			(layer "B.Fab")
		)
		(pad "1" smd rect
			(at 0 0)
			(size 0.508 0.508)
			(layers "B.Cu" "B.Mask" "B.Paste")
			(net "VR_FET_SW_P12V_STBY_PVPP_GHJ")
		)
		(pad "2" smd rect
			(at 0 0.889)
			(size 0.508 0.508)
			(layers "B.Cu" "B.Mask" "B.Paste")
			(net "GND")
		)
		(zone
			(layer "B.Cu")
			(hatch none 0.5)
			(connect_pads
				(clearance 0)
			)
			(min_thickness 0.25)
			(keepout
				(tracks allowed)
				(vias not_allowed)
				(pads allowed)
				(copperpour not_allowed)
				(footprints allowed)
			)
			(placement
				(enabled no)
				(sheetname "")
			)
			(fill
				(thermal_gap 0.5)
				(thermal_bridge_width 0.5)
				(island_removal_mode 0)
			)
			(polygon
				(pts
					(xy 181.737 -12.954) (xy 182.245 -12.954) (xy 182.245 -13.335) (xy 181.737 -13.335)
				)
			)
		)
		(zone
			(layer "B.Cu")
			(hatch none 0.5)
			(connect_pads
				(clearance 0)
			)
			(min_thickness 0.25)
			(keepout
				(tracks not_allowed)
				(vias allowed)
				(pads allowed)
				(copperpour not_allowed)
				(footprints allowed)
			)
			(placement
				(enabled no)
				(sheetname "")
			)
			(fill
				(thermal_gap 0.5)
				(thermal_bridge_width 0.5)
				(island_removal_mode 0)
			)
			(polygon
				(pts
					(xy 181.737 -12.954) (xy 182.245 -12.954) (xy 182.245 -13.335) (xy 181.737 -13.335)
				)
			)
		)
	)
	(footprint ""
		(layer "B.Cu")
		(at 17.272 -90.805)
		(property "Reference" "C9W1"
			(at 0 0 0)
			(layer "B.SilkS")
			(hide yes)
			(effects
				(font
					(size 1.27 1.27)
				)
				(justify mirror)
			)
		)
		(property "Value" "*"
			(at -1.1811 -2.8194 0)
			(unlocked yes)
			(layer "B.Fab")
			(hide yes)
			(effects
				(font
					(size 1.27 1.016)
					(thickness 0.1524)
				)
				(justify mirror)
			)
		)
		(property "Device Type" "SC22P50V2JN-4GP_SMD-BCG-SC22P5A"
			(at -1.1811 -4.3434 0)
			(unlocked yes)
			(layer "B.Fab")
			(hide yes)
			(effects
				(font
					(size 1.27 1.016)
					(thickness 0.1524)
				)
				(justify mirror)
			)
		)
		(duplicate_pad_numbers_are_jumpers no)
		(fp_rect
			(start 0.4318 0.9525)
			(end -0.4318 -0.9525)
			(stroke
				(width 0)
				(type default)
			)
			(fill no)
			(layer "B.CrtYd")
		)
		(fp_rect
			(start 0.4318 0.9525)
			(end -0.4318 -0.9525)
			(stroke
				(width 0)
				(type default)
			)
			(fill no)
			(layer "B.Fab")
		)
		(pad "1" smd custom
			(at 0 -0.4445 180)
			(size 0.1524 0.1524)
			(layers "B.Cu" "B.Mask" "B.Paste")
			(net "A_P12V_STBY_FP_TRIGGER")
			(options
				(clearance outline)
				(anchor circle)
			)
			(primitives
				(gr_poly
					(pts
						(arc
							(start 0.3048 0.2032)
							(mid 0.275042 0.275042)
							(end 0.2032 0.3048)
						)
						(arc
							(start -0.2032 0.3048)
							(mid -0.275042 0.275042)
							(end -0.3048 0.2032)
						)
						(arc
							(start -0.3048 -0.2032)
							(mid -0.275042 -0.275042)
							(end -0.2032 -0.3048)
						)
						(arc
							(start 0.2032 -0.3048)
							(mid 0.275042 -0.275042)
							(end 0.3048 -0.2032)
						)
					)
					(width 0)
					(fill yes)
				)
			)
		)
		(pad "2" smd custom
			(at 0 0.4445 180)
			(size 0.1524 0.1524)
			(layers "B.Cu" "B.Mask" "B.Paste")
			(net "AGND_HSC")
			(options
				(clearance outline)
				(anchor circle)
			)
			(primitives
				(gr_poly
					(pts
						(arc
							(start 0.3048 0.2032)
							(mid 0.275042 0.275042)
							(end 0.2032 0.3048)
						)
						(arc
							(start -0.2032 0.3048)
							(mid -0.275042 0.275042)
							(end -0.3048 0.2032)
						)
						(arc
							(start -0.3048 -0.2032)
							(mid -0.275042 -0.275042)
							(end -0.2032 -0.3048)
						)
						(arc
							(start 0.2032 -0.3048)
							(mid 0.275042 -0.275042)
							(end 0.3048 -0.2032)
						)
					)
					(width 0)
					(fill yes)
				)
			)
		)
	)
	(footprint ""
		(layer "B.Cu")
		(at 385.33705 -105.45445 -90)
		(property "Reference" "C3N22"
			(at 0 0 90)
			(layer "B.SilkS")
			(hide yes)
			(effects
				(font
					(size 1.27 1.27)
				)
				(justify mirror)
			)
		)
		(property "Value" ""
			(at 0 0 90)
			(layer "B.Fab")
			(effects
				(font
					(size 1.27 1.27)
				)
				(justify mirror)
			)
		)
		(duplicate_pad_numbers_are_jumpers no)
		(fp_rect
			(start 0.2794 0.9144)
			(end -0.2794 -0.1143)
			(stroke
				(width 0)
				(type default)
			)
			(fill no)
			(layer "B.CrtYd")
		)
		(fp_line
			(start -0.2794 0.9144)
			(end 0.2794 0.9144)
			(stroke
				(width 0.1)
				(type default)
			)
			(layer "B.Fab")
		)
		(fp_line
			(start 0.2794 0.9144)
			(end 0.2794 -0.1143)
			(stroke
				(width 0.1)
				(type default)
			)
			(layer "B.Fab")
		)
		(fp_line
			(start -0.2794 -0.1143)
			(end -0.2794 0.9144)
			(stroke
				(width 0.1)
				(type default)
			)
			(layer "B.Fab")
		)
		(fp_line
			(start 0.2794 -0.1143)
			(end -0.2794 -0.1143)
			(stroke
				(width 0.1)
				(type default)
			)
			(layer "B.Fab")
		)
		(pad "1" smd custom
			(at 0 0 180)
			(size 0.10414 0.10414)
			(layers "B.Cu" "B.Mask" "B.Paste")
			(net "P1V8_PCH_STBY")
			(options
				(clearance outline)
				(anchor circle)
			)
			(primitives
				(gr_poly
					(pts
						(xy -0.20828 -0.08636) (xy -0.20828 0.08636) (xy -0.08636 0.20828) (xy 0.086614 0.20828) (xy 0.20828 0.086614)
						(xy 0.20828 -0.08636) (xy 0.08636 -0.20828) (xy -0.08636 -0.20828)
					)
					(width 0)
					(fill yes)
				)
			)
		)
		(pad "2" smd custom
			(at 0 0.8001 180)
			(size 0.10414 0.10414)
			(layers "B.Cu" "B.Mask" "B.Paste")
			(net "GND")
			(options
				(clearance outline)
				(anchor circle)
			)
			(primitives
				(gr_poly
					(pts
						(xy -0.20828 -0.08636) (xy -0.20828 0.08636) (xy -0.08636 0.20828) (xy 0.086614 0.20828) (xy 0.20828 0.086614)
						(xy 0.20828 -0.08636) (xy 0.08636 -0.20828) (xy -0.08636 -0.20828)
					)
					(width 0)
					(fill yes)
				)
			)
		)
		(zone
			(layer "B.Cu")
			(hatch none 0.5)
			(connect_pads
				(clearance 0)
			)
			(min_thickness 0.25)
			(keepout
				(tracks not_allowed)
				(vias allowed)
				(pads allowed)
				(copperpour not_allowed)
				(footprints allowed)
			)
			(placement
				(enabled no)
				(sheetname "")
			)
			(fill
				(thermal_gap 0.5)
				(thermal_bridge_width 0.5)
				(island_removal_mode 0)
			)
			(polygon
				(pts
					(xy 385.1275 -105.36682) (xy 384.7465 -105.36682) (xy 384.7465 -105.54208) (xy 385.1275 -105.542334)
				)
			)
		)
		(zone
			(layer "B.Cu")
			(hatch none 0.5)
			(connect_pads
				(clearance 0)
			)
			(min_thickness 0.25)
			(keepout
				(tracks allowed)
				(vias not_allowed)
				(pads allowed)
				(copperpour not_allowed)
				(footprints allowed)
			)
			(placement
				(enabled no)
				(sheetname "")
			)
			(fill
				(thermal_gap 0.5)
				(thermal_bridge_width 0.5)
				(island_removal_mode 0)
			)
			(polygon
				(pts
					(xy 385.1275 -105.36682) (xy 384.7465 -105.36682) (xy 384.7465 -105.54208) (xy 385.1275 -105.542334)
				)
			)
		)
	)
	(footprint ""
		(layer "B.Cu")
		(at 416.179 -22.225)
		(property "Reference" "C25W72"
			(at 0.8382 -0.67818 0)
			(unlocked yes)
			(layer "B.SilkS")
			(effects
				(font
					(size 0.4064 0.254)
					(thickness 0.1524)
				)
				(justify left mirror)
			)
		)
		(property "Value" ""
			(at 0 0 0)
			(layer "B.Fab")
			(effects
				(font
					(size 1.27 1.27)
				)
				(justify mirror)
			)
		)
		(duplicate_pad_numbers_are_jumpers no)
		(fp_poly
			(pts
				(xy -0.3048 -0.1016) (xy -0.3048 0.9906) (xy 0.3048 0.9906) (xy 0.3048 -0.1016)
			)
			(stroke
				(width 0)
				(type default)
			)
			(fill no)
			(layer "B.CrtYd")
		)
		(fp_line
			(start -0.3048 -0.1016)
			(end 0.3048 -0.1016)
			(stroke
				(width 0.1)
				(type default)
			)
			(layer "B.Fab")
		)
		(fp_line
			(start -0.3048 0.9906)
			(end -0.3048 -0.1016)
			(stroke
				(width 0.1)
				(type default)
			)
			(layer "B.Fab")
		)
		(fp_line
			(start 0.3048 -0.1016)
			(end 0.3048 0.9906)
			(stroke
				(width 0.1)
				(type default)
			)
			(layer "B.Fab")
		)
		(fp_line
			(start 0.3048 0.9906)
			(end -0.3048 0.9906)
			(stroke
				(width 0.1)
				(type default)
			)
			(layer "B.Fab")
		)
		(pad "1" smd rect
			(at 0 0 180)
			(size 0.508 0.508)
			(layers "B.Cu" "B.Mask" "B.Paste")
			(net "BMC_VGA_BLUE")
		)
		(pad "2" smd rect
			(at 0 0.889 180)
			(size 0.508 0.508)
			(layers "B.Cu" "B.Mask" "B.Paste")
			(net "GND")
		)
		(zone
			(layer "B.Cu")
			(hatch none 0.5)
			(connect_pads
				(clearance 0)
			)
			(min_thickness 0.25)
			(keepout
				(tracks allowed)
				(vias not_allowed)
				(pads allowed)
				(copperpour not_allowed)
				(footprints allowed)
			)
			(placement
				(enabled no)
				(sheetname "")
			)
			(fill
				(thermal_gap 0.5)
				(thermal_bridge_width 0.5)
				(island_removal_mode 0)
			)
			(polygon
				(pts
					(xy 416.433 -21.971) (xy 415.925 -21.971) (xy 415.925 -21.59) (xy 416.433 -21.59)
				)
			)
		)
		(zone
			(layer "B.Cu")
			(hatch none 0.5)
			(connect_pads
				(clearance 0)
			)
			(min_thickness 0.25)
			(keepout
				(tracks not_allowed)
				(vias allowed)
				(pads allowed)
				(copperpour not_allowed)
				(footprints allowed)
			)
			(placement
				(enabled no)
				(sheetname "")
			)
			(fill
				(thermal_gap 0.5)
				(thermal_bridge_width 0.5)
				(island_removal_mode 0)
			)
			(polygon
				(pts
					(xy 416.433 -21.59) (xy 415.925 -21.59) (xy 415.925 -21.971) (xy 416.433 -21.971)
				)
			)
		)
	)
	(footprint ""
		(layer "B.Cu")
		(at -1.3208 -114.1349 -90)
		(property "Reference" "C9M9"
			(at 0 0 90)
			(layer "B.SilkS")
			(hide yes)
			(effects
				(font
					(size 1.27 1.27)
				)
				(justify mirror)
			)
		)
		(property "Value" ""
			(at 0 0 90)
			(layer "B.Fab")
			(effects
				(font
					(size 1.27 1.27)
				)
				(justify mirror)
			)
		)
		(duplicate_pad_numbers_are_jumpers no)
		(fp_rect
			(start 0.3048 0.9906)
			(end -0.3048 -0.1016)
			(stroke
				(width 0)
				(type default)
			)
			(fill no)
			(layer "B.CrtYd")
		)
		(fp_line
			(start -0.3048 0.9906)
			(end -0.3048 -0.1016)
			(stroke
				(width 0.1)
				(type default)
			)
			(layer "B.Fab")
		)
		(fp_line
			(start 0.3048 0.9906)
			(end -0.3048 0.9906)
			(stroke
				(width 0.1)
				(type default)
			)
			(layer "B.Fab")
		)
		(fp_line
			(start -0.3048 -0.1016)
			(end 0.3048 -0.1016)
			(stroke
				(width 0.1)
				(type default)
			)
			(layer "B.Fab")
		)
		(fp_line
			(start 0.3048 -0.1016)
			(end 0.3048 0.9906)
			(stroke
				(width 0.1)
				(type default)
			)
			(layer "B.Fab")
		)
		(pad "1" smd rect
			(at 0 0 90)
			(size 0.508 0.508)
			(layers "B.Cu" "B.Mask" "B.Paste")
			(net "P12V_STBY")
		)
		(pad "2" smd rect
			(at 0 0.889 90)
			(size 0.508 0.508)
			(layers "B.Cu" "B.Mask" "B.Paste")
			(net "GND")
		)
		(zone
			(layer "B.Cu")
			(hatch none 0.5)
			(connect_pads
				(clearance 0)
			)
			(min_thickness 0.25)
			(keepout
				(tracks allowed)
				(vias not_allowed)
				(pads allowed)
				(copperpour not_allowed)
				(footprints allowed)
			)
			(placement
				(enabled no)
				(sheetname "")
			)
			(fill
				(thermal_gap 0.5)
				(thermal_bridge_width 0.5)
				(island_removal_mode 0)
			)
			(polygon
				(pts
					(xy -1.9558 -113.8809) (xy -1.5748 -113.8809) (xy -1.5748 -114.3889) (xy -1.9558 -114.3889)
				)
			)
		)
		(zone
			(layer "B.Cu")
			(hatch none 0.5)
			(connect_pads
				(clearance 0)
			)
			(min_thickness 0.25)
			(keepout
				(tracks not_allowed)
				(vias allowed)
				(pads allowed)
				(copperpour not_allowed)
				(footprints allowed)
			)
			(placement
				(enabled no)
				(sheetname "")
			)
			(fill
				(thermal_gap 0.5)
				(thermal_bridge_width 0.5)
				(island_removal_mode 0)
			)
			(polygon
				(pts
					(xy -1.9558 -113.8809) (xy -1.5748 -113.8809) (xy -1.5748 -114.3889) (xy -1.9558 -114.3889)
				)
			)
		)
	)
	(footprint ""
		(layer "B.Cu")
		(at 469.197944 -9.64692 180)
		(property "Reference" "R2U35"
			(at 0.8382 -0.67818 180)
			(unlocked yes)
			(layer "B.SilkS")
			(effects
				(font
					(size 0.4064 0.254)
					(thickness 0.1524)
				)
				(justify left mirror)
			)
		)
		(property "Value" ""
			(at 0 0 0)
			(layer "B.Fab")
			(effects
				(font
					(size 1.27 1.27)
				)
				(justify mirror)
			)
		)
		(duplicate_pad_numbers_are_jumpers no)
		(fp_poly
			(pts
				(xy 0.2794 -0.1016) (xy -0.2794 -0.1016) (xy -0.2794 0.9906) (xy 0.2794 0.9906)
			)
			(stroke
				(width 0)
				(type default)
			)
			(fill no)
			(layer "B.CrtYd")
		)
		(fp_line
			(start 0.2794 0.9906)
			(end -0.2794 0.9906)
			(stroke
				(width 0.1)
				(type default)
			)
			(layer "B.Fab")
		)
		(fp_line
			(start 0.2794 -0.1016)
			(end 0.2794 0.9906)
			(stroke
				(width 0.1)
				(type default)
			)
			(layer "B.Fab")
		)
		(fp_line
			(start -0.2794 0.9906)
			(end -0.2794 -0.1016)
			(stroke
				(width 0.1)
				(type default)
			)
			(layer "B.Fab")
		)
		(fp_line
			(start -0.2794 -0.1016)
			(end 0.2794 -0.1016)
			(stroke
				(width 0.1)
				(type default)
			)
			(layer "B.Fab")
		)
		(pad "1" smd rect
			(at 0 0)
			(size 0.508 0.508)
			(layers "B.Cu" "B.Mask" "B.Paste")
			(net "SMB_SLOTX24_PCH_STBY_LVC3_SDA")
		)
		(pad "2" smd rect
			(at 0 0.889)
			(size 0.508 0.508)
			(layers "B.Cu" "B.Mask" "B.Paste")
			(net "SMB_SLOTX24_STBY_LVC3_SDA_R2")
		)
		(zone
			(layer "B.Cu")
			(hatch none 0.5)
			(connect_pads
				(clearance 0)
			)
			(min_thickness 0.25)
			(keepout
				(tracks not_allowed)
				(vias allowed)
				(pads allowed)
				(copperpour not_allowed)
				(footprints allowed)
			)
			(placement
				(enabled no)
				(sheetname "")
			)
			(fill
				(thermal_gap 0.5)
				(thermal_bridge_width 0.5)
				(island_removal_mode 0)
			)
			(polygon
				(pts
					(xy 468.943944 -10.28192) (xy 469.451944 -10.28192) (xy 469.451944 -9.90092) (xy 468.943944 -9.90092)
				)
			)
		)
		(zone
			(layer "B.Cu")
			(hatch none 0.5)
			(connect_pads
				(clearance 0)
			)
			(min_thickness 0.25)
			(keepout
				(tracks allowed)
				(vias not_allowed)
				(pads allowed)
				(copperpour not_allowed)
				(footprints allowed)
			)
			(placement
				(enabled no)
				(sheetname "")
			)
			(fill
				(thermal_gap 0.5)
				(thermal_bridge_width 0.5)
				(island_removal_mode 0)
			)
			(polygon
				(pts
					(xy 468.943944 -9.90092) (xy 469.451944 -9.90092) (xy 469.451944 -10.28192) (xy 468.943944 -10.28192)
				)
			)
		)
	)
	(footprint ""
		(layer "B.Cu")
		(at 102.692454 -73.51014)
		(property "Reference" "C8P24"
			(at 0 0 0)
			(layer "B.SilkS")
			(hide yes)
			(effects
				(font
					(size 1.27 1.27)
				)
				(justify mirror)
			)
		)
		(property "Value" ""
			(at 0 0 0)
			(layer "B.Fab")
			(effects
				(font
					(size 1.27 1.27)
				)
				(justify mirror)
			)
		)
		(duplicate_pad_numbers_are_jumpers no)
		(fp_poly
			(pts
				(xy 0.7239 -0.2159) (xy -0.7239 -0.2159) (xy -0.7239 1.9939) (xy 0.7239 1.9939)
			)
			(stroke
				(width 0)
				(type default)
			)
			(fill no)
			(layer "B.CrtYd")
		)
		(fp_line
			(start -0.7239 -0.2159)
			(end 0.7239 -0.2159)
			(stroke
				(width 0.1)
				(type default)
			)
			(layer "B.Fab")
		)
		(fp_line
			(start -0.7239 1.9939)
			(end -0.7239 -0.2159)
			(stroke
				(width 0.1)
				(type default)
			)
			(layer "B.Fab")
		)
		(fp_line
			(start 0.7239 -0.2159)
			(end 0.7239 1.9939)
			(stroke
				(width 0.1)
				(type default)
			)
			(layer "B.Fab")
		)
		(fp_line
			(start 0.7239 1.9939)
			(end -0.7239 1.9939)
			(stroke
				(width 0.1)
				(type default)
			)
			(layer "B.Fab")
		)
		(pad "1" smd rect
			(at 0 0 180)
			(size 1.27 1.016)
			(layers "B.Cu" "B.Mask" "B.Paste")
			(net "PVCCIN_CPU1")
		)
		(pad "2" smd rect
			(at 0 1.778 180)
			(size 1.27 1.016)
			(layers "B.Cu" "B.Mask" "B.Paste")
			(net "GND")
		)
		(zone
			(layer "B.Cu")
			(hatch none 0.5)
			(connect_pads
				(clearance 0)
			)
			(min_thickness 0.25)
			(keepout
				(tracks not_allowed)
				(vias allowed)
				(pads allowed)
				(copperpour not_allowed)
				(footprints allowed)
			)
			(placement
				(enabled no)
				(sheetname "")
			)
			(fill
				(thermal_gap 0.5)
				(thermal_bridge_width 0.5)
				(island_removal_mode 0)
			)
			(polygon
				(pts
					(xy 103.327454 -73.00214) (xy 102.057454 -73.00214) (xy 102.057454 -72.24014) (xy 103.327454 -72.24014)
				)
			)
		)
	)
	(footprint ""
		(layer "B.Cu")
		(at 450.215 -147.8026 -90)
		(property "Reference" "R25W175"
			(at 0.8382 -0.67818 270)
			(unlocked yes)
			(layer "B.SilkS")
			(effects
				(font
					(size 0.4064 0.254)
					(thickness 0.1524)
				)
				(justify left mirror)
			)
		)
		(property "Value" ""
			(at 0 0 90)
			(layer "B.Fab")
			(effects
				(font
					(size 1.27 1.27)
				)
				(justify mirror)
			)
		)
		(duplicate_pad_numbers_are_jumpers no)
		(fp_poly
			(pts
				(xy 0.2794 -0.1016) (xy -0.2794 -0.1016) (xy -0.2794 0.9906) (xy 0.2794 0.9906)
			)
			(stroke
				(width 0)
				(type default)
			)
			(fill no)
			(layer "B.CrtYd")
		)
		(fp_line
			(start -0.2794 0.9906)
			(end -0.2794 -0.1016)
			(stroke
				(width 0.1)
				(type default)
			)
			(layer "B.Fab")
		)
		(fp_line
			(start 0.2794 0.9906)
			(end -0.2794 0.9906)
			(stroke
				(width 0.1)
				(type default)
			)
			(layer "B.Fab")
		)
		(fp_line
			(start -0.2794 -0.1016)
			(end 0.2794 -0.1016)
			(stroke
				(width 0.1)
				(type default)
			)
			(layer "B.Fab")
		)
		(fp_line
			(start 0.2794 -0.1016)
			(end 0.2794 0.9906)
			(stroke
				(width 0.1)
				(type default)
			)
			(layer "B.Fab")
		)
		(pad "1" smd rect
			(at 0 0 90)
			(size 0.508 0.508)
			(layers "B.Cu" "B.Mask" "B.Paste")
			(net "PD_GTL2014_6_B0")
		)
		(pad "2" smd rect
			(at 0 0.889 90)
			(size 0.508 0.508)
			(layers "B.Cu" "B.Mask" "B.Paste")
			(net "GND")
		)
		(zone
			(layer "B.Cu")
			(hatch none 0.5)
			(connect_pads
				(clearance 0)
			)
			(min_thickness 0.25)
			(keepout
				(tracks not_allowed)
				(vias allowed)
				(pads allowed)
				(copperpour not_allowed)
				(footprints allowed)
			)
			(placement
				(enabled no)
				(sheetname "")
			)
			(fill
				(thermal_gap 0.5)
				(thermal_bridge_width 0.5)
				(island_removal_mode 0)
			)
			(polygon
				(pts
					(xy 449.58 -147.5486) (xy 449.58 -148.0566) (xy 449.961 -148.0566) (xy 449.961 -147.5486)
				)
			)
		)
		(zone
			(layer "B.Cu")
			(hatch none 0.5)
			(connect_pads
				(clearance 0)
			)
			(min_thickness 0.25)
			(keepout
				(tracks allowed)
				(vias not_allowed)
				(pads allowed)
				(copperpour not_allowed)
				(footprints allowed)
			)
			(placement
				(enabled no)
				(sheetname "")
			)
			(fill
				(thermal_gap 0.5)
				(thermal_bridge_width 0.5)
				(island_removal_mode 0)
			)
			(polygon
				(pts
					(xy 449.961 -147.5486) (xy 449.961 -148.0566) (xy 449.58 -148.0566) (xy 449.58 -147.5486)
				)
			)
		)
	)
	(footprint ""
		(layer "B.Cu")
		(at 173.482 -74.8792)
		(property "Reference" "R6P20"
			(at 0 0 0)
			(layer "B.SilkS")
			(hide yes)
			(effects
				(font
					(size 1.27 1.27)
				)
				(justify mirror)
			)
		)
		(property "Value" ""
			(at 0 0 0)
			(layer "B.Fab")
			(effects
				(font
					(size 1.27 1.27)
				)
				(justify mirror)
			)
		)
		(duplicate_pad_numbers_are_jumpers no)
		(fp_poly
			(pts
				(xy 0.2794 -0.1016) (xy -0.2794 -0.1016) (xy -0.2794 0.9906) (xy 0.2794 0.9906)
			)
			(stroke
				(width 0)
				(type default)
			)
			(fill no)
			(layer "B.CrtYd")
		)
		(fp_line
			(start -0.2794 -0.1016)
			(end 0.2794 -0.1016)
			(stroke
				(width 0.1)
				(type default)
			)
			(layer "B.Fab")
		)
		(fp_line
			(start -0.2794 0.9906)
			(end -0.2794 -0.1016)
			(stroke
				(width 0.1)
				(type default)
			)
			(layer "B.Fab")
		)
		(fp_line
			(start 0.2794 -0.1016)
			(end 0.2794 0.9906)
			(stroke
				(width 0.1)
				(type default)
			)
			(layer "B.Fab")
		)
		(fp_line
			(start 0.2794 0.9906)
			(end -0.2794 0.9906)
			(stroke
				(width 0.1)
				(type default)
			)
			(layer "B.Fab")
		)
		(pad "1" smd rect
			(at 0 0 180)
			(size 0.508 0.508)
			(layers "B.Cu" "B.Mask" "B.Paste")
			(net "FM_DB1200_SMB_SA1")
		)
		(pad "2" smd rect
			(at 0 0.889 180)
			(size 0.508 0.508)
			(layers "B.Cu" "B.Mask" "B.Paste")
			(net "GND")
		)
		(zone
			(layer "B.Cu")
			(hatch none 0.5)
			(connect_pads
				(clearance 0)
			)
			(min_thickness 0.25)
			(keepout
				(tracks allowed)
				(vias not_allowed)
				(pads allowed)
				(copperpour not_allowed)
				(footprints allowed)
			)
			(placement
				(enabled no)
				(sheetname "")
			)
			(fill
				(thermal_gap 0.5)
				(thermal_bridge_width 0.5)
				(island_removal_mode 0)
			)
			(polygon
				(pts
					(xy 173.736 -74.6252) (xy 173.228 -74.6252) (xy 173.228 -74.2442) (xy 173.736 -74.2442)
				)
			)
		)
		(zone
			(layer "B.Cu")
			(hatch none 0.5)
			(connect_pads
				(clearance 0)
			)
			(min_thickness 0.25)
			(keepout
				(tracks not_allowed)
				(vias allowed)
				(pads allowed)
				(copperpour not_allowed)
				(footprints allowed)
			)
			(placement
				(enabled no)
				(sheetname "")
			)
			(fill
				(thermal_gap 0.5)
				(thermal_bridge_width 0.5)
				(island_removal_mode 0)
			)
			(polygon
				(pts
					(xy 173.736 -74.2442) (xy 173.228 -74.2442) (xy 173.228 -74.6252) (xy 173.736 -74.6252)
				)
			)
		)
	)
	(footprint ""
		(layer "B.Cu")
		(at 450.5325 -26.543 -90)
		(property "Reference" "C6W3"
			(at 0.8382 -0.67818 270)
			(unlocked yes)
			(layer "B.SilkS")
			(effects
				(font
					(size 0.4064 0.254)
					(thickness 0.1524)
				)
				(justify left mirror)
			)
		)
		(property "Value" ""
			(at 0 0 90)
			(layer "B.Fab")
			(effects
				(font
					(size 1.27 1.27)
				)
				(justify mirror)
			)
		)
		(duplicate_pad_numbers_are_jumpers no)
		(fp_poly
			(pts
				(xy -0.3048 -0.1016) (xy -0.3048 0.9906) (xy 0.3048 0.9906) (xy 0.3048 -0.1016)
			)
			(stroke
				(width 0)
				(type default)
			)
			(fill no)
			(layer "B.CrtYd")
		)
		(fp_line
			(start -0.3048 0.9906)
			(end -0.3048 -0.1016)
			(stroke
				(width 0.1)
				(type default)
			)
			(layer "B.Fab")
		)
		(fp_line
			(start 0.3048 0.9906)
			(end -0.3048 0.9906)
			(stroke
				(width 0.1)
				(type default)
			)
			(layer "B.Fab")
		)
		(fp_line
			(start -0.3048 -0.1016)
			(end 0.3048 -0.1016)
			(stroke
				(width 0.1)
				(type default)
			)
			(layer "B.Fab")
		)
		(fp_line
			(start 0.3048 -0.1016)
			(end 0.3048 0.9906)
			(stroke
				(width 0.1)
				(type default)
			)
			(layer "B.Fab")
		)
		(pad "1" smd rect
			(at 0 0 90)
			(size 0.508 0.508)
			(layers "B.Cu" "B.Mask" "B.Paste")
			(net "P3V3_STBY")
		)
		(pad "2" smd rect
			(at 0 0.889 90)
			(size 0.508 0.508)
			(layers "B.Cu" "B.Mask" "B.Paste")
			(net "GND")
		)
		(zone
			(layer "B.Cu")
			(hatch none 0.5)
			(connect_pads
				(clearance 0)
			)
			(min_thickness 0.25)
			(keepout
				(tracks not_allowed)
				(vias allowed)
				(pads allowed)
				(copperpour not_allowed)
				(footprints allowed)
			)
			(placement
				(enabled no)
				(sheetname "")
			)
			(fill
				(thermal_gap 0.5)
				(thermal_bridge_width 0.5)
				(island_removal_mode 0)
			)
			(polygon
				(pts
					(xy 449.8975 -26.289) (xy 449.8975 -26.797) (xy 450.2785 -26.797) (xy 450.2785 -26.289)
				)
			)
		)
		(zone
			(layer "B.Cu")
			(hatch none 0.5)
			(connect_pads
				(clearance 0)
			)
			(min_thickness 0.25)
			(keepout
				(tracks allowed)
				(vias not_allowed)
				(pads allowed)
				(copperpour not_allowed)
				(footprints allowed)
			)
			(placement
				(enabled no)
				(sheetname "")
			)
			(fill
				(thermal_gap 0.5)
				(thermal_bridge_width 0.5)
				(island_removal_mode 0)
			)
			(polygon
				(pts
					(xy 450.2785 -26.289) (xy 450.2785 -26.797) (xy 449.8975 -26.797) (xy 449.8975 -26.289)
				)
			)
		)
	)
	(footprint ""
		(layer "B.Cu")
		(at 408.1526 -154.4828 90)
		(property "Reference" "C2L5"
			(at 0 0 90)
			(layer "B.SilkS")
			(hide yes)
			(effects
				(font
					(size 1.27 1.27)
				)
				(justify mirror)
			)
		)
		(property "Value" ""
			(at 0 0 90)
			(layer "B.Fab")
			(effects
				(font
					(size 1.27 1.27)
				)
				(justify mirror)
			)
		)
		(duplicate_pad_numbers_are_jumpers no)
		(fp_poly
			(pts
				(xy -0.3048 -0.1016) (xy -0.3048 0.9906) (xy 0.3048 0.9906) (xy 0.3048 -0.1016)
			)
			(stroke
				(width 0)
				(type default)
			)
			(fill no)
			(layer "B.CrtYd")
		)
		(fp_line
			(start 0.3048 -0.1016)
			(end 0.3048 0.9906)
			(stroke
				(width 0.1)
				(type default)
			)
			(layer "B.Fab")
		)
		(fp_line
			(start -0.3048 -0.1016)
			(end 0.3048 -0.1016)
			(stroke
				(width 0.1)
				(type default)
			)
			(layer "B.Fab")
		)
		(fp_line
			(start 0.3048 0.9906)
			(end -0.3048 0.9906)
			(stroke
				(width 0.1)
				(type default)
			)
			(layer "B.Fab")
		)
		(fp_line
			(start -0.3048 0.9906)
			(end -0.3048 -0.1016)
			(stroke
				(width 0.1)
				(type default)
			)
			(layer "B.Fab")
		)
		(pad "1" smd rect
			(at 0 0 270)
			(size 0.508 0.508)
			(layers "B.Cu" "B.Mask" "B.Paste")
			(net "SATA6G_PCH_PCIE_UP_SATA_RXN<7>")
		)
		(pad "2" smd rect
			(at 0 0.889 270)
			(size 0.508 0.508)
			(layers "B.Cu" "B.Mask" "B.Paste")
			(net "SATA6G_P7_RX_C_DN")
		)
		(zone
			(layer "B.Cu")
			(hatch none 0.5)
			(connect_pads
				(clearance 0)
			)
			(min_thickness 0.25)
			(keepout
				(tracks allowed)
				(vias not_allowed)
				(pads allowed)
				(copperpour not_allowed)
				(footprints allowed)
			)
			(placement
				(enabled no)
				(sheetname "")
			)
			(fill
				(thermal_gap 0.5)
				(thermal_bridge_width 0.5)
				(island_removal_mode 0)
			)
			(polygon
				(pts
					(xy 408.4066 -154.7368) (xy 408.4066 -154.2288) (xy 408.7876 -154.2288) (xy 408.7876 -154.7368)
				)
			)
		)
		(zone
			(layer "B.Cu")
			(hatch none 0.5)
			(connect_pads
				(clearance 0)
			)
			(min_thickness 0.25)
			(keepout
				(tracks not_allowed)
				(vias allowed)
				(pads allowed)
				(copperpour not_allowed)
				(footprints allowed)
			)
			(placement
				(enabled no)
				(sheetname "")
			)
			(fill
				(thermal_gap 0.5)
				(thermal_bridge_width 0.5)
				(island_removal_mode 0)
			)
			(polygon
				(pts
					(xy 408.7876 -154.7368) (xy 408.7876 -154.2288) (xy 408.4066 -154.2288) (xy 408.4066 -154.7368)
				)
			)
		)
	)
	(footprint ""
		(layer "B.Cu")
		(at 379.3363 -67.21856)
		(property "Reference" "R7E18"
			(at 0 0 0)
			(layer "B.SilkS")
			(hide yes)
			(effects
				(font
					(size 1.27 1.27)
				)
				(justify mirror)
			)
		)
		(property "Value" ""
			(at 0 0 0)
			(layer "B.Fab")
			(effects
				(font
					(size 1.27 1.27)
				)
				(justify mirror)
			)
		)
		(duplicate_pad_numbers_are_jumpers no)
		(fp_poly
			(pts
				(xy 0.2794 -0.1016) (xy -0.2794 -0.1016) (xy -0.2794 0.9906) (xy 0.2794 0.9906)
			)
			(stroke
				(width 0)
				(type default)
			)
			(fill no)
			(layer "B.CrtYd")
		)
		(fp_line
			(start -0.2794 -0.1016)
			(end 0.2794 -0.1016)
			(stroke
				(width 0.1)
				(type default)
			)
			(layer "B.Fab")
		)
		(fp_line
			(start -0.2794 0.9906)
			(end -0.2794 -0.1016)
			(stroke
				(width 0.1)
				(type default)
			)
			(layer "B.Fab")
		)
		(fp_line
			(start 0.2794 -0.1016)
			(end 0.2794 0.9906)
			(stroke
				(width 0.1)
				(type default)
			)
			(layer "B.Fab")
		)
		(fp_line
			(start 0.2794 0.9906)
			(end -0.2794 0.9906)
			(stroke
				(width 0.1)
				(type default)
			)
			(layer "B.Fab")
		)
		(pad "1" smd rect
			(at 0 0 180)
			(size 0.508 0.508)
			(layers "B.Cu" "B.Mask" "B.Paste")
			(net "P3V3_STBY")
		)
		(pad "2" smd rect
			(at 0 0.889 180)
			(size 0.508 0.508)
			(layers "B.Cu" "B.Mask" "B.Paste")
			(net "RST_RSMRST_N")
		)
		(zone
			(layer "B.Cu")
			(hatch none 0.5)
			(connect_pads
				(clearance 0)
			)
			(min_thickness 0.25)
			(keepout
				(tracks allowed)
				(vias not_allowed)
				(pads allowed)
				(copperpour not_allowed)
				(footprints allowed)
			)
			(placement
				(enabled no)
				(sheetname "")
			)
			(fill
				(thermal_gap 0.5)
				(thermal_bridge_width 0.5)
				(island_removal_mode 0)
			)
			(polygon
				(pts
					(xy 379.5903 -66.96456) (xy 379.0823 -66.96456) (xy 379.0823 -66.58356) (xy 379.5903 -66.58356)
				)
			)
		)
		(zone
			(layer "B.Cu")
			(hatch none 0.5)
			(connect_pads
				(clearance 0)
			)
			(min_thickness 0.25)
			(keepout
				(tracks not_allowed)
				(vias allowed)
				(pads allowed)
				(copperpour not_allowed)
				(footprints allowed)
			)
			(placement
				(enabled no)
				(sheetname "")
			)
			(fill
				(thermal_gap 0.5)
				(thermal_bridge_width 0.5)
				(island_removal_mode 0)
			)
			(polygon
				(pts
					(xy 379.5903 -66.58356) (xy 379.0823 -66.58356) (xy 379.0823 -66.96456) (xy 379.5903 -66.96456)
				)
			)
		)
	)
	(footprint ""
		(layer "B.Cu")
		(at 259.6896 -3.321812 90)
		(property "Reference" "C5G21"
			(at -1.64973 0.78994 180)
			(unlocked yes)
			(layer "B.SilkS")
			(effects
				(font
					(size 0.7874 0.5842)
					(thickness 0.1524)
				)
				(justify mirror)
			)
		)
		(property "Value" ""
			(at 0 0 90)
			(layer "B.Fab")
			(effects
				(font
					(size 1.27 1.27)
				)
				(justify mirror)
			)
		)
		(duplicate_pad_numbers_are_jumpers no)
		(fp_rect
			(start -0.7239 -0.2159)
			(end 0.7239 1.9939)
			(stroke
				(width 0)
				(type default)
			)
			(fill no)
			(layer "B.CrtYd")
		)
		(fp_line
			(start 0.7239 -0.2159)
			(end 0.7239 1.9939)
			(stroke
				(width 0.1)
				(type default)
			)
			(layer "B.Fab")
		)
		(fp_line
			(start -0.7239 -0.2159)
			(end 0.7239 -0.2159)
			(stroke
				(width 0.1)
				(type default)
			)
			(layer "B.Fab")
		)
		(fp_line
			(start 0.7239 1.9939)
			(end -0.7239 1.9939)
			(stroke
				(width 0.1)
				(type default)
			)
			(layer "B.Fab")
		)
		(fp_line
			(start -0.7239 1.9939)
			(end -0.7239 -0.2159)
			(stroke
				(width 0.1)
				(type default)
			)
			(layer "B.Fab")
		)
		(pad "1" smd rect
			(at 0 0 270)
			(size 1.27 1.016)
			(layers "B.Cu" "B.Mask" "B.Paste")
			(net "PVDDQ_ABC")
		)
		(pad "2" smd rect
			(at 0 1.778 270)
			(size 1.27 1.016)
			(layers "B.Cu" "B.Mask" "B.Paste")
			(net "GND")
		)
		(zone
			(layer "B.Cu")
			(hatch none 0.5)
			(connect_pads
				(clearance 0)
			)
			(min_thickness 0.25)
			(keepout
				(tracks not_allowed)
				(vias allowed)
				(pads allowed)
				(copperpour not_allowed)
				(footprints allowed)
			)
			(placement
				(enabled no)
				(sheetname "")
			)
			(fill
				(thermal_gap 0.5)
				(thermal_bridge_width 0.5)
				(island_removal_mode 0)
			)
			(polygon
				(pts
					(xy 260.1976 -2.686812) (xy 260.9596 -2.686812) (xy 260.9596 -3.956812) (xy 260.1976 -3.956812)
				)
			)
		)
	)
	(footprint ""
		(layer "B.Cu")
		(at 479.923602 -58.010298 90)
		(property "Reference" "R8E21"
			(at 0 0 90)
			(layer "B.SilkS")
			(hide yes)
			(effects
				(font
					(size 1.27 1.27)
				)
				(justify mirror)
			)
		)
		(property "Value" ""
			(at 0 0 90)
			(layer "B.Fab")
			(effects
				(font
					(size 1.27 1.27)
				)
				(justify mirror)
			)
		)
		(duplicate_pad_numbers_are_jumpers no)
		(fp_poly
			(pts
				(xy 0.2794 -0.1016) (xy -0.2794 -0.1016) (xy -0.2794 0.9906) (xy 0.2794 0.9906)
			)
			(stroke
				(width 0)
				(type default)
			)
			(fill no)
			(layer "B.CrtYd")
		)
		(fp_line
			(start 0.2794 -0.1016)
			(end 0.2794 0.9906)
			(stroke
				(width 0.1)
				(type default)
			)
			(layer "B.Fab")
		)
		(fp_line
			(start -0.2794 -0.1016)
			(end 0.2794 -0.1016)
			(stroke
				(width 0.1)
				(type default)
			)
			(layer "B.Fab")
		)
		(fp_line
			(start 0.2794 0.9906)
			(end -0.2794 0.9906)
			(stroke
				(width 0.1)
				(type default)
			)
			(layer "B.Fab")
		)
		(fp_line
			(start -0.2794 0.9906)
			(end -0.2794 -0.1016)
			(stroke
				(width 0.1)
				(type default)
			)
			(layer "B.Fab")
		)
		(pad "1" smd rect
			(at 0 0 270)
			(size 0.508 0.508)
			(layers "B.Cu" "B.Mask" "B.Paste")
			(net "FM_PE_SPRV_WAKE_N")
		)
		(pad "2" smd rect
			(at 0 0.889 270)
			(size 0.508 0.508)
			(layers "B.Cu" "B.Mask" "B.Paste")
			(net "FM_ALL_WAKE_N")
		)
		(zone
			(layer "B.Cu")
			(hatch none 0.5)
			(connect_pads
				(clearance 0)
			)
			(min_thickness 0.25)
			(keepout
				(tracks allowed)
				(vias not_allowed)
				(pads allowed)
				(copperpour not_allowed)
				(footprints allowed)
			)
			(placement
				(enabled no)
				(sheetname "")
			)
			(fill
				(thermal_gap 0.5)
				(thermal_bridge_width 0.5)
				(island_removal_mode 0)
			)
			(polygon
				(pts
					(xy 480.177602 -58.264298) (xy 480.177602 -57.756298) (xy 480.558602 -57.756298) (xy 480.558602 -58.264298)
				)
			)
		)
		(zone
			(layer "B.Cu")
			(hatch none 0.5)
			(connect_pads
				(clearance 0)
			)
			(min_thickness 0.25)
			(keepout
				(tracks not_allowed)
				(vias allowed)
				(pads allowed)
				(copperpour not_allowed)
				(footprints allowed)
			)
			(placement
				(enabled no)
				(sheetname "")
			)
			(fill
				(thermal_gap 0.5)
				(thermal_bridge_width 0.5)
				(island_removal_mode 0)
			)
			(polygon
				(pts
					(xy 480.558602 -58.264298) (xy 480.558602 -57.756298) (xy 480.177602 -57.756298) (xy 480.177602 -58.264298)
				)
			)
		)
	)
	(footprint ""
		(layer "B.Cu")
		(at 385.9276 -65.3288 90)
		(property "Reference" "Q8F1"
			(at -3.42773 -1.1938 180)
			(unlocked yes)
			(layer "B.SilkS")
			(effects
				(font
					(size 0.7874 0.5842)
					(thickness 0.1524)
				)
				(justify left mirror)
			)
		)
		(property "Value" ""
			(at 0 0 90)
			(layer "B.Fab")
			(effects
				(font
					(size 1.27 1.27)
				)
				(justify mirror)
			)
		)
		(duplicate_pad_numbers_are_jumpers no)
		(fp_line
			(start -0.9525 -0.5715)
			(end -1.778 -0.5715)
			(stroke
				(width 0.1524)
				(type default)
			)
			(layer "B.SilkS")
		)
		(fp_line
			(start -1.778 -0.5715)
			(end -1.778 0.3175)
			(stroke
				(width 0.1524)
				(type default)
			)
			(layer "B.SilkS")
		)
		(fp_line
			(start -0.381 0.635)
			(end -0.381 1.27)
			(stroke
				(width 0.1524)
				(type default)
			)
			(layer "B.SilkS")
		)
		(fp_line
			(start -0.9525 2.4765)
			(end -1.778 2.4765)
			(stroke
				(width 0.1524)
				(type default)
			)
			(layer "B.SilkS")
		)
		(fp_line
			(start -1.778 2.4765)
			(end -1.778 1.5875)
			(stroke
				(width 0.1524)
				(type default)
			)
			(layer "B.SilkS")
		)
		(fp_circle
			(center 0.9525 -0.9271)
			(end 0.9525 -0.8001)
			(stroke
				(width 0.254)
				(type default)
			)
			(fill no)
			(layer "B.SilkS")
		)
		(fp_poly
			(pts
				(xy -1.778 2.4765) (xy -0.381 2.4765) (xy -0.381 -0.5715) (xy -1.778 -0.5715)
			)
			(stroke
				(width 0)
				(type default)
			)
			(fill no)
			(layer "B.CrtYd")
		)
		(fp_line
			(start -0.381 -0.5715)
			(end -0.381 2.4765)
			(stroke
				(width 0.1)
				(type default)
			)
			(layer "B.Fab")
		)
		(fp_line
			(start -1.778 -0.5715)
			(end -0.381 -0.5715)
			(stroke
				(width 0.1)
				(type default)
			)
			(layer "B.Fab")
		)
		(fp_line
			(start -0.381 2.4765)
			(end -1.778 2.4765)
			(stroke
				(width 0.1)
				(type default)
			)
			(layer "B.Fab")
		)
		(fp_line
			(start -1.778 2.4765)
			(end -1.778 -0.5715)
			(stroke
				(width 0.1)
				(type default)
			)
			(layer "B.Fab")
		)
		(fp_circle
			(center 0.9525 -0.9271)
			(end 0.9525 -0.8001)
			(stroke
				(width 0.254)
				(type default)
			)
			(fill no)
			(layer "B.Fab")
		)
		(pad "1" smd rect
			(at 0 0 270)
			(size 1.143 0.508)
			(layers "B.Cu" "B.Mask" "B.Paste")
			(net "FM_BACKUP_BIOS_SEL_N")
		)
		(pad "2" smd rect
			(at 0 1.905 270)
			(size 1.143 0.508)
			(layers "B.Cu" "B.Mask" "B.Paste")
			(net "GND")
		)
		(pad "3" smd rect
			(at -2.159 0.9525 270)
			(size 1.143 0.508)
			(layers "B.Cu" "B.Mask" "B.Paste")
			(net "FM_DUAL_BIOS_SEL_N")
		)
	)
	(footprint ""
		(layer "B.Cu")
		(at 169.926 -87.757)
		(property "Reference" "R6P4"
			(at 0 0 0)
			(layer "B.SilkS")
			(hide yes)
			(effects
				(font
					(size 1.27 1.27)
				)
				(justify mirror)
			)
		)
		(property "Value" ""
			(at 0 0 0)
			(layer "B.Fab")
			(effects
				(font
					(size 1.27 1.27)
				)
				(justify mirror)
			)
		)
		(duplicate_pad_numbers_are_jumpers no)
		(fp_poly
			(pts
				(xy 0.2794 -0.1016) (xy -0.2794 -0.1016) (xy -0.2794 0.9906) (xy 0.2794 0.9906)
			)
			(stroke
				(width 0)
				(type default)
			)
			(fill no)
			(layer "B.CrtYd")
		)
		(fp_line
			(start -0.2794 -0.1016)
			(end 0.2794 -0.1016)
			(stroke
				(width 0.1)
				(type default)
			)
			(layer "B.Fab")
		)
		(fp_line
			(start -0.2794 0.9906)
			(end -0.2794 -0.1016)
			(stroke
				(width 0.1)
				(type default)
			)
			(layer "B.Fab")
		)
		(fp_line
			(start 0.2794 -0.1016)
			(end 0.2794 0.9906)
			(stroke
				(width 0.1)
				(type default)
			)
			(layer "B.Fab")
		)
		(fp_line
			(start 0.2794 0.9906)
			(end -0.2794 0.9906)
			(stroke
				(width 0.1)
				(type default)
			)
			(layer "B.Fab")
		)
		(pad "1" smd rect
			(at 0 0 180)
			(size 0.508 0.508)
			(layers "B.Cu" "B.Mask" "B.Paste")
			(net "CLK_100M_CPU0_RC_REFCLK1_DN")
		)
		(pad "2" smd rect
			(at 0 0.889 180)
			(size 0.508 0.508)
			(layers "B.Cu" "B.Mask" "B.Paste")
			(net "GND")
		)
		(zone
			(layer "B.Cu")
			(hatch none 0.5)
			(connect_pads
				(clearance 0)
			)
			(min_thickness 0.25)
			(keepout
				(tracks allowed)
				(vias not_allowed)
				(pads allowed)
				(copperpour not_allowed)
				(footprints allowed)
			)
			(placement
				(enabled no)
				(sheetname "")
			)
			(fill
				(thermal_gap 0.5)
				(thermal_bridge_width 0.5)
				(island_removal_mode 0)
			)
			(polygon
				(pts
					(xy 170.18 -87.503) (xy 169.672 -87.503) (xy 169.672 -87.122) (xy 170.18 -87.122)
				)
			)
		)
		(zone
			(layer "B.Cu")
			(hatch none 0.5)
			(connect_pads
				(clearance 0)
			)
			(min_thickness 0.25)
			(keepout
				(tracks not_allowed)
				(vias allowed)
				(pads allowed)
				(copperpour not_allowed)
				(footprints allowed)
			)
			(placement
				(enabled no)
				(sheetname "")
			)
			(fill
				(thermal_gap 0.5)
				(thermal_bridge_width 0.5)
				(island_removal_mode 0)
			)
			(polygon
				(pts
					(xy 170.18 -87.122) (xy 169.672 -87.122) (xy 169.672 -87.503) (xy 170.18 -87.503)
				)
			)
		)
	)
	(footprint ""
		(layer "B.Cu")
		(at 352.552 -104.267 180)
		(property "Reference" "C22W33"
			(at 0 0 0)
			(layer "B.SilkS")
			(hide yes)
			(effects
				(font
					(size 1.27 1.27)
				)
				(justify mirror)
			)
		)
		(property "Value" "*"
			(at 0.0762 -6.2357 180)
			(unlocked yes)
			(layer "B.Fab")
			(hide yes)
			(effects
				(font
					(size 1.27 1.016)
					(thickness 0.1524)
				)
				(justify mirror)
			)
		)
		(property "Device Type" "SC22U16V5MX-4-GP_SMD-BCG5-SC22A"
			(at 0.0762 -8.2677 180)
			(unlocked yes)
			(layer "B.Fab")
			(hide yes)
			(effects
				(font
					(size 1.27 1.016)
					(thickness 0.1524)
				)
				(justify mirror)
			)
		)
		(duplicate_pad_numbers_are_jumpers no)
		(fp_line
			(start -0.635 0)
			(end 0.635 0)
			(stroke
				(width 0.508)
				(type default)
			)
			(layer "B.SilkS")
		)
		(fp_rect
			(start 0.9652 1.778)
			(end -0.9652 -1.778)
			(stroke
				(width 0)
				(type default)
			)
			(fill no)
			(layer "B.CrtYd")
		)
		(fp_poly
			(pts
				(xy 0.9652 -1.778) (xy -0.9652 -1.778) (xy -0.9652 1.778) (xy 0.9652 1.778)
			)
			(stroke
				(width 0)
				(type default)
			)
			(fill no)
			(layer "B.Fab")
		)
		(pad "1" smd rect
			(at 0 -0.9652)
			(size 1.397 1.143)
			(layers "B.Cu" "B.Mask" "B.Paste")
			(net "VR_FET_SW_P12V_STBY_PVCCIO_CPU0")
		)
		(pad "2" smd rect
			(at 0 0.9652)
			(size 1.397 1.143)
			(layers "B.Cu" "B.Mask" "B.Paste")
			(net "GND")
		)
	)
	(footprint ""
		(layer "B.Cu")
		(at 275.389086 -79.60614 180)
		(property "Reference" "C5P10"
			(at 0 0 0)
			(layer "B.SilkS")
			(hide yes)
			(effects
				(font
					(size 1.27 1.27)
				)
				(justify mirror)
			)
		)
		(property "Value" ""
			(at 0 0 0)
			(layer "B.Fab")
			(effects
				(font
					(size 1.27 1.27)
				)
				(justify mirror)
			)
		)
		(duplicate_pad_numbers_are_jumpers no)
		(fp_poly
			(pts
				(xy 0.7239 -0.2159) (xy -0.7239 -0.2159) (xy -0.7239 1.9939) (xy 0.7239 1.9939)
			)
			(stroke
				(width 0)
				(type default)
			)
			(fill no)
			(layer "B.CrtYd")
		)
		(fp_line
			(start 0.7239 1.9939)
			(end -0.7239 1.9939)
			(stroke
				(width 0.1)
				(type default)
			)
			(layer "B.Fab")
		)
		(fp_line
			(start 0.7239 -0.2159)
			(end 0.7239 1.9939)
			(stroke
				(width 0.1)
				(type default)
			)
			(layer "B.Fab")
		)
		(fp_line
			(start -0.7239 1.9939)
			(end -0.7239 -0.2159)
			(stroke
				(width 0.1)
				(type default)
			)
			(layer "B.Fab")
		)
		(fp_line
			(start -0.7239 -0.2159)
			(end 0.7239 -0.2159)
			(stroke
				(width 0.1)
				(type default)
			)
			(layer "B.Fab")
		)
		(pad "1" smd rect
			(at 0 0)
			(size 1.27 1.016)
			(layers "B.Cu" "B.Mask" "B.Paste")
			(net "PVCCMCP_CPU0")
		)
		(pad "2" smd rect
			(at 0 1.778)
			(size 1.27 1.016)
			(layers "B.Cu" "B.Mask" "B.Paste")
			(net "GND")
		)
		(zone
			(layer "B.Cu")
			(hatch none 0.5)
			(connect_pads
				(clearance 0)
			)
			(min_thickness 0.25)
			(keepout
				(tracks not_allowed)
				(vias allowed)
				(pads allowed)
				(copperpour not_allowed)
				(footprints allowed)
			)
			(placement
				(enabled no)
				(sheetname "")
			)
			(fill
				(thermal_gap 0.5)
				(thermal_bridge_width 0.5)
				(island_removal_mode 0)
			)
			(polygon
				(pts
					(xy 274.754086 -80.11414) (xy 276.024086 -80.11414) (xy 276.024086 -80.87614) (xy 274.754086 -80.87614)
				)
			)
		)
	)
	(footprint ""
		(layer "B.Cu")
		(at 88.392 -145.0086 90)
		(property "Reference" "C8L7"
			(at -1.848866 0.752348 90)
			(unlocked yes)
			(layer "B.SilkS")
			(effects
				(font
					(size 1.27 0.9652)
					(thickness 0.1524)
				)
				(justify mirror)
			)
		)
		(property "Value" ""
			(at 0 0 90)
			(layer "B.Fab")
			(effects
				(font
					(size 1.27 1.27)
				)
				(justify mirror)
			)
		)
		(duplicate_pad_numbers_are_jumpers no)
		(fp_rect
			(start 0.500126 1.598422)
			(end -0.500126 -0.201422)
			(stroke
				(width 0)
				(type default)
			)
			(fill no)
			(layer "B.CrtYd")
		)
		(fp_line
			(start 0.500126 -0.201422)
			(end -0.500126 -0.201422)
			(stroke
				(width 0.1)
				(type default)
			)
			(layer "B.Fab")
		)
		(fp_line
			(start -0.500126 -0.201422)
			(end -0.500126 1.598422)
			(stroke
				(width 0.1)
				(type default)
			)
			(layer "B.Fab")
		)
		(fp_line
			(start 0.500126 1.598422)
			(end 0.500126 -0.201422)
			(stroke
				(width 0.1)
				(type default)
			)
			(layer "B.Fab")
		)
		(fp_line
			(start -0.500126 1.598422)
			(end 0.500126 1.598422)
			(stroke
				(width 0.1)
				(type default)
			)
			(layer "B.Fab")
		)
		(pad "1" smd rect
			(at 0 0)
			(size 0.889 0.9906)
			(layers "B.Cu" "B.Mask" "B.Paste")
			(net "PVDDQ_KLM")
		)
		(pad "2" smd rect
			(at 0 1.397)
			(size 0.889 0.9906)
			(layers "B.Cu" "B.Mask" "B.Paste")
			(net "GND")
		)
		(zone
			(layer "B.Cu")
			(hatch none 0.5)
			(connect_pads
				(clearance 0)
			)
			(min_thickness 0.25)
			(keepout
				(tracks not_allowed)
				(vias allowed)
				(pads allowed)
				(copperpour not_allowed)
				(footprints allowed)
			)
			(placement
				(enabled no)
				(sheetname "")
			)
			(fill
				(thermal_gap 0.5)
				(thermal_bridge_width 0.5)
				(island_removal_mode 0)
			)
			(polygon
				(pts
					(xy 89.3445 -145.5039) (xy 88.8365 -145.5039) (xy 88.8365 -144.5133) (xy 89.3445 -144.5133)
				)
			)
		)
		(zone
			(layer "B.Cu")
			(hatch none 0.5)
			(connect_pads
				(clearance 0)
			)
			(min_thickness 0.25)
			(keepout
				(tracks allowed)
				(vias not_allowed)
				(pads allowed)
				(copperpour not_allowed)
				(footprints allowed)
			)
			(placement
				(enabled no)
				(sheetname "")
			)
			(fill
				(thermal_gap 0.5)
				(thermal_bridge_width 0.5)
				(island_removal_mode 0)
			)
			(polygon
				(pts
					(xy 89.3445 -145.5039) (xy 88.8365 -145.5039) (xy 88.8365 -144.5133) (xy 89.3445 -144.5133)
				)
			)
		)
	)
	(footprint ""
		(layer "B.Cu")
		(at 399.923 -55.118 180)
		(property "Reference" "R3T4"
			(at 0 0 0)
			(layer "B.SilkS")
			(hide yes)
			(effects
				(font
					(size 1.27 1.27)
				)
				(justify mirror)
			)
		)
		(property "Value" ""
			(at 0 0 0)
			(layer "B.Fab")
			(effects
				(font
					(size 1.27 1.27)
				)
				(justify mirror)
			)
		)
		(duplicate_pad_numbers_are_jumpers no)
		(fp_poly
			(pts
				(xy 0.2794 -0.1016) (xy -0.2794 -0.1016) (xy -0.2794 0.9906) (xy 0.2794 0.9906)
			)
			(stroke
				(width 0)
				(type default)
			)
			(fill no)
			(layer "B.CrtYd")
		)
		(fp_line
			(start 0.2794 0.9906)
			(end -0.2794 0.9906)
			(stroke
				(width 0.1)
				(type default)
			)
			(layer "B.Fab")
		)
		(fp_line
			(start 0.2794 -0.1016)
			(end 0.2794 0.9906)
			(stroke
				(width 0.1)
				(type default)
			)
			(layer "B.Fab")
		)
		(fp_line
			(start -0.2794 0.9906)
			(end -0.2794 -0.1016)
			(stroke
				(width 0.1)
				(type default)
			)
			(layer "B.Fab")
		)
		(fp_line
			(start -0.2794 -0.1016)
			(end 0.2794 -0.1016)
			(stroke
				(width 0.1)
				(type default)
			)
			(layer "B.Fab")
		)
		(pad "1" smd rect
			(at 0 0)
			(size 0.508 0.508)
			(layers "B.Cu" "B.Mask" "B.Paste")
			(net "P3V3_STBY")
		)
		(pad "2" smd rect
			(at 0 0.889)
			(size 0.508 0.508)
			(layers "B.Cu" "B.Mask" "B.Paste")
			(net "PU_BIOS_SPI_HOLD1_N")
		)
		(zone
			(layer "B.Cu")
			(hatch none 0.5)
			(connect_pads
				(clearance 0)
			)
			(min_thickness 0.25)
			(keepout
				(tracks not_allowed)
				(vias allowed)
				(pads allowed)
				(copperpour not_allowed)
				(footprints allowed)
			)
			(placement
				(enabled no)
				(sheetname "")
			)
			(fill
				(thermal_gap 0.5)
				(thermal_bridge_width 0.5)
				(island_removal_mode 0)
			)
			(polygon
				(pts
					(xy 399.669 -55.753) (xy 400.177 -55.753) (xy 400.177 -55.372) (xy 399.669 -55.372)
				)
			)
		)
		(zone
			(layer "B.Cu")
			(hatch none 0.5)
			(connect_pads
				(clearance 0)
			)
			(min_thickness 0.25)
			(keepout
				(tracks allowed)
				(vias not_allowed)
				(pads allowed)
				(copperpour not_allowed)
				(footprints allowed)
			)
			(placement
				(enabled no)
				(sheetname "")
			)
			(fill
				(thermal_gap 0.5)
				(thermal_bridge_width 0.5)
				(island_removal_mode 0)
			)
			(polygon
				(pts
					(xy 399.669 -55.372) (xy 400.177 -55.372) (xy 400.177 -55.753) (xy 399.669 -55.753)
				)
			)
		)
	)
	(footprint ""
		(layer "B.Cu")
		(at 373.4308 -44.8818 90)
		(property "Reference" "R2T36"
			(at 0 0 90)
			(layer "B.SilkS")
			(hide yes)
			(effects
				(font
					(size 1.27 1.27)
				)
				(justify mirror)
			)
		)
		(property "Value" "*"
			(at -0.064008 -4.108196 90)
			(unlocked yes)
			(layer "B.Fab")
			(hide yes)
			(effects
				(font
					(size 1.27 1.016)
					(thickness 0.1524)
				)
				(justify mirror)
			)
		)
		(property "Device Type" "374R2F-1-GP_SMD-RG-374R2F-1-GPA"
			(at -0.064008 -5.632196 90)
			(unlocked yes)
			(layer "B.Fab")
			(hide yes)
			(effects
				(font
					(size 1.27 1.016)
					(thickness 0.1524)
				)
				(justify mirror)
			)
		)
		(duplicate_pad_numbers_are_jumpers no)
		(fp_line
			(start 0.508 -0.9398)
			(end 0.508 0.9398)
			(stroke
				(width 0.1524)
				(type default)
			)
			(layer "B.SilkS")
		)
		(fp_line
			(start -0.508 -0.9398)
			(end 0.508 -0.9398)
			(stroke
				(width 0.1524)
				(type default)
			)
			(layer "B.SilkS")
		)
		(fp_rect
			(start 0.508 0.9398)
			(end -0.508 -0.9398)
			(stroke
				(width 0)
				(type default)
			)
			(fill no)
			(layer "B.CrtYd")
		)
		(fp_rect
			(start 0.508 0.9398)
			(end -0.508 -0.9398)
			(stroke
				(width 0)
				(type default)
			)
			(fill no)
			(layer "B.Fab")
		)
		(pad "1" smd custom
			(at 0 -0.4445 270)
			(size 0.1397 0.1397)
			(layers "B.Cu" "B.Mask" "B.Paste")
			(net "P3V3")
			(options
				(clearance outline)
				(anchor circle)
			)
			(primitives
				(gr_poly
					(pts
						(arc
							(start -0.1778 0.2794)
							(mid -0.249642 0.249642)
							(end -0.2794 0.1778)
						)
						(arc
							(start -0.2794 -0.1778)
							(mid -0.249642 -0.249642)
							(end -0.1778 -0.2794)
						)
						(arc
							(start 0.1778 -0.2794)
							(mid 0.249642 -0.249642)
							(end 0.2794 -0.1778)
						)
						(arc
							(start 0.2794 0.1778)
							(mid 0.249642 0.249642)
							(end 0.1778 0.2794)
						)
					)
					(width 0)
					(fill yes)
				)
			)
		)
		(pad "2" smd custom
			(at 0 0.4445 270)
			(size 0.1397 0.1397)
			(layers "B.Cu" "B.Mask" "B.Paste")
			(net "P0V7_GTL2104_5_VREF")
			(options
				(clearance outline)
				(anchor circle)
			)
			(primitives
				(gr_poly
					(pts
						(arc
							(start -0.1778 0.2794)
							(mid -0.249642 0.249642)
							(end -0.2794 0.1778)
						)
						(arc
							(start -0.2794 -0.1778)
							(mid -0.249642 -0.249642)
							(end -0.1778 -0.2794)
						)
						(arc
							(start 0.1778 -0.2794)
							(mid 0.249642 -0.249642)
							(end 0.2794 -0.1778)
						)
						(arc
							(start 0.2794 0.1778)
							(mid 0.249642 0.249642)
							(end 0.1778 0.2794)
						)
					)
					(width 0)
					(fill yes)
				)
			)
		)
	)
	(footprint ""
		(layer "B.Cu")
		(at 372.51894 -153.956766)
		(property "Reference" "C3L1"
			(at 0 0 0)
			(layer "B.SilkS")
			(hide yes)
			(effects
				(font
					(size 1.27 1.27)
				)
				(justify mirror)
			)
		)
		(property "Value" "*"
			(at -1.1811 -2.8194 0)
			(unlocked yes)
			(layer "B.Fab")
			(hide yes)
			(effects
				(font
					(size 1.27 1.016)
					(thickness 0.1524)
				)
				(justify mirror)
			)
		)
		(property "Device Type" "SC1U10V2KX-4-GP_SMD-BCG6-SC1U1A"
			(at -1.1811 -4.3434 0)
			(unlocked yes)
			(layer "B.Fab")
			(hide yes)
			(effects
				(font
					(size 1.27 1.016)
					(thickness 0.1524)
				)
				(justify mirror)
			)
		)
		(duplicate_pad_numbers_are_jumpers no)
		(fp_rect
			(start 0.4318 0.9525)
			(end -0.4318 -0.9525)
			(stroke
				(width 0)
				(type default)
			)
			(fill no)
			(layer "B.CrtYd")
		)
		(fp_rect
			(start 0.4318 0.9525)
			(end -0.4318 -0.9525)
			(stroke
				(width 0)
				(type default)
			)
			(fill no)
			(layer "B.Fab")
		)
		(pad "1" smd custom
			(at 0 -0.4445 180)
			(size 0.1524 0.1524)
			(layers "B.Cu" "B.Mask" "B.Paste")
			(net "P5V_STBY")
			(options
				(clearance outline)
				(anchor circle)
			)
			(primitives
				(gr_poly
					(pts
						(arc
							(start 0.3048 0.2032)
							(mid 0.275042 0.275042)
							(end 0.2032 0.3048)
						)
						(arc
							(start -0.2032 0.3048)
							(mid -0.275042 0.275042)
							(end -0.3048 0.2032)
						)
						(arc
							(start -0.3048 -0.2032)
							(mid -0.275042 -0.275042)
							(end -0.2032 -0.3048)
						)
						(arc
							(start 0.2032 -0.3048)
							(mid 0.275042 -0.275042)
							(end 0.3048 -0.2032)
						)
					)
					(width 0)
					(fill yes)
				)
			)
		)
		(pad "2" smd custom
			(at 0 0.4445 180)
			(size 0.1524 0.1524)
			(layers "B.Cu" "B.Mask" "B.Paste")
			(net "GND")
			(options
				(clearance outline)
				(anchor circle)
			)
			(primitives
				(gr_poly
					(pts
						(arc
							(start 0.3048 0.2032)
							(mid 0.275042 0.275042)
							(end 0.2032 0.3048)
						)
						(arc
							(start -0.2032 0.3048)
							(mid -0.275042 0.275042)
							(end -0.3048 0.2032)
						)
						(arc
							(start -0.3048 -0.2032)
							(mid -0.275042 -0.275042)
							(end -0.2032 -0.3048)
						)
						(arc
							(start 0.2032 -0.3048)
							(mid 0.275042 -0.275042)
							(end 0.3048 -0.2032)
						)
					)
					(width 0)
					(fill yes)
				)
			)
		)
	)
	(footprint ""
		(layer "B.Cu")
		(at 19.431 -83.312 -90)
		(property "Reference" "R9P9"
			(at 0 0 90)
			(layer "B.SilkS")
			(hide yes)
			(effects
				(font
					(size 1.27 1.27)
				)
				(justify mirror)
			)
		)
		(property "Value" ""
			(at 0 0 90)
			(layer "B.Fab")
			(effects
				(font
					(size 1.27 1.27)
				)
				(justify mirror)
			)
		)
		(duplicate_pad_numbers_are_jumpers no)
		(fp_poly
			(pts
				(xy 0.2794 -0.1016) (xy -0.2794 -0.1016) (xy -0.2794 0.9906) (xy 0.2794 0.9906)
			)
			(stroke
				(width 0)
				(type default)
			)
			(fill no)
			(layer "B.CrtYd")
		)
		(fp_line
			(start -0.2794 0.9906)
			(end -0.2794 -0.1016)
			(stroke
				(width 0.1)
				(type default)
			)
			(layer "B.Fab")
		)
		(fp_line
			(start 0.2794 0.9906)
			(end -0.2794 0.9906)
			(stroke
				(width 0.1)
				(type default)
			)
			(layer "B.Fab")
		)
		(fp_line
			(start -0.2794 -0.1016)
			(end 0.2794 -0.1016)
			(stroke
				(width 0.1)
				(type default)
			)
			(layer "B.Fab")
		)
		(fp_line
			(start 0.2794 -0.1016)
			(end 0.2794 0.9906)
			(stroke
				(width 0.1)
				(type default)
			)
			(layer "B.Fab")
		)
		(pad "1" smd rect
			(at 0 0 90)
			(size 0.508 0.508)
			(layers "B.Cu" "B.Mask" "B.Paste")
			(net "A_P12V_STBY_ADR_TRIGGER")
		)
		(pad "2" smd rect
			(at 0 0.889 90)
			(size 0.508 0.508)
			(layers "B.Cu" "B.Mask" "B.Paste")
			(net "AGND_HSC")
		)
		(zone
			(layer "B.Cu")
			(hatch none 0.5)
			(connect_pads
				(clearance 0)
			)
			(min_thickness 0.25)
			(keepout
				(tracks not_allowed)
				(vias allowed)
				(pads allowed)
				(copperpour not_allowed)
				(footprints allowed)
			)
			(placement
				(enabled no)
				(sheetname "")
			)
			(fill
				(thermal_gap 0.5)
				(thermal_bridge_width 0.5)
				(island_removal_mode 0)
			)
			(polygon
				(pts
					(xy 18.796 -83.058) (xy 18.796 -83.566) (xy 19.177 -83.566) (xy 19.177 -83.058)
				)
			)
		)
		(zone
			(layer "B.Cu")
			(hatch none 0.5)
			(connect_pads
				(clearance 0)
			)
			(min_thickness 0.25)
			(keepout
				(tracks allowed)
				(vias not_allowed)
				(pads allowed)
				(copperpour not_allowed)
				(footprints allowed)
			)
			(placement
				(enabled no)
				(sheetname "")
			)
			(fill
				(thermal_gap 0.5)
				(thermal_bridge_width 0.5)
				(island_removal_mode 0)
			)
			(polygon
				(pts
					(xy 19.177 -83.058) (xy 19.177 -83.566) (xy 18.796 -83.566) (xy 18.796 -83.058)
				)
			)
		)
	)
	(footprint ""
		(layer "B.Cu")
		(at 418.846 -22.225 90)
		(property "Reference" "L25W1"
			(at 0 0 90)
			(layer "B.SilkS")
			(hide yes)
			(effects
				(font
					(size 1.27 1.27)
				)
				(justify mirror)
			)
		)
		(property "Value" "*"
			(at -0.0254 -2.8829 90)
			(unlocked yes)
			(layer "B.Fab")
			(hide yes)
			(effects
				(font
					(size 1.27 1.016)
					(thickness 0.1524)
				)
				(justify mirror)
			)
		)
		(property "Device Type" "IND-68NH-15-GP_DISCRET-GC1-INDA"
			(at -0.0254 -4.4069 90)
			(unlocked yes)
			(layer "B.Fab")
			(hide yes)
			(effects
				(font
					(size 1.27 1.016)
					(thickness 0.1524)
				)
				(justify mirror)
			)
		)
		(duplicate_pad_numbers_are_jumpers no)
		(fp_line
			(start -0.254 0)
			(end 0.254 0)
			(stroke
				(width 0.2032)
				(type default)
			)
			(layer "B.SilkS")
		)
		(fp_rect
			(start 0.5842 1.3335)
			(end -0.5842 -1.3335)
			(stroke
				(width 0)
				(type default)
			)
			(fill no)
			(layer "B.CrtYd")
		)
		(fp_rect
			(start 0.5842 1.3335)
			(end -0.5842 -1.3335)
			(stroke
				(width 0)
				(type default)
			)
			(fill no)
			(layer "B.Fab")
		)
		(pad "1" smd custom
			(at 0 -0.762 270)
			(size 0.2159 0.2159)
			(layers "B.Cu" "B.Mask" "B.Paste")
			(net "BMC_VGA_BLUE")
			(options
				(clearance outline)
				(anchor circle)
			)
			(primitives
				(gr_poly
					(pts
						(arc
							(start -0.3302 0.4318)
							(mid -0.402042 0.402042)
							(end -0.4318 0.3302)
						)
						(arc
							(start -0.4318 -0.3302)
							(mid -0.402042 -0.402042)
							(end -0.3302 -0.4318)
						)
						(arc
							(start 0.3302 -0.4318)
							(mid 0.402042 -0.402042)
							(end 0.4318 -0.3302)
						)
						(arc
							(start 0.4318 0.3302)
							(mid 0.402042 0.402042)
							(end 0.3302 0.4318)
						)
					)
					(width 0)
					(fill yes)
				)
			)
		)
		(pad "2" smd custom
			(at 0 0.762 270)
			(size 0.2159 0.2159)
			(layers "B.Cu" "B.Mask" "B.Paste")
			(net "V_IO_B_J")
			(options
				(clearance outline)
				(anchor circle)
			)
			(primitives
				(gr_poly
					(pts
						(arc
							(start -0.3302 0.4318)
							(mid -0.402042 0.402042)
							(end -0.4318 0.3302)
						)
						(arc
							(start -0.4318 -0.3302)
							(mid -0.402042 -0.402042)
							(end -0.3302 -0.4318)
						)
						(arc
							(start 0.3302 -0.4318)
							(mid 0.402042 -0.402042)
							(end 0.4318 -0.3302)
						)
						(arc
							(start 0.4318 0.3302)
							(mid 0.402042 0.402042)
							(end 0.3302 0.4318)
						)
					)
					(width 0)
					(fill yes)
				)
			)
		)
	)
	(footprint ""
		(layer "B.Cu")
		(at 346.8751 -156.5656 -90)
		(property "Reference" "C7A18"
			(at 0 0 90)
			(layer "B.SilkS")
			(hide yes)
			(effects
				(font
					(size 1.27 1.27)
				)
				(justify mirror)
			)
		)
		(property "Value" "*"
			(at -1.1811 -2.8194 270)
			(unlocked yes)
			(layer "B.Fab")
			(hide yes)
			(effects
				(font
					(size 1.27 1.016)
					(thickness 0.1524)
				)
				(justify mirror)
			)
		)
		(property "Device Type" "SC1U10V2KX-4-GP_SMD-BCG6-SC1U1A"
			(at -1.1811 -4.3434 270)
			(unlocked yes)
			(layer "B.Fab")
			(hide yes)
			(effects
				(font
					(size 1.27 1.016)
					(thickness 0.1524)
				)
				(justify mirror)
			)
		)
		(duplicate_pad_numbers_are_jumpers no)
		(fp_rect
			(start 0.4318 0.9525)
			(end -0.4318 -0.9525)
			(stroke
				(width 0)
				(type default)
			)
			(fill no)
			(layer "B.CrtYd")
		)
		(fp_rect
			(start 0.4318 0.9525)
			(end -0.4318 -0.9525)
			(stroke
				(width 0)
				(type default)
			)
			(fill no)
			(layer "B.Fab")
		)
		(pad "1" smd custom
			(at 0 -0.4445 90)
			(size 0.1524 0.1524)
			(layers "B.Cu" "B.Mask" "B.Paste")
			(net "P5V_STBY")
			(options
				(clearance outline)
				(anchor circle)
			)
			(primitives
				(gr_poly
					(pts
						(arc
							(start 0.3048 0.2032)
							(mid 0.275042 0.275042)
							(end 0.2032 0.3048)
						)
						(arc
							(start -0.2032 0.3048)
							(mid -0.275042 0.275042)
							(end -0.3048 0.2032)
						)
						(arc
							(start -0.3048 -0.2032)
							(mid -0.275042 -0.275042)
							(end -0.2032 -0.3048)
						)
						(arc
							(start 0.2032 -0.3048)
							(mid 0.275042 -0.275042)
							(end 0.3048 -0.2032)
						)
					)
					(width 0)
					(fill yes)
				)
			)
		)
		(pad "2" smd custom
			(at 0 0.4445 90)
			(size 0.1524 0.1524)
			(layers "B.Cu" "B.Mask" "B.Paste")
			(net "GND")
			(options
				(clearance outline)
				(anchor circle)
			)
			(primitives
				(gr_poly
					(pts
						(arc
							(start 0.3048 0.2032)
							(mid 0.275042 0.275042)
							(end 0.2032 0.3048)
						)
						(arc
							(start -0.2032 0.3048)
							(mid -0.275042 0.275042)
							(end -0.3048 0.2032)
						)
						(arc
							(start -0.3048 -0.2032)
							(mid -0.275042 -0.275042)
							(end -0.2032 -0.3048)
						)
						(arc
							(start 0.2032 -0.3048)
							(mid 0.275042 -0.275042)
							(end 0.3048 -0.2032)
						)
					)
					(width 0)
					(fill yes)
				)
			)
		)
	)
	(footprint ""
		(layer "B.Cu")
		(at 104.5591 -12.954 90)
		(property "Reference" "C5G94"
			(at -1.14681 0.76708 180)
			(unlocked yes)
			(layer "B.SilkS")
			(effects
				(font
					(size 0.7874 0.5842)
					(thickness 0.1524)
				)
				(justify mirror)
			)
		)
		(property "Value" ""
			(at 0 0 90)
			(layer "B.Fab")
			(effects
				(font
					(size 1.27 1.27)
				)
				(justify mirror)
			)
		)
		(duplicate_pad_numbers_are_jumpers no)
		(fp_rect
			(start -0.4953 -0.2032)
			(end 0.4953 1.6002)
			(stroke
				(width 0)
				(type default)
			)
			(fill no)
			(layer "B.CrtYd")
		)
		(fp_line
			(start 0.4953 -0.2032)
			(end -0.4953 -0.2032)
			(stroke
				(width 0.1)
				(type default)
			)
			(layer "B.Fab")
		)
		(fp_line
			(start -0.4953 -0.2032)
			(end -0.4953 1.6002)
			(stroke
				(width 0.1)
				(type default)
			)
			(layer "B.Fab")
		)
		(fp_line
			(start 0.4953 1.6002)
			(end 0.4953 -0.2032)
			(stroke
				(width 0.1)
				(type default)
			)
			(layer "B.Fab")
		)
		(fp_line
			(start -0.4953 1.6002)
			(end 0.4953 1.6002)
			(stroke
				(width 0.1)
				(type default)
			)
			(layer "B.Fab")
		)
		(pad "1" smd rect
			(at 0 0 270)
			(size 0.762 0.889)
			(layers "B.Cu" "B.Mask" "B.Paste")
			(net "PVDDQ_GHJ")
		)
		(pad "2" smd rect
			(at 0 1.397 270)
			(size 0.762 0.889)
			(layers "B.Cu" "B.Mask" "B.Paste")
			(net "GND")
		)
		(zone
			(layer "B.Cu")
			(hatch none 0.5)
			(connect_pads
				(clearance 0)
			)
			(min_thickness 0.25)
			(keepout
				(tracks not_allowed)
				(vias allowed)
				(pads allowed)
				(copperpour not_allowed)
				(footprints allowed)
			)
			(placement
				(enabled no)
				(sheetname "")
			)
			(fill
				(thermal_gap 0.5)
				(thermal_bridge_width 0.5)
				(island_removal_mode 0)
			)
			(polygon
				(pts
					(xy 105.0036 -12.573) (xy 105.5116 -12.573) (xy 105.5116 -13.335) (xy 105.0036 -13.335)
				)
			)
		)
	)
	(footprint ""
		(layer "B.Cu")
		(at 390.635744 -23.356316 -90)
		(property "Reference" "C2T24"
			(at 0 0 90)
			(layer "B.SilkS")
			(hide yes)
			(effects
				(font
					(size 1.27 1.27)
				)
				(justify mirror)
			)
		)
		(property "Value" ""
			(at 0 0 90)
			(layer "B.Fab")
			(effects
				(font
					(size 1.27 1.27)
				)
				(justify mirror)
			)
		)
		(duplicate_pad_numbers_are_jumpers no)
		(fp_poly
			(pts
				(xy -0.3048 -0.1016) (xy -0.3048 0.9906) (xy 0.3048 0.9906) (xy 0.3048 -0.1016)
			)
			(stroke
				(width 0)
				(type default)
			)
			(fill no)
			(layer "B.CrtYd")
		)
		(fp_line
			(start -0.3048 0.9906)
			(end -0.3048 -0.1016)
			(stroke
				(width 0.1)
				(type default)
			)
			(layer "B.Fab")
		)
		(fp_line
			(start 0.3048 0.9906)
			(end -0.3048 0.9906)
			(stroke
				(width 0.1)
				(type default)
			)
			(layer "B.Fab")
		)
		(fp_line
			(start -0.3048 -0.1016)
			(end 0.3048 -0.1016)
			(stroke
				(width 0.1)
				(type default)
			)
			(layer "B.Fab")
		)
		(fp_line
			(start 0.3048 -0.1016)
			(end 0.3048 0.9906)
			(stroke
				(width 0.1)
				(type default)
			)
			(layer "B.Fab")
		)
		(pad "1" smd rect
			(at 0 0 90)
			(size 0.508 0.508)
			(layers "B.Cu" "B.Mask" "B.Paste")
			(net "P3V3")
		)
		(pad "2" smd rect
			(at 0 0.889 90)
			(size 0.508 0.508)
			(layers "B.Cu" "B.Mask" "B.Paste")
			(net "GND")
		)
		(zone
			(layer "B.Cu")
			(hatch none 0.5)
			(connect_pads
				(clearance 0)
			)
			(min_thickness 0.25)
			(keepout
				(tracks not_allowed)
				(vias allowed)
				(pads allowed)
				(copperpour not_allowed)
				(footprints allowed)
			)
			(placement
				(enabled no)
				(sheetname "")
			)
			(fill
				(thermal_gap 0.5)
				(thermal_bridge_width 0.5)
				(island_removal_mode 0)
			)
			(polygon
				(pts
					(xy 390.000744 -23.102316) (xy 390.000744 -23.610316) (xy 390.381744 -23.610316) (xy 390.381744 -23.102316)
				)
			)
		)
		(zone
			(layer "B.Cu")
			(hatch none 0.5)
			(connect_pads
				(clearance 0)
			)
			(min_thickness 0.25)
			(keepout
				(tracks allowed)
				(vias not_allowed)
				(pads allowed)
				(copperpour not_allowed)
				(footprints allowed)
			)
			(placement
				(enabled no)
				(sheetname "")
			)
			(fill
				(thermal_gap 0.5)
				(thermal_bridge_width 0.5)
				(island_removal_mode 0)
			)
			(polygon
				(pts
					(xy 390.381744 -23.102316) (xy 390.381744 -23.610316) (xy 390.000744 -23.610316) (xy 390.000744 -23.102316)
				)
			)
		)
	)
	(footprint ""
		(layer "B.Cu")
		(at 450.215 -147.0406 -90)
		(property "Reference" "R25W166"
			(at 0.8382 -0.67818 270)
			(unlocked yes)
			(layer "B.SilkS")
			(effects
				(font
					(size 0.4064 0.254)
					(thickness 0.1524)
				)
				(justify left mirror)
			)
		)
		(property "Value" ""
			(at 0 0 90)
			(layer "B.Fab")
			(effects
				(font
					(size 1.27 1.27)
				)
				(justify mirror)
			)
		)
		(duplicate_pad_numbers_are_jumpers no)
		(fp_poly
			(pts
				(xy 0.2794 -0.1016) (xy -0.2794 -0.1016) (xy -0.2794 0.9906) (xy 0.2794 0.9906)
			)
			(stroke
				(width 0)
				(type default)
			)
			(fill no)
			(layer "B.CrtYd")
		)
		(fp_line
			(start -0.2794 0.9906)
			(end -0.2794 -0.1016)
			(stroke
				(width 0.1)
				(type default)
			)
			(layer "B.Fab")
		)
		(fp_line
			(start 0.2794 0.9906)
			(end -0.2794 0.9906)
			(stroke
				(width 0.1)
				(type default)
			)
			(layer "B.Fab")
		)
		(fp_line
			(start -0.2794 -0.1016)
			(end 0.2794 -0.1016)
			(stroke
				(width 0.1)
				(type default)
			)
			(layer "B.Fab")
		)
		(fp_line
			(start 0.2794 -0.1016)
			(end 0.2794 0.9906)
			(stroke
				(width 0.1)
				(type default)
			)
			(layer "B.Fab")
		)
		(pad "1" smd rect
			(at 0 0 90)
			(size 0.508 0.508)
			(layers "B.Cu" "B.Mask" "B.Paste")
			(net "PD_GTL2014_DIR_6")
		)
		(pad "2" smd rect
			(at 0 0.889 90)
			(size 0.508 0.508)
			(layers "B.Cu" "B.Mask" "B.Paste")
			(net "GND")
		)
		(zone
			(layer "B.Cu")
			(hatch none 0.5)
			(connect_pads
				(clearance 0)
			)
			(min_thickness 0.25)
			(keepout
				(tracks not_allowed)
				(vias allowed)
				(pads allowed)
				(copperpour not_allowed)
				(footprints allowed)
			)
			(placement
				(enabled no)
				(sheetname "")
			)
			(fill
				(thermal_gap 0.5)
				(thermal_bridge_width 0.5)
				(island_removal_mode 0)
			)
			(polygon
				(pts
					(xy 449.58 -146.7866) (xy 449.58 -147.2946) (xy 449.961 -147.2946) (xy 449.961 -146.7866)
				)
			)
		)
		(zone
			(layer "B.Cu")
			(hatch none 0.5)
			(connect_pads
				(clearance 0)
			)
			(min_thickness 0.25)
			(keepout
				(tracks allowed)
				(vias not_allowed)
				(pads allowed)
				(copperpour not_allowed)
				(footprints allowed)
			)
			(placement
				(enabled no)
				(sheetname "")
			)
			(fill
				(thermal_gap 0.5)
				(thermal_bridge_width 0.5)
				(island_removal_mode 0)
			)
			(polygon
				(pts
					(xy 449.961 -146.7866) (xy 449.961 -147.2946) (xy 449.58 -147.2946) (xy 449.58 -146.7866)
				)
			)
		)
	)
	(footprint ""
		(layer "B.Cu")
		(at 389.0518 -125.507242 90)
		(property "Reference" "R3M11"
			(at 0 0 90)
			(layer "B.SilkS")
			(hide yes)
			(effects
				(font
					(size 1.27 1.27)
				)
				(justify mirror)
			)
		)
		(property "Value" ""
			(at 0 0 90)
			(layer "B.Fab")
			(effects
				(font
					(size 1.27 1.27)
				)
				(justify mirror)
			)
		)
		(duplicate_pad_numbers_are_jumpers no)
		(fp_poly
			(pts
				(xy 0.2794 -0.1016) (xy -0.2794 -0.1016) (xy -0.2794 0.9906) (xy 0.2794 0.9906)
			)
			(stroke
				(width 0)
				(type default)
			)
			(fill no)
			(layer "B.CrtYd")
		)
		(fp_line
			(start 0.2794 -0.1016)
			(end 0.2794 0.9906)
			(stroke
				(width 0.1)
				(type default)
			)
			(layer "B.Fab")
		)
		(fp_line
			(start -0.2794 -0.1016)
			(end 0.2794 -0.1016)
			(stroke
				(width 0.1)
				(type default)
			)
			(layer "B.Fab")
		)
		(fp_line
			(start 0.2794 0.9906)
			(end -0.2794 0.9906)
			(stroke
				(width 0.1)
				(type default)
			)
			(layer "B.Fab")
		)
		(fp_line
			(start -0.2794 0.9906)
			(end -0.2794 -0.1016)
			(stroke
				(width 0.1)
				(type default)
			)
			(layer "B.Fab")
		)
		(pad "1" smd rect
			(at 0 0 270)
			(size 0.508 0.508)
			(layers "B.Cu" "B.Mask" "B.Paste")
			(net "A_PCIE_RCOMP_P")
		)
		(pad "2" smd rect
			(at 0 0.889 270)
			(size 0.508 0.508)
			(layers "B.Cu" "B.Mask" "B.Paste")
			(net "A_PCIE_RCOMP_N")
		)
		(zone
			(layer "B.Cu")
			(hatch none 0.5)
			(connect_pads
				(clearance 0)
			)
			(min_thickness 0.25)
			(keepout
				(tracks allowed)
				(vias not_allowed)
				(pads allowed)
				(copperpour not_allowed)
				(footprints allowed)
			)
			(placement
				(enabled no)
				(sheetname "")
			)
			(fill
				(thermal_gap 0.5)
				(thermal_bridge_width 0.5)
				(island_removal_mode 0)
			)
			(polygon
				(pts
					(xy 389.3058 -125.761242) (xy 389.3058 -125.253242) (xy 389.6868 -125.253242) (xy 389.6868 -125.761242)
				)
			)
		)
		(zone
			(layer "B.Cu")
			(hatch none 0.5)
			(connect_pads
				(clearance 0)
			)
			(min_thickness 0.25)
			(keepout
				(tracks not_allowed)
				(vias allowed)
				(pads allowed)
				(copperpour not_allowed)
				(footprints allowed)
			)
			(placement
				(enabled no)
				(sheetname "")
			)
			(fill
				(thermal_gap 0.5)
				(thermal_bridge_width 0.5)
				(island_removal_mode 0)
			)
			(polygon
				(pts
					(xy 389.6868 -125.761242) (xy 389.6868 -125.253242) (xy 389.3058 -125.253242) (xy 389.3058 -125.761242)
				)
			)
		)
	)
	(footprint ""
		(layer "B.Cu")
		(at 411.861 -23.0632 90)
		(property "Reference" "FB2T3"
			(at 0 0 90)
			(layer "B.SilkS")
			(hide yes)
			(effects
				(font
					(size 1.27 1.27)
				)
				(justify mirror)
			)
		)
		(property "Value" "*"
			(at -0.0254 -2.8829 90)
			(unlocked yes)
			(layer "B.Fab")
			(hide yes)
			(effects
				(font
					(size 1.27 1.016)
					(thickness 0.1524)
				)
				(justify mirror)
			)
		)
		(property "Device Type" "HCB1608KF-800T30-GP_DISCRET-G9A"
			(at -0.0254 -4.4069 90)
			(unlocked yes)
			(layer "B.Fab")
			(hide yes)
			(effects
				(font
					(size 1.27 1.016)
					(thickness 0.1524)
				)
				(justify mirror)
			)
		)
		(duplicate_pad_numbers_are_jumpers no)
		(fp_line
			(start -0.254 0)
			(end 0.254 0)
			(stroke
				(width 0.2032)
				(type default)
			)
			(layer "B.SilkS")
		)
		(fp_rect
			(start 0.5842 1.3335)
			(end -0.5842 -1.3335)
			(stroke
				(width 0)
				(type default)
			)
			(fill no)
			(layer "B.CrtYd")
		)
		(fp_rect
			(start 0.5842 1.3335)
			(end -0.5842 -1.3335)
			(stroke
				(width 0)
				(type default)
			)
			(fill no)
			(layer "B.Fab")
		)
		(pad "1" smd custom
			(at 0 -0.762 270)
			(size 0.2159 0.2159)
			(layers "B.Cu" "B.Mask" "B.Paste")
			(net "P3V3_STBY")
			(options
				(clearance outline)
				(anchor circle)
			)
			(primitives
				(gr_poly
					(pts
						(arc
							(start -0.3302 0.4318)
							(mid -0.402042 0.402042)
							(end -0.4318 0.3302)
						)
						(arc
							(start -0.4318 -0.3302)
							(mid -0.402042 -0.402042)
							(end -0.3302 -0.4318)
						)
						(arc
							(start 0.3302 -0.4318)
							(mid 0.402042 -0.402042)
							(end 0.4318 -0.3302)
						)
						(arc
							(start 0.4318 0.3302)
							(mid 0.402042 0.402042)
							(end 0.3302 0.4318)
						)
					)
					(width 0)
					(fill yes)
				)
			)
		)
		(pad "2" smd custom
			(at 0 0.762 270)
			(size 0.2159 0.2159)
			(layers "B.Cu" "B.Mask" "B.Paste")
			(net "VCC_ADCAV3V3")
			(options
				(clearance outline)
				(anchor circle)
			)
			(primitives
				(gr_poly
					(pts
						(arc
							(start -0.3302 0.4318)
							(mid -0.402042 0.402042)
							(end -0.4318 0.3302)
						)
						(arc
							(start -0.4318 -0.3302)
							(mid -0.402042 -0.402042)
							(end -0.3302 -0.4318)
						)
						(arc
							(start 0.3302 -0.4318)
							(mid 0.402042 -0.402042)
							(end 0.4318 -0.3302)
						)
						(arc
							(start 0.4318 0.3302)
							(mid 0.402042 0.402042)
							(end 0.3302 0.4318)
						)
					)
					(width 0)
					(fill yes)
				)
			)
		)
	)
	(footprint ""
		(layer "B.Cu")
		(at 184.421272 -9.119108 90)
		(property "Reference" "C22W6"
			(at 0 0 90)
			(layer "B.SilkS")
			(hide yes)
			(effects
				(font
					(size 1.27 1.27)
				)
				(justify mirror)
			)
		)
		(property "Value" "*"
			(at 0.0762 -6.2357 90)
			(unlocked yes)
			(layer "B.Fab")
			(hide yes)
			(effects
				(font
					(size 1.27 1.016)
					(thickness 0.1524)
				)
				(justify mirror)
			)
		)
		(property "Device Type" "SC22U16V5MX-4-GP_SMD-BCG5-SC22A"
			(at 0.0762 -8.2677 90)
			(unlocked yes)
			(layer "B.Fab")
			(hide yes)
			(effects
				(font
					(size 1.27 1.016)
					(thickness 0.1524)
				)
				(justify mirror)
			)
		)
		(duplicate_pad_numbers_are_jumpers no)
		(fp_line
			(start -0.635 0)
			(end 0.635 0)
			(stroke
				(width 0.508)
				(type default)
			)
			(layer "B.SilkS")
		)
		(fp_rect
			(start 0.9652 1.778)
			(end -0.9652 -1.778)
			(stroke
				(width 0)
				(type default)
			)
			(fill no)
			(layer "B.CrtYd")
		)
		(fp_poly
			(pts
				(xy 0.9652 -1.778) (xy -0.9652 -1.778) (xy -0.9652 1.778) (xy 0.9652 1.778)
			)
			(stroke
				(width 0)
				(type default)
			)
			(fill no)
			(layer "B.Fab")
		)
		(pad "1" smd rect
			(at 0 -0.9652 270)
			(size 1.397 1.143)
			(layers "B.Cu" "B.Mask" "B.Paste")
			(net "VR_FET_SW_P12V_STBY_PVPP_GHJ")
		)
		(pad "2" smd rect
			(at 0 0.9652 270)
			(size 1.397 1.143)
			(layers "B.Cu" "B.Mask" "B.Paste")
			(net "GND")
		)
	)
	(footprint ""
		(layer "B.Cu")
		(at 342.642952 -89.300558 180)
		(property "Reference" "C3N39"
			(at 0 0 0)
			(layer "B.SilkS")
			(hide yes)
			(effects
				(font
					(size 1.27 1.27)
				)
				(justify mirror)
			)
		)
		(property "Value" ""
			(at 0 0 0)
			(layer "B.Fab")
			(effects
				(font
					(size 1.27 1.27)
				)
				(justify mirror)
			)
		)
		(duplicate_pad_numbers_are_jumpers no)
		(fp_poly
			(pts
				(xy -0.3048 -0.1016) (xy -0.3048 0.9906) (xy 0.3048 0.9906) (xy 0.3048 -0.1016)
			)
			(stroke
				(width 0)
				(type default)
			)
			(fill no)
			(layer "B.CrtYd")
		)
		(fp_line
			(start 0.3048 0.9906)
			(end -0.3048 0.9906)
			(stroke
				(width 0.1)
				(type default)
			)
			(layer "B.Fab")
		)
		(fp_line
			(start 0.3048 -0.1016)
			(end 0.3048 0.9906)
			(stroke
				(width 0.1)
				(type default)
			)
			(layer "B.Fab")
		)
		(fp_line
			(start -0.3048 0.9906)
			(end -0.3048 -0.1016)
			(stroke
				(width 0.1)
				(type default)
			)
			(layer "B.Fab")
		)
		(fp_line
			(start -0.3048 -0.1016)
			(end 0.3048 -0.1016)
			(stroke
				(width 0.1)
				(type default)
			)
			(layer "B.Fab")
		)
		(pad "1" smd rect
			(at 0 0)
			(size 0.508 0.508)
			(layers "B.Cu" "B.Mask" "B.Paste")
			(net "VR_PVCCIO_CPU0_AVSP")
		)
		(pad "2" smd rect
			(at 0 0.889)
			(size 0.508 0.508)
			(layers "B.Cu" "B.Mask" "B.Paste")
			(net "VSENSE_PVCCIO_CPU0_AVSN")
		)
		(zone
			(layer "B.Cu")
			(hatch none 0.5)
			(connect_pads
				(clearance 0)
			)
			(min_thickness 0.25)
			(keepout
				(tracks not_allowed)
				(vias allowed)
				(pads allowed)
				(copperpour not_allowed)
				(footprints allowed)
			)
			(placement
				(enabled no)
				(sheetname "")
			)
			(fill
				(thermal_gap 0.5)
				(thermal_bridge_width 0.5)
				(island_removal_mode 0)
			)
			(polygon
				(pts
					(xy 342.388952 -89.935558) (xy 342.896952 -89.935558) (xy 342.896952 -89.554558) (xy 342.388952 -89.554558)
				)
			)
		)
		(zone
			(layer "B.Cu")
			(hatch none 0.5)
			(connect_pads
				(clearance 0)
			)
			(min_thickness 0.25)
			(keepout
				(tracks allowed)
				(vias not_allowed)
				(pads allowed)
				(copperpour not_allowed)
				(footprints allowed)
			)
			(placement
				(enabled no)
				(sheetname "")
			)
			(fill
				(thermal_gap 0.5)
				(thermal_bridge_width 0.5)
				(island_removal_mode 0)
			)
			(polygon
				(pts
					(xy 342.388952 -89.554558) (xy 342.896952 -89.554558) (xy 342.896952 -89.935558) (xy 342.388952 -89.935558)
				)
			)
		)
	)
	(footprint ""
		(layer "B.Cu")
		(at 391.73785 -111.05515 180)
		(property "Reference" "C2N2"
			(at 0 0 0)
			(layer "B.SilkS")
			(hide yes)
			(effects
				(font
					(size 1.27 1.27)
				)
				(justify mirror)
			)
		)
		(property "Value" ""
			(at 0 0 0)
			(layer "B.Fab")
			(effects
				(font
					(size 1.27 1.27)
				)
				(justify mirror)
			)
		)
		(duplicate_pad_numbers_are_jumpers no)
		(fp_rect
			(start 0.2794 0.9144)
			(end -0.2794 -0.1143)
			(stroke
				(width 0)
				(type default)
			)
			(fill no)
			(layer "B.CrtYd")
		)
		(fp_line
			(start 0.2794 0.9144)
			(end 0.2794 -0.1143)
			(stroke
				(width 0.1)
				(type default)
			)
			(layer "B.Fab")
		)
		(fp_line
			(start 0.2794 -0.1143)
			(end -0.2794 -0.1143)
			(stroke
				(width 0.1)
				(type default)
			)
			(layer "B.Fab")
		)
		(fp_line
			(start -0.2794 0.9144)
			(end 0.2794 0.9144)
			(stroke
				(width 0.1)
				(type default)
			)
			(layer "B.Fab")
		)
		(fp_line
			(start -0.2794 -0.1143)
			(end -0.2794 0.9144)
			(stroke
				(width 0.1)
				(type default)
			)
			(layer "B.Fab")
		)
		(pad "1" smd custom
			(at 0 0 90)
			(size 0.10414 0.10414)
			(layers "B.Cu" "B.Mask" "B.Paste")
			(net "P1V05_PCH_STBY")
			(options
				(clearance outline)
				(anchor circle)
			)
			(primitives
				(gr_poly
					(pts
						(xy -0.20828 -0.08636) (xy -0.20828 0.08636) (xy -0.08636 0.20828) (xy 0.086614 0.20828) (xy 0.20828 0.086614)
						(xy 0.20828 -0.08636) (xy 0.08636 -0.20828) (xy -0.08636 -0.20828)
					)
					(width 0)
					(fill yes)
				)
			)
		)
		(pad "2" smd custom
			(at 0 0.8001 90)
			(size 0.10414 0.10414)
			(layers "B.Cu" "B.Mask" "B.Paste")
			(net "GND")
			(options
				(clearance outline)
				(anchor circle)
			)
			(primitives
				(gr_poly
					(pts
						(xy -0.20828 -0.08636) (xy -0.20828 0.08636) (xy -0.08636 0.20828) (xy 0.086614 0.20828) (xy 0.20828 0.086614)
						(xy 0.20828 -0.08636) (xy 0.08636 -0.20828) (xy -0.08636 -0.20828)
					)
					(width 0)
					(fill yes)
				)
			)
		)
		(zone
			(layer "B.Cu")
			(hatch none 0.5)
			(connect_pads
				(clearance 0)
			)
			(min_thickness 0.25)
			(keepout
				(tracks not_allowed)
				(vias allowed)
				(pads allowed)
				(copperpour not_allowed)
				(footprints allowed)
			)
			(placement
				(enabled no)
				(sheetname "")
			)
			(fill
				(thermal_gap 0.5)
				(thermal_bridge_width 0.5)
				(island_removal_mode 0)
			)
			(polygon
				(pts
					(xy 391.65022 -111.2647) (xy 391.65022 -111.6457) (xy 391.82548 -111.6457) (xy 391.825734 -111.2647)
				)
			)
		)
		(zone
			(layer "B.Cu")
			(hatch none 0.5)
			(connect_pads
				(clearance 0)
			)
			(min_thickness 0.25)
			(keepout
				(tracks allowed)
				(vias not_allowed)
				(pads allowed)
				(copperpour not_allowed)
				(footprints allowed)
			)
			(placement
				(enabled no)
				(sheetname "")
			)
			(fill
				(thermal_gap 0.5)
				(thermal_bridge_width 0.5)
				(island_removal_mode 0)
			)
			(polygon
				(pts
					(xy 391.65022 -111.2647) (xy 391.65022 -111.6457) (xy 391.82548 -111.6457) (xy 391.825734 -111.2647)
				)
			)
		)
	)
	(footprint ""
		(layer "B.Cu")
		(at 370.334794 -68.048632)
		(property "Reference" "R1W28"
			(at 0.8382 -0.67818 0)
			(unlocked yes)
			(layer "B.SilkS")
			(effects
				(font
					(size 0.4064 0.254)
					(thickness 0.1524)
				)
				(justify left mirror)
			)
		)
		(property "Value" ""
			(at 0 0 0)
			(layer "B.Fab")
			(effects
				(font
					(size 1.27 1.27)
				)
				(justify mirror)
			)
		)
		(duplicate_pad_numbers_are_jumpers no)
		(fp_poly
			(pts
				(xy 0.2794 -0.1016) (xy -0.2794 -0.1016) (xy -0.2794 0.9906) (xy 0.2794 0.9906)
			)
			(stroke
				(width 0)
				(type default)
			)
			(fill no)
			(layer "B.CrtYd")
		)
		(fp_line
			(start -0.2794 -0.1016)
			(end 0.2794 -0.1016)
			(stroke
				(width 0.1)
				(type default)
			)
			(layer "B.Fab")
		)
		(fp_line
			(start -0.2794 0.9906)
			(end -0.2794 -0.1016)
			(stroke
				(width 0.1)
				(type default)
			)
			(layer "B.Fab")
		)
		(fp_line
			(start 0.2794 -0.1016)
			(end 0.2794 0.9906)
			(stroke
				(width 0.1)
				(type default)
			)
			(layer "B.Fab")
		)
		(fp_line
			(start 0.2794 0.9906)
			(end -0.2794 0.9906)
			(stroke
				(width 0.1)
				(type default)
			)
			(layer "B.Fab")
		)
		(pad "1" smd rect
			(at 0 0 180)
			(size 0.508 0.508)
			(layers "B.Cu" "B.Mask" "B.Paste")
			(net "FM_PCH_PWRBTN_R1_N")
		)
		(pad "2" smd rect
			(at 0 0.889 180)
			(size 0.508 0.508)
			(layers "B.Cu" "B.Mask" "B.Paste")
			(net "FM_PCH_PWRBTN_N")
		)
		(zone
			(layer "B.Cu")
			(hatch none 0.5)
			(connect_pads
				(clearance 0)
			)
			(min_thickness 0.25)
			(keepout
				(tracks allowed)
				(vias not_allowed)
				(pads allowed)
				(copperpour not_allowed)
				(footprints allowed)
			)
			(placement
				(enabled no)
				(sheetname "")
			)
			(fill
				(thermal_gap 0.5)
				(thermal_bridge_width 0.5)
				(island_removal_mode 0)
			)
			(polygon
				(pts
					(xy 370.588794 -67.794632) (xy 370.080794 -67.794632) (xy 370.080794 -67.413632) (xy 370.588794 -67.413632)
				)
			)
		)
		(zone
			(layer "B.Cu")
			(hatch none 0.5)
			(connect_pads
				(clearance 0)
			)
			(min_thickness 0.25)
			(keepout
				(tracks not_allowed)
				(vias allowed)
				(pads allowed)
				(copperpour not_allowed)
				(footprints allowed)
			)
			(placement
				(enabled no)
				(sheetname "")
			)
			(fill
				(thermal_gap 0.5)
				(thermal_bridge_width 0.5)
				(island_removal_mode 0)
			)
			(polygon
				(pts
					(xy 370.588794 -67.413632) (xy 370.080794 -67.413632) (xy 370.080794 -67.794632) (xy 370.588794 -67.794632)
				)
			)
		)
	)
	(footprint ""
		(layer "B.Cu")
		(at 280.354024 -71.841614 180)
		(property "Reference" "C4P8"
			(at 0 0 0)
			(layer "B.SilkS")
			(hide yes)
			(effects
				(font
					(size 1.27 1.27)
				)
				(justify mirror)
			)
		)
		(property "Value" ""
			(at 0 0 0)
			(layer "B.Fab")
			(effects
				(font
					(size 1.27 1.27)
				)
				(justify mirror)
			)
		)
		(duplicate_pad_numbers_are_jumpers no)
		(fp_poly
			(pts
				(xy 0.4953 -0.2032) (xy -0.4953 -0.2032) (xy -0.4953 1.6002) (xy 0.4953 1.6002)
			)
			(stroke
				(width 0)
				(type default)
			)
			(fill no)
			(layer "B.CrtYd")
		)
		(fp_line
			(start 0.4953 1.6002)
			(end 0.4953 -0.2032)
			(stroke
				(width 0.1)
				(type default)
			)
			(layer "B.Fab")
		)
		(fp_line
			(start 0.4953 -0.2032)
			(end -0.4953 -0.2032)
			(stroke
				(width 0.1)
				(type default)
			)
			(layer "B.Fab")
		)
		(fp_line
			(start -0.4953 1.6002)
			(end 0.4953 1.6002)
			(stroke
				(width 0.1)
				(type default)
			)
			(layer "B.Fab")
		)
		(fp_line
			(start -0.4953 -0.2032)
			(end -0.4953 1.6002)
			(stroke
				(width 0.1)
				(type default)
			)
			(layer "B.Fab")
		)
		(pad "1" smd rect
			(at 0 0)
			(size 0.762 0.889)
			(layers "B.Cu" "B.Mask" "B.Paste")
			(net "PVCCIO_CPU0")
		)
		(pad "2" smd rect
			(at 0 1.397)
			(size 0.762 0.889)
			(layers "B.Cu" "B.Mask" "B.Paste")
			(net "GND")
		)
		(zone
			(layer "B.Cu")
			(hatch none 0.5)
			(connect_pads
				(clearance 0)
			)
			(min_thickness 0.25)
			(keepout
				(tracks not_allowed)
				(vias allowed)
				(pads allowed)
				(copperpour not_allowed)
				(footprints allowed)
			)
			(placement
				(enabled no)
				(sheetname "")
			)
			(fill
				(thermal_gap 0.5)
				(thermal_bridge_width 0.5)
				(island_removal_mode 0)
			)
			(polygon
				(pts
					(xy 279.973024 -72.286114) (xy 280.735024 -72.286114) (xy 280.735024 -72.794114) (xy 279.973024 -72.794114)
				)
			)
		)
	)
	(footprint ""
		(layer "B.Cu")
		(at 457.6064 -144.145 90)
		(property "Reference" "C1L11"
			(at 0 0 90)
			(layer "B.SilkS")
			(hide yes)
			(effects
				(font
					(size 1.27 1.27)
				)
				(justify mirror)
			)
		)
		(property "Value" ""
			(at 0 0 90)
			(layer "B.Fab")
			(effects
				(font
					(size 1.27 1.27)
				)
				(justify mirror)
			)
		)
		(duplicate_pad_numbers_are_jumpers no)
		(fp_poly
			(pts
				(xy -0.3048 -0.1016) (xy -0.3048 0.9906) (xy 0.3048 0.9906) (xy 0.3048 -0.1016)
			)
			(stroke
				(width 0)
				(type default)
			)
			(fill no)
			(layer "B.CrtYd")
		)
		(fp_line
			(start 0.3048 -0.1016)
			(end 0.3048 0.9906)
			(stroke
				(width 0.1)
				(type default)
			)
			(layer "B.Fab")
		)
		(fp_line
			(start -0.3048 -0.1016)
			(end 0.3048 -0.1016)
			(stroke
				(width 0.1)
				(type default)
			)
			(layer "B.Fab")
		)
		(fp_line
			(start 0.3048 0.9906)
			(end -0.3048 0.9906)
			(stroke
				(width 0.1)
				(type default)
			)
			(layer "B.Fab")
		)
		(fp_line
			(start -0.3048 0.9906)
			(end -0.3048 -0.1016)
			(stroke
				(width 0.1)
				(type default)
			)
			(layer "B.Fab")
		)
		(pad "1" smd rect
			(at 0 0 270)
			(size 0.508 0.508)
			(layers "B.Cu" "B.Mask" "B.Paste")
			(net "P3V3_STBY")
		)
		(pad "2" smd rect
			(at 0 0.889 270)
			(size 0.508 0.508)
			(layers "B.Cu" "B.Mask" "B.Paste")
			(net "GND")
		)
		(zone
			(layer "B.Cu")
			(hatch none 0.5)
			(connect_pads
				(clearance 0)
			)
			(min_thickness 0.25)
			(keepout
				(tracks allowed)
				(vias not_allowed)
				(pads allowed)
				(copperpour not_allowed)
				(footprints allowed)
			)
			(placement
				(enabled no)
				(sheetname "")
			)
			(fill
				(thermal_gap 0.5)
				(thermal_bridge_width 0.5)
				(island_removal_mode 0)
			)
			(polygon
				(pts
					(xy 457.8604 -144.399) (xy 457.8604 -143.891) (xy 458.2414 -143.891) (xy 458.2414 -144.399)
				)
			)
		)
		(zone
			(layer "B.Cu")
			(hatch none 0.5)
			(connect_pads
				(clearance 0)
			)
			(min_thickness 0.25)
			(keepout
				(tracks not_allowed)
				(vias allowed)
				(pads allowed)
				(copperpour not_allowed)
				(footprints allowed)
			)
			(placement
				(enabled no)
				(sheetname "")
			)
			(fill
				(thermal_gap 0.5)
				(thermal_bridge_width 0.5)
				(island_removal_mode 0)
			)
			(polygon
				(pts
					(xy 458.2414 -144.399) (xy 458.2414 -143.891) (xy 457.8604 -143.891) (xy 457.8604 -144.399)
				)
			)
		)
	)
	(footprint ""
		(layer "B.Cu")
		(at 101.244654 -79.60614 180)
		(property "Reference" "C8P11"
			(at 0 0 0)
			(layer "B.SilkS")
			(hide yes)
			(effects
				(font
					(size 1.27 1.27)
				)
				(justify mirror)
			)
		)
		(property "Value" ""
			(at 0 0 0)
			(layer "B.Fab")
			(effects
				(font
					(size 1.27 1.27)
				)
				(justify mirror)
			)
		)
		(duplicate_pad_numbers_are_jumpers no)
		(fp_poly
			(pts
				(xy 0.7239 -0.2159) (xy -0.7239 -0.2159) (xy -0.7239 1.9939) (xy 0.7239 1.9939)
			)
			(stroke
				(width 0)
				(type default)
			)
			(fill no)
			(layer "B.CrtYd")
		)
		(fp_line
			(start 0.7239 1.9939)
			(end -0.7239 1.9939)
			(stroke
				(width 0.1)
				(type default)
			)
			(layer "B.Fab")
		)
		(fp_line
			(start 0.7239 -0.2159)
			(end 0.7239 1.9939)
			(stroke
				(width 0.1)
				(type default)
			)
			(layer "B.Fab")
		)
		(fp_line
			(start -0.7239 1.9939)
			(end -0.7239 -0.2159)
			(stroke
				(width 0.1)
				(type default)
			)
			(layer "B.Fab")
		)
		(fp_line
			(start -0.7239 -0.2159)
			(end 0.7239 -0.2159)
			(stroke
				(width 0.1)
				(type default)
			)
			(layer "B.Fab")
		)
		(pad "1" smd rect
			(at 0 0)
			(size 1.27 1.016)
			(layers "B.Cu" "B.Mask" "B.Paste")
			(net "PVCCIN_CPU1")
		)
		(pad "2" smd rect
			(at 0 1.778)
			(size 1.27 1.016)
			(layers "B.Cu" "B.Mask" "B.Paste")
			(net "GND")
		)
		(zone
			(layer "B.Cu")
			(hatch none 0.5)
			(connect_pads
				(clearance 0)
			)
			(min_thickness 0.25)
			(keepout
				(tracks not_allowed)
				(vias allowed)
				(pads allowed)
				(copperpour not_allowed)
				(footprints allowed)
			)
			(placement
				(enabled no)
				(sheetname "")
			)
			(fill
				(thermal_gap 0.5)
				(thermal_bridge_width 0.5)
				(island_removal_mode 0)
			)
			(polygon
				(pts
					(xy 100.609654 -80.11414) (xy 101.879654 -80.11414) (xy 101.879654 -80.87614) (xy 100.609654 -80.87614)
				)
			)
		)
	)
	(footprint ""
		(layer "B.Cu")
		(at 197.239128 -54.531006 90)
		(property "Reference" "R6R2"
			(at 0 0 90)
			(layer "B.SilkS")
			(hide yes)
			(effects
				(font
					(size 1.27 1.27)
				)
				(justify mirror)
			)
		)
		(property "Value" ""
			(at 0 0 90)
			(layer "B.Fab")
			(effects
				(font
					(size 1.27 1.27)
				)
				(justify mirror)
			)
		)
		(duplicate_pad_numbers_are_jumpers no)
		(fp_rect
			(start 0.2794 -0.1016)
			(end -0.2794 0.9906)
			(stroke
				(width 0)
				(type default)
			)
			(fill no)
			(layer "B.CrtYd")
		)
		(fp_line
			(start 0.2794 -0.1016)
			(end 0.2794 0.9906)
			(stroke
				(width 0.1)
				(type default)
			)
			(layer "B.Fab")
		)
		(fp_line
			(start -0.2794 -0.1016)
			(end 0.2794 -0.1016)
			(stroke
				(width 0.1)
				(type default)
			)
			(layer "B.Fab")
		)
		(fp_line
			(start 0.2794 0.9906)
			(end -0.2794 0.9906)
			(stroke
				(width 0.1)
				(type default)
			)
			(layer "B.Fab")
		)
		(fp_line
			(start -0.2794 0.9906)
			(end -0.2794 -0.1016)
			(stroke
				(width 0.1)
				(type default)
			)
			(layer "B.Fab")
		)
		(pad "1" smd rect
			(at 0 0 270)
			(size 0.508 0.508)
			(layers "B.Cu" "B.Mask" "B.Paste")
			(net "VR_PVCCIN_CPU0_PH1_VCIN")
		)
		(pad "2" smd rect
			(at 0 0.889 270)
			(size 0.508 0.508)
			(layers "B.Cu" "B.Mask" "B.Paste")
			(net "P5V_STBY")
		)
		(zone
			(layer "B.Cu")
			(hatch none 0.5)
			(connect_pads
				(clearance 0)
			)
			(min_thickness 0.25)
			(keepout
				(tracks allowed)
				(vias not_allowed)
				(pads allowed)
				(copperpour not_allowed)
				(footprints allowed)
			)
			(placement
				(enabled no)
				(sheetname "")
			)
			(fill
				(thermal_gap 0.5)
				(thermal_bridge_width 0.5)
				(island_removal_mode 0)
			)
			(polygon
				(pts
					(xy 197.493128 -54.785006) (xy 197.493128 -54.277006) (xy 197.874128 -54.277006) (xy 197.874128 -54.785006)
				)
			)
		)
		(zone
			(layer "B.Cu")
			(hatch none 0.5)
			(connect_pads
				(clearance 0)
			)
			(min_thickness 0.25)
			(keepout
				(tracks not_allowed)
				(vias allowed)
				(pads allowed)
				(copperpour not_allowed)
				(footprints allowed)
			)
			(placement
				(enabled no)
				(sheetname "")
			)
			(fill
				(thermal_gap 0.5)
				(thermal_bridge_width 0.5)
				(island_removal_mode 0)
			)
			(polygon
				(pts
					(xy 197.493128 -54.785006) (xy 197.493128 -54.277006) (xy 197.874128 -54.277006) (xy 197.874128 -54.785006)
				)
			)
		)
	)
	(footprint ""
		(layer "B.Cu")
		(at 166.751 4.445 180)
		(property "Reference" "R6U17"
			(at 0 0 0)
			(layer "B.SilkS")
			(hide yes)
			(effects
				(font
					(size 1.27 1.27)
				)
				(justify mirror)
			)
		)
		(property "Value" ""
			(at 0 0 0)
			(layer "B.Fab")
			(effects
				(font
					(size 1.27 1.27)
				)
				(justify mirror)
			)
		)
		(duplicate_pad_numbers_are_jumpers no)
		(fp_poly
			(pts
				(xy 0.2794 -0.1016) (xy -0.2794 -0.1016) (xy -0.2794 0.9906) (xy 0.2794 0.9906)
			)
			(stroke
				(width 0)
				(type default)
			)
			(fill no)
			(layer "B.CrtYd")
		)
		(fp_line
			(start 0.2794 0.9906)
			(end -0.2794 0.9906)
			(stroke
				(width 0.1)
				(type default)
			)
			(layer "B.Fab")
		)
		(fp_line
			(start 0.2794 -0.1016)
			(end 0.2794 0.9906)
			(stroke
				(width 0.1)
				(type default)
			)
			(layer "B.Fab")
		)
		(fp_line
			(start -0.2794 0.9906)
			(end -0.2794 -0.1016)
			(stroke
				(width 0.1)
				(type default)
			)
			(layer "B.Fab")
		)
		(fp_line
			(start -0.2794 -0.1016)
			(end 0.2794 -0.1016)
			(stroke
				(width 0.1)
				(type default)
			)
			(layer "B.Fab")
		)
		(pad "1" smd rect
			(at 0 0)
			(size 0.508 0.508)
			(layers "B.Cu" "B.Mask" "B.Paste")
			(net "PVPP_GHJ")
		)
		(pad "2" smd rect
			(at 0 0.889)
			(size 0.508 0.508)
			(layers "B.Cu" "B.Mask" "B.Paste")
			(net "SMB_DDR_GHJ_VPP_SCL_R")
		)
		(zone
			(layer "B.Cu")
			(hatch none 0.5)
			(connect_pads
				(clearance 0)
			)
			(min_thickness 0.25)
			(keepout
				(tracks not_allowed)
				(vias allowed)
				(pads allowed)
				(copperpour not_allowed)
				(footprints allowed)
			)
			(placement
				(enabled no)
				(sheetname "")
			)
			(fill
				(thermal_gap 0.5)
				(thermal_bridge_width 0.5)
				(island_removal_mode 0)
			)
			(polygon
				(pts
					(xy 166.497 3.81) (xy 167.005 3.81) (xy 167.005 4.191) (xy 166.497 4.191)
				)
			)
		)
		(zone
			(layer "B.Cu")
			(hatch none 0.5)
			(connect_pads
				(clearance 0)
			)
			(min_thickness 0.25)
			(keepout
				(tracks allowed)
				(vias not_allowed)
				(pads allowed)
				(copperpour not_allowed)
				(footprints allowed)
			)
			(placement
				(enabled no)
				(sheetname "")
			)
			(fill
				(thermal_gap 0.5)
				(thermal_bridge_width 0.5)
				(island_removal_mode 0)
			)
			(polygon
				(pts
					(xy 166.497 4.191) (xy 167.005 4.191) (xy 167.005 3.81) (xy 166.497 3.81)
				)
			)
		)
	)
	(footprint ""
		(layer "B.Cu")
		(at 355.3333 -146.82724)
		(property "Reference" "C7W9"
			(at 0 0 0)
			(layer "B.SilkS")
			(hide yes)
			(effects
				(font
					(size 1.27 1.27)
				)
				(justify mirror)
			)
		)
		(property "Value" "*"
			(at 0.0762 -6.2357 0)
			(unlocked yes)
			(layer "B.Fab")
			(hide yes)
			(effects
				(font
					(size 1.27 1.016)
					(thickness 0.1524)
				)
				(justify mirror)
			)
		)
		(property "Device Type" "SC22U16V5MX-4-GP_SMD-BCG5-SC22A"
			(at 0.0762 -8.2677 0)
			(unlocked yes)
			(layer "B.Fab")
			(hide yes)
			(effects
				(font
					(size 1.27 1.016)
					(thickness 0.1524)
				)
				(justify mirror)
			)
		)
		(duplicate_pad_numbers_are_jumpers no)
		(fp_line
			(start -0.635 0)
			(end 0.635 0)
			(stroke
				(width 0.508)
				(type default)
			)
			(layer "B.SilkS")
		)
		(fp_rect
			(start 0.9652 1.778)
			(end -0.9652 -1.778)
			(stroke
				(width 0)
				(type default)
			)
			(fill no)
			(layer "B.CrtYd")
		)
		(fp_poly
			(pts
				(xy 0.9652 -1.778) (xy -0.9652 -1.778) (xy -0.9652 1.778) (xy 0.9652 1.778)
			)
			(stroke
				(width 0)
				(type default)
			)
			(fill no)
			(layer "B.Fab")
		)
		(pad "1" smd rect
			(at 0 -0.9652 180)
			(size 1.397 1.143)
			(layers "B.Cu" "B.Mask" "B.Paste")
			(net "VR_FET_SW_P12V_STBY_PVDDQ_DEF")
		)
		(pad "2" smd rect
			(at 0 0.9652 180)
			(size 1.397 1.143)
			(layers "B.Cu" "B.Mask" "B.Paste")
			(net "GND")
		)
	)
	(footprint ""
		(layer "B.Cu")
		(at 402.209 -33.655)
		(property "Reference" "C25W36"
			(at -0.97536 0.76708 90)
			(unlocked yes)
			(layer "B.SilkS")
			(effects
				(font
					(size 0.4064 0.254)
					(thickness 0.1524)
				)
				(justify mirror)
			)
		)
		(property "Value" ""
			(at 0 0 0)
			(layer "B.Fab")
			(effects
				(font
					(size 1.27 1.27)
				)
				(justify mirror)
			)
		)
		(duplicate_pad_numbers_are_jumpers no)
		(fp_poly
			(pts
				(xy 0.4953 -0.2032) (xy -0.4953 -0.2032) (xy -0.4953 1.6002) (xy 0.4953 1.6002)
			)
			(stroke
				(width 0)
				(type default)
			)
			(fill no)
			(layer "B.CrtYd")
		)
		(fp_line
			(start -0.4953 -0.2032)
			(end -0.4953 1.6002)
			(stroke
				(width 0.1)
				(type default)
			)
			(layer "B.Fab")
		)
		(fp_line
			(start -0.4953 1.6002)
			(end 0.4953 1.6002)
			(stroke
				(width 0.1)
				(type default)
			)
			(layer "B.Fab")
		)
		(fp_line
			(start 0.4953 -0.2032)
			(end -0.4953 -0.2032)
			(stroke
				(width 0.1)
				(type default)
			)
			(layer "B.Fab")
		)
		(fp_line
			(start 0.4953 1.6002)
			(end 0.4953 -0.2032)
			(stroke
				(width 0.1)
				(type default)
			)
			(layer "B.Fab")
		)
		(pad "1" smd rect
			(at 0 0 180)
			(size 0.762 0.889)
			(layers "B.Cu" "B.Mask" "B.Paste")
			(net "VCC_DACAV3V3")
		)
		(pad "2" smd rect
			(at 0 1.397 180)
			(size 0.762 0.889)
			(layers "B.Cu" "B.Mask" "B.Paste")
			(net "GND")
		)
		(zone
			(layer "B.Cu")
			(hatch none 0.5)
			(connect_pads
				(clearance 0)
			)
			(min_thickness 0.25)
			(keepout
				(tracks not_allowed)
				(vias allowed)
				(pads allowed)
				(copperpour not_allowed)
				(footprints allowed)
			)
			(placement
				(enabled no)
				(sheetname "")
			)
			(fill
				(thermal_gap 0.5)
				(thermal_bridge_width 0.5)
				(island_removal_mode 0)
			)
			(polygon
				(pts
					(xy 402.59 -33.2105) (xy 401.828 -33.2105) (xy 401.828 -32.7025) (xy 402.59 -32.7025)
				)
			)
		)
	)
	(footprint ""
		(layer "B.Cu")
		(at 346.456 -104.267 180)
		(property "Reference" "C22W29"
			(at 0 0 0)
			(layer "B.SilkS")
			(hide yes)
			(effects
				(font
					(size 1.27 1.27)
				)
				(justify mirror)
			)
		)
		(property "Value" "*"
			(at 0.0762 -6.2357 180)
			(unlocked yes)
			(layer "B.Fab")
			(hide yes)
			(effects
				(font
					(size 1.27 1.016)
					(thickness 0.1524)
				)
				(justify mirror)
			)
		)
		(property "Device Type" "SC22U16V5MX-4-GP_SMD-BCG5-SC22A"
			(at 0.0762 -8.2677 180)
			(unlocked yes)
			(layer "B.Fab")
			(hide yes)
			(effects
				(font
					(size 1.27 1.016)
					(thickness 0.1524)
				)
				(justify mirror)
			)
		)
		(duplicate_pad_numbers_are_jumpers no)
		(fp_line
			(start -0.635 0)
			(end 0.635 0)
			(stroke
				(width 0.508)
				(type default)
			)
			(layer "B.SilkS")
		)
		(fp_rect
			(start 0.9652 1.778)
			(end -0.9652 -1.778)
			(stroke
				(width 0)
				(type default)
			)
			(fill no)
			(layer "B.CrtYd")
		)
		(fp_poly
			(pts
				(xy 0.9652 -1.778) (xy -0.9652 -1.778) (xy -0.9652 1.778) (xy 0.9652 1.778)
			)
			(stroke
				(width 0)
				(type default)
			)
			(fill no)
			(layer "B.Fab")
		)
		(pad "1" smd rect
			(at 0 -0.9652)
			(size 1.397 1.143)
			(layers "B.Cu" "B.Mask" "B.Paste")
			(net "VR_FET_SW_P12V_STBY_PVCCIO_CPU0")
		)
		(pad "2" smd rect
			(at 0 0.9652)
			(size 1.397 1.143)
			(layers "B.Cu" "B.Mask" "B.Paste")
			(net "GND")
		)
	)
	(footprint ""
		(layer "B.Cu")
		(at 399.4404 -74.168 90)
		(property "Reference" "C6W2"
			(at 0.8382 -0.67818 90)
			(unlocked yes)
			(layer "B.SilkS")
			(effects
				(font
					(size 0.4064 0.254)
					(thickness 0.1524)
				)
				(justify left mirror)
			)
		)
		(property "Value" ""
			(at 0 0 90)
			(layer "B.Fab")
			(effects
				(font
					(size 1.27 1.27)
				)
				(justify mirror)
			)
		)
		(duplicate_pad_numbers_are_jumpers no)
		(fp_poly
			(pts
				(xy -0.3048 -0.1016) (xy -0.3048 0.9906) (xy 0.3048 0.9906) (xy 0.3048 -0.1016)
			)
			(stroke
				(width 0)
				(type default)
			)
			(fill no)
			(layer "B.CrtYd")
		)
		(fp_line
			(start 0.3048 -0.1016)
			(end 0.3048 0.9906)
			(stroke
				(width 0.1)
				(type default)
			)
			(layer "B.Fab")
		)
		(fp_line
			(start -0.3048 -0.1016)
			(end 0.3048 -0.1016)
			(stroke
				(width 0.1)
				(type default)
			)
			(layer "B.Fab")
		)
		(fp_line
			(start 0.3048 0.9906)
			(end -0.3048 0.9906)
			(stroke
				(width 0.1)
				(type default)
			)
			(layer "B.Fab")
		)
		(fp_line
			(start -0.3048 0.9906)
			(end -0.3048 -0.1016)
			(stroke
				(width 0.1)
				(type default)
			)
			(layer "B.Fab")
		)
		(pad "1" smd rect
			(at 0 0 270)
			(size 0.508 0.508)
			(layers "B.Cu" "B.Mask" "B.Paste")
			(net "P3V3_STBY")
		)
		(pad "2" smd rect
			(at 0 0.889 270)
			(size 0.508 0.508)
			(layers "B.Cu" "B.Mask" "B.Paste")
			(net "GND")
		)
		(zone
			(layer "B.Cu")
			(hatch none 0.5)
			(connect_pads
				(clearance 0)
			)
			(min_thickness 0.25)
			(keepout
				(tracks allowed)
				(vias not_allowed)
				(pads allowed)
				(copperpour not_allowed)
				(footprints allowed)
			)
			(placement
				(enabled no)
				(sheetname "")
			)
			(fill
				(thermal_gap 0.5)
				(thermal_bridge_width 0.5)
				(island_removal_mode 0)
			)
			(polygon
				(pts
					(xy 399.6944 -74.422) (xy 399.6944 -73.914) (xy 400.0754 -73.914) (xy 400.0754 -74.422)
				)
			)
		)
		(zone
			(layer "B.Cu")
			(hatch none 0.5)
			(connect_pads
				(clearance 0)
			)
			(min_thickness 0.25)
			(keepout
				(tracks not_allowed)
				(vias allowed)
				(pads allowed)
				(copperpour not_allowed)
				(footprints allowed)
			)
			(placement
				(enabled no)
				(sheetname "")
			)
			(fill
				(thermal_gap 0.5)
				(thermal_bridge_width 0.5)
				(island_removal_mode 0)
			)
			(polygon
				(pts
					(xy 400.0754 -74.422) (xy 400.0754 -73.914) (xy 399.6944 -73.914) (xy 399.6944 -74.422)
				)
			)
		)
	)
	(footprint ""
		(layer "B.Cu")
		(at 178.562 -51.562 -90)
		(property "Reference" "C6R14"
			(at 0 0 90)
			(layer "B.SilkS")
			(hide yes)
			(effects
				(font
					(size 1.27 1.27)
				)
				(justify mirror)
			)
		)
		(property "Value" ""
			(at 0 0 90)
			(layer "B.Fab")
			(effects
				(font
					(size 1.27 1.27)
				)
				(justify mirror)
			)
		)
		(duplicate_pad_numbers_are_jumpers no)
		(fp_poly
			(pts
				(xy 0.7239 -0.2159) (xy -0.7239 -0.2159) (xy -0.7239 1.9939) (xy 0.7239 1.9939)
			)
			(stroke
				(width 0)
				(type default)
			)
			(fill no)
			(layer "B.CrtYd")
		)
		(fp_line
			(start -0.7239 1.9939)
			(end -0.7239 -0.2159)
			(stroke
				(width 0.1)
				(type default)
			)
			(layer "B.Fab")
		)
		(fp_line
			(start 0.7239 1.9939)
			(end -0.7239 1.9939)
			(stroke
				(width 0.1)
				(type default)
			)
			(layer "B.Fab")
		)
		(fp_line
			(start -0.7239 -0.2159)
			(end 0.7239 -0.2159)
			(stroke
				(width 0.1)
				(type default)
			)
			(layer "B.Fab")
		)
		(fp_line
			(start 0.7239 -0.2159)
			(end 0.7239 1.9939)
			(stroke
				(width 0.1)
				(type default)
			)
			(layer "B.Fab")
		)
		(pad "1" smd rect
			(at 0 0 90)
			(size 1.27 1.016)
			(layers "B.Cu" "B.Mask" "B.Paste")
			(net "VR_FET_SW_P12V_STBY_PVCCIN_CPU0")
		)
		(pad "2" smd rect
			(at 0 1.778 90)
			(size 1.27 1.016)
			(layers "B.Cu" "B.Mask" "B.Paste")
			(net "GND")
		)
		(zone
			(layer "B.Cu")
			(hatch none 0.5)
			(connect_pads
				(clearance 0)
			)
			(min_thickness 0.25)
			(keepout
				(tracks not_allowed)
				(vias allowed)
				(pads allowed)
				(copperpour not_allowed)
				(footprints allowed)
			)
			(placement
				(enabled no)
				(sheetname "")
			)
			(fill
				(thermal_gap 0.5)
				(thermal_bridge_width 0.5)
				(island_removal_mode 0)
			)
			(polygon
				(pts
					(xy 178.054 -50.927) (xy 178.054 -52.197) (xy 177.292 -52.197) (xy 177.292 -50.927)
				)
			)
		)
	)
	(footprint ""
		(layer "B.Cu")
		(at 437.769 -20.193 -90)
		(property "Reference" "Q9W3"
			(at 0.229362 -1.59512 270)
			(unlocked yes)
			(layer "B.SilkS")
			(effects
				(font
					(size 1.27 0.9652)
					(thickness 0.1524)
				)
				(justify left mirror)
			)
		)
		(property "Value" ""
			(at 0 0 90)
			(layer "B.Fab")
			(effects
				(font
					(size 1.27 1.27)
				)
				(justify mirror)
			)
		)
		(duplicate_pad_numbers_are_jumpers no)
		(fp_line
			(start -1.778 2.4765)
			(end -1.778 1.5875)
			(stroke
				(width 0.1524)
				(type default)
			)
			(layer "B.SilkS")
		)
		(fp_line
			(start -0.9525 2.4765)
			(end -1.778 2.4765)
			(stroke
				(width 0.1524)
				(type default)
			)
			(layer "B.SilkS")
		)
		(fp_line
			(start -0.381 0.635)
			(end -0.381 1.27)
			(stroke
				(width 0.1524)
				(type default)
			)
			(layer "B.SilkS")
		)
		(fp_line
			(start -1.778 -0.5715)
			(end -1.778 0.3175)
			(stroke
				(width 0.1524)
				(type default)
			)
			(layer "B.SilkS")
		)
		(fp_line
			(start -0.9525 -0.5715)
			(end -1.778 -0.5715)
			(stroke
				(width 0.1524)
				(type default)
			)
			(layer "B.SilkS")
		)
		(fp_circle
			(center 0.9525 -0.9271)
			(end 0.9525 -1.0541)
			(stroke
				(width 0.254)
				(type default)
			)
			(fill no)
			(layer "B.SilkS")
		)
		(fp_poly
			(pts
				(xy -1.778 2.4765) (xy -0.381 2.4765) (xy -0.381 -0.5715) (xy -1.778 -0.5715)
			)
			(stroke
				(width 0)
				(type default)
			)
			(fill no)
			(layer "B.CrtYd")
		)
		(fp_line
			(start -1.778 2.4765)
			(end -1.778 -0.5715)
			(stroke
				(width 0.1)
				(type default)
			)
			(layer "B.Fab")
		)
		(fp_line
			(start -0.381 2.4765)
			(end -1.778 2.4765)
			(stroke
				(width 0.1)
				(type default)
			)
			(layer "B.Fab")
		)
		(fp_line
			(start -1.778 -0.5715)
			(end -0.381 -0.5715)
			(stroke
				(width 0.1)
				(type default)
			)
			(layer "B.Fab")
		)
		(fp_line
			(start -0.381 -0.5715)
			(end -0.381 2.4765)
			(stroke
				(width 0.1)
				(type default)
			)
			(layer "B.Fab")
		)
		(fp_circle
			(center 0.9525 -0.9271)
			(end 0.9525 -1.0541)
			(stroke
				(width 0.254)
				(type default)
			)
			(fill no)
			(layer "B.Fab")
		)
		(pad "1" smd rect
			(at 0 0 90)
			(size 1.143 0.508)
			(layers "B.Cu" "B.Mask" "B.Paste")
			(net "FM_TPM_PRES_RST")
		)
		(pad "2" smd rect
			(at 0 1.905 90)
			(size 1.143 0.508)
			(layers "B.Cu" "B.Mask" "B.Paste")
			(net "GND")
		)
		(pad "3" smd rect
			(at -2.159 0.9525 90)
			(size 1.143 0.508)
			(layers "B.Cu" "B.Mask" "B.Paste")
			(net "RST_BMC_EXTRST_N")
		)
	)
	(footprint ""
		(layer "B.Cu")
		(at 259.9182 -126.1364 -90)
		(property "Reference" "C5M13"
			(at 0 0 90)
			(layer "B.SilkS")
			(hide yes)
			(effects
				(font
					(size 1.27 1.27)
				)
				(justify mirror)
			)
		)
		(property "Value" ""
			(at 0 0 90)
			(layer "B.Fab")
			(effects
				(font
					(size 1.27 1.27)
				)
				(justify mirror)
			)
		)
		(duplicate_pad_numbers_are_jumpers no)
		(fp_rect
			(start 0.500126 1.598422)
			(end -0.500126 -0.201422)
			(stroke
				(width 0)
				(type default)
			)
			(fill no)
			(layer "B.CrtYd")
		)
		(fp_line
			(start -0.500126 1.598422)
			(end 0.500126 1.598422)
			(stroke
				(width 0.1)
				(type default)
			)
			(layer "B.Fab")
		)
		(fp_line
			(start 0.500126 1.598422)
			(end 0.500126 -0.201422)
			(stroke
				(width 0.1)
				(type default)
			)
			(layer "B.Fab")
		)
		(fp_line
			(start -0.500126 -0.201422)
			(end -0.500126 1.598422)
			(stroke
				(width 0.1)
				(type default)
			)
			(layer "B.Fab")
		)
		(fp_line
			(start 0.500126 -0.201422)
			(end -0.500126 -0.201422)
			(stroke
				(width 0.1)
				(type default)
			)
			(layer "B.Fab")
		)
		(pad "1" smd rect
			(at 0 0 180)
			(size 0.889 0.9906)
			(layers "B.Cu" "B.Mask" "B.Paste")
			(net "PVTT_DEF")
		)
		(pad "2" smd rect
			(at 0 1.397 180)
			(size 0.889 0.9906)
			(layers "B.Cu" "B.Mask" "B.Paste")
			(net "GND")
		)
		(zone
			(layer "B.Cu")
			(hatch none 0.5)
			(connect_pads
				(clearance 0)
			)
			(min_thickness 0.25)
			(keepout
				(tracks allowed)
				(vias not_allowed)
				(pads allowed)
				(copperpour not_allowed)
				(footprints allowed)
			)
			(placement
				(enabled no)
				(sheetname "")
			)
			(fill
				(thermal_gap 0.5)
				(thermal_bridge_width 0.5)
				(island_removal_mode 0)
			)
			(polygon
				(pts
					(xy 258.9657 -125.6411) (xy 259.4737 -125.6411) (xy 259.4737 -126.6317) (xy 258.9657 -126.6317)
				)
			)
		)
		(zone
			(layer "B.Cu")
			(hatch none 0.5)
			(connect_pads
				(clearance 0)
			)
			(min_thickness 0.25)
			(keepout
				(tracks not_allowed)
				(vias allowed)
				(pads allowed)
				(copperpour not_allowed)
				(footprints allowed)
			)
			(placement
				(enabled no)
				(sheetname "")
			)
			(fill
				(thermal_gap 0.5)
				(thermal_bridge_width 0.5)
				(island_removal_mode 0)
			)
			(polygon
				(pts
					(xy 258.9657 -125.6411) (xy 259.4737 -125.6411) (xy 259.4737 -126.6317) (xy 258.9657 -126.6317)
				)
			)
		)
	)
	(footprint ""
		(layer "B.Cu")
		(at 413.0675 -25.273 -90)
		(property "Reference" "C25W33"
			(at 0.8382 -0.67818 270)
			(unlocked yes)
			(layer "B.SilkS")
			(effects
				(font
					(size 0.4064 0.254)
					(thickness 0.1524)
				)
				(justify left mirror)
			)
		)
		(property "Value" ""
			(at 0 0 90)
			(layer "B.Fab")
			(effects
				(font
					(size 1.27 1.27)
				)
				(justify mirror)
			)
		)
		(duplicate_pad_numbers_are_jumpers no)
		(fp_poly
			(pts
				(xy -0.3048 -0.1016) (xy -0.3048 0.9906) (xy 0.3048 0.9906) (xy 0.3048 -0.1016)
			)
			(stroke
				(width 0)
				(type default)
			)
			(fill no)
			(layer "B.CrtYd")
		)
		(fp_line
			(start -0.3048 0.9906)
			(end -0.3048 -0.1016)
			(stroke
				(width 0.1)
				(type default)
			)
			(layer "B.Fab")
		)
		(fp_line
			(start 0.3048 0.9906)
			(end -0.3048 0.9906)
			(stroke
				(width 0.1)
				(type default)
			)
			(layer "B.Fab")
		)
		(fp_line
			(start -0.3048 -0.1016)
			(end 0.3048 -0.1016)
			(stroke
				(width 0.1)
				(type default)
			)
			(layer "B.Fab")
		)
		(fp_line
			(start 0.3048 -0.1016)
			(end 0.3048 0.9906)
			(stroke
				(width 0.1)
				(type default)
			)
			(layer "B.Fab")
		)
		(pad "1" smd rect
			(at 0 0 90)
			(size 0.508 0.508)
			(layers "B.Cu" "B.Mask" "B.Paste")
			(net "VCC_ADCAV3V3")
		)
		(pad "2" smd rect
			(at 0 0.889 90)
			(size 0.508 0.508)
			(layers "B.Cu" "B.Mask" "B.Paste")
			(net "GND")
		)
		(zone
			(layer "B.Cu")
			(hatch none 0.5)
			(connect_pads
				(clearance 0)
			)
			(min_thickness 0.25)
			(keepout
				(tracks not_allowed)
				(vias allowed)
				(pads allowed)
				(copperpour not_allowed)
				(footprints allowed)
			)
			(placement
				(enabled no)
				(sheetname "")
			)
			(fill
				(thermal_gap 0.5)
				(thermal_bridge_width 0.5)
				(island_removal_mode 0)
			)
			(polygon
				(pts
					(xy 412.4325 -25.019) (xy 412.4325 -25.527) (xy 412.8135 -25.527) (xy 412.8135 -25.019)
				)
			)
		)
		(zone
			(layer "B.Cu")
			(hatch none 0.5)
			(connect_pads
				(clearance 0)
			)
			(min_thickness 0.25)
			(keepout
				(tracks allowed)
				(vias not_allowed)
				(pads allowed)
				(copperpour not_allowed)
				(footprints allowed)
			)
			(placement
				(enabled no)
				(sheetname "")
			)
			(fill
				(thermal_gap 0.5)
				(thermal_bridge_width 0.5)
				(island_removal_mode 0)
			)
			(polygon
				(pts
					(xy 412.8135 -25.019) (xy 412.8135 -25.527) (xy 412.4325 -25.527) (xy 412.4325 -25.019)
				)
			)
		)
	)
	(footprint ""
		(layer "B.Cu")
		(at 22.0345 -83.312 -90)
		(property "Reference" "U9P1"
			(at -1.05918 -0.62357 270)
			(unlocked yes)
			(layer "B.SilkS")
			(effects
				(font
					(size 0.7874 0.5842)
					(thickness 0.1524)
				)
				(justify mirror)
			)
		)
		(property "Value" ""
			(at 0 0 90)
			(layer "B.Fab")
			(effects
				(font
					(size 1.27 1.27)
				)
				(justify mirror)
			)
		)
		(duplicate_pad_numbers_are_jumpers no)
		(fp_circle
			(center 1.0795 -0.054102)
			(end 1.0795 -0.181102)
			(stroke
				(width 0.254)
				(type default)
			)
			(fill no)
			(layer "B.SilkS")
		)
		(fp_rect
			(start 0.216154 1.27508)
			(end -1.333754 -0.275082)
			(stroke
				(width 0)
				(type default)
			)
			(fill no)
			(layer "B.CrtYd")
		)
		(fp_line
			(start -1.333754 1.27508)
			(end 0.216154 1.27508)
			(stroke
				(width 0.1)
				(type default)
			)
			(layer "B.Fab")
		)
		(fp_line
			(start 0.216154 1.27508)
			(end 0.216154 -0.275082)
			(stroke
				(width 0.1)
				(type default)
			)
			(layer "B.Fab")
		)
		(fp_line
			(start -1.333754 -0.275082)
			(end -1.333754 1.27508)
			(stroke
				(width 0.1)
				(type default)
			)
			(layer "B.Fab")
		)
		(fp_line
			(start 0.216154 -0.275082)
			(end -1.333754 -0.275082)
			(stroke
				(width 0.1)
				(type default)
			)
			(layer "B.Fab")
		)
		(fp_circle
			(center 1.0795 -0.054102)
			(end 1.0795 -0.181102)
			(stroke
				(width 0.254)
				(type default)
			)
			(fill no)
			(layer "B.Fab")
		)
		(pad "1" smd rect
			(at 0 0 90)
			(size 0.9398 0.3048)
			(layers "B.Cu" "B.Mask" "B.Paste")
			(net "A_P12V_STBY_FPH_GATE")
		)
		(pad "2" smd rect
			(at 0.0254 0.500126 90)
			(size 0.889 0.3048)
			(layers "B.Cu" "B.Mask" "B.Paste")
			(net "P12V_STBY")
		)
		(pad "3" smd rect
			(at 0.0254 0.999998 90)
			(size 0.889 0.3048)
			(layers "B.Cu" "B.Mask" "B.Paste")
			(net "A_P12V_STBY_FP_TRIGGER")
		)
		(pad "4" smd rect
			(at -1.143 0.999998 90)
			(size 0.889 0.3048)
			(layers "B.Cu" "B.Mask" "B.Paste")
			(net "A_P12V_STBY_ADR_TRIGGER")
		)
		(pad "5" smd rect
			(at -1.143 0.500126 90)
			(size 0.889 0.3048)
			(layers "B.Cu" "B.Mask" "B.Paste")
			(net "GND")
		)
		(pad "6" smd rect
			(at -1.143 0 90)
			(size 0.889 0.3048)
			(layers "B.Cu" "B.Mask" "B.Paste")
			(net "FM_UV_ADR_TRIGGER_N")
		)
	)
	(footprint ""
		(layer "B.Cu")
		(at 486.7402 -39.7002 180)
		(property "Reference" "C1T3"
			(at 0 0 0)
			(layer "B.SilkS")
			(hide yes)
			(effects
				(font
					(size 1.27 1.27)
				)
				(justify mirror)
			)
		)
		(property "Value" ""
			(at 0 0 0)
			(layer "B.Fab")
			(effects
				(font
					(size 1.27 1.27)
				)
				(justify mirror)
			)
		)
		(duplicate_pad_numbers_are_jumpers no)
		(fp_poly
			(pts
				(xy -0.3048 -0.1016) (xy -0.3048 0.9906) (xy 0.3048 0.9906) (xy 0.3048 -0.1016)
			)
			(stroke
				(width 0)
				(type default)
			)
			(fill no)
			(layer "B.CrtYd")
		)
		(fp_line
			(start 0.3048 0.9906)
			(end -0.3048 0.9906)
			(stroke
				(width 0.1)
				(type default)
			)
			(layer "B.Fab")
		)
		(fp_line
			(start 0.3048 -0.1016)
			(end 0.3048 0.9906)
			(stroke
				(width 0.1)
				(type default)
			)
			(layer "B.Fab")
		)
		(fp_line
			(start -0.3048 0.9906)
			(end -0.3048 -0.1016)
			(stroke
				(width 0.1)
				(type default)
			)
			(layer "B.Fab")
		)
		(fp_line
			(start -0.3048 -0.1016)
			(end 0.3048 -0.1016)
			(stroke
				(width 0.1)
				(type default)
			)
			(layer "B.Fab")
		)
		(pad "1" smd rect
			(at 0 0)
			(size 0.508 0.508)
			(layers "B.Cu" "B.Mask" "B.Paste")
			(net "P3V3_STBY")
		)
		(pad "2" smd rect
			(at 0 0.889)
			(size 0.508 0.508)
			(layers "B.Cu" "B.Mask" "B.Paste")
			(net "GND")
		)
		(zone
			(layer "B.Cu")
			(hatch none 0.5)
			(connect_pads
				(clearance 0)
			)
			(min_thickness 0.25)
			(keepout
				(tracks not_allowed)
				(vias allowed)
				(pads allowed)
				(copperpour not_allowed)
				(footprints allowed)
			)
			(placement
				(enabled no)
				(sheetname "")
			)
			(fill
				(thermal_gap 0.5)
				(thermal_bridge_width 0.5)
				(island_removal_mode 0)
			)
			(polygon
				(pts
					(xy 486.4862 -40.3352) (xy 486.9942 -40.3352) (xy 486.9942 -39.9542) (xy 486.4862 -39.9542)
				)
			)
		)
		(zone
			(layer "B.Cu")
			(hatch none 0.5)
			(connect_pads
				(clearance 0)
			)
			(min_thickness 0.25)
			(keepout
				(tracks allowed)
				(vias not_allowed)
				(pads allowed)
				(copperpour not_allowed)
				(footprints allowed)
			)
			(placement
				(enabled no)
				(sheetname "")
			)
			(fill
				(thermal_gap 0.5)
				(thermal_bridge_width 0.5)
				(island_removal_mode 0)
			)
			(polygon
				(pts
					(xy 486.4862 -39.9542) (xy 486.9942 -39.9542) (xy 486.9942 -40.3352) (xy 486.4862 -40.3352)
				)
			)
		)
	)
	(footprint ""
		(layer "B.Cu")
		(at 408.051 -6.9215 180)
		(property "Reference" "R8D38"
			(at 0 0 0)
			(layer "B.SilkS")
			(hide yes)
			(effects
				(font
					(size 1.27 1.27)
				)
				(justify mirror)
			)
		)
		(property "Value" ""
			(at 0 0 0)
			(layer "B.Fab")
			(effects
				(font
					(size 1.27 1.27)
				)
				(justify mirror)
			)
		)
		(duplicate_pad_numbers_are_jumpers no)
		(fp_poly
			(pts
				(xy 0.2794 -0.1016) (xy -0.2794 -0.1016) (xy -0.2794 0.9906) (xy 0.2794 0.9906)
			)
			(stroke
				(width 0)
				(type default)
			)
			(fill no)
			(layer "B.CrtYd")
		)
		(fp_line
			(start 0.2794 0.9906)
			(end -0.2794 0.9906)
			(stroke
				(width 0.1)
				(type default)
			)
			(layer "B.Fab")
		)
		(fp_line
			(start 0.2794 -0.1016)
			(end 0.2794 0.9906)
			(stroke
				(width 0.1)
				(type default)
			)
			(layer "B.Fab")
		)
		(fp_line
			(start -0.2794 0.9906)
			(end -0.2794 -0.1016)
			(stroke
				(width 0.1)
				(type default)
			)
			(layer "B.Fab")
		)
		(fp_line
			(start -0.2794 -0.1016)
			(end 0.2794 -0.1016)
			(stroke
				(width 0.1)
				(type default)
			)
			(layer "B.Fab")
		)
		(pad "1" smd rect
			(at 0 0)
			(size 0.508 0.508)
			(layers "B.Cu" "B.Mask" "B.Paste")
			(net "P12V")
		)
		(pad "2" smd rect
			(at 0 0.889)
			(size 0.508 0.508)
			(layers "B.Cu" "B.Mask" "B.Paste")
			(net "A_PG_P12V_MAIN")
		)
		(zone
			(layer "B.Cu")
			(hatch none 0.5)
			(connect_pads
				(clearance 0)
			)
			(min_thickness 0.25)
			(keepout
				(tracks not_allowed)
				(vias allowed)
				(pads allowed)
				(copperpour not_allowed)
				(footprints allowed)
			)
			(placement
				(enabled no)
				(sheetname "")
			)
			(fill
				(thermal_gap 0.5)
				(thermal_bridge_width 0.5)
				(island_removal_mode 0)
			)
			(polygon
				(pts
					(xy 407.797 -7.5565) (xy 408.305 -7.5565) (xy 408.305 -7.1755) (xy 407.797 -7.1755)
				)
			)
		)
		(zone
			(layer "B.Cu")
			(hatch none 0.5)
			(connect_pads
				(clearance 0)
			)
			(min_thickness 0.25)
			(keepout
				(tracks allowed)
				(vias not_allowed)
				(pads allowed)
				(copperpour not_allowed)
				(footprints allowed)
			)
			(placement
				(enabled no)
				(sheetname "")
			)
			(fill
				(thermal_gap 0.5)
				(thermal_bridge_width 0.5)
				(island_removal_mode 0)
			)
			(polygon
				(pts
					(xy 407.797 -7.1755) (xy 408.305 -7.1755) (xy 408.305 -7.5565) (xy 407.797 -7.5565)
				)
			)
		)
	)
	(footprint ""
		(layer "B.Cu")
		(at 365.76 -62.2935 180)
		(property "Reference" "R3R3"
			(at 0 0 0)
			(layer "B.SilkS")
			(hide yes)
			(effects
				(font
					(size 1.27 1.27)
				)
				(justify mirror)
			)
		)
		(property "Value" ""
			(at 0 0 0)
			(layer "B.Fab")
			(effects
				(font
					(size 1.27 1.27)
				)
				(justify mirror)
			)
		)
		(duplicate_pad_numbers_are_jumpers no)
		(fp_poly
			(pts
				(xy 0.2794 -0.1016) (xy -0.2794 -0.1016) (xy -0.2794 0.9906) (xy 0.2794 0.9906)
			)
			(stroke
				(width 0)
				(type default)
			)
			(fill no)
			(layer "B.CrtYd")
		)
		(fp_line
			(start 0.2794 0.9906)
			(end -0.2794 0.9906)
			(stroke
				(width 0.1)
				(type default)
			)
			(layer "B.Fab")
		)
		(fp_line
			(start 0.2794 -0.1016)
			(end 0.2794 0.9906)
			(stroke
				(width 0.1)
				(type default)
			)
			(layer "B.Fab")
		)
		(fp_line
			(start -0.2794 0.9906)
			(end -0.2794 -0.1016)
			(stroke
				(width 0.1)
				(type default)
			)
			(layer "B.Fab")
		)
		(fp_line
			(start -0.2794 -0.1016)
			(end 0.2794 -0.1016)
			(stroke
				(width 0.1)
				(type default)
			)
			(layer "B.Fab")
		)
		(pad "1" smd rect
			(at 0 0)
			(size 0.508 0.508)
			(layers "B.Cu" "B.Mask" "B.Paste")
			(net "PWRGD_CPUPWRGD_R1")
		)
		(pad "2" smd rect
			(at 0 0.889)
			(size 0.508 0.508)
			(layers "B.Cu" "B.Mask" "B.Paste")
			(net "PWRGD_CPUPWRGD")
		)
		(zone
			(layer "B.Cu")
			(hatch none 0.5)
			(connect_pads
				(clearance 0)
			)
			(min_thickness 0.25)
			(keepout
				(tracks not_allowed)
				(vias allowed)
				(pads allowed)
				(copperpour not_allowed)
				(footprints allowed)
			)
			(placement
				(enabled no)
				(sheetname "")
			)
			(fill
				(thermal_gap 0.5)
				(thermal_bridge_width 0.5)
				(island_removal_mode 0)
			)
			(polygon
				(pts
					(xy 365.506 -62.9285) (xy 366.014 -62.9285) (xy 366.014 -62.5475) (xy 365.506 -62.5475)
				)
			)
		)
		(zone
			(layer "B.Cu")
			(hatch none 0.5)
			(connect_pads
				(clearance 0)
			)
			(min_thickness 0.25)
			(keepout
				(tracks allowed)
				(vias not_allowed)
				(pads allowed)
				(copperpour not_allowed)
				(footprints allowed)
			)
			(placement
				(enabled no)
				(sheetname "")
			)
			(fill
				(thermal_gap 0.5)
				(thermal_bridge_width 0.5)
				(island_removal_mode 0)
			)
			(polygon
				(pts
					(xy 365.506 -62.5475) (xy 366.014 -62.5475) (xy 366.014 -62.9285) (xy 365.506 -62.9285)
				)
			)
		)
	)
	(footprint ""
		(layer "B.Cu")
		(at 401.454874 -23.114)
		(property "Reference" "C9G14"
			(at 0 0 0)
			(layer "B.SilkS")
			(hide yes)
			(effects
				(font
					(size 1.27 1.27)
				)
				(justify mirror)
			)
		)
		(property "Value" ""
			(at 0 0 0)
			(layer "B.Fab")
			(effects
				(font
					(size 1.27 1.27)
				)
				(justify mirror)
			)
		)
		(duplicate_pad_numbers_are_jumpers no)
		(fp_poly
			(pts
				(xy -0.3048 -0.1016) (xy -0.3048 0.9906) (xy 0.3048 0.9906) (xy 0.3048 -0.1016)
			)
			(stroke
				(width 0)
				(type default)
			)
			(fill no)
			(layer "B.CrtYd")
		)
		(fp_line
			(start -0.3048 -0.1016)
			(end 0.3048 -0.1016)
			(stroke
				(width 0.1)
				(type default)
			)
			(layer "B.Fab")
		)
		(fp_line
			(start -0.3048 0.9906)
			(end -0.3048 -0.1016)
			(stroke
				(width 0.1)
				(type default)
			)
			(layer "B.Fab")
		)
		(fp_line
			(start 0.3048 -0.1016)
			(end 0.3048 0.9906)
			(stroke
				(width 0.1)
				(type default)
			)
			(layer "B.Fab")
		)
		(fp_line
			(start 0.3048 0.9906)
			(end -0.3048 0.9906)
			(stroke
				(width 0.1)
				(type default)
			)
			(layer "B.Fab")
		)
		(pad "1" smd rect
			(at 0 0 180)
			(size 0.508 0.508)
			(layers "B.Cu" "B.Mask" "B.Paste")
			(net "A_P3V3_SCALED")
		)
		(pad "2" smd rect
			(at 0 0.889 180)
			(size 0.508 0.508)
			(layers "B.Cu" "B.Mask" "B.Paste")
			(net "GND")
		)
		(zone
			(layer "B.Cu")
			(hatch none 0.5)
			(connect_pads
				(clearance 0)
			)
			(min_thickness 0.25)
			(keepout
				(tracks allowed)
				(vias not_allowed)
				(pads allowed)
				(copperpour not_allowed)
				(footprints allowed)
			)
			(placement
				(enabled no)
				(sheetname "")
			)
			(fill
				(thermal_gap 0.5)
				(thermal_bridge_width 0.5)
				(island_removal_mode 0)
			)
			(polygon
				(pts
					(xy 401.708874 -22.86) (xy 401.200874 -22.86) (xy 401.200874 -22.479) (xy 401.708874 -22.479)
				)
			)
		)
		(zone
			(layer "B.Cu")
			(hatch none 0.5)
			(connect_pads
				(clearance 0)
			)
			(min_thickness 0.25)
			(keepout
				(tracks not_allowed)
				(vias allowed)
				(pads allowed)
				(copperpour not_allowed)
				(footprints allowed)
			)
			(placement
				(enabled no)
				(sheetname "")
			)
			(fill
				(thermal_gap 0.5)
				(thermal_bridge_width 0.5)
				(island_removal_mode 0)
			)
			(polygon
				(pts
					(xy 401.708874 -22.479) (xy 401.200874 -22.479) (xy 401.200874 -22.86) (xy 401.708874 -22.86)
				)
			)
		)
	)
	(footprint ""
		(layer "B.Cu")
		(at 354.289614 -125.532642 -90)
		(property "Reference" "R760"
			(at 0.8382 -0.67818 270)
			(unlocked yes)
			(layer "B.SilkS")
			(effects
				(font
					(size 0.4064 0.254)
					(thickness 0.1524)
				)
				(justify left mirror)
			)
		)
		(property "Value" ""
			(at 0 0 90)
			(layer "B.Fab")
			(effects
				(font
					(size 1.27 1.27)
				)
				(justify mirror)
			)
		)
		(duplicate_pad_numbers_are_jumpers no)
		(fp_poly
			(pts
				(xy 0.2794 -0.1016) (xy -0.2794 -0.1016) (xy -0.2794 0.9906) (xy 0.2794 0.9906)
			)
			(stroke
				(width 0)
				(type default)
			)
			(fill no)
			(layer "B.CrtYd")
		)
		(fp_line
			(start -0.2794 0.9906)
			(end -0.2794 -0.1016)
			(stroke
				(width 0.1)
				(type default)
			)
			(layer "B.Fab")
		)
		(fp_line
			(start 0.2794 0.9906)
			(end -0.2794 0.9906)
			(stroke
				(width 0.1)
				(type default)
			)
			(layer "B.Fab")
		)
		(fp_line
			(start -0.2794 -0.1016)
			(end 0.2794 -0.1016)
			(stroke
				(width 0.1)
				(type default)
			)
			(layer "B.Fab")
		)
		(fp_line
			(start 0.2794 -0.1016)
			(end 0.2794 0.9906)
			(stroke
				(width 0.1)
				(type default)
			)
			(layer "B.Fab")
		)
		(pad "1" smd rect
			(at 0 0 90)
			(size 0.508 0.508)
			(layers "B.Cu" "B.Mask" "B.Paste")
			(net "P3E_CPU0_PE1_PCH_RXN<15>")
		)
		(pad "2" smd rect
			(at 0 0.889 90)
			(size 0.508 0.508)
			(layers "B.Cu" "B.Mask" "B.Paste")
			(net "P3E_CPU0_PE1_PCH_CON_RXN<15>")
		)
		(zone
			(layer "B.Cu")
			(hatch none 0.5)
			(connect_pads
				(clearance 0)
			)
			(min_thickness 0.25)
			(keepout
				(tracks not_allowed)
				(vias allowed)
				(pads allowed)
				(copperpour not_allowed)
				(footprints allowed)
			)
			(placement
				(enabled no)
				(sheetname "")
			)
			(fill
				(thermal_gap 0.5)
				(thermal_bridge_width 0.5)
				(island_removal_mode 0)
			)
			(polygon
				(pts
					(xy 353.654614 -125.278642) (xy 353.654614 -125.786642) (xy 354.035614 -125.786642) (xy 354.035614 -125.278642)
				)
			)
		)
		(zone
			(layer "B.Cu")
			(hatch none 0.5)
			(connect_pads
				(clearance 0)
			)
			(min_thickness 0.25)
			(keepout
				(tracks allowed)
				(vias not_allowed)
				(pads allowed)
				(copperpour not_allowed)
				(footprints allowed)
			)
			(placement
				(enabled no)
				(sheetname "")
			)
			(fill
				(thermal_gap 0.5)
				(thermal_bridge_width 0.5)
				(island_removal_mode 0)
			)
			(polygon
				(pts
					(xy 354.035614 -125.278642) (xy 354.035614 -125.786642) (xy 353.654614 -125.786642) (xy 353.654614 -125.278642)
				)
			)
		)
	)
	(footprint ""
		(layer "B.Cu")
		(at 361.826556 -121.392442 -90)
		(property "Reference" "R779"
			(at 0.8382 -0.67818 270)
			(unlocked yes)
			(layer "B.SilkS")
			(effects
				(font
					(size 0.4064 0.254)
					(thickness 0.1524)
				)
				(justify left mirror)
			)
		)
		(property "Value" ""
			(at 0 0 90)
			(layer "B.Fab")
			(effects
				(font
					(size 1.27 1.27)
				)
				(justify mirror)
			)
		)
		(duplicate_pad_numbers_are_jumpers no)
		(fp_poly
			(pts
				(xy 0.2794 -0.1016) (xy -0.2794 -0.1016) (xy -0.2794 0.9906) (xy 0.2794 0.9906)
			)
			(stroke
				(width 0)
				(type default)
			)
			(fill no)
			(layer "B.CrtYd")
		)
		(fp_line
			(start -0.2794 0.9906)
			(end -0.2794 -0.1016)
			(stroke
				(width 0.1)
				(type default)
			)
			(layer "B.Fab")
		)
		(fp_line
			(start 0.2794 0.9906)
			(end -0.2794 0.9906)
			(stroke
				(width 0.1)
				(type default)
			)
			(layer "B.Fab")
		)
		(fp_line
			(start -0.2794 -0.1016)
			(end 0.2794 -0.1016)
			(stroke
				(width 0.1)
				(type default)
			)
			(layer "B.Fab")
		)
		(fp_line
			(start 0.2794 -0.1016)
			(end 0.2794 0.9906)
			(stroke
				(width 0.1)
				(type default)
			)
			(layer "B.Fab")
		)
		(pad "1" smd rect
			(at 0 0 90)
			(size 0.508 0.508)
			(layers "B.Cu" "B.Mask" "B.Paste")
			(net "P3E_CPU0_PE1_PCH_RXP<11>")
		)
		(pad "2" smd rect
			(at 0 0.889 90)
			(size 0.508 0.508)
			(layers "B.Cu" "B.Mask" "B.Paste")
			(net "P3E_CPU0_PE1_PCH_CON_RXP<11>")
		)
		(zone
			(layer "B.Cu")
			(hatch none 0.5)
			(connect_pads
				(clearance 0)
			)
			(min_thickness 0.25)
			(keepout
				(tracks not_allowed)
				(vias allowed)
				(pads allowed)
				(copperpour not_allowed)
				(footprints allowed)
			)
			(placement
				(enabled no)
				(sheetname "")
			)
			(fill
				(thermal_gap 0.5)
				(thermal_bridge_width 0.5)
				(island_removal_mode 0)
			)
			(polygon
				(pts
					(xy 361.191556 -121.138442) (xy 361.191556 -121.646442) (xy 361.572556 -121.646442) (xy 361.572556 -121.138442)
				)
			)
		)
		(zone
			(layer "B.Cu")
			(hatch none 0.5)
			(connect_pads
				(clearance 0)
			)
			(min_thickness 0.25)
			(keepout
				(tracks allowed)
				(vias not_allowed)
				(pads allowed)
				(copperpour not_allowed)
				(footprints allowed)
			)
			(placement
				(enabled no)
				(sheetname "")
			)
			(fill
				(thermal_gap 0.5)
				(thermal_bridge_width 0.5)
				(island_removal_mode 0)
			)
			(polygon
				(pts
					(xy 361.572556 -121.138442) (xy 361.572556 -121.646442) (xy 361.191556 -121.646442) (xy 361.191556 -121.138442)
				)
			)
		)
	)
	(footprint ""
		(layer "B.Cu")
		(at 308.768496 -33.874202)
		(property "Reference" ""
			(at 0 0 0)
			(layer "B.SilkS")
			(hide yes)
			(effects
				(font
					(size 1.27 1.27)
				)
				(justify mirror)
			)
		)
		(property "Value" ""
			(at 0 0 0)
			(layer "B.Fab")
			(effects
				(font
					(size 1.27 1.27)
				)
				(justify mirror)
			)
		)
		(duplicate_pad_numbers_are_jumpers no)
		(fp_poly
			(pts
				(arc
					(start 2.032 0)
					(mid -2.032 0)
					(end 2.032 0)
				)
			)
			(stroke
				(width 0)
				(type default)
			)
			(fill no)
			(layer "B.CrtYd")
		)
		(pad "1" smd circle
			(at 0 0 180)
			(size 1.016 1.016)
			(layers "B.Cu" "B.Mask" "B.Paste")
			(net "Net_398")
		)
		(zone
			(layers "F.Cu" "B.Cu" "In1.Cu" "In2.Cu" "In3.Cu" "In4.Cu" "In5.Cu" "In6.Cu"
				"In7.Cu" "In8.Cu" "In9.Cu" "In10.Cu" "In11.Cu" "In12.Cu"
			)
			(hatch none 0.5)
			(connect_pads
				(clearance 0)
			)
			(min_thickness 0.25)
			(keepout
				(tracks allowed)
				(vias not_allowed)
				(pads allowed)
				(copperpour not_allowed)
				(footprints allowed)
			)
			(placement
				(enabled no)
				(sheetname "")
			)
			(fill
				(thermal_gap 0.5)
				(thermal_bridge_width 0.5)
				(island_removal_mode 0)
			)
			(polygon
				(pts
					(arc
						(start 310.292496 -33.874202)
						(mid 307.244496 -33.874202)
						(end 310.292496 -33.874202)
					)
				)
			)
		)
		(zone
			(layer "B.Cu")
			(hatch none 0.5)
			(connect_pads
				(clearance 0)
			)
			(min_thickness 0.25)
			(keepout
				(tracks not_allowed)
				(vias allowed)
				(pads allowed)
				(copperpour not_allowed)
				(footprints allowed)
			)
			(placement
				(enabled no)
				(sheetname "")
			)
			(fill
				(thermal_gap 0.5)
				(thermal_bridge_width 0.5)
				(island_removal_mode 0)
			)
			(polygon
				(pts
					(arc
						(start 310.292496 -33.874202)
						(mid 307.244496 -33.874202)
						(end 310.292496 -33.874202)
					)
				)
			)
		)
	)
	(footprint ""
		(layer "B.Cu")
		(at 183.261 -13.589 180)
		(property "Reference" "C6U4"
			(at 0 0 0)
			(layer "B.SilkS")
			(hide yes)
			(effects
				(font
					(size 1.27 1.27)
				)
				(justify mirror)
			)
		)
		(property "Value" ""
			(at 0 0 0)
			(layer "B.Fab")
			(effects
				(font
					(size 1.27 1.27)
				)
				(justify mirror)
			)
		)
		(duplicate_pad_numbers_are_jumpers no)
		(fp_poly
			(pts
				(xy 0.7239 -0.2159) (xy -0.7239 -0.2159) (xy -0.7239 1.9939) (xy 0.7239 1.9939)
			)
			(stroke
				(width 0)
				(type default)
			)
			(fill no)
			(layer "B.CrtYd")
		)
		(fp_line
			(start 0.7239 1.9939)
			(end -0.7239 1.9939)
			(stroke
				(width 0.1)
				(type default)
			)
			(layer "B.Fab")
		)
		(fp_line
			(start 0.7239 -0.2159)
			(end 0.7239 1.9939)
			(stroke
				(width 0.1)
				(type default)
			)
			(layer "B.Fab")
		)
		(fp_line
			(start -0.7239 1.9939)
			(end -0.7239 -0.2159)
			(stroke
				(width 0.1)
				(type default)
			)
			(layer "B.Fab")
		)
		(fp_line
			(start -0.7239 -0.2159)
			(end 0.7239 -0.2159)
			(stroke
				(width 0.1)
				(type default)
			)
			(layer "B.Fab")
		)
		(pad "1" smd rect
			(at 0 0)
			(size 1.27 1.016)
			(layers "B.Cu" "B.Mask" "B.Paste")
			(net "VR_FET_SW_P12V_STBY_PVPP_GHJ")
		)
		(pad "2" smd rect
			(at 0 1.778)
			(size 1.27 1.016)
			(layers "B.Cu" "B.Mask" "B.Paste")
			(net "GND")
		)
		(zone
			(layer "B.Cu")
			(hatch none 0.5)
			(connect_pads
				(clearance 0)
			)
			(min_thickness 0.25)
			(keepout
				(tracks not_allowed)
				(vias allowed)
				(pads allowed)
				(copperpour not_allowed)
				(footprints allowed)
			)
			(placement
				(enabled no)
				(sheetname "")
			)
			(fill
				(thermal_gap 0.5)
				(thermal_bridge_width 0.5)
				(island_removal_mode 0)
			)
			(polygon
				(pts
					(xy 182.626 -14.097) (xy 183.896 -14.097) (xy 183.896 -14.859) (xy 182.626 -14.859)
				)
			)
		)
	)
	(footprint ""
		(layer "B.Cu")
		(at 104.5591 -149.8092 90)
		(property "Reference" "C5G103"
			(at -1.14681 0.76708 180)
			(unlocked yes)
			(layer "B.SilkS")
			(effects
				(font
					(size 0.7874 0.5842)
					(thickness 0.1524)
				)
				(justify mirror)
			)
		)
		(property "Value" ""
			(at 0 0 90)
			(layer "B.Fab")
			(effects
				(font
					(size 1.27 1.27)
				)
				(justify mirror)
			)
		)
		(duplicate_pad_numbers_are_jumpers no)
		(fp_rect
			(start -0.4953 -0.2032)
			(end 0.4953 1.6002)
			(stroke
				(width 0)
				(type default)
			)
			(fill no)
			(layer "B.CrtYd")
		)
		(fp_line
			(start 0.4953 -0.2032)
			(end -0.4953 -0.2032)
			(stroke
				(width 0.1)
				(type default)
			)
			(layer "B.Fab")
		)
		(fp_line
			(start -0.4953 -0.2032)
			(end -0.4953 1.6002)
			(stroke
				(width 0.1)
				(type default)
			)
			(layer "B.Fab")
		)
		(fp_line
			(start 0.4953 1.6002)
			(end 0.4953 -0.2032)
			(stroke
				(width 0.1)
				(type default)
			)
			(layer "B.Fab")
		)
		(fp_line
			(start -0.4953 1.6002)
			(end 0.4953 1.6002)
			(stroke
				(width 0.1)
				(type default)
			)
			(layer "B.Fab")
		)
		(pad "1" smd rect
			(at 0 0 270)
			(size 0.762 0.889)
			(layers "B.Cu" "B.Mask" "B.Paste")
			(net "PVDDQ_KLM")
		)
		(pad "2" smd rect
			(at 0 1.397 270)
			(size 0.762 0.889)
			(layers "B.Cu" "B.Mask" "B.Paste")
			(net "GND")
		)
		(zone
			(layer "B.Cu")
			(hatch none 0.5)
			(connect_pads
				(clearance 0)
			)
			(min_thickness 0.25)
			(keepout
				(tracks not_allowed)
				(vias allowed)
				(pads allowed)
				(copperpour not_allowed)
				(footprints allowed)
			)
			(placement
				(enabled no)
				(sheetname "")
			)
			(fill
				(thermal_gap 0.5)
				(thermal_bridge_width 0.5)
				(island_removal_mode 0)
			)
			(polygon
				(pts
					(xy 105.0036 -149.4282) (xy 105.5116 -149.4282) (xy 105.5116 -150.1902) (xy 105.0036 -150.1902)
				)
			)
		)
	)
	(footprint ""
		(layer "B.Cu")
		(at 473.122498 -135.78459 -90)
		(property "Reference" "C1W18"
			(at 0.8382 -0.67818 270)
			(unlocked yes)
			(layer "B.SilkS")
			(effects
				(font
					(size 0.4064 0.254)
					(thickness 0.1524)
				)
				(justify left mirror)
			)
		)
		(property "Value" ""
			(at 0 0 90)
			(layer "B.Fab")
			(effects
				(font
					(size 1.27 1.27)
				)
				(justify mirror)
			)
		)
		(duplicate_pad_numbers_are_jumpers no)
		(fp_poly
			(pts
				(xy -0.3048 -0.1016) (xy -0.3048 0.9906) (xy 0.3048 0.9906) (xy 0.3048 -0.1016)
			)
			(stroke
				(width 0)
				(type default)
			)
			(fill no)
			(layer "B.CrtYd")
		)
		(fp_line
			(start -0.3048 0.9906)
			(end -0.3048 -0.1016)
			(stroke
				(width 0.1)
				(type default)
			)
			(layer "B.Fab")
		)
		(fp_line
			(start 0.3048 0.9906)
			(end -0.3048 0.9906)
			(stroke
				(width 0.1)
				(type default)
			)
			(layer "B.Fab")
		)
		(fp_line
			(start -0.3048 -0.1016)
			(end 0.3048 -0.1016)
			(stroke
				(width 0.1)
				(type default)
			)
			(layer "B.Fab")
		)
		(fp_line
			(start 0.3048 -0.1016)
			(end 0.3048 0.9906)
			(stroke
				(width 0.1)
				(type default)
			)
			(layer "B.Fab")
		)
		(pad "1" smd rect
			(at 0 0 90)
			(size 0.508 0.508)
			(layers "B.Cu" "B.Mask" "B.Paste")
			(net "P3V3_STBY")
		)
		(pad "2" smd rect
			(at 0 0.889 90)
			(size 0.508 0.508)
			(layers "B.Cu" "B.Mask" "B.Paste")
			(net "GND")
		)
		(zone
			(layer "B.Cu")
			(hatch none 0.5)
			(connect_pads
				(clearance 0)
			)
			(min_thickness 0.25)
			(keepout
				(tracks not_allowed)
				(vias allowed)
				(pads allowed)
				(copperpour not_allowed)
				(footprints allowed)
			)
			(placement
				(enabled no)
				(sheetname "")
			)
			(fill
				(thermal_gap 0.5)
				(thermal_bridge_width 0.5)
				(island_removal_mode 0)
			)
			(polygon
				(pts
					(xy 472.487498 -135.53059) (xy 472.487498 -136.03859) (xy 472.868498 -136.03859) (xy 472.868498 -135.53059)
				)
			)
		)
		(zone
			(layer "B.Cu")
			(hatch none 0.5)
			(connect_pads
				(clearance 0)
			)
			(min_thickness 0.25)
			(keepout
				(tracks allowed)
				(vias not_allowed)
				(pads allowed)
				(copperpour not_allowed)
				(footprints allowed)
			)
			(placement
				(enabled no)
				(sheetname "")
			)
			(fill
				(thermal_gap 0.5)
				(thermal_bridge_width 0.5)
				(island_removal_mode 0)
			)
			(polygon
				(pts
					(xy 472.868498 -135.53059) (xy 472.868498 -136.03859) (xy 472.487498 -136.03859) (xy 472.487498 -135.53059)
				)
			)
		)
	)
	(footprint ""
		(layer "B.Cu")
		(at 500.246142 -43.04284 -90)
		(property "Reference" "C25W90"
			(at 0.8382 -0.67818 270)
			(unlocked yes)
			(layer "B.SilkS")
			(effects
				(font
					(size 0.4064 0.254)
					(thickness 0.1524)
				)
				(justify left mirror)
			)
		)
		(property "Value" ""
			(at 0 0 90)
			(layer "B.Fab")
			(effects
				(font
					(size 1.27 1.27)
				)
				(justify mirror)
			)
		)
		(duplicate_pad_numbers_are_jumpers no)
		(fp_poly
			(pts
				(xy -0.3048 -0.1016) (xy -0.3048 0.9906) (xy 0.3048 0.9906) (xy 0.3048 -0.1016)
			)
			(stroke
				(width 0)
				(type default)
			)
			(fill no)
			(layer "B.CrtYd")
		)
		(fp_line
			(start -0.3048 0.9906)
			(end -0.3048 -0.1016)
			(stroke
				(width 0.1)
				(type default)
			)
			(layer "B.Fab")
		)
		(fp_line
			(start 0.3048 0.9906)
			(end -0.3048 0.9906)
			(stroke
				(width 0.1)
				(type default)
			)
			(layer "B.Fab")
		)
		(fp_line
			(start -0.3048 -0.1016)
			(end 0.3048 -0.1016)
			(stroke
				(width 0.1)
				(type default)
			)
			(layer "B.Fab")
		)
		(fp_line
			(start 0.3048 -0.1016)
			(end 0.3048 0.9906)
			(stroke
				(width 0.1)
				(type default)
			)
			(layer "B.Fab")
		)
		(pad "1" smd rect
			(at 0 0 90)
			(size 0.508 0.508)
			(layers "B.Cu" "B.Mask" "B.Paste")
			(net "P5V_VGA_D")
		)
		(pad "2" smd rect
			(at 0 0.889 90)
			(size 0.508 0.508)
			(layers "B.Cu" "B.Mask" "B.Paste")
			(net "GND")
		)
		(zone
			(layer "B.Cu")
			(hatch none 0.5)
			(connect_pads
				(clearance 0)
			)
			(min_thickness 0.25)
			(keepout
				(tracks not_allowed)
				(vias allowed)
				(pads allowed)
				(copperpour not_allowed)
				(footprints allowed)
			)
			(placement
				(enabled no)
				(sheetname "")
			)
			(fill
				(thermal_gap 0.5)
				(thermal_bridge_width 0.5)
				(island_removal_mode 0)
			)
			(polygon
				(pts
					(xy 499.611142 -42.78884) (xy 499.611142 -43.29684) (xy 499.992142 -43.29684) (xy 499.992142 -42.78884)
				)
			)
		)
		(zone
			(layer "B.Cu")
			(hatch none 0.5)
			(connect_pads
				(clearance 0)
			)
			(min_thickness 0.25)
			(keepout
				(tracks allowed)
				(vias not_allowed)
				(pads allowed)
				(copperpour not_allowed)
				(footprints allowed)
			)
			(placement
				(enabled no)
				(sheetname "")
			)
			(fill
				(thermal_gap 0.5)
				(thermal_bridge_width 0.5)
				(island_removal_mode 0)
			)
			(polygon
				(pts
					(xy 499.992142 -42.78884) (xy 499.992142 -43.29684) (xy 499.611142 -43.29684) (xy 499.611142 -42.78884)
				)
			)
		)
	)
	(footprint ""
		(layer "B.Cu")
		(at 449.1736 -129.3622 180)
		(property "Reference" "C1M34"
			(at 0 0 0)
			(layer "B.SilkS")
			(hide yes)
			(effects
				(font
					(size 1.27 1.27)
				)
				(justify mirror)
			)
		)
		(property "Value" ""
			(at 0 0 0)
			(layer "B.Fab")
			(effects
				(font
					(size 1.27 1.27)
				)
				(justify mirror)
			)
		)
		(duplicate_pad_numbers_are_jumpers no)
		(fp_poly
			(pts
				(xy -0.3048 -0.1016) (xy -0.3048 0.9906) (xy 0.3048 0.9906) (xy 0.3048 -0.1016)
			)
			(stroke
				(width 0)
				(type default)
			)
			(fill no)
			(layer "B.CrtYd")
		)
		(fp_line
			(start 0.3048 0.9906)
			(end -0.3048 0.9906)
			(stroke
				(width 0.1)
				(type default)
			)
			(layer "B.Fab")
		)
		(fp_line
			(start 0.3048 -0.1016)
			(end 0.3048 0.9906)
			(stroke
				(width 0.1)
				(type default)
			)
			(layer "B.Fab")
		)
		(fp_line
			(start -0.3048 0.9906)
			(end -0.3048 -0.1016)
			(stroke
				(width 0.1)
				(type default)
			)
			(layer "B.Fab")
		)
		(fp_line
			(start -0.3048 -0.1016)
			(end 0.3048 -0.1016)
			(stroke
				(width 0.1)
				(type default)
			)
			(layer "B.Fab")
		)
		(pad "1" smd rect
			(at 0 0)
			(size 0.508 0.508)
			(layers "B.Cu" "B.Mask" "B.Paste")
			(net "P3V3_STBY")
		)
		(pad "2" smd rect
			(at 0 0.889)
			(size 0.508 0.508)
			(layers "B.Cu" "B.Mask" "B.Paste")
			(net "GND")
		)
		(zone
			(layer "B.Cu")
			(hatch none 0.5)
			(connect_pads
				(clearance 0)
			)
			(min_thickness 0.25)
			(keepout
				(tracks not_allowed)
				(vias allowed)
				(pads allowed)
				(copperpour not_allowed)
				(footprints allowed)
			)
			(placement
				(enabled no)
				(sheetname "")
			)
			(fill
				(thermal_gap 0.5)
				(thermal_bridge_width 0.5)
				(island_removal_mode 0)
			)
			(polygon
				(pts
					(xy 448.9196 -129.9972) (xy 449.4276 -129.9972) (xy 449.4276 -129.6162) (xy 448.9196 -129.6162)
				)
			)
		)
		(zone
			(layer "B.Cu")
			(hatch none 0.5)
			(connect_pads
				(clearance 0)
			)
			(min_thickness 0.25)
			(keepout
				(tracks allowed)
				(vias not_allowed)
				(pads allowed)
				(copperpour not_allowed)
				(footprints allowed)
			)
			(placement
				(enabled no)
				(sheetname "")
			)
			(fill
				(thermal_gap 0.5)
				(thermal_bridge_width 0.5)
				(island_removal_mode 0)
			)
			(polygon
				(pts
					(xy 448.9196 -129.6162) (xy 449.4276 -129.6162) (xy 449.4276 -129.9972) (xy 448.9196 -129.9972)
				)
			)
		)
	)
	(footprint ""
		(layer "B.Cu")
		(at 407.0858 -119.4816)
		(property "Reference" "C2M9"
			(at 0 0 0)
			(layer "B.SilkS")
			(hide yes)
			(effects
				(font
					(size 1.27 1.27)
				)
				(justify mirror)
			)
		)
		(property "Value" ""
			(at 0 0 0)
			(layer "B.Fab")
			(effects
				(font
					(size 1.27 1.27)
				)
				(justify mirror)
			)
		)
		(duplicate_pad_numbers_are_jumpers no)
		(fp_poly
			(pts
				(xy -0.3048 -0.1016) (xy -0.3048 0.9906) (xy 0.3048 0.9906) (xy 0.3048 -0.1016)
			)
			(stroke
				(width 0)
				(type default)
			)
			(fill no)
			(layer "B.CrtYd")
		)
		(fp_line
			(start -0.3048 -0.1016)
			(end 0.3048 -0.1016)
			(stroke
				(width 0.1)
				(type default)
			)
			(layer "B.Fab")
		)
		(fp_line
			(start -0.3048 0.9906)
			(end -0.3048 -0.1016)
			(stroke
				(width 0.1)
				(type default)
			)
			(layer "B.Fab")
		)
		(fp_line
			(start 0.3048 -0.1016)
			(end 0.3048 0.9906)
			(stroke
				(width 0.1)
				(type default)
			)
			(layer "B.Fab")
		)
		(fp_line
			(start 0.3048 0.9906)
			(end -0.3048 0.9906)
			(stroke
				(width 0.1)
				(type default)
			)
			(layer "B.Fab")
		)
		(pad "1" smd rect
			(at 0 0 180)
			(size 0.508 0.508)
			(layers "B.Cu" "B.Mask" "B.Paste")
			(net "P1V05_PCH_STBY_WM26_PLL")
		)
		(pad "2" smd rect
			(at 0 0.889 180)
			(size 0.508 0.508)
			(layers "B.Cu" "B.Mask" "B.Paste")
			(net "GND")
		)
		(zone
			(layer "B.Cu")
			(hatch none 0.5)
			(connect_pads
				(clearance 0)
			)
			(min_thickness 0.25)
			(keepout
				(tracks allowed)
				(vias not_allowed)
				(pads allowed)
				(copperpour not_allowed)
				(footprints allowed)
			)
			(placement
				(enabled no)
				(sheetname "")
			)
			(fill
				(thermal_gap 0.5)
				(thermal_bridge_width 0.5)
				(island_removal_mode 0)
			)
			(polygon
				(pts
					(xy 407.3398 -119.2276) (xy 406.8318 -119.2276) (xy 406.8318 -118.8466) (xy 407.3398 -118.8466)
				)
			)
		)
		(zone
			(layer "B.Cu")
			(hatch none 0.5)
			(connect_pads
				(clearance 0)
			)
			(min_thickness 0.25)
			(keepout
				(tracks not_allowed)
				(vias allowed)
				(pads allowed)
				(copperpour not_allowed)
				(footprints allowed)
			)
			(placement
				(enabled no)
				(sheetname "")
			)
			(fill
				(thermal_gap 0.5)
				(thermal_bridge_width 0.5)
				(island_removal_mode 0)
			)
			(polygon
				(pts
					(xy 407.3398 -118.8466) (xy 406.8318 -118.8466) (xy 406.8318 -119.2276) (xy 407.3398 -119.2276)
				)
			)
		)
	)
	(footprint ""
		(layer "B.Cu")
		(at 433.7685 -17.399 90)
		(property "Reference" "R9G28"
			(at 0 0 90)
			(layer "B.SilkS")
			(hide yes)
			(effects
				(font
					(size 1.27 1.27)
				)
				(justify mirror)
			)
		)
		(property "Value" ""
			(at 0 0 90)
			(layer "B.Fab")
			(effects
				(font
					(size 1.27 1.27)
				)
				(justify mirror)
			)
		)
		(duplicate_pad_numbers_are_jumpers no)
		(fp_poly
			(pts
				(xy 0.2794 -0.1016) (xy -0.2794 -0.1016) (xy -0.2794 0.9906) (xy 0.2794 0.9906)
			)
			(stroke
				(width 0)
				(type default)
			)
			(fill no)
			(layer "B.CrtYd")
		)
		(fp_line
			(start 0.2794 -0.1016)
			(end 0.2794 0.9906)
			(stroke
				(width 0.1)
				(type default)
			)
			(layer "B.Fab")
		)
		(fp_line
			(start -0.2794 -0.1016)
			(end 0.2794 -0.1016)
			(stroke
				(width 0.1)
				(type default)
			)
			(layer "B.Fab")
		)
		(fp_line
			(start 0.2794 0.9906)
			(end -0.2794 0.9906)
			(stroke
				(width 0.1)
				(type default)
			)
			(layer "B.Fab")
		)
		(fp_line
			(start -0.2794 0.9906)
			(end -0.2794 -0.1016)
			(stroke
				(width 0.1)
				(type default)
			)
			(layer "B.Fab")
		)
		(pad "1" smd rect
			(at 0 0 270)
			(size 0.508 0.508)
			(layers "B.Cu" "B.Mask" "B.Paste")
			(net "H_CPU1_KLM_MEMHOT_LVT3_R_N")
		)
		(pad "2" smd rect
			(at 0 0.889 270)
			(size 0.508 0.508)
			(layers "B.Cu" "B.Mask" "B.Paste")
			(net "H_CPU1_MEMKLM_MEMHOT_LVT3_K_N")
		)
		(zone
			(layer "B.Cu")
			(hatch none 0.5)
			(connect_pads
				(clearance 0)
			)
			(min_thickness 0.25)
			(keepout
				(tracks allowed)
				(vias not_allowed)
				(pads allowed)
				(copperpour not_allowed)
				(footprints allowed)
			)
			(placement
				(enabled no)
				(sheetname "")
			)
			(fill
				(thermal_gap 0.5)
				(thermal_bridge_width 0.5)
				(island_removal_mode 0)
			)
			(polygon
				(pts
					(xy 434.0225 -17.653) (xy 434.0225 -17.145) (xy 434.4035 -17.145) (xy 434.4035 -17.653)
				)
			)
		)
		(zone
			(layer "B.Cu")
			(hatch none 0.5)
			(connect_pads
				(clearance 0)
			)
			(min_thickness 0.25)
			(keepout
				(tracks not_allowed)
				(vias allowed)
				(pads allowed)
				(copperpour not_allowed)
				(footprints allowed)
			)
			(placement
				(enabled no)
				(sheetname "")
			)
			(fill
				(thermal_gap 0.5)
				(thermal_bridge_width 0.5)
				(island_removal_mode 0)
			)
			(polygon
				(pts
					(xy 434.4035 -17.653) (xy 434.4035 -17.145) (xy 434.0225 -17.145) (xy 434.0225 -17.653)
				)
			)
		)
	)
	(footprint ""
		(layer "B.Cu")
		(at 465.595208 -147.955254 180)
		(property "Reference" "R1L13"
			(at 0 0 0)
			(layer "B.SilkS")
			(hide yes)
			(effects
				(font
					(size 1.27 1.27)
				)
				(justify mirror)
			)
		)
		(property "Value" ""
			(at 0 0 0)
			(layer "B.Fab")
			(effects
				(font
					(size 1.27 1.27)
				)
				(justify mirror)
			)
		)
		(duplicate_pad_numbers_are_jumpers no)
		(fp_poly
			(pts
				(xy 0.2794 -0.1016) (xy -0.2794 -0.1016) (xy -0.2794 0.9906) (xy 0.2794 0.9906)
			)
			(stroke
				(width 0)
				(type default)
			)
			(fill no)
			(layer "B.CrtYd")
		)
		(fp_line
			(start 0.2794 0.9906)
			(end -0.2794 0.9906)
			(stroke
				(width 0.1)
				(type default)
			)
			(layer "B.Fab")
		)
		(fp_line
			(start 0.2794 -0.1016)
			(end 0.2794 0.9906)
			(stroke
				(width 0.1)
				(type default)
			)
			(layer "B.Fab")
		)
		(fp_line
			(start -0.2794 0.9906)
			(end -0.2794 -0.1016)
			(stroke
				(width 0.1)
				(type default)
			)
			(layer "B.Fab")
		)
		(fp_line
			(start -0.2794 -0.1016)
			(end 0.2794 -0.1016)
			(stroke
				(width 0.1)
				(type default)
			)
			(layer "B.Fab")
		)
		(pad "1" smd rect
			(at 0 0)
			(size 0.508 0.508)
			(layers "B.Cu" "B.Mask" "B.Paste")
			(net "XDP_SYSPWROK")
		)
		(pad "2" smd rect
			(at 0 0.889)
			(size 0.508 0.508)
			(layers "B.Cu" "B.Mask" "B.Paste")
			(net "P3V3_STBY")
		)
		(zone
			(layer "B.Cu")
			(hatch none 0.5)
			(connect_pads
				(clearance 0)
			)
			(min_thickness 0.25)
			(keepout
				(tracks not_allowed)
				(vias allowed)
				(pads allowed)
				(copperpour not_allowed)
				(footprints allowed)
			)
			(placement
				(enabled no)
				(sheetname "")
			)
			(fill
				(thermal_gap 0.5)
				(thermal_bridge_width 0.5)
				(island_removal_mode 0)
			)
			(polygon
				(pts
					(xy 465.341208 -148.590254) (xy 465.849208 -148.590254) (xy 465.849208 -148.209254) (xy 465.341208 -148.209254)
				)
			)
		)
		(zone
			(layer "B.Cu")
			(hatch none 0.5)
			(connect_pads
				(clearance 0)
			)
			(min_thickness 0.25)
			(keepout
				(tracks allowed)
				(vias not_allowed)
				(pads allowed)
				(copperpour not_allowed)
				(footprints allowed)
			)
			(placement
				(enabled no)
				(sheetname "")
			)
			(fill
				(thermal_gap 0.5)
				(thermal_bridge_width 0.5)
				(island_removal_mode 0)
			)
			(polygon
				(pts
					(xy 465.341208 -148.209254) (xy 465.849208 -148.209254) (xy 465.849208 -148.590254) (xy 465.341208 -148.590254)
				)
			)
		)
	)
	(footprint ""
		(layer "B.Cu")
		(at 462.8134 -52.432458)
		(property "Reference" "C1R2"
			(at 0 0 0)
			(layer "B.SilkS")
			(hide yes)
			(effects
				(font
					(size 1.27 1.27)
				)
				(justify mirror)
			)
		)
		(property "Value" ""
			(at 0 0 0)
			(layer "B.Fab")
			(effects
				(font
					(size 1.27 1.27)
				)
				(justify mirror)
			)
		)
		(duplicate_pad_numbers_are_jumpers no)
		(fp_poly
			(pts
				(xy -0.3048 -0.1016) (xy -0.3048 0.9906) (xy 0.3048 0.9906) (xy 0.3048 -0.1016)
			)
			(stroke
				(width 0)
				(type default)
			)
			(fill no)
			(layer "B.CrtYd")
		)
		(fp_line
			(start -0.3048 -0.1016)
			(end 0.3048 -0.1016)
			(stroke
				(width 0.1)
				(type default)
			)
			(layer "B.Fab")
		)
		(fp_line
			(start -0.3048 0.9906)
			(end -0.3048 -0.1016)
			(stroke
				(width 0.1)
				(type default)
			)
			(layer "B.Fab")
		)
		(fp_line
			(start 0.3048 -0.1016)
			(end 0.3048 0.9906)
			(stroke
				(width 0.1)
				(type default)
			)
			(layer "B.Fab")
		)
		(fp_line
			(start 0.3048 0.9906)
			(end -0.3048 0.9906)
			(stroke
				(width 0.1)
				(type default)
			)
			(layer "B.Fab")
		)
		(pad "1" smd rect
			(at 0 0 180)
			(size 0.508 0.508)
			(layers "B.Cu" "B.Mask" "B.Paste")
			(net "P3E_CPU0_PE3_OCP_TXP<0>")
		)
		(pad "2" smd rect
			(at 0 0.889 180)
			(size 0.508 0.508)
			(layers "B.Cu" "B.Mask" "B.Paste")
			(net "P3E_OCP_CPU0_PE3_C_TXP<0>")
		)
		(zone
			(layer "B.Cu")
			(hatch none 0.5)
			(connect_pads
				(clearance 0)
			)
			(min_thickness 0.25)
			(keepout
				(tracks allowed)
				(vias not_allowed)
				(pads allowed)
				(copperpour not_allowed)
				(footprints allowed)
			)
			(placement
				(enabled no)
				(sheetname "")
			)
			(fill
				(thermal_gap 0.5)
				(thermal_bridge_width 0.5)
				(island_removal_mode 0)
			)
			(polygon
				(pts
					(xy 463.0674 -52.178458) (xy 462.5594 -52.178458) (xy 462.5594 -51.797458) (xy 463.0674 -51.797458)
				)
			)
		)
		(zone
			(layer "B.Cu")
			(hatch none 0.5)
			(connect_pads
				(clearance 0)
			)
			(min_thickness 0.25)
			(keepout
				(tracks not_allowed)
				(vias allowed)
				(pads allowed)
				(copperpour not_allowed)
				(footprints allowed)
			)
			(placement
				(enabled no)
				(sheetname "")
			)
			(fill
				(thermal_gap 0.5)
				(thermal_bridge_width 0.5)
				(island_removal_mode 0)
			)
			(polygon
				(pts
					(xy 463.0674 -51.797458) (xy 462.5594 -51.797458) (xy 462.5594 -52.178458) (xy 463.0674 -52.178458)
				)
			)
		)
	)
	(footprint ""
		(layer "B.Cu")
		(at 413.2326 -37.5412)
		(property "Reference" "C25W25"
			(at 0.8382 -0.67818 0)
			(unlocked yes)
			(layer "B.SilkS")
			(effects
				(font
					(size 0.4064 0.254)
					(thickness 0.1524)
				)
				(justify left mirror)
			)
		)
		(property "Value" ""
			(at 0 0 0)
			(layer "B.Fab")
			(effects
				(font
					(size 1.27 1.27)
				)
				(justify mirror)
			)
		)
		(duplicate_pad_numbers_are_jumpers no)
		(fp_poly
			(pts
				(xy -0.3048 -0.1016) (xy -0.3048 0.9906) (xy 0.3048 0.9906) (xy 0.3048 -0.1016)
			)
			(stroke
				(width 0)
				(type default)
			)
			(fill no)
			(layer "B.CrtYd")
		)
		(fp_line
			(start -0.3048 -0.1016)
			(end 0.3048 -0.1016)
			(stroke
				(width 0.1)
				(type default)
			)
			(layer "B.Fab")
		)
		(fp_line
			(start -0.3048 0.9906)
			(end -0.3048 -0.1016)
			(stroke
				(width 0.1)
				(type default)
			)
			(layer "B.Fab")
		)
		(fp_line
			(start 0.3048 -0.1016)
			(end 0.3048 0.9906)
			(stroke
				(width 0.1)
				(type default)
			)
			(layer "B.Fab")
		)
		(fp_line
			(start 0.3048 0.9906)
			(end -0.3048 0.9906)
			(stroke
				(width 0.1)
				(type default)
			)
			(layer "B.Fab")
		)
		(pad "1" smd rect
			(at 0 0 180)
			(size 0.508 0.508)
			(layers "B.Cu" "B.Mask" "B.Paste")
			(net "P1V15_AUX_BMC")
		)
		(pad "2" smd rect
			(at 0 0.889 180)
			(size 0.508 0.508)
			(layers "B.Cu" "B.Mask" "B.Paste")
			(net "GND")
		)
		(zone
			(layer "B.Cu")
			(hatch none 0.5)
			(connect_pads
				(clearance 0)
			)
			(min_thickness 0.25)
			(keepout
				(tracks allowed)
				(vias not_allowed)
				(pads allowed)
				(copperpour not_allowed)
				(footprints allowed)
			)
			(placement
				(enabled no)
				(sheetname "")
			)
			(fill
				(thermal_gap 0.5)
				(thermal_bridge_width 0.5)
				(island_removal_mode 0)
			)
			(polygon
				(pts
					(xy 413.4866 -37.2872) (xy 412.9786 -37.2872) (xy 412.9786 -36.9062) (xy 413.4866 -36.9062)
				)
			)
		)
		(zone
			(layer "B.Cu")
			(hatch none 0.5)
			(connect_pads
				(clearance 0)
			)
			(min_thickness 0.25)
			(keepout
				(tracks not_allowed)
				(vias allowed)
				(pads allowed)
				(copperpour not_allowed)
				(footprints allowed)
			)
			(placement
				(enabled no)
				(sheetname "")
			)
			(fill
				(thermal_gap 0.5)
				(thermal_bridge_width 0.5)
				(island_removal_mode 0)
			)
			(polygon
				(pts
					(xy 413.4866 -36.9062) (xy 412.9786 -36.9062) (xy 412.9786 -37.2872) (xy 413.4866 -37.2872)
				)
			)
		)
	)
	(footprint ""
		(layer "B.Cu")
		(at 320.194432 -8.128 90)
		(property "Reference" "C4U1"
			(at 0 0 90)
			(layer "B.SilkS")
			(hide yes)
			(effects
				(font
					(size 1.27 1.27)
				)
				(justify mirror)
			)
		)
		(property "Value" ""
			(at 0 0 90)
			(layer "B.Fab")
			(effects
				(font
					(size 1.27 1.27)
				)
				(justify mirror)
			)
		)
		(duplicate_pad_numbers_are_jumpers no)
		(fp_poly
			(pts
				(xy 0.4953 -0.2032) (xy -0.4953 -0.2032) (xy -0.4953 1.6002) (xy 0.4953 1.6002)
			)
			(stroke
				(width 0)
				(type default)
			)
			(fill no)
			(layer "B.CrtYd")
		)
		(fp_line
			(start 0.4953 -0.2032)
			(end -0.4953 -0.2032)
			(stroke
				(width 0.1)
				(type default)
			)
			(layer "B.Fab")
		)
		(fp_line
			(start -0.4953 -0.2032)
			(end -0.4953 1.6002)
			(stroke
				(width 0.1)
				(type default)
			)
			(layer "B.Fab")
		)
		(fp_line
			(start 0.4953 1.6002)
			(end 0.4953 -0.2032)
			(stroke
				(width 0.1)
				(type default)
			)
			(layer "B.Fab")
		)
		(fp_line
			(start -0.4953 1.6002)
			(end 0.4953 1.6002)
			(stroke
				(width 0.1)
				(type default)
			)
			(layer "B.Fab")
		)
		(pad "1" smd rect
			(at 0 0 270)
			(size 0.762 0.889)
			(layers "B.Cu" "B.Mask" "B.Paste")
			(net "PVPP_ABC")
		)
		(pad "2" smd rect
			(at 0 1.397 270)
			(size 0.762 0.889)
			(layers "B.Cu" "B.Mask" "B.Paste")
			(net "GND")
		)
		(zone
			(layer "B.Cu")
			(hatch none 0.5)
			(connect_pads
				(clearance 0)
			)
			(min_thickness 0.25)
			(keepout
				(tracks not_allowed)
				(vias allowed)
				(pads allowed)
				(copperpour not_allowed)
				(footprints allowed)
			)
			(placement
				(enabled no)
				(sheetname "")
			)
			(fill
				(thermal_gap 0.5)
				(thermal_bridge_width 0.5)
				(island_removal_mode 0)
			)
			(polygon
				(pts
					(xy 320.638932 -8.509) (xy 320.638932 -7.747) (xy 321.146932 -7.747) (xy 321.146932 -8.509)
				)
			)
		)
	)
	(footprint ""
		(layer "B.Cu")
		(at 0.889 -135.763 90)
		(property "Reference" "R9L9"
			(at 0 0 90)
			(layer "B.SilkS")
			(hide yes)
			(effects
				(font
					(size 1.27 1.27)
				)
				(justify mirror)
			)
		)
		(property "Value" ""
			(at 0 0 90)
			(layer "B.Fab")
			(effects
				(font
					(size 1.27 1.27)
				)
				(justify mirror)
			)
		)
		(duplicate_pad_numbers_are_jumpers no)
		(fp_rect
			(start 0.2794 -0.1016)
			(end -0.2794 0.9906)
			(stroke
				(width 0)
				(type default)
			)
			(fill no)
			(layer "B.CrtYd")
		)
		(fp_line
			(start 0.2794 -0.1016)
			(end 0.2794 0.9906)
			(stroke
				(width 0.1)
				(type default)
			)
			(layer "B.Fab")
		)
		(fp_line
			(start -0.2794 -0.1016)
			(end 0.2794 -0.1016)
			(stroke
				(width 0.1)
				(type default)
			)
			(layer "B.Fab")
		)
		(fp_line
			(start 0.2794 0.9906)
			(end -0.2794 0.9906)
			(stroke
				(width 0.1)
				(type default)
			)
			(layer "B.Fab")
		)
		(fp_line
			(start -0.2794 0.9906)
			(end -0.2794 -0.1016)
			(stroke
				(width 0.1)
				(type default)
			)
			(layer "B.Fab")
		)
		(pad "1" smd rect
			(at 0 0 270)
			(size 0.508 0.508)
			(layers "B.Cu" "B.Mask" "B.Paste")
			(net "VR_PVDDQ_KLM_PH1_VCIN")
		)
		(pad "2" smd rect
			(at 0 0.889 270)
			(size 0.508 0.508)
			(layers "B.Cu" "B.Mask" "B.Paste")
			(net "P5V_STBY")
		)
		(zone
			(layer "B.Cu")
			(hatch none 0.5)
			(connect_pads
				(clearance 0)
			)
			(min_thickness 0.25)
			(keepout
				(tracks allowed)
				(vias not_allowed)
				(pads allowed)
				(copperpour not_allowed)
				(footprints allowed)
			)
			(placement
				(enabled no)
				(sheetname "")
			)
			(fill
				(thermal_gap 0.5)
				(thermal_bridge_width 0.5)
				(island_removal_mode 0)
			)
			(polygon
				(pts
					(xy 1.143 -136.017) (xy 1.143 -135.509) (xy 1.524 -135.509) (xy 1.524 -136.017)
				)
			)
		)
		(zone
			(layer "B.Cu")
			(hatch none 0.5)
			(connect_pads
				(clearance 0)
			)
			(min_thickness 0.25)
			(keepout
				(tracks not_allowed)
				(vias allowed)
				(pads allowed)
				(copperpour not_allowed)
				(footprints allowed)
			)
			(placement
				(enabled no)
				(sheetname "")
			)
			(fill
				(thermal_gap 0.5)
				(thermal_bridge_width 0.5)
				(island_removal_mode 0)
			)
			(polygon
				(pts
					(xy 1.143 -136.017) (xy 1.143 -135.509) (xy 1.524 -135.509) (xy 1.524 -136.017)
				)
			)
		)
	)
	(footprint ""
		(layer "B.Cu")
		(at 345.8972 -112.7252 -90)
		(property "Reference" "C3M46"
			(at 0 0 90)
			(layer "B.SilkS")
			(hide yes)
			(effects
				(font
					(size 1.27 1.27)
				)
				(justify mirror)
			)
		)
		(property "Value" ""
			(at 0 0 90)
			(layer "B.Fab")
			(effects
				(font
					(size 1.27 1.27)
				)
				(justify mirror)
			)
		)
		(duplicate_pad_numbers_are_jumpers no)
		(fp_poly
			(pts
				(xy -0.3048 -0.1016) (xy -0.3048 0.9906) (xy 0.3048 0.9906) (xy 0.3048 -0.1016)
			)
			(stroke
				(width 0)
				(type default)
			)
			(fill no)
			(layer "B.CrtYd")
		)
		(fp_line
			(start -0.3048 0.9906)
			(end -0.3048 -0.1016)
			(stroke
				(width 0.1)
				(type default)
			)
			(layer "B.Fab")
		)
		(fp_line
			(start 0.3048 0.9906)
			(end -0.3048 0.9906)
			(stroke
				(width 0.1)
				(type default)
			)
			(layer "B.Fab")
		)
		(fp_line
			(start -0.3048 -0.1016)
			(end 0.3048 -0.1016)
			(stroke
				(width 0.1)
				(type default)
			)
			(layer "B.Fab")
		)
		(fp_line
			(start 0.3048 -0.1016)
			(end 0.3048 0.9906)
			(stroke
				(width 0.1)
				(type default)
			)
			(layer "B.Fab")
		)
		(pad "1" smd rect
			(at 0 0 90)
			(size 0.508 0.508)
			(layers "B.Cu" "B.Mask" "B.Paste")
			(net "PVCCIOMCP_CPU0")
		)
		(pad "2" smd rect
			(at 0 0.889 90)
			(size 0.508 0.508)
			(layers "B.Cu" "B.Mask" "B.Paste")
			(net "GND")
		)
		(zone
			(layer "B.Cu")
			(hatch none 0.5)
			(connect_pads
				(clearance 0)
			)
			(min_thickness 0.25)
			(keepout
				(tracks not_allowed)
				(vias allowed)
				(pads allowed)
				(copperpour not_allowed)
				(footprints allowed)
			)
			(placement
				(enabled no)
				(sheetname "")
			)
			(fill
				(thermal_gap 0.5)
				(thermal_bridge_width 0.5)
				(island_removal_mode 0)
			)
			(polygon
				(pts
					(xy 345.2622 -112.4712) (xy 345.2622 -112.9792) (xy 345.6432 -112.9792) (xy 345.6432 -112.4712)
				)
			)
		)
		(zone
			(layer "B.Cu")
			(hatch none 0.5)
			(connect_pads
				(clearance 0)
			)
			(min_thickness 0.25)
			(keepout
				(tracks allowed)
				(vias not_allowed)
				(pads allowed)
				(copperpour not_allowed)
				(footprints allowed)
			)
			(placement
				(enabled no)
				(sheetname "")
			)
			(fill
				(thermal_gap 0.5)
				(thermal_bridge_width 0.5)
				(island_removal_mode 0)
			)
			(polygon
				(pts
					(xy 345.6432 -112.4712) (xy 345.6432 -112.9792) (xy 345.2622 -112.9792) (xy 345.2622 -112.4712)
				)
			)
		)
	)
	(footprint ""
		(layer "B.Cu")
		(at 470.027 -60.198 -90)
		(property "Reference" "R1R19"
			(at 0 0 90)
			(layer "B.SilkS")
			(hide yes)
			(effects
				(font
					(size 1.27 1.27)
				)
				(justify mirror)
			)
		)
		(property "Value" ""
			(at 0 0 90)
			(layer "B.Fab")
			(effects
				(font
					(size 1.27 1.27)
				)
				(justify mirror)
			)
		)
		(duplicate_pad_numbers_are_jumpers no)
		(fp_poly
			(pts
				(xy 0.2794 -0.1016) (xy -0.2794 -0.1016) (xy -0.2794 0.9906) (xy 0.2794 0.9906)
			)
			(stroke
				(width 0)
				(type default)
			)
			(fill no)
			(layer "B.CrtYd")
		)
		(fp_line
			(start -0.2794 0.9906)
			(end -0.2794 -0.1016)
			(stroke
				(width 0.1)
				(type default)
			)
			(layer "B.Fab")
		)
		(fp_line
			(start 0.2794 0.9906)
			(end -0.2794 0.9906)
			(stroke
				(width 0.1)
				(type default)
			)
			(layer "B.Fab")
		)
		(fp_line
			(start -0.2794 -0.1016)
			(end 0.2794 -0.1016)
			(stroke
				(width 0.1)
				(type default)
			)
			(layer "B.Fab")
		)
		(fp_line
			(start 0.2794 -0.1016)
			(end 0.2794 0.9906)
			(stroke
				(width 0.1)
				(type default)
			)
			(layer "B.Fab")
		)
		(pad "1" smd rect
			(at 0 0 90)
			(size 0.508 0.508)
			(layers "B.Cu" "B.Mask" "B.Paste")
			(net "P3V3_STBY")
		)
		(pad "2" smd rect
			(at 0 0.889 90)
			(size 0.508 0.508)
			(layers "B.Cu" "B.Mask" "B.Paste")
			(net "SMB_PCH_MEZZ_LOM0_SDA")
		)
		(zone
			(layer "B.Cu")
			(hatch none 0.5)
			(connect_pads
				(clearance 0)
			)
			(min_thickness 0.25)
			(keepout
				(tracks not_allowed)
				(vias allowed)
				(pads allowed)
				(copperpour not_allowed)
				(footprints allowed)
			)
			(placement
				(enabled no)
				(sheetname "")
			)
			(fill
				(thermal_gap 0.5)
				(thermal_bridge_width 0.5)
				(island_removal_mode 0)
			)
			(polygon
				(pts
					(xy 469.392 -59.944) (xy 469.392 -60.452) (xy 469.773 -60.452) (xy 469.773 -59.944)
				)
			)
		)
		(zone
			(layer "B.Cu")
			(hatch none 0.5)
			(connect_pads
				(clearance 0)
			)
			(min_thickness 0.25)
			(keepout
				(tracks allowed)
				(vias not_allowed)
				(pads allowed)
				(copperpour not_allowed)
				(footprints allowed)
			)
			(placement
				(enabled no)
				(sheetname "")
			)
			(fill
				(thermal_gap 0.5)
				(thermal_bridge_width 0.5)
				(island_removal_mode 0)
			)
			(polygon
				(pts
					(xy 469.773 -59.944) (xy 469.773 -60.452) (xy 469.392 -60.452) (xy 469.392 -59.944)
				)
			)
		)
	)
	(footprint ""
		(layer "B.Cu")
		(at 197.866 -98.933 90)
		(property "Reference" "C6N3"
			(at 0 0 90)
			(layer "B.SilkS")
			(hide yes)
			(effects
				(font
					(size 1.27 1.27)
				)
				(justify mirror)
			)
		)
		(property "Value" ""
			(at 0 0 90)
			(layer "B.Fab")
			(effects
				(font
					(size 1.27 1.27)
				)
				(justify mirror)
			)
		)
		(duplicate_pad_numbers_are_jumpers no)
		(fp_rect
			(start 0.7239 1.9939)
			(end -0.7239 -0.2159)
			(stroke
				(width 0)
				(type default)
			)
			(fill no)
			(layer "B.CrtYd")
		)
		(fp_line
			(start 0.7239 -0.2159)
			(end 0.7239 1.9939)
			(stroke
				(width 0.1)
				(type default)
			)
			(layer "B.Fab")
		)
		(fp_line
			(start -0.7239 -0.2159)
			(end 0.7239 -0.2159)
			(stroke
				(width 0.1)
				(type default)
			)
			(layer "B.Fab")
		)
		(fp_line
			(start 0.7239 1.9939)
			(end -0.7239 1.9939)
			(stroke
				(width 0.1)
				(type default)
			)
			(layer "B.Fab")
		)
		(fp_line
			(start -0.7239 1.9939)
			(end -0.7239 -0.2159)
			(stroke
				(width 0.1)
				(type default)
			)
			(layer "B.Fab")
		)
		(pad "1" smd rect
			(at 0 0 270)
			(size 1.27 1.016)
			(layers "B.Cu" "B.Mask" "B.Paste")
			(net "VR_FET_SW_P12V_STBY_PVCCIN_CPU0")
		)
		(pad "2" smd rect
			(at 0 1.778 270)
			(size 1.27 1.016)
			(layers "B.Cu" "B.Mask" "B.Paste")
			(net "GND")
		)
		(zone
			(layer "B.Cu")
			(hatch none 0.5)
			(connect_pads
				(clearance 0)
			)
			(min_thickness 0.25)
			(keepout
				(tracks not_allowed)
				(vias allowed)
				(pads allowed)
				(copperpour not_allowed)
				(footprints allowed)
			)
			(placement
				(enabled no)
				(sheetname "")
			)
			(fill
				(thermal_gap 0.5)
				(thermal_bridge_width 0.5)
				(island_removal_mode 0)
			)
			(polygon
				(pts
					(xy 199.136 -99.568) (xy 198.374 -99.568) (xy 198.374 -98.298) (xy 199.136 -98.298)
				)
			)
		)
	)
	(footprint ""
		(layer "B.Cu")
		(at 394.335 -67.056 90)
		(property "Reference" "R7W5"
			(at 0.8382 -0.67818 90)
			(unlocked yes)
			(layer "B.SilkS")
			(effects
				(font
					(size 0.4064 0.254)
					(thickness 0.1524)
				)
				(justify left mirror)
			)
		)
		(property "Value" ""
			(at 0 0 90)
			(layer "B.Fab")
			(effects
				(font
					(size 1.27 1.27)
				)
				(justify mirror)
			)
		)
		(duplicate_pad_numbers_are_jumpers no)
		(fp_poly
			(pts
				(xy 0.2794 -0.1016) (xy -0.2794 -0.1016) (xy -0.2794 0.9906) (xy 0.2794 0.9906)
			)
			(stroke
				(width 0)
				(type default)
			)
			(fill no)
			(layer "B.CrtYd")
		)
		(fp_line
			(start 0.2794 -0.1016)
			(end 0.2794 0.9906)
			(stroke
				(width 0.1)
				(type default)
			)
			(layer "B.Fab")
		)
		(fp_line
			(start -0.2794 -0.1016)
			(end 0.2794 -0.1016)
			(stroke
				(width 0.1)
				(type default)
			)
			(layer "B.Fab")
		)
		(fp_line
			(start 0.2794 0.9906)
			(end -0.2794 0.9906)
			(stroke
				(width 0.1)
				(type default)
			)
			(layer "B.Fab")
		)
		(fp_line
			(start -0.2794 0.9906)
			(end -0.2794 -0.1016)
			(stroke
				(width 0.1)
				(type default)
			)
			(layer "B.Fab")
		)
		(pad "1" smd rect
			(at 0 0 270)
			(size 0.508 0.508)
			(layers "B.Cu" "B.Mask" "B.Paste")
			(net "SPI_SWITCH_CS0_N")
		)
		(pad "2" smd rect
			(at 0 0.889 270)
			(size 0.508 0.508)
			(layers "B.Cu" "B.Mask" "B.Paste")
			(net "SPI_CS0_PRIMARY_R_N")
		)
		(zone
			(layer "B.Cu")
			(hatch none 0.5)
			(connect_pads
				(clearance 0)
			)
			(min_thickness 0.25)
			(keepout
				(tracks allowed)
				(vias not_allowed)
				(pads allowed)
				(copperpour not_allowed)
				(footprints allowed)
			)
			(placement
				(enabled no)
				(sheetname "")
			)
			(fill
				(thermal_gap 0.5)
				(thermal_bridge_width 0.5)
				(island_removal_mode 0)
			)
			(polygon
				(pts
					(xy 394.589 -67.31) (xy 394.589 -66.802) (xy 394.97 -66.802) (xy 394.97 -67.31)
				)
			)
		)
		(zone
			(layer "B.Cu")
			(hatch none 0.5)
			(connect_pads
				(clearance 0)
			)
			(min_thickness 0.25)
			(keepout
				(tracks not_allowed)
				(vias allowed)
				(pads allowed)
				(copperpour not_allowed)
				(footprints allowed)
			)
			(placement
				(enabled no)
				(sheetname "")
			)
			(fill
				(thermal_gap 0.5)
				(thermal_bridge_width 0.5)
				(island_removal_mode 0)
			)
			(polygon
				(pts
					(xy 394.97 -67.31) (xy 394.97 -66.802) (xy 394.589 -66.802) (xy 394.589 -67.31)
				)
			)
		)
	)
	(footprint ""
		(layer "B.Cu")
		(at 488.3531 -41.4274 -90)
		(property "Reference" "R1R12"
			(at 0 0 90)
			(layer "B.SilkS")
			(hide yes)
			(effects
				(font
					(size 1.27 1.27)
				)
				(justify mirror)
			)
		)
		(property "Value" ""
			(at 0 0 90)
			(layer "B.Fab")
			(effects
				(font
					(size 1.27 1.27)
				)
				(justify mirror)
			)
		)
		(duplicate_pad_numbers_are_jumpers no)
		(fp_poly
			(pts
				(xy 0.2794 -0.1016) (xy -0.2794 -0.1016) (xy -0.2794 0.9906) (xy 0.2794 0.9906)
			)
			(stroke
				(width 0)
				(type default)
			)
			(fill no)
			(layer "B.CrtYd")
		)
		(fp_line
			(start -0.2794 0.9906)
			(end -0.2794 -0.1016)
			(stroke
				(width 0.1)
				(type default)
			)
			(layer "B.Fab")
		)
		(fp_line
			(start 0.2794 0.9906)
			(end -0.2794 0.9906)
			(stroke
				(width 0.1)
				(type default)
			)
			(layer "B.Fab")
		)
		(fp_line
			(start -0.2794 -0.1016)
			(end 0.2794 -0.1016)
			(stroke
				(width 0.1)
				(type default)
			)
			(layer "B.Fab")
		)
		(fp_line
			(start 0.2794 -0.1016)
			(end 0.2794 0.9906)
			(stroke
				(width 0.1)
				(type default)
			)
			(layer "B.Fab")
		)
		(pad "1" smd rect
			(at 0 0 90)
			(size 0.508 0.508)
			(layers "B.Cu" "B.Mask" "B.Paste")
			(net "CLK_50M_CKMNG_SPRVLLE")
		)
		(pad "2" smd rect
			(at 0 0.889 90)
			(size 0.508 0.508)
			(layers "B.Cu" "B.Mask" "B.Paste")
			(net "GND")
		)
		(zone
			(layer "B.Cu")
			(hatch none 0.5)
			(connect_pads
				(clearance 0)
			)
			(min_thickness 0.25)
			(keepout
				(tracks not_allowed)
				(vias allowed)
				(pads allowed)
				(copperpour not_allowed)
				(footprints allowed)
			)
			(placement
				(enabled no)
				(sheetname "")
			)
			(fill
				(thermal_gap 0.5)
				(thermal_bridge_width 0.5)
				(island_removal_mode 0)
			)
			(polygon
				(pts
					(xy 487.7181 -41.1734) (xy 487.7181 -41.6814) (xy 488.0991 -41.6814) (xy 488.0991 -41.1734)
				)
			)
		)
		(zone
			(layer "B.Cu")
			(hatch none 0.5)
			(connect_pads
				(clearance 0)
			)
			(min_thickness 0.25)
			(keepout
				(tracks allowed)
				(vias not_allowed)
				(pads allowed)
				(copperpour not_allowed)
				(footprints allowed)
			)
			(placement
				(enabled no)
				(sheetname "")
			)
			(fill
				(thermal_gap 0.5)
				(thermal_bridge_width 0.5)
				(island_removal_mode 0)
			)
			(polygon
				(pts
					(xy 488.0991 -41.1734) (xy 488.0991 -41.6814) (xy 487.7181 -41.6814) (xy 487.7181 -41.1734)
				)
			)
		)
	)
	(footprint ""
		(layer "B.Cu")
		(at 375.3612 -156.337 -90)
		(property "Reference" "R3L15"
			(at 0 0 90)
			(layer "B.SilkS")
			(hide yes)
			(effects
				(font
					(size 1.27 1.27)
				)
				(justify mirror)
			)
		)
		(property "Value" ""
			(at 0 0 90)
			(layer "B.Fab")
			(effects
				(font
					(size 1.27 1.27)
				)
				(justify mirror)
			)
		)
		(duplicate_pad_numbers_are_jumpers no)
		(fp_poly
			(pts
				(xy 0.2794 -0.1016) (xy -0.2794 -0.1016) (xy -0.2794 0.9906) (xy 0.2794 0.9906)
			)
			(stroke
				(width 0)
				(type default)
			)
			(fill no)
			(layer "B.CrtYd")
		)
		(fp_line
			(start -0.2794 0.9906)
			(end -0.2794 -0.1016)
			(stroke
				(width 0.1)
				(type default)
			)
			(layer "B.Fab")
		)
		(fp_line
			(start 0.2794 0.9906)
			(end -0.2794 0.9906)
			(stroke
				(width 0.1)
				(type default)
			)
			(layer "B.Fab")
		)
		(fp_line
			(start -0.2794 -0.1016)
			(end 0.2794 -0.1016)
			(stroke
				(width 0.1)
				(type default)
			)
			(layer "B.Fab")
		)
		(fp_line
			(start 0.2794 -0.1016)
			(end 0.2794 0.9906)
			(stroke
				(width 0.1)
				(type default)
			)
			(layer "B.Fab")
		)
		(pad "1" smd rect
			(at 0 0 90)
			(size 0.508 0.508)
			(layers "B.Cu" "B.Mask" "B.Paste")
			(net "VR_PVNN_PCH_STBY_OCSET")
		)
		(pad "2" smd rect
			(at 0 0.889 90)
			(size 0.508 0.508)
			(layers "B.Cu" "B.Mask" "B.Paste")
			(net "GND")
		)
		(zone
			(layer "B.Cu")
			(hatch none 0.5)
			(connect_pads
				(clearance 0)
			)
			(min_thickness 0.25)
			(keepout
				(tracks not_allowed)
				(vias allowed)
				(pads allowed)
				(copperpour not_allowed)
				(footprints allowed)
			)
			(placement
				(enabled no)
				(sheetname "")
			)
			(fill
				(thermal_gap 0.5)
				(thermal_bridge_width 0.5)
				(island_removal_mode 0)
			)
			(polygon
				(pts
					(xy 374.7262 -156.083) (xy 374.7262 -156.591) (xy 375.1072 -156.591) (xy 375.1072 -156.083)
				)
			)
		)
		(zone
			(layer "B.Cu")
			(hatch none 0.5)
			(connect_pads
				(clearance 0)
			)
			(min_thickness 0.25)
			(keepout
				(tracks allowed)
				(vias not_allowed)
				(pads allowed)
				(copperpour not_allowed)
				(footprints allowed)
			)
			(placement
				(enabled no)
				(sheetname "")
			)
			(fill
				(thermal_gap 0.5)
				(thermal_bridge_width 0.5)
				(island_removal_mode 0)
			)
			(polygon
				(pts
					(xy 375.1072 -156.083) (xy 375.1072 -156.591) (xy 374.7262 -156.591) (xy 374.7262 -156.083)
				)
			)
		)
	)
	(footprint ""
		(layer "B.Cu")
		(at 259.6642 -17.5514 90)
		(property "Reference" "C5U1"
			(at 0 0 90)
			(layer "B.SilkS")
			(hide yes)
			(effects
				(font
					(size 1.27 1.27)
				)
				(justify mirror)
			)
		)
		(property "Value" ""
			(at 0 0 90)
			(layer "B.Fab")
			(effects
				(font
					(size 1.27 1.27)
				)
				(justify mirror)
			)
		)
		(duplicate_pad_numbers_are_jumpers no)
		(fp_rect
			(start -0.7239 -0.2159)
			(end 0.7239 1.9939)
			(stroke
				(width 0)
				(type default)
			)
			(fill no)
			(layer "B.CrtYd")
		)
		(fp_line
			(start 0.7239 -0.2159)
			(end 0.7239 1.9939)
			(stroke
				(width 0.1)
				(type default)
			)
			(layer "B.Fab")
		)
		(fp_line
			(start -0.7239 -0.2159)
			(end 0.7239 -0.2159)
			(stroke
				(width 0.1)
				(type default)
			)
			(layer "B.Fab")
		)
		(fp_line
			(start 0.7239 1.9939)
			(end -0.7239 1.9939)
			(stroke
				(width 0.1)
				(type default)
			)
			(layer "B.Fab")
		)
		(fp_line
			(start -0.7239 1.9939)
			(end -0.7239 -0.2159)
			(stroke
				(width 0.1)
				(type default)
			)
			(layer "B.Fab")
		)
		(pad "1" smd rect
			(at 0 0 270)
			(size 1.27 1.016)
			(layers "B.Cu" "B.Mask" "B.Paste")
			(net "PVDDQ_ABC")
		)
		(pad "2" smd rect
			(at 0 1.778 270)
			(size 1.27 1.016)
			(layers "B.Cu" "B.Mask" "B.Paste")
			(net "GND")
		)
		(zone
			(layer "B.Cu")
			(hatch none 0.5)
			(connect_pads
				(clearance 0)
			)
			(min_thickness 0.25)
			(keepout
				(tracks not_allowed)
				(vias allowed)
				(pads allowed)
				(copperpour not_allowed)
				(footprints allowed)
			)
			(placement
				(enabled no)
				(sheetname "")
			)
			(fill
				(thermal_gap 0.5)
				(thermal_bridge_width 0.5)
				(island_removal_mode 0)
			)
			(polygon
				(pts
					(xy 260.1722 -16.9164) (xy 260.9342 -16.9164) (xy 260.9342 -18.1864) (xy 260.1722 -18.1864)
				)
			)
		)
	)
	(footprint ""
		(layer "B.Cu")
		(at 387.73735 -111.05515 180)
		(property "Reference" "C3N4"
			(at 0 0 0)
			(layer "B.SilkS")
			(hide yes)
			(effects
				(font
					(size 1.27 1.27)
				)
				(justify mirror)
			)
		)
		(property "Value" ""
			(at 0 0 0)
			(layer "B.Fab")
			(effects
				(font
					(size 1.27 1.27)
				)
				(justify mirror)
			)
		)
		(duplicate_pad_numbers_are_jumpers no)
		(fp_rect
			(start 0.2794 0.9144)
			(end -0.2794 -0.1143)
			(stroke
				(width 0)
				(type default)
			)
			(fill no)
			(layer "B.CrtYd")
		)
		(fp_line
			(start 0.2794 0.9144)
			(end 0.2794 -0.1143)
			(stroke
				(width 0.1)
				(type default)
			)
			(layer "B.Fab")
		)
		(fp_line
			(start 0.2794 -0.1143)
			(end -0.2794 -0.1143)
			(stroke
				(width 0.1)
				(type default)
			)
			(layer "B.Fab")
		)
		(fp_line
			(start -0.2794 0.9144)
			(end 0.2794 0.9144)
			(stroke
				(width 0.1)
				(type default)
			)
			(layer "B.Fab")
		)
		(fp_line
			(start -0.2794 -0.1143)
			(end -0.2794 0.9144)
			(stroke
				(width 0.1)
				(type default)
			)
			(layer "B.Fab")
		)
		(pad "1" smd custom
			(at 0 0 90)
			(size 0.10414 0.10414)
			(layers "B.Cu" "B.Mask" "B.Paste")
			(net "PVNN_PCH_STBY")
			(options
				(clearance outline)
				(anchor circle)
			)
			(primitives
				(gr_poly
					(pts
						(xy -0.20828 -0.08636) (xy -0.20828 0.08636) (xy -0.08636 0.20828) (xy 0.086614 0.20828) (xy 0.20828 0.086614)
						(xy 0.20828 -0.08636) (xy 0.08636 -0.20828) (xy -0.08636 -0.20828)
					)
					(width 0)
					(fill yes)
				)
			)
		)
		(pad "2" smd custom
			(at 0 0.8001 90)
			(size 0.10414 0.10414)
			(layers "B.Cu" "B.Mask" "B.Paste")
			(net "GND")
			(options
				(clearance outline)
				(anchor circle)
			)
			(primitives
				(gr_poly
					(pts
						(xy -0.20828 -0.08636) (xy -0.20828 0.08636) (xy -0.08636 0.20828) (xy 0.086614 0.20828) (xy 0.20828 0.086614)
						(xy 0.20828 -0.08636) (xy 0.08636 -0.20828) (xy -0.08636 -0.20828)
					)
					(width 0)
					(fill yes)
				)
			)
		)
		(zone
			(layer "B.Cu")
			(hatch none 0.5)
			(connect_pads
				(clearance 0)
			)
			(min_thickness 0.25)
			(keepout
				(tracks allowed)
				(vias not_allowed)
				(pads allowed)
				(copperpour not_allowed)
				(footprints allowed)
			)
			(placement
				(enabled no)
				(sheetname "")
			)
			(fill
				(thermal_gap 0.5)
				(thermal_bridge_width 0.5)
				(island_removal_mode 0)
			)
			(polygon
				(pts
					(xy 387.64972 -111.2647) (xy 387.64972 -111.6457) (xy 387.82498 -111.6457) (xy 387.825234 -111.2647)
				)
			)
		)
		(zone
			(layer "B.Cu")
			(hatch none 0.5)
			(connect_pads
				(clearance 0)
			)
			(min_thickness 0.25)
			(keepout
				(tracks not_allowed)
				(vias allowed)
				(pads allowed)
				(copperpour not_allowed)
				(footprints allowed)
			)
			(placement
				(enabled no)
				(sheetname "")
			)
			(fill
				(thermal_gap 0.5)
				(thermal_bridge_width 0.5)
				(island_removal_mode 0)
			)
			(polygon
				(pts
					(xy 387.64972 -111.2647) (xy 387.64972 -111.6457) (xy 387.82498 -111.6457) (xy 387.825234 -111.2647)
				)
			)
		)
	)
	(footprint ""
		(layer "B.Cu")
		(at 80.153002 -87.632286 -90)
		(property "Reference" "R8P1"
			(at 0 0 90)
			(layer "B.SilkS")
			(hide yes)
			(effects
				(font
					(size 1.27 1.27)
				)
				(justify mirror)
			)
		)
		(property "Value" ""
			(at 0 0 90)
			(layer "B.Fab")
			(effects
				(font
					(size 1.27 1.27)
				)
				(justify mirror)
			)
		)
		(duplicate_pad_numbers_are_jumpers no)
		(fp_poly
			(pts
				(xy 0.2794 -0.1016) (xy -0.2794 -0.1016) (xy -0.2794 0.9906) (xy 0.2794 0.9906)
			)
			(stroke
				(width 0)
				(type default)
			)
			(fill no)
			(layer "B.CrtYd")
		)
		(fp_line
			(start -0.2794 0.9906)
			(end -0.2794 -0.1016)
			(stroke
				(width 0.1)
				(type default)
			)
			(layer "B.Fab")
		)
		(fp_line
			(start 0.2794 0.9906)
			(end -0.2794 0.9906)
			(stroke
				(width 0.1)
				(type default)
			)
			(layer "B.Fab")
		)
		(fp_line
			(start -0.2794 -0.1016)
			(end 0.2794 -0.1016)
			(stroke
				(width 0.1)
				(type default)
			)
			(layer "B.Fab")
		)
		(fp_line
			(start 0.2794 -0.1016)
			(end 0.2794 0.9906)
			(stroke
				(width 0.1)
				(type default)
			)
			(layer "B.Fab")
		)
		(pad "1" smd rect
			(at 0 0 90)
			(size 0.508 0.508)
			(layers "B.Cu" "B.Mask" "B.Paste")
			(net "PD_CPU1_TEST14")
		)
		(pad "2" smd rect
			(at 0 0.889 90)
			(size 0.508 0.508)
			(layers "B.Cu" "B.Mask" "B.Paste")
			(net "GND")
		)
		(zone
			(layer "B.Cu")
			(hatch none 0.5)
			(connect_pads
				(clearance 0)
			)
			(min_thickness 0.25)
			(keepout
				(tracks not_allowed)
				(vias allowed)
				(pads allowed)
				(copperpour not_allowed)
				(footprints allowed)
			)
			(placement
				(enabled no)
				(sheetname "")
			)
			(fill
				(thermal_gap 0.5)
				(thermal_bridge_width 0.5)
				(island_removal_mode 0)
			)
			(polygon
				(pts
					(xy 79.518002 -87.378286) (xy 79.518002 -87.886286) (xy 79.899002 -87.886286) (xy 79.899002 -87.378286)
				)
			)
		)
		(zone
			(layer "B.Cu")
			(hatch none 0.5)
			(connect_pads
				(clearance 0)
			)
			(min_thickness 0.25)
			(keepout
				(tracks allowed)
				(vias not_allowed)
				(pads allowed)
				(copperpour not_allowed)
				(footprints allowed)
			)
			(placement
				(enabled no)
				(sheetname "")
			)
			(fill
				(thermal_gap 0.5)
				(thermal_bridge_width 0.5)
				(island_removal_mode 0)
			)
			(polygon
				(pts
					(xy 79.899002 -87.378286) (xy 79.899002 -87.886286) (xy 79.518002 -87.886286) (xy 79.518002 -87.378286)
				)
			)
		)
	)
	(footprint ""
		(layer "B.Cu")
		(at 229.3747 -64.6303 180)
		(property "Reference" "R4E18"
			(at 0 0 0)
			(layer "B.SilkS")
			(hide yes)
			(effects
				(font
					(size 1.27 1.27)
				)
				(justify mirror)
			)
		)
		(property "Value" ""
			(at 0 0 0)
			(layer "B.Fab")
			(effects
				(font
					(size 1.27 1.27)
				)
				(justify mirror)
			)
		)
		(duplicate_pad_numbers_are_jumpers no)
		(fp_poly
			(pts
				(xy 0.2794 -0.1016) (xy -0.2794 -0.1016) (xy -0.2794 0.9906) (xy 0.2794 0.9906)
			)
			(stroke
				(width 0)
				(type default)
			)
			(fill no)
			(layer "B.CrtYd")
		)
		(fp_line
			(start 0.2794 0.9906)
			(end -0.2794 0.9906)
			(stroke
				(width 0.1)
				(type default)
			)
			(layer "B.Fab")
		)
		(fp_line
			(start 0.2794 -0.1016)
			(end 0.2794 0.9906)
			(stroke
				(width 0.1)
				(type default)
			)
			(layer "B.Fab")
		)
		(fp_line
			(start -0.2794 0.9906)
			(end -0.2794 -0.1016)
			(stroke
				(width 0.1)
				(type default)
			)
			(layer "B.Fab")
		)
		(fp_line
			(start -0.2794 -0.1016)
			(end 0.2794 -0.1016)
			(stroke
				(width 0.1)
				(type default)
			)
			(layer "B.Fab")
		)
		(pad "1" smd rect
			(at 0 0)
			(size 0.508 0.508)
			(layers "B.Cu" "B.Mask" "B.Paste")
			(net "VSENSE_PVCCIN_CPU0_N")
		)
		(pad "2" smd rect
			(at 0 0.889)
			(size 0.508 0.508)
			(layers "B.Cu" "B.Mask" "B.Paste")
			(net "GND")
		)
		(zone
			(layer "B.Cu")
			(hatch none 0.5)
			(connect_pads
				(clearance 0)
			)
			(min_thickness 0.25)
			(keepout
				(tracks not_allowed)
				(vias allowed)
				(pads allowed)
				(copperpour not_allowed)
				(footprints allowed)
			)
			(placement
				(enabled no)
				(sheetname "")
			)
			(fill
				(thermal_gap 0.5)
				(thermal_bridge_width 0.5)
				(island_removal_mode 0)
			)
			(polygon
				(pts
					(xy 229.1207 -65.2653) (xy 229.6287 -65.2653) (xy 229.6287 -64.8843) (xy 229.1207 -64.8843)
				)
			)
		)
		(zone
			(layer "B.Cu")
			(hatch none 0.5)
			(connect_pads
				(clearance 0)
			)
			(min_thickness 0.25)
			(keepout
				(tracks allowed)
				(vias not_allowed)
				(pads allowed)
				(copperpour not_allowed)
				(footprints allowed)
			)
			(placement
				(enabled no)
				(sheetname "")
			)
			(fill
				(thermal_gap 0.5)
				(thermal_bridge_width 0.5)
				(island_removal_mode 0)
			)
			(polygon
				(pts
					(xy 229.1207 -64.8843) (xy 229.6287 -64.8843) (xy 229.6287 -65.2653) (xy 229.1207 -65.2653)
				)
			)
		)
	)
	(footprint ""
		(layer "B.Cu")
		(at 80.731868 -149.8092 -90)
		(property "Reference" "C5G101"
			(at -1.14681 0.76708 0)
			(unlocked yes)
			(layer "B.SilkS")
			(effects
				(font
					(size 0.7874 0.5842)
					(thickness 0.1524)
				)
				(justify mirror)
			)
		)
		(property "Value" ""
			(at 0 0 90)
			(layer "B.Fab")
			(effects
				(font
					(size 1.27 1.27)
				)
				(justify mirror)
			)
		)
		(duplicate_pad_numbers_are_jumpers no)
		(fp_rect
			(start 0.4953 1.6002)
			(end -0.4953 -0.2032)
			(stroke
				(width 0)
				(type default)
			)
			(fill no)
			(layer "B.CrtYd")
		)
		(fp_line
			(start -0.4953 1.6002)
			(end 0.4953 1.6002)
			(stroke
				(width 0.1)
				(type default)
			)
			(layer "B.Fab")
		)
		(fp_line
			(start 0.4953 1.6002)
			(end 0.4953 -0.2032)
			(stroke
				(width 0.1)
				(type default)
			)
			(layer "B.Fab")
		)
		(fp_line
			(start -0.4953 -0.2032)
			(end -0.4953 1.6002)
			(stroke
				(width 0.1)
				(type default)
			)
			(layer "B.Fab")
		)
		(fp_line
			(start 0.4953 -0.2032)
			(end -0.4953 -0.2032)
			(stroke
				(width 0.1)
				(type default)
			)
			(layer "B.Fab")
		)
		(pad "1" smd rect
			(at 0 0 90)
			(size 0.762 0.889)
			(layers "B.Cu" "B.Mask" "B.Paste")
			(net "PVDDQ_KLM")
		)
		(pad "2" smd rect
			(at 0 1.397 90)
			(size 0.762 0.889)
			(layers "B.Cu" "B.Mask" "B.Paste")
			(net "GND")
		)
		(zone
			(layer "B.Cu")
			(hatch none 0.5)
			(connect_pads
				(clearance 0)
			)
			(min_thickness 0.25)
			(keepout
				(tracks not_allowed)
				(vias allowed)
				(pads allowed)
				(copperpour not_allowed)
				(footprints allowed)
			)
			(placement
				(enabled no)
				(sheetname "")
			)
			(fill
				(thermal_gap 0.5)
				(thermal_bridge_width 0.5)
				(island_removal_mode 0)
			)
			(polygon
				(pts
					(xy 79.779368 -149.4282) (xy 80.287368 -149.4282) (xy 80.287368 -150.1902) (xy 79.779368 -150.1902)
				)
			)
		)
	)
	(footprint ""
		(layer "B.Cu")
		(at 266.397232 -8.1534 90)
		(property "Reference" "C5U5"
			(at -1.848866 0.752348 90)
			(unlocked yes)
			(layer "B.SilkS")
			(effects
				(font
					(size 1.27 0.9652)
					(thickness 0.1524)
				)
				(justify mirror)
			)
		)
		(property "Value" ""
			(at 0 0 90)
			(layer "B.Fab")
			(effects
				(font
					(size 1.27 1.27)
				)
				(justify mirror)
			)
		)
		(duplicate_pad_numbers_are_jumpers no)
		(fp_rect
			(start 0.500126 1.598422)
			(end -0.500126 -0.201422)
			(stroke
				(width 0)
				(type default)
			)
			(fill no)
			(layer "B.CrtYd")
		)
		(fp_line
			(start 0.500126 -0.201422)
			(end -0.500126 -0.201422)
			(stroke
				(width 0.1)
				(type default)
			)
			(layer "B.Fab")
		)
		(fp_line
			(start -0.500126 -0.201422)
			(end -0.500126 1.598422)
			(stroke
				(width 0.1)
				(type default)
			)
			(layer "B.Fab")
		)
		(fp_line
			(start 0.500126 1.598422)
			(end 0.500126 -0.201422)
			(stroke
				(width 0.1)
				(type default)
			)
			(layer "B.Fab")
		)
		(fp_line
			(start -0.500126 1.598422)
			(end 0.500126 1.598422)
			(stroke
				(width 0.1)
				(type default)
			)
			(layer "B.Fab")
		)
		(pad "1" smd rect
			(at 0 0)
			(size 0.889 0.9906)
			(layers "B.Cu" "B.Mask" "B.Paste")
			(net "PVDDQ_ABC")
		)
		(pad "2" smd rect
			(at 0 1.397)
			(size 0.889 0.9906)
			(layers "B.Cu" "B.Mask" "B.Paste")
			(net "GND")
		)
		(zone
			(layer "B.Cu")
			(hatch none 0.5)
			(connect_pads
				(clearance 0)
			)
			(min_thickness 0.25)
			(keepout
				(tracks allowed)
				(vias not_allowed)
				(pads allowed)
				(copperpour not_allowed)
				(footprints allowed)
			)
			(placement
				(enabled no)
				(sheetname "")
			)
			(fill
				(thermal_gap 0.5)
				(thermal_bridge_width 0.5)
				(island_removal_mode 0)
			)
			(polygon
				(pts
					(xy 267.349732 -8.6487) (xy 266.841732 -8.6487) (xy 266.841732 -7.6581) (xy 267.349732 -7.6581)
				)
			)
		)
		(zone
			(layer "B.Cu")
			(hatch none 0.5)
			(connect_pads
				(clearance 0)
			)
			(min_thickness 0.25)
			(keepout
				(tracks not_allowed)
				(vias allowed)
				(pads allowed)
				(copperpour not_allowed)
				(footprints allowed)
			)
			(placement
				(enabled no)
				(sheetname "")
			)
			(fill
				(thermal_gap 0.5)
				(thermal_bridge_width 0.5)
				(island_removal_mode 0)
			)
			(polygon
				(pts
					(xy 267.349732 -8.6487) (xy 266.841732 -8.6487) (xy 266.841732 -7.6581) (xy 267.349732 -7.6581)
				)
			)
		)
	)
	(footprint ""
		(layer "B.Cu")
		(at 327.95718 -58.724546 -90)
		(property "Reference" "R4R5"
			(at 0 0 90)
			(layer "B.SilkS")
			(hide yes)
			(effects
				(font
					(size 1.27 1.27)
				)
				(justify mirror)
			)
		)
		(property "Value" ""
			(at 0 0 90)
			(layer "B.Fab")
			(effects
				(font
					(size 1.27 1.27)
				)
				(justify mirror)
			)
		)
		(duplicate_pad_numbers_are_jumpers no)
		(fp_poly
			(pts
				(xy 0.2794 -0.1016) (xy -0.2794 -0.1016) (xy -0.2794 0.9906) (xy 0.2794 0.9906)
			)
			(stroke
				(width 0)
				(type default)
			)
			(fill no)
			(layer "B.CrtYd")
		)
		(fp_line
			(start -0.2794 0.9906)
			(end -0.2794 -0.1016)
			(stroke
				(width 0.1)
				(type default)
			)
			(layer "B.Fab")
		)
		(fp_line
			(start 0.2794 0.9906)
			(end -0.2794 0.9906)
			(stroke
				(width 0.1)
				(type default)
			)
			(layer "B.Fab")
		)
		(fp_line
			(start -0.2794 -0.1016)
			(end 0.2794 -0.1016)
			(stroke
				(width 0.1)
				(type default)
			)
			(layer "B.Fab")
		)
		(fp_line
			(start 0.2794 -0.1016)
			(end 0.2794 0.9906)
			(stroke
				(width 0.1)
				(type default)
			)
			(layer "B.Fab")
		)
		(pad "1" smd rect
			(at 0 0 90)
			(size 0.508 0.508)
			(layers "B.Cu" "B.Mask" "B.Paste")
			(net "P3V3_STBY")
		)
		(pad "2" smd rect
			(at 0 0.889 90)
			(size 0.508 0.508)
			(layers "B.Cu" "B.Mask" "B.Paste")
			(net "FM_CPU0_SKTOCC_LVT3_N")
		)
		(zone
			(layer "B.Cu")
			(hatch none 0.5)
			(connect_pads
				(clearance 0)
			)
			(min_thickness 0.25)
			(keepout
				(tracks not_allowed)
				(vias allowed)
				(pads allowed)
				(copperpour not_allowed)
				(footprints allowed)
			)
			(placement
				(enabled no)
				(sheetname "")
			)
			(fill
				(thermal_gap 0.5)
				(thermal_bridge_width 0.5)
				(island_removal_mode 0)
			)
			(polygon
				(pts
					(xy 327.32218 -58.470546) (xy 327.32218 -58.978546) (xy 327.70318 -58.978546) (xy 327.70318 -58.470546)
				)
			)
		)
		(zone
			(layer "B.Cu")
			(hatch none 0.5)
			(connect_pads
				(clearance 0)
			)
			(min_thickness 0.25)
			(keepout
				(tracks allowed)
				(vias not_allowed)
				(pads allowed)
				(copperpour not_allowed)
				(footprints allowed)
			)
			(placement
				(enabled no)
				(sheetname "")
			)
			(fill
				(thermal_gap 0.5)
				(thermal_bridge_width 0.5)
				(island_removal_mode 0)
			)
			(polygon
				(pts
					(xy 327.70318 -58.470546) (xy 327.70318 -58.978546) (xy 327.32218 -58.978546) (xy 327.32218 -58.470546)
				)
			)
		)
	)
	(footprint ""
		(layer "B.Cu")
		(at 425.5008 -15.0622 -90)
		(property "Reference" "R9G30"
			(at 0 0 90)
			(layer "B.SilkS")
			(hide yes)
			(effects
				(font
					(size 1.27 1.27)
				)
				(justify mirror)
			)
		)
		(property "Value" ""
			(at 0 0 90)
			(layer "B.Fab")
			(effects
				(font
					(size 1.27 1.27)
				)
				(justify mirror)
			)
		)
		(duplicate_pad_numbers_are_jumpers no)
		(fp_poly
			(pts
				(xy 0.2794 -0.1016) (xy -0.2794 -0.1016) (xy -0.2794 0.9906) (xy 0.2794 0.9906)
			)
			(stroke
				(width 0)
				(type default)
			)
			(fill no)
			(layer "B.CrtYd")
		)
		(fp_line
			(start -0.2794 0.9906)
			(end -0.2794 -0.1016)
			(stroke
				(width 0.1)
				(type default)
			)
			(layer "B.Fab")
		)
		(fp_line
			(start 0.2794 0.9906)
			(end -0.2794 0.9906)
			(stroke
				(width 0.1)
				(type default)
			)
			(layer "B.Fab")
		)
		(fp_line
			(start -0.2794 -0.1016)
			(end 0.2794 -0.1016)
			(stroke
				(width 0.1)
				(type default)
			)
			(layer "B.Fab")
		)
		(fp_line
			(start 0.2794 -0.1016)
			(end 0.2794 0.9906)
			(stroke
				(width 0.1)
				(type default)
			)
			(layer "B.Fab")
		)
		(pad "1" smd rect
			(at 0 0 90)
			(size 0.508 0.508)
			(layers "B.Cu" "B.Mask" "B.Paste")
			(net "H_CPU0_MEMDEF_MEMHOT_LVT3_N")
		)
		(pad "2" smd rect
			(at 0 0.889 90)
			(size 0.508 0.508)
			(layers "B.Cu" "B.Mask" "B.Paste")
			(net "H_CPU0_MEMDEF_MEMHOT_PCH_N")
		)
		(zone
			(layer "B.Cu")
			(hatch none 0.5)
			(connect_pads
				(clearance 0)
			)
			(min_thickness 0.25)
			(keepout
				(tracks not_allowed)
				(vias allowed)
				(pads allowed)
				(copperpour not_allowed)
				(footprints allowed)
			)
			(placement
				(enabled no)
				(sheetname "")
			)
			(fill
				(thermal_gap 0.5)
				(thermal_bridge_width 0.5)
				(island_removal_mode 0)
			)
			(polygon
				(pts
					(xy 424.8658 -14.8082) (xy 424.8658 -15.3162) (xy 425.2468 -15.3162) (xy 425.2468 -14.8082)
				)
			)
		)
		(zone
			(layer "B.Cu")
			(hatch none 0.5)
			(connect_pads
				(clearance 0)
			)
			(min_thickness 0.25)
			(keepout
				(tracks allowed)
				(vias not_allowed)
				(pads allowed)
				(copperpour not_allowed)
				(footprints allowed)
			)
			(placement
				(enabled no)
				(sheetname "")
			)
			(fill
				(thermal_gap 0.5)
				(thermal_bridge_width 0.5)
				(island_removal_mode 0)
			)
			(polygon
				(pts
					(xy 425.2468 -14.8082) (xy 425.2468 -15.3162) (xy 424.8658 -15.3162) (xy 424.8658 -14.8082)
				)
			)
		)
	)
	(footprint ""
		(layer "B.Cu")
		(at 158.6738 -123.8504)
		(property "Reference" "R7M6"
			(at 0 0 0)
			(layer "B.SilkS")
			(hide yes)
			(effects
				(font
					(size 1.27 1.27)
				)
				(justify mirror)
			)
		)
		(property "Value" ""
			(at 0 0 0)
			(layer "B.Fab")
			(effects
				(font
					(size 1.27 1.27)
				)
				(justify mirror)
			)
		)
		(duplicate_pad_numbers_are_jumpers no)
		(fp_poly
			(pts
				(xy 0.2794 -0.1016) (xy -0.2794 -0.1016) (xy -0.2794 0.9906) (xy 0.2794 0.9906)
			)
			(stroke
				(width 0)
				(type default)
			)
			(fill no)
			(layer "B.CrtYd")
		)
		(fp_line
			(start -0.2794 -0.1016)
			(end 0.2794 -0.1016)
			(stroke
				(width 0.1)
				(type default)
			)
			(layer "B.Fab")
		)
		(fp_line
			(start -0.2794 0.9906)
			(end -0.2794 -0.1016)
			(stroke
				(width 0.1)
				(type default)
			)
			(layer "B.Fab")
		)
		(fp_line
			(start 0.2794 -0.1016)
			(end 0.2794 0.9906)
			(stroke
				(width 0.1)
				(type default)
			)
			(layer "B.Fab")
		)
		(fp_line
			(start 0.2794 0.9906)
			(end -0.2794 0.9906)
			(stroke
				(width 0.1)
				(type default)
			)
			(layer "B.Fab")
		)
		(pad "1" smd rect
			(at 0 0 180)
			(size 0.508 0.508)
			(layers "B.Cu" "B.Mask" "B.Paste")
			(net "PVPP_KLM")
		)
		(pad "2" smd rect
			(at 0 0.889 180)
			(size 0.508 0.508)
			(layers "B.Cu" "B.Mask" "B.Paste")
			(net "SMB_DDR_KLM_VPP_SDA_R")
		)
		(zone
			(layer "B.Cu")
			(hatch none 0.5)
			(connect_pads
				(clearance 0)
			)
			(min_thickness 0.25)
			(keepout
				(tracks allowed)
				(vias not_allowed)
				(pads allowed)
				(copperpour not_allowed)
				(footprints allowed)
			)
			(placement
				(enabled no)
				(sheetname "")
			)
			(fill
				(thermal_gap 0.5)
				(thermal_bridge_width 0.5)
				(island_removal_mode 0)
			)
			(polygon
				(pts
					(xy 158.9278 -123.5964) (xy 158.4198 -123.5964) (xy 158.4198 -123.2154) (xy 158.9278 -123.2154)
				)
			)
		)
		(zone
			(layer "B.Cu")
			(hatch none 0.5)
			(connect_pads
				(clearance 0)
			)
			(min_thickness 0.25)
			(keepout
				(tracks not_allowed)
				(vias allowed)
				(pads allowed)
				(copperpour not_allowed)
				(footprints allowed)
			)
			(placement
				(enabled no)
				(sheetname "")
			)
			(fill
				(thermal_gap 0.5)
				(thermal_bridge_width 0.5)
				(island_removal_mode 0)
			)
			(polygon
				(pts
					(xy 158.9278 -123.2154) (xy 158.4198 -123.2154) (xy 158.4198 -123.5964) (xy 158.9278 -123.5964)
				)
			)
		)
	)
	(footprint ""
		(layer "B.Cu")
		(at 227.584 -91.059 90)
		(property "Reference" "R5N4"
			(at 0 0 90)
			(layer "B.SilkS")
			(hide yes)
			(effects
				(font
					(size 1.27 1.27)
				)
				(justify mirror)
			)
		)
		(property "Value" ""
			(at 0 0 90)
			(layer "B.Fab")
			(effects
				(font
					(size 1.27 1.27)
				)
				(justify mirror)
			)
		)
		(duplicate_pad_numbers_are_jumpers no)
		(fp_poly
			(pts
				(xy 0.2794 -0.1016) (xy -0.2794 -0.1016) (xy -0.2794 0.9906) (xy 0.2794 0.9906)
			)
			(stroke
				(width 0)
				(type default)
			)
			(fill no)
			(layer "B.CrtYd")
		)
		(fp_line
			(start 0.2794 -0.1016)
			(end 0.2794 0.9906)
			(stroke
				(width 0.1)
				(type default)
			)
			(layer "B.Fab")
		)
		(fp_line
			(start -0.2794 -0.1016)
			(end 0.2794 -0.1016)
			(stroke
				(width 0.1)
				(type default)
			)
			(layer "B.Fab")
		)
		(fp_line
			(start 0.2794 0.9906)
			(end -0.2794 0.9906)
			(stroke
				(width 0.1)
				(type default)
			)
			(layer "B.Fab")
		)
		(fp_line
			(start -0.2794 0.9906)
			(end -0.2794 -0.1016)
			(stroke
				(width 0.1)
				(type default)
			)
			(layer "B.Fab")
		)
		(pad "1" smd rect
			(at 0 0 270)
			(size 0.508 0.508)
			(layers "B.Cu" "B.Mask" "B.Paste")
			(net "P3V3_STBY")
		)
		(pad "2" smd rect
			(at 0 0.889 270)
			(size 0.508 0.508)
			(layers "B.Cu" "B.Mask" "B.Paste")
			(net "FM_CPU0_PROC_ID0")
		)
		(zone
			(layer "B.Cu")
			(hatch none 0.5)
			(connect_pads
				(clearance 0)
			)
			(min_thickness 0.25)
			(keepout
				(tracks allowed)
				(vias not_allowed)
				(pads allowed)
				(copperpour not_allowed)
				(footprints allowed)
			)
			(placement
				(enabled no)
				(sheetname "")
			)
			(fill
				(thermal_gap 0.5)
				(thermal_bridge_width 0.5)
				(island_removal_mode 0)
			)
			(polygon
				(pts
					(xy 227.838 -91.313) (xy 227.838 -90.805) (xy 228.219 -90.805) (xy 228.219 -91.313)
				)
			)
		)
		(zone
			(layer "B.Cu")
			(hatch none 0.5)
			(connect_pads
				(clearance 0)
			)
			(min_thickness 0.25)
			(keepout
				(tracks not_allowed)
				(vias allowed)
				(pads allowed)
				(copperpour not_allowed)
				(footprints allowed)
			)
			(placement
				(enabled no)
				(sheetname "")
			)
			(fill
				(thermal_gap 0.5)
				(thermal_bridge_width 0.5)
				(island_removal_mode 0)
			)
			(polygon
				(pts
					(xy 228.219 -91.313) (xy 228.219 -90.805) (xy 227.838 -90.805) (xy 227.838 -91.313)
				)
			)
		)
	)
	(footprint ""
		(layer "B.Cu")
		(at 351.1296 -89.865962 90)
		(property "Reference" "R3N22"
			(at 0 0 90)
			(layer "B.SilkS")
			(hide yes)
			(effects
				(font
					(size 1.27 1.27)
				)
				(justify mirror)
			)
		)
		(property "Value" ""
			(at 0 0 90)
			(layer "B.Fab")
			(effects
				(font
					(size 1.27 1.27)
				)
				(justify mirror)
			)
		)
		(duplicate_pad_numbers_are_jumpers no)
		(fp_poly
			(pts
				(xy 0.2794 -0.1016) (xy -0.2794 -0.1016) (xy -0.2794 0.9906) (xy 0.2794 0.9906)
			)
			(stroke
				(width 0)
				(type default)
			)
			(fill no)
			(layer "B.CrtYd")
		)
		(fp_line
			(start 0.2794 -0.1016)
			(end 0.2794 0.9906)
			(stroke
				(width 0.1)
				(type default)
			)
			(layer "B.Fab")
		)
		(fp_line
			(start -0.2794 -0.1016)
			(end 0.2794 -0.1016)
			(stroke
				(width 0.1)
				(type default)
			)
			(layer "B.Fab")
		)
		(fp_line
			(start 0.2794 0.9906)
			(end -0.2794 0.9906)
			(stroke
				(width 0.1)
				(type default)
			)
			(layer "B.Fab")
		)
		(fp_line
			(start -0.2794 0.9906)
			(end -0.2794 -0.1016)
			(stroke
				(width 0.1)
				(type default)
			)
			(layer "B.Fab")
		)
		(pad "1" smd rect
			(at 0 0 270)
			(size 0.508 0.508)
			(layers "B.Cu" "B.Mask" "B.Paste")
			(net "VR_PVCCIO_CPU0_XADDR2")
		)
		(pad "2" smd rect
			(at 0 0.889 270)
			(size 0.508 0.508)
			(layers "B.Cu" "B.Mask" "B.Paste")
			(net "GND")
		)
		(zone
			(layer "B.Cu")
			(hatch none 0.5)
			(connect_pads
				(clearance 0)
			)
			(min_thickness 0.25)
			(keepout
				(tracks allowed)
				(vias not_allowed)
				(pads allowed)
				(copperpour not_allowed)
				(footprints allowed)
			)
			(placement
				(enabled no)
				(sheetname "")
			)
			(fill
				(thermal_gap 0.5)
				(thermal_bridge_width 0.5)
				(island_removal_mode 0)
			)
			(polygon
				(pts
					(xy 351.3836 -90.119962) (xy 351.3836 -89.611962) (xy 351.7646 -89.611962) (xy 351.7646 -90.119962)
				)
			)
		)
		(zone
			(layer "B.Cu")
			(hatch none 0.5)
			(connect_pads
				(clearance 0)
			)
			(min_thickness 0.25)
			(keepout
				(tracks not_allowed)
				(vias allowed)
				(pads allowed)
				(copperpour not_allowed)
				(footprints allowed)
			)
			(placement
				(enabled no)
				(sheetname "")
			)
			(fill
				(thermal_gap 0.5)
				(thermal_bridge_width 0.5)
				(island_removal_mode 0)
			)
			(polygon
				(pts
					(xy 351.7646 -90.119962) (xy 351.7646 -89.611962) (xy 351.3836 -89.611962) (xy 351.3836 -90.119962)
				)
			)
		)
	)
	(footprint ""
		(layer "B.Cu")
		(at 228.4603 -64.6557 180)
		(property "Reference" "R4E14"
			(at 0 0 0)
			(layer "B.SilkS")
			(hide yes)
			(effects
				(font
					(size 1.27 1.27)
				)
				(justify mirror)
			)
		)
		(property "Value" ""
			(at 0 0 0)
			(layer "B.Fab")
			(effects
				(font
					(size 1.27 1.27)
				)
				(justify mirror)
			)
		)
		(duplicate_pad_numbers_are_jumpers no)
		(fp_poly
			(pts
				(xy 0.2794 -0.1016) (xy -0.2794 -0.1016) (xy -0.2794 0.9906) (xy 0.2794 0.9906)
			)
			(stroke
				(width 0)
				(type default)
			)
			(fill no)
			(layer "B.CrtYd")
		)
		(fp_line
			(start 0.2794 0.9906)
			(end -0.2794 0.9906)
			(stroke
				(width 0.1)
				(type default)
			)
			(layer "B.Fab")
		)
		(fp_line
			(start 0.2794 -0.1016)
			(end 0.2794 0.9906)
			(stroke
				(width 0.1)
				(type default)
			)
			(layer "B.Fab")
		)
		(fp_line
			(start -0.2794 0.9906)
			(end -0.2794 -0.1016)
			(stroke
				(width 0.1)
				(type default)
			)
			(layer "B.Fab")
		)
		(fp_line
			(start -0.2794 -0.1016)
			(end 0.2794 -0.1016)
			(stroke
				(width 0.1)
				(type default)
			)
			(layer "B.Fab")
		)
		(pad "1" smd rect
			(at 0 0)
			(size 0.508 0.508)
			(layers "B.Cu" "B.Mask" "B.Paste")
			(net "VSENSE_PVCCIN_CPU0_P")
		)
		(pad "2" smd rect
			(at 0 0.889)
			(size 0.508 0.508)
			(layers "B.Cu" "B.Mask" "B.Paste")
			(net "PVCCIN_CPU0")
		)
		(zone
			(layer "B.Cu")
			(hatch none 0.5)
			(connect_pads
				(clearance 0)
			)
			(min_thickness 0.25)
			(keepout
				(tracks not_allowed)
				(vias allowed)
				(pads allowed)
				(copperpour not_allowed)
				(footprints allowed)
			)
			(placement
				(enabled no)
				(sheetname "")
			)
			(fill
				(thermal_gap 0.5)
				(thermal_bridge_width 0.5)
				(island_removal_mode 0)
			)
			(polygon
				(pts
					(xy 228.2063 -65.2907) (xy 228.7143 -65.2907) (xy 228.7143 -64.9097) (xy 228.2063 -64.9097)
				)
			)
		)
		(zone
			(layer "B.Cu")
			(hatch none 0.5)
			(connect_pads
				(clearance 0)
			)
			(min_thickness 0.25)
			(keepout
				(tracks allowed)
				(vias not_allowed)
				(pads allowed)
				(copperpour not_allowed)
				(footprints allowed)
			)
			(placement
				(enabled no)
				(sheetname "")
			)
			(fill
				(thermal_gap 0.5)
				(thermal_bridge_width 0.5)
				(island_removal_mode 0)
			)
			(polygon
				(pts
					(xy 228.2063 -64.9097) (xy 228.7143 -64.9097) (xy 228.7143 -65.2907) (xy 228.2063 -65.2907)
				)
			)
		)
	)
	(footprint ""
		(layer "B.Cu")
		(at 365.506 -110.998 -90)
		(property "Reference" "C3N9"
			(at 0 0 90)
			(layer "B.SilkS")
			(hide yes)
			(effects
				(font
					(size 1.27 1.27)
				)
				(justify mirror)
			)
		)
		(property "Value" ""
			(at 0 0 90)
			(layer "B.Fab")
			(effects
				(font
					(size 1.27 1.27)
				)
				(justify mirror)
			)
		)
		(duplicate_pad_numbers_are_jumpers no)
		(fp_poly
			(pts
				(xy -0.3048 -0.1016) (xy -0.3048 0.9906) (xy 0.3048 0.9906) (xy 0.3048 -0.1016)
			)
			(stroke
				(width 0)
				(type default)
			)
			(fill no)
			(layer "B.CrtYd")
		)
		(fp_line
			(start -0.3048 0.9906)
			(end -0.3048 -0.1016)
			(stroke
				(width 0.1)
				(type default)
			)
			(layer "B.Fab")
		)
		(fp_line
			(start 0.3048 0.9906)
			(end -0.3048 0.9906)
			(stroke
				(width 0.1)
				(type default)
			)
			(layer "B.Fab")
		)
		(fp_line
			(start -0.3048 -0.1016)
			(end 0.3048 -0.1016)
			(stroke
				(width 0.1)
				(type default)
			)
			(layer "B.Fab")
		)
		(fp_line
			(start 0.3048 -0.1016)
			(end 0.3048 0.9906)
			(stroke
				(width 0.1)
				(type default)
			)
			(layer "B.Fab")
		)
		(pad "1" smd rect
			(at 0 0 90)
			(size 0.508 0.508)
			(layers "B.Cu" "B.Mask" "B.Paste")
			(net "DMI_CPU0_PCH_RX_DP<2>")
		)
		(pad "2" smd rect
			(at 0 0.889 90)
			(size 0.508 0.508)
			(layers "B.Cu" "B.Mask" "B.Paste")
			(net "DMI_CPU0_PCH_RX_C_DP<2>")
		)
		(zone
			(layer "B.Cu")
			(hatch none 0.5)
			(connect_pads
				(clearance 0)
			)
			(min_thickness 0.25)
			(keepout
				(tracks not_allowed)
				(vias allowed)
				(pads allowed)
				(copperpour not_allowed)
				(footprints allowed)
			)
			(placement
				(enabled no)
				(sheetname "")
			)
			(fill
				(thermal_gap 0.5)
				(thermal_bridge_width 0.5)
				(island_removal_mode 0)
			)
			(polygon
				(pts
					(xy 364.871 -110.744) (xy 364.871 -111.252) (xy 365.252 -111.252) (xy 365.252 -110.744)
				)
			)
		)
		(zone
			(layer "B.Cu")
			(hatch none 0.5)
			(connect_pads
				(clearance 0)
			)
			(min_thickness 0.25)
			(keepout
				(tracks allowed)
				(vias not_allowed)
				(pads allowed)
				(copperpour not_allowed)
				(footprints allowed)
			)
			(placement
				(enabled no)
				(sheetname "")
			)
			(fill
				(thermal_gap 0.5)
				(thermal_bridge_width 0.5)
				(island_removal_mode 0)
			)
			(polygon
				(pts
					(xy 365.252 -110.744) (xy 365.252 -111.252) (xy 364.871 -111.252) (xy 364.871 -110.744)
				)
			)
		)
	)
	(footprint ""
		(layer "B.Cu")
		(at 330.08316 -66.25336 90)
		(property "Reference" "R4P12"
			(at 0 0 90)
			(layer "B.SilkS")
			(hide yes)
			(effects
				(font
					(size 1.27 1.27)
				)
				(justify mirror)
			)
		)
		(property "Value" ""
			(at 0 0 90)
			(layer "B.Fab")
			(effects
				(font
					(size 1.27 1.27)
				)
				(justify mirror)
			)
		)
		(duplicate_pad_numbers_are_jumpers no)
		(fp_poly
			(pts
				(xy 0.2794 -0.1016) (xy -0.2794 -0.1016) (xy -0.2794 0.9906) (xy 0.2794 0.9906)
			)
			(stroke
				(width 0)
				(type default)
			)
			(fill no)
			(layer "B.CrtYd")
		)
		(fp_line
			(start 0.2794 -0.1016)
			(end 0.2794 0.9906)
			(stroke
				(width 0.1)
				(type default)
			)
			(layer "B.Fab")
		)
		(fp_line
			(start -0.2794 -0.1016)
			(end 0.2794 -0.1016)
			(stroke
				(width 0.1)
				(type default)
			)
			(layer "B.Fab")
		)
		(fp_line
			(start 0.2794 0.9906)
			(end -0.2794 0.9906)
			(stroke
				(width 0.1)
				(type default)
			)
			(layer "B.Fab")
		)
		(fp_line
			(start -0.2794 0.9906)
			(end -0.2794 -0.1016)
			(stroke
				(width 0.1)
				(type default)
			)
			(layer "B.Fab")
		)
		(pad "1" smd rect
			(at 0 0 270)
			(size 0.508 0.508)
			(layers "B.Cu" "B.Mask" "B.Paste")
			(net "PVCCIO_CPU0")
		)
		(pad "2" smd rect
			(at 0 0.889 270)
			(size 0.508 0.508)
			(layers "B.Cu" "B.Mask" "B.Paste")
			(net "XDP_CPU_MBP0_N")
		)
		(zone
			(layer "B.Cu")
			(hatch none 0.5)
			(connect_pads
				(clearance 0)
			)
			(min_thickness 0.25)
			(keepout
				(tracks allowed)
				(vias not_allowed)
				(pads allowed)
				(copperpour not_allowed)
				(footprints allowed)
			)
			(placement
				(enabled no)
				(sheetname "")
			)
			(fill
				(thermal_gap 0.5)
				(thermal_bridge_width 0.5)
				(island_removal_mode 0)
			)
			(polygon
				(pts
					(xy 330.33716 -66.50736) (xy 330.33716 -65.99936) (xy 330.71816 -65.99936) (xy 330.71816 -66.50736)
				)
			)
		)
		(zone
			(layer "B.Cu")
			(hatch none 0.5)
			(connect_pads
				(clearance 0)
			)
			(min_thickness 0.25)
			(keepout
				(tracks not_allowed)
				(vias allowed)
				(pads allowed)
				(copperpour not_allowed)
				(footprints allowed)
			)
			(placement
				(enabled no)
				(sheetname "")
			)
			(fill
				(thermal_gap 0.5)
				(thermal_bridge_width 0.5)
				(island_removal_mode 0)
			)
			(polygon
				(pts
					(xy 330.71816 -66.50736) (xy 330.71816 -65.99936) (xy 330.33716 -65.99936) (xy 330.33716 -66.50736)
				)
			)
		)
	)
	(footprint ""
		(layer "B.Cu")
		(at 375.7041 -110.281212)
		(property "Reference" "C3W1"
			(at 0.8382 -0.67818 0)
			(unlocked yes)
			(layer "B.SilkS")
			(effects
				(font
					(size 0.4064 0.254)
					(thickness 0.1524)
				)
				(justify left mirror)
			)
		)
		(property "Value" ""
			(at 0 0 0)
			(layer "B.Fab")
			(effects
				(font
					(size 1.27 1.27)
				)
				(justify mirror)
			)
		)
		(duplicate_pad_numbers_are_jumpers no)
		(fp_poly
			(pts
				(xy -0.3048 -0.1016) (xy -0.3048 0.9906) (xy 0.3048 0.9906) (xy 0.3048 -0.1016)
			)
			(stroke
				(width 0)
				(type default)
			)
			(fill no)
			(layer "B.CrtYd")
		)
		(fp_line
			(start -0.3048 -0.1016)
			(end 0.3048 -0.1016)
			(stroke
				(width 0.1)
				(type default)
			)
			(layer "B.Fab")
		)
		(fp_line
			(start -0.3048 0.9906)
			(end -0.3048 -0.1016)
			(stroke
				(width 0.1)
				(type default)
			)
			(layer "B.Fab")
		)
		(fp_line
			(start 0.3048 -0.1016)
			(end 0.3048 0.9906)
			(stroke
				(width 0.1)
				(type default)
			)
			(layer "B.Fab")
		)
		(fp_line
			(start 0.3048 0.9906)
			(end -0.3048 0.9906)
			(stroke
				(width 0.1)
				(type default)
			)
			(layer "B.Fab")
		)
		(pad "1" smd rect
			(at 0 0 180)
			(size 0.508 0.508)
			(layers "B.Cu" "B.Mask" "B.Paste")
			(net "A_PCH_XCLK_BIASREF")
		)
		(pad "2" smd rect
			(at 0 0.889 180)
			(size 0.508 0.508)
			(layers "B.Cu" "B.Mask" "B.Paste")
			(net "GND")
		)
		(zone
			(layer "B.Cu")
			(hatch none 0.5)
			(connect_pads
				(clearance 0)
			)
			(min_thickness 0.25)
			(keepout
				(tracks allowed)
				(vias not_allowed)
				(pads allowed)
				(copperpour not_allowed)
				(footprints allowed)
			)
			(placement
				(enabled no)
				(sheetname "")
			)
			(fill
				(thermal_gap 0.5)
				(thermal_bridge_width 0.5)
				(island_removal_mode 0)
			)
			(polygon
				(pts
					(xy 375.9581 -110.027212) (xy 375.4501 -110.027212) (xy 375.4501 -109.646212) (xy 375.9581 -109.646212)
				)
			)
		)
		(zone
			(layer "B.Cu")
			(hatch none 0.5)
			(connect_pads
				(clearance 0)
			)
			(min_thickness 0.25)
			(keepout
				(tracks not_allowed)
				(vias allowed)
				(pads allowed)
				(copperpour not_allowed)
				(footprints allowed)
			)
			(placement
				(enabled no)
				(sheetname "")
			)
			(fill
				(thermal_gap 0.5)
				(thermal_bridge_width 0.5)
				(island_removal_mode 0)
			)
			(polygon
				(pts
					(xy 375.9581 -109.646212) (xy 375.4501 -109.646212) (xy 375.4501 -110.027212) (xy 375.9581 -110.027212)
				)
			)
		)
	)
	(footprint ""
		(layer "B.Cu")
		(at 495.2492 -137.7569 180)
		(property "Reference" "R1L32"
			(at 0 0 0)
			(layer "B.SilkS")
			(hide yes)
			(effects
				(font
					(size 1.27 1.27)
				)
				(justify mirror)
			)
		)
		(property "Value" ""
			(at 0 0 0)
			(layer "B.Fab")
			(effects
				(font
					(size 1.27 1.27)
				)
				(justify mirror)
			)
		)
		(duplicate_pad_numbers_are_jumpers no)
		(fp_poly
			(pts
				(xy 0.2794 -0.1016) (xy -0.2794 -0.1016) (xy -0.2794 0.9906) (xy 0.2794 0.9906)
			)
			(stroke
				(width 0)
				(type default)
			)
			(fill no)
			(layer "B.CrtYd")
		)
		(fp_line
			(start 0.2794 0.9906)
			(end -0.2794 0.9906)
			(stroke
				(width 0.1)
				(type default)
			)
			(layer "B.Fab")
		)
		(fp_line
			(start 0.2794 -0.1016)
			(end 0.2794 0.9906)
			(stroke
				(width 0.1)
				(type default)
			)
			(layer "B.Fab")
		)
		(fp_line
			(start -0.2794 0.9906)
			(end -0.2794 -0.1016)
			(stroke
				(width 0.1)
				(type default)
			)
			(layer "B.Fab")
		)
		(fp_line
			(start -0.2794 -0.1016)
			(end 0.2794 -0.1016)
			(stroke
				(width 0.1)
				(type default)
			)
			(layer "B.Fab")
		)
		(pad "1" smd rect
			(at 0 0)
			(size 0.508 0.508)
			(layers "B.Cu" "B.Mask" "B.Paste")
			(net "LED_POSTCODE_0")
		)
		(pad "2" smd rect
			(at 0 0.889)
			(size 0.508 0.508)
			(layers "B.Cu" "B.Mask" "B.Paste")
			(net "LED_POSTCODE_0_R")
		)
		(zone
			(layer "B.Cu")
			(hatch none 0.5)
			(connect_pads
				(clearance 0)
			)
			(min_thickness 0.25)
			(keepout
				(tracks not_allowed)
				(vias allowed)
				(pads allowed)
				(copperpour not_allowed)
				(footprints allowed)
			)
			(placement
				(enabled no)
				(sheetname "")
			)
			(fill
				(thermal_gap 0.5)
				(thermal_bridge_width 0.5)
				(island_removal_mode 0)
			)
			(polygon
				(pts
					(xy 494.9952 -138.3919) (xy 495.5032 -138.3919) (xy 495.5032 -138.0109) (xy 494.9952 -138.0109)
				)
			)
		)
		(zone
			(layer "B.Cu")
			(hatch none 0.5)
			(connect_pads
				(clearance 0)
			)
			(min_thickness 0.25)
			(keepout
				(tracks allowed)
				(vias not_allowed)
				(pads allowed)
				(copperpour not_allowed)
				(footprints allowed)
			)
			(placement
				(enabled no)
				(sheetname "")
			)
			(fill
				(thermal_gap 0.5)
				(thermal_bridge_width 0.5)
				(island_removal_mode 0)
			)
			(polygon
				(pts
					(xy 494.9952 -138.0109) (xy 495.5032 -138.0109) (xy 495.5032 -138.3919) (xy 494.9952 -138.3919)
				)
			)
		)
	)
	(footprint ""
		(layer "B.Cu")
		(at 467.106 -46.6725 180)
		(property "Reference" "R9E10"
			(at 0 0 0)
			(layer "B.SilkS")
			(hide yes)
			(effects
				(font
					(size 1.27 1.27)
				)
				(justify mirror)
			)
		)
		(property "Value" ""
			(at 0 0 0)
			(layer "B.Fab")
			(effects
				(font
					(size 1.27 1.27)
				)
				(justify mirror)
			)
		)
		(duplicate_pad_numbers_are_jumpers no)
		(fp_poly
			(pts
				(xy 0.2794 -0.1016) (xy -0.2794 -0.1016) (xy -0.2794 0.9906) (xy 0.2794 0.9906)
			)
			(stroke
				(width 0)
				(type default)
			)
			(fill no)
			(layer "B.CrtYd")
		)
		(fp_line
			(start 0.2794 0.9906)
			(end -0.2794 0.9906)
			(stroke
				(width 0.1)
				(type default)
			)
			(layer "B.Fab")
		)
		(fp_line
			(start 0.2794 -0.1016)
			(end 0.2794 0.9906)
			(stroke
				(width 0.1)
				(type default)
			)
			(layer "B.Fab")
		)
		(fp_line
			(start -0.2794 0.9906)
			(end -0.2794 -0.1016)
			(stroke
				(width 0.1)
				(type default)
			)
			(layer "B.Fab")
		)
		(fp_line
			(start -0.2794 -0.1016)
			(end 0.2794 -0.1016)
			(stroke
				(width 0.1)
				(type default)
			)
			(layer "B.Fab")
		)
		(pad "1" smd rect
			(at 0 0)
			(size 0.508 0.508)
			(layers "B.Cu" "B.Mask" "B.Paste")
			(net "RST_PCIE_CPU_DEV1_R_N")
		)
		(pad "2" smd rect
			(at 0 0.889)
			(size 0.508 0.508)
			(layers "B.Cu" "B.Mask" "B.Paste")
			(net "RST_PCIE_CPU_DEV1_N")
		)
		(zone
			(layer "B.Cu")
			(hatch none 0.5)
			(connect_pads
				(clearance 0)
			)
			(min_thickness 0.25)
			(keepout
				(tracks not_allowed)
				(vias allowed)
				(pads allowed)
				(copperpour not_allowed)
				(footprints allowed)
			)
			(placement
				(enabled no)
				(sheetname "")
			)
			(fill
				(thermal_gap 0.5)
				(thermal_bridge_width 0.5)
				(island_removal_mode 0)
			)
			(polygon
				(pts
					(xy 466.852 -47.3075) (xy 467.36 -47.3075) (xy 467.36 -46.9265) (xy 466.852 -46.9265)
				)
			)
		)
		(zone
			(layer "B.Cu")
			(hatch none 0.5)
			(connect_pads
				(clearance 0)
			)
			(min_thickness 0.25)
			(keepout
				(tracks allowed)
				(vias not_allowed)
				(pads allowed)
				(copperpour not_allowed)
				(footprints allowed)
			)
			(placement
				(enabled no)
				(sheetname "")
			)
			(fill
				(thermal_gap 0.5)
				(thermal_bridge_width 0.5)
				(island_removal_mode 0)
			)
			(polygon
				(pts
					(xy 466.852 -46.9265) (xy 467.36 -46.9265) (xy 467.36 -47.3075) (xy 466.852 -47.3075)
				)
			)
		)
	)
	(footprint ""
		(layer "B.Cu")
		(at 463.042 -116.49202)
		(property "Reference" "C1M8"
			(at 0 0 0)
			(layer "B.SilkS")
			(hide yes)
			(effects
				(font
					(size 1.27 1.27)
				)
				(justify mirror)
			)
		)
		(property "Value" ""
			(at 0 0 0)
			(layer "B.Fab")
			(effects
				(font
					(size 1.27 1.27)
				)
				(justify mirror)
			)
		)
		(duplicate_pad_numbers_are_jumpers no)
		(fp_rect
			(start -0.3048 0.9906)
			(end 0.3048 -0.1016)
			(stroke
				(width 0)
				(type default)
			)
			(fill no)
			(layer "B.CrtYd")
		)
		(fp_line
			(start -0.3048 -0.1016)
			(end 0.3048 -0.1016)
			(stroke
				(width 0.1)
				(type default)
			)
			(layer "B.Fab")
		)
		(fp_line
			(start -0.3048 0.9906)
			(end -0.3048 -0.1016)
			(stroke
				(width 0.1)
				(type default)
			)
			(layer "B.Fab")
		)
		(fp_line
			(start 0.3048 -0.1016)
			(end 0.3048 0.9906)
			(stroke
				(width 0.1)
				(type default)
			)
			(layer "B.Fab")
		)
		(fp_line
			(start 0.3048 0.9906)
			(end -0.3048 0.9906)
			(stroke
				(width 0.1)
				(type default)
			)
			(layer "B.Fab")
		)
		(pad "1" smd rect
			(at 0 0 180)
			(size 0.508 0.508)
			(layers "B.Cu" "B.Mask" "B.Paste")
			(net "P3E_CPU0_PE3_OCP_TXP<14>")
		)
		(pad "2" smd rect
			(at 0 0.889 180)
			(size 0.508 0.508)
			(layers "B.Cu" "B.Mask" "B.Paste")
			(net "P3E_OCP_CPU0_PE3_C_TXP<14>")
		)
		(zone
			(layer "B.Cu")
			(hatch none 0.5)
			(connect_pads
				(clearance 0)
			)
			(min_thickness 0.25)
			(keepout
				(tracks allowed)
				(vias not_allowed)
				(pads allowed)
				(copperpour not_allowed)
				(footprints allowed)
			)
			(placement
				(enabled no)
				(sheetname "")
			)
			(fill
				(thermal_gap 0.5)
				(thermal_bridge_width 0.5)
				(island_removal_mode 0)
			)
			(polygon
				(pts
					(xy 462.788 -115.85702) (xy 463.296 -115.85702) (xy 463.296 -116.23802) (xy 462.788 -116.23802)
				)
			)
		)
		(zone
			(layer "B.Cu")
			(hatch none 0.5)
			(connect_pads
				(clearance 0)
			)
			(min_thickness 0.25)
			(keepout
				(tracks not_allowed)
				(vias allowed)
				(pads allowed)
				(copperpour not_allowed)
				(footprints allowed)
			)
			(placement
				(enabled no)
				(sheetname "")
			)
			(fill
				(thermal_gap 0.5)
				(thermal_bridge_width 0.5)
				(island_removal_mode 0)
			)
			(polygon
				(pts
					(xy 462.788 -115.85702) (xy 463.296 -115.85702) (xy 463.296 -116.23802) (xy 462.788 -116.23802)
				)
			)
		)
	)
	(footprint ""
		(layer "B.Cu")
		(at 1.3462 -146.685 90)
		(property "Reference" "C9L13"
			(at 0 0 90)
			(layer "B.SilkS")
			(hide yes)
			(effects
				(font
					(size 1.27 1.27)
				)
				(justify mirror)
			)
		)
		(property "Value" ""
			(at 0 0 90)
			(layer "B.Fab")
			(effects
				(font
					(size 1.27 1.27)
				)
				(justify mirror)
			)
		)
		(duplicate_pad_numbers_are_jumpers no)
		(fp_rect
			(start -0.7239 -0.2159)
			(end 0.7239 1.9939)
			(stroke
				(width 0)
				(type default)
			)
			(fill no)
			(layer "B.CrtYd")
		)
		(fp_line
			(start 0.7239 -0.2159)
			(end 0.7239 1.9939)
			(stroke
				(width 0.1)
				(type default)
			)
			(layer "B.Fab")
		)
		(fp_line
			(start -0.7239 -0.2159)
			(end 0.7239 -0.2159)
			(stroke
				(width 0.1)
				(type default)
			)
			(layer "B.Fab")
		)
		(fp_line
			(start 0.7239 1.9939)
			(end -0.7239 1.9939)
			(stroke
				(width 0.1)
				(type default)
			)
			(layer "B.Fab")
		)
		(fp_line
			(start -0.7239 1.9939)
			(end -0.7239 -0.2159)
			(stroke
				(width 0.1)
				(type default)
			)
			(layer "B.Fab")
		)
		(pad "1" smd rect
			(at 0 0 270)
			(size 1.27 1.016)
			(layers "B.Cu" "B.Mask" "B.Paste")
			(net "VR_FET_SW_P12V_STBY_PVDDQ_KLM")
		)
		(pad "2" smd rect
			(at 0 1.778 270)
			(size 1.27 1.016)
			(layers "B.Cu" "B.Mask" "B.Paste")
			(net "GND")
		)
		(zone
			(layer "B.Cu")
			(hatch none 0.5)
			(connect_pads
				(clearance 0)
			)
			(min_thickness 0.25)
			(keepout
				(tracks not_allowed)
				(vias allowed)
				(pads allowed)
				(copperpour not_allowed)
				(footprints allowed)
			)
			(placement
				(enabled no)
				(sheetname "")
			)
			(fill
				(thermal_gap 0.5)
				(thermal_bridge_width 0.5)
				(island_removal_mode 0)
			)
			(polygon
				(pts
					(xy 1.8542 -146.05) (xy 2.6162 -146.05) (xy 2.6162 -147.32) (xy 1.8542 -147.32)
				)
			)
		)
	)
	(footprint ""
		(layer "B.Cu")
		(at 16.82242 -107.94492 90)
		(property "Reference" "C9N2"
			(at 0 0 90)
			(layer "B.SilkS")
			(hide yes)
			(effects
				(font
					(size 1.27 1.27)
				)
				(justify mirror)
			)
		)
		(property "Value" ""
			(at 0 0 90)
			(layer "B.Fab")
			(effects
				(font
					(size 1.27 1.27)
				)
				(justify mirror)
			)
		)
		(duplicate_pad_numbers_are_jumpers no)
		(fp_poly
			(pts
				(xy -0.3048 -0.1016) (xy -0.3048 0.9906) (xy 0.3048 0.9906) (xy 0.3048 -0.1016)
			)
			(stroke
				(width 0)
				(type default)
			)
			(fill no)
			(layer "B.CrtYd")
		)
		(fp_line
			(start 0.3048 -0.1016)
			(end 0.3048 0.9906)
			(stroke
				(width 0.1)
				(type default)
			)
			(layer "B.Fab")
		)
		(fp_line
			(start -0.3048 -0.1016)
			(end 0.3048 -0.1016)
			(stroke
				(width 0.1)
				(type default)
			)
			(layer "B.Fab")
		)
		(fp_line
			(start 0.3048 0.9906)
			(end -0.3048 0.9906)
			(stroke
				(width 0.1)
				(type default)
			)
			(layer "B.Fab")
		)
		(fp_line
			(start -0.3048 0.9906)
			(end -0.3048 -0.1016)
			(stroke
				(width 0.1)
				(type default)
			)
			(layer "B.Fab")
		)
		(pad "1" smd rect
			(at 0 0 270)
			(size 0.508 0.508)
			(layers "B.Cu" "B.Mask" "B.Paste")
			(net "P3E_CPU1_PE3_MP_C_TXN<10>")
		)
		(pad "2" smd rect
			(at 0 0.889 270)
			(size 0.508 0.508)
			(layers "B.Cu" "B.Mask" "B.Paste")
			(net "P3E_CPU1_PE3_MP_TXN<10>")
		)
		(zone
			(layer "B.Cu")
			(hatch none 0.5)
			(connect_pads
				(clearance 0)
			)
			(min_thickness 0.25)
			(keepout
				(tracks allowed)
				(vias not_allowed)
				(pads allowed)
				(copperpour not_allowed)
				(footprints allowed)
			)
			(placement
				(enabled no)
				(sheetname "")
			)
			(fill
				(thermal_gap 0.5)
				(thermal_bridge_width 0.5)
				(island_removal_mode 0)
			)
			(polygon
				(pts
					(xy 17.07642 -108.19892) (xy 17.07642 -107.69092) (xy 17.45742 -107.69092) (xy 17.45742 -108.19892)
				)
			)
		)
		(zone
			(layer "B.Cu")
			(hatch none 0.5)
			(connect_pads
				(clearance 0)
			)
			(min_thickness 0.25)
			(keepout
				(tracks not_allowed)
				(vias allowed)
				(pads allowed)
				(copperpour not_allowed)
				(footprints allowed)
			)
			(placement
				(enabled no)
				(sheetname "")
			)
			(fill
				(thermal_gap 0.5)
				(thermal_bridge_width 0.5)
				(island_removal_mode 0)
			)
			(polygon
				(pts
					(xy 17.45742 -108.19892) (xy 17.45742 -107.69092) (xy 17.07642 -107.69092) (xy 17.07642 -108.19892)
				)
			)
		)
	)
	(footprint ""
		(layer "B.Cu")
		(at 323.758306 -29.812742 -90)
		(property "Reference" "R3R16"
			(at 0 0 90)
			(layer "B.SilkS")
			(hide yes)
			(effects
				(font
					(size 1.27 1.27)
				)
				(justify mirror)
			)
		)
		(property "Value" ""
			(at 0 0 90)
			(layer "B.Fab")
			(effects
				(font
					(size 1.27 1.27)
				)
				(justify mirror)
			)
		)
		(duplicate_pad_numbers_are_jumpers no)
		(fp_poly
			(pts
				(xy 0.2794 -0.1016) (xy -0.2794 -0.1016) (xy -0.2794 0.9906) (xy 0.2794 0.9906)
			)
			(stroke
				(width 0)
				(type default)
			)
			(fill no)
			(layer "B.CrtYd")
		)
		(fp_line
			(start -0.2794 0.9906)
			(end -0.2794 -0.1016)
			(stroke
				(width 0.1)
				(type default)
			)
			(layer "B.Fab")
		)
		(fp_line
			(start 0.2794 0.9906)
			(end -0.2794 0.9906)
			(stroke
				(width 0.1)
				(type default)
			)
			(layer "B.Fab")
		)
		(fp_line
			(start -0.2794 -0.1016)
			(end 0.2794 -0.1016)
			(stroke
				(width 0.1)
				(type default)
			)
			(layer "B.Fab")
		)
		(fp_line
			(start 0.2794 -0.1016)
			(end 0.2794 0.9906)
			(stroke
				(width 0.1)
				(type default)
			)
			(layer "B.Fab")
		)
		(pad "1" smd rect
			(at 0 0 90)
			(size 0.508 0.508)
			(layers "B.Cu" "B.Mask" "B.Paste")
			(net "PVPP_ABC")
		)
		(pad "2" smd rect
			(at 0 0.889 90)
			(size 0.508 0.508)
			(layers "B.Cu" "B.Mask" "B.Paste")
			(net "RST_CD_CPU0_POR_N")
		)
		(zone
			(layer "B.Cu")
			(hatch none 0.5)
			(connect_pads
				(clearance 0)
			)
			(min_thickness 0.25)
			(keepout
				(tracks not_allowed)
				(vias allowed)
				(pads allowed)
				(copperpour not_allowed)
				(footprints allowed)
			)
			(placement
				(enabled no)
				(sheetname "")
			)
			(fill
				(thermal_gap 0.5)
				(thermal_bridge_width 0.5)
				(island_removal_mode 0)
			)
			(polygon
				(pts
					(xy 323.123306 -29.558742) (xy 323.123306 -30.066742) (xy 323.504306 -30.066742) (xy 323.504306 -29.558742)
				)
			)
		)
		(zone
			(layer "B.Cu")
			(hatch none 0.5)
			(connect_pads
				(clearance 0)
			)
			(min_thickness 0.25)
			(keepout
				(tracks allowed)
				(vias not_allowed)
				(pads allowed)
				(copperpour not_allowed)
				(footprints allowed)
			)
			(placement
				(enabled no)
				(sheetname "")
			)
			(fill
				(thermal_gap 0.5)
				(thermal_bridge_width 0.5)
				(island_removal_mode 0)
			)
			(polygon
				(pts
					(xy 323.504306 -29.558742) (xy 323.504306 -30.066742) (xy 323.123306 -30.066742) (xy 323.123306 -29.558742)
				)
			)
		)
	)
	(footprint ""
		(layer "B.Cu")
		(at 83.856068 -8.1534 -90)
		(property "Reference" "C8U6"
			(at -1.848866 0.752348 270)
			(unlocked yes)
			(layer "B.SilkS")
			(effects
				(font
					(size 1.27 0.9652)
					(thickness 0.1524)
				)
				(justify mirror)
			)
		)
		(property "Value" ""
			(at 0 0 90)
			(layer "B.Fab")
			(effects
				(font
					(size 1.27 1.27)
				)
				(justify mirror)
			)
		)
		(duplicate_pad_numbers_are_jumpers no)
		(fp_rect
			(start 0.500126 1.598422)
			(end -0.500126 -0.201422)
			(stroke
				(width 0)
				(type default)
			)
			(fill no)
			(layer "B.CrtYd")
		)
		(fp_line
			(start -0.500126 1.598422)
			(end 0.500126 1.598422)
			(stroke
				(width 0.1)
				(type default)
			)
			(layer "B.Fab")
		)
		(fp_line
			(start 0.500126 1.598422)
			(end 0.500126 -0.201422)
			(stroke
				(width 0.1)
				(type default)
			)
			(layer "B.Fab")
		)
		(fp_line
			(start -0.500126 -0.201422)
			(end -0.500126 1.598422)
			(stroke
				(width 0.1)
				(type default)
			)
			(layer "B.Fab")
		)
		(fp_line
			(start 0.500126 -0.201422)
			(end -0.500126 -0.201422)
			(stroke
				(width 0.1)
				(type default)
			)
			(layer "B.Fab")
		)
		(pad "1" smd rect
			(at 0 0 180)
			(size 0.889 0.9906)
			(layers "B.Cu" "B.Mask" "B.Paste")
			(net "PVDDQ_GHJ")
		)
		(pad "2" smd rect
			(at 0 1.397 180)
			(size 0.889 0.9906)
			(layers "B.Cu" "B.Mask" "B.Paste")
			(net "GND")
		)
		(zone
			(layer "B.Cu")
			(hatch none 0.5)
			(connect_pads
				(clearance 0)
			)
			(min_thickness 0.25)
			(keepout
				(tracks not_allowed)
				(vias allowed)
				(pads allowed)
				(copperpour not_allowed)
				(footprints allowed)
			)
			(placement
				(enabled no)
				(sheetname "")
			)
			(fill
				(thermal_gap 0.5)
				(thermal_bridge_width 0.5)
				(island_removal_mode 0)
			)
			(polygon
				(pts
					(xy 82.903568 -7.6581) (xy 83.411568 -7.6581) (xy 83.411568 -8.6487) (xy 82.903568 -8.6487)
				)
			)
		)
		(zone
			(layer "B.Cu")
			(hatch none 0.5)
			(connect_pads
				(clearance 0)
			)
			(min_thickness 0.25)
			(keepout
				(tracks allowed)
				(vias not_allowed)
				(pads allowed)
				(copperpour not_allowed)
				(footprints allowed)
			)
			(placement
				(enabled no)
				(sheetname "")
			)
			(fill
				(thermal_gap 0.5)
				(thermal_bridge_width 0.5)
				(island_removal_mode 0)
			)
			(polygon
				(pts
					(xy 82.903568 -7.6581) (xy 83.411568 -7.6581) (xy 83.411568 -8.6487) (xy 82.903568 -8.6487)
				)
			)
		)
	)
	(footprint ""
		(layer "B.Cu")
		(at 275.262086 -68.17614 180)
		(property "Reference" "C5P40"
			(at 0 0 0)
			(layer "B.SilkS")
			(hide yes)
			(effects
				(font
					(size 1.27 1.27)
				)
				(justify mirror)
			)
		)
		(property "Value" ""
			(at 0 0 0)
			(layer "B.Fab")
			(effects
				(font
					(size 1.27 1.27)
				)
				(justify mirror)
			)
		)
		(duplicate_pad_numbers_are_jumpers no)
		(fp_poly
			(pts
				(xy 0.7239 -0.2159) (xy -0.7239 -0.2159) (xy -0.7239 1.9939) (xy 0.7239 1.9939)
			)
			(stroke
				(width 0)
				(type default)
			)
			(fill no)
			(layer "B.CrtYd")
		)
		(fp_line
			(start 0.7239 1.9939)
			(end -0.7239 1.9939)
			(stroke
				(width 0.1)
				(type default)
			)
			(layer "B.Fab")
		)
		(fp_line
			(start 0.7239 -0.2159)
			(end 0.7239 1.9939)
			(stroke
				(width 0.1)
				(type default)
			)
			(layer "B.Fab")
		)
		(fp_line
			(start -0.7239 1.9939)
			(end -0.7239 -0.2159)
			(stroke
				(width 0.1)
				(type default)
			)
			(layer "B.Fab")
		)
		(fp_line
			(start -0.7239 -0.2159)
			(end 0.7239 -0.2159)
			(stroke
				(width 0.1)
				(type default)
			)
			(layer "B.Fab")
		)
		(pad "1" smd rect
			(at 0 0)
			(size 1.27 1.016)
			(layers "B.Cu" "B.Mask" "B.Paste")
			(net "PVCCIN_CPU0")
		)
		(pad "2" smd rect
			(at 0 1.778)
			(size 1.27 1.016)
			(layers "B.Cu" "B.Mask" "B.Paste")
			(net "GND")
		)
		(zone
			(layer "B.Cu")
			(hatch none 0.5)
			(connect_pads
				(clearance 0)
			)
			(min_thickness 0.25)
			(keepout
				(tracks not_allowed)
				(vias allowed)
				(pads allowed)
				(copperpour not_allowed)
				(footprints allowed)
			)
			(placement
				(enabled no)
				(sheetname "")
			)
			(fill
				(thermal_gap 0.5)
				(thermal_bridge_width 0.5)
				(island_removal_mode 0)
			)
			(polygon
				(pts
					(xy 274.627086 -68.68414) (xy 275.897086 -68.68414) (xy 275.897086 -69.44614) (xy 274.627086 -69.44614)
				)
			)
		)
	)
	(footprint ""
		(layer "B.Cu")
		(at 477.698816 -146.359372)
		(property "Reference" "R6W10"
			(at 0.8382 -0.67818 0)
			(unlocked yes)
			(layer "B.SilkS")
			(effects
				(font
					(size 0.4064 0.254)
					(thickness 0.1524)
				)
				(justify left mirror)
			)
		)
		(property "Value" ""
			(at 0 0 0)
			(layer "B.Fab")
			(effects
				(font
					(size 1.27 1.27)
				)
				(justify mirror)
			)
		)
		(duplicate_pad_numbers_are_jumpers no)
		(fp_poly
			(pts
				(xy 0.2794 -0.1016) (xy -0.2794 -0.1016) (xy -0.2794 0.9906) (xy 0.2794 0.9906)
			)
			(stroke
				(width 0)
				(type default)
			)
			(fill no)
			(layer "B.CrtYd")
		)
		(fp_line
			(start -0.2794 -0.1016)
			(end 0.2794 -0.1016)
			(stroke
				(width 0.1)
				(type default)
			)
			(layer "B.Fab")
		)
		(fp_line
			(start -0.2794 0.9906)
			(end -0.2794 -0.1016)
			(stroke
				(width 0.1)
				(type default)
			)
			(layer "B.Fab")
		)
		(fp_line
			(start 0.2794 -0.1016)
			(end 0.2794 0.9906)
			(stroke
				(width 0.1)
				(type default)
			)
			(layer "B.Fab")
		)
		(fp_line
			(start 0.2794 0.9906)
			(end -0.2794 0.9906)
			(stroke
				(width 0.1)
				(type default)
			)
			(layer "B.Fab")
		)
		(pad "1" smd rect
			(at 0 0 180)
			(size 0.508 0.508)
			(layers "B.Cu" "B.Mask" "B.Paste")
			(net "P3V3_STBY")
		)
		(pad "2" smd rect
			(at 0 0.889 180)
			(size 0.508 0.508)
			(layers "B.Cu" "B.Mask" "B.Paste")
			(net "PCA9555_INT_N")
		)
		(zone
			(layer "B.Cu")
			(hatch none 0.5)
			(connect_pads
				(clearance 0)
			)
			(min_thickness 0.25)
			(keepout
				(tracks allowed)
				(vias not_allowed)
				(pads allowed)
				(copperpour not_allowed)
				(footprints allowed)
			)
			(placement
				(enabled no)
				(sheetname "")
			)
			(fill
				(thermal_gap 0.5)
				(thermal_bridge_width 0.5)
				(island_removal_mode 0)
			)
			(polygon
				(pts
					(xy 477.952816 -146.105372) (xy 477.444816 -146.105372) (xy 477.444816 -145.724372) (xy 477.952816 -145.724372)
				)
			)
		)
		(zone
			(layer "B.Cu")
			(hatch none 0.5)
			(connect_pads
				(clearance 0)
			)
			(min_thickness 0.25)
			(keepout
				(tracks not_allowed)
				(vias allowed)
				(pads allowed)
				(copperpour not_allowed)
				(footprints allowed)
			)
			(placement
				(enabled no)
				(sheetname "")
			)
			(fill
				(thermal_gap 0.5)
				(thermal_bridge_width 0.5)
				(island_removal_mode 0)
			)
			(polygon
				(pts
					(xy 477.952816 -145.724372) (xy 477.444816 -145.724372) (xy 477.444816 -146.105372) (xy 477.952816 -146.105372)
				)
			)
		)
	)
	(footprint ""
		(layer "B.Cu")
		(at 371.060472 -93.952822 180)
		(property "Reference" "R3N15"
			(at 0.8382 -0.67818 180)
			(unlocked yes)
			(layer "B.SilkS")
			(effects
				(font
					(size 0.4064 0.254)
					(thickness 0.1524)
				)
				(justify left mirror)
			)
		)
		(property "Value" ""
			(at 0 0 0)
			(layer "B.Fab")
			(effects
				(font
					(size 1.27 1.27)
				)
				(justify mirror)
			)
		)
		(duplicate_pad_numbers_are_jumpers no)
		(fp_poly
			(pts
				(xy 0.2794 -0.1016) (xy -0.2794 -0.1016) (xy -0.2794 0.9906) (xy 0.2794 0.9906)
			)
			(stroke
				(width 0)
				(type default)
			)
			(fill no)
			(layer "B.CrtYd")
		)
		(fp_line
			(start 0.2794 0.9906)
			(end -0.2794 0.9906)
			(stroke
				(width 0.1)
				(type default)
			)
			(layer "B.Fab")
		)
		(fp_line
			(start 0.2794 -0.1016)
			(end 0.2794 0.9906)
			(stroke
				(width 0.1)
				(type default)
			)
			(layer "B.Fab")
		)
		(fp_line
			(start -0.2794 0.9906)
			(end -0.2794 -0.1016)
			(stroke
				(width 0.1)
				(type default)
			)
			(layer "B.Fab")
		)
		(fp_line
			(start -0.2794 -0.1016)
			(end 0.2794 -0.1016)
			(stroke
				(width 0.1)
				(type default)
			)
			(layer "B.Fab")
		)
		(pad "1" smd rect
			(at 0 0)
			(size 0.508 0.508)
			(layers "B.Cu" "B.Mask" "B.Paste")
			(net "P1V05_PCH_STBY")
		)
		(pad "2" smd rect
			(at 0 0.889)
			(size 0.508 0.508)
			(layers "B.Cu" "B.Mask" "B.Paste")
			(net "FM_PRSNT_2_4_N")
		)
		(zone
			(layer "B.Cu")
			(hatch none 0.5)
			(connect_pads
				(clearance 0)
			)
			(min_thickness 0.25)
			(keepout
				(tracks not_allowed)
				(vias allowed)
				(pads allowed)
				(copperpour not_allowed)
				(footprints allowed)
			)
			(placement
				(enabled no)
				(sheetname "")
			)
			(fill
				(thermal_gap 0.5)
				(thermal_bridge_width 0.5)
				(island_removal_mode 0)
			)
			(polygon
				(pts
					(xy 370.806472 -94.587822) (xy 371.314472 -94.587822) (xy 371.314472 -94.206822) (xy 370.806472 -94.206822)
				)
			)
		)
		(zone
			(layer "B.Cu")
			(hatch none 0.5)
			(connect_pads
				(clearance 0)
			)
			(min_thickness 0.25)
			(keepout
				(tracks allowed)
				(vias not_allowed)
				(pads allowed)
				(copperpour not_allowed)
				(footprints allowed)
			)
			(placement
				(enabled no)
				(sheetname "")
			)
			(fill
				(thermal_gap 0.5)
				(thermal_bridge_width 0.5)
				(island_removal_mode 0)
			)
			(polygon
				(pts
					(xy 370.806472 -94.206822) (xy 371.314472 -94.206822) (xy 371.314472 -94.587822) (xy 370.806472 -94.587822)
				)
			)
		)
	)
	(footprint ""
		(layer "B.Cu")
		(at 402.13026 -54.24678)
		(property "Reference" "C3T4"
			(at 0 0 0)
			(layer "B.SilkS")
			(hide yes)
			(effects
				(font
					(size 1.27 1.27)
				)
				(justify mirror)
			)
		)
		(property "Value" ""
			(at 0 0 0)
			(layer "B.Fab")
			(effects
				(font
					(size 1.27 1.27)
				)
				(justify mirror)
			)
		)
		(duplicate_pad_numbers_are_jumpers no)
		(fp_poly
			(pts
				(xy -0.3048 -0.1016) (xy -0.3048 0.9906) (xy 0.3048 0.9906) (xy 0.3048 -0.1016)
			)
			(stroke
				(width 0)
				(type default)
			)
			(fill no)
			(layer "B.CrtYd")
		)
		(fp_line
			(start -0.3048 -0.1016)
			(end 0.3048 -0.1016)
			(stroke
				(width 0.1)
				(type default)
			)
			(layer "B.Fab")
		)
		(fp_line
			(start -0.3048 0.9906)
			(end -0.3048 -0.1016)
			(stroke
				(width 0.1)
				(type default)
			)
			(layer "B.Fab")
		)
		(fp_line
			(start 0.3048 -0.1016)
			(end 0.3048 0.9906)
			(stroke
				(width 0.1)
				(type default)
			)
			(layer "B.Fab")
		)
		(fp_line
			(start 0.3048 0.9906)
			(end -0.3048 0.9906)
			(stroke
				(width 0.1)
				(type default)
			)
			(layer "B.Fab")
		)
		(pad "1" smd rect
			(at 0 0 180)
			(size 0.508 0.508)
			(layers "B.Cu" "B.Mask" "B.Paste")
			(net "P3V3_STBY")
		)
		(pad "2" smd rect
			(at 0 0.889 180)
			(size 0.508 0.508)
			(layers "B.Cu" "B.Mask" "B.Paste")
			(net "GND")
		)
		(zone
			(layer "B.Cu")
			(hatch none 0.5)
			(connect_pads
				(clearance 0)
			)
			(min_thickness 0.25)
			(keepout
				(tracks allowed)
				(vias not_allowed)
				(pads allowed)
				(copperpour not_allowed)
				(footprints allowed)
			)
			(placement
				(enabled no)
				(sheetname "")
			)
			(fill
				(thermal_gap 0.5)
				(thermal_bridge_width 0.5)
				(island_removal_mode 0)
			)
			(polygon
				(pts
					(xy 402.38426 -53.99278) (xy 401.87626 -53.99278) (xy 401.87626 -53.61178) (xy 402.38426 -53.61178)
				)
			)
		)
		(zone
			(layer "B.Cu")
			(hatch none 0.5)
			(connect_pads
				(clearance 0)
			)
			(min_thickness 0.25)
			(keepout
				(tracks not_allowed)
				(vias allowed)
				(pads allowed)
				(copperpour not_allowed)
				(footprints allowed)
			)
			(placement
				(enabled no)
				(sheetname "")
			)
			(fill
				(thermal_gap 0.5)
				(thermal_bridge_width 0.5)
				(island_removal_mode 0)
			)
			(polygon
				(pts
					(xy 402.38426 -53.61178) (xy 401.87626 -53.61178) (xy 401.87626 -53.99278) (xy 402.38426 -53.99278)
				)
			)
		)
	)
	(footprint ""
		(layer "B.Cu")
		(at 344.461846 -90.97137 90)
		(property "Reference" "RF13"
			(at 0.8382 -0.67818 90)
			(unlocked yes)
			(layer "B.SilkS")
			(effects
				(font
					(size 0.4064 0.254)
					(thickness 0.1524)
				)
				(justify left mirror)
			)
		)
		(property "Value" ""
			(at 0 0 90)
			(layer "B.Fab")
			(effects
				(font
					(size 1.27 1.27)
				)
				(justify mirror)
			)
		)
		(duplicate_pad_numbers_are_jumpers no)
		(fp_poly
			(pts
				(xy 0.2794 -0.1016) (xy -0.2794 -0.1016) (xy -0.2794 0.9906) (xy 0.2794 0.9906)
			)
			(stroke
				(width 0)
				(type default)
			)
			(fill no)
			(layer "B.CrtYd")
		)
		(fp_line
			(start 0.2794 -0.1016)
			(end 0.2794 0.9906)
			(stroke
				(width 0.1)
				(type default)
			)
			(layer "B.Fab")
		)
		(fp_line
			(start -0.2794 -0.1016)
			(end 0.2794 -0.1016)
			(stroke
				(width 0.1)
				(type default)
			)
			(layer "B.Fab")
		)
		(fp_line
			(start 0.2794 0.9906)
			(end -0.2794 0.9906)
			(stroke
				(width 0.1)
				(type default)
			)
			(layer "B.Fab")
		)
		(fp_line
			(start -0.2794 0.9906)
			(end -0.2794 -0.1016)
			(stroke
				(width 0.1)
				(type default)
			)
			(layer "B.Fab")
		)
		(pad "1" smd rect
			(at 0 0 270)
			(size 0.508 0.508)
			(layers "B.Cu" "B.Mask" "B.Paste")
			(net "VR_PVCCIO_CPU0_AIREF1")
		)
		(pad "2" smd rect
			(at 0 0.889 270)
			(size 0.508 0.508)
			(layers "B.Cu" "B.Mask" "B.Paste")
			(net "ISENSE_PVCCIO_CPU0_PH1_IMON")
		)
		(zone
			(layer "B.Cu")
			(hatch none 0.5)
			(connect_pads
				(clearance 0)
			)
			(min_thickness 0.25)
			(keepout
				(tracks allowed)
				(vias not_allowed)
				(pads allowed)
				(copperpour not_allowed)
				(footprints allowed)
			)
			(placement
				(enabled no)
				(sheetname "")
			)
			(fill
				(thermal_gap 0.5)
				(thermal_bridge_width 0.5)
				(island_removal_mode 0)
			)
			(polygon
				(pts
					(xy 344.715846 -91.22537) (xy 344.715846 -90.71737) (xy 345.096846 -90.71737) (xy 345.096846 -91.22537)
				)
			)
		)
		(zone
			(layer "B.Cu")
			(hatch none 0.5)
			(connect_pads
				(clearance 0)
			)
			(min_thickness 0.25)
			(keepout
				(tracks not_allowed)
				(vias allowed)
				(pads allowed)
				(copperpour not_allowed)
				(footprints allowed)
			)
			(placement
				(enabled no)
				(sheetname "")
			)
			(fill
				(thermal_gap 0.5)
				(thermal_bridge_width 0.5)
				(island_removal_mode 0)
			)
			(polygon
				(pts
					(xy 345.096846 -91.22537) (xy 345.096846 -90.71737) (xy 344.715846 -90.71737) (xy 344.715846 -91.22537)
				)
			)
		)
	)
	(footprint ""
		(layer "B.Cu")
		(at 91.619324 -157.004258 90)
		(property "Reference" "C8L3"
			(at -1.47828 0.78994 180)
			(unlocked yes)
			(layer "B.SilkS")
			(effects
				(font
					(size 0.4064 0.254)
					(thickness 0.1524)
				)
				(justify mirror)
			)
		)
		(property "Value" ""
			(at 0 0 90)
			(layer "B.Fab")
			(effects
				(font
					(size 1.27 1.27)
				)
				(justify mirror)
			)
		)
		(duplicate_pad_numbers_are_jumpers no)
		(fp_poly
			(pts
				(xy 0.7239 -0.2159) (xy -0.7239 -0.2159) (xy -0.7239 1.9939) (xy 0.7239 1.9939)
			)
			(stroke
				(width 0)
				(type default)
			)
			(fill no)
			(layer "B.CrtYd")
		)
		(fp_line
			(start 0.7239 -0.2159)
			(end 0.7239 1.9939)
			(stroke
				(width 0.1)
				(type default)
			)
			(layer "B.Fab")
		)
		(fp_line
			(start -0.7239 -0.2159)
			(end 0.7239 -0.2159)
			(stroke
				(width 0.1)
				(type default)
			)
			(layer "B.Fab")
		)
		(fp_line
			(start 0.7239 1.9939)
			(end -0.7239 1.9939)
			(stroke
				(width 0.1)
				(type default)
			)
			(layer "B.Fab")
		)
		(fp_line
			(start -0.7239 1.9939)
			(end -0.7239 -0.2159)
			(stroke
				(width 0.1)
				(type default)
			)
			(layer "B.Fab")
		)
		(pad "1" smd rect
			(at 0 0 270)
			(size 1.27 1.016)
			(layers "B.Cu" "B.Mask" "B.Paste")
			(net "PVTT_KLM")
		)
		(pad "2" smd rect
			(at 0 1.778 270)
			(size 1.27 1.016)
			(layers "B.Cu" "B.Mask" "B.Paste")
			(net "GND")
		)
		(zone
			(layer "B.Cu")
			(hatch none 0.5)
			(connect_pads
				(clearance 0)
			)
			(min_thickness 0.25)
			(keepout
				(tracks not_allowed)
				(vias allowed)
				(pads allowed)
				(copperpour not_allowed)
				(footprints allowed)
			)
			(placement
				(enabled no)
				(sheetname "")
			)
			(fill
				(thermal_gap 0.5)
				(thermal_bridge_width 0.5)
				(island_removal_mode 0)
			)
			(polygon
				(pts
					(xy 92.127324 -157.639258) (xy 92.127324 -156.369258) (xy 92.889324 -156.369258) (xy 92.889324 -157.639258)
				)
			)
		)
	)
	(footprint ""
		(layer "B.Cu")
		(at 401.574 -87.3125 180)
		(property "Reference" "R2N26"
			(at 0.8382 -0.67818 180)
			(unlocked yes)
			(layer "B.SilkS")
			(effects
				(font
					(size 0.4064 0.254)
					(thickness 0.1524)
				)
				(justify left mirror)
			)
		)
		(property "Value" ""
			(at 0 0 0)
			(layer "B.Fab")
			(effects
				(font
					(size 1.27 1.27)
				)
				(justify mirror)
			)
		)
		(duplicate_pad_numbers_are_jumpers no)
		(fp_poly
			(pts
				(xy 0.2794 -0.1016) (xy -0.2794 -0.1016) (xy -0.2794 0.9906) (xy 0.2794 0.9906)
			)
			(stroke
				(width 0)
				(type default)
			)
			(fill no)
			(layer "B.CrtYd")
		)
		(fp_line
			(start 0.2794 0.9906)
			(end -0.2794 0.9906)
			(stroke
				(width 0.1)
				(type default)
			)
			(layer "B.Fab")
		)
		(fp_line
			(start 0.2794 -0.1016)
			(end 0.2794 0.9906)
			(stroke
				(width 0.1)
				(type default)
			)
			(layer "B.Fab")
		)
		(fp_line
			(start -0.2794 0.9906)
			(end -0.2794 -0.1016)
			(stroke
				(width 0.1)
				(type default)
			)
			(layer "B.Fab")
		)
		(fp_line
			(start -0.2794 -0.1016)
			(end 0.2794 -0.1016)
			(stroke
				(width 0.1)
				(type default)
			)
			(layer "B.Fab")
		)
		(pad "1" smd rect
			(at 0 0)
			(size 0.508 0.508)
			(layers "B.Cu" "B.Mask" "B.Paste")
			(net "FM_ADR_COMPLETE")
		)
		(pad "2" smd rect
			(at 0 0.889)
			(size 0.508 0.508)
			(layers "B.Cu" "B.Mask" "B.Paste")
			(net "FM_ADR_COMPLETE_R1")
		)
		(zone
			(layer "B.Cu")
			(hatch none 0.5)
			(connect_pads
				(clearance 0)
			)
			(min_thickness 0.25)
			(keepout
				(tracks not_allowed)
				(vias allowed)
				(pads allowed)
				(copperpour not_allowed)
				(footprints allowed)
			)
			(placement
				(enabled no)
				(sheetname "")
			)
			(fill
				(thermal_gap 0.5)
				(thermal_bridge_width 0.5)
				(island_removal_mode 0)
			)
			(polygon
				(pts
					(xy 401.32 -87.9475) (xy 401.828 -87.9475) (xy 401.828 -87.5665) (xy 401.32 -87.5665)
				)
			)
		)
		(zone
			(layer "B.Cu")
			(hatch none 0.5)
			(connect_pads
				(clearance 0)
			)
			(min_thickness 0.25)
			(keepout
				(tracks allowed)
				(vias not_allowed)
				(pads allowed)
				(copperpour not_allowed)
				(footprints allowed)
			)
			(placement
				(enabled no)
				(sheetname "")
			)
			(fill
				(thermal_gap 0.5)
				(thermal_bridge_width 0.5)
				(island_removal_mode 0)
			)
			(polygon
				(pts
					(xy 401.32 -87.5665) (xy 401.828 -87.5665) (xy 401.828 -87.9475) (xy 401.32 -87.9475)
				)
			)
		)
	)
	(footprint ""
		(layer "B.Cu")
		(at 130.61188 -67.764914)
		(property "Reference" "R7P25"
			(at 0 0 0)
			(layer "B.SilkS")
			(hide yes)
			(effects
				(font
					(size 1.27 1.27)
				)
				(justify mirror)
			)
		)
		(property "Value" ""
			(at 0 0 0)
			(layer "B.Fab")
			(effects
				(font
					(size 1.27 1.27)
				)
				(justify mirror)
			)
		)
		(duplicate_pad_numbers_are_jumpers no)
		(fp_poly
			(pts
				(xy 0.2794 -0.1016) (xy -0.2794 -0.1016) (xy -0.2794 0.9906) (xy 0.2794 0.9906)
			)
			(stroke
				(width 0)
				(type default)
			)
			(fill no)
			(layer "B.CrtYd")
		)
		(fp_line
			(start -0.2794 -0.1016)
			(end 0.2794 -0.1016)
			(stroke
				(width 0.1)
				(type default)
			)
			(layer "B.Fab")
		)
		(fp_line
			(start -0.2794 0.9906)
			(end -0.2794 -0.1016)
			(stroke
				(width 0.1)
				(type default)
			)
			(layer "B.Fab")
		)
		(fp_line
			(start 0.2794 -0.1016)
			(end 0.2794 0.9906)
			(stroke
				(width 0.1)
				(type default)
			)
			(layer "B.Fab")
		)
		(fp_line
			(start 0.2794 0.9906)
			(end -0.2794 0.9906)
			(stroke
				(width 0.1)
				(type default)
			)
			(layer "B.Fab")
		)
		(pad "1" smd rect
			(at 0 0 180)
			(size 0.508 0.508)
			(layers "B.Cu" "B.Mask" "B.Paste")
			(net "H_PM_SYNC_GTL_R2")
		)
		(pad "2" smd rect
			(at 0 0.889 180)
			(size 0.508 0.508)
			(layers "B.Cu" "B.Mask" "B.Paste")
			(net "H_PM_SYNC_GTL")
		)
		(zone
			(layer "B.Cu")
			(hatch none 0.5)
			(connect_pads
				(clearance 0)
			)
			(min_thickness 0.25)
			(keepout
				(tracks allowed)
				(vias not_allowed)
				(pads allowed)
				(copperpour not_allowed)
				(footprints allowed)
			)
			(placement
				(enabled no)
				(sheetname "")
			)
			(fill
				(thermal_gap 0.5)
				(thermal_bridge_width 0.5)
				(island_removal_mode 0)
			)
			(polygon
				(pts
					(xy 130.86588 -67.510914) (xy 130.35788 -67.510914) (xy 130.35788 -67.129914) (xy 130.86588 -67.129914)
				)
			)
		)
		(zone
			(layer "B.Cu")
			(hatch none 0.5)
			(connect_pads
				(clearance 0)
			)
			(min_thickness 0.25)
			(keepout
				(tracks not_allowed)
				(vias allowed)
				(pads allowed)
				(copperpour not_allowed)
				(footprints allowed)
			)
			(placement
				(enabled no)
				(sheetname "")
			)
			(fill
				(thermal_gap 0.5)
				(thermal_bridge_width 0.5)
				(island_removal_mode 0)
			)
			(polygon
				(pts
					(xy 130.86588 -67.129914) (xy 130.35788 -67.129914) (xy 130.35788 -67.510914) (xy 130.86588 -67.510914)
				)
			)
		)
	)
	(footprint ""
		(layer "B.Cu")
		(at 375.666 -101.1936 -90)
		(property "Reference" "C3N32"
			(at 0 0 90)
			(layer "B.SilkS")
			(hide yes)
			(effects
				(font
					(size 1.27 1.27)
				)
				(justify mirror)
			)
		)
		(property "Value" ""
			(at 0 0 90)
			(layer "B.Fab")
			(effects
				(font
					(size 1.27 1.27)
				)
				(justify mirror)
			)
		)
		(duplicate_pad_numbers_are_jumpers no)
		(fp_poly
			(pts
				(xy -0.3048 -0.1016) (xy -0.3048 0.9906) (xy 0.3048 0.9906) (xy 0.3048 -0.1016)
			)
			(stroke
				(width 0)
				(type default)
			)
			(fill no)
			(layer "B.CrtYd")
		)
		(fp_line
			(start -0.3048 0.9906)
			(end -0.3048 -0.1016)
			(stroke
				(width 0.1)
				(type default)
			)
			(layer "B.Fab")
		)
		(fp_line
			(start 0.3048 0.9906)
			(end -0.3048 0.9906)
			(stroke
				(width 0.1)
				(type default)
			)
			(layer "B.Fab")
		)
		(fp_line
			(start -0.3048 -0.1016)
			(end 0.3048 -0.1016)
			(stroke
				(width 0.1)
				(type default)
			)
			(layer "B.Fab")
		)
		(fp_line
			(start 0.3048 -0.1016)
			(end 0.3048 0.9906)
			(stroke
				(width 0.1)
				(type default)
			)
			(layer "B.Fab")
		)
		(pad "1" smd rect
			(at 0 0 90)
			(size 0.508 0.508)
			(layers "B.Cu" "B.Mask" "B.Paste")
			(net "RST_SRTCRST_N")
		)
		(pad "2" smd rect
			(at 0 0.889 90)
			(size 0.508 0.508)
			(layers "B.Cu" "B.Mask" "B.Paste")
			(net "GND")
		)
		(zone
			(layer "B.Cu")
			(hatch none 0.5)
			(connect_pads
				(clearance 0)
			)
			(min_thickness 0.25)
			(keepout
				(tracks not_allowed)
				(vias allowed)
				(pads allowed)
				(copperpour not_allowed)
				(footprints allowed)
			)
			(placement
				(enabled no)
				(sheetname "")
			)
			(fill
				(thermal_gap 0.5)
				(thermal_bridge_width 0.5)
				(island_removal_mode 0)
			)
			(polygon
				(pts
					(xy 375.031 -100.9396) (xy 375.031 -101.4476) (xy 375.412 -101.4476) (xy 375.412 -100.9396)
				)
			)
		)
		(zone
			(layer "B.Cu")
			(hatch none 0.5)
			(connect_pads
				(clearance 0)
			)
			(min_thickness 0.25)
			(keepout
				(tracks allowed)
				(vias not_allowed)
				(pads allowed)
				(copperpour not_allowed)
				(footprints allowed)
			)
			(placement
				(enabled no)
				(sheetname "")
			)
			(fill
				(thermal_gap 0.5)
				(thermal_bridge_width 0.5)
				(island_removal_mode 0)
			)
			(polygon
				(pts
					(xy 375.412 -100.9396) (xy 375.412 -101.4476) (xy 375.031 -101.4476) (xy 375.031 -100.9396)
				)
			)
		)
	)
	(footprint ""
		(layer "B.Cu")
		(at 362.671614 -125.558042 -90)
		(property "Reference" "C3M28"
			(at 0 0 90)
			(layer "B.SilkS")
			(hide yes)
			(effects
				(font
					(size 1.27 1.27)
				)
				(justify mirror)
			)
		)
		(property "Value" ""
			(at 0 0 90)
			(layer "B.Fab")
			(effects
				(font
					(size 1.27 1.27)
				)
				(justify mirror)
			)
		)
		(duplicate_pad_numbers_are_jumpers no)
		(fp_poly
			(pts
				(xy -0.3048 -0.1016) (xy -0.3048 0.9906) (xy 0.3048 0.9906) (xy 0.3048 -0.1016)
			)
			(stroke
				(width 0)
				(type default)
			)
			(fill no)
			(layer "B.CrtYd")
		)
		(fp_line
			(start -0.3048 0.9906)
			(end -0.3048 -0.1016)
			(stroke
				(width 0.1)
				(type default)
			)
			(layer "B.Fab")
		)
		(fp_line
			(start 0.3048 0.9906)
			(end -0.3048 0.9906)
			(stroke
				(width 0.1)
				(type default)
			)
			(layer "B.Fab")
		)
		(fp_line
			(start -0.3048 -0.1016)
			(end 0.3048 -0.1016)
			(stroke
				(width 0.1)
				(type default)
			)
			(layer "B.Fab")
		)
		(fp_line
			(start 0.3048 -0.1016)
			(end 0.3048 0.9906)
			(stroke
				(width 0.1)
				(type default)
			)
			(layer "B.Fab")
		)
		(pad "1" smd rect
			(at 0 0 90)
			(size 0.508 0.508)
			(layers "B.Cu" "B.Mask" "B.Paste")
			(net "P3E_CPU0_PE1_PCH_R_RXP<10>")
		)
		(pad "2" smd rect
			(at 0 0.889 90)
			(size 0.508 0.508)
			(layers "B.Cu" "B.Mask" "B.Paste")
			(net "P3E_CPU0_PE1_PCH_RXP<10>")
		)
		(zone
			(layer "B.Cu")
			(hatch none 0.5)
			(connect_pads
				(clearance 0)
			)
			(min_thickness 0.25)
			(keepout
				(tracks not_allowed)
				(vias allowed)
				(pads allowed)
				(copperpour not_allowed)
				(footprints allowed)
			)
			(placement
				(enabled no)
				(sheetname "")
			)
			(fill
				(thermal_gap 0.5)
				(thermal_bridge_width 0.5)
				(island_removal_mode 0)
			)
			(polygon
				(pts
					(xy 362.036614 -125.304042) (xy 362.036614 -125.812042) (xy 362.417614 -125.812042) (xy 362.417614 -125.304042)
				)
			)
		)
		(zone
			(layer "B.Cu")
			(hatch none 0.5)
			(connect_pads
				(clearance 0)
			)
			(min_thickness 0.25)
			(keepout
				(tracks allowed)
				(vias not_allowed)
				(pads allowed)
				(copperpour not_allowed)
				(footprints allowed)
			)
			(placement
				(enabled no)
				(sheetname "")
			)
			(fill
				(thermal_gap 0.5)
				(thermal_bridge_width 0.5)
				(island_removal_mode 0)
			)
			(polygon
				(pts
					(xy 362.417614 -125.304042) (xy 362.417614 -125.812042) (xy 362.036614 -125.812042) (xy 362.036614 -125.304042)
				)
			)
		)
	)
	(footprint ""
		(layer "B.Cu")
		(at 394.335 -65.3415 90)
		(property "Reference" "R2T9"
			(at 0 0 90)
			(layer "B.SilkS")
			(hide yes)
			(effects
				(font
					(size 1.27 1.27)
				)
				(justify mirror)
			)
		)
		(property "Value" ""
			(at 0 0 90)
			(layer "B.Fab")
			(effects
				(font
					(size 1.27 1.27)
				)
				(justify mirror)
			)
		)
		(duplicate_pad_numbers_are_jumpers no)
		(fp_poly
			(pts
				(xy 0.2794 -0.1016) (xy -0.2794 -0.1016) (xy -0.2794 0.9906) (xy 0.2794 0.9906)
			)
			(stroke
				(width 0)
				(type default)
			)
			(fill no)
			(layer "B.CrtYd")
		)
		(fp_line
			(start 0.2794 -0.1016)
			(end 0.2794 0.9906)
			(stroke
				(width 0.1)
				(type default)
			)
			(layer "B.Fab")
		)
		(fp_line
			(start -0.2794 -0.1016)
			(end 0.2794 -0.1016)
			(stroke
				(width 0.1)
				(type default)
			)
			(layer "B.Fab")
		)
		(fp_line
			(start 0.2794 0.9906)
			(end -0.2794 0.9906)
			(stroke
				(width 0.1)
				(type default)
			)
			(layer "B.Fab")
		)
		(fp_line
			(start -0.2794 0.9906)
			(end -0.2794 -0.1016)
			(stroke
				(width 0.1)
				(type default)
			)
			(layer "B.Fab")
		)
		(pad "1" smd rect
			(at 0 0 270)
			(size 0.508 0.508)
			(layers "B.Cu" "B.Mask" "B.Paste")
			(net "SPI_CS0_SECONDARY_N")
		)
		(pad "2" smd rect
			(at 0 0.889 270)
			(size 0.508 0.508)
			(layers "B.Cu" "B.Mask" "B.Paste")
			(net "SPI_CS0_SECONDARY_R_N")
		)
		(zone
			(layer "B.Cu")
			(hatch none 0.5)
			(connect_pads
				(clearance 0)
			)
			(min_thickness 0.25)
			(keepout
				(tracks allowed)
				(vias not_allowed)
				(pads allowed)
				(copperpour not_allowed)
				(footprints allowed)
			)
			(placement
				(enabled no)
				(sheetname "")
			)
			(fill
				(thermal_gap 0.5)
				(thermal_bridge_width 0.5)
				(island_removal_mode 0)
			)
			(polygon
				(pts
					(xy 394.589 -65.5955) (xy 394.589 -65.0875) (xy 394.97 -65.0875) (xy 394.97 -65.5955)
				)
			)
		)
		(zone
			(layer "B.Cu")
			(hatch none 0.5)
			(connect_pads
				(clearance 0)
			)
			(min_thickness 0.25)
			(keepout
				(tracks not_allowed)
				(vias allowed)
				(pads allowed)
				(copperpour not_allowed)
				(footprints allowed)
			)
			(placement
				(enabled no)
				(sheetname "")
			)
			(fill
				(thermal_gap 0.5)
				(thermal_bridge_width 0.5)
				(island_removal_mode 0)
			)
			(polygon
				(pts
					(xy 394.97 -65.5955) (xy 394.97 -65.0875) (xy 394.589 -65.0875) (xy 394.589 -65.5955)
				)
			)
		)
	)
	(footprint ""
		(layer "B.Cu")
		(at 102.946454 -68.17614 180)
		(property "Reference" "C8P34"
			(at 0 0 0)
			(layer "B.SilkS")
			(hide yes)
			(effects
				(font
					(size 1.27 1.27)
				)
				(justify mirror)
			)
		)
		(property "Value" ""
			(at 0 0 0)
			(layer "B.Fab")
			(effects
				(font
					(size 1.27 1.27)
				)
				(justify mirror)
			)
		)
		(duplicate_pad_numbers_are_jumpers no)
		(fp_poly
			(pts
				(xy 0.7239 -0.2159) (xy -0.7239 -0.2159) (xy -0.7239 1.9939) (xy 0.7239 1.9939)
			)
			(stroke
				(width 0)
				(type default)
			)
			(fill no)
			(layer "B.CrtYd")
		)
		(fp_line
			(start 0.7239 1.9939)
			(end -0.7239 1.9939)
			(stroke
				(width 0.1)
				(type default)
			)
			(layer "B.Fab")
		)
		(fp_line
			(start 0.7239 -0.2159)
			(end 0.7239 1.9939)
			(stroke
				(width 0.1)
				(type default)
			)
			(layer "B.Fab")
		)
		(fp_line
			(start -0.7239 1.9939)
			(end -0.7239 -0.2159)
			(stroke
				(width 0.1)
				(type default)
			)
			(layer "B.Fab")
		)
		(fp_line
			(start -0.7239 -0.2159)
			(end 0.7239 -0.2159)
			(stroke
				(width 0.1)
				(type default)
			)
			(layer "B.Fab")
		)
		(pad "1" smd rect
			(at 0 0)
			(size 1.27 1.016)
			(layers "B.Cu" "B.Mask" "B.Paste")
			(net "PVDDQ_GHJ")
		)
		(pad "2" smd rect
			(at 0 1.778)
			(size 1.27 1.016)
			(layers "B.Cu" "B.Mask" "B.Paste")
			(net "GND")
		)
		(zone
			(layer "B.Cu")
			(hatch none 0.5)
			(connect_pads
				(clearance 0)
			)
			(min_thickness 0.25)
			(keepout
				(tracks not_allowed)
				(vias allowed)
				(pads allowed)
				(copperpour not_allowed)
				(footprints allowed)
			)
			(placement
				(enabled no)
				(sheetname "")
			)
			(fill
				(thermal_gap 0.5)
				(thermal_bridge_width 0.5)
				(island_removal_mode 0)
			)
			(polygon
				(pts
					(xy 102.311454 -68.68414) (xy 103.581454 -68.68414) (xy 103.581454 -69.44614) (xy 102.311454 -69.44614)
				)
			)
		)
	)
	(footprint ""
		(layer "B.Cu")
		(at 373.945404 -75.495404)
		(property "Reference" "C3R3"
			(at 0 0 0)
			(layer "B.SilkS")
			(hide yes)
			(effects
				(font
					(size 1.27 1.27)
				)
				(justify mirror)
			)
		)
		(property "Value" ""
			(at 0 0 0)
			(layer "B.Fab")
			(effects
				(font
					(size 1.27 1.27)
				)
				(justify mirror)
			)
		)
		(duplicate_pad_numbers_are_jumpers no)
		(fp_rect
			(start 0.2794 0.9144)
			(end -0.2794 -0.1143)
			(stroke
				(width 0)
				(type default)
			)
			(fill no)
			(layer "B.CrtYd")
		)
		(fp_line
			(start -0.2794 -0.1143)
			(end -0.2794 0.9144)
			(stroke
				(width 0.1)
				(type default)
			)
			(layer "B.Fab")
		)
		(fp_line
			(start -0.2794 0.9144)
			(end 0.2794 0.9144)
			(stroke
				(width 0.1)
				(type default)
			)
			(layer "B.Fab")
		)
		(fp_line
			(start 0.2794 -0.1143)
			(end -0.2794 -0.1143)
			(stroke
				(width 0.1)
				(type default)
			)
			(layer "B.Fab")
		)
		(fp_line
			(start 0.2794 0.9144)
			(end 0.2794 -0.1143)
			(stroke
				(width 0.1)
				(type default)
			)
			(layer "B.Fab")
		)
		(pad "1" smd custom
			(at 0 0 270)
			(size 0.10414 0.10414)
			(layers "B.Cu" "B.Mask" "B.Paste")
			(net "P3V3_STBY")
			(options
				(clearance outline)
				(anchor circle)
			)
			(primitives
				(gr_poly
					(pts
						(xy -0.20828 -0.08636) (xy -0.20828 0.08636) (xy -0.08636 0.20828) (xy 0.086614 0.20828) (xy 0.20828 0.086614)
						(xy 0.20828 -0.08636) (xy 0.08636 -0.20828) (xy -0.08636 -0.20828)
					)
					(width 0)
					(fill yes)
				)
			)
		)
		(pad "2" smd custom
			(at 0 0.8001 270)
			(size 0.10414 0.10414)
			(layers "B.Cu" "B.Mask" "B.Paste")
			(net "GND")
			(options
				(clearance outline)
				(anchor circle)
			)
			(primitives
				(gr_poly
					(pts
						(xy -0.20828 -0.08636) (xy -0.20828 0.08636) (xy -0.08636 0.20828) (xy 0.086614 0.20828) (xy 0.20828 0.086614)
						(xy 0.20828 -0.08636) (xy 0.08636 -0.20828) (xy -0.08636 -0.20828)
					)
					(width 0)
					(fill yes)
				)
			)
		)
		(zone
			(layer "B.Cu")
			(hatch none 0.5)
			(connect_pads
				(clearance 0)
			)
			(min_thickness 0.25)
			(keepout
				(tracks allowed)
				(vias not_allowed)
				(pads allowed)
				(copperpour not_allowed)
				(footprints allowed)
			)
			(placement
				(enabled no)
				(sheetname "")
			)
			(fill
				(thermal_gap 0.5)
				(thermal_bridge_width 0.5)
				(island_removal_mode 0)
			)
			(polygon
				(pts
					(xy 374.033034 -75.285854) (xy 374.033034 -74.904854) (xy 373.857774 -74.904854) (xy 373.85752 -75.285854)
				)
			)
		)
		(zone
			(layer "B.Cu")
			(hatch none 0.5)
			(connect_pads
				(clearance 0)
			)
			(min_thickness 0.25)
			(keepout
				(tracks not_allowed)
				(vias allowed)
				(pads allowed)
				(copperpour not_allowed)
				(footprints allowed)
			)
			(placement
				(enabled no)
				(sheetname "")
			)
			(fill
				(thermal_gap 0.5)
				(thermal_bridge_width 0.5)
				(island_removal_mode 0)
			)
			(polygon
				(pts
					(xy 374.033034 -75.285854) (xy 374.033034 -74.904854) (xy 373.857774 -74.904854) (xy 373.85752 -75.285854)
				)
			)
		)
	)
	(footprint ""
		(layer "B.Cu")
		(at 445.503046 -150.810722 90)
		(property "Reference" "U25W14"
			(at 0.14986 2.621788 90)
			(unlocked yes)
			(layer "B.SilkS")
			(effects
				(font
					(size 1.27 0.964946)
					(thickness 0.000001)
				)
				(justify left mirror)
			)
		)
		(property "Value" ""
			(at 0 0 90)
			(layer "B.Fab")
			(effects
				(font
					(size 1.27 1.27)
				)
				(justify mirror)
			)
		)
		(duplicate_pad_numbers_are_jumpers no)
		(fp_circle
			(center 0.4699 -0.8382)
			(end 0.4699 -0.7112)
			(stroke
				(width 0.254)
				(type default)
			)
			(fill no)
			(layer "B.SilkS")
		)
		(fp_poly
			(pts
				(xy -0.21463 -0.450088) (xy -1.56337 -0.450088) (xy -1.56337 1.75006) (xy -0.21463 1.75006)
			)
			(stroke
				(width 0)
				(type default)
			)
			(fill no)
			(layer "B.CrtYd")
		)
		(fp_line
			(start -0.21463 -0.450088)
			(end -1.56337 -0.450088)
			(stroke
				(width 0.1)
				(type default)
			)
			(layer "B.Fab")
		)
		(fp_line
			(start -1.56337 -0.450088)
			(end -1.56337 1.75006)
			(stroke
				(width 0.1)
				(type default)
			)
			(layer "B.Fab")
		)
		(fp_line
			(start -0.21463 1.75006)
			(end -0.21463 -0.450088)
			(stroke
				(width 0.1)
				(type default)
			)
			(layer "B.Fab")
		)
		(fp_line
			(start -1.56337 1.75006)
			(end -0.21463 1.75006)
			(stroke
				(width 0.1)
				(type default)
			)
			(layer "B.Fab")
		)
		(fp_circle
			(center 0.4699 -0.8382)
			(end 0.4699 -0.7112)
			(stroke
				(width 0.254)
				(type default)
			)
			(fill no)
			(layer "B.Fab")
		)
		(pad "1" smd rect
			(at 0 0 270)
			(size 1.016 0.381)
			(layers "B.Cu" "B.Mask" "B.Paste")
			(net "Net_6509")
		)
		(pad "2" smd rect
			(at 0 0.649986 270)
			(size 1.016 0.381)
			(layers "B.Cu" "B.Mask" "B.Paste")
			(net "XDP_PRESENT_N")
		)
		(pad "3" smd rect
			(at 0 1.299972 270)
			(size 1.016 0.381)
			(layers "B.Cu" "B.Mask" "B.Paste")
			(net "GND")
		)
		(pad "4" smd rect
			(at -1.778 1.299972 270)
			(size 1.016 0.381)
			(layers "B.Cu" "B.Mask" "B.Paste")
			(net "CPU_XDP_PRESENT_N")
		)
		(pad "5" smd rect
			(at -1.778 0 270)
			(size 1.016 0.381)
			(layers "B.Cu" "B.Mask" "B.Paste")
			(net "P3V3_STBY")
		)
	)
	(footprint ""
		(layer "B.Cu")
		(at 174.5234 -146.939 -90)
		(property "Reference" "R6L8"
			(at 0 0 90)
			(layer "B.SilkS")
			(hide yes)
			(effects
				(font
					(size 1.27 1.27)
				)
				(justify mirror)
			)
		)
		(property "Value" ""
			(at 0 0 90)
			(layer "B.Fab")
			(effects
				(font
					(size 1.27 1.27)
				)
				(justify mirror)
			)
		)
		(duplicate_pad_numbers_are_jumpers no)
		(fp_rect
			(start -0.2794 -0.1016)
			(end 0.2794 0.9906)
			(stroke
				(width 0)
				(type default)
			)
			(fill no)
			(layer "B.CrtYd")
		)
		(fp_line
			(start -0.2794 0.9906)
			(end -0.2794 -0.1016)
			(stroke
				(width 0.1)
				(type default)
			)
			(layer "B.Fab")
		)
		(fp_line
			(start 0.2794 0.9906)
			(end -0.2794 0.9906)
			(stroke
				(width 0.1)
				(type default)
			)
			(layer "B.Fab")
		)
		(fp_line
			(start -0.2794 -0.1016)
			(end 0.2794 -0.1016)
			(stroke
				(width 0.1)
				(type default)
			)
			(layer "B.Fab")
		)
		(fp_line
			(start 0.2794 -0.1016)
			(end 0.2794 0.9906)
			(stroke
				(width 0.1)
				(type default)
			)
			(layer "B.Fab")
		)
		(pad "1" smd rect
			(at 0 0 90)
			(size 0.508 0.508)
			(layers "B.Cu" "B.Mask" "B.Paste")
			(net "P3V3")
		)
		(pad "2" smd rect
			(at 0 0.889 90)
			(size 0.508 0.508)
			(layers "B.Cu" "B.Mask" "B.Paste")
			(net "VR_PVTT_KLM_BIAS")
		)
		(zone
			(layer "B.Cu")
			(hatch none 0.5)
			(connect_pads
				(clearance 0)
			)
			(min_thickness 0.25)
			(keepout
				(tracks allowed)
				(vias not_allowed)
				(pads allowed)
				(copperpour not_allowed)
				(footprints allowed)
			)
			(placement
				(enabled no)
				(sheetname "")
			)
			(fill
				(thermal_gap 0.5)
				(thermal_bridge_width 0.5)
				(island_removal_mode 0)
			)
			(polygon
				(pts
					(xy 174.2694 -147.193) (xy 173.8884 -147.193) (xy 173.8884 -146.685) (xy 174.2694 -146.685)
				)
			)
		)
		(zone
			(layer "B.Cu")
			(hatch none 0.5)
			(connect_pads
				(clearance 0)
			)
			(min_thickness 0.25)
			(keepout
				(tracks not_allowed)
				(vias allowed)
				(pads allowed)
				(copperpour not_allowed)
				(footprints allowed)
			)
			(placement
				(enabled no)
				(sheetname "")
			)
			(fill
				(thermal_gap 0.5)
				(thermal_bridge_width 0.5)
				(island_removal_mode 0)
			)
			(polygon
				(pts
					(xy 174.2694 -147.193) (xy 173.8884 -147.193) (xy 173.8884 -146.685) (xy 174.2694 -146.685)
				)
			)
		)
	)
	(footprint ""
		(layer "B.Cu")
		(at 500.38 -151.0538 180)
		(property "Reference" "R6W37"
			(at 0.8382 -0.67818 180)
			(unlocked yes)
			(layer "B.SilkS")
			(effects
				(font
					(size 0.4064 0.254)
					(thickness 0.1524)
				)
				(justify left mirror)
			)
		)
		(property "Value" ""
			(at 0 0 0)
			(layer "B.Fab")
			(effects
				(font
					(size 1.27 1.27)
				)
				(justify mirror)
			)
		)
		(duplicate_pad_numbers_are_jumpers no)
		(fp_poly
			(pts
				(xy 0.2794 -0.1016) (xy -0.2794 -0.1016) (xy -0.2794 0.9906) (xy 0.2794 0.9906)
			)
			(stroke
				(width 0)
				(type default)
			)
			(fill no)
			(layer "B.CrtYd")
		)
		(fp_line
			(start 0.2794 0.9906)
			(end -0.2794 0.9906)
			(stroke
				(width 0.1)
				(type default)
			)
			(layer "B.Fab")
		)
		(fp_line
			(start 0.2794 -0.1016)
			(end 0.2794 0.9906)
			(stroke
				(width 0.1)
				(type default)
			)
			(layer "B.Fab")
		)
		(fp_line
			(start -0.2794 0.9906)
			(end -0.2794 -0.1016)
			(stroke
				(width 0.1)
				(type default)
			)
			(layer "B.Fab")
		)
		(fp_line
			(start -0.2794 -0.1016)
			(end 0.2794 -0.1016)
			(stroke
				(width 0.1)
				(type default)
			)
			(layer "B.Fab")
		)
		(pad "1" smd rect
			(at 0 0)
			(size 0.508 0.508)
			(layers "B.Cu" "B.Mask" "B.Paste")
			(net "SPA_MID_DBG2_TX_R")
		)
		(pad "2" smd rect
			(at 0 0.889)
			(size 0.508 0.508)
			(layers "B.Cu" "B.Mask" "B.Paste")
			(net "SPA_MID_DBG2_TX")
		)
		(zone
			(layer "B.Cu")
			(hatch none 0.5)
			(connect_pads
				(clearance 0)
			)
			(min_thickness 0.25)
			(keepout
				(tracks not_allowed)
				(vias allowed)
				(pads allowed)
				(copperpour not_allowed)
				(footprints allowed)
			)
			(placement
				(enabled no)
				(sheetname "")
			)
			(fill
				(thermal_gap 0.5)
				(thermal_bridge_width 0.5)
				(island_removal_mode 0)
			)
			(polygon
				(pts
					(xy 500.126 -151.6888) (xy 500.634 -151.6888) (xy 500.634 -151.3078) (xy 500.126 -151.3078)
				)
			)
		)
		(zone
			(layer "B.Cu")
			(hatch none 0.5)
			(connect_pads
				(clearance 0)
			)
			(min_thickness 0.25)
			(keepout
				(tracks allowed)
				(vias not_allowed)
				(pads allowed)
				(copperpour not_allowed)
				(footprints allowed)
			)
			(placement
				(enabled no)
				(sheetname "")
			)
			(fill
				(thermal_gap 0.5)
				(thermal_bridge_width 0.5)
				(island_removal_mode 0)
			)
			(polygon
				(pts
					(xy 500.126 -151.3078) (xy 500.634 -151.3078) (xy 500.634 -151.6888) (xy 500.126 -151.6888)
				)
			)
		)
	)
	(footprint ""
		(layer "B.Cu")
		(at 177.906426 -21.0439 90)
		(property "Reference" "R6T6"
			(at 0 0 90)
			(layer "B.SilkS")
			(hide yes)
			(effects
				(font
					(size 1.27 1.27)
				)
				(justify mirror)
			)
		)
		(property "Value" ""
			(at 0 0 90)
			(layer "B.Fab")
			(effects
				(font
					(size 1.27 1.27)
				)
				(justify mirror)
			)
		)
		(duplicate_pad_numbers_are_jumpers no)
		(fp_poly
			(pts
				(xy 0.2794 -0.1016) (xy -0.2794 -0.1016) (xy -0.2794 0.9906) (xy 0.2794 0.9906)
			)
			(stroke
				(width 0)
				(type default)
			)
			(fill no)
			(layer "B.CrtYd")
		)
		(fp_line
			(start 0.2794 -0.1016)
			(end 0.2794 0.9906)
			(stroke
				(width 0.1)
				(type default)
			)
			(layer "B.Fab")
		)
		(fp_line
			(start -0.2794 -0.1016)
			(end 0.2794 -0.1016)
			(stroke
				(width 0.1)
				(type default)
			)
			(layer "B.Fab")
		)
		(fp_line
			(start 0.2794 0.9906)
			(end -0.2794 0.9906)
			(stroke
				(width 0.1)
				(type default)
			)
			(layer "B.Fab")
		)
		(fp_line
			(start -0.2794 0.9906)
			(end -0.2794 -0.1016)
			(stroke
				(width 0.1)
				(type default)
			)
			(layer "B.Fab")
		)
		(pad "1" smd rect
			(at 0 0 270)
			(size 0.508 0.508)
			(layers "B.Cu" "B.Mask" "B.Paste")
			(net "PVCCIO_CPU1")
		)
		(pad "2" smd rect
			(at 0 0.889 270)
			(size 0.508 0.508)
			(layers "B.Cu" "B.Mask" "B.Paste")
			(net "XDP_CPU1_TDI")
		)
		(zone
			(layer "B.Cu")
			(hatch none 0.5)
			(connect_pads
				(clearance 0)
			)
			(min_thickness 0.25)
			(keepout
				(tracks allowed)
				(vias not_allowed)
				(pads allowed)
				(copperpour not_allowed)
				(footprints allowed)
			)
			(placement
				(enabled no)
				(sheetname "")
			)
			(fill
				(thermal_gap 0.5)
				(thermal_bridge_width 0.5)
				(island_removal_mode 0)
			)
			(polygon
				(pts
					(xy 178.160426 -21.2979) (xy 178.160426 -20.7899) (xy 178.541426 -20.7899) (xy 178.541426 -21.2979)
				)
			)
		)
		(zone
			(layer "B.Cu")
			(hatch none 0.5)
			(connect_pads
				(clearance 0)
			)
			(min_thickness 0.25)
			(keepout
				(tracks not_allowed)
				(vias allowed)
				(pads allowed)
				(copperpour not_allowed)
				(footprints allowed)
			)
			(placement
				(enabled no)
				(sheetname "")
			)
			(fill
				(thermal_gap 0.5)
				(thermal_bridge_width 0.5)
				(island_removal_mode 0)
			)
			(polygon
				(pts
					(xy 178.541426 -21.2979) (xy 178.541426 -20.7899) (xy 178.160426 -20.7899) (xy 178.160426 -21.2979)
				)
			)
		)
	)
	(footprint ""
		(layer "B.Cu")
		(at 446.381632 -35.8775 90)
		(property "Reference" "R25W6"
			(at 0 0 90)
			(layer "B.SilkS")
			(hide yes)
			(effects
				(font
					(size 1.27 1.27)
				)
				(justify mirror)
			)
		)
		(property "Value" "*"
			(at -0.064008 -4.108196 90)
			(unlocked yes)
			(layer "B.Fab")
			(hide yes)
			(effects
				(font
					(size 1.27 1.016)
					(thickness 0.1524)
				)
				(justify mirror)
			)
		)
		(property "Device Type" "120R2F-GP_RCL_GP-120R2F-GP,64.A"
			(at -0.064008 -5.632196 90)
			(unlocked yes)
			(layer "B.Fab")
			(hide yes)
			(effects
				(font
					(size 1.27 1.016)
					(thickness 0.1524)
				)
				(justify mirror)
			)
		)
		(duplicate_pad_numbers_are_jumpers no)
		(fp_line
			(start 0.508 -0.9398)
			(end 0.508 0.9398)
			(stroke
				(width 0.1524)
				(type default)
			)
			(layer "B.SilkS")
		)
		(fp_line
			(start -0.508 -0.9398)
			(end 0.508 -0.9398)
			(stroke
				(width 0.1524)
				(type default)
			)
			(layer "B.SilkS")
		)
		(fp_rect
			(start 0.508 0.9398)
			(end -0.508 -0.9398)
			(stroke
				(width 0)
				(type default)
			)
			(fill no)
			(layer "B.CrtYd")
		)
		(fp_rect
			(start 0.508 0.9398)
			(end -0.508 -0.9398)
			(stroke
				(width 0)
				(type default)
			)
			(fill no)
			(layer "B.Fab")
		)
		(pad "1" smd custom
			(at 0 -0.4445 270)
			(size 0.1397 0.1397)
			(layers "B.Cu" "B.Mask" "B.Paste")
			(net "GND")
			(options
				(clearance outline)
				(anchor circle)
			)
			(primitives
				(gr_poly
					(pts
						(arc
							(start -0.1778 0.2794)
							(mid -0.249642 0.249642)
							(end -0.2794 0.1778)
						)
						(arc
							(start -0.2794 -0.1778)
							(mid -0.249642 -0.249642)
							(end -0.1778 -0.2794)
						)
						(arc
							(start 0.1778 -0.2794)
							(mid 0.249642 -0.249642)
							(end 0.2794 -0.1778)
						)
						(arc
							(start 0.2794 0.1778)
							(mid 0.249642 0.249642)
							(end 0.1778 0.2794)
						)
					)
					(width 0)
					(fill yes)
				)
			)
		)
		(pad "2" smd custom
			(at 0 0.4445 270)
			(size 0.1397 0.1397)
			(layers "B.Cu" "B.Mask" "B.Paste")
			(net "BMC_M_RAS_N")
			(options
				(clearance outline)
				(anchor circle)
			)
			(primitives
				(gr_poly
					(pts
						(arc
							(start -0.1778 0.2794)
							(mid -0.249642 0.249642)
							(end -0.2794 0.1778)
						)
						(arc
							(start -0.2794 -0.1778)
							(mid -0.249642 -0.249642)
							(end -0.1778 -0.2794)
						)
						(arc
							(start 0.1778 -0.2794)
							(mid 0.249642 -0.249642)
							(end 0.2794 -0.1778)
						)
						(arc
							(start 0.2794 0.1778)
							(mid 0.249642 0.249642)
							(end 0.1778 0.2794)
						)
					)
					(width 0)
					(fill yes)
				)
			)
		)
	)
	(footprint ""
		(layer "B.Cu")
		(at 108.178854 -77.82814)
		(property "Reference" "C7P10"
			(at 0 0 0)
			(layer "B.SilkS")
			(hide yes)
			(effects
				(font
					(size 1.27 1.27)
				)
				(justify mirror)
			)
		)
		(property "Value" ""
			(at 0 0 0)
			(layer "B.Fab")
			(effects
				(font
					(size 1.27 1.27)
				)
				(justify mirror)
			)
		)
		(duplicate_pad_numbers_are_jumpers no)
		(fp_poly
			(pts
				(xy 0.7239 -0.2159) (xy -0.7239 -0.2159) (xy -0.7239 1.9939) (xy 0.7239 1.9939)
			)
			(stroke
				(width 0)
				(type default)
			)
			(fill no)
			(layer "B.CrtYd")
		)
		(fp_line
			(start -0.7239 -0.2159)
			(end 0.7239 -0.2159)
			(stroke
				(width 0.1)
				(type default)
			)
			(layer "B.Fab")
		)
		(fp_line
			(start -0.7239 1.9939)
			(end -0.7239 -0.2159)
			(stroke
				(width 0.1)
				(type default)
			)
			(layer "B.Fab")
		)
		(fp_line
			(start 0.7239 -0.2159)
			(end 0.7239 1.9939)
			(stroke
				(width 0.1)
				(type default)
			)
			(layer "B.Fab")
		)
		(fp_line
			(start 0.7239 1.9939)
			(end -0.7239 1.9939)
			(stroke
				(width 0.1)
				(type default)
			)
			(layer "B.Fab")
		)
		(pad "1" smd rect
			(at 0 0 180)
			(size 1.27 1.016)
			(layers "B.Cu" "B.Mask" "B.Paste")
			(net "PVCCMCP_CPU1")
		)
		(pad "2" smd rect
			(at 0 1.778 180)
			(size 1.27 1.016)
			(layers "B.Cu" "B.Mask" "B.Paste")
			(net "GND")
		)
		(zone
			(layer "B.Cu")
			(hatch none 0.5)
			(connect_pads
				(clearance 0)
			)
			(min_thickness 0.25)
			(keepout
				(tracks not_allowed)
				(vias allowed)
				(pads allowed)
				(copperpour not_allowed)
				(footprints allowed)
			)
			(placement
				(enabled no)
				(sheetname "")
			)
			(fill
				(thermal_gap 0.5)
				(thermal_bridge_width 0.5)
				(island_removal_mode 0)
			)
			(polygon
				(pts
					(xy 108.813854 -77.32014) (xy 107.543854 -77.32014) (xy 107.543854 -76.55814) (xy 108.813854 -76.55814)
				)
			)
		)
	)
	(footprint ""
		(layer "B.Cu")
		(at 474.85046 -27.29992 180)
		(property "Reference" "R2T23"
			(at 0 0 0)
			(layer "B.SilkS")
			(hide yes)
			(effects
				(font
					(size 1.27 1.27)
				)
				(justify mirror)
			)
		)
		(property "Value" ""
			(at 0 0 0)
			(layer "B.Fab")
			(effects
				(font
					(size 1.27 1.27)
				)
				(justify mirror)
			)
		)
		(duplicate_pad_numbers_are_jumpers no)
		(fp_poly
			(pts
				(xy 0.4953 -0.2032) (xy -0.4953 -0.2032) (xy -0.4953 1.6002) (xy 0.4953 1.6002)
			)
			(stroke
				(width 0)
				(type default)
			)
			(fill no)
			(layer "B.CrtYd")
		)
		(fp_line
			(start 0.4953 1.6002)
			(end 0.4953 -0.2032)
			(stroke
				(width 0.1)
				(type default)
			)
			(layer "B.Fab")
		)
		(fp_line
			(start 0.4953 -0.2032)
			(end -0.4953 -0.2032)
			(stroke
				(width 0.1)
				(type default)
			)
			(layer "B.Fab")
		)
		(fp_line
			(start -0.4953 1.6002)
			(end 0.4953 1.6002)
			(stroke
				(width 0.1)
				(type default)
			)
			(layer "B.Fab")
		)
		(fp_line
			(start -0.4953 -0.2032)
			(end -0.4953 1.6002)
			(stroke
				(width 0.1)
				(type default)
			)
			(layer "B.Fab")
		)
		(pad "1" smd rect
			(at 0 0)
			(size 0.762 0.889)
			(layers "B.Cu" "B.Mask" "B.Paste")
			(net "P3V3_STBY_MNG")
		)
		(pad "2" smd rect
			(at 0 1.397)
			(size 0.762 0.889)
			(layers "B.Cu" "B.Mask" "B.Paste")
			(net "P3V3_STBY_MNG_RGMII")
		)
		(zone
			(layer "B.Cu")
			(hatch none 0.5)
			(connect_pads
				(clearance 0)
			)
			(min_thickness 0.25)
			(keepout
				(tracks not_allowed)
				(vias allowed)
				(pads allowed)
				(copperpour not_allowed)
				(footprints allowed)
			)
			(placement
				(enabled no)
				(sheetname "")
			)
			(fill
				(thermal_gap 0.5)
				(thermal_bridge_width 0.5)
				(island_removal_mode 0)
			)
			(polygon
				(pts
					(xy 474.46946 -28.25242) (xy 474.46946 -27.74442) (xy 475.23146 -27.74442) (xy 475.23146 -28.25242)
				)
			)
		)
		(zone
			(layer "B.Cu")
			(hatch none 0.5)
			(connect_pads
				(clearance 0)
			)
			(min_thickness 0.25)
			(keepout
				(tracks allowed)
				(vias not_allowed)
				(pads allowed)
				(copperpour not_allowed)
				(footprints allowed)
			)
			(placement
				(enabled no)
				(sheetname "")
			)
			(fill
				(thermal_gap 0.5)
				(thermal_bridge_width 0.5)
				(island_removal_mode 0)
			)
			(polygon
				(pts
					(xy 475.23146 -28.25242) (xy 475.23146 -27.74442) (xy 474.46946 -27.74442) (xy 474.46946 -28.25242)
				)
			)
		)
	)
	(footprint ""
		(layer "B.Cu")
		(at 488.696 -18.161 -90)
		(property "Reference" "R1R3"
			(at 0.8382 -0.67818 270)
			(unlocked yes)
			(layer "B.SilkS")
			(effects
				(font
					(size 0.4064 0.254)
					(thickness 0.1524)
				)
				(justify left mirror)
			)
		)
		(property "Value" ""
			(at 0 0 90)
			(layer "B.Fab")
			(effects
				(font
					(size 1.27 1.27)
				)
				(justify mirror)
			)
		)
		(duplicate_pad_numbers_are_jumpers no)
		(fp_poly
			(pts
				(xy 0.2794 -0.1016) (xy -0.2794 -0.1016) (xy -0.2794 0.9906) (xy 0.2794 0.9906)
			)
			(stroke
				(width 0)
				(type default)
			)
			(fill no)
			(layer "B.CrtYd")
		)
		(fp_line
			(start -0.2794 0.9906)
			(end -0.2794 -0.1016)
			(stroke
				(width 0.1)
				(type default)
			)
			(layer "B.Fab")
		)
		(fp_line
			(start 0.2794 0.9906)
			(end -0.2794 0.9906)
			(stroke
				(width 0.1)
				(type default)
			)
			(layer "B.Fab")
		)
		(fp_line
			(start -0.2794 -0.1016)
			(end 0.2794 -0.1016)
			(stroke
				(width 0.1)
				(type default)
			)
			(layer "B.Fab")
		)
		(fp_line
			(start 0.2794 -0.1016)
			(end 0.2794 0.9906)
			(stroke
				(width 0.1)
				(type default)
			)
			(layer "B.Fab")
		)
		(pad "1" smd rect
			(at 0 0 90)
			(size 0.508 0.508)
			(layers "B.Cu" "B.Mask" "B.Paste")
			(net "P3V3_STBY")
		)
		(pad "2" smd rect
			(at 0 0.889 90)
			(size 0.508 0.508)
			(layers "B.Cu" "B.Mask" "B.Paste")
			(net "PU_NV_WP_N")
		)
		(zone
			(layer "B.Cu")
			(hatch none 0.5)
			(connect_pads
				(clearance 0)
			)
			(min_thickness 0.25)
			(keepout
				(tracks not_allowed)
				(vias allowed)
				(pads allowed)
				(copperpour not_allowed)
				(footprints allowed)
			)
			(placement
				(enabled no)
				(sheetname "")
			)
			(fill
				(thermal_gap 0.5)
				(thermal_bridge_width 0.5)
				(island_removal_mode 0)
			)
			(polygon
				(pts
					(xy 488.061 -17.907) (xy 488.061 -18.415) (xy 488.442 -18.415) (xy 488.442 -17.907)
				)
			)
		)
		(zone
			(layer "B.Cu")
			(hatch none 0.5)
			(connect_pads
				(clearance 0)
			)
			(min_thickness 0.25)
			(keepout
				(tracks allowed)
				(vias not_allowed)
				(pads allowed)
				(copperpour not_allowed)
				(footprints allowed)
			)
			(placement
				(enabled no)
				(sheetname "")
			)
			(fill
				(thermal_gap 0.5)
				(thermal_bridge_width 0.5)
				(island_removal_mode 0)
			)
			(polygon
				(pts
					(xy 488.442 -17.907) (xy 488.442 -18.415) (xy 488.061 -18.415) (xy 488.061 -17.907)
				)
			)
		)
	)
	(footprint ""
		(layer "B.Cu")
		(at 388.0104 -125.507242 -90)
		(property "Reference" "R3M12"
			(at 0 0 90)
			(layer "B.SilkS")
			(hide yes)
			(effects
				(font
					(size 1.27 1.27)
				)
				(justify mirror)
			)
		)
		(property "Value" ""
			(at 0 0 90)
			(layer "B.Fab")
			(effects
				(font
					(size 1.27 1.27)
				)
				(justify mirror)
			)
		)
		(duplicate_pad_numbers_are_jumpers no)
		(fp_poly
			(pts
				(xy 0.2794 -0.1016) (xy -0.2794 -0.1016) (xy -0.2794 0.9906) (xy 0.2794 0.9906)
			)
			(stroke
				(width 0)
				(type default)
			)
			(fill no)
			(layer "B.CrtYd")
		)
		(fp_line
			(start -0.2794 0.9906)
			(end -0.2794 -0.1016)
			(stroke
				(width 0.1)
				(type default)
			)
			(layer "B.Fab")
		)
		(fp_line
			(start 0.2794 0.9906)
			(end -0.2794 0.9906)
			(stroke
				(width 0.1)
				(type default)
			)
			(layer "B.Fab")
		)
		(fp_line
			(start -0.2794 -0.1016)
			(end 0.2794 -0.1016)
			(stroke
				(width 0.1)
				(type default)
			)
			(layer "B.Fab")
		)
		(fp_line
			(start 0.2794 -0.1016)
			(end 0.2794 0.9906)
			(stroke
				(width 0.1)
				(type default)
			)
			(layer "B.Fab")
		)
		(pad "1" smd rect
			(at 0 0 90)
			(size 0.508 0.508)
			(layers "B.Cu" "B.Mask" "B.Paste")
			(net "A_PCIEUP_RCOMP_P")
		)
		(pad "2" smd rect
			(at 0 0.889 90)
			(size 0.508 0.508)
			(layers "B.Cu" "B.Mask" "B.Paste")
			(net "A_PCIEUP_RCOMP_N")
		)
		(zone
			(layer "B.Cu")
			(hatch none 0.5)
			(connect_pads
				(clearance 0)
			)
			(min_thickness 0.25)
			(keepout
				(tracks not_allowed)
				(vias allowed)
				(pads allowed)
				(copperpour not_allowed)
				(footprints allowed)
			)
			(placement
				(enabled no)
				(sheetname "")
			)
			(fill
				(thermal_gap 0.5)
				(thermal_bridge_width 0.5)
				(island_removal_mode 0)
			)
			(polygon
				(pts
					(xy 387.3754 -125.253242) (xy 387.3754 -125.761242) (xy 387.7564 -125.761242) (xy 387.7564 -125.253242)
				)
			)
		)
		(zone
			(layer "B.Cu")
			(hatch none 0.5)
			(connect_pads
				(clearance 0)
			)
			(min_thickness 0.25)
			(keepout
				(tracks allowed)
				(vias not_allowed)
				(pads allowed)
				(copperpour not_allowed)
				(footprints allowed)
			)
			(placement
				(enabled no)
				(sheetname "")
			)
			(fill
				(thermal_gap 0.5)
				(thermal_bridge_width 0.5)
				(island_removal_mode 0)
			)
			(polygon
				(pts
					(xy 387.7564 -125.253242) (xy 387.7564 -125.761242) (xy 387.3754 -125.761242) (xy 387.3754 -125.253242)
				)
			)
		)
	)
	(footprint ""
		(layer "B.Cu")
		(at 87.158068 -17.7546 -90)
		(property "Reference" "C8T8"
			(at -1.848866 0.752348 270)
			(unlocked yes)
			(layer "B.SilkS")
			(effects
				(font
					(size 1.27 0.9652)
					(thickness 0.1524)
				)
				(justify mirror)
			)
		)
		(property "Value" ""
			(at 0 0 90)
			(layer "B.Fab")
			(effects
				(font
					(size 1.27 1.27)
				)
				(justify mirror)
			)
		)
		(duplicate_pad_numbers_are_jumpers no)
		(fp_rect
			(start 0.500126 1.598422)
			(end -0.500126 -0.201422)
			(stroke
				(width 0)
				(type default)
			)
			(fill no)
			(layer "B.CrtYd")
		)
		(fp_line
			(start -0.500126 1.598422)
			(end 0.500126 1.598422)
			(stroke
				(width 0.1)
				(type default)
			)
			(layer "B.Fab")
		)
		(fp_line
			(start 0.500126 1.598422)
			(end 0.500126 -0.201422)
			(stroke
				(width 0.1)
				(type default)
			)
			(layer "B.Fab")
		)
		(fp_line
			(start -0.500126 -0.201422)
			(end -0.500126 1.598422)
			(stroke
				(width 0.1)
				(type default)
			)
			(layer "B.Fab")
		)
		(fp_line
			(start 0.500126 -0.201422)
			(end -0.500126 -0.201422)
			(stroke
				(width 0.1)
				(type default)
			)
			(layer "B.Fab")
		)
		(pad "1" smd rect
			(at 0 0 180)
			(size 0.889 0.9906)
			(layers "B.Cu" "B.Mask" "B.Paste")
			(net "PVDDQ_GHJ")
		)
		(pad "2" smd rect
			(at 0 1.397 180)
			(size 0.889 0.9906)
			(layers "B.Cu" "B.Mask" "B.Paste")
			(net "GND")
		)
		(zone
			(layer "B.Cu")
			(hatch none 0.5)
			(connect_pads
				(clearance 0)
			)
			(min_thickness 0.25)
			(keepout
				(tracks allowed)
				(vias not_allowed)
				(pads allowed)
				(copperpour not_allowed)
				(footprints allowed)
			)
			(placement
				(enabled no)
				(sheetname "")
			)
			(fill
				(thermal_gap 0.5)
				(thermal_bridge_width 0.5)
				(island_removal_mode 0)
			)
			(polygon
				(pts
					(xy 86.205568 -17.2593) (xy 86.713568 -17.2593) (xy 86.713568 -18.2499) (xy 86.205568 -18.2499)
				)
			)
		)
		(zone
			(layer "B.Cu")
			(hatch none 0.5)
			(connect_pads
				(clearance 0)
			)
			(min_thickness 0.25)
			(keepout
				(tracks not_allowed)
				(vias allowed)
				(pads allowed)
				(copperpour not_allowed)
				(footprints allowed)
			)
			(placement
				(enabled no)
				(sheetname "")
			)
			(fill
				(thermal_gap 0.5)
				(thermal_bridge_width 0.5)
				(island_removal_mode 0)
			)
			(polygon
				(pts
					(xy 86.205568 -17.2593) (xy 86.713568 -17.2593) (xy 86.713568 -18.2499) (xy 86.205568 -18.2499)
				)
			)
		)
	)
	(footprint ""
		(layer "B.Cu")
		(at 413.0675 -26.162 -90)
		(property "Reference" "C25W31"
			(at 0.8382 -0.67818 270)
			(unlocked yes)
			(layer "B.SilkS")
			(effects
				(font
					(size 0.4064 0.254)
					(thickness 0.1524)
				)
				(justify left mirror)
			)
		)
		(property "Value" ""
			(at 0 0 90)
			(layer "B.Fab")
			(effects
				(font
					(size 1.27 1.27)
				)
				(justify mirror)
			)
		)
		(duplicate_pad_numbers_are_jumpers no)
		(fp_poly
			(pts
				(xy -0.3048 -0.1016) (xy -0.3048 0.9906) (xy 0.3048 0.9906) (xy 0.3048 -0.1016)
			)
			(stroke
				(width 0)
				(type default)
			)
			(fill no)
			(layer "B.CrtYd")
		)
		(fp_line
			(start -0.3048 0.9906)
			(end -0.3048 -0.1016)
			(stroke
				(width 0.1)
				(type default)
			)
			(layer "B.Fab")
		)
		(fp_line
			(start 0.3048 0.9906)
			(end -0.3048 0.9906)
			(stroke
				(width 0.1)
				(type default)
			)
			(layer "B.Fab")
		)
		(fp_line
			(start -0.3048 -0.1016)
			(end 0.3048 -0.1016)
			(stroke
				(width 0.1)
				(type default)
			)
			(layer "B.Fab")
		)
		(fp_line
			(start 0.3048 -0.1016)
			(end 0.3048 0.9906)
			(stroke
				(width 0.1)
				(type default)
			)
			(layer "B.Fab")
		)
		(pad "1" smd rect
			(at 0 0 90)
			(size 0.508 0.508)
			(layers "B.Cu" "B.Mask" "B.Paste")
			(net "VCC_ADCAV3V3")
		)
		(pad "2" smd rect
			(at 0 0.889 90)
			(size 0.508 0.508)
			(layers "B.Cu" "B.Mask" "B.Paste")
			(net "GND")
		)
		(zone
			(layer "B.Cu")
			(hatch none 0.5)
			(connect_pads
				(clearance 0)
			)
			(min_thickness 0.25)
			(keepout
				(tracks not_allowed)
				(vias allowed)
				(pads allowed)
				(copperpour not_allowed)
				(footprints allowed)
			)
			(placement
				(enabled no)
				(sheetname "")
			)
			(fill
				(thermal_gap 0.5)
				(thermal_bridge_width 0.5)
				(island_removal_mode 0)
			)
			(polygon
				(pts
					(xy 412.4325 -25.908) (xy 412.4325 -26.416) (xy 412.8135 -26.416) (xy 412.8135 -25.908)
				)
			)
		)
		(zone
			(layer "B.Cu")
			(hatch none 0.5)
			(connect_pads
				(clearance 0)
			)
			(min_thickness 0.25)
			(keepout
				(tracks allowed)
				(vias not_allowed)
				(pads allowed)
				(copperpour not_allowed)
				(footprints allowed)
			)
			(placement
				(enabled no)
				(sheetname "")
			)
			(fill
				(thermal_gap 0.5)
				(thermal_bridge_width 0.5)
				(island_removal_mode 0)
			)
			(polygon
				(pts
					(xy 412.8135 -25.908) (xy 412.8135 -26.416) (xy 412.4325 -26.416) (xy 412.4325 -25.908)
				)
			)
		)
	)
	(footprint ""
		(layer "B.Cu")
		(at 253.392432 -17.7546 90)
		(property "Reference" "C5T9"
			(at -1.848866 0.752348 90)
			(unlocked yes)
			(layer "B.SilkS")
			(effects
				(font
					(size 1.27 0.9652)
					(thickness 0.1524)
				)
				(justify mirror)
			)
		)
		(property "Value" ""
			(at 0 0 90)
			(layer "B.Fab")
			(effects
				(font
					(size 1.27 1.27)
				)
				(justify mirror)
			)
		)
		(duplicate_pad_numbers_are_jumpers no)
		(fp_rect
			(start 0.500126 1.598422)
			(end -0.500126 -0.201422)
			(stroke
				(width 0)
				(type default)
			)
			(fill no)
			(layer "B.CrtYd")
		)
		(fp_line
			(start 0.500126 -0.201422)
			(end -0.500126 -0.201422)
			(stroke
				(width 0.1)
				(type default)
			)
			(layer "B.Fab")
		)
		(fp_line
			(start -0.500126 -0.201422)
			(end -0.500126 1.598422)
			(stroke
				(width 0.1)
				(type default)
			)
			(layer "B.Fab")
		)
		(fp_line
			(start 0.500126 1.598422)
			(end 0.500126 -0.201422)
			(stroke
				(width 0.1)
				(type default)
			)
			(layer "B.Fab")
		)
		(fp_line
			(start -0.500126 1.598422)
			(end 0.500126 1.598422)
			(stroke
				(width 0.1)
				(type default)
			)
			(layer "B.Fab")
		)
		(pad "1" smd rect
			(at 0 0)
			(size 0.889 0.9906)
			(layers "B.Cu" "B.Mask" "B.Paste")
			(net "PVDDQ_ABC")
		)
		(pad "2" smd rect
			(at 0 1.397)
			(size 0.889 0.9906)
			(layers "B.Cu" "B.Mask" "B.Paste")
			(net "GND")
		)
		(zone
			(layer "B.Cu")
			(hatch none 0.5)
			(connect_pads
				(clearance 0)
			)
			(min_thickness 0.25)
			(keepout
				(tracks allowed)
				(vias not_allowed)
				(pads allowed)
				(copperpour not_allowed)
				(footprints allowed)
			)
			(placement
				(enabled no)
				(sheetname "")
			)
			(fill
				(thermal_gap 0.5)
				(thermal_bridge_width 0.5)
				(island_removal_mode 0)
			)
			(polygon
				(pts
					(xy 254.344932 -18.2499) (xy 253.836932 -18.2499) (xy 253.836932 -17.2593) (xy 254.344932 -17.2593)
				)
			)
		)
		(zone
			(layer "B.Cu")
			(hatch none 0.5)
			(connect_pads
				(clearance 0)
			)
			(min_thickness 0.25)
			(keepout
				(tracks not_allowed)
				(vias allowed)
				(pads allowed)
				(copperpour not_allowed)
				(footprints allowed)
			)
			(placement
				(enabled no)
				(sheetname "")
			)
			(fill
				(thermal_gap 0.5)
				(thermal_bridge_width 0.5)
				(island_removal_mode 0)
			)
			(polygon
				(pts
					(xy 254.344932 -18.2499) (xy 253.836932 -18.2499) (xy 253.836932 -17.2593) (xy 254.344932 -17.2593)
				)
			)
		)
	)
	(footprint ""
		(layer "B.Cu")
		(at 18.6309 -124.5616 180)
		(property "Reference" "C9M3"
			(at 3.03657 4.9784 270)
			(unlocked yes)
			(layer "B.SilkS")
			(effects
				(font
					(size 0.7874 0.5842)
					(thickness 0.1524)
				)
				(justify mirror)
			)
		)
		(property "Value" ""
			(at 0 0 0)
			(layer "B.Fab")
			(effects
				(font
					(size 1.27 1.27)
				)
				(justify mirror)
			)
		)
		(duplicate_pad_numbers_are_jumpers no)
		(fp_line
			(start 2.563114 1.633728)
			(end 1.6002 1.633728)
			(stroke
				(width 0.1524)
				(type default)
			)
			(layer "B.SilkS")
		)
		(fp_line
			(start 2.563114 -1.616456)
			(end 2.563114 1.633728)
			(stroke
				(width 0.1524)
				(type default)
			)
			(layer "B.SilkS")
		)
		(fp_line
			(start 2.286 7.366)
			(end 2.286 1.632712)
			(stroke
				(width 0.1524)
				(type default)
			)
			(layer "B.SilkS")
		)
		(fp_line
			(start 2.286 7.366)
			(end 1.60147 7.366)
			(stroke
				(width 0.1524)
				(type default)
			)
			(layer "B.SilkS")
		)
		(fp_line
			(start 1.6002 -1.616456)
			(end 2.563114 -1.616456)
			(stroke
				(width 0.1524)
				(type default)
			)
			(layer "B.SilkS")
		)
		(fp_line
			(start -1.6002 -1.616456)
			(end -2.504948 -1.616456)
			(stroke
				(width 0.1524)
				(type default)
			)
			(layer "B.SilkS")
		)
		(fp_line
			(start -2.286 7.366)
			(end -1.600708 7.366)
			(stroke
				(width 0.1524)
				(type default)
			)
			(layer "B.SilkS")
		)
		(fp_line
			(start -2.286 7.366)
			(end -2.286 1.63195)
			(stroke
				(width 0.1524)
				(type default)
			)
			(layer "B.SilkS")
		)
		(fp_line
			(start -2.504948 1.633728)
			(end -1.6002 1.633728)
			(stroke
				(width 0.1524)
				(type default)
			)
			(layer "B.SilkS")
		)
		(fp_line
			(start -2.504948 -1.616456)
			(end -2.504948 1.633728)
			(stroke
				(width 0.1524)
				(type default)
			)
			(layer "B.SilkS")
		)
		(fp_rect
			(start 2.286 7.366)
			(end -2.286 -0.254)
			(stroke
				(width 0)
				(type default)
			)
			(fill no)
			(layer "B.CrtYd")
		)
		(fp_line
			(start 2.286 7.366)
			(end 2.286 -0.254)
			(stroke
				(width 0.1)
				(type default)
			)
			(layer "B.Fab")
		)
		(fp_line
			(start 2.286 -0.254)
			(end -2.286 -0.254)
			(stroke
				(width 0.1)
				(type default)
			)
			(layer "B.Fab")
		)
		(fp_line
			(start -2.286 7.366)
			(end 2.286 7.366)
			(stroke
				(width 0.1)
				(type default)
			)
			(layer "B.Fab")
		)
		(fp_line
			(start -2.286 -0.254)
			(end -2.286 7.366)
			(stroke
				(width 0.1)
				(type default)
			)
			(layer "B.Fab")
		)
		(pad "1" smd rect
			(at 0 0)
			(size 2.54 3.048)
			(layers "B.Cu" "B.Mask" "B.Paste")
			(net "P12V_STBY")
		)
		(pad "2" smd rect
			(at 0 7.112)
			(size 2.54 3.048)
			(layers "B.Cu" "B.Mask" "B.Paste")
			(net "GND")
		)
	)
	(footprint ""
		(layer "B.Cu")
		(at 410.591 -48.768)
		(property "Reference" "R1T5"
			(at 0 0 0)
			(layer "B.SilkS")
			(hide yes)
			(effects
				(font
					(size 1.27 1.27)
				)
				(justify mirror)
			)
		)
		(property "Value" ""
			(at 0 0 0)
			(layer "B.Fab")
			(effects
				(font
					(size 1.27 1.27)
				)
				(justify mirror)
			)
		)
		(duplicate_pad_numbers_are_jumpers no)
		(fp_poly
			(pts
				(xy 0.2794 -0.1016) (xy -0.2794 -0.1016) (xy -0.2794 0.9906) (xy 0.2794 0.9906)
			)
			(stroke
				(width 0)
				(type default)
			)
			(fill no)
			(layer "B.CrtYd")
		)
		(fp_line
			(start -0.2794 -0.1016)
			(end 0.2794 -0.1016)
			(stroke
				(width 0.1)
				(type default)
			)
			(layer "B.Fab")
		)
		(fp_line
			(start -0.2794 0.9906)
			(end -0.2794 -0.1016)
			(stroke
				(width 0.1)
				(type default)
			)
			(layer "B.Fab")
		)
		(fp_line
			(start 0.2794 -0.1016)
			(end 0.2794 0.9906)
			(stroke
				(width 0.1)
				(type default)
			)
			(layer "B.Fab")
		)
		(fp_line
			(start 0.2794 0.9906)
			(end -0.2794 0.9906)
			(stroke
				(width 0.1)
				(type default)
			)
			(layer "B.Fab")
		)
		(pad "1" smd rect
			(at 0 0 180)
			(size 0.508 0.508)
			(layers "B.Cu" "B.Mask" "B.Paste")
			(net "P3V3_STBY")
		)
		(pad "2" smd rect
			(at 0 0.889 180)
			(size 0.508 0.508)
			(layers "B.Cu" "B.Mask" "B.Paste")
			(net "FM_BOARD_REV_ID2")
		)
	)
	(footprint ""
		(layer "B.Cu")
		(at 155.194 1.7018 90)
		(property "Reference" "C7U5"
			(at 0 0 90)
			(layer "B.SilkS")
			(hide yes)
			(effects
				(font
					(size 1.27 1.27)
				)
				(justify mirror)
			)
		)
		(property "Value" ""
			(at 0 0 90)
			(layer "B.Fab")
			(effects
				(font
					(size 1.27 1.27)
				)
				(justify mirror)
			)
		)
		(duplicate_pad_numbers_are_jumpers no)
		(fp_poly
			(pts
				(xy 0.4953 -0.2032) (xy -0.4953 -0.2032) (xy -0.4953 1.6002) (xy 0.4953 1.6002)
			)
			(stroke
				(width 0)
				(type default)
			)
			(fill no)
			(layer "B.CrtYd")
		)
		(fp_line
			(start 0.4953 -0.2032)
			(end -0.4953 -0.2032)
			(stroke
				(width 0.1)
				(type default)
			)
			(layer "B.Fab")
		)
		(fp_line
			(start -0.4953 -0.2032)
			(end -0.4953 1.6002)
			(stroke
				(width 0.1)
				(type default)
			)
			(layer "B.Fab")
		)
		(fp_line
			(start 0.4953 1.6002)
			(end 0.4953 -0.2032)
			(stroke
				(width 0.1)
				(type default)
			)
			(layer "B.Fab")
		)
		(fp_line
			(start -0.4953 1.6002)
			(end 0.4953 1.6002)
			(stroke
				(width 0.1)
				(type default)
			)
			(layer "B.Fab")
		)
		(pad "1" smd rect
			(at 0 0 270)
			(size 0.762 0.889)
			(layers "B.Cu" "B.Mask" "B.Paste")
			(net "PVPP_GHJ")
		)
		(pad "2" smd rect
			(at 0 1.397 270)
			(size 0.762 0.889)
			(layers "B.Cu" "B.Mask" "B.Paste")
			(net "GND")
		)
		(zone
			(layer "B.Cu")
			(hatch none 0.5)
			(connect_pads
				(clearance 0)
			)
			(min_thickness 0.25)
			(keepout
				(tracks not_allowed)
				(vias allowed)
				(pads allowed)
				(copperpour not_allowed)
				(footprints allowed)
			)
			(placement
				(enabled no)
				(sheetname "")
			)
			(fill
				(thermal_gap 0.5)
				(thermal_bridge_width 0.5)
				(island_removal_mode 0)
			)
			(polygon
				(pts
					(xy 155.6385 1.3208) (xy 155.6385 2.0828) (xy 156.1465 2.0828) (xy 156.1465 1.3208)
				)
			)
		)
	)
	(footprint ""
		(layer "B.Cu")
		(at 266.397232 -12.954 90)
		(property "Reference" "C5G46"
			(at -1.14681 0.76708 180)
			(unlocked yes)
			(layer "B.SilkS")
			(effects
				(font
					(size 0.7874 0.5842)
					(thickness 0.1524)
				)
				(justify mirror)
			)
		)
		(property "Value" ""
			(at 0 0 90)
			(layer "B.Fab")
			(effects
				(font
					(size 1.27 1.27)
				)
				(justify mirror)
			)
		)
		(duplicate_pad_numbers_are_jumpers no)
		(fp_rect
			(start -0.4953 -0.2032)
			(end 0.4953 1.6002)
			(stroke
				(width 0)
				(type default)
			)
			(fill no)
			(layer "B.CrtYd")
		)
		(fp_line
			(start 0.4953 -0.2032)
			(end -0.4953 -0.2032)
			(stroke
				(width 0.1)
				(type default)
			)
			(layer "B.Fab")
		)
		(fp_line
			(start -0.4953 -0.2032)
			(end -0.4953 1.6002)
			(stroke
				(width 0.1)
				(type default)
			)
			(layer "B.Fab")
		)
		(fp_line
			(start 0.4953 1.6002)
			(end 0.4953 -0.2032)
			(stroke
				(width 0.1)
				(type default)
			)
			(layer "B.Fab")
		)
		(fp_line
			(start -0.4953 1.6002)
			(end 0.4953 1.6002)
			(stroke
				(width 0.1)
				(type default)
			)
			(layer "B.Fab")
		)
		(pad "1" smd rect
			(at 0 0 270)
			(size 0.762 0.889)
			(layers "B.Cu" "B.Mask" "B.Paste")
			(net "PVDDQ_ABC")
		)
		(pad "2" smd rect
			(at 0 1.397 270)
			(size 0.762 0.889)
			(layers "B.Cu" "B.Mask" "B.Paste")
			(net "GND")
		)
		(zone
			(layer "B.Cu")
			(hatch none 0.5)
			(connect_pads
				(clearance 0)
			)
			(min_thickness 0.25)
			(keepout
				(tracks not_allowed)
				(vias allowed)
				(pads allowed)
				(copperpour not_allowed)
				(footprints allowed)
			)
			(placement
				(enabled no)
				(sheetname "")
			)
			(fill
				(thermal_gap 0.5)
				(thermal_bridge_width 0.5)
				(island_removal_mode 0)
			)
			(polygon
				(pts
					(xy 266.841732 -12.573) (xy 267.349732 -12.573) (xy 267.349732 -13.335) (xy 266.841732 -13.335)
				)
			)
		)
	)
	(footprint ""
		(layer "B.Cu")
		(at 16.383 -90.805)
		(property "Reference" "C9W2"
			(at 0 0 0)
			(layer "B.SilkS")
			(hide yes)
			(effects
				(font
					(size 1.27 1.27)
				)
				(justify mirror)
			)
		)
		(property "Value" "*"
			(at -1.1811 -2.8194 0)
			(unlocked yes)
			(layer "B.Fab")
			(hide yes)
			(effects
				(font
					(size 1.27 1.016)
					(thickness 0.1524)
				)
				(justify mirror)
			)
		)
		(property "Device Type" "SC22P50V2JN-4GP_SMD-BCG-SC22P5A"
			(at -1.1811 -4.3434 0)
			(unlocked yes)
			(layer "B.Fab")
			(hide yes)
			(effects
				(font
					(size 1.27 1.016)
					(thickness 0.1524)
				)
				(justify mirror)
			)
		)
		(duplicate_pad_numbers_are_jumpers no)
		(fp_rect
			(start 0.4318 0.9525)
			(end -0.4318 -0.9525)
			(stroke
				(width 0)
				(type default)
			)
			(fill no)
			(layer "B.CrtYd")
		)
		(fp_rect
			(start 0.4318 0.9525)
			(end -0.4318 -0.9525)
			(stroke
				(width 0)
				(type default)
			)
			(fill no)
			(layer "B.Fab")
		)
		(pad "1" smd custom
			(at 0 -0.4445 180)
			(size 0.1524 0.1524)
			(layers "B.Cu" "B.Mask" "B.Paste")
			(net "A_P12V_STBY_ADR_TRIGGER")
			(options
				(clearance outline)
				(anchor circle)
			)
			(primitives
				(gr_poly
					(pts
						(arc
							(start 0.3048 0.2032)
							(mid 0.275042 0.275042)
							(end 0.2032 0.3048)
						)
						(arc
							(start -0.2032 0.3048)
							(mid -0.275042 0.275042)
							(end -0.3048 0.2032)
						)
						(arc
							(start -0.3048 -0.2032)
							(mid -0.275042 -0.275042)
							(end -0.2032 -0.3048)
						)
						(arc
							(start 0.2032 -0.3048)
							(mid 0.275042 -0.275042)
							(end 0.3048 -0.2032)
						)
					)
					(width 0)
					(fill yes)
				)
			)
		)
		(pad "2" smd custom
			(at 0 0.4445 180)
			(size 0.1524 0.1524)
			(layers "B.Cu" "B.Mask" "B.Paste")
			(net "AGND_HSC")
			(options
				(clearance outline)
				(anchor circle)
			)
			(primitives
				(gr_poly
					(pts
						(arc
							(start 0.3048 0.2032)
							(mid 0.275042 0.275042)
							(end 0.2032 0.3048)
						)
						(arc
							(start -0.2032 0.3048)
							(mid -0.275042 0.275042)
							(end -0.3048 0.2032)
						)
						(arc
							(start -0.3048 -0.2032)
							(mid -0.275042 -0.275042)
							(end -0.2032 -0.3048)
						)
						(arc
							(start 0.2032 -0.3048)
							(mid 0.275042 -0.275042)
							(end 0.3048 -0.2032)
						)
					)
					(width 0)
					(fill yes)
				)
			)
		)
	)
	(footprint ""
		(layer "B.Cu")
		(at 471.95486 -130.0734)
		(property "Reference" "R1M21"
			(at 0 0 0)
			(layer "B.SilkS")
			(hide yes)
			(effects
				(font
					(size 1.27 1.27)
				)
				(justify mirror)
			)
		)
		(property "Value" ""
			(at 0 0 0)
			(layer "B.Fab")
			(effects
				(font
					(size 1.27 1.27)
				)
				(justify mirror)
			)
		)
		(duplicate_pad_numbers_are_jumpers no)
		(fp_poly
			(pts
				(xy 0.2794 -0.1016) (xy -0.2794 -0.1016) (xy -0.2794 0.9906) (xy 0.2794 0.9906)
			)
			(stroke
				(width 0)
				(type default)
			)
			(fill no)
			(layer "B.CrtYd")
		)
		(fp_line
			(start -0.2794 -0.1016)
			(end 0.2794 -0.1016)
			(stroke
				(width 0.1)
				(type default)
			)
			(layer "B.Fab")
		)
		(fp_line
			(start -0.2794 0.9906)
			(end -0.2794 -0.1016)
			(stroke
				(width 0.1)
				(type default)
			)
			(layer "B.Fab")
		)
		(fp_line
			(start 0.2794 -0.1016)
			(end 0.2794 0.9906)
			(stroke
				(width 0.1)
				(type default)
			)
			(layer "B.Fab")
		)
		(fp_line
			(start 0.2794 0.9906)
			(end -0.2794 0.9906)
			(stroke
				(width 0.1)
				(type default)
			)
			(layer "B.Fab")
		)
		(pad "1" smd rect
			(at 0 0 180)
			(size 0.508 0.508)
			(layers "B.Cu" "B.Mask" "B.Paste")
			(net "P1V8_MCP_CPU0")
		)
		(pad "2" smd rect
			(at 0 0.889 180)
			(size 0.508 0.508)
			(layers "B.Cu" "B.Mask" "B.Paste")
			(net "JTAG_MCP_TRST_N")
		)
		(zone
			(layer "B.Cu")
			(hatch none 0.5)
			(connect_pads
				(clearance 0)
			)
			(min_thickness 0.25)
			(keepout
				(tracks allowed)
				(vias not_allowed)
				(pads allowed)
				(copperpour not_allowed)
				(footprints allowed)
			)
			(placement
				(enabled no)
				(sheetname "")
			)
			(fill
				(thermal_gap 0.5)
				(thermal_bridge_width 0.5)
				(island_removal_mode 0)
			)
			(polygon
				(pts
					(xy 472.20886 -129.8194) (xy 471.70086 -129.8194) (xy 471.70086 -129.4384) (xy 472.20886 -129.4384)
				)
			)
		)
		(zone
			(layer "B.Cu")
			(hatch none 0.5)
			(connect_pads
				(clearance 0)
			)
			(min_thickness 0.25)
			(keepout
				(tracks not_allowed)
				(vias allowed)
				(pads allowed)
				(copperpour not_allowed)
				(footprints allowed)
			)
			(placement
				(enabled no)
				(sheetname "")
			)
			(fill
				(thermal_gap 0.5)
				(thermal_bridge_width 0.5)
				(island_removal_mode 0)
			)
			(polygon
				(pts
					(xy 472.20886 -129.4384) (xy 471.70086 -129.4384) (xy 471.70086 -129.8194) (xy 472.20886 -129.8194)
				)
			)
		)
	)
	(footprint ""
		(layer "B.Cu")
		(at 391.573512 -43.599608 180)
		(property "Reference" "Q7E3"
			(at -2.65938 -1.15697 0)
			(unlocked yes)
			(layer "B.SilkS")
			(effects
				(font
					(size 0.7874 0.5842)
					(thickness 0.1524)
				)
				(justify left mirror)
			)
		)
		(property "Value" ""
			(at 0 0 0)
			(layer "B.Fab")
			(effects
				(font
					(size 1.27 1.27)
				)
				(justify mirror)
			)
		)
		(duplicate_pad_numbers_are_jumpers no)
		(fp_circle
			(center 0.508 -0.7874)
			(end 0.381 -0.7874)
			(stroke
				(width 0.254)
				(type default)
			)
			(fill no)
			(layer "B.SilkS")
		)
		(fp_poly
			(pts
				(xy -0.2159 1.7526) (xy -1.5621 1.7526) (xy -1.5621 -0.4572) (xy -0.2159 -0.4572)
			)
			(stroke
				(width 0)
				(type default)
			)
			(fill no)
			(layer "B.CrtYd")
		)
		(fp_line
			(start -0.2159 1.75514)
			(end -1.5621 1.75514)
			(stroke
				(width 0.1)
				(type default)
			)
			(layer "B.Fab")
		)
		(fp_line
			(start -0.2159 -0.45466)
			(end -0.2159 1.75514)
			(stroke
				(width 0.1)
				(type default)
			)
			(layer "B.Fab")
		)
		(fp_line
			(start -1.5621 1.75514)
			(end -1.5621 -0.45466)
			(stroke
				(width 0.1)
				(type default)
			)
			(layer "B.Fab")
		)
		(fp_line
			(start -1.5621 -0.45466)
			(end -0.2159 -0.45466)
			(stroke
				(width 0.1)
				(type default)
			)
			(layer "B.Fab")
		)
		(fp_circle
			(center 0.508 -0.7874)
			(end 0.381 -0.7874)
			(stroke
				(width 0.254)
				(type default)
			)
			(fill no)
			(layer "B.Fab")
		)
		(pad "1" smd rect
			(at 0 0)
			(size 1.016 0.381)
			(layers "B.Cu" "B.Mask" "B.Paste")
			(net "GND")
		)
		(pad "2" smd rect
			(at 0 0.65024)
			(size 1.016 0.381)
			(layers "B.Cu" "B.Mask" "B.Paste")
			(net "FM_SYS_THROTTLE_LVC3")
		)
		(pad "3" smd rect
			(at 0 1.30048)
			(size 1.016 0.381)
			(layers "B.Cu" "B.Mask" "B.Paste")
			(net "H_CPU1_PROCHOT_G_N")
		)
		(pad "4" smd rect
			(at -1.778 1.30048)
			(size 1.016 0.381)
			(layers "B.Cu" "B.Mask" "B.Paste")
			(net "GND")
		)
		(pad "5" smd rect
			(at -1.778 0.65024)
			(size 1.016 0.381)
			(layers "B.Cu" "B.Mask" "B.Paste")
			(net "FM_SYS_THROTTLE_LVC3")
		)
		(pad "6" smd rect
			(at -1.778 0)
			(size 1.016 0.381)
			(layers "B.Cu" "B.Mask" "B.Paste")
			(net "H_CPU0_PROCHOT_G_N")
		)
		(zone
			(layer "B.Cu")
			(hatch none 0.5)
			(connect_pads
				(clearance 0)
			)
			(min_thickness 0.25)
			(keepout
				(tracks allowed)
				(vias not_allowed)
				(pads allowed)
				(copperpour not_allowed)
				(footprints allowed)
			)
			(placement
				(enabled no)
				(sheetname "")
			)
			(fill
				(thermal_gap 0.5)
				(thermal_bridge_width 0.5)
				(island_removal_mode 0)
			)
			(polygon
				(pts
					(xy 391.065512 -43.409108) (xy 392.081512 -43.409108) (xy 392.081512 -45.098208) (xy 391.065512 -45.098208)
				)
			)
		)
		(zone
			(layer "B.Cu")
			(hatch none 0.5)
			(connect_pads
				(clearance 0)
			)
			(min_thickness 0.25)
			(keepout
				(tracks allowed)
				(vias not_allowed)
				(pads allowed)
				(copperpour not_allowed)
				(footprints allowed)
			)
			(placement
				(enabled no)
				(sheetname "")
			)
			(fill
				(thermal_gap 0.5)
				(thermal_bridge_width 0.5)
				(island_removal_mode 0)
			)
			(polygon
				(pts
					(xy 392.843512 -43.409108) (xy 393.859512 -43.409108) (xy 393.859512 -45.098208) (xy 392.843512 -45.098208)
				)
			)
		)
	)
	(footprint ""
		(layer "B.Cu")
		(at 367.284 -62.2935 180)
		(property "Reference" "R3P43"
			(at 0 0 0)
			(layer "B.SilkS")
			(hide yes)
			(effects
				(font
					(size 1.27 1.27)
				)
				(justify mirror)
			)
		)
		(property "Value" ""
			(at 0 0 0)
			(layer "B.Fab")
			(effects
				(font
					(size 1.27 1.27)
				)
				(justify mirror)
			)
		)
		(duplicate_pad_numbers_are_jumpers no)
		(fp_poly
			(pts
				(xy 0.2794 -0.1016) (xy -0.2794 -0.1016) (xy -0.2794 0.9906) (xy 0.2794 0.9906)
			)
			(stroke
				(width 0)
				(type default)
			)
			(fill no)
			(layer "B.CrtYd")
		)
		(fp_line
			(start 0.2794 0.9906)
			(end -0.2794 0.9906)
			(stroke
				(width 0.1)
				(type default)
			)
			(layer "B.Fab")
		)
		(fp_line
			(start 0.2794 -0.1016)
			(end 0.2794 0.9906)
			(stroke
				(width 0.1)
				(type default)
			)
			(layer "B.Fab")
		)
		(fp_line
			(start -0.2794 0.9906)
			(end -0.2794 -0.1016)
			(stroke
				(width 0.1)
				(type default)
			)
			(layer "B.Fab")
		)
		(fp_line
			(start -0.2794 -0.1016)
			(end 0.2794 -0.1016)
			(stroke
				(width 0.1)
				(type default)
			)
			(layer "B.Fab")
		)
		(pad "1" smd rect
			(at 0 0)
			(size 0.508 0.508)
			(layers "B.Cu" "B.Mask" "B.Paste")
			(net "FM_CPU_CATERR_LVT3_R2_N")
		)
		(pad "2" smd rect
			(at 0 0.889)
			(size 0.508 0.508)
			(layers "B.Cu" "B.Mask" "B.Paste")
			(net "FM_CPU_CATERR_LVT3_N")
		)
		(zone
			(layer "B.Cu")
			(hatch none 0.5)
			(connect_pads
				(clearance 0)
			)
			(min_thickness 0.25)
			(keepout
				(tracks not_allowed)
				(vias allowed)
				(pads allowed)
				(copperpour not_allowed)
				(footprints allowed)
			)
			(placement
				(enabled no)
				(sheetname "")
			)
			(fill
				(thermal_gap 0.5)
				(thermal_bridge_width 0.5)
				(island_removal_mode 0)
			)
			(polygon
				(pts
					(xy 367.03 -62.9285) (xy 367.538 -62.9285) (xy 367.538 -62.5475) (xy 367.03 -62.5475)
				)
			)
		)
		(zone
			(layer "B.Cu")
			(hatch none 0.5)
			(connect_pads
				(clearance 0)
			)
			(min_thickness 0.25)
			(keepout
				(tracks allowed)
				(vias not_allowed)
				(pads allowed)
				(copperpour not_allowed)
				(footprints allowed)
			)
			(placement
				(enabled no)
				(sheetname "")
			)
			(fill
				(thermal_gap 0.5)
				(thermal_bridge_width 0.5)
				(island_removal_mode 0)
			)
			(polygon
				(pts
					(xy 367.03 -62.5475) (xy 367.538 -62.5475) (xy 367.538 -62.9285) (xy 367.03 -62.9285)
				)
			)
		)
	)
	(footprint ""
		(layer "B.Cu")
		(at 463.7278 -7.112)
		(property "Reference" "R8E36"
			(at 0 0 0)
			(layer "B.SilkS")
			(hide yes)
			(effects
				(font
					(size 1.27 1.27)
				)
				(justify mirror)
			)
		)
		(property "Value" "*"
			(at -0.064008 -4.108196 0)
			(unlocked yes)
			(layer "B.Fab")
			(hide yes)
			(effects
				(font
					(size 1.27 1.016)
					(thickness 0.1524)
				)
				(justify mirror)
			)
		)
		(property "Device Type" "2K15R2F-1-GP_SMD-RG1-2K15R2F-1A"
			(at -0.064008 -5.632196 0)
			(unlocked yes)
			(layer "B.Fab")
			(hide yes)
			(effects
				(font
					(size 1.27 1.016)
					(thickness 0.1524)
				)
				(justify mirror)
			)
		)
		(duplicate_pad_numbers_are_jumpers no)
		(fp_line
			(start -0.508 -0.9398)
			(end 0.508 -0.9398)
			(stroke
				(width 0.1524)
				(type default)
			)
			(layer "B.SilkS")
		)
		(fp_line
			(start 0.508 -0.9398)
			(end 0.508 0.9398)
			(stroke
				(width 0.1524)
				(type default)
			)
			(layer "B.SilkS")
		)
		(fp_rect
			(start 0.508 0.9398)
			(end -0.508 -0.9398)
			(stroke
				(width 0)
				(type default)
			)
			(fill no)
			(layer "B.CrtYd")
		)
		(fp_rect
			(start 0.508 0.9398)
			(end -0.508 -0.9398)
			(stroke
				(width 0)
				(type default)
			)
			(fill no)
			(layer "B.Fab")
		)
		(pad "1" smd custom
			(at 0 -0.4445 180)
			(size 0.1397 0.1397)
			(layers "B.Cu" "B.Mask" "B.Paste")
			(net "P3V3_STBY")
			(options
				(clearance outline)
				(anchor circle)
			)
			(primitives
				(gr_poly
					(pts
						(arc
							(start -0.1778 0.2794)
							(mid -0.249642 0.249642)
							(end -0.2794 0.1778)
						)
						(arc
							(start -0.2794 -0.1778)
							(mid -0.249642 -0.249642)
							(end -0.1778 -0.2794)
						)
						(arc
							(start 0.1778 -0.2794)
							(mid 0.249642 -0.249642)
							(end 0.2794 -0.1778)
						)
						(arc
							(start 0.2794 0.1778)
							(mid 0.249642 0.249642)
							(end 0.1778 0.2794)
						)
					)
					(width 0)
					(fill yes)
				)
			)
		)
		(pad "2" smd custom
			(at 0 0.4445 180)
			(size 0.1397 0.1397)
			(layers "B.Cu" "B.Mask" "B.Paste")
			(net "FM_PE_SLOTX24_WAKE_N")
			(options
				(clearance outline)
				(anchor circle)
			)
			(primitives
				(gr_poly
					(pts
						(arc
							(start -0.1778 0.2794)
							(mid -0.249642 0.249642)
							(end -0.2794 0.1778)
						)
						(arc
							(start -0.2794 -0.1778)
							(mid -0.249642 -0.249642)
							(end -0.1778 -0.2794)
						)
						(arc
							(start 0.1778 -0.2794)
							(mid 0.249642 -0.249642)
							(end 0.2794 -0.1778)
						)
						(arc
							(start 0.2794 0.1778)
							(mid 0.249642 0.249642)
							(end 0.1778 0.2794)
						)
					)
					(width 0)
					(fill yes)
				)
			)
		)
	)
	(footprint ""
		(layer "B.Cu")
		(at 94.663768 -8.122412 90)
		(property "Reference" "C8U8"
			(at 0 0 90)
			(layer "B.SilkS")
			(hide yes)
			(effects
				(font
					(size 1.27 1.27)
				)
				(justify mirror)
			)
		)
		(property "Value" ""
			(at 0 0 90)
			(layer "B.Fab")
			(effects
				(font
					(size 1.27 1.27)
				)
				(justify mirror)
			)
		)
		(duplicate_pad_numbers_are_jumpers no)
		(fp_poly
			(pts
				(xy 0.7239 -0.2159) (xy -0.7239 -0.2159) (xy -0.7239 1.9939) (xy 0.7239 1.9939)
			)
			(stroke
				(width 0)
				(type default)
			)
			(fill no)
			(layer "B.CrtYd")
		)
		(fp_line
			(start 0.7239 -0.2159)
			(end 0.7239 1.9939)
			(stroke
				(width 0.1)
				(type default)
			)
			(layer "B.Fab")
		)
		(fp_line
			(start -0.7239 -0.2159)
			(end 0.7239 -0.2159)
			(stroke
				(width 0.1)
				(type default)
			)
			(layer "B.Fab")
		)
		(fp_line
			(start 0.7239 1.9939)
			(end -0.7239 1.9939)
			(stroke
				(width 0.1)
				(type default)
			)
			(layer "B.Fab")
		)
		(fp_line
			(start -0.7239 1.9939)
			(end -0.7239 -0.2159)
			(stroke
				(width 0.1)
				(type default)
			)
			(layer "B.Fab")
		)
		(pad "1" smd rect
			(at 0 0 270)
			(size 1.27 1.016)
			(layers "B.Cu" "B.Mask" "B.Paste")
			(net "PVDDQ_GHJ")
		)
		(pad "2" smd rect
			(at 0 1.778 270)
			(size 1.27 1.016)
			(layers "B.Cu" "B.Mask" "B.Paste")
			(net "GND")
		)
		(zone
			(layer "B.Cu")
			(hatch none 0.5)
			(connect_pads
				(clearance 0)
			)
			(min_thickness 0.25)
			(keepout
				(tracks not_allowed)
				(vias allowed)
				(pads allowed)
				(copperpour not_allowed)
				(footprints allowed)
			)
			(placement
				(enabled no)
				(sheetname "")
			)
			(fill
				(thermal_gap 0.5)
				(thermal_bridge_width 0.5)
				(island_removal_mode 0)
			)
			(polygon
				(pts
					(xy 95.171768 -8.757412) (xy 95.171768 -7.487412) (xy 95.933768 -7.487412) (xy 95.933768 -8.757412)
				)
			)
		)
	)
	(footprint ""
		(layer "B.Cu")
		(at 385.217924 -23.869904 90)
		(property "Reference" "C2T23"
			(at 0 0 90)
			(layer "B.SilkS")
			(hide yes)
			(effects
				(font
					(size 1.27 1.27)
				)
				(justify mirror)
			)
		)
		(property "Value" ""
			(at 0 0 90)
			(layer "B.Fab")
			(effects
				(font
					(size 1.27 1.27)
				)
				(justify mirror)
			)
		)
		(duplicate_pad_numbers_are_jumpers no)
		(fp_poly
			(pts
				(xy -0.3048 -0.1016) (xy -0.3048 0.9906) (xy 0.3048 0.9906) (xy 0.3048 -0.1016)
			)
			(stroke
				(width 0)
				(type default)
			)
			(fill no)
			(layer "B.CrtYd")
		)
		(fp_line
			(start 0.3048 -0.1016)
			(end 0.3048 0.9906)
			(stroke
				(width 0.1)
				(type default)
			)
			(layer "B.Fab")
		)
		(fp_line
			(start -0.3048 -0.1016)
			(end 0.3048 -0.1016)
			(stroke
				(width 0.1)
				(type default)
			)
			(layer "B.Fab")
		)
		(fp_line
			(start 0.3048 0.9906)
			(end -0.3048 0.9906)
			(stroke
				(width 0.1)
				(type default)
			)
			(layer "B.Fab")
		)
		(fp_line
			(start -0.3048 0.9906)
			(end -0.3048 -0.1016)
			(stroke
				(width 0.1)
				(type default)
			)
			(layer "B.Fab")
		)
		(pad "1" smd rect
			(at 0 0 270)
			(size 0.508 0.508)
			(layers "B.Cu" "B.Mask" "B.Paste")
			(net "P3E_PCH_M2_TX_C_DN<3>")
		)
		(pad "2" smd rect
			(at 0 0.889 270)
			(size 0.508 0.508)
			(layers "B.Cu" "B.Mask" "B.Paste")
			(net "P3E_PCH_M2_TX_DN<3>")
		)
		(zone
			(layer "B.Cu")
			(hatch none 0.5)
			(connect_pads
				(clearance 0)
			)
			(min_thickness 0.25)
			(keepout
				(tracks allowed)
				(vias not_allowed)
				(pads allowed)
				(copperpour not_allowed)
				(footprints allowed)
			)
			(placement
				(enabled no)
				(sheetname "")
			)
			(fill
				(thermal_gap 0.5)
				(thermal_bridge_width 0.5)
				(island_removal_mode 0)
			)
			(polygon
				(pts
					(xy 385.471924 -24.123904) (xy 385.471924 -23.615904) (xy 385.852924 -23.615904) (xy 385.852924 -24.123904)
				)
			)
		)
		(zone
			(layer "B.Cu")
			(hatch none 0.5)
			(connect_pads
				(clearance 0)
			)
			(min_thickness 0.25)
			(keepout
				(tracks not_allowed)
				(vias allowed)
				(pads allowed)
				(copperpour not_allowed)
				(footprints allowed)
			)
			(placement
				(enabled no)
				(sheetname "")
			)
			(fill
				(thermal_gap 0.5)
				(thermal_bridge_width 0.5)
				(island_removal_mode 0)
			)
			(polygon
				(pts
					(xy 385.852924 -24.123904) (xy 385.852924 -23.615904) (xy 385.471924 -23.615904) (xy 385.471924 -24.123904)
				)
			)
		)
	)
	(footprint ""
		(layer "B.Cu")
		(at 273.052286 -85.06714)
		(property "Reference" "C5P4"
			(at 0 0 0)
			(layer "B.SilkS")
			(hide yes)
			(effects
				(font
					(size 1.27 1.27)
				)
				(justify mirror)
			)
		)
		(property "Value" ""
			(at 0 0 0)
			(layer "B.Fab")
			(effects
				(font
					(size 1.27 1.27)
				)
				(justify mirror)
			)
		)
		(duplicate_pad_numbers_are_jumpers no)
		(fp_poly
			(pts
				(xy 0.7239 -0.2159) (xy -0.7239 -0.2159) (xy -0.7239 1.9939) (xy 0.7239 1.9939)
			)
			(stroke
				(width 0)
				(type default)
			)
			(fill no)
			(layer "B.CrtYd")
		)
		(fp_line
			(start -0.7239 -0.2159)
			(end 0.7239 -0.2159)
			(stroke
				(width 0.1)
				(type default)
			)
			(layer "B.Fab")
		)
		(fp_line
			(start -0.7239 1.9939)
			(end -0.7239 -0.2159)
			(stroke
				(width 0.1)
				(type default)
			)
			(layer "B.Fab")
		)
		(fp_line
			(start 0.7239 -0.2159)
			(end 0.7239 1.9939)
			(stroke
				(width 0.1)
				(type default)
			)
			(layer "B.Fab")
		)
		(fp_line
			(start 0.7239 1.9939)
			(end -0.7239 1.9939)
			(stroke
				(width 0.1)
				(type default)
			)
			(layer "B.Fab")
		)
		(pad "1" smd rect
			(at 0 0 180)
			(size 1.27 1.016)
			(layers "B.Cu" "B.Mask" "B.Paste")
			(net "PVDDQ_DEF")
		)
		(pad "2" smd rect
			(at 0 1.778 180)
			(size 1.27 1.016)
			(layers "B.Cu" "B.Mask" "B.Paste")
			(net "GND")
		)
		(zone
			(layer "B.Cu")
			(hatch none 0.5)
			(connect_pads
				(clearance 0)
			)
			(min_thickness 0.25)
			(keepout
				(tracks not_allowed)
				(vias allowed)
				(pads allowed)
				(copperpour not_allowed)
				(footprints allowed)
			)
			(placement
				(enabled no)
				(sheetname "")
			)
			(fill
				(thermal_gap 0.5)
				(thermal_bridge_width 0.5)
				(island_removal_mode 0)
			)
			(polygon
				(pts
					(xy 273.687286 -84.55914) (xy 272.417286 -84.55914) (xy 272.417286 -83.79714) (xy 273.687286 -83.79714)
				)
			)
		)
	)
	(footprint ""
		(layer "B.Cu")
		(at 192.913 -134.874 180)
		(property "Reference" "R6M2"
			(at 0 0 0)
			(layer "B.SilkS")
			(hide yes)
			(effects
				(font
					(size 1.27 1.27)
				)
				(justify mirror)
			)
		)
		(property "Value" ""
			(at 0 0 0)
			(layer "B.Fab")
			(effects
				(font
					(size 1.27 1.27)
				)
				(justify mirror)
			)
		)
		(duplicate_pad_numbers_are_jumpers no)
		(fp_poly
			(pts
				(xy 0.2794 -0.1016) (xy -0.2794 -0.1016) (xy -0.2794 0.9906) (xy 0.2794 0.9906)
			)
			(stroke
				(width 0)
				(type default)
			)
			(fill no)
			(layer "B.CrtYd")
		)
		(fp_line
			(start 0.2794 0.9906)
			(end -0.2794 0.9906)
			(stroke
				(width 0.1)
				(type default)
			)
			(layer "B.Fab")
		)
		(fp_line
			(start 0.2794 -0.1016)
			(end 0.2794 0.9906)
			(stroke
				(width 0.1)
				(type default)
			)
			(layer "B.Fab")
		)
		(fp_line
			(start -0.2794 0.9906)
			(end -0.2794 -0.1016)
			(stroke
				(width 0.1)
				(type default)
			)
			(layer "B.Fab")
		)
		(fp_line
			(start -0.2794 -0.1016)
			(end 0.2794 -0.1016)
			(stroke
				(width 0.1)
				(type default)
			)
			(layer "B.Fab")
		)
		(pad "1" smd rect
			(at 0 0)
			(size 0.508 0.508)
			(layers "B.Cu" "B.Mask" "B.Paste")
			(net "M_D_CPU_VREF")
		)
		(pad "2" smd rect
			(at 0 0.889)
			(size 0.508 0.508)
			(layers "B.Cu" "B.Mask" "B.Paste")
			(net "M_D_VREF")
		)
		(zone
			(layer "B.Cu")
			(hatch none 0.5)
			(connect_pads
				(clearance 0)
			)
			(min_thickness 0.25)
			(keepout
				(tracks not_allowed)
				(vias allowed)
				(pads allowed)
				(copperpour not_allowed)
				(footprints allowed)
			)
			(placement
				(enabled no)
				(sheetname "")
			)
			(fill
				(thermal_gap 0.5)
				(thermal_bridge_width 0.5)
				(island_removal_mode 0)
			)
			(polygon
				(pts
					(xy 192.659 -135.509) (xy 193.167 -135.509) (xy 193.167 -135.128) (xy 192.659 -135.128)
				)
			)
		)
		(zone
			(layer "B.Cu")
			(hatch none 0.5)
			(connect_pads
				(clearance 0)
			)
			(min_thickness 0.25)
			(keepout
				(tracks allowed)
				(vias not_allowed)
				(pads allowed)
				(copperpour not_allowed)
				(footprints allowed)
			)
			(placement
				(enabled no)
				(sheetname "")
			)
			(fill
				(thermal_gap 0.5)
				(thermal_bridge_width 0.5)
				(island_removal_mode 0)
			)
			(polygon
				(pts
					(xy 192.659 -135.128) (xy 193.167 -135.128) (xy 193.167 -135.509) (xy 192.659 -135.509)
				)
			)
		)
	)
	(footprint ""
		(layer "B.Cu")
		(at 162.7886 -80.3402 90)
		(property "Reference" "R7P6"
			(at 0 0 90)
			(layer "B.SilkS")
			(hide yes)
			(effects
				(font
					(size 1.27 1.27)
				)
				(justify mirror)
			)
		)
		(property "Value" ""
			(at 0 0 90)
			(layer "B.Fab")
			(effects
				(font
					(size 1.27 1.27)
				)
				(justify mirror)
			)
		)
		(duplicate_pad_numbers_are_jumpers no)
		(fp_poly
			(pts
				(xy 0.2794 -0.1016) (xy -0.2794 -0.1016) (xy -0.2794 0.9906) (xy 0.2794 0.9906)
			)
			(stroke
				(width 0)
				(type default)
			)
			(fill no)
			(layer "B.CrtYd")
		)
		(fp_line
			(start 0.2794 -0.1016)
			(end 0.2794 0.9906)
			(stroke
				(width 0.1)
				(type default)
			)
			(layer "B.Fab")
		)
		(fp_line
			(start -0.2794 -0.1016)
			(end 0.2794 -0.1016)
			(stroke
				(width 0.1)
				(type default)
			)
			(layer "B.Fab")
		)
		(fp_line
			(start 0.2794 0.9906)
			(end -0.2794 0.9906)
			(stroke
				(width 0.1)
				(type default)
			)
			(layer "B.Fab")
		)
		(fp_line
			(start -0.2794 0.9906)
			(end -0.2794 -0.1016)
			(stroke
				(width 0.1)
				(type default)
			)
			(layer "B.Fab")
		)
		(pad "1" smd rect
			(at 0 0 270)
			(size 0.508 0.508)
			(layers "B.Cu" "B.Mask" "B.Paste")
			(net "CLK_100M_CPU1_RC_REFCLK0_DP")
		)
		(pad "2" smd rect
			(at 0 0.889 270)
			(size 0.508 0.508)
			(layers "B.Cu" "B.Mask" "B.Paste")
			(net "GND")
		)
		(zone
			(layer "B.Cu")
			(hatch none 0.5)
			(connect_pads
				(clearance 0)
			)
			(min_thickness 0.25)
			(keepout
				(tracks allowed)
				(vias not_allowed)
				(pads allowed)
				(copperpour not_allowed)
				(footprints allowed)
			)
			(placement
				(enabled no)
				(sheetname "")
			)
			(fill
				(thermal_gap 0.5)
				(thermal_bridge_width 0.5)
				(island_removal_mode 0)
			)
			(polygon
				(pts
					(xy 163.0426 -80.5942) (xy 163.0426 -80.0862) (xy 163.4236 -80.0862) (xy 163.4236 -80.5942)
				)
			)
		)
		(zone
			(layer "B.Cu")
			(hatch none 0.5)
			(connect_pads
				(clearance 0)
			)
			(min_thickness 0.25)
			(keepout
				(tracks not_allowed)
				(vias allowed)
				(pads allowed)
				(copperpour not_allowed)
				(footprints allowed)
			)
			(placement
				(enabled no)
				(sheetname "")
			)
			(fill
				(thermal_gap 0.5)
				(thermal_bridge_width 0.5)
				(island_removal_mode 0)
			)
			(polygon
				(pts
					(xy 163.4236 -80.5942) (xy 163.4236 -80.0862) (xy 163.0426 -80.0862) (xy 163.0426 -80.5942)
				)
			)
		)
	)
	(footprint ""
		(layer "B.Cu")
		(at 112.217454 -79.575914 180)
		(property "Reference" "C7P5"
			(at 0 0 0)
			(layer "B.SilkS")
			(hide yes)
			(effects
				(font
					(size 1.27 1.27)
				)
				(justify mirror)
			)
		)
		(property "Value" ""
			(at 0 0 0)
			(layer "B.Fab")
			(effects
				(font
					(size 1.27 1.27)
				)
				(justify mirror)
			)
		)
		(duplicate_pad_numbers_are_jumpers no)
		(fp_poly
			(pts
				(xy 0.7239 -0.2159) (xy -0.7239 -0.2159) (xy -0.7239 1.9939) (xy 0.7239 1.9939)
			)
			(stroke
				(width 0)
				(type default)
			)
			(fill no)
			(layer "B.CrtYd")
		)
		(fp_line
			(start 0.7239 1.9939)
			(end -0.7239 1.9939)
			(stroke
				(width 0.1)
				(type default)
			)
			(layer "B.Fab")
		)
		(fp_line
			(start 0.7239 -0.2159)
			(end 0.7239 1.9939)
			(stroke
				(width 0.1)
				(type default)
			)
			(layer "B.Fab")
		)
		(fp_line
			(start -0.7239 1.9939)
			(end -0.7239 -0.2159)
			(stroke
				(width 0.1)
				(type default)
			)
			(layer "B.Fab")
		)
		(fp_line
			(start -0.7239 -0.2159)
			(end 0.7239 -0.2159)
			(stroke
				(width 0.1)
				(type default)
			)
			(layer "B.Fab")
		)
		(pad "1" smd rect
			(at 0 0)
			(size 1.27 1.016)
			(layers "B.Cu" "B.Mask" "B.Paste")
			(net "PVCCMCP_CPU1")
		)
		(pad "2" smd rect
			(at 0 1.778)
			(size 1.27 1.016)
			(layers "B.Cu" "B.Mask" "B.Paste")
			(net "GND")
		)
		(zone
			(layer "B.Cu")
			(hatch none 0.5)
			(connect_pads
				(clearance 0)
			)
			(min_thickness 0.25)
			(keepout
				(tracks not_allowed)
				(vias allowed)
				(pads allowed)
				(copperpour not_allowed)
				(footprints allowed)
			)
			(placement
				(enabled no)
				(sheetname "")
			)
			(fill
				(thermal_gap 0.5)
				(thermal_bridge_width 0.5)
				(island_removal_mode 0)
			)
			(polygon
				(pts
					(xy 111.582454 -80.083914) (xy 112.852454 -80.083914) (xy 112.852454 -80.845914) (xy 111.582454 -80.845914)
				)
			)
		)
	)
	(footprint ""
		(layer "B.Cu")
		(at 390.93775 -108.65485 90)
		(property "Reference" "C2N9"
			(at 0 0 90)
			(layer "B.SilkS")
			(hide yes)
			(effects
				(font
					(size 1.27 1.27)
				)
				(justify mirror)
			)
		)
		(property "Value" ""
			(at 0 0 90)
			(layer "B.Fab")
			(effects
				(font
					(size 1.27 1.27)
				)
				(justify mirror)
			)
		)
		(duplicate_pad_numbers_are_jumpers no)
		(fp_rect
			(start 0.2794 0.9144)
			(end -0.2794 -0.1143)
			(stroke
				(width 0)
				(type default)
			)
			(fill no)
			(layer "B.CrtYd")
		)
		(fp_line
			(start 0.2794 -0.1143)
			(end -0.2794 -0.1143)
			(stroke
				(width 0.1)
				(type default)
			)
			(layer "B.Fab")
		)
		(fp_line
			(start -0.2794 -0.1143)
			(end -0.2794 0.9144)
			(stroke
				(width 0.1)
				(type default)
			)
			(layer "B.Fab")
		)
		(fp_line
			(start 0.2794 0.9144)
			(end 0.2794 -0.1143)
			(stroke
				(width 0.1)
				(type default)
			)
			(layer "B.Fab")
		)
		(fp_line
			(start -0.2794 0.9144)
			(end 0.2794 0.9144)
			(stroke
				(width 0.1)
				(type default)
			)
			(layer "B.Fab")
		)
		(pad "1" smd custom
			(at 0 0)
			(size 0.10414 0.10414)
			(layers "B.Cu" "B.Mask" "B.Paste")
			(net "PVNN_PCH_STBY")
			(options
				(clearance outline)
				(anchor circle)
			)
			(primitives
				(gr_poly
					(pts
						(xy -0.20828 -0.08636) (xy -0.20828 0.08636) (xy -0.08636 0.20828) (xy 0.086614 0.20828) (xy 0.20828 0.086614)
						(xy 0.20828 -0.08636) (xy 0.08636 -0.20828) (xy -0.08636 -0.20828)
					)
					(width 0)
					(fill yes)
				)
			)
		)
		(pad "2" smd custom
			(at 0 0.8001)
			(size 0.10414 0.10414)
			(layers "B.Cu" "B.Mask" "B.Paste")
			(net "GND")
			(options
				(clearance outline)
				(anchor circle)
			)
			(primitives
				(gr_poly
					(pts
						(xy -0.20828 -0.08636) (xy -0.20828 0.08636) (xy -0.08636 0.20828) (xy 0.086614 0.20828) (xy 0.20828 0.086614)
						(xy 0.20828 -0.08636) (xy 0.08636 -0.20828) (xy -0.08636 -0.20828)
					)
					(width 0)
					(fill yes)
				)
			)
		)
		(zone
			(layer "B.Cu")
			(hatch none 0.5)
			(connect_pads
				(clearance 0)
			)
			(min_thickness 0.25)
			(keepout
				(tracks allowed)
				(vias not_allowed)
				(pads allowed)
				(copperpour not_allowed)
				(footprints allowed)
			)
			(placement
				(enabled no)
				(sheetname "")
			)
			(fill
				(thermal_gap 0.5)
				(thermal_bridge_width 0.5)
				(island_removal_mode 0)
			)
			(polygon
				(pts
					(xy 391.1473 -108.74248) (xy 391.5283 -108.74248) (xy 391.5283 -108.56722) (xy 391.1473 -108.566966)
				)
			)
		)
		(zone
			(layer "B.Cu")
			(hatch none 0.5)
			(connect_pads
				(clearance 0)
			)
			(min_thickness 0.25)
			(keepout
				(tracks not_allowed)
				(vias allowed)
				(pads allowed)
				(copperpour not_allowed)
				(footprints allowed)
			)
			(placement
				(enabled no)
				(sheetname "")
			)
			(fill
				(thermal_gap 0.5)
				(thermal_bridge_width 0.5)
				(island_removal_mode 0)
			)
			(polygon
				(pts
					(xy 391.1473 -108.74248) (xy 391.5283 -108.74248) (xy 391.5283 -108.56722) (xy 391.1473 -108.566966)
				)
			)
		)
	)
	(footprint ""
		(layer "B.Cu")
		(at 24.257 -83.185 -90)
		(property "Reference" "R9P10"
			(at 0 0 90)
			(layer "B.SilkS")
			(hide yes)
			(effects
				(font
					(size 1.27 1.27)
				)
				(justify mirror)
			)
		)
		(property "Value" ""
			(at 0 0 90)
			(layer "B.Fab")
			(effects
				(font
					(size 1.27 1.27)
				)
				(justify mirror)
			)
		)
		(duplicate_pad_numbers_are_jumpers no)
		(fp_poly
			(pts
				(xy 0.2794 -0.1016) (xy -0.2794 -0.1016) (xy -0.2794 0.9906) (xy 0.2794 0.9906)
			)
			(stroke
				(width 0)
				(type default)
			)
			(fill no)
			(layer "B.CrtYd")
		)
		(fp_line
			(start -0.2794 0.9906)
			(end -0.2794 -0.1016)
			(stroke
				(width 0.1)
				(type default)
			)
			(layer "B.Fab")
		)
		(fp_line
			(start 0.2794 0.9906)
			(end -0.2794 0.9906)
			(stroke
				(width 0.1)
				(type default)
			)
			(layer "B.Fab")
		)
		(fp_line
			(start -0.2794 -0.1016)
			(end 0.2794 -0.1016)
			(stroke
				(width 0.1)
				(type default)
			)
			(layer "B.Fab")
		)
		(fp_line
			(start 0.2794 -0.1016)
			(end 0.2794 0.9906)
			(stroke
				(width 0.1)
				(type default)
			)
			(layer "B.Fab")
		)
		(pad "1" smd rect
			(at 0 0 90)
			(size 0.508 0.508)
			(layers "B.Cu" "B.Mask" "B.Paste")
			(net "P3V3_STBY")
		)
		(pad "2" smd rect
			(at 0 0.889 90)
			(size 0.508 0.508)
			(layers "B.Cu" "B.Mask" "B.Paste")
			(net "A_P12V_STBY_FPH_GATE")
		)
		(zone
			(layer "B.Cu")
			(hatch none 0.5)
			(connect_pads
				(clearance 0)
			)
			(min_thickness 0.25)
			(keepout
				(tracks not_allowed)
				(vias allowed)
				(pads allowed)
				(copperpour not_allowed)
				(footprints allowed)
			)
			(placement
				(enabled no)
				(sheetname "")
			)
			(fill
				(thermal_gap 0.5)
				(thermal_bridge_width 0.5)
				(island_removal_mode 0)
			)
			(polygon
				(pts
					(xy 23.622 -82.931) (xy 23.622 -83.439) (xy 24.003 -83.439) (xy 24.003 -82.931)
				)
			)
		)
		(zone
			(layer "B.Cu")
			(hatch none 0.5)
			(connect_pads
				(clearance 0)
			)
			(min_thickness 0.25)
			(keepout
				(tracks allowed)
				(vias not_allowed)
				(pads allowed)
				(copperpour not_allowed)
				(footprints allowed)
			)
			(placement
				(enabled no)
				(sheetname "")
			)
			(fill
				(thermal_gap 0.5)
				(thermal_bridge_width 0.5)
				(island_removal_mode 0)
			)
			(polygon
				(pts
					(xy 24.003 -82.931) (xy 24.003 -83.439) (xy 23.622 -83.439) (xy 23.622 -82.931)
				)
			)
		)
	)
	(footprint ""
		(layer "B.Cu")
		(at 32.832802 -81.030064 90)
		(property "Reference" "C9P24"
			(at 0 0 90)
			(layer "B.SilkS")
			(hide yes)
			(effects
				(font
					(size 1.27 1.27)
				)
				(justify mirror)
			)
		)
		(property "Value" ""
			(at 0 0 90)
			(layer "B.Fab")
			(effects
				(font
					(size 1.27 1.27)
				)
				(justify mirror)
			)
		)
		(duplicate_pad_numbers_are_jumpers no)
		(fp_poly
			(pts
				(xy 0.7239 -0.2159) (xy -0.7239 -0.2159) (xy -0.7239 1.9939) (xy 0.7239 1.9939)
			)
			(stroke
				(width 0)
				(type default)
			)
			(fill no)
			(layer "B.CrtYd")
		)
		(fp_line
			(start 0.7239 -0.2159)
			(end 0.7239 1.9939)
			(stroke
				(width 0.1)
				(type default)
			)
			(layer "B.Fab")
		)
		(fp_line
			(start -0.7239 -0.2159)
			(end 0.7239 -0.2159)
			(stroke
				(width 0.1)
				(type default)
			)
			(layer "B.Fab")
		)
		(fp_line
			(start 0.7239 1.9939)
			(end -0.7239 1.9939)
			(stroke
				(width 0.1)
				(type default)
			)
			(layer "B.Fab")
		)
		(fp_line
			(start -0.7239 1.9939)
			(end -0.7239 -0.2159)
			(stroke
				(width 0.1)
				(type default)
			)
			(layer "B.Fab")
		)
		(pad "1" smd rect
			(at 0 0 270)
			(size 1.27 1.016)
			(layers "B.Cu" "B.Mask" "B.Paste")
			(net "VR_FET_SW_P12V_STBY_PVCCIN_CPU1")
		)
		(pad "2" smd rect
			(at 0 1.778 270)
			(size 1.27 1.016)
			(layers "B.Cu" "B.Mask" "B.Paste")
			(net "GND")
		)
		(zone
			(layer "B.Cu")
			(hatch none 0.5)
			(connect_pads
				(clearance 0)
			)
			(min_thickness 0.25)
			(keepout
				(tracks not_allowed)
				(vias allowed)
				(pads allowed)
				(copperpour not_allowed)
				(footprints allowed)
			)
			(placement
				(enabled no)
				(sheetname "")
			)
			(fill
				(thermal_gap 0.5)
				(thermal_bridge_width 0.5)
				(island_removal_mode 0)
			)
			(polygon
				(pts
					(xy 33.340802 -81.665064) (xy 33.340802 -80.395064) (xy 34.102802 -80.395064) (xy 34.102802 -81.665064)
				)
			)
		)
	)
	(footprint ""
		(layer "B.Cu")
		(at 13.0048 -124.6505 180)
		(property "Reference" "R12W19"
			(at -1.01473 0.656336 270)
			(unlocked yes)
			(layer "B.SilkS")
			(effects
				(font
					(size 0.4064 0.254)
					(thickness 0.1524)
				)
				(justify mirror)
			)
		)
		(property "Value" ""
			(at 0 0 0)
			(layer "B.Fab")
			(effects
				(font
					(size 1.27 1.27)
				)
				(justify mirror)
			)
		)
		(duplicate_pad_numbers_are_jumpers no)
		(fp_poly
			(pts
				(xy 0.4953 -0.2032) (xy -0.4953 -0.2032) (xy -0.4953 1.6002) (xy 0.4953 1.6002)
			)
			(stroke
				(width 0)
				(type default)
			)
			(fill no)
			(layer "B.CrtYd")
		)
		(fp_line
			(start 0.4953 1.6002)
			(end 0.4953 -0.2032)
			(stroke
				(width 0.1)
				(type default)
			)
			(layer "B.Fab")
		)
		(fp_line
			(start 0.4953 -0.2032)
			(end -0.4953 -0.2032)
			(stroke
				(width 0.1)
				(type default)
			)
			(layer "B.Fab")
		)
		(fp_line
			(start -0.4953 1.6002)
			(end 0.4953 1.6002)
			(stroke
				(width 0.1)
				(type default)
			)
			(layer "B.Fab")
		)
		(fp_line
			(start -0.4953 -0.2032)
			(end -0.4953 1.6002)
			(stroke
				(width 0.1)
				(type default)
			)
			(layer "B.Fab")
		)
		(pad "1" smd rect
			(at 0 0)
			(size 0.762 0.889)
			(layers "B.Cu" "B.Mask" "B.Paste")
			(net "P12V_NVDIMM_KLM")
		)
		(pad "2" smd rect
			(at 0 1.397)
			(size 0.762 0.889)
			(layers "B.Cu" "B.Mask" "B.Paste")
			(net "PWRGD_PVDDQ_KLM_N")
		)
		(zone
			(layer "B.Cu")
			(hatch none 0.5)
			(connect_pads
				(clearance 0)
			)
			(min_thickness 0.25)
			(keepout
				(tracks not_allowed)
				(vias allowed)
				(pads allowed)
				(copperpour not_allowed)
				(footprints allowed)
			)
			(placement
				(enabled no)
				(sheetname "")
			)
			(fill
				(thermal_gap 0.5)
				(thermal_bridge_width 0.5)
				(island_removal_mode 0)
			)
			(polygon
				(pts
					(xy 12.6238 -125.603) (xy 12.6238 -125.095) (xy 13.3858 -125.095) (xy 13.3858 -125.603)
				)
			)
		)
		(zone
			(layer "B.Cu")
			(hatch none 0.5)
			(connect_pads
				(clearance 0)
			)
			(min_thickness 0.25)
			(keepout
				(tracks allowed)
				(vias not_allowed)
				(pads allowed)
				(copperpour not_allowed)
				(footprints allowed)
			)
			(placement
				(enabled no)
				(sheetname "")
			)
			(fill
				(thermal_gap 0.5)
				(thermal_bridge_width 0.5)
				(island_removal_mode 0)
			)
			(polygon
				(pts
					(xy 13.3858 -125.603) (xy 13.3858 -125.095) (xy 12.6238 -125.095) (xy 12.6238 -125.603)
				)
			)
		)
	)
	(footprint ""
		(layer "B.Cu")
		(at 465.7471 -41.23182)
		(property "Reference" "C9W17"
			(at -0.97536 0.76708 90)
			(unlocked yes)
			(layer "B.SilkS")
			(effects
				(font
					(size 0.4064 0.254)
					(thickness 0.1524)
				)
				(justify mirror)
			)
		)
		(property "Value" ""
			(at 0 0 0)
			(layer "B.Fab")
			(effects
				(font
					(size 1.27 1.27)
				)
				(justify mirror)
			)
		)
		(duplicate_pad_numbers_are_jumpers no)
		(fp_poly
			(pts
				(xy 0.4953 -0.2032) (xy -0.4953 -0.2032) (xy -0.4953 1.6002) (xy 0.4953 1.6002)
			)
			(stroke
				(width 0)
				(type default)
			)
			(fill no)
			(layer "B.CrtYd")
		)
		(fp_line
			(start -0.4953 -0.2032)
			(end -0.4953 1.6002)
			(stroke
				(width 0.1)
				(type default)
			)
			(layer "B.Fab")
		)
		(fp_line
			(start -0.4953 1.6002)
			(end 0.4953 1.6002)
			(stroke
				(width 0.1)
				(type default)
			)
			(layer "B.Fab")
		)
		(fp_line
			(start 0.4953 -0.2032)
			(end -0.4953 -0.2032)
			(stroke
				(width 0.1)
				(type default)
			)
			(layer "B.Fab")
		)
		(fp_line
			(start 0.4953 1.6002)
			(end 0.4953 -0.2032)
			(stroke
				(width 0.1)
				(type default)
			)
			(layer "B.Fab")
		)
		(pad "1" smd rect
			(at 0 0 180)
			(size 0.762 0.889)
			(layers "B.Cu" "B.Mask" "B.Paste")
			(net "P3V3_STBY")
		)
		(pad "2" smd rect
			(at 0 1.397 180)
			(size 0.762 0.889)
			(layers "B.Cu" "B.Mask" "B.Paste")
			(net "GND")
		)
		(zone
			(layer "B.Cu")
			(hatch none 0.5)
			(connect_pads
				(clearance 0)
			)
			(min_thickness 0.25)
			(keepout
				(tracks not_allowed)
				(vias allowed)
				(pads allowed)
				(copperpour not_allowed)
				(footprints allowed)
			)
			(placement
				(enabled no)
				(sheetname "")
			)
			(fill
				(thermal_gap 0.5)
				(thermal_bridge_width 0.5)
				(island_removal_mode 0)
			)
			(polygon
				(pts
					(xy 466.1281 -40.78732) (xy 465.3661 -40.78732) (xy 465.3661 -40.27932) (xy 466.1281 -40.27932)
				)
			)
		)
	)
	(footprint ""
		(layer "B.Cu")
		(at 333.346806 -60.368434)
		(property "Reference" "R2U14"
			(at 0 0 0)
			(layer "B.SilkS")
			(hide yes)
			(effects
				(font
					(size 1.27 1.27)
				)
				(justify mirror)
			)
		)
		(property "Value" ""
			(at 0 0 0)
			(layer "B.Fab")
			(effects
				(font
					(size 1.27 1.27)
				)
				(justify mirror)
			)
		)
		(duplicate_pad_numbers_are_jumpers no)
		(fp_poly
			(pts
				(xy 0.2794 -0.1016) (xy -0.2794 -0.1016) (xy -0.2794 0.9906) (xy 0.2794 0.9906)
			)
			(stroke
				(width 0)
				(type default)
			)
			(fill no)
			(layer "B.CrtYd")
		)
		(fp_line
			(start -0.2794 -0.1016)
			(end 0.2794 -0.1016)
			(stroke
				(width 0.1)
				(type default)
			)
			(layer "B.Fab")
		)
		(fp_line
			(start -0.2794 0.9906)
			(end -0.2794 -0.1016)
			(stroke
				(width 0.1)
				(type default)
			)
			(layer "B.Fab")
		)
		(fp_line
			(start 0.2794 -0.1016)
			(end 0.2794 0.9906)
			(stroke
				(width 0.1)
				(type default)
			)
			(layer "B.Fab")
		)
		(fp_line
			(start 0.2794 0.9906)
			(end -0.2794 0.9906)
			(stroke
				(width 0.1)
				(type default)
			)
			(layer "B.Fab")
		)
		(pad "1" smd rect
			(at 0 0 180)
			(size 0.508 0.508)
			(layers "B.Cu" "B.Mask" "B.Paste")
			(net "P3E_CPU0_PE1_SS_RXP<0>")
		)
		(pad "2" smd rect
			(at 0 0.889 180)
			(size 0.508 0.508)
			(layers "B.Cu" "B.Mask" "B.Paste")
			(net "P3E_CPU0_PE1_SS_R_RXP<0>")
		)
		(zone
			(layer "B.Cu")
			(hatch none 0.5)
			(connect_pads
				(clearance 0)
			)
			(min_thickness 0.25)
			(keepout
				(tracks allowed)
				(vias not_allowed)
				(pads allowed)
				(copperpour not_allowed)
				(footprints allowed)
			)
			(placement
				(enabled no)
				(sheetname "")
			)
			(fill
				(thermal_gap 0.5)
				(thermal_bridge_width 0.5)
				(island_removal_mode 0)
			)
			(polygon
				(pts
					(xy 333.600806 -60.114434) (xy 333.092806 -60.114434) (xy 333.092806 -59.733434) (xy 333.600806 -59.733434)
				)
			)
		)
		(zone
			(layer "B.Cu")
			(hatch none 0.5)
			(connect_pads
				(clearance 0)
			)
			(min_thickness 0.25)
			(keepout
				(tracks not_allowed)
				(vias allowed)
				(pads allowed)
				(copperpour not_allowed)
				(footprints allowed)
			)
			(placement
				(enabled no)
				(sheetname "")
			)
			(fill
				(thermal_gap 0.5)
				(thermal_bridge_width 0.5)
				(island_removal_mode 0)
			)
			(polygon
				(pts
					(xy 333.600806 -59.733434) (xy 333.092806 -59.733434) (xy 333.092806 -60.114434) (xy 333.600806 -60.114434)
				)
			)
		)
	)
	(footprint ""
		(layer "B.Cu")
		(at 469.646 -125.984 180)
		(property "Reference" "R1W12"
			(at 0.8382 -0.67818 180)
			(unlocked yes)
			(layer "B.SilkS")
			(effects
				(font
					(size 0.4064 0.254)
					(thickness 0.1524)
				)
				(justify left mirror)
			)
		)
		(property "Value" ""
			(at 0 0 0)
			(layer "B.Fab")
			(effects
				(font
					(size 1.27 1.27)
				)
				(justify mirror)
			)
		)
		(duplicate_pad_numbers_are_jumpers no)
		(fp_poly
			(pts
				(xy 0.2794 -0.1016) (xy -0.2794 -0.1016) (xy -0.2794 0.9906) (xy 0.2794 0.9906)
			)
			(stroke
				(width 0)
				(type default)
			)
			(fill no)
			(layer "B.CrtYd")
		)
		(fp_line
			(start 0.2794 0.9906)
			(end -0.2794 0.9906)
			(stroke
				(width 0.1)
				(type default)
			)
			(layer "B.Fab")
		)
		(fp_line
			(start 0.2794 -0.1016)
			(end 0.2794 0.9906)
			(stroke
				(width 0.1)
				(type default)
			)
			(layer "B.Fab")
		)
		(fp_line
			(start -0.2794 0.9906)
			(end -0.2794 -0.1016)
			(stroke
				(width 0.1)
				(type default)
			)
			(layer "B.Fab")
		)
		(fp_line
			(start -0.2794 -0.1016)
			(end 0.2794 -0.1016)
			(stroke
				(width 0.1)
				(type default)
			)
			(layer "B.Fab")
		)
		(pad "1" smd rect
			(at 0 0)
			(size 0.508 0.508)
			(layers "B.Cu" "B.Mask" "B.Paste")
			(net "FM_CPLD_USB_P0_EN_N")
		)
		(pad "2" smd rect
			(at 0 0.889)
			(size 0.508 0.508)
			(layers "B.Cu" "B.Mask" "B.Paste")
			(net "FM_USB_P0_EN_R_N")
		)
		(zone
			(layer "B.Cu")
			(hatch none 0.5)
			(connect_pads
				(clearance 0)
			)
			(min_thickness 0.25)
			(keepout
				(tracks not_allowed)
				(vias allowed)
				(pads allowed)
				(copperpour not_allowed)
				(footprints allowed)
			)
			(placement
				(enabled no)
				(sheetname "")
			)
			(fill
				(thermal_gap 0.5)
				(thermal_bridge_width 0.5)
				(island_removal_mode 0)
			)
			(polygon
				(pts
					(xy 469.392 -126.619) (xy 469.9 -126.619) (xy 469.9 -126.238) (xy 469.392 -126.238)
				)
			)
		)
		(zone
			(layer "B.Cu")
			(hatch none 0.5)
			(connect_pads
				(clearance 0)
			)
			(min_thickness 0.25)
			(keepout
				(tracks allowed)
				(vias not_allowed)
				(pads allowed)
				(copperpour not_allowed)
				(footprints allowed)
			)
			(placement
				(enabled no)
				(sheetname "")
			)
			(fill
				(thermal_gap 0.5)
				(thermal_bridge_width 0.5)
				(island_removal_mode 0)
			)
			(polygon
				(pts
					(xy 469.392 -126.238) (xy 469.9 -126.238) (xy 469.9 -126.619) (xy 469.392 -126.619)
				)
			)
		)
	)
	(footprint ""
		(layer "B.Cu")
		(at 409.321 -20.828 -90)
		(property "Reference" "R1U28"
			(at 0 0 90)
			(layer "B.SilkS")
			(hide yes)
			(effects
				(font
					(size 1.27 1.27)
				)
				(justify mirror)
			)
		)
		(property "Value" "*"
			(at -0.064008 -4.108196 270)
			(unlocked yes)
			(layer "B.Fab")
			(hide yes)
			(effects
				(font
					(size 1.27 1.016)
					(thickness 0.1524)
				)
				(justify mirror)
			)
		)
		(property "Device Type" "1K82R2F-1-GP_SMD-RG-1K82R2F-1-A"
			(at -0.064008 -5.632196 270)
			(unlocked yes)
			(layer "B.Fab")
			(hide yes)
			(effects
				(font
					(size 1.27 1.016)
					(thickness 0.1524)
				)
				(justify mirror)
			)
		)
		(duplicate_pad_numbers_are_jumpers no)
		(fp_line
			(start -0.508 -0.9398)
			(end 0.508 -0.9398)
			(stroke
				(width 0.1524)
				(type default)
			)
			(layer "B.SilkS")
		)
		(fp_line
			(start 0.508 -0.9398)
			(end 0.508 0.9398)
			(stroke
				(width 0.1524)
				(type default)
			)
			(layer "B.SilkS")
		)
		(fp_rect
			(start 0.508 0.9398)
			(end -0.508 -0.9398)
			(stroke
				(width 0)
				(type default)
			)
			(fill no)
			(layer "B.CrtYd")
		)
		(fp_rect
			(start 0.508 0.9398)
			(end -0.508 -0.9398)
			(stroke
				(width 0)
				(type default)
			)
			(fill no)
			(layer "B.Fab")
		)
		(pad "1" smd custom
			(at 0 -0.4445 90)
			(size 0.1397 0.1397)
			(layers "B.Cu" "B.Mask" "B.Paste")
			(net "A_P5V_SCALED")
			(options
				(clearance outline)
				(anchor circle)
			)
			(primitives
				(gr_poly
					(pts
						(arc
							(start -0.1778 0.2794)
							(mid -0.249642 0.249642)
							(end -0.2794 0.1778)
						)
						(arc
							(start -0.2794 -0.1778)
							(mid -0.249642 -0.249642)
							(end -0.1778 -0.2794)
						)
						(arc
							(start 0.1778 -0.2794)
							(mid 0.249642 -0.249642)
							(end 0.2794 -0.1778)
						)
						(arc
							(start 0.2794 0.1778)
							(mid 0.249642 0.249642)
							(end 0.1778 0.2794)
						)
					)
					(width 0)
					(fill yes)
				)
			)
		)
		(pad "2" smd custom
			(at 0 0.4445 90)
			(size 0.1397 0.1397)
			(layers "B.Cu" "B.Mask" "B.Paste")
			(net "GND")
			(options
				(clearance outline)
				(anchor circle)
			)
			(primitives
				(gr_poly
					(pts
						(arc
							(start -0.1778 0.2794)
							(mid -0.249642 0.249642)
							(end -0.2794 0.1778)
						)
						(arc
							(start -0.2794 -0.1778)
							(mid -0.249642 -0.249642)
							(end -0.1778 -0.2794)
						)
						(arc
							(start 0.1778 -0.2794)
							(mid 0.249642 -0.249642)
							(end 0.2794 -0.1778)
						)
						(arc
							(start 0.2794 0.1778)
							(mid 0.249642 0.249642)
							(end 0.1778 0.2794)
						)
					)
					(width 0)
					(fill yes)
				)
			)
		)
	)
	(footprint ""
		(layer "B.Cu")
		(at 368.716814 -125.507242 -90)
		(property "Reference" "C3M35"
			(at 0 0 90)
			(layer "B.SilkS")
			(hide yes)
			(effects
				(font
					(size 1.27 1.27)
				)
				(justify mirror)
			)
		)
		(property "Value" ""
			(at 0 0 90)
			(layer "B.Fab")
			(effects
				(font
					(size 1.27 1.27)
				)
				(justify mirror)
			)
		)
		(duplicate_pad_numbers_are_jumpers no)
		(fp_poly
			(pts
				(xy -0.3048 -0.1016) (xy -0.3048 0.9906) (xy 0.3048 0.9906) (xy 0.3048 -0.1016)
			)
			(stroke
				(width 0)
				(type default)
			)
			(fill no)
			(layer "B.CrtYd")
		)
		(fp_line
			(start -0.3048 0.9906)
			(end -0.3048 -0.1016)
			(stroke
				(width 0.1)
				(type default)
			)
			(layer "B.Fab")
		)
		(fp_line
			(start 0.3048 0.9906)
			(end -0.3048 0.9906)
			(stroke
				(width 0.1)
				(type default)
			)
			(layer "B.Fab")
		)
		(fp_line
			(start -0.3048 -0.1016)
			(end 0.3048 -0.1016)
			(stroke
				(width 0.1)
				(type default)
			)
			(layer "B.Fab")
		)
		(fp_line
			(start 0.3048 -0.1016)
			(end 0.3048 0.9906)
			(stroke
				(width 0.1)
				(type default)
			)
			(layer "B.Fab")
		)
		(pad "1" smd rect
			(at 0 0 90)
			(size 0.508 0.508)
			(layers "B.Cu" "B.Mask" "B.Paste")
			(net "P3E_CPU0_PE1_PCH_R_RXN<9>")
		)
		(pad "2" smd rect
			(at 0 0.889 90)
			(size 0.508 0.508)
			(layers "B.Cu" "B.Mask" "B.Paste")
			(net "P3E_CPU0_PE1_PCH_RXN<9>")
		)
		(zone
			(layer "B.Cu")
			(hatch none 0.5)
			(connect_pads
				(clearance 0)
			)
			(min_thickness 0.25)
			(keepout
				(tracks not_allowed)
				(vias allowed)
				(pads allowed)
				(copperpour not_allowed)
				(footprints allowed)
			)
			(placement
				(enabled no)
				(sheetname "")
			)
			(fill
				(thermal_gap 0.5)
				(thermal_bridge_width 0.5)
				(island_removal_mode 0)
			)
			(polygon
				(pts
					(xy 368.081814 -125.253242) (xy 368.081814 -125.761242) (xy 368.462814 -125.761242) (xy 368.462814 -125.253242)
				)
			)
		)
		(zone
			(layer "B.Cu")
			(hatch none 0.5)
			(connect_pads
				(clearance 0)
			)
			(min_thickness 0.25)
			(keepout
				(tracks allowed)
				(vias not_allowed)
				(pads allowed)
				(copperpour not_allowed)
				(footprints allowed)
			)
			(placement
				(enabled no)
				(sheetname "")
			)
			(fill
				(thermal_gap 0.5)
				(thermal_bridge_width 0.5)
				(island_removal_mode 0)
			)
			(polygon
				(pts
					(xy 368.462814 -125.253242) (xy 368.462814 -125.761242) (xy 368.081814 -125.761242) (xy 368.081814 -125.253242)
				)
			)
		)
	)
	(footprint ""
		(layer "B.Cu")
		(at 33.622996 -85.733382 90)
		(property "Reference" "C1C18"
			(at 0 0 90)
			(layer "B.SilkS")
			(hide yes)
			(effects
				(font
					(size 1.27 1.27)
				)
				(justify mirror)
			)
		)
		(property "Value" "*"
			(at -1.1811 -2.8194 90)
			(unlocked yes)
			(layer "B.Fab")
			(hide yes)
			(effects
				(font
					(size 1.27 1.016)
					(thickness 0.1524)
				)
				(justify mirror)
			)
		)
		(property "Device Type" "SC1U10V2KX-4-GP_SMD-BCG6-SC1U1A"
			(at -1.1811 -4.3434 90)
			(unlocked yes)
			(layer "B.Fab")
			(hide yes)
			(effects
				(font
					(size 1.27 1.016)
					(thickness 0.1524)
				)
				(justify mirror)
			)
		)
		(duplicate_pad_numbers_are_jumpers no)
		(fp_rect
			(start 0.4318 0.9525)
			(end -0.4318 -0.9525)
			(stroke
				(width 0)
				(type default)
			)
			(fill no)
			(layer "B.CrtYd")
		)
		(fp_rect
			(start 0.4318 0.9525)
			(end -0.4318 -0.9525)
			(stroke
				(width 0)
				(type default)
			)
			(fill no)
			(layer "B.Fab")
		)
		(pad "1" smd custom
			(at 0 -0.4445 270)
			(size 0.1524 0.1524)
			(layers "B.Cu" "B.Mask" "B.Paste")
			(net "P5V_STBY")
			(options
				(clearance outline)
				(anchor circle)
			)
			(primitives
				(gr_poly
					(pts
						(arc
							(start 0.3048 0.2032)
							(mid 0.275042 0.275042)
							(end 0.2032 0.3048)
						)
						(arc
							(start -0.2032 0.3048)
							(mid -0.275042 0.275042)
							(end -0.3048 0.2032)
						)
						(arc
							(start -0.3048 -0.2032)
							(mid -0.275042 -0.275042)
							(end -0.2032 -0.3048)
						)
						(arc
							(start 0.2032 -0.3048)
							(mid 0.275042 -0.275042)
							(end 0.3048 -0.2032)
						)
					)
					(width 0)
					(fill yes)
				)
			)
		)
		(pad "2" smd custom
			(at 0 0.4445 270)
			(size 0.1524 0.1524)
			(layers "B.Cu" "B.Mask" "B.Paste")
			(net "GND")
			(options
				(clearance outline)
				(anchor circle)
			)
			(primitives
				(gr_poly
					(pts
						(arc
							(start 0.3048 0.2032)
							(mid 0.275042 0.275042)
							(end 0.2032 0.3048)
						)
						(arc
							(start -0.2032 0.3048)
							(mid -0.275042 0.275042)
							(end -0.3048 0.2032)
						)
						(arc
							(start -0.3048 -0.2032)
							(mid -0.275042 -0.275042)
							(end -0.2032 -0.3048)
						)
						(arc
							(start 0.2032 -0.3048)
							(mid 0.275042 -0.275042)
							(end 0.3048 -0.2032)
						)
					)
					(width 0)
					(fill yes)
				)
			)
		)
	)
	(footprint ""
		(layer "B.Cu")
		(at 399.530824 -124.738384 90)
		(property "Reference" "C2M4"
			(at 0 0 90)
			(layer "B.SilkS")
			(hide yes)
			(effects
				(font
					(size 1.27 1.27)
				)
				(justify mirror)
			)
		)
		(property "Value" ""
			(at 0 0 90)
			(layer "B.Fab")
			(effects
				(font
					(size 1.27 1.27)
				)
				(justify mirror)
			)
		)
		(duplicate_pad_numbers_are_jumpers no)
		(fp_poly
			(pts
				(xy -0.3048 -0.1016) (xy -0.3048 0.9906) (xy 0.3048 0.9906) (xy 0.3048 -0.1016)
			)
			(stroke
				(width 0)
				(type default)
			)
			(fill no)
			(layer "B.CrtYd")
		)
		(fp_line
			(start 0.3048 -0.1016)
			(end 0.3048 0.9906)
			(stroke
				(width 0.1)
				(type default)
			)
			(layer "B.Fab")
		)
		(fp_line
			(start -0.3048 -0.1016)
			(end 0.3048 -0.1016)
			(stroke
				(width 0.1)
				(type default)
			)
			(layer "B.Fab")
		)
		(fp_line
			(start 0.3048 0.9906)
			(end -0.3048 0.9906)
			(stroke
				(width 0.1)
				(type default)
			)
			(layer "B.Fab")
		)
		(fp_line
			(start -0.3048 0.9906)
			(end -0.3048 -0.1016)
			(stroke
				(width 0.1)
				(type default)
			)
			(layer "B.Fab")
		)
		(pad "1" smd rect
			(at 0 0 270)
			(size 0.508 0.508)
			(layers "B.Cu" "B.Mask" "B.Paste")
			(net "P2E_SSB_BMC_TX_DP")
		)
		(pad "2" smd rect
			(at 0 0.889 270)
			(size 0.508 0.508)
			(layers "B.Cu" "B.Mask" "B.Paste")
			(net "P2E_SSB_BMC_TX_C_DP")
		)
		(zone
			(layer "B.Cu")
			(hatch none 0.5)
			(connect_pads
				(clearance 0)
			)
			(min_thickness 0.25)
			(keepout
				(tracks allowed)
				(vias not_allowed)
				(pads allowed)
				(copperpour not_allowed)
				(footprints allowed)
			)
			(placement
				(enabled no)
				(sheetname "")
			)
			(fill
				(thermal_gap 0.5)
				(thermal_bridge_width 0.5)
				(island_removal_mode 0)
			)
			(polygon
				(pts
					(xy 399.784824 -124.992384) (xy 399.784824 -124.484384) (xy 400.165824 -124.484384) (xy 400.165824 -124.992384)
				)
			)
		)
		(zone
			(layer "B.Cu")
			(hatch none 0.5)
			(connect_pads
				(clearance 0)
			)
			(min_thickness 0.25)
			(keepout
				(tracks not_allowed)
				(vias allowed)
				(pads allowed)
				(copperpour not_allowed)
				(footprints allowed)
			)
			(placement
				(enabled no)
				(sheetname "")
			)
			(fill
				(thermal_gap 0.5)
				(thermal_bridge_width 0.5)
				(island_removal_mode 0)
			)
			(polygon
				(pts
					(xy 400.165824 -124.992384) (xy 400.165824 -124.484384) (xy 399.784824 -124.484384) (xy 399.784824 -124.992384)
				)
			)
		)
	)
	(footprint ""
		(layer "B.Cu")
		(at 437.690006 -43.54195 180)
		(property "Reference" "R25W39"
			(at 0 0 0)
			(layer "B.SilkS")
			(hide yes)
			(effects
				(font
					(size 1.27 1.27)
				)
				(justify mirror)
			)
		)
		(property "Value" "*"
			(at -0.064008 -4.108196 180)
			(unlocked yes)
			(layer "B.Fab")
			(hide yes)
			(effects
				(font
					(size 1.27 1.016)
					(thickness 0.1524)
				)
				(justify mirror)
			)
		)
		(property "Device Type" "120R2F-GP_RCL_GP-120R2F-GP,64.A"
			(at -0.064008 -5.632196 180)
			(unlocked yes)
			(layer "B.Fab")
			(hide yes)
			(effects
				(font
					(size 1.27 1.016)
					(thickness 0.1524)
				)
				(justify mirror)
			)
		)
		(duplicate_pad_numbers_are_jumpers no)
		(fp_line
			(start 0.508 -0.9398)
			(end 0.508 0.9398)
			(stroke
				(width 0.1524)
				(type default)
			)
			(layer "B.SilkS")
		)
		(fp_line
			(start -0.508 -0.9398)
			(end 0.508 -0.9398)
			(stroke
				(width 0.1524)
				(type default)
			)
			(layer "B.SilkS")
		)
		(fp_rect
			(start 0.508 0.9398)
			(end -0.508 -0.9398)
			(stroke
				(width 0)
				(type default)
			)
			(fill no)
			(layer "B.CrtYd")
		)
		(fp_rect
			(start 0.508 0.9398)
			(end -0.508 -0.9398)
			(stroke
				(width 0)
				(type default)
			)
			(fill no)
			(layer "B.Fab")
		)
		(pad "1" smd custom
			(at 0 -0.4445)
			(size 0.1397 0.1397)
			(layers "B.Cu" "B.Mask" "B.Paste")
			(net "BMC_M_A1")
			(options
				(clearance outline)
				(anchor circle)
			)
			(primitives
				(gr_poly
					(pts
						(arc
							(start -0.1778 0.2794)
							(mid -0.249642 0.249642)
							(end -0.2794 0.1778)
						)
						(arc
							(start -0.2794 -0.1778)
							(mid -0.249642 -0.249642)
							(end -0.1778 -0.2794)
						)
						(arc
							(start 0.1778 -0.2794)
							(mid 0.249642 -0.249642)
							(end 0.2794 -0.1778)
						)
						(arc
							(start 0.2794 0.1778)
							(mid 0.249642 0.249642)
							(end 0.1778 0.2794)
						)
					)
					(width 0)
					(fill yes)
				)
			)
		)
		(pad "2" smd custom
			(at 0 0.4445)
			(size 0.1397 0.1397)
			(layers "B.Cu" "B.Mask" "B.Paste")
			(net "P1V2_AUX_BMC")
			(options
				(clearance outline)
				(anchor circle)
			)
			(primitives
				(gr_poly
					(pts
						(arc
							(start -0.1778 0.2794)
							(mid -0.249642 0.249642)
							(end -0.2794 0.1778)
						)
						(arc
							(start -0.2794 -0.1778)
							(mid -0.249642 -0.249642)
							(end -0.1778 -0.2794)
						)
						(arc
							(start 0.1778 -0.2794)
							(mid 0.249642 -0.249642)
							(end 0.2794 -0.1778)
						)
						(arc
							(start 0.2794 0.1778)
							(mid 0.249642 0.249642)
							(end 0.1778 0.2794)
						)
					)
					(width 0)
					(fill yes)
				)
			)
		)
	)
	(footprint ""
		(layer "B.Cu")
		(at 444.062866 -38.39591 90)
		(property "Reference" "R25W118"
			(at 0.8382 -0.67818 90)
			(unlocked yes)
			(layer "B.SilkS")
			(effects
				(font
					(size 0.4064 0.254)
					(thickness 0.1524)
				)
				(justify left mirror)
			)
		)
		(property "Value" ""
			(at 0 0 90)
			(layer "B.Fab")
			(effects
				(font
					(size 1.27 1.27)
				)
				(justify mirror)
			)
		)
		(duplicate_pad_numbers_are_jumpers no)
		(fp_poly
			(pts
				(xy 0.2794 -0.1016) (xy -0.2794 -0.1016) (xy -0.2794 0.9906) (xy 0.2794 0.9906)
			)
			(stroke
				(width 0)
				(type default)
			)
			(fill no)
			(layer "B.CrtYd")
		)
		(fp_line
			(start 0.2794 -0.1016)
			(end 0.2794 0.9906)
			(stroke
				(width 0.1)
				(type default)
			)
			(layer "B.Fab")
		)
		(fp_line
			(start -0.2794 -0.1016)
			(end 0.2794 -0.1016)
			(stroke
				(width 0.1)
				(type default)
			)
			(layer "B.Fab")
		)
		(fp_line
			(start 0.2794 0.9906)
			(end -0.2794 0.9906)
			(stroke
				(width 0.1)
				(type default)
			)
			(layer "B.Fab")
		)
		(fp_line
			(start -0.2794 0.9906)
			(end -0.2794 -0.1016)
			(stroke
				(width 0.1)
				(type default)
			)
			(layer "B.Fab")
		)
		(pad "1" smd rect
			(at 0 0 270)
			(size 0.508 0.508)
			(layers "B.Cu" "B.Mask" "B.Paste")
			(net "BMC_M_PAR")
		)
		(pad "2" smd rect
			(at 0 0.889 270)
			(size 0.508 0.508)
			(layers "B.Cu" "B.Mask" "B.Paste")
			(net "GND")
		)
		(zone
			(layer "B.Cu")
			(hatch none 0.5)
			(connect_pads
				(clearance 0)
			)
			(min_thickness 0.25)
			(keepout
				(tracks allowed)
				(vias not_allowed)
				(pads allowed)
				(copperpour not_allowed)
				(footprints allowed)
			)
			(placement
				(enabled no)
				(sheetname "")
			)
			(fill
				(thermal_gap 0.5)
				(thermal_bridge_width 0.5)
				(island_removal_mode 0)
			)
			(polygon
				(pts
					(xy 444.316866 -38.64991) (xy 444.316866 -38.14191) (xy 444.697866 -38.14191) (xy 444.697866 -38.64991)
				)
			)
		)
		(zone
			(layer "B.Cu")
			(hatch none 0.5)
			(connect_pads
				(clearance 0)
			)
			(min_thickness 0.25)
			(keepout
				(tracks not_allowed)
				(vias allowed)
				(pads allowed)
				(copperpour not_allowed)
				(footprints allowed)
			)
			(placement
				(enabled no)
				(sheetname "")
			)
			(fill
				(thermal_gap 0.5)
				(thermal_bridge_width 0.5)
				(island_removal_mode 0)
			)
			(polygon
				(pts
					(xy 444.697866 -38.64991) (xy 444.697866 -38.14191) (xy 444.316866 -38.14191) (xy 444.316866 -38.64991)
				)
			)
		)
	)
	(footprint ""
		(layer "B.Cu")
		(at 2.8702 -61.6712 -90)
		(property "Reference" "C9R5"
			(at 0 0 90)
			(layer "B.SilkS")
			(hide yes)
			(effects
				(font
					(size 1.27 1.27)
				)
				(justify mirror)
			)
		)
		(property "Value" ""
			(at 0 0 90)
			(layer "B.Fab")
			(effects
				(font
					(size 1.27 1.27)
				)
				(justify mirror)
			)
		)
		(duplicate_pad_numbers_are_jumpers no)
		(fp_rect
			(start -0.7239 -0.2159)
			(end 0.7239 1.9939)
			(stroke
				(width 0)
				(type default)
			)
			(fill no)
			(layer "B.CrtYd")
		)
		(fp_line
			(start -0.7239 1.9939)
			(end -0.7239 -0.2159)
			(stroke
				(width 0.1)
				(type default)
			)
			(layer "B.Fab")
		)
		(fp_line
			(start 0.7239 1.9939)
			(end -0.7239 1.9939)
			(stroke
				(width 0.1)
				(type default)
			)
			(layer "B.Fab")
		)
		(fp_line
			(start -0.7239 -0.2159)
			(end 0.7239 -0.2159)
			(stroke
				(width 0.1)
				(type default)
			)
			(layer "B.Fab")
		)
		(fp_line
			(start 0.7239 -0.2159)
			(end 0.7239 1.9939)
			(stroke
				(width 0.1)
				(type default)
			)
			(layer "B.Fab")
		)
		(pad "1" smd rect
			(at 0 0 90)
			(size 1.27 1.016)
			(layers "B.Cu" "B.Mask" "B.Paste")
			(net "P12V_PSU")
		)
		(pad "2" smd rect
			(at 0 1.778 90)
			(size 1.27 1.016)
			(layers "B.Cu" "B.Mask" "B.Paste")
			(net "GND")
		)
		(zone
			(layer "B.Cu")
			(hatch none 0.5)
			(connect_pads
				(clearance 0)
			)
			(min_thickness 0.25)
			(keepout
				(tracks not_allowed)
				(vias allowed)
				(pads allowed)
				(copperpour not_allowed)
				(footprints allowed)
			)
			(placement
				(enabled no)
				(sheetname "")
			)
			(fill
				(thermal_gap 0.5)
				(thermal_bridge_width 0.5)
				(island_removal_mode 0)
			)
			(polygon
				(pts
					(xy 2.3622 -62.3062) (xy 1.6002 -62.3062) (xy 1.6002 -61.0362) (xy 2.3622 -61.0362)
				)
			)
		)
	)
	(footprint ""
		(layer "B.Cu")
		(at 486.114344 -58.908696 90)
		(property "Reference" "R30W1"
			(at 0.8382 -0.67818 90)
			(unlocked yes)
			(layer "B.SilkS")
			(effects
				(font
					(size 0.4064 0.254)
					(thickness 0.1524)
				)
				(justify left mirror)
			)
		)
		(property "Value" ""
			(at 0 0 90)
			(layer "B.Fab")
			(effects
				(font
					(size 1.27 1.27)
				)
				(justify mirror)
			)
		)
		(duplicate_pad_numbers_are_jumpers no)
		(fp_poly
			(pts
				(xy 0.2794 -0.1016) (xy -0.2794 -0.1016) (xy -0.2794 0.9906) (xy 0.2794 0.9906)
			)
			(stroke
				(width 0)
				(type default)
			)
			(fill no)
			(layer "B.CrtYd")
		)
		(fp_line
			(start 0.2794 -0.1016)
			(end 0.2794 0.9906)
			(stroke
				(width 0.1)
				(type default)
			)
			(layer "B.Fab")
		)
		(fp_line
			(start -0.2794 -0.1016)
			(end 0.2794 -0.1016)
			(stroke
				(width 0.1)
				(type default)
			)
			(layer "B.Fab")
		)
		(fp_line
			(start 0.2794 0.9906)
			(end -0.2794 0.9906)
			(stroke
				(width 0.1)
				(type default)
			)
			(layer "B.Fab")
		)
		(fp_line
			(start -0.2794 0.9906)
			(end -0.2794 -0.1016)
			(stroke
				(width 0.1)
				(type default)
			)
			(layer "B.Fab")
		)
		(pad "1" smd rect
			(at 0 0 270)
			(size 0.508 0.508)
			(layers "B.Cu" "B.Mask" "B.Paste")
			(net "USB3_P01_RXN")
		)
		(pad "2" smd rect
			(at 0 0.889 270)
			(size 0.508 0.508)
			(layers "B.Cu" "B.Mask" "B.Paste")
			(net "USB3_P01_FB_RXN")
		)
		(zone
			(layer "B.Cu")
			(hatch none 0.5)
			(connect_pads
				(clearance 0)
			)
			(min_thickness 0.25)
			(keepout
				(tracks allowed)
				(vias not_allowed)
				(pads allowed)
				(copperpour not_allowed)
				(footprints allowed)
			)
			(placement
				(enabled no)
				(sheetname "")
			)
			(fill
				(thermal_gap 0.5)
				(thermal_bridge_width 0.5)
				(island_removal_mode 0)
			)
			(polygon
				(pts
					(xy 486.368344 -59.162696) (xy 486.368344 -58.654696) (xy 486.749344 -58.654696) (xy 486.749344 -59.162696)
				)
			)
		)
		(zone
			(layer "B.Cu")
			(hatch none 0.5)
			(connect_pads
				(clearance 0)
			)
			(min_thickness 0.25)
			(keepout
				(tracks not_allowed)
				(vias allowed)
				(pads allowed)
				(copperpour not_allowed)
				(footprints allowed)
			)
			(placement
				(enabled no)
				(sheetname "")
			)
			(fill
				(thermal_gap 0.5)
				(thermal_bridge_width 0.5)
				(island_removal_mode 0)
			)
			(polygon
				(pts
					(xy 486.749344 -59.162696) (xy 486.749344 -58.654696) (xy 486.368344 -58.654696) (xy 486.368344 -59.162696)
				)
			)
		)
	)
	(footprint ""
		(layer "B.Cu")
		(at 386.13715 -111.05515 180)
		(property "Reference" "C3N6"
			(at 0 0 0)
			(layer "B.SilkS")
			(hide yes)
			(effects
				(font
					(size 1.27 1.27)
				)
				(justify mirror)
			)
		)
		(property "Value" ""
			(at 0 0 0)
			(layer "B.Fab")
			(effects
				(font
					(size 1.27 1.27)
				)
				(justify mirror)
			)
		)
		(duplicate_pad_numbers_are_jumpers no)
		(fp_rect
			(start 0.2794 0.9144)
			(end -0.2794 -0.1143)
			(stroke
				(width 0)
				(type default)
			)
			(fill no)
			(layer "B.CrtYd")
		)
		(fp_line
			(start 0.2794 0.9144)
			(end 0.2794 -0.1143)
			(stroke
				(width 0.1)
				(type default)
			)
			(layer "B.Fab")
		)
		(fp_line
			(start 0.2794 -0.1143)
			(end -0.2794 -0.1143)
			(stroke
				(width 0.1)
				(type default)
			)
			(layer "B.Fab")
		)
		(fp_line
			(start -0.2794 0.9144)
			(end 0.2794 0.9144)
			(stroke
				(width 0.1)
				(type default)
			)
			(layer "B.Fab")
		)
		(fp_line
			(start -0.2794 -0.1143)
			(end -0.2794 0.9144)
			(stroke
				(width 0.1)
				(type default)
			)
			(layer "B.Fab")
		)
		(pad "1" smd custom
			(at 0 0 90)
			(size 0.10414 0.10414)
			(layers "B.Cu" "B.Mask" "B.Paste")
			(net "PVNN_PCH_STBY")
			(options
				(clearance outline)
				(anchor circle)
			)
			(primitives
				(gr_poly
					(pts
						(xy -0.20828 -0.08636) (xy -0.20828 0.08636) (xy -0.08636 0.20828) (xy 0.086614 0.20828) (xy 0.20828 0.086614)
						(xy 0.20828 -0.08636) (xy 0.08636 -0.20828) (xy -0.08636 -0.20828)
					)
					(width 0)
					(fill yes)
				)
			)
		)
		(pad "2" smd custom
			(at 0 0.8001 90)
			(size 0.10414 0.10414)
			(layers "B.Cu" "B.Mask" "B.Paste")
			(net "GND")
			(options
				(clearance outline)
				(anchor circle)
			)
			(primitives
				(gr_poly
					(pts
						(xy -0.20828 -0.08636) (xy -0.20828 0.08636) (xy -0.08636 0.20828) (xy 0.086614 0.20828) (xy 0.20828 0.086614)
						(xy 0.20828 -0.08636) (xy 0.08636 -0.20828) (xy -0.08636 -0.20828)
					)
					(width 0)
					(fill yes)
				)
			)
		)
		(zone
			(layer "B.Cu")
			(hatch none 0.5)
			(connect_pads
				(clearance 0)
			)
			(min_thickness 0.25)
			(keepout
				(tracks not_allowed)
				(vias allowed)
				(pads allowed)
				(copperpour not_allowed)
				(footprints allowed)
			)
			(placement
				(enabled no)
				(sheetname "")
			)
			(fill
				(thermal_gap 0.5)
				(thermal_bridge_width 0.5)
				(island_removal_mode 0)
			)
			(polygon
				(pts
					(xy 386.04952 -111.2647) (xy 386.04952 -111.6457) (xy 386.22478 -111.6457) (xy 386.225034 -111.2647)
				)
			)
		)
		(zone
			(layer "B.Cu")
			(hatch none 0.5)
			(connect_pads
				(clearance 0)
			)
			(min_thickness 0.25)
			(keepout
				(tracks allowed)
				(vias not_allowed)
				(pads allowed)
				(copperpour not_allowed)
				(footprints allowed)
			)
			(placement
				(enabled no)
				(sheetname "")
			)
			(fill
				(thermal_gap 0.5)
				(thermal_bridge_width 0.5)
				(island_removal_mode 0)
			)
			(polygon
				(pts
					(xy 386.04952 -111.2647) (xy 386.04952 -111.6457) (xy 386.22478 -111.6457) (xy 386.225034 -111.2647)
				)
			)
		)
	)
	(footprint ""
		(layer "B.Cu")
		(at 45.212 -78.867 -90)
		(property "Reference" "C9P8"
			(at -0.60833 -3.429 0)
			(unlocked yes)
			(layer "B.SilkS")
			(effects
				(font
					(size 0.7874 0.5842)
					(thickness 0.1524)
				)
				(justify mirror)
			)
		)
		(property "Value" ""
			(at 0 0 90)
			(layer "B.Fab")
			(effects
				(font
					(size 1.27 1.27)
				)
				(justify mirror)
			)
		)
		(duplicate_pad_numbers_are_jumpers no)
		(fp_line
			(start -2.286 7.366)
			(end -1.600708 7.366)
			(stroke
				(width 0.1524)
				(type default)
			)
			(layer "B.SilkS")
		)
		(fp_line
			(start -2.286 7.366)
			(end -2.286 1.63195)
			(stroke
				(width 0.1524)
				(type default)
			)
			(layer "B.SilkS")
		)
		(fp_line
			(start 2.286 7.366)
			(end 1.60147 7.366)
			(stroke
				(width 0.1524)
				(type default)
			)
			(layer "B.SilkS")
		)
		(fp_line
			(start 2.286 7.366)
			(end 2.286 1.632712)
			(stroke
				(width 0.1524)
				(type default)
			)
			(layer "B.SilkS")
		)
		(fp_line
			(start -2.504948 1.633728)
			(end -1.6002 1.633728)
			(stroke
				(width 0.1524)
				(type default)
			)
			(layer "B.SilkS")
		)
		(fp_line
			(start 2.563114 1.633728)
			(end 1.6002 1.633728)
			(stroke
				(width 0.1524)
				(type default)
			)
			(layer "B.SilkS")
		)
		(fp_line
			(start -2.504948 -1.616456)
			(end -2.504948 1.633728)
			(stroke
				(width 0.1524)
				(type default)
			)
			(layer "B.SilkS")
		)
		(fp_line
			(start -1.6002 -1.616456)
			(end -2.504948 -1.616456)
			(stroke
				(width 0.1524)
				(type default)
			)
			(layer "B.SilkS")
		)
		(fp_line
			(start 1.6002 -1.616456)
			(end 2.563114 -1.616456)
			(stroke
				(width 0.1524)
				(type default)
			)
			(layer "B.SilkS")
		)
		(fp_line
			(start 2.563114 -1.616456)
			(end 2.563114 1.633728)
			(stroke
				(width 0.1524)
				(type default)
			)
			(layer "B.SilkS")
		)
		(fp_rect
			(start 2.286 7.366)
			(end -2.286 -0.254)
			(stroke
				(width 0)
				(type default)
			)
			(fill no)
			(layer "B.CrtYd")
		)
		(fp_line
			(start -2.286 7.366)
			(end 2.286 7.366)
			(stroke
				(width 0.1)
				(type default)
			)
			(layer "B.Fab")
		)
		(fp_line
			(start 2.286 7.366)
			(end 2.286 -0.254)
			(stroke
				(width 0.1)
				(type default)
			)
			(layer "B.Fab")
		)
		(fp_line
			(start -2.286 -0.254)
			(end -2.286 7.366)
			(stroke
				(width 0.1)
				(type default)
			)
			(layer "B.Fab")
		)
		(fp_line
			(start 2.286 -0.254)
			(end -2.286 -0.254)
			(stroke
				(width 0.1)
				(type default)
			)
			(layer "B.Fab")
		)
		(pad "1" smd rect
			(at 0 0 90)
			(size 2.54 3.048)
			(layers "B.Cu" "B.Mask" "B.Paste")
			(net "PVCCIN_CPU1")
		)
		(pad "2" smd rect
			(at 0 7.112 90)
			(size 2.54 3.048)
			(layers "B.Cu" "B.Mask" "B.Paste")
			(net "GND")
		)
	)
	(footprint ""
		(layer "B.Cu")
		(at 258.445 -8.0772 -90)
		(property "Reference" "C5U11"
			(at 0 0 90)
			(layer "B.SilkS")
			(hide yes)
			(effects
				(font
					(size 1.27 1.27)
				)
				(justify mirror)
			)
		)
		(property "Value" ""
			(at 0 0 90)
			(layer "B.Fab")
			(effects
				(font
					(size 1.27 1.27)
				)
				(justify mirror)
			)
		)
		(duplicate_pad_numbers_are_jumpers no)
		(fp_rect
			(start 0.500126 1.598422)
			(end -0.500126 -0.201422)
			(stroke
				(width 0)
				(type default)
			)
			(fill no)
			(layer "B.CrtYd")
		)
		(fp_line
			(start -0.500126 1.598422)
			(end 0.500126 1.598422)
			(stroke
				(width 0.1)
				(type default)
			)
			(layer "B.Fab")
		)
		(fp_line
			(start 0.500126 1.598422)
			(end 0.500126 -0.201422)
			(stroke
				(width 0.1)
				(type default)
			)
			(layer "B.Fab")
		)
		(fp_line
			(start -0.500126 -0.201422)
			(end -0.500126 1.598422)
			(stroke
				(width 0.1)
				(type default)
			)
			(layer "B.Fab")
		)
		(fp_line
			(start 0.500126 -0.201422)
			(end -0.500126 -0.201422)
			(stroke
				(width 0.1)
				(type default)
			)
			(layer "B.Fab")
		)
		(pad "1" smd rect
			(at 0 0 180)
			(size 0.889 0.9906)
			(layers "B.Cu" "B.Mask" "B.Paste")
			(net "PVDDQ_ABC")
		)
		(pad "2" smd rect
			(at 0 1.397 180)
			(size 0.889 0.9906)
			(layers "B.Cu" "B.Mask" "B.Paste")
			(net "GND")
		)
		(zone
			(layer "B.Cu")
			(hatch none 0.5)
			(connect_pads
				(clearance 0)
			)
			(min_thickness 0.25)
			(keepout
				(tracks allowed)
				(vias not_allowed)
				(pads allowed)
				(copperpour not_allowed)
				(footprints allowed)
			)
			(placement
				(enabled no)
				(sheetname "")
			)
			(fill
				(thermal_gap 0.5)
				(thermal_bridge_width 0.5)
				(island_removal_mode 0)
			)
			(polygon
				(pts
					(xy 257.4925 -7.5819) (xy 258.0005 -7.5819) (xy 258.0005 -8.5725) (xy 257.4925 -8.5725)
				)
			)
		)
		(zone
			(layer "B.Cu")
			(hatch none 0.5)
			(connect_pads
				(clearance 0)
			)
			(min_thickness 0.25)
			(keepout
				(tracks not_allowed)
				(vias allowed)
				(pads allowed)
				(copperpour not_allowed)
				(footprints allowed)
			)
			(placement
				(enabled no)
				(sheetname "")
			)
			(fill
				(thermal_gap 0.5)
				(thermal_bridge_width 0.5)
				(island_removal_mode 0)
			)
			(polygon
				(pts
					(xy 257.4925 -7.5819) (xy 258.0005 -7.5819) (xy 258.0005 -8.5725) (xy 257.4925 -8.5725)
				)
			)
		)
	)
	(footprint ""
		(layer "B.Cu")
		(at 343.125806 -60.368434)
		(property "Reference" "R2U21"
			(at 0 0 0)
			(layer "B.SilkS")
			(hide yes)
			(effects
				(font
					(size 1.27 1.27)
				)
				(justify mirror)
			)
		)
		(property "Value" ""
			(at 0 0 0)
			(layer "B.Fab")
			(effects
				(font
					(size 1.27 1.27)
				)
				(justify mirror)
			)
		)
		(duplicate_pad_numbers_are_jumpers no)
		(fp_poly
			(pts
				(xy 0.2794 -0.1016) (xy -0.2794 -0.1016) (xy -0.2794 0.9906) (xy 0.2794 0.9906)
			)
			(stroke
				(width 0)
				(type default)
			)
			(fill no)
			(layer "B.CrtYd")
		)
		(fp_line
			(start -0.2794 -0.1016)
			(end 0.2794 -0.1016)
			(stroke
				(width 0.1)
				(type default)
			)
			(layer "B.Fab")
		)
		(fp_line
			(start -0.2794 0.9906)
			(end -0.2794 -0.1016)
			(stroke
				(width 0.1)
				(type default)
			)
			(layer "B.Fab")
		)
		(fp_line
			(start 0.2794 -0.1016)
			(end 0.2794 0.9906)
			(stroke
				(width 0.1)
				(type default)
			)
			(layer "B.Fab")
		)
		(fp_line
			(start 0.2794 0.9906)
			(end -0.2794 0.9906)
			(stroke
				(width 0.1)
				(type default)
			)
			(layer "B.Fab")
		)
		(pad "1" smd rect
			(at 0 0 180)
			(size 0.508 0.508)
			(layers "B.Cu" "B.Mask" "B.Paste")
			(net "P3E_CPU0_PE1_SS_RXN<3>")
		)
		(pad "2" smd rect
			(at 0 0.889 180)
			(size 0.508 0.508)
			(layers "B.Cu" "B.Mask" "B.Paste")
			(net "P3E_CPU0_PE1_SS_R_RXN<3>")
		)
		(zone
			(layer "B.Cu")
			(hatch none 0.5)
			(connect_pads
				(clearance 0)
			)
			(min_thickness 0.25)
			(keepout
				(tracks allowed)
				(vias not_allowed)
				(pads allowed)
				(copperpour not_allowed)
				(footprints allowed)
			)
			(placement
				(enabled no)
				(sheetname "")
			)
			(fill
				(thermal_gap 0.5)
				(thermal_bridge_width 0.5)
				(island_removal_mode 0)
			)
			(polygon
				(pts
					(xy 343.379806 -60.114434) (xy 342.871806 -60.114434) (xy 342.871806 -59.733434) (xy 343.379806 -59.733434)
				)
			)
		)
		(zone
			(layer "B.Cu")
			(hatch none 0.5)
			(connect_pads
				(clearance 0)
			)
			(min_thickness 0.25)
			(keepout
				(tracks not_allowed)
				(vias allowed)
				(pads allowed)
				(copperpour not_allowed)
				(footprints allowed)
			)
			(placement
				(enabled no)
				(sheetname "")
			)
			(fill
				(thermal_gap 0.5)
				(thermal_bridge_width 0.5)
				(island_removal_mode 0)
			)
			(polygon
				(pts
					(xy 343.379806 -59.733434) (xy 342.871806 -59.733434) (xy 342.871806 -60.114434) (xy 343.379806 -60.114434)
				)
			)
		)
	)
	(footprint ""
		(layer "B.Cu")
		(at 17.83842 -105.20172 90)
		(property "Reference" "C9N6"
			(at 0 0 90)
			(layer "B.SilkS")
			(hide yes)
			(effects
				(font
					(size 1.27 1.27)
				)
				(justify mirror)
			)
		)
		(property "Value" ""
			(at 0 0 90)
			(layer "B.Fab")
			(effects
				(font
					(size 1.27 1.27)
				)
				(justify mirror)
			)
		)
		(duplicate_pad_numbers_are_jumpers no)
		(fp_poly
			(pts
				(xy -0.3048 -0.1016) (xy -0.3048 0.9906) (xy 0.3048 0.9906) (xy 0.3048 -0.1016)
			)
			(stroke
				(width 0)
				(type default)
			)
			(fill no)
			(layer "B.CrtYd")
		)
		(fp_line
			(start 0.3048 -0.1016)
			(end 0.3048 0.9906)
			(stroke
				(width 0.1)
				(type default)
			)
			(layer "B.Fab")
		)
		(fp_line
			(start -0.3048 -0.1016)
			(end 0.3048 -0.1016)
			(stroke
				(width 0.1)
				(type default)
			)
			(layer "B.Fab")
		)
		(fp_line
			(start 0.3048 0.9906)
			(end -0.3048 0.9906)
			(stroke
				(width 0.1)
				(type default)
			)
			(layer "B.Fab")
		)
		(fp_line
			(start -0.3048 0.9906)
			(end -0.3048 -0.1016)
			(stroke
				(width 0.1)
				(type default)
			)
			(layer "B.Fab")
		)
		(pad "1" smd rect
			(at 0 0 270)
			(size 0.508 0.508)
			(layers "B.Cu" "B.Mask" "B.Paste")
			(net "P3E_CPU1_PE3_MP_C_TXN<13>")
		)
		(pad "2" smd rect
			(at 0 0.889 270)
			(size 0.508 0.508)
			(layers "B.Cu" "B.Mask" "B.Paste")
			(net "P3E_CPU1_PE3_MP_TXN<13>")
		)
		(zone
			(layer "B.Cu")
			(hatch none 0.5)
			(connect_pads
				(clearance 0)
			)
			(min_thickness 0.25)
			(keepout
				(tracks allowed)
				(vias not_allowed)
				(pads allowed)
				(copperpour not_allowed)
				(footprints allowed)
			)
			(placement
				(enabled no)
				(sheetname "")
			)
			(fill
				(thermal_gap 0.5)
				(thermal_bridge_width 0.5)
				(island_removal_mode 0)
			)
			(polygon
				(pts
					(xy 18.09242 -105.45572) (xy 18.09242 -104.94772) (xy 18.47342 -104.94772) (xy 18.47342 -105.45572)
				)
			)
		)
		(zone
			(layer "B.Cu")
			(hatch none 0.5)
			(connect_pads
				(clearance 0)
			)
			(min_thickness 0.25)
			(keepout
				(tracks not_allowed)
				(vias allowed)
				(pads allowed)
				(copperpour not_allowed)
				(footprints allowed)
			)
			(placement
				(enabled no)
				(sheetname "")
			)
			(fill
				(thermal_gap 0.5)
				(thermal_bridge_width 0.5)
				(island_removal_mode 0)
			)
			(polygon
				(pts
					(xy 18.47342 -105.45572) (xy 18.47342 -104.94772) (xy 18.09242 -104.94772) (xy 18.09242 -105.45572)
				)
			)
		)
	)
	(footprint ""
		(layer "B.Cu")
		(at 498.602 -138.557 90)
		(property "Reference" "R1L43"
			(at 0 0 90)
			(layer "B.SilkS")
			(hide yes)
			(effects
				(font
					(size 1.27 1.27)
				)
				(justify mirror)
			)
		)
		(property "Value" ""
			(at 0 0 90)
			(layer "B.Fab")
			(effects
				(font
					(size 1.27 1.27)
				)
				(justify mirror)
			)
		)
		(duplicate_pad_numbers_are_jumpers no)
		(fp_poly
			(pts
				(xy 0.2794 -0.1016) (xy -0.2794 -0.1016) (xy -0.2794 0.9906) (xy 0.2794 0.9906)
			)
			(stroke
				(width 0)
				(type default)
			)
			(fill no)
			(layer "B.CrtYd")
		)
		(fp_line
			(start 0.2794 -0.1016)
			(end 0.2794 0.9906)
			(stroke
				(width 0.1)
				(type default)
			)
			(layer "B.Fab")
		)
		(fp_line
			(start -0.2794 -0.1016)
			(end 0.2794 -0.1016)
			(stroke
				(width 0.1)
				(type default)
			)
			(layer "B.Fab")
		)
		(fp_line
			(start 0.2794 0.9906)
			(end -0.2794 0.9906)
			(stroke
				(width 0.1)
				(type default)
			)
			(layer "B.Fab")
		)
		(fp_line
			(start -0.2794 0.9906)
			(end -0.2794 -0.1016)
			(stroke
				(width 0.1)
				(type default)
			)
			(layer "B.Fab")
		)
		(pad "1" smd rect
			(at 0 0 270)
			(size 0.508 0.508)
			(layers "B.Cu" "B.Mask" "B.Paste")
			(net "FM_UARTSW_LSB_R_N")
		)
		(pad "2" smd rect
			(at 0 0.889 270)
			(size 0.508 0.508)
			(layers "B.Cu" "B.Mask" "B.Paste")
			(net "P3V3_STBY")
		)
		(zone
			(layer "B.Cu")
			(hatch none 0.5)
			(connect_pads
				(clearance 0)
			)
			(min_thickness 0.25)
			(keepout
				(tracks allowed)
				(vias not_allowed)
				(pads allowed)
				(copperpour not_allowed)
				(footprints allowed)
			)
			(placement
				(enabled no)
				(sheetname "")
			)
			(fill
				(thermal_gap 0.5)
				(thermal_bridge_width 0.5)
				(island_removal_mode 0)
			)
			(polygon
				(pts
					(xy 498.856 -138.811) (xy 498.856 -138.303) (xy 499.237 -138.303) (xy 499.237 -138.811)
				)
			)
		)
		(zone
			(layer "B.Cu")
			(hatch none 0.5)
			(connect_pads
				(clearance 0)
			)
			(min_thickness 0.25)
			(keepout
				(tracks not_allowed)
				(vias allowed)
				(pads allowed)
				(copperpour not_allowed)
				(footprints allowed)
			)
			(placement
				(enabled no)
				(sheetname "")
			)
			(fill
				(thermal_gap 0.5)
				(thermal_bridge_width 0.5)
				(island_removal_mode 0)
			)
			(polygon
				(pts
					(xy 499.237 -138.811) (xy 499.237 -138.303) (xy 498.856 -138.303) (xy 498.856 -138.811)
				)
			)
		)
	)
	(footprint ""
		(layer "B.Cu")
		(at 442.3918 -141.062202 90)
		(property "Reference" "C25W91"
			(at 0.8382 -0.67818 90)
			(unlocked yes)
			(layer "B.SilkS")
			(effects
				(font
					(size 0.4064 0.254)
					(thickness 0.1524)
				)
				(justify left mirror)
			)
		)
		(property "Value" ""
			(at 0 0 90)
			(layer "B.Fab")
			(effects
				(font
					(size 1.27 1.27)
				)
				(justify mirror)
			)
		)
		(duplicate_pad_numbers_are_jumpers no)
		(fp_poly
			(pts
				(xy -0.3048 -0.1016) (xy -0.3048 0.9906) (xy 0.3048 0.9906) (xy 0.3048 -0.1016)
			)
			(stroke
				(width 0)
				(type default)
			)
			(fill no)
			(layer "B.CrtYd")
		)
		(fp_line
			(start 0.3048 -0.1016)
			(end 0.3048 0.9906)
			(stroke
				(width 0.1)
				(type default)
			)
			(layer "B.Fab")
		)
		(fp_line
			(start -0.3048 -0.1016)
			(end 0.3048 -0.1016)
			(stroke
				(width 0.1)
				(type default)
			)
			(layer "B.Fab")
		)
		(fp_line
			(start 0.3048 0.9906)
			(end -0.3048 0.9906)
			(stroke
				(width 0.1)
				(type default)
			)
			(layer "B.Fab")
		)
		(fp_line
			(start -0.3048 0.9906)
			(end -0.3048 -0.1016)
			(stroke
				(width 0.1)
				(type default)
			)
			(layer "B.Fab")
		)
		(pad "1" smd rect
			(at 0 0 270)
			(size 0.508 0.508)
			(layers "B.Cu" "B.Mask" "B.Paste")
			(net "P3V3_STBY")
		)
		(pad "2" smd rect
			(at 0 0.889 270)
			(size 0.508 0.508)
			(layers "B.Cu" "B.Mask" "B.Paste")
			(net "GND")
		)
		(zone
			(layer "B.Cu")
			(hatch none 0.5)
			(connect_pads
				(clearance 0)
			)
			(min_thickness 0.25)
			(keepout
				(tracks allowed)
				(vias not_allowed)
				(pads allowed)
				(copperpour not_allowed)
				(footprints allowed)
			)
			(placement
				(enabled no)
				(sheetname "")
			)
			(fill
				(thermal_gap 0.5)
				(thermal_bridge_width 0.5)
				(island_removal_mode 0)
			)
			(polygon
				(pts
					(xy 442.6458 -141.316202) (xy 442.6458 -140.808202) (xy 443.0268 -140.808202) (xy 443.0268 -141.316202)
				)
			)
		)
		(zone
			(layer "B.Cu")
			(hatch none 0.5)
			(connect_pads
				(clearance 0)
			)
			(min_thickness 0.25)
			(keepout
				(tracks not_allowed)
				(vias allowed)
				(pads allowed)
				(copperpour not_allowed)
				(footprints allowed)
			)
			(placement
				(enabled no)
				(sheetname "")
			)
			(fill
				(thermal_gap 0.5)
				(thermal_bridge_width 0.5)
				(island_removal_mode 0)
			)
			(polygon
				(pts
					(xy 443.0268 -141.316202) (xy 443.0268 -140.808202) (xy 442.6458 -140.808202) (xy 442.6458 -141.316202)
				)
			)
		)
	)
	(footprint ""
		(layer "B.Cu")
		(at 454.2282 -52.330858)
		(property "Reference" "C1R7"
			(at 0 0 0)
			(layer "B.SilkS")
			(hide yes)
			(effects
				(font
					(size 1.27 1.27)
				)
				(justify mirror)
			)
		)
		(property "Value" ""
			(at 0 0 0)
			(layer "B.Fab")
			(effects
				(font
					(size 1.27 1.27)
				)
				(justify mirror)
			)
		)
		(duplicate_pad_numbers_are_jumpers no)
		(fp_poly
			(pts
				(xy -0.3048 -0.1016) (xy -0.3048 0.9906) (xy 0.3048 0.9906) (xy 0.3048 -0.1016)
			)
			(stroke
				(width 0)
				(type default)
			)
			(fill no)
			(layer "B.CrtYd")
		)
		(fp_line
			(start -0.3048 -0.1016)
			(end 0.3048 -0.1016)
			(stroke
				(width 0.1)
				(type default)
			)
			(layer "B.Fab")
		)
		(fp_line
			(start -0.3048 0.9906)
			(end -0.3048 -0.1016)
			(stroke
				(width 0.1)
				(type default)
			)
			(layer "B.Fab")
		)
		(fp_line
			(start 0.3048 -0.1016)
			(end 0.3048 0.9906)
			(stroke
				(width 0.1)
				(type default)
			)
			(layer "B.Fab")
		)
		(fp_line
			(start 0.3048 0.9906)
			(end -0.3048 0.9906)
			(stroke
				(width 0.1)
				(type default)
			)
			(layer "B.Fab")
		)
		(pad "1" smd rect
			(at 0 0 180)
			(size 0.508 0.508)
			(layers "B.Cu" "B.Mask" "B.Paste")
			(net "P3E_CPU0_PE3_OCP_TXN<3>")
		)
		(pad "2" smd rect
			(at 0 0.889 180)
			(size 0.508 0.508)
			(layers "B.Cu" "B.Mask" "B.Paste")
			(net "P3E_OCP_CPU0_PE3_C_TXN<3>")
		)
		(zone
			(layer "B.Cu")
			(hatch none 0.5)
			(connect_pads
				(clearance 0)
			)
			(min_thickness 0.25)
			(keepout
				(tracks allowed)
				(vias not_allowed)
				(pads allowed)
				(copperpour not_allowed)
				(footprints allowed)
			)
			(placement
				(enabled no)
				(sheetname "")
			)
			(fill
				(thermal_gap 0.5)
				(thermal_bridge_width 0.5)
				(island_removal_mode 0)
			)
			(polygon
				(pts
					(xy 454.4822 -52.076858) (xy 453.9742 -52.076858) (xy 453.9742 -51.695858) (xy 454.4822 -51.695858)
				)
			)
		)
	)
	(footprint ""
		(layer "B.Cu")
		(at 113.761012 -29.94152 90)
		(property "Reference" "SH7U2"
			(at 0 0 90)
			(layer "B.SilkS")
			(hide yes)
			(effects
				(font
					(size 1.27 1.27)
				)
				(justify mirror)
			)
		)
		(property "Value" ""
			(at 0 0 90)
			(layer "B.Fab")
			(effects
				(font
					(size 1.27 1.27)
				)
				(justify mirror)
			)
		)
		(duplicate_pad_numbers_are_jumpers no)
		(fp_poly
			(pts
				(xy 0.1651 -0.0508) (xy 0.1651 0.5842) (xy -0.1651 0.5842) (xy -0.1651 -0.0508)
			)
			(stroke
				(width 0)
				(type default)
			)
			(fill no)
			(layer "B.CrtYd")
		)
		(fp_line
			(start 0.1651 -0.0508)
			(end -0.1651 -0.0508)
			(stroke
				(width 0.1)
				(type default)
			)
			(layer "B.Fab")
		)
		(fp_line
			(start -0.1651 -0.0508)
			(end -0.1651 0.5842)
			(stroke
				(width 0.1)
				(type default)
			)
			(layer "B.Fab")
		)
		(fp_line
			(start 0.1651 0.5842)
			(end 0.1651 -0.0508)
			(stroke
				(width 0.1)
				(type default)
			)
			(layer "B.Fab")
		)
		(fp_line
			(start -0.1651 0.5842)
			(end 0.1651 0.5842)
			(stroke
				(width 0.1)
				(type default)
			)
			(layer "B.Fab")
		)
		(pad "1" smd custom
			(at 0 0 90)
			(size 0.0762 0.0762)
			(layers "B.Cu" "B.Mask" "B.Paste")
			(net "VSENSE_PVDDQ_GHJ_N")
			(options
				(clearance outline)
				(anchor circle)
			)
			(primitives
				(gr_poly
					(pts
						(arc
							(start -0.1524 0.10795)
							(mid -0.098518 0.130268)
							(end -0.0762 0.18415)
						)
						(xy -0.0762 0.22225) (xy 0.0762 0.22225)
						(arc
							(start 0.0762 0.18415)
							(mid 0.098518 0.130268)
							(end 0.1524 0.10795)
						)
						(xy 0.1524 -0.22225) (xy -0.1524 -0.22225)
					)
					(width 0)
					(fill yes)
				)
			)
		)
		(pad "2" smd custom
			(at 0 0.5334 270)
			(size 0.0762 0.0762)
			(layers "B.Cu" "B.Mask" "B.Paste")
			(net "GND")
			(options
				(clearance outline)
				(anchor circle)
			)
			(primitives
				(gr_poly
					(pts
						(arc
							(start -0.1524 0.10795)
							(mid -0.098518 0.130268)
							(end -0.0762 0.18415)
						)
						(xy -0.0762 0.22225) (xy 0.0762 0.22225)
						(arc
							(start 0.0762 0.18415)
							(mid 0.098518 0.130268)
							(end 0.1524 0.10795)
						)
						(xy 0.1524 -0.22225) (xy -0.1524 -0.22225)
					)
					(width 0)
					(fill yes)
				)
			)
		)
	)
	(footprint ""
		(layer "B.Cu")
		(at 116.332 -75.692 90)
		(property "Reference" "R7P14"
			(at 0 0 90)
			(layer "B.SilkS")
			(hide yes)
			(effects
				(font
					(size 1.27 1.27)
				)
				(justify mirror)
			)
		)
		(property "Value" ""
			(at 0 0 90)
			(layer "B.Fab")
			(effects
				(font
					(size 1.27 1.27)
				)
				(justify mirror)
			)
		)
		(duplicate_pad_numbers_are_jumpers no)
		(fp_poly
			(pts
				(xy 0.2794 -0.1016) (xy -0.2794 -0.1016) (xy -0.2794 0.9906) (xy 0.2794 0.9906)
			)
			(stroke
				(width 0)
				(type default)
			)
			(fill no)
			(layer "B.CrtYd")
		)
		(fp_line
			(start 0.2794 -0.1016)
			(end 0.2794 0.9906)
			(stroke
				(width 0.1)
				(type default)
			)
			(layer "B.Fab")
		)
		(fp_line
			(start -0.2794 -0.1016)
			(end 0.2794 -0.1016)
			(stroke
				(width 0.1)
				(type default)
			)
			(layer "B.Fab")
		)
		(fp_line
			(start 0.2794 0.9906)
			(end -0.2794 0.9906)
			(stroke
				(width 0.1)
				(type default)
			)
			(layer "B.Fab")
		)
		(fp_line
			(start -0.2794 0.9906)
			(end -0.2794 -0.1016)
			(stroke
				(width 0.1)
				(type default)
			)
			(layer "B.Fab")
		)
		(pad "1" smd rect
			(at 0 0 270)
			(size 0.508 0.508)
			(layers "B.Cu" "B.Mask" "B.Paste")
			(net "GND")
		)
		(pad "2" smd rect
			(at 0 0.889 270)
			(size 0.508 0.508)
			(layers "B.Cu" "B.Mask" "B.Paste")
			(net "PD_CPU1_DMIMODE_OVERRIDE")
		)
		(zone
			(layer "B.Cu")
			(hatch none 0.5)
			(connect_pads
				(clearance 0)
			)
			(min_thickness 0.25)
			(keepout
				(tracks allowed)
				(vias not_allowed)
				(pads allowed)
				(copperpour not_allowed)
				(footprints allowed)
			)
			(placement
				(enabled no)
				(sheetname "")
			)
			(fill
				(thermal_gap 0.5)
				(thermal_bridge_width 0.5)
				(island_removal_mode 0)
			)
			(polygon
				(pts
					(xy 116.586 -75.946) (xy 116.586 -75.438) (xy 116.967 -75.438) (xy 116.967 -75.946)
				)
			)
		)
		(zone
			(layer "B.Cu")
			(hatch none 0.5)
			(connect_pads
				(clearance 0)
			)
			(min_thickness 0.25)
			(keepout
				(tracks not_allowed)
				(vias allowed)
				(pads allowed)
				(copperpour not_allowed)
				(footprints allowed)
			)
			(placement
				(enabled no)
				(sheetname "")
			)
			(fill
				(thermal_gap 0.5)
				(thermal_bridge_width 0.5)
				(island_removal_mode 0)
			)
			(polygon
				(pts
					(xy 116.967 -75.946) (xy 116.967 -75.438) (xy 116.586 -75.438) (xy 116.586 -75.946)
				)
			)
		)
	)
	(footprint ""
		(layer "B.Cu")
		(at 271.350486 -73.51014)
		(property "Reference" "C5P30"
			(at 0 0 0)
			(layer "B.SilkS")
			(hide yes)
			(effects
				(font
					(size 1.27 1.27)
				)
				(justify mirror)
			)
		)
		(property "Value" ""
			(at 0 0 0)
			(layer "B.Fab")
			(effects
				(font
					(size 1.27 1.27)
				)
				(justify mirror)
			)
		)
		(duplicate_pad_numbers_are_jumpers no)
		(fp_poly
			(pts
				(xy 0.7239 -0.2159) (xy -0.7239 -0.2159) (xy -0.7239 1.9939) (xy 0.7239 1.9939)
			)
			(stroke
				(width 0)
				(type default)
			)
			(fill no)
			(layer "B.CrtYd")
		)
		(fp_line
			(start -0.7239 -0.2159)
			(end 0.7239 -0.2159)
			(stroke
				(width 0.1)
				(type default)
			)
			(layer "B.Fab")
		)
		(fp_line
			(start -0.7239 1.9939)
			(end -0.7239 -0.2159)
			(stroke
				(width 0.1)
				(type default)
			)
			(layer "B.Fab")
		)
		(fp_line
			(start 0.7239 -0.2159)
			(end 0.7239 1.9939)
			(stroke
				(width 0.1)
				(type default)
			)
			(layer "B.Fab")
		)
		(fp_line
			(start 0.7239 1.9939)
			(end -0.7239 1.9939)
			(stroke
				(width 0.1)
				(type default)
			)
			(layer "B.Fab")
		)
		(pad "1" smd rect
			(at 0 0 180)
			(size 1.27 1.016)
			(layers "B.Cu" "B.Mask" "B.Paste")
			(net "PVCCMCP_CPU0")
		)
		(pad "2" smd rect
			(at 0 1.778 180)
			(size 1.27 1.016)
			(layers "B.Cu" "B.Mask" "B.Paste")
			(net "GND")
		)
		(zone
			(layer "B.Cu")
			(hatch none 0.5)
			(connect_pads
				(clearance 0)
			)
			(min_thickness 0.25)
			(keepout
				(tracks not_allowed)
				(vias allowed)
				(pads allowed)
				(copperpour not_allowed)
				(footprints allowed)
			)
			(placement
				(enabled no)
				(sheetname "")
			)
			(fill
				(thermal_gap 0.5)
				(thermal_bridge_width 0.5)
				(island_removal_mode 0)
			)
			(polygon
				(pts
					(xy 271.985486 -73.00214) (xy 270.715486 -73.00214) (xy 270.715486 -72.24014) (xy 271.985486 -72.24014)
				)
			)
		)
	)
	(footprint ""
		(layer "B.Cu")
		(at 197.866 -97.282 90)
		(property "Reference" "C6N6"
			(at 0 0 90)
			(layer "B.SilkS")
			(hide yes)
			(effects
				(font
					(size 1.27 1.27)
				)
				(justify mirror)
			)
		)
		(property "Value" ""
			(at 0 0 90)
			(layer "B.Fab")
			(effects
				(font
					(size 1.27 1.27)
				)
				(justify mirror)
			)
		)
		(duplicate_pad_numbers_are_jumpers no)
		(fp_rect
			(start -0.7239 -0.2159)
			(end 0.7239 1.9939)
			(stroke
				(width 0)
				(type default)
			)
			(fill no)
			(layer "B.CrtYd")
		)
		(fp_line
			(start 0.7239 -0.2159)
			(end 0.7239 1.9939)
			(stroke
				(width 0.1)
				(type default)
			)
			(layer "B.Fab")
		)
		(fp_line
			(start -0.7239 -0.2159)
			(end 0.7239 -0.2159)
			(stroke
				(width 0.1)
				(type default)
			)
			(layer "B.Fab")
		)
		(fp_line
			(start 0.7239 1.9939)
			(end -0.7239 1.9939)
			(stroke
				(width 0.1)
				(type default)
			)
			(layer "B.Fab")
		)
		(fp_line
			(start -0.7239 1.9939)
			(end -0.7239 -0.2159)
			(stroke
				(width 0.1)
				(type default)
			)
			(layer "B.Fab")
		)
		(pad "1" smd rect
			(at 0 0 270)
			(size 1.27 1.016)
			(layers "B.Cu" "B.Mask" "B.Paste")
			(net "VR_FET_SW_P12V_STBY_PVCCIN_CPU0")
		)
		(pad "2" smd rect
			(at 0 1.778 270)
			(size 1.27 1.016)
			(layers "B.Cu" "B.Mask" "B.Paste")
			(net "GND")
		)
		(zone
			(layer "B.Cu")
			(hatch none 0.5)
			(connect_pads
				(clearance 0)
			)
			(min_thickness 0.25)
			(keepout
				(tracks not_allowed)
				(vias allowed)
				(pads allowed)
				(copperpour not_allowed)
				(footprints allowed)
			)
			(placement
				(enabled no)
				(sheetname "")
			)
			(fill
				(thermal_gap 0.5)
				(thermal_bridge_width 0.5)
				(island_removal_mode 0)
			)
			(polygon
				(pts
					(xy 198.374 -96.647) (xy 199.136 -96.647) (xy 199.136 -97.917) (xy 198.374 -97.917)
				)
			)
		)
	)
	(footprint ""
		(layer "B.Cu")
		(at 422.574974 -40.982646 180)
		(property "Reference" "C25W57"
			(at 0.8382 -0.67818 180)
			(unlocked yes)
			(layer "B.SilkS")
			(effects
				(font
					(size 0.4064 0.254)
					(thickness 0.1524)
				)
				(justify left mirror)
			)
		)
		(property "Value" ""
			(at 0 0 0)
			(layer "B.Fab")
			(effects
				(font
					(size 1.27 1.27)
				)
				(justify mirror)
			)
		)
		(duplicate_pad_numbers_are_jumpers no)
		(fp_poly
			(pts
				(xy -0.3048 -0.1016) (xy -0.3048 0.9906) (xy 0.3048 0.9906) (xy 0.3048 -0.1016)
			)
			(stroke
				(width 0)
				(type default)
			)
			(fill no)
			(layer "B.CrtYd")
		)
		(fp_line
			(start 0.3048 0.9906)
			(end -0.3048 0.9906)
			(stroke
				(width 0.1)
				(type default)
			)
			(layer "B.Fab")
		)
		(fp_line
			(start 0.3048 -0.1016)
			(end 0.3048 0.9906)
			(stroke
				(width 0.1)
				(type default)
			)
			(layer "B.Fab")
		)
		(fp_line
			(start -0.3048 0.9906)
			(end -0.3048 -0.1016)
			(stroke
				(width 0.1)
				(type default)
			)
			(layer "B.Fab")
		)
		(fp_line
			(start -0.3048 -0.1016)
			(end 0.3048 -0.1016)
			(stroke
				(width 0.1)
				(type default)
			)
			(layer "B.Fab")
		)
		(pad "1" smd rect
			(at 0 0)
			(size 0.508 0.508)
			(layers "B.Cu" "B.Mask" "B.Paste")
			(net "VCC_PA_3V3")
		)
		(pad "2" smd rect
			(at 0 0.889)
			(size 0.508 0.508)
			(layers "B.Cu" "B.Mask" "B.Paste")
			(net "GND")
		)
		(zone
			(layer "B.Cu")
			(hatch none 0.5)
			(connect_pads
				(clearance 0)
			)
			(min_thickness 0.25)
			(keepout
				(tracks not_allowed)
				(vias allowed)
				(pads allowed)
				(copperpour not_allowed)
				(footprints allowed)
			)
			(placement
				(enabled no)
				(sheetname "")
			)
			(fill
				(thermal_gap 0.5)
				(thermal_bridge_width 0.5)
				(island_removal_mode 0)
			)
			(polygon
				(pts
					(xy 422.320974 -41.617646) (xy 422.828974 -41.617646) (xy 422.828974 -41.236646) (xy 422.320974 -41.236646)
				)
			)
		)
		(zone
			(layer "B.Cu")
			(hatch none 0.5)
			(connect_pads
				(clearance 0)
			)
			(min_thickness 0.25)
			(keepout
				(tracks allowed)
				(vias not_allowed)
				(pads allowed)
				(copperpour not_allowed)
				(footprints allowed)
			)
			(placement
				(enabled no)
				(sheetname "")
			)
			(fill
				(thermal_gap 0.5)
				(thermal_bridge_width 0.5)
				(island_removal_mode 0)
			)
			(polygon
				(pts
					(xy 422.320974 -41.236646) (xy 422.828974 -41.236646) (xy 422.828974 -41.617646) (xy 422.320974 -41.617646)
				)
			)
		)
	)
	(footprint ""
		(layer "B.Cu")
		(at 88.392 -3.3528 90)
		(property "Reference" "C5G85"
			(at -1.14681 0.76708 180)
			(unlocked yes)
			(layer "B.SilkS")
			(effects
				(font
					(size 0.7874 0.5842)
					(thickness 0.1524)
				)
				(justify mirror)
			)
		)
		(property "Value" ""
			(at 0 0 90)
			(layer "B.Fab")
			(effects
				(font
					(size 1.27 1.27)
				)
				(justify mirror)
			)
		)
		(duplicate_pad_numbers_are_jumpers no)
		(fp_rect
			(start -0.4953 -0.2032)
			(end 0.4953 1.6002)
			(stroke
				(width 0)
				(type default)
			)
			(fill no)
			(layer "B.CrtYd")
		)
		(fp_line
			(start 0.4953 -0.2032)
			(end -0.4953 -0.2032)
			(stroke
				(width 0.1)
				(type default)
			)
			(layer "B.Fab")
		)
		(fp_line
			(start -0.4953 -0.2032)
			(end -0.4953 1.6002)
			(stroke
				(width 0.1)
				(type default)
			)
			(layer "B.Fab")
		)
		(fp_line
			(start 0.4953 1.6002)
			(end 0.4953 -0.2032)
			(stroke
				(width 0.1)
				(type default)
			)
			(layer "B.Fab")
		)
		(fp_line
			(start -0.4953 1.6002)
			(end 0.4953 1.6002)
			(stroke
				(width 0.1)
				(type default)
			)
			(layer "B.Fab")
		)
		(pad "1" smd rect
			(at 0 0 270)
			(size 0.762 0.889)
			(layers "B.Cu" "B.Mask" "B.Paste")
			(net "PVDDQ_GHJ")
		)
		(pad "2" smd rect
			(at 0 1.397 270)
			(size 0.762 0.889)
			(layers "B.Cu" "B.Mask" "B.Paste")
			(net "GND")
		)
		(zone
			(layer "B.Cu")
			(hatch none 0.5)
			(connect_pads
				(clearance 0)
			)
			(min_thickness 0.25)
			(keepout
				(tracks not_allowed)
				(vias allowed)
				(pads allowed)
				(copperpour not_allowed)
				(footprints allowed)
			)
			(placement
				(enabled no)
				(sheetname "")
			)
			(fill
				(thermal_gap 0.5)
				(thermal_bridge_width 0.5)
				(island_removal_mode 0)
			)
			(polygon
				(pts
					(xy 88.8365 -2.9718) (xy 89.3445 -2.9718) (xy 89.3445 -3.7338) (xy 88.8365 -3.7338)
				)
			)
		)
	)
	(footprint ""
		(layer "B.Cu")
		(at 457.533756 -21.494242 90)
		(property "Reference" "C9W6"
			(at 0.8382 -0.67818 90)
			(unlocked yes)
			(layer "B.SilkS")
			(effects
				(font
					(size 0.4064 0.254)
					(thickness 0.1524)
				)
				(justify left mirror)
			)
		)
		(property "Value" ""
			(at 0 0 90)
			(layer "B.Fab")
			(effects
				(font
					(size 1.27 1.27)
				)
				(justify mirror)
			)
		)
		(duplicate_pad_numbers_are_jumpers no)
		(fp_poly
			(pts
				(xy -0.3048 -0.1016) (xy -0.3048 0.9906) (xy 0.3048 0.9906) (xy 0.3048 -0.1016)
			)
			(stroke
				(width 0)
				(type default)
			)
			(fill no)
			(layer "B.CrtYd")
		)
		(fp_line
			(start 0.3048 -0.1016)
			(end 0.3048 0.9906)
			(stroke
				(width 0.1)
				(type default)
			)
			(layer "B.Fab")
		)
		(fp_line
			(start -0.3048 -0.1016)
			(end 0.3048 -0.1016)
			(stroke
				(width 0.1)
				(type default)
			)
			(layer "B.Fab")
		)
		(fp_line
			(start 0.3048 0.9906)
			(end -0.3048 0.9906)
			(stroke
				(width 0.1)
				(type default)
			)
			(layer "B.Fab")
		)
		(fp_line
			(start -0.3048 0.9906)
			(end -0.3048 -0.1016)
			(stroke
				(width 0.1)
				(type default)
			)
			(layer "B.Fab")
		)
		(pad "1" smd rect
			(at 0 0 270)
			(size 0.508 0.508)
			(layers "B.Cu" "B.Mask" "B.Paste")
			(net "PWRGD_P3V3_STBY")
		)
		(pad "2" smd rect
			(at 0 0.889 270)
			(size 0.508 0.508)
			(layers "B.Cu" "B.Mask" "B.Paste")
			(net "GND")
		)
		(zone
			(layer "B.Cu")
			(hatch none 0.5)
			(connect_pads
				(clearance 0)
			)
			(min_thickness 0.25)
			(keepout
				(tracks allowed)
				(vias not_allowed)
				(pads allowed)
				(copperpour not_allowed)
				(footprints allowed)
			)
			(placement
				(enabled no)
				(sheetname "")
			)
			(fill
				(thermal_gap 0.5)
				(thermal_bridge_width 0.5)
				(island_removal_mode 0)
			)
			(polygon
				(pts
					(xy 457.787756 -21.748242) (xy 457.787756 -21.240242) (xy 458.168756 -21.240242) (xy 458.168756 -21.748242)
				)
			)
		)
		(zone
			(layer "B.Cu")
			(hatch none 0.5)
			(connect_pads
				(clearance 0)
			)
			(min_thickness 0.25)
			(keepout
				(tracks not_allowed)
				(vias allowed)
				(pads allowed)
				(copperpour not_allowed)
				(footprints allowed)
			)
			(placement
				(enabled no)
				(sheetname "")
			)
			(fill
				(thermal_gap 0.5)
				(thermal_bridge_width 0.5)
				(island_removal_mode 0)
			)
			(polygon
				(pts
					(xy 458.168756 -21.748242) (xy 458.168756 -21.240242) (xy 457.787756 -21.240242) (xy 457.787756 -21.748242)
				)
			)
		)
	)
	(footprint ""
		(layer "B.Cu")
		(at 63.2968 -88.8492 90)
		(property "Reference" "R8N5"
			(at 0 0 90)
			(layer "B.SilkS")
			(hide yes)
			(effects
				(font
					(size 1.27 1.27)
				)
				(justify mirror)
			)
		)
		(property "Value" ""
			(at 0 0 90)
			(layer "B.Fab")
			(effects
				(font
					(size 1.27 1.27)
				)
				(justify mirror)
			)
		)
		(duplicate_pad_numbers_are_jumpers no)
		(fp_poly
			(pts
				(xy 0.2794 -0.1016) (xy -0.2794 -0.1016) (xy -0.2794 0.9906) (xy 0.2794 0.9906)
			)
			(stroke
				(width 0)
				(type default)
			)
			(fill no)
			(layer "B.CrtYd")
		)
		(fp_line
			(start 0.2794 -0.1016)
			(end 0.2794 0.9906)
			(stroke
				(width 0.1)
				(type default)
			)
			(layer "B.Fab")
		)
		(fp_line
			(start -0.2794 -0.1016)
			(end 0.2794 -0.1016)
			(stroke
				(width 0.1)
				(type default)
			)
			(layer "B.Fab")
		)
		(fp_line
			(start 0.2794 0.9906)
			(end -0.2794 0.9906)
			(stroke
				(width 0.1)
				(type default)
			)
			(layer "B.Fab")
		)
		(fp_line
			(start -0.2794 0.9906)
			(end -0.2794 -0.1016)
			(stroke
				(width 0.1)
				(type default)
			)
			(layer "B.Fab")
		)
		(pad "1" smd rect
			(at 0 0 270)
			(size 0.508 0.508)
			(layers "B.Cu" "B.Mask" "B.Paste")
			(net "P3V3_STBY")
		)
		(pad "2" smd rect
			(at 0 0.889 270)
			(size 0.508 0.508)
			(layers "B.Cu" "B.Mask" "B.Paste")
			(net "FM_CPU1_PKGID1")
		)
		(zone
			(layer "B.Cu")
			(hatch none 0.5)
			(connect_pads
				(clearance 0)
			)
			(min_thickness 0.25)
			(keepout
				(tracks allowed)
				(vias not_allowed)
				(pads allowed)
				(copperpour not_allowed)
				(footprints allowed)
			)
			(placement
				(enabled no)
				(sheetname "")
			)
			(fill
				(thermal_gap 0.5)
				(thermal_bridge_width 0.5)
				(island_removal_mode 0)
			)
			(polygon
				(pts
					(xy 63.5508 -89.1032) (xy 63.5508 -88.5952) (xy 63.9318 -88.5952) (xy 63.9318 -89.1032)
				)
			)
		)
		(zone
			(layer "B.Cu")
			(hatch none 0.5)
			(connect_pads
				(clearance 0)
			)
			(min_thickness 0.25)
			(keepout
				(tracks not_allowed)
				(vias allowed)
				(pads allowed)
				(copperpour not_allowed)
				(footprints allowed)
			)
			(placement
				(enabled no)
				(sheetname "")
			)
			(fill
				(thermal_gap 0.5)
				(thermal_bridge_width 0.5)
				(island_removal_mode 0)
			)
			(polygon
				(pts
					(xy 63.9318 -89.1032) (xy 63.9318 -88.5952) (xy 63.5508 -88.5952) (xy 63.5508 -89.1032)
				)
			)
		)
	)
	(footprint ""
		(layer "B.Cu")
		(at 198.615808 -53.127402 90)
		(property "Reference" "C4E6"
			(at 0 0 90)
			(layer "B.SilkS")
			(hide yes)
			(effects
				(font
					(size 1.27 1.27)
				)
				(justify mirror)
			)
		)
		(property "Value" "*"
			(at -1.1811 -2.8194 90)
			(unlocked yes)
			(layer "B.Fab")
			(hide yes)
			(effects
				(font
					(size 1.27 1.016)
					(thickness 0.1524)
				)
				(justify mirror)
			)
		)
		(property "Device Type" "SC1U10V2KX-4-GP_SMD-BCG6-SC1U1A"
			(at -1.1811 -4.3434 90)
			(unlocked yes)
			(layer "B.Fab")
			(hide yes)
			(effects
				(font
					(size 1.27 1.016)
					(thickness 0.1524)
				)
				(justify mirror)
			)
		)
		(duplicate_pad_numbers_are_jumpers no)
		(fp_rect
			(start 0.4318 0.9525)
			(end -0.4318 -0.9525)
			(stroke
				(width 0)
				(type default)
			)
			(fill no)
			(layer "B.CrtYd")
		)
		(fp_rect
			(start 0.4318 0.9525)
			(end -0.4318 -0.9525)
			(stroke
				(width 0)
				(type default)
			)
			(fill no)
			(layer "B.Fab")
		)
		(pad "1" smd custom
			(at 0 -0.4445 270)
			(size 0.1524 0.1524)
			(layers "B.Cu" "B.Mask" "B.Paste")
			(net "P5V_STBY")
			(options
				(clearance outline)
				(anchor circle)
			)
			(primitives
				(gr_poly
					(pts
						(arc
							(start 0.3048 0.2032)
							(mid 0.275042 0.275042)
							(end 0.2032 0.3048)
						)
						(arc
							(start -0.2032 0.3048)
							(mid -0.275042 0.275042)
							(end -0.3048 0.2032)
						)
						(arc
							(start -0.3048 -0.2032)
							(mid -0.275042 -0.275042)
							(end -0.2032 -0.3048)
						)
						(arc
							(start 0.2032 -0.3048)
							(mid 0.275042 -0.275042)
							(end 0.3048 -0.2032)
						)
					)
					(width 0)
					(fill yes)
				)
			)
		)
		(pad "2" smd custom
			(at 0 0.4445 270)
			(size 0.1524 0.1524)
			(layers "B.Cu" "B.Mask" "B.Paste")
			(net "GND")
			(options
				(clearance outline)
				(anchor circle)
			)
			(primitives
				(gr_poly
					(pts
						(arc
							(start 0.3048 0.2032)
							(mid 0.275042 0.275042)
							(end 0.2032 0.3048)
						)
						(arc
							(start -0.2032 0.3048)
							(mid -0.275042 0.275042)
							(end -0.3048 0.2032)
						)
						(arc
							(start -0.3048 -0.2032)
							(mid -0.275042 -0.275042)
							(end -0.2032 -0.3048)
						)
						(arc
							(start 0.2032 -0.3048)
							(mid 0.275042 -0.275042)
							(end 0.3048 -0.2032)
						)
					)
					(width 0)
					(fill yes)
				)
			)
		)
	)
	(footprint ""
		(layer "B.Cu")
		(at 443.405006 -41.648126 180)
		(property "Reference" "R25W16"
			(at 0 0 0)
			(layer "B.SilkS")
			(hide yes)
			(effects
				(font
					(size 1.27 1.27)
				)
				(justify mirror)
			)
		)
		(property "Value" "*"
			(at -0.064008 -4.108196 180)
			(unlocked yes)
			(layer "B.Fab")
			(hide yes)
			(effects
				(font
					(size 1.27 1.016)
					(thickness 0.1524)
				)
				(justify mirror)
			)
		)
		(property "Device Type" "120R2F-GP_RCL_GP-120R2F-GP,64.A"
			(at -0.064008 -5.632196 180)
			(unlocked yes)
			(layer "B.Fab")
			(hide yes)
			(effects
				(font
					(size 1.27 1.016)
					(thickness 0.1524)
				)
				(justify mirror)
			)
		)
		(duplicate_pad_numbers_are_jumpers no)
		(fp_line
			(start 0.508 -0.9398)
			(end 0.508 0.9398)
			(stroke
				(width 0.1524)
				(type default)
			)
			(layer "B.SilkS")
		)
		(fp_line
			(start -0.508 -0.9398)
			(end 0.508 -0.9398)
			(stroke
				(width 0.1524)
				(type default)
			)
			(layer "B.SilkS")
		)
		(fp_rect
			(start 0.508 0.9398)
			(end -0.508 -0.9398)
			(stroke
				(width 0)
				(type default)
			)
			(fill no)
			(layer "B.CrtYd")
		)
		(fp_rect
			(start 0.508 0.9398)
			(end -0.508 -0.9398)
			(stroke
				(width 0)
				(type default)
			)
			(fill no)
			(layer "B.Fab")
		)
		(pad "1" smd custom
			(at 0 -0.4445)
			(size 0.1397 0.1397)
			(layers "B.Cu" "B.Mask" "B.Paste")
			(net "GND")
			(options
				(clearance outline)
				(anchor circle)
			)
			(primitives
				(gr_poly
					(pts
						(arc
							(start -0.1778 0.2794)
							(mid -0.249642 0.249642)
							(end -0.2794 0.1778)
						)
						(arc
							(start -0.2794 -0.1778)
							(mid -0.249642 -0.249642)
							(end -0.1778 -0.2794)
						)
						(arc
							(start 0.1778 -0.2794)
							(mid 0.249642 -0.249642)
							(end 0.2794 -0.1778)
						)
						(arc
							(start 0.2794 0.1778)
							(mid 0.249642 0.249642)
							(end 0.1778 0.2794)
						)
					)
					(width 0)
					(fill yes)
				)
			)
		)
		(pad "2" smd custom
			(at 0 0.4445)
			(size 0.1397 0.1397)
			(layers "B.Cu" "B.Mask" "B.Paste")
			(net "BMC_M_A4")
			(options
				(clearance outline)
				(anchor circle)
			)
			(primitives
				(gr_poly
					(pts
						(arc
							(start -0.1778 0.2794)
							(mid -0.249642 0.249642)
							(end -0.2794 0.1778)
						)
						(arc
							(start -0.2794 -0.1778)
							(mid -0.249642 -0.249642)
							(end -0.1778 -0.2794)
						)
						(arc
							(start 0.1778 -0.2794)
							(mid 0.249642 -0.249642)
							(end 0.2794 -0.1778)
						)
						(arc
							(start 0.2794 0.1778)
							(mid 0.249642 0.249642)
							(end 0.1778 0.2794)
						)
					)
					(width 0)
					(fill yes)
				)
			)
		)
	)
	(footprint ""
		(layer "B.Cu")
		(at 479.16211 4.716272 180)
		(property "Reference" "R9G1"
			(at 0 0 0)
			(layer "B.SilkS")
			(hide yes)
			(effects
				(font
					(size 1.27 1.27)
				)
				(justify mirror)
			)
		)
		(property "Value" ""
			(at 0 0 0)
			(layer "B.Fab")
			(effects
				(font
					(size 1.27 1.27)
				)
				(justify mirror)
			)
		)
		(duplicate_pad_numbers_are_jumpers no)
		(fp_poly
			(pts
				(xy 0.2794 -0.1016) (xy -0.2794 -0.1016) (xy -0.2794 0.9906) (xy 0.2794 0.9906)
			)
			(stroke
				(width 0)
				(type default)
			)
			(fill no)
			(layer "B.CrtYd")
		)
		(fp_line
			(start 0.2794 0.9906)
			(end -0.2794 0.9906)
			(stroke
				(width 0.1)
				(type default)
			)
			(layer "B.Fab")
		)
		(fp_line
			(start 0.2794 -0.1016)
			(end 0.2794 0.9906)
			(stroke
				(width 0.1)
				(type default)
			)
			(layer "B.Fab")
		)
		(fp_line
			(start -0.2794 0.9906)
			(end -0.2794 -0.1016)
			(stroke
				(width 0.1)
				(type default)
			)
			(layer "B.Fab")
		)
		(fp_line
			(start -0.2794 -0.1016)
			(end 0.2794 -0.1016)
			(stroke
				(width 0.1)
				(type default)
			)
			(layer "B.Fab")
		)
		(pad "1" smd rect
			(at 0 0)
			(size 0.508 0.508)
			(layers "B.Cu" "B.Mask" "B.Paste")
			(net "LED_LAN_1_N")
		)
		(pad "2" smd rect
			(at 0 0.889)
			(size 0.508 0.508)
			(layers "B.Cu" "B.Mask" "B.Paste")
			(net "LED_LAN_1_R_N")
		)
		(zone
			(layer "B.Cu")
			(hatch none 0.5)
			(connect_pads
				(clearance 0)
			)
			(min_thickness 0.25)
			(keepout
				(tracks not_allowed)
				(vias allowed)
				(pads allowed)
				(copperpour not_allowed)
				(footprints allowed)
			)
			(placement
				(enabled no)
				(sheetname "")
			)
			(fill
				(thermal_gap 0.5)
				(thermal_bridge_width 0.5)
				(island_removal_mode 0)
			)
			(polygon
				(pts
					(xy 478.90811 4.081272) (xy 479.41611 4.081272) (xy 479.41611 4.462272) (xy 478.90811 4.462272)
				)
			)
		)
		(zone
			(layer "B.Cu")
			(hatch none 0.5)
			(connect_pads
				(clearance 0)
			)
			(min_thickness 0.25)
			(keepout
				(tracks allowed)
				(vias not_allowed)
				(pads allowed)
				(copperpour not_allowed)
				(footprints allowed)
			)
			(placement
				(enabled no)
				(sheetname "")
			)
			(fill
				(thermal_gap 0.5)
				(thermal_bridge_width 0.5)
				(island_removal_mode 0)
			)
			(polygon
				(pts
					(xy 478.90811 4.462272) (xy 479.41611 4.462272) (xy 479.41611 4.081272) (xy 478.90811 4.081272)
				)
			)
		)
	)
	(footprint ""
		(layer "B.Cu")
		(at 179.39258 -60.99683 180)
		(property "Reference" "C22W20"
			(at 0 0 0)
			(layer "B.SilkS")
			(hide yes)
			(effects
				(font
					(size 1.27 1.27)
				)
				(justify mirror)
			)
		)
		(property "Value" "*"
			(at 0.0762 -6.2357 180)
			(unlocked yes)
			(layer "B.Fab")
			(hide yes)
			(effects
				(font
					(size 1.27 1.016)
					(thickness 0.1524)
				)
				(justify mirror)
			)
		)
		(property "Device Type" "SC22U16V5MX-4-GP_SMD-BCG5-SC22A"
			(at 0.0762 -8.2677 180)
			(unlocked yes)
			(layer "B.Fab")
			(hide yes)
			(effects
				(font
					(size 1.27 1.016)
					(thickness 0.1524)
				)
				(justify mirror)
			)
		)
		(duplicate_pad_numbers_are_jumpers no)
		(fp_line
			(start -0.635 0)
			(end 0.635 0)
			(stroke
				(width 0.508)
				(type default)
			)
			(layer "B.SilkS")
		)
		(fp_rect
			(start 0.9652 1.778)
			(end -0.9652 -1.778)
			(stroke
				(width 0)
				(type default)
			)
			(fill no)
			(layer "B.CrtYd")
		)
		(fp_poly
			(pts
				(xy 0.9652 -1.778) (xy -0.9652 -1.778) (xy -0.9652 1.778) (xy 0.9652 1.778)
			)
			(stroke
				(width 0)
				(type default)
			)
			(fill no)
			(layer "B.Fab")
		)
		(pad "1" smd rect
			(at 0 -0.9652)
			(size 1.397 1.143)
			(layers "B.Cu" "B.Mask" "B.Paste")
			(net "VR_FET_SW_P12V_STBY_PVCCIN_CPU0")
		)
		(pad "2" smd rect
			(at 0 0.9652)
			(size 1.397 1.143)
			(layers "B.Cu" "B.Mask" "B.Paste")
			(net "GND")
		)
	)
	(footprint ""
		(layer "B.Cu")
		(at 94.308168 -3.321812 90)
		(property "Reference" "C5G117"
			(at -1.64973 0.78994 180)
			(unlocked yes)
			(layer "B.SilkS")
			(effects
				(font
					(size 0.7874 0.5842)
					(thickness 0.1524)
				)
				(justify mirror)
			)
		)
		(property "Value" ""
			(at 0 0 90)
			(layer "B.Fab")
			(effects
				(font
					(size 1.27 1.27)
				)
				(justify mirror)
			)
		)
		(duplicate_pad_numbers_are_jumpers no)
		(fp_rect
			(start -0.7239 -0.2159)
			(end 0.7239 1.9939)
			(stroke
				(width 0)
				(type default)
			)
			(fill no)
			(layer "B.CrtYd")
		)
		(fp_line
			(start 0.7239 -0.2159)
			(end 0.7239 1.9939)
			(stroke
				(width 0.1)
				(type default)
			)
			(layer "B.Fab")
		)
		(fp_line
			(start -0.7239 -0.2159)
			(end 0.7239 -0.2159)
			(stroke
				(width 0.1)
				(type default)
			)
			(layer "B.Fab")
		)
		(fp_line
			(start 0.7239 1.9939)
			(end -0.7239 1.9939)
			(stroke
				(width 0.1)
				(type default)
			)
			(layer "B.Fab")
		)
		(fp_line
			(start -0.7239 1.9939)
			(end -0.7239 -0.2159)
			(stroke
				(width 0.1)
				(type default)
			)
			(layer "B.Fab")
		)
		(pad "1" smd rect
			(at 0 0 270)
			(size 1.27 1.016)
			(layers "B.Cu" "B.Mask" "B.Paste")
			(net "PVDDQ_GHJ")
		)
		(pad "2" smd rect
			(at 0 1.778 270)
			(size 1.27 1.016)
			(layers "B.Cu" "B.Mask" "B.Paste")
			(net "GND")
		)
		(zone
			(layer "B.Cu")
			(hatch none 0.5)
			(connect_pads
				(clearance 0)
			)
			(min_thickness 0.25)
			(keepout
				(tracks not_allowed)
				(vias allowed)
				(pads allowed)
				(copperpour not_allowed)
				(footprints allowed)
			)
			(placement
				(enabled no)
				(sheetname "")
			)
			(fill
				(thermal_gap 0.5)
				(thermal_bridge_width 0.5)
				(island_removal_mode 0)
			)
			(polygon
				(pts
					(xy 94.816168 -2.686812) (xy 95.578168 -2.686812) (xy 95.578168 -3.956812) (xy 94.816168 -3.956812)
				)
			)
		)
	)
	(footprint ""
		(layer "B.Cu")
		(at 488.09148 -29.3116)
		(property "Reference" "R1R7"
			(at 0.8382 -0.67818 0)
			(unlocked yes)
			(layer "B.SilkS")
			(effects
				(font
					(size 0.4064 0.254)
					(thickness 0.1524)
				)
				(justify left mirror)
			)
		)
		(property "Value" ""
			(at 0 0 0)
			(layer "B.Fab")
			(effects
				(font
					(size 1.27 1.27)
				)
				(justify mirror)
			)
		)
		(duplicate_pad_numbers_are_jumpers no)
		(fp_poly
			(pts
				(xy 0.2794 -0.1016) (xy -0.2794 -0.1016) (xy -0.2794 0.9906) (xy 0.2794 0.9906)
			)
			(stroke
				(width 0)
				(type default)
			)
			(fill no)
			(layer "B.CrtYd")
		)
		(fp_line
			(start -0.2794 -0.1016)
			(end 0.2794 -0.1016)
			(stroke
				(width 0.1)
				(type default)
			)
			(layer "B.Fab")
		)
		(fp_line
			(start -0.2794 0.9906)
			(end -0.2794 -0.1016)
			(stroke
				(width 0.1)
				(type default)
			)
			(layer "B.Fab")
		)
		(fp_line
			(start 0.2794 -0.1016)
			(end 0.2794 0.9906)
			(stroke
				(width 0.1)
				(type default)
			)
			(layer "B.Fab")
		)
		(fp_line
			(start 0.2794 0.9906)
			(end -0.2794 0.9906)
			(stroke
				(width 0.1)
				(type default)
			)
			(layer "B.Fab")
		)
		(pad "1" smd rect
			(at 0 0 180)
			(size 0.508 0.508)
			(layers "B.Cu" "B.Mask" "B.Paste")
			(net "P3V3_STBY")
		)
		(pad "2" smd rect
			(at 0 0.889 180)
			(size 0.508 0.508)
			(layers "B.Cu" "B.Mask" "B.Paste")
			(net "SPI_NIC_MOSI")
		)
		(zone
			(layer "B.Cu")
			(hatch none 0.5)
			(connect_pads
				(clearance 0)
			)
			(min_thickness 0.25)
			(keepout
				(tracks allowed)
				(vias not_allowed)
				(pads allowed)
				(copperpour not_allowed)
				(footprints allowed)
			)
			(placement
				(enabled no)
				(sheetname "")
			)
			(fill
				(thermal_gap 0.5)
				(thermal_bridge_width 0.5)
				(island_removal_mode 0)
			)
			(polygon
				(pts
					(xy 488.34548 -29.0576) (xy 487.83748 -29.0576) (xy 487.83748 -28.6766) (xy 488.34548 -28.6766)
				)
			)
		)
		(zone
			(layer "B.Cu")
			(hatch none 0.5)
			(connect_pads
				(clearance 0)
			)
			(min_thickness 0.25)
			(keepout
				(tracks not_allowed)
				(vias allowed)
				(pads allowed)
				(copperpour not_allowed)
				(footprints allowed)
			)
			(placement
				(enabled no)
				(sheetname "")
			)
			(fill
				(thermal_gap 0.5)
				(thermal_bridge_width 0.5)
				(island_removal_mode 0)
			)
			(polygon
				(pts
					(xy 488.34548 -28.6766) (xy 487.83748 -28.6766) (xy 487.83748 -29.0576) (xy 488.34548 -29.0576)
				)
			)
		)
	)
	(footprint ""
		(layer "B.Cu")
		(at 197.848728 -82.842862 90)
		(property "Reference" "C6P13"
			(at 0 0 90)
			(layer "B.SilkS")
			(hide yes)
			(effects
				(font
					(size 1.27 1.27)
				)
				(justify mirror)
			)
		)
		(property "Value" ""
			(at 0 0 90)
			(layer "B.Fab")
			(effects
				(font
					(size 1.27 1.27)
				)
				(justify mirror)
			)
		)
		(duplicate_pad_numbers_are_jumpers no)
		(fp_rect
			(start 0.7239 1.9939)
			(end -0.7239 -0.2159)
			(stroke
				(width 0)
				(type default)
			)
			(fill no)
			(layer "B.CrtYd")
		)
		(fp_line
			(start 0.7239 -0.2159)
			(end 0.7239 1.9939)
			(stroke
				(width 0.1)
				(type default)
			)
			(layer "B.Fab")
		)
		(fp_line
			(start -0.7239 -0.2159)
			(end 0.7239 -0.2159)
			(stroke
				(width 0.1)
				(type default)
			)
			(layer "B.Fab")
		)
		(fp_line
			(start 0.7239 1.9939)
			(end -0.7239 1.9939)
			(stroke
				(width 0.1)
				(type default)
			)
			(layer "B.Fab")
		)
		(fp_line
			(start -0.7239 1.9939)
			(end -0.7239 -0.2159)
			(stroke
				(width 0.1)
				(type default)
			)
			(layer "B.Fab")
		)
		(pad "1" smd rect
			(at 0 0 270)
			(size 1.27 1.016)
			(layers "B.Cu" "B.Mask" "B.Paste")
			(net "VR_FET_SW_P12V_STBY_PVCCIN_CPU0")
		)
		(pad "2" smd rect
			(at 0 1.778 270)
			(size 1.27 1.016)
			(layers "B.Cu" "B.Mask" "B.Paste")
			(net "GND")
		)
		(zone
			(layer "B.Cu")
			(hatch none 0.5)
			(connect_pads
				(clearance 0)
			)
			(min_thickness 0.25)
			(keepout
				(tracks not_allowed)
				(vias allowed)
				(pads allowed)
				(copperpour not_allowed)
				(footprints allowed)
			)
			(placement
				(enabled no)
				(sheetname "")
			)
			(fill
				(thermal_gap 0.5)
				(thermal_bridge_width 0.5)
				(island_removal_mode 0)
			)
			(polygon
				(pts
					(xy 199.118728 -83.477862) (xy 198.356728 -83.477862) (xy 198.356728 -82.207862) (xy 199.118728 -82.207862)
				)
			)
		)
	)
	(footprint ""
		(layer "B.Cu")
		(at 400.1262 -102.8319)
		(property "Reference" "C7D2"
			(at 0 0 0)
			(layer "B.SilkS")
			(hide yes)
			(effects
				(font
					(size 1.27 1.27)
				)
				(justify mirror)
			)
		)
		(property "Value" ""
			(at 0 0 0)
			(layer "B.Fab")
			(effects
				(font
					(size 1.27 1.27)
				)
				(justify mirror)
			)
		)
		(duplicate_pad_numbers_are_jumpers no)
		(fp_poly
			(pts
				(xy 0.4953 -0.2032) (xy -0.4953 -0.2032) (xy -0.4953 1.6002) (xy 0.4953 1.6002)
			)
			(stroke
				(width 0)
				(type default)
			)
			(fill no)
			(layer "B.CrtYd")
		)
		(fp_line
			(start -0.4953 -0.2032)
			(end -0.4953 1.6002)
			(stroke
				(width 0.1)
				(type default)
			)
			(layer "B.Fab")
		)
		(fp_line
			(start -0.4953 1.6002)
			(end 0.4953 1.6002)
			(stroke
				(width 0.1)
				(type default)
			)
			(layer "B.Fab")
		)
		(fp_line
			(start 0.4953 -0.2032)
			(end -0.4953 -0.2032)
			(stroke
				(width 0.1)
				(type default)
			)
			(layer "B.Fab")
		)
		(fp_line
			(start 0.4953 1.6002)
			(end 0.4953 -0.2032)
			(stroke
				(width 0.1)
				(type default)
			)
			(layer "B.Fab")
		)
		(pad "1" smd rect
			(at 0 0 180)
			(size 0.762 0.889)
			(layers "B.Cu" "B.Mask" "B.Paste")
			(net "P3V3_STBY")
		)
		(pad "2" smd rect
			(at 0 1.397 180)
			(size 0.762 0.889)
			(layers "B.Cu" "B.Mask" "B.Paste")
			(net "GND")
		)
		(zone
			(layer "B.Cu")
			(hatch none 0.5)
			(connect_pads
				(clearance 0)
			)
			(min_thickness 0.25)
			(keepout
				(tracks not_allowed)
				(vias allowed)
				(pads allowed)
				(copperpour not_allowed)
				(footprints allowed)
			)
			(placement
				(enabled no)
				(sheetname "")
			)
			(fill
				(thermal_gap 0.5)
				(thermal_bridge_width 0.5)
				(island_removal_mode 0)
			)
			(polygon
				(pts
					(xy 400.5072 -102.3874) (xy 399.7452 -102.3874) (xy 399.7452 -101.8794) (xy 400.5072 -101.8794)
				)
			)
		)
	)
	(footprint ""
		(layer "B.Cu")
		(at 382.3335 -44.196 90)
		(property "Reference" "R7E7"
			(at 0 0 90)
			(layer "B.SilkS")
			(hide yes)
			(effects
				(font
					(size 1.27 1.27)
				)
				(justify mirror)
			)
		)
		(property "Value" ""
			(at 0 0 90)
			(layer "B.Fab")
			(effects
				(font
					(size 1.27 1.27)
				)
				(justify mirror)
			)
		)
		(duplicate_pad_numbers_are_jumpers no)
		(fp_poly
			(pts
				(xy 0.2794 -0.1016) (xy -0.2794 -0.1016) (xy -0.2794 0.9906) (xy 0.2794 0.9906)
			)
			(stroke
				(width 0)
				(type default)
			)
			(fill no)
			(layer "B.CrtYd")
		)
		(fp_line
			(start 0.2794 -0.1016)
			(end 0.2794 0.9906)
			(stroke
				(width 0.1)
				(type default)
			)
			(layer "B.Fab")
		)
		(fp_line
			(start -0.2794 -0.1016)
			(end 0.2794 -0.1016)
			(stroke
				(width 0.1)
				(type default)
			)
			(layer "B.Fab")
		)
		(fp_line
			(start 0.2794 0.9906)
			(end -0.2794 0.9906)
			(stroke
				(width 0.1)
				(type default)
			)
			(layer "B.Fab")
		)
		(fp_line
			(start -0.2794 0.9906)
			(end -0.2794 -0.1016)
			(stroke
				(width 0.1)
				(type default)
			)
			(layer "B.Fab")
		)
		(pad "1" smd rect
			(at 0 0 270)
			(size 0.508 0.508)
			(layers "B.Cu" "B.Mask" "B.Paste")
			(net "P3V3")
		)
		(pad "2" smd rect
			(at 0 0.889 270)
			(size 0.508 0.508)
			(layers "B.Cu" "B.Mask" "B.Paste")
			(net "FM_SYS_THROTTLE_LVC3")
		)
		(zone
			(layer "B.Cu")
			(hatch none 0.5)
			(connect_pads
				(clearance 0)
			)
			(min_thickness 0.25)
			(keepout
				(tracks allowed)
				(vias not_allowed)
				(pads allowed)
				(copperpour not_allowed)
				(footprints allowed)
			)
			(placement
				(enabled no)
				(sheetname "")
			)
			(fill
				(thermal_gap 0.5)
				(thermal_bridge_width 0.5)
				(island_removal_mode 0)
			)
			(polygon
				(pts
					(xy 382.5875 -44.45) (xy 382.5875 -43.942) (xy 382.9685 -43.942) (xy 382.9685 -44.45)
				)
			)
		)
		(zone
			(layer "B.Cu")
			(hatch none 0.5)
			(connect_pads
				(clearance 0)
			)
			(min_thickness 0.25)
			(keepout
				(tracks not_allowed)
				(vias allowed)
				(pads allowed)
				(copperpour not_allowed)
				(footprints allowed)
			)
			(placement
				(enabled no)
				(sheetname "")
			)
			(fill
				(thermal_gap 0.5)
				(thermal_bridge_width 0.5)
				(island_removal_mode 0)
			)
			(polygon
				(pts
					(xy 382.9685 -44.45) (xy 382.9685 -43.942) (xy 382.5875 -43.942) (xy 382.5875 -44.45)
				)
			)
		)
	)
	(footprint ""
		(layer "B.Cu")
		(at 79.499968 -27.813 -90)
		(property "Reference" "C8T1"
			(at 0 0 90)
			(layer "B.SilkS")
			(hide yes)
			(effects
				(font
					(size 1.27 1.27)
				)
				(justify mirror)
			)
		)
		(property "Value" ""
			(at 0 0 90)
			(layer "B.Fab")
			(effects
				(font
					(size 1.27 1.27)
				)
				(justify mirror)
			)
		)
		(duplicate_pad_numbers_are_jumpers no)
		(fp_rect
			(start 0.500126 1.598422)
			(end -0.500126 -0.201422)
			(stroke
				(width 0)
				(type default)
			)
			(fill no)
			(layer "B.CrtYd")
		)
		(fp_line
			(start -0.500126 1.598422)
			(end 0.500126 1.598422)
			(stroke
				(width 0.1)
				(type default)
			)
			(layer "B.Fab")
		)
		(fp_line
			(start 0.500126 1.598422)
			(end 0.500126 -0.201422)
			(stroke
				(width 0.1)
				(type default)
			)
			(layer "B.Fab")
		)
		(fp_line
			(start -0.500126 -0.201422)
			(end -0.500126 1.598422)
			(stroke
				(width 0.1)
				(type default)
			)
			(layer "B.Fab")
		)
		(fp_line
			(start 0.500126 -0.201422)
			(end -0.500126 -0.201422)
			(stroke
				(width 0.1)
				(type default)
			)
			(layer "B.Fab")
		)
		(pad "1" smd rect
			(at 0 0 180)
			(size 0.889 0.9906)
			(layers "B.Cu" "B.Mask" "B.Paste")
			(net "PVDDQ_GHJ")
		)
		(pad "2" smd rect
			(at 0 1.397 180)
			(size 0.889 0.9906)
			(layers "B.Cu" "B.Mask" "B.Paste")
			(net "GND")
		)
		(zone
			(layer "B.Cu")
			(hatch none 0.5)
			(connect_pads
				(clearance 0)
			)
			(min_thickness 0.25)
			(keepout
				(tracks allowed)
				(vias not_allowed)
				(pads allowed)
				(copperpour not_allowed)
				(footprints allowed)
			)
			(placement
				(enabled no)
				(sheetname "")
			)
			(fill
				(thermal_gap 0.5)
				(thermal_bridge_width 0.5)
				(island_removal_mode 0)
			)
			(polygon
				(pts
					(xy 78.547468 -27.3177) (xy 79.055468 -27.3177) (xy 79.055468 -28.3083) (xy 78.547468 -28.3083)
				)
			)
		)
		(zone
			(layer "B.Cu")
			(hatch none 0.5)
			(connect_pads
				(clearance 0)
			)
			(min_thickness 0.25)
			(keepout
				(tracks not_allowed)
				(vias allowed)
				(pads allowed)
				(copperpour not_allowed)
				(footprints allowed)
			)
			(placement
				(enabled no)
				(sheetname "")
			)
			(fill
				(thermal_gap 0.5)
				(thermal_bridge_width 0.5)
				(island_removal_mode 0)
			)
			(polygon
				(pts
					(xy 78.547468 -27.3177) (xy 79.055468 -27.3177) (xy 79.055468 -28.3083) (xy 78.547468 -28.3083)
				)
			)
		)
	)
	(footprint ""
		(layer "B.Cu")
		(at 214.503 -86.4235)
		(property "Reference" "C6P3"
			(at 0 0 0)
			(layer "B.SilkS")
			(hide yes)
			(effects
				(font
					(size 1.27 1.27)
				)
				(justify mirror)
			)
		)
		(property "Value" ""
			(at 0 0 0)
			(layer "B.Fab")
			(effects
				(font
					(size 1.27 1.27)
				)
				(justify mirror)
			)
		)
		(duplicate_pad_numbers_are_jumpers no)
		(fp_poly
			(pts
				(xy 0.4953 -0.2032) (xy -0.4953 -0.2032) (xy -0.4953 1.6002) (xy 0.4953 1.6002)
			)
			(stroke
				(width 0)
				(type default)
			)
			(fill no)
			(layer "B.CrtYd")
		)
		(fp_line
			(start -0.4953 -0.2032)
			(end -0.4953 1.6002)
			(stroke
				(width 0.1)
				(type default)
			)
			(layer "B.Fab")
		)
		(fp_line
			(start -0.4953 1.6002)
			(end 0.4953 1.6002)
			(stroke
				(width 0.1)
				(type default)
			)
			(layer "B.Fab")
		)
		(fp_line
			(start 0.4953 -0.2032)
			(end -0.4953 -0.2032)
			(stroke
				(width 0.1)
				(type default)
			)
			(layer "B.Fab")
		)
		(fp_line
			(start 0.4953 1.6002)
			(end 0.4953 -0.2032)
			(stroke
				(width 0.1)
				(type default)
			)
			(layer "B.Fab")
		)
		(pad "1" smd rect
			(at 0 0 180)
			(size 0.762 0.889)
			(layers "B.Cu" "B.Mask" "B.Paste")
			(net "PVCCIN_CPU0")
		)
		(pad "2" smd rect
			(at 0 1.397 180)
			(size 0.762 0.889)
			(layers "B.Cu" "B.Mask" "B.Paste")
			(net "GND")
		)
		(zone
			(layer "B.Cu")
			(hatch none 0.5)
			(connect_pads
				(clearance 0)
			)
			(min_thickness 0.25)
			(keepout
				(tracks not_allowed)
				(vias allowed)
				(pads allowed)
				(copperpour not_allowed)
				(footprints allowed)
			)
			(placement
				(enabled no)
				(sheetname "")
			)
			(fill
				(thermal_gap 0.5)
				(thermal_bridge_width 0.5)
				(island_removal_mode 0)
			)
			(polygon
				(pts
					(xy 214.884 -85.979) (xy 214.122 -85.979) (xy 214.122 -85.471) (xy 214.884 -85.471)
				)
			)
		)
	)
	(footprint ""
		(layer "B.Cu")
		(at 375.270268 -47.566326 -90)
		(property "Reference" "R2T72"
			(at 0 0 90)
			(layer "B.SilkS")
			(hide yes)
			(effects
				(font
					(size 1.27 1.27)
				)
				(justify mirror)
			)
		)
		(property "Value" ""
			(at 0 0 90)
			(layer "B.Fab")
			(effects
				(font
					(size 1.27 1.27)
				)
				(justify mirror)
			)
		)
		(duplicate_pad_numbers_are_jumpers no)
		(fp_poly
			(pts
				(xy 0.2794 -0.1016) (xy -0.2794 -0.1016) (xy -0.2794 0.9906) (xy 0.2794 0.9906)
			)
			(stroke
				(width 0)
				(type default)
			)
			(fill no)
			(layer "B.CrtYd")
		)
		(fp_line
			(start -0.2794 0.9906)
			(end -0.2794 -0.1016)
			(stroke
				(width 0.1)
				(type default)
			)
			(layer "B.Fab")
		)
		(fp_line
			(start 0.2794 0.9906)
			(end -0.2794 0.9906)
			(stroke
				(width 0.1)
				(type default)
			)
			(layer "B.Fab")
		)
		(fp_line
			(start -0.2794 -0.1016)
			(end 0.2794 -0.1016)
			(stroke
				(width 0.1)
				(type default)
			)
			(layer "B.Fab")
		)
		(fp_line
			(start 0.2794 -0.1016)
			(end 0.2794 0.9906)
			(stroke
				(width 0.1)
				(type default)
			)
			(layer "B.Fab")
		)
		(pad "1" smd rect
			(at 0 0 90)
			(size 0.508 0.508)
			(layers "B.Cu" "B.Mask" "B.Paste")
			(net "PVCCIO_CPU0")
		)
		(pad "2" smd rect
			(at 0 0.889 90)
			(size 0.508 0.508)
			(layers "B.Cu" "B.Mask" "B.Paste")
			(net "H_CPU0_PROCHOT_G_N")
		)
		(zone
			(layer "B.Cu")
			(hatch none 0.5)
			(connect_pads
				(clearance 0)
			)
			(min_thickness 0.25)
			(keepout
				(tracks not_allowed)
				(vias allowed)
				(pads allowed)
				(copperpour not_allowed)
				(footprints allowed)
			)
			(placement
				(enabled no)
				(sheetname "")
			)
			(fill
				(thermal_gap 0.5)
				(thermal_bridge_width 0.5)
				(island_removal_mode 0)
			)
			(polygon
				(pts
					(xy 374.635268 -47.312326) (xy 374.635268 -47.820326) (xy 375.016268 -47.820326) (xy 375.016268 -47.312326)
				)
			)
		)
		(zone
			(layer "B.Cu")
			(hatch none 0.5)
			(connect_pads
				(clearance 0)
			)
			(min_thickness 0.25)
			(keepout
				(tracks allowed)
				(vias not_allowed)
				(pads allowed)
				(copperpour not_allowed)
				(footprints allowed)
			)
			(placement
				(enabled no)
				(sheetname "")
			)
			(fill
				(thermal_gap 0.5)
				(thermal_bridge_width 0.5)
				(island_removal_mode 0)
			)
			(polygon
				(pts
					(xy 375.016268 -47.312326) (xy 375.016268 -47.820326) (xy 374.635268 -47.820326) (xy 374.635268 -47.312326)
				)
			)
		)
	)
	(footprint ""
		(layer "B.Cu")
		(at 343.063068 -77.694536 180)
		(property "Reference" "C3P17"
			(at 0 0 0)
			(layer "B.SilkS")
			(hide yes)
			(effects
				(font
					(size 1.27 1.27)
				)
				(justify mirror)
			)
		)
		(property "Value" ""
			(at 0 0 0)
			(layer "B.Fab")
			(effects
				(font
					(size 1.27 1.27)
				)
				(justify mirror)
			)
		)
		(duplicate_pad_numbers_are_jumpers no)
		(fp_poly
			(pts
				(xy -0.3048 -0.1016) (xy -0.3048 0.9906) (xy 0.3048 0.9906) (xy 0.3048 -0.1016)
			)
			(stroke
				(width 0)
				(type default)
			)
			(fill no)
			(layer "B.CrtYd")
		)
		(fp_line
			(start 0.3048 0.9906)
			(end -0.3048 0.9906)
			(stroke
				(width 0.1)
				(type default)
			)
			(layer "B.Fab")
		)
		(fp_line
			(start 0.3048 -0.1016)
			(end 0.3048 0.9906)
			(stroke
				(width 0.1)
				(type default)
			)
			(layer "B.Fab")
		)
		(fp_line
			(start -0.3048 0.9906)
			(end -0.3048 -0.1016)
			(stroke
				(width 0.1)
				(type default)
			)
			(layer "B.Fab")
		)
		(fp_line
			(start -0.3048 -0.1016)
			(end 0.3048 -0.1016)
			(stroke
				(width 0.1)
				(type default)
			)
			(layer "B.Fab")
		)
		(pad "1" smd rect
			(at 0 0)
			(size 0.508 0.508)
			(layers "B.Cu" "B.Mask" "B.Paste")
			(net "P3E_CPU0_PE1_SS_TXN<1>")
		)
		(pad "2" smd rect
			(at 0 0.889)
			(size 0.508 0.508)
			(layers "B.Cu" "B.Mask" "B.Paste")
			(net "P3E_CPU0_PE1_PCH_TXN<1>")
		)
		(zone
			(layer "B.Cu")
			(hatch none 0.5)
			(connect_pads
				(clearance 0)
			)
			(min_thickness 0.25)
			(keepout
				(tracks not_allowed)
				(vias allowed)
				(pads allowed)
				(copperpour not_allowed)
				(footprints allowed)
			)
			(placement
				(enabled no)
				(sheetname "")
			)
			(fill
				(thermal_gap 0.5)
				(thermal_bridge_width 0.5)
				(island_removal_mode 0)
			)
			(polygon
				(pts
					(xy 342.809068 -78.329536) (xy 343.317068 -78.329536) (xy 343.317068 -77.948536) (xy 342.809068 -77.948536)
				)
			)
		)
		(zone
			(layer "B.Cu")
			(hatch none 0.5)
			(connect_pads
				(clearance 0)
			)
			(min_thickness 0.25)
			(keepout
				(tracks allowed)
				(vias not_allowed)
				(pads allowed)
				(copperpour not_allowed)
				(footprints allowed)
			)
			(placement
				(enabled no)
				(sheetname "")
			)
			(fill
				(thermal_gap 0.5)
				(thermal_bridge_width 0.5)
				(island_removal_mode 0)
			)
			(polygon
				(pts
					(xy 342.809068 -77.948536) (xy 343.317068 -77.948536) (xy 343.317068 -78.329536) (xy 342.809068 -78.329536)
				)
			)
		)
	)
	(footprint ""
		(layer "B.Cu")
		(at 320.194432 -145.034 90)
		(property "Reference" "C4L3"
			(at 0 0 90)
			(layer "B.SilkS")
			(hide yes)
			(effects
				(font
					(size 1.27 1.27)
				)
				(justify mirror)
			)
		)
		(property "Value" ""
			(at 0 0 90)
			(layer "B.Fab")
			(effects
				(font
					(size 1.27 1.27)
				)
				(justify mirror)
			)
		)
		(duplicate_pad_numbers_are_jumpers no)
		(fp_poly
			(pts
				(xy 0.4953 -0.2032) (xy -0.4953 -0.2032) (xy -0.4953 1.6002) (xy 0.4953 1.6002)
			)
			(stroke
				(width 0)
				(type default)
			)
			(fill no)
			(layer "B.CrtYd")
		)
		(fp_line
			(start 0.4953 -0.2032)
			(end -0.4953 -0.2032)
			(stroke
				(width 0.1)
				(type default)
			)
			(layer "B.Fab")
		)
		(fp_line
			(start -0.4953 -0.2032)
			(end -0.4953 1.6002)
			(stroke
				(width 0.1)
				(type default)
			)
			(layer "B.Fab")
		)
		(fp_line
			(start 0.4953 1.6002)
			(end 0.4953 -0.2032)
			(stroke
				(width 0.1)
				(type default)
			)
			(layer "B.Fab")
		)
		(fp_line
			(start -0.4953 1.6002)
			(end 0.4953 1.6002)
			(stroke
				(width 0.1)
				(type default)
			)
			(layer "B.Fab")
		)
		(pad "1" smd rect
			(at 0 0 270)
			(size 0.762 0.889)
			(layers "B.Cu" "B.Mask" "B.Paste")
			(net "PVPP_DEF")
		)
		(pad "2" smd rect
			(at 0 1.397 270)
			(size 0.762 0.889)
			(layers "B.Cu" "B.Mask" "B.Paste")
			(net "GND")
		)
		(zone
			(layer "B.Cu")
			(hatch none 0.5)
			(connect_pads
				(clearance 0)
			)
			(min_thickness 0.25)
			(keepout
				(tracks not_allowed)
				(vias allowed)
				(pads allowed)
				(copperpour not_allowed)
				(footprints allowed)
			)
			(placement
				(enabled no)
				(sheetname "")
			)
			(fill
				(thermal_gap 0.5)
				(thermal_bridge_width 0.5)
				(island_removal_mode 0)
			)
			(polygon
				(pts
					(xy 320.638932 -145.415) (xy 320.638932 -144.653) (xy 321.146932 -144.653) (xy 321.146932 -145.415)
				)
			)
		)
	)
	(footprint ""
		(layer "B.Cu")
		(at 436.547006 -41.648126 180)
		(property "Reference" "R25W17"
			(at 0 0 0)
			(layer "B.SilkS")
			(hide yes)
			(effects
				(font
					(size 1.27 1.27)
				)
				(justify mirror)
			)
		)
		(property "Value" "*"
			(at -0.064008 -4.108196 180)
			(unlocked yes)
			(layer "B.Fab")
			(hide yes)
			(effects
				(font
					(size 1.27 1.016)
					(thickness 0.1524)
				)
				(justify mirror)
			)
		)
		(property "Device Type" "120R2F-GP_RCL_GP-120R2F-GP,64.A"
			(at -0.064008 -5.632196 180)
			(unlocked yes)
			(layer "B.Fab")
			(hide yes)
			(effects
				(font
					(size 1.27 1.016)
					(thickness 0.1524)
				)
				(justify mirror)
			)
		)
		(duplicate_pad_numbers_are_jumpers no)
		(fp_line
			(start 0.508 -0.9398)
			(end 0.508 0.9398)
			(stroke
				(width 0.1524)
				(type default)
			)
			(layer "B.SilkS")
		)
		(fp_line
			(start -0.508 -0.9398)
			(end 0.508 -0.9398)
			(stroke
				(width 0.1524)
				(type default)
			)
			(layer "B.SilkS")
		)
		(fp_rect
			(start 0.508 0.9398)
			(end -0.508 -0.9398)
			(stroke
				(width 0)
				(type default)
			)
			(fill no)
			(layer "B.CrtYd")
		)
		(fp_rect
			(start 0.508 0.9398)
			(end -0.508 -0.9398)
			(stroke
				(width 0)
				(type default)
			)
			(fill no)
			(layer "B.Fab")
		)
		(pad "1" smd custom
			(at 0 -0.4445)
			(size 0.1397 0.1397)
			(layers "B.Cu" "B.Mask" "B.Paste")
			(net "GND")
			(options
				(clearance outline)
				(anchor circle)
			)
			(primitives
				(gr_poly
					(pts
						(arc
							(start -0.1778 0.2794)
							(mid -0.249642 0.249642)
							(end -0.2794 0.1778)
						)
						(arc
							(start -0.2794 -0.1778)
							(mid -0.249642 -0.249642)
							(end -0.1778 -0.2794)
						)
						(arc
							(start 0.1778 -0.2794)
							(mid 0.249642 -0.249642)
							(end 0.2794 -0.1778)
						)
						(arc
							(start 0.2794 0.1778)
							(mid 0.249642 0.249642)
							(end 0.1778 0.2794)
						)
					)
					(width 0)
					(fill yes)
				)
			)
		)
		(pad "2" smd custom
			(at 0 0.4445)
			(size 0.1397 0.1397)
			(layers "B.Cu" "B.Mask" "B.Paste")
			(net "BMC_M_A5")
			(options
				(clearance outline)
				(anchor circle)
			)
			(primitives
				(gr_poly
					(pts
						(arc
							(start -0.1778 0.2794)
							(mid -0.249642 0.249642)
							(end -0.2794 0.1778)
						)
						(arc
							(start -0.2794 -0.1778)
							(mid -0.249642 -0.249642)
							(end -0.1778 -0.2794)
						)
						(arc
							(start 0.1778 -0.2794)
							(mid 0.249642 -0.249642)
							(end 0.2794 -0.1778)
						)
						(arc
							(start 0.2794 0.1778)
							(mid 0.249642 0.249642)
							(end 0.1778 0.2794)
						)
					)
					(width 0)
					(fill yes)
				)
			)
		)
	)
	(footprint ""
		(layer "B.Cu")
		(at 276.000464 -149.8092 90)
		(property "Reference" "C5G72"
			(at -1.14681 0.76708 180)
			(unlocked yes)
			(layer "B.SilkS")
			(effects
				(font
					(size 0.7874 0.5842)
					(thickness 0.1524)
				)
				(justify mirror)
			)
		)
		(property "Value" ""
			(at 0 0 90)
			(layer "B.Fab")
			(effects
				(font
					(size 1.27 1.27)
				)
				(justify mirror)
			)
		)
		(duplicate_pad_numbers_are_jumpers no)
		(fp_rect
			(start -0.4953 -0.2032)
			(end 0.4953 1.6002)
			(stroke
				(width 0)
				(type default)
			)
			(fill no)
			(layer "B.CrtYd")
		)
		(fp_line
			(start 0.4953 -0.2032)
			(end -0.4953 -0.2032)
			(stroke
				(width 0.1)
				(type default)
			)
			(layer "B.Fab")
		)
		(fp_line
			(start -0.4953 -0.2032)
			(end -0.4953 1.6002)
			(stroke
				(width 0.1)
				(type default)
			)
			(layer "B.Fab")
		)
		(fp_line
			(start 0.4953 1.6002)
			(end 0.4953 -0.2032)
			(stroke
				(width 0.1)
				(type default)
			)
			(layer "B.Fab")
		)
		(fp_line
			(start -0.4953 1.6002)
			(end 0.4953 1.6002)
			(stroke
				(width 0.1)
				(type default)
			)
			(layer "B.Fab")
		)
		(pad "1" smd rect
			(at 0 0 270)
			(size 0.762 0.889)
			(layers "B.Cu" "B.Mask" "B.Paste")
			(net "PVDDQ_DEF")
		)
		(pad "2" smd rect
			(at 0 1.397 270)
			(size 0.762 0.889)
			(layers "B.Cu" "B.Mask" "B.Paste")
			(net "GND")
		)
		(zone
			(layer "B.Cu")
			(hatch none 0.5)
			(connect_pads
				(clearance 0)
			)
			(min_thickness 0.25)
			(keepout
				(tracks not_allowed)
				(vias allowed)
				(pads allowed)
				(copperpour not_allowed)
				(footprints allowed)
			)
			(placement
				(enabled no)
				(sheetname "")
			)
			(fill
				(thermal_gap 0.5)
				(thermal_bridge_width 0.5)
				(island_removal_mode 0)
			)
			(polygon
				(pts
					(xy 276.444964 -149.4282) (xy 276.952964 -149.4282) (xy 276.952964 -150.1902) (xy 276.444964 -150.1902)
				)
			)
		)
	)
	(footprint ""
		(layer "B.Cu")
		(at 341.1982 -86.5632 90)
		(property "Reference" "R3P15"
			(at 0 0 90)
			(layer "B.SilkS")
			(hide yes)
			(effects
				(font
					(size 1.27 1.27)
				)
				(justify mirror)
			)
		)
		(property "Value" ""
			(at 0 0 90)
			(layer "B.Fab")
			(effects
				(font
					(size 1.27 1.27)
				)
				(justify mirror)
			)
		)
		(duplicate_pad_numbers_are_jumpers no)
		(fp_poly
			(pts
				(xy 0.2794 -0.1016) (xy -0.2794 -0.1016) (xy -0.2794 0.9906) (xy 0.2794 0.9906)
			)
			(stroke
				(width 0)
				(type default)
			)
			(fill no)
			(layer "B.CrtYd")
		)
		(fp_line
			(start 0.2794 -0.1016)
			(end 0.2794 0.9906)
			(stroke
				(width 0.1)
				(type default)
			)
			(layer "B.Fab")
		)
		(fp_line
			(start -0.2794 -0.1016)
			(end 0.2794 -0.1016)
			(stroke
				(width 0.1)
				(type default)
			)
			(layer "B.Fab")
		)
		(fp_line
			(start 0.2794 0.9906)
			(end -0.2794 0.9906)
			(stroke
				(width 0.1)
				(type default)
			)
			(layer "B.Fab")
		)
		(fp_line
			(start -0.2794 0.9906)
			(end -0.2794 -0.1016)
			(stroke
				(width 0.1)
				(type default)
			)
			(layer "B.Fab")
		)
		(pad "1" smd rect
			(at 0 0 270)
			(size 0.508 0.508)
			(layers "B.Cu" "B.Mask" "B.Paste")
			(net "SVID_CLK0_CPU0_R")
		)
		(pad "2" smd rect
			(at 0 0.889 270)
			(size 0.508 0.508)
			(layers "B.Cu" "B.Mask" "B.Paste")
			(net "SVID_CLK_PVCCIO_CPU0")
		)
		(zone
			(layer "B.Cu")
			(hatch none 0.5)
			(connect_pads
				(clearance 0)
			)
			(min_thickness 0.25)
			(keepout
				(tracks allowed)
				(vias not_allowed)
				(pads allowed)
				(copperpour not_allowed)
				(footprints allowed)
			)
			(placement
				(enabled no)
				(sheetname "")
			)
			(fill
				(thermal_gap 0.5)
				(thermal_bridge_width 0.5)
				(island_removal_mode 0)
			)
			(polygon
				(pts
					(xy 341.4522 -86.8172) (xy 341.4522 -86.3092) (xy 341.8332 -86.3092) (xy 341.8332 -86.8172)
				)
			)
		)
		(zone
			(layer "B.Cu")
			(hatch none 0.5)
			(connect_pads
				(clearance 0)
			)
			(min_thickness 0.25)
			(keepout
				(tracks not_allowed)
				(vias allowed)
				(pads allowed)
				(copperpour not_allowed)
				(footprints allowed)
			)
			(placement
				(enabled no)
				(sheetname "")
			)
			(fill
				(thermal_gap 0.5)
				(thermal_bridge_width 0.5)
				(island_removal_mode 0)
			)
			(polygon
				(pts
					(xy 341.8332 -86.8172) (xy 341.8332 -86.3092) (xy 341.4522 -86.3092) (xy 341.4522 -86.8172)
				)
			)
		)
	)
	(footprint ""
		(layer "B.Cu")
		(at 388.502906 -164.916612 90)
		(property "Reference" "T1D18"
			(at 0 0 90)
			(layer "B.SilkS")
			(hide yes)
			(effects
				(font
					(size 1.27 1.27)
				)
				(justify mirror)
			)
		)
		(property "Value" "*"
			(at 3.4036 -4.46405 90)
			(unlocked yes)
			(layer "B.Fab")
			(hide yes)
			(effects
				(font
					(size 0.889 0.889)
					(thickness 0.1524)
				)
				(justify mirror)
			)
		)
		(property "Device Type" "TEST-PAD-12P-1-GP-U_DISCRET-GBA"
			(at 3.4036 -5.98805 90)
			(unlocked yes)
			(layer "B.Fab")
			(hide yes)
			(effects
				(font
					(size 0.889 0.889)
					(thickness 0.1524)
				)
				(justify mirror)
			)
		)
		(duplicate_pad_numbers_are_jumpers no)
		(fp_line
			(start 2.3876 -4.826)
			(end -2.3622 -4.826)
			(stroke
				(width 0.1524)
				(type default)
			)
			(layer "B.SilkS")
		)
		(fp_line
			(start -2.3622 -4.826)
			(end -2.3622 3.4798)
			(stroke
				(width 0.1524)
				(type default)
			)
			(layer "B.SilkS")
		)
		(fp_line
			(start 2.3876 3.4798)
			(end 2.3876 -4.826)
			(stroke
				(width 0.1524)
				(type default)
			)
			(layer "B.SilkS")
		)
		(fp_line
			(start -2.3622 3.4798)
			(end 2.3876 3.4798)
			(stroke
				(width 0.1524)
				(type default)
			)
			(layer "B.SilkS")
		)
		(fp_rect
			(start 2.6416 3.7338)
			(end -2.6162 -5.08)
			(stroke
				(width 0)
				(type default)
			)
			(fill no)
			(layer "B.CrtYd")
		)
		(fp_rect
			(start 2.6416 3.7338)
			(end -2.6162 -5.08)
			(stroke
				(width 0)
				(type default)
			)
			(fill no)
			(layer "B.Fab")
		)
		(pad "1" smd circle
			(at -0.496824 -1.301496 270)
			(size 0.6604 0.6604)
			(layers "B.Cu" "B.Mask" "B.Paste")
			(net "L5_85OHM_10INCH_DN")
		)
		(pad "2" smd circle
			(at 0.503936 -1.301496 270)
			(size 0.6604 0.6604)
			(layers "B.Cu" "B.Mask" "B.Paste")
			(net "L5_85OHM_10INCH_DP")
		)
		(pad "3" smd custom
			(at 0.00889 0.370078 270)
			(size 0.74295 0.74295)
			(layers "B.Cu" "B.Mask" "B.Paste")
			(net "GND")
			(options
				(clearance outline)
				(anchor circle)
			)
			(primitives
				(gr_poly
					(pts
						(xy -2.1209 -1.4859) (xy 2.1209 -1.4859) (xy 2.1209 1.4859) (xy 1.08585 1.4859) (xy 1.08585 0.4699)
						(xy -1.08585 0.4699) (xy -1.08585 1.4859) (xy -2.1209 1.4859)
					)
					(width 0)
					(fill yes)
				)
			)
		)
		(pad "4" thru_hole circle
			(at -1.266444 -3.851656 270)
			(size 1.4478 1.4478)
			(drill 1.0414)
			(layers "*.Cu" "*.Mask")
			(remove_unused_layers no)
			(net "GND")
			(clearance 0.1524)
			(thermal_gap 0.1524)
		)
		(pad "5" thru_hole circle
			(at 1.273556 -3.851656 270)
			(size 1.4478 1.4478)
			(drill 1.0414)
			(layers "*.Cu" "*.Mask")
			(remove_unused_layers no)
			(net "GND")
			(clearance 0.1524)
			(thermal_gap 0.1524)
		)
		(pad "6" thru_hole circle
			(at -1.266444 2.498344 270)
			(size 1.4478 1.4478)
			(drill 1.0414)
			(layers "*.Cu" "*.Mask")
			(remove_unused_layers no)
			(net "GND")
			(clearance 0.1524)
			(thermal_gap 0.1524)
		)
		(pad "7" thru_hole circle
			(at 1.273556 2.498344 270)
			(size 1.4478 1.4478)
			(drill 1.0414)
			(layers "*.Cu" "*.Mask")
			(remove_unused_layers no)
			(net "GND")
			(clearance 0.1524)
			(thermal_gap 0.1524)
		)
		(pad "8" thru_hole circle
			(at -1.27 -0.4572 270)
			(size 0.7112 0.7112)
			(drill 0.4064)
			(layers "*.Cu" "*.Mask")
			(remove_unused_layers no)
			(net "GND")
			(clearance 0.1016)
			(thermal_gap 0.1016)
		)
		(pad "9" thru_hole circle
			(at -1.27 0.762 270)
			(size 0.7112 0.7112)
			(drill 0.4064)
			(layers "*.Cu" "*.Mask")
			(remove_unused_layers no)
			(net "GND")
			(clearance 0.1016)
			(thermal_gap 0.1016)
		)
		(pad "10" thru_hole circle
			(at 0.0254 0.762 270)
			(size 0.7112 0.7112)
			(drill 0.4064)
			(layers "*.Cu" "*.Mask")
			(remove_unused_layers no)
			(net "GND")
			(clearance 0.1016)
			(thermal_gap 0.1016)
		)
		(pad "11" thru_hole circle
			(at 1.27 0.762 270)
			(size 0.7112 0.7112)
			(drill 0.4064)
			(layers "*.Cu" "*.Mask")
			(remove_unused_layers no)
			(net "GND")
			(clearance 0.1016)
			(thermal_gap 0.1016)
		)
		(pad "12" thru_hole circle
			(at 1.27 -0.4572 270)
			(size 0.7112 0.7112)
			(drill 0.4064)
			(layers "*.Cu" "*.Mask")
			(remove_unused_layers no)
			(net "GND")
			(clearance 0.1016)
			(thermal_gap 0.1016)
		)
	)
	(footprint ""
		(layer "B.Cu")
		(at 388.9248 -3.103372)
		(property "Reference" "U8W1"
			(at 0.14986 2.621788 0)
			(unlocked yes)
			(layer "B.SilkS")
			(effects
				(font
					(size 1.27 0.964946)
					(thickness 0.000001)
				)
				(justify left mirror)
			)
		)
		(property "Value" ""
			(at 0 0 0)
			(layer "B.Fab")
			(effects
				(font
					(size 1.27 1.27)
				)
				(justify mirror)
			)
		)
		(duplicate_pad_numbers_are_jumpers no)
		(fp_circle
			(center 0.4699 -0.8382)
			(end 0.5969 -0.8382)
			(stroke
				(width 0.254)
				(type default)
			)
			(fill no)
			(layer "B.SilkS")
		)
		(fp_poly
			(pts
				(xy -0.21463 -0.450088) (xy -1.56337 -0.450088) (xy -1.56337 1.75006) (xy -0.21463 1.75006)
			)
			(stroke
				(width 0)
				(type default)
			)
			(fill no)
			(layer "B.CrtYd")
		)
		(fp_line
			(start -1.56337 -0.450088)
			(end -1.56337 1.75006)
			(stroke
				(width 0.1)
				(type default)
			)
			(layer "B.Fab")
		)
		(fp_line
			(start -1.56337 1.75006)
			(end -0.21463 1.75006)
			(stroke
				(width 0.1)
				(type default)
			)
			(layer "B.Fab")
		)
		(fp_line
			(start -0.21463 -0.450088)
			(end -1.56337 -0.450088)
			(stroke
				(width 0.1)
				(type default)
			)
			(layer "B.Fab")
		)
		(fp_line
			(start -0.21463 1.75006)
			(end -0.21463 -0.450088)
			(stroke
				(width 0.1)
				(type default)
			)
			(layer "B.Fab")
		)
		(fp_circle
			(center 0.4699 -0.8382)
			(end 0.5969 -0.8382)
			(stroke
				(width 0.254)
				(type default)
			)
			(fill no)
			(layer "B.Fab")
		)
		(pad "1" smd rect
			(at 0 0 180)
			(size 1.016 0.381)
			(layers "B.Cu" "B.Mask" "B.Paste")
			(net "JTAG_RISER_N")
		)
		(pad "2" smd rect
			(at 0 0.649986 180)
			(size 1.016 0.381)
			(layers "B.Cu" "B.Mask" "B.Paste")
			(net "JTAG_PLD_TDO")
		)
		(pad "3" smd rect
			(at 0 1.299972 180)
			(size 1.016 0.381)
			(layers "B.Cu" "B.Mask" "B.Paste")
			(net "GND")
		)
		(pad "4" smd rect
			(at -1.778 1.299972 180)
			(size 1.016 0.381)
			(layers "B.Cu" "B.Mask" "B.Paste")
			(net "JTAG_RISER_TDI_R")
		)
		(pad "5" smd rect
			(at -1.778 0 180)
			(size 1.016 0.381)
			(layers "B.Cu" "B.Mask" "B.Paste")
			(net "P3V3_STBY")
		)
	)
	(footprint ""
		(layer "B.Cu")
		(at 384.0734 -158.26994 -90)
		(property "Reference" "CT69"
			(at 0.8382 -0.84963 270)
			(unlocked yes)
			(layer "B.SilkS")
			(effects
				(font
					(size 0.7874 0.5842)
					(thickness 0.1524)
				)
				(justify left mirror)
			)
		)
		(property "Value" ""
			(at 0 0 90)
			(layer "B.Fab")
			(effects
				(font
					(size 1.27 1.27)
				)
				(justify mirror)
			)
		)
		(duplicate_pad_numbers_are_jumpers no)
		(fp_poly
			(pts
				(xy -0.3048 -0.1016) (xy -0.3048 0.9906) (xy 0.3048 0.9906) (xy 0.3048 -0.1016)
			)
			(stroke
				(width 0)
				(type default)
			)
			(fill no)
			(layer "B.CrtYd")
		)
		(fp_line
			(start -0.3048 0.9906)
			(end -0.3048 -0.1016)
			(stroke
				(width 0.1)
				(type default)
			)
			(layer "B.Fab")
		)
		(fp_line
			(start 0.3048 0.9906)
			(end -0.3048 0.9906)
			(stroke
				(width 0.1)
				(type default)
			)
			(layer "B.Fab")
		)
		(fp_line
			(start -0.3048 -0.1016)
			(end 0.3048 -0.1016)
			(stroke
				(width 0.1)
				(type default)
			)
			(layer "B.Fab")
		)
		(fp_line
			(start 0.3048 -0.1016)
			(end 0.3048 0.9906)
			(stroke
				(width 0.1)
				(type default)
			)
			(layer "B.Fab")
		)
		(pad "1" smd rect
			(at 0 0 90)
			(size 0.508 0.508)
			(layers "B.Cu" "B.Mask" "B.Paste")
			(net "A_TSENSE_P1V05_PCH_STBY_TMON")
		)
		(pad "2" smd rect
			(at 0 0.889 90)
			(size 0.508 0.508)
			(layers "B.Cu" "B.Mask" "B.Paste")
			(net "GND")
		)
		(zone
			(layer "B.Cu")
			(hatch none 0.5)
			(connect_pads
				(clearance 0)
			)
			(min_thickness 0.25)
			(keepout
				(tracks not_allowed)
				(vias allowed)
				(pads allowed)
				(copperpour not_allowed)
				(footprints allowed)
			)
			(placement
				(enabled no)
				(sheetname "")
			)
			(fill
				(thermal_gap 0.5)
				(thermal_bridge_width 0.5)
				(island_removal_mode 0)
			)
			(polygon
				(pts
					(xy 383.4384 -158.01594) (xy 383.4384 -158.52394) (xy 383.8194 -158.52394) (xy 383.8194 -158.01594)
				)
			)
		)
		(zone
			(layer "B.Cu")
			(hatch none 0.5)
			(connect_pads
				(clearance 0)
			)
			(min_thickness 0.25)
			(keepout
				(tracks allowed)
				(vias not_allowed)
				(pads allowed)
				(copperpour not_allowed)
				(footprints allowed)
			)
			(placement
				(enabled no)
				(sheetname "")
			)
			(fill
				(thermal_gap 0.5)
				(thermal_bridge_width 0.5)
				(island_removal_mode 0)
			)
			(polygon
				(pts
					(xy 383.8194 -158.01594) (xy 383.8194 -158.52394) (xy 383.4384 -158.52394) (xy 383.4384 -158.01594)
				)
			)
		)
	)
	(footprint ""
		(layer "B.Cu")
		(at 400.409156 -30.806898)
		(property "Reference" "C25W71"
			(at 0.8382 -0.67818 0)
			(unlocked yes)
			(layer "B.SilkS")
			(effects
				(font
					(size 0.4064 0.254)
					(thickness 0.1524)
				)
				(justify left mirror)
			)
		)
		(property "Value" ""
			(at 0 0 0)
			(layer "B.Fab")
			(effects
				(font
					(size 1.27 1.27)
				)
				(justify mirror)
			)
		)
		(duplicate_pad_numbers_are_jumpers no)
		(fp_poly
			(pts
				(xy -0.3048 -0.1016) (xy -0.3048 0.9906) (xy 0.3048 0.9906) (xy 0.3048 -0.1016)
			)
			(stroke
				(width 0)
				(type default)
			)
			(fill no)
			(layer "B.CrtYd")
		)
		(fp_line
			(start -0.3048 -0.1016)
			(end 0.3048 -0.1016)
			(stroke
				(width 0.1)
				(type default)
			)
			(layer "B.Fab")
		)
		(fp_line
			(start -0.3048 0.9906)
			(end -0.3048 -0.1016)
			(stroke
				(width 0.1)
				(type default)
			)
			(layer "B.Fab")
		)
		(fp_line
			(start 0.3048 -0.1016)
			(end 0.3048 0.9906)
			(stroke
				(width 0.1)
				(type default)
			)
			(layer "B.Fab")
		)
		(fp_line
			(start 0.3048 0.9906)
			(end -0.3048 0.9906)
			(stroke
				(width 0.1)
				(type default)
			)
			(layer "B.Fab")
		)
		(pad "1" smd rect
			(at 0 0 180)
			(size 0.508 0.508)
			(layers "B.Cu" "B.Mask" "B.Paste")
			(net "P3V3_USB2A_ALG")
		)
		(pad "2" smd rect
			(at 0 0.889 180)
			(size 0.508 0.508)
			(layers "B.Cu" "B.Mask" "B.Paste")
			(net "GND")
		)
		(zone
			(layer "B.Cu")
			(hatch none 0.5)
			(connect_pads
				(clearance 0)
			)
			(min_thickness 0.25)
			(keepout
				(tracks allowed)
				(vias not_allowed)
				(pads allowed)
				(copperpour not_allowed)
				(footprints allowed)
			)
			(placement
				(enabled no)
				(sheetname "")
			)
			(fill
				(thermal_gap 0.5)
				(thermal_bridge_width 0.5)
				(island_removal_mode 0)
			)
			(polygon
				(pts
					(xy 400.663156 -30.552898) (xy 400.155156 -30.552898) (xy 400.155156 -30.171898) (xy 400.663156 -30.171898)
				)
			)
		)
		(zone
			(layer "B.Cu")
			(hatch none 0.5)
			(connect_pads
				(clearance 0)
			)
			(min_thickness 0.25)
			(keepout
				(tracks not_allowed)
				(vias allowed)
				(pads allowed)
				(copperpour not_allowed)
				(footprints allowed)
			)
			(placement
				(enabled no)
				(sheetname "")
			)
			(fill
				(thermal_gap 0.5)
				(thermal_bridge_width 0.5)
				(island_removal_mode 0)
			)
			(polygon
				(pts
					(xy 400.663156 -30.171898) (xy 400.155156 -30.171898) (xy 400.155156 -30.552898) (xy 400.663156 -30.552898)
				)
			)
		)
	)
	(footprint ""
		(layer "B.Cu")
		(at 106.731054 -79.60614 180)
		(property "Reference" "C8P8"
			(at 0 0 0)
			(layer "B.SilkS")
			(hide yes)
			(effects
				(font
					(size 1.27 1.27)
				)
				(justify mirror)
			)
		)
		(property "Value" ""
			(at 0 0 0)
			(layer "B.Fab")
			(effects
				(font
					(size 1.27 1.27)
				)
				(justify mirror)
			)
		)
		(duplicate_pad_numbers_are_jumpers no)
		(fp_poly
			(pts
				(xy 0.7239 -0.2159) (xy -0.7239 -0.2159) (xy -0.7239 1.9939) (xy 0.7239 1.9939)
			)
			(stroke
				(width 0)
				(type default)
			)
			(fill no)
			(layer "B.CrtYd")
		)
		(fp_line
			(start 0.7239 1.9939)
			(end -0.7239 1.9939)
			(stroke
				(width 0.1)
				(type default)
			)
			(layer "B.Fab")
		)
		(fp_line
			(start 0.7239 -0.2159)
			(end 0.7239 1.9939)
			(stroke
				(width 0.1)
				(type default)
			)
			(layer "B.Fab")
		)
		(fp_line
			(start -0.7239 1.9939)
			(end -0.7239 -0.2159)
			(stroke
				(width 0.1)
				(type default)
			)
			(layer "B.Fab")
		)
		(fp_line
			(start -0.7239 -0.2159)
			(end 0.7239 -0.2159)
			(stroke
				(width 0.1)
				(type default)
			)
			(layer "B.Fab")
		)
		(pad "1" smd rect
			(at 0 0)
			(size 1.27 1.016)
			(layers "B.Cu" "B.Mask" "B.Paste")
			(net "PVCCMCP_CPU1")
		)
		(pad "2" smd rect
			(at 0 1.778)
			(size 1.27 1.016)
			(layers "B.Cu" "B.Mask" "B.Paste")
			(net "GND")
		)
		(zone
			(layer "B.Cu")
			(hatch none 0.5)
			(connect_pads
				(clearance 0)
			)
			(min_thickness 0.25)
			(keepout
				(tracks not_allowed)
				(vias allowed)
				(pads allowed)
				(copperpour not_allowed)
				(footprints allowed)
			)
			(placement
				(enabled no)
				(sheetname "")
			)
			(fill
				(thermal_gap 0.5)
				(thermal_bridge_width 0.5)
				(island_removal_mode 0)
			)
			(polygon
				(pts
					(xy 106.096054 -80.11414) (xy 107.366054 -80.11414) (xy 107.366054 -80.87614) (xy 106.096054 -80.87614)
				)
			)
		)
	)
	(footprint ""
		(layer "B.Cu")
		(at 385.826 -140.589 180)
		(property "Reference" "C3L19"
			(at -3.10007 3.24612 270)
			(unlocked yes)
			(layer "B.SilkS")
			(effects
				(font
					(size 0.7874 0.5842)
					(thickness 0.1524)
				)
				(justify mirror)
			)
		)
		(property "Value" ""
			(at 0 0 0)
			(layer "B.Fab")
			(effects
				(font
					(size 1.27 1.27)
				)
				(justify mirror)
			)
		)
		(duplicate_pad_numbers_are_jumpers no)
		(fp_line
			(start 2.563114 1.633728)
			(end 1.6002 1.633728)
			(stroke
				(width 0.1524)
				(type default)
			)
			(layer "B.SilkS")
		)
		(fp_line
			(start 2.563114 -1.616456)
			(end 2.563114 1.633728)
			(stroke
				(width 0.1524)
				(type default)
			)
			(layer "B.SilkS")
		)
		(fp_line
			(start 2.286 7.366)
			(end 2.286 1.632712)
			(stroke
				(width 0.1524)
				(type default)
			)
			(layer "B.SilkS")
		)
		(fp_line
			(start 2.286 7.366)
			(end 1.60147 7.366)
			(stroke
				(width 0.1524)
				(type default)
			)
			(layer "B.SilkS")
		)
		(fp_line
			(start 1.6002 -1.616456)
			(end 2.563114 -1.616456)
			(stroke
				(width 0.1524)
				(type default)
			)
			(layer "B.SilkS")
		)
		(fp_line
			(start -1.6002 -1.616456)
			(end -2.504948 -1.616456)
			(stroke
				(width 0.1524)
				(type default)
			)
			(layer "B.SilkS")
		)
		(fp_line
			(start -2.286 7.366)
			(end -1.600708 7.366)
			(stroke
				(width 0.1524)
				(type default)
			)
			(layer "B.SilkS")
		)
		(fp_line
			(start -2.286 7.366)
			(end -2.286 1.63195)
			(stroke
				(width 0.1524)
				(type default)
			)
			(layer "B.SilkS")
		)
		(fp_line
			(start -2.504948 1.633728)
			(end -1.6002 1.633728)
			(stroke
				(width 0.1524)
				(type default)
			)
			(layer "B.SilkS")
		)
		(fp_line
			(start -2.504948 -1.616456)
			(end -2.504948 1.633728)
			(stroke
				(width 0.1524)
				(type default)
			)
			(layer "B.SilkS")
		)
		(fp_rect
			(start 2.286 7.366)
			(end -2.286 -0.254)
			(stroke
				(width 0)
				(type default)
			)
			(fill no)
			(layer "B.CrtYd")
		)
		(fp_line
			(start 2.286 7.366)
			(end 2.286 -0.254)
			(stroke
				(width 0.1)
				(type default)
			)
			(layer "B.Fab")
		)
		(fp_line
			(start 2.286 -0.254)
			(end -2.286 -0.254)
			(stroke
				(width 0.1)
				(type default)
			)
			(layer "B.Fab")
		)
		(fp_line
			(start -2.286 7.366)
			(end 2.286 7.366)
			(stroke
				(width 0.1)
				(type default)
			)
			(layer "B.Fab")
		)
		(fp_line
			(start -2.286 -0.254)
			(end -2.286 7.366)
			(stroke
				(width 0.1)
				(type default)
			)
			(layer "B.Fab")
		)
		(pad "1" smd rect
			(at 0 0)
			(size 2.54 3.048)
			(layers "B.Cu" "B.Mask" "B.Paste")
			(net "P1V05_PCH_STBY")
		)
		(pad "2" smd rect
			(at 0 7.112)
			(size 2.54 3.048)
			(layers "B.Cu" "B.Mask" "B.Paste")
			(net "GND")
		)
	)
	(footprint ""
		(layer "B.Cu")
		(at 320.194432 -135.382 90)
		(property "Reference" "C4M3"
			(at 0 0 90)
			(layer "B.SilkS")
			(hide yes)
			(effects
				(font
					(size 1.27 1.27)
				)
				(justify mirror)
			)
		)
		(property "Value" ""
			(at 0 0 90)
			(layer "B.Fab")
			(effects
				(font
					(size 1.27 1.27)
				)
				(justify mirror)
			)
		)
		(duplicate_pad_numbers_are_jumpers no)
		(fp_poly
			(pts
				(xy 0.4953 -0.2032) (xy -0.4953 -0.2032) (xy -0.4953 1.6002) (xy 0.4953 1.6002)
			)
			(stroke
				(width 0)
				(type default)
			)
			(fill no)
			(layer "B.CrtYd")
		)
		(fp_line
			(start 0.4953 -0.2032)
			(end -0.4953 -0.2032)
			(stroke
				(width 0.1)
				(type default)
			)
			(layer "B.Fab")
		)
		(fp_line
			(start -0.4953 -0.2032)
			(end -0.4953 1.6002)
			(stroke
				(width 0.1)
				(type default)
			)
			(layer "B.Fab")
		)
		(fp_line
			(start 0.4953 1.6002)
			(end 0.4953 -0.2032)
			(stroke
				(width 0.1)
				(type default)
			)
			(layer "B.Fab")
		)
		(fp_line
			(start -0.4953 1.6002)
			(end 0.4953 1.6002)
			(stroke
				(width 0.1)
				(type default)
			)
			(layer "B.Fab")
		)
		(pad "1" smd rect
			(at 0 0 270)
			(size 0.762 0.889)
			(layers "B.Cu" "B.Mask" "B.Paste")
			(net "PVPP_DEF")
		)
		(pad "2" smd rect
			(at 0 1.397 270)
			(size 0.762 0.889)
			(layers "B.Cu" "B.Mask" "B.Paste")
			(net "GND")
		)
		(zone
			(layer "B.Cu")
			(hatch none 0.5)
			(connect_pads
				(clearance 0)
			)
			(min_thickness 0.25)
			(keepout
				(tracks not_allowed)
				(vias allowed)
				(pads allowed)
				(copperpour not_allowed)
				(footprints allowed)
			)
			(placement
				(enabled no)
				(sheetname "")
			)
			(fill
				(thermal_gap 0.5)
				(thermal_bridge_width 0.5)
				(island_removal_mode 0)
			)
			(polygon
				(pts
					(xy 320.638932 -135.763) (xy 320.638932 -135.001) (xy 321.146932 -135.001) (xy 321.146932 -135.763)
				)
			)
		)
	)
	(footprint ""
		(layer "B.Cu")
		(at 411.21076 -45.53712)
		(property "Reference" "R25W73"
			(at 0.8382 -0.67818 0)
			(unlocked yes)
			(layer "B.SilkS")
			(effects
				(font
					(size 0.4064 0.254)
					(thickness 0.1524)
				)
				(justify left mirror)
			)
		)
		(property "Value" ""
			(at 0 0 0)
			(layer "B.Fab")
			(effects
				(font
					(size 1.27 1.27)
				)
				(justify mirror)
			)
		)
		(duplicate_pad_numbers_are_jumpers no)
		(fp_poly
			(pts
				(xy 0.2794 -0.1016) (xy -0.2794 -0.1016) (xy -0.2794 0.9906) (xy 0.2794 0.9906)
			)
			(stroke
				(width 0)
				(type default)
			)
			(fill no)
			(layer "B.CrtYd")
		)
		(fp_line
			(start -0.2794 -0.1016)
			(end 0.2794 -0.1016)
			(stroke
				(width 0.1)
				(type default)
			)
			(layer "B.Fab")
		)
		(fp_line
			(start -0.2794 0.9906)
			(end -0.2794 -0.1016)
			(stroke
				(width 0.1)
				(type default)
			)
			(layer "B.Fab")
		)
		(fp_line
			(start 0.2794 -0.1016)
			(end 0.2794 0.9906)
			(stroke
				(width 0.1)
				(type default)
			)
			(layer "B.Fab")
		)
		(fp_line
			(start 0.2794 0.9906)
			(end -0.2794 0.9906)
			(stroke
				(width 0.1)
				(type default)
			)
			(layer "B.Fab")
		)
		(pad "1" smd rect
			(at 0 0 180)
			(size 0.508 0.508)
			(layers "B.Cu" "B.Mask" "B.Paste")
			(net "IRQ_LPC_SERIRQ_N")
		)
		(pad "2" smd rect
			(at 0 0.889 180)
			(size 0.508 0.508)
			(layers "B.Cu" "B.Mask" "B.Paste")
			(net "IRQ_LPC_SERIRQ_R")
		)
		(zone
			(layer "B.Cu")
			(hatch none 0.5)
			(connect_pads
				(clearance 0)
			)
			(min_thickness 0.25)
			(keepout
				(tracks allowed)
				(vias not_allowed)
				(pads allowed)
				(copperpour not_allowed)
				(footprints allowed)
			)
			(placement
				(enabled no)
				(sheetname "")
			)
			(fill
				(thermal_gap 0.5)
				(thermal_bridge_width 0.5)
				(island_removal_mode 0)
			)
			(polygon
				(pts
					(xy 411.46476 -45.28312) (xy 410.95676 -45.28312) (xy 410.95676 -44.90212) (xy 411.46476 -44.90212)
				)
			)
		)
		(zone
			(layer "B.Cu")
			(hatch none 0.5)
			(connect_pads
				(clearance 0)
			)
			(min_thickness 0.25)
			(keepout
				(tracks not_allowed)
				(vias allowed)
				(pads allowed)
				(copperpour not_allowed)
				(footprints allowed)
			)
			(placement
				(enabled no)
				(sheetname "")
			)
			(fill
				(thermal_gap 0.5)
				(thermal_bridge_width 0.5)
				(island_removal_mode 0)
			)
			(polygon
				(pts
					(xy 411.46476 -44.90212) (xy 410.95676 -44.90212) (xy 410.95676 -45.28312) (xy 411.46476 -45.28312)
				)
			)
		)
	)
	(footprint ""
		(layer "B.Cu")
		(at 491.4392 -115.3668 180)
		(property "Reference" "R9W1"
			(at 0.8382 -0.67818 180)
			(unlocked yes)
			(layer "B.SilkS")
			(effects
				(font
					(size 0.4064 0.254)
					(thickness 0.1524)
				)
				(justify left mirror)
			)
		)
		(property "Value" ""
			(at 0 0 0)
			(layer "B.Fab")
			(effects
				(font
					(size 1.27 1.27)
				)
				(justify mirror)
			)
		)
		(duplicate_pad_numbers_are_jumpers no)
		(fp_poly
			(pts
				(xy 0.2794 -0.1016) (xy -0.2794 -0.1016) (xy -0.2794 0.9906) (xy 0.2794 0.9906)
			)
			(stroke
				(width 0)
				(type default)
			)
			(fill no)
			(layer "B.CrtYd")
		)
		(fp_line
			(start 0.2794 0.9906)
			(end -0.2794 0.9906)
			(stroke
				(width 0.1)
				(type default)
			)
			(layer "B.Fab")
		)
		(fp_line
			(start 0.2794 -0.1016)
			(end 0.2794 0.9906)
			(stroke
				(width 0.1)
				(type default)
			)
			(layer "B.Fab")
		)
		(fp_line
			(start -0.2794 0.9906)
			(end -0.2794 -0.1016)
			(stroke
				(width 0.1)
				(type default)
			)
			(layer "B.Fab")
		)
		(fp_line
			(start -0.2794 -0.1016)
			(end 0.2794 -0.1016)
			(stroke
				(width 0.1)
				(type default)
			)
			(layer "B.Fab")
		)
		(pad "1" smd rect
			(at 0 0)
			(size 0.508 0.508)
			(layers "B.Cu" "B.Mask" "B.Paste")
			(net "P3V3_STBY")
		)
		(pad "2" smd rect
			(at 0 0.889)
			(size 0.508 0.508)
			(layers "B.Cu" "B.Mask" "B.Paste")
			(net "FM_MEZZA_PRSNT1_N")
		)
		(zone
			(layer "B.Cu")
			(hatch none 0.5)
			(connect_pads
				(clearance 0)
			)
			(min_thickness 0.25)
			(keepout
				(tracks not_allowed)
				(vias allowed)
				(pads allowed)
				(copperpour not_allowed)
				(footprints allowed)
			)
			(placement
				(enabled no)
				(sheetname "")
			)
			(fill
				(thermal_gap 0.5)
				(thermal_bridge_width 0.5)
				(island_removal_mode 0)
			)
			(polygon
				(pts
					(xy 491.1852 -116.0018) (xy 491.6932 -116.0018) (xy 491.6932 -115.6208) (xy 491.1852 -115.6208)
				)
			)
		)
		(zone
			(layer "B.Cu")
			(hatch none 0.5)
			(connect_pads
				(clearance 0)
			)
			(min_thickness 0.25)
			(keepout
				(tracks allowed)
				(vias not_allowed)
				(pads allowed)
				(copperpour not_allowed)
				(footprints allowed)
			)
			(placement
				(enabled no)
				(sheetname "")
			)
			(fill
				(thermal_gap 0.5)
				(thermal_bridge_width 0.5)
				(island_removal_mode 0)
			)
			(polygon
				(pts
					(xy 491.1852 -115.6208) (xy 491.6932 -115.6208) (xy 491.6932 -116.0018) (xy 491.1852 -116.0018)
				)
			)
		)
	)
	(footprint ""
		(layer "B.Cu")
		(at 276.7076 -28.2956 90)
		(property "Reference" "C5T4"
			(at 0 0 90)
			(layer "B.SilkS")
			(hide yes)
			(effects
				(font
					(size 1.27 1.27)
				)
				(justify mirror)
			)
		)
		(property "Value" ""
			(at 0 0 90)
			(layer "B.Fab")
			(effects
				(font
					(size 1.27 1.27)
				)
				(justify mirror)
			)
		)
		(duplicate_pad_numbers_are_jumpers no)
		(fp_rect
			(start 0.500126 1.598422)
			(end -0.500126 -0.201422)
			(stroke
				(width 0)
				(type default)
			)
			(fill no)
			(layer "B.CrtYd")
		)
		(fp_line
			(start 0.500126 -0.201422)
			(end -0.500126 -0.201422)
			(stroke
				(width 0.1)
				(type default)
			)
			(layer "B.Fab")
		)
		(fp_line
			(start -0.500126 -0.201422)
			(end -0.500126 1.598422)
			(stroke
				(width 0.1)
				(type default)
			)
			(layer "B.Fab")
		)
		(fp_line
			(start 0.500126 1.598422)
			(end 0.500126 -0.201422)
			(stroke
				(width 0.1)
				(type default)
			)
			(layer "B.Fab")
		)
		(fp_line
			(start -0.500126 1.598422)
			(end 0.500126 1.598422)
			(stroke
				(width 0.1)
				(type default)
			)
			(layer "B.Fab")
		)
		(pad "1" smd rect
			(at 0 0)
			(size 0.889 0.9906)
			(layers "B.Cu" "B.Mask" "B.Paste")
			(net "PVDDQ_ABC")
		)
		(pad "2" smd rect
			(at 0 1.397)
			(size 0.889 0.9906)
			(layers "B.Cu" "B.Mask" "B.Paste")
			(net "GND")
		)
		(zone
			(layer "B.Cu")
			(hatch none 0.5)
			(connect_pads
				(clearance 0)
			)
			(min_thickness 0.25)
			(keepout
				(tracks allowed)
				(vias not_allowed)
				(pads allowed)
				(copperpour not_allowed)
				(footprints allowed)
			)
			(placement
				(enabled no)
				(sheetname "")
			)
			(fill
				(thermal_gap 0.5)
				(thermal_bridge_width 0.5)
				(island_removal_mode 0)
			)
			(polygon
				(pts
					(xy 277.6601 -28.7909) (xy 277.1521 -28.7909) (xy 277.1521 -27.8003) (xy 277.6601 -27.8003)
				)
			)
		)
		(zone
			(layer "B.Cu")
			(hatch none 0.5)
			(connect_pads
				(clearance 0)
			)
			(min_thickness 0.25)
			(keepout
				(tracks not_allowed)
				(vias allowed)
				(pads allowed)
				(copperpour not_allowed)
				(footprints allowed)
			)
			(placement
				(enabled no)
				(sheetname "")
			)
			(fill
				(thermal_gap 0.5)
				(thermal_bridge_width 0.5)
				(island_removal_mode 0)
			)
			(polygon
				(pts
					(xy 277.6601 -28.7909) (xy 277.1521 -28.7909) (xy 277.1521 -27.8003) (xy 277.6601 -27.8003)
				)
			)
		)
	)
	(footprint ""
		(layer "B.Cu")
		(at 466.344 -116.49202)
		(property "Reference" "C1M6"
			(at 0 0 0)
			(layer "B.SilkS")
			(hide yes)
			(effects
				(font
					(size 1.27 1.27)
				)
				(justify mirror)
			)
		)
		(property "Value" ""
			(at 0 0 0)
			(layer "B.Fab")
			(effects
				(font
					(size 1.27 1.27)
				)
				(justify mirror)
			)
		)
		(duplicate_pad_numbers_are_jumpers no)
		(fp_rect
			(start -0.3048 0.9906)
			(end 0.3048 -0.1016)
			(stroke
				(width 0)
				(type default)
			)
			(fill no)
			(layer "B.CrtYd")
		)
		(fp_line
			(start -0.3048 -0.1016)
			(end 0.3048 -0.1016)
			(stroke
				(width 0.1)
				(type default)
			)
			(layer "B.Fab")
		)
		(fp_line
			(start -0.3048 0.9906)
			(end -0.3048 -0.1016)
			(stroke
				(width 0.1)
				(type default)
			)
			(layer "B.Fab")
		)
		(fp_line
			(start 0.3048 -0.1016)
			(end 0.3048 0.9906)
			(stroke
				(width 0.1)
				(type default)
			)
			(layer "B.Fab")
		)
		(fp_line
			(start 0.3048 0.9906)
			(end -0.3048 0.9906)
			(stroke
				(width 0.1)
				(type default)
			)
			(layer "B.Fab")
		)
		(pad "1" smd rect
			(at 0 0 180)
			(size 0.508 0.508)
			(layers "B.Cu" "B.Mask" "B.Paste")
			(net "P3E_CPU0_PE3_OCP_TXP<15>")
		)
		(pad "2" smd rect
			(at 0 0.889 180)
			(size 0.508 0.508)
			(layers "B.Cu" "B.Mask" "B.Paste")
			(net "P3E_OCP_CPU0_PE3_C_TXP<15>")
		)
		(zone
			(layer "B.Cu")
			(hatch none 0.5)
			(connect_pads
				(clearance 0)
			)
			(min_thickness 0.25)
			(keepout
				(tracks allowed)
				(vias not_allowed)
				(pads allowed)
				(copperpour not_allowed)
				(footprints allowed)
			)
			(placement
				(enabled no)
				(sheetname "")
			)
			(fill
				(thermal_gap 0.5)
				(thermal_bridge_width 0.5)
				(island_removal_mode 0)
			)
			(polygon
				(pts
					(xy 466.09 -115.85702) (xy 466.598 -115.85702) (xy 466.598 -116.23802) (xy 466.09 -116.23802)
				)
			)
		)
		(zone
			(layer "B.Cu")
			(hatch none 0.5)
			(connect_pads
				(clearance 0)
			)
			(min_thickness 0.25)
			(keepout
				(tracks not_allowed)
				(vias allowed)
				(pads allowed)
				(copperpour not_allowed)
				(footprints allowed)
			)
			(placement
				(enabled no)
				(sheetname "")
			)
			(fill
				(thermal_gap 0.5)
				(thermal_bridge_width 0.5)
				(island_removal_mode 0)
			)
			(polygon
				(pts
					(xy 466.09 -115.85702) (xy 466.598 -115.85702) (xy 466.598 -116.23802) (xy 466.09 -116.23802)
				)
			)
		)
	)
	(footprint ""
		(layer "B.Cu")
		(at 102.551992 -85.075014)
		(property "Reference" "C8P1"
			(at 0 0 0)
			(layer "B.SilkS")
			(hide yes)
			(effects
				(font
					(size 1.27 1.27)
				)
				(justify mirror)
			)
		)
		(property "Value" ""
			(at 0 0 0)
			(layer "B.Fab")
			(effects
				(font
					(size 1.27 1.27)
				)
				(justify mirror)
			)
		)
		(duplicate_pad_numbers_are_jumpers no)
		(fp_poly
			(pts
				(xy 0.7239 -0.2159) (xy -0.7239 -0.2159) (xy -0.7239 1.9939) (xy 0.7239 1.9939)
			)
			(stroke
				(width 0)
				(type default)
			)
			(fill no)
			(layer "B.CrtYd")
		)
		(fp_line
			(start -0.7239 -0.2159)
			(end 0.7239 -0.2159)
			(stroke
				(width 0.1)
				(type default)
			)
			(layer "B.Fab")
		)
		(fp_line
			(start -0.7239 1.9939)
			(end -0.7239 -0.2159)
			(stroke
				(width 0.1)
				(type default)
			)
			(layer "B.Fab")
		)
		(fp_line
			(start 0.7239 -0.2159)
			(end 0.7239 1.9939)
			(stroke
				(width 0.1)
				(type default)
			)
			(layer "B.Fab")
		)
		(fp_line
			(start 0.7239 1.9939)
			(end -0.7239 1.9939)
			(stroke
				(width 0.1)
				(type default)
			)
			(layer "B.Fab")
		)
		(pad "1" smd rect
			(at 0 0 180)
			(size 1.27 1.016)
			(layers "B.Cu" "B.Mask" "B.Paste")
			(net "PVDDQ_KLM")
		)
		(pad "2" smd rect
			(at 0 1.778 180)
			(size 1.27 1.016)
			(layers "B.Cu" "B.Mask" "B.Paste")
			(net "GND")
		)
		(zone
			(layer "B.Cu")
			(hatch none 0.5)
			(connect_pads
				(clearance 0)
			)
			(min_thickness 0.25)
			(keepout
				(tracks not_allowed)
				(vias allowed)
				(pads allowed)
				(copperpour not_allowed)
				(footprints allowed)
			)
			(placement
				(enabled no)
				(sheetname "")
			)
			(fill
				(thermal_gap 0.5)
				(thermal_bridge_width 0.5)
				(island_removal_mode 0)
			)
			(polygon
				(pts
					(xy 103.186992 -84.567014) (xy 101.916992 -84.567014) (xy 101.916992 -83.805014) (xy 103.186992 -83.805014)
				)
			)
		)
	)
	(footprint ""
		(layer "B.Cu")
		(at 406.4762 -13.8303 180)
		(property "Reference" "C2T3"
			(at 0 0 0)
			(layer "B.SilkS")
			(hide yes)
			(effects
				(font
					(size 1.27 1.27)
				)
				(justify mirror)
			)
		)
		(property "Value" ""
			(at 0 0 0)
			(layer "B.Fab")
			(effects
				(font
					(size 1.27 1.27)
				)
				(justify mirror)
			)
		)
		(duplicate_pad_numbers_are_jumpers no)
		(fp_poly
			(pts
				(xy -0.3048 -0.1016) (xy -0.3048 0.9906) (xy 0.3048 0.9906) (xy 0.3048 -0.1016)
			)
			(stroke
				(width 0)
				(type default)
			)
			(fill no)
			(layer "B.CrtYd")
		)
		(fp_line
			(start 0.3048 0.9906)
			(end -0.3048 0.9906)
			(stroke
				(width 0.1)
				(type default)
			)
			(layer "B.Fab")
		)
		(fp_line
			(start 0.3048 -0.1016)
			(end 0.3048 0.9906)
			(stroke
				(width 0.1)
				(type default)
			)
			(layer "B.Fab")
		)
		(fp_line
			(start -0.3048 0.9906)
			(end -0.3048 -0.1016)
			(stroke
				(width 0.1)
				(type default)
			)
			(layer "B.Fab")
		)
		(fp_line
			(start -0.3048 -0.1016)
			(end 0.3048 -0.1016)
			(stroke
				(width 0.1)
				(type default)
			)
			(layer "B.Fab")
		)
		(pad "1" smd rect
			(at 0 0)
			(size 0.508 0.508)
			(layers "B.Cu" "B.Mask" "B.Paste")
			(net "P3V3_STBY")
		)
		(pad "2" smd rect
			(at 0 0.889)
			(size 0.508 0.508)
			(layers "B.Cu" "B.Mask" "B.Paste")
			(net "GND")
		)
		(zone
			(layer "B.Cu")
			(hatch none 0.5)
			(connect_pads
				(clearance 0)
			)
			(min_thickness 0.25)
			(keepout
				(tracks not_allowed)
				(vias allowed)
				(pads allowed)
				(copperpour not_allowed)
				(footprints allowed)
			)
			(placement
				(enabled no)
				(sheetname "")
			)
			(fill
				(thermal_gap 0.5)
				(thermal_bridge_width 0.5)
				(island_removal_mode 0)
			)
			(polygon
				(pts
					(xy 406.2222 -14.4653) (xy 406.7302 -14.4653) (xy 406.7302 -14.0843) (xy 406.2222 -14.0843)
				)
			)
		)
		(zone
			(layer "B.Cu")
			(hatch none 0.5)
			(connect_pads
				(clearance 0)
			)
			(min_thickness 0.25)
			(keepout
				(tracks allowed)
				(vias not_allowed)
				(pads allowed)
				(copperpour not_allowed)
				(footprints allowed)
			)
			(placement
				(enabled no)
				(sheetname "")
			)
			(fill
				(thermal_gap 0.5)
				(thermal_bridge_width 0.5)
				(island_removal_mode 0)
			)
			(polygon
				(pts
					(xy 406.2222 -14.0843) (xy 406.7302 -14.0843) (xy 406.7302 -14.4653) (xy 406.2222 -14.4653)
				)
			)
		)
	)
	(footprint ""
		(layer "B.Cu")
		(at 344.522806 -61.257434)
		(property "Reference" "C2U11"
			(at 0 0 0)
			(layer "B.SilkS")
			(hide yes)
			(effects
				(font
					(size 1.27 1.27)
				)
				(justify mirror)
			)
		)
		(property "Value" ""
			(at 0 0 0)
			(layer "B.Fab")
			(effects
				(font
					(size 1.27 1.27)
				)
				(justify mirror)
			)
		)
		(duplicate_pad_numbers_are_jumpers no)
		(fp_poly
			(pts
				(xy -0.3048 -0.1016) (xy -0.3048 0.9906) (xy 0.3048 0.9906) (xy 0.3048 -0.1016)
			)
			(stroke
				(width 0)
				(type default)
			)
			(fill no)
			(layer "B.CrtYd")
		)
		(fp_line
			(start -0.3048 -0.1016)
			(end 0.3048 -0.1016)
			(stroke
				(width 0.1)
				(type default)
			)
			(layer "B.Fab")
		)
		(fp_line
			(start -0.3048 0.9906)
			(end -0.3048 -0.1016)
			(stroke
				(width 0.1)
				(type default)
			)
			(layer "B.Fab")
		)
		(fp_line
			(start 0.3048 -0.1016)
			(end 0.3048 0.9906)
			(stroke
				(width 0.1)
				(type default)
			)
			(layer "B.Fab")
		)
		(fp_line
			(start 0.3048 0.9906)
			(end -0.3048 0.9906)
			(stroke
				(width 0.1)
				(type default)
			)
			(layer "B.Fab")
		)
		(pad "1" smd rect
			(at 0 0 180)
			(size 0.508 0.508)
			(layers "B.Cu" "B.Mask" "B.Paste")
			(net "P3E_CPU0_PE1_PCH_RXP<4>")
		)
		(pad "2" smd rect
			(at 0 0.889 180)
			(size 0.508 0.508)
			(layers "B.Cu" "B.Mask" "B.Paste")
			(net "P3E_CPU0_PE1_SS_RXP<4>")
		)
		(zone
			(layer "B.Cu")
			(hatch none 0.5)
			(connect_pads
				(clearance 0)
			)
			(min_thickness 0.25)
			(keepout
				(tracks allowed)
				(vias not_allowed)
				(pads allowed)
				(copperpour not_allowed)
				(footprints allowed)
			)
			(placement
				(enabled no)
				(sheetname "")
			)
			(fill
				(thermal_gap 0.5)
				(thermal_bridge_width 0.5)
				(island_removal_mode 0)
			)
			(polygon
				(pts
					(xy 344.776806 -61.003434) (xy 344.268806 -61.003434) (xy 344.268806 -60.622434) (xy 344.776806 -60.622434)
				)
			)
		)
	)
	(footprint ""
		(layer "B.Cu")
		(at 370.967 -135.636 180)
		(property "Reference" "C3M22"
			(at 0 0 0)
			(layer "B.SilkS")
			(hide yes)
			(effects
				(font
					(size 1.27 1.27)
				)
				(justify mirror)
			)
		)
		(property "Value" ""
			(at 0 0 0)
			(layer "B.Fab")
			(effects
				(font
					(size 1.27 1.27)
				)
				(justify mirror)
			)
		)
		(duplicate_pad_numbers_are_jumpers no)
		(fp_poly
			(pts
				(xy -0.3048 -0.1016) (xy -0.3048 0.9906) (xy 0.3048 0.9906) (xy 0.3048 -0.1016)
			)
			(stroke
				(width 0)
				(type default)
			)
			(fill no)
			(layer "B.CrtYd")
		)
		(fp_line
			(start 0.3048 0.9906)
			(end -0.3048 0.9906)
			(stroke
				(width 0.1)
				(type default)
			)
			(layer "B.Fab")
		)
		(fp_line
			(start 0.3048 -0.1016)
			(end 0.3048 0.9906)
			(stroke
				(width 0.1)
				(type default)
			)
			(layer "B.Fab")
		)
		(fp_line
			(start -0.3048 0.9906)
			(end -0.3048 -0.1016)
			(stroke
				(width 0.1)
				(type default)
			)
			(layer "B.Fab")
		)
		(fp_line
			(start -0.3048 -0.1016)
			(end 0.3048 -0.1016)
			(stroke
				(width 0.1)
				(type default)
			)
			(layer "B.Fab")
		)
		(pad "1" smd rect
			(at 0 0)
			(size 0.508 0.508)
			(layers "B.Cu" "B.Mask" "B.Paste")
			(net "P1V05_PCH_STBY")
		)
		(pad "2" smd rect
			(at 0 0.889)
			(size 0.508 0.508)
			(layers "B.Cu" "B.Mask" "B.Paste")
			(net "GND")
		)
		(zone
			(layer "B.Cu")
			(hatch none 0.5)
			(connect_pads
				(clearance 0)
			)
			(min_thickness 0.25)
			(keepout
				(tracks not_allowed)
				(vias allowed)
				(pads allowed)
				(copperpour not_allowed)
				(footprints allowed)
			)
			(placement
				(enabled no)
				(sheetname "")
			)
			(fill
				(thermal_gap 0.5)
				(thermal_bridge_width 0.5)
				(island_removal_mode 0)
			)
			(polygon
				(pts
					(xy 370.713 -136.271) (xy 371.221 -136.271) (xy 371.221 -135.89) (xy 370.713 -135.89)
				)
			)
		)
		(zone
			(layer "B.Cu")
			(hatch none 0.5)
			(connect_pads
				(clearance 0)
			)
			(min_thickness 0.25)
			(keepout
				(tracks allowed)
				(vias not_allowed)
				(pads allowed)
				(copperpour not_allowed)
				(footprints allowed)
			)
			(placement
				(enabled no)
				(sheetname "")
			)
			(fill
				(thermal_gap 0.5)
				(thermal_bridge_width 0.5)
				(island_removal_mode 0)
			)
			(polygon
				(pts
					(xy 370.713 -135.89) (xy 371.221 -135.89) (xy 371.221 -136.271) (xy 370.713 -136.271)
				)
			)
		)
	)
	(footprint ""
		(layer "B.Cu")
		(at 344.435176 -77.694536)
		(property "Reference" "C3P19"
			(at 0 0 0)
			(layer "B.SilkS")
			(hide yes)
			(effects
				(font
					(size 1.27 1.27)
				)
				(justify mirror)
			)
		)
		(property "Value" ""
			(at 0 0 0)
			(layer "B.Fab")
			(effects
				(font
					(size 1.27 1.27)
				)
				(justify mirror)
			)
		)
		(duplicate_pad_numbers_are_jumpers no)
		(fp_poly
			(pts
				(xy -0.3048 -0.1016) (xy -0.3048 0.9906) (xy 0.3048 0.9906) (xy 0.3048 -0.1016)
			)
			(stroke
				(width 0)
				(type default)
			)
			(fill no)
			(layer "B.CrtYd")
		)
		(fp_line
			(start -0.3048 -0.1016)
			(end 0.3048 -0.1016)
			(stroke
				(width 0.1)
				(type default)
			)
			(layer "B.Fab")
		)
		(fp_line
			(start -0.3048 0.9906)
			(end -0.3048 -0.1016)
			(stroke
				(width 0.1)
				(type default)
			)
			(layer "B.Fab")
		)
		(fp_line
			(start 0.3048 -0.1016)
			(end 0.3048 0.9906)
			(stroke
				(width 0.1)
				(type default)
			)
			(layer "B.Fab")
		)
		(fp_line
			(start 0.3048 0.9906)
			(end -0.3048 0.9906)
			(stroke
				(width 0.1)
				(type default)
			)
			(layer "B.Fab")
		)
		(pad "1" smd rect
			(at 0 0 180)
			(size 0.508 0.508)
			(layers "B.Cu" "B.Mask" "B.Paste")
			(net "P3E_CPU0_PE1_SS_TXP<2>")
		)
		(pad "2" smd rect
			(at 0 0.889 180)
			(size 0.508 0.508)
			(layers "B.Cu" "B.Mask" "B.Paste")
			(net "P3E_CPU0_PE1_SS_C_TXP<2>")
		)
		(zone
			(layer "B.Cu")
			(hatch none 0.5)
			(connect_pads
				(clearance 0)
			)
			(min_thickness 0.25)
			(keepout
				(tracks allowed)
				(vias not_allowed)
				(pads allowed)
				(copperpour not_allowed)
				(footprints allowed)
			)
			(placement
				(enabled no)
				(sheetname "")
			)
			(fill
				(thermal_gap 0.5)
				(thermal_bridge_width 0.5)
				(island_removal_mode 0)
			)
			(polygon
				(pts
					(xy 344.689176 -77.440536) (xy 344.181176 -77.440536) (xy 344.181176 -77.059536) (xy 344.689176 -77.059536)
				)
			)
		)
	)
	(footprint ""
		(layer "B.Cu")
		(at 30.452568 -17.723612 90)
		(property "Reference" "C9T7"
			(at 0 0 90)
			(layer "B.SilkS")
			(hide yes)
			(effects
				(font
					(size 1.27 1.27)
				)
				(justify mirror)
			)
		)
		(property "Value" ""
			(at 0 0 90)
			(layer "B.Fab")
			(effects
				(font
					(size 1.27 1.27)
				)
				(justify mirror)
			)
		)
		(duplicate_pad_numbers_are_jumpers no)
		(fp_poly
			(pts
				(xy -0.3048 -0.1016) (xy -0.3048 0.9906) (xy 0.3048 0.9906) (xy 0.3048 -0.1016)
			)
			(stroke
				(width 0)
				(type default)
			)
			(fill no)
			(layer "B.CrtYd")
		)
		(fp_line
			(start 0.3048 -0.1016)
			(end 0.3048 0.9906)
			(stroke
				(width 0.1)
				(type default)
			)
			(layer "B.Fab")
		)
		(fp_line
			(start -0.3048 -0.1016)
			(end 0.3048 -0.1016)
			(stroke
				(width 0.1)
				(type default)
			)
			(layer "B.Fab")
		)
		(fp_line
			(start 0.3048 0.9906)
			(end -0.3048 0.9906)
			(stroke
				(width 0.1)
				(type default)
			)
			(layer "B.Fab")
		)
		(fp_line
			(start -0.3048 0.9906)
			(end -0.3048 -0.1016)
			(stroke
				(width 0.1)
				(type default)
			)
			(layer "B.Fab")
		)
		(pad "1" smd rect
			(at 0 0 270)
			(size 0.508 0.508)
			(layers "B.Cu" "B.Mask" "B.Paste")
			(net "M_G_VREF")
		)
		(pad "2" smd rect
			(at 0 0.889 270)
			(size 0.508 0.508)
			(layers "B.Cu" "B.Mask" "B.Paste")
			(net "GND")
		)
		(zone
			(layer "B.Cu")
			(hatch none 0.5)
			(connect_pads
				(clearance 0)
			)
			(min_thickness 0.25)
			(keepout
				(tracks allowed)
				(vias not_allowed)
				(pads allowed)
				(copperpour not_allowed)
				(footprints allowed)
			)
			(placement
				(enabled no)
				(sheetname "")
			)
			(fill
				(thermal_gap 0.5)
				(thermal_bridge_width 0.5)
				(island_removal_mode 0)
			)
			(polygon
				(pts
					(xy 30.706568 -17.977612) (xy 30.706568 -17.469612) (xy 31.087568 -17.469612) (xy 31.087568 -17.977612)
				)
			)
		)
		(zone
			(layer "B.Cu")
			(hatch none 0.5)
			(connect_pads
				(clearance 0)
			)
			(min_thickness 0.25)
			(keepout
				(tracks not_allowed)
				(vias allowed)
				(pads allowed)
				(copperpour not_allowed)
				(footprints allowed)
			)
			(placement
				(enabled no)
				(sheetname "")
			)
			(fill
				(thermal_gap 0.5)
				(thermal_bridge_width 0.5)
				(island_removal_mode 0)
			)
			(polygon
				(pts
					(xy 31.087568 -17.977612) (xy 31.087568 -17.469612) (xy 30.706568 -17.469612) (xy 30.706568 -17.977612)
				)
			)
		)
	)
	(footprint ""
		(layer "B.Cu")
		(at 321.1957 -32.93618 90)
		(property "Reference" "R4T4"
			(at 0 0 90)
			(layer "B.SilkS")
			(hide yes)
			(effects
				(font
					(size 1.27 1.27)
				)
				(justify mirror)
			)
		)
		(property "Value" ""
			(at 0 0 90)
			(layer "B.Fab")
			(effects
				(font
					(size 1.27 1.27)
				)
				(justify mirror)
			)
		)
		(duplicate_pad_numbers_are_jumpers no)
		(fp_poly
			(pts
				(xy 0.2794 -0.1016) (xy -0.2794 -0.1016) (xy -0.2794 0.9906) (xy 0.2794 0.9906)
			)
			(stroke
				(width 0)
				(type default)
			)
			(fill no)
			(layer "B.CrtYd")
		)
		(fp_line
			(start 0.2794 -0.1016)
			(end 0.2794 0.9906)
			(stroke
				(width 0.1)
				(type default)
			)
			(layer "B.Fab")
		)
		(fp_line
			(start -0.2794 -0.1016)
			(end 0.2794 -0.1016)
			(stroke
				(width 0.1)
				(type default)
			)
			(layer "B.Fab")
		)
		(fp_line
			(start 0.2794 0.9906)
			(end -0.2794 0.9906)
			(stroke
				(width 0.1)
				(type default)
			)
			(layer "B.Fab")
		)
		(fp_line
			(start -0.2794 0.9906)
			(end -0.2794 -0.1016)
			(stroke
				(width 0.1)
				(type default)
			)
			(layer "B.Fab")
		)
		(pad "1" smd rect
			(at 0 0 270)
			(size 0.508 0.508)
			(layers "B.Cu" "B.Mask" "B.Paste")
			(net "SMB_DDR_ABC_SDA_G_R")
		)
		(pad "2" smd rect
			(at 0 0.889 270)
			(size 0.508 0.508)
			(layers "B.Cu" "B.Mask" "B.Paste")
			(net "SMB_DDR_ABC_SDA_G")
		)
		(zone
			(layer "B.Cu")
			(hatch none 0.5)
			(connect_pads
				(clearance 0)
			)
			(min_thickness 0.25)
			(keepout
				(tracks allowed)
				(vias not_allowed)
				(pads allowed)
				(copperpour not_allowed)
				(footprints allowed)
			)
			(placement
				(enabled no)
				(sheetname "")
			)
			(fill
				(thermal_gap 0.5)
				(thermal_bridge_width 0.5)
				(island_removal_mode 0)
			)
			(polygon
				(pts
					(xy 321.4497 -33.19018) (xy 321.4497 -32.68218) (xy 321.8307 -32.68218) (xy 321.8307 -33.19018)
				)
			)
		)
		(zone
			(layer "B.Cu")
			(hatch none 0.5)
			(connect_pads
				(clearance 0)
			)
			(min_thickness 0.25)
			(keepout
				(tracks not_allowed)
				(vias allowed)
				(pads allowed)
				(copperpour not_allowed)
				(footprints allowed)
			)
			(placement
				(enabled no)
				(sheetname "")
			)
			(fill
				(thermal_gap 0.5)
				(thermal_bridge_width 0.5)
				(island_removal_mode 0)
			)
			(polygon
				(pts
					(xy 321.8307 -33.19018) (xy 321.8307 -32.68218) (xy 321.4497 -32.68218) (xy 321.4497 -33.19018)
				)
			)
		)
	)
	(footprint ""
		(layer "B.Cu")
		(at 409.3845 -26.035 -90)
		(property "Reference" "C25W69"
			(at -0.97536 0.76708 0)
			(unlocked yes)
			(layer "B.SilkS")
			(effects
				(font
					(size 0.4064 0.254)
					(thickness 0.1524)
				)
				(justify mirror)
			)
		)
		(property "Value" ""
			(at 0 0 90)
			(layer "B.Fab")
			(effects
				(font
					(size 1.27 1.27)
				)
				(justify mirror)
			)
		)
		(duplicate_pad_numbers_are_jumpers no)
		(fp_poly
			(pts
				(xy 0.4953 -0.2032) (xy -0.4953 -0.2032) (xy -0.4953 1.6002) (xy 0.4953 1.6002)
			)
			(stroke
				(width 0)
				(type default)
			)
			(fill no)
			(layer "B.CrtYd")
		)
		(fp_line
			(start -0.4953 1.6002)
			(end 0.4953 1.6002)
			(stroke
				(width 0.1)
				(type default)
			)
			(layer "B.Fab")
		)
		(fp_line
			(start 0.4953 1.6002)
			(end 0.4953 -0.2032)
			(stroke
				(width 0.1)
				(type default)
			)
			(layer "B.Fab")
		)
		(fp_line
			(start -0.4953 -0.2032)
			(end -0.4953 1.6002)
			(stroke
				(width 0.1)
				(type default)
			)
			(layer "B.Fab")
		)
		(fp_line
			(start 0.4953 -0.2032)
			(end -0.4953 -0.2032)
			(stroke
				(width 0.1)
				(type default)
			)
			(layer "B.Fab")
		)
		(pad "1" smd rect
			(at 0 0 90)
			(size 0.762 0.889)
			(layers "B.Cu" "B.Mask" "B.Paste")
			(net "VCC_VA_3V3")
		)
		(pad "2" smd rect
			(at 0 1.397 90)
			(size 0.762 0.889)
			(layers "B.Cu" "B.Mask" "B.Paste")
			(net "GND")
		)
		(zone
			(layer "B.Cu")
			(hatch none 0.5)
			(connect_pads
				(clearance 0)
			)
			(min_thickness 0.25)
			(keepout
				(tracks not_allowed)
				(vias allowed)
				(pads allowed)
				(copperpour not_allowed)
				(footprints allowed)
			)
			(placement
				(enabled no)
				(sheetname "")
			)
			(fill
				(thermal_gap 0.5)
				(thermal_bridge_width 0.5)
				(island_removal_mode 0)
			)
			(polygon
				(pts
					(xy 408.94 -25.654) (xy 408.94 -26.416) (xy 408.432 -26.416) (xy 408.432 -25.654)
				)
			)
		)
	)
	(footprint ""
		(layer "B.Cu")
		(at 496.529614 -47.605696 -90)
		(property "Reference" "R25W132"
			(at 0.8382 -0.67818 270)
			(unlocked yes)
			(layer "B.SilkS")
			(effects
				(font
					(size 0.4064 0.254)
					(thickness 0.1524)
				)
				(justify left mirror)
			)
		)
		(property "Value" ""
			(at 0 0 90)
			(layer "B.Fab")
			(effects
				(font
					(size 1.27 1.27)
				)
				(justify mirror)
			)
		)
		(duplicate_pad_numbers_are_jumpers no)
		(fp_poly
			(pts
				(xy 0.2794 -0.1016) (xy -0.2794 -0.1016) (xy -0.2794 0.9906) (xy 0.2794 0.9906)
			)
			(stroke
				(width 0)
				(type default)
			)
			(fill no)
			(layer "B.CrtYd")
		)
		(fp_line
			(start -0.2794 0.9906)
			(end -0.2794 -0.1016)
			(stroke
				(width 0.1)
				(type default)
			)
			(layer "B.Fab")
		)
		(fp_line
			(start 0.2794 0.9906)
			(end -0.2794 0.9906)
			(stroke
				(width 0.1)
				(type default)
			)
			(layer "B.Fab")
		)
		(fp_line
			(start -0.2794 -0.1016)
			(end 0.2794 -0.1016)
			(stroke
				(width 0.1)
				(type default)
			)
			(layer "B.Fab")
		)
		(fp_line
			(start 0.2794 -0.1016)
			(end 0.2794 0.9906)
			(stroke
				(width 0.1)
				(type default)
			)
			(layer "B.Fab")
		)
		(pad "1" smd rect
			(at 0 0 90)
			(size 0.508 0.508)
			(layers "B.Cu" "B.Mask" "B.Paste")
			(net "P5V_VGA_D")
		)
		(pad "2" smd rect
			(at 0 0.889 90)
			(size 0.508 0.508)
			(layers "B.Cu" "B.Mask" "B.Paste")
			(net "I2C_BMC_VGA_DDC_SCL_G")
		)
		(zone
			(layer "B.Cu")
			(hatch none 0.5)
			(connect_pads
				(clearance 0)
			)
			(min_thickness 0.25)
			(keepout
				(tracks not_allowed)
				(vias allowed)
				(pads allowed)
				(copperpour not_allowed)
				(footprints allowed)
			)
			(placement
				(enabled no)
				(sheetname "")
			)
			(fill
				(thermal_gap 0.5)
				(thermal_bridge_width 0.5)
				(island_removal_mode 0)
			)
			(polygon
				(pts
					(xy 495.894614 -47.351696) (xy 495.894614 -47.859696) (xy 496.275614 -47.859696) (xy 496.275614 -47.351696)
				)
			)
		)
		(zone
			(layer "B.Cu")
			(hatch none 0.5)
			(connect_pads
				(clearance 0)
			)
			(min_thickness 0.25)
			(keepout
				(tracks allowed)
				(vias not_allowed)
				(pads allowed)
				(copperpour not_allowed)
				(footprints allowed)
			)
			(placement
				(enabled no)
				(sheetname "")
			)
			(fill
				(thermal_gap 0.5)
				(thermal_bridge_width 0.5)
				(island_removal_mode 0)
			)
			(polygon
				(pts
					(xy 496.275614 -47.351696) (xy 496.275614 -47.859696) (xy 495.894614 -47.859696) (xy 495.894614 -47.351696)
				)
			)
		)
	)
	(footprint ""
		(layer "B.Cu")
		(at 467.791038 -6.858 90)
		(property "Reference" "C2U25"
			(at 0 0 90)
			(layer "B.SilkS")
			(hide yes)
			(effects
				(font
					(size 1.27 1.27)
				)
				(justify mirror)
			)
		)
		(property "Value" ""
			(at 0 0 90)
			(layer "B.Fab")
			(effects
				(font
					(size 1.27 1.27)
				)
				(justify mirror)
			)
		)
		(duplicate_pad_numbers_are_jumpers no)
		(fp_poly
			(pts
				(xy -0.3048 -0.1016) (xy -0.3048 0.9906) (xy 0.3048 0.9906) (xy 0.3048 -0.1016)
			)
			(stroke
				(width 0)
				(type default)
			)
			(fill no)
			(layer "B.CrtYd")
		)
		(fp_line
			(start 0.3048 -0.1016)
			(end 0.3048 0.9906)
			(stroke
				(width 0.1)
				(type default)
			)
			(layer "B.Fab")
		)
		(fp_line
			(start -0.3048 -0.1016)
			(end 0.3048 -0.1016)
			(stroke
				(width 0.1)
				(type default)
			)
			(layer "B.Fab")
		)
		(fp_line
			(start 0.3048 0.9906)
			(end -0.3048 0.9906)
			(stroke
				(width 0.1)
				(type default)
			)
			(layer "B.Fab")
		)
		(fp_line
			(start -0.3048 0.9906)
			(end -0.3048 -0.1016)
			(stroke
				(width 0.1)
				(type default)
			)
			(layer "B.Fab")
		)
		(pad "1" smd rect
			(at 0 0 270)
			(size 0.508 0.508)
			(layers "B.Cu" "B.Mask" "B.Paste")
			(net "P3V3")
		)
		(pad "2" smd rect
			(at 0 0.889 270)
			(size 0.508 0.508)
			(layers "B.Cu" "B.Mask" "B.Paste")
			(net "GND")
		)
		(zone
			(layer "B.Cu")
			(hatch none 0.5)
			(connect_pads
				(clearance 0)
			)
			(min_thickness 0.25)
			(keepout
				(tracks allowed)
				(vias not_allowed)
				(pads allowed)
				(copperpour not_allowed)
				(footprints allowed)
			)
			(placement
				(enabled no)
				(sheetname "")
			)
			(fill
				(thermal_gap 0.5)
				(thermal_bridge_width 0.5)
				(island_removal_mode 0)
			)
			(polygon
				(pts
					(xy 468.045038 -7.112) (xy 468.045038 -6.604) (xy 468.426038 -6.604) (xy 468.426038 -7.112)
				)
			)
		)
		(zone
			(layer "B.Cu")
			(hatch none 0.5)
			(connect_pads
				(clearance 0)
			)
			(min_thickness 0.25)
			(keepout
				(tracks not_allowed)
				(vias allowed)
				(pads allowed)
				(copperpour not_allowed)
				(footprints allowed)
			)
			(placement
				(enabled no)
				(sheetname "")
			)
			(fill
				(thermal_gap 0.5)
				(thermal_bridge_width 0.5)
				(island_removal_mode 0)
			)
			(polygon
				(pts
					(xy 468.426038 -7.112) (xy 468.426038 -6.604) (xy 468.045038 -6.604) (xy 468.045038 -7.112)
				)
			)
		)
	)
	(footprint ""
		(layer "B.Cu")
		(at 454.4822 -42.545 180)
		(property "Reference" "R25W145"
			(at 0.8382 -0.67818 180)
			(unlocked yes)
			(layer "B.SilkS")
			(effects
				(font
					(size 0.4064 0.254)
					(thickness 0.1524)
				)
				(justify left mirror)
			)
		)
		(property "Value" ""
			(at 0 0 0)
			(layer "B.Fab")
			(effects
				(font
					(size 1.27 1.27)
				)
				(justify mirror)
			)
		)
		(duplicate_pad_numbers_are_jumpers no)
		(fp_poly
			(pts
				(xy 0.2794 -0.1016) (xy -0.2794 -0.1016) (xy -0.2794 0.9906) (xy 0.2794 0.9906)
			)
			(stroke
				(width 0)
				(type default)
			)
			(fill no)
			(layer "B.CrtYd")
		)
		(fp_line
			(start 0.2794 0.9906)
			(end -0.2794 0.9906)
			(stroke
				(width 0.1)
				(type default)
			)
			(layer "B.Fab")
		)
		(fp_line
			(start 0.2794 -0.1016)
			(end 0.2794 0.9906)
			(stroke
				(width 0.1)
				(type default)
			)
			(layer "B.Fab")
		)
		(fp_line
			(start -0.2794 0.9906)
			(end -0.2794 -0.1016)
			(stroke
				(width 0.1)
				(type default)
			)
			(layer "B.Fab")
		)
		(fp_line
			(start -0.2794 -0.1016)
			(end 0.2794 -0.1016)
			(stroke
				(width 0.1)
				(type default)
			)
			(layer "B.Fab")
		)
		(pad "1" smd rect
			(at 0 0)
			(size 0.508 0.508)
			(layers "B.Cu" "B.Mask" "B.Paste")
			(net "RST_SYSTEM_BTN_R_N")
		)
		(pad "2" smd rect
			(at 0 0.889)
			(size 0.508 0.508)
			(layers "B.Cu" "B.Mask" "B.Paste")
			(net "RST_SYSTEM_BTN_N")
		)
		(zone
			(layer "B.Cu")
			(hatch none 0.5)
			(connect_pads
				(clearance 0)
			)
			(min_thickness 0.25)
			(keepout
				(tracks not_allowed)
				(vias allowed)
				(pads allowed)
				(copperpour not_allowed)
				(footprints allowed)
			)
			(placement
				(enabled no)
				(sheetname "")
			)
			(fill
				(thermal_gap 0.5)
				(thermal_bridge_width 0.5)
				(island_removal_mode 0)
			)
			(polygon
				(pts
					(xy 454.2282 -43.18) (xy 454.7362 -43.18) (xy 454.7362 -42.799) (xy 454.2282 -42.799)
				)
			)
		)
		(zone
			(layer "B.Cu")
			(hatch none 0.5)
			(connect_pads
				(clearance 0)
			)
			(min_thickness 0.25)
			(keepout
				(tracks allowed)
				(vias not_allowed)
				(pads allowed)
				(copperpour not_allowed)
				(footprints allowed)
			)
			(placement
				(enabled no)
				(sheetname "")
			)
			(fill
				(thermal_gap 0.5)
				(thermal_bridge_width 0.5)
				(island_removal_mode 0)
			)
			(polygon
				(pts
					(xy 454.2282 -42.799) (xy 454.7362 -42.799) (xy 454.7362 -43.18) (xy 454.2282 -43.18)
				)
			)
		)
	)
	(footprint ""
		(layer "B.Cu")
		(at 413.639 -6.1976 180)
		(property "Reference" "Q1P2"
			(at 0.229362 -1.2065 180)
			(unlocked yes)
			(layer "B.SilkS")
			(effects
				(font
					(size 0.4064 0.254)
					(thickness 0.1524)
				)
				(justify left mirror)
			)
		)
		(property "Value" ""
			(at 0 0 0)
			(layer "B.Fab")
			(effects
				(font
					(size 1.27 1.27)
				)
				(justify mirror)
			)
		)
		(duplicate_pad_numbers_are_jumpers no)
		(fp_line
			(start -0.381 0.635)
			(end -0.381 1.27)
			(stroke
				(width 0.1524)
				(type default)
			)
			(layer "B.SilkS")
		)
		(fp_line
			(start -0.9525 2.4765)
			(end -1.778 2.4765)
			(stroke
				(width 0.1524)
				(type default)
			)
			(layer "B.SilkS")
		)
		(fp_line
			(start -0.9525 -0.5715)
			(end -1.778 -0.5715)
			(stroke
				(width 0.1524)
				(type default)
			)
			(layer "B.SilkS")
		)
		(fp_line
			(start -1.778 2.4765)
			(end -1.778 1.5875)
			(stroke
				(width 0.1524)
				(type default)
			)
			(layer "B.SilkS")
		)
		(fp_line
			(start -1.778 -0.5715)
			(end -1.778 0.3175)
			(stroke
				(width 0.1524)
				(type default)
			)
			(layer "B.SilkS")
		)
		(fp_circle
			(center 0.9525 -0.9271)
			(end 0.8255 -0.9271)
			(stroke
				(width 0.254)
				(type default)
			)
			(fill no)
			(layer "B.SilkS")
		)
		(fp_poly
			(pts
				(xy -1.778 2.4765) (xy -0.381 2.4765) (xy -0.381 -0.5715) (xy -1.778 -0.5715)
			)
			(stroke
				(width 0)
				(type default)
			)
			(fill no)
			(layer "B.CrtYd")
		)
		(fp_line
			(start -0.381 2.4765)
			(end -1.778 2.4765)
			(stroke
				(width 0.1)
				(type default)
			)
			(layer "B.Fab")
		)
		(fp_line
			(start -0.381 -0.5715)
			(end -0.381 2.4765)
			(stroke
				(width 0.1)
				(type default)
			)
			(layer "B.Fab")
		)
		(fp_line
			(start -1.778 2.4765)
			(end -1.778 -0.5715)
			(stroke
				(width 0.1)
				(type default)
			)
			(layer "B.Fab")
		)
		(fp_line
			(start -1.778 -0.5715)
			(end -0.381 -0.5715)
			(stroke
				(width 0.1)
				(type default)
			)
			(layer "B.Fab")
		)
		(fp_circle
			(center 0.9525 -0.9271)
			(end 0.8255 -0.9271)
			(stroke
				(width 0.254)
				(type default)
			)
			(fill no)
			(layer "B.Fab")
		)
		(pad "1" smd rect
			(at 0 0)
			(size 1.143 0.508)
			(layers "B.Cu" "B.Mask" "B.Paste")
			(net "PWRGD_P5V_N")
		)
		(pad "2" smd rect
			(at 0 1.905)
			(size 1.143 0.508)
			(layers "B.Cu" "B.Mask" "B.Paste")
			(net "GND")
		)
		(pad "3" smd rect
			(at -2.159 0.9525)
			(size 1.143 0.508)
			(layers "B.Cu" "B.Mask" "B.Paste")
			(net "PWRGD_P5V_R")
		)
	)
	(footprint ""
		(layer "B.Cu")
		(at 452.8058 -153.6446 180)
		(property "Reference" "R9A3"
			(at 0 0 0)
			(layer "B.SilkS")
			(hide yes)
			(effects
				(font
					(size 1.27 1.27)
				)
				(justify mirror)
			)
		)
		(property "Value" ""
			(at 0 0 0)
			(layer "B.Fab")
			(effects
				(font
					(size 1.27 1.27)
				)
				(justify mirror)
			)
		)
		(duplicate_pad_numbers_are_jumpers no)
		(fp_poly
			(pts
				(xy 0.2794 -0.1016) (xy -0.2794 -0.1016) (xy -0.2794 0.9906) (xy 0.2794 0.9906)
			)
			(stroke
				(width 0)
				(type default)
			)
			(fill no)
			(layer "B.CrtYd")
		)
		(fp_line
			(start 0.2794 0.9906)
			(end -0.2794 0.9906)
			(stroke
				(width 0.1)
				(type default)
			)
			(layer "B.Fab")
		)
		(fp_line
			(start 0.2794 -0.1016)
			(end 0.2794 0.9906)
			(stroke
				(width 0.1)
				(type default)
			)
			(layer "B.Fab")
		)
		(fp_line
			(start -0.2794 0.9906)
			(end -0.2794 -0.1016)
			(stroke
				(width 0.1)
				(type default)
			)
			(layer "B.Fab")
		)
		(fp_line
			(start -0.2794 -0.1016)
			(end 0.2794 -0.1016)
			(stroke
				(width 0.1)
				(type default)
			)
			(layer "B.Fab")
		)
		(pad "1" smd rect
			(at 0 0)
			(size 0.508 0.508)
			(layers "B.Cu" "B.Mask" "B.Paste")
			(net "XDP_PCH_CPU_TCK0")
		)
		(pad "2" smd rect
			(at 0 0.889)
			(size 0.508 0.508)
			(layers "B.Cu" "B.Mask" "B.Paste")
			(net "XDP_CPU_TCK0")
		)
		(zone
			(layer "B.Cu")
			(hatch none 0.5)
			(connect_pads
				(clearance 0)
			)
			(min_thickness 0.25)
			(keepout
				(tracks not_allowed)
				(vias allowed)
				(pads allowed)
				(copperpour not_allowed)
				(footprints allowed)
			)
			(placement
				(enabled no)
				(sheetname "")
			)
			(fill
				(thermal_gap 0.5)
				(thermal_bridge_width 0.5)
				(island_removal_mode 0)
			)
			(polygon
				(pts
					(xy 452.5518 -154.2796) (xy 453.0598 -154.2796) (xy 453.0598 -153.8986) (xy 452.5518 -153.8986)
				)
			)
		)
		(zone
			(layer "B.Cu")
			(hatch none 0.5)
			(connect_pads
				(clearance 0)
			)
			(min_thickness 0.25)
			(keepout
				(tracks allowed)
				(vias not_allowed)
				(pads allowed)
				(copperpour not_allowed)
				(footprints allowed)
			)
			(placement
				(enabled no)
				(sheetname "")
			)
			(fill
				(thermal_gap 0.5)
				(thermal_bridge_width 0.5)
				(island_removal_mode 0)
			)
			(polygon
				(pts
					(xy 452.5518 -153.8986) (xy 453.0598 -153.8986) (xy 453.0598 -154.2796) (xy 452.5518 -154.2796)
				)
			)
		)
	)
	(footprint ""
		(layer "B.Cu")
		(at 165.8874 2.286 -90)
		(property "Reference" "R6U14"
			(at 0 0 90)
			(layer "B.SilkS")
			(hide yes)
			(effects
				(font
					(size 1.27 1.27)
				)
				(justify mirror)
			)
		)
		(property "Value" ""
			(at 0 0 90)
			(layer "B.Fab")
			(effects
				(font
					(size 1.27 1.27)
				)
				(justify mirror)
			)
		)
		(duplicate_pad_numbers_are_jumpers no)
		(fp_poly
			(pts
				(xy 0.2794 -0.1016) (xy -0.2794 -0.1016) (xy -0.2794 0.9906) (xy 0.2794 0.9906)
			)
			(stroke
				(width 0)
				(type default)
			)
			(fill no)
			(layer "B.CrtYd")
		)
		(fp_line
			(start -0.2794 0.9906)
			(end -0.2794 -0.1016)
			(stroke
				(width 0.1)
				(type default)
			)
			(layer "B.Fab")
		)
		(fp_line
			(start 0.2794 0.9906)
			(end -0.2794 0.9906)
			(stroke
				(width 0.1)
				(type default)
			)
			(layer "B.Fab")
		)
		(fp_line
			(start -0.2794 -0.1016)
			(end 0.2794 -0.1016)
			(stroke
				(width 0.1)
				(type default)
			)
			(layer "B.Fab")
		)
		(fp_line
			(start 0.2794 -0.1016)
			(end 0.2794 0.9906)
			(stroke
				(width 0.1)
				(type default)
			)
			(layer "B.Fab")
		)
		(pad "1" smd rect
			(at 0 0 90)
			(size 0.508 0.508)
			(layers "B.Cu" "B.Mask" "B.Paste")
			(net "SMB_DDR_GHJ_VPP_SDA_R")
		)
		(pad "2" smd rect
			(at 0 0.889 90)
			(size 0.508 0.508)
			(layers "B.Cu" "B.Mask" "B.Paste")
			(net "SMB_DDR_GHJ_VPP_SDA")
		)
		(zone
			(layer "B.Cu")
			(hatch none 0.5)
			(connect_pads
				(clearance 0)
			)
			(min_thickness 0.25)
			(keepout
				(tracks not_allowed)
				(vias allowed)
				(pads allowed)
				(copperpour not_allowed)
				(footprints allowed)
			)
			(placement
				(enabled no)
				(sheetname "")
			)
			(fill
				(thermal_gap 0.5)
				(thermal_bridge_width 0.5)
				(island_removal_mode 0)
			)
			(polygon
				(pts
					(xy 165.2524 2.54) (xy 165.2524 2.032) (xy 165.6334 2.032) (xy 165.6334 2.54)
				)
			)
		)
		(zone
			(layer "B.Cu")
			(hatch none 0.5)
			(connect_pads
				(clearance 0)
			)
			(min_thickness 0.25)
			(keepout
				(tracks allowed)
				(vias not_allowed)
				(pads allowed)
				(copperpour not_allowed)
				(footprints allowed)
			)
			(placement
				(enabled no)
				(sheetname "")
			)
			(fill
				(thermal_gap 0.5)
				(thermal_bridge_width 0.5)
				(island_removal_mode 0)
			)
			(polygon
				(pts
					(xy 165.6334 2.54) (xy 165.6334 2.032) (xy 165.2524 2.032) (xy 165.2524 2.54)
				)
			)
		)
	)
	(footprint ""
		(layer "B.Cu")
		(at 372.11 -135.1661 -90)
		(property "Reference" "FB3M2"
			(at 0 0 90)
			(layer "B.SilkS")
			(hide yes)
			(effects
				(font
					(size 1.27 1.27)
				)
				(justify mirror)
			)
		)
		(property "Value" ""
			(at 0 0 90)
			(layer "B.Fab")
			(effects
				(font
					(size 1.27 1.27)
				)
				(justify mirror)
			)
		)
		(duplicate_pad_numbers_are_jumpers no)
		(fp_poly
			(pts
				(xy 0.15113 -0.47498) (xy -1.59893 -0.47498) (xy -1.59893 0.47498) (xy 0.15113 0.47498)
			)
			(stroke
				(width 0)
				(type default)
			)
			(fill no)
			(layer "B.CrtYd")
		)
		(fp_line
			(start -1.59893 0.47498)
			(end 0.15113 0.47498)
			(stroke
				(width 0.1)
				(type default)
			)
			(layer "B.Fab")
		)
		(fp_line
			(start 0.15113 0.47498)
			(end 0.15113 -0.47498)
			(stroke
				(width 0.1)
				(type default)
			)
			(layer "B.Fab")
		)
		(fp_line
			(start -1.59893 -0.47498)
			(end -1.59893 0.47498)
			(stroke
				(width 0.1)
				(type default)
			)
			(layer "B.Fab")
		)
		(fp_line
			(start 0.15113 -0.47498)
			(end -1.59893 -0.47498)
			(stroke
				(width 0.1)
				(type default)
			)
			(layer "B.Fab")
		)
		(pad "1" smd rect
			(at 0 0 90)
			(size 0.9398 0.9398)
			(layers "B.Cu" "B.Mask" "B.Paste")
			(net "P1V05_PCH_STBY")
		)
		(pad "2" smd rect
			(at -1.4478 0 90)
			(size 0.9398 0.9398)
			(layers "B.Cu" "B.Mask" "B.Paste")
			(net "P1V05_PCH_STBY_VCCA_PLL0")
		)
		(zone
			(layer "B.Cu")
			(hatch none 0.5)
			(connect_pads
				(clearance 0)
			)
			(min_thickness 0.25)
			(keepout
				(tracks allowed)
				(vias not_allowed)
				(pads allowed)
				(copperpour not_allowed)
				(footprints allowed)
			)
			(placement
				(enabled no)
				(sheetname "")
			)
			(fill
				(thermal_gap 0.5)
				(thermal_bridge_width 0.5)
				(island_removal_mode 0)
			)
			(polygon
				(pts
					(xy 371.6401 -135.636) (xy 372.5799 -135.636) (xy 372.5799 -136.144) (xy 371.6401 -136.144)
				)
			)
		)
		(zone
			(layer "B.Cu")
			(hatch none 0.5)
			(connect_pads
				(clearance 0)
			)
			(min_thickness 0.25)
			(keepout
				(tracks not_allowed)
				(vias allowed)
				(pads allowed)
				(copperpour not_allowed)
				(footprints allowed)
			)
			(placement
				(enabled no)
				(sheetname "")
			)
			(fill
				(thermal_gap 0.5)
				(thermal_bridge_width 0.5)
				(island_removal_mode 0)
			)
			(polygon
				(pts
					(xy 371.6401 -135.636) (xy 372.5799 -135.636) (xy 372.5799 -136.144) (xy 371.6401 -136.144)
				)
			)
		)
	)
	(footprint ""
		(layer "B.Cu")
		(at 331.343 -11.7094)
		(property "Reference" "R4U1"
			(at 0 0 0)
			(layer "B.SilkS")
			(hide yes)
			(effects
				(font
					(size 1.27 1.27)
				)
				(justify mirror)
			)
		)
		(property "Value" ""
			(at 0 0 0)
			(layer "B.Fab")
			(effects
				(font
					(size 1.27 1.27)
				)
				(justify mirror)
			)
		)
		(duplicate_pad_numbers_are_jumpers no)
		(fp_poly
			(pts
				(xy 0.2794 -0.1016) (xy -0.2794 -0.1016) (xy -0.2794 0.9906) (xy 0.2794 0.9906)
			)
			(stroke
				(width 0)
				(type default)
			)
			(fill no)
			(layer "B.CrtYd")
		)
		(fp_line
			(start -0.2794 -0.1016)
			(end 0.2794 -0.1016)
			(stroke
				(width 0.1)
				(type default)
			)
			(layer "B.Fab")
		)
		(fp_line
			(start -0.2794 0.9906)
			(end -0.2794 -0.1016)
			(stroke
				(width 0.1)
				(type default)
			)
			(layer "B.Fab")
		)
		(fp_line
			(start 0.2794 -0.1016)
			(end 0.2794 0.9906)
			(stroke
				(width 0.1)
				(type default)
			)
			(layer "B.Fab")
		)
		(fp_line
			(start 0.2794 0.9906)
			(end -0.2794 0.9906)
			(stroke
				(width 0.1)
				(type default)
			)
			(layer "B.Fab")
		)
		(pad "1" smd rect
			(at 0 0 180)
			(size 0.508 0.508)
			(layers "B.Cu" "B.Mask" "B.Paste")
			(net "P3V3_STBY")
		)
		(pad "2" smd rect
			(at 0 0.889 180)
			(size 0.508 0.508)
			(layers "B.Cu" "B.Mask" "B.Paste")
			(net "FM_MEM_THERM_EVENT_LVT3_N")
		)
		(zone
			(layer "B.Cu")
			(hatch none 0.5)
			(connect_pads
				(clearance 0)
			)
			(min_thickness 0.25)
			(keepout
				(tracks allowed)
				(vias not_allowed)
				(pads allowed)
				(copperpour not_allowed)
				(footprints allowed)
			)
			(placement
				(enabled no)
				(sheetname "")
			)
			(fill
				(thermal_gap 0.5)
				(thermal_bridge_width 0.5)
				(island_removal_mode 0)
			)
			(polygon
				(pts
					(xy 331.597 -11.4554) (xy 331.089 -11.4554) (xy 331.089 -11.0744) (xy 331.597 -11.0744)
				)
			)
		)
		(zone
			(layer "B.Cu")
			(hatch none 0.5)
			(connect_pads
				(clearance 0)
			)
			(min_thickness 0.25)
			(keepout
				(tracks not_allowed)
				(vias allowed)
				(pads allowed)
				(copperpour not_allowed)
				(footprints allowed)
			)
			(placement
				(enabled no)
				(sheetname "")
			)
			(fill
				(thermal_gap 0.5)
				(thermal_bridge_width 0.5)
				(island_removal_mode 0)
			)
			(polygon
				(pts
					(xy 331.597 -11.0744) (xy 331.089 -11.0744) (xy 331.089 -11.4554) (xy 331.597 -11.4554)
				)
			)
		)
	)
	(footprint ""
		(layer "B.Cu")
		(at 449.199 -116.49202)
		(property "Reference" "C1M17"
			(at 0 0 0)
			(layer "B.SilkS")
			(hide yes)
			(effects
				(font
					(size 1.27 1.27)
				)
				(justify mirror)
			)
		)
		(property "Value" ""
			(at 0 0 0)
			(layer "B.Fab")
			(effects
				(font
					(size 1.27 1.27)
				)
				(justify mirror)
			)
		)
		(duplicate_pad_numbers_are_jumpers no)
		(fp_rect
			(start -0.3048 0.9906)
			(end 0.3048 -0.1016)
			(stroke
				(width 0)
				(type default)
			)
			(fill no)
			(layer "B.CrtYd")
		)
		(fp_line
			(start -0.3048 -0.1016)
			(end 0.3048 -0.1016)
			(stroke
				(width 0.1)
				(type default)
			)
			(layer "B.Fab")
		)
		(fp_line
			(start -0.3048 0.9906)
			(end -0.3048 -0.1016)
			(stroke
				(width 0.1)
				(type default)
			)
			(layer "B.Fab")
		)
		(fp_line
			(start 0.3048 -0.1016)
			(end 0.3048 0.9906)
			(stroke
				(width 0.1)
				(type default)
			)
			(layer "B.Fab")
		)
		(fp_line
			(start 0.3048 0.9906)
			(end -0.3048 0.9906)
			(stroke
				(width 0.1)
				(type default)
			)
			(layer "B.Fab")
		)
		(pad "1" smd rect
			(at 0 0 180)
			(size 0.508 0.508)
			(layers "B.Cu" "B.Mask" "B.Paste")
			(net "P3E_CPU0_PE3_OCP_TXN<10>")
		)
		(pad "2" smd rect
			(at 0 0.889 180)
			(size 0.508 0.508)
			(layers "B.Cu" "B.Mask" "B.Paste")
			(net "P3E_OCP_CPU0_PE3_C_TXN<10>")
		)
		(zone
			(layer "B.Cu")
			(hatch none 0.5)
			(connect_pads
				(clearance 0)
			)
			(min_thickness 0.25)
			(keepout
				(tracks allowed)
				(vias not_allowed)
				(pads allowed)
				(copperpour not_allowed)
				(footprints allowed)
			)
			(placement
				(enabled no)
				(sheetname "")
			)
			(fill
				(thermal_gap 0.5)
				(thermal_bridge_width 0.5)
				(island_removal_mode 0)
			)
			(polygon
				(pts
					(xy 448.945 -115.85702) (xy 449.453 -115.85702) (xy 449.453 -116.23802) (xy 448.945 -116.23802)
				)
			)
		)
		(zone
			(layer "B.Cu")
			(hatch none 0.5)
			(connect_pads
				(clearance 0)
			)
			(min_thickness 0.25)
			(keepout
				(tracks not_allowed)
				(vias allowed)
				(pads allowed)
				(copperpour not_allowed)
				(footprints allowed)
			)
			(placement
				(enabled no)
				(sheetname "")
			)
			(fill
				(thermal_gap 0.5)
				(thermal_bridge_width 0.5)
				(island_removal_mode 0)
			)
			(polygon
				(pts
					(xy 448.945 -115.85702) (xy 449.453 -115.85702) (xy 449.453 -116.23802) (xy 448.945 -116.23802)
				)
			)
		)
	)
	(footprint ""
		(layer "B.Cu")
		(at 440.4233 -147.956016 180)
		(property "Reference" "R25W169"
			(at 0.8382 -0.67818 180)
			(unlocked yes)
			(layer "B.SilkS")
			(effects
				(font
					(size 0.4064 0.254)
					(thickness 0.1524)
				)
				(justify left mirror)
			)
		)
		(property "Value" ""
			(at 0 0 0)
			(layer "B.Fab")
			(effects
				(font
					(size 1.27 1.27)
				)
				(justify mirror)
			)
		)
		(duplicate_pad_numbers_are_jumpers no)
		(fp_poly
			(pts
				(xy 0.2794 -0.1016) (xy -0.2794 -0.1016) (xy -0.2794 0.9906) (xy 0.2794 0.9906)
			)
			(stroke
				(width 0)
				(type default)
			)
			(fill no)
			(layer "B.CrtYd")
		)
		(fp_line
			(start 0.2794 0.9906)
			(end -0.2794 0.9906)
			(stroke
				(width 0.1)
				(type default)
			)
			(layer "B.Fab")
		)
		(fp_line
			(start 0.2794 -0.1016)
			(end 0.2794 0.9906)
			(stroke
				(width 0.1)
				(type default)
			)
			(layer "B.Fab")
		)
		(fp_line
			(start -0.2794 0.9906)
			(end -0.2794 -0.1016)
			(stroke
				(width 0.1)
				(type default)
			)
			(layer "B.Fab")
		)
		(fp_line
			(start -0.2794 -0.1016)
			(end 0.2794 -0.1016)
			(stroke
				(width 0.1)
				(type default)
			)
			(layer "B.Fab")
		)
		(pad "1" smd rect
			(at 0 0)
			(size 0.508 0.508)
			(layers "B.Cu" "B.Mask" "B.Paste")
			(net "JTAG_BMC_TCK1")
		)
		(pad "2" smd rect
			(at 0 0.889)
			(size 0.508 0.508)
			(layers "B.Cu" "B.Mask" "B.Paste")
			(net "GND")
		)
		(zone
			(layer "B.Cu")
			(hatch none 0.5)
			(connect_pads
				(clearance 0)
			)
			(min_thickness 0.25)
			(keepout
				(tracks not_allowed)
				(vias allowed)
				(pads allowed)
				(copperpour not_allowed)
				(footprints allowed)
			)
			(placement
				(enabled no)
				(sheetname "")
			)
			(fill
				(thermal_gap 0.5)
				(thermal_bridge_width 0.5)
				(island_removal_mode 0)
			)
			(polygon
				(pts
					(xy 440.1693 -148.591016) (xy 440.6773 -148.591016) (xy 440.6773 -148.210016) (xy 440.1693 -148.210016)
				)
			)
		)
		(zone
			(layer "B.Cu")
			(hatch none 0.5)
			(connect_pads
				(clearance 0)
			)
			(min_thickness 0.25)
			(keepout
				(tracks allowed)
				(vias not_allowed)
				(pads allowed)
				(copperpour not_allowed)
				(footprints allowed)
			)
			(placement
				(enabled no)
				(sheetname "")
			)
			(fill
				(thermal_gap 0.5)
				(thermal_bridge_width 0.5)
				(island_removal_mode 0)
			)
			(polygon
				(pts
					(xy 440.1693 -148.210016) (xy 440.6773 -148.210016) (xy 440.6773 -148.591016) (xy 440.1693 -148.591016)
				)
			)
		)
	)
	(footprint ""
		(layer "B.Cu")
		(at 377.698 -20.32 180)
		(property "Reference" "RN8F4"
			(at 0.8382 -0.67818 180)
			(unlocked yes)
			(layer "B.SilkS")
			(effects
				(font
					(size 0.4064 0.254)
					(thickness 0.1524)
				)
				(justify left mirror)
			)
		)
		(property "Value" ""
			(at 0 0 0)
			(layer "B.Fab")
			(effects
				(font
					(size 1.27 1.27)
				)
				(justify mirror)
			)
		)
		(duplicate_pad_numbers_are_jumpers no)
		(fp_poly
			(pts
				(xy 0.2794 -0.1016) (xy -0.2794 -0.1016) (xy -0.2794 0.9906) (xy 0.2794 0.9906)
			)
			(stroke
				(width 0)
				(type default)
			)
			(fill no)
			(layer "B.CrtYd")
		)
		(fp_line
			(start 0.2794 0.9906)
			(end -0.2794 0.9906)
			(stroke
				(width 0.1)
				(type default)
			)
			(layer "B.Fab")
		)
		(fp_line
			(start 0.2794 -0.1016)
			(end 0.2794 0.9906)
			(stroke
				(width 0.1)
				(type default)
			)
			(layer "B.Fab")
		)
		(fp_line
			(start -0.2794 0.9906)
			(end -0.2794 -0.1016)
			(stroke
				(width 0.1)
				(type default)
			)
			(layer "B.Fab")
		)
		(fp_line
			(start -0.2794 -0.1016)
			(end 0.2794 -0.1016)
			(stroke
				(width 0.1)
				(type default)
			)
			(layer "B.Fab")
		)
		(pad "1" smd rect
			(at 0 0)
			(size 0.508 0.508)
			(layers "B.Cu" "B.Mask" "B.Paste")
			(net "P3V3_STBY")
		)
		(pad "2" smd rect
			(at 0 0.889)
			(size 0.508 0.508)
			(layers "B.Cu" "B.Mask" "B.Paste")
			(net "PU_TPM_SPI_FLASH_RESET_2_N")
		)
		(zone
			(layer "B.Cu")
			(hatch none 0.5)
			(connect_pads
				(clearance 0)
			)
			(min_thickness 0.25)
			(keepout
				(tracks not_allowed)
				(vias allowed)
				(pads allowed)
				(copperpour not_allowed)
				(footprints allowed)
			)
			(placement
				(enabled no)
				(sheetname "")
			)
			(fill
				(thermal_gap 0.5)
				(thermal_bridge_width 0.5)
				(island_removal_mode 0)
			)
			(polygon
				(pts
					(xy 377.444 -20.955) (xy 377.952 -20.955) (xy 377.952 -20.574) (xy 377.444 -20.574)
				)
			)
		)
		(zone
			(layer "B.Cu")
			(hatch none 0.5)
			(connect_pads
				(clearance 0)
			)
			(min_thickness 0.25)
			(keepout
				(tracks allowed)
				(vias not_allowed)
				(pads allowed)
				(copperpour not_allowed)
				(footprints allowed)
			)
			(placement
				(enabled no)
				(sheetname "")
			)
			(fill
				(thermal_gap 0.5)
				(thermal_bridge_width 0.5)
				(island_removal_mode 0)
			)
			(polygon
				(pts
					(xy 377.444 -20.574) (xy 377.952 -20.574) (xy 377.952 -20.955) (xy 377.444 -20.955)
				)
			)
		)
	)
	(footprint ""
		(layer "B.Cu")
		(at 382.79705 -108.4834 -90)
		(property "Reference" "C3N16"
			(at 0 0 90)
			(layer "B.SilkS")
			(hide yes)
			(effects
				(font
					(size 1.27 1.27)
				)
				(justify mirror)
			)
		)
		(property "Value" ""
			(at 0 0 90)
			(layer "B.Fab")
			(effects
				(font
					(size 1.27 1.27)
				)
				(justify mirror)
			)
		)
		(duplicate_pad_numbers_are_jumpers no)
		(fp_rect
			(start 0.2794 0.9144)
			(end -0.2794 -0.1143)
			(stroke
				(width 0)
				(type default)
			)
			(fill no)
			(layer "B.CrtYd")
		)
		(fp_line
			(start -0.2794 0.9144)
			(end 0.2794 0.9144)
			(stroke
				(width 0.1)
				(type default)
			)
			(layer "B.Fab")
		)
		(fp_line
			(start 0.2794 0.9144)
			(end 0.2794 -0.1143)
			(stroke
				(width 0.1)
				(type default)
			)
			(layer "B.Fab")
		)
		(fp_line
			(start -0.2794 -0.1143)
			(end -0.2794 0.9144)
			(stroke
				(width 0.1)
				(type default)
			)
			(layer "B.Fab")
		)
		(fp_line
			(start 0.2794 -0.1143)
			(end -0.2794 -0.1143)
			(stroke
				(width 0.1)
				(type default)
			)
			(layer "B.Fab")
		)
		(pad "1" smd custom
			(at 0 0 180)
			(size 0.10414 0.10414)
			(layers "B.Cu" "B.Mask" "B.Paste")
			(net "PVNN_PCH_STBY")
			(options
				(clearance outline)
				(anchor circle)
			)
			(primitives
				(gr_poly
					(pts
						(xy -0.20828 -0.08636) (xy -0.20828 0.08636) (xy -0.08636 0.20828) (xy 0.086614 0.20828) (xy 0.20828 0.086614)
						(xy 0.20828 -0.08636) (xy 0.08636 -0.20828) (xy -0.08636 -0.20828)
					)
					(width 0)
					(fill yes)
				)
			)
		)
		(pad "2" smd custom
			(at 0 0.8001 180)
			(size 0.10414 0.10414)
			(layers "B.Cu" "B.Mask" "B.Paste")
			(net "GND")
			(options
				(clearance outline)
				(anchor circle)
			)
			(primitives
				(gr_poly
					(pts
						(xy -0.20828 -0.08636) (xy -0.20828 0.08636) (xy -0.08636 0.20828) (xy 0.086614 0.20828) (xy 0.20828 0.086614)
						(xy 0.20828 -0.08636) (xy 0.08636 -0.20828) (xy -0.08636 -0.20828)
					)
					(width 0)
					(fill yes)
				)
			)
		)
		(zone
			(layer "B.Cu")
			(hatch none 0.5)
			(connect_pads
				(clearance 0)
			)
			(min_thickness 0.25)
			(keepout
				(tracks allowed)
				(vias not_allowed)
				(pads allowed)
				(copperpour not_allowed)
				(footprints allowed)
			)
			(placement
				(enabled no)
				(sheetname "")
			)
			(fill
				(thermal_gap 0.5)
				(thermal_bridge_width 0.5)
				(island_removal_mode 0)
			)
			(polygon
				(pts
					(xy 382.5875 -108.39577) (xy 382.2065 -108.39577) (xy 382.2065 -108.57103) (xy 382.5875 -108.571284)
				)
			)
		)
		(zone
			(layer "B.Cu")
			(hatch none 0.5)
			(connect_pads
				(clearance 0)
			)
			(min_thickness 0.25)
			(keepout
				(tracks not_allowed)
				(vias allowed)
				(pads allowed)
				(copperpour not_allowed)
				(footprints allowed)
			)
			(placement
				(enabled no)
				(sheetname "")
			)
			(fill
				(thermal_gap 0.5)
				(thermal_bridge_width 0.5)
				(island_removal_mode 0)
			)
			(polygon
				(pts
					(xy 382.5875 -108.39577) (xy 382.2065 -108.39577) (xy 382.2065 -108.57103) (xy 382.5875 -108.571284)
				)
			)
		)
	)
	(footprint ""
		(layer "B.Cu")
		(at 28.0924 2.1336 -90)
		(property "Reference" "C9U11"
			(at 0 0 90)
			(layer "B.SilkS")
			(hide yes)
			(effects
				(font
					(size 1.27 1.27)
				)
				(justify mirror)
			)
		)
		(property "Value" ""
			(at 0 0 90)
			(layer "B.Fab")
			(effects
				(font
					(size 1.27 1.27)
				)
				(justify mirror)
			)
		)
		(duplicate_pad_numbers_are_jumpers no)
		(fp_rect
			(start 0.7239 -0.2159)
			(end -0.7239 1.9939)
			(stroke
				(width 0)
				(type default)
			)
			(fill no)
			(layer "B.CrtYd")
		)
		(fp_line
			(start -0.7239 1.9939)
			(end -0.7239 -0.2159)
			(stroke
				(width 0.1)
				(type default)
			)
			(layer "B.Fab")
		)
		(fp_line
			(start 0.7239 1.9939)
			(end -0.7239 1.9939)
			(stroke
				(width 0.1)
				(type default)
			)
			(layer "B.Fab")
		)
		(fp_line
			(start -0.7239 -0.2159)
			(end 0.7239 -0.2159)
			(stroke
				(width 0.1)
				(type default)
			)
			(layer "B.Fab")
		)
		(fp_line
			(start 0.7239 -0.2159)
			(end 0.7239 1.9939)
			(stroke
				(width 0.1)
				(type default)
			)
			(layer "B.Fab")
		)
		(pad "1" smd rect
			(at 0 0 90)
			(size 1.27 1.016)
			(layers "B.Cu" "B.Mask" "B.Paste")
			(net "P12V_NVDIMM_GHJ")
		)
		(pad "2" smd rect
			(at 0 1.778 90)
			(size 1.27 1.016)
			(layers "B.Cu" "B.Mask" "B.Paste")
			(net "GND")
		)
		(zone
			(layer "B.Cu")
			(hatch none 0.5)
			(connect_pads
				(clearance 0)
			)
			(min_thickness 0.25)
			(keepout
				(tracks not_allowed)
				(vias allowed)
				(pads allowed)
				(copperpour not_allowed)
				(footprints allowed)
			)
			(placement
				(enabled no)
				(sheetname "")
			)
			(fill
				(thermal_gap 0.5)
				(thermal_bridge_width 0.5)
				(island_removal_mode 0)
			)
			(polygon
				(pts
					(xy 27.5844 2.7686) (xy 27.5844 1.4986) (xy 26.8224 1.4986) (xy 26.8224 2.7686)
				)
			)
		)
	)
	(footprint ""
		(layer "B.Cu")
		(at 402.3995 -42.164 -90)
		(property "Reference" "R25W75"
			(at 0.8382 -0.67818 270)
			(unlocked yes)
			(layer "B.SilkS")
			(effects
				(font
					(size 0.4064 0.254)
					(thickness 0.1524)
				)
				(justify left mirror)
			)
		)
		(property "Value" ""
			(at 0 0 90)
			(layer "B.Fab")
			(effects
				(font
					(size 1.27 1.27)
				)
				(justify mirror)
			)
		)
		(duplicate_pad_numbers_are_jumpers no)
		(fp_poly
			(pts
				(xy 0.2794 -0.1016) (xy -0.2794 -0.1016) (xy -0.2794 0.9906) (xy 0.2794 0.9906)
			)
			(stroke
				(width 0)
				(type default)
			)
			(fill no)
			(layer "B.CrtYd")
		)
		(fp_line
			(start -0.2794 0.9906)
			(end -0.2794 -0.1016)
			(stroke
				(width 0.1)
				(type default)
			)
			(layer "B.Fab")
		)
		(fp_line
			(start 0.2794 0.9906)
			(end -0.2794 0.9906)
			(stroke
				(width 0.1)
				(type default)
			)
			(layer "B.Fab")
		)
		(fp_line
			(start -0.2794 -0.1016)
			(end 0.2794 -0.1016)
			(stroke
				(width 0.1)
				(type default)
			)
			(layer "B.Fab")
		)
		(fp_line
			(start 0.2794 -0.1016)
			(end 0.2794 0.9906)
			(stroke
				(width 0.1)
				(type default)
			)
			(layer "B.Fab")
		)
		(pad "1" smd rect
			(at 0 0 90)
			(size 0.508 0.508)
			(layers "B.Cu" "B.Mask" "B.Paste")
			(net "FM_CPU1_FIVR_FAULT_LVT3_R_N")
		)
		(pad "2" smd rect
			(at 0 0.889 90)
			(size 0.508 0.508)
			(layers "B.Cu" "B.Mask" "B.Paste")
			(net "FM_CPU1_FIVR_FAULT_LVT3_N")
		)
		(zone
			(layer "B.Cu")
			(hatch none 0.5)
			(connect_pads
				(clearance 0)
			)
			(min_thickness 0.25)
			(keepout
				(tracks not_allowed)
				(vias allowed)
				(pads allowed)
				(copperpour not_allowed)
				(footprints allowed)
			)
			(placement
				(enabled no)
				(sheetname "")
			)
			(fill
				(thermal_gap 0.5)
				(thermal_bridge_width 0.5)
				(island_removal_mode 0)
			)
			(polygon
				(pts
					(xy 401.7645 -41.91) (xy 401.7645 -42.418) (xy 402.1455 -42.418) (xy 402.1455 -41.91)
				)
			)
		)
		(zone
			(layer "B.Cu")
			(hatch none 0.5)
			(connect_pads
				(clearance 0)
			)
			(min_thickness 0.25)
			(keepout
				(tracks allowed)
				(vias not_allowed)
				(pads allowed)
				(copperpour not_allowed)
				(footprints allowed)
			)
			(placement
				(enabled no)
				(sheetname "")
			)
			(fill
				(thermal_gap 0.5)
				(thermal_bridge_width 0.5)
				(island_removal_mode 0)
			)
			(polygon
				(pts
					(xy 402.1455 -41.91) (xy 402.1455 -42.418) (xy 401.7645 -42.418) (xy 401.7645 -41.91)
				)
			)
		)
	)
	(footprint ""
		(layer "B.Cu")
		(at 186.015376 -59.243722 180)
		(property "Reference" "C22W15"
			(at 0 0 0)
			(layer "B.SilkS")
			(hide yes)
			(effects
				(font
					(size 1.27 1.27)
				)
				(justify mirror)
			)
		)
		(property "Value" "*"
			(at 0.0762 -6.2357 180)
			(unlocked yes)
			(layer "B.Fab")
			(hide yes)
			(effects
				(font
					(size 1.27 1.016)
					(thickness 0.1524)
				)
				(justify mirror)
			)
		)
		(property "Device Type" "SC22U16V5MX-4-GP_SMD-BCG5-SC22A"
			(at 0.0762 -8.2677 180)
			(unlocked yes)
			(layer "B.Fab")
			(hide yes)
			(effects
				(font
					(size 1.27 1.016)
					(thickness 0.1524)
				)
				(justify mirror)
			)
		)
		(duplicate_pad_numbers_are_jumpers no)
		(fp_line
			(start -0.635 0)
			(end 0.635 0)
			(stroke
				(width 0.508)
				(type default)
			)
			(layer "B.SilkS")
		)
		(fp_rect
			(start 0.9652 1.778)
			(end -0.9652 -1.778)
			(stroke
				(width 0)
				(type default)
			)
			(fill no)
			(layer "B.CrtYd")
		)
		(fp_poly
			(pts
				(xy 0.9652 -1.778) (xy -0.9652 -1.778) (xy -0.9652 1.778) (xy 0.9652 1.778)
			)
			(stroke
				(width 0)
				(type default)
			)
			(fill no)
			(layer "B.Fab")
		)
		(pad "1" smd rect
			(at 0 -0.9652)
			(size 1.397 1.143)
			(layers "B.Cu" "B.Mask" "B.Paste")
			(net "VR_FET_SW_P12V_STBY_PVCCIN_CPU0")
		)
		(pad "2" smd rect
			(at 0 0.9652)
			(size 1.397 1.143)
			(layers "B.Cu" "B.Mask" "B.Paste")
			(net "GND")
		)
	)
	(footprint ""
		(layer "B.Cu")
		(at 330.5048 -9.1186 90)
		(property "Reference" "Q4U1"
			(at -0.76327 4.7752 0)
			(unlocked yes)
			(layer "B.SilkS")
			(effects
				(font
					(size 0.7874 0.5842)
					(thickness 0.1524)
				)
				(justify left mirror)
			)
		)
		(property "Value" ""
			(at 0 0 90)
			(layer "B.Fab")
			(effects
				(font
					(size 1.27 1.27)
				)
				(justify mirror)
			)
		)
		(duplicate_pad_numbers_are_jumpers no)
		(fp_circle
			(center 0.508 -0.7874)
			(end 0.508 -0.6604)
			(stroke
				(width 0.254)
				(type default)
			)
			(fill no)
			(layer "B.SilkS")
		)
		(fp_poly
			(pts
				(xy -0.2159 1.7526) (xy -1.5621 1.7526) (xy -1.5621 -0.4572) (xy -0.2159 -0.4572)
			)
			(stroke
				(width 0)
				(type default)
			)
			(fill no)
			(layer "B.CrtYd")
		)
		(fp_line
			(start -0.2159 -0.45466)
			(end -0.2159 1.75514)
			(stroke
				(width 0.1)
				(type default)
			)
			(layer "B.Fab")
		)
		(fp_line
			(start -1.5621 -0.45466)
			(end -0.2159 -0.45466)
			(stroke
				(width 0.1)
				(type default)
			)
			(layer "B.Fab")
		)
		(fp_line
			(start -0.2159 1.75514)
			(end -1.5621 1.75514)
			(stroke
				(width 0.1)
				(type default)
			)
			(layer "B.Fab")
		)
		(fp_line
			(start -1.5621 1.75514)
			(end -1.5621 -0.45466)
			(stroke
				(width 0.1)
				(type default)
			)
			(layer "B.Fab")
		)
		(fp_circle
			(center 0.508 -0.7874)
			(end 0.508 -0.6604)
			(stroke
				(width 0.254)
				(type default)
			)
			(fill no)
			(layer "B.Fab")
		)
		(pad "1" smd rect
			(at 0 0 270)
			(size 1.016 0.381)
			(layers "B.Cu" "B.Mask" "B.Paste")
			(net "GND")
		)
		(pad "2" smd rect
			(at 0 0.65024 270)
			(size 1.016 0.381)
			(layers "B.Cu" "B.Mask" "B.Paste")
			(net "FM_DIMM_EVENT_COD_N")
		)
		(pad "3" smd rect
			(at 0 1.30048 270)
			(size 1.016 0.381)
			(layers "B.Cu" "B.Mask" "B.Paste")
			(net "FM_MEM_THERM_EVENT_LVT3_N")
		)
		(pad "4" smd rect
			(at -1.778 1.30048 270)
			(size 1.016 0.381)
			(layers "B.Cu" "B.Mask" "B.Paste")
			(net "GND")
		)
		(pad "5" smd rect
			(at -1.778 0.65024 270)
			(size 1.016 0.381)
			(layers "B.Cu" "B.Mask" "B.Paste")
			(net "FM_DIMM_EVENT_FET")
		)
		(pad "6" smd rect
			(at -1.778 0 270)
			(size 1.016 0.381)
			(layers "B.Cu" "B.Mask" "B.Paste")
			(net "FM_DIMM_EVENT_FET")
		)
		(zone
			(layer "B.Cu")
			(hatch none 0.5)
			(connect_pads
				(clearance 0)
			)
			(min_thickness 0.25)
			(keepout
				(tracks allowed)
				(vias not_allowed)
				(pads allowed)
				(copperpour not_allowed)
				(footprints allowed)
			)
			(placement
				(enabled no)
				(sheetname "")
			)
			(fill
				(thermal_gap 0.5)
				(thermal_bridge_width 0.5)
				(island_removal_mode 0)
			)
			(polygon
				(pts
					(xy 330.3143 -9.6266) (xy 330.3143 -8.6106) (xy 332.0034 -8.6106) (xy 332.0034 -9.6266)
				)
			)
		)
		(zone
			(layer "B.Cu")
			(hatch none 0.5)
			(connect_pads
				(clearance 0)
			)
			(min_thickness 0.25)
			(keepout
				(tracks allowed)
				(vias not_allowed)
				(pads allowed)
				(copperpour not_allowed)
				(footprints allowed)
			)
			(placement
				(enabled no)
				(sheetname "")
			)
			(fill
				(thermal_gap 0.5)
				(thermal_bridge_width 0.5)
				(island_removal_mode 0)
			)
			(polygon
				(pts
					(xy 330.3143 -7.8486) (xy 330.3143 -6.8326) (xy 332.0034 -6.8326) (xy 332.0034 -7.8486)
				)
			)
		)
	)
	(footprint ""
		(layer "B.Cu")
		(at 252.1585 -149.8092 -90)
		(property "Reference" "C5G61"
			(at -1.14681 0.76708 0)
			(unlocked yes)
			(layer "B.SilkS")
			(effects
				(font
					(size 0.7874 0.5842)
					(thickness 0.1524)
				)
				(justify mirror)
			)
		)
		(property "Value" ""
			(at 0 0 90)
			(layer "B.Fab")
			(effects
				(font
					(size 1.27 1.27)
				)
				(justify mirror)
			)
		)
		(duplicate_pad_numbers_are_jumpers no)
		(fp_rect
			(start 0.4953 1.6002)
			(end -0.4953 -0.2032)
			(stroke
				(width 0)
				(type default)
			)
			(fill no)
			(layer "B.CrtYd")
		)
		(fp_line
			(start -0.4953 1.6002)
			(end 0.4953 1.6002)
			(stroke
				(width 0.1)
				(type default)
			)
			(layer "B.Fab")
		)
		(fp_line
			(start 0.4953 1.6002)
			(end 0.4953 -0.2032)
			(stroke
				(width 0.1)
				(type default)
			)
			(layer "B.Fab")
		)
		(fp_line
			(start -0.4953 -0.2032)
			(end -0.4953 1.6002)
			(stroke
				(width 0.1)
				(type default)
			)
			(layer "B.Fab")
		)
		(fp_line
			(start 0.4953 -0.2032)
			(end -0.4953 -0.2032)
			(stroke
				(width 0.1)
				(type default)
			)
			(layer "B.Fab")
		)
		(pad "1" smd rect
			(at 0 0 90)
			(size 0.762 0.889)
			(layers "B.Cu" "B.Mask" "B.Paste")
			(net "PVDDQ_DEF")
		)
		(pad "2" smd rect
			(at 0 1.397 90)
			(size 0.762 0.889)
			(layers "B.Cu" "B.Mask" "B.Paste")
			(net "GND")
		)
		(zone
			(layer "B.Cu")
			(hatch none 0.5)
			(connect_pads
				(clearance 0)
			)
			(min_thickness 0.25)
			(keepout
				(tracks not_allowed)
				(vias allowed)
				(pads allowed)
				(copperpour not_allowed)
				(footprints allowed)
			)
			(placement
				(enabled no)
				(sheetname "")
			)
			(fill
				(thermal_gap 0.5)
				(thermal_bridge_width 0.5)
				(island_removal_mode 0)
			)
			(polygon
				(pts
					(xy 251.206 -149.4282) (xy 251.714 -149.4282) (xy 251.714 -150.1902) (xy 251.206 -150.1902)
				)
			)
		)
	)
	(footprint ""
		(layer "B.Cu")
		(at 408.559 0.2794 -90)
		(property "Reference" "C2U27"
			(at 0 0 90)
			(layer "B.SilkS")
			(hide yes)
			(effects
				(font
					(size 1.27 1.27)
				)
				(justify mirror)
			)
		)
		(property "Value" ""
			(at 0 0 90)
			(layer "B.Fab")
			(effects
				(font
					(size 1.27 1.27)
				)
				(justify mirror)
			)
		)
		(duplicate_pad_numbers_are_jumpers no)
		(fp_poly
			(pts
				(xy -0.3048 -0.1016) (xy -0.3048 0.9906) (xy 0.3048 0.9906) (xy 0.3048 -0.1016)
			)
			(stroke
				(width 0)
				(type default)
			)
			(fill no)
			(layer "B.CrtYd")
		)
		(fp_line
			(start -0.3048 0.9906)
			(end -0.3048 -0.1016)
			(stroke
				(width 0.1)
				(type default)
			)
			(layer "B.Fab")
		)
		(fp_line
			(start 0.3048 0.9906)
			(end -0.3048 0.9906)
			(stroke
				(width 0.1)
				(type default)
			)
			(layer "B.Fab")
		)
		(fp_line
			(start -0.3048 -0.1016)
			(end 0.3048 -0.1016)
			(stroke
				(width 0.1)
				(type default)
			)
			(layer "B.Fab")
		)
		(fp_line
			(start 0.3048 -0.1016)
			(end 0.3048 0.9906)
			(stroke
				(width 0.1)
				(type default)
			)
			(layer "B.Fab")
		)
		(pad "1" smd rect
			(at 0 0 90)
			(size 0.508 0.508)
			(layers "B.Cu" "B.Mask" "B.Paste")
			(net "P3V3_STBY")
		)
		(pad "2" smd rect
			(at 0 0.889 90)
			(size 0.508 0.508)
			(layers "B.Cu" "B.Mask" "B.Paste")
			(net "GND")
		)
		(zone
			(layer "B.Cu")
			(hatch none 0.5)
			(connect_pads
				(clearance 0)
			)
			(min_thickness 0.25)
			(keepout
				(tracks not_allowed)
				(vias allowed)
				(pads allowed)
				(copperpour not_allowed)
				(footprints allowed)
			)
			(placement
				(enabled no)
				(sheetname "")
			)
			(fill
				(thermal_gap 0.5)
				(thermal_bridge_width 0.5)
				(island_removal_mode 0)
			)
			(polygon
				(pts
					(xy 407.924 0.5334) (xy 407.924 0.0254) (xy 408.305 0.0254) (xy 408.305 0.5334)
				)
			)
		)
		(zone
			(layer "B.Cu")
			(hatch none 0.5)
			(connect_pads
				(clearance 0)
			)
			(min_thickness 0.25)
			(keepout
				(tracks allowed)
				(vias not_allowed)
				(pads allowed)
				(copperpour not_allowed)
				(footprints allowed)
			)
			(placement
				(enabled no)
				(sheetname "")
			)
			(fill
				(thermal_gap 0.5)
				(thermal_bridge_width 0.5)
				(island_removal_mode 0)
			)
			(polygon
				(pts
					(xy 408.305 0.5334) (xy 408.305 0.0254) (xy 407.924 0.0254) (xy 407.924 0.5334)
				)
			)
		)
	)
	(footprint ""
		(layer "B.Cu")
		(at 401.5613 -37.1094 90)
		(property "Reference" "R2U13"
			(at 0 0 90)
			(layer "B.SilkS")
			(hide yes)
			(effects
				(font
					(size 1.27 1.27)
				)
				(justify mirror)
			)
		)
		(property "Value" ""
			(at 0 0 90)
			(layer "B.Fab")
			(effects
				(font
					(size 1.27 1.27)
				)
				(justify mirror)
			)
		)
		(duplicate_pad_numbers_are_jumpers no)
		(fp_poly
			(pts
				(xy 0.2794 -0.1016) (xy -0.2794 -0.1016) (xy -0.2794 0.9906) (xy 0.2794 0.9906)
			)
			(stroke
				(width 0)
				(type default)
			)
			(fill no)
			(layer "B.CrtYd")
		)
		(fp_line
			(start 0.2794 -0.1016)
			(end 0.2794 0.9906)
			(stroke
				(width 0.1)
				(type default)
			)
			(layer "B.Fab")
		)
		(fp_line
			(start -0.2794 -0.1016)
			(end 0.2794 -0.1016)
			(stroke
				(width 0.1)
				(type default)
			)
			(layer "B.Fab")
		)
		(fp_line
			(start 0.2794 0.9906)
			(end -0.2794 0.9906)
			(stroke
				(width 0.1)
				(type default)
			)
			(layer "B.Fab")
		)
		(fp_line
			(start -0.2794 0.9906)
			(end -0.2794 -0.1016)
			(stroke
				(width 0.1)
				(type default)
			)
			(layer "B.Fab")
		)
		(pad "1" smd rect
			(at 0 0 270)
			(size 0.508 0.508)
			(layers "B.Cu" "B.Mask" "B.Paste")
			(net "P3V3_STBY")
		)
		(pad "2" smd rect
			(at 0 0.889 270)
			(size 0.508 0.508)
			(layers "B.Cu" "B.Mask" "B.Paste")
			(net "SMB_OCP_FRU_STBY_LVC3_SDA_R")
		)
		(zone
			(layer "B.Cu")
			(hatch none 0.5)
			(connect_pads
				(clearance 0)
			)
			(min_thickness 0.25)
			(keepout
				(tracks allowed)
				(vias not_allowed)
				(pads allowed)
				(copperpour not_allowed)
				(footprints allowed)
			)
			(placement
				(enabled no)
				(sheetname "")
			)
			(fill
				(thermal_gap 0.5)
				(thermal_bridge_width 0.5)
				(island_removal_mode 0)
			)
			(polygon
				(pts
					(xy 401.8153 -37.3634) (xy 401.8153 -36.8554) (xy 402.1963 -36.8554) (xy 402.1963 -37.3634)
				)
			)
		)
		(zone
			(layer "B.Cu")
			(hatch none 0.5)
			(connect_pads
				(clearance 0)
			)
			(min_thickness 0.25)
			(keepout
				(tracks not_allowed)
				(vias allowed)
				(pads allowed)
				(copperpour not_allowed)
				(footprints allowed)
			)
			(placement
				(enabled no)
				(sheetname "")
			)
			(fill
				(thermal_gap 0.5)
				(thermal_bridge_width 0.5)
				(island_removal_mode 0)
			)
			(polygon
				(pts
					(xy 402.1963 -37.3634) (xy 402.1963 -36.8554) (xy 401.8153 -36.8554) (xy 401.8153 -37.3634)
				)
			)
		)
	)
	(footprint ""
		(layer "B.Cu")
		(at 417.6522 -74.0537)
		(property "Reference" "R9F3"
			(at 0 0 0)
			(layer "B.SilkS")
			(hide yes)
			(effects
				(font
					(size 1.27 1.27)
				)
				(justify mirror)
			)
		)
		(property "Value" ""
			(at 0 0 0)
			(layer "B.Fab")
			(effects
				(font
					(size 1.27 1.27)
				)
				(justify mirror)
			)
		)
		(duplicate_pad_numbers_are_jumpers no)
		(fp_poly
			(pts
				(xy 0.2794 -0.1016) (xy -0.2794 -0.1016) (xy -0.2794 0.9906) (xy 0.2794 0.9906)
			)
			(stroke
				(width 0)
				(type default)
			)
			(fill no)
			(layer "B.CrtYd")
		)
		(fp_line
			(start -0.2794 -0.1016)
			(end 0.2794 -0.1016)
			(stroke
				(width 0.1)
				(type default)
			)
			(layer "B.Fab")
		)
		(fp_line
			(start -0.2794 0.9906)
			(end -0.2794 -0.1016)
			(stroke
				(width 0.1)
				(type default)
			)
			(layer "B.Fab")
		)
		(fp_line
			(start 0.2794 -0.1016)
			(end 0.2794 0.9906)
			(stroke
				(width 0.1)
				(type default)
			)
			(layer "B.Fab")
		)
		(fp_line
			(start 0.2794 0.9906)
			(end -0.2794 0.9906)
			(stroke
				(width 0.1)
				(type default)
			)
			(layer "B.Fab")
		)
		(pad "1" smd rect
			(at 0 0 180)
			(size 0.508 0.508)
			(layers "B.Cu" "B.Mask" "B.Paste")
			(net "P3V3_STBY")
		)
		(pad "2" smd rect
			(at 0 0.889 180)
			(size 0.508 0.508)
			(layers "B.Cu" "B.Mask" "B.Paste")
			(net "FM_FAST_PROCHOT_EN")
		)
		(zone
			(layer "B.Cu")
			(hatch none 0.5)
			(connect_pads
				(clearance 0)
			)
			(min_thickness 0.25)
			(keepout
				(tracks allowed)
				(vias not_allowed)
				(pads allowed)
				(copperpour not_allowed)
				(footprints allowed)
			)
			(placement
				(enabled no)
				(sheetname "")
			)
			(fill
				(thermal_gap 0.5)
				(thermal_bridge_width 0.5)
				(island_removal_mode 0)
			)
			(polygon
				(pts
					(xy 417.9062 -73.7997) (xy 417.3982 -73.7997) (xy 417.3982 -73.4187) (xy 417.9062 -73.4187)
				)
			)
		)
		(zone
			(layer "B.Cu")
			(hatch none 0.5)
			(connect_pads
				(clearance 0)
			)
			(min_thickness 0.25)
			(keepout
				(tracks not_allowed)
				(vias allowed)
				(pads allowed)
				(copperpour not_allowed)
				(footprints allowed)
			)
			(placement
				(enabled no)
				(sheetname "")
			)
			(fill
				(thermal_gap 0.5)
				(thermal_bridge_width 0.5)
				(island_removal_mode 0)
			)
			(polygon
				(pts
					(xy 417.9062 -73.4187) (xy 417.3982 -73.4187) (xy 417.3982 -73.7997) (xy 417.9062 -73.7997)
				)
			)
		)
	)
	(footprint ""
		(layer "B.Cu")
		(at 375.158 -82.169 90)
		(property "Reference" "R7D18"
			(at 0.8382 -0.67818 90)
			(unlocked yes)
			(layer "B.SilkS")
			(effects
				(font
					(size 0.4064 0.254)
					(thickness 0.1524)
				)
				(justify left mirror)
			)
		)
		(property "Value" ""
			(at 0 0 90)
			(layer "B.Fab")
			(effects
				(font
					(size 1.27 1.27)
				)
				(justify mirror)
			)
		)
		(duplicate_pad_numbers_are_jumpers no)
		(fp_poly
			(pts
				(xy 0.2794 -0.1016) (xy -0.2794 -0.1016) (xy -0.2794 0.9906) (xy 0.2794 0.9906)
			)
			(stroke
				(width 0)
				(type default)
			)
			(fill no)
			(layer "B.CrtYd")
		)
		(fp_line
			(start 0.2794 -0.1016)
			(end 0.2794 0.9906)
			(stroke
				(width 0.1)
				(type default)
			)
			(layer "B.Fab")
		)
		(fp_line
			(start -0.2794 -0.1016)
			(end 0.2794 -0.1016)
			(stroke
				(width 0.1)
				(type default)
			)
			(layer "B.Fab")
		)
		(fp_line
			(start 0.2794 0.9906)
			(end -0.2794 0.9906)
			(stroke
				(width 0.1)
				(type default)
			)
			(layer "B.Fab")
		)
		(fp_line
			(start -0.2794 0.9906)
			(end -0.2794 -0.1016)
			(stroke
				(width 0.1)
				(type default)
			)
			(layer "B.Fab")
		)
		(pad "1" smd rect
			(at 0 0 270)
			(size 0.508 0.508)
			(layers "B.Cu" "B.Mask" "B.Paste")
			(net "FM_THERMTRIP_DLY")
		)
		(pad "2" smd rect
			(at 0 0.889 270)
			(size 0.508 0.508)
			(layers "B.Cu" "B.Mask" "B.Paste")
			(net "FM_THERMTRIP_DLY_R")
		)
		(zone
			(layer "B.Cu")
			(hatch none 0.5)
			(connect_pads
				(clearance 0)
			)
			(min_thickness 0.25)
			(keepout
				(tracks allowed)
				(vias not_allowed)
				(pads allowed)
				(copperpour not_allowed)
				(footprints allowed)
			)
			(placement
				(enabled no)
				(sheetname "")
			)
			(fill
				(thermal_gap 0.5)
				(thermal_bridge_width 0.5)
				(island_removal_mode 0)
			)
			(polygon
				(pts
					(xy 375.412 -82.423) (xy 375.412 -81.915) (xy 375.793 -81.915) (xy 375.793 -82.423)
				)
			)
		)
		(zone
			(layer "B.Cu")
			(hatch none 0.5)
			(connect_pads
				(clearance 0)
			)
			(min_thickness 0.25)
			(keepout
				(tracks not_allowed)
				(vias allowed)
				(pads allowed)
				(copperpour not_allowed)
				(footprints allowed)
			)
			(placement
				(enabled no)
				(sheetname "")
			)
			(fill
				(thermal_gap 0.5)
				(thermal_bridge_width 0.5)
				(island_removal_mode 0)
			)
			(polygon
				(pts
					(xy 375.793 -82.423) (xy 375.793 -81.915) (xy 375.412 -81.915) (xy 375.412 -82.423)
				)
			)
		)
	)
	(footprint ""
		(layer "B.Cu")
		(at 193.092832 2.1336 -90)
		(property "Reference" "C6U18"
			(at 0 0 90)
			(layer "B.SilkS")
			(hide yes)
			(effects
				(font
					(size 1.27 1.27)
				)
				(justify mirror)
			)
		)
		(property "Value" ""
			(at 0 0 90)
			(layer "B.Fab")
			(effects
				(font
					(size 1.27 1.27)
				)
				(justify mirror)
			)
		)
		(duplicate_pad_numbers_are_jumpers no)
		(fp_rect
			(start -0.7239 1.9939)
			(end 0.7239 -0.2159)
			(stroke
				(width 0)
				(type default)
			)
			(fill no)
			(layer "B.CrtYd")
		)
		(fp_line
			(start -0.7239 1.9939)
			(end -0.7239 -0.2159)
			(stroke
				(width 0.1)
				(type default)
			)
			(layer "B.Fab")
		)
		(fp_line
			(start 0.7239 1.9939)
			(end -0.7239 1.9939)
			(stroke
				(width 0.1)
				(type default)
			)
			(layer "B.Fab")
		)
		(fp_line
			(start -0.7239 -0.2159)
			(end 0.7239 -0.2159)
			(stroke
				(width 0.1)
				(type default)
			)
			(layer "B.Fab")
		)
		(fp_line
			(start 0.7239 -0.2159)
			(end 0.7239 1.9939)
			(stroke
				(width 0.1)
				(type default)
			)
			(layer "B.Fab")
		)
		(pad "1" smd rect
			(at 0 0 90)
			(size 1.27 1.016)
			(layers "B.Cu" "B.Mask" "B.Paste")
			(net "P12V_NVDIMM_ABC")
		)
		(pad "2" smd rect
			(at 0 1.778 90)
			(size 1.27 1.016)
			(layers "B.Cu" "B.Mask" "B.Paste")
			(net "GND")
		)
		(zone
			(layer "B.Cu")
			(hatch none 0.5)
			(connect_pads
				(clearance 0)
			)
			(min_thickness 0.25)
			(keepout
				(tracks not_allowed)
				(vias allowed)
				(pads allowed)
				(copperpour not_allowed)
				(footprints allowed)
			)
			(placement
				(enabled no)
				(sheetname "")
			)
			(fill
				(thermal_gap 0.5)
				(thermal_bridge_width 0.5)
				(island_removal_mode 0)
			)
			(polygon
				(pts
					(xy 191.822832 1.4986) (xy 191.822832 2.7686) (xy 192.584832 2.7686) (xy 192.584832 1.4986)
				)
			)
		)
	)
	(footprint ""
		(layer "B.Cu")
		(at 87.158068 -145.0086 -90)
		(property "Reference" "C8L8"
			(at -1.848866 0.752348 270)
			(unlocked yes)
			(layer "B.SilkS")
			(effects
				(font
					(size 1.27 0.9652)
					(thickness 0.1524)
				)
				(justify mirror)
			)
		)
		(property "Value" ""
			(at 0 0 90)
			(layer "B.Fab")
			(effects
				(font
					(size 1.27 1.27)
				)
				(justify mirror)
			)
		)
		(duplicate_pad_numbers_are_jumpers no)
		(fp_rect
			(start 0.500126 1.598422)
			(end -0.500126 -0.201422)
			(stroke
				(width 0)
				(type default)
			)
			(fill no)
			(layer "B.CrtYd")
		)
		(fp_line
			(start -0.500126 1.598422)
			(end 0.500126 1.598422)
			(stroke
				(width 0.1)
				(type default)
			)
			(layer "B.Fab")
		)
		(fp_line
			(start 0.500126 1.598422)
			(end 0.500126 -0.201422)
			(stroke
				(width 0.1)
				(type default)
			)
			(layer "B.Fab")
		)
		(fp_line
			(start -0.500126 -0.201422)
			(end -0.500126 1.598422)
			(stroke
				(width 0.1)
				(type default)
			)
			(layer "B.Fab")
		)
		(fp_line
			(start 0.500126 -0.201422)
			(end -0.500126 -0.201422)
			(stroke
				(width 0.1)
				(type default)
			)
			(layer "B.Fab")
		)
		(pad "1" smd rect
			(at 0 0 180)
			(size 0.889 0.9906)
			(layers "B.Cu" "B.Mask" "B.Paste")
			(net "PVDDQ_KLM")
		)
		(pad "2" smd rect
			(at 0 1.397 180)
			(size 0.889 0.9906)
			(layers "B.Cu" "B.Mask" "B.Paste")
			(net "GND")
		)
		(zone
			(layer "B.Cu")
			(hatch none 0.5)
			(connect_pads
				(clearance 0)
			)
			(min_thickness 0.25)
			(keepout
				(tracks allowed)
				(vias not_allowed)
				(pads allowed)
				(copperpour not_allowed)
				(footprints allowed)
			)
			(placement
				(enabled no)
				(sheetname "")
			)
			(fill
				(thermal_gap 0.5)
				(thermal_bridge_width 0.5)
				(island_removal_mode 0)
			)
			(polygon
				(pts
					(xy 86.205568 -144.5133) (xy 86.713568 -144.5133) (xy 86.713568 -145.5039) (xy 86.205568 -145.5039)
				)
			)
		)
		(zone
			(layer "B.Cu")
			(hatch none 0.5)
			(connect_pads
				(clearance 0)
			)
			(min_thickness 0.25)
			(keepout
				(tracks not_allowed)
				(vias allowed)
				(pads allowed)
				(copperpour not_allowed)
				(footprints allowed)
			)
			(placement
				(enabled no)
				(sheetname "")
			)
			(fill
				(thermal_gap 0.5)
				(thermal_bridge_width 0.5)
				(island_removal_mode 0)
			)
			(polygon
				(pts
					(xy 86.205568 -144.5133) (xy 86.713568 -144.5133) (xy 86.713568 -145.5039) (xy 86.205568 -145.5039)
				)
			)
		)
	)
	(footprint ""
		(layer "B.Cu")
		(at 96.03232 -126.43358 90)
		(property "Reference" "C8M12"
			(at -1.66497 0.408432 0)
			(unlocked yes)
			(layer "B.SilkS")
			(effects
				(font
					(size 0.7874 0.5842)
					(thickness 0.1524)
				)
				(justify mirror)
			)
		)
		(property "Value" ""
			(at 0 0 90)
			(layer "B.Fab")
			(effects
				(font
					(size 1.27 1.27)
				)
				(justify mirror)
			)
		)
		(duplicate_pad_numbers_are_jumpers no)
		(fp_rect
			(start 0.500126 1.598422)
			(end -0.500126 -0.201422)
			(stroke
				(width 0)
				(type default)
			)
			(fill no)
			(layer "B.CrtYd")
		)
		(fp_line
			(start 0.500126 -0.201422)
			(end -0.500126 -0.201422)
			(stroke
				(width 0.1)
				(type default)
			)
			(layer "B.Fab")
		)
		(fp_line
			(start -0.500126 -0.201422)
			(end -0.500126 1.598422)
			(stroke
				(width 0.1)
				(type default)
			)
			(layer "B.Fab")
		)
		(fp_line
			(start 0.500126 1.598422)
			(end 0.500126 -0.201422)
			(stroke
				(width 0.1)
				(type default)
			)
			(layer "B.Fab")
		)
		(fp_line
			(start -0.500126 1.598422)
			(end 0.500126 1.598422)
			(stroke
				(width 0.1)
				(type default)
			)
			(layer "B.Fab")
		)
		(pad "1" smd rect
			(at 0 0)
			(size 0.889 0.9906)
			(layers "B.Cu" "B.Mask" "B.Paste")
			(net "PVTT_KLM")
		)
		(pad "2" smd rect
			(at 0 1.397)
			(size 0.889 0.9906)
			(layers "B.Cu" "B.Mask" "B.Paste")
			(net "GND")
		)
		(zone
			(layer "B.Cu")
			(hatch none 0.5)
			(connect_pads
				(clearance 0)
			)
			(min_thickness 0.25)
			(keepout
				(tracks not_allowed)
				(vias allowed)
				(pads allowed)
				(copperpour not_allowed)
				(footprints allowed)
			)
			(placement
				(enabled no)
				(sheetname "")
			)
			(fill
				(thermal_gap 0.5)
				(thermal_bridge_width 0.5)
				(island_removal_mode 0)
			)
			(polygon
				(pts
					(xy 96.98482 -126.92888) (xy 96.47682 -126.92888) (xy 96.47682 -125.93828) (xy 96.98482 -125.93828)
				)
			)
		)
		(zone
			(layer "B.Cu")
			(hatch none 0.5)
			(connect_pads
				(clearance 0)
			)
			(min_thickness 0.25)
			(keepout
				(tracks allowed)
				(vias not_allowed)
				(pads allowed)
				(copperpour not_allowed)
				(footprints allowed)
			)
			(placement
				(enabled no)
				(sheetname "")
			)
			(fill
				(thermal_gap 0.5)
				(thermal_bridge_width 0.5)
				(island_removal_mode 0)
			)
			(polygon
				(pts
					(xy 96.98482 -126.92888) (xy 96.47682 -126.92888) (xy 96.47682 -125.93828) (xy 96.98482 -125.93828)
				)
			)
		)
	)
	(footprint ""
		(layer "B.Cu")
		(at 496.016534 -38.029896 90)
		(property "Reference" "R9F26"
			(at 0 0 90)
			(layer "B.SilkS")
			(hide yes)
			(effects
				(font
					(size 1.27 1.27)
				)
				(justify mirror)
			)
		)
		(property "Value" ""
			(at 0 0 90)
			(layer "B.Fab")
			(effects
				(font
					(size 1.27 1.27)
				)
				(justify mirror)
			)
		)
		(duplicate_pad_numbers_are_jumpers no)
		(fp_poly
			(pts
				(xy 0.2794 -0.1016) (xy -0.2794 -0.1016) (xy -0.2794 0.9906) (xy 0.2794 0.9906)
			)
			(stroke
				(width 0)
				(type default)
			)
			(fill no)
			(layer "B.CrtYd")
		)
		(fp_line
			(start 0.2794 -0.1016)
			(end 0.2794 0.9906)
			(stroke
				(width 0.1)
				(type default)
			)
			(layer "B.Fab")
		)
		(fp_line
			(start -0.2794 -0.1016)
			(end 0.2794 -0.1016)
			(stroke
				(width 0.1)
				(type default)
			)
			(layer "B.Fab")
		)
		(fp_line
			(start 0.2794 0.9906)
			(end -0.2794 0.9906)
			(stroke
				(width 0.1)
				(type default)
			)
			(layer "B.Fab")
		)
		(fp_line
			(start -0.2794 0.9906)
			(end -0.2794 -0.1016)
			(stroke
				(width 0.1)
				(type default)
			)
			(layer "B.Fab")
		)
		(pad "1" smd rect
			(at 0 0 270)
			(size 0.508 0.508)
			(layers "B.Cu" "B.Mask" "B.Paste")
			(net "SP2_BMC_CM_UART_TX")
		)
		(pad "2" smd rect
			(at 0 0.889 270)
			(size 0.508 0.508)
			(layers "B.Cu" "B.Mask" "B.Paste")
			(net "SPA_MID_DBG_TX")
		)
		(zone
			(layer "B.Cu")
			(hatch none 0.5)
			(connect_pads
				(clearance 0)
			)
			(min_thickness 0.25)
			(keepout
				(tracks allowed)
				(vias not_allowed)
				(pads allowed)
				(copperpour not_allowed)
				(footprints allowed)
			)
			(placement
				(enabled no)
				(sheetname "")
			)
			(fill
				(thermal_gap 0.5)
				(thermal_bridge_width 0.5)
				(island_removal_mode 0)
			)
			(polygon
				(pts
					(xy 496.270534 -38.283896) (xy 496.270534 -37.775896) (xy 496.651534 -37.775896) (xy 496.651534 -38.283896)
				)
			)
		)
		(zone
			(layer "B.Cu")
			(hatch none 0.5)
			(connect_pads
				(clearance 0)
			)
			(min_thickness 0.25)
			(keepout
				(tracks not_allowed)
				(vias allowed)
				(pads allowed)
				(copperpour not_allowed)
				(footprints allowed)
			)
			(placement
				(enabled no)
				(sheetname "")
			)
			(fill
				(thermal_gap 0.5)
				(thermal_bridge_width 0.5)
				(island_removal_mode 0)
			)
			(polygon
				(pts
					(xy 496.651534 -38.283896) (xy 496.651534 -37.775896) (xy 496.270534 -37.775896) (xy 496.270534 -38.283896)
				)
			)
		)
	)
	(footprint ""
		(layer "B.Cu")
		(at 257.8862 -149.7838 -90)
		(property "Reference" "C5G63"
			(at -1.14681 0.76708 0)
			(unlocked yes)
			(layer "B.SilkS")
			(effects
				(font
					(size 0.7874 0.5842)
					(thickness 0.1524)
				)
				(justify mirror)
			)
		)
		(property "Value" ""
			(at 0 0 90)
			(layer "B.Fab")
			(effects
				(font
					(size 1.27 1.27)
				)
				(justify mirror)
			)
		)
		(duplicate_pad_numbers_are_jumpers no)
		(fp_rect
			(start -0.4953 -0.2032)
			(end 0.4953 1.6002)
			(stroke
				(width 0)
				(type default)
			)
			(fill no)
			(layer "B.CrtYd")
		)
		(fp_line
			(start -0.4953 1.6002)
			(end 0.4953 1.6002)
			(stroke
				(width 0.1)
				(type default)
			)
			(layer "B.Fab")
		)
		(fp_line
			(start 0.4953 1.6002)
			(end 0.4953 -0.2032)
			(stroke
				(width 0.1)
				(type default)
			)
			(layer "B.Fab")
		)
		(fp_line
			(start -0.4953 -0.2032)
			(end -0.4953 1.6002)
			(stroke
				(width 0.1)
				(type default)
			)
			(layer "B.Fab")
		)
		(fp_line
			(start 0.4953 -0.2032)
			(end -0.4953 -0.2032)
			(stroke
				(width 0.1)
				(type default)
			)
			(layer "B.Fab")
		)
		(pad "1" smd rect
			(at 0 0 90)
			(size 0.762 0.889)
			(layers "B.Cu" "B.Mask" "B.Paste")
			(net "PVDDQ_DEF")
		)
		(pad "2" smd rect
			(at 0 1.397 90)
			(size 0.762 0.889)
			(layers "B.Cu" "B.Mask" "B.Paste")
			(net "GND")
		)
		(zone
			(layer "B.Cu")
			(hatch none 0.5)
			(connect_pads
				(clearance 0)
			)
			(min_thickness 0.25)
			(keepout
				(tracks not_allowed)
				(vias allowed)
				(pads allowed)
				(copperpour not_allowed)
				(footprints allowed)
			)
			(placement
				(enabled no)
				(sheetname "")
			)
			(fill
				(thermal_gap 0.5)
				(thermal_bridge_width 0.5)
				(island_removal_mode 0)
			)
			(polygon
				(pts
					(xy 257.4417 -150.1648) (xy 256.9337 -150.1648) (xy 256.9337 -149.4028) (xy 257.4417 -149.4028)
				)
			)
		)
	)
	(footprint ""
		(layer "B.Cu")
		(at 448.31 -147.066 180)
		(property "Reference" "C25W98"
			(at 0.8382 -0.67818 180)
			(unlocked yes)
			(layer "B.SilkS")
			(effects
				(font
					(size 0.4064 0.254)
					(thickness 0.1524)
				)
				(justify left mirror)
			)
		)
		(property "Value" ""
			(at 0 0 0)
			(layer "B.Fab")
			(effects
				(font
					(size 1.27 1.27)
				)
				(justify mirror)
			)
		)
		(duplicate_pad_numbers_are_jumpers no)
		(fp_poly
			(pts
				(xy -0.3048 -0.1016) (xy -0.3048 0.9906) (xy 0.3048 0.9906) (xy 0.3048 -0.1016)
			)
			(stroke
				(width 0)
				(type default)
			)
			(fill no)
			(layer "B.CrtYd")
		)
		(fp_line
			(start 0.3048 0.9906)
			(end -0.3048 0.9906)
			(stroke
				(width 0.1)
				(type default)
			)
			(layer "B.Fab")
		)
		(fp_line
			(start 0.3048 -0.1016)
			(end 0.3048 0.9906)
			(stroke
				(width 0.1)
				(type default)
			)
			(layer "B.Fab")
		)
		(fp_line
			(start -0.3048 0.9906)
			(end -0.3048 -0.1016)
			(stroke
				(width 0.1)
				(type default)
			)
			(layer "B.Fab")
		)
		(fp_line
			(start -0.3048 -0.1016)
			(end 0.3048 -0.1016)
			(stroke
				(width 0.1)
				(type default)
			)
			(layer "B.Fab")
		)
		(pad "1" smd rect
			(at 0 0)
			(size 0.508 0.508)
			(layers "B.Cu" "B.Mask" "B.Paste")
			(net "P3V3_STBY")
		)
		(pad "2" smd rect
			(at 0 0.889)
			(size 0.508 0.508)
			(layers "B.Cu" "B.Mask" "B.Paste")
			(net "GND")
		)
		(zone
			(layer "B.Cu")
			(hatch none 0.5)
			(connect_pads
				(clearance 0)
			)
			(min_thickness 0.25)
			(keepout
				(tracks not_allowed)
				(vias allowed)
				(pads allowed)
				(copperpour not_allowed)
				(footprints allowed)
			)
			(placement
				(enabled no)
				(sheetname "")
			)
			(fill
				(thermal_gap 0.5)
				(thermal_bridge_width 0.5)
				(island_removal_mode 0)
			)
			(polygon
				(pts
					(xy 448.056 -147.701) (xy 448.564 -147.701) (xy 448.564 -147.32) (xy 448.056 -147.32)
				)
			)
		)
		(zone
			(layer "B.Cu")
			(hatch none 0.5)
			(connect_pads
				(clearance 0)
			)
			(min_thickness 0.25)
			(keepout
				(tracks allowed)
				(vias not_allowed)
				(pads allowed)
				(copperpour not_allowed)
				(footprints allowed)
			)
			(placement
				(enabled no)
				(sheetname "")
			)
			(fill
				(thermal_gap 0.5)
				(thermal_bridge_width 0.5)
				(island_removal_mode 0)
			)
			(polygon
				(pts
					(xy 448.056 -147.32) (xy 448.564 -147.32) (xy 448.564 -147.701) (xy 448.056 -147.701)
				)
			)
		)
	)
	(footprint ""
		(layer "B.Cu")
		(at 483.0445 -48.514 -90)
		(property "Reference" "R9E1"
			(at 0 0 90)
			(layer "B.SilkS")
			(hide yes)
			(effects
				(font
					(size 1.27 1.27)
				)
				(justify mirror)
			)
		)
		(property "Value" ""
			(at 0 0 90)
			(layer "B.Fab")
			(effects
				(font
					(size 1.27 1.27)
				)
				(justify mirror)
			)
		)
		(duplicate_pad_numbers_are_jumpers no)
		(fp_poly
			(pts
				(xy 0.2794 -0.1016) (xy -0.2794 -0.1016) (xy -0.2794 0.9906) (xy 0.2794 0.9906)
			)
			(stroke
				(width 0)
				(type default)
			)
			(fill no)
			(layer "B.CrtYd")
		)
		(fp_line
			(start -0.2794 0.9906)
			(end -0.2794 -0.1016)
			(stroke
				(width 0.1)
				(type default)
			)
			(layer "B.Fab")
		)
		(fp_line
			(start 0.2794 0.9906)
			(end -0.2794 0.9906)
			(stroke
				(width 0.1)
				(type default)
			)
			(layer "B.Fab")
		)
		(fp_line
			(start -0.2794 -0.1016)
			(end 0.2794 -0.1016)
			(stroke
				(width 0.1)
				(type default)
			)
			(layer "B.Fab")
		)
		(fp_line
			(start 0.2794 -0.1016)
			(end 0.2794 0.9906)
			(stroke
				(width 0.1)
				(type default)
			)
			(layer "B.Fab")
		)
		(pad "1" smd rect
			(at 0 0 90)
			(size 0.508 0.508)
			(layers "B.Cu" "B.Mask" "B.Paste")
			(net "P3V3_STBY")
		)
		(pad "2" smd rect
			(at 0 0.889 90)
			(size 0.508 0.508)
			(layers "B.Cu" "B.Mask" "B.Paste")
			(net "PU_JTAG_SPRV_TDI")
		)
		(zone
			(layer "B.Cu")
			(hatch none 0.5)
			(connect_pads
				(clearance 0)
			)
			(min_thickness 0.25)
			(keepout
				(tracks not_allowed)
				(vias allowed)
				(pads allowed)
				(copperpour not_allowed)
				(footprints allowed)
			)
			(placement
				(enabled no)
				(sheetname "")
			)
			(fill
				(thermal_gap 0.5)
				(thermal_bridge_width 0.5)
				(island_removal_mode 0)
			)
			(polygon
				(pts
					(xy 482.4095 -48.26) (xy 482.4095 -48.768) (xy 482.7905 -48.768) (xy 482.7905 -48.26)
				)
			)
		)
		(zone
			(layer "B.Cu")
			(hatch none 0.5)
			(connect_pads
				(clearance 0)
			)
			(min_thickness 0.25)
			(keepout
				(tracks allowed)
				(vias not_allowed)
				(pads allowed)
				(copperpour not_allowed)
				(footprints allowed)
			)
			(placement
				(enabled no)
				(sheetname "")
			)
			(fill
				(thermal_gap 0.5)
				(thermal_bridge_width 0.5)
				(island_removal_mode 0)
			)
			(polygon
				(pts
					(xy 482.7905 -48.26) (xy 482.7905 -48.768) (xy 482.4095 -48.768) (xy 482.4095 -48.26)
				)
			)
		)
	)
	(footprint ""
		(layer "B.Cu")
		(at 484.691944 -17.934178 -90)
		(property "Reference" "C9G1"
			(at 0 0 90)
			(layer "B.SilkS")
			(hide yes)
			(effects
				(font
					(size 1.27 1.27)
				)
				(justify mirror)
			)
		)
		(property "Value" ""
			(at 0 0 90)
			(layer "B.Fab")
			(effects
				(font
					(size 1.27 1.27)
				)
				(justify mirror)
			)
		)
		(duplicate_pad_numbers_are_jumpers no)
		(fp_poly
			(pts
				(xy -0.3048 -0.1016) (xy -0.3048 0.9906) (xy 0.3048 0.9906) (xy 0.3048 -0.1016)
			)
			(stroke
				(width 0)
				(type default)
			)
			(fill no)
			(layer "B.CrtYd")
		)
		(fp_line
			(start -0.3048 0.9906)
			(end -0.3048 -0.1016)
			(stroke
				(width 0.1)
				(type default)
			)
			(layer "B.Fab")
		)
		(fp_line
			(start 0.3048 0.9906)
			(end -0.3048 0.9906)
			(stroke
				(width 0.1)
				(type default)
			)
			(layer "B.Fab")
		)
		(fp_line
			(start -0.3048 -0.1016)
			(end 0.3048 -0.1016)
			(stroke
				(width 0.1)
				(type default)
			)
			(layer "B.Fab")
		)
		(fp_line
			(start 0.3048 -0.1016)
			(end 0.3048 0.9906)
			(stroke
				(width 0.1)
				(type default)
			)
			(layer "B.Fab")
		)
		(pad "1" smd rect
			(at 0 0 90)
			(size 0.508 0.508)
			(layers "B.Cu" "B.Mask" "B.Paste")
			(net "LED_LAN_2_N")
		)
		(pad "2" smd rect
			(at 0 0.889 90)
			(size 0.508 0.508)
			(layers "B.Cu" "B.Mask" "B.Paste")
			(net "GND")
		)
		(zone
			(layer "B.Cu")
			(hatch none 0.5)
			(connect_pads
				(clearance 0)
			)
			(min_thickness 0.25)
			(keepout
				(tracks not_allowed)
				(vias allowed)
				(pads allowed)
				(copperpour not_allowed)
				(footprints allowed)
			)
			(placement
				(enabled no)
				(sheetname "")
			)
			(fill
				(thermal_gap 0.5)
				(thermal_bridge_width 0.5)
				(island_removal_mode 0)
			)
			(polygon
				(pts
					(xy 484.056944 -17.680178) (xy 484.056944 -18.188178) (xy 484.437944 -18.188178) (xy 484.437944 -17.680178)
				)
			)
		)
		(zone
			(layer "B.Cu")
			(hatch none 0.5)
			(connect_pads
				(clearance 0)
			)
			(min_thickness 0.25)
			(keepout
				(tracks allowed)
				(vias not_allowed)
				(pads allowed)
				(copperpour not_allowed)
				(footprints allowed)
			)
			(placement
				(enabled no)
				(sheetname "")
			)
			(fill
				(thermal_gap 0.5)
				(thermal_bridge_width 0.5)
				(island_removal_mode 0)
			)
			(polygon
				(pts
					(xy 484.437944 -17.680178) (xy 484.437944 -18.188178) (xy 484.056944 -18.188178) (xy 484.056944 -17.680178)
				)
			)
		)
	)
	(footprint ""
		(layer "B.Cu")
		(at 486.156 -113.2332 -90)
		(property "Reference" "C1M23"
			(at 0 0 90)
			(layer "B.SilkS")
			(hide yes)
			(effects
				(font
					(size 1.27 1.27)
				)
				(justify mirror)
			)
		)
		(property "Value" ""
			(at 0 0 90)
			(layer "B.Fab")
			(effects
				(font
					(size 1.27 1.27)
				)
				(justify mirror)
			)
		)
		(duplicate_pad_numbers_are_jumpers no)
		(fp_rect
			(start 0.3048 0.9906)
			(end -0.3048 -0.1016)
			(stroke
				(width 0)
				(type default)
			)
			(fill no)
			(layer "B.CrtYd")
		)
		(fp_line
			(start -0.3048 0.9906)
			(end -0.3048 -0.1016)
			(stroke
				(width 0.1)
				(type default)
			)
			(layer "B.Fab")
		)
		(fp_line
			(start 0.3048 0.9906)
			(end -0.3048 0.9906)
			(stroke
				(width 0.1)
				(type default)
			)
			(layer "B.Fab")
		)
		(fp_line
			(start -0.3048 -0.1016)
			(end 0.3048 -0.1016)
			(stroke
				(width 0.1)
				(type default)
			)
			(layer "B.Fab")
		)
		(fp_line
			(start 0.3048 -0.1016)
			(end 0.3048 0.9906)
			(stroke
				(width 0.1)
				(type default)
			)
			(layer "B.Fab")
		)
		(pad "1" smd rect
			(at 0 0 90)
			(size 0.508 0.508)
			(layers "B.Cu" "B.Mask" "B.Paste")
			(net "P12V_STBY")
		)
		(pad "2" smd rect
			(at 0 0.889 90)
			(size 0.508 0.508)
			(layers "B.Cu" "B.Mask" "B.Paste")
			(net "GND")
		)
		(zone
			(layer "B.Cu")
			(hatch none 0.5)
			(connect_pads
				(clearance 0)
			)
			(min_thickness 0.25)
			(keepout
				(tracks allowed)
				(vias not_allowed)
				(pads allowed)
				(copperpour not_allowed)
				(footprints allowed)
			)
			(placement
				(enabled no)
				(sheetname "")
			)
			(fill
				(thermal_gap 0.5)
				(thermal_bridge_width 0.5)
				(island_removal_mode 0)
			)
			(polygon
				(pts
					(xy 485.521 -112.9792) (xy 485.902 -112.9792) (xy 485.902 -113.4872) (xy 485.521 -113.4872)
				)
			)
		)
		(zone
			(layer "B.Cu")
			(hatch none 0.5)
			(connect_pads
				(clearance 0)
			)
			(min_thickness 0.25)
			(keepout
				(tracks not_allowed)
				(vias allowed)
				(pads allowed)
				(copperpour not_allowed)
				(footprints allowed)
			)
			(placement
				(enabled no)
				(sheetname "")
			)
			(fill
				(thermal_gap 0.5)
				(thermal_bridge_width 0.5)
				(island_removal_mode 0)
			)
			(polygon
				(pts
					(xy 485.521 -112.9792) (xy 485.902 -112.9792) (xy 485.902 -113.4872) (xy 485.521 -113.4872)
				)
			)
		)
	)
	(footprint ""
		(layer "B.Cu")
		(at 424.200574 -40.982646 180)
		(property "Reference" "C25W56"
			(at 0.8382 -0.67818 180)
			(unlocked yes)
			(layer "B.SilkS")
			(effects
				(font
					(size 0.4064 0.254)
					(thickness 0.1524)
				)
				(justify left mirror)
			)
		)
		(property "Value" ""
			(at 0 0 0)
			(layer "B.Fab")
			(effects
				(font
					(size 1.27 1.27)
				)
				(justify mirror)
			)
		)
		(duplicate_pad_numbers_are_jumpers no)
		(fp_poly
			(pts
				(xy -0.3048 -0.1016) (xy -0.3048 0.9906) (xy 0.3048 0.9906) (xy 0.3048 -0.1016)
			)
			(stroke
				(width 0)
				(type default)
			)
			(fill no)
			(layer "B.CrtYd")
		)
		(fp_line
			(start 0.3048 0.9906)
			(end -0.3048 0.9906)
			(stroke
				(width 0.1)
				(type default)
			)
			(layer "B.Fab")
		)
		(fp_line
			(start 0.3048 -0.1016)
			(end 0.3048 0.9906)
			(stroke
				(width 0.1)
				(type default)
			)
			(layer "B.Fab")
		)
		(fp_line
			(start -0.3048 0.9906)
			(end -0.3048 -0.1016)
			(stroke
				(width 0.1)
				(type default)
			)
			(layer "B.Fab")
		)
		(fp_line
			(start -0.3048 -0.1016)
			(end 0.3048 -0.1016)
			(stroke
				(width 0.1)
				(type default)
			)
			(layer "B.Fab")
		)
		(pad "1" smd rect
			(at 0 0)
			(size 0.508 0.508)
			(layers "B.Cu" "B.Mask" "B.Paste")
			(net "VCC_PA_3V3")
		)
		(pad "2" smd rect
			(at 0 0.889)
			(size 0.508 0.508)
			(layers "B.Cu" "B.Mask" "B.Paste")
			(net "GND")
		)
		(zone
			(layer "B.Cu")
			(hatch none 0.5)
			(connect_pads
				(clearance 0)
			)
			(min_thickness 0.25)
			(keepout
				(tracks not_allowed)
				(vias allowed)
				(pads allowed)
				(copperpour not_allowed)
				(footprints allowed)
			)
			(placement
				(enabled no)
				(sheetname "")
			)
			(fill
				(thermal_gap 0.5)
				(thermal_bridge_width 0.5)
				(island_removal_mode 0)
			)
			(polygon
				(pts
					(xy 423.946574 -41.617646) (xy 424.454574 -41.617646) (xy 424.454574 -41.236646) (xy 423.946574 -41.236646)
				)
			)
		)
		(zone
			(layer "B.Cu")
			(hatch none 0.5)
			(connect_pads
				(clearance 0)
			)
			(min_thickness 0.25)
			(keepout
				(tracks allowed)
				(vias not_allowed)
				(pads allowed)
				(copperpour not_allowed)
				(footprints allowed)
			)
			(placement
				(enabled no)
				(sheetname "")
			)
			(fill
				(thermal_gap 0.5)
				(thermal_bridge_width 0.5)
				(island_removal_mode 0)
			)
			(polygon
				(pts
					(xy 423.946574 -41.236646) (xy 424.454574 -41.236646) (xy 424.454574 -41.617646) (xy 423.946574 -41.617646)
				)
			)
		)
	)
	(footprint ""
		(layer "B.Cu")
		(at 295.153588 -66.330322 90)
		(property "Reference" "R4P21"
			(at 0 0 90)
			(layer "B.SilkS")
			(hide yes)
			(effects
				(font
					(size 1.27 1.27)
				)
				(justify mirror)
			)
		)
		(property "Value" ""
			(at 0 0 90)
			(layer "B.Fab")
			(effects
				(font
					(size 1.27 1.27)
				)
				(justify mirror)
			)
		)
		(duplicate_pad_numbers_are_jumpers no)
		(fp_poly
			(pts
				(xy 0.2794 -0.1016) (xy -0.2794 -0.1016) (xy -0.2794 0.9906) (xy 0.2794 0.9906)
			)
			(stroke
				(width 0)
				(type default)
			)
			(fill no)
			(layer "B.CrtYd")
		)
		(fp_line
			(start 0.2794 -0.1016)
			(end 0.2794 0.9906)
			(stroke
				(width 0.1)
				(type default)
			)
			(layer "B.Fab")
		)
		(fp_line
			(start -0.2794 -0.1016)
			(end 0.2794 -0.1016)
			(stroke
				(width 0.1)
				(type default)
			)
			(layer "B.Fab")
		)
		(fp_line
			(start 0.2794 0.9906)
			(end -0.2794 0.9906)
			(stroke
				(width 0.1)
				(type default)
			)
			(layer "B.Fab")
		)
		(fp_line
			(start -0.2794 0.9906)
			(end -0.2794 -0.1016)
			(stroke
				(width 0.1)
				(type default)
			)
			(layer "B.Fab")
		)
		(pad "1" smd rect
			(at 0 0 270)
			(size 0.508 0.508)
			(layers "B.Cu" "B.Mask" "B.Paste")
			(net "PVCCIO_CPU0")
		)
		(pad "2" smd rect
			(at 0 0.889 270)
			(size 0.508 0.508)
			(layers "B.Cu" "B.Mask" "B.Paste")
			(net "PU_CPU0_TSC_SYNC")
		)
		(zone
			(layer "B.Cu")
			(hatch none 0.5)
			(connect_pads
				(clearance 0)
			)
			(min_thickness 0.25)
			(keepout
				(tracks allowed)
				(vias not_allowed)
				(pads allowed)
				(copperpour not_allowed)
				(footprints allowed)
			)
			(placement
				(enabled no)
				(sheetname "")
			)
			(fill
				(thermal_gap 0.5)
				(thermal_bridge_width 0.5)
				(island_removal_mode 0)
			)
			(polygon
				(pts
					(xy 295.407588 -66.584322) (xy 295.407588 -66.076322) (xy 295.788588 -66.076322) (xy 295.788588 -66.584322)
				)
			)
		)
		(zone
			(layer "B.Cu")
			(hatch none 0.5)
			(connect_pads
				(clearance 0)
			)
			(min_thickness 0.25)
			(keepout
				(tracks not_allowed)
				(vias allowed)
				(pads allowed)
				(copperpour not_allowed)
				(footprints allowed)
			)
			(placement
				(enabled no)
				(sheetname "")
			)
			(fill
				(thermal_gap 0.5)
				(thermal_bridge_width 0.5)
				(island_removal_mode 0)
			)
			(polygon
				(pts
					(xy 295.788588 -66.584322) (xy 295.788588 -66.076322) (xy 295.407588 -66.076322) (xy 295.407588 -66.584322)
				)
			)
		)
	)
	(footprint ""
		(layer "B.Cu")
		(at 93.081348 -135.3312 -90)
		(property "Reference" "C8M8"
			(at 0 0 90)
			(layer "B.SilkS")
			(hide yes)
			(effects
				(font
					(size 1.27 1.27)
				)
				(justify mirror)
			)
		)
		(property "Value" ""
			(at 0 0 90)
			(layer "B.Fab")
			(effects
				(font
					(size 1.27 1.27)
				)
				(justify mirror)
			)
		)
		(duplicate_pad_numbers_are_jumpers no)
		(fp_rect
			(start 0.500126 1.598422)
			(end -0.500126 -0.201422)
			(stroke
				(width 0)
				(type default)
			)
			(fill no)
			(layer "B.CrtYd")
		)
		(fp_line
			(start -0.500126 1.598422)
			(end 0.500126 1.598422)
			(stroke
				(width 0.1)
				(type default)
			)
			(layer "B.Fab")
		)
		(fp_line
			(start 0.500126 1.598422)
			(end 0.500126 -0.201422)
			(stroke
				(width 0.1)
				(type default)
			)
			(layer "B.Fab")
		)
		(fp_line
			(start -0.500126 -0.201422)
			(end -0.500126 1.598422)
			(stroke
				(width 0.1)
				(type default)
			)
			(layer "B.Fab")
		)
		(fp_line
			(start 0.500126 -0.201422)
			(end -0.500126 -0.201422)
			(stroke
				(width 0.1)
				(type default)
			)
			(layer "B.Fab")
		)
		(pad "1" smd rect
			(at 0 0 180)
			(size 0.889 0.9906)
			(layers "B.Cu" "B.Mask" "B.Paste")
			(net "PVDDQ_KLM")
		)
		(pad "2" smd rect
			(at 0 1.397 180)
			(size 0.889 0.9906)
			(layers "B.Cu" "B.Mask" "B.Paste")
			(net "GND")
		)
		(zone
			(layer "B.Cu")
			(hatch none 0.5)
			(connect_pads
				(clearance 0)
			)
			(min_thickness 0.25)
			(keepout
				(tracks not_allowed)
				(vias allowed)
				(pads allowed)
				(copperpour not_allowed)
				(footprints allowed)
			)
			(placement
				(enabled no)
				(sheetname "")
			)
			(fill
				(thermal_gap 0.5)
				(thermal_bridge_width 0.5)
				(island_removal_mode 0)
			)
			(polygon
				(pts
					(xy 92.128848 -134.8359) (xy 92.636848 -134.8359) (xy 92.636848 -135.8265) (xy 92.128848 -135.8265)
				)
			)
		)
		(zone
			(layer "B.Cu")
			(hatch none 0.5)
			(connect_pads
				(clearance 0)
			)
			(min_thickness 0.25)
			(keepout
				(tracks allowed)
				(vias not_allowed)
				(pads allowed)
				(copperpour not_allowed)
				(footprints allowed)
			)
			(placement
				(enabled no)
				(sheetname "")
			)
			(fill
				(thermal_gap 0.5)
				(thermal_bridge_width 0.5)
				(island_removal_mode 0)
			)
			(polygon
				(pts
					(xy 92.128848 -134.8359) (xy 92.636848 -134.8359) (xy 92.636848 -135.8265) (xy 92.128848 -135.8265)
				)
			)
		)
	)
	(footprint ""
		(layer "B.Cu")
		(at 360.555794 -41.543986 90)
		(property "Reference" "R2T58"
			(at 0 0 90)
			(layer "B.SilkS")
			(hide yes)
			(effects
				(font
					(size 1.27 1.27)
				)
				(justify mirror)
			)
		)
		(property "Value" ""
			(at 0 0 90)
			(layer "B.Fab")
			(effects
				(font
					(size 1.27 1.27)
				)
				(justify mirror)
			)
		)
		(duplicate_pad_numbers_are_jumpers no)
		(fp_poly
			(pts
				(xy 0.2794 -0.1016) (xy -0.2794 -0.1016) (xy -0.2794 0.9906) (xy 0.2794 0.9906)
			)
			(stroke
				(width 0)
				(type default)
			)
			(fill no)
			(layer "B.CrtYd")
		)
		(fp_line
			(start 0.2794 -0.1016)
			(end 0.2794 0.9906)
			(stroke
				(width 0.1)
				(type default)
			)
			(layer "B.Fab")
		)
		(fp_line
			(start -0.2794 -0.1016)
			(end 0.2794 -0.1016)
			(stroke
				(width 0.1)
				(type default)
			)
			(layer "B.Fab")
		)
		(fp_line
			(start 0.2794 0.9906)
			(end -0.2794 0.9906)
			(stroke
				(width 0.1)
				(type default)
			)
			(layer "B.Fab")
		)
		(fp_line
			(start -0.2794 0.9906)
			(end -0.2794 -0.1016)
			(stroke
				(width 0.1)
				(type default)
			)
			(layer "B.Fab")
		)
		(pad "1" smd rect
			(at 0 0 270)
			(size 0.508 0.508)
			(layers "B.Cu" "B.Mask" "B.Paste")
			(net "H_CPU_ERR0_PCH_N")
		)
		(pad "2" smd rect
			(at 0 0.889 270)
			(size 0.508 0.508)
			(layers "B.Cu" "B.Mask" "B.Paste")
			(net "FM_CPU_ERR0_LVT3_K_N")
		)
		(zone
			(layer "B.Cu")
			(hatch none 0.5)
			(connect_pads
				(clearance 0)
			)
			(min_thickness 0.25)
			(keepout
				(tracks allowed)
				(vias not_allowed)
				(pads allowed)
				(copperpour not_allowed)
				(footprints allowed)
			)
			(placement
				(enabled no)
				(sheetname "")
			)
			(fill
				(thermal_gap 0.5)
				(thermal_bridge_width 0.5)
				(island_removal_mode 0)
			)
			(polygon
				(pts
					(xy 360.809794 -41.797986) (xy 360.809794 -41.289986) (xy 361.190794 -41.289986) (xy 361.190794 -41.797986)
				)
			)
		)
		(zone
			(layer "B.Cu")
			(hatch none 0.5)
			(connect_pads
				(clearance 0)
			)
			(min_thickness 0.25)
			(keepout
				(tracks not_allowed)
				(vias allowed)
				(pads allowed)
				(copperpour not_allowed)
				(footprints allowed)
			)
			(placement
				(enabled no)
				(sheetname "")
			)
			(fill
				(thermal_gap 0.5)
				(thermal_bridge_width 0.5)
				(island_removal_mode 0)
			)
			(polygon
				(pts
					(xy 361.190794 -41.797986) (xy 361.190794 -41.289986) (xy 360.809794 -41.289986) (xy 360.809794 -41.797986)
				)
			)
		)
	)
	(footprint ""
		(layer "B.Cu")
		(at 176.149 -76.327 -90)
		(property "Reference" "R6P17"
			(at 0 0 90)
			(layer "B.SilkS")
			(hide yes)
			(effects
				(font
					(size 1.27 1.27)
				)
				(justify mirror)
			)
		)
		(property "Value" ""
			(at 0 0 90)
			(layer "B.Fab")
			(effects
				(font
					(size 1.27 1.27)
				)
				(justify mirror)
			)
		)
		(duplicate_pad_numbers_are_jumpers no)
		(fp_poly
			(pts
				(xy 0.2794 -0.1016) (xy -0.2794 -0.1016) (xy -0.2794 0.9906) (xy 0.2794 0.9906)
			)
			(stroke
				(width 0)
				(type default)
			)
			(fill no)
			(layer "B.CrtYd")
		)
		(fp_line
			(start -0.2794 0.9906)
			(end -0.2794 -0.1016)
			(stroke
				(width 0.1)
				(type default)
			)
			(layer "B.Fab")
		)
		(fp_line
			(start 0.2794 0.9906)
			(end -0.2794 0.9906)
			(stroke
				(width 0.1)
				(type default)
			)
			(layer "B.Fab")
		)
		(fp_line
			(start -0.2794 -0.1016)
			(end 0.2794 -0.1016)
			(stroke
				(width 0.1)
				(type default)
			)
			(layer "B.Fab")
		)
		(fp_line
			(start 0.2794 -0.1016)
			(end 0.2794 0.9906)
			(stroke
				(width 0.1)
				(type default)
			)
			(layer "B.Fab")
		)
		(pad "1" smd rect
			(at 0 0 90)
			(size 0.508 0.508)
			(layers "B.Cu" "B.Mask" "B.Paste")
			(net "CLK_100M_CPU0_BCLK0_DP")
		)
		(pad "2" smd rect
			(at 0 0.889 90)
			(size 0.508 0.508)
			(layers "B.Cu" "B.Mask" "B.Paste")
			(net "GND")
		)
		(zone
			(layer "B.Cu")
			(hatch none 0.5)
			(connect_pads
				(clearance 0)
			)
			(min_thickness 0.25)
			(keepout
				(tracks not_allowed)
				(vias allowed)
				(pads allowed)
				(copperpour not_allowed)
				(footprints allowed)
			)
			(placement
				(enabled no)
				(sheetname "")
			)
			(fill
				(thermal_gap 0.5)
				(thermal_bridge_width 0.5)
				(island_removal_mode 0)
			)
			(polygon
				(pts
					(xy 175.514 -76.073) (xy 175.514 -76.581) (xy 175.895 -76.581) (xy 175.895 -76.073)
				)
			)
		)
		(zone
			(layer "B.Cu")
			(hatch none 0.5)
			(connect_pads
				(clearance 0)
			)
			(min_thickness 0.25)
			(keepout
				(tracks allowed)
				(vias not_allowed)
				(pads allowed)
				(copperpour not_allowed)
				(footprints allowed)
			)
			(placement
				(enabled no)
				(sheetname "")
			)
			(fill
				(thermal_gap 0.5)
				(thermal_bridge_width 0.5)
				(island_removal_mode 0)
			)
			(polygon
				(pts
					(xy 175.895 -76.073) (xy 175.895 -76.581) (xy 175.514 -76.581) (xy 175.514 -76.073)
				)
			)
		)
	)
	(footprint ""
		(layer "B.Cu")
		(at 457.5048 -52.483258)
		(property "Reference" "C1R5"
			(at 0 0 0)
			(layer "B.SilkS")
			(hide yes)
			(effects
				(font
					(size 1.27 1.27)
				)
				(justify mirror)
			)
		)
		(property "Value" ""
			(at 0 0 0)
			(layer "B.Fab")
			(effects
				(font
					(size 1.27 1.27)
				)
				(justify mirror)
			)
		)
		(duplicate_pad_numbers_are_jumpers no)
		(fp_poly
			(pts
				(xy -0.3048 -0.1016) (xy -0.3048 0.9906) (xy 0.3048 0.9906) (xy 0.3048 -0.1016)
			)
			(stroke
				(width 0)
				(type default)
			)
			(fill no)
			(layer "B.CrtYd")
		)
		(fp_line
			(start -0.3048 -0.1016)
			(end 0.3048 -0.1016)
			(stroke
				(width 0.1)
				(type default)
			)
			(layer "B.Fab")
		)
		(fp_line
			(start -0.3048 0.9906)
			(end -0.3048 -0.1016)
			(stroke
				(width 0.1)
				(type default)
			)
			(layer "B.Fab")
		)
		(fp_line
			(start 0.3048 -0.1016)
			(end 0.3048 0.9906)
			(stroke
				(width 0.1)
				(type default)
			)
			(layer "B.Fab")
		)
		(fp_line
			(start 0.3048 0.9906)
			(end -0.3048 0.9906)
			(stroke
				(width 0.1)
				(type default)
			)
			(layer "B.Fab")
		)
		(pad "1" smd rect
			(at 0 0 180)
			(size 0.508 0.508)
			(layers "B.Cu" "B.Mask" "B.Paste")
			(net "P3E_CPU0_PE3_OCP_TXN<2>")
		)
		(pad "2" smd rect
			(at 0 0.889 180)
			(size 0.508 0.508)
			(layers "B.Cu" "B.Mask" "B.Paste")
			(net "P3E_OCP_CPU0_PE3_C_TXN<2>")
		)
		(zone
			(layer "B.Cu")
			(hatch none 0.5)
			(connect_pads
				(clearance 0)
			)
			(min_thickness 0.25)
			(keepout
				(tracks allowed)
				(vias not_allowed)
				(pads allowed)
				(copperpour not_allowed)
				(footprints allowed)
			)
			(placement
				(enabled no)
				(sheetname "")
			)
			(fill
				(thermal_gap 0.5)
				(thermal_bridge_width 0.5)
				(island_removal_mode 0)
			)
			(polygon
				(pts
					(xy 457.7588 -52.229258) (xy 457.2508 -52.229258) (xy 457.2508 -51.848258) (xy 457.7588 -51.848258)
				)
			)
		)
	)
	(footprint ""
		(layer "B.Cu")
		(at 1.3462 -141.097 90)
		(property "Reference" "C9L11"
			(at 0 0 90)
			(layer "B.SilkS")
			(hide yes)
			(effects
				(font
					(size 1.27 1.27)
				)
				(justify mirror)
			)
		)
		(property "Value" ""
			(at 0 0 90)
			(layer "B.Fab")
			(effects
				(font
					(size 1.27 1.27)
				)
				(justify mirror)
			)
		)
		(duplicate_pad_numbers_are_jumpers no)
		(fp_rect
			(start -0.7239 -0.2159)
			(end 0.7239 1.9939)
			(stroke
				(width 0)
				(type default)
			)
			(fill no)
			(layer "B.CrtYd")
		)
		(fp_line
			(start 0.7239 -0.2159)
			(end 0.7239 1.9939)
			(stroke
				(width 0.1)
				(type default)
			)
			(layer "B.Fab")
		)
		(fp_line
			(start -0.7239 -0.2159)
			(end 0.7239 -0.2159)
			(stroke
				(width 0.1)
				(type default)
			)
			(layer "B.Fab")
		)
		(fp_line
			(start 0.7239 1.9939)
			(end -0.7239 1.9939)
			(stroke
				(width 0.1)
				(type default)
			)
			(layer "B.Fab")
		)
		(fp_line
			(start -0.7239 1.9939)
			(end -0.7239 -0.2159)
			(stroke
				(width 0.1)
				(type default)
			)
			(layer "B.Fab")
		)
		(pad "1" smd rect
			(at 0 0 270)
			(size 1.27 1.016)
			(layers "B.Cu" "B.Mask" "B.Paste")
			(net "VR_FET_SW_P12V_STBY_PVDDQ_KLM")
		)
		(pad "2" smd rect
			(at 0 1.778 270)
			(size 1.27 1.016)
			(layers "B.Cu" "B.Mask" "B.Paste")
			(net "GND")
		)
		(zone
			(layer "B.Cu")
			(hatch none 0.5)
			(connect_pads
				(clearance 0)
			)
			(min_thickness 0.25)
			(keepout
				(tracks not_allowed)
				(vias allowed)
				(pads allowed)
				(copperpour not_allowed)
				(footprints allowed)
			)
			(placement
				(enabled no)
				(sheetname "")
			)
			(fill
				(thermal_gap 0.5)
				(thermal_bridge_width 0.5)
				(island_removal_mode 0)
			)
			(polygon
				(pts
					(xy 1.8542 -140.462) (xy 2.6162 -140.462) (xy 2.6162 -141.732) (xy 1.8542 -141.732)
				)
			)
		)
	)
	(footprint ""
		(layer "B.Cu")
		(at 97.587054 -79.60614 180)
		(property "Reference" "C8P13"
			(at 0 0 0)
			(layer "B.SilkS")
			(hide yes)
			(effects
				(font
					(size 1.27 1.27)
				)
				(justify mirror)
			)
		)
		(property "Value" ""
			(at 0 0 0)
			(layer "B.Fab")
			(effects
				(font
					(size 1.27 1.27)
				)
				(justify mirror)
			)
		)
		(duplicate_pad_numbers_are_jumpers no)
		(fp_poly
			(pts
				(xy 0.7239 -0.2159) (xy -0.7239 -0.2159) (xy -0.7239 1.9939) (xy 0.7239 1.9939)
			)
			(stroke
				(width 0)
				(type default)
			)
			(fill no)
			(layer "B.CrtYd")
		)
		(fp_line
			(start 0.7239 1.9939)
			(end -0.7239 1.9939)
			(stroke
				(width 0.1)
				(type default)
			)
			(layer "B.Fab")
		)
		(fp_line
			(start 0.7239 -0.2159)
			(end 0.7239 1.9939)
			(stroke
				(width 0.1)
				(type default)
			)
			(layer "B.Fab")
		)
		(fp_line
			(start -0.7239 1.9939)
			(end -0.7239 -0.2159)
			(stroke
				(width 0.1)
				(type default)
			)
			(layer "B.Fab")
		)
		(fp_line
			(start -0.7239 -0.2159)
			(end 0.7239 -0.2159)
			(stroke
				(width 0.1)
				(type default)
			)
			(layer "B.Fab")
		)
		(pad "1" smd rect
			(at 0 0)
			(size 1.27 1.016)
			(layers "B.Cu" "B.Mask" "B.Paste")
			(net "PVCCIN_CPU1")
		)
		(pad "2" smd rect
			(at 0 1.778)
			(size 1.27 1.016)
			(layers "B.Cu" "B.Mask" "B.Paste")
			(net "GND")
		)
		(zone
			(layer "B.Cu")
			(hatch none 0.5)
			(connect_pads
				(clearance 0)
			)
			(min_thickness 0.25)
			(keepout
				(tracks not_allowed)
				(vias allowed)
				(pads allowed)
				(copperpour not_allowed)
				(footprints allowed)
			)
			(placement
				(enabled no)
				(sheetname "")
			)
			(fill
				(thermal_gap 0.5)
				(thermal_bridge_width 0.5)
				(island_removal_mode 0)
			)
			(polygon
				(pts
					(xy 96.952054 -80.11414) (xy 98.222054 -80.11414) (xy 98.222054 -80.87614) (xy 96.952054 -80.87614)
				)
			)
		)
	)
	(footprint ""
		(layer "B.Cu")
		(at 104.521254 -77.82814)
		(property "Reference" "C8P15"
			(at 0 0 0)
			(layer "B.SilkS")
			(hide yes)
			(effects
				(font
					(size 1.27 1.27)
				)
				(justify mirror)
			)
		)
		(property "Value" ""
			(at 0 0 0)
			(layer "B.Fab")
			(effects
				(font
					(size 1.27 1.27)
				)
				(justify mirror)
			)
		)
		(duplicate_pad_numbers_are_jumpers no)
		(fp_poly
			(pts
				(xy 0.7239 -0.2159) (xy -0.7239 -0.2159) (xy -0.7239 1.9939) (xy 0.7239 1.9939)
			)
			(stroke
				(width 0)
				(type default)
			)
			(fill no)
			(layer "B.CrtYd")
		)
		(fp_line
			(start -0.7239 -0.2159)
			(end 0.7239 -0.2159)
			(stroke
				(width 0.1)
				(type default)
			)
			(layer "B.Fab")
		)
		(fp_line
			(start -0.7239 1.9939)
			(end -0.7239 -0.2159)
			(stroke
				(width 0.1)
				(type default)
			)
			(layer "B.Fab")
		)
		(fp_line
			(start 0.7239 -0.2159)
			(end 0.7239 1.9939)
			(stroke
				(width 0.1)
				(type default)
			)
			(layer "B.Fab")
		)
		(fp_line
			(start 0.7239 1.9939)
			(end -0.7239 1.9939)
			(stroke
				(width 0.1)
				(type default)
			)
			(layer "B.Fab")
		)
		(pad "1" smd rect
			(at 0 0 180)
			(size 1.27 1.016)
			(layers "B.Cu" "B.Mask" "B.Paste")
			(net "PVCCMCP_CPU1")
		)
		(pad "2" smd rect
			(at 0 1.778 180)
			(size 1.27 1.016)
			(layers "B.Cu" "B.Mask" "B.Paste")
			(net "GND")
		)
		(zone
			(layer "B.Cu")
			(hatch none 0.5)
			(connect_pads
				(clearance 0)
			)
			(min_thickness 0.25)
			(keepout
				(tracks not_allowed)
				(vias allowed)
				(pads allowed)
				(copperpour not_allowed)
				(footprints allowed)
			)
			(placement
				(enabled no)
				(sheetname "")
			)
			(fill
				(thermal_gap 0.5)
				(thermal_bridge_width 0.5)
				(island_removal_mode 0)
			)
			(polygon
				(pts
					(xy 105.156254 -77.32014) (xy 103.886254 -77.32014) (xy 103.886254 -76.55814) (xy 105.156254 -76.55814)
				)
			)
		)
	)
	(footprint ""
		(layer "B.Cu")
		(at 198.605648 -93.835982 90)
		(property "Reference" "C4C4"
			(at 0 0 90)
			(layer "B.SilkS")
			(hide yes)
			(effects
				(font
					(size 1.27 1.27)
				)
				(justify mirror)
			)
		)
		(property "Value" "*"
			(at -1.1811 -2.8194 90)
			(unlocked yes)
			(layer "B.Fab")
			(hide yes)
			(effects
				(font
					(size 1.27 1.016)
					(thickness 0.1524)
				)
				(justify mirror)
			)
		)
		(property "Device Type" "SC1U10V2KX-4-GP_SMD-BCG6-SC1U1A"
			(at -1.1811 -4.3434 90)
			(unlocked yes)
			(layer "B.Fab")
			(hide yes)
			(effects
				(font
					(size 1.27 1.016)
					(thickness 0.1524)
				)
				(justify mirror)
			)
		)
		(duplicate_pad_numbers_are_jumpers no)
		(fp_rect
			(start 0.4318 0.9525)
			(end -0.4318 -0.9525)
			(stroke
				(width 0)
				(type default)
			)
			(fill no)
			(layer "B.CrtYd")
		)
		(fp_rect
			(start 0.4318 0.9525)
			(end -0.4318 -0.9525)
			(stroke
				(width 0)
				(type default)
			)
			(fill no)
			(layer "B.Fab")
		)
		(pad "1" smd custom
			(at 0 -0.4445 270)
			(size 0.1524 0.1524)
			(layers "B.Cu" "B.Mask" "B.Paste")
			(net "P5V_STBY")
			(options
				(clearance outline)
				(anchor circle)
			)
			(primitives
				(gr_poly
					(pts
						(arc
							(start 0.3048 0.2032)
							(mid 0.275042 0.275042)
							(end 0.2032 0.3048)
						)
						(arc
							(start -0.2032 0.3048)
							(mid -0.275042 0.275042)
							(end -0.3048 0.2032)
						)
						(arc
							(start -0.3048 -0.2032)
							(mid -0.275042 -0.275042)
							(end -0.2032 -0.3048)
						)
						(arc
							(start 0.2032 -0.3048)
							(mid 0.275042 -0.275042)
							(end 0.3048 -0.2032)
						)
					)
					(width 0)
					(fill yes)
				)
			)
		)
		(pad "2" smd custom
			(at 0 0.4445 270)
			(size 0.1524 0.1524)
			(layers "B.Cu" "B.Mask" "B.Paste")
			(net "GND")
			(options
				(clearance outline)
				(anchor circle)
			)
			(primitives
				(gr_poly
					(pts
						(arc
							(start 0.3048 0.2032)
							(mid 0.275042 0.275042)
							(end 0.2032 0.3048)
						)
						(arc
							(start -0.2032 0.3048)
							(mid -0.275042 0.275042)
							(end -0.3048 0.2032)
						)
						(arc
							(start -0.3048 -0.2032)
							(mid -0.275042 -0.275042)
							(end -0.2032 -0.3048)
						)
						(arc
							(start 0.2032 -0.3048)
							(mid 0.275042 -0.275042)
							(end 0.3048 -0.2032)
						)
					)
					(width 0)
					(fill yes)
				)
			)
		)
	)
	(footprint ""
		(layer "B.Cu")
		(at 264.035286 -73.51014)
		(property "Reference" "C5P34"
			(at 0 0 0)
			(layer "B.SilkS")
			(hide yes)
			(effects
				(font
					(size 1.27 1.27)
				)
				(justify mirror)
			)
		)
		(property "Value" ""
			(at 0 0 0)
			(layer "B.Fab")
			(effects
				(font
					(size 1.27 1.27)
				)
				(justify mirror)
			)
		)
		(duplicate_pad_numbers_are_jumpers no)
		(fp_poly
			(pts
				(xy 0.7239 -0.2159) (xy -0.7239 -0.2159) (xy -0.7239 1.9939) (xy 0.7239 1.9939)
			)
			(stroke
				(width 0)
				(type default)
			)
			(fill no)
			(layer "B.CrtYd")
		)
		(fp_line
			(start -0.7239 -0.2159)
			(end 0.7239 -0.2159)
			(stroke
				(width 0.1)
				(type default)
			)
			(layer "B.Fab")
		)
		(fp_line
			(start -0.7239 1.9939)
			(end -0.7239 -0.2159)
			(stroke
				(width 0.1)
				(type default)
			)
			(layer "B.Fab")
		)
		(fp_line
			(start 0.7239 -0.2159)
			(end 0.7239 1.9939)
			(stroke
				(width 0.1)
				(type default)
			)
			(layer "B.Fab")
		)
		(fp_line
			(start 0.7239 1.9939)
			(end -0.7239 1.9939)
			(stroke
				(width 0.1)
				(type default)
			)
			(layer "B.Fab")
		)
		(pad "1" smd rect
			(at 0 0 180)
			(size 1.27 1.016)
			(layers "B.Cu" "B.Mask" "B.Paste")
			(net "PVCCIN_CPU0")
		)
		(pad "2" smd rect
			(at 0 1.778 180)
			(size 1.27 1.016)
			(layers "B.Cu" "B.Mask" "B.Paste")
			(net "GND")
		)
		(zone
			(layer "B.Cu")
			(hatch none 0.5)
			(connect_pads
				(clearance 0)
			)
			(min_thickness 0.25)
			(keepout
				(tracks not_allowed)
				(vias allowed)
				(pads allowed)
				(copperpour not_allowed)
				(footprints allowed)
			)
			(placement
				(enabled no)
				(sheetname "")
			)
			(fill
				(thermal_gap 0.5)
				(thermal_bridge_width 0.5)
				(island_removal_mode 0)
			)
			(polygon
				(pts
					(xy 264.670286 -73.00214) (xy 263.400286 -73.00214) (xy 263.400286 -72.24014) (xy 264.670286 -72.24014)
				)
			)
		)
	)
	(footprint ""
		(layer "B.Cu")
		(at 29.699458 -152.078436 90)
		(property "Reference" "J9L1"
			(at 2.200148 37.737542 0)
			(unlocked yes)
			(layer "B.SilkS")
			(effects
				(font
					(size 0.7874 0.5842)
					(thickness 0.1524)
				)
				(justify left mirror)
			)
		)
		(property "Value" ""
			(at 0 0 90)
			(layer "B.Fab")
			(effects
				(font
					(size 1.27 1.27)
				)
				(justify mirror)
			)
		)
		(duplicate_pad_numbers_are_jumpers no)
		(fp_line
			(start 0.94996 -7.675118)
			(end -5.5499 -7.675118)
			(stroke
				(width 0.1524)
				(type default)
			)
			(layer "B.SilkS")
		)
		(fp_line
			(start -5.5499 -7.675118)
			(end -5.5499 -1.480058)
			(stroke
				(width 0.1524)
				(type default)
			)
			(layer "B.SilkS")
		)
		(fp_line
			(start 0.94996 -1.480058)
			(end 0.94996 -7.675118)
			(stroke
				(width 0.1524)
				(type default)
			)
			(layer "B.SilkS")
		)
		(fp_line
			(start -5.5499 128.130046)
			(end -5.5499 134.325106)
			(stroke
				(width 0.1524)
				(type default)
			)
			(layer "B.SilkS")
		)
		(fp_line
			(start 0.94996 134.325106)
			(end 0.94996 128.130046)
			(stroke
				(width 0.1524)
				(type default)
			)
			(layer "B.SilkS")
		)
		(fp_line
			(start -5.5499 134.325106)
			(end 0.94996 134.325106)
			(stroke
				(width 0.1524)
				(type default)
			)
			(layer "B.SilkS")
		)
		(fp_poly
			(pts
				(xy 2.213102 -0.47498) (xy 2.213102 0.54102) (xy 0.943102 0.03302)
			)
			(stroke
				(width 0)
				(type default)
			)
			(fill yes)
			(layer "B.SilkS")
		)
		(fp_poly
			(pts
				(xy 0.94996 -7.675118) (xy 0.94996 134.325106) (xy -5.5499 134.325106) (xy -5.5499 -7.675118)
			)
			(stroke
				(width 0)
				(type default)
			)
			(fill no)
			(layer "B.CrtYd")
		)
		(fp_line
			(start 0.94996 -7.675118)
			(end -5.5499 -7.675118)
			(stroke
				(width 0.1)
				(type default)
			)
			(layer "B.Fab")
		)
		(fp_line
			(start -5.5499 -7.675118)
			(end -5.5499 134.325106)
			(stroke
				(width 0.1)
				(type default)
			)
			(layer "B.Fab")
		)
		(fp_line
			(start 0.94996 134.325106)
			(end 0.94996 -7.675118)
			(stroke
				(width 0.1)
				(type default)
			)
			(layer "B.Fab")
		)
		(fp_line
			(start -5.5499 134.325106)
			(end 0.94996 134.325106)
			(stroke
				(width 0.1)
				(type default)
			)
			(layer "B.Fab")
		)
		(fp_poly
			(pts
				(xy 2.984246 -0.461264) (xy 2.984246 0.554736) (xy 1.714246 0.046736)
			)
			(stroke
				(width 0)
				(type default)
			)
			(fill yes)
			(layer "B.Fab")
		)
		(fp_text user "145"
			(at -6.085586 2.299462 0)
			(unlocked yes)
			(layer "B.SilkS")
			(effects
				(font
					(size 0.7874 0.5842)
					(thickness 0.1524)
				)
				(justify left mirror)
			)
		)
		(fp_text user "77"
			(at 1.50495 65.7733 0)
			(unlocked yes)
			(layer "B.SilkS")
			(effects
				(font
					(size 0.7874 0.5842)
					(thickness 0.1524)
				)
				(justify left mirror)
			)
		)
		(fp_text user "221"
			(at -5.673852 67.074542 0)
			(unlocked yes)
			(layer "B.SilkS")
			(effects
				(font
					(size 0.7874 0.5842)
					(thickness 0.1524)
				)
				(justify left mirror)
			)
		)
		(fp_text user "78"
			(at 1.437894 71.240142 0)
			(unlocked yes)
			(layer "B.SilkS")
			(effects
				(font
					(size 0.7874 0.5842)
					(thickness 0.1524)
				)
				(justify left mirror)
			)
		)
		(fp_text user "222"
			(at -6.110732 71.94804 0)
			(unlocked yes)
			(layer "B.SilkS")
			(effects
				(font
					(size 0.7874 0.5842)
					(thickness 0.1524)
				)
				(justify left mirror)
			)
		)
		(fp_text user "144"
			(at 1.565148 129.304542 0)
			(unlocked yes)
			(layer "B.SilkS")
			(effects
				(font
					(size 0.7874 0.5842)
					(thickness 0.1524)
				)
				(justify left mirror)
			)
		)
		(fp_text user "288"
			(at -6.181852 129.812542 0)
			(unlocked yes)
			(layer "B.SilkS")
			(effects
				(font
					(size 0.7874 0.5842)
					(thickness 0.1524)
				)
				(justify left mirror)
			)
		)
		(fp_text user "145"
			(at -2.853182 -1.478788 90)
			(unlocked yes)
			(layer "B.Fab")
			(effects
				(font
					(size 0.7874 0.5842)
					(thickness 0.1524)
				)
				(justify left mirror)
			)
		)
		(fp_text user "77"
			(at 0.321818 65.831212 90)
			(unlocked yes)
			(layer "B.Fab")
			(effects
				(font
					(size 0.7874 0.5842)
					(thickness 0.1524)
				)
				(justify left mirror)
			)
		)
		(fp_text user "221"
			(at -3.488182 65.831212 90)
			(unlocked yes)
			(layer "B.Fab")
			(effects
				(font
					(size 0.7874 0.5842)
					(thickness 0.1524)
				)
				(justify left mirror)
			)
		)
		(fp_text user "78"
			(at 0.321818 69.641212 90)
			(unlocked yes)
			(layer "B.Fab")
			(effects
				(font
					(size 0.7874 0.5842)
					(thickness 0.1524)
				)
				(justify left mirror)
			)
		)
		(fp_text user "222"
			(at -3.488182 69.641212 90)
			(unlocked yes)
			(layer "B.Fab")
			(effects
				(font
					(size 0.7874 0.5842)
					(thickness 0.1524)
				)
				(justify left mirror)
			)
		)
		(fp_text user "144"
			(at 0.321818 128.061212 90)
			(unlocked yes)
			(layer "B.Fab")
			(effects
				(font
					(size 0.7874 0.5842)
					(thickness 0.1524)
				)
				(justify left mirror)
			)
		)
		(fp_text user "288"
			(at -2.853182 128.061212 90)
			(unlocked yes)
			(layer "B.Fab")
			(effects
				(font
					(size 0.7874 0.5842)
					(thickness 0.1524)
				)
				(justify left mirror)
			)
		)
		(pad "" thru_hole circle
			(at -2.29997 -5.649976 270)
			(size 2.8194 2.8194)
			(drill 2.4384)
			(layers "*.Cu" "*.Mask")
			(remove_unused_layers no)
			(clearance 0.127)
			(thermal_gap 0.127)
		)
		(pad "" thru_hole oval
			(at -2.29997 68.90004 270)
			(size 2.8194 1.5748)
			(drill oval 2.4384 1.1938)
			(layers "*.Cu" "*.Mask")
			(remove_unused_layers no)
			(clearance 0.127)
			(thermal_gap 0.127)
		)
		(pad "" thru_hole circle
			(at -2.29997 132.299964 270)
			(size 2.8194 2.8194)
			(drill 2.4384)
			(layers "*.Cu" "*.Mask")
			(remove_unused_layers no)
			(clearance 0.127)
			(thermal_gap 0.127)
		)
		(pad "1" smd rect
			(at 0 0 270)
			(size 1.8034 0.508)
			(layers "B.Cu" "B.Mask" "B.Paste")
			(net "P12V_NVDIMM_KLM")
		)
		(pad "2" smd rect
			(at 0 0.849884 270)
			(size 1.8034 0.508)
			(layers "B.Cu" "B.Mask" "B.Paste")
			(net "GND")
		)
		(pad "3" smd rect
			(at 0 1.700022 270)
			(size 1.8034 0.508)
			(layers "B.Cu" "B.Mask" "B.Paste")
			(net "M_M_DQ<4>")
		)
		(pad "4" smd rect
			(at 0 2.549906 270)
			(size 1.8034 0.508)
			(layers "B.Cu" "B.Mask" "B.Paste")
			(net "GND")
		)
		(pad "5" smd rect
			(at 0 3.400044 270)
			(size 1.8034 0.508)
			(layers "B.Cu" "B.Mask" "B.Paste")
			(net "M_M_DQ<0>")
		)
		(pad "6" smd rect
			(at 0 4.249928 270)
			(size 1.8034 0.508)
			(layers "B.Cu" "B.Mask" "B.Paste")
			(net "GND")
		)
		(pad "7" smd rect
			(at 0 5.100066 270)
			(size 1.8034 0.508)
			(layers "B.Cu" "B.Mask" "B.Paste")
			(net "M_M_DQS_DP<9>")
		)
		(pad "8" smd rect
			(at 0 5.94995 270)
			(size 1.8034 0.508)
			(layers "B.Cu" "B.Mask" "B.Paste")
			(net "M_M_DQS_DN<9>")
		)
		(pad "9" smd rect
			(at 0 6.800088 270)
			(size 1.8034 0.508)
			(layers "B.Cu" "B.Mask" "B.Paste")
			(net "GND")
		)
		(pad "10" smd rect
			(at 0 7.649972 270)
			(size 1.8034 0.508)
			(layers "B.Cu" "B.Mask" "B.Paste")
			(net "M_M_DQ<6>")
		)
		(pad "11" smd rect
			(at 0 8.50011 270)
			(size 1.8034 0.508)
			(layers "B.Cu" "B.Mask" "B.Paste")
			(net "GND")
		)
		(pad "12" smd rect
			(at 0 9.349994 270)
			(size 1.8034 0.508)
			(layers "B.Cu" "B.Mask" "B.Paste")
			(net "M_M_DQ<2>")
		)
		(pad "13" smd rect
			(at 0 10.199878 270)
			(size 1.8034 0.508)
			(layers "B.Cu" "B.Mask" "B.Paste")
			(net "GND")
		)
		(pad "14" smd rect
			(at 0 11.050016 270)
			(size 1.8034 0.508)
			(layers "B.Cu" "B.Mask" "B.Paste")
			(net "M_M_DQ<12>")
		)
		(pad "15" smd rect
			(at 0 11.8999 270)
			(size 1.8034 0.508)
			(layers "B.Cu" "B.Mask" "B.Paste")
			(net "GND")
		)
		(pad "16" smd rect
			(at 0 12.750038 270)
			(size 1.8034 0.508)
			(layers "B.Cu" "B.Mask" "B.Paste")
			(net "M_M_DQ<8>")
		)
		(pad "17" smd rect
			(at 0 13.599922 270)
			(size 1.8034 0.508)
			(layers "B.Cu" "B.Mask" "B.Paste")
			(net "GND")
		)
		(pad "18" smd rect
			(at 0 14.45006 270)
			(size 1.8034 0.508)
			(layers "B.Cu" "B.Mask" "B.Paste")
			(net "M_M_DQS_DP<10>")
		)
		(pad "19" smd rect
			(at 0 15.299944 270)
			(size 1.8034 0.508)
			(layers "B.Cu" "B.Mask" "B.Paste")
			(net "M_M_DQS_DN<10>")
		)
		(pad "20" smd rect
			(at 0 16.150082 270)
			(size 1.8034 0.508)
			(layers "B.Cu" "B.Mask" "B.Paste")
			(net "GND")
		)
		(pad "21" smd rect
			(at 0 16.999966 270)
			(size 1.8034 0.508)
			(layers "B.Cu" "B.Mask" "B.Paste")
			(net "M_M_DQ<14>")
		)
		(pad "22" smd rect
			(at 0 17.850104 270)
			(size 1.8034 0.508)
			(layers "B.Cu" "B.Mask" "B.Paste")
			(net "GND")
		)
		(pad "23" smd rect
			(at 0 18.699988 270)
			(size 1.8034 0.508)
			(layers "B.Cu" "B.Mask" "B.Paste")
			(net "M_M_DQ<10>")
		)
		(pad "24" smd rect
			(at 0 19.550126 270)
			(size 1.8034 0.508)
			(layers "B.Cu" "B.Mask" "B.Paste")
			(net "GND")
		)
		(pad "25" smd rect
			(at 0 20.40001 270)
			(size 1.8034 0.508)
			(layers "B.Cu" "B.Mask" "B.Paste")
			(net "M_M_DQ<20>")
		)
		(pad "26" smd rect
			(at 0 21.249894 270)
			(size 1.8034 0.508)
			(layers "B.Cu" "B.Mask" "B.Paste")
			(net "GND")
		)
		(pad "27" smd rect
			(at 0 22.100032 270)
			(size 1.8034 0.508)
			(layers "B.Cu" "B.Mask" "B.Paste")
			(net "M_M_DQ<16>")
		)
		(pad "28" smd rect
			(at 0 22.949916 270)
			(size 1.8034 0.508)
			(layers "B.Cu" "B.Mask" "B.Paste")
			(net "GND")
		)
		(pad "29" smd rect
			(at 0 23.800054 270)
			(size 1.8034 0.508)
			(layers "B.Cu" "B.Mask" "B.Paste")
			(net "M_M_DQS_DP<11>")
		)
		(pad "30" smd rect
			(at 0 24.649938 270)
			(size 1.8034 0.508)
			(layers "B.Cu" "B.Mask" "B.Paste")
			(net "M_M_DQS_DN<11>")
		)
		(pad "31" smd rect
			(at 0 25.500076 270)
			(size 1.8034 0.508)
			(layers "B.Cu" "B.Mask" "B.Paste")
			(net "GND")
		)
		(pad "32" smd rect
			(at 0 26.34996 270)
			(size 1.8034 0.508)
			(layers "B.Cu" "B.Mask" "B.Paste")
			(net "M_M_DQ<22>")
		)
		(pad "33" smd rect
			(at 0 27.200098 270)
			(size 1.8034 0.508)
			(layers "B.Cu" "B.Mask" "B.Paste")
			(net "GND")
		)
		(pad "34" smd rect
			(at 0 28.049982 270)
			(size 1.8034 0.508)
			(layers "B.Cu" "B.Mask" "B.Paste")
			(net "M_M_DQ<18>")
		)
		(pad "35" smd rect
			(at 0 28.90012 270)
			(size 1.8034 0.508)
			(layers "B.Cu" "B.Mask" "B.Paste")
			(net "GND")
		)
		(pad "36" smd rect
			(at 0 29.750004 270)
			(size 1.8034 0.508)
			(layers "B.Cu" "B.Mask" "B.Paste")
			(net "M_M_DQ<28>")
		)
		(pad "37" smd rect
			(at 0 30.599888 270)
			(size 1.8034 0.508)
			(layers "B.Cu" "B.Mask" "B.Paste")
			(net "GND")
		)
		(pad "38" smd rect
			(at 0 31.450026 270)
			(size 1.8034 0.508)
			(layers "B.Cu" "B.Mask" "B.Paste")
			(net "M_M_DQ<24>")
		)
		(pad "39" smd rect
			(at 0 32.29991 270)
			(size 1.8034 0.508)
			(layers "B.Cu" "B.Mask" "B.Paste")
			(net "GND")
		)
		(pad "40" smd rect
			(at 0 33.150048 270)
			(size 1.8034 0.508)
			(layers "B.Cu" "B.Mask" "B.Paste")
			(net "M_M_DQS_DP<12>")
		)
		(pad "41" smd rect
			(at 0 33.999932 270)
			(size 1.8034 0.508)
			(layers "B.Cu" "B.Mask" "B.Paste")
			(net "M_M_DQS_DN<12>")
		)
		(pad "42" smd rect
			(at 0 34.85007 270)
			(size 1.8034 0.508)
			(layers "B.Cu" "B.Mask" "B.Paste")
			(net "GND")
		)
		(pad "43" smd rect
			(at 0 35.699954 270)
			(size 1.8034 0.508)
			(layers "B.Cu" "B.Mask" "B.Paste")
			(net "M_M_DQ<30>")
		)
		(pad "44" smd rect
			(at 0 36.550092 270)
			(size 1.8034 0.508)
			(layers "B.Cu" "B.Mask" "B.Paste")
			(net "GND")
		)
		(pad "45" smd rect
			(at 0 37.399976 270)
			(size 1.8034 0.508)
			(layers "B.Cu" "B.Mask" "B.Paste")
			(net "M_M_DQ<26>")
		)
		(pad "46" smd rect
			(at 0 38.250114 270)
			(size 1.8034 0.508)
			(layers "B.Cu" "B.Mask" "B.Paste")
			(net "GND")
		)
		(pad "47" smd rect
			(at 0 39.099998 270)
			(size 1.8034 0.508)
			(layers "B.Cu" "B.Mask" "B.Paste")
			(net "M_M_ECC<4>")
		)
		(pad "48" smd rect
			(at 0 39.949882 270)
			(size 1.8034 0.508)
			(layers "B.Cu" "B.Mask" "B.Paste")
			(net "GND")
		)
		(pad "49" smd rect
			(at 0 40.80002 270)
			(size 1.8034 0.508)
			(layers "B.Cu" "B.Mask" "B.Paste")
			(net "M_M_ECC<0>")
		)
		(pad "50" smd rect
			(at 0 41.649904 270)
			(size 1.8034 0.508)
			(layers "B.Cu" "B.Mask" "B.Paste")
			(net "GND")
		)
		(pad "51" smd rect
			(at 0 42.500042 270)
			(size 1.8034 0.508)
			(layers "B.Cu" "B.Mask" "B.Paste")
			(net "M_M_DQS_DP<17>")
		)
		(pad "52" smd rect
			(at 0 43.349926 270)
			(size 1.8034 0.508)
			(layers "B.Cu" "B.Mask" "B.Paste")
			(net "M_M_DQS_DN<17>")
		)
		(pad "53" smd rect
			(at 0 44.200064 270)
			(size 1.8034 0.508)
			(layers "B.Cu" "B.Mask" "B.Paste")
			(net "GND")
		)
		(pad "54" smd rect
			(at 0 45.049948 270)
			(size 1.8034 0.508)
			(layers "B.Cu" "B.Mask" "B.Paste")
			(net "M_M_ECC<6>")
		)
		(pad "55" smd rect
			(at 0 45.900086 270)
			(size 1.8034 0.508)
			(layers "B.Cu" "B.Mask" "B.Paste")
			(net "GND")
		)
		(pad "56" smd rect
			(at 0 46.74997 270)
			(size 1.8034 0.508)
			(layers "B.Cu" "B.Mask" "B.Paste")
			(net "M_M_ECC<2>")
		)
		(pad "57" smd rect
			(at 0 47.600108 270)
			(size 1.8034 0.508)
			(layers "B.Cu" "B.Mask" "B.Paste")
			(net "GND")
		)
		(pad "58" smd rect
			(at 0 48.449992 270)
			(size 1.8034 0.508)
			(layers "B.Cu" "B.Mask" "B.Paste")
			(net "M_KLM_RST_N")
		)
		(pad "59" smd rect
			(at 0 49.299876 270)
			(size 1.8034 0.508)
			(layers "B.Cu" "B.Mask" "B.Paste")
			(net "PVDDQ_KLM")
		)
		(pad "60" smd rect
			(at 0 50.150014 270)
			(size 1.8034 0.508)
			(layers "B.Cu" "B.Mask" "B.Paste")
			(net "M_M_CKE<2>")
		)
		(pad "61" smd rect
			(at 0 50.999898 270)
			(size 1.8034 0.508)
			(layers "B.Cu" "B.Mask" "B.Paste")
			(net "PVDDQ_KLM")
		)
		(pad "62" smd rect
			(at 0 51.850036 270)
			(size 1.8034 0.508)
			(layers "B.Cu" "B.Mask" "B.Paste")
			(net "M_M_ACT_N")
		)
		(pad "63" smd rect
			(at 0 52.69992 270)
			(size 1.8034 0.508)
			(layers "B.Cu" "B.Mask" "B.Paste")
			(net "M_M_BG<0>")
		)
		(pad "64" smd rect
			(at 0 53.550058 270)
			(size 1.8034 0.508)
			(layers "B.Cu" "B.Mask" "B.Paste")
			(net "PVDDQ_KLM")
		)
		(pad "65" smd rect
			(at 0 54.399942 270)
			(size 1.8034 0.508)
			(layers "B.Cu" "B.Mask" "B.Paste")
			(net "M_M_MA<12>")
		)
		(pad "66" smd rect
			(at 0 55.25008 270)
			(size 1.8034 0.508)
			(layers "B.Cu" "B.Mask" "B.Paste")
			(net "M_M_MA<9>")
		)
		(pad "67" smd rect
			(at 0 56.099964 270)
			(size 1.8034 0.508)
			(layers "B.Cu" "B.Mask" "B.Paste")
			(net "PVDDQ_KLM")
		)
		(pad "68" smd rect
			(at 0 56.950102 270)
			(size 1.8034 0.508)
			(layers "B.Cu" "B.Mask" "B.Paste")
			(net "M_M_MA<8>")
		)
		(pad "69" smd rect
			(at 0 57.799986 270)
			(size 1.8034 0.508)
			(layers "B.Cu" "B.Mask" "B.Paste")
			(net "M_M_MA<6>")
		)
		(pad "70" smd rect
			(at 0 58.650124 270)
			(size 1.8034 0.508)
			(layers "B.Cu" "B.Mask" "B.Paste")
			(net "PVDDQ_KLM")
		)
		(pad "71" smd rect
			(at 0 59.500008 270)
			(size 1.8034 0.508)
			(layers "B.Cu" "B.Mask" "B.Paste")
			(net "M_M_MA<3>")
		)
		(pad "72" smd rect
			(at 0 60.349892 270)
			(size 1.8034 0.508)
			(layers "B.Cu" "B.Mask" "B.Paste")
			(net "M_M_MA<1>")
		)
		(pad "73" smd rect
			(at 0 61.20003 270)
			(size 1.8034 0.508)
			(layers "B.Cu" "B.Mask" "B.Paste")
			(net "PVDDQ_KLM")
		)
		(pad "74" smd rect
			(at 0 62.049914 270)
			(size 1.8034 0.508)
			(layers "B.Cu" "B.Mask" "B.Paste")
			(net "M_M_CLK_DP<2>")
		)
		(pad "75" smd rect
			(at 0 62.900052 270)
			(size 1.8034 0.508)
			(layers "B.Cu" "B.Mask" "B.Paste")
			(net "M_M_CLK_DN<2>")
		)
		(pad "76" smd rect
			(at 0 63.749936 270)
			(size 1.8034 0.508)
			(layers "B.Cu" "B.Mask" "B.Paste")
			(net "PVDDQ_KLM")
		)
		(pad "77" smd rect
			(at 0 64.600074 270)
			(size 1.8034 0.508)
			(layers "B.Cu" "B.Mask" "B.Paste")
			(net "PVTT_KLM")
		)
		(pad "78" smd rect
			(at 0 70.550024 270)
			(size 1.8034 0.508)
			(layers "B.Cu" "B.Mask" "B.Paste")
			(net "FM_DIMM_EVENT_COD_N")
		)
		(pad "79" smd rect
			(at 0 71.399908 270)
			(size 1.8034 0.508)
			(layers "B.Cu" "B.Mask" "B.Paste")
			(net "M_M_MA<0>")
		)
		(pad "80" smd rect
			(at 0 72.250046 270)
			(size 1.8034 0.508)
			(layers "B.Cu" "B.Mask" "B.Paste")
			(net "PVDDQ_KLM")
		)
		(pad "81" smd rect
			(at 0 73.09993 270)
			(size 1.8034 0.508)
			(layers "B.Cu" "B.Mask" "B.Paste")
			(net "M_M_BA<0>")
		)
		(pad "82" smd rect
			(at 0 73.950068 270)
			(size 1.8034 0.508)
			(layers "B.Cu" "B.Mask" "B.Paste")
			(net "M_M_MA<16>")
		)
		(pad "83" smd rect
			(at 0 74.799952 270)
			(size 1.8034 0.508)
			(layers "B.Cu" "B.Mask" "B.Paste")
			(net "PVDDQ_KLM")
		)
		(pad "84" smd rect
			(at 0 75.65009 270)
			(size 1.8034 0.508)
			(layers "B.Cu" "B.Mask" "B.Paste")
			(net "M_M_CS_N<4>")
		)
		(pad "85" smd rect
			(at 0 76.499974 270)
			(size 1.8034 0.508)
			(layers "B.Cu" "B.Mask" "B.Paste")
			(net "PVDDQ_KLM")
		)
		(pad "86" smd rect
			(at 0 77.350112 270)
			(size 1.8034 0.508)
			(layers "B.Cu" "B.Mask" "B.Paste")
			(net "M_M_MA<15>")
		)
		(pad "87" smd rect
			(at 0 78.199996 270)
			(size 1.8034 0.508)
			(layers "B.Cu" "B.Mask" "B.Paste")
			(net "M_M_ODT<2>")
		)
		(pad "88" smd rect
			(at 0 79.04988 270)
			(size 1.8034 0.508)
			(layers "B.Cu" "B.Mask" "B.Paste")
			(net "PVDDQ_KLM")
		)
		(pad "89" smd rect
			(at 0 79.900018 270)
			(size 1.8034 0.508)
			(layers "B.Cu" "B.Mask" "B.Paste")
			(net "M_M_CS_N<5>")
		)
		(pad "90" smd rect
			(at 0 80.749902 270)
			(size 1.8034 0.508)
			(layers "B.Cu" "B.Mask" "B.Paste")
			(net "PVDDQ_KLM")
		)
		(pad "91" smd rect
			(at 0 81.60004 270)
			(size 1.8034 0.508)
			(layers "B.Cu" "B.Mask" "B.Paste")
			(net "M_M_ODT<3>")
		)
		(pad "92" smd rect
			(at 0 82.449924 270)
			(size 1.8034 0.508)
			(layers "B.Cu" "B.Mask" "B.Paste")
			(net "PVDDQ_KLM")
		)
		(pad "93" smd rect
			(at 0 83.300062 270)
			(size 1.8034 0.508)
			(layers "B.Cu" "B.Mask" "B.Paste")
			(net "M_M_CS_N<6>")
		)
		(pad "94" smd rect
			(at 0 84.149946 270)
			(size 1.8034 0.508)
			(layers "B.Cu" "B.Mask" "B.Paste")
			(net "GND")
		)
		(pad "95" smd rect
			(at 0 85.000084 270)
			(size 1.8034 0.508)
			(layers "B.Cu" "B.Mask" "B.Paste")
			(net "M_M_DQ<36>")
		)
		(pad "96" smd rect
			(at 0 85.849968 270)
			(size 1.8034 0.508)
			(layers "B.Cu" "B.Mask" "B.Paste")
			(net "GND")
		)
		(pad "97" smd rect
			(at 0 86.700106 270)
			(size 1.8034 0.508)
			(layers "B.Cu" "B.Mask" "B.Paste")
			(net "M_M_DQ<32>")
		)
		(pad "98" smd rect
			(at 0 87.54999 270)
			(size 1.8034 0.508)
			(layers "B.Cu" "B.Mask" "B.Paste")
			(net "GND")
		)
		(pad "99" smd rect
			(at 0 88.399874 270)
			(size 1.8034 0.508)
			(layers "B.Cu" "B.Mask" "B.Paste")
			(net "M_M_DQS_DP<13>")
		)
		(pad "100" smd rect
			(at 0 89.250012 270)
			(size 1.8034 0.508)
			(layers "B.Cu" "B.Mask" "B.Paste")
			(net "M_M_DQS_DN<13>")
		)
		(pad "101" smd rect
			(at 0 90.099896 270)
			(size 1.8034 0.508)
			(layers "B.Cu" "B.Mask" "B.Paste")
			(net "GND")
		)
		(pad "102" smd rect
			(at 0 90.950034 270)
			(size 1.8034 0.508)
			(layers "B.Cu" "B.Mask" "B.Paste")
			(net "M_M_DQ<38>")
		)
		(pad "103" smd rect
			(at 0 91.799918 270)
			(size 1.8034 0.508)
			(layers "B.Cu" "B.Mask" "B.Paste")
			(net "GND")
		)
		(pad "104" smd rect
			(at 0 92.650056 270)
			(size 1.8034 0.508)
			(layers "B.Cu" "B.Mask" "B.Paste")
			(net "M_M_DQ<34>")
		)
		(pad "105" smd rect
			(at 0 93.49994 270)
			(size 1.8034 0.508)
			(layers "B.Cu" "B.Mask" "B.Paste")
			(net "GND")
		)
		(pad "106" smd rect
			(at 0 94.350078 270)
			(size 1.8034 0.508)
			(layers "B.Cu" "B.Mask" "B.Paste")
			(net "M_M_DQ<44>")
		)
		(pad "107" smd rect
			(at 0 95.199962 270)
			(size 1.8034 0.508)
			(layers "B.Cu" "B.Mask" "B.Paste")
			(net "GND")
		)
		(pad "108" smd rect
			(at 0 96.0501 270)
			(size 1.8034 0.508)
			(layers "B.Cu" "B.Mask" "B.Paste")
			(net "M_M_DQ<40>")
		)
		(pad "109" smd rect
			(at 0 96.899984 270)
			(size 1.8034 0.508)
			(layers "B.Cu" "B.Mask" "B.Paste")
			(net "GND")
		)
		(pad "110" smd rect
			(at 0 97.750122 270)
			(size 1.8034 0.508)
			(layers "B.Cu" "B.Mask" "B.Paste")
			(net "M_M_DQS_DP<14>")
		)
		(pad "111" smd rect
			(at 0 98.600006 270)
			(size 1.8034 0.508)
			(layers "B.Cu" "B.Mask" "B.Paste")
			(net "M_M_DQS_DN<14>")
		)
		(pad "112" smd rect
			(at 0 99.44989 270)
			(size 1.8034 0.508)
			(layers "B.Cu" "B.Mask" "B.Paste")
			(net "GND")
		)
		(pad "113" smd rect
			(at 0 100.300028 270)
			(size 1.8034 0.508)
			(layers "B.Cu" "B.Mask" "B.Paste")
			(net "M_M_DQ<46>")
		)
		(pad "114" smd rect
			(at 0 101.149912 270)
			(size 1.8034 0.508)
			(layers "B.Cu" "B.Mask" "B.Paste")
			(net "GND")
		)
		(pad "115" smd rect
			(at 0 102.00005 270)
			(size 1.8034 0.508)
			(layers "B.Cu" "B.Mask" "B.Paste")
			(net "M_M_DQ<42>")
		)
		(pad "116" smd rect
			(at 0 102.849934 270)
			(size 1.8034 0.508)
			(layers "B.Cu" "B.Mask" "B.Paste")
			(net "GND")
		)
		(pad "117" smd rect
			(at 0 103.700072 270)
			(size 1.8034 0.508)
			(layers "B.Cu" "B.Mask" "B.Paste")
			(net "M_M_DQ<52>")
		)
		(pad "118" smd rect
			(at 0 104.549956 270)
			(size 1.8034 0.508)
			(layers "B.Cu" "B.Mask" "B.Paste")
			(net "GND")
		)
		(pad "119" smd rect
			(at 0 105.400094 270)
			(size 1.8034 0.508)
			(layers "B.Cu" "B.Mask" "B.Paste")
			(net "M_M_DQ<48>")
		)
		(pad "120" smd rect
			(at 0 106.249978 270)
			(size 1.8034 0.508)
			(layers "B.Cu" "B.Mask" "B.Paste")
			(net "GND")
		)
		(pad "121" smd rect
			(at 0 107.100116 270)
			(size 1.8034 0.508)
			(layers "B.Cu" "B.Mask" "B.Paste")
			(net "M_M_DQS_DP<15>")
		)
		(pad "122" smd rect
			(at 0 107.95 270)
			(size 1.8034 0.508)
			(layers "B.Cu" "B.Mask" "B.Paste")
			(net "M_M_DQS_DN<15>")
		)
		(pad "123" smd rect
			(at 0 108.799884 270)
			(size 1.8034 0.508)
			(layers "B.Cu" "B.Mask" "B.Paste")
			(net "GND")
		)
		(pad "124" smd rect
			(at 0 109.650022 270)
			(size 1.8034 0.508)
			(layers "B.Cu" "B.Mask" "B.Paste")
			(net "M_M_DQ<54>")
		)
		(pad "125" smd rect
			(at 0 110.499906 270)
			(size 1.8034 0.508)
			(layers "B.Cu" "B.Mask" "B.Paste")
			(net "GND")
		)
		(pad "126" smd rect
			(at 0 111.350044 270)
			(size 1.8034 0.508)
			(layers "B.Cu" "B.Mask" "B.Paste")
			(net "M_M_DQ<50>")
		)
		(pad "127" smd rect
			(at 0 112.199928 270)
			(size 1.8034 0.508)
			(layers "B.Cu" "B.Mask" "B.Paste")
			(net "GND")
		)
		(pad "128" smd rect
			(at 0 113.050066 270)
			(size 1.8034 0.508)
			(layers "B.Cu" "B.Mask" "B.Paste")
			(net "M_M_DQ<60>")
		)
		(pad "129" smd rect
			(at 0 113.89995 270)
			(size 1.8034 0.508)
			(layers "B.Cu" "B.Mask" "B.Paste")
			(net "GND")
		)
		(pad "130" smd rect
			(at 0 114.750088 270)
			(size 1.8034 0.508)
			(layers "B.Cu" "B.Mask" "B.Paste")
			(net "M_M_DQ<56>")
		)
		(pad "131" smd rect
			(at 0 115.599972 270)
			(size 1.8034 0.508)
			(layers "B.Cu" "B.Mask" "B.Paste")
			(net "GND")
		)
		(pad "132" smd rect
			(at 0 116.45011 270)
			(size 1.8034 0.508)
			(layers "B.Cu" "B.Mask" "B.Paste")
			(net "M_M_DQS_DP<16>")
		)
		(pad "133" smd rect
			(at 0 117.299994 270)
			(size 1.8034 0.508)
			(layers "B.Cu" "B.Mask" "B.Paste")
			(net "M_M_DQS_DN<16>")
		)
		(pad "134" smd rect
			(at 0 118.149878 270)
			(size 1.8034 0.508)
			(layers "B.Cu" "B.Mask" "B.Paste")
			(net "GND")
		)
		(pad "135" smd rect
			(at 0 119.000016 270)
			(size 1.8034 0.508)
			(layers "B.Cu" "B.Mask" "B.Paste")
			(net "M_M_DQ<62>")
		)
		(pad "136" smd rect
			(at 0 119.8499 270)
			(size 1.8034 0.508)
			(layers "B.Cu" "B.Mask" "B.Paste")
			(net "GND")
		)
		(pad "137" smd rect
			(at 0 120.700038 270)
			(size 1.8034 0.508)
			(layers "B.Cu" "B.Mask" "B.Paste")
			(net "M_M_DQ<58>")
		)
		(pad "138" smd rect
			(at 0 121.549922 270)
			(size 1.8034 0.508)
			(layers "B.Cu" "B.Mask" "B.Paste")
			(net "GND")
		)
		(pad "139" smd rect
			(at 0 122.40006 270)
			(size 1.8034 0.508)
			(layers "B.Cu" "B.Mask" "B.Paste")
			(net "PVPP_KLM")
		)
		(pad "140" smd rect
			(at 0 123.249944 270)
			(size 1.8034 0.508)
			(layers "B.Cu" "B.Mask" "B.Paste")
			(net "GND")
		)
		(pad "141" smd rect
			(at 0 124.100082 270)
			(size 1.8034 0.508)
			(layers "B.Cu" "B.Mask" "B.Paste")
			(net "SMB_DDR_KLM_VPP_SCL")
		)
		(pad "142" smd rect
			(at 0 124.949966 270)
			(size 1.8034 0.508)
			(layers "B.Cu" "B.Mask" "B.Paste")
			(net "PVPP_KLM")
		)
		(pad "143" smd rect
			(at 0 125.800104 270)
			(size 1.8034 0.508)
			(layers "B.Cu" "B.Mask" "B.Paste")
			(net "PVPP_KLM")
		)
		(pad "144" smd rect
			(at 0 126.649988 270)
			(size 1.8034 0.508)
			(layers "B.Cu" "B.Mask" "B.Paste")
			(net "TP_CH_M_DIMM_M1_RFU_2")
		)
		(pad "145" smd rect
			(at -4.59994 0 270)
			(size 1.8034 0.508)
			(layers "B.Cu" "B.Mask" "B.Paste")
			(net "P12V_NVDIMM_KLM")
		)
		(pad "146" smd rect
			(at -4.59994 0.849884 270)
			(size 1.8034 0.508)
			(layers "B.Cu" "B.Mask" "B.Paste")
			(net "M_M_VREF")
		)
		(pad "147" smd rect
			(at -4.59994 1.700022 270)
			(size 1.8034 0.508)
			(layers "B.Cu" "B.Mask" "B.Paste")
			(net "GND")
		)
		(pad "148" smd rect
			(at -4.59994 2.549906 270)
			(size 1.8034 0.508)
			(layers "B.Cu" "B.Mask" "B.Paste")
			(net "M_M_DQ<5>")
		)
		(pad "149" smd rect
			(at -4.59994 3.400044 270)
			(size 1.8034 0.508)
			(layers "B.Cu" "B.Mask" "B.Paste")
			(net "GND")
		)
		(pad "150" smd rect
			(at -4.59994 4.249928 270)
			(size 1.8034 0.508)
			(layers "B.Cu" "B.Mask" "B.Paste")
			(net "M_M_DQ<1>")
		)
		(pad "151" smd rect
			(at -4.59994 5.100066 270)
			(size 1.8034 0.508)
			(layers "B.Cu" "B.Mask" "B.Paste")
			(net "GND")
		)
		(pad "152" smd rect
			(at -4.59994 5.94995 270)
			(size 1.8034 0.508)
			(layers "B.Cu" "B.Mask" "B.Paste")
			(net "M_M_DQS_DN<0>")
		)
		(pad "153" smd rect
			(at -4.59994 6.800088 270)
			(size 1.8034 0.508)
			(layers "B.Cu" "B.Mask" "B.Paste")
			(net "M_M_DQS_DP<0>")
		)
		(pad "154" smd rect
			(at -4.59994 7.649972 270)
			(size 1.8034 0.508)
			(layers "B.Cu" "B.Mask" "B.Paste")
			(net "GND")
		)
		(pad "155" smd rect
			(at -4.59994 8.50011 270)
			(size 1.8034 0.508)
			(layers "B.Cu" "B.Mask" "B.Paste")
			(net "M_M_DQ<7>")
		)
		(pad "156" smd rect
			(at -4.59994 9.349994 270)
			(size 1.8034 0.508)
			(layers "B.Cu" "B.Mask" "B.Paste")
			(net "GND")
		)
		(pad "157" smd rect
			(at -4.59994 10.199878 270)
			(size 1.8034 0.508)
			(layers "B.Cu" "B.Mask" "B.Paste")
			(net "M_M_DQ<3>")
		)
		(pad "158" smd rect
			(at -4.59994 11.050016 270)
			(size 1.8034 0.508)
			(layers "B.Cu" "B.Mask" "B.Paste")
			(net "GND")
		)
		(pad "159" smd rect
			(at -4.59994 11.8999 270)
			(size 1.8034 0.508)
			(layers "B.Cu" "B.Mask" "B.Paste")
			(net "M_M_DQ<13>")
		)
		(pad "160" smd rect
			(at -4.59994 12.750038 270)
			(size 1.8034 0.508)
			(layers "B.Cu" "B.Mask" "B.Paste")
			(net "GND")
		)
		(pad "161" smd rect
			(at -4.59994 13.599922 270)
			(size 1.8034 0.508)
			(layers "B.Cu" "B.Mask" "B.Paste")
			(net "M_M_DQ<9>")
		)
		(pad "162" smd rect
			(at -4.59994 14.45006 270)
			(size 1.8034 0.508)
			(layers "B.Cu" "B.Mask" "B.Paste")
			(net "GND")
		)
		(pad "163" smd rect
			(at -4.59994 15.299944 270)
			(size 1.8034 0.508)
			(layers "B.Cu" "B.Mask" "B.Paste")
			(net "M_M_DQS_DN<1>")
		)
		(pad "164" smd rect
			(at -4.59994 16.150082 270)
			(size 1.8034 0.508)
			(layers "B.Cu" "B.Mask" "B.Paste")
			(net "M_M_DQS_DP<1>")
		)
		(pad "165" smd rect
			(at -4.59994 16.999966 270)
			(size 1.8034 0.508)
			(layers "B.Cu" "B.Mask" "B.Paste")
			(net "GND")
		)
		(pad "166" smd rect
			(at -4.59994 17.850104 270)
			(size 1.8034 0.508)
			(layers "B.Cu" "B.Mask" "B.Paste")
			(net "M_M_DQ<15>")
		)
		(pad "167" smd rect
			(at -4.59994 18.699988 270)
			(size 1.8034 0.508)
			(layers "B.Cu" "B.Mask" "B.Paste")
			(net "GND")
		)
		(pad "168" smd rect
			(at -4.59994 19.550126 270)
			(size 1.8034 0.508)
			(layers "B.Cu" "B.Mask" "B.Paste")
			(net "M_M_DQ<11>")
		)
		(pad "169" smd rect
			(at -4.59994 20.40001 270)
			(size 1.8034 0.508)
			(layers "B.Cu" "B.Mask" "B.Paste")
			(net "GND")
		)
		(pad "170" smd rect
			(at -4.59994 21.249894 270)
			(size 1.8034 0.508)
			(layers "B.Cu" "B.Mask" "B.Paste")
			(net "M_M_DQ<21>")
		)
		(pad "171" smd rect
			(at -4.59994 22.100032 270)
			(size 1.8034 0.508)
			(layers "B.Cu" "B.Mask" "B.Paste")
			(net "GND")
		)
		(pad "172" smd rect
			(at -4.59994 22.949916 270)
			(size 1.8034 0.508)
			(layers "B.Cu" "B.Mask" "B.Paste")
			(net "M_M_DQ<17>")
		)
		(pad "173" smd rect
			(at -4.59994 23.800054 270)
			(size 1.8034 0.508)
			(layers "B.Cu" "B.Mask" "B.Paste")
			(net "GND")
		)
		(pad "174" smd rect
			(at -4.59994 24.649938 270)
			(size 1.8034 0.508)
			(layers "B.Cu" "B.Mask" "B.Paste")
			(net "M_M_DQS_DN<2>")
		)
		(pad "175" smd rect
			(at -4.59994 25.500076 270)
			(size 1.8034 0.508)
			(layers "B.Cu" "B.Mask" "B.Paste")
			(net "M_M_DQS_DP<2>")
		)
		(pad "176" smd rect
			(at -4.59994 26.34996 270)
			(size 1.8034 0.508)
			(layers "B.Cu" "B.Mask" "B.Paste")
			(net "GND")
		)
		(pad "177" smd rect
			(at -4.59994 27.200098 270)
			(size 1.8034 0.508)
			(layers "B.Cu" "B.Mask" "B.Paste")
			(net "M_M_DQ<23>")
		)
		(pad "178" smd rect
			(at -4.59994 28.049982 270)
			(size 1.8034 0.508)
			(layers "B.Cu" "B.Mask" "B.Paste")
			(net "GND")
		)
		(pad "179" smd rect
			(at -4.59994 28.90012 270)
			(size 1.8034 0.508)
			(layers "B.Cu" "B.Mask" "B.Paste")
			(net "M_M_DQ<19>")
		)
		(pad "180" smd rect
			(at -4.59994 29.750004 270)
			(size 1.8034 0.508)
			(layers "B.Cu" "B.Mask" "B.Paste")
			(net "GND")
		)
		(pad "181" smd rect
			(at -4.59994 30.599888 270)
			(size 1.8034 0.508)
			(layers "B.Cu" "B.Mask" "B.Paste")
			(net "M_M_DQ<29>")
		)
		(pad "182" smd rect
			(at -4.59994 31.450026 270)
			(size 1.8034 0.508)
			(layers "B.Cu" "B.Mask" "B.Paste")
			(net "GND")
		)
		(pad "183" smd rect
			(at -4.59994 32.29991 270)
			(size 1.8034 0.508)
			(layers "B.Cu" "B.Mask" "B.Paste")
			(net "M_M_DQ<25>")
		)
		(pad "184" smd rect
			(at -4.59994 33.150048 270)
			(size 1.8034 0.508)
			(layers "B.Cu" "B.Mask" "B.Paste")
			(net "GND")
		)
		(pad "185" smd rect
			(at -4.59994 33.999932 270)
			(size 1.8034 0.508)
			(layers "B.Cu" "B.Mask" "B.Paste")
			(net "M_M_DQS_DN<3>")
		)
		(pad "186" smd rect
			(at -4.59994 34.85007 270)
			(size 1.8034 0.508)
			(layers "B.Cu" "B.Mask" "B.Paste")
			(net "M_M_DQS_DP<3>")
		)
		(pad "187" smd rect
			(at -4.59994 35.699954 270)
			(size 1.8034 0.508)
			(layers "B.Cu" "B.Mask" "B.Paste")
			(net "GND")
		)
		(pad "188" smd rect
			(at -4.59994 36.550092 270)
			(size 1.8034 0.508)
			(layers "B.Cu" "B.Mask" "B.Paste")
			(net "M_M_DQ<31>")
		)
		(pad "189" smd rect
			(at -4.59994 37.399976 270)
			(size 1.8034 0.508)
			(layers "B.Cu" "B.Mask" "B.Paste")
			(net "GND")
		)
		(pad "190" smd rect
			(at -4.59994 38.250114 270)
			(size 1.8034 0.508)
			(layers "B.Cu" "B.Mask" "B.Paste")
			(net "M_M_DQ<27>")
		)
		(pad "191" smd rect
			(at -4.59994 39.099998 270)
			(size 1.8034 0.508)
			(layers "B.Cu" "B.Mask" "B.Paste")
			(net "GND")
		)
		(pad "192" smd rect
			(at -4.59994 39.949882 270)
			(size 1.8034 0.508)
			(layers "B.Cu" "B.Mask" "B.Paste")
			(net "M_M_ECC<5>")
		)
		(pad "193" smd rect
			(at -4.59994 40.80002 270)
			(size 1.8034 0.508)
			(layers "B.Cu" "B.Mask" "B.Paste")
			(net "GND")
		)
		(pad "194" smd rect
			(at -4.59994 41.649904 270)
			(size 1.8034 0.508)
			(layers "B.Cu" "B.Mask" "B.Paste")
			(net "M_M_ECC<1>")
		)
		(pad "195" smd rect
			(at -4.59994 42.500042 270)
			(size 1.8034 0.508)
			(layers "B.Cu" "B.Mask" "B.Paste")
			(net "GND")
		)
		(pad "196" smd rect
			(at -4.59994 43.349926 270)
			(size 1.8034 0.508)
			(layers "B.Cu" "B.Mask" "B.Paste")
			(net "M_M_DQS_DN<8>")
		)
		(pad "197" smd rect
			(at -4.59994 44.200064 270)
			(size 1.8034 0.508)
			(layers "B.Cu" "B.Mask" "B.Paste")
			(net "M_M_DQS_DP<8>")
		)
		(pad "198" smd rect
			(at -4.59994 45.049948 270)
			(size 1.8034 0.508)
			(layers "B.Cu" "B.Mask" "B.Paste")
			(net "GND")
		)
		(pad "199" smd rect
			(at -4.59994 45.900086 270)
			(size 1.8034 0.508)
			(layers "B.Cu" "B.Mask" "B.Paste")
			(net "M_M_ECC<7>")
		)
		(pad "200" smd rect
			(at -4.59994 46.74997 270)
			(size 1.8034 0.508)
			(layers "B.Cu" "B.Mask" "B.Paste")
			(net "GND")
		)
		(pad "201" smd rect
			(at -4.59994 47.600108 270)
			(size 1.8034 0.508)
			(layers "B.Cu" "B.Mask" "B.Paste")
			(net "M_M_ECC<3>")
		)
		(pad "202" smd rect
			(at -4.59994 48.449992 270)
			(size 1.8034 0.508)
			(layers "B.Cu" "B.Mask" "B.Paste")
			(net "GND")
		)
		(pad "203" smd rect
			(at -4.59994 49.299876 270)
			(size 1.8034 0.508)
			(layers "B.Cu" "B.Mask" "B.Paste")
			(net "M_M_CKE<3>")
		)
		(pad "204" smd rect
			(at -4.59994 50.150014 270)
			(size 1.8034 0.508)
			(layers "B.Cu" "B.Mask" "B.Paste")
			(net "PVDDQ_KLM")
		)
		(pad "205" smd rect
			(at -4.59994 50.999898 270)
			(size 1.8034 0.508)
			(layers "B.Cu" "B.Mask" "B.Paste")
			(net "TP_CH_M_DIMM_M1_RFU_0")
		)
		(pad "206" smd rect
			(at -4.59994 51.850036 270)
			(size 1.8034 0.508)
			(layers "B.Cu" "B.Mask" "B.Paste")
			(net "PVDDQ_KLM")
		)
		(pad "207" smd rect
			(at -4.59994 52.69992 270)
			(size 1.8034 0.508)
			(layers "B.Cu" "B.Mask" "B.Paste")
			(net "M_M_BG<1>")
		)
		(pad "208" smd rect
			(at -4.59994 53.550058 270)
			(size 1.8034 0.508)
			(layers "B.Cu" "B.Mask" "B.Paste")
			(net "M_M_ALERT_N")
		)
		(pad "209" smd rect
			(at -4.59994 54.399942 270)
			(size 1.8034 0.508)
			(layers "B.Cu" "B.Mask" "B.Paste")
			(net "PVDDQ_KLM")
		)
		(pad "210" smd rect
			(at -4.59994 55.25008 270)
			(size 1.8034 0.508)
			(layers "B.Cu" "B.Mask" "B.Paste")
			(net "M_M_MA<11>")
		)
		(pad "211" smd rect
			(at -4.59994 56.099964 270)
			(size 1.8034 0.508)
			(layers "B.Cu" "B.Mask" "B.Paste")
			(net "M_M_MA<7>")
		)
		(pad "212" smd rect
			(at -4.59994 56.950102 270)
			(size 1.8034 0.508)
			(layers "B.Cu" "B.Mask" "B.Paste")
			(net "PVDDQ_KLM")
		)
		(pad "213" smd rect
			(at -4.59994 57.799986 270)
			(size 1.8034 0.508)
			(layers "B.Cu" "B.Mask" "B.Paste")
			(net "M_M_MA<5>")
		)
		(pad "214" smd rect
			(at -4.59994 58.650124 270)
			(size 1.8034 0.508)
			(layers "B.Cu" "B.Mask" "B.Paste")
			(net "M_M_MA<4>")
		)
		(pad "215" smd rect
			(at -4.59994 59.500008 270)
			(size 1.8034 0.508)
			(layers "B.Cu" "B.Mask" "B.Paste")
			(net "PVDDQ_KLM")
		)
		(pad "216" smd rect
			(at -4.59994 60.349892 270)
			(size 1.8034 0.508)
			(layers "B.Cu" "B.Mask" "B.Paste")
			(net "M_M_MA<2>")
		)
		(pad "217" smd rect
			(at -4.59994 61.20003 270)
			(size 1.8034 0.508)
			(layers "B.Cu" "B.Mask" "B.Paste")
			(net "PVDDQ_KLM")
		)
		(pad "218" smd rect
			(at -4.59994 62.049914 270)
			(size 1.8034 0.508)
			(layers "B.Cu" "B.Mask" "B.Paste")
			(net "M_M_CLK_DP<3>")
		)
		(pad "219" smd rect
			(at -4.59994 62.900052 270)
			(size 1.8034 0.508)
			(layers "B.Cu" "B.Mask" "B.Paste")
			(net "M_M_CLK_DN<3>")
		)
		(pad "220" smd rect
			(at -4.59994 63.749936 270)
			(size 1.8034 0.508)
			(layers "B.Cu" "B.Mask" "B.Paste")
			(net "PVDDQ_KLM")
		)
		(pad "221" smd rect
			(at -4.59994 64.600074 270)
			(size 1.8034 0.508)
			(layers "B.Cu" "B.Mask" "B.Paste")
			(net "PVTT_KLM")
		)
		(pad "222" smd rect
			(at -4.59994 70.550024 270)
			(size 1.8034 0.508)
			(layers "B.Cu" "B.Mask" "B.Paste")
			(net "M_M_PAR")
		)
		(pad "223" smd rect
			(at -4.59994 71.399908 270)
			(size 1.8034 0.508)
			(layers "B.Cu" "B.Mask" "B.Paste")
			(net "PVDDQ_KLM")
		)
		(pad "224" smd rect
			(at -4.59994 72.250046 270)
			(size 1.8034 0.508)
			(layers "B.Cu" "B.Mask" "B.Paste")
			(net "M_M_BA<1>")
		)
		(pad "225" smd rect
			(at -4.59994 73.09993 270)
			(size 1.8034 0.508)
			(layers "B.Cu" "B.Mask" "B.Paste")
			(net "M_M_MA<10>")
		)
		(pad "226" smd rect
			(at -4.59994 73.950068 270)
			(size 1.8034 0.508)
			(layers "B.Cu" "B.Mask" "B.Paste")
			(net "PVDDQ_KLM")
		)
		(pad "227" smd rect
			(at -4.59994 74.799952 270)
			(size 1.8034 0.508)
			(layers "B.Cu" "B.Mask" "B.Paste")
			(net "TP_CH_M_DIMM_M1_RFU_1")
		)
		(pad "228" smd rect
			(at -4.59994 75.65009 270)
			(size 1.8034 0.508)
			(layers "B.Cu" "B.Mask" "B.Paste")
			(net "M_M_MA<14>")
		)
		(pad "229" smd rect
			(at -4.59994 76.499974 270)
			(size 1.8034 0.508)
			(layers "B.Cu" "B.Mask" "B.Paste")
			(net "PVDDQ_KLM")
		)
		(pad "230" smd rect
			(at -4.59994 77.350112 270)
			(size 1.8034 0.508)
			(layers "B.Cu" "B.Mask" "B.Paste")
			(net "FM_ADR_COMPLETE_KLM_N")
		)
		(pad "231" smd rect
			(at -4.59994 78.199996 270)
			(size 1.8034 0.508)
			(layers "B.Cu" "B.Mask" "B.Paste")
			(net "PVDDQ_KLM")
		)
		(pad "232" smd rect
			(at -4.59994 79.04988 270)
			(size 1.8034 0.508)
			(layers "B.Cu" "B.Mask" "B.Paste")
			(net "M_M_MA<13>")
		)
		(pad "233" smd rect
			(at -4.59994 79.900018 270)
			(size 1.8034 0.508)
			(layers "B.Cu" "B.Mask" "B.Paste")
			(net "PVDDQ_KLM")
		)
		(pad "234" smd rect
			(at -4.59994 80.749902 270)
			(size 1.8034 0.508)
			(layers "B.Cu" "B.Mask" "B.Paste")
			(net "M_M_MA<17>")
		)
		(pad "235" smd rect
			(at -4.59994 81.60004 270)
			(size 1.8034 0.508)
			(layers "B.Cu" "B.Mask" "B.Paste")
			(net "M_M_C<2>")
		)
		(pad "236" smd rect
			(at -4.59994 82.449924 270)
			(size 1.8034 0.508)
			(layers "B.Cu" "B.Mask" "B.Paste")
			(net "PVDDQ_KLM")
		)
		(pad "237" smd rect
			(at -4.59994 83.300062 270)
			(size 1.8034 0.508)
			(layers "B.Cu" "B.Mask" "B.Paste")
			(net "M_M_CS_N<7>")
		)
		(pad "238" smd rect
			(at -4.59994 84.149946 270)
			(size 1.8034 0.508)
			(layers "B.Cu" "B.Mask" "B.Paste")
			(net "PVPP_KLM")
		)
		(pad "239" smd rect
			(at -4.59994 85.000084 270)
			(size 1.8034 0.508)
			(layers "B.Cu" "B.Mask" "B.Paste")
			(net "GND")
		)
		(pad "240" smd rect
			(at -4.59994 85.849968 270)
			(size 1.8034 0.508)
			(layers "B.Cu" "B.Mask" "B.Paste")
			(net "M_M_DQ<37>")
		)
		(pad "241" smd rect
			(at -4.59994 86.700106 270)
			(size 1.8034 0.508)
			(layers "B.Cu" "B.Mask" "B.Paste")
			(net "GND")
		)
		(pad "242" smd rect
			(at -4.59994 87.54999 270)
			(size 1.8034 0.508)
			(layers "B.Cu" "B.Mask" "B.Paste")
			(net "M_M_DQ<33>")
		)
		(pad "243" smd rect
			(at -4.59994 88.399874 270)
			(size 1.8034 0.508)
			(layers "B.Cu" "B.Mask" "B.Paste")
			(net "GND")
		)
		(pad "244" smd rect
			(at -4.59994 89.250012 270)
			(size 1.8034 0.508)
			(layers "B.Cu" "B.Mask" "B.Paste")
			(net "M_M_DQS_DN<4>")
		)
		(pad "245" smd rect
			(at -4.59994 90.099896 270)
			(size 1.8034 0.508)
			(layers "B.Cu" "B.Mask" "B.Paste")
			(net "M_M_DQS_DP<4>")
		)
		(pad "246" smd rect
			(at -4.59994 90.950034 270)
			(size 1.8034 0.508)
			(layers "B.Cu" "B.Mask" "B.Paste")
			(net "GND")
		)
		(pad "247" smd rect
			(at -4.59994 91.799918 270)
			(size 1.8034 0.508)
			(layers "B.Cu" "B.Mask" "B.Paste")
			(net "M_M_DQ<39>")
		)
		(pad "248" smd rect
			(at -4.59994 92.650056 270)
			(size 1.8034 0.508)
			(layers "B.Cu" "B.Mask" "B.Paste")
			(net "GND")
		)
		(pad "249" smd rect
			(at -4.59994 93.49994 270)
			(size 1.8034 0.508)
			(layers "B.Cu" "B.Mask" "B.Paste")
			(net "M_M_DQ<35>")
		)
		(pad "250" smd rect
			(at -4.59994 94.350078 270)
			(size 1.8034 0.508)
			(layers "B.Cu" "B.Mask" "B.Paste")
			(net "GND")
		)
		(pad "251" smd rect
			(at -4.59994 95.199962 270)
			(size 1.8034 0.508)
			(layers "B.Cu" "B.Mask" "B.Paste")
			(net "M_M_DQ<45>")
		)
		(pad "252" smd rect
			(at -4.59994 96.0501 270)
			(size 1.8034 0.508)
			(layers "B.Cu" "B.Mask" "B.Paste")
			(net "GND")
		)
		(pad "253" smd rect
			(at -4.59994 96.899984 270)
			(size 1.8034 0.508)
			(layers "B.Cu" "B.Mask" "B.Paste")
			(net "M_M_DQ<41>")
		)
		(pad "254" smd rect
			(at -4.59994 97.750122 270)
			(size 1.8034 0.508)
			(layers "B.Cu" "B.Mask" "B.Paste")
			(net "GND")
		)
		(pad "255" smd rect
			(at -4.59994 98.600006 270)
			(size 1.8034 0.508)
			(layers "B.Cu" "B.Mask" "B.Paste")
			(net "M_M_DQS_DN<5>")
		)
		(pad "256" smd rect
			(at -4.59994 99.44989 270)
			(size 1.8034 0.508)
			(layers "B.Cu" "B.Mask" "B.Paste")
			(net "M_M_DQS_DP<5>")
		)
		(pad "257" smd rect
			(at -4.59994 100.300028 270)
			(size 1.8034 0.508)
			(layers "B.Cu" "B.Mask" "B.Paste")
			(net "GND")
		)
		(pad "258" smd rect
			(at -4.59994 101.149912 270)
			(size 1.8034 0.508)
			(layers "B.Cu" "B.Mask" "B.Paste")
			(net "M_M_DQ<47>")
		)
		(pad "259" smd rect
			(at -4.59994 102.00005 270)
			(size 1.8034 0.508)
			(layers "B.Cu" "B.Mask" "B.Paste")
			(net "GND")
		)
		(pad "260" smd rect
			(at -4.59994 102.849934 270)
			(size 1.8034 0.508)
			(layers "B.Cu" "B.Mask" "B.Paste")
			(net "M_M_DQ<43>")
		)
		(pad "261" smd rect
			(at -4.59994 103.700072 270)
			(size 1.8034 0.508)
			(layers "B.Cu" "B.Mask" "B.Paste")
			(net "GND")
		)
		(pad "262" smd rect
			(at -4.59994 104.549956 270)
			(size 1.8034 0.508)
			(layers "B.Cu" "B.Mask" "B.Paste")
			(net "M_M_DQ<53>")
		)
		(pad "263" smd rect
			(at -4.59994 105.400094 270)
			(size 1.8034 0.508)
			(layers "B.Cu" "B.Mask" "B.Paste")
			(net "GND")
		)
		(pad "264" smd rect
			(at -4.59994 106.249978 270)
			(size 1.8034 0.508)
			(layers "B.Cu" "B.Mask" "B.Paste")
			(net "M_M_DQ<49>")
		)
		(pad "265" smd rect
			(at -4.59994 107.100116 270)
			(size 1.8034 0.508)
			(layers "B.Cu" "B.Mask" "B.Paste")
			(net "GND")
		)
		(pad "266" smd rect
			(at -4.59994 107.95 270)
			(size 1.8034 0.508)
			(layers "B.Cu" "B.Mask" "B.Paste")
			(net "M_M_DQS_DN<6>")
		)
		(pad "267" smd rect
			(at -4.59994 108.799884 270)
			(size 1.8034 0.508)
			(layers "B.Cu" "B.Mask" "B.Paste")
			(net "M_M_DQS_DP<6>")
		)
		(pad "268" smd rect
			(at -4.59994 109.650022 270)
			(size 1.8034 0.508)
			(layers "B.Cu" "B.Mask" "B.Paste")
			(net "GND")
		)
		(pad "269" smd rect
			(at -4.59994 110.499906 270)
			(size 1.8034 0.508)
			(layers "B.Cu" "B.Mask" "B.Paste")
			(net "M_M_DQ<55>")
		)
		(pad "270" smd rect
			(at -4.59994 111.350044 270)
			(size 1.8034 0.508)
			(layers "B.Cu" "B.Mask" "B.Paste")
			(net "GND")
		)
		(pad "271" smd rect
			(at -4.59994 112.199928 270)
			(size 1.8034 0.508)
			(layers "B.Cu" "B.Mask" "B.Paste")
			(net "M_M_DQ<51>")
		)
		(pad "272" smd rect
			(at -4.59994 113.050066 270)
			(size 1.8034 0.508)
			(layers "B.Cu" "B.Mask" "B.Paste")
			(net "GND")
		)
		(pad "273" smd rect
			(at -4.59994 113.89995 270)
			(size 1.8034 0.508)
			(layers "B.Cu" "B.Mask" "B.Paste")
			(net "M_M_DQ<61>")
		)
		(pad "274" smd rect
			(at -4.59994 114.750088 270)
			(size 1.8034 0.508)
			(layers "B.Cu" "B.Mask" "B.Paste")
			(net "GND")
		)
		(pad "275" smd rect
			(at -4.59994 115.599972 270)
			(size 1.8034 0.508)
			(layers "B.Cu" "B.Mask" "B.Paste")
			(net "M_M_DQ<57>")
		)
		(pad "276" smd rect
			(at -4.59994 116.45011 270)
			(size 1.8034 0.508)
			(layers "B.Cu" "B.Mask" "B.Paste")
			(net "GND")
		)
		(pad "277" smd rect
			(at -4.59994 117.299994 270)
			(size 1.8034 0.508)
			(layers "B.Cu" "B.Mask" "B.Paste")
			(net "M_M_DQS_DN<7>")
		)
		(pad "278" smd rect
			(at -4.59994 118.149878 270)
			(size 1.8034 0.508)
			(layers "B.Cu" "B.Mask" "B.Paste")
			(net "M_M_DQS_DP<7>")
		)
		(pad "279" smd rect
			(at -4.59994 119.000016 270)
			(size 1.8034 0.508)
			(layers "B.Cu" "B.Mask" "B.Paste")
			(net "GND")
		)
		(pad "280" smd rect
			(at -4.59994 119.8499 270)
			(size 1.8034 0.508)
			(layers "B.Cu" "B.Mask" "B.Paste")
			(net "M_M_DQ<63>")
		)
		(pad "281" smd rect
			(at -4.59994 120.700038 270)
			(size 1.8034 0.508)
			(layers "B.Cu" "B.Mask" "B.Paste")
			(net "GND")
		)
		(pad "282" smd rect
			(at -4.59994 121.549922 270)
			(size 1.8034 0.508)
			(layers "B.Cu" "B.Mask" "B.Paste")
			(net "M_M_DQ<59>")
		)
		(pad "283" smd rect
			(at -4.59994 122.40006 270)
			(size 1.8034 0.508)
			(layers "B.Cu" "B.Mask" "B.Paste")
			(net "GND")
		)
		(pad "284" smd rect
			(at -4.59994 123.249944 270)
			(size 1.8034 0.508)
			(layers "B.Cu" "B.Mask" "B.Paste")
			(net "PVPP_KLM")
		)
		(pad "285" smd rect
			(at -4.59994 124.100082 270)
			(size 1.8034 0.508)
			(layers "B.Cu" "B.Mask" "B.Paste")
			(net "SMB_DDR_KLM_VPP_SDA")
		)
		(pad "286" smd rect
			(at -4.59994 124.949966 270)
			(size 1.8034 0.508)
			(layers "B.Cu" "B.Mask" "B.Paste")
			(net "PVPP_KLM")
		)
		(pad "287" smd rect
			(at -4.59994 125.800104 270)
			(size 1.8034 0.508)
			(layers "B.Cu" "B.Mask" "B.Paste")
			(net "PVPP_KLM")
		)
		(pad "288" smd rect
			(at -4.59994 126.649988 270)
			(size 1.8034 0.508)
			(layers "B.Cu" "B.Mask" "B.Paste")
			(net "PVPP_KLM")
		)
	)
	(footprint ""
		(layer "B.Cu")
		(at 269.521686 -77.82814)
		(property "Reference" "C5P21"
			(at 0 0 0)
			(layer "B.SilkS")
			(hide yes)
			(effects
				(font
					(size 1.27 1.27)
				)
				(justify mirror)
			)
		)
		(property "Value" ""
			(at 0 0 0)
			(layer "B.Fab")
			(effects
				(font
					(size 1.27 1.27)
				)
				(justify mirror)
			)
		)
		(duplicate_pad_numbers_are_jumpers no)
		(fp_poly
			(pts
				(xy 0.7239 -0.2159) (xy -0.7239 -0.2159) (xy -0.7239 1.9939) (xy 0.7239 1.9939)
			)
			(stroke
				(width 0)
				(type default)
			)
			(fill no)
			(layer "B.CrtYd")
		)
		(fp_line
			(start -0.7239 -0.2159)
			(end 0.7239 -0.2159)
			(stroke
				(width 0.1)
				(type default)
			)
			(layer "B.Fab")
		)
		(fp_line
			(start -0.7239 1.9939)
			(end -0.7239 -0.2159)
			(stroke
				(width 0.1)
				(type default)
			)
			(layer "B.Fab")
		)
		(fp_line
			(start 0.7239 -0.2159)
			(end 0.7239 1.9939)
			(stroke
				(width 0.1)
				(type default)
			)
			(layer "B.Fab")
		)
		(fp_line
			(start 0.7239 1.9939)
			(end -0.7239 1.9939)
			(stroke
				(width 0.1)
				(type default)
			)
			(layer "B.Fab")
		)
		(pad "1" smd rect
			(at 0 0 180)
			(size 1.27 1.016)
			(layers "B.Cu" "B.Mask" "B.Paste")
			(net "PVCCMCP_CPU0")
		)
		(pad "2" smd rect
			(at 0 1.778 180)
			(size 1.27 1.016)
			(layers "B.Cu" "B.Mask" "B.Paste")
			(net "GND")
		)
		(zone
			(layer "B.Cu")
			(hatch none 0.5)
			(connect_pads
				(clearance 0)
			)
			(min_thickness 0.25)
			(keepout
				(tracks not_allowed)
				(vias allowed)
				(pads allowed)
				(copperpour not_allowed)
				(footprints allowed)
			)
			(placement
				(enabled no)
				(sheetname "")
			)
			(fill
				(thermal_gap 0.5)
				(thermal_bridge_width 0.5)
				(island_removal_mode 0)
			)
			(polygon
				(pts
					(xy 270.156686 -77.32014) (xy 268.886686 -77.32014) (xy 268.886686 -76.55814) (xy 270.156686 -76.55814)
				)
			)
		)
	)
	(footprint ""
		(layer "B.Cu")
		(at 276.000464 -12.954 90)
		(property "Reference" "C5G49"
			(at -1.14681 0.76708 180)
			(unlocked yes)
			(layer "B.SilkS")
			(effects
				(font
					(size 0.7874 0.5842)
					(thickness 0.1524)
				)
				(justify mirror)
			)
		)
		(property "Value" ""
			(at 0 0 90)
			(layer "B.Fab")
			(effects
				(font
					(size 1.27 1.27)
				)
				(justify mirror)
			)
		)
		(duplicate_pad_numbers_are_jumpers no)
		(fp_rect
			(start -0.4953 -0.2032)
			(end 0.4953 1.6002)
			(stroke
				(width 0)
				(type default)
			)
			(fill no)
			(layer "B.CrtYd")
		)
		(fp_line
			(start 0.4953 -0.2032)
			(end -0.4953 -0.2032)
			(stroke
				(width 0.1)
				(type default)
			)
			(layer "B.Fab")
		)
		(fp_line
			(start -0.4953 -0.2032)
			(end -0.4953 1.6002)
			(stroke
				(width 0.1)
				(type default)
			)
			(layer "B.Fab")
		)
		(fp_line
			(start 0.4953 1.6002)
			(end 0.4953 -0.2032)
			(stroke
				(width 0.1)
				(type default)
			)
			(layer "B.Fab")
		)
		(fp_line
			(start -0.4953 1.6002)
			(end 0.4953 1.6002)
			(stroke
				(width 0.1)
				(type default)
			)
			(layer "B.Fab")
		)
		(pad "1" smd rect
			(at 0 0 270)
			(size 0.762 0.889)
			(layers "B.Cu" "B.Mask" "B.Paste")
			(net "PVDDQ_ABC")
		)
		(pad "2" smd rect
			(at 0 1.397 270)
			(size 0.762 0.889)
			(layers "B.Cu" "B.Mask" "B.Paste")
			(net "GND")
		)
		(zone
			(layer "B.Cu")
			(hatch none 0.5)
			(connect_pads
				(clearance 0)
			)
			(min_thickness 0.25)
			(keepout
				(tracks not_allowed)
				(vias allowed)
				(pads allowed)
				(copperpour not_allowed)
				(footprints allowed)
			)
			(placement
				(enabled no)
				(sheetname "")
			)
			(fill
				(thermal_gap 0.5)
				(thermal_bridge_width 0.5)
				(island_removal_mode 0)
			)
			(polygon
				(pts
					(xy 276.444964 -12.573) (xy 276.952964 -12.573) (xy 276.952964 -13.335) (xy 276.444964 -13.335)
				)
			)
		)
	)
	(footprint ""
		(layer "B.Cu")
		(at 80.719168 -27.2034 90)
		(property "Reference" "C8T2"
			(at 0.96393 5.132832 0)
			(unlocked yes)
			(layer "B.SilkS")
			(effects
				(font
					(size 0.7874 0.5842)
					(thickness 0.1524)
				)
				(justify mirror)
			)
		)
		(property "Value" ""
			(at 0 0 90)
			(layer "B.Fab")
			(effects
				(font
					(size 1.27 1.27)
				)
				(justify mirror)
			)
		)
		(duplicate_pad_numbers_are_jumpers no)
		(fp_rect
			(start 0.500126 1.598422)
			(end -0.500126 -0.201422)
			(stroke
				(width 0)
				(type default)
			)
			(fill no)
			(layer "B.CrtYd")
		)
		(fp_line
			(start 0.500126 -0.201422)
			(end -0.500126 -0.201422)
			(stroke
				(width 0.1)
				(type default)
			)
			(layer "B.Fab")
		)
		(fp_line
			(start -0.500126 -0.201422)
			(end -0.500126 1.598422)
			(stroke
				(width 0.1)
				(type default)
			)
			(layer "B.Fab")
		)
		(fp_line
			(start 0.500126 1.598422)
			(end 0.500126 -0.201422)
			(stroke
				(width 0.1)
				(type default)
			)
			(layer "B.Fab")
		)
		(fp_line
			(start -0.500126 1.598422)
			(end 0.500126 1.598422)
			(stroke
				(width 0.1)
				(type default)
			)
			(layer "B.Fab")
		)
		(pad "1" smd rect
			(at 0 0)
			(size 0.889 0.9906)
			(layers "B.Cu" "B.Mask" "B.Paste")
			(net "PVDDQ_GHJ")
		)
		(pad "2" smd rect
			(at 0 1.397)
			(size 0.889 0.9906)
			(layers "B.Cu" "B.Mask" "B.Paste")
			(net "GND")
		)
		(zone
			(layer "B.Cu")
			(hatch none 0.5)
			(connect_pads
				(clearance 0)
			)
			(min_thickness 0.25)
			(keepout
				(tracks allowed)
				(vias not_allowed)
				(pads allowed)
				(copperpour not_allowed)
				(footprints allowed)
			)
			(placement
				(enabled no)
				(sheetname "")
			)
			(fill
				(thermal_gap 0.5)
				(thermal_bridge_width 0.5)
				(island_removal_mode 0)
			)
			(polygon
				(pts
					(xy 81.671668 -27.6987) (xy 81.163668 -27.6987) (xy 81.163668 -26.7081) (xy 81.671668 -26.7081)
				)
			)
		)
		(zone
			(layer "B.Cu")
			(hatch none 0.5)
			(connect_pads
				(clearance 0)
			)
			(min_thickness 0.25)
			(keepout
				(tracks not_allowed)
				(vias allowed)
				(pads allowed)
				(copperpour not_allowed)
				(footprints allowed)
			)
			(placement
				(enabled no)
				(sheetname "")
			)
			(fill
				(thermal_gap 0.5)
				(thermal_bridge_width 0.5)
				(island_removal_mode 0)
			)
			(polygon
				(pts
					(xy 81.671668 -27.6987) (xy 81.163668 -27.6987) (xy 81.163668 -26.7081) (xy 81.671668 -26.7081)
				)
			)
		)
	)
	(footprint ""
		(layer "B.Cu")
		(at 94.271592 -82.001614)
		(property "Reference" "C8P7"
			(at 0 0 0)
			(layer "B.SilkS")
			(hide yes)
			(effects
				(font
					(size 1.27 1.27)
				)
				(justify mirror)
			)
		)
		(property "Value" ""
			(at 0 0 0)
			(layer "B.Fab")
			(effects
				(font
					(size 1.27 1.27)
				)
				(justify mirror)
			)
		)
		(duplicate_pad_numbers_are_jumpers no)
		(fp_poly
			(pts
				(xy 0.7239 -0.2159) (xy -0.7239 -0.2159) (xy -0.7239 1.9939) (xy 0.7239 1.9939)
			)
			(stroke
				(width 0)
				(type default)
			)
			(fill no)
			(layer "B.CrtYd")
		)
		(fp_line
			(start -0.7239 -0.2159)
			(end 0.7239 -0.2159)
			(stroke
				(width 0.1)
				(type default)
			)
			(layer "B.Fab")
		)
		(fp_line
			(start -0.7239 1.9939)
			(end -0.7239 -0.2159)
			(stroke
				(width 0.1)
				(type default)
			)
			(layer "B.Fab")
		)
		(fp_line
			(start 0.7239 -0.2159)
			(end 0.7239 1.9939)
			(stroke
				(width 0.1)
				(type default)
			)
			(layer "B.Fab")
		)
		(fp_line
			(start 0.7239 1.9939)
			(end -0.7239 1.9939)
			(stroke
				(width 0.1)
				(type default)
			)
			(layer "B.Fab")
		)
		(pad "1" smd rect
			(at 0 0 180)
			(size 1.27 1.016)
			(layers "B.Cu" "B.Mask" "B.Paste")
			(net "PVSA_CPU1")
		)
		(pad "2" smd rect
			(at 0 1.778 180)
			(size 1.27 1.016)
			(layers "B.Cu" "B.Mask" "B.Paste")
			(net "GND")
		)
		(zone
			(layer "B.Cu")
			(hatch none 0.5)
			(connect_pads
				(clearance 0)
			)
			(min_thickness 0.25)
			(keepout
				(tracks not_allowed)
				(vias allowed)
				(pads allowed)
				(copperpour not_allowed)
				(footprints allowed)
			)
			(placement
				(enabled no)
				(sheetname "")
			)
			(fill
				(thermal_gap 0.5)
				(thermal_bridge_width 0.5)
				(island_removal_mode 0)
			)
			(polygon
				(pts
					(xy 94.906592 -81.493614) (xy 93.636592 -81.493614) (xy 93.636592 -80.731614) (xy 94.906592 -80.731614)
				)
			)
		)
	)
	(footprint ""
		(layer "B.Cu")
		(at 367.827814 -124.389642 -90)
		(property "Reference" "R783"
			(at 0.8382 -0.67818 270)
			(unlocked yes)
			(layer "B.SilkS")
			(effects
				(font
					(size 0.4064 0.254)
					(thickness 0.1524)
				)
				(justify left mirror)
			)
		)
		(property "Value" ""
			(at 0 0 90)
			(layer "B.Fab")
			(effects
				(font
					(size 1.27 1.27)
				)
				(justify mirror)
			)
		)
		(duplicate_pad_numbers_are_jumpers no)
		(fp_poly
			(pts
				(xy 0.2794 -0.1016) (xy -0.2794 -0.1016) (xy -0.2794 0.9906) (xy 0.2794 0.9906)
			)
			(stroke
				(width 0)
				(type default)
			)
			(fill no)
			(layer "B.CrtYd")
		)
		(fp_line
			(start -0.2794 0.9906)
			(end -0.2794 -0.1016)
			(stroke
				(width 0.1)
				(type default)
			)
			(layer "B.Fab")
		)
		(fp_line
			(start 0.2794 0.9906)
			(end -0.2794 0.9906)
			(stroke
				(width 0.1)
				(type default)
			)
			(layer "B.Fab")
		)
		(fp_line
			(start -0.2794 -0.1016)
			(end 0.2794 -0.1016)
			(stroke
				(width 0.1)
				(type default)
			)
			(layer "B.Fab")
		)
		(fp_line
			(start 0.2794 -0.1016)
			(end 0.2794 0.9906)
			(stroke
				(width 0.1)
				(type default)
			)
			(layer "B.Fab")
		)
		(pad "1" smd rect
			(at 0 0 90)
			(size 0.508 0.508)
			(layers "B.Cu" "B.Mask" "B.Paste")
			(net "P3E_CPU0_PE1_PCH_RXP<9>")
		)
		(pad "2" smd rect
			(at 0 0.889 90)
			(size 0.508 0.508)
			(layers "B.Cu" "B.Mask" "B.Paste")
			(net "P3E_CPU0_PE1_PCH_CON_RXP<9>")
		)
		(zone
			(layer "B.Cu")
			(hatch none 0.5)
			(connect_pads
				(clearance 0)
			)
			(min_thickness 0.25)
			(keepout
				(tracks not_allowed)
				(vias allowed)
				(pads allowed)
				(copperpour not_allowed)
				(footprints allowed)
			)
			(placement
				(enabled no)
				(sheetname "")
			)
			(fill
				(thermal_gap 0.5)
				(thermal_bridge_width 0.5)
				(island_removal_mode 0)
			)
			(polygon
				(pts
					(xy 367.192814 -124.135642) (xy 367.192814 -124.643642) (xy 367.573814 -124.643642) (xy 367.573814 -124.135642)
				)
			)
		)
		(zone
			(layer "B.Cu")
			(hatch none 0.5)
			(connect_pads
				(clearance 0)
			)
			(min_thickness 0.25)
			(keepout
				(tracks allowed)
				(vias not_allowed)
				(pads allowed)
				(copperpour not_allowed)
				(footprints allowed)
			)
			(placement
				(enabled no)
				(sheetname "")
			)
			(fill
				(thermal_gap 0.5)
				(thermal_bridge_width 0.5)
				(island_removal_mode 0)
			)
			(polygon
				(pts
					(xy 367.573814 -124.135642) (xy 367.573814 -124.643642) (xy 367.192814 -124.643642) (xy 367.192814 -124.135642)
				)
			)
		)
	)
	(footprint ""
		(layer "B.Cu")
		(at 2.1082 -50.1142 -90)
		(property "Reference" "C9R12"
			(at 0 0 90)
			(layer "B.SilkS")
			(hide yes)
			(effects
				(font
					(size 1.27 1.27)
				)
				(justify mirror)
			)
		)
		(property "Value" ""
			(at 0 0 90)
			(layer "B.Fab")
			(effects
				(font
					(size 1.27 1.27)
				)
				(justify mirror)
			)
		)
		(duplicate_pad_numbers_are_jumpers no)
		(fp_rect
			(start 0.3048 -0.1016)
			(end -0.3048 0.9906)
			(stroke
				(width 0)
				(type default)
			)
			(fill no)
			(layer "B.CrtYd")
		)
		(fp_line
			(start -0.3048 0.9906)
			(end -0.3048 -0.1016)
			(stroke
				(width 0.1)
				(type default)
			)
			(layer "B.Fab")
		)
		(fp_line
			(start 0.3048 0.9906)
			(end -0.3048 0.9906)
			(stroke
				(width 0.1)
				(type default)
			)
			(layer "B.Fab")
		)
		(fp_line
			(start -0.3048 -0.1016)
			(end 0.3048 -0.1016)
			(stroke
				(width 0.1)
				(type default)
			)
			(layer "B.Fab")
		)
		(fp_line
			(start 0.3048 -0.1016)
			(end 0.3048 0.9906)
			(stroke
				(width 0.1)
				(type default)
			)
			(layer "B.Fab")
		)
		(pad "1" smd rect
			(at 0 0 90)
			(size 0.508 0.508)
			(layers "B.Cu" "B.Mask" "B.Paste")
			(net "P12V_PSU")
		)
		(pad "2" smd rect
			(at 0 0.889 90)
			(size 0.508 0.508)
			(layers "B.Cu" "B.Mask" "B.Paste")
			(net "GND")
		)
		(zone
			(layer "B.Cu")
			(hatch none 0.5)
			(connect_pads
				(clearance 0)
			)
			(min_thickness 0.25)
			(keepout
				(tracks not_allowed)
				(vias allowed)
				(pads allowed)
				(copperpour not_allowed)
				(footprints allowed)
			)
			(placement
				(enabled no)
				(sheetname "")
			)
			(fill
				(thermal_gap 0.5)
				(thermal_bridge_width 0.5)
				(island_removal_mode 0)
			)
			(polygon
				(pts
					(xy 1.8542 -49.8602) (xy 1.8542 -50.3682) (xy 1.4732 -50.3682) (xy 1.4732 -49.8602)
				)
			)
		)
		(zone
			(layer "B.Cu")
			(hatch none 0.5)
			(connect_pads
				(clearance 0)
			)
			(min_thickness 0.25)
			(keepout
				(tracks allowed)
				(vias not_allowed)
				(pads allowed)
				(copperpour not_allowed)
				(footprints allowed)
			)
			(placement
				(enabled no)
				(sheetname "")
			)
			(fill
				(thermal_gap 0.5)
				(thermal_bridge_width 0.5)
				(island_removal_mode 0)
			)
			(polygon
				(pts
					(xy 1.8542 -49.8602) (xy 1.8542 -50.3682) (xy 1.4732 -50.3682) (xy 1.4732 -49.8602)
				)
			)
		)
	)
	(footprint ""
		(layer "B.Cu")
		(at 390.635744 -24.169116 -90)
		(property "Reference" "C2T21"
			(at 0 0 90)
			(layer "B.SilkS")
			(hide yes)
			(effects
				(font
					(size 1.27 1.27)
				)
				(justify mirror)
			)
		)
		(property "Value" ""
			(at 0 0 90)
			(layer "B.Fab")
			(effects
				(font
					(size 1.27 1.27)
				)
				(justify mirror)
			)
		)
		(duplicate_pad_numbers_are_jumpers no)
		(fp_poly
			(pts
				(xy -0.3048 -0.1016) (xy -0.3048 0.9906) (xy 0.3048 0.9906) (xy 0.3048 -0.1016)
			)
			(stroke
				(width 0)
				(type default)
			)
			(fill no)
			(layer "B.CrtYd")
		)
		(fp_line
			(start -0.3048 0.9906)
			(end -0.3048 -0.1016)
			(stroke
				(width 0.1)
				(type default)
			)
			(layer "B.Fab")
		)
		(fp_line
			(start 0.3048 0.9906)
			(end -0.3048 0.9906)
			(stroke
				(width 0.1)
				(type default)
			)
			(layer "B.Fab")
		)
		(fp_line
			(start -0.3048 -0.1016)
			(end 0.3048 -0.1016)
			(stroke
				(width 0.1)
				(type default)
			)
			(layer "B.Fab")
		)
		(fp_line
			(start 0.3048 -0.1016)
			(end 0.3048 0.9906)
			(stroke
				(width 0.1)
				(type default)
			)
			(layer "B.Fab")
		)
		(pad "1" smd rect
			(at 0 0 90)
			(size 0.508 0.508)
			(layers "B.Cu" "B.Mask" "B.Paste")
			(net "P3V3")
		)
		(pad "2" smd rect
			(at 0 0.889 90)
			(size 0.508 0.508)
			(layers "B.Cu" "B.Mask" "B.Paste")
			(net "GND")
		)
		(zone
			(layer "B.Cu")
			(hatch none 0.5)
			(connect_pads
				(clearance 0)
			)
			(min_thickness 0.25)
			(keepout
				(tracks not_allowed)
				(vias allowed)
				(pads allowed)
				(copperpour not_allowed)
				(footprints allowed)
			)
			(placement
				(enabled no)
				(sheetname "")
			)
			(fill
				(thermal_gap 0.5)
				(thermal_bridge_width 0.5)
				(island_removal_mode 0)
			)
			(polygon
				(pts
					(xy 390.000744 -23.915116) (xy 390.000744 -24.423116) (xy 390.381744 -24.423116) (xy 390.381744 -23.915116)
				)
			)
		)
		(zone
			(layer "B.Cu")
			(hatch none 0.5)
			(connect_pads
				(clearance 0)
			)
			(min_thickness 0.25)
			(keepout
				(tracks allowed)
				(vias not_allowed)
				(pads allowed)
				(copperpour not_allowed)
				(footprints allowed)
			)
			(placement
				(enabled no)
				(sheetname "")
			)
			(fill
				(thermal_gap 0.5)
				(thermal_bridge_width 0.5)
				(island_removal_mode 0)
			)
			(polygon
				(pts
					(xy 390.381744 -23.915116) (xy 390.381744 -24.423116) (xy 390.000744 -24.423116) (xy 390.000744 -23.915116)
				)
			)
		)
	)
	(footprint ""
		(layer "B.Cu")
		(at 415.4805 -29.337 90)
		(property "Reference" "C25W37"
			(at 0.8382 -0.67818 90)
			(unlocked yes)
			(layer "B.SilkS")
			(effects
				(font
					(size 0.4064 0.254)
					(thickness 0.1524)
				)
				(justify left mirror)
			)
		)
		(property "Value" ""
			(at 0 0 90)
			(layer "B.Fab")
			(effects
				(font
					(size 1.27 1.27)
				)
				(justify mirror)
			)
		)
		(duplicate_pad_numbers_are_jumpers no)
		(fp_poly
			(pts
				(xy -0.3048 -0.1016) (xy -0.3048 0.9906) (xy 0.3048 0.9906) (xy 0.3048 -0.1016)
			)
			(stroke
				(width 0)
				(type default)
			)
			(fill no)
			(layer "B.CrtYd")
		)
		(fp_line
			(start 0.3048 -0.1016)
			(end 0.3048 0.9906)
			(stroke
				(width 0.1)
				(type default)
			)
			(layer "B.Fab")
		)
		(fp_line
			(start -0.3048 -0.1016)
			(end 0.3048 -0.1016)
			(stroke
				(width 0.1)
				(type default)
			)
			(layer "B.Fab")
		)
		(fp_line
			(start 0.3048 0.9906)
			(end -0.3048 0.9906)
			(stroke
				(width 0.1)
				(type default)
			)
			(layer "B.Fab")
		)
		(fp_line
			(start -0.3048 0.9906)
			(end -0.3048 -0.1016)
			(stroke
				(width 0.1)
				(type default)
			)
			(layer "B.Fab")
		)
		(pad "1" smd rect
			(at 0 0 270)
			(size 0.508 0.508)
			(layers "B.Cu" "B.Mask" "B.Paste")
			(net "VCC_A_1V1")
		)
		(pad "2" smd rect
			(at 0 0.889 270)
			(size 0.508 0.508)
			(layers "B.Cu" "B.Mask" "B.Paste")
			(net "GND")
		)
		(zone
			(layer "B.Cu")
			(hatch none 0.5)
			(connect_pads
				(clearance 0)
			)
			(min_thickness 0.25)
			(keepout
				(tracks allowed)
				(vias not_allowed)
				(pads allowed)
				(copperpour not_allowed)
				(footprints allowed)
			)
			(placement
				(enabled no)
				(sheetname "")
			)
			(fill
				(thermal_gap 0.5)
				(thermal_bridge_width 0.5)
				(island_removal_mode 0)
			)
			(polygon
				(pts
					(xy 415.7345 -29.591) (xy 415.7345 -29.083) (xy 416.1155 -29.083) (xy 416.1155 -29.591)
				)
			)
		)
		(zone
			(layer "B.Cu")
			(hatch none 0.5)
			(connect_pads
				(clearance 0)
			)
			(min_thickness 0.25)
			(keepout
				(tracks not_allowed)
				(vias allowed)
				(pads allowed)
				(copperpour not_allowed)
				(footprints allowed)
			)
			(placement
				(enabled no)
				(sheetname "")
			)
			(fill
				(thermal_gap 0.5)
				(thermal_bridge_width 0.5)
				(island_removal_mode 0)
			)
			(polygon
				(pts
					(xy 416.1155 -29.591) (xy 416.1155 -29.083) (xy 415.7345 -29.083) (xy 415.7345 -29.591)
				)
			)
		)
	)
	(footprint ""
		(layer "B.Cu")
		(at 482.53015 -22.163024 -90)
		(property "Reference" "C1R23"
			(at -3.25247 1.2954 180)
			(unlocked yes)
			(layer "B.SilkS")
			(effects
				(font
					(size 0.7874 0.5842)
					(thickness 0.1524)
				)
				(justify mirror)
			)
		)
		(property "Value" ""
			(at 0 0 90)
			(layer "B.Fab")
			(effects
				(font
					(size 1.27 1.27)
				)
				(justify mirror)
			)
		)
		(duplicate_pad_numbers_are_jumpers no)
		(fp_line
			(start -2.286 7.366)
			(end -1.600708 7.366)
			(stroke
				(width 0.1524)
				(type default)
			)
			(layer "B.SilkS")
		)
		(fp_line
			(start -2.286 7.366)
			(end -2.286 1.63195)
			(stroke
				(width 0.1524)
				(type default)
			)
			(layer "B.SilkS")
		)
		(fp_line
			(start 2.286 7.366)
			(end 1.60147 7.366)
			(stroke
				(width 0.1524)
				(type default)
			)
			(layer "B.SilkS")
		)
		(fp_line
			(start 2.286 7.366)
			(end 2.286 1.632712)
			(stroke
				(width 0.1524)
				(type default)
			)
			(layer "B.SilkS")
		)
		(fp_line
			(start -2.504948 1.633728)
			(end -1.6002 1.633728)
			(stroke
				(width 0.1524)
				(type default)
			)
			(layer "B.SilkS")
		)
		(fp_line
			(start 2.563114 1.633728)
			(end 1.6002 1.633728)
			(stroke
				(width 0.1524)
				(type default)
			)
			(layer "B.SilkS")
		)
		(fp_line
			(start -2.504948 -1.616456)
			(end -2.504948 1.633728)
			(stroke
				(width 0.1524)
				(type default)
			)
			(layer "B.SilkS")
		)
		(fp_line
			(start -1.6002 -1.616456)
			(end -2.504948 -1.616456)
			(stroke
				(width 0.1524)
				(type default)
			)
			(layer "B.SilkS")
		)
		(fp_line
			(start 1.6002 -1.616456)
			(end 2.563114 -1.616456)
			(stroke
				(width 0.1524)
				(type default)
			)
			(layer "B.SilkS")
		)
		(fp_line
			(start 2.563114 -1.616456)
			(end 2.563114 1.633728)
			(stroke
				(width 0.1524)
				(type default)
			)
			(layer "B.SilkS")
		)
		(fp_line
			(start -2.286 7.366)
			(end 2.286 7.366)
			(stroke
				(width 0.1)
				(type default)
			)
			(layer "B.Fab")
		)
		(fp_line
			(start 2.286 7.366)
			(end 2.286 -0.254)
			(stroke
				(width 0.1)
				(type default)
			)
			(layer "B.Fab")
		)
		(fp_line
			(start -2.286 -0.254)
			(end -2.286 7.366)
			(stroke
				(width 0.1)
				(type default)
			)
			(layer "B.Fab")
		)
		(fp_line
			(start 2.286 -0.254)
			(end -2.286 -0.254)
			(stroke
				(width 0.1)
				(type default)
			)
			(layer "B.Fab")
		)
		(pad "1" smd rect
			(at 0 0 90)
			(size 2.54 3.048)
			(layers "B.Cu" "B.Mask" "B.Paste")
			(net "P12V_STBY")
		)
		(pad "2" smd rect
			(at 0 7.112 90)
			(size 2.54 3.048)
			(layers "B.Cu" "B.Mask" "B.Paste")
			(net "GND")
		)
	)
	(footprint ""
		(layer "B.Cu")
		(at 422.656 -153.035 90)
		(property "Reference" "C2L10"
			(at 0 0 90)
			(layer "B.SilkS")
			(hide yes)
			(effects
				(font
					(size 1.27 1.27)
				)
				(justify mirror)
			)
		)
		(property "Value" ""
			(at 0 0 90)
			(layer "B.Fab")
			(effects
				(font
					(size 1.27 1.27)
				)
				(justify mirror)
			)
		)
		(duplicate_pad_numbers_are_jumpers no)
		(fp_poly
			(pts
				(xy -0.3048 -0.1016) (xy -0.3048 0.9906) (xy 0.3048 0.9906) (xy 0.3048 -0.1016)
			)
			(stroke
				(width 0)
				(type default)
			)
			(fill no)
			(layer "B.CrtYd")
		)
		(fp_line
			(start 0.3048 -0.1016)
			(end 0.3048 0.9906)
			(stroke
				(width 0.1)
				(type default)
			)
			(layer "B.Fab")
		)
		(fp_line
			(start -0.3048 -0.1016)
			(end 0.3048 -0.1016)
			(stroke
				(width 0.1)
				(type default)
			)
			(layer "B.Fab")
		)
		(fp_line
			(start 0.3048 0.9906)
			(end -0.3048 0.9906)
			(stroke
				(width 0.1)
				(type default)
			)
			(layer "B.Fab")
		)
		(fp_line
			(start -0.3048 0.9906)
			(end -0.3048 -0.1016)
			(stroke
				(width 0.1)
				(type default)
			)
			(layer "B.Fab")
		)
		(pad "1" smd rect
			(at 0 0 270)
			(size 0.508 0.508)
			(layers "B.Cu" "B.Mask" "B.Paste")
			(net "SATA6G_PCH_PCIE_UP_SATA_RXP<1>")
		)
		(pad "2" smd rect
			(at 0 0.889 270)
			(size 0.508 0.508)
			(layers "B.Cu" "B.Mask" "B.Paste")
			(net "SATA6G_P1_RX_C_DP")
		)
		(zone
			(layer "B.Cu")
			(hatch none 0.5)
			(connect_pads
				(clearance 0)
			)
			(min_thickness 0.25)
			(keepout
				(tracks allowed)
				(vias not_allowed)
				(pads allowed)
				(copperpour not_allowed)
				(footprints allowed)
			)
			(placement
				(enabled no)
				(sheetname "")
			)
			(fill
				(thermal_gap 0.5)
				(thermal_bridge_width 0.5)
				(island_removal_mode 0)
			)
			(polygon
				(pts
					(xy 422.91 -153.289) (xy 422.91 -152.781) (xy 423.291 -152.781) (xy 423.291 -153.289)
				)
			)
		)
		(zone
			(layer "B.Cu")
			(hatch none 0.5)
			(connect_pads
				(clearance 0)
			)
			(min_thickness 0.25)
			(keepout
				(tracks not_allowed)
				(vias allowed)
				(pads allowed)
				(copperpour not_allowed)
				(footprints allowed)
			)
			(placement
				(enabled no)
				(sheetname "")
			)
			(fill
				(thermal_gap 0.5)
				(thermal_bridge_width 0.5)
				(island_removal_mode 0)
			)
			(polygon
				(pts
					(xy 423.291 -153.289) (xy 423.291 -152.781) (xy 422.91 -152.781) (xy 422.91 -153.289)
				)
			)
		)
	)
	(footprint ""
		(layer "B.Cu")
		(at 32.832802 -76.229464 90)
		(property "Reference" "C9P9"
			(at 0 0 90)
			(layer "B.SilkS")
			(hide yes)
			(effects
				(font
					(size 1.27 1.27)
				)
				(justify mirror)
			)
		)
		(property "Value" ""
			(at 0 0 90)
			(layer "B.Fab")
			(effects
				(font
					(size 1.27 1.27)
				)
				(justify mirror)
			)
		)
		(duplicate_pad_numbers_are_jumpers no)
		(fp_poly
			(pts
				(xy 0.7239 -0.2159) (xy -0.7239 -0.2159) (xy -0.7239 1.9939) (xy 0.7239 1.9939)
			)
			(stroke
				(width 0)
				(type default)
			)
			(fill no)
			(layer "B.CrtYd")
		)
		(fp_line
			(start 0.7239 -0.2159)
			(end 0.7239 1.9939)
			(stroke
				(width 0.1)
				(type default)
			)
			(layer "B.Fab")
		)
		(fp_line
			(start -0.7239 -0.2159)
			(end 0.7239 -0.2159)
			(stroke
				(width 0.1)
				(type default)
			)
			(layer "B.Fab")
		)
		(fp_line
			(start 0.7239 1.9939)
			(end -0.7239 1.9939)
			(stroke
				(width 0.1)
				(type default)
			)
			(layer "B.Fab")
		)
		(fp_line
			(start -0.7239 1.9939)
			(end -0.7239 -0.2159)
			(stroke
				(width 0.1)
				(type default)
			)
			(layer "B.Fab")
		)
		(pad "1" smd rect
			(at 0 0 270)
			(size 1.27 1.016)
			(layers "B.Cu" "B.Mask" "B.Paste")
			(net "VR_FET_SW_P12V_STBY_PVCCIN_CPU1")
		)
		(pad "2" smd rect
			(at 0 1.778 270)
			(size 1.27 1.016)
			(layers "B.Cu" "B.Mask" "B.Paste")
			(net "GND")
		)
		(zone
			(layer "B.Cu")
			(hatch none 0.5)
			(connect_pads
				(clearance 0)
			)
			(min_thickness 0.25)
			(keepout
				(tracks not_allowed)
				(vias allowed)
				(pads allowed)
				(copperpour not_allowed)
				(footprints allowed)
			)
			(placement
				(enabled no)
				(sheetname "")
			)
			(fill
				(thermal_gap 0.5)
				(thermal_bridge_width 0.5)
				(island_removal_mode 0)
			)
			(polygon
				(pts
					(xy 33.340802 -76.864464) (xy 33.340802 -75.594464) (xy 34.102802 -75.594464) (xy 34.102802 -76.864464)
				)
			)
		)
	)
	(footprint ""
		(layer "B.Cu")
		(at 422.402 -141.9606)
		(property "Reference" "C2L43"
			(at 0 0 0)
			(layer "B.SilkS")
			(hide yes)
			(effects
				(font
					(size 1.27 1.27)
				)
				(justify mirror)
			)
		)
		(property "Value" ""
			(at 0 0 0)
			(layer "B.Fab")
			(effects
				(font
					(size 1.27 1.27)
				)
				(justify mirror)
			)
		)
		(duplicate_pad_numbers_are_jumpers no)
		(fp_poly
			(pts
				(xy -0.3048 -0.1016) (xy -0.3048 0.9906) (xy 0.3048 0.9906) (xy 0.3048 -0.1016)
			)
			(stroke
				(width 0)
				(type default)
			)
			(fill no)
			(layer "B.CrtYd")
		)
		(fp_line
			(start -0.3048 -0.1016)
			(end 0.3048 -0.1016)
			(stroke
				(width 0.1)
				(type default)
			)
			(layer "B.Fab")
		)
		(fp_line
			(start -0.3048 0.9906)
			(end -0.3048 -0.1016)
			(stroke
				(width 0.1)
				(type default)
			)
			(layer "B.Fab")
		)
		(fp_line
			(start 0.3048 -0.1016)
			(end 0.3048 0.9906)
			(stroke
				(width 0.1)
				(type default)
			)
			(layer "B.Fab")
		)
		(fp_line
			(start 0.3048 0.9906)
			(end -0.3048 0.9906)
			(stroke
				(width 0.1)
				(type default)
			)
			(layer "B.Fab")
		)
		(pad "1" smd rect
			(at 0 0 180)
			(size 0.508 0.508)
			(layers "B.Cu" "B.Mask" "B.Paste")
			(net "SATA6G_P1_TX_C_DP")
		)
		(pad "2" smd rect
			(at 0 0.889 180)
			(size 0.508 0.508)
			(layers "B.Cu" "B.Mask" "B.Paste")
			(net "SATA6G_PCH_PCIE_UP_SATA_TXP<1>")
		)
		(zone
			(layer "B.Cu")
			(hatch none 0.5)
			(connect_pads
				(clearance 0)
			)
			(min_thickness 0.25)
			(keepout
				(tracks allowed)
				(vias not_allowed)
				(pads allowed)
				(copperpour not_allowed)
				(footprints allowed)
			)
			(placement
				(enabled no)
				(sheetname "")
			)
			(fill
				(thermal_gap 0.5)
				(thermal_bridge_width 0.5)
				(island_removal_mode 0)
			)
			(polygon
				(pts
					(xy 422.656 -141.7066) (xy 422.148 -141.7066) (xy 422.148 -141.3256) (xy 422.656 -141.3256)
				)
			)
		)
		(zone
			(layer "B.Cu")
			(hatch none 0.5)
			(connect_pads
				(clearance 0)
			)
			(min_thickness 0.25)
			(keepout
				(tracks not_allowed)
				(vias allowed)
				(pads allowed)
				(copperpour not_allowed)
				(footprints allowed)
			)
			(placement
				(enabled no)
				(sheetname "")
			)
			(fill
				(thermal_gap 0.5)
				(thermal_bridge_width 0.5)
				(island_removal_mode 0)
			)
			(polygon
				(pts
					(xy 422.656 -141.3256) (xy 422.148 -141.3256) (xy 422.148 -141.7066) (xy 422.656 -141.7066)
				)
			)
		)
	)
	(footprint ""
		(layer "B.Cu")
		(at 396.376906 -156.115258 -90)
		(property "Reference" "R2L24"
			(at 0 0 90)
			(layer "B.SilkS")
			(hide yes)
			(effects
				(font
					(size 1.27 1.27)
				)
				(justify mirror)
			)
		)
		(property "Value" ""
			(at 0 0 90)
			(layer "B.Fab")
			(effects
				(font
					(size 1.27 1.27)
				)
				(justify mirror)
			)
		)
		(duplicate_pad_numbers_are_jumpers no)
		(fp_poly
			(pts
				(xy 0.2794 -0.1016) (xy -0.2794 -0.1016) (xy -0.2794 0.9906) (xy 0.2794 0.9906)
			)
			(stroke
				(width 0)
				(type default)
			)
			(fill no)
			(layer "B.CrtYd")
		)
		(fp_line
			(start -0.2794 0.9906)
			(end -0.2794 -0.1016)
			(stroke
				(width 0.1)
				(type default)
			)
			(layer "B.Fab")
		)
		(fp_line
			(start 0.2794 0.9906)
			(end -0.2794 0.9906)
			(stroke
				(width 0.1)
				(type default)
			)
			(layer "B.Fab")
		)
		(fp_line
			(start -0.2794 -0.1016)
			(end 0.2794 -0.1016)
			(stroke
				(width 0.1)
				(type default)
			)
			(layer "B.Fab")
		)
		(fp_line
			(start 0.2794 -0.1016)
			(end 0.2794 0.9906)
			(stroke
				(width 0.1)
				(type default)
			)
			(layer "B.Fab")
		)
		(pad "1" smd rect
			(at 0 0 90)
			(size 0.508 0.508)
			(layers "B.Cu" "B.Mask" "B.Paste")
			(net "P3V3_STBY")
		)
		(pad "2" smd rect
			(at 0 0.889 90)
			(size 0.508 0.508)
			(layers "B.Cu" "B.Mask" "B.Paste")
			(net "PU_VR_PVNN_PCH_FAULT1")
		)
		(zone
			(layer "B.Cu")
			(hatch none 0.5)
			(connect_pads
				(clearance 0)
			)
			(min_thickness 0.25)
			(keepout
				(tracks not_allowed)
				(vias allowed)
				(pads allowed)
				(copperpour not_allowed)
				(footprints allowed)
			)
			(placement
				(enabled no)
				(sheetname "")
			)
			(fill
				(thermal_gap 0.5)
				(thermal_bridge_width 0.5)
				(island_removal_mode 0)
			)
			(polygon
				(pts
					(xy 395.741906 -155.861258) (xy 395.741906 -156.369258) (xy 396.122906 -156.369258) (xy 396.122906 -155.861258)
				)
			)
		)
		(zone
			(layer "B.Cu")
			(hatch none 0.5)
			(connect_pads
				(clearance 0)
			)
			(min_thickness 0.25)
			(keepout
				(tracks allowed)
				(vias not_allowed)
				(pads allowed)
				(copperpour not_allowed)
				(footprints allowed)
			)
			(placement
				(enabled no)
				(sheetname "")
			)
			(fill
				(thermal_gap 0.5)
				(thermal_bridge_width 0.5)
				(island_removal_mode 0)
			)
			(polygon
				(pts
					(xy 396.122906 -155.861258) (xy 396.122906 -156.369258) (xy 395.741906 -156.369258) (xy 395.741906 -155.861258)
				)
			)
		)
	)
	(footprint ""
		(layer "B.Cu")
		(at 439.1025 -48.641 -90)
		(property "Reference" "R2W1"
			(at 0.8382 -0.67818 270)
			(unlocked yes)
			(layer "B.SilkS")
			(effects
				(font
					(size 0.4064 0.254)
					(thickness 0.1524)
				)
				(justify left mirror)
			)
		)
		(property "Value" ""
			(at 0 0 90)
			(layer "B.Fab")
			(effects
				(font
					(size 1.27 1.27)
				)
				(justify mirror)
			)
		)
		(duplicate_pad_numbers_are_jumpers no)
		(fp_poly
			(pts
				(xy 0.2794 -0.1016) (xy -0.2794 -0.1016) (xy -0.2794 0.9906) (xy 0.2794 0.9906)
			)
			(stroke
				(width 0)
				(type default)
			)
			(fill no)
			(layer "B.CrtYd")
		)
		(fp_line
			(start -0.2794 0.9906)
			(end -0.2794 -0.1016)
			(stroke
				(width 0.1)
				(type default)
			)
			(layer "B.Fab")
		)
		(fp_line
			(start 0.2794 0.9906)
			(end -0.2794 0.9906)
			(stroke
				(width 0.1)
				(type default)
			)
			(layer "B.Fab")
		)
		(fp_line
			(start -0.2794 -0.1016)
			(end 0.2794 -0.1016)
			(stroke
				(width 0.1)
				(type default)
			)
			(layer "B.Fab")
		)
		(fp_line
			(start 0.2794 -0.1016)
			(end 0.2794 0.9906)
			(stroke
				(width 0.1)
				(type default)
			)
			(layer "B.Fab")
		)
		(pad "1" smd rect
			(at 0 0 90)
			(size 0.508 0.508)
			(layers "B.Cu" "B.Mask" "B.Paste")
			(net "P3V3_STBY")
		)
		(pad "2" smd rect
			(at 0 0.889 90)
			(size 0.508 0.508)
			(layers "B.Cu" "B.Mask" "B.Paste")
			(net "FM_MEZZB_PRSNT1_N")
		)
		(zone
			(layer "B.Cu")
			(hatch none 0.5)
			(connect_pads
				(clearance 0)
			)
			(min_thickness 0.25)
			(keepout
				(tracks not_allowed)
				(vias allowed)
				(pads allowed)
				(copperpour not_allowed)
				(footprints allowed)
			)
			(placement
				(enabled no)
				(sheetname "")
			)
			(fill
				(thermal_gap 0.5)
				(thermal_bridge_width 0.5)
				(island_removal_mode 0)
			)
			(polygon
				(pts
					(xy 438.4675 -48.387) (xy 438.4675 -48.895) (xy 438.8485 -48.895) (xy 438.8485 -48.387)
				)
			)
		)
		(zone
			(layer "B.Cu")
			(hatch none 0.5)
			(connect_pads
				(clearance 0)
			)
			(min_thickness 0.25)
			(keepout
				(tracks allowed)
				(vias not_allowed)
				(pads allowed)
				(copperpour not_allowed)
				(footprints allowed)
			)
			(placement
				(enabled no)
				(sheetname "")
			)
			(fill
				(thermal_gap 0.5)
				(thermal_bridge_width 0.5)
				(island_removal_mode 0)
			)
			(polygon
				(pts
					(xy 438.8485 -48.387) (xy 438.8485 -48.895) (xy 438.4675 -48.895) (xy 438.4675 -48.387)
				)
			)
		)
	)
	(footprint ""
		(layer "B.Cu")
		(at 453.5678 -153.6446 180)
		(property "Reference" "R9A2"
			(at 0 0 0)
			(layer "B.SilkS")
			(hide yes)
			(effects
				(font
					(size 1.27 1.27)
				)
				(justify mirror)
			)
		)
		(property "Value" ""
			(at 0 0 0)
			(layer "B.Fab")
			(effects
				(font
					(size 1.27 1.27)
				)
				(justify mirror)
			)
		)
		(duplicate_pad_numbers_are_jumpers no)
		(fp_poly
			(pts
				(xy 0.2794 -0.1016) (xy -0.2794 -0.1016) (xy -0.2794 0.9906) (xy 0.2794 0.9906)
			)
			(stroke
				(width 0)
				(type default)
			)
			(fill no)
			(layer "B.CrtYd")
		)
		(fp_line
			(start 0.2794 0.9906)
			(end -0.2794 0.9906)
			(stroke
				(width 0.1)
				(type default)
			)
			(layer "B.Fab")
		)
		(fp_line
			(start 0.2794 -0.1016)
			(end 0.2794 0.9906)
			(stroke
				(width 0.1)
				(type default)
			)
			(layer "B.Fab")
		)
		(fp_line
			(start -0.2794 0.9906)
			(end -0.2794 -0.1016)
			(stroke
				(width 0.1)
				(type default)
			)
			(layer "B.Fab")
		)
		(fp_line
			(start -0.2794 -0.1016)
			(end 0.2794 -0.1016)
			(stroke
				(width 0.1)
				(type default)
			)
			(layer "B.Fab")
		)
		(pad "1" smd rect
			(at 0 0)
			(size 0.508 0.508)
			(layers "B.Cu" "B.Mask" "B.Paste")
			(net "XDP_PCH_CPU_TCK0")
		)
		(pad "2" smd rect
			(at 0 0.889)
			(size 0.508 0.508)
			(layers "B.Cu" "B.Mask" "B.Paste")
			(net "XDP_CPU_GTL_TCK_R2")
		)
		(zone
			(layer "B.Cu")
			(hatch none 0.5)
			(connect_pads
				(clearance 0)
			)
			(min_thickness 0.25)
			(keepout
				(tracks not_allowed)
				(vias allowed)
				(pads allowed)
				(copperpour not_allowed)
				(footprints allowed)
			)
			(placement
				(enabled no)
				(sheetname "")
			)
			(fill
				(thermal_gap 0.5)
				(thermal_bridge_width 0.5)
				(island_removal_mode 0)
			)
			(polygon
				(pts
					(xy 453.3138 -154.2796) (xy 453.8218 -154.2796) (xy 453.8218 -153.8986) (xy 453.3138 -153.8986)
				)
			)
		)
		(zone
			(layer "B.Cu")
			(hatch none 0.5)
			(connect_pads
				(clearance 0)
			)
			(min_thickness 0.25)
			(keepout
				(tracks allowed)
				(vias not_allowed)
				(pads allowed)
				(copperpour not_allowed)
				(footprints allowed)
			)
			(placement
				(enabled no)
				(sheetname "")
			)
			(fill
				(thermal_gap 0.5)
				(thermal_bridge_width 0.5)
				(island_removal_mode 0)
			)
			(polygon
				(pts
					(xy 453.3138 -153.8986) (xy 453.8218 -153.8986) (xy 453.8218 -154.2796) (xy 453.3138 -154.2796)
				)
			)
		)
	)
	(footprint ""
		(layer "B.Cu")
		(at 417.895024 -140.843 180)
		(property "Reference" "R2L23"
			(at 0 0 0)
			(layer "B.SilkS")
			(hide yes)
			(effects
				(font
					(size 1.27 1.27)
				)
				(justify mirror)
			)
		)
		(property "Value" ""
			(at 0 0 0)
			(layer "B.Fab")
			(effects
				(font
					(size 1.27 1.27)
				)
				(justify mirror)
			)
		)
		(duplicate_pad_numbers_are_jumpers no)
		(fp_poly
			(pts
				(xy 0.2794 -0.1016) (xy -0.2794 -0.1016) (xy -0.2794 0.9906) (xy 0.2794 0.9906)
			)
			(stroke
				(width 0)
				(type default)
			)
			(fill no)
			(layer "B.CrtYd")
		)
		(fp_line
			(start 0.2794 0.9906)
			(end -0.2794 0.9906)
			(stroke
				(width 0.1)
				(type default)
			)
			(layer "B.Fab")
		)
		(fp_line
			(start 0.2794 -0.1016)
			(end 0.2794 0.9906)
			(stroke
				(width 0.1)
				(type default)
			)
			(layer "B.Fab")
		)
		(fp_line
			(start -0.2794 0.9906)
			(end -0.2794 -0.1016)
			(stroke
				(width 0.1)
				(type default)
			)
			(layer "B.Fab")
		)
		(fp_line
			(start -0.2794 -0.1016)
			(end 0.2794 -0.1016)
			(stroke
				(width 0.1)
				(type default)
			)
			(layer "B.Fab")
		)
		(pad "1" smd rect
			(at 0 0)
			(size 0.508 0.508)
			(layers "B.Cu" "B.Mask" "B.Paste")
			(net "P3V3")
		)
		(pad "2" smd rect
			(at 0 0.889)
			(size 0.508 0.508)
			(layers "B.Cu" "B.Mask" "B.Paste")
			(net "PU_DATAIN1_SATA_1_R")
		)
		(zone
			(layer "B.Cu")
			(hatch none 0.5)
			(connect_pads
				(clearance 0)
			)
			(min_thickness 0.25)
			(keepout
				(tracks not_allowed)
				(vias allowed)
				(pads allowed)
				(copperpour not_allowed)
				(footprints allowed)
			)
			(placement
				(enabled no)
				(sheetname "")
			)
			(fill
				(thermal_gap 0.5)
				(thermal_bridge_width 0.5)
				(island_removal_mode 0)
			)
			(polygon
				(pts
					(xy 417.641024 -141.478) (xy 418.149024 -141.478) (xy 418.149024 -141.097) (xy 417.641024 -141.097)
				)
			)
		)
		(zone
			(layer "B.Cu")
			(hatch none 0.5)
			(connect_pads
				(clearance 0)
			)
			(min_thickness 0.25)
			(keepout
				(tracks allowed)
				(vias not_allowed)
				(pads allowed)
				(copperpour not_allowed)
				(footprints allowed)
			)
			(placement
				(enabled no)
				(sheetname "")
			)
			(fill
				(thermal_gap 0.5)
				(thermal_bridge_width 0.5)
				(island_removal_mode 0)
			)
			(polygon
				(pts
					(xy 417.641024 -141.097) (xy 418.149024 -141.097) (xy 418.149024 -141.478) (xy 417.641024 -141.478)
				)
			)
		)
	)
	(footprint ""
		(layer "B.Cu")
		(at 14.478 -87.63)
		(property "Reference" "R9P3"
			(at 0 0 0)
			(layer "B.SilkS")
			(hide yes)
			(effects
				(font
					(size 1.27 1.27)
				)
				(justify mirror)
			)
		)
		(property "Value" ""
			(at 0 0 0)
			(layer "B.Fab")
			(effects
				(font
					(size 1.27 1.27)
				)
				(justify mirror)
			)
		)
		(duplicate_pad_numbers_are_jumpers no)
		(fp_poly
			(pts
				(xy 0.2794 -0.1016) (xy -0.2794 -0.1016) (xy -0.2794 0.9906) (xy 0.2794 0.9906)
			)
			(stroke
				(width 0)
				(type default)
			)
			(fill no)
			(layer "B.CrtYd")
		)
		(fp_line
			(start -0.2794 -0.1016)
			(end 0.2794 -0.1016)
			(stroke
				(width 0.1)
				(type default)
			)
			(layer "B.Fab")
		)
		(fp_line
			(start -0.2794 0.9906)
			(end -0.2794 -0.1016)
			(stroke
				(width 0.1)
				(type default)
			)
			(layer "B.Fab")
		)
		(fp_line
			(start 0.2794 -0.1016)
			(end 0.2794 0.9906)
			(stroke
				(width 0.1)
				(type default)
			)
			(layer "B.Fab")
		)
		(fp_line
			(start 0.2794 0.9906)
			(end -0.2794 0.9906)
			(stroke
				(width 0.1)
				(type default)
			)
			(layer "B.Fab")
		)
		(pad "1" smd rect
			(at 0 0 180)
			(size 0.508 0.508)
			(layers "B.Cu" "B.Mask" "B.Paste")
			(net "IRQ_PVCCIN_CPU1_VRHOT_LVC3_R_N")
		)
		(pad "2" smd rect
			(at 0 0.889 180)
			(size 0.508 0.508)
			(layers "B.Cu" "B.Mask" "B.Paste")
			(net "IRQ_PVCCIN_CPU1_VRHOT_LVC3_N")
		)
		(zone
			(layer "B.Cu")
			(hatch none 0.5)
			(connect_pads
				(clearance 0)
			)
			(min_thickness 0.25)
			(keepout
				(tracks allowed)
				(vias not_allowed)
				(pads allowed)
				(copperpour not_allowed)
				(footprints allowed)
			)
			(placement
				(enabled no)
				(sheetname "")
			)
			(fill
				(thermal_gap 0.5)
				(thermal_bridge_width 0.5)
				(island_removal_mode 0)
			)
			(polygon
				(pts
					(xy 14.732 -87.376) (xy 14.224 -87.376) (xy 14.224 -86.995) (xy 14.732 -86.995)
				)
			)
		)
		(zone
			(layer "B.Cu")
			(hatch none 0.5)
			(connect_pads
				(clearance 0)
			)
			(min_thickness 0.25)
			(keepout
				(tracks not_allowed)
				(vias allowed)
				(pads allowed)
				(copperpour not_allowed)
				(footprints allowed)
			)
			(placement
				(enabled no)
				(sheetname "")
			)
			(fill
				(thermal_gap 0.5)
				(thermal_bridge_width 0.5)
				(island_removal_mode 0)
			)
			(polygon
				(pts
					(xy 14.732 -86.995) (xy 14.224 -86.995) (xy 14.224 -87.376) (xy 14.732 -87.376)
				)
			)
		)
	)
	(footprint ""
		(layer "B.Cu")
		(at 183.3626 -134.5438 90)
		(property "Reference" "C6M3"
			(at -1.47828 0.78994 180)
			(unlocked yes)
			(layer "B.SilkS")
			(effects
				(font
					(size 0.4064 0.254)
					(thickness 0.1524)
				)
				(justify mirror)
			)
		)
		(property "Value" ""
			(at 0 0 90)
			(layer "B.Fab")
			(effects
				(font
					(size 1.27 1.27)
				)
				(justify mirror)
			)
		)
		(duplicate_pad_numbers_are_jumpers no)
		(fp_poly
			(pts
				(xy 0.7239 -0.2159) (xy -0.7239 -0.2159) (xy -0.7239 1.9939) (xy 0.7239 1.9939)
			)
			(stroke
				(width 0)
				(type default)
			)
			(fill no)
			(layer "B.CrtYd")
		)
		(fp_line
			(start 0.7239 -0.2159)
			(end 0.7239 1.9939)
			(stroke
				(width 0.1)
				(type default)
			)
			(layer "B.Fab")
		)
		(fp_line
			(start -0.7239 -0.2159)
			(end 0.7239 -0.2159)
			(stroke
				(width 0.1)
				(type default)
			)
			(layer "B.Fab")
		)
		(fp_line
			(start 0.7239 1.9939)
			(end -0.7239 1.9939)
			(stroke
				(width 0.1)
				(type default)
			)
			(layer "B.Fab")
		)
		(fp_line
			(start -0.7239 1.9939)
			(end -0.7239 -0.2159)
			(stroke
				(width 0.1)
				(type default)
			)
			(layer "B.Fab")
		)
		(pad "1" smd rect
			(at 0 0 270)
			(size 1.27 1.016)
			(layers "B.Cu" "B.Mask" "B.Paste")
			(net "VR_FET_SW_P12V_STBY_PVPP_KLM")
		)
		(pad "2" smd rect
			(at 0 1.778 270)
			(size 1.27 1.016)
			(layers "B.Cu" "B.Mask" "B.Paste")
			(net "GND")
		)
		(zone
			(layer "B.Cu")
			(hatch none 0.5)
			(connect_pads
				(clearance 0)
			)
			(min_thickness 0.25)
			(keepout
				(tracks not_allowed)
				(vias allowed)
				(pads allowed)
				(copperpour not_allowed)
				(footprints allowed)
			)
			(placement
				(enabled no)
				(sheetname "")
			)
			(fill
				(thermal_gap 0.5)
				(thermal_bridge_width 0.5)
				(island_removal_mode 0)
			)
			(polygon
				(pts
					(xy 183.8706 -135.1788) (xy 183.8706 -133.9088) (xy 184.6326 -133.9088) (xy 184.6326 -135.1788)
				)
			)
		)
	)
	(footprint ""
		(layer "B.Cu")
		(at 374.777 -100.3046 90)
		(property "Reference" "R3N4"
			(at 0 0 90)
			(layer "B.SilkS")
			(hide yes)
			(effects
				(font
					(size 1.27 1.27)
				)
				(justify mirror)
			)
		)
		(property "Value" ""
			(at 0 0 90)
			(layer "B.Fab")
			(effects
				(font
					(size 1.27 1.27)
				)
				(justify mirror)
			)
		)
		(duplicate_pad_numbers_are_jumpers no)
		(fp_poly
			(pts
				(xy 0.2794 -0.1016) (xy -0.2794 -0.1016) (xy -0.2794 0.9906) (xy 0.2794 0.9906)
			)
			(stroke
				(width 0)
				(type default)
			)
			(fill no)
			(layer "B.CrtYd")
		)
		(fp_line
			(start 0.2794 -0.1016)
			(end 0.2794 0.9906)
			(stroke
				(width 0.1)
				(type default)
			)
			(layer "B.Fab")
		)
		(fp_line
			(start -0.2794 -0.1016)
			(end 0.2794 -0.1016)
			(stroke
				(width 0.1)
				(type default)
			)
			(layer "B.Fab")
		)
		(fp_line
			(start 0.2794 0.9906)
			(end -0.2794 0.9906)
			(stroke
				(width 0.1)
				(type default)
			)
			(layer "B.Fab")
		)
		(fp_line
			(start -0.2794 0.9906)
			(end -0.2794 -0.1016)
			(stroke
				(width 0.1)
				(type default)
			)
			(layer "B.Fab")
		)
		(pad "1" smd rect
			(at 0 0 270)
			(size 0.508 0.508)
			(layers "B.Cu" "B.Mask" "B.Paste")
			(net "P3V3_RTC_STBY")
		)
		(pad "2" smd rect
			(at 0 0.889 270)
			(size 0.508 0.508)
			(layers "B.Cu" "B.Mask" "B.Paste")
			(net "RST_SRTCRST_N")
		)
		(zone
			(layer "B.Cu")
			(hatch none 0.5)
			(connect_pads
				(clearance 0)
			)
			(min_thickness 0.25)
			(keepout
				(tracks allowed)
				(vias not_allowed)
				(pads allowed)
				(copperpour not_allowed)
				(footprints allowed)
			)
			(placement
				(enabled no)
				(sheetname "")
			)
			(fill
				(thermal_gap 0.5)
				(thermal_bridge_width 0.5)
				(island_removal_mode 0)
			)
			(polygon
				(pts
					(xy 375.031 -100.5586) (xy 375.031 -100.0506) (xy 375.412 -100.0506) (xy 375.412 -100.5586)
				)
			)
		)
		(zone
			(layer "B.Cu")
			(hatch none 0.5)
			(connect_pads
				(clearance 0)
			)
			(min_thickness 0.25)
			(keepout
				(tracks not_allowed)
				(vias allowed)
				(pads allowed)
				(copperpour not_allowed)
				(footprints allowed)
			)
			(placement
				(enabled no)
				(sheetname "")
			)
			(fill
				(thermal_gap 0.5)
				(thermal_bridge_width 0.5)
				(island_removal_mode 0)
			)
			(polygon
				(pts
					(xy 375.412 -100.5586) (xy 375.412 -100.0506) (xy 375.031 -100.0506) (xy 375.031 -100.5586)
				)
			)
		)
	)
	(footprint ""
		(layer "B.Cu")
		(at -2.5146 -128.6002 -90)
		(property "Reference" "R9M6"
			(at 0 0 90)
			(layer "B.SilkS")
			(hide yes)
			(effects
				(font
					(size 1.27 1.27)
				)
				(justify mirror)
			)
		)
		(property "Value" ""
			(at 0 0 90)
			(layer "B.Fab")
			(effects
				(font
					(size 1.27 1.27)
				)
				(justify mirror)
			)
		)
		(duplicate_pad_numbers_are_jumpers no)
		(fp_rect
			(start 0.2794 0.9906)
			(end -0.2794 -0.1016)
			(stroke
				(width 0)
				(type default)
			)
			(fill no)
			(layer "B.CrtYd")
		)
		(fp_line
			(start -0.2794 0.9906)
			(end -0.2794 -0.1016)
			(stroke
				(width 0.1)
				(type default)
			)
			(layer "B.Fab")
		)
		(fp_line
			(start 0.2794 0.9906)
			(end -0.2794 0.9906)
			(stroke
				(width 0.1)
				(type default)
			)
			(layer "B.Fab")
		)
		(fp_line
			(start -0.2794 -0.1016)
			(end 0.2794 -0.1016)
			(stroke
				(width 0.1)
				(type default)
			)
			(layer "B.Fab")
		)
		(fp_line
			(start 0.2794 -0.1016)
			(end 0.2794 0.9906)
			(stroke
				(width 0.1)
				(type default)
			)
			(layer "B.Fab")
		)
		(pad "1" smd rect
			(at 0 0 90)
			(size 0.508 0.508)
			(layers "B.Cu" "B.Mask" "B.Paste")
			(net "PVCCIO_CPU1")
		)
		(pad "2" smd rect
			(at 0 0.889 90)
			(size 0.508 0.508)
			(layers "B.Cu" "B.Mask" "B.Paste")
			(net "SVID_CLK1_CPU1_R")
		)
		(zone
			(layer "B.Cu")
			(hatch none 0.5)
			(connect_pads
				(clearance 0)
			)
			(min_thickness 0.25)
			(keepout
				(tracks not_allowed)
				(vias allowed)
				(pads allowed)
				(copperpour not_allowed)
				(footprints allowed)
			)
			(placement
				(enabled no)
				(sheetname "")
			)
			(fill
				(thermal_gap 0.5)
				(thermal_bridge_width 0.5)
				(island_removal_mode 0)
			)
			(polygon
				(pts
					(xy -3.1496 -128.3462) (xy -2.7686 -128.3462) (xy -2.7686 -128.8542) (xy -3.1496 -128.8542)
				)
			)
		)
		(zone
			(layer "B.Cu")
			(hatch none 0.5)
			(connect_pads
				(clearance 0)
			)
			(min_thickness 0.25)
			(keepout
				(tracks allowed)
				(vias not_allowed)
				(pads allowed)
				(copperpour not_allowed)
				(footprints allowed)
			)
			(placement
				(enabled no)
				(sheetname "")
			)
			(fill
				(thermal_gap 0.5)
				(thermal_bridge_width 0.5)
				(island_removal_mode 0)
			)
			(polygon
				(pts
					(xy -3.1496 -128.3462) (xy -2.7686 -128.3462) (xy -2.7686 -128.8542) (xy -3.1496 -128.8542)
				)
			)
		)
	)
	(footprint ""
		(layer "B.Cu")
		(at 494.75136 -126.5174 -90)
		(property "Reference" "U1M1"
			(at 0 0 90)
			(layer "B.SilkS")
			(hide yes)
			(effects
				(font
					(size 1.27 1.27)
				)
				(justify mirror)
			)
		)
		(property "Value" ""
			(at 0 0 90)
			(layer "B.Fab")
			(effects
				(font
					(size 1.27 1.27)
				)
				(justify mirror)
			)
		)
		(duplicate_pad_numbers_are_jumpers no)
		(fp_circle
			(center 0.813308 -0.4826)
			(end 0.813308 -0.6096)
			(stroke
				(width 0.254)
				(type default)
			)
			(fill no)
			(layer "B.SilkS")
		)
		(fp_poly
			(pts
				(xy -0.21463 -0.450088) (xy -1.56337 -0.450088) (xy -1.56337 1.75006) (xy -0.21463 1.75006)
			)
			(stroke
				(width 0)
				(type default)
			)
			(fill no)
			(layer "B.CrtYd")
		)
		(fp_line
			(start -1.56337 1.75006)
			(end -0.21463 1.75006)
			(stroke
				(width 0.1)
				(type default)
			)
			(layer "B.Fab")
		)
		(fp_line
			(start -0.21463 1.75006)
			(end -0.21463 -0.450088)
			(stroke
				(width 0.1)
				(type default)
			)
			(layer "B.Fab")
		)
		(fp_line
			(start -1.56337 -0.450088)
			(end -1.56337 1.75006)
			(stroke
				(width 0.1)
				(type default)
			)
			(layer "B.Fab")
		)
		(fp_line
			(start -0.21463 -0.450088)
			(end -1.56337 -0.450088)
			(stroke
				(width 0.1)
				(type default)
			)
			(layer "B.Fab")
		)
		(fp_circle
			(center -0.544322 -0.583946)
			(end -0.544322 -0.710946)
			(stroke
				(width 0.254)
				(type default)
			)
			(fill no)
			(layer "B.Fab")
		)
		(pad "1" smd rect
			(at 0 0 90)
			(size 1.016 0.381)
			(layers "B.Cu" "B.Mask" "B.Paste")
			(net "LED_SATA_ACT_R_N")
		)
		(pad "2" smd rect
			(at 0 0.649986 90)
			(size 1.016 0.381)
			(layers "B.Cu" "B.Mask" "B.Paste")
			(net "LED_SAS_ACT_R_N")
		)
		(pad "3" smd rect
			(at 0 1.299972 90)
			(size 1.016 0.381)
			(layers "B.Cu" "B.Mask" "B.Paste")
			(net "GND")
		)
		(pad "4" smd rect
			(at -1.778 1.299972 90)
			(size 1.016 0.381)
			(layers "B.Cu" "B.Mask" "B.Paste")
			(net "FP_LED_HDD_ACTIVITY_AND_N")
		)
		(pad "5" smd rect
			(at -1.778 0 90)
			(size 1.016 0.381)
			(layers "B.Cu" "B.Mask" "B.Paste")
			(net "P3V3")
		)
	)
	(footprint ""
		(layer "B.Cu")
		(at 93.548454 -77.82814)
		(property "Reference" "C8P21"
			(at 0 0 0)
			(layer "B.SilkS")
			(hide yes)
			(effects
				(font
					(size 1.27 1.27)
				)
				(justify mirror)
			)
		)
		(property "Value" ""
			(at 0 0 0)
			(layer "B.Fab")
			(effects
				(font
					(size 1.27 1.27)
				)
				(justify mirror)
			)
		)
		(duplicate_pad_numbers_are_jumpers no)
		(fp_poly
			(pts
				(xy 0.7239 -0.2159) (xy -0.7239 -0.2159) (xy -0.7239 1.9939) (xy 0.7239 1.9939)
			)
			(stroke
				(width 0)
				(type default)
			)
			(fill no)
			(layer "B.CrtYd")
		)
		(fp_line
			(start -0.7239 -0.2159)
			(end 0.7239 -0.2159)
			(stroke
				(width 0.1)
				(type default)
			)
			(layer "B.Fab")
		)
		(fp_line
			(start -0.7239 1.9939)
			(end -0.7239 -0.2159)
			(stroke
				(width 0.1)
				(type default)
			)
			(layer "B.Fab")
		)
		(fp_line
			(start 0.7239 -0.2159)
			(end 0.7239 1.9939)
			(stroke
				(width 0.1)
				(type default)
			)
			(layer "B.Fab")
		)
		(fp_line
			(start 0.7239 1.9939)
			(end -0.7239 1.9939)
			(stroke
				(width 0.1)
				(type default)
			)
			(layer "B.Fab")
		)
		(pad "1" smd rect
			(at 0 0 180)
			(size 1.27 1.016)
			(layers "B.Cu" "B.Mask" "B.Paste")
			(net "PVCCIN_CPU1")
		)
		(pad "2" smd rect
			(at 0 1.778 180)
			(size 1.27 1.016)
			(layers "B.Cu" "B.Mask" "B.Paste")
			(net "GND")
		)
		(zone
			(layer "B.Cu")
			(hatch none 0.5)
			(connect_pads
				(clearance 0)
			)
			(min_thickness 0.25)
			(keepout
				(tracks not_allowed)
				(vias allowed)
				(pads allowed)
				(copperpour not_allowed)
				(footprints allowed)
			)
			(placement
				(enabled no)
				(sheetname "")
			)
			(fill
				(thermal_gap 0.5)
				(thermal_bridge_width 0.5)
				(island_removal_mode 0)
			)
			(polygon
				(pts
					(xy 94.183454 -77.32014) (xy 92.913454 -77.32014) (xy 92.913454 -76.55814) (xy 94.183454 -76.55814)
				)
			)
		)
	)
	(footprint ""
		(layer "B.Cu")
		(at 267.692886 -77.82814)
		(property "Reference" "C5P22"
			(at 0 0 0)
			(layer "B.SilkS")
			(hide yes)
			(effects
				(font
					(size 1.27 1.27)
				)
				(justify mirror)
			)
		)
		(property "Value" ""
			(at 0 0 0)
			(layer "B.Fab")
			(effects
				(font
					(size 1.27 1.27)
				)
				(justify mirror)
			)
		)
		(duplicate_pad_numbers_are_jumpers no)
		(fp_poly
			(pts
				(xy 0.7239 -0.2159) (xy -0.7239 -0.2159) (xy -0.7239 1.9939) (xy 0.7239 1.9939)
			)
			(stroke
				(width 0)
				(type default)
			)
			(fill no)
			(layer "B.CrtYd")
		)
		(fp_line
			(start -0.7239 -0.2159)
			(end 0.7239 -0.2159)
			(stroke
				(width 0.1)
				(type default)
			)
			(layer "B.Fab")
		)
		(fp_line
			(start -0.7239 1.9939)
			(end -0.7239 -0.2159)
			(stroke
				(width 0.1)
				(type default)
			)
			(layer "B.Fab")
		)
		(fp_line
			(start 0.7239 -0.2159)
			(end 0.7239 1.9939)
			(stroke
				(width 0.1)
				(type default)
			)
			(layer "B.Fab")
		)
		(fp_line
			(start 0.7239 1.9939)
			(end -0.7239 1.9939)
			(stroke
				(width 0.1)
				(type default)
			)
			(layer "B.Fab")
		)
		(pad "1" smd rect
			(at 0 0 180)
			(size 1.27 1.016)
			(layers "B.Cu" "B.Mask" "B.Paste")
			(net "PVCCIN_CPU0")
		)
		(pad "2" smd rect
			(at 0 1.778 180)
			(size 1.27 1.016)
			(layers "B.Cu" "B.Mask" "B.Paste")
			(net "GND")
		)
		(zone
			(layer "B.Cu")
			(hatch none 0.5)
			(connect_pads
				(clearance 0)
			)
			(min_thickness 0.25)
			(keepout
				(tracks not_allowed)
				(vias allowed)
				(pads allowed)
				(copperpour not_allowed)
				(footprints allowed)
			)
			(placement
				(enabled no)
				(sheetname "")
			)
			(fill
				(thermal_gap 0.5)
				(thermal_bridge_width 0.5)
				(island_removal_mode 0)
			)
			(polygon
				(pts
					(xy 268.327886 -77.32014) (xy 267.057886 -77.32014) (xy 267.057886 -76.55814) (xy 268.327886 -76.55814)
				)
			)
		)
	)
	(footprint ""
		(layer "B.Cu")
		(at 387.689598 -34.655506 -90)
		(property "Reference" "R7W6"
			(at 0.8382 -0.67818 270)
			(unlocked yes)
			(layer "B.SilkS")
			(effects
				(font
					(size 0.4064 0.254)
					(thickness 0.1524)
				)
				(justify left mirror)
			)
		)
		(property "Value" ""
			(at 0 0 90)
			(layer "B.Fab")
			(effects
				(font
					(size 1.27 1.27)
				)
				(justify mirror)
			)
		)
		(duplicate_pad_numbers_are_jumpers no)
		(fp_poly
			(pts
				(xy 0.2794 -0.1016) (xy -0.2794 -0.1016) (xy -0.2794 0.9906) (xy 0.2794 0.9906)
			)
			(stroke
				(width 0)
				(type default)
			)
			(fill no)
			(layer "B.CrtYd")
		)
		(fp_line
			(start -0.2794 0.9906)
			(end -0.2794 -0.1016)
			(stroke
				(width 0.1)
				(type default)
			)
			(layer "B.Fab")
		)
		(fp_line
			(start 0.2794 0.9906)
			(end -0.2794 0.9906)
			(stroke
				(width 0.1)
				(type default)
			)
			(layer "B.Fab")
		)
		(fp_line
			(start -0.2794 -0.1016)
			(end 0.2794 -0.1016)
			(stroke
				(width 0.1)
				(type default)
			)
			(layer "B.Fab")
		)
		(fp_line
			(start 0.2794 -0.1016)
			(end 0.2794 0.9906)
			(stroke
				(width 0.1)
				(type default)
			)
			(layer "B.Fab")
		)
		(pad "1" smd rect
			(at 0 0 90)
			(size 0.508 0.508)
			(layers "B.Cu" "B.Mask" "B.Paste")
			(net "FM_BATTERY_SENSE_EN_N")
		)
		(pad "2" smd rect
			(at 0 0.889 90)
			(size 0.508 0.508)
			(layers "B.Cu" "B.Mask" "B.Paste")
			(net "FM_BATTERY_SENSE_EN_R_N")
		)
		(zone
			(layer "B.Cu")
			(hatch none 0.5)
			(connect_pads
				(clearance 0)
			)
			(min_thickness 0.25)
			(keepout
				(tracks not_allowed)
				(vias allowed)
				(pads allowed)
				(copperpour not_allowed)
				(footprints allowed)
			)
			(placement
				(enabled no)
				(sheetname "")
			)
			(fill
				(thermal_gap 0.5)
				(thermal_bridge_width 0.5)
				(island_removal_mode 0)
			)
			(polygon
				(pts
					(xy 387.054598 -34.401506) (xy 387.054598 -34.909506) (xy 387.435598 -34.909506) (xy 387.435598 -34.401506)
				)
			)
		)
		(zone
			(layer "B.Cu")
			(hatch none 0.5)
			(connect_pads
				(clearance 0)
			)
			(min_thickness 0.25)
			(keepout
				(tracks allowed)
				(vias not_allowed)
				(pads allowed)
				(copperpour not_allowed)
				(footprints allowed)
			)
			(placement
				(enabled no)
				(sheetname "")
			)
			(fill
				(thermal_gap 0.5)
				(thermal_bridge_width 0.5)
				(island_removal_mode 0)
			)
			(polygon
				(pts
					(xy 387.435598 -34.401506) (xy 387.435598 -34.909506) (xy 387.054598 -34.909506) (xy 387.054598 -34.401506)
				)
			)
		)
	)
	(footprint ""
		(layer "B.Cu")
		(at 248.8565 -149.8092 -90)
		(property "Reference" "C5G60"
			(at -1.14681 0.76708 0)
			(unlocked yes)
			(layer "B.SilkS")
			(effects
				(font
					(size 0.7874 0.5842)
					(thickness 0.1524)
				)
				(justify mirror)
			)
		)
		(property "Value" ""
			(at 0 0 90)
			(layer "B.Fab")
			(effects
				(font
					(size 1.27 1.27)
				)
				(justify mirror)
			)
		)
		(duplicate_pad_numbers_are_jumpers no)
		(fp_rect
			(start 0.4953 1.6002)
			(end -0.4953 -0.2032)
			(stroke
				(width 0)
				(type default)
			)
			(fill no)
			(layer "B.CrtYd")
		)
		(fp_line
			(start -0.4953 1.6002)
			(end 0.4953 1.6002)
			(stroke
				(width 0.1)
				(type default)
			)
			(layer "B.Fab")
		)
		(fp_line
			(start 0.4953 1.6002)
			(end 0.4953 -0.2032)
			(stroke
				(width 0.1)
				(type default)
			)
			(layer "B.Fab")
		)
		(fp_line
			(start -0.4953 -0.2032)
			(end -0.4953 1.6002)
			(stroke
				(width 0.1)
				(type default)
			)
			(layer "B.Fab")
		)
		(fp_line
			(start 0.4953 -0.2032)
			(end -0.4953 -0.2032)
			(stroke
				(width 0.1)
				(type default)
			)
			(layer "B.Fab")
		)
		(pad "1" smd rect
			(at 0 0 90)
			(size 0.762 0.889)
			(layers "B.Cu" "B.Mask" "B.Paste")
			(net "PVDDQ_DEF")
		)
		(pad "2" smd rect
			(at 0 1.397 90)
			(size 0.762 0.889)
			(layers "B.Cu" "B.Mask" "B.Paste")
			(net "GND")
		)
		(zone
			(layer "B.Cu")
			(hatch none 0.5)
			(connect_pads
				(clearance 0)
			)
			(min_thickness 0.25)
			(keepout
				(tracks not_allowed)
				(vias allowed)
				(pads allowed)
				(copperpour not_allowed)
				(footprints allowed)
			)
			(placement
				(enabled no)
				(sheetname "")
			)
			(fill
				(thermal_gap 0.5)
				(thermal_bridge_width 0.5)
				(island_removal_mode 0)
			)
			(polygon
				(pts
					(xy 247.904 -149.4282) (xy 248.412 -149.4282) (xy 248.412 -150.1902) (xy 247.904 -150.1902)
				)
			)
		)
	)
	(footprint ""
		(layer "B.Cu")
		(at 389.509 -104.4702 -90)
		(property "Reference" "C2N20"
			(at 0 0 90)
			(layer "B.SilkS")
			(hide yes)
			(effects
				(font
					(size 1.27 1.27)
				)
				(justify mirror)
			)
		)
		(property "Value" ""
			(at 0 0 90)
			(layer "B.Fab")
			(effects
				(font
					(size 1.27 1.27)
				)
				(justify mirror)
			)
		)
		(duplicate_pad_numbers_are_jumpers no)
		(fp_rect
			(start 0.2794 0.9144)
			(end -0.2794 -0.1143)
			(stroke
				(width 0)
				(type default)
			)
			(fill no)
			(layer "B.CrtYd")
		)
		(fp_line
			(start -0.2794 0.9144)
			(end 0.2794 0.9144)
			(stroke
				(width 0.1)
				(type default)
			)
			(layer "B.Fab")
		)
		(fp_line
			(start 0.2794 0.9144)
			(end 0.2794 -0.1143)
			(stroke
				(width 0.1)
				(type default)
			)
			(layer "B.Fab")
		)
		(fp_line
			(start -0.2794 -0.1143)
			(end -0.2794 0.9144)
			(stroke
				(width 0.1)
				(type default)
			)
			(layer "B.Fab")
		)
		(fp_line
			(start 0.2794 -0.1143)
			(end -0.2794 -0.1143)
			(stroke
				(width 0.1)
				(type default)
			)
			(layer "B.Fab")
		)
		(pad "1" smd custom
			(at 0 0 180)
			(size 0.10414 0.10414)
			(layers "B.Cu" "B.Mask" "B.Paste")
			(net "P3V3_STBY")
			(options
				(clearance outline)
				(anchor circle)
			)
			(primitives
				(gr_poly
					(pts
						(xy -0.20828 -0.08636) (xy -0.20828 0.08636) (xy -0.08636 0.20828) (xy 0.086614 0.20828) (xy 0.20828 0.086614)
						(xy 0.20828 -0.08636) (xy 0.08636 -0.20828) (xy -0.08636 -0.20828)
					)
					(width 0)
					(fill yes)
				)
			)
		)
		(pad "2" smd custom
			(at 0 0.8001 180)
			(size 0.10414 0.10414)
			(layers "B.Cu" "B.Mask" "B.Paste")
			(net "GND")
			(options
				(clearance outline)
				(anchor circle)
			)
			(primitives
				(gr_poly
					(pts
						(xy -0.20828 -0.08636) (xy -0.20828 0.08636) (xy -0.08636 0.20828) (xy 0.086614 0.20828) (xy 0.20828 0.086614)
						(xy 0.20828 -0.08636) (xy 0.08636 -0.20828) (xy -0.08636 -0.20828)
					)
					(width 0)
					(fill yes)
				)
			)
		)
		(zone
			(layer "B.Cu")
			(hatch none 0.5)
			(connect_pads
				(clearance 0)
			)
			(min_thickness 0.25)
			(keepout
				(tracks allowed)
				(vias not_allowed)
				(pads allowed)
				(copperpour not_allowed)
				(footprints allowed)
			)
			(placement
				(enabled no)
				(sheetname "")
			)
			(fill
				(thermal_gap 0.5)
				(thermal_bridge_width 0.5)
				(island_removal_mode 0)
			)
			(polygon
				(pts
					(xy 389.29945 -104.38257) (xy 388.91845 -104.38257) (xy 388.91845 -104.55783) (xy 389.29945 -104.558084)
				)
			)
		)
		(zone
			(layer "B.Cu")
			(hatch none 0.5)
			(connect_pads
				(clearance 0)
			)
			(min_thickness 0.25)
			(keepout
				(tracks not_allowed)
				(vias allowed)
				(pads allowed)
				(copperpour not_allowed)
				(footprints allowed)
			)
			(placement
				(enabled no)
				(sheetname "")
			)
			(fill
				(thermal_gap 0.5)
				(thermal_bridge_width 0.5)
				(island_removal_mode 0)
			)
			(polygon
				(pts
					(xy 389.29945 -104.38257) (xy 388.91845 -104.38257) (xy 388.91845 -104.55783) (xy 389.29945 -104.558084)
				)
			)
		)
	)
	(footprint ""
		(layer "B.Cu")
		(at 94.292928 -144.987772 90)
		(property "Reference" "C8L11"
			(at 0 0 90)
			(layer "B.SilkS")
			(hide yes)
			(effects
				(font
					(size 1.27 1.27)
				)
				(justify mirror)
			)
		)
		(property "Value" ""
			(at 0 0 90)
			(layer "B.Fab")
			(effects
				(font
					(size 1.27 1.27)
				)
				(justify mirror)
			)
		)
		(duplicate_pad_numbers_are_jumpers no)
		(fp_poly
			(pts
				(xy 0.7239 -0.2159) (xy -0.7239 -0.2159) (xy -0.7239 1.9939) (xy 0.7239 1.9939)
			)
			(stroke
				(width 0)
				(type default)
			)
			(fill no)
			(layer "B.CrtYd")
		)
		(fp_line
			(start 0.7239 -0.2159)
			(end 0.7239 1.9939)
			(stroke
				(width 0.1)
				(type default)
			)
			(layer "B.Fab")
		)
		(fp_line
			(start -0.7239 -0.2159)
			(end 0.7239 -0.2159)
			(stroke
				(width 0.1)
				(type default)
			)
			(layer "B.Fab")
		)
		(fp_line
			(start 0.7239 1.9939)
			(end -0.7239 1.9939)
			(stroke
				(width 0.1)
				(type default)
			)
			(layer "B.Fab")
		)
		(fp_line
			(start -0.7239 1.9939)
			(end -0.7239 -0.2159)
			(stroke
				(width 0.1)
				(type default)
			)
			(layer "B.Fab")
		)
		(pad "1" smd rect
			(at 0 0 270)
			(size 1.27 1.016)
			(layers "B.Cu" "B.Mask" "B.Paste")
			(net "PVDDQ_KLM")
		)
		(pad "2" smd rect
			(at 0 1.778 270)
			(size 1.27 1.016)
			(layers "B.Cu" "B.Mask" "B.Paste")
			(net "GND")
		)
		(zone
			(layer "B.Cu")
			(hatch none 0.5)
			(connect_pads
				(clearance 0)
			)
			(min_thickness 0.25)
			(keepout
				(tracks not_allowed)
				(vias allowed)
				(pads allowed)
				(copperpour not_allowed)
				(footprints allowed)
			)
			(placement
				(enabled no)
				(sheetname "")
			)
			(fill
				(thermal_gap 0.5)
				(thermal_bridge_width 0.5)
				(island_removal_mode 0)
			)
			(polygon
				(pts
					(xy 94.800928 -145.622772) (xy 94.800928 -144.352772) (xy 95.562928 -144.352772) (xy 95.562928 -145.622772)
				)
			)
		)
	)
	(footprint ""
		(layer "B.Cu")
		(at 353.654614 -122.662442 -90)
		(property "Reference" "R777"
			(at 0.8382 -0.67818 270)
			(unlocked yes)
			(layer "B.SilkS")
			(effects
				(font
					(size 0.4064 0.254)
					(thickness 0.1524)
				)
				(justify left mirror)
			)
		)
		(property "Value" ""
			(at 0 0 90)
			(layer "B.Fab")
			(effects
				(font
					(size 1.27 1.27)
				)
				(justify mirror)
			)
		)
		(duplicate_pad_numbers_are_jumpers no)
		(fp_poly
			(pts
				(xy 0.2794 -0.1016) (xy -0.2794 -0.1016) (xy -0.2794 0.9906) (xy 0.2794 0.9906)
			)
			(stroke
				(width 0)
				(type default)
			)
			(fill no)
			(layer "B.CrtYd")
		)
		(fp_line
			(start -0.2794 0.9906)
			(end -0.2794 -0.1016)
			(stroke
				(width 0.1)
				(type default)
			)
			(layer "B.Fab")
		)
		(fp_line
			(start 0.2794 0.9906)
			(end -0.2794 0.9906)
			(stroke
				(width 0.1)
				(type default)
			)
			(layer "B.Fab")
		)
		(fp_line
			(start -0.2794 -0.1016)
			(end 0.2794 -0.1016)
			(stroke
				(width 0.1)
				(type default)
			)
			(layer "B.Fab")
		)
		(fp_line
			(start 0.2794 -0.1016)
			(end 0.2794 0.9906)
			(stroke
				(width 0.1)
				(type default)
			)
			(layer "B.Fab")
		)
		(pad "1" smd rect
			(at 0 0 90)
			(size 0.508 0.508)
			(layers "B.Cu" "B.Mask" "B.Paste")
			(net "P3E_CPU0_PE1_PCH_RXP<12>")
		)
		(pad "2" smd rect
			(at 0 0.889 90)
			(size 0.508 0.508)
			(layers "B.Cu" "B.Mask" "B.Paste")
			(net "P3E_CPU0_PE1_PCH_CON_RXP<12>")
		)
		(zone
			(layer "B.Cu")
			(hatch none 0.5)
			(connect_pads
				(clearance 0)
			)
			(min_thickness 0.25)
			(keepout
				(tracks not_allowed)
				(vias allowed)
				(pads allowed)
				(copperpour not_allowed)
				(footprints allowed)
			)
			(placement
				(enabled no)
				(sheetname "")
			)
			(fill
				(thermal_gap 0.5)
				(thermal_bridge_width 0.5)
				(island_removal_mode 0)
			)
			(polygon
				(pts
					(xy 353.019614 -122.408442) (xy 353.019614 -122.916442) (xy 353.400614 -122.916442) (xy 353.400614 -122.408442)
				)
			)
		)
		(zone
			(layer "B.Cu")
			(hatch none 0.5)
			(connect_pads
				(clearance 0)
			)
			(min_thickness 0.25)
			(keepout
				(tracks allowed)
				(vias not_allowed)
				(pads allowed)
				(copperpour not_allowed)
				(footprints allowed)
			)
			(placement
				(enabled no)
				(sheetname "")
			)
			(fill
				(thermal_gap 0.5)
				(thermal_bridge_width 0.5)
				(island_removal_mode 0)
			)
			(polygon
				(pts
					(xy 353.400614 -122.408442) (xy 353.400614 -122.916442) (xy 353.019614 -122.916442) (xy 353.019614 -122.408442)
				)
			)
		)
	)
	(footprint ""
		(layer "B.Cu")
		(at 45.212 -57.023 -90)
		(property "Reference" "C9R9"
			(at 0.15367 -3.556 0)
			(unlocked yes)
			(layer "B.SilkS")
			(effects
				(font
					(size 0.7874 0.5842)
					(thickness 0.1524)
				)
				(justify mirror)
			)
		)
		(property "Value" ""
			(at 0 0 90)
			(layer "B.Fab")
			(effects
				(font
					(size 1.27 1.27)
				)
				(justify mirror)
			)
		)
		(duplicate_pad_numbers_are_jumpers no)
		(fp_line
			(start -2.286 7.366)
			(end -1.600708 7.366)
			(stroke
				(width 0.1524)
				(type default)
			)
			(layer "B.SilkS")
		)
		(fp_line
			(start -2.286 7.366)
			(end -2.286 1.63195)
			(stroke
				(width 0.1524)
				(type default)
			)
			(layer "B.SilkS")
		)
		(fp_line
			(start 2.286 7.366)
			(end 1.60147 7.366)
			(stroke
				(width 0.1524)
				(type default)
			)
			(layer "B.SilkS")
		)
		(fp_line
			(start 2.286 7.366)
			(end 2.286 1.632712)
			(stroke
				(width 0.1524)
				(type default)
			)
			(layer "B.SilkS")
		)
		(fp_line
			(start -2.504948 1.633728)
			(end -1.6002 1.633728)
			(stroke
				(width 0.1524)
				(type default)
			)
			(layer "B.SilkS")
		)
		(fp_line
			(start 2.563114 1.633728)
			(end 1.6002 1.633728)
			(stroke
				(width 0.1524)
				(type default)
			)
			(layer "B.SilkS")
		)
		(fp_line
			(start -2.504948 -1.616456)
			(end -2.504948 1.633728)
			(stroke
				(width 0.1524)
				(type default)
			)
			(layer "B.SilkS")
		)
		(fp_line
			(start -1.6002 -1.616456)
			(end -2.504948 -1.616456)
			(stroke
				(width 0.1524)
				(type default)
			)
			(layer "B.SilkS")
		)
		(fp_line
			(start 1.6002 -1.616456)
			(end 2.563114 -1.616456)
			(stroke
				(width 0.1524)
				(type default)
			)
			(layer "B.SilkS")
		)
		(fp_line
			(start 2.563114 -1.616456)
			(end 2.563114 1.633728)
			(stroke
				(width 0.1524)
				(type default)
			)
			(layer "B.SilkS")
		)
		(fp_rect
			(start 2.286 7.366)
			(end -2.286 -0.254)
			(stroke
				(width 0)
				(type default)
			)
			(fill no)
			(layer "B.CrtYd")
		)
		(fp_line
			(start -2.286 7.366)
			(end 2.286 7.366)
			(stroke
				(width 0.1)
				(type default)
			)
			(layer "B.Fab")
		)
		(fp_line
			(start 2.286 7.366)
			(end 2.286 -0.254)
			(stroke
				(width 0.1)
				(type default)
			)
			(layer "B.Fab")
		)
		(fp_line
			(start -2.286 -0.254)
			(end -2.286 7.366)
			(stroke
				(width 0.1)
				(type default)
			)
			(layer "B.Fab")
		)
		(fp_line
			(start 2.286 -0.254)
			(end -2.286 -0.254)
			(stroke
				(width 0.1)
				(type default)
			)
			(layer "B.Fab")
		)
		(pad "1" smd rect
			(at 0 0 90)
			(size 2.54 3.048)
			(layers "B.Cu" "B.Mask" "B.Paste")
			(net "PVCCIN_CPU1")
		)
		(pad "2" smd rect
			(at 0 7.112 90)
			(size 2.54 3.048)
			(layers "B.Cu" "B.Mask" "B.Paste")
			(net "GND")
		)
	)
	(footprint ""
		(layer "B.Cu")
		(at 169.6466 -142.8242 90)
		(property "Reference" "C6L8"
			(at -3.15087 3.4544 0)
			(unlocked yes)
			(layer "B.SilkS")
			(effects
				(font
					(size 0.7874 0.5842)
					(thickness 0.1524)
				)
				(justify left mirror)
			)
		)
		(property "Value" ""
			(at 0 0 90)
			(layer "B.Fab")
			(effects
				(font
					(size 1.27 1.27)
				)
				(justify mirror)
			)
		)
		(duplicate_pad_numbers_are_jumpers no)
		(fp_line
			(start 2.032 -1.524)
			(end 2.032 1.524)
			(stroke
				(width 0.1524)
				(type default)
			)
			(layer "B.SilkS")
		)
		(fp_line
			(start 1.7272 -1.524)
			(end 2.032 -1.524)
			(stroke
				(width 0.1524)
				(type default)
			)
			(layer "B.SilkS")
		)
		(fp_line
			(start -1.7272 -1.524)
			(end -2.032 -1.524)
			(stroke
				(width 0.1524)
				(type default)
			)
			(layer "B.SilkS")
		)
		(fp_line
			(start -2.032 -1.524)
			(end -2.032 1.524)
			(stroke
				(width 0.1524)
				(type default)
			)
			(layer "B.SilkS")
		)
		(fp_line
			(start 2.2987 -0.2413)
			(end 2.2987 7.3533)
			(stroke
				(width 0.1524)
				(type default)
			)
			(layer "B.SilkS")
		)
		(fp_line
			(start 2.032 -0.2413)
			(end 2.2987 -0.2413)
			(stroke
				(width 0.1524)
				(type default)
			)
			(layer "B.SilkS")
		)
		(fp_line
			(start -2.2987 -0.2413)
			(end -2.032 -0.2413)
			(stroke
				(width 0.1524)
				(type default)
			)
			(layer "B.SilkS")
		)
		(fp_line
			(start 2.032 1.524)
			(end 1.7272 1.524)
			(stroke
				(width 0.1524)
				(type default)
			)
			(layer "B.SilkS")
		)
		(fp_line
			(start -2.032 1.524)
			(end -1.7272 1.524)
			(stroke
				(width 0.1524)
				(type default)
			)
			(layer "B.SilkS")
		)
		(fp_line
			(start 2.2987 7.3533)
			(end 1.7272 7.3533)
			(stroke
				(width 0.1524)
				(type default)
			)
			(layer "B.SilkS")
		)
		(fp_line
			(start -1.7272 7.3533)
			(end -2.2987 7.3533)
			(stroke
				(width 0.1524)
				(type default)
			)
			(layer "B.SilkS")
		)
		(fp_line
			(start -2.2987 7.3533)
			(end -2.2987 -0.2413)
			(stroke
				(width 0.1524)
				(type default)
			)
			(layer "B.SilkS")
		)
		(fp_poly
			(pts
				(xy 2.2987 -0.2413) (xy -2.2987 -0.2413) (xy -2.2987 7.3533) (xy 2.2987 7.3533)
			)
			(stroke
				(width 0)
				(type default)
			)
			(fill no)
			(layer "B.CrtYd")
		)
		(fp_line
			(start 2.2987 -0.2413)
			(end -2.2987 -0.2413)
			(stroke
				(width 0.1)
				(type default)
			)
			(layer "B.Fab")
		)
		(fp_line
			(start -2.2987 -0.2413)
			(end -2.2987 7.3533)
			(stroke
				(width 0.1)
				(type default)
			)
			(layer "B.Fab")
		)
		(fp_line
			(start 2.2987 7.3533)
			(end 2.2987 -0.2413)
			(stroke
				(width 0.1)
				(type default)
			)
			(layer "B.Fab")
		)
		(fp_line
			(start -2.2987 7.3533)
			(end 2.2987 7.3533)
			(stroke
				(width 0.1)
				(type default)
			)
			(layer "B.Fab")
		)
		(pad "1" smd rect
			(at 0 0 270)
			(size 2.54 3.048)
			(layers "B.Cu" "B.Mask" "B.Paste")
			(net "PVPP_KLM")
		)
		(pad "2" smd rect
			(at 0 7.112 270)
			(size 2.54 3.048)
			(layers "B.Cu" "B.Mask" "B.Paste")
			(net "GND")
		)
	)
	(footprint ""
		(layer "B.Cu")
		(at 420.503604 -75.048872 180)
		(property "Reference" "U1R1"
			(at -1.24333 2.032 270)
			(unlocked yes)
			(layer "B.SilkS")
			(effects
				(font
					(size 0.7874 0.5842)
					(thickness 0.1524)
				)
				(justify left mirror)
			)
		)
		(property "Value" ""
			(at 0 0 0)
			(layer "B.Fab")
			(effects
				(font
					(size 1.27 1.27)
				)
				(justify mirror)
			)
		)
		(duplicate_pad_numbers_are_jumpers no)
		(fp_circle
			(center 0.351536 -0.648462)
			(end 0.224536 -0.648462)
			(stroke
				(width 0.254)
				(type default)
			)
			(fill no)
			(layer "B.SilkS")
		)
		(fp_poly
			(pts
				(xy -0.21463 -0.450088) (xy -1.56337 -0.450088) (xy -1.56337 1.75006) (xy -0.21463 1.75006)
			)
			(stroke
				(width 0)
				(type default)
			)
			(fill no)
			(layer "B.CrtYd")
		)
		(fp_line
			(start -0.21463 1.75006)
			(end -0.21463 -0.450088)
			(stroke
				(width 0.1)
				(type default)
			)
			(layer "B.Fab")
		)
		(fp_line
			(start -0.21463 -0.450088)
			(end -1.56337 -0.450088)
			(stroke
				(width 0.1)
				(type default)
			)
			(layer "B.Fab")
		)
		(fp_line
			(start -1.56337 1.75006)
			(end -0.21463 1.75006)
			(stroke
				(width 0.1)
				(type default)
			)
			(layer "B.Fab")
		)
		(fp_line
			(start -1.56337 -0.450088)
			(end -1.56337 1.75006)
			(stroke
				(width 0.1)
				(type default)
			)
			(layer "B.Fab")
		)
		(fp_circle
			(center 0.4699 -0.8382)
			(end 0.3429 -0.8382)
			(stroke
				(width 0.254)
				(type default)
			)
			(fill no)
			(layer "B.Fab")
		)
		(pad "1" smd rect
			(at 0 0)
			(size 1.016 0.381)
			(layers "B.Cu" "B.Mask" "B.Paste")
			(net "Net_6472")
		)
		(pad "2" smd rect
			(at 0 0.649986)
			(size 1.016 0.381)
			(layers "B.Cu" "B.Mask" "B.Paste")
			(net "FM_FAST_PROCHOT_THROTTLE_DLY_BU")
		)
		(pad "3" smd rect
			(at 0 1.299972)
			(size 1.016 0.381)
			(layers "B.Cu" "B.Mask" "B.Paste")
			(net "GND")
		)
		(pad "4" smd rect
			(at -1.778 1.299972)
			(size 1.016 0.381)
			(layers "B.Cu" "B.Mask" "B.Paste")
			(net "FM_THROTTLE_R1_N")
		)
		(pad "5" smd rect
			(at -1.778 0)
			(size 1.016 0.381)
			(layers "B.Cu" "B.Mask" "B.Paste")
			(net "P3V3_STBY")
		)
	)
	(footprint ""
		(layer "B.Cu")
		(at 80.391 -64.262 -90)
		(property "Reference" "R8R1"
			(at 0 0 90)
			(layer "B.SilkS")
			(hide yes)
			(effects
				(font
					(size 1.27 1.27)
				)
				(justify mirror)
			)
		)
		(property "Value" ""
			(at 0 0 90)
			(layer "B.Fab")
			(effects
				(font
					(size 1.27 1.27)
				)
				(justify mirror)
			)
		)
		(duplicate_pad_numbers_are_jumpers no)
		(fp_poly
			(pts
				(xy 0.2794 -0.1016) (xy -0.2794 -0.1016) (xy -0.2794 0.9906) (xy 0.2794 0.9906)
			)
			(stroke
				(width 0)
				(type default)
			)
			(fill no)
			(layer "B.CrtYd")
		)
		(fp_line
			(start -0.2794 0.9906)
			(end -0.2794 -0.1016)
			(stroke
				(width 0.1)
				(type default)
			)
			(layer "B.Fab")
		)
		(fp_line
			(start 0.2794 0.9906)
			(end -0.2794 0.9906)
			(stroke
				(width 0.1)
				(type default)
			)
			(layer "B.Fab")
		)
		(fp_line
			(start -0.2794 -0.1016)
			(end 0.2794 -0.1016)
			(stroke
				(width 0.1)
				(type default)
			)
			(layer "B.Fab")
		)
		(fp_line
			(start 0.2794 -0.1016)
			(end 0.2794 0.9906)
			(stroke
				(width 0.1)
				(type default)
			)
			(layer "B.Fab")
		)
		(pad "1" smd rect
			(at 0 0 90)
			(size 0.508 0.508)
			(layers "B.Cu" "B.Mask" "B.Paste")
			(net "PD_CPU1_RSVD_TEST_1")
		)
		(pad "2" smd rect
			(at 0 0.889 90)
			(size 0.508 0.508)
			(layers "B.Cu" "B.Mask" "B.Paste")
			(net "GND")
		)
		(zone
			(layer "B.Cu")
			(hatch none 0.5)
			(connect_pads
				(clearance 0)
			)
			(min_thickness 0.25)
			(keepout
				(tracks not_allowed)
				(vias allowed)
				(pads allowed)
				(copperpour not_allowed)
				(footprints allowed)
			)
			(placement
				(enabled no)
				(sheetname "")
			)
			(fill
				(thermal_gap 0.5)
				(thermal_bridge_width 0.5)
				(island_removal_mode 0)
			)
			(polygon
				(pts
					(xy 79.756 -64.008) (xy 79.756 -64.516) (xy 80.137 -64.516) (xy 80.137 -64.008)
				)
			)
		)
		(zone
			(layer "B.Cu")
			(hatch none 0.5)
			(connect_pads
				(clearance 0)
			)
			(min_thickness 0.25)
			(keepout
				(tracks allowed)
				(vias not_allowed)
				(pads allowed)
				(copperpour not_allowed)
				(footprints allowed)
			)
			(placement
				(enabled no)
				(sheetname "")
			)
			(fill
				(thermal_gap 0.5)
				(thermal_bridge_width 0.5)
				(island_removal_mode 0)
			)
			(polygon
				(pts
					(xy 80.137 -64.008) (xy 80.137 -64.516) (xy 79.756 -64.516) (xy 79.756 -64.008)
				)
			)
		)
	)
	(footprint ""
		(layer "B.Cu")
		(at 469.138 -131.2164 180)
		(property "Reference" "CR6W2"
			(at -1.06934 -0.39116 270)
			(unlocked yes)
			(layer "B.SilkS")
			(effects
				(font
					(size 0.4064 0.254)
					(thickness 0.1524)
				)
				(justify left mirror)
			)
		)
		(property "Value" ""
			(at 0 0 0)
			(layer "B.Fab")
			(effects
				(font
					(size 1.27 1.27)
				)
				(justify mirror)
			)
		)
		(duplicate_pad_numbers_are_jumpers no)
		(fp_line
			(start 1.234186 1.636522)
			(end 0.753364 0.803656)
			(stroke
				(width 0.1524)
				(type default)
			)
			(layer "B.SilkS")
		)
		(fp_line
			(start 0.753364 2.548128)
			(end 0.753364 1.636522)
			(stroke
				(width 0.1524)
				(type default)
			)
			(layer "B.SilkS")
		)
		(fp_line
			(start 0.753364 1.636522)
			(end 1.234186 1.636522)
			(stroke
				(width 0.1524)
				(type default)
			)
			(layer "B.SilkS")
		)
		(fp_line
			(start 0.753364 0.803656)
			(end 0.272542 1.636522)
			(stroke
				(width 0.1524)
				(type default)
			)
			(layer "B.SilkS")
		)
		(fp_line
			(start 0.753364 -0.319786)
			(end 0.753364 0.803656)
			(stroke
				(width 0.1524)
				(type default)
			)
			(layer "B.SilkS")
		)
		(fp_line
			(start 0.272542 1.636522)
			(end 0.753364 1.636522)
			(stroke
				(width 0.1524)
				(type default)
			)
			(layer "B.SilkS")
		)
		(fp_line
			(start 0.272542 0.803656)
			(end 1.234186 0.803656)
			(stroke
				(width 0.1524)
				(type default)
			)
			(layer "B.SilkS")
		)
		(fp_poly
			(pts
				(xy 0.67437 0.24384) (xy 0.67437 2.04216) (xy -0.67437 2.04216) (xy -0.67437 0.24384)
			)
			(stroke
				(width 0)
				(type default)
			)
			(fill no)
			(layer "B.CrtYd")
		)
		(fp_line
			(start 1.229106 1.63195)
			(end 0.748284 0.799084)
			(stroke
				(width 0.1)
				(type default)
			)
			(layer "B.Fab")
		)
		(fp_line
			(start 0.752348 1.628902)
			(end 0.752348 2.540508)
			(stroke
				(width 0.1)
				(type default)
			)
			(layer "B.Fab")
		)
		(fp_line
			(start 0.748284 0.799084)
			(end 0.748284 -0.324358)
			(stroke
				(width 0.1)
				(type default)
			)
			(layer "B.Fab")
		)
		(fp_line
			(start 0.748284 0.799084)
			(end 0.267462 1.63195)
			(stroke
				(width 0.1)
				(type default)
			)
			(layer "B.Fab")
		)
		(fp_line
			(start 0.67437 2.04216)
			(end -0.67437 2.04216)
			(stroke
				(width 0.1)
				(type default)
			)
			(layer "B.Fab")
		)
		(fp_line
			(start 0.67437 0.24384)
			(end 0.67437 2.04216)
			(stroke
				(width 0.1)
				(type default)
			)
			(layer "B.Fab")
		)
		(fp_line
			(start 0.267462 1.63195)
			(end 1.229106 1.63195)
			(stroke
				(width 0.1)
				(type default)
			)
			(layer "B.Fab")
		)
		(fp_line
			(start 0.267462 0.799084)
			(end 1.229106 0.799084)
			(stroke
				(width 0.1)
				(type default)
			)
			(layer "B.Fab")
		)
		(fp_line
			(start -0.67437 2.04216)
			(end -0.67437 0.24384)
			(stroke
				(width 0.1)
				(type default)
			)
			(layer "B.Fab")
		)
		(fp_line
			(start -0.67437 0.24384)
			(end 0.67437 0.24384)
			(stroke
				(width 0.1)
				(type default)
			)
			(layer "B.Fab")
		)
		(pad "1" smd rect
			(at 0 0)
			(size 0.4064 1.016)
			(layers "B.Cu" "B.Mask" "B.Paste")
			(net "FM_CPU_MSMI_LVT3_N")
		)
		(pad "2" smd rect
			(at 0 2.286)
			(size 0.4064 1.016)
			(layers "B.Cu" "B.Mask" "B.Paste")
			(net "FM_CPU_CATERR_MSMI_LVT3_N")
		)
	)
	(footprint ""
		(layer "B.Cu")
		(at 327.025 -60.325 90)
		(property "Reference" "R4R1"
			(at 0 0 90)
			(layer "B.SilkS")
			(hide yes)
			(effects
				(font
					(size 1.27 1.27)
				)
				(justify mirror)
			)
		)
		(property "Value" ""
			(at 0 0 90)
			(layer "B.Fab")
			(effects
				(font
					(size 1.27 1.27)
				)
				(justify mirror)
			)
		)
		(duplicate_pad_numbers_are_jumpers no)
		(fp_poly
			(pts
				(xy 0.2794 -0.1016) (xy -0.2794 -0.1016) (xy -0.2794 0.9906) (xy 0.2794 0.9906)
			)
			(stroke
				(width 0)
				(type default)
			)
			(fill no)
			(layer "B.CrtYd")
		)
		(fp_line
			(start 0.2794 -0.1016)
			(end 0.2794 0.9906)
			(stroke
				(width 0.1)
				(type default)
			)
			(layer "B.Fab")
		)
		(fp_line
			(start -0.2794 -0.1016)
			(end 0.2794 -0.1016)
			(stroke
				(width 0.1)
				(type default)
			)
			(layer "B.Fab")
		)
		(fp_line
			(start 0.2794 0.9906)
			(end -0.2794 0.9906)
			(stroke
				(width 0.1)
				(type default)
			)
			(layer "B.Fab")
		)
		(fp_line
			(start -0.2794 0.9906)
			(end -0.2794 -0.1016)
			(stroke
				(width 0.1)
				(type default)
			)
			(layer "B.Fab")
		)
		(pad "1" smd rect
			(at 0 0 270)
			(size 0.508 0.508)
			(layers "B.Cu" "B.Mask" "B.Paste")
			(net "H_CPU0_FAST_WAKE_N")
		)
		(pad "2" smd rect
			(at 0 0.889 270)
			(size 0.508 0.508)
			(layers "B.Cu" "B.Mask" "B.Paste")
			(net "H_CPU0_FAST_WAKE_B_N")
		)
		(zone
			(layer "B.Cu")
			(hatch none 0.5)
			(connect_pads
				(clearance 0)
			)
			(min_thickness 0.25)
			(keepout
				(tracks allowed)
				(vias not_allowed)
				(pads allowed)
				(copperpour not_allowed)
				(footprints allowed)
			)
			(placement
				(enabled no)
				(sheetname "")
			)
			(fill
				(thermal_gap 0.5)
				(thermal_bridge_width 0.5)
				(island_removal_mode 0)
			)
			(polygon
				(pts
					(xy 327.279 -60.579) (xy 327.279 -60.071) (xy 327.66 -60.071) (xy 327.66 -60.579)
				)
			)
		)
		(zone
			(layer "B.Cu")
			(hatch none 0.5)
			(connect_pads
				(clearance 0)
			)
			(min_thickness 0.25)
			(keepout
				(tracks not_allowed)
				(vias allowed)
				(pads allowed)
				(copperpour not_allowed)
				(footprints allowed)
			)
			(placement
				(enabled no)
				(sheetname "")
			)
			(fill
				(thermal_gap 0.5)
				(thermal_bridge_width 0.5)
				(island_removal_mode 0)
			)
			(polygon
				(pts
					(xy 327.66 -60.579) (xy 327.66 -60.071) (xy 327.279 -60.071) (xy 327.279 -60.579)
				)
			)
		)
	)
	(footprint ""
		(layer "B.Cu")
		(at 411.479492 -31.107888 -90)
		(property "Reference" "C25W61"
			(at 0.8382 -0.67818 270)
			(unlocked yes)
			(layer "B.SilkS")
			(effects
				(font
					(size 0.4064 0.254)
					(thickness 0.1524)
				)
				(justify left mirror)
			)
		)
		(property "Value" ""
			(at 0 0 90)
			(layer "B.Fab")
			(effects
				(font
					(size 1.27 1.27)
				)
				(justify mirror)
			)
		)
		(duplicate_pad_numbers_are_jumpers no)
		(fp_poly
			(pts
				(xy -0.3048 -0.1016) (xy -0.3048 0.9906) (xy 0.3048 0.9906) (xy 0.3048 -0.1016)
			)
			(stroke
				(width 0)
				(type default)
			)
			(fill no)
			(layer "B.CrtYd")
		)
		(fp_line
			(start -0.3048 0.9906)
			(end -0.3048 -0.1016)
			(stroke
				(width 0.1)
				(type default)
			)
			(layer "B.Fab")
		)
		(fp_line
			(start 0.3048 0.9906)
			(end -0.3048 0.9906)
			(stroke
				(width 0.1)
				(type default)
			)
			(layer "B.Fab")
		)
		(fp_line
			(start -0.3048 -0.1016)
			(end 0.3048 -0.1016)
			(stroke
				(width 0.1)
				(type default)
			)
			(layer "B.Fab")
		)
		(fp_line
			(start 0.3048 -0.1016)
			(end 0.3048 0.9906)
			(stroke
				(width 0.1)
				(type default)
			)
			(layer "B.Fab")
		)
		(pad "1" smd rect
			(at 0 0 90)
			(size 0.508 0.508)
			(layers "B.Cu" "B.Mask" "B.Paste")
			(net "P3V3_STBY")
		)
		(pad "2" smd rect
			(at 0 0.889 90)
			(size 0.508 0.508)
			(layers "B.Cu" "B.Mask" "B.Paste")
			(net "GND")
		)
		(zone
			(layer "B.Cu")
			(hatch none 0.5)
			(connect_pads
				(clearance 0)
			)
			(min_thickness 0.25)
			(keepout
				(tracks not_allowed)
				(vias allowed)
				(pads allowed)
				(copperpour not_allowed)
				(footprints allowed)
			)
			(placement
				(enabled no)
				(sheetname "")
			)
			(fill
				(thermal_gap 0.5)
				(thermal_bridge_width 0.5)
				(island_removal_mode 0)
			)
			(polygon
				(pts
					(xy 410.844492 -30.853888) (xy 410.844492 -31.361888) (xy 411.225492 -31.361888) (xy 411.225492 -30.853888)
				)
			)
		)
		(zone
			(layer "B.Cu")
			(hatch none 0.5)
			(connect_pads
				(clearance 0)
			)
			(min_thickness 0.25)
			(keepout
				(tracks allowed)
				(vias not_allowed)
				(pads allowed)
				(copperpour not_allowed)
				(footprints allowed)
			)
			(placement
				(enabled no)
				(sheetname "")
			)
			(fill
				(thermal_gap 0.5)
				(thermal_bridge_width 0.5)
				(island_removal_mode 0)
			)
			(polygon
				(pts
					(xy 411.225492 -30.853888) (xy 411.225492 -31.361888) (xy 410.844492 -31.361888) (xy 410.844492 -30.853888)
				)
			)
		)
	)
	(footprint ""
		(layer "B.Cu")
		(at 205.74 -106.299 -90)
		(property "Reference" "R6N10"
			(at 0 0 90)
			(layer "B.SilkS")
			(hide yes)
			(effects
				(font
					(size 1.27 1.27)
				)
				(justify mirror)
			)
		)
		(property "Value" ""
			(at 0 0 90)
			(layer "B.Fab")
			(effects
				(font
					(size 1.27 1.27)
				)
				(justify mirror)
			)
		)
		(duplicate_pad_numbers_are_jumpers no)
		(fp_poly
			(pts
				(xy 0.2794 -0.1016) (xy -0.2794 -0.1016) (xy -0.2794 0.9906) (xy 0.2794 0.9906)
			)
			(stroke
				(width 0)
				(type default)
			)
			(fill no)
			(layer "B.CrtYd")
		)
		(fp_line
			(start -0.2794 0.9906)
			(end -0.2794 -0.1016)
			(stroke
				(width 0.1)
				(type default)
			)
			(layer "B.Fab")
		)
		(fp_line
			(start 0.2794 0.9906)
			(end -0.2794 0.9906)
			(stroke
				(width 0.1)
				(type default)
			)
			(layer "B.Fab")
		)
		(fp_line
			(start -0.2794 -0.1016)
			(end 0.2794 -0.1016)
			(stroke
				(width 0.1)
				(type default)
			)
			(layer "B.Fab")
		)
		(fp_line
			(start 0.2794 -0.1016)
			(end 0.2794 0.9906)
			(stroke
				(width 0.1)
				(type default)
			)
			(layer "B.Fab")
		)
		(pad "1" smd rect
			(at 0 0 90)
			(size 0.508 0.508)
			(layers "B.Cu" "B.Mask" "B.Paste")
			(net "SVID_ALERT0_CPU0_N")
		)
		(pad "2" smd rect
			(at 0 0.889 90)
			(size 0.508 0.508)
			(layers "B.Cu" "B.Mask" "B.Paste")
			(net "SVID_ALERT0_CPU0_R_N")
		)
		(zone
			(layer "B.Cu")
			(hatch none 0.5)
			(connect_pads
				(clearance 0)
			)
			(min_thickness 0.25)
			(keepout
				(tracks not_allowed)
				(vias allowed)
				(pads allowed)
				(copperpour not_allowed)
				(footprints allowed)
			)
			(placement
				(enabled no)
				(sheetname "")
			)
			(fill
				(thermal_gap 0.5)
				(thermal_bridge_width 0.5)
				(island_removal_mode 0)
			)
			(polygon
				(pts
					(xy 205.105 -106.045) (xy 205.105 -106.553) (xy 205.486 -106.553) (xy 205.486 -106.045)
				)
			)
		)
		(zone
			(layer "B.Cu")
			(hatch none 0.5)
			(connect_pads
				(clearance 0)
			)
			(min_thickness 0.25)
			(keepout
				(tracks allowed)
				(vias not_allowed)
				(pads allowed)
				(copperpour not_allowed)
				(footprints allowed)
			)
			(placement
				(enabled no)
				(sheetname "")
			)
			(fill
				(thermal_gap 0.5)
				(thermal_bridge_width 0.5)
				(island_removal_mode 0)
			)
			(polygon
				(pts
					(xy 205.486 -106.045) (xy 205.486 -106.553) (xy 205.105 -106.553) (xy 205.105 -106.045)
				)
			)
		)
	)
	(footprint ""
		(layer "B.Cu")
		(at 19.431 -82.423 -90)
		(property "Reference" "R9P11"
			(at 0 0 90)
			(layer "B.SilkS")
			(hide yes)
			(effects
				(font
					(size 1.27 1.27)
				)
				(justify mirror)
			)
		)
		(property "Value" ""
			(at 0 0 90)
			(layer "B.Fab")
			(effects
				(font
					(size 1.27 1.27)
				)
				(justify mirror)
			)
		)
		(duplicate_pad_numbers_are_jumpers no)
		(fp_poly
			(pts
				(xy 0.2794 -0.1016) (xy -0.2794 -0.1016) (xy -0.2794 0.9906) (xy 0.2794 0.9906)
			)
			(stroke
				(width 0)
				(type default)
			)
			(fill no)
			(layer "B.CrtYd")
		)
		(fp_line
			(start -0.2794 0.9906)
			(end -0.2794 -0.1016)
			(stroke
				(width 0.1)
				(type default)
			)
			(layer "B.Fab")
		)
		(fp_line
			(start 0.2794 0.9906)
			(end -0.2794 0.9906)
			(stroke
				(width 0.1)
				(type default)
			)
			(layer "B.Fab")
		)
		(fp_line
			(start -0.2794 -0.1016)
			(end 0.2794 -0.1016)
			(stroke
				(width 0.1)
				(type default)
			)
			(layer "B.Fab")
		)
		(fp_line
			(start 0.2794 -0.1016)
			(end 0.2794 0.9906)
			(stroke
				(width 0.1)
				(type default)
			)
			(layer "B.Fab")
		)
		(pad "1" smd rect
			(at 0 0 90)
			(size 0.508 0.508)
			(layers "B.Cu" "B.Mask" "B.Paste")
			(net "A_P12V_STBY_FP_TRIGGER")
		)
		(pad "2" smd rect
			(at 0 0.889 90)
			(size 0.508 0.508)
			(layers "B.Cu" "B.Mask" "B.Paste")
			(net "AGND_HSC")
		)
		(zone
			(layer "B.Cu")
			(hatch none 0.5)
			(connect_pads
				(clearance 0)
			)
			(min_thickness 0.25)
			(keepout
				(tracks not_allowed)
				(vias allowed)
				(pads allowed)
				(copperpour not_allowed)
				(footprints allowed)
			)
			(placement
				(enabled no)
				(sheetname "")
			)
			(fill
				(thermal_gap 0.5)
				(thermal_bridge_width 0.5)
				(island_removal_mode 0)
			)
			(polygon
				(pts
					(xy 18.796 -82.169) (xy 18.796 -82.677) (xy 19.177 -82.677) (xy 19.177 -82.169)
				)
			)
		)
		(zone
			(layer "B.Cu")
			(hatch none 0.5)
			(connect_pads
				(clearance 0)
			)
			(min_thickness 0.25)
			(keepout
				(tracks allowed)
				(vias not_allowed)
				(pads allowed)
				(copperpour not_allowed)
				(footprints allowed)
			)
			(placement
				(enabled no)
				(sheetname "")
			)
			(fill
				(thermal_gap 0.5)
				(thermal_bridge_width 0.5)
				(island_removal_mode 0)
			)
			(polygon
				(pts
					(xy 19.177 -82.169) (xy 19.177 -82.677) (xy 18.796 -82.677) (xy 18.796 -82.169)
				)
			)
		)
	)
	(footprint ""
		(layer "B.Cu")
		(at 370.000276 -156.15158 180)
		(property "Reference" "C22W23"
			(at 0 0 0)
			(layer "B.SilkS")
			(hide yes)
			(effects
				(font
					(size 1.27 1.27)
				)
				(justify mirror)
			)
		)
		(property "Value" "*"
			(at 0.0762 -6.2357 180)
			(unlocked yes)
			(layer "B.Fab")
			(hide yes)
			(effects
				(font
					(size 1.27 1.016)
					(thickness 0.1524)
				)
				(justify mirror)
			)
		)
		(property "Device Type" "SC22U16V5MX-4-GP_SMD-BCG5-SC22A"
			(at 0.0762 -8.2677 180)
			(unlocked yes)
			(layer "B.Fab")
			(hide yes)
			(effects
				(font
					(size 1.27 1.016)
					(thickness 0.1524)
				)
				(justify mirror)
			)
		)
		(duplicate_pad_numbers_are_jumpers no)
		(fp_line
			(start -0.635 0)
			(end 0.635 0)
			(stroke
				(width 0.508)
				(type default)
			)
			(layer "B.SilkS")
		)
		(fp_rect
			(start 0.9652 1.778)
			(end -0.9652 -1.778)
			(stroke
				(width 0)
				(type default)
			)
			(fill no)
			(layer "B.CrtYd")
		)
		(fp_poly
			(pts
				(xy 0.9652 -1.778) (xy -0.9652 -1.778) (xy -0.9652 1.778) (xy 0.9652 1.778)
			)
			(stroke
				(width 0)
				(type default)
			)
			(fill no)
			(layer "B.Fab")
		)
		(pad "1" smd rect
			(at 0 -0.9652)
			(size 1.397 1.143)
			(layers "B.Cu" "B.Mask" "B.Paste")
			(net "VR_FET_SW_P12V_STBY_PVDDQ_DEF")
		)
		(pad "2" smd rect
			(at 0 0.9652)
			(size 1.397 1.143)
			(layers "B.Cu" "B.Mask" "B.Paste")
			(net "GND")
		)
	)
	(footprint ""
		(layer "B.Cu")
		(at 354.301806 -60.368434)
		(property "Reference" "R2U29"
			(at 0 0 0)
			(layer "B.SilkS")
			(hide yes)
			(effects
				(font
					(size 1.27 1.27)
				)
				(justify mirror)
			)
		)
		(property "Value" ""
			(at 0 0 0)
			(layer "B.Fab")
			(effects
				(font
					(size 1.27 1.27)
				)
				(justify mirror)
			)
		)
		(duplicate_pad_numbers_are_jumpers no)
		(fp_poly
			(pts
				(xy 0.2794 -0.1016) (xy -0.2794 -0.1016) (xy -0.2794 0.9906) (xy 0.2794 0.9906)
			)
			(stroke
				(width 0)
				(type default)
			)
			(fill no)
			(layer "B.CrtYd")
		)
		(fp_line
			(start -0.2794 -0.1016)
			(end 0.2794 -0.1016)
			(stroke
				(width 0.1)
				(type default)
			)
			(layer "B.Fab")
		)
		(fp_line
			(start -0.2794 0.9906)
			(end -0.2794 -0.1016)
			(stroke
				(width 0.1)
				(type default)
			)
			(layer "B.Fab")
		)
		(fp_line
			(start 0.2794 -0.1016)
			(end 0.2794 0.9906)
			(stroke
				(width 0.1)
				(type default)
			)
			(layer "B.Fab")
		)
		(fp_line
			(start 0.2794 0.9906)
			(end -0.2794 0.9906)
			(stroke
				(width 0.1)
				(type default)
			)
			(layer "B.Fab")
		)
		(pad "1" smd rect
			(at 0 0 180)
			(size 0.508 0.508)
			(layers "B.Cu" "B.Mask" "B.Paste")
			(net "P3E_CPU0_PE1_SS_RXN<7>")
		)
		(pad "2" smd rect
			(at 0 0.889 180)
			(size 0.508 0.508)
			(layers "B.Cu" "B.Mask" "B.Paste")
			(net "P3E_CPU0_PE1_SS_R_RXN<7>")
		)
		(zone
			(layer "B.Cu")
			(hatch none 0.5)
			(connect_pads
				(clearance 0)
			)
			(min_thickness 0.25)
			(keepout
				(tracks allowed)
				(vias not_allowed)
				(pads allowed)
				(copperpour not_allowed)
				(footprints allowed)
			)
			(placement
				(enabled no)
				(sheetname "")
			)
			(fill
				(thermal_gap 0.5)
				(thermal_bridge_width 0.5)
				(island_removal_mode 0)
			)
			(polygon
				(pts
					(xy 354.555806 -60.114434) (xy 354.047806 -60.114434) (xy 354.047806 -59.733434) (xy 354.555806 -59.733434)
				)
			)
		)
		(zone
			(layer "B.Cu")
			(hatch none 0.5)
			(connect_pads
				(clearance 0)
			)
			(min_thickness 0.25)
			(keepout
				(tracks not_allowed)
				(vias allowed)
				(pads allowed)
				(copperpour not_allowed)
				(footprints allowed)
			)
			(placement
				(enabled no)
				(sheetname "")
			)
			(fill
				(thermal_gap 0.5)
				(thermal_bridge_width 0.5)
				(island_removal_mode 0)
			)
			(polygon
				(pts
					(xy 354.555806 -59.733434) (xy 354.047806 -59.733434) (xy 354.047806 -60.114434) (xy 354.555806 -60.114434)
				)
			)
		)
	)
	(footprint ""
		(layer "B.Cu")
		(at 117.1956 -73.406 -90)
		(property "Reference" "R7P16"
			(at 0 0 90)
			(layer "B.SilkS")
			(hide yes)
			(effects
				(font
					(size 1.27 1.27)
				)
				(justify mirror)
			)
		)
		(property "Value" ""
			(at 0 0 90)
			(layer "B.Fab")
			(effects
				(font
					(size 1.27 1.27)
				)
				(justify mirror)
			)
		)
		(duplicate_pad_numbers_are_jumpers no)
		(fp_poly
			(pts
				(xy 0.2794 -0.1016) (xy -0.2794 -0.1016) (xy -0.2794 0.9906) (xy 0.2794 0.9906)
			)
			(stroke
				(width 0)
				(type default)
			)
			(fill no)
			(layer "B.CrtYd")
		)
		(fp_line
			(start -0.2794 0.9906)
			(end -0.2794 -0.1016)
			(stroke
				(width 0.1)
				(type default)
			)
			(layer "B.Fab")
		)
		(fp_line
			(start 0.2794 0.9906)
			(end -0.2794 0.9906)
			(stroke
				(width 0.1)
				(type default)
			)
			(layer "B.Fab")
		)
		(fp_line
			(start -0.2794 -0.1016)
			(end 0.2794 -0.1016)
			(stroke
				(width 0.1)
				(type default)
			)
			(layer "B.Fab")
		)
		(fp_line
			(start 0.2794 -0.1016)
			(end 0.2794 0.9906)
			(stroke
				(width 0.1)
				(type default)
			)
			(layer "B.Fab")
		)
		(pad "1" smd rect
			(at 0 0 90)
			(size 0.508 0.508)
			(layers "B.Cu" "B.Mask" "B.Paste")
			(net "A_CPU1_GHJ_RCOMP0")
		)
		(pad "2" smd rect
			(at 0 0.889 90)
			(size 0.508 0.508)
			(layers "B.Cu" "B.Mask" "B.Paste")
			(net "GND")
		)
		(zone
			(layer "B.Cu")
			(hatch none 0.5)
			(connect_pads
				(clearance 0)
			)
			(min_thickness 0.25)
			(keepout
				(tracks not_allowed)
				(vias allowed)
				(pads allowed)
				(copperpour not_allowed)
				(footprints allowed)
			)
			(placement
				(enabled no)
				(sheetname "")
			)
			(fill
				(thermal_gap 0.5)
				(thermal_bridge_width 0.5)
				(island_removal_mode 0)
			)
			(polygon
				(pts
					(xy 116.5606 -73.152) (xy 116.5606 -73.66) (xy 116.9416 -73.66) (xy 116.9416 -73.152)
				)
			)
		)
		(zone
			(layer "B.Cu")
			(hatch none 0.5)
			(connect_pads
				(clearance 0)
			)
			(min_thickness 0.25)
			(keepout
				(tracks allowed)
				(vias not_allowed)
				(pads allowed)
				(copperpour not_allowed)
				(footprints allowed)
			)
			(placement
				(enabled no)
				(sheetname "")
			)
			(fill
				(thermal_gap 0.5)
				(thermal_bridge_width 0.5)
				(island_removal_mode 0)
			)
			(polygon
				(pts
					(xy 116.9416 -73.152) (xy 116.9416 -73.66) (xy 116.5606 -73.66) (xy 116.5606 -73.152)
				)
			)
		)
	)
	(footprint ""
		(layer "B.Cu")
		(at 375.408952 -43.224958)
		(property "Reference" "R2T32"
			(at 0 0 0)
			(layer "B.SilkS")
			(hide yes)
			(effects
				(font
					(size 1.27 1.27)
				)
				(justify mirror)
			)
		)
		(property "Value" ""
			(at 0 0 0)
			(layer "B.Fab")
			(effects
				(font
					(size 1.27 1.27)
				)
				(justify mirror)
			)
		)
		(duplicate_pad_numbers_are_jumpers no)
		(fp_poly
			(pts
				(xy 0.2794 -0.1016) (xy -0.2794 -0.1016) (xy -0.2794 0.9906) (xy 0.2794 0.9906)
			)
			(stroke
				(width 0)
				(type default)
			)
			(fill no)
			(layer "B.CrtYd")
		)
		(fp_line
			(start -0.2794 -0.1016)
			(end 0.2794 -0.1016)
			(stroke
				(width 0.1)
				(type default)
			)
			(layer "B.Fab")
		)
		(fp_line
			(start -0.2794 0.9906)
			(end -0.2794 -0.1016)
			(stroke
				(width 0.1)
				(type default)
			)
			(layer "B.Fab")
		)
		(fp_line
			(start 0.2794 -0.1016)
			(end 0.2794 0.9906)
			(stroke
				(width 0.1)
				(type default)
			)
			(layer "B.Fab")
		)
		(fp_line
			(start 0.2794 0.9906)
			(end -0.2794 0.9906)
			(stroke
				(width 0.1)
				(type default)
			)
			(layer "B.Fab")
		)
		(pad "1" smd rect
			(at 0 0 180)
			(size 0.508 0.508)
			(layers "B.Cu" "B.Mask" "B.Paste")
			(net "H_CPU0_ERR1_G_N")
		)
		(pad "2" smd rect
			(at 0 0.889 180)
			(size 0.508 0.508)
			(layers "B.Cu" "B.Mask" "B.Paste")
			(net "H_CPU_ERR1_GTL_R_N")
		)
		(zone
			(layer "B.Cu")
			(hatch none 0.5)
			(connect_pads
				(clearance 0)
			)
			(min_thickness 0.25)
			(keepout
				(tracks allowed)
				(vias not_allowed)
				(pads allowed)
				(copperpour not_allowed)
				(footprints allowed)
			)
			(placement
				(enabled no)
				(sheetname "")
			)
			(fill
				(thermal_gap 0.5)
				(thermal_bridge_width 0.5)
				(island_removal_mode 0)
			)
			(polygon
				(pts
					(xy 375.662952 -42.970958) (xy 375.154952 -42.970958) (xy 375.154952 -42.589958) (xy 375.662952 -42.589958)
				)
			)
		)
		(zone
			(layer "B.Cu")
			(hatch none 0.5)
			(connect_pads
				(clearance 0)
			)
			(min_thickness 0.25)
			(keepout
				(tracks not_allowed)
				(vias allowed)
				(pads allowed)
				(copperpour not_allowed)
				(footprints allowed)
			)
			(placement
				(enabled no)
				(sheetname "")
			)
			(fill
				(thermal_gap 0.5)
				(thermal_bridge_width 0.5)
				(island_removal_mode 0)
			)
			(polygon
				(pts
					(xy 375.662952 -42.589958) (xy 375.154952 -42.589958) (xy 375.154952 -42.970958) (xy 375.662952 -42.970958)
				)
			)
		)
	)
	(footprint ""
		(layer "B.Cu")
		(at 371.54485 -72.29348)
		(property "Reference" "C2P4"
			(at 0 0 0)
			(layer "B.SilkS")
			(hide yes)
			(effects
				(font
					(size 1.27 1.27)
				)
				(justify mirror)
			)
		)
		(property "Value" ""
			(at 0 0 0)
			(layer "B.Fab")
			(effects
				(font
					(size 1.27 1.27)
				)
				(justify mirror)
			)
		)
		(duplicate_pad_numbers_are_jumpers no)
		(fp_rect
			(start 0.2794 0.9144)
			(end -0.2794 -0.1143)
			(stroke
				(width 0)
				(type default)
			)
			(fill no)
			(layer "B.CrtYd")
		)
		(fp_line
			(start -0.2794 -0.1143)
			(end -0.2794 0.9144)
			(stroke
				(width 0.1)
				(type default)
			)
			(layer "B.Fab")
		)
		(fp_line
			(start -0.2794 0.9144)
			(end 0.2794 0.9144)
			(stroke
				(width 0.1)
				(type default)
			)
			(layer "B.Fab")
		)
		(fp_line
			(start 0.2794 -0.1143)
			(end -0.2794 -0.1143)
			(stroke
				(width 0.1)
				(type default)
			)
			(layer "B.Fab")
		)
		(fp_line
			(start 0.2794 0.9144)
			(end 0.2794 -0.1143)
			(stroke
				(width 0.1)
				(type default)
			)
			(layer "B.Fab")
		)
		(pad "1" smd custom
			(at 0 0 270)
			(size 0.10414 0.10414)
			(layers "B.Cu" "B.Mask" "B.Paste")
			(net "P3V3_STBY")
			(options
				(clearance outline)
				(anchor circle)
			)
			(primitives
				(gr_poly
					(pts
						(xy -0.20828 -0.08636) (xy -0.20828 0.08636) (xy -0.08636 0.20828) (xy 0.086614 0.20828) (xy 0.20828 0.086614)
						(xy 0.20828 -0.08636) (xy 0.08636 -0.20828) (xy -0.08636 -0.20828)
					)
					(width 0)
					(fill yes)
				)
			)
		)
		(pad "2" smd custom
			(at 0 0.8001 270)
			(size 0.10414 0.10414)
			(layers "B.Cu" "B.Mask" "B.Paste")
			(net "GND")
			(options
				(clearance outline)
				(anchor circle)
			)
			(primitives
				(gr_poly
					(pts
						(xy -0.20828 -0.08636) (xy -0.20828 0.08636) (xy -0.08636 0.20828) (xy 0.086614 0.20828) (xy 0.20828 0.086614)
						(xy 0.20828 -0.08636) (xy 0.08636 -0.20828) (xy -0.08636 -0.20828)
					)
					(width 0)
					(fill yes)
				)
			)
		)
		(zone
			(layer "B.Cu")
			(hatch none 0.5)
			(connect_pads
				(clearance 0)
			)
			(min_thickness 0.25)
			(keepout
				(tracks not_allowed)
				(vias allowed)
				(pads allowed)
				(copperpour not_allowed)
				(footprints allowed)
			)
			(placement
				(enabled no)
				(sheetname "")
			)
			(fill
				(thermal_gap 0.5)
				(thermal_bridge_width 0.5)
				(island_removal_mode 0)
			)
			(polygon
				(pts
					(xy 371.63248 -72.08393) (xy 371.63248 -71.70293) (xy 371.45722 -71.70293) (xy 371.456966 -72.08393)
				)
			)
		)
		(zone
			(layer "B.Cu")
			(hatch none 0.5)
			(connect_pads
				(clearance 0)
			)
			(min_thickness 0.25)
			(keepout
				(tracks allowed)
				(vias not_allowed)
				(pads allowed)
				(copperpour not_allowed)
				(footprints allowed)
			)
			(placement
				(enabled no)
				(sheetname "")
			)
			(fill
				(thermal_gap 0.5)
				(thermal_bridge_width 0.5)
				(island_removal_mode 0)
			)
			(polygon
				(pts
					(xy 371.63248 -72.08393) (xy 371.63248 -71.70293) (xy 371.45722 -71.70293) (xy 371.456966 -72.08393)
				)
			)
		)
	)
	(footprint ""
		(layer "B.Cu")
		(at 418.871654 -36.7665 -90)
		(property "Reference" "C25W52"
			(at 0.8382 -0.67818 270)
			(unlocked yes)
			(layer "B.SilkS")
			(effects
				(font
					(size 0.4064 0.254)
					(thickness 0.1524)
				)
				(justify left mirror)
			)
		)
		(property "Value" ""
			(at 0 0 90)
			(layer "B.Fab")
			(effects
				(font
					(size 1.27 1.27)
				)
				(justify mirror)
			)
		)
		(duplicate_pad_numbers_are_jumpers no)
		(fp_poly
			(pts
				(xy -0.3048 -0.1016) (xy -0.3048 0.9906) (xy 0.3048 0.9906) (xy 0.3048 -0.1016)
			)
			(stroke
				(width 0)
				(type default)
			)
			(fill no)
			(layer "B.CrtYd")
		)
		(fp_line
			(start -0.3048 0.9906)
			(end -0.3048 -0.1016)
			(stroke
				(width 0.1)
				(type default)
			)
			(layer "B.Fab")
		)
		(fp_line
			(start 0.3048 0.9906)
			(end -0.3048 0.9906)
			(stroke
				(width 0.1)
				(type default)
			)
			(layer "B.Fab")
		)
		(fp_line
			(start -0.3048 -0.1016)
			(end 0.3048 -0.1016)
			(stroke
				(width 0.1)
				(type default)
			)
			(layer "B.Fab")
		)
		(fp_line
			(start 0.3048 -0.1016)
			(end 0.3048 0.9906)
			(stroke
				(width 0.1)
				(type default)
			)
			(layer "B.Fab")
		)
		(pad "1" smd rect
			(at 0 0 90)
			(size 0.508 0.508)
			(layers "B.Cu" "B.Mask" "B.Paste")
			(net "P1V2_AUX_BMC")
		)
		(pad "2" smd rect
			(at 0 0.889 90)
			(size 0.508 0.508)
			(layers "B.Cu" "B.Mask" "B.Paste")
			(net "GND")
		)
		(zone
			(layer "B.Cu")
			(hatch none 0.5)
			(connect_pads
				(clearance 0)
			)
			(min_thickness 0.25)
			(keepout
				(tracks not_allowed)
				(vias allowed)
				(pads allowed)
				(copperpour not_allowed)
				(footprints allowed)
			)
			(placement
				(enabled no)
				(sheetname "")
			)
			(fill
				(thermal_gap 0.5)
				(thermal_bridge_width 0.5)
				(island_removal_mode 0)
			)
			(polygon
				(pts
					(xy 418.236654 -36.5125) (xy 418.236654 -37.0205) (xy 418.617654 -37.0205) (xy 418.617654 -36.5125)
				)
			)
		)
		(zone
			(layer "B.Cu")
			(hatch none 0.5)
			(connect_pads
				(clearance 0)
			)
			(min_thickness 0.25)
			(keepout
				(tracks allowed)
				(vias not_allowed)
				(pads allowed)
				(copperpour not_allowed)
				(footprints allowed)
			)
			(placement
				(enabled no)
				(sheetname "")
			)
			(fill
				(thermal_gap 0.5)
				(thermal_bridge_width 0.5)
				(island_removal_mode 0)
			)
			(polygon
				(pts
					(xy 418.617654 -36.5125) (xy 418.617654 -37.0205) (xy 418.236654 -37.0205) (xy 418.236654 -36.5125)
				)
			)
		)
	)
	(footprint ""
		(layer "B.Cu")
		(at 448.55638 -33.5915 90)
		(property "Reference" "R25W28"
			(at 0 0 90)
			(layer "B.SilkS")
			(hide yes)
			(effects
				(font
					(size 1.27 1.27)
				)
				(justify mirror)
			)
		)
		(property "Value" "*"
			(at -0.064008 -4.108196 90)
			(unlocked yes)
			(layer "B.Fab")
			(hide yes)
			(effects
				(font
					(size 1.27 1.016)
					(thickness 0.1524)
				)
				(justify mirror)
			)
		)
		(property "Device Type" "120R2F-GP_RCL_GP-120R2F-GP,64.A"
			(at -0.064008 -5.632196 90)
			(unlocked yes)
			(layer "B.Fab")
			(hide yes)
			(effects
				(font
					(size 1.27 1.016)
					(thickness 0.1524)
				)
				(justify mirror)
			)
		)
		(duplicate_pad_numbers_are_jumpers no)
		(fp_line
			(start 0.508 -0.9398)
			(end 0.508 0.9398)
			(stroke
				(width 0.1524)
				(type default)
			)
			(layer "B.SilkS")
		)
		(fp_line
			(start -0.508 -0.9398)
			(end 0.508 -0.9398)
			(stroke
				(width 0.1524)
				(type default)
			)
			(layer "B.SilkS")
		)
		(fp_rect
			(start 0.508 0.9398)
			(end -0.508 -0.9398)
			(stroke
				(width 0)
				(type default)
			)
			(fill no)
			(layer "B.CrtYd")
		)
		(fp_rect
			(start 0.508 0.9398)
			(end -0.508 -0.9398)
			(stroke
				(width 0)
				(type default)
			)
			(fill no)
			(layer "B.Fab")
		)
		(pad "1" smd custom
			(at 0 -0.4445 270)
			(size 0.1397 0.1397)
			(layers "B.Cu" "B.Mask" "B.Paste")
			(net "BMC_M_ODT")
			(options
				(clearance outline)
				(anchor circle)
			)
			(primitives
				(gr_poly
					(pts
						(arc
							(start -0.1778 0.2794)
							(mid -0.249642 0.249642)
							(end -0.2794 0.1778)
						)
						(arc
							(start -0.2794 -0.1778)
							(mid -0.249642 -0.249642)
							(end -0.1778 -0.2794)
						)
						(arc
							(start 0.1778 -0.2794)
							(mid 0.249642 -0.249642)
							(end 0.2794 -0.1778)
						)
						(arc
							(start 0.2794 0.1778)
							(mid 0.249642 0.249642)
							(end 0.1778 0.2794)
						)
					)
					(width 0)
					(fill yes)
				)
			)
		)
		(pad "2" smd custom
			(at 0 0.4445 270)
			(size 0.1397 0.1397)
			(layers "B.Cu" "B.Mask" "B.Paste")
			(net "P1V2_AUX_BMC")
			(options
				(clearance outline)
				(anchor circle)
			)
			(primitives
				(gr_poly
					(pts
						(arc
							(start -0.1778 0.2794)
							(mid -0.249642 0.249642)
							(end -0.2794 0.1778)
						)
						(arc
							(start -0.2794 -0.1778)
							(mid -0.249642 -0.249642)
							(end -0.1778 -0.2794)
						)
						(arc
							(start 0.1778 -0.2794)
							(mid 0.249642 -0.249642)
							(end 0.2794 -0.1778)
						)
						(arc
							(start 0.2794 0.1778)
							(mid 0.249642 0.249642)
							(end 0.1778 0.2794)
						)
					)
					(width 0)
					(fill yes)
				)
			)
		)
	)
	(footprint ""
		(layer "B.Cu")
		(at 129.777998 -67.677538)
		(property "Reference" "R7P26"
			(at 0 0 0)
			(layer "B.SilkS")
			(hide yes)
			(effects
				(font
					(size 1.27 1.27)
				)
				(justify mirror)
			)
		)
		(property "Value" ""
			(at 0 0 0)
			(layer "B.Fab")
			(effects
				(font
					(size 1.27 1.27)
				)
				(justify mirror)
			)
		)
		(duplicate_pad_numbers_are_jumpers no)
		(fp_poly
			(pts
				(xy 0.2794 -0.1016) (xy -0.2794 -0.1016) (xy -0.2794 0.9906) (xy 0.2794 0.9906)
			)
			(stroke
				(width 0)
				(type default)
			)
			(fill no)
			(layer "B.CrtYd")
		)
		(fp_line
			(start -0.2794 -0.1016)
			(end 0.2794 -0.1016)
			(stroke
				(width 0.1)
				(type default)
			)
			(layer "B.Fab")
		)
		(fp_line
			(start -0.2794 0.9906)
			(end -0.2794 -0.1016)
			(stroke
				(width 0.1)
				(type default)
			)
			(layer "B.Fab")
		)
		(fp_line
			(start 0.2794 -0.1016)
			(end 0.2794 0.9906)
			(stroke
				(width 0.1)
				(type default)
			)
			(layer "B.Fab")
		)
		(fp_line
			(start 0.2794 0.9906)
			(end -0.2794 0.9906)
			(stroke
				(width 0.1)
				(type default)
			)
			(layer "B.Fab")
		)
		(pad "1" smd rect
			(at 0 0 180)
			(size 0.508 0.508)
			(layers "B.Cu" "B.Mask" "B.Paste")
			(net "H_PMSYNC_CLK_24M_CPU1")
		)
		(pad "2" smd rect
			(at 0 0.889 180)
			(size 0.508 0.508)
			(layers "B.Cu" "B.Mask" "B.Paste")
			(net "H_PMSYNC_CLK_24M")
		)
		(zone
			(layer "B.Cu")
			(hatch none 0.5)
			(connect_pads
				(clearance 0)
			)
			(min_thickness 0.25)
			(keepout
				(tracks allowed)
				(vias not_allowed)
				(pads allowed)
				(copperpour not_allowed)
				(footprints allowed)
			)
			(placement
				(enabled no)
				(sheetname "")
			)
			(fill
				(thermal_gap 0.5)
				(thermal_bridge_width 0.5)
				(island_removal_mode 0)
			)
			(polygon
				(pts
					(xy 130.031998 -67.423538) (xy 129.523998 -67.423538) (xy 129.523998 -67.042538) (xy 130.031998 -67.042538)
				)
			)
		)
		(zone
			(layer "B.Cu")
			(hatch none 0.5)
			(connect_pads
				(clearance 0)
			)
			(min_thickness 0.25)
			(keepout
				(tracks not_allowed)
				(vias allowed)
				(pads allowed)
				(copperpour not_allowed)
				(footprints allowed)
			)
			(placement
				(enabled no)
				(sheetname "")
			)
			(fill
				(thermal_gap 0.5)
				(thermal_bridge_width 0.5)
				(island_removal_mode 0)
			)
			(polygon
				(pts
					(xy 130.031998 -67.042538) (xy 129.523998 -67.042538) (xy 129.523998 -67.423538) (xy 130.031998 -67.423538)
				)
			)
		)
	)
	(footprint ""
		(layer "B.Cu")
		(at 383.73685 -111.05515 -90)
		(property "Reference" "C3N7"
			(at 0 0 90)
			(layer "B.SilkS")
			(hide yes)
			(effects
				(font
					(size 1.27 1.27)
				)
				(justify mirror)
			)
		)
		(property "Value" ""
			(at 0 0 90)
			(layer "B.Fab")
			(effects
				(font
					(size 1.27 1.27)
				)
				(justify mirror)
			)
		)
		(duplicate_pad_numbers_are_jumpers no)
		(fp_rect
			(start 0.2794 0.9144)
			(end -0.2794 -0.1143)
			(stroke
				(width 0)
				(type default)
			)
			(fill no)
			(layer "B.CrtYd")
		)
		(fp_line
			(start -0.2794 0.9144)
			(end 0.2794 0.9144)
			(stroke
				(width 0.1)
				(type default)
			)
			(layer "B.Fab")
		)
		(fp_line
			(start 0.2794 0.9144)
			(end 0.2794 -0.1143)
			(stroke
				(width 0.1)
				(type default)
			)
			(layer "B.Fab")
		)
		(fp_line
			(start -0.2794 -0.1143)
			(end -0.2794 0.9144)
			(stroke
				(width 0.1)
				(type default)
			)
			(layer "B.Fab")
		)
		(fp_line
			(start 0.2794 -0.1143)
			(end -0.2794 -0.1143)
			(stroke
				(width 0.1)
				(type default)
			)
			(layer "B.Fab")
		)
		(pad "1" smd custom
			(at 0 0 180)
			(size 0.10414 0.10414)
			(layers "B.Cu" "B.Mask" "B.Paste")
			(net "PVNN_PCH_STBY")
			(options
				(clearance outline)
				(anchor circle)
			)
			(primitives
				(gr_poly
					(pts
						(xy -0.20828 -0.08636) (xy -0.20828 0.08636) (xy -0.08636 0.20828) (xy 0.086614 0.20828) (xy 0.20828 0.086614)
						(xy 0.20828 -0.08636) (xy 0.08636 -0.20828) (xy -0.08636 -0.20828)
					)
					(width 0)
					(fill yes)
				)
			)
		)
		(pad "2" smd custom
			(at 0 0.8001 180)
			(size 0.10414 0.10414)
			(layers "B.Cu" "B.Mask" "B.Paste")
			(net "GND")
			(options
				(clearance outline)
				(anchor circle)
			)
			(primitives
				(gr_poly
					(pts
						(xy -0.20828 -0.08636) (xy -0.20828 0.08636) (xy -0.08636 0.20828) (xy 0.086614 0.20828) (xy 0.20828 0.086614)
						(xy 0.20828 -0.08636) (xy 0.08636 -0.20828) (xy -0.08636 -0.20828)
					)
					(width 0)
					(fill yes)
				)
			)
		)
		(zone
			(layer "B.Cu")
			(hatch none 0.5)
			(connect_pads
				(clearance 0)
			)
			(min_thickness 0.25)
			(keepout
				(tracks allowed)
				(vias not_allowed)
				(pads allowed)
				(copperpour not_allowed)
				(footprints allowed)
			)
			(placement
				(enabled no)
				(sheetname "")
			)
			(fill
				(thermal_gap 0.5)
				(thermal_bridge_width 0.5)
				(island_removal_mode 0)
			)
			(polygon
				(pts
					(xy 383.5273 -110.96752) (xy 383.1463 -110.96752) (xy 383.1463 -111.14278) (xy 383.5273 -111.143034)
				)
			)
		)
		(zone
			(layer "B.Cu")
			(hatch none 0.5)
			(connect_pads
				(clearance 0)
			)
			(min_thickness 0.25)
			(keepout
				(tracks not_allowed)
				(vias allowed)
				(pads allowed)
				(copperpour not_allowed)
				(footprints allowed)
			)
			(placement
				(enabled no)
				(sheetname "")
			)
			(fill
				(thermal_gap 0.5)
				(thermal_bridge_width 0.5)
				(island_removal_mode 0)
			)
			(polygon
				(pts
					(xy 383.5273 -110.96752) (xy 383.1463 -110.96752) (xy 383.1463 -111.14278) (xy 383.5273 -111.143034)
				)
			)
		)
	)
	(footprint ""
		(layer "B.Cu")
		(at 376.170952 -43.224958)
		(property "Reference" "R2T61"
			(at 0 0 0)
			(layer "B.SilkS")
			(hide yes)
			(effects
				(font
					(size 1.27 1.27)
				)
				(justify mirror)
			)
		)
		(property "Value" ""
			(at 0 0 0)
			(layer "B.Fab")
			(effects
				(font
					(size 1.27 1.27)
				)
				(justify mirror)
			)
		)
		(duplicate_pad_numbers_are_jumpers no)
		(fp_poly
			(pts
				(xy 0.2794 -0.1016) (xy -0.2794 -0.1016) (xy -0.2794 0.9906) (xy 0.2794 0.9906)
			)
			(stroke
				(width 0)
				(type default)
			)
			(fill no)
			(layer "B.CrtYd")
		)
		(fp_line
			(start -0.2794 -0.1016)
			(end 0.2794 -0.1016)
			(stroke
				(width 0.1)
				(type default)
			)
			(layer "B.Fab")
		)
		(fp_line
			(start -0.2794 0.9906)
			(end -0.2794 -0.1016)
			(stroke
				(width 0.1)
				(type default)
			)
			(layer "B.Fab")
		)
		(fp_line
			(start 0.2794 -0.1016)
			(end 0.2794 0.9906)
			(stroke
				(width 0.1)
				(type default)
			)
			(layer "B.Fab")
		)
		(fp_line
			(start 0.2794 0.9906)
			(end -0.2794 0.9906)
			(stroke
				(width 0.1)
				(type default)
			)
			(layer "B.Fab")
		)
		(pad "1" smd rect
			(at 0 0 180)
			(size 0.508 0.508)
			(layers "B.Cu" "B.Mask" "B.Paste")
			(net "H_CPU_ERR1_PCH_N")
		)
		(pad "2" smd rect
			(at 0 0.889 180)
			(size 0.508 0.508)
			(layers "B.Cu" "B.Mask" "B.Paste")
			(net "H_CPU_ERR1_GTL_R_N")
		)
		(zone
			(layer "B.Cu")
			(hatch none 0.5)
			(connect_pads
				(clearance 0)
			)
			(min_thickness 0.25)
			(keepout
				(tracks allowed)
				(vias not_allowed)
				(pads allowed)
				(copperpour not_allowed)
				(footprints allowed)
			)
			(placement
				(enabled no)
				(sheetname "")
			)
			(fill
				(thermal_gap 0.5)
				(thermal_bridge_width 0.5)
				(island_removal_mode 0)
			)
			(polygon
				(pts
					(xy 376.424952 -42.970958) (xy 375.916952 -42.970958) (xy 375.916952 -42.589958) (xy 376.424952 -42.589958)
				)
			)
		)
		(zone
			(layer "B.Cu")
			(hatch none 0.5)
			(connect_pads
				(clearance 0)
			)
			(min_thickness 0.25)
			(keepout
				(tracks not_allowed)
				(vias allowed)
				(pads allowed)
				(copperpour not_allowed)
				(footprints allowed)
			)
			(placement
				(enabled no)
				(sheetname "")
			)
			(fill
				(thermal_gap 0.5)
				(thermal_bridge_width 0.5)
				(island_removal_mode 0)
			)
			(polygon
				(pts
					(xy 376.424952 -42.589958) (xy 375.916952 -42.589958) (xy 375.916952 -42.970958) (xy 376.424952 -42.970958)
				)
			)
		)
	)
	(footprint ""
		(layer "B.Cu")
		(at 396.978886 -16.438372 180)
		(property "Reference" "R32W5"
			(at 0.8382 -0.67818 180)
			(unlocked yes)
			(layer "B.SilkS")
			(effects
				(font
					(size 0.4064 0.254)
					(thickness 0.1524)
				)
				(justify left mirror)
			)
		)
		(property "Value" ""
			(at 0 0 0)
			(layer "B.Fab")
			(effects
				(font
					(size 1.27 1.27)
				)
				(justify mirror)
			)
		)
		(duplicate_pad_numbers_are_jumpers no)
		(fp_poly
			(pts
				(xy 0.2794 -0.1016) (xy -0.2794 -0.1016) (xy -0.2794 0.9906) (xy 0.2794 0.9906)
			)
			(stroke
				(width 0)
				(type default)
			)
			(fill no)
			(layer "B.CrtYd")
		)
		(fp_line
			(start 0.2794 0.9906)
			(end -0.2794 0.9906)
			(stroke
				(width 0.1)
				(type default)
			)
			(layer "B.Fab")
		)
		(fp_line
			(start 0.2794 -0.1016)
			(end 0.2794 0.9906)
			(stroke
				(width 0.1)
				(type default)
			)
			(layer "B.Fab")
		)
		(fp_line
			(start -0.2794 0.9906)
			(end -0.2794 -0.1016)
			(stroke
				(width 0.1)
				(type default)
			)
			(layer "B.Fab")
		)
		(fp_line
			(start -0.2794 -0.1016)
			(end 0.2794 -0.1016)
			(stroke
				(width 0.1)
				(type default)
			)
			(layer "B.Fab")
		)
		(pad "1" smd rect
			(at 0 0)
			(size 0.508 0.508)
			(layers "B.Cu" "B.Mask" "B.Paste")
			(net "P1V8_M2")
		)
		(pad "2" smd rect
			(at 0 0.889)
			(size 0.508 0.508)
			(layers "B.Cu" "B.Mask" "B.Paste")
			(net "SMB_M2_SCL")
		)
		(zone
			(layer "B.Cu")
			(hatch none 0.5)
			(connect_pads
				(clearance 0)
			)
			(min_thickness 0.25)
			(keepout
				(tracks not_allowed)
				(vias allowed)
				(pads allowed)
				(copperpour not_allowed)
				(footprints allowed)
			)
			(placement
				(enabled no)
				(sheetname "")
			)
			(fill
				(thermal_gap 0.5)
				(thermal_bridge_width 0.5)
				(island_removal_mode 0)
			)
			(polygon
				(pts
					(xy 396.724886 -17.073372) (xy 397.232886 -17.073372) (xy 397.232886 -16.692372) (xy 396.724886 -16.692372)
				)
			)
		)
		(zone
			(layer "B.Cu")
			(hatch none 0.5)
			(connect_pads
				(clearance 0)
			)
			(min_thickness 0.25)
			(keepout
				(tracks allowed)
				(vias not_allowed)
				(pads allowed)
				(copperpour not_allowed)
				(footprints allowed)
			)
			(placement
				(enabled no)
				(sheetname "")
			)
			(fill
				(thermal_gap 0.5)
				(thermal_bridge_width 0.5)
				(island_removal_mode 0)
			)
			(polygon
				(pts
					(xy 396.724886 -16.692372) (xy 397.232886 -16.692372) (xy 397.232886 -17.073372) (xy 396.724886 -17.073372)
				)
			)
		)
	)
	(footprint ""
		(layer "B.Cu")
		(at 430.726088 -15.280894 -90)
		(property "Reference" "R9G32"
			(at 0 0 90)
			(layer "B.SilkS")
			(hide yes)
			(effects
				(font
					(size 1.27 1.27)
				)
				(justify mirror)
			)
		)
		(property "Value" ""
			(at 0 0 90)
			(layer "B.Fab")
			(effects
				(font
					(size 1.27 1.27)
				)
				(justify mirror)
			)
		)
		(duplicate_pad_numbers_are_jumpers no)
		(fp_poly
			(pts
				(xy 0.2794 -0.1016) (xy -0.2794 -0.1016) (xy -0.2794 0.9906) (xy 0.2794 0.9906)
			)
			(stroke
				(width 0)
				(type default)
			)
			(fill no)
			(layer "B.CrtYd")
		)
		(fp_line
			(start -0.2794 0.9906)
			(end -0.2794 -0.1016)
			(stroke
				(width 0.1)
				(type default)
			)
			(layer "B.Fab")
		)
		(fp_line
			(start 0.2794 0.9906)
			(end -0.2794 0.9906)
			(stroke
				(width 0.1)
				(type default)
			)
			(layer "B.Fab")
		)
		(fp_line
			(start -0.2794 -0.1016)
			(end 0.2794 -0.1016)
			(stroke
				(width 0.1)
				(type default)
			)
			(layer "B.Fab")
		)
		(fp_line
			(start 0.2794 -0.1016)
			(end 0.2794 0.9906)
			(stroke
				(width 0.1)
				(type default)
			)
			(layer "B.Fab")
		)
		(pad "1" smd rect
			(at 0 0 90)
			(size 0.508 0.508)
			(layers "B.Cu" "B.Mask" "B.Paste")
			(net "H_CPU1_GHJ_MEMHOT_LVT3_R_N")
		)
		(pad "2" smd rect
			(at 0 0.889 90)
			(size 0.508 0.508)
			(layers "B.Cu" "B.Mask" "B.Paste")
			(net "H_CPU1_MEMGHJ_MEMHOT_LVT3_K_N")
		)
		(zone
			(layer "B.Cu")
			(hatch none 0.5)
			(connect_pads
				(clearance 0)
			)
			(min_thickness 0.25)
			(keepout
				(tracks not_allowed)
				(vias allowed)
				(pads allowed)
				(copperpour not_allowed)
				(footprints allowed)
			)
			(placement
				(enabled no)
				(sheetname "")
			)
			(fill
				(thermal_gap 0.5)
				(thermal_bridge_width 0.5)
				(island_removal_mode 0)
			)
			(polygon
				(pts
					(xy 430.091088 -15.026894) (xy 430.091088 -15.534894) (xy 430.472088 -15.534894) (xy 430.472088 -15.026894)
				)
			)
		)
		(zone
			(layer "B.Cu")
			(hatch none 0.5)
			(connect_pads
				(clearance 0)
			)
			(min_thickness 0.25)
			(keepout
				(tracks allowed)
				(vias not_allowed)
				(pads allowed)
				(copperpour not_allowed)
				(footprints allowed)
			)
			(placement
				(enabled no)
				(sheetname "")
			)
			(fill
				(thermal_gap 0.5)
				(thermal_bridge_width 0.5)
				(island_removal_mode 0)
			)
			(polygon
				(pts
					(xy 430.472088 -15.026894) (xy 430.472088 -15.534894) (xy 430.091088 -15.534894) (xy 430.091088 -15.026894)
				)
			)
		)
	)
	(footprint ""
		(layer "B.Cu")
		(at 430.85512 -141.939518 90)
		(property "Reference" "C2L52"
			(at 0 0 90)
			(layer "B.SilkS")
			(hide yes)
			(effects
				(font
					(size 1.27 1.27)
				)
				(justify mirror)
			)
		)
		(property "Value" ""
			(at 0 0 90)
			(layer "B.Fab")
			(effects
				(font
					(size 1.27 1.27)
				)
				(justify mirror)
			)
		)
		(duplicate_pad_numbers_are_jumpers no)
		(fp_poly
			(pts
				(xy -0.3048 -0.1016) (xy -0.3048 0.9906) (xy 0.3048 0.9906) (xy 0.3048 -0.1016)
			)
			(stroke
				(width 0)
				(type default)
			)
			(fill no)
			(layer "B.CrtYd")
		)
		(fp_line
			(start 0.3048 -0.1016)
			(end 0.3048 0.9906)
			(stroke
				(width 0.1)
				(type default)
			)
			(layer "B.Fab")
		)
		(fp_line
			(start -0.3048 -0.1016)
			(end 0.3048 -0.1016)
			(stroke
				(width 0.1)
				(type default)
			)
			(layer "B.Fab")
		)
		(fp_line
			(start 0.3048 0.9906)
			(end -0.3048 0.9906)
			(stroke
				(width 0.1)
				(type default)
			)
			(layer "B.Fab")
		)
		(fp_line
			(start -0.3048 0.9906)
			(end -0.3048 -0.1016)
			(stroke
				(width 0.1)
				(type default)
			)
			(layer "B.Fab")
		)
		(pad "1" smd rect
			(at 0 0 270)
			(size 0.508 0.508)
			(layers "B.Cu" "B.Mask" "B.Paste")
			(net "SATA6G_S1_TX_C_DP")
		)
		(pad "2" smd rect
			(at 0 0.889 270)
			(size 0.508 0.508)
			(layers "B.Cu" "B.Mask" "B.Paste")
			(net "SATA6G_S1_TX_DP")
		)
		(zone
			(layer "B.Cu")
			(hatch none 0.5)
			(connect_pads
				(clearance 0)
			)
			(min_thickness 0.25)
			(keepout
				(tracks allowed)
				(vias not_allowed)
				(pads allowed)
				(copperpour not_allowed)
				(footprints allowed)
			)
			(placement
				(enabled no)
				(sheetname "")
			)
			(fill
				(thermal_gap 0.5)
				(thermal_bridge_width 0.5)
				(island_removal_mode 0)
			)
			(polygon
				(pts
					(xy 431.10912 -142.193518) (xy 431.10912 -141.685518) (xy 431.49012 -141.685518) (xy 431.49012 -142.193518)
				)
			)
		)
		(zone
			(layer "B.Cu")
			(hatch none 0.5)
			(connect_pads
				(clearance 0)
			)
			(min_thickness 0.25)
			(keepout
				(tracks not_allowed)
				(vias allowed)
				(pads allowed)
				(copperpour not_allowed)
				(footprints allowed)
			)
			(placement
				(enabled no)
				(sheetname "")
			)
			(fill
				(thermal_gap 0.5)
				(thermal_bridge_width 0.5)
				(island_removal_mode 0)
			)
			(polygon
				(pts
					(xy 431.49012 -142.193518) (xy 431.49012 -141.685518) (xy 431.10912 -141.685518) (xy 431.10912 -142.193518)
				)
			)
		)
	)
	(footprint ""
		(layer "B.Cu")
		(at 468.2744 -41.5798)
		(property "Reference" "C1T7"
			(at 0 0 0)
			(layer "B.SilkS")
			(hide yes)
			(effects
				(font
					(size 1.27 1.27)
				)
				(justify mirror)
			)
		)
		(property "Value" ""
			(at 0 0 0)
			(layer "B.Fab")
			(effects
				(font
					(size 1.27 1.27)
				)
				(justify mirror)
			)
		)
		(duplicate_pad_numbers_are_jumpers no)
		(fp_poly
			(pts
				(xy 0.4953 -0.2032) (xy -0.4953 -0.2032) (xy -0.4953 1.6002) (xy 0.4953 1.6002)
			)
			(stroke
				(width 0)
				(type default)
			)
			(fill no)
			(layer "B.CrtYd")
		)
		(fp_line
			(start -0.4953 -0.2032)
			(end -0.4953 1.6002)
			(stroke
				(width 0.1)
				(type default)
			)
			(layer "B.Fab")
		)
		(fp_line
			(start -0.4953 1.6002)
			(end 0.4953 1.6002)
			(stroke
				(width 0.1)
				(type default)
			)
			(layer "B.Fab")
		)
		(fp_line
			(start 0.4953 -0.2032)
			(end -0.4953 -0.2032)
			(stroke
				(width 0.1)
				(type default)
			)
			(layer "B.Fab")
		)
		(fp_line
			(start 0.4953 1.6002)
			(end 0.4953 -0.2032)
			(stroke
				(width 0.1)
				(type default)
			)
			(layer "B.Fab")
		)
		(pad "1" smd rect
			(at 0 0 180)
			(size 0.762 0.889)
			(layers "B.Cu" "B.Mask" "B.Paste")
			(net "P3V3_STBY")
		)
		(pad "2" smd rect
			(at 0 1.397 180)
			(size 0.762 0.889)
			(layers "B.Cu" "B.Mask" "B.Paste")
			(net "GND")
		)
		(zone
			(layer "B.Cu")
			(hatch none 0.5)
			(connect_pads
				(clearance 0)
			)
			(min_thickness 0.25)
			(keepout
				(tracks not_allowed)
				(vias allowed)
				(pads allowed)
				(copperpour not_allowed)
				(footprints allowed)
			)
			(placement
				(enabled no)
				(sheetname "")
			)
			(fill
				(thermal_gap 0.5)
				(thermal_bridge_width 0.5)
				(island_removal_mode 0)
			)
			(polygon
				(pts
					(xy 468.6554 -41.1353) (xy 467.8934 -41.1353) (xy 467.8934 -40.6273) (xy 468.6554 -40.6273)
				)
			)
		)
	)
	(footprint ""
		(layer "B.Cu")
		(at 490.3851 -120.7516 90)
		(property "Reference" "R9G13"
			(at 0 0 90)
			(layer "B.SilkS")
			(hide yes)
			(effects
				(font
					(size 1.27 1.27)
				)
				(justify mirror)
			)
		)
		(property "Value" ""
			(at 0 0 90)
			(layer "B.Fab")
			(effects
				(font
					(size 1.27 1.27)
				)
				(justify mirror)
			)
		)
		(duplicate_pad_numbers_are_jumpers no)
		(fp_poly
			(pts
				(xy 0.2794 -0.1016) (xy -0.2794 -0.1016) (xy -0.2794 0.9906) (xy 0.2794 0.9906)
			)
			(stroke
				(width 0)
				(type default)
			)
			(fill no)
			(layer "B.CrtYd")
		)
		(fp_line
			(start 0.2794 -0.1016)
			(end 0.2794 0.9906)
			(stroke
				(width 0.1)
				(type default)
			)
			(layer "B.Fab")
		)
		(fp_line
			(start -0.2794 -0.1016)
			(end 0.2794 -0.1016)
			(stroke
				(width 0.1)
				(type default)
			)
			(layer "B.Fab")
		)
		(fp_line
			(start 0.2794 0.9906)
			(end -0.2794 0.9906)
			(stroke
				(width 0.1)
				(type default)
			)
			(layer "B.Fab")
		)
		(fp_line
			(start -0.2794 0.9906)
			(end -0.2794 -0.1016)
			(stroke
				(width 0.1)
				(type default)
			)
			(layer "B.Fab")
		)
		(pad "1" smd rect
			(at 0 0 270)
			(size 0.508 0.508)
			(layers "B.Cu" "B.Mask" "B.Paste")
			(net "SMB_OCP_LAN_STBY_LVC3_SCL")
		)
		(pad "2" smd rect
			(at 0 0.889 270)
			(size 0.508 0.508)
			(layers "B.Cu" "B.Mask" "B.Paste")
			(net "SMB_SPRINGVILLE_STBY_LVC3_SCL")
		)
		(zone
			(layer "B.Cu")
			(hatch none 0.5)
			(connect_pads
				(clearance 0)
			)
			(min_thickness 0.25)
			(keepout
				(tracks allowed)
				(vias not_allowed)
				(pads allowed)
				(copperpour not_allowed)
				(footprints allowed)
			)
			(placement
				(enabled no)
				(sheetname "")
			)
			(fill
				(thermal_gap 0.5)
				(thermal_bridge_width 0.5)
				(island_removal_mode 0)
			)
			(polygon
				(pts
					(xy 490.6391 -121.0056) (xy 490.6391 -120.4976) (xy 491.0201 -120.4976) (xy 491.0201 -121.0056)
				)
			)
		)
		(zone
			(layer "B.Cu")
			(hatch none 0.5)
			(connect_pads
				(clearance 0)
			)
			(min_thickness 0.25)
			(keepout
				(tracks not_allowed)
				(vias allowed)
				(pads allowed)
				(copperpour not_allowed)
				(footprints allowed)
			)
			(placement
				(enabled no)
				(sheetname "")
			)
			(fill
				(thermal_gap 0.5)
				(thermal_bridge_width 0.5)
				(island_removal_mode 0)
			)
			(polygon
				(pts
					(xy 491.0201 -121.0056) (xy 491.0201 -120.4976) (xy 490.6391 -120.4976) (xy 490.6391 -121.0056)
				)
			)
		)
	)
	(footprint ""
		(layer "B.Cu")
		(at 408.051 -4.3815 180)
		(property "Reference" "R8D39"
			(at 0 0 0)
			(layer "B.SilkS")
			(hide yes)
			(effects
				(font
					(size 1.27 1.27)
				)
				(justify mirror)
			)
		)
		(property "Value" ""
			(at 0 0 0)
			(layer "B.Fab")
			(effects
				(font
					(size 1.27 1.27)
				)
				(justify mirror)
			)
		)
		(duplicate_pad_numbers_are_jumpers no)
		(fp_poly
			(pts
				(xy 0.2794 -0.1016) (xy -0.2794 -0.1016) (xy -0.2794 0.9906) (xy 0.2794 0.9906)
			)
			(stroke
				(width 0)
				(type default)
			)
			(fill no)
			(layer "B.CrtYd")
		)
		(fp_line
			(start 0.2794 0.9906)
			(end -0.2794 0.9906)
			(stroke
				(width 0.1)
				(type default)
			)
			(layer "B.Fab")
		)
		(fp_line
			(start 0.2794 -0.1016)
			(end 0.2794 0.9906)
			(stroke
				(width 0.1)
				(type default)
			)
			(layer "B.Fab")
		)
		(fp_line
			(start -0.2794 0.9906)
			(end -0.2794 -0.1016)
			(stroke
				(width 0.1)
				(type default)
			)
			(layer "B.Fab")
		)
		(fp_line
			(start -0.2794 -0.1016)
			(end 0.2794 -0.1016)
			(stroke
				(width 0.1)
				(type default)
			)
			(layer "B.Fab")
		)
		(pad "1" smd rect
			(at 0 0)
			(size 0.508 0.508)
			(layers "B.Cu" "B.Mask" "B.Paste")
			(net "P5V")
		)
		(pad "2" smd rect
			(at 0 0.889)
			(size 0.508 0.508)
			(layers "B.Cu" "B.Mask" "B.Paste")
			(net "A_PG_P5V")
		)
		(zone
			(layer "B.Cu")
			(hatch none 0.5)
			(connect_pads
				(clearance 0)
			)
			(min_thickness 0.25)
			(keepout
				(tracks not_allowed)
				(vias allowed)
				(pads allowed)
				(copperpour not_allowed)
				(footprints allowed)
			)
			(placement
				(enabled no)
				(sheetname "")
			)
			(fill
				(thermal_gap 0.5)
				(thermal_bridge_width 0.5)
				(island_removal_mode 0)
			)
			(polygon
				(pts
					(xy 407.797 -5.0165) (xy 408.305 -5.0165) (xy 408.305 -4.6355) (xy 407.797 -4.6355)
				)
			)
		)
		(zone
			(layer "B.Cu")
			(hatch none 0.5)
			(connect_pads
				(clearance 0)
			)
			(min_thickness 0.25)
			(keepout
				(tracks allowed)
				(vias not_allowed)
				(pads allowed)
				(copperpour not_allowed)
				(footprints allowed)
			)
			(placement
				(enabled no)
				(sheetname "")
			)
			(fill
				(thermal_gap 0.5)
				(thermal_bridge_width 0.5)
				(island_removal_mode 0)
			)
			(polygon
				(pts
					(xy 407.797 -4.6355) (xy 408.305 -4.6355) (xy 408.305 -5.0165) (xy 407.797 -5.0165)
				)
			)
		)
	)
	(footprint ""
		(layer "B.Cu")
		(at 381.7112 -90.53068 180)
		(property "Reference" "R7W13"
			(at 0.8382 -0.67818 180)
			(unlocked yes)
			(layer "B.SilkS")
			(effects
				(font
					(size 0.4064 0.254)
					(thickness 0.1524)
				)
				(justify left mirror)
			)
		)
		(property "Value" ""
			(at 0 0 0)
			(layer "B.Fab")
			(effects
				(font
					(size 1.27 1.27)
				)
				(justify mirror)
			)
		)
		(duplicate_pad_numbers_are_jumpers no)
		(fp_poly
			(pts
				(xy 0.2794 -0.1016) (xy -0.2794 -0.1016) (xy -0.2794 0.9906) (xy 0.2794 0.9906)
			)
			(stroke
				(width 0)
				(type default)
			)
			(fill no)
			(layer "B.CrtYd")
		)
		(fp_line
			(start 0.2794 0.9906)
			(end -0.2794 0.9906)
			(stroke
				(width 0.1)
				(type default)
			)
			(layer "B.Fab")
		)
		(fp_line
			(start 0.2794 -0.1016)
			(end 0.2794 0.9906)
			(stroke
				(width 0.1)
				(type default)
			)
			(layer "B.Fab")
		)
		(fp_line
			(start -0.2794 0.9906)
			(end -0.2794 -0.1016)
			(stroke
				(width 0.1)
				(type default)
			)
			(layer "B.Fab")
		)
		(fp_line
			(start -0.2794 -0.1016)
			(end 0.2794 -0.1016)
			(stroke
				(width 0.1)
				(type default)
			)
			(layer "B.Fab")
		)
		(pad "1" smd rect
			(at 0 0)
			(size 0.508 0.508)
			(layers "B.Cu" "B.Mask" "B.Paste")
			(net "FM_BMC_READY_N")
		)
		(pad "2" smd rect
			(at 0 0.889)
			(size 0.508 0.508)
			(layers "B.Cu" "B.Mask" "B.Paste")
			(net "FM_BMC_READY_R_N")
		)
		(zone
			(layer "B.Cu")
			(hatch none 0.5)
			(connect_pads
				(clearance 0)
			)
			(min_thickness 0.25)
			(keepout
				(tracks not_allowed)
				(vias allowed)
				(pads allowed)
				(copperpour not_allowed)
				(footprints allowed)
			)
			(placement
				(enabled no)
				(sheetname "")
			)
			(fill
				(thermal_gap 0.5)
				(thermal_bridge_width 0.5)
				(island_removal_mode 0)
			)
			(polygon
				(pts
					(xy 381.4572 -91.16568) (xy 381.9652 -91.16568) (xy 381.9652 -90.78468) (xy 381.4572 -90.78468)
				)
			)
		)
		(zone
			(layer "B.Cu")
			(hatch none 0.5)
			(connect_pads
				(clearance 0)
			)
			(min_thickness 0.25)
			(keepout
				(tracks allowed)
				(vias not_allowed)
				(pads allowed)
				(copperpour not_allowed)
				(footprints allowed)
			)
			(placement
				(enabled no)
				(sheetname "")
			)
			(fill
				(thermal_gap 0.5)
				(thermal_bridge_width 0.5)
				(island_removal_mode 0)
			)
			(polygon
				(pts
					(xy 381.4572 -90.78468) (xy 381.9652 -90.78468) (xy 381.9652 -91.16568) (xy 381.4572 -91.16568)
				)
			)
		)
	)
	(footprint ""
		(layer "B.Cu")
		(at 80.757268 -135.4074 -90)
		(property "Reference" "C8M6"
			(at -1.848866 0.752348 270)
			(unlocked yes)
			(layer "B.SilkS")
			(effects
				(font
					(size 1.27 0.9652)
					(thickness 0.1524)
				)
				(justify mirror)
			)
		)
		(property "Value" ""
			(at 0 0 90)
			(layer "B.Fab")
			(effects
				(font
					(size 1.27 1.27)
				)
				(justify mirror)
			)
		)
		(duplicate_pad_numbers_are_jumpers no)
		(fp_rect
			(start 0.500126 1.598422)
			(end -0.500126 -0.201422)
			(stroke
				(width 0)
				(type default)
			)
			(fill no)
			(layer "B.CrtYd")
		)
		(fp_line
			(start -0.500126 1.598422)
			(end 0.500126 1.598422)
			(stroke
				(width 0.1)
				(type default)
			)
			(layer "B.Fab")
		)
		(fp_line
			(start 0.500126 1.598422)
			(end 0.500126 -0.201422)
			(stroke
				(width 0.1)
				(type default)
			)
			(layer "B.Fab")
		)
		(fp_line
			(start -0.500126 -0.201422)
			(end -0.500126 1.598422)
			(stroke
				(width 0.1)
				(type default)
			)
			(layer "B.Fab")
		)
		(fp_line
			(start 0.500126 -0.201422)
			(end -0.500126 -0.201422)
			(stroke
				(width 0.1)
				(type default)
			)
			(layer "B.Fab")
		)
		(pad "1" smd rect
			(at 0 0 180)
			(size 0.889 0.9906)
			(layers "B.Cu" "B.Mask" "B.Paste")
			(net "PVDDQ_KLM")
		)
		(pad "2" smd rect
			(at 0 1.397 180)
			(size 0.889 0.9906)
			(layers "B.Cu" "B.Mask" "B.Paste")
			(net "GND")
		)
		(zone
			(layer "B.Cu")
			(hatch none 0.5)
			(connect_pads
				(clearance 0)
			)
			(min_thickness 0.25)
			(keepout
				(tracks allowed)
				(vias not_allowed)
				(pads allowed)
				(copperpour not_allowed)
				(footprints allowed)
			)
			(placement
				(enabled no)
				(sheetname "")
			)
			(fill
				(thermal_gap 0.5)
				(thermal_bridge_width 0.5)
				(island_removal_mode 0)
			)
			(polygon
				(pts
					(xy 79.804768 -134.9121) (xy 80.312768 -134.9121) (xy 80.312768 -135.9027) (xy 79.804768 -135.9027)
				)
			)
		)
		(zone
			(layer "B.Cu")
			(hatch none 0.5)
			(connect_pads
				(clearance 0)
			)
			(min_thickness 0.25)
			(keepout
				(tracks not_allowed)
				(vias allowed)
				(pads allowed)
				(copperpour not_allowed)
				(footprints allowed)
			)
			(placement
				(enabled no)
				(sheetname "")
			)
			(fill
				(thermal_gap 0.5)
				(thermal_bridge_width 0.5)
				(island_removal_mode 0)
			)
			(polygon
				(pts
					(xy 79.804768 -134.9121) (xy 80.312768 -134.9121) (xy 80.312768 -135.9027) (xy 79.804768 -135.9027)
				)
			)
		)
	)
	(footprint ""
		(layer "B.Cu")
		(at 484.124 -145.6182 90)
		(property "Reference" "CR1L3"
			(at 0 0 90)
			(layer "B.SilkS")
			(hide yes)
			(effects
				(font
					(size 1.27 1.27)
				)
				(justify mirror)
			)
		)
		(property "Value" ""
			(at 0 0 90)
			(layer "B.Fab")
			(effects
				(font
					(size 1.27 1.27)
				)
				(justify mirror)
			)
		)
		(duplicate_pad_numbers_are_jumpers no)
		(fp_line
			(start 0.9144 0.1016)
			(end 0.9144 2.9464)
			(stroke
				(width 0.1524)
				(type default)
			)
			(layer "B.SilkS")
		)
		(fp_line
			(start 0.8382 0.1016)
			(end 0.9144 0.1016)
			(stroke
				(width 0.1524)
				(type default)
			)
			(layer "B.SilkS")
		)
		(fp_line
			(start -0.8382 0.1016)
			(end -0.9144 0.1016)
			(stroke
				(width 0.1524)
				(type default)
			)
			(layer "B.SilkS")
		)
		(fp_line
			(start -0.9144 0.1016)
			(end -0.9144 2.9464)
			(stroke
				(width 0.1524)
				(type default)
			)
			(layer "B.SilkS")
		)
		(fp_line
			(start 0.9144 2.9464)
			(end 0.8382 2.9464)
			(stroke
				(width 0.1524)
				(type default)
			)
			(layer "B.SilkS")
		)
		(fp_line
			(start -0.9144 2.9464)
			(end -0.8382 2.9464)
			(stroke
				(width 0.1524)
				(type default)
			)
			(layer "B.SilkS")
		)
		(fp_circle
			(center -1.128776 -0.907288)
			(end -1.128776 -0.780288)
			(stroke
				(width 0.254)
				(type default)
			)
			(fill no)
			(layer "B.SilkS")
		)
		(fp_poly
			(pts
				(xy 0 0.1016) (xy -0.5334 0.1016) (xy -0.7366 0.1016) (xy -0.9144 0.1016) (xy -0.9144 2.9464) (xy -0.8382 2.9464)
				(xy -0.762 2.9464) (xy 0.9144 2.9464) (xy 0.9144 2.7686) (xy 0.9144 2.159) (xy 0.9144 0.1016) (xy 0.7366 0.1016)
				(xy 0.5842 0.1016)
			)
			(stroke
				(width 0)
				(type default)
			)
			(fill no)
			(layer "B.CrtYd")
		)
		(fp_line
			(start 0.9144 0.1016)
			(end 0.9144 2.9464)
			(stroke
				(width 0.1)
				(type default)
			)
			(layer "B.Fab")
		)
		(fp_line
			(start -0.9144 0.1016)
			(end 0.9144 0.1016)
			(stroke
				(width 0.1)
				(type default)
			)
			(layer "B.Fab")
		)
		(fp_line
			(start 0.9144 2.9464)
			(end -0.9144 2.9464)
			(stroke
				(width 0.1)
				(type default)
			)
			(layer "B.Fab")
		)
		(fp_line
			(start -0.9144 2.9464)
			(end -0.9144 0.1016)
			(stroke
				(width 0.1)
				(type default)
			)
			(layer "B.Fab")
		)
		(fp_circle
			(center -1.128776 -0.907288)
			(end -1.128776 -0.780288)
			(stroke
				(width 0.254)
				(type default)
			)
			(fill no)
			(layer "B.Fab")
		)
		(pad "1" smd rect
			(at 0 0)
			(size 1.524 0.762)
			(layers "B.Cu" "B.Mask" "B.Paste")
			(net "FM_DB_UART_SEL3_N")
		)
		(pad "2" smd rect
			(at 0 3.048 180)
			(size 1.524 0.762)
			(layers "B.Cu" "B.Mask" "B.Paste")
			(net "FM_DB_UART_SEL2_N")
		)
	)
	(footprint ""
		(layer "B.Cu")
		(at 337.537806 -61.257434)
		(property "Reference" "C2U6"
			(at 0 0 0)
			(layer "B.SilkS")
			(hide yes)
			(effects
				(font
					(size 1.27 1.27)
				)
				(justify mirror)
			)
		)
		(property "Value" ""
			(at 0 0 0)
			(layer "B.Fab")
			(effects
				(font
					(size 1.27 1.27)
				)
				(justify mirror)
			)
		)
		(duplicate_pad_numbers_are_jumpers no)
		(fp_poly
			(pts
				(xy -0.3048 -0.1016) (xy -0.3048 0.9906) (xy 0.3048 0.9906) (xy 0.3048 -0.1016)
			)
			(stroke
				(width 0)
				(type default)
			)
			(fill no)
			(layer "B.CrtYd")
		)
		(fp_line
			(start -0.3048 -0.1016)
			(end 0.3048 -0.1016)
			(stroke
				(width 0.1)
				(type default)
			)
			(layer "B.Fab")
		)
		(fp_line
			(start -0.3048 0.9906)
			(end -0.3048 -0.1016)
			(stroke
				(width 0.1)
				(type default)
			)
			(layer "B.Fab")
		)
		(fp_line
			(start 0.3048 -0.1016)
			(end 0.3048 0.9906)
			(stroke
				(width 0.1)
				(type default)
			)
			(layer "B.Fab")
		)
		(fp_line
			(start 0.3048 0.9906)
			(end -0.3048 0.9906)
			(stroke
				(width 0.1)
				(type default)
			)
			(layer "B.Fab")
		)
		(pad "1" smd rect
			(at 0 0 180)
			(size 0.508 0.508)
			(layers "B.Cu" "B.Mask" "B.Paste")
			(net "P3E_CPU0_PE1_PCH_RXN<1>")
		)
		(pad "2" smd rect
			(at 0 0.889 180)
			(size 0.508 0.508)
			(layers "B.Cu" "B.Mask" "B.Paste")
			(net "P3E_CPU0_PE1_SS_RXN<1>")
		)
		(zone
			(layer "B.Cu")
			(hatch none 0.5)
			(connect_pads
				(clearance 0)
			)
			(min_thickness 0.25)
			(keepout
				(tracks allowed)
				(vias not_allowed)
				(pads allowed)
				(copperpour not_allowed)
				(footprints allowed)
			)
			(placement
				(enabled no)
				(sheetname "")
			)
			(fill
				(thermal_gap 0.5)
				(thermal_bridge_width 0.5)
				(island_removal_mode 0)
			)
			(polygon
				(pts
					(xy 337.791806 -61.003434) (xy 337.283806 -61.003434) (xy 337.283806 -60.622434) (xy 337.791806 -60.622434)
				)
			)
		)
		(zone
			(layer "B.Cu")
			(hatch none 0.5)
			(connect_pads
				(clearance 0)
			)
			(min_thickness 0.25)
			(keepout
				(tracks not_allowed)
				(vias allowed)
				(pads allowed)
				(copperpour not_allowed)
				(footprints allowed)
			)
			(placement
				(enabled no)
				(sheetname "")
			)
			(fill
				(thermal_gap 0.5)
				(thermal_bridge_width 0.5)
				(island_removal_mode 0)
			)
			(polygon
				(pts
					(xy 337.791806 -60.622434) (xy 337.283806 -60.622434) (xy 337.283806 -61.003434) (xy 337.791806 -61.003434)
				)
			)
		)
	)
	(footprint ""
		(layer "B.Cu")
		(at 489.26496 -151.06904 90)
		(property "Reference" "R1L19"
			(at 0 0 90)
			(layer "B.SilkS")
			(hide yes)
			(effects
				(font
					(size 1.27 1.27)
				)
				(justify mirror)
			)
		)
		(property "Value" ""
			(at 0 0 90)
			(layer "B.Fab")
			(effects
				(font
					(size 1.27 1.27)
				)
				(justify mirror)
			)
		)
		(duplicate_pad_numbers_are_jumpers no)
		(fp_poly
			(pts
				(xy 0.2794 -0.1016) (xy -0.2794 -0.1016) (xy -0.2794 0.9906) (xy 0.2794 0.9906)
			)
			(stroke
				(width 0)
				(type default)
			)
			(fill no)
			(layer "B.CrtYd")
		)
		(fp_line
			(start 0.2794 -0.1016)
			(end 0.2794 0.9906)
			(stroke
				(width 0.1)
				(type default)
			)
			(layer "B.Fab")
		)
		(fp_line
			(start -0.2794 -0.1016)
			(end 0.2794 -0.1016)
			(stroke
				(width 0.1)
				(type default)
			)
			(layer "B.Fab")
		)
		(fp_line
			(start 0.2794 0.9906)
			(end -0.2794 0.9906)
			(stroke
				(width 0.1)
				(type default)
			)
			(layer "B.Fab")
		)
		(fp_line
			(start -0.2794 0.9906)
			(end -0.2794 -0.1016)
			(stroke
				(width 0.1)
				(type default)
			)
			(layer "B.Fab")
		)
		(pad "1" smd rect
			(at 0 0 270)
			(size 0.508 0.508)
			(layers "B.Cu" "B.Mask" "B.Paste")
			(net "P3V3_STBY")
		)
		(pad "2" smd rect
			(at 0 0.889 270)
			(size 0.508 0.508)
			(layers "B.Cu" "B.Mask" "B.Paste")
			(net "FM_DEBUG_RST_BTN_N")
		)
		(zone
			(layer "B.Cu")
			(hatch none 0.5)
			(connect_pads
				(clearance 0)
			)
			(min_thickness 0.25)
			(keepout
				(tracks allowed)
				(vias not_allowed)
				(pads allowed)
				(copperpour not_allowed)
				(footprints allowed)
			)
			(placement
				(enabled no)
				(sheetname "")
			)
			(fill
				(thermal_gap 0.5)
				(thermal_bridge_width 0.5)
				(island_removal_mode 0)
			)
			(polygon
				(pts
					(xy 489.51896 -151.32304) (xy 489.51896 -150.81504) (xy 489.89996 -150.81504) (xy 489.89996 -151.32304)
				)
			)
		)
		(zone
			(layer "B.Cu")
			(hatch none 0.5)
			(connect_pads
				(clearance 0)
			)
			(min_thickness 0.25)
			(keepout
				(tracks not_allowed)
				(vias allowed)
				(pads allowed)
				(copperpour not_allowed)
				(footprints allowed)
			)
			(placement
				(enabled no)
				(sheetname "")
			)
			(fill
				(thermal_gap 0.5)
				(thermal_bridge_width 0.5)
				(island_removal_mode 0)
			)
			(polygon
				(pts
					(xy 489.89996 -151.32304) (xy 489.89996 -150.81504) (xy 489.51896 -150.81504) (xy 489.51896 -151.32304)
				)
			)
		)
	)
	(footprint ""
		(layer "B.Cu")
		(at 214.503 -59.17692 180)
		(property "Reference" "C6R7"
			(at 0 0 0)
			(layer "B.SilkS")
			(hide yes)
			(effects
				(font
					(size 1.27 1.27)
				)
				(justify mirror)
			)
		)
		(property "Value" ""
			(at 0 0 0)
			(layer "B.Fab")
			(effects
				(font
					(size 1.27 1.27)
				)
				(justify mirror)
			)
		)
		(duplicate_pad_numbers_are_jumpers no)
		(fp_poly
			(pts
				(xy 0.4953 -0.2032) (xy -0.4953 -0.2032) (xy -0.4953 1.6002) (xy 0.4953 1.6002)
			)
			(stroke
				(width 0)
				(type default)
			)
			(fill no)
			(layer "B.CrtYd")
		)
		(fp_line
			(start 0.4953 1.6002)
			(end 0.4953 -0.2032)
			(stroke
				(width 0.1)
				(type default)
			)
			(layer "B.Fab")
		)
		(fp_line
			(start 0.4953 -0.2032)
			(end -0.4953 -0.2032)
			(stroke
				(width 0.1)
				(type default)
			)
			(layer "B.Fab")
		)
		(fp_line
			(start -0.4953 1.6002)
			(end 0.4953 1.6002)
			(stroke
				(width 0.1)
				(type default)
			)
			(layer "B.Fab")
		)
		(fp_line
			(start -0.4953 -0.2032)
			(end -0.4953 1.6002)
			(stroke
				(width 0.1)
				(type default)
			)
			(layer "B.Fab")
		)
		(pad "1" smd rect
			(at 0 0)
			(size 0.762 0.889)
			(layers "B.Cu" "B.Mask" "B.Paste")
			(net "PVCCIN_CPU0")
		)
		(pad "2" smd rect
			(at 0 1.397)
			(size 0.762 0.889)
			(layers "B.Cu" "B.Mask" "B.Paste")
			(net "GND")
		)
		(zone
			(layer "B.Cu")
			(hatch none 0.5)
			(connect_pads
				(clearance 0)
			)
			(min_thickness 0.25)
			(keepout
				(tracks not_allowed)
				(vias allowed)
				(pads allowed)
				(copperpour not_allowed)
				(footprints allowed)
			)
			(placement
				(enabled no)
				(sheetname "")
			)
			(fill
				(thermal_gap 0.5)
				(thermal_bridge_width 0.5)
				(island_removal_mode 0)
			)
			(polygon
				(pts
					(xy 214.122 -59.62142) (xy 214.884 -59.62142) (xy 214.884 -60.12942) (xy 214.122 -60.12942)
				)
			)
		)
	)
	(footprint ""
		(layer "B.Cu")
		(at 446.53835 -29.6164)
		(property "Reference" "C25W11"
			(at 0.8382 -0.67818 0)
			(unlocked yes)
			(layer "B.SilkS")
			(effects
				(font
					(size 0.4064 0.254)
					(thickness 0.1524)
				)
				(justify left mirror)
			)
		)
		(property "Value" ""
			(at 0 0 0)
			(layer "B.Fab")
			(effects
				(font
					(size 1.27 1.27)
				)
				(justify mirror)
			)
		)
		(duplicate_pad_numbers_are_jumpers no)
		(fp_poly
			(pts
				(xy -0.3048 -0.1016) (xy -0.3048 0.9906) (xy 0.3048 0.9906) (xy 0.3048 -0.1016)
			)
			(stroke
				(width 0)
				(type default)
			)
			(fill no)
			(layer "B.CrtYd")
		)
		(fp_line
			(start -0.3048 -0.1016)
			(end 0.3048 -0.1016)
			(stroke
				(width 0.1)
				(type default)
			)
			(layer "B.Fab")
		)
		(fp_line
			(start -0.3048 0.9906)
			(end -0.3048 -0.1016)
			(stroke
				(width 0.1)
				(type default)
			)
			(layer "B.Fab")
		)
		(fp_line
			(start 0.3048 -0.1016)
			(end 0.3048 0.9906)
			(stroke
				(width 0.1)
				(type default)
			)
			(layer "B.Fab")
		)
		(fp_line
			(start 0.3048 0.9906)
			(end -0.3048 0.9906)
			(stroke
				(width 0.1)
				(type default)
			)
			(layer "B.Fab")
		)
		(pad "1" smd rect
			(at 0 0 180)
			(size 0.508 0.508)
			(layers "B.Cu" "B.Mask" "B.Paste")
			(net "BMC_M_VREFCA")
		)
		(pad "2" smd rect
			(at 0 0.889 180)
			(size 0.508 0.508)
			(layers "B.Cu" "B.Mask" "B.Paste")
			(net "GND")
		)
		(zone
			(layer "B.Cu")
			(hatch none 0.5)
			(connect_pads
				(clearance 0)
			)
			(min_thickness 0.25)
			(keepout
				(tracks allowed)
				(vias not_allowed)
				(pads allowed)
				(copperpour not_allowed)
				(footprints allowed)
			)
			(placement
				(enabled no)
				(sheetname "")
			)
			(fill
				(thermal_gap 0.5)
				(thermal_bridge_width 0.5)
				(island_removal_mode 0)
			)
			(polygon
				(pts
					(xy 446.79235 -29.3624) (xy 446.28435 -29.3624) (xy 446.28435 -28.9814) (xy 446.79235 -28.9814)
				)
			)
		)
		(zone
			(layer "B.Cu")
			(hatch none 0.5)
			(connect_pads
				(clearance 0)
			)
			(min_thickness 0.25)
			(keepout
				(tracks not_allowed)
				(vias allowed)
				(pads allowed)
				(copperpour not_allowed)
				(footprints allowed)
			)
			(placement
				(enabled no)
				(sheetname "")
			)
			(fill
				(thermal_gap 0.5)
				(thermal_bridge_width 0.5)
				(island_removal_mode 0)
			)
			(polygon
				(pts
					(xy 446.79235 -28.9814) (xy 446.28435 -28.9814) (xy 446.28435 -29.3624) (xy 446.79235 -29.3624)
				)
			)
		)
	)
	(footprint ""
		(layer "B.Cu")
		(at 405.3586 -34.313368 90)
		(property "Reference" "R25W121"
			(at 0.8382 -0.67818 90)
			(unlocked yes)
			(layer "B.SilkS")
			(effects
				(font
					(size 0.4064 0.254)
					(thickness 0.1524)
				)
				(justify left mirror)
			)
		)
		(property "Value" ""
			(at 0 0 90)
			(layer "B.Fab")
			(effects
				(font
					(size 1.27 1.27)
				)
				(justify mirror)
			)
		)
		(duplicate_pad_numbers_are_jumpers no)
		(fp_poly
			(pts
				(xy 0.2794 -0.1016) (xy -0.2794 -0.1016) (xy -0.2794 0.9906) (xy 0.2794 0.9906)
			)
			(stroke
				(width 0)
				(type default)
			)
			(fill no)
			(layer "B.CrtYd")
		)
		(fp_line
			(start 0.2794 -0.1016)
			(end 0.2794 0.9906)
			(stroke
				(width 0.1)
				(type default)
			)
			(layer "B.Fab")
		)
		(fp_line
			(start -0.2794 -0.1016)
			(end 0.2794 -0.1016)
			(stroke
				(width 0.1)
				(type default)
			)
			(layer "B.Fab")
		)
		(fp_line
			(start 0.2794 0.9906)
			(end -0.2794 0.9906)
			(stroke
				(width 0.1)
				(type default)
			)
			(layer "B.Fab")
		)
		(fp_line
			(start -0.2794 0.9906)
			(end -0.2794 -0.1016)
			(stroke
				(width 0.1)
				(type default)
			)
			(layer "B.Fab")
		)
		(pad "1" smd rect
			(at 0 0 270)
			(size 0.508 0.508)
			(layers "B.Cu" "B.Mask" "B.Paste")
			(net "SMB_PEHPCPU0_STBY_LVC3_R_SDA")
		)
		(pad "2" smd rect
			(at 0 0.889 270)
			(size 0.508 0.508)
			(layers "B.Cu" "B.Mask" "B.Paste")
			(net "SMB_PEHPCPU0_STBY_LVC3_R2_SDA")
		)
		(zone
			(layer "B.Cu")
			(hatch none 0.5)
			(connect_pads
				(clearance 0)
			)
			(min_thickness 0.25)
			(keepout
				(tracks allowed)
				(vias not_allowed)
				(pads allowed)
				(copperpour not_allowed)
				(footprints allowed)
			)
			(placement
				(enabled no)
				(sheetname "")
			)
			(fill
				(thermal_gap 0.5)
				(thermal_bridge_width 0.5)
				(island_removal_mode 0)
			)
			(polygon
				(pts
					(xy 405.6126 -34.567368) (xy 405.6126 -34.059368) (xy 405.9936 -34.059368) (xy 405.9936 -34.567368)
				)
			)
		)
		(zone
			(layer "B.Cu")
			(hatch none 0.5)
			(connect_pads
				(clearance 0)
			)
			(min_thickness 0.25)
			(keepout
				(tracks not_allowed)
				(vias allowed)
				(pads allowed)
				(copperpour not_allowed)
				(footprints allowed)
			)
			(placement
				(enabled no)
				(sheetname "")
			)
			(fill
				(thermal_gap 0.5)
				(thermal_bridge_width 0.5)
				(island_removal_mode 0)
			)
			(polygon
				(pts
					(xy 405.9936 -34.567368) (xy 405.9936 -34.059368) (xy 405.6126 -34.059368) (xy 405.6126 -34.567368)
				)
			)
		)
	)
	(footprint ""
		(layer "B.Cu")
		(at 99.034854 -73.51014)
		(property "Reference" "C8P26"
			(at 0 0 0)
			(layer "B.SilkS")
			(hide yes)
			(effects
				(font
					(size 1.27 1.27)
				)
				(justify mirror)
			)
		)
		(property "Value" ""
			(at 0 0 0)
			(layer "B.Fab")
			(effects
				(font
					(size 1.27 1.27)
				)
				(justify mirror)
			)
		)
		(duplicate_pad_numbers_are_jumpers no)
		(fp_poly
			(pts
				(xy 0.7239 -0.2159) (xy -0.7239 -0.2159) (xy -0.7239 1.9939) (xy 0.7239 1.9939)
			)
			(stroke
				(width 0)
				(type default)
			)
			(fill no)
			(layer "B.CrtYd")
		)
		(fp_line
			(start -0.7239 -0.2159)
			(end 0.7239 -0.2159)
			(stroke
				(width 0.1)
				(type default)
			)
			(layer "B.Fab")
		)
		(fp_line
			(start -0.7239 1.9939)
			(end -0.7239 -0.2159)
			(stroke
				(width 0.1)
				(type default)
			)
			(layer "B.Fab")
		)
		(fp_line
			(start 0.7239 -0.2159)
			(end 0.7239 1.9939)
			(stroke
				(width 0.1)
				(type default)
			)
			(layer "B.Fab")
		)
		(fp_line
			(start 0.7239 1.9939)
			(end -0.7239 1.9939)
			(stroke
				(width 0.1)
				(type default)
			)
			(layer "B.Fab")
		)
		(pad "1" smd rect
			(at 0 0 180)
			(size 1.27 1.016)
			(layers "B.Cu" "B.Mask" "B.Paste")
			(net "PVCCIN_CPU1")
		)
		(pad "2" smd rect
			(at 0 1.778 180)
			(size 1.27 1.016)
			(layers "B.Cu" "B.Mask" "B.Paste")
			(net "GND")
		)
		(zone
			(layer "B.Cu")
			(hatch none 0.5)
			(connect_pads
				(clearance 0)
			)
			(min_thickness 0.25)
			(keepout
				(tracks not_allowed)
				(vias allowed)
				(pads allowed)
				(copperpour not_allowed)
				(footprints allowed)
			)
			(placement
				(enabled no)
				(sheetname "")
			)
			(fill
				(thermal_gap 0.5)
				(thermal_bridge_width 0.5)
				(island_removal_mode 0)
			)
			(polygon
				(pts
					(xy 99.669854 -73.00214) (xy 98.399854 -73.00214) (xy 98.399854 -72.24014) (xy 99.669854 -72.24014)
				)
			)
		)
	)
	(footprint ""
		(layer "B.Cu")
		(at 379.984 -87.3125 180)
		(property "Reference" "R7D3"
			(at 0 0 0)
			(layer "B.SilkS")
			(hide yes)
			(effects
				(font
					(size 1.27 1.27)
				)
				(justify mirror)
			)
		)
		(property "Value" ""
			(at 0 0 0)
			(layer "B.Fab")
			(effects
				(font
					(size 1.27 1.27)
				)
				(justify mirror)
			)
		)
		(duplicate_pad_numbers_are_jumpers no)
		(fp_poly
			(pts
				(xy 0.2794 -0.1016) (xy -0.2794 -0.1016) (xy -0.2794 0.9906) (xy 0.2794 0.9906)
			)
			(stroke
				(width 0)
				(type default)
			)
			(fill no)
			(layer "B.CrtYd")
		)
		(fp_line
			(start 0.2794 0.9906)
			(end -0.2794 0.9906)
			(stroke
				(width 0.1)
				(type default)
			)
			(layer "B.Fab")
		)
		(fp_line
			(start 0.2794 -0.1016)
			(end 0.2794 0.9906)
			(stroke
				(width 0.1)
				(type default)
			)
			(layer "B.Fab")
		)
		(fp_line
			(start -0.2794 0.9906)
			(end -0.2794 -0.1016)
			(stroke
				(width 0.1)
				(type default)
			)
			(layer "B.Fab")
		)
		(fp_line
			(start -0.2794 -0.1016)
			(end 0.2794 -0.1016)
			(stroke
				(width 0.1)
				(type default)
			)
			(layer "B.Fab")
		)
		(pad "1" smd rect
			(at 0 0)
			(size 0.508 0.508)
			(layers "B.Cu" "B.Mask" "B.Paste")
			(net "P3V3_STBY")
		)
		(pad "2" smd rect
			(at 0 0.889)
			(size 0.508 0.508)
			(layers "B.Cu" "B.Mask" "B.Paste")
			(net "IRQ_LPC_SERIRQ_N")
		)
		(zone
			(layer "B.Cu")
			(hatch none 0.5)
			(connect_pads
				(clearance 0)
			)
			(min_thickness 0.25)
			(keepout
				(tracks not_allowed)
				(vias allowed)
				(pads allowed)
				(copperpour not_allowed)
				(footprints allowed)
			)
			(placement
				(enabled no)
				(sheetname "")
			)
			(fill
				(thermal_gap 0.5)
				(thermal_bridge_width 0.5)
				(island_removal_mode 0)
			)
			(polygon
				(pts
					(xy 379.73 -87.9475) (xy 380.238 -87.9475) (xy 380.238 -87.5665) (xy 379.73 -87.5665)
				)
			)
		)
		(zone
			(layer "B.Cu")
			(hatch none 0.5)
			(connect_pads
				(clearance 0)
			)
			(min_thickness 0.25)
			(keepout
				(tracks allowed)
				(vias not_allowed)
				(pads allowed)
				(copperpour not_allowed)
				(footprints allowed)
			)
			(placement
				(enabled no)
				(sheetname "")
			)
			(fill
				(thermal_gap 0.5)
				(thermal_bridge_width 0.5)
				(island_removal_mode 0)
			)
			(polygon
				(pts
					(xy 379.73 -87.5665) (xy 380.238 -87.5665) (xy 380.238 -87.9475) (xy 379.73 -87.9475)
				)
			)
		)
	)
	(footprint ""
		(layer "B.Cu")
		(at 245.7323 -140.208 -90)
		(property "Reference" "C5G64"
			(at -1.14681 0.76708 0)
			(unlocked yes)
			(layer "B.SilkS")
			(effects
				(font
					(size 0.7874 0.5842)
					(thickness 0.1524)
				)
				(justify mirror)
			)
		)
		(property "Value" ""
			(at 0 0 90)
			(layer "B.Fab")
			(effects
				(font
					(size 1.27 1.27)
				)
				(justify mirror)
			)
		)
		(duplicate_pad_numbers_are_jumpers no)
		(fp_rect
			(start 0.4953 1.6002)
			(end -0.4953 -0.2032)
			(stroke
				(width 0)
				(type default)
			)
			(fill no)
			(layer "B.CrtYd")
		)
		(fp_line
			(start -0.4953 1.6002)
			(end 0.4953 1.6002)
			(stroke
				(width 0.1)
				(type default)
			)
			(layer "B.Fab")
		)
		(fp_line
			(start 0.4953 1.6002)
			(end 0.4953 -0.2032)
			(stroke
				(width 0.1)
				(type default)
			)
			(layer "B.Fab")
		)
		(fp_line
			(start -0.4953 -0.2032)
			(end -0.4953 1.6002)
			(stroke
				(width 0.1)
				(type default)
			)
			(layer "B.Fab")
		)
		(fp_line
			(start 0.4953 -0.2032)
			(end -0.4953 -0.2032)
			(stroke
				(width 0.1)
				(type default)
			)
			(layer "B.Fab")
		)
		(pad "1" smd rect
			(at 0 0 90)
			(size 0.762 0.889)
			(layers "B.Cu" "B.Mask" "B.Paste")
			(net "PVDDQ_DEF")
		)
		(pad "2" smd rect
			(at 0 1.397 90)
			(size 0.762 0.889)
			(layers "B.Cu" "B.Mask" "B.Paste")
			(net "GND")
		)
		(zone
			(layer "B.Cu")
			(hatch none 0.5)
			(connect_pads
				(clearance 0)
			)
			(min_thickness 0.25)
			(keepout
				(tracks not_allowed)
				(vias allowed)
				(pads allowed)
				(copperpour not_allowed)
				(footprints allowed)
			)
			(placement
				(enabled no)
				(sheetname "")
			)
			(fill
				(thermal_gap 0.5)
				(thermal_bridge_width 0.5)
				(island_removal_mode 0)
			)
			(polygon
				(pts
					(xy 244.7798 -139.827) (xy 245.2878 -139.827) (xy 245.2878 -140.589) (xy 244.7798 -140.589)
				)
			)
		)
	)
	(footprint ""
		(layer "B.Cu")
		(at 496.919504 -35.458146 180)
		(property "Reference" "U9F2"
			(at 0.4064 2.41427 180)
			(unlocked yes)
			(layer "B.SilkS")
			(effects
				(font
					(size 0.7874 0.5842)
					(thickness 0.1524)
				)
				(justify mirror)
			)
		)
		(property "Value" ""
			(at 0 0 0)
			(layer "B.Fab")
			(effects
				(font
					(size 1.27 1.27)
				)
				(justify mirror)
			)
		)
		(duplicate_pad_numbers_are_jumpers no)
		(fp_line
			(start -1.269238 1.8034)
			(end -1.77673 1.8034)
			(stroke
				(width 0.1524)
				(type default)
			)
			(layer "B.SilkS")
		)
		(fp_line
			(start -1.269238 -0.3048)
			(end -1.77673 -0.3048)
			(stroke
				(width 0.1524)
				(type default)
			)
			(layer "B.SilkS")
		)
		(fp_circle
			(center 0.967994 -0.635)
			(end 0.840994 -0.635)
			(stroke
				(width 0.254)
				(type default)
			)
			(fill no)
			(layer "B.SilkS")
		)
		(fp_rect
			(start -0.3302 1.8034)
			(end -2.7432 -0.3048)
			(stroke
				(width 0)
				(type default)
			)
			(fill no)
			(layer "B.CrtYd")
		)
		(fp_line
			(start -0.3302 1.8034)
			(end -0.3302 -0.3048)
			(stroke
				(width 0.1)
				(type default)
			)
			(layer "B.Fab")
		)
		(fp_line
			(start -0.3302 -0.3048)
			(end -2.7432 -0.3048)
			(stroke
				(width 0.1)
				(type default)
			)
			(layer "B.Fab")
		)
		(fp_line
			(start -2.7432 1.8034)
			(end -0.3302 1.8034)
			(stroke
				(width 0.1)
				(type default)
			)
			(layer "B.Fab")
		)
		(fp_line
			(start -2.7432 -0.3048)
			(end -2.7432 1.8034)
			(stroke
				(width 0.1)
				(type default)
			)
			(layer "B.Fab")
		)
		(fp_circle
			(center 0.967994 -0.635)
			(end 0.840994 -0.635)
			(stroke
				(width 0.254)
				(type default)
			)
			(fill no)
			(layer "B.Fab")
		)
		(pad "1" smd rect
			(at 0 0)
			(size 1.524 0.254)
			(layers "B.Cu" "B.Mask" "B.Paste")
			(net "SP2_BMC_CM_UART_TX_R")
		)
		(pad "2" smd rect
			(at 0 0.499872)
			(size 1.524 0.254)
			(layers "B.Cu" "B.Mask" "B.Paste")
			(net "UART_BMC_TXD5")
		)
		(pad "3" smd rect
			(at 0 0.999744)
			(size 1.524 0.254)
			(layers "B.Cu" "B.Mask" "B.Paste")
			(net "SP1_BMC_HOST_UART_TX")
		)
		(pad "4" smd rect
			(at 0 1.499616)
			(size 1.524 0.254)
			(layers "B.Cu" "B.Mask" "B.Paste")
			(net "GND")
		)
		(pad "5" smd rect
			(at -3.048 1.499616)
			(size 1.524 0.254)
			(layers "B.Cu" "B.Mask" "B.Paste")
			(net "FM_UARTSW_MSB_N")
		)
		(pad "6" smd rect
			(at -3.048 0.999744)
			(size 1.524 0.254)
			(layers "B.Cu" "B.Mask" "B.Paste")
			(net "FM_UARTSW_LSB_N")
		)
		(pad "7" smd rect
			(at -3.048 0.499872)
			(size 1.524 0.254)
			(layers "B.Cu" "B.Mask" "B.Paste")
			(net "UART_MUX_OUT_R")
		)
		(pad "8" smd rect
			(at -3.048 0)
			(size 1.524 0.254)
			(layers "B.Cu" "B.Mask" "B.Paste")
			(net "P3V3_STBY")
		)
	)
	(footprint ""
		(layer "B.Cu")
		(at 162.687 -83.058 90)
		(property "Reference" "R7P3"
			(at 0 0 90)
			(layer "B.SilkS")
			(hide yes)
			(effects
				(font
					(size 1.27 1.27)
				)
				(justify mirror)
			)
		)
		(property "Value" ""
			(at 0 0 90)
			(layer "B.Fab")
			(effects
				(font
					(size 1.27 1.27)
				)
				(justify mirror)
			)
		)
		(duplicate_pad_numbers_are_jumpers no)
		(fp_poly
			(pts
				(xy 0.2794 -0.1016) (xy -0.2794 -0.1016) (xy -0.2794 0.9906) (xy 0.2794 0.9906)
			)
			(stroke
				(width 0)
				(type default)
			)
			(fill no)
			(layer "B.CrtYd")
		)
		(fp_line
			(start 0.2794 -0.1016)
			(end 0.2794 0.9906)
			(stroke
				(width 0.1)
				(type default)
			)
			(layer "B.Fab")
		)
		(fp_line
			(start -0.2794 -0.1016)
			(end 0.2794 -0.1016)
			(stroke
				(width 0.1)
				(type default)
			)
			(layer "B.Fab")
		)
		(fp_line
			(start 0.2794 0.9906)
			(end -0.2794 0.9906)
			(stroke
				(width 0.1)
				(type default)
			)
			(layer "B.Fab")
		)
		(fp_line
			(start -0.2794 0.9906)
			(end -0.2794 -0.1016)
			(stroke
				(width 0.1)
				(type default)
			)
			(layer "B.Fab")
		)
		(pad "1" smd rect
			(at 0 0 270)
			(size 0.508 0.508)
			(layers "B.Cu" "B.Mask" "B.Paste")
			(net "CLK_100M_CPU1_PE_REFCLK_DP")
		)
		(pad "2" smd rect
			(at 0 0.889 270)
			(size 0.508 0.508)
			(layers "B.Cu" "B.Mask" "B.Paste")
			(net "GND")
		)
		(zone
			(layer "B.Cu")
			(hatch none 0.5)
			(connect_pads
				(clearance 0)
			)
			(min_thickness 0.25)
			(keepout
				(tracks allowed)
				(vias not_allowed)
				(pads allowed)
				(copperpour not_allowed)
				(footprints allowed)
			)
			(placement
				(enabled no)
				(sheetname "")
			)
			(fill
				(thermal_gap 0.5)
				(thermal_bridge_width 0.5)
				(island_removal_mode 0)
			)
			(polygon
				(pts
					(xy 162.941 -83.312) (xy 162.941 -82.804) (xy 163.322 -82.804) (xy 163.322 -83.312)
				)
			)
		)
		(zone
			(layer "B.Cu")
			(hatch none 0.5)
			(connect_pads
				(clearance 0)
			)
			(min_thickness 0.25)
			(keepout
				(tracks not_allowed)
				(vias allowed)
				(pads allowed)
				(copperpour not_allowed)
				(footprints allowed)
			)
			(placement
				(enabled no)
				(sheetname "")
			)
			(fill
				(thermal_gap 0.5)
				(thermal_bridge_width 0.5)
				(island_removal_mode 0)
			)
			(polygon
				(pts
					(xy 163.322 -83.312) (xy 163.322 -82.804) (xy 162.941 -82.804) (xy 162.941 -83.312)
				)
			)
		)
	)
	(footprint ""
		(layer "B.Cu")
		(at 197.848728 -76.157582 90)
		(property "Reference" "C6P17"
			(at 0 0 90)
			(layer "B.SilkS")
			(hide yes)
			(effects
				(font
					(size 1.27 1.27)
				)
				(justify mirror)
			)
		)
		(property "Value" ""
			(at 0 0 90)
			(layer "B.Fab")
			(effects
				(font
					(size 1.27 1.27)
				)
				(justify mirror)
			)
		)
		(duplicate_pad_numbers_are_jumpers no)
		(fp_rect
			(start -0.7239 -0.2159)
			(end 0.7239 1.9939)
			(stroke
				(width 0)
				(type default)
			)
			(fill no)
			(layer "B.CrtYd")
		)
		(fp_line
			(start 0.7239 -0.2159)
			(end 0.7239 1.9939)
			(stroke
				(width 0.1)
				(type default)
			)
			(layer "B.Fab")
		)
		(fp_line
			(start -0.7239 -0.2159)
			(end 0.7239 -0.2159)
			(stroke
				(width 0.1)
				(type default)
			)
			(layer "B.Fab")
		)
		(fp_line
			(start 0.7239 1.9939)
			(end -0.7239 1.9939)
			(stroke
				(width 0.1)
				(type default)
			)
			(layer "B.Fab")
		)
		(fp_line
			(start -0.7239 1.9939)
			(end -0.7239 -0.2159)
			(stroke
				(width 0.1)
				(type default)
			)
			(layer "B.Fab")
		)
		(pad "1" smd rect
			(at 0 0 270)
			(size 1.27 1.016)
			(layers "B.Cu" "B.Mask" "B.Paste")
			(net "VR_FET_SW_P12V_STBY_PVCCIN_CPU0")
		)
		(pad "2" smd rect
			(at 0 1.778 270)
			(size 1.27 1.016)
			(layers "B.Cu" "B.Mask" "B.Paste")
			(net "GND")
		)
		(zone
			(layer "B.Cu")
			(hatch none 0.5)
			(connect_pads
				(clearance 0)
			)
			(min_thickness 0.25)
			(keepout
				(tracks not_allowed)
				(vias allowed)
				(pads allowed)
				(copperpour not_allowed)
				(footprints allowed)
			)
			(placement
				(enabled no)
				(sheetname "")
			)
			(fill
				(thermal_gap 0.5)
				(thermal_bridge_width 0.5)
				(island_removal_mode 0)
			)
			(polygon
				(pts
					(xy 198.356728 -75.522582) (xy 199.118728 -75.522582) (xy 199.118728 -76.792582) (xy 198.356728 -76.792582)
				)
			)
		)
	)
	(footprint ""
		(layer "B.Cu")
		(at 439.02884 -21.29282 90)
		(property "Reference" "R3W5"
			(at 0.8382 -0.67818 90)
			(unlocked yes)
			(layer "B.SilkS")
			(effects
				(font
					(size 0.4064 0.254)
					(thickness 0.1524)
				)
				(justify left mirror)
			)
		)
		(property "Value" ""
			(at 0 0 90)
			(layer "B.Fab")
			(effects
				(font
					(size 1.27 1.27)
				)
				(justify mirror)
			)
		)
		(duplicate_pad_numbers_are_jumpers no)
		(fp_poly
			(pts
				(xy 0.2794 -0.1016) (xy -0.2794 -0.1016) (xy -0.2794 0.9906) (xy 0.2794 0.9906)
			)
			(stroke
				(width 0)
				(type default)
			)
			(fill no)
			(layer "B.CrtYd")
		)
		(fp_line
			(start 0.2794 -0.1016)
			(end 0.2794 0.9906)
			(stroke
				(width 0.1)
				(type default)
			)
			(layer "B.Fab")
		)
		(fp_line
			(start -0.2794 -0.1016)
			(end 0.2794 -0.1016)
			(stroke
				(width 0.1)
				(type default)
			)
			(layer "B.Fab")
		)
		(fp_line
			(start 0.2794 0.9906)
			(end -0.2794 0.9906)
			(stroke
				(width 0.1)
				(type default)
			)
			(layer "B.Fab")
		)
		(fp_line
			(start -0.2794 0.9906)
			(end -0.2794 -0.1016)
			(stroke
				(width 0.1)
				(type default)
			)
			(layer "B.Fab")
		)
		(pad "1" smd rect
			(at 0 0 270)
			(size 0.508 0.508)
			(layers "B.Cu" "B.Mask" "B.Paste")
			(net "P3V3_STBY")
		)
		(pad "2" smd rect
			(at 0 0.889 270)
			(size 0.508 0.508)
			(layers "B.Cu" "B.Mask" "B.Paste")
			(net "FM_TPM_PRES_RST")
		)
		(zone
			(layer "B.Cu")
			(hatch none 0.5)
			(connect_pads
				(clearance 0)
			)
			(min_thickness 0.25)
			(keepout
				(tracks allowed)
				(vias not_allowed)
				(pads allowed)
				(copperpour not_allowed)
				(footprints allowed)
			)
			(placement
				(enabled no)
				(sheetname "")
			)
			(fill
				(thermal_gap 0.5)
				(thermal_bridge_width 0.5)
				(island_removal_mode 0)
			)
			(polygon
				(pts
					(xy 439.28284 -21.54682) (xy 439.28284 -21.03882) (xy 439.66384 -21.03882) (xy 439.66384 -21.54682)
				)
			)
		)
		(zone
			(layer "B.Cu")
			(hatch none 0.5)
			(connect_pads
				(clearance 0)
			)
			(min_thickness 0.25)
			(keepout
				(tracks not_allowed)
				(vias allowed)
				(pads allowed)
				(copperpour not_allowed)
				(footprints allowed)
			)
			(placement
				(enabled no)
				(sheetname "")
			)
			(fill
				(thermal_gap 0.5)
				(thermal_bridge_width 0.5)
				(island_removal_mode 0)
			)
			(polygon
				(pts
					(xy 439.66384 -21.54682) (xy 439.66384 -21.03882) (xy 439.28284 -21.03882) (xy 439.28284 -21.54682)
				)
			)
		)
	)
	(footprint ""
		(layer "B.Cu")
		(at 362.1024 -133.0198 180)
		(property "Reference" "R3M5"
			(at 0 0 0)
			(layer "B.SilkS")
			(hide yes)
			(effects
				(font
					(size 1.27 1.27)
				)
				(justify mirror)
			)
		)
		(property "Value" ""
			(at 0 0 0)
			(layer "B.Fab")
			(effects
				(font
					(size 1.27 1.27)
				)
				(justify mirror)
			)
		)
		(duplicate_pad_numbers_are_jumpers no)
		(fp_poly
			(pts
				(xy 0.2794 -0.1016) (xy -0.2794 -0.1016) (xy -0.2794 0.9906) (xy 0.2794 0.9906)
			)
			(stroke
				(width 0)
				(type default)
			)
			(fill no)
			(layer "B.CrtYd")
		)
		(fp_line
			(start 0.2794 0.9906)
			(end -0.2794 0.9906)
			(stroke
				(width 0.1)
				(type default)
			)
			(layer "B.Fab")
		)
		(fp_line
			(start 0.2794 -0.1016)
			(end 0.2794 0.9906)
			(stroke
				(width 0.1)
				(type default)
			)
			(layer "B.Fab")
		)
		(fp_line
			(start -0.2794 0.9906)
			(end -0.2794 -0.1016)
			(stroke
				(width 0.1)
				(type default)
			)
			(layer "B.Fab")
		)
		(fp_line
			(start -0.2794 -0.1016)
			(end 0.2794 -0.1016)
			(stroke
				(width 0.1)
				(type default)
			)
			(layer "B.Fab")
		)
		(pad "1" smd rect
			(at 0 0)
			(size 0.508 0.508)
			(layers "B.Cu" "B.Mask" "B.Paste")
			(net "P3V3_STBY")
		)
		(pad "2" smd rect
			(at 0 0.889)
			(size 0.508 0.508)
			(layers "B.Cu" "B.Mask" "B.Paste")
			(net "VR_PVDDQ_DEF_VREN")
		)
		(zone
			(layer "B.Cu")
			(hatch none 0.5)
			(connect_pads
				(clearance 0)
			)
			(min_thickness 0.25)
			(keepout
				(tracks not_allowed)
				(vias allowed)
				(pads allowed)
				(copperpour not_allowed)
				(footprints allowed)
			)
			(placement
				(enabled no)
				(sheetname "")
			)
			(fill
				(thermal_gap 0.5)
				(thermal_bridge_width 0.5)
				(island_removal_mode 0)
			)
			(polygon
				(pts
					(xy 361.8484 -133.6548) (xy 362.3564 -133.6548) (xy 362.3564 -133.2738) (xy 361.8484 -133.2738)
				)
			)
		)
		(zone
			(layer "B.Cu")
			(hatch none 0.5)
			(connect_pads
				(clearance 0)
			)
			(min_thickness 0.25)
			(keepout
				(tracks allowed)
				(vias not_allowed)
				(pads allowed)
				(copperpour not_allowed)
				(footprints allowed)
			)
			(placement
				(enabled no)
				(sheetname "")
			)
			(fill
				(thermal_gap 0.5)
				(thermal_bridge_width 0.5)
				(island_removal_mode 0)
			)
			(polygon
				(pts
					(xy 361.8484 -133.2738) (xy 362.3564 -133.2738) (xy 362.3564 -133.6548) (xy 361.8484 -133.6548)
				)
			)
		)
	)
	(footprint ""
		(layer "B.Cu")
		(at 385.33705 -107.85475 90)
		(property "Reference" "C3N17"
			(at 0 0 90)
			(layer "B.SilkS")
			(hide yes)
			(effects
				(font
					(size 1.27 1.27)
				)
				(justify mirror)
			)
		)
		(property "Value" ""
			(at 0 0 90)
			(layer "B.Fab")
			(effects
				(font
					(size 1.27 1.27)
				)
				(justify mirror)
			)
		)
		(duplicate_pad_numbers_are_jumpers no)
		(fp_rect
			(start 0.2794 0.9144)
			(end -0.2794 -0.1143)
			(stroke
				(width 0)
				(type default)
			)
			(fill no)
			(layer "B.CrtYd")
		)
		(fp_line
			(start 0.2794 -0.1143)
			(end -0.2794 -0.1143)
			(stroke
				(width 0.1)
				(type default)
			)
			(layer "B.Fab")
		)
		(fp_line
			(start -0.2794 -0.1143)
			(end -0.2794 0.9144)
			(stroke
				(width 0.1)
				(type default)
			)
			(layer "B.Fab")
		)
		(fp_line
			(start 0.2794 0.9144)
			(end 0.2794 -0.1143)
			(stroke
				(width 0.1)
				(type default)
			)
			(layer "B.Fab")
		)
		(fp_line
			(start -0.2794 0.9144)
			(end 0.2794 0.9144)
			(stroke
				(width 0.1)
				(type default)
			)
			(layer "B.Fab")
		)
		(pad "1" smd custom
			(at 0 0)
			(size 0.10414 0.10414)
			(layers "B.Cu" "B.Mask" "B.Paste")
			(net "PVNN_PCH_STBY")
			(options
				(clearance outline)
				(anchor circle)
			)
			(primitives
				(gr_poly
					(pts
						(xy -0.20828 -0.08636) (xy -0.20828 0.08636) (xy -0.08636 0.20828) (xy 0.086614 0.20828) (xy 0.20828 0.086614)
						(xy 0.20828 -0.08636) (xy 0.08636 -0.20828) (xy -0.08636 -0.20828)
					)
					(width 0)
					(fill yes)
				)
			)
		)
		(pad "2" smd custom
			(at 0 0.8001)
			(size 0.10414 0.10414)
			(layers "B.Cu" "B.Mask" "B.Paste")
			(net "GND")
			(options
				(clearance outline)
				(anchor circle)
			)
			(primitives
				(gr_poly
					(pts
						(xy -0.20828 -0.08636) (xy -0.20828 0.08636) (xy -0.08636 0.20828) (xy 0.086614 0.20828) (xy 0.20828 0.086614)
						(xy 0.20828 -0.08636) (xy 0.08636 -0.20828) (xy -0.08636 -0.20828)
					)
					(width 0)
					(fill yes)
				)
			)
		)
		(zone
			(layer "B.Cu")
			(hatch none 0.5)
			(connect_pads
				(clearance 0)
			)
			(min_thickness 0.25)
			(keepout
				(tracks allowed)
				(vias not_allowed)
				(pads allowed)
				(copperpour not_allowed)
				(footprints allowed)
			)
			(placement
				(enabled no)
				(sheetname "")
			)
			(fill
				(thermal_gap 0.5)
				(thermal_bridge_width 0.5)
				(island_removal_mode 0)
			)
			(polygon
				(pts
					(xy 385.5466 -107.94238) (xy 385.9276 -107.94238) (xy 385.9276 -107.76712) (xy 385.5466 -107.766866)
				)
			)
		)
		(zone
			(layer "B.Cu")
			(hatch none 0.5)
			(connect_pads
				(clearance 0)
			)
			(min_thickness 0.25)
			(keepout
				(tracks not_allowed)
				(vias allowed)
				(pads allowed)
				(copperpour not_allowed)
				(footprints allowed)
			)
			(placement
				(enabled no)
				(sheetname "")
			)
			(fill
				(thermal_gap 0.5)
				(thermal_bridge_width 0.5)
				(island_removal_mode 0)
			)
			(polygon
				(pts
					(xy 385.5466 -107.94238) (xy 385.9276 -107.94238) (xy 385.9276 -107.76712) (xy 385.5466 -107.766866)
				)
			)
		)
	)
	(footprint ""
		(layer "B.Cu")
		(at 500.253 -148.1582 -90)
		(property "Reference" "U6W6"
			(at 0.14986 2.621788 270)
			(unlocked yes)
			(layer "B.SilkS")
			(effects
				(font
					(size 1.27 0.964946)
					(thickness 0.000001)
				)
				(justify left mirror)
			)
		)
		(property "Value" ""
			(at 0 0 90)
			(layer "B.Fab")
			(effects
				(font
					(size 1.27 1.27)
				)
				(justify mirror)
			)
		)
		(duplicate_pad_numbers_are_jumpers no)
		(fp_circle
			(center 0.4699 -0.8382)
			(end 0.4699 -0.9652)
			(stroke
				(width 0.254)
				(type default)
			)
			(fill no)
			(layer "B.SilkS")
		)
		(fp_poly
			(pts
				(xy -0.21463 -0.450088) (xy -1.56337 -0.450088) (xy -1.56337 1.75006) (xy -0.21463 1.75006)
			)
			(stroke
				(width 0)
				(type default)
			)
			(fill no)
			(layer "B.CrtYd")
		)
		(fp_line
			(start -1.56337 1.75006)
			(end -0.21463 1.75006)
			(stroke
				(width 0.1)
				(type default)
			)
			(layer "B.Fab")
		)
		(fp_line
			(start -0.21463 1.75006)
			(end -0.21463 -0.450088)
			(stroke
				(width 0.1)
				(type default)
			)
			(layer "B.Fab")
		)
		(fp_line
			(start -1.56337 -0.450088)
			(end -1.56337 1.75006)
			(stroke
				(width 0.1)
				(type default)
			)
			(layer "B.Fab")
		)
		(fp_line
			(start -0.21463 -0.450088)
			(end -1.56337 -0.450088)
			(stroke
				(width 0.1)
				(type default)
			)
			(layer "B.Fab")
		)
		(fp_circle
			(center 0.4699 -0.8382)
			(end 0.4699 -0.9652)
			(stroke
				(width 0.254)
				(type default)
			)
			(fill no)
			(layer "B.Fab")
		)
		(pad "1" smd rect
			(at 0 0 90)
			(size 1.016 0.381)
			(layers "B.Cu" "B.Mask" "B.Paste")
			(net "SPA_MID_DBG1_TX_EN")
		)
		(pad "2" smd rect
			(at 0 0.649986 90)
			(size 1.016 0.381)
			(layers "B.Cu" "B.Mask" "B.Paste")
			(net "SPA_MID_DBG_TX")
		)
		(pad "3" smd rect
			(at 0 1.299972 90)
			(size 1.016 0.381)
			(layers "B.Cu" "B.Mask" "B.Paste")
			(net "GND")
		)
		(pad "4" smd rect
			(at -1.778 1.299972 90)
			(size 1.016 0.381)
			(layers "B.Cu" "B.Mask" "B.Paste")
			(net "SPA_MID_DBG1_TX_R")
		)
		(pad "5" smd rect
			(at -1.778 0 90)
			(size 1.016 0.381)
			(layers "B.Cu" "B.Mask" "B.Paste")
			(net "P3V3_STBY")
		)
	)
	(footprint ""
		(layer "B.Cu")
		(at 404.5585 -97.917 -90)
		(property "Reference" "R2N10"
			(at 0 0 90)
			(layer "B.SilkS")
			(hide yes)
			(effects
				(font
					(size 1.27 1.27)
				)
				(justify mirror)
			)
		)
		(property "Value" ""
			(at 0 0 90)
			(layer "B.Fab")
			(effects
				(font
					(size 1.27 1.27)
				)
				(justify mirror)
			)
		)
		(duplicate_pad_numbers_are_jumpers no)
		(fp_poly
			(pts
				(xy 0.2794 -0.1016) (xy -0.2794 -0.1016) (xy -0.2794 0.9906) (xy 0.2794 0.9906)
			)
			(stroke
				(width 0)
				(type default)
			)
			(fill no)
			(layer "B.CrtYd")
		)
		(fp_line
			(start -0.2794 0.9906)
			(end -0.2794 -0.1016)
			(stroke
				(width 0.1)
				(type default)
			)
			(layer "B.Fab")
		)
		(fp_line
			(start 0.2794 0.9906)
			(end -0.2794 0.9906)
			(stroke
				(width 0.1)
				(type default)
			)
			(layer "B.Fab")
		)
		(fp_line
			(start -0.2794 -0.1016)
			(end 0.2794 -0.1016)
			(stroke
				(width 0.1)
				(type default)
			)
			(layer "B.Fab")
		)
		(fp_line
			(start 0.2794 -0.1016)
			(end 0.2794 0.9906)
			(stroke
				(width 0.1)
				(type default)
			)
			(layer "B.Fab")
		)
		(pad "1" smd rect
			(at 0 0 90)
			(size 0.508 0.508)
			(layers "B.Cu" "B.Mask" "B.Paste")
			(net "P3V3_STBY")
		)
		(pad "2" smd rect
			(at 0 0.889 90)
			(size 0.508 0.508)
			(layers "B.Cu" "B.Mask" "B.Paste")
			(net "FM_PCH_BMC_THERMTRIP_EXI_STRAP_")
		)
		(zone
			(layer "B.Cu")
			(hatch none 0.5)
			(connect_pads
				(clearance 0)
			)
			(min_thickness 0.25)
			(keepout
				(tracks not_allowed)
				(vias allowed)
				(pads allowed)
				(copperpour not_allowed)
				(footprints allowed)
			)
			(placement
				(enabled no)
				(sheetname "")
			)
			(fill
				(thermal_gap 0.5)
				(thermal_bridge_width 0.5)
				(island_removal_mode 0)
			)
			(polygon
				(pts
					(xy 403.9235 -97.663) (xy 403.9235 -98.171) (xy 404.3045 -98.171) (xy 404.3045 -97.663)
				)
			)
		)
		(zone
			(layer "B.Cu")
			(hatch none 0.5)
			(connect_pads
				(clearance 0)
			)
			(min_thickness 0.25)
			(keepout
				(tracks allowed)
				(vias not_allowed)
				(pads allowed)
				(copperpour not_allowed)
				(footprints allowed)
			)
			(placement
				(enabled no)
				(sheetname "")
			)
			(fill
				(thermal_gap 0.5)
				(thermal_bridge_width 0.5)
				(island_removal_mode 0)
			)
			(polygon
				(pts
					(xy 404.3045 -97.663) (xy 404.3045 -98.171) (xy 403.9235 -98.171) (xy 403.9235 -97.663)
				)
			)
		)
	)
	(footprint ""
		(layer "B.Cu")
		(at 392.692128 -88.314784 90)
		(property "Reference" "R2W3"
			(at 0.8382 -0.67818 90)
			(unlocked yes)
			(layer "B.SilkS")
			(effects
				(font
					(size 0.4064 0.254)
					(thickness 0.1524)
				)
				(justify left mirror)
			)
		)
		(property "Value" ""
			(at 0 0 90)
			(layer "B.Fab")
			(effects
				(font
					(size 1.27 1.27)
				)
				(justify mirror)
			)
		)
		(duplicate_pad_numbers_are_jumpers no)
		(fp_poly
			(pts
				(xy 0.2794 -0.1016) (xy -0.2794 -0.1016) (xy -0.2794 0.9906) (xy 0.2794 0.9906)
			)
			(stroke
				(width 0)
				(type default)
			)
			(fill no)
			(layer "B.CrtYd")
		)
		(fp_line
			(start 0.2794 -0.1016)
			(end 0.2794 0.9906)
			(stroke
				(width 0.1)
				(type default)
			)
			(layer "B.Fab")
		)
		(fp_line
			(start -0.2794 -0.1016)
			(end 0.2794 -0.1016)
			(stroke
				(width 0.1)
				(type default)
			)
			(layer "B.Fab")
		)
		(fp_line
			(start 0.2794 0.9906)
			(end -0.2794 0.9906)
			(stroke
				(width 0.1)
				(type default)
			)
			(layer "B.Fab")
		)
		(fp_line
			(start -0.2794 0.9906)
			(end -0.2794 -0.1016)
			(stroke
				(width 0.1)
				(type default)
			)
			(layer "B.Fab")
		)
		(pad "1" smd rect
			(at 0 0 270)
			(size 0.508 0.508)
			(layers "B.Cu" "B.Mask" "B.Paste")
			(net "FM_PMBUS_ALERT_BUF_EN_R_N")
		)
		(pad "2" smd rect
			(at 0 0.889 270)
			(size 0.508 0.508)
			(layers "B.Cu" "B.Mask" "B.Paste")
			(net "FM_PMBUS_ALERT_BUF_EN_N")
		)
		(zone
			(layer "B.Cu")
			(hatch none 0.5)
			(connect_pads
				(clearance 0)
			)
			(min_thickness 0.25)
			(keepout
				(tracks allowed)
				(vias not_allowed)
				(pads allowed)
				(copperpour not_allowed)
				(footprints allowed)
			)
			(placement
				(enabled no)
				(sheetname "")
			)
			(fill
				(thermal_gap 0.5)
				(thermal_bridge_width 0.5)
				(island_removal_mode 0)
			)
			(polygon
				(pts
					(xy 392.946128 -88.568784) (xy 392.946128 -88.060784) (xy 393.327128 -88.060784) (xy 393.327128 -88.568784)
				)
			)
		)
		(zone
			(layer "B.Cu")
			(hatch none 0.5)
			(connect_pads
				(clearance 0)
			)
			(min_thickness 0.25)
			(keepout
				(tracks not_allowed)
				(vias allowed)
				(pads allowed)
				(copperpour not_allowed)
				(footprints allowed)
			)
			(placement
				(enabled no)
				(sheetname "")
			)
			(fill
				(thermal_gap 0.5)
				(thermal_bridge_width 0.5)
				(island_removal_mode 0)
			)
			(polygon
				(pts
					(xy 393.327128 -88.568784) (xy 393.327128 -88.060784) (xy 392.946128 -88.060784) (xy 392.946128 -88.568784)
				)
			)
		)
	)
	(footprint ""
		(layer "B.Cu")
		(at 386.1816 -104.5464 90)
		(property "Reference" "C3N25"
			(at 0 0 90)
			(layer "B.SilkS")
			(hide yes)
			(effects
				(font
					(size 1.27 1.27)
				)
				(justify mirror)
			)
		)
		(property "Value" ""
			(at 0 0 90)
			(layer "B.Fab")
			(effects
				(font
					(size 1.27 1.27)
				)
				(justify mirror)
			)
		)
		(duplicate_pad_numbers_are_jumpers no)
		(fp_rect
			(start 0.2794 0.9144)
			(end -0.2794 -0.1143)
			(stroke
				(width 0)
				(type default)
			)
			(fill no)
			(layer "B.CrtYd")
		)
		(fp_line
			(start 0.2794 -0.1143)
			(end -0.2794 -0.1143)
			(stroke
				(width 0.1)
				(type default)
			)
			(layer "B.Fab")
		)
		(fp_line
			(start -0.2794 -0.1143)
			(end -0.2794 0.9144)
			(stroke
				(width 0.1)
				(type default)
			)
			(layer "B.Fab")
		)
		(fp_line
			(start 0.2794 0.9144)
			(end 0.2794 -0.1143)
			(stroke
				(width 0.1)
				(type default)
			)
			(layer "B.Fab")
		)
		(fp_line
			(start -0.2794 0.9144)
			(end 0.2794 0.9144)
			(stroke
				(width 0.1)
				(type default)
			)
			(layer "B.Fab")
		)
		(pad "1" smd custom
			(at 0 0)
			(size 0.10414 0.10414)
			(layers "B.Cu" "B.Mask" "B.Paste")
			(net "P1V8_PCH_STBY")
			(options
				(clearance outline)
				(anchor circle)
			)
			(primitives
				(gr_poly
					(pts
						(xy -0.20828 -0.08636) (xy -0.20828 0.08636) (xy -0.08636 0.20828) (xy 0.086614 0.20828) (xy 0.20828 0.086614)
						(xy 0.20828 -0.08636) (xy 0.08636 -0.20828) (xy -0.08636 -0.20828)
					)
					(width 0)
					(fill yes)
				)
			)
		)
		(pad "2" smd custom
			(at 0 0.8001)
			(size 0.10414 0.10414)
			(layers "B.Cu" "B.Mask" "B.Paste")
			(net "GND")
			(options
				(clearance outline)
				(anchor circle)
			)
			(primitives
				(gr_poly
					(pts
						(xy -0.20828 -0.08636) (xy -0.20828 0.08636) (xy -0.08636 0.20828) (xy 0.086614 0.20828) (xy 0.20828 0.086614)
						(xy 0.20828 -0.08636) (xy 0.08636 -0.20828) (xy -0.08636 -0.20828)
					)
					(width 0)
					(fill yes)
				)
			)
		)
		(zone
			(layer "B.Cu")
			(hatch none 0.5)
			(connect_pads
				(clearance 0)
			)
			(min_thickness 0.25)
			(keepout
				(tracks not_allowed)
				(vias allowed)
				(pads allowed)
				(copperpour not_allowed)
				(footprints allowed)
			)
			(placement
				(enabled no)
				(sheetname "")
			)
			(fill
				(thermal_gap 0.5)
				(thermal_bridge_width 0.5)
				(island_removal_mode 0)
			)
			(polygon
				(pts
					(xy 386.39115 -104.63403) (xy 386.77215 -104.63403) (xy 386.77215 -104.45877) (xy 386.39115 -104.458516)
				)
			)
		)
		(zone
			(layer "B.Cu")
			(hatch none 0.5)
			(connect_pads
				(clearance 0)
			)
			(min_thickness 0.25)
			(keepout
				(tracks allowed)
				(vias not_allowed)
				(pads allowed)
				(copperpour not_allowed)
				(footprints allowed)
			)
			(placement
				(enabled no)
				(sheetname "")
			)
			(fill
				(thermal_gap 0.5)
				(thermal_bridge_width 0.5)
				(island_removal_mode 0)
			)
			(polygon
				(pts
					(xy 386.39115 -104.63403) (xy 386.77215 -104.63403) (xy 386.77215 -104.45877) (xy 386.39115 -104.458516)
				)
			)
		)
	)
	(footprint ""
		(layer "B.Cu")
		(at 439.6613 -147.955 180)
		(property "Reference" "R25W167"
			(at 0.8382 -0.67818 180)
			(unlocked yes)
			(layer "B.SilkS")
			(effects
				(font
					(size 0.4064 0.254)
					(thickness 0.1524)
				)
				(justify left mirror)
			)
		)
		(property "Value" ""
			(at 0 0 0)
			(layer "B.Fab")
			(effects
				(font
					(size 1.27 1.27)
				)
				(justify mirror)
			)
		)
		(duplicate_pad_numbers_are_jumpers no)
		(fp_poly
			(pts
				(xy 0.2794 -0.1016) (xy -0.2794 -0.1016) (xy -0.2794 0.9906) (xy 0.2794 0.9906)
			)
			(stroke
				(width 0)
				(type default)
			)
			(fill no)
			(layer "B.CrtYd")
		)
		(fp_line
			(start 0.2794 0.9906)
			(end -0.2794 0.9906)
			(stroke
				(width 0.1)
				(type default)
			)
			(layer "B.Fab")
		)
		(fp_line
			(start 0.2794 -0.1016)
			(end 0.2794 0.9906)
			(stroke
				(width 0.1)
				(type default)
			)
			(layer "B.Fab")
		)
		(fp_line
			(start -0.2794 0.9906)
			(end -0.2794 -0.1016)
			(stroke
				(width 0.1)
				(type default)
			)
			(layer "B.Fab")
		)
		(fp_line
			(start -0.2794 -0.1016)
			(end 0.2794 -0.1016)
			(stroke
				(width 0.1)
				(type default)
			)
			(layer "B.Fab")
		)
		(pad "1" smd rect
			(at 0 0)
			(size 0.508 0.508)
			(layers "B.Cu" "B.Mask" "B.Paste")
			(net "BMC_TCK_MUX_SEL")
		)
		(pad "2" smd rect
			(at 0 0.889)
			(size 0.508 0.508)
			(layers "B.Cu" "B.Mask" "B.Paste")
			(net "GND")
		)
		(zone
			(layer "B.Cu")
			(hatch none 0.5)
			(connect_pads
				(clearance 0)
			)
			(min_thickness 0.25)
			(keepout
				(tracks not_allowed)
				(vias allowed)
				(pads allowed)
				(copperpour not_allowed)
				(footprints allowed)
			)
			(placement
				(enabled no)
				(sheetname "")
			)
			(fill
				(thermal_gap 0.5)
				(thermal_bridge_width 0.5)
				(island_removal_mode 0)
			)
			(polygon
				(pts
					(xy 439.4073 -148.59) (xy 439.9153 -148.59) (xy 439.9153 -148.209) (xy 439.4073 -148.209)
				)
			)
		)
		(zone
			(layer "B.Cu")
			(hatch none 0.5)
			(connect_pads
				(clearance 0)
			)
			(min_thickness 0.25)
			(keepout
				(tracks allowed)
				(vias not_allowed)
				(pads allowed)
				(copperpour not_allowed)
				(footprints allowed)
			)
			(placement
				(enabled no)
				(sheetname "")
			)
			(fill
				(thermal_gap 0.5)
				(thermal_bridge_width 0.5)
				(island_removal_mode 0)
			)
			(polygon
				(pts
					(xy 439.4073 -148.209) (xy 439.9153 -148.209) (xy 439.9153 -148.59) (xy 439.4073 -148.59)
				)
			)
		)
	)
	(footprint ""
		(layer "B.Cu")
		(at 441.119006 -41.648126 180)
		(property "Reference" "R25W24"
			(at 0 0 0)
			(layer "B.SilkS")
			(hide yes)
			(effects
				(font
					(size 1.27 1.27)
				)
				(justify mirror)
			)
		)
		(property "Value" "*"
			(at -0.064008 -4.108196 180)
			(unlocked yes)
			(layer "B.Fab")
			(hide yes)
			(effects
				(font
					(size 1.27 1.016)
					(thickness 0.1524)
				)
				(justify mirror)
			)
		)
		(property "Device Type" "120R2F-GP_RCL_GP-120R2F-GP,64.A"
			(at -0.064008 -5.632196 180)
			(unlocked yes)
			(layer "B.Fab")
			(hide yes)
			(effects
				(font
					(size 1.27 1.016)
					(thickness 0.1524)
				)
				(justify mirror)
			)
		)
		(duplicate_pad_numbers_are_jumpers no)
		(fp_line
			(start 0.508 -0.9398)
			(end 0.508 0.9398)
			(stroke
				(width 0.1524)
				(type default)
			)
			(layer "B.SilkS")
		)
		(fp_line
			(start -0.508 -0.9398)
			(end 0.508 -0.9398)
			(stroke
				(width 0.1524)
				(type default)
			)
			(layer "B.SilkS")
		)
		(fp_rect
			(start 0.508 0.9398)
			(end -0.508 -0.9398)
			(stroke
				(width 0)
				(type default)
			)
			(fill no)
			(layer "B.CrtYd")
		)
		(fp_rect
			(start 0.508 0.9398)
			(end -0.508 -0.9398)
			(stroke
				(width 0)
				(type default)
			)
			(fill no)
			(layer "B.Fab")
		)
		(pad "1" smd custom
			(at 0 -0.4445)
			(size 0.1397 0.1397)
			(layers "B.Cu" "B.Mask" "B.Paste")
			(net "GND")
			(options
				(clearance outline)
				(anchor circle)
			)
			(primitives
				(gr_poly
					(pts
						(arc
							(start -0.1778 0.2794)
							(mid -0.249642 0.249642)
							(end -0.2794 0.1778)
						)
						(arc
							(start -0.2794 -0.1778)
							(mid -0.249642 -0.249642)
							(end -0.1778 -0.2794)
						)
						(arc
							(start 0.1778 -0.2794)
							(mid 0.249642 -0.249642)
							(end 0.2794 -0.1778)
						)
						(arc
							(start 0.2794 0.1778)
							(mid 0.249642 0.249642)
							(end 0.1778 0.2794)
						)
					)
					(width 0)
					(fill yes)
				)
			)
		)
		(pad "2" smd custom
			(at 0 0.4445)
			(size 0.1397 0.1397)
			(layers "B.Cu" "B.Mask" "B.Paste")
			(net "BMC_M_A12")
			(options
				(clearance outline)
				(anchor circle)
			)
			(primitives
				(gr_poly
					(pts
						(arc
							(start -0.1778 0.2794)
							(mid -0.249642 0.249642)
							(end -0.2794 0.1778)
						)
						(arc
							(start -0.2794 -0.1778)
							(mid -0.249642 -0.249642)
							(end -0.1778 -0.2794)
						)
						(arc
							(start 0.1778 -0.2794)
							(mid 0.249642 -0.249642)
							(end 0.2794 -0.1778)
						)
						(arc
							(start 0.2794 0.1778)
							(mid 0.249642 0.249642)
							(end 0.1778 0.2794)
						)
					)
					(width 0)
					(fill yes)
				)
			)
		)
	)
	(footprint ""
		(layer "B.Cu")
		(at 344.435176 -77.694536 180)
		(property "Reference" "C3P18"
			(at 0 0 0)
			(layer "B.SilkS")
			(hide yes)
			(effects
				(font
					(size 1.27 1.27)
				)
				(justify mirror)
			)
		)
		(property "Value" ""
			(at 0 0 0)
			(layer "B.Fab")
			(effects
				(font
					(size 1.27 1.27)
				)
				(justify mirror)
			)
		)
		(duplicate_pad_numbers_are_jumpers no)
		(fp_poly
			(pts
				(xy -0.3048 -0.1016) (xy -0.3048 0.9906) (xy 0.3048 0.9906) (xy 0.3048 -0.1016)
			)
			(stroke
				(width 0)
				(type default)
			)
			(fill no)
			(layer "B.CrtYd")
		)
		(fp_line
			(start 0.3048 0.9906)
			(end -0.3048 0.9906)
			(stroke
				(width 0.1)
				(type default)
			)
			(layer "B.Fab")
		)
		(fp_line
			(start 0.3048 -0.1016)
			(end 0.3048 0.9906)
			(stroke
				(width 0.1)
				(type default)
			)
			(layer "B.Fab")
		)
		(fp_line
			(start -0.3048 0.9906)
			(end -0.3048 -0.1016)
			(stroke
				(width 0.1)
				(type default)
			)
			(layer "B.Fab")
		)
		(fp_line
			(start -0.3048 -0.1016)
			(end 0.3048 -0.1016)
			(stroke
				(width 0.1)
				(type default)
			)
			(layer "B.Fab")
		)
		(pad "1" smd rect
			(at 0 0)
			(size 0.508 0.508)
			(layers "B.Cu" "B.Mask" "B.Paste")
			(net "P3E_CPU0_PE1_SS_TXP<2>")
		)
		(pad "2" smd rect
			(at 0 0.889)
			(size 0.508 0.508)
			(layers "B.Cu" "B.Mask" "B.Paste")
			(net "P3E_CPU0_PE1_PCH_TXP<2>")
		)
		(zone
			(layer "B.Cu")
			(hatch none 0.5)
			(connect_pads
				(clearance 0)
			)
			(min_thickness 0.25)
			(keepout
				(tracks allowed)
				(vias not_allowed)
				(pads allowed)
				(copperpour not_allowed)
				(footprints allowed)
			)
			(placement
				(enabled no)
				(sheetname "")
			)
			(fill
				(thermal_gap 0.5)
				(thermal_bridge_width 0.5)
				(island_removal_mode 0)
			)
			(polygon
				(pts
					(xy 344.181176 -77.948536) (xy 344.689176 -77.948536) (xy 344.689176 -78.329536) (xy 344.181176 -78.329536)
				)
			)
		)
	)
	(footprint ""
		(layer "B.Cu")
		(at 318.543432 -17.78 -90)
		(property "Reference" "C4T6"
			(at 0 0 90)
			(layer "B.SilkS")
			(hide yes)
			(effects
				(font
					(size 1.27 1.27)
				)
				(justify mirror)
			)
		)
		(property "Value" ""
			(at 0 0 90)
			(layer "B.Fab")
			(effects
				(font
					(size 1.27 1.27)
				)
				(justify mirror)
			)
		)
		(duplicate_pad_numbers_are_jumpers no)
		(fp_poly
			(pts
				(xy 0.4953 -0.2032) (xy -0.4953 -0.2032) (xy -0.4953 1.6002) (xy 0.4953 1.6002)
			)
			(stroke
				(width 0)
				(type default)
			)
			(fill no)
			(layer "B.CrtYd")
		)
		(fp_line
			(start -0.4953 1.6002)
			(end 0.4953 1.6002)
			(stroke
				(width 0.1)
				(type default)
			)
			(layer "B.Fab")
		)
		(fp_line
			(start 0.4953 1.6002)
			(end 0.4953 -0.2032)
			(stroke
				(width 0.1)
				(type default)
			)
			(layer "B.Fab")
		)
		(fp_line
			(start -0.4953 -0.2032)
			(end -0.4953 1.6002)
			(stroke
				(width 0.1)
				(type default)
			)
			(layer "B.Fab")
		)
		(fp_line
			(start 0.4953 -0.2032)
			(end -0.4953 -0.2032)
			(stroke
				(width 0.1)
				(type default)
			)
			(layer "B.Fab")
		)
		(pad "1" smd rect
			(at 0 0 90)
			(size 0.762 0.889)
			(layers "B.Cu" "B.Mask" "B.Paste")
			(net "PVPP_ABC")
		)
		(pad "2" smd rect
			(at 0 1.397 90)
			(size 0.762 0.889)
			(layers "B.Cu" "B.Mask" "B.Paste")
			(net "GND")
		)
		(zone
			(layer "B.Cu")
			(hatch none 0.5)
			(connect_pads
				(clearance 0)
			)
			(min_thickness 0.25)
			(keepout
				(tracks not_allowed)
				(vias allowed)
				(pads allowed)
				(copperpour not_allowed)
				(footprints allowed)
			)
			(placement
				(enabled no)
				(sheetname "")
			)
			(fill
				(thermal_gap 0.5)
				(thermal_bridge_width 0.5)
				(island_removal_mode 0)
			)
			(polygon
				(pts
					(xy 318.098932 -17.399) (xy 318.098932 -18.161) (xy 317.590932 -18.161) (xy 317.590932 -17.399)
				)
			)
		)
	)
	(footprint ""
		(layer "B.Cu")
		(at 494.706148 -44.533312)
		(property "Reference" "C25W79"
			(at 0.8382 -0.67818 0)
			(unlocked yes)
			(layer "B.SilkS")
			(effects
				(font
					(size 0.4064 0.254)
					(thickness 0.1524)
				)
				(justify left mirror)
			)
		)
		(property "Value" ""
			(at 0 0 0)
			(layer "B.Fab")
			(effects
				(font
					(size 1.27 1.27)
				)
				(justify mirror)
			)
		)
		(duplicate_pad_numbers_are_jumpers no)
		(fp_poly
			(pts
				(xy -0.3048 -0.1016) (xy -0.3048 0.9906) (xy 0.3048 0.9906) (xy 0.3048 -0.1016)
			)
			(stroke
				(width 0)
				(type default)
			)
			(fill no)
			(layer "B.CrtYd")
		)
		(fp_line
			(start -0.3048 -0.1016)
			(end 0.3048 -0.1016)
			(stroke
				(width 0.1)
				(type default)
			)
			(layer "B.Fab")
		)
		(fp_line
			(start -0.3048 0.9906)
			(end -0.3048 -0.1016)
			(stroke
				(width 0.1)
				(type default)
			)
			(layer "B.Fab")
		)
		(fp_line
			(start 0.3048 -0.1016)
			(end 0.3048 0.9906)
			(stroke
				(width 0.1)
				(type default)
			)
			(layer "B.Fab")
		)
		(fp_line
			(start 0.3048 0.9906)
			(end -0.3048 0.9906)
			(stroke
				(width 0.1)
				(type default)
			)
			(layer "B.Fab")
		)
		(pad "1" smd rect
			(at 0 0 180)
			(size 0.508 0.508)
			(layers "B.Cu" "B.Mask" "B.Paste")
			(net "V_IBMC_5V_DDC_SDA_J")
		)
		(pad "2" smd rect
			(at 0 0.889 180)
			(size 0.508 0.508)
			(layers "B.Cu" "B.Mask" "B.Paste")
			(net "GND")
		)
		(zone
			(layer "B.Cu")
			(hatch none 0.5)
			(connect_pads
				(clearance 0)
			)
			(min_thickness 0.25)
			(keepout
				(tracks allowed)
				(vias not_allowed)
				(pads allowed)
				(copperpour not_allowed)
				(footprints allowed)
			)
			(placement
				(enabled no)
				(sheetname "")
			)
			(fill
				(thermal_gap 0.5)
				(thermal_bridge_width 0.5)
				(island_removal_mode 0)
			)
			(polygon
				(pts
					(xy 494.960148 -44.279312) (xy 494.452148 -44.279312) (xy 494.452148 -43.898312) (xy 494.960148 -43.898312)
				)
			)
		)
		(zone
			(layer "B.Cu")
			(hatch none 0.5)
			(connect_pads
				(clearance 0)
			)
			(min_thickness 0.25)
			(keepout
				(tracks not_allowed)
				(vias allowed)
				(pads allowed)
				(copperpour not_allowed)
				(footprints allowed)
			)
			(placement
				(enabled no)
				(sheetname "")
			)
			(fill
				(thermal_gap 0.5)
				(thermal_bridge_width 0.5)
				(island_removal_mode 0)
			)
			(polygon
				(pts
					(xy 494.960148 -43.898312) (xy 494.452148 -43.898312) (xy 494.452148 -44.279312) (xy 494.960148 -44.279312)
				)
			)
		)
	)
	(footprint ""
		(layer "B.Cu")
		(at 258.2164 -140.1826 -90)
		(property "Reference" "C5G68"
			(at -1.14681 0.76708 0)
			(unlocked yes)
			(layer "B.SilkS")
			(effects
				(font
					(size 0.7874 0.5842)
					(thickness 0.1524)
				)
				(justify mirror)
			)
		)
		(property "Value" ""
			(at 0 0 90)
			(layer "B.Fab")
			(effects
				(font
					(size 1.27 1.27)
				)
				(justify mirror)
			)
		)
		(duplicate_pad_numbers_are_jumpers no)
		(fp_rect
			(start -0.4953 -0.2032)
			(end 0.4953 1.6002)
			(stroke
				(width 0)
				(type default)
			)
			(fill no)
			(layer "B.CrtYd")
		)
		(fp_line
			(start -0.4953 1.6002)
			(end 0.4953 1.6002)
			(stroke
				(width 0.1)
				(type default)
			)
			(layer "B.Fab")
		)
		(fp_line
			(start 0.4953 1.6002)
			(end 0.4953 -0.2032)
			(stroke
				(width 0.1)
				(type default)
			)
			(layer "B.Fab")
		)
		(fp_line
			(start -0.4953 -0.2032)
			(end -0.4953 1.6002)
			(stroke
				(width 0.1)
				(type default)
			)
			(layer "B.Fab")
		)
		(fp_line
			(start 0.4953 -0.2032)
			(end -0.4953 -0.2032)
			(stroke
				(width 0.1)
				(type default)
			)
			(layer "B.Fab")
		)
		(pad "1" smd rect
			(at 0 0 90)
			(size 0.762 0.889)
			(layers "B.Cu" "B.Mask" "B.Paste")
			(net "PVDDQ_DEF")
		)
		(pad "2" smd rect
			(at 0 1.397 90)
			(size 0.762 0.889)
			(layers "B.Cu" "B.Mask" "B.Paste")
			(net "GND")
		)
		(zone
			(layer "B.Cu")
			(hatch none 0.5)
			(connect_pads
				(clearance 0)
			)
			(min_thickness 0.25)
			(keepout
				(tracks not_allowed)
				(vias allowed)
				(pads allowed)
				(copperpour not_allowed)
				(footprints allowed)
			)
			(placement
				(enabled no)
				(sheetname "")
			)
			(fill
				(thermal_gap 0.5)
				(thermal_bridge_width 0.5)
				(island_removal_mode 0)
			)
			(polygon
				(pts
					(xy 257.7719 -140.5636) (xy 257.2639 -140.5636) (xy 257.2639 -139.8016) (xy 257.7719 -139.8016)
				)
			)
		)
	)
	(footprint ""
		(layer "B.Cu")
		(at 500.38 -143.002 -90)
		(property "Reference" "U6W5"
			(at 0.14986 2.621788 270)
			(unlocked yes)
			(layer "B.SilkS")
			(effects
				(font
					(size 1.27 0.964946)
					(thickness 0.000001)
				)
				(justify left mirror)
			)
		)
		(property "Value" ""
			(at 0 0 90)
			(layer "B.Fab")
			(effects
				(font
					(size 1.27 1.27)
				)
				(justify mirror)
			)
		)
		(duplicate_pad_numbers_are_jumpers no)
		(fp_circle
			(center 0.4699 -0.8382)
			(end 0.4699 -0.9652)
			(stroke
				(width 0.254)
				(type default)
			)
			(fill no)
			(layer "B.SilkS")
		)
		(fp_poly
			(pts
				(xy -0.21463 -0.450088) (xy -1.56337 -0.450088) (xy -1.56337 1.75006) (xy -0.21463 1.75006)
			)
			(stroke
				(width 0)
				(type default)
			)
			(fill no)
			(layer "B.CrtYd")
		)
		(fp_line
			(start -1.56337 1.75006)
			(end -0.21463 1.75006)
			(stroke
				(width 0.1)
				(type default)
			)
			(layer "B.Fab")
		)
		(fp_line
			(start -0.21463 1.75006)
			(end -0.21463 -0.450088)
			(stroke
				(width 0.1)
				(type default)
			)
			(layer "B.Fab")
		)
		(fp_line
			(start -1.56337 -0.450088)
			(end -1.56337 1.75006)
			(stroke
				(width 0.1)
				(type default)
			)
			(layer "B.Fab")
		)
		(fp_line
			(start -0.21463 -0.450088)
			(end -1.56337 -0.450088)
			(stroke
				(width 0.1)
				(type default)
			)
			(layer "B.Fab")
		)
		(fp_circle
			(center 0.4699 -0.8382)
			(end 0.4699 -0.9652)
			(stroke
				(width 0.254)
				(type default)
			)
			(fill no)
			(layer "B.Fab")
		)
		(pad "1" smd rect
			(at 0 0 90)
			(size 1.016 0.381)
			(layers "B.Cu" "B.Mask" "B.Paste")
			(net "DEBUG_CARD2_PRSNT")
		)
		(pad "2" smd rect
			(at 0 0.649986 90)
			(size 1.016 0.381)
			(layers "B.Cu" "B.Mask" "B.Paste")
			(net "SPA_MID_DBG_TX")
		)
		(pad "3" smd rect
			(at 0 1.299972 90)
			(size 1.016 0.381)
			(layers "B.Cu" "B.Mask" "B.Paste")
			(net "GND")
		)
		(pad "4" smd rect
			(at -1.778 1.299972 90)
			(size 1.016 0.381)
			(layers "B.Cu" "B.Mask" "B.Paste")
			(net "SPA_MID_DBG2_TX_R")
		)
		(pad "5" smd rect
			(at -1.778 0 90)
			(size 1.016 0.381)
			(layers "B.Cu" "B.Mask" "B.Paste")
			(net "P3V3_STBY")
		)
	)
	(footprint ""
		(layer "B.Cu")
		(at 115.353592 -71.841614 180)
		(property "Reference" "C7P16"
			(at 0 0 0)
			(layer "B.SilkS")
			(hide yes)
			(effects
				(font
					(size 1.27 1.27)
				)
				(justify mirror)
			)
		)
		(property "Value" ""
			(at 0 0 0)
			(layer "B.Fab")
			(effects
				(font
					(size 1.27 1.27)
				)
				(justify mirror)
			)
		)
		(duplicate_pad_numbers_are_jumpers no)
		(fp_poly
			(pts
				(xy 0.4953 -0.2032) (xy -0.4953 -0.2032) (xy -0.4953 1.6002) (xy 0.4953 1.6002)
			)
			(stroke
				(width 0)
				(type default)
			)
			(fill no)
			(layer "B.CrtYd")
		)
		(fp_line
			(start 0.4953 1.6002)
			(end 0.4953 -0.2032)
			(stroke
				(width 0.1)
				(type default)
			)
			(layer "B.Fab")
		)
		(fp_line
			(start 0.4953 -0.2032)
			(end -0.4953 -0.2032)
			(stroke
				(width 0.1)
				(type default)
			)
			(layer "B.Fab")
		)
		(fp_line
			(start -0.4953 1.6002)
			(end 0.4953 1.6002)
			(stroke
				(width 0.1)
				(type default)
			)
			(layer "B.Fab")
		)
		(fp_line
			(start -0.4953 -0.2032)
			(end -0.4953 1.6002)
			(stroke
				(width 0.1)
				(type default)
			)
			(layer "B.Fab")
		)
		(pad "1" smd rect
			(at 0 0)
			(size 0.762 0.889)
			(layers "B.Cu" "B.Mask" "B.Paste")
			(net "PVCCIO_CPU1")
		)
		(pad "2" smd rect
			(at 0 1.397)
			(size 0.762 0.889)
			(layers "B.Cu" "B.Mask" "B.Paste")
			(net "GND")
		)
		(zone
			(layer "B.Cu")
			(hatch none 0.5)
			(connect_pads
				(clearance 0)
			)
			(min_thickness 0.25)
			(keepout
				(tracks not_allowed)
				(vias allowed)
				(pads allowed)
				(copperpour not_allowed)
				(footprints allowed)
			)
			(placement
				(enabled no)
				(sheetname "")
			)
			(fill
				(thermal_gap 0.5)
				(thermal_bridge_width 0.5)
				(island_removal_mode 0)
			)
			(polygon
				(pts
					(xy 114.972592 -72.286114) (xy 115.734592 -72.286114) (xy 115.734592 -72.794114) (xy 114.972592 -72.794114)
				)
			)
		)
	)
	(footprint ""
		(layer "B.Cu")
		(at 107.8611 -12.954 90)
		(property "Reference" "C5G95"
			(at -1.14681 0.76708 180)
			(unlocked yes)
			(layer "B.SilkS")
			(effects
				(font
					(size 0.7874 0.5842)
					(thickness 0.1524)
				)
				(justify mirror)
			)
		)
		(property "Value" ""
			(at 0 0 90)
			(layer "B.Fab")
			(effects
				(font
					(size 1.27 1.27)
				)
				(justify mirror)
			)
		)
		(duplicate_pad_numbers_are_jumpers no)
		(fp_rect
			(start -0.4953 -0.2032)
			(end 0.4953 1.6002)
			(stroke
				(width 0)
				(type default)
			)
			(fill no)
			(layer "B.CrtYd")
		)
		(fp_line
			(start 0.4953 -0.2032)
			(end -0.4953 -0.2032)
			(stroke
				(width 0.1)
				(type default)
			)
			(layer "B.Fab")
		)
		(fp_line
			(start -0.4953 -0.2032)
			(end -0.4953 1.6002)
			(stroke
				(width 0.1)
				(type default)
			)
			(layer "B.Fab")
		)
		(fp_line
			(start 0.4953 1.6002)
			(end 0.4953 -0.2032)
			(stroke
				(width 0.1)
				(type default)
			)
			(layer "B.Fab")
		)
		(fp_line
			(start -0.4953 1.6002)
			(end 0.4953 1.6002)
			(stroke
				(width 0.1)
				(type default)
			)
			(layer "B.Fab")
		)
		(pad "1" smd rect
			(at 0 0 270)
			(size 0.762 0.889)
			(layers "B.Cu" "B.Mask" "B.Paste")
			(net "PVDDQ_GHJ")
		)
		(pad "2" smd rect
			(at 0 1.397 270)
			(size 0.762 0.889)
			(layers "B.Cu" "B.Mask" "B.Paste")
			(net "GND")
		)
		(zone
			(layer "B.Cu")
			(hatch none 0.5)
			(connect_pads
				(clearance 0)
			)
			(min_thickness 0.25)
			(keepout
				(tracks not_allowed)
				(vias allowed)
				(pads allowed)
				(copperpour not_allowed)
				(footprints allowed)
			)
			(placement
				(enabled no)
				(sheetname "")
			)
			(fill
				(thermal_gap 0.5)
				(thermal_bridge_width 0.5)
				(island_removal_mode 0)
			)
			(polygon
				(pts
					(xy 108.3056 -12.573) (xy 108.8136 -12.573) (xy 108.8136 -13.335) (xy 108.3056 -13.335)
				)
			)
		)
	)
	(footprint ""
		(layer "B.Cu")
		(at 374.381268 -48.328326 90)
		(property "Reference" "R2T59"
			(at 0 0 90)
			(layer "B.SilkS")
			(hide yes)
			(effects
				(font
					(size 1.27 1.27)
				)
				(justify mirror)
			)
		)
		(property "Value" ""
			(at 0 0 90)
			(layer "B.Fab")
			(effects
				(font
					(size 1.27 1.27)
				)
				(justify mirror)
			)
		)
		(duplicate_pad_numbers_are_jumpers no)
		(fp_poly
			(pts
				(xy 0.2794 -0.1016) (xy -0.2794 -0.1016) (xy -0.2794 0.9906) (xy 0.2794 0.9906)
			)
			(stroke
				(width 0)
				(type default)
			)
			(fill no)
			(layer "B.CrtYd")
		)
		(fp_line
			(start 0.2794 -0.1016)
			(end 0.2794 0.9906)
			(stroke
				(width 0.1)
				(type default)
			)
			(layer "B.Fab")
		)
		(fp_line
			(start -0.2794 -0.1016)
			(end 0.2794 -0.1016)
			(stroke
				(width 0.1)
				(type default)
			)
			(layer "B.Fab")
		)
		(fp_line
			(start 0.2794 0.9906)
			(end -0.2794 0.9906)
			(stroke
				(width 0.1)
				(type default)
			)
			(layer "B.Fab")
		)
		(fp_line
			(start -0.2794 0.9906)
			(end -0.2794 -0.1016)
			(stroke
				(width 0.1)
				(type default)
			)
			(layer "B.Fab")
		)
		(pad "1" smd rect
			(at 0 0 270)
			(size 0.508 0.508)
			(layers "B.Cu" "B.Mask" "B.Paste")
			(net "H_CPU0_PROCHOT_G_N")
		)
		(pad "2" smd rect
			(at 0 0.889 270)
			(size 0.508 0.508)
			(layers "B.Cu" "B.Mask" "B.Paste")
			(net "H_CPU0_PROCHOT_G_PCH_N")
		)
		(zone
			(layer "B.Cu")
			(hatch none 0.5)
			(connect_pads
				(clearance 0)
			)
			(min_thickness 0.25)
			(keepout
				(tracks allowed)
				(vias not_allowed)
				(pads allowed)
				(copperpour not_allowed)
				(footprints allowed)
			)
			(placement
				(enabled no)
				(sheetname "")
			)
			(fill
				(thermal_gap 0.5)
				(thermal_bridge_width 0.5)
				(island_removal_mode 0)
			)
			(polygon
				(pts
					(xy 374.635268 -48.582326) (xy 374.635268 -48.074326) (xy 375.016268 -48.074326) (xy 375.016268 -48.582326)
				)
			)
		)
		(zone
			(layer "B.Cu")
			(hatch none 0.5)
			(connect_pads
				(clearance 0)
			)
			(min_thickness 0.25)
			(keepout
				(tracks not_allowed)
				(vias allowed)
				(pads allowed)
				(copperpour not_allowed)
				(footprints allowed)
			)
			(placement
				(enabled no)
				(sheetname "")
			)
			(fill
				(thermal_gap 0.5)
				(thermal_bridge_width 0.5)
				(island_removal_mode 0)
			)
			(polygon
				(pts
					(xy 375.016268 -48.582326) (xy 375.016268 -48.074326) (xy 374.635268 -48.074326) (xy 374.635268 -48.582326)
				)
			)
		)
	)
	(footprint ""
		(layer "B.Cu")
		(at 469.646 -134.7978 90)
		(property "Reference" "R6W35"
			(at 0.8382 -0.67818 90)
			(unlocked yes)
			(layer "B.SilkS")
			(effects
				(font
					(size 0.4064 0.254)
					(thickness 0.1524)
				)
				(justify left mirror)
			)
		)
		(property "Value" ""
			(at 0 0 90)
			(layer "B.Fab")
			(effects
				(font
					(size 1.27 1.27)
				)
				(justify mirror)
			)
		)
		(duplicate_pad_numbers_are_jumpers no)
		(fp_poly
			(pts
				(xy 0.2794 -0.1016) (xy -0.2794 -0.1016) (xy -0.2794 0.9906) (xy 0.2794 0.9906)
			)
			(stroke
				(width 0)
				(type default)
			)
			(fill no)
			(layer "B.CrtYd")
		)
		(fp_line
			(start 0.2794 -0.1016)
			(end 0.2794 0.9906)
			(stroke
				(width 0.1)
				(type default)
			)
			(layer "B.Fab")
		)
		(fp_line
			(start -0.2794 -0.1016)
			(end 0.2794 -0.1016)
			(stroke
				(width 0.1)
				(type default)
			)
			(layer "B.Fab")
		)
		(fp_line
			(start 0.2794 0.9906)
			(end -0.2794 0.9906)
			(stroke
				(width 0.1)
				(type default)
			)
			(layer "B.Fab")
		)
		(fp_line
			(start -0.2794 0.9906)
			(end -0.2794 -0.1016)
			(stroke
				(width 0.1)
				(type default)
			)
			(layer "B.Fab")
		)
		(pad "1" smd rect
			(at 0 0 270)
			(size 0.508 0.508)
			(layers "B.Cu" "B.Mask" "B.Paste")
			(net "P3V3_STBY")
		)
		(pad "2" smd rect
			(at 0 0.889 270)
			(size 0.508 0.508)
			(layers "B.Cu" "B.Mask" "B.Paste")
			(net "FM_CPU_CATERR_MSMI_LVT3_N")
		)
		(zone
			(layer "B.Cu")
			(hatch none 0.5)
			(connect_pads
				(clearance 0)
			)
			(min_thickness 0.25)
			(keepout
				(tracks allowed)
				(vias not_allowed)
				(pads allowed)
				(copperpour not_allowed)
				(footprints allowed)
			)
			(placement
				(enabled no)
				(sheetname "")
			)
			(fill
				(thermal_gap 0.5)
				(thermal_bridge_width 0.5)
				(island_removal_mode 0)
			)
			(polygon
				(pts
					(xy 469.9 -135.0518) (xy 469.9 -134.5438) (xy 470.281 -134.5438) (xy 470.281 -135.0518)
				)
			)
		)
		(zone
			(layer "B.Cu")
			(hatch none 0.5)
			(connect_pads
				(clearance 0)
			)
			(min_thickness 0.25)
			(keepout
				(tracks not_allowed)
				(vias allowed)
				(pads allowed)
				(copperpour not_allowed)
				(footprints allowed)
			)
			(placement
				(enabled no)
				(sheetname "")
			)
			(fill
				(thermal_gap 0.5)
				(thermal_bridge_width 0.5)
				(island_removal_mode 0)
			)
			(polygon
				(pts
					(xy 470.281 -135.0518) (xy 470.281 -134.5438) (xy 469.9 -134.5438) (xy 469.9 -135.0518)
				)
			)
		)
	)
	(footprint ""
		(layer "B.Cu")
		(at 26.0096 -79.502 -90)
		(property "Reference" "U9P2"
			(at -1.3716 -1.44653 270)
			(unlocked yes)
			(layer "B.SilkS")
			(effects
				(font
					(size 0.7874 0.5842)
					(thickness 0.1524)
				)
				(justify mirror)
			)
		)
		(property "Value" ""
			(at 0 0 90)
			(layer "B.Fab")
			(effects
				(font
					(size 1.27 1.27)
				)
				(justify mirror)
			)
		)
		(duplicate_pad_numbers_are_jumpers no)
		(fp_circle
			(center 0.8255 0.199898)
			(end 0.8255 0.072644)
			(stroke
				(width 0.254)
				(type default)
			)
			(fill no)
			(layer "B.SilkS")
		)
		(fp_rect
			(start 0.216154 1.27508)
			(end -1.333754 -0.275082)
			(stroke
				(width 0)
				(type default)
			)
			(fill no)
			(layer "B.CrtYd")
		)
		(fp_line
			(start -1.333754 1.27508)
			(end 0.216154 1.27508)
			(stroke
				(width 0.1)
				(type default)
			)
			(layer "B.Fab")
		)
		(fp_line
			(start 0.216154 1.27508)
			(end 0.216154 -0.275082)
			(stroke
				(width 0.1)
				(type default)
			)
			(layer "B.Fab")
		)
		(fp_line
			(start -1.333754 -0.275082)
			(end -1.333754 1.27508)
			(stroke
				(width 0.1)
				(type default)
			)
			(layer "B.Fab")
		)
		(fp_line
			(start 0.216154 -0.275082)
			(end -1.333754 -0.275082)
			(stroke
				(width 0.1)
				(type default)
			)
			(layer "B.Fab")
		)
		(fp_circle
			(center 1.0795 -0.054102)
			(end 1.0795 -0.181356)
			(stroke
				(width 0.254)
				(type default)
			)
			(fill no)
			(layer "B.Fab")
		)
		(pad "1" smd rect
			(at 0 0 90)
			(size 0.9398 0.3048)
			(layers "B.Cu" "B.Mask" "B.Paste")
			(net "FM_HSC_TIMER_EXP_N")
		)
		(pad "2" smd rect
			(at 0.0254 0.500126 90)
			(size 0.889 0.3048)
			(layers "B.Cu" "B.Mask" "B.Paste")
			(net "P3V3_STBY")
		)
		(pad "3" smd rect
			(at 0.0254 0.999998 90)
			(size 0.889 0.3048)
			(layers "B.Cu" "B.Mask" "B.Paste")
			(net "A_HSC_TIMER_R")
		)
		(pad "4" smd rect
			(at -1.143 0.999998 90)
			(size 0.889 0.3048)
			(layers "B.Cu" "B.Mask" "B.Paste")
			(net "A_HSC_INAP")
		)
		(pad "5" smd rect
			(at -1.143 0.500126 90)
			(size 0.889 0.3048)
			(layers "B.Cu" "B.Mask" "B.Paste")
			(net "GND")
		)
		(pad "6" smd rect
			(at -1.143 0 90)
			(size 0.889 0.3048)
			(layers "B.Cu" "B.Mask" "B.Paste")
			(net "PWRGD_DSW_PWROK")
		)
	)
	(footprint ""
		(layer "B.Cu")
		(at 22.606 -77.724 180)
		(property "Reference" "R9P17"
			(at 0 0 0)
			(layer "B.SilkS")
			(hide yes)
			(effects
				(font
					(size 1.27 1.27)
				)
				(justify mirror)
			)
		)
		(property "Value" ""
			(at 0 0 0)
			(layer "B.Fab")
			(effects
				(font
					(size 1.27 1.27)
				)
				(justify mirror)
			)
		)
		(duplicate_pad_numbers_are_jumpers no)
		(fp_rect
			(start 0.2794 -0.1016)
			(end -0.2794 0.9906)
			(stroke
				(width 0)
				(type default)
			)
			(fill no)
			(layer "B.CrtYd")
		)
		(fp_line
			(start 0.2794 0.9906)
			(end -0.2794 0.9906)
			(stroke
				(width 0.1)
				(type default)
			)
			(layer "B.Fab")
		)
		(fp_line
			(start 0.2794 -0.1016)
			(end 0.2794 0.9906)
			(stroke
				(width 0.1)
				(type default)
			)
			(layer "B.Fab")
		)
		(fp_line
			(start -0.2794 0.9906)
			(end -0.2794 -0.1016)
			(stroke
				(width 0.1)
				(type default)
			)
			(layer "B.Fab")
		)
		(fp_line
			(start -0.2794 -0.1016)
			(end 0.2794 -0.1016)
			(stroke
				(width 0.1)
				(type default)
			)
			(layer "B.Fab")
		)
		(pad "1" smd rect
			(at 0 0)
			(size 0.508 0.508)
			(layers "B.Cu" "B.Mask" "B.Paste")
			(net "FM_P12V_HSC_ADR1")
		)
		(pad "2" smd rect
			(at 0 0.889)
			(size 0.508 0.508)
			(layers "B.Cu" "B.Mask" "B.Paste")
			(net "AGND_HSC")
		)
		(zone
			(layer "B.Cu")
			(hatch none 0.5)
			(connect_pads
				(clearance 0)
			)
			(min_thickness 0.25)
			(keepout
				(tracks not_allowed)
				(vias allowed)
				(pads allowed)
				(copperpour not_allowed)
				(footprints allowed)
			)
			(placement
				(enabled no)
				(sheetname "")
			)
			(fill
				(thermal_gap 0.5)
				(thermal_bridge_width 0.5)
				(island_removal_mode 0)
			)
			(polygon
				(pts
					(xy 22.352 -77.978) (xy 22.86 -77.978) (xy 22.86 -78.359) (xy 22.352 -78.359)
				)
			)
		)
		(zone
			(layer "B.Cu")
			(hatch none 0.5)
			(connect_pads
				(clearance 0)
			)
			(min_thickness 0.25)
			(keepout
				(tracks allowed)
				(vias not_allowed)
				(pads allowed)
				(copperpour not_allowed)
				(footprints allowed)
			)
			(placement
				(enabled no)
				(sheetname "")
			)
			(fill
				(thermal_gap 0.5)
				(thermal_bridge_width 0.5)
				(island_removal_mode 0)
			)
			(polygon
				(pts
					(xy 22.352 -77.978) (xy 22.86 -77.978) (xy 22.86 -78.359) (xy 22.352 -78.359)
				)
			)
		)
	)
	(footprint ""
		(layer "B.Cu")
		(at 107.8611 -17.7546 90)
		(property "Reference" "C7T5"
			(at -1.848866 0.752348 90)
			(unlocked yes)
			(layer "B.SilkS")
			(effects
				(font
					(size 1.27 0.9652)
					(thickness 0.1524)
				)
				(justify mirror)
			)
		)
		(property "Value" ""
			(at 0 0 90)
			(layer "B.Fab")
			(effects
				(font
					(size 1.27 1.27)
				)
				(justify mirror)
			)
		)
		(duplicate_pad_numbers_are_jumpers no)
		(fp_rect
			(start 0.500126 1.598422)
			(end -0.500126 -0.201422)
			(stroke
				(width 0)
				(type default)
			)
			(fill no)
			(layer "B.CrtYd")
		)
		(fp_line
			(start 0.500126 -0.201422)
			(end -0.500126 -0.201422)
			(stroke
				(width 0.1)
				(type default)
			)
			(layer "B.Fab")
		)
		(fp_line
			(start -0.500126 -0.201422)
			(end -0.500126 1.598422)
			(stroke
				(width 0.1)
				(type default)
			)
			(layer "B.Fab")
		)
		(fp_line
			(start 0.500126 1.598422)
			(end 0.500126 -0.201422)
			(stroke
				(width 0.1)
				(type default)
			)
			(layer "B.Fab")
		)
		(fp_line
			(start -0.500126 1.598422)
			(end 0.500126 1.598422)
			(stroke
				(width 0.1)
				(type default)
			)
			(layer "B.Fab")
		)
		(pad "1" smd rect
			(at 0 0)
			(size 0.889 0.9906)
			(layers "B.Cu" "B.Mask" "B.Paste")
			(net "PVDDQ_GHJ")
		)
		(pad "2" smd rect
			(at 0 1.397)
			(size 0.889 0.9906)
			(layers "B.Cu" "B.Mask" "B.Paste")
			(net "GND")
		)
		(zone
			(layer "B.Cu")
			(hatch none 0.5)
			(connect_pads
				(clearance 0)
			)
			(min_thickness 0.25)
			(keepout
				(tracks not_allowed)
				(vias allowed)
				(pads allowed)
				(copperpour not_allowed)
				(footprints allowed)
			)
			(placement
				(enabled no)
				(sheetname "")
			)
			(fill
				(thermal_gap 0.5)
				(thermal_bridge_width 0.5)
				(island_removal_mode 0)
			)
			(polygon
				(pts
					(xy 108.8136 -18.2499) (xy 108.3056 -18.2499) (xy 108.3056 -17.2593) (xy 108.8136 -17.2593)
				)
			)
		)
		(zone
			(layer "B.Cu")
			(hatch none 0.5)
			(connect_pads
				(clearance 0)
			)
			(min_thickness 0.25)
			(keepout
				(tracks allowed)
				(vias not_allowed)
				(pads allowed)
				(copperpour not_allowed)
				(footprints allowed)
			)
			(placement
				(enabled no)
				(sheetname "")
			)
			(fill
				(thermal_gap 0.5)
				(thermal_bridge_width 0.5)
				(island_removal_mode 0)
			)
			(polygon
				(pts
					(xy 108.8136 -18.2499) (xy 108.3056 -18.2499) (xy 108.3056 -17.2593) (xy 108.8136 -17.2593)
				)
			)
		)
	)
	(footprint ""
		(layer "B.Cu")
		(at 427.38675 -13.010642 90)
		(property "Reference" "R9G27"
			(at 0 0 90)
			(layer "B.SilkS")
			(hide yes)
			(effects
				(font
					(size 1.27 1.27)
				)
				(justify mirror)
			)
		)
		(property "Value" ""
			(at 0 0 90)
			(layer "B.Fab")
			(effects
				(font
					(size 1.27 1.27)
				)
				(justify mirror)
			)
		)
		(duplicate_pad_numbers_are_jumpers no)
		(fp_poly
			(pts
				(xy 0.2794 -0.1016) (xy -0.2794 -0.1016) (xy -0.2794 0.9906) (xy 0.2794 0.9906)
			)
			(stroke
				(width 0)
				(type default)
			)
			(fill no)
			(layer "B.CrtYd")
		)
		(fp_line
			(start 0.2794 -0.1016)
			(end 0.2794 0.9906)
			(stroke
				(width 0.1)
				(type default)
			)
			(layer "B.Fab")
		)
		(fp_line
			(start -0.2794 -0.1016)
			(end 0.2794 -0.1016)
			(stroke
				(width 0.1)
				(type default)
			)
			(layer "B.Fab")
		)
		(fp_line
			(start 0.2794 0.9906)
			(end -0.2794 0.9906)
			(stroke
				(width 0.1)
				(type default)
			)
			(layer "B.Fab")
		)
		(fp_line
			(start -0.2794 0.9906)
			(end -0.2794 -0.1016)
			(stroke
				(width 0.1)
				(type default)
			)
			(layer "B.Fab")
		)
		(pad "1" smd rect
			(at 0 0 270)
			(size 0.508 0.508)
			(layers "B.Cu" "B.Mask" "B.Paste")
			(net "H_CPU0_MEMDEF_MEMHOT_G_PCH_N")
		)
		(pad "2" smd rect
			(at 0 0.889 270)
			(size 0.508 0.508)
			(layers "B.Cu" "B.Mask" "B.Paste")
			(net "H_CPU0_MEMDEF_MEMHOT_LVT3_K_N")
		)
		(zone
			(layer "B.Cu")
			(hatch none 0.5)
			(connect_pads
				(clearance 0)
			)
			(min_thickness 0.25)
			(keepout
				(tracks allowed)
				(vias not_allowed)
				(pads allowed)
				(copperpour not_allowed)
				(footprints allowed)
			)
			(placement
				(enabled no)
				(sheetname "")
			)
			(fill
				(thermal_gap 0.5)
				(thermal_bridge_width 0.5)
				(island_removal_mode 0)
			)
			(polygon
				(pts
					(xy 427.64075 -13.264642) (xy 427.64075 -12.756642) (xy 428.02175 -12.756642) (xy 428.02175 -13.264642)
				)
			)
		)
		(zone
			(layer "B.Cu")
			(hatch none 0.5)
			(connect_pads
				(clearance 0)
			)
			(min_thickness 0.25)
			(keepout
				(tracks not_allowed)
				(vias allowed)
				(pads allowed)
				(copperpour not_allowed)
				(footprints allowed)
			)
			(placement
				(enabled no)
				(sheetname "")
			)
			(fill
				(thermal_gap 0.5)
				(thermal_bridge_width 0.5)
				(island_removal_mode 0)
			)
			(polygon
				(pts
					(xy 428.02175 -13.264642) (xy 428.02175 -12.756642) (xy 427.64075 -12.756642) (xy 427.64075 -13.264642)
				)
			)
		)
	)
	(footprint ""
		(layer "B.Cu")
		(at 377.144788 -70.695058)
		(property "Reference" "C2P8"
			(at 0 0 0)
			(layer "B.SilkS")
			(hide yes)
			(effects
				(font
					(size 1.27 1.27)
				)
				(justify mirror)
			)
		)
		(property "Value" ""
			(at 0 0 0)
			(layer "B.Fab")
			(effects
				(font
					(size 1.27 1.27)
				)
				(justify mirror)
			)
		)
		(duplicate_pad_numbers_are_jumpers no)
		(fp_rect
			(start 0.2794 0.9144)
			(end -0.2794 -0.1143)
			(stroke
				(width 0)
				(type default)
			)
			(fill no)
			(layer "B.CrtYd")
		)
		(fp_line
			(start -0.2794 -0.1143)
			(end -0.2794 0.9144)
			(stroke
				(width 0.1)
				(type default)
			)
			(layer "B.Fab")
		)
		(fp_line
			(start -0.2794 0.9144)
			(end 0.2794 0.9144)
			(stroke
				(width 0.1)
				(type default)
			)
			(layer "B.Fab")
		)
		(fp_line
			(start 0.2794 -0.1143)
			(end -0.2794 -0.1143)
			(stroke
				(width 0.1)
				(type default)
			)
			(layer "B.Fab")
		)
		(fp_line
			(start 0.2794 0.9144)
			(end 0.2794 -0.1143)
			(stroke
				(width 0.1)
				(type default)
			)
			(layer "B.Fab")
		)
		(pad "1" smd custom
			(at 0 0 270)
			(size 0.10414 0.10414)
			(layers "B.Cu" "B.Mask" "B.Paste")
			(net "P3V3_STBY")
			(options
				(clearance outline)
				(anchor circle)
			)
			(primitives
				(gr_poly
					(pts
						(xy -0.20828 -0.08636) (xy -0.20828 0.08636) (xy -0.08636 0.20828) (xy 0.086614 0.20828) (xy 0.20828 0.086614)
						(xy 0.20828 -0.08636) (xy 0.08636 -0.20828) (xy -0.08636 -0.20828)
					)
					(width 0)
					(fill yes)
				)
			)
		)
		(pad "2" smd custom
			(at 0 0.8001 270)
			(size 0.10414 0.10414)
			(layers "B.Cu" "B.Mask" "B.Paste")
			(net "GND")
			(options
				(clearance outline)
				(anchor circle)
			)
			(primitives
				(gr_poly
					(pts
						(xy -0.20828 -0.08636) (xy -0.20828 0.08636) (xy -0.08636 0.20828) (xy 0.086614 0.20828) (xy 0.20828 0.086614)
						(xy 0.20828 -0.08636) (xy 0.08636 -0.20828) (xy -0.08636 -0.20828)
					)
					(width 0)
					(fill yes)
				)
			)
		)
		(zone
			(layer "B.Cu")
			(hatch none 0.5)
			(connect_pads
				(clearance 0)
			)
			(min_thickness 0.25)
			(keepout
				(tracks allowed)
				(vias not_allowed)
				(pads allowed)
				(copperpour not_allowed)
				(footprints allowed)
			)
			(placement
				(enabled no)
				(sheetname "")
			)
			(fill
				(thermal_gap 0.5)
				(thermal_bridge_width 0.5)
				(island_removal_mode 0)
			)
			(polygon
				(pts
					(xy 377.232418 -70.485508) (xy 377.232418 -70.104508) (xy 377.057158 -70.104508) (xy 377.056904 -70.485508)
				)
			)
		)
		(zone
			(layer "B.Cu")
			(hatch none 0.5)
			(connect_pads
				(clearance 0)
			)
			(min_thickness 0.25)
			(keepout
				(tracks not_allowed)
				(vias allowed)
				(pads allowed)
				(copperpour not_allowed)
				(footprints allowed)
			)
			(placement
				(enabled no)
				(sheetname "")
			)
			(fill
				(thermal_gap 0.5)
				(thermal_bridge_width 0.5)
				(island_removal_mode 0)
			)
			(polygon
				(pts
					(xy 377.232418 -70.485508) (xy 377.232418 -70.104508) (xy 377.057158 -70.104508) (xy 377.056904 -70.485508)
				)
			)
		)
	)
	(footprint ""
		(layer "B.Cu")
		(at 349.489014 -122.459242 -90)
		(property "Reference" "C3M14"
			(at 0 0 90)
			(layer "B.SilkS")
			(hide yes)
			(effects
				(font
					(size 1.27 1.27)
				)
				(justify mirror)
			)
		)
		(property "Value" ""
			(at 0 0 90)
			(layer "B.Fab")
			(effects
				(font
					(size 1.27 1.27)
				)
				(justify mirror)
			)
		)
		(duplicate_pad_numbers_are_jumpers no)
		(fp_poly
			(pts
				(xy -0.3048 -0.1016) (xy -0.3048 0.9906) (xy 0.3048 0.9906) (xy 0.3048 -0.1016)
			)
			(stroke
				(width 0)
				(type default)
			)
			(fill no)
			(layer "B.CrtYd")
		)
		(fp_line
			(start -0.3048 0.9906)
			(end -0.3048 -0.1016)
			(stroke
				(width 0.1)
				(type default)
			)
			(layer "B.Fab")
		)
		(fp_line
			(start 0.3048 0.9906)
			(end -0.3048 0.9906)
			(stroke
				(width 0.1)
				(type default)
			)
			(layer "B.Fab")
		)
		(fp_line
			(start -0.3048 -0.1016)
			(end 0.3048 -0.1016)
			(stroke
				(width 0.1)
				(type default)
			)
			(layer "B.Fab")
		)
		(fp_line
			(start 0.3048 -0.1016)
			(end 0.3048 0.9906)
			(stroke
				(width 0.1)
				(type default)
			)
			(layer "B.Fab")
		)
		(pad "1" smd rect
			(at 0 0 90)
			(size 0.508 0.508)
			(layers "B.Cu" "B.Mask" "B.Paste")
			(net "P3E_CPU0_PE1_PCH_R_RXN<13>")
		)
		(pad "2" smd rect
			(at 0 0.889 90)
			(size 0.508 0.508)
			(layers "B.Cu" "B.Mask" "B.Paste")
			(net "P3E_CPU0_PE1_PCH_RXN<13>")
		)
		(zone
			(layer "B.Cu")
			(hatch none 0.5)
			(connect_pads
				(clearance 0)
			)
			(min_thickness 0.25)
			(keepout
				(tracks not_allowed)
				(vias allowed)
				(pads allowed)
				(copperpour not_allowed)
				(footprints allowed)
			)
			(placement
				(enabled no)
				(sheetname "")
			)
			(fill
				(thermal_gap 0.5)
				(thermal_bridge_width 0.5)
				(island_removal_mode 0)
			)
			(polygon
				(pts
					(xy 348.854014 -122.205242) (xy 348.854014 -122.713242) (xy 349.235014 -122.713242) (xy 349.235014 -122.205242)
				)
			)
		)
		(zone
			(layer "B.Cu")
			(hatch none 0.5)
			(connect_pads
				(clearance 0)
			)
			(min_thickness 0.25)
			(keepout
				(tracks allowed)
				(vias not_allowed)
				(pads allowed)
				(copperpour not_allowed)
				(footprints allowed)
			)
			(placement
				(enabled no)
				(sheetname "")
			)
			(fill
				(thermal_gap 0.5)
				(thermal_bridge_width 0.5)
				(island_removal_mode 0)
			)
			(polygon
				(pts
					(xy 349.235014 -122.205242) (xy 349.235014 -122.713242) (xy 348.854014 -122.713242) (xy 348.854014 -122.205242)
				)
			)
		)
	)
	(footprint ""
		(layer "B.Cu")
		(at 403.352 -36.068)
		(property "Reference" "R25W86"
			(at 0.8382 -0.67818 0)
			(unlocked yes)
			(layer "B.SilkS")
			(effects
				(font
					(size 0.4064 0.254)
					(thickness 0.1524)
				)
				(justify left mirror)
			)
		)
		(property "Value" ""
			(at 0 0 0)
			(layer "B.Fab")
			(effects
				(font
					(size 1.27 1.27)
				)
				(justify mirror)
			)
		)
		(duplicate_pad_numbers_are_jumpers no)
		(fp_poly
			(pts
				(xy 0.2794 -0.1016) (xy -0.2794 -0.1016) (xy -0.2794 0.9906) (xy 0.2794 0.9906)
			)
			(stroke
				(width 0)
				(type default)
			)
			(fill no)
			(layer "B.CrtYd")
		)
		(fp_line
			(start -0.2794 -0.1016)
			(end 0.2794 -0.1016)
			(stroke
				(width 0.1)
				(type default)
			)
			(layer "B.Fab")
		)
		(fp_line
			(start -0.2794 0.9906)
			(end -0.2794 -0.1016)
			(stroke
				(width 0.1)
				(type default)
			)
			(layer "B.Fab")
		)
		(fp_line
			(start 0.2794 -0.1016)
			(end 0.2794 0.9906)
			(stroke
				(width 0.1)
				(type default)
			)
			(layer "B.Fab")
		)
		(fp_line
			(start 0.2794 0.9906)
			(end -0.2794 0.9906)
			(stroke
				(width 0.1)
				(type default)
			)
			(layer "B.Fab")
		)
		(pad "1" smd rect
			(at 0 0 180)
			(size 0.508 0.508)
			(layers "B.Cu" "B.Mask" "B.Paste")
			(net "RMII_BMC_OCP_TXD0_R")
		)
		(pad "2" smd rect
			(at 0 0.889 180)
			(size 0.508 0.508)
			(layers "B.Cu" "B.Mask" "B.Paste")
			(net "RMII_BMC_OCP_TXD0")
		)
		(zone
			(layer "B.Cu")
			(hatch none 0.5)
			(connect_pads
				(clearance 0)
			)
			(min_thickness 0.25)
			(keepout
				(tracks allowed)
				(vias not_allowed)
				(pads allowed)
				(copperpour not_allowed)
				(footprints allowed)
			)
			(placement
				(enabled no)
				(sheetname "")
			)
			(fill
				(thermal_gap 0.5)
				(thermal_bridge_width 0.5)
				(island_removal_mode 0)
			)
			(polygon
				(pts
					(xy 403.606 -35.814) (xy 403.098 -35.814) (xy 403.098 -35.433) (xy 403.606 -35.433)
				)
			)
		)
		(zone
			(layer "B.Cu")
			(hatch none 0.5)
			(connect_pads
				(clearance 0)
			)
			(min_thickness 0.25)
			(keepout
				(tracks not_allowed)
				(vias allowed)
				(pads allowed)
				(copperpour not_allowed)
				(footprints allowed)
			)
			(placement
				(enabled no)
				(sheetname "")
			)
			(fill
				(thermal_gap 0.5)
				(thermal_bridge_width 0.5)
				(island_removal_mode 0)
			)
			(polygon
				(pts
					(xy 403.606 -35.433) (xy 403.098 -35.433) (xy 403.098 -35.814) (xy 403.606 -35.814)
				)
			)
		)
	)
	(footprint ""
		(layer "B.Cu")
		(at 494.665 -135.2804 -90)
		(property "Reference" "Q6W4"
			(at 0.229362 -1.59512 270)
			(unlocked yes)
			(layer "B.SilkS")
			(effects
				(font
					(size 1.27 0.9652)
					(thickness 0.1524)
				)
				(justify left mirror)
			)
		)
		(property "Value" ""
			(at 0 0 90)
			(layer "B.Fab")
			(effects
				(font
					(size 1.27 1.27)
				)
				(justify mirror)
			)
		)
		(duplicate_pad_numbers_are_jumpers no)
		(fp_line
			(start -1.778 2.4765)
			(end -1.778 1.5875)
			(stroke
				(width 0.1524)
				(type default)
			)
			(layer "B.SilkS")
		)
		(fp_line
			(start -0.9525 2.4765)
			(end -1.778 2.4765)
			(stroke
				(width 0.1524)
				(type default)
			)
			(layer "B.SilkS")
		)
		(fp_line
			(start -0.381 0.635)
			(end -0.381 1.27)
			(stroke
				(width 0.1524)
				(type default)
			)
			(layer "B.SilkS")
		)
		(fp_line
			(start -1.778 -0.5715)
			(end -1.778 0.3175)
			(stroke
				(width 0.1524)
				(type default)
			)
			(layer "B.SilkS")
		)
		(fp_line
			(start -0.9525 -0.5715)
			(end -1.778 -0.5715)
			(stroke
				(width 0.1524)
				(type default)
			)
			(layer "B.SilkS")
		)
		(fp_circle
			(center 0.51816 -0.82423)
			(end 0.51816 -0.95123)
			(stroke
				(width 0.254)
				(type default)
			)
			(fill no)
			(layer "B.SilkS")
		)
		(fp_poly
			(pts
				(xy -1.778 2.4765) (xy -0.381 2.4765) (xy -0.381 -0.5715) (xy -1.778 -0.5715)
			)
			(stroke
				(width 0)
				(type default)
			)
			(fill no)
			(layer "B.CrtYd")
		)
		(fp_line
			(start -1.778 2.4765)
			(end -1.778 -0.5715)
			(stroke
				(width 0.1)
				(type default)
			)
			(layer "B.Fab")
		)
		(fp_line
			(start -0.381 2.4765)
			(end -1.778 2.4765)
			(stroke
				(width 0.1)
				(type default)
			)
			(layer "B.Fab")
		)
		(fp_line
			(start -1.778 -0.5715)
			(end -0.381 -0.5715)
			(stroke
				(width 0.1)
				(type default)
			)
			(layer "B.Fab")
		)
		(fp_line
			(start -0.381 -0.5715)
			(end -0.381 2.4765)
			(stroke
				(width 0.1)
				(type default)
			)
			(layer "B.Fab")
		)
		(fp_circle
			(center 0.9525 -0.9271)
			(end 0.9525 -1.0541)
			(stroke
				(width 0.254)
				(type default)
			)
			(fill no)
			(layer "B.Fab")
		)
		(pad "1" smd rect
			(at 0 0 90)
			(size 1.143 0.508)
			(layers "B.Cu" "B.Mask" "B.Paste")
			(net "DEBUG_CARD2_PRSNT")
		)
		(pad "2" smd rect
			(at 0 1.905 90)
			(size 1.143 0.508)
			(layers "B.Cu" "B.Mask" "B.Paste")
			(net "GND")
		)
		(pad "3" smd rect
			(at -2.159 0.9525 90)
			(size 1.143 0.508)
			(layers "B.Cu" "B.Mask" "B.Paste")
			(net "FM_POST_CARD_PRES_BMC_N")
		)
	)
	(footprint ""
		(layer "B.Cu")
		(at 22.225 -81.534)
		(property "Reference" "C9P6"
			(at 0 0 0)
			(layer "B.SilkS")
			(hide yes)
			(effects
				(font
					(size 1.27 1.27)
				)
				(justify mirror)
			)
		)
		(property "Value" ""
			(at 0 0 0)
			(layer "B.Fab")
			(effects
				(font
					(size 1.27 1.27)
				)
				(justify mirror)
			)
		)
		(duplicate_pad_numbers_are_jumpers no)
		(fp_poly
			(pts
				(xy -0.3048 -0.1016) (xy -0.3048 0.9906) (xy 0.3048 0.9906) (xy 0.3048 -0.1016)
			)
			(stroke
				(width 0)
				(type default)
			)
			(fill no)
			(layer "B.CrtYd")
		)
		(fp_line
			(start -0.3048 -0.1016)
			(end 0.3048 -0.1016)
			(stroke
				(width 0.1)
				(type default)
			)
			(layer "B.Fab")
		)
		(fp_line
			(start -0.3048 0.9906)
			(end -0.3048 -0.1016)
			(stroke
				(width 0.1)
				(type default)
			)
			(layer "B.Fab")
		)
		(fp_line
			(start 0.3048 -0.1016)
			(end 0.3048 0.9906)
			(stroke
				(width 0.1)
				(type default)
			)
			(layer "B.Fab")
		)
		(fp_line
			(start 0.3048 0.9906)
			(end -0.3048 0.9906)
			(stroke
				(width 0.1)
				(type default)
			)
			(layer "B.Fab")
		)
		(pad "1" smd rect
			(at 0 0 180)
			(size 0.508 0.508)
			(layers "B.Cu" "B.Mask" "B.Paste")
			(net "P12V_STBY")
		)
		(pad "2" smd rect
			(at 0 0.889 180)
			(size 0.508 0.508)
			(layers "B.Cu" "B.Mask" "B.Paste")
			(net "AGND_HSC")
		)
		(zone
			(layer "B.Cu")
			(hatch none 0.5)
			(connect_pads
				(clearance 0)
			)
			(min_thickness 0.25)
			(keepout
				(tracks allowed)
				(vias not_allowed)
				(pads allowed)
				(copperpour not_allowed)
				(footprints allowed)
			)
			(placement
				(enabled no)
				(sheetname "")
			)
			(fill
				(thermal_gap 0.5)
				(thermal_bridge_width 0.5)
				(island_removal_mode 0)
			)
			(polygon
				(pts
					(xy 22.479 -81.28) (xy 21.971 -81.28) (xy 21.971 -80.899) (xy 22.479 -80.899)
				)
			)
		)
		(zone
			(layer "B.Cu")
			(hatch none 0.5)
			(connect_pads
				(clearance 0)
			)
			(min_thickness 0.25)
			(keepout
				(tracks not_allowed)
				(vias allowed)
				(pads allowed)
				(copperpour not_allowed)
				(footprints allowed)
			)
			(placement
				(enabled no)
				(sheetname "")
			)
			(fill
				(thermal_gap 0.5)
				(thermal_bridge_width 0.5)
				(island_removal_mode 0)
			)
			(polygon
				(pts
					(xy 22.479 -80.899) (xy 21.971 -80.899) (xy 21.971 -81.28) (xy 22.479 -81.28)
				)
			)
		)
	)
	(footprint ""
		(layer "B.Cu")
		(at 394.208 -62.738 90)
		(property "Reference" "C2T12"
			(at 0 0 90)
			(layer "B.SilkS")
			(hide yes)
			(effects
				(font
					(size 1.27 1.27)
				)
				(justify mirror)
			)
		)
		(property "Value" ""
			(at 0 0 90)
			(layer "B.Fab")
			(effects
				(font
					(size 1.27 1.27)
				)
				(justify mirror)
			)
		)
		(duplicate_pad_numbers_are_jumpers no)
		(fp_poly
			(pts
				(xy -0.3048 -0.1016) (xy -0.3048 0.9906) (xy 0.3048 0.9906) (xy 0.3048 -0.1016)
			)
			(stroke
				(width 0)
				(type default)
			)
			(fill no)
			(layer "B.CrtYd")
		)
		(fp_line
			(start 0.3048 -0.1016)
			(end 0.3048 0.9906)
			(stroke
				(width 0.1)
				(type default)
			)
			(layer "B.Fab")
		)
		(fp_line
			(start -0.3048 -0.1016)
			(end 0.3048 -0.1016)
			(stroke
				(width 0.1)
				(type default)
			)
			(layer "B.Fab")
		)
		(fp_line
			(start 0.3048 0.9906)
			(end -0.3048 0.9906)
			(stroke
				(width 0.1)
				(type default)
			)
			(layer "B.Fab")
		)
		(fp_line
			(start -0.3048 0.9906)
			(end -0.3048 -0.1016)
			(stroke
				(width 0.1)
				(type default)
			)
			(layer "B.Fab")
		)
		(pad "1" smd rect
			(at 0 0 270)
			(size 0.508 0.508)
			(layers "B.Cu" "B.Mask" "B.Paste")
			(net "P3V3_STBY")
		)
		(pad "2" smd rect
			(at 0 0.889 270)
			(size 0.508 0.508)
			(layers "B.Cu" "B.Mask" "B.Paste")
			(net "GND")
		)
		(zone
			(layer "B.Cu")
			(hatch none 0.5)
			(connect_pads
				(clearance 0)
			)
			(min_thickness 0.25)
			(keepout
				(tracks allowed)
				(vias not_allowed)
				(pads allowed)
				(copperpour not_allowed)
				(footprints allowed)
			)
			(placement
				(enabled no)
				(sheetname "")
			)
			(fill
				(thermal_gap 0.5)
				(thermal_bridge_width 0.5)
				(island_removal_mode 0)
			)
			(polygon
				(pts
					(xy 394.462 -62.992) (xy 394.462 -62.484) (xy 394.843 -62.484) (xy 394.843 -62.992)
				)
			)
		)
		(zone
			(layer "B.Cu")
			(hatch none 0.5)
			(connect_pads
				(clearance 0)
			)
			(min_thickness 0.25)
			(keepout
				(tracks not_allowed)
				(vias allowed)
				(pads allowed)
				(copperpour not_allowed)
				(footprints allowed)
			)
			(placement
				(enabled no)
				(sheetname "")
			)
			(fill
				(thermal_gap 0.5)
				(thermal_bridge_width 0.5)
				(island_removal_mode 0)
			)
			(polygon
				(pts
					(xy 394.843 -62.992) (xy 394.843 -62.484) (xy 394.462 -62.484) (xy 394.462 -62.992)
				)
			)
		)
	)
	(footprint ""
		(layer "B.Cu")
		(at 348.713806 -60.368434)
		(property "Reference" "R2U25"
			(at 0 0 0)
			(layer "B.SilkS")
			(hide yes)
			(effects
				(font
					(size 1.27 1.27)
				)
				(justify mirror)
			)
		)
		(property "Value" ""
			(at 0 0 0)
			(layer "B.Fab")
			(effects
				(font
					(size 1.27 1.27)
				)
				(justify mirror)
			)
		)
		(duplicate_pad_numbers_are_jumpers no)
		(fp_poly
			(pts
				(xy 0.2794 -0.1016) (xy -0.2794 -0.1016) (xy -0.2794 0.9906) (xy 0.2794 0.9906)
			)
			(stroke
				(width 0)
				(type default)
			)
			(fill no)
			(layer "B.CrtYd")
		)
		(fp_line
			(start -0.2794 -0.1016)
			(end 0.2794 -0.1016)
			(stroke
				(width 0.1)
				(type default)
			)
			(layer "B.Fab")
		)
		(fp_line
			(start -0.2794 0.9906)
			(end -0.2794 -0.1016)
			(stroke
				(width 0.1)
				(type default)
			)
			(layer "B.Fab")
		)
		(fp_line
			(start 0.2794 -0.1016)
			(end 0.2794 0.9906)
			(stroke
				(width 0.1)
				(type default)
			)
			(layer "B.Fab")
		)
		(fp_line
			(start 0.2794 0.9906)
			(end -0.2794 0.9906)
			(stroke
				(width 0.1)
				(type default)
			)
			(layer "B.Fab")
		)
		(pad "1" smd rect
			(at 0 0 180)
			(size 0.508 0.508)
			(layers "B.Cu" "B.Mask" "B.Paste")
			(net "P3E_CPU0_PE1_SS_RXN<5>")
		)
		(pad "2" smd rect
			(at 0 0.889 180)
			(size 0.508 0.508)
			(layers "B.Cu" "B.Mask" "B.Paste")
			(net "P3E_CPU0_PE1_SS_R_RXN<5>")
		)
		(zone
			(layer "B.Cu")
			(hatch none 0.5)
			(connect_pads
				(clearance 0)
			)
			(min_thickness 0.25)
			(keepout
				(tracks allowed)
				(vias not_allowed)
				(pads allowed)
				(copperpour not_allowed)
				(footprints allowed)
			)
			(placement
				(enabled no)
				(sheetname "")
			)
			(fill
				(thermal_gap 0.5)
				(thermal_bridge_width 0.5)
				(island_removal_mode 0)
			)
			(polygon
				(pts
					(xy 348.967806 -60.114434) (xy 348.459806 -60.114434) (xy 348.459806 -59.733434) (xy 348.967806 -59.733434)
				)
			)
		)
	)
	(footprint ""
		(layer "B.Cu")
		(at 344.522806 -60.368434)
		(property "Reference" "R2U22"
			(at 0 0 0)
			(layer "B.SilkS")
			(hide yes)
			(effects
				(font
					(size 1.27 1.27)
				)
				(justify mirror)
			)
		)
		(property "Value" ""
			(at 0 0 0)
			(layer "B.Fab")
			(effects
				(font
					(size 1.27 1.27)
				)
				(justify mirror)
			)
		)
		(duplicate_pad_numbers_are_jumpers no)
		(fp_poly
			(pts
				(xy 0.2794 -0.1016) (xy -0.2794 -0.1016) (xy -0.2794 0.9906) (xy 0.2794 0.9906)
			)
			(stroke
				(width 0)
				(type default)
			)
			(fill no)
			(layer "B.CrtYd")
		)
		(fp_line
			(start -0.2794 -0.1016)
			(end 0.2794 -0.1016)
			(stroke
				(width 0.1)
				(type default)
			)
			(layer "B.Fab")
		)
		(fp_line
			(start -0.2794 0.9906)
			(end -0.2794 -0.1016)
			(stroke
				(width 0.1)
				(type default)
			)
			(layer "B.Fab")
		)
		(fp_line
			(start 0.2794 -0.1016)
			(end 0.2794 0.9906)
			(stroke
				(width 0.1)
				(type default)
			)
			(layer "B.Fab")
		)
		(fp_line
			(start 0.2794 0.9906)
			(end -0.2794 0.9906)
			(stroke
				(width 0.1)
				(type default)
			)
			(layer "B.Fab")
		)
		(pad "1" smd rect
			(at 0 0 180)
			(size 0.508 0.508)
			(layers "B.Cu" "B.Mask" "B.Paste")
			(net "P3E_CPU0_PE1_SS_RXP<4>")
		)
		(pad "2" smd rect
			(at 0 0.889 180)
			(size 0.508 0.508)
			(layers "B.Cu" "B.Mask" "B.Paste")
			(net "P3E_CPU0_PE1_SS_R_RXP<4>")
		)
		(zone
			(layer "B.Cu")
			(hatch none 0.5)
			(connect_pads
				(clearance 0)
			)
			(min_thickness 0.25)
			(keepout
				(tracks allowed)
				(vias not_allowed)
				(pads allowed)
				(copperpour not_allowed)
				(footprints allowed)
			)
			(placement
				(enabled no)
				(sheetname "")
			)
			(fill
				(thermal_gap 0.5)
				(thermal_bridge_width 0.5)
				(island_removal_mode 0)
			)
			(polygon
				(pts
					(xy 344.776806 -60.114434) (xy 344.268806 -60.114434) (xy 344.268806 -59.733434) (xy 344.776806 -59.733434)
				)
			)
		)
	)
	(footprint ""
		(layer "B.Cu")
		(at 453.8472 -131.8514 -90)
		(property "Reference" "R1M19"
			(at 0 0 90)
			(layer "B.SilkS")
			(hide yes)
			(effects
				(font
					(size 1.27 1.27)
				)
				(justify mirror)
			)
		)
		(property "Value" ""
			(at 0 0 90)
			(layer "B.Fab")
			(effects
				(font
					(size 1.27 1.27)
				)
				(justify mirror)
			)
		)
		(duplicate_pad_numbers_are_jumpers no)
		(fp_poly
			(pts
				(xy 0.2794 -0.1016) (xy -0.2794 -0.1016) (xy -0.2794 0.9906) (xy 0.2794 0.9906)
			)
			(stroke
				(width 0)
				(type default)
			)
			(fill no)
			(layer "B.CrtYd")
		)
		(fp_line
			(start -0.2794 0.9906)
			(end -0.2794 -0.1016)
			(stroke
				(width 0.1)
				(type default)
			)
			(layer "B.Fab")
		)
		(fp_line
			(start 0.2794 0.9906)
			(end -0.2794 0.9906)
			(stroke
				(width 0.1)
				(type default)
			)
			(layer "B.Fab")
		)
		(fp_line
			(start -0.2794 -0.1016)
			(end 0.2794 -0.1016)
			(stroke
				(width 0.1)
				(type default)
			)
			(layer "B.Fab")
		)
		(fp_line
			(start 0.2794 -0.1016)
			(end 0.2794 0.9906)
			(stroke
				(width 0.1)
				(type default)
			)
			(layer "B.Fab")
		)
		(pad "1" smd rect
			(at 0 0 90)
			(size 0.508 0.508)
			(layers "B.Cu" "B.Mask" "B.Paste")
			(net "P1V8_MCP_CPU0")
		)
		(pad "2" smd rect
			(at 0 0.889 90)
			(size 0.508 0.508)
			(layers "B.Cu" "B.Mask" "B.Paste")
			(net "JTAG_MCP_TMS")
		)
		(zone
			(layer "B.Cu")
			(hatch none 0.5)
			(connect_pads
				(clearance 0)
			)
			(min_thickness 0.25)
			(keepout
				(tracks not_allowed)
				(vias allowed)
				(pads allowed)
				(copperpour not_allowed)
				(footprints allowed)
			)
			(placement
				(enabled no)
				(sheetname "")
			)
			(fill
				(thermal_gap 0.5)
				(thermal_bridge_width 0.5)
				(island_removal_mode 0)
			)
			(polygon
				(pts
					(xy 453.2122 -131.5974) (xy 453.2122 -132.1054) (xy 453.5932 -132.1054) (xy 453.5932 -131.5974)
				)
			)
		)
		(zone
			(layer "B.Cu")
			(hatch none 0.5)
			(connect_pads
				(clearance 0)
			)
			(min_thickness 0.25)
			(keepout
				(tracks allowed)
				(vias not_allowed)
				(pads allowed)
				(copperpour not_allowed)
				(footprints allowed)
			)
			(placement
				(enabled no)
				(sheetname "")
			)
			(fill
				(thermal_gap 0.5)
				(thermal_bridge_width 0.5)
				(island_removal_mode 0)
			)
			(polygon
				(pts
					(xy 453.5932 -131.5974) (xy 453.5932 -132.1054) (xy 453.2122 -132.1054) (xy 453.2122 -131.5974)
				)
			)
		)
	)
	(footprint ""
		(layer "B.Cu")
		(at 32.832802 -92.485464 90)
		(property "Reference" "C9N25"
			(at 0 0 90)
			(layer "B.SilkS")
			(hide yes)
			(effects
				(font
					(size 1.27 1.27)
				)
				(justify mirror)
			)
		)
		(property "Value" ""
			(at 0 0 90)
			(layer "B.Fab")
			(effects
				(font
					(size 1.27 1.27)
				)
				(justify mirror)
			)
		)
		(duplicate_pad_numbers_are_jumpers no)
		(fp_poly
			(pts
				(xy 0.7239 -0.2159) (xy -0.7239 -0.2159) (xy -0.7239 1.9939) (xy 0.7239 1.9939)
			)
			(stroke
				(width 0)
				(type default)
			)
			(fill no)
			(layer "B.CrtYd")
		)
		(fp_line
			(start 0.7239 -0.2159)
			(end 0.7239 1.9939)
			(stroke
				(width 0.1)
				(type default)
			)
			(layer "B.Fab")
		)
		(fp_line
			(start -0.7239 -0.2159)
			(end 0.7239 -0.2159)
			(stroke
				(width 0.1)
				(type default)
			)
			(layer "B.Fab")
		)
		(fp_line
			(start 0.7239 1.9939)
			(end -0.7239 1.9939)
			(stroke
				(width 0.1)
				(type default)
			)
			(layer "B.Fab")
		)
		(fp_line
			(start -0.7239 1.9939)
			(end -0.7239 -0.2159)
			(stroke
				(width 0.1)
				(type default)
			)
			(layer "B.Fab")
		)
		(pad "1" smd rect
			(at 0 0 270)
			(size 1.27 1.016)
			(layers "B.Cu" "B.Mask" "B.Paste")
			(net "VR_FET_SW_P12V_STBY_PVCCIN_CPU1")
		)
		(pad "2" smd rect
			(at 0 1.778 270)
			(size 1.27 1.016)
			(layers "B.Cu" "B.Mask" "B.Paste")
			(net "GND")
		)
		(zone
			(layer "B.Cu")
			(hatch none 0.5)
			(connect_pads
				(clearance 0)
			)
			(min_thickness 0.25)
			(keepout
				(tracks not_allowed)
				(vias allowed)
				(pads allowed)
				(copperpour not_allowed)
				(footprints allowed)
			)
			(placement
				(enabled no)
				(sheetname "")
			)
			(fill
				(thermal_gap 0.5)
				(thermal_bridge_width 0.5)
				(island_removal_mode 0)
			)
			(polygon
				(pts
					(xy 33.340802 -93.120464) (xy 33.340802 -91.850464) (xy 34.102802 -91.850464) (xy 34.102802 -93.120464)
				)
			)
		)
	)
	(footprint ""
		(layer "B.Cu")
		(at 418.680646 -45.539152)
		(property "Reference" "R25W98"
			(at 0.8382 -0.67818 0)
			(unlocked yes)
			(layer "B.SilkS")
			(effects
				(font
					(size 0.4064 0.254)
					(thickness 0.1524)
				)
				(justify left mirror)
			)
		)
		(property "Value" ""
			(at 0 0 0)
			(layer "B.Fab")
			(effects
				(font
					(size 1.27 1.27)
				)
				(justify mirror)
			)
		)
		(duplicate_pad_numbers_are_jumpers no)
		(fp_poly
			(pts
				(xy 0.2794 -0.1016) (xy -0.2794 -0.1016) (xy -0.2794 0.9906) (xy 0.2794 0.9906)
			)
			(stroke
				(width 0)
				(type default)
			)
			(fill no)
			(layer "B.CrtYd")
		)
		(fp_line
			(start -0.2794 -0.1016)
			(end 0.2794 -0.1016)
			(stroke
				(width 0.1)
				(type default)
			)
			(layer "B.Fab")
		)
		(fp_line
			(start -0.2794 0.9906)
			(end -0.2794 -0.1016)
			(stroke
				(width 0.1)
				(type default)
			)
			(layer "B.Fab")
		)
		(fp_line
			(start 0.2794 -0.1016)
			(end 0.2794 0.9906)
			(stroke
				(width 0.1)
				(type default)
			)
			(layer "B.Fab")
		)
		(fp_line
			(start 0.2794 0.9906)
			(end -0.2794 0.9906)
			(stroke
				(width 0.1)
				(type default)
			)
			(layer "B.Fab")
		)
		(pad "1" smd rect
			(at 0 0 180)
			(size 0.508 0.508)
			(layers "B.Cu" "B.Mask" "B.Paste")
			(net "P3V3_STBY")
		)
		(pad "2" smd rect
			(at 0 0.889 180)
			(size 0.508 0.508)
			(layers "B.Cu" "B.Mask" "B.Paste")
			(net "BMC_STRAP_BIT3")
		)
		(zone
			(layer "B.Cu")
			(hatch none 0.5)
			(connect_pads
				(clearance 0)
			)
			(min_thickness 0.25)
			(keepout
				(tracks allowed)
				(vias not_allowed)
				(pads allowed)
				(copperpour not_allowed)
				(footprints allowed)
			)
			(placement
				(enabled no)
				(sheetname "")
			)
			(fill
				(thermal_gap 0.5)
				(thermal_bridge_width 0.5)
				(island_removal_mode 0)
			)
			(polygon
				(pts
					(xy 418.934646 -45.285152) (xy 418.426646 -45.285152) (xy 418.426646 -44.904152) (xy 418.934646 -44.904152)
				)
			)
		)
		(zone
			(layer "B.Cu")
			(hatch none 0.5)
			(connect_pads
				(clearance 0)
			)
			(min_thickness 0.25)
			(keepout
				(tracks not_allowed)
				(vias allowed)
				(pads allowed)
				(copperpour not_allowed)
				(footprints allowed)
			)
			(placement
				(enabled no)
				(sheetname "")
			)
			(fill
				(thermal_gap 0.5)
				(thermal_bridge_width 0.5)
				(island_removal_mode 0)
			)
			(polygon
				(pts
					(xy 418.934646 -44.904152) (xy 418.426646 -44.904152) (xy 418.426646 -45.285152) (xy 418.934646 -45.285152)
				)
			)
		)
	)
	(footprint ""
		(layer "B.Cu")
		(at 184.0484 -132.842 90)
		(property "Reference" "C22W5"
			(at 0 0 90)
			(layer "B.SilkS")
			(hide yes)
			(effects
				(font
					(size 1.27 1.27)
				)
				(justify mirror)
			)
		)
		(property "Value" "*"
			(at 0.0762 -6.2357 90)
			(unlocked yes)
			(layer "B.Fab")
			(hide yes)
			(effects
				(font
					(size 1.27 1.016)
					(thickness 0.1524)
				)
				(justify mirror)
			)
		)
		(property "Device Type" "SC22U16V5MX-4-GP_SMD-BCG5-SC22A"
			(at 0.0762 -8.2677 90)
			(unlocked yes)
			(layer "B.Fab")
			(hide yes)
			(effects
				(font
					(size 1.27 1.016)
					(thickness 0.1524)
				)
				(justify mirror)
			)
		)
		(duplicate_pad_numbers_are_jumpers no)
		(fp_line
			(start -0.635 0)
			(end 0.635 0)
			(stroke
				(width 0.508)
				(type default)
			)
			(layer "B.SilkS")
		)
		(fp_rect
			(start 0.9652 1.778)
			(end -0.9652 -1.778)
			(stroke
				(width 0)
				(type default)
			)
			(fill no)
			(layer "B.CrtYd")
		)
		(fp_poly
			(pts
				(xy 0.9652 -1.778) (xy -0.9652 -1.778) (xy -0.9652 1.778) (xy 0.9652 1.778)
			)
			(stroke
				(width 0)
				(type default)
			)
			(fill no)
			(layer "B.Fab")
		)
		(pad "1" smd rect
			(at 0 -0.9652 270)
			(size 1.397 1.143)
			(layers "B.Cu" "B.Mask" "B.Paste")
			(net "VR_FET_SW_P12V_STBY_PVPP_KLM")
		)
		(pad "2" smd rect
			(at 0 0.9652 270)
			(size 1.397 1.143)
			(layers "B.Cu" "B.Mask" "B.Paste")
			(net "GND")
		)
	)
	(footprint ""
		(layer "B.Cu")
		(at 16.4084 -87.1601 -90)
		(property "Reference" "R9P4"
			(at 0 0 90)
			(layer "B.SilkS")
			(hide yes)
			(effects
				(font
					(size 1.27 1.27)
				)
				(justify mirror)
			)
		)
		(property "Value" ""
			(at 0 0 90)
			(layer "B.Fab")
			(effects
				(font
					(size 1.27 1.27)
				)
				(justify mirror)
			)
		)
		(duplicate_pad_numbers_are_jumpers no)
		(fp_poly
			(pts
				(xy 0.2794 -0.1016) (xy -0.2794 -0.1016) (xy -0.2794 0.9906) (xy 0.2794 0.9906)
			)
			(stroke
				(width 0)
				(type default)
			)
			(fill no)
			(layer "B.CrtYd")
		)
		(fp_line
			(start -0.2794 0.9906)
			(end -0.2794 -0.1016)
			(stroke
				(width 0.1)
				(type default)
			)
			(layer "B.Fab")
		)
		(fp_line
			(start 0.2794 0.9906)
			(end -0.2794 0.9906)
			(stroke
				(width 0.1)
				(type default)
			)
			(layer "B.Fab")
		)
		(fp_line
			(start -0.2794 -0.1016)
			(end 0.2794 -0.1016)
			(stroke
				(width 0.1)
				(type default)
			)
			(layer "B.Fab")
		)
		(fp_line
			(start 0.2794 -0.1016)
			(end 0.2794 0.9906)
			(stroke
				(width 0.1)
				(type default)
			)
			(layer "B.Fab")
		)
		(pad "1" smd rect
			(at 0 0 90)
			(size 0.508 0.508)
			(layers "B.Cu" "B.Mask" "B.Paste")
			(net "P3V3_STBY")
		)
		(pad "2" smd rect
			(at 0 0.889 90)
			(size 0.508 0.508)
			(layers "B.Cu" "B.Mask" "B.Paste")
			(net "IRQ_UV_DETECT_N")
		)
		(zone
			(layer "B.Cu")
			(hatch none 0.5)
			(connect_pads
				(clearance 0)
			)
			(min_thickness 0.25)
			(keepout
				(tracks not_allowed)
				(vias allowed)
				(pads allowed)
				(copperpour not_allowed)
				(footprints allowed)
			)
			(placement
				(enabled no)
				(sheetname "")
			)
			(fill
				(thermal_gap 0.5)
				(thermal_bridge_width 0.5)
				(island_removal_mode 0)
			)
			(polygon
				(pts
					(xy 15.7734 -86.9061) (xy 15.7734 -87.4141) (xy 16.1544 -87.4141) (xy 16.1544 -86.9061)
				)
			)
		)
		(zone
			(layer "B.Cu")
			(hatch none 0.5)
			(connect_pads
				(clearance 0)
			)
			(min_thickness 0.25)
			(keepout
				(tracks allowed)
				(vias not_allowed)
				(pads allowed)
				(copperpour not_allowed)
				(footprints allowed)
			)
			(placement
				(enabled no)
				(sheetname "")
			)
			(fill
				(thermal_gap 0.5)
				(thermal_bridge_width 0.5)
				(island_removal_mode 0)
			)
			(polygon
				(pts
					(xy 16.1544 -86.9061) (xy 16.1544 -87.4141) (xy 15.7734 -87.4141) (xy 15.7734 -86.9061)
				)
			)
		)
	)
	(footprint ""
		(layer "B.Cu")
		(at 17.83842 -100.60432 90)
		(property "Reference" "C9N12"
			(at 0 0 90)
			(layer "B.SilkS")
			(hide yes)
			(effects
				(font
					(size 1.27 1.27)
				)
				(justify mirror)
			)
		)
		(property "Value" ""
			(at 0 0 90)
			(layer "B.Fab")
			(effects
				(font
					(size 1.27 1.27)
				)
				(justify mirror)
			)
		)
		(duplicate_pad_numbers_are_jumpers no)
		(fp_poly
			(pts
				(xy -0.3048 -0.1016) (xy -0.3048 0.9906) (xy 0.3048 0.9906) (xy 0.3048 -0.1016)
			)
			(stroke
				(width 0)
				(type default)
			)
			(fill no)
			(layer "B.CrtYd")
		)
		(fp_line
			(start 0.3048 -0.1016)
			(end 0.3048 0.9906)
			(stroke
				(width 0.1)
				(type default)
			)
			(layer "B.Fab")
		)
		(fp_line
			(start -0.3048 -0.1016)
			(end 0.3048 -0.1016)
			(stroke
				(width 0.1)
				(type default)
			)
			(layer "B.Fab")
		)
		(fp_line
			(start 0.3048 0.9906)
			(end -0.3048 0.9906)
			(stroke
				(width 0.1)
				(type default)
			)
			(layer "B.Fab")
		)
		(fp_line
			(start -0.3048 0.9906)
			(end -0.3048 -0.1016)
			(stroke
				(width 0.1)
				(type default)
			)
			(layer "B.Fab")
		)
		(pad "1" smd rect
			(at 0 0 270)
			(size 0.508 0.508)
			(layers "B.Cu" "B.Mask" "B.Paste")
			(net "P3E_CPU1_PE3_MP_C_TXP<9>")
		)
		(pad "2" smd rect
			(at 0 0.889 270)
			(size 0.508 0.508)
			(layers "B.Cu" "B.Mask" "B.Paste")
			(net "P3E_CPU1_PE3_MP_TXP<9>")
		)
		(zone
			(layer "B.Cu")
			(hatch none 0.5)
			(connect_pads
				(clearance 0)
			)
			(min_thickness 0.25)
			(keepout
				(tracks allowed)
				(vias not_allowed)
				(pads allowed)
				(copperpour not_allowed)
				(footprints allowed)
			)
			(placement
				(enabled no)
				(sheetname "")
			)
			(fill
				(thermal_gap 0.5)
				(thermal_bridge_width 0.5)
				(island_removal_mode 0)
			)
			(polygon
				(pts
					(xy 18.09242 -100.85832) (xy 18.09242 -100.35032) (xy 18.47342 -100.35032) (xy 18.47342 -100.85832)
				)
			)
		)
		(zone
			(layer "B.Cu")
			(hatch none 0.5)
			(connect_pads
				(clearance 0)
			)
			(min_thickness 0.25)
			(keepout
				(tracks not_allowed)
				(vias allowed)
				(pads allowed)
				(copperpour not_allowed)
				(footprints allowed)
			)
			(placement
				(enabled no)
				(sheetname "")
			)
			(fill
				(thermal_gap 0.5)
				(thermal_bridge_width 0.5)
				(island_removal_mode 0)
			)
			(polygon
				(pts
					(xy 18.47342 -100.85832) (xy 18.47342 -100.35032) (xy 18.09242 -100.35032) (xy 18.09242 -100.85832)
				)
			)
		)
	)
	(footprint ""
		(layer "B.Cu")
		(at 30.554168 -135.3312 90)
		(property "Reference" "C9M1"
			(at 0 0 90)
			(layer "B.SilkS")
			(hide yes)
			(effects
				(font
					(size 1.27 1.27)
				)
				(justify mirror)
			)
		)
		(property "Value" ""
			(at 0 0 90)
			(layer "B.Fab")
			(effects
				(font
					(size 1.27 1.27)
				)
				(justify mirror)
			)
		)
		(duplicate_pad_numbers_are_jumpers no)
		(fp_poly
			(pts
				(xy -0.3048 -0.1016) (xy -0.3048 0.9906) (xy 0.3048 0.9906) (xy 0.3048 -0.1016)
			)
			(stroke
				(width 0)
				(type default)
			)
			(fill no)
			(layer "B.CrtYd")
		)
		(fp_line
			(start 0.3048 -0.1016)
			(end 0.3048 0.9906)
			(stroke
				(width 0.1)
				(type default)
			)
			(layer "B.Fab")
		)
		(fp_line
			(start -0.3048 -0.1016)
			(end 0.3048 -0.1016)
			(stroke
				(width 0.1)
				(type default)
			)
			(layer "B.Fab")
		)
		(fp_line
			(start 0.3048 0.9906)
			(end -0.3048 0.9906)
			(stroke
				(width 0.1)
				(type default)
			)
			(layer "B.Fab")
		)
		(fp_line
			(start -0.3048 0.9906)
			(end -0.3048 -0.1016)
			(stroke
				(width 0.1)
				(type default)
			)
			(layer "B.Fab")
		)
		(pad "1" smd rect
			(at 0 0 270)
			(size 0.508 0.508)
			(layers "B.Cu" "B.Mask" "B.Paste")
			(net "M_K_VREF")
		)
		(pad "2" smd rect
			(at 0 0.889 270)
			(size 0.508 0.508)
			(layers "B.Cu" "B.Mask" "B.Paste")
			(net "GND")
		)
		(zone
			(layer "B.Cu")
			(hatch none 0.5)
			(connect_pads
				(clearance 0)
			)
			(min_thickness 0.25)
			(keepout
				(tracks allowed)
				(vias not_allowed)
				(pads allowed)
				(copperpour not_allowed)
				(footprints allowed)
			)
			(placement
				(enabled no)
				(sheetname "")
			)
			(fill
				(thermal_gap 0.5)
				(thermal_bridge_width 0.5)
				(island_removal_mode 0)
			)
			(polygon
				(pts
					(xy 30.808168 -135.5852) (xy 30.808168 -135.0772) (xy 31.189168 -135.0772) (xy 31.189168 -135.5852)
				)
			)
		)
		(zone
			(layer "B.Cu")
			(hatch none 0.5)
			(connect_pads
				(clearance 0)
			)
			(min_thickness 0.25)
			(keepout
				(tracks not_allowed)
				(vias allowed)
				(pads allowed)
				(copperpour not_allowed)
				(footprints allowed)
			)
			(placement
				(enabled no)
				(sheetname "")
			)
			(fill
				(thermal_gap 0.5)
				(thermal_bridge_width 0.5)
				(island_removal_mode 0)
			)
			(polygon
				(pts
					(xy 31.189168 -135.5852) (xy 31.189168 -135.0772) (xy 30.808168 -135.0772) (xy 30.808168 -135.5852)
				)
			)
		)
	)
	(footprint ""
		(layer "B.Cu")
		(at 193.675 -154.559 180)
		(property "Reference" "R6L2"
			(at 0 0 0)
			(layer "B.SilkS")
			(hide yes)
			(effects
				(font
					(size 1.27 1.27)
				)
				(justify mirror)
			)
		)
		(property "Value" ""
			(at 0 0 0)
			(layer "B.Fab")
			(effects
				(font
					(size 1.27 1.27)
				)
				(justify mirror)
			)
		)
		(duplicate_pad_numbers_are_jumpers no)
		(fp_poly
			(pts
				(xy 0.2794 -0.1016) (xy -0.2794 -0.1016) (xy -0.2794 0.9906) (xy 0.2794 0.9906)
			)
			(stroke
				(width 0)
				(type default)
			)
			(fill no)
			(layer "B.CrtYd")
		)
		(fp_line
			(start 0.2794 0.9906)
			(end -0.2794 0.9906)
			(stroke
				(width 0.1)
				(type default)
			)
			(layer "B.Fab")
		)
		(fp_line
			(start 0.2794 -0.1016)
			(end 0.2794 0.9906)
			(stroke
				(width 0.1)
				(type default)
			)
			(layer "B.Fab")
		)
		(fp_line
			(start -0.2794 0.9906)
			(end -0.2794 -0.1016)
			(stroke
				(width 0.1)
				(type default)
			)
			(layer "B.Fab")
		)
		(fp_line
			(start -0.2794 -0.1016)
			(end 0.2794 -0.1016)
			(stroke
				(width 0.1)
				(type default)
			)
			(layer "B.Fab")
		)
		(pad "1" smd rect
			(at 0 0)
			(size 0.508 0.508)
			(layers "B.Cu" "B.Mask" "B.Paste")
			(net "PVDDQ_DEF")
		)
		(pad "2" smd rect
			(at 0 0.889)
			(size 0.508 0.508)
			(layers "B.Cu" "B.Mask" "B.Paste")
			(net "M_F_VREF")
		)
		(zone
			(layer "B.Cu")
			(hatch none 0.5)
			(connect_pads
				(clearance 0)
			)
			(min_thickness 0.25)
			(keepout
				(tracks not_allowed)
				(vias allowed)
				(pads allowed)
				(copperpour not_allowed)
				(footprints allowed)
			)
			(placement
				(enabled no)
				(sheetname "")
			)
			(fill
				(thermal_gap 0.5)
				(thermal_bridge_width 0.5)
				(island_removal_mode 0)
			)
			(polygon
				(pts
					(xy 193.421 -155.194) (xy 193.929 -155.194) (xy 193.929 -154.813) (xy 193.421 -154.813)
				)
			)
		)
		(zone
			(layer "B.Cu")
			(hatch none 0.5)
			(connect_pads
				(clearance 0)
			)
			(min_thickness 0.25)
			(keepout
				(tracks allowed)
				(vias not_allowed)
				(pads allowed)
				(copperpour not_allowed)
				(footprints allowed)
			)
			(placement
				(enabled no)
				(sheetname "")
			)
			(fill
				(thermal_gap 0.5)
				(thermal_bridge_width 0.5)
				(island_removal_mode 0)
			)
			(polygon
				(pts
					(xy 193.421 -154.813) (xy 193.929 -154.813) (xy 193.929 -155.194) (xy 193.421 -155.194)
				)
			)
		)
	)
	(footprint ""
		(layer "B.Cu")
		(at 378.1298 -133.9088 -90)
		(property "Reference" "C3M23"
			(at 0 0 90)
			(layer "B.SilkS")
			(hide yes)
			(effects
				(font
					(size 1.27 1.27)
				)
				(justify mirror)
			)
		)
		(property "Value" ""
			(at 0 0 90)
			(layer "B.Fab")
			(effects
				(font
					(size 1.27 1.27)
				)
				(justify mirror)
			)
		)
		(duplicate_pad_numbers_are_jumpers no)
		(fp_poly
			(pts
				(xy 0.4953 -0.2032) (xy -0.4953 -0.2032) (xy -0.4953 1.6002) (xy 0.4953 1.6002)
			)
			(stroke
				(width 0)
				(type default)
			)
			(fill no)
			(layer "B.CrtYd")
		)
		(fp_line
			(start -0.4953 1.6002)
			(end 0.4953 1.6002)
			(stroke
				(width 0.1)
				(type default)
			)
			(layer "B.Fab")
		)
		(fp_line
			(start 0.4953 1.6002)
			(end 0.4953 -0.2032)
			(stroke
				(width 0.1)
				(type default)
			)
			(layer "B.Fab")
		)
		(fp_line
			(start -0.4953 -0.2032)
			(end -0.4953 1.6002)
			(stroke
				(width 0.1)
				(type default)
			)
			(layer "B.Fab")
		)
		(fp_line
			(start 0.4953 -0.2032)
			(end -0.4953 -0.2032)
			(stroke
				(width 0.1)
				(type default)
			)
			(layer "B.Fab")
		)
		(pad "1" smd rect
			(at 0 0 90)
			(size 0.762 0.889)
			(layers "B.Cu" "B.Mask" "B.Paste")
			(net "P1V05_PCH_STBY_VCCA_XTAL")
		)
		(pad "2" smd rect
			(at 0 1.397 90)
			(size 0.762 0.889)
			(layers "B.Cu" "B.Mask" "B.Paste")
			(net "GND")
		)
		(zone
			(layer "B.Cu")
			(hatch none 0.5)
			(connect_pads
				(clearance 0)
			)
			(min_thickness 0.25)
			(keepout
				(tracks not_allowed)
				(vias allowed)
				(pads allowed)
				(copperpour not_allowed)
				(footprints allowed)
			)
			(placement
				(enabled no)
				(sheetname "")
			)
			(fill
				(thermal_gap 0.5)
				(thermal_bridge_width 0.5)
				(island_removal_mode 0)
			)
			(polygon
				(pts
					(xy 377.6853 -133.5278) (xy 377.6853 -134.2898) (xy 377.1773 -134.2898) (xy 377.1773 -133.5278)
				)
			)
		)
	)
	(footprint ""
		(layer "B.Cu")
		(at 83.856068 -149.8092 -90)
		(property "Reference" "C5G100"
			(at -1.14681 0.76708 0)
			(unlocked yes)
			(layer "B.SilkS")
			(effects
				(font
					(size 0.7874 0.5842)
					(thickness 0.1524)
				)
				(justify mirror)
			)
		)
		(property "Value" ""
			(at 0 0 90)
			(layer "B.Fab")
			(effects
				(font
					(size 1.27 1.27)
				)
				(justify mirror)
			)
		)
		(duplicate_pad_numbers_are_jumpers no)
		(fp_rect
			(start 0.4953 1.6002)
			(end -0.4953 -0.2032)
			(stroke
				(width 0)
				(type default)
			)
			(fill no)
			(layer "B.CrtYd")
		)
		(fp_line
			(start -0.4953 1.6002)
			(end 0.4953 1.6002)
			(stroke
				(width 0.1)
				(type default)
			)
			(layer "B.Fab")
		)
		(fp_line
			(start 0.4953 1.6002)
			(end 0.4953 -0.2032)
			(stroke
				(width 0.1)
				(type default)
			)
			(layer "B.Fab")
		)
		(fp_line
			(start -0.4953 -0.2032)
			(end -0.4953 1.6002)
			(stroke
				(width 0.1)
				(type default)
			)
			(layer "B.Fab")
		)
		(fp_line
			(start 0.4953 -0.2032)
			(end -0.4953 -0.2032)
			(stroke
				(width 0.1)
				(type default)
			)
			(layer "B.Fab")
		)
		(pad "1" smd rect
			(at 0 0 90)
			(size 0.762 0.889)
			(layers "B.Cu" "B.Mask" "B.Paste")
			(net "PVDDQ_KLM")
		)
		(pad "2" smd rect
			(at 0 1.397 90)
			(size 0.762 0.889)
			(layers "B.Cu" "B.Mask" "B.Paste")
			(net "GND")
		)
		(zone
			(layer "B.Cu")
			(hatch none 0.5)
			(connect_pads
				(clearance 0)
			)
			(min_thickness 0.25)
			(keepout
				(tracks not_allowed)
				(vias allowed)
				(pads allowed)
				(copperpour not_allowed)
				(footprints allowed)
			)
			(placement
				(enabled no)
				(sheetname "")
			)
			(fill
				(thermal_gap 0.5)
				(thermal_bridge_width 0.5)
				(island_removal_mode 0)
			)
			(polygon
				(pts
					(xy 82.903568 -149.4282) (xy 83.411568 -149.4282) (xy 83.411568 -150.1902) (xy 82.903568 -150.1902)
				)
			)
		)
	)
	(footprint ""
		(layer "B.Cu")
		(at 467.868 -46.6725 180)
		(property "Reference" "R9E11"
			(at 0 0 0)
			(layer "B.SilkS")
			(hide yes)
			(effects
				(font
					(size 1.27 1.27)
				)
				(justify mirror)
			)
		)
		(property "Value" ""
			(at 0 0 0)
			(layer "B.Fab")
			(effects
				(font
					(size 1.27 1.27)
				)
				(justify mirror)
			)
		)
		(duplicate_pad_numbers_are_jumpers no)
		(fp_poly
			(pts
				(xy 0.2794 -0.1016) (xy -0.2794 -0.1016) (xy -0.2794 0.9906) (xy 0.2794 0.9906)
			)
			(stroke
				(width 0)
				(type default)
			)
			(fill no)
			(layer "B.CrtYd")
		)
		(fp_line
			(start 0.2794 0.9906)
			(end -0.2794 0.9906)
			(stroke
				(width 0.1)
				(type default)
			)
			(layer "B.Fab")
		)
		(fp_line
			(start 0.2794 -0.1016)
			(end 0.2794 0.9906)
			(stroke
				(width 0.1)
				(type default)
			)
			(layer "B.Fab")
		)
		(fp_line
			(start -0.2794 0.9906)
			(end -0.2794 -0.1016)
			(stroke
				(width 0.1)
				(type default)
			)
			(layer "B.Fab")
		)
		(fp_line
			(start -0.2794 -0.1016)
			(end 0.2794 -0.1016)
			(stroke
				(width 0.1)
				(type default)
			)
			(layer "B.Fab")
		)
		(pad "1" smd rect
			(at 0 0)
			(size 0.508 0.508)
			(layers "B.Cu" "B.Mask" "B.Paste")
			(net "RST_PCIE_CPU_DEV2_R_N")
		)
		(pad "2" smd rect
			(at 0 0.889)
			(size 0.508 0.508)
			(layers "B.Cu" "B.Mask" "B.Paste")
			(net "RST_PCIE_CPU_DEV2_N")
		)
		(zone
			(layer "B.Cu")
			(hatch none 0.5)
			(connect_pads
				(clearance 0)
			)
			(min_thickness 0.25)
			(keepout
				(tracks not_allowed)
				(vias allowed)
				(pads allowed)
				(copperpour not_allowed)
				(footprints allowed)
			)
			(placement
				(enabled no)
				(sheetname "")
			)
			(fill
				(thermal_gap 0.5)
				(thermal_bridge_width 0.5)
				(island_removal_mode 0)
			)
			(polygon
				(pts
					(xy 467.614 -47.3075) (xy 468.122 -47.3075) (xy 468.122 -46.9265) (xy 467.614 -46.9265)
				)
			)
		)
		(zone
			(layer "B.Cu")
			(hatch none 0.5)
			(connect_pads
				(clearance 0)
			)
			(min_thickness 0.25)
			(keepout
				(tracks allowed)
				(vias not_allowed)
				(pads allowed)
				(copperpour not_allowed)
				(footprints allowed)
			)
			(placement
				(enabled no)
				(sheetname "")
			)
			(fill
				(thermal_gap 0.5)
				(thermal_bridge_width 0.5)
				(island_removal_mode 0)
			)
			(polygon
				(pts
					(xy 467.614 -46.9265) (xy 468.122 -46.9265) (xy 468.122 -47.3075) (xy 467.614 -47.3075)
				)
			)
		)
	)
	(footprint ""
		(layer "B.Cu")
		(at 197.848728 -60.079382 90)
		(property "Reference" "C6R6"
			(at 0 0 90)
			(layer "B.SilkS")
			(hide yes)
			(effects
				(font
					(size 1.27 1.27)
				)
				(justify mirror)
			)
		)
		(property "Value" ""
			(at 0 0 90)
			(layer "B.Fab")
			(effects
				(font
					(size 1.27 1.27)
				)
				(justify mirror)
			)
		)
		(duplicate_pad_numbers_are_jumpers no)
		(fp_rect
			(start -0.7239 -0.2159)
			(end 0.7239 1.9939)
			(stroke
				(width 0)
				(type default)
			)
			(fill no)
			(layer "B.CrtYd")
		)
		(fp_line
			(start 0.7239 -0.2159)
			(end 0.7239 1.9939)
			(stroke
				(width 0.1)
				(type default)
			)
			(layer "B.Fab")
		)
		(fp_line
			(start -0.7239 -0.2159)
			(end 0.7239 -0.2159)
			(stroke
				(width 0.1)
				(type default)
			)
			(layer "B.Fab")
		)
		(fp_line
			(start 0.7239 1.9939)
			(end -0.7239 1.9939)
			(stroke
				(width 0.1)
				(type default)
			)
			(layer "B.Fab")
		)
		(fp_line
			(start -0.7239 1.9939)
			(end -0.7239 -0.2159)
			(stroke
				(width 0.1)
				(type default)
			)
			(layer "B.Fab")
		)
		(pad "1" smd rect
			(at 0 0 270)
			(size 1.27 1.016)
			(layers "B.Cu" "B.Mask" "B.Paste")
			(net "VR_FET_SW_P12V_STBY_PVCCIN_CPU0")
		)
		(pad "2" smd rect
			(at 0 1.778 270)
			(size 1.27 1.016)
			(layers "B.Cu" "B.Mask" "B.Paste")
			(net "GND")
		)
		(zone
			(layer "B.Cu")
			(hatch none 0.5)
			(connect_pads
				(clearance 0)
			)
			(min_thickness 0.25)
			(keepout
				(tracks not_allowed)
				(vias allowed)
				(pads allowed)
				(copperpour not_allowed)
				(footprints allowed)
			)
			(placement
				(enabled no)
				(sheetname "")
			)
			(fill
				(thermal_gap 0.5)
				(thermal_bridge_width 0.5)
				(island_removal_mode 0)
			)
			(polygon
				(pts
					(xy 198.356728 -59.444382) (xy 199.118728 -59.444382) (xy 199.118728 -60.714382) (xy 198.356728 -60.714382)
				)
			)
		)
	)
	(footprint ""
		(layer "B.Cu")
		(at 340.16696 -77.694536)
		(property "Reference" "C3P12"
			(at 0 0 0)
			(layer "B.SilkS")
			(hide yes)
			(effects
				(font
					(size 1.27 1.27)
				)
				(justify mirror)
			)
		)
		(property "Value" ""
			(at 0 0 0)
			(layer "B.Fab")
			(effects
				(font
					(size 1.27 1.27)
				)
				(justify mirror)
			)
		)
		(duplicate_pad_numbers_are_jumpers no)
		(fp_poly
			(pts
				(xy -0.3048 -0.1016) (xy -0.3048 0.9906) (xy 0.3048 0.9906) (xy 0.3048 -0.1016)
			)
			(stroke
				(width 0)
				(type default)
			)
			(fill no)
			(layer "B.CrtYd")
		)
		(fp_line
			(start -0.3048 -0.1016)
			(end 0.3048 -0.1016)
			(stroke
				(width 0.1)
				(type default)
			)
			(layer "B.Fab")
		)
		(fp_line
			(start -0.3048 0.9906)
			(end -0.3048 -0.1016)
			(stroke
				(width 0.1)
				(type default)
			)
			(layer "B.Fab")
		)
		(fp_line
			(start 0.3048 -0.1016)
			(end 0.3048 0.9906)
			(stroke
				(width 0.1)
				(type default)
			)
			(layer "B.Fab")
		)
		(fp_line
			(start 0.3048 0.9906)
			(end -0.3048 0.9906)
			(stroke
				(width 0.1)
				(type default)
			)
			(layer "B.Fab")
		)
		(pad "1" smd rect
			(at 0 0 180)
			(size 0.508 0.508)
			(layers "B.Cu" "B.Mask" "B.Paste")
			(net "P3E_CPU0_PE1_SS_TXN<0>")
		)
		(pad "2" smd rect
			(at 0 0.889 180)
			(size 0.508 0.508)
			(layers "B.Cu" "B.Mask" "B.Paste")
			(net "P3E_CPU0_PE1_SS_C_TXN<0>")
		)
		(zone
			(layer "B.Cu")
			(hatch none 0.5)
			(connect_pads
				(clearance 0)
			)
			(min_thickness 0.25)
			(keepout
				(tracks allowed)
				(vias not_allowed)
				(pads allowed)
				(copperpour not_allowed)
				(footprints allowed)
			)
			(placement
				(enabled no)
				(sheetname "")
			)
			(fill
				(thermal_gap 0.5)
				(thermal_bridge_width 0.5)
				(island_removal_mode 0)
			)
			(polygon
				(pts
					(xy 340.42096 -77.440536) (xy 339.91296 -77.440536) (xy 339.91296 -77.059536) (xy 340.42096 -77.059536)
				)
			)
		)
		(zone
			(layer "B.Cu")
			(hatch none 0.5)
			(connect_pads
				(clearance 0)
			)
			(min_thickness 0.25)
			(keepout
				(tracks not_allowed)
				(vias allowed)
				(pads allowed)
				(copperpour not_allowed)
				(footprints allowed)
			)
			(placement
				(enabled no)
				(sheetname "")
			)
			(fill
				(thermal_gap 0.5)
				(thermal_bridge_width 0.5)
				(island_removal_mode 0)
			)
			(polygon
				(pts
					(xy 340.42096 -77.059536) (xy 339.91296 -77.059536) (xy 339.91296 -77.440536) (xy 340.42096 -77.440536)
				)
			)
		)
	)
	(footprint ""
		(layer "B.Cu")
		(at 476.174816 -146.359372)
		(property "Reference" "R6W6"
			(at 0.8382 -0.67818 0)
			(unlocked yes)
			(layer "B.SilkS")
			(effects
				(font
					(size 0.4064 0.254)
					(thickness 0.1524)
				)
				(justify left mirror)
			)
		)
		(property "Value" ""
			(at 0 0 0)
			(layer "B.Fab")
			(effects
				(font
					(size 1.27 1.27)
				)
				(justify mirror)
			)
		)
		(duplicate_pad_numbers_are_jumpers no)
		(fp_poly
			(pts
				(xy 0.2794 -0.1016) (xy -0.2794 -0.1016) (xy -0.2794 0.9906) (xy 0.2794 0.9906)
			)
			(stroke
				(width 0)
				(type default)
			)
			(fill no)
			(layer "B.CrtYd")
		)
		(fp_line
			(start -0.2794 -0.1016)
			(end 0.2794 -0.1016)
			(stroke
				(width 0.1)
				(type default)
			)
			(layer "B.Fab")
		)
		(fp_line
			(start -0.2794 0.9906)
			(end -0.2794 -0.1016)
			(stroke
				(width 0.1)
				(type default)
			)
			(layer "B.Fab")
		)
		(fp_line
			(start 0.2794 -0.1016)
			(end 0.2794 0.9906)
			(stroke
				(width 0.1)
				(type default)
			)
			(layer "B.Fab")
		)
		(fp_line
			(start 0.2794 0.9906)
			(end -0.2794 0.9906)
			(stroke
				(width 0.1)
				(type default)
			)
			(layer "B.Fab")
		)
		(pad "1" smd rect
			(at 0 0 180)
			(size 0.508 0.508)
			(layers "B.Cu" "B.Mask" "B.Paste")
			(net "P3V3_STBY")
		)
		(pad "2" smd rect
			(at 0 0.889 180)
			(size 0.508 0.508)
			(layers "B.Cu" "B.Mask" "B.Paste")
			(net "PCA9555_A0")
		)
		(zone
			(layer "B.Cu")
			(hatch none 0.5)
			(connect_pads
				(clearance 0)
			)
			(min_thickness 0.25)
			(keepout
				(tracks allowed)
				(vias not_allowed)
				(pads allowed)
				(copperpour not_allowed)
				(footprints allowed)
			)
			(placement
				(enabled no)
				(sheetname "")
			)
			(fill
				(thermal_gap 0.5)
				(thermal_bridge_width 0.5)
				(island_removal_mode 0)
			)
			(polygon
				(pts
					(xy 476.428816 -146.105372) (xy 475.920816 -146.105372) (xy 475.920816 -145.724372) (xy 476.428816 -145.724372)
				)
			)
		)
		(zone
			(layer "B.Cu")
			(hatch none 0.5)
			(connect_pads
				(clearance 0)
			)
			(min_thickness 0.25)
			(keepout
				(tracks not_allowed)
				(vias allowed)
				(pads allowed)
				(copperpour not_allowed)
				(footprints allowed)
			)
			(placement
				(enabled no)
				(sheetname "")
			)
			(fill
				(thermal_gap 0.5)
				(thermal_bridge_width 0.5)
				(island_removal_mode 0)
			)
			(polygon
				(pts
					(xy 476.428816 -145.724372) (xy 475.920816 -145.724372) (xy 475.920816 -146.105372) (xy 476.428816 -146.105372)
				)
			)
		)
	)
	(footprint ""
		(layer "B.Cu")
		(at 20.193 -95.5294)
		(property "Reference" "R9N7"
			(at 0 0 0)
			(layer "B.SilkS")
			(hide yes)
			(effects
				(font
					(size 1.27 1.27)
				)
				(justify mirror)
			)
		)
		(property "Value" ""
			(at 0 0 0)
			(layer "B.Fab")
			(effects
				(font
					(size 1.27 1.27)
				)
				(justify mirror)
			)
		)
		(duplicate_pad_numbers_are_jumpers no)
		(fp_poly
			(pts
				(xy 0.2794 -0.1016) (xy -0.2794 -0.1016) (xy -0.2794 0.9906) (xy 0.2794 0.9906)
			)
			(stroke
				(width 0)
				(type default)
			)
			(fill no)
			(layer "B.CrtYd")
		)
		(fp_line
			(start -0.2794 -0.1016)
			(end 0.2794 -0.1016)
			(stroke
				(width 0.1)
				(type default)
			)
			(layer "B.Fab")
		)
		(fp_line
			(start -0.2794 0.9906)
			(end -0.2794 -0.1016)
			(stroke
				(width 0.1)
				(type default)
			)
			(layer "B.Fab")
		)
		(fp_line
			(start 0.2794 -0.1016)
			(end 0.2794 0.9906)
			(stroke
				(width 0.1)
				(type default)
			)
			(layer "B.Fab")
		)
		(fp_line
			(start 0.2794 0.9906)
			(end -0.2794 0.9906)
			(stroke
				(width 0.1)
				(type default)
			)
			(layer "B.Fab")
		)
		(pad "1" smd rect
			(at 0 0 180)
			(size 0.508 0.508)
			(layers "B.Cu" "B.Mask" "B.Paste")
			(net "VR_PVCCIN_CPU1_XADDR2")
		)
		(pad "2" smd rect
			(at 0 0.889 180)
			(size 0.508 0.508)
			(layers "B.Cu" "B.Mask" "B.Paste")
			(net "GND")
		)
		(zone
			(layer "B.Cu")
			(hatch none 0.5)
			(connect_pads
				(clearance 0)
			)
			(min_thickness 0.25)
			(keepout
				(tracks allowed)
				(vias not_allowed)
				(pads allowed)
				(copperpour not_allowed)
				(footprints allowed)
			)
			(placement
				(enabled no)
				(sheetname "")
			)
			(fill
				(thermal_gap 0.5)
				(thermal_bridge_width 0.5)
				(island_removal_mode 0)
			)
			(polygon
				(pts
					(xy 20.447 -95.2754) (xy 19.939 -95.2754) (xy 19.939 -94.8944) (xy 20.447 -94.8944)
				)
			)
		)
		(zone
			(layer "B.Cu")
			(hatch none 0.5)
			(connect_pads
				(clearance 0)
			)
			(min_thickness 0.25)
			(keepout
				(tracks not_allowed)
				(vias allowed)
				(pads allowed)
				(copperpour not_allowed)
				(footprints allowed)
			)
			(placement
				(enabled no)
				(sheetname "")
			)
			(fill
				(thermal_gap 0.5)
				(thermal_bridge_width 0.5)
				(island_removal_mode 0)
			)
			(polygon
				(pts
					(xy 20.447 -94.8944) (xy 19.939 -94.8944) (xy 19.939 -95.2754) (xy 20.447 -95.2754)
				)
			)
		)
	)
	(footprint ""
		(layer "B.Cu")
		(at 342.0872 -88.3412 -90)
		(property "Reference" "R3P1"
			(at 0 0 90)
			(layer "B.SilkS")
			(hide yes)
			(effects
				(font
					(size 1.27 1.27)
				)
				(justify mirror)
			)
		)
		(property "Value" ""
			(at 0 0 90)
			(layer "B.Fab")
			(effects
				(font
					(size 1.27 1.27)
				)
				(justify mirror)
			)
		)
		(duplicate_pad_numbers_are_jumpers no)
		(fp_poly
			(pts
				(xy 0.2794 -0.1016) (xy -0.2794 -0.1016) (xy -0.2794 0.9906) (xy 0.2794 0.9906)
			)
			(stroke
				(width 0)
				(type default)
			)
			(fill no)
			(layer "B.CrtYd")
		)
		(fp_line
			(start -0.2794 0.9906)
			(end -0.2794 -0.1016)
			(stroke
				(width 0.1)
				(type default)
			)
			(layer "B.Fab")
		)
		(fp_line
			(start 0.2794 0.9906)
			(end -0.2794 0.9906)
			(stroke
				(width 0.1)
				(type default)
			)
			(layer "B.Fab")
		)
		(fp_line
			(start -0.2794 -0.1016)
			(end 0.2794 -0.1016)
			(stroke
				(width 0.1)
				(type default)
			)
			(layer "B.Fab")
		)
		(fp_line
			(start 0.2794 -0.1016)
			(end 0.2794 0.9906)
			(stroke
				(width 0.1)
				(type default)
			)
			(layer "B.Fab")
		)
		(pad "1" smd rect
			(at 0 0 90)
			(size 0.508 0.508)
			(layers "B.Cu" "B.Mask" "B.Paste")
			(net "SVID_ALERT_PVCCIO_CPU0")
		)
		(pad "2" smd rect
			(at 0 0.889 90)
			(size 0.508 0.508)
			(layers "B.Cu" "B.Mask" "B.Paste")
			(net "SVID_ALERT0_CPU0_R_N")
		)
		(zone
			(layer "B.Cu")
			(hatch none 0.5)
			(connect_pads
				(clearance 0)
			)
			(min_thickness 0.25)
			(keepout
				(tracks not_allowed)
				(vias allowed)
				(pads allowed)
				(copperpour not_allowed)
				(footprints allowed)
			)
			(placement
				(enabled no)
				(sheetname "")
			)
			(fill
				(thermal_gap 0.5)
				(thermal_bridge_width 0.5)
				(island_removal_mode 0)
			)
			(polygon
				(pts
					(xy 341.4522 -88.0872) (xy 341.4522 -88.5952) (xy 341.8332 -88.5952) (xy 341.8332 -88.0872)
				)
			)
		)
		(zone
			(layer "B.Cu")
			(hatch none 0.5)
			(connect_pads
				(clearance 0)
			)
			(min_thickness 0.25)
			(keepout
				(tracks allowed)
				(vias not_allowed)
				(pads allowed)
				(copperpour not_allowed)
				(footprints allowed)
			)
			(placement
				(enabled no)
				(sheetname "")
			)
			(fill
				(thermal_gap 0.5)
				(thermal_bridge_width 0.5)
				(island_removal_mode 0)
			)
			(polygon
				(pts
					(xy 341.8332 -88.0872) (xy 341.8332 -88.5952) (xy 341.4522 -88.5952) (xy 341.4522 -88.0872)
				)
			)
		)
	)
	(footprint ""
		(layer "B.Cu")
		(at 477.645222 -3.3782 90)
		(property "Reference" "R9G9"
			(at 0 0 90)
			(layer "B.SilkS")
			(hide yes)
			(effects
				(font
					(size 1.27 1.27)
				)
				(justify mirror)
			)
		)
		(property "Value" ""
			(at 0 0 90)
			(layer "B.Fab")
			(effects
				(font
					(size 1.27 1.27)
				)
				(justify mirror)
			)
		)
		(duplicate_pad_numbers_are_jumpers no)
		(fp_poly
			(pts
				(xy 0.2794 -0.1016) (xy -0.2794 -0.1016) (xy -0.2794 0.9906) (xy 0.2794 0.9906)
			)
			(stroke
				(width 0)
				(type default)
			)
			(fill no)
			(layer "B.CrtYd")
		)
		(fp_line
			(start 0.2794 -0.1016)
			(end 0.2794 0.9906)
			(stroke
				(width 0.1)
				(type default)
			)
			(layer "B.Fab")
		)
		(fp_line
			(start -0.2794 -0.1016)
			(end 0.2794 -0.1016)
			(stroke
				(width 0.1)
				(type default)
			)
			(layer "B.Fab")
		)
		(fp_line
			(start 0.2794 0.9906)
			(end -0.2794 0.9906)
			(stroke
				(width 0.1)
				(type default)
			)
			(layer "B.Fab")
		)
		(fp_line
			(start -0.2794 0.9906)
			(end -0.2794 -0.1016)
			(stroke
				(width 0.1)
				(type default)
			)
			(layer "B.Fab")
		)
		(pad "1" smd rect
			(at 0 0 270)
			(size 0.508 0.508)
			(layers "B.Cu" "B.Mask" "B.Paste")
			(net "NIC_SER_P_MDI_3_DP")
		)
		(pad "2" smd rect
			(at 0 0.889 270)
			(size 0.508 0.508)
			(layers "B.Cu" "B.Mask" "B.Paste")
			(net "NIC_MDI_SPRV_RJ45_3_R_DP")
		)
		(zone
			(layer "B.Cu")
			(hatch none 0.5)
			(connect_pads
				(clearance 0)
			)
			(min_thickness 0.25)
			(keepout
				(tracks allowed)
				(vias not_allowed)
				(pads allowed)
				(copperpour not_allowed)
				(footprints allowed)
			)
			(placement
				(enabled no)
				(sheetname "")
			)
			(fill
				(thermal_gap 0.5)
				(thermal_bridge_width 0.5)
				(island_removal_mode 0)
			)
			(polygon
				(pts
					(xy 477.899222 -3.6322) (xy 477.899222 -3.1242) (xy 478.280222 -3.1242) (xy 478.280222 -3.6322)
				)
			)
		)
		(zone
			(layer "B.Cu")
			(hatch none 0.5)
			(connect_pads
				(clearance 0)
			)
			(min_thickness 0.25)
			(keepout
				(tracks not_allowed)
				(vias allowed)
				(pads allowed)
				(copperpour not_allowed)
				(footprints allowed)
			)
			(placement
				(enabled no)
				(sheetname "")
			)
			(fill
				(thermal_gap 0.5)
				(thermal_bridge_width 0.5)
				(island_removal_mode 0)
			)
			(polygon
				(pts
					(xy 478.280222 -3.6322) (xy 478.280222 -3.1242) (xy 477.899222 -3.1242) (xy 477.899222 -3.6322)
				)
			)
		)
	)
	(footprint ""
		(layer "B.Cu")
		(at 176.7078 -79.502 -90)
		(property "Reference" "FB6P1"
			(at 0.53467 4.4958 0)
			(unlocked yes)
			(layer "B.SilkS")
			(effects
				(font
					(size 0.7874 0.5842)
					(thickness 0.1524)
				)
				(justify mirror)
			)
		)
		(property "Value" ""
			(at 0 0 90)
			(layer "B.Fab")
			(effects
				(font
					(size 1.27 1.27)
				)
				(justify mirror)
			)
		)
		(duplicate_pad_numbers_are_jumpers no)
		(fp_poly
			(pts
				(xy 0.7239 -0.26035) (xy -0.7239 -0.26035) (xy -0.7239 2.03835) (xy 0.7239 2.03835)
			)
			(stroke
				(width 0)
				(type default)
			)
			(fill no)
			(layer "B.CrtYd")
		)
		(fp_line
			(start -0.7239 2.03835)
			(end 0.7239 2.03835)
			(stroke
				(width 0.1)
				(type default)
			)
			(layer "B.Fab")
		)
		(fp_line
			(start 0.7239 2.03835)
			(end 0.7239 -0.26035)
			(stroke
				(width 0.1)
				(type default)
			)
			(layer "B.Fab")
		)
		(fp_line
			(start -0.7239 -0.26035)
			(end -0.7239 2.03835)
			(stroke
				(width 0.1)
				(type default)
			)
			(layer "B.Fab")
		)
		(fp_line
			(start 0.7239 -0.26035)
			(end -0.7239 -0.26035)
			(stroke
				(width 0.1)
				(type default)
			)
			(layer "B.Fab")
		)
		(pad "1" smd rect
			(at 0 0 90)
			(size 1.27 1.016)
			(layers "B.Cu" "B.Mask" "B.Paste")
			(net "P3V3")
		)
		(pad "2" smd rect
			(at 0 1.778 90)
			(size 1.27 1.016)
			(layers "B.Cu" "B.Mask" "B.Paste")
			(net "P3V3_DB1200")
		)
		(zone
			(layer "B.Cu")
			(hatch none 0.5)
			(connect_pads
				(clearance 0)
			)
			(min_thickness 0.25)
			(keepout
				(tracks not_allowed)
				(vias allowed)
				(pads allowed)
				(copperpour not_allowed)
				(footprints allowed)
			)
			(placement
				(enabled no)
				(sheetname "")
			)
			(fill
				(thermal_gap 0.5)
				(thermal_bridge_width 0.5)
				(island_removal_mode 0)
			)
			(polygon
				(pts
					(xy 176.1998 -80.137) (xy 175.4378 -80.137) (xy 175.4378 -80.0481) (xy 175.4378 -78.867) (xy 176.1998 -78.867)
				)
			)
		)
	)
	(footprint ""
		(layer "B.Cu")
		(at 390.144 -17.272 -90)
		(property "Reference" "C32W4"
			(at 0.8382 -0.67818 270)
			(unlocked yes)
			(layer "B.SilkS")
			(effects
				(font
					(size 0.4064 0.254)
					(thickness 0.1524)
				)
				(justify left mirror)
			)
		)
		(property "Value" ""
			(at 0 0 90)
			(layer "B.Fab")
			(effects
				(font
					(size 1.27 1.27)
				)
				(justify mirror)
			)
		)
		(duplicate_pad_numbers_are_jumpers no)
		(fp_poly
			(pts
				(xy -0.3048 -0.1016) (xy -0.3048 0.9906) (xy 0.3048 0.9906) (xy 0.3048 -0.1016)
			)
			(stroke
				(width 0)
				(type default)
			)
			(fill no)
			(layer "B.CrtYd")
		)
		(fp_line
			(start -0.3048 0.9906)
			(end -0.3048 -0.1016)
			(stroke
				(width 0.1)
				(type default)
			)
			(layer "B.Fab")
		)
		(fp_line
			(start 0.3048 0.9906)
			(end -0.3048 0.9906)
			(stroke
				(width 0.1)
				(type default)
			)
			(layer "B.Fab")
		)
		(fp_line
			(start -0.3048 -0.1016)
			(end 0.3048 -0.1016)
			(stroke
				(width 0.1)
				(type default)
			)
			(layer "B.Fab")
		)
		(fp_line
			(start 0.3048 -0.1016)
			(end 0.3048 0.9906)
			(stroke
				(width 0.1)
				(type default)
			)
			(layer "B.Fab")
		)
		(pad "1" smd rect
			(at 0 0 90)
			(size 0.508 0.508)
			(layers "B.Cu" "B.Mask" "B.Paste")
			(net "P3V3_STBY")
		)
		(pad "2" smd rect
			(at 0 0.889 90)
			(size 0.508 0.508)
			(layers "B.Cu" "B.Mask" "B.Paste")
			(net "GND")
		)
		(zone
			(layer "B.Cu")
			(hatch none 0.5)
			(connect_pads
				(clearance 0)
			)
			(min_thickness 0.25)
			(keepout
				(tracks not_allowed)
				(vias allowed)
				(pads allowed)
				(copperpour not_allowed)
				(footprints allowed)
			)
			(placement
				(enabled no)
				(sheetname "")
			)
			(fill
				(thermal_gap 0.5)
				(thermal_bridge_width 0.5)
				(island_removal_mode 0)
			)
			(polygon
				(pts
					(xy 389.509 -17.018) (xy 389.509 -17.526) (xy 389.89 -17.526) (xy 389.89 -17.018)
				)
			)
		)
		(zone
			(layer "B.Cu")
			(hatch none 0.5)
			(connect_pads
				(clearance 0)
			)
			(min_thickness 0.25)
			(keepout
				(tracks allowed)
				(vias not_allowed)
				(pads allowed)
				(copperpour not_allowed)
				(footprints allowed)
			)
			(placement
				(enabled no)
				(sheetname "")
			)
			(fill
				(thermal_gap 0.5)
				(thermal_bridge_width 0.5)
				(island_removal_mode 0)
			)
			(polygon
				(pts
					(xy 389.89 -17.018) (xy 389.89 -17.526) (xy 389.509 -17.526) (xy 389.509 -17.018)
				)
			)
		)
	)
	(footprint ""
		(layer "B.Cu")
		(at 104.521254 -73.51014)
		(property "Reference" "C8P23"
			(at 0 0 0)
			(layer "B.SilkS")
			(hide yes)
			(effects
				(font
					(size 1.27 1.27)
				)
				(justify mirror)
			)
		)
		(property "Value" ""
			(at 0 0 0)
			(layer "B.Fab")
			(effects
				(font
					(size 1.27 1.27)
				)
				(justify mirror)
			)
		)
		(duplicate_pad_numbers_are_jumpers no)
		(fp_poly
			(pts
				(xy 0.7239 -0.2159) (xy -0.7239 -0.2159) (xy -0.7239 1.9939) (xy 0.7239 1.9939)
			)
			(stroke
				(width 0)
				(type default)
			)
			(fill no)
			(layer "B.CrtYd")
		)
		(fp_line
			(start -0.7239 -0.2159)
			(end 0.7239 -0.2159)
			(stroke
				(width 0.1)
				(type default)
			)
			(layer "B.Fab")
		)
		(fp_line
			(start -0.7239 1.9939)
			(end -0.7239 -0.2159)
			(stroke
				(width 0.1)
				(type default)
			)
			(layer "B.Fab")
		)
		(fp_line
			(start 0.7239 -0.2159)
			(end 0.7239 1.9939)
			(stroke
				(width 0.1)
				(type default)
			)
			(layer "B.Fab")
		)
		(fp_line
			(start 0.7239 1.9939)
			(end -0.7239 1.9939)
			(stroke
				(width 0.1)
				(type default)
			)
			(layer "B.Fab")
		)
		(pad "1" smd rect
			(at 0 0 180)
			(size 1.27 1.016)
			(layers "B.Cu" "B.Mask" "B.Paste")
			(net "PVCCMCP_CPU1")
		)
		(pad "2" smd rect
			(at 0 1.778 180)
			(size 1.27 1.016)
			(layers "B.Cu" "B.Mask" "B.Paste")
			(net "GND")
		)
		(zone
			(layer "B.Cu")
			(hatch none 0.5)
			(connect_pads
				(clearance 0)
			)
			(min_thickness 0.25)
			(keepout
				(tracks not_allowed)
				(vias allowed)
				(pads allowed)
				(copperpour not_allowed)
				(footprints allowed)
			)
			(placement
				(enabled no)
				(sheetname "")
			)
			(fill
				(thermal_gap 0.5)
				(thermal_bridge_width 0.5)
				(island_removal_mode 0)
			)
			(polygon
				(pts
					(xy 105.156254 -73.00214) (xy 103.886254 -73.00214) (xy 103.886254 -72.24014) (xy 105.156254 -72.24014)
				)
			)
		)
	)
	(footprint ""
		(layer "B.Cu")
		(at 178.562 -53.213 -90)
		(property "Reference" "C6R10"
			(at 0 0 90)
			(layer "B.SilkS")
			(hide yes)
			(effects
				(font
					(size 1.27 1.27)
				)
				(justify mirror)
			)
		)
		(property "Value" ""
			(at 0 0 90)
			(layer "B.Fab")
			(effects
				(font
					(size 1.27 1.27)
				)
				(justify mirror)
			)
		)
		(duplicate_pad_numbers_are_jumpers no)
		(fp_poly
			(pts
				(xy 0.7239 -0.2159) (xy -0.7239 -0.2159) (xy -0.7239 1.9939) (xy 0.7239 1.9939)
			)
			(stroke
				(width 0)
				(type default)
			)
			(fill no)
			(layer "B.CrtYd")
		)
		(fp_line
			(start -0.7239 1.9939)
			(end -0.7239 -0.2159)
			(stroke
				(width 0.1)
				(type default)
			)
			(layer "B.Fab")
		)
		(fp_line
			(start 0.7239 1.9939)
			(end -0.7239 1.9939)
			(stroke
				(width 0.1)
				(type default)
			)
			(layer "B.Fab")
		)
		(fp_line
			(start -0.7239 -0.2159)
			(end 0.7239 -0.2159)
			(stroke
				(width 0.1)
				(type default)
			)
			(layer "B.Fab")
		)
		(fp_line
			(start 0.7239 -0.2159)
			(end 0.7239 1.9939)
			(stroke
				(width 0.1)
				(type default)
			)
			(layer "B.Fab")
		)
		(pad "1" smd rect
			(at 0 0 90)
			(size 1.27 1.016)
			(layers "B.Cu" "B.Mask" "B.Paste")
			(net "VR_FET_SW_P12V_STBY_PVCCIN_CPU0")
		)
		(pad "2" smd rect
			(at 0 1.778 90)
			(size 1.27 1.016)
			(layers "B.Cu" "B.Mask" "B.Paste")
			(net "GND")
		)
		(zone
			(layer "B.Cu")
			(hatch none 0.5)
			(connect_pads
				(clearance 0)
			)
			(min_thickness 0.25)
			(keepout
				(tracks not_allowed)
				(vias allowed)
				(pads allowed)
				(copperpour not_allowed)
				(footprints allowed)
			)
			(placement
				(enabled no)
				(sheetname "")
			)
			(fill
				(thermal_gap 0.5)
				(thermal_bridge_width 0.5)
				(island_removal_mode 0)
			)
			(polygon
				(pts
					(xy 178.054 -52.578) (xy 178.054 -53.848) (xy 177.292 -53.848) (xy 177.292 -52.578)
				)
			)
		)
	)
	(footprint ""
		(layer "B.Cu")
		(at 197.239128 -87.043006 90)
		(property "Reference" "R6P47"
			(at 0 0 90)
			(layer "B.SilkS")
			(hide yes)
			(effects
				(font
					(size 1.27 1.27)
				)
				(justify mirror)
			)
		)
		(property "Value" ""
			(at 0 0 90)
			(layer "B.Fab")
			(effects
				(font
					(size 1.27 1.27)
				)
				(justify mirror)
			)
		)
		(duplicate_pad_numbers_are_jumpers no)
		(fp_rect
			(start 0.2794 -0.1016)
			(end -0.2794 0.9906)
			(stroke
				(width 0)
				(type default)
			)
			(fill no)
			(layer "B.CrtYd")
		)
		(fp_line
			(start 0.2794 -0.1016)
			(end 0.2794 0.9906)
			(stroke
				(width 0.1)
				(type default)
			)
			(layer "B.Fab")
		)
		(fp_line
			(start -0.2794 -0.1016)
			(end 0.2794 -0.1016)
			(stroke
				(width 0.1)
				(type default)
			)
			(layer "B.Fab")
		)
		(fp_line
			(start 0.2794 0.9906)
			(end -0.2794 0.9906)
			(stroke
				(width 0.1)
				(type default)
			)
			(layer "B.Fab")
		)
		(fp_line
			(start -0.2794 0.9906)
			(end -0.2794 -0.1016)
			(stroke
				(width 0.1)
				(type default)
			)
			(layer "B.Fab")
		)
		(pad "1" smd rect
			(at 0 0 270)
			(size 0.508 0.508)
			(layers "B.Cu" "B.Mask" "B.Paste")
			(net "VR_PVCCIN_CPU0_PH5_VCIN")
		)
		(pad "2" smd rect
			(at 0 0.889 270)
			(size 0.508 0.508)
			(layers "B.Cu" "B.Mask" "B.Paste")
			(net "P5V_STBY")
		)
		(zone
			(layer "B.Cu")
			(hatch none 0.5)
			(connect_pads
				(clearance 0)
			)
			(min_thickness 0.25)
			(keepout
				(tracks not_allowed)
				(vias allowed)
				(pads allowed)
				(copperpour not_allowed)
				(footprints allowed)
			)
			(placement
				(enabled no)
				(sheetname "")
			)
			(fill
				(thermal_gap 0.5)
				(thermal_bridge_width 0.5)
				(island_removal_mode 0)
			)
			(polygon
				(pts
					(xy 197.493128 -87.297006) (xy 197.493128 -86.789006) (xy 197.874128 -86.789006) (xy 197.874128 -87.297006)
				)
			)
		)
		(zone
			(layer "B.Cu")
			(hatch none 0.5)
			(connect_pads
				(clearance 0)
			)
			(min_thickness 0.25)
			(keepout
				(tracks allowed)
				(vias not_allowed)
				(pads allowed)
				(copperpour not_allowed)
				(footprints allowed)
			)
			(placement
				(enabled no)
				(sheetname "")
			)
			(fill
				(thermal_gap 0.5)
				(thermal_bridge_width 0.5)
				(island_removal_mode 0)
			)
			(polygon
				(pts
					(xy 197.493128 -87.297006) (xy 197.493128 -86.789006) (xy 197.874128 -86.789006) (xy 197.874128 -87.297006)
				)
			)
		)
	)
	(footprint ""
		(layer "B.Cu")
		(at 397.764 -85.0265 180)
		(property "Reference" "R8D17"
			(at 0.8382 -0.67818 180)
			(unlocked yes)
			(layer "B.SilkS")
			(effects
				(font
					(size 0.4064 0.254)
					(thickness 0.1524)
				)
				(justify left mirror)
			)
		)
		(property "Value" ""
			(at 0 0 0)
			(layer "B.Fab")
			(effects
				(font
					(size 1.27 1.27)
				)
				(justify mirror)
			)
		)
		(duplicate_pad_numbers_are_jumpers no)
		(fp_poly
			(pts
				(xy 0.2794 -0.1016) (xy -0.2794 -0.1016) (xy -0.2794 0.9906) (xy 0.2794 0.9906)
			)
			(stroke
				(width 0)
				(type default)
			)
			(fill no)
			(layer "B.CrtYd")
		)
		(fp_line
			(start 0.2794 0.9906)
			(end -0.2794 0.9906)
			(stroke
				(width 0.1)
				(type default)
			)
			(layer "B.Fab")
		)
		(fp_line
			(start 0.2794 -0.1016)
			(end 0.2794 0.9906)
			(stroke
				(width 0.1)
				(type default)
			)
			(layer "B.Fab")
		)
		(fp_line
			(start -0.2794 0.9906)
			(end -0.2794 -0.1016)
			(stroke
				(width 0.1)
				(type default)
			)
			(layer "B.Fab")
		)
		(fp_line
			(start -0.2794 -0.1016)
			(end 0.2794 -0.1016)
			(stroke
				(width 0.1)
				(type default)
			)
			(layer "B.Fab")
		)
		(pad "1" smd rect
			(at 0 0)
			(size 0.508 0.508)
			(layers "B.Cu" "B.Mask" "B.Paste")
			(net "P3V3_STBY")
		)
		(pad "2" smd rect
			(at 0 0.889)
			(size 0.508 0.508)
			(layers "B.Cu" "B.Mask" "B.Paste")
			(net "SMB_VR_STBY_LVC3_SDA")
		)
		(zone
			(layer "B.Cu")
			(hatch none 0.5)
			(connect_pads
				(clearance 0)
			)
			(min_thickness 0.25)
			(keepout
				(tracks not_allowed)
				(vias allowed)
				(pads allowed)
				(copperpour not_allowed)
				(footprints allowed)
			)
			(placement
				(enabled no)
				(sheetname "")
			)
			(fill
				(thermal_gap 0.5)
				(thermal_bridge_width 0.5)
				(island_removal_mode 0)
			)
			(polygon
				(pts
					(xy 397.51 -85.6615) (xy 398.018 -85.6615) (xy 398.018 -85.2805) (xy 397.51 -85.2805)
				)
			)
		)
		(zone
			(layer "B.Cu")
			(hatch none 0.5)
			(connect_pads
				(clearance 0)
			)
			(min_thickness 0.25)
			(keepout
				(tracks allowed)
				(vias not_allowed)
				(pads allowed)
				(copperpour not_allowed)
				(footprints allowed)
			)
			(placement
				(enabled no)
				(sheetname "")
			)
			(fill
				(thermal_gap 0.5)
				(thermal_bridge_width 0.5)
				(island_removal_mode 0)
			)
			(polygon
				(pts
					(xy 397.51 -85.2805) (xy 398.018 -85.2805) (xy 398.018 -85.6615) (xy 397.51 -85.6615)
				)
			)
		)
	)
	(footprint ""
		(layer "B.Cu")
		(at 194.700398 -5.621782 90)
		(property "Reference" "J6U2"
			(at 2.225548 39.48811 0)
			(unlocked yes)
			(layer "B.SilkS")
			(effects
				(font
					(size 0.7874 0.5842)
					(thickness 0.1524)
				)
				(justify left mirror)
			)
		)
		(property "Value" ""
			(at 0 0 90)
			(layer "B.Fab")
			(effects
				(font
					(size 1.27 1.27)
				)
				(justify mirror)
			)
		)
		(duplicate_pad_numbers_are_jumpers no)
		(fp_line
			(start 0.94996 -7.675118)
			(end -5.5499 -7.675118)
			(stroke
				(width 0.1524)
				(type default)
			)
			(layer "B.SilkS")
		)
		(fp_line
			(start -5.5499 -7.675118)
			(end -5.5499 -1.480058)
			(stroke
				(width 0.1524)
				(type default)
			)
			(layer "B.SilkS")
		)
		(fp_line
			(start 0.94996 -1.480058)
			(end 0.94996 -7.675118)
			(stroke
				(width 0.1524)
				(type default)
			)
			(layer "B.SilkS")
		)
		(fp_line
			(start -5.5499 128.130046)
			(end -5.5499 134.325106)
			(stroke
				(width 0.1524)
				(type default)
			)
			(layer "B.SilkS")
		)
		(fp_line
			(start 0.94996 134.325106)
			(end 0.94996 128.130046)
			(stroke
				(width 0.1524)
				(type default)
			)
			(layer "B.SilkS")
		)
		(fp_line
			(start -5.5499 134.325106)
			(end 0.94996 134.325106)
			(stroke
				(width 0.1524)
				(type default)
			)
			(layer "B.SilkS")
		)
		(fp_poly
			(pts
				(xy 2.762758 -0.69088) (xy 2.762758 0.32512) (xy 1.492758 -0.18288)
			)
			(stroke
				(width 0)
				(type default)
			)
			(fill yes)
			(layer "B.SilkS")
		)
		(fp_poly
			(pts
				(xy 0.94996 -7.675118) (xy 0.94996 134.325106) (xy -5.5499 134.325106) (xy -5.5499 -7.675118)
			)
			(stroke
				(width 0)
				(type default)
			)
			(fill no)
			(layer "B.CrtYd")
		)
		(fp_line
			(start 0.94996 -7.675118)
			(end -5.5499 -7.675118)
			(stroke
				(width 0.1)
				(type default)
			)
			(layer "B.Fab")
		)
		(fp_line
			(start -5.5499 -7.675118)
			(end -5.5499 134.325106)
			(stroke
				(width 0.1)
				(type default)
			)
			(layer "B.Fab")
		)
		(fp_line
			(start 0.94996 134.325106)
			(end 0.94996 -7.675118)
			(stroke
				(width 0.1)
				(type default)
			)
			(layer "B.Fab")
		)
		(fp_line
			(start -5.5499 134.325106)
			(end 0.94996 134.325106)
			(stroke
				(width 0.1)
				(type default)
			)
			(layer "B.Fab")
		)
		(fp_poly
			(pts
				(xy 2.984246 -0.461264) (xy 2.984246 0.554736) (xy 1.714246 0.046736)
			)
			(stroke
				(width 0)
				(type default)
			)
			(fill yes)
			(layer "B.Fab")
		)
		(fp_text user "145"
			(at -6.283452 0.62611 0)
			(unlocked yes)
			(layer "B.SilkS")
			(effects
				(font
					(size 0.7874 0.5842)
					(thickness 0.1524)
				)
				(justify left mirror)
			)
		)
		(fp_text user "77"
			(at 0.955548 66.41211 0)
			(unlocked yes)
			(layer "B.SilkS")
			(effects
				(font
					(size 0.7874 0.5842)
					(thickness 0.1524)
				)
				(justify left mirror)
			)
		)
		(fp_text user "221"
			(at -6.029452 66.92011 0)
			(unlocked yes)
			(layer "B.SilkS")
			(effects
				(font
					(size 0.7874 0.5842)
					(thickness 0.1524)
				)
				(justify left mirror)
			)
		)
		(fp_text user "78"
			(at 1.590548 71.11111 0)
			(unlocked yes)
			(layer "B.SilkS")
			(effects
				(font
					(size 0.7874 0.5842)
					(thickness 0.1524)
				)
				(justify left mirror)
			)
		)
		(fp_text user "222"
			(at -6.156452 72.00011 0)
			(unlocked yes)
			(layer "B.SilkS")
			(effects
				(font
					(size 0.7874 0.5842)
					(thickness 0.1524)
				)
				(justify left mirror)
			)
		)
		(fp_text user "144"
			(at 3.241548 129.65811 0)
			(unlocked yes)
			(layer "B.SilkS")
			(effects
				(font
					(size 0.7874 0.5842)
					(thickness 0.1524)
				)
				(justify left mirror)
			)
		)
		(fp_text user "288"
			(at -6.283452 129.78511 0)
			(unlocked yes)
			(layer "B.SilkS")
			(effects
				(font
					(size 0.7874 0.5842)
					(thickness 0.1524)
				)
				(justify left mirror)
			)
		)
		(fp_text user "145"
			(at -3.081782 -1.37922 90)
			(unlocked yes)
			(layer "B.Fab")
			(effects
				(font
					(size 0.7874 0.5842)
					(thickness 0.1524)
				)
				(justify left mirror)
			)
		)
		(fp_text user "77"
			(at 0.728218 65.93078 90)
			(unlocked yes)
			(layer "B.Fab")
			(effects
				(font
					(size 0.7874 0.5842)
					(thickness 0.1524)
				)
				(justify left mirror)
			)
		)
		(fp_text user "221"
			(at -3.081782 65.93078 90)
			(unlocked yes)
			(layer "B.Fab")
			(effects
				(font
					(size 0.7874 0.5842)
					(thickness 0.1524)
				)
				(justify left mirror)
			)
		)
		(fp_text user "78"
			(at 0.728218 69.10578 90)
			(unlocked yes)
			(layer "B.Fab")
			(effects
				(font
					(size 0.7874 0.5842)
					(thickness 0.1524)
				)
				(justify left mirror)
			)
		)
		(fp_text user "222"
			(at -3.081782 69.10578 90)
			(unlocked yes)
			(layer "B.Fab")
			(effects
				(font
					(size 0.7874 0.5842)
					(thickness 0.1524)
				)
				(justify left mirror)
			)
		)
		(fp_text user "144"
			(at 0.728218 127.52578 90)
			(unlocked yes)
			(layer "B.Fab")
			(effects
				(font
					(size 0.7874 0.5842)
					(thickness 0.1524)
				)
				(justify left mirror)
			)
		)
		(fp_text user "288"
			(at -3.081782 127.52578 90)
			(unlocked yes)
			(layer "B.Fab")
			(effects
				(font
					(size 0.7874 0.5842)
					(thickness 0.1524)
				)
				(justify left mirror)
			)
		)
		(pad "" thru_hole circle
			(at -2.29997 -5.649976 270)
			(size 2.8194 2.8194)
			(drill 2.4384)
			(layers "*.Cu" "*.Mask")
			(remove_unused_layers no)
			(clearance 0.127)
			(thermal_gap 0.127)
		)
		(pad "" thru_hole oval
			(at -2.29997 68.90004 270)
			(size 2.8194 1.5748)
			(drill oval 2.4384 1.1938)
			(layers "*.Cu" "*.Mask")
			(remove_unused_layers no)
			(clearance 0.127)
			(thermal_gap 0.127)
		)
		(pad "" thru_hole circle
			(at -2.29997 132.299964 270)
			(size 2.8194 2.8194)
			(drill 2.4384)
			(layers "*.Cu" "*.Mask")
			(remove_unused_layers no)
			(clearance 0.127)
			(thermal_gap 0.127)
		)
		(pad "1" smd rect
			(at 0 0 270)
			(size 1.8034 0.508)
			(layers "B.Cu" "B.Mask" "B.Paste")
			(net "P12V_NVDIMM_ABC")
		)
		(pad "2" smd rect
			(at 0 0.849884 270)
			(size 1.8034 0.508)
			(layers "B.Cu" "B.Mask" "B.Paste")
			(net "GND")
		)
		(pad "3" smd rect
			(at 0 1.700022 270)
			(size 1.8034 0.508)
			(layers "B.Cu" "B.Mask" "B.Paste")
			(net "M_C_DQ<4>")
		)
		(pad "4" smd rect
			(at 0 2.549906 270)
			(size 1.8034 0.508)
			(layers "B.Cu" "B.Mask" "B.Paste")
			(net "GND")
		)
		(pad "5" smd rect
			(at 0 3.400044 270)
			(size 1.8034 0.508)
			(layers "B.Cu" "B.Mask" "B.Paste")
			(net "M_C_DQ<0>")
		)
		(pad "6" smd rect
			(at 0 4.249928 270)
			(size 1.8034 0.508)
			(layers "B.Cu" "B.Mask" "B.Paste")
			(net "GND")
		)
		(pad "7" smd rect
			(at 0 5.100066 270)
			(size 1.8034 0.508)
			(layers "B.Cu" "B.Mask" "B.Paste")
			(net "M_C_DQS_DP<9>")
		)
		(pad "8" smd rect
			(at 0 5.94995 270)
			(size 1.8034 0.508)
			(layers "B.Cu" "B.Mask" "B.Paste")
			(net "M_C_DQS_DN<9>")
		)
		(pad "9" smd rect
			(at 0 6.800088 270)
			(size 1.8034 0.508)
			(layers "B.Cu" "B.Mask" "B.Paste")
			(net "GND")
		)
		(pad "10" smd rect
			(at 0 7.649972 270)
			(size 1.8034 0.508)
			(layers "B.Cu" "B.Mask" "B.Paste")
			(net "M_C_DQ<6>")
		)
		(pad "11" smd rect
			(at 0 8.50011 270)
			(size 1.8034 0.508)
			(layers "B.Cu" "B.Mask" "B.Paste")
			(net "GND")
		)
		(pad "12" smd rect
			(at 0 9.349994 270)
			(size 1.8034 0.508)
			(layers "B.Cu" "B.Mask" "B.Paste")
			(net "M_C_DQ<2>")
		)
		(pad "13" smd rect
			(at 0 10.199878 270)
			(size 1.8034 0.508)
			(layers "B.Cu" "B.Mask" "B.Paste")
			(net "GND")
		)
		(pad "14" smd rect
			(at 0 11.050016 270)
			(size 1.8034 0.508)
			(layers "B.Cu" "B.Mask" "B.Paste")
			(net "M_C_DQ<12>")
		)
		(pad "15" smd rect
			(at 0 11.8999 270)
			(size 1.8034 0.508)
			(layers "B.Cu" "B.Mask" "B.Paste")
			(net "GND")
		)
		(pad "16" smd rect
			(at 0 12.750038 270)
			(size 1.8034 0.508)
			(layers "B.Cu" "B.Mask" "B.Paste")
			(net "M_C_DQ<8>")
		)
		(pad "17" smd rect
			(at 0 13.599922 270)
			(size 1.8034 0.508)
			(layers "B.Cu" "B.Mask" "B.Paste")
			(net "GND")
		)
		(pad "18" smd rect
			(at 0 14.45006 270)
			(size 1.8034 0.508)
			(layers "B.Cu" "B.Mask" "B.Paste")
			(net "M_C_DQS_DP<10>")
		)
		(pad "19" smd rect
			(at 0 15.299944 270)
			(size 1.8034 0.508)
			(layers "B.Cu" "B.Mask" "B.Paste")
			(net "M_C_DQS_DN<10>")
		)
		(pad "20" smd rect
			(at 0 16.150082 270)
			(size 1.8034 0.508)
			(layers "B.Cu" "B.Mask" "B.Paste")
			(net "GND")
		)
		(pad "21" smd rect
			(at 0 16.999966 270)
			(size 1.8034 0.508)
			(layers "B.Cu" "B.Mask" "B.Paste")
			(net "M_C_DQ<14>")
		)
		(pad "22" smd rect
			(at 0 17.850104 270)
			(size 1.8034 0.508)
			(layers "B.Cu" "B.Mask" "B.Paste")
			(net "GND")
		)
		(pad "23" smd rect
			(at 0 18.699988 270)
			(size 1.8034 0.508)
			(layers "B.Cu" "B.Mask" "B.Paste")
			(net "M_C_DQ<10>")
		)
		(pad "24" smd rect
			(at 0 19.550126 270)
			(size 1.8034 0.508)
			(layers "B.Cu" "B.Mask" "B.Paste")
			(net "GND")
		)
		(pad "25" smd rect
			(at 0 20.40001 270)
			(size 1.8034 0.508)
			(layers "B.Cu" "B.Mask" "B.Paste")
			(net "M_C_DQ<20>")
		)
		(pad "26" smd rect
			(at 0 21.249894 270)
			(size 1.8034 0.508)
			(layers "B.Cu" "B.Mask" "B.Paste")
			(net "GND")
		)
		(pad "27" smd rect
			(at 0 22.100032 270)
			(size 1.8034 0.508)
			(layers "B.Cu" "B.Mask" "B.Paste")
			(net "M_C_DQ<16>")
		)
		(pad "28" smd rect
			(at 0 22.949916 270)
			(size 1.8034 0.508)
			(layers "B.Cu" "B.Mask" "B.Paste")
			(net "GND")
		)
		(pad "29" smd rect
			(at 0 23.800054 270)
			(size 1.8034 0.508)
			(layers "B.Cu" "B.Mask" "B.Paste")
			(net "M_C_DQS_DP<11>")
		)
		(pad "30" smd rect
			(at 0 24.649938 270)
			(size 1.8034 0.508)
			(layers "B.Cu" "B.Mask" "B.Paste")
			(net "M_C_DQS_DN<11>")
		)
		(pad "31" smd rect
			(at 0 25.500076 270)
			(size 1.8034 0.508)
			(layers "B.Cu" "B.Mask" "B.Paste")
			(net "GND")
		)
		(pad "32" smd rect
			(at 0 26.34996 270)
			(size 1.8034 0.508)
			(layers "B.Cu" "B.Mask" "B.Paste")
			(net "M_C_DQ<22>")
		)
		(pad "33" smd rect
			(at 0 27.200098 270)
			(size 1.8034 0.508)
			(layers "B.Cu" "B.Mask" "B.Paste")
			(net "GND")
		)
		(pad "34" smd rect
			(at 0 28.049982 270)
			(size 1.8034 0.508)
			(layers "B.Cu" "B.Mask" "B.Paste")
			(net "M_C_DQ<18>")
		)
		(pad "35" smd rect
			(at 0 28.90012 270)
			(size 1.8034 0.508)
			(layers "B.Cu" "B.Mask" "B.Paste")
			(net "GND")
		)
		(pad "36" smd rect
			(at 0 29.750004 270)
			(size 1.8034 0.508)
			(layers "B.Cu" "B.Mask" "B.Paste")
			(net "M_C_DQ<28>")
		)
		(pad "37" smd rect
			(at 0 30.599888 270)
			(size 1.8034 0.508)
			(layers "B.Cu" "B.Mask" "B.Paste")
			(net "GND")
		)
		(pad "38" smd rect
			(at 0 31.450026 270)
			(size 1.8034 0.508)
			(layers "B.Cu" "B.Mask" "B.Paste")
			(net "M_C_DQ<24>")
		)
		(pad "39" smd rect
			(at 0 32.29991 270)
			(size 1.8034 0.508)
			(layers "B.Cu" "B.Mask" "B.Paste")
			(net "GND")
		)
		(pad "40" smd rect
			(at 0 33.150048 270)
			(size 1.8034 0.508)
			(layers "B.Cu" "B.Mask" "B.Paste")
			(net "M_C_DQS_DP<12>")
		)
		(pad "41" smd rect
			(at 0 33.999932 270)
			(size 1.8034 0.508)
			(layers "B.Cu" "B.Mask" "B.Paste")
			(net "M_C_DQS_DN<12>")
		)
		(pad "42" smd rect
			(at 0 34.85007 270)
			(size 1.8034 0.508)
			(layers "B.Cu" "B.Mask" "B.Paste")
			(net "GND")
		)
		(pad "43" smd rect
			(at 0 35.699954 270)
			(size 1.8034 0.508)
			(layers "B.Cu" "B.Mask" "B.Paste")
			(net "M_C_DQ<30>")
		)
		(pad "44" smd rect
			(at 0 36.550092 270)
			(size 1.8034 0.508)
			(layers "B.Cu" "B.Mask" "B.Paste")
			(net "GND")
		)
		(pad "45" smd rect
			(at 0 37.399976 270)
			(size 1.8034 0.508)
			(layers "B.Cu" "B.Mask" "B.Paste")
			(net "M_C_DQ<26>")
		)
		(pad "46" smd rect
			(at 0 38.250114 270)
			(size 1.8034 0.508)
			(layers "B.Cu" "B.Mask" "B.Paste")
			(net "GND")
		)
		(pad "47" smd rect
			(at 0 39.099998 270)
			(size 1.8034 0.508)
			(layers "B.Cu" "B.Mask" "B.Paste")
			(net "M_C_ECC<4>")
		)
		(pad "48" smd rect
			(at 0 39.949882 270)
			(size 1.8034 0.508)
			(layers "B.Cu" "B.Mask" "B.Paste")
			(net "GND")
		)
		(pad "49" smd rect
			(at 0 40.80002 270)
			(size 1.8034 0.508)
			(layers "B.Cu" "B.Mask" "B.Paste")
			(net "M_C_ECC<0>")
		)
		(pad "50" smd rect
			(at 0 41.649904 270)
			(size 1.8034 0.508)
			(layers "B.Cu" "B.Mask" "B.Paste")
			(net "GND")
		)
		(pad "51" smd rect
			(at 0 42.500042 270)
			(size 1.8034 0.508)
			(layers "B.Cu" "B.Mask" "B.Paste")
			(net "M_C_DQS_DP<17>")
		)
		(pad "52" smd rect
			(at 0 43.349926 270)
			(size 1.8034 0.508)
			(layers "B.Cu" "B.Mask" "B.Paste")
			(net "M_C_DQS_DN<17>")
		)
		(pad "53" smd rect
			(at 0 44.200064 270)
			(size 1.8034 0.508)
			(layers "B.Cu" "B.Mask" "B.Paste")
			(net "GND")
		)
		(pad "54" smd rect
			(at 0 45.049948 270)
			(size 1.8034 0.508)
			(layers "B.Cu" "B.Mask" "B.Paste")
			(net "M_C_ECC<6>")
		)
		(pad "55" smd rect
			(at 0 45.900086 270)
			(size 1.8034 0.508)
			(layers "B.Cu" "B.Mask" "B.Paste")
			(net "GND")
		)
		(pad "56" smd rect
			(at 0 46.74997 270)
			(size 1.8034 0.508)
			(layers "B.Cu" "B.Mask" "B.Paste")
			(net "M_C_ECC<2>")
		)
		(pad "57" smd rect
			(at 0 47.600108 270)
			(size 1.8034 0.508)
			(layers "B.Cu" "B.Mask" "B.Paste")
			(net "GND")
		)
		(pad "58" smd rect
			(at 0 48.449992 270)
			(size 1.8034 0.508)
			(layers "B.Cu" "B.Mask" "B.Paste")
			(net "M_ABC_RST_N")
		)
		(pad "59" smd rect
			(at 0 49.299876 270)
			(size 1.8034 0.508)
			(layers "B.Cu" "B.Mask" "B.Paste")
			(net "PVDDQ_ABC")
		)
		(pad "60" smd rect
			(at 0 50.150014 270)
			(size 1.8034 0.508)
			(layers "B.Cu" "B.Mask" "B.Paste")
			(net "M_C_CKE<2>")
		)
		(pad "61" smd rect
			(at 0 50.999898 270)
			(size 1.8034 0.508)
			(layers "B.Cu" "B.Mask" "B.Paste")
			(net "PVDDQ_ABC")
		)
		(pad "62" smd rect
			(at 0 51.850036 270)
			(size 1.8034 0.508)
			(layers "B.Cu" "B.Mask" "B.Paste")
			(net "M_C_ACT_N")
		)
		(pad "63" smd rect
			(at 0 52.69992 270)
			(size 1.8034 0.508)
			(layers "B.Cu" "B.Mask" "B.Paste")
			(net "M_C_BG<0>")
		)
		(pad "64" smd rect
			(at 0 53.550058 270)
			(size 1.8034 0.508)
			(layers "B.Cu" "B.Mask" "B.Paste")
			(net "PVDDQ_ABC")
		)
		(pad "65" smd rect
			(at 0 54.399942 270)
			(size 1.8034 0.508)
			(layers "B.Cu" "B.Mask" "B.Paste")
			(net "M_C_MA<12>")
		)
		(pad "66" smd rect
			(at 0 55.25008 270)
			(size 1.8034 0.508)
			(layers "B.Cu" "B.Mask" "B.Paste")
			(net "M_C_MA<9>")
		)
		(pad "67" smd rect
			(at 0 56.099964 270)
			(size 1.8034 0.508)
			(layers "B.Cu" "B.Mask" "B.Paste")
			(net "PVDDQ_ABC")
		)
		(pad "68" smd rect
			(at 0 56.950102 270)
			(size 1.8034 0.508)
			(layers "B.Cu" "B.Mask" "B.Paste")
			(net "M_C_MA<8>")
		)
		(pad "69" smd rect
			(at 0 57.799986 270)
			(size 1.8034 0.508)
			(layers "B.Cu" "B.Mask" "B.Paste")
			(net "M_C_MA<6>")
		)
		(pad "70" smd rect
			(at 0 58.650124 270)
			(size 1.8034 0.508)
			(layers "B.Cu" "B.Mask" "B.Paste")
			(net "PVDDQ_ABC")
		)
		(pad "71" smd rect
			(at 0 59.500008 270)
			(size 1.8034 0.508)
			(layers "B.Cu" "B.Mask" "B.Paste")
			(net "M_C_MA<3>")
		)
		(pad "72" smd rect
			(at 0 60.349892 270)
			(size 1.8034 0.508)
			(layers "B.Cu" "B.Mask" "B.Paste")
			(net "M_C_MA<1>")
		)
		(pad "73" smd rect
			(at 0 61.20003 270)
			(size 1.8034 0.508)
			(layers "B.Cu" "B.Mask" "B.Paste")
			(net "PVDDQ_ABC")
		)
		(pad "74" smd rect
			(at 0 62.049914 270)
			(size 1.8034 0.508)
			(layers "B.Cu" "B.Mask" "B.Paste")
			(net "M_C_CLK_DP<2>")
		)
		(pad "75" smd rect
			(at 0 62.900052 270)
			(size 1.8034 0.508)
			(layers "B.Cu" "B.Mask" "B.Paste")
			(net "M_C_CLK_DN<2>")
		)
		(pad "76" smd rect
			(at 0 63.749936 270)
			(size 1.8034 0.508)
			(layers "B.Cu" "B.Mask" "B.Paste")
			(net "PVDDQ_ABC")
		)
		(pad "77" smd rect
			(at 0 64.600074 270)
			(size 1.8034 0.508)
			(layers "B.Cu" "B.Mask" "B.Paste")
			(net "PVTT_ABC")
		)
		(pad "78" smd rect
			(at 0 70.550024 270)
			(size 1.8034 0.508)
			(layers "B.Cu" "B.Mask" "B.Paste")
			(net "FM_DIMM_EVENT_COD_N")
		)
		(pad "79" smd rect
			(at 0 71.399908 270)
			(size 1.8034 0.508)
			(layers "B.Cu" "B.Mask" "B.Paste")
			(net "M_C_MA<0>")
		)
		(pad "80" smd rect
			(at 0 72.250046 270)
			(size 1.8034 0.508)
			(layers "B.Cu" "B.Mask" "B.Paste")
			(net "PVDDQ_ABC")
		)
		(pad "81" smd rect
			(at 0 73.09993 270)
			(size 1.8034 0.508)
			(layers "B.Cu" "B.Mask" "B.Paste")
			(net "M_C_BA<0>")
		)
		(pad "82" smd rect
			(at 0 73.950068 270)
			(size 1.8034 0.508)
			(layers "B.Cu" "B.Mask" "B.Paste")
			(net "M_C_MA<16>")
		)
		(pad "83" smd rect
			(at 0 74.799952 270)
			(size 1.8034 0.508)
			(layers "B.Cu" "B.Mask" "B.Paste")
			(net "PVDDQ_ABC")
		)
		(pad "84" smd rect
			(at 0 75.65009 270)
			(size 1.8034 0.508)
			(layers "B.Cu" "B.Mask" "B.Paste")
			(net "M_C_CS_N<4>")
		)
		(pad "85" smd rect
			(at 0 76.499974 270)
			(size 1.8034 0.508)
			(layers "B.Cu" "B.Mask" "B.Paste")
			(net "PVDDQ_ABC")
		)
		(pad "86" smd rect
			(at 0 77.350112 270)
			(size 1.8034 0.508)
			(layers "B.Cu" "B.Mask" "B.Paste")
			(net "M_C_MA<15>")
		)
		(pad "87" smd rect
			(at 0 78.199996 270)
			(size 1.8034 0.508)
			(layers "B.Cu" "B.Mask" "B.Paste")
			(net "M_C_ODT<2>")
		)
		(pad "88" smd rect
			(at 0 79.04988 270)
			(size 1.8034 0.508)
			(layers "B.Cu" "B.Mask" "B.Paste")
			(net "PVDDQ_ABC")
		)
		(pad "89" smd rect
			(at 0 79.900018 270)
			(size 1.8034 0.508)
			(layers "B.Cu" "B.Mask" "B.Paste")
			(net "M_C_CS_N<5>")
		)
		(pad "90" smd rect
			(at 0 80.749902 270)
			(size 1.8034 0.508)
			(layers "B.Cu" "B.Mask" "B.Paste")
			(net "PVDDQ_ABC")
		)
		(pad "91" smd rect
			(at 0 81.60004 270)
			(size 1.8034 0.508)
			(layers "B.Cu" "B.Mask" "B.Paste")
			(net "M_C_ODT<3>")
		)
		(pad "92" smd rect
			(at 0 82.449924 270)
			(size 1.8034 0.508)
			(layers "B.Cu" "B.Mask" "B.Paste")
			(net "PVDDQ_ABC")
		)
		(pad "93" smd rect
			(at 0 83.300062 270)
			(size 1.8034 0.508)
			(layers "B.Cu" "B.Mask" "B.Paste")
			(net "M_C_CS_N<6>")
		)
		(pad "94" smd rect
			(at 0 84.149946 270)
			(size 1.8034 0.508)
			(layers "B.Cu" "B.Mask" "B.Paste")
			(net "GND")
		)
		(pad "95" smd rect
			(at 0 85.000084 270)
			(size 1.8034 0.508)
			(layers "B.Cu" "B.Mask" "B.Paste")
			(net "M_C_DQ<36>")
		)
		(pad "96" smd rect
			(at 0 85.849968 270)
			(size 1.8034 0.508)
			(layers "B.Cu" "B.Mask" "B.Paste")
			(net "GND")
		)
		(pad "97" smd rect
			(at 0 86.700106 270)
			(size 1.8034 0.508)
			(layers "B.Cu" "B.Mask" "B.Paste")
			(net "M_C_DQ<32>")
		)
		(pad "98" smd rect
			(at 0 87.54999 270)
			(size 1.8034 0.508)
			(layers "B.Cu" "B.Mask" "B.Paste")
			(net "GND")
		)
		(pad "99" smd rect
			(at 0 88.399874 270)
			(size 1.8034 0.508)
			(layers "B.Cu" "B.Mask" "B.Paste")
			(net "M_C_DQS_DP<13>")
		)
		(pad "100" smd rect
			(at 0 89.250012 270)
			(size 1.8034 0.508)
			(layers "B.Cu" "B.Mask" "B.Paste")
			(net "M_C_DQS_DN<13>")
		)
		(pad "101" smd rect
			(at 0 90.099896 270)
			(size 1.8034 0.508)
			(layers "B.Cu" "B.Mask" "B.Paste")
			(net "GND")
		)
		(pad "102" smd rect
			(at 0 90.950034 270)
			(size 1.8034 0.508)
			(layers "B.Cu" "B.Mask" "B.Paste")
			(net "M_C_DQ<38>")
		)
		(pad "103" smd rect
			(at 0 91.799918 270)
			(size 1.8034 0.508)
			(layers "B.Cu" "B.Mask" "B.Paste")
			(net "GND")
		)
		(pad "104" smd rect
			(at 0 92.650056 270)
			(size 1.8034 0.508)
			(layers "B.Cu" "B.Mask" "B.Paste")
			(net "M_C_DQ<34>")
		)
		(pad "105" smd rect
			(at 0 93.49994 270)
			(size 1.8034 0.508)
			(layers "B.Cu" "B.Mask" "B.Paste")
			(net "GND")
		)
		(pad "106" smd rect
			(at 0 94.350078 270)
			(size 1.8034 0.508)
			(layers "B.Cu" "B.Mask" "B.Paste")
			(net "M_C_DQ<44>")
		)
		(pad "107" smd rect
			(at 0 95.199962 270)
			(size 1.8034 0.508)
			(layers "B.Cu" "B.Mask" "B.Paste")
			(net "GND")
		)
		(pad "108" smd rect
			(at 0 96.0501 270)
			(size 1.8034 0.508)
			(layers "B.Cu" "B.Mask" "B.Paste")
			(net "M_C_DQ<40>")
		)
		(pad "109" smd rect
			(at 0 96.899984 270)
			(size 1.8034 0.508)
			(layers "B.Cu" "B.Mask" "B.Paste")
			(net "GND")
		)
		(pad "110" smd rect
			(at 0 97.750122 270)
			(size 1.8034 0.508)
			(layers "B.Cu" "B.Mask" "B.Paste")
			(net "M_C_DQS_DP<14>")
		)
		(pad "111" smd rect
			(at 0 98.600006 270)
			(size 1.8034 0.508)
			(layers "B.Cu" "B.Mask" "B.Paste")
			(net "M_C_DQS_DN<14>")
		)
		(pad "112" smd rect
			(at 0 99.44989 270)
			(size 1.8034 0.508)
			(layers "B.Cu" "B.Mask" "B.Paste")
			(net "GND")
		)
		(pad "113" smd rect
			(at 0 100.300028 270)
			(size 1.8034 0.508)
			(layers "B.Cu" "B.Mask" "B.Paste")
			(net "M_C_DQ<46>")
		)
		(pad "114" smd rect
			(at 0 101.149912 270)
			(size 1.8034 0.508)
			(layers "B.Cu" "B.Mask" "B.Paste")
			(net "GND")
		)
		(pad "115" smd rect
			(at 0 102.00005 270)
			(size 1.8034 0.508)
			(layers "B.Cu" "B.Mask" "B.Paste")
			(net "M_C_DQ<42>")
		)
		(pad "116" smd rect
			(at 0 102.849934 270)
			(size 1.8034 0.508)
			(layers "B.Cu" "B.Mask" "B.Paste")
			(net "GND")
		)
		(pad "117" smd rect
			(at 0 103.700072 270)
			(size 1.8034 0.508)
			(layers "B.Cu" "B.Mask" "B.Paste")
			(net "M_C_DQ<52>")
		)
		(pad "118" smd rect
			(at 0 104.549956 270)
			(size 1.8034 0.508)
			(layers "B.Cu" "B.Mask" "B.Paste")
			(net "GND")
		)
		(pad "119" smd rect
			(at 0 105.400094 270)
			(size 1.8034 0.508)
			(layers "B.Cu" "B.Mask" "B.Paste")
			(net "M_C_DQ<48>")
		)
		(pad "120" smd rect
			(at 0 106.249978 270)
			(size 1.8034 0.508)
			(layers "B.Cu" "B.Mask" "B.Paste")
			(net "GND")
		)
		(pad "121" smd rect
			(at 0 107.100116 270)
			(size 1.8034 0.508)
			(layers "B.Cu" "B.Mask" "B.Paste")
			(net "M_C_DQS_DP<15>")
		)
		(pad "122" smd rect
			(at 0 107.95 270)
			(size 1.8034 0.508)
			(layers "B.Cu" "B.Mask" "B.Paste")
			(net "M_C_DQS_DN<15>")
		)
		(pad "123" smd rect
			(at 0 108.799884 270)
			(size 1.8034 0.508)
			(layers "B.Cu" "B.Mask" "B.Paste")
			(net "GND")
		)
		(pad "124" smd rect
			(at 0 109.650022 270)
			(size 1.8034 0.508)
			(layers "B.Cu" "B.Mask" "B.Paste")
			(net "M_C_DQ<54>")
		)
		(pad "125" smd rect
			(at 0 110.499906 270)
			(size 1.8034 0.508)
			(layers "B.Cu" "B.Mask" "B.Paste")
			(net "GND")
		)
		(pad "126" smd rect
			(at 0 111.350044 270)
			(size 1.8034 0.508)
			(layers "B.Cu" "B.Mask" "B.Paste")
			(net "M_C_DQ<50>")
		)
		(pad "127" smd rect
			(at 0 112.199928 270)
			(size 1.8034 0.508)
			(layers "B.Cu" "B.Mask" "B.Paste")
			(net "GND")
		)
		(pad "128" smd rect
			(at 0 113.050066 270)
			(size 1.8034 0.508)
			(layers "B.Cu" "B.Mask" "B.Paste")
			(net "M_C_DQ<60>")
		)
		(pad "129" smd rect
			(at 0 113.89995 270)
			(size 1.8034 0.508)
			(layers "B.Cu" "B.Mask" "B.Paste")
			(net "GND")
		)
		(pad "130" smd rect
			(at 0 114.750088 270)
			(size 1.8034 0.508)
			(layers "B.Cu" "B.Mask" "B.Paste")
			(net "M_C_DQ<56>")
		)
		(pad "131" smd rect
			(at 0 115.599972 270)
			(size 1.8034 0.508)
			(layers "B.Cu" "B.Mask" "B.Paste")
			(net "GND")
		)
		(pad "132" smd rect
			(at 0 116.45011 270)
			(size 1.8034 0.508)
			(layers "B.Cu" "B.Mask" "B.Paste")
			(net "M_C_DQS_DP<16>")
		)
		(pad "133" smd rect
			(at 0 117.299994 270)
			(size 1.8034 0.508)
			(layers "B.Cu" "B.Mask" "B.Paste")
			(net "M_C_DQS_DN<16>")
		)
		(pad "134" smd rect
			(at 0 118.149878 270)
			(size 1.8034 0.508)
			(layers "B.Cu" "B.Mask" "B.Paste")
			(net "GND")
		)
		(pad "135" smd rect
			(at 0 119.000016 270)
			(size 1.8034 0.508)
			(layers "B.Cu" "B.Mask" "B.Paste")
			(net "M_C_DQ<62>")
		)
		(pad "136" smd rect
			(at 0 119.8499 270)
			(size 1.8034 0.508)
			(layers "B.Cu" "B.Mask" "B.Paste")
			(net "GND")
		)
		(pad "137" smd rect
			(at 0 120.700038 270)
			(size 1.8034 0.508)
			(layers "B.Cu" "B.Mask" "B.Paste")
			(net "M_C_DQ<58>")
		)
		(pad "138" smd rect
			(at 0 121.549922 270)
			(size 1.8034 0.508)
			(layers "B.Cu" "B.Mask" "B.Paste")
			(net "GND")
		)
		(pad "139" smd rect
			(at 0 122.40006 270)
			(size 1.8034 0.508)
			(layers "B.Cu" "B.Mask" "B.Paste")
			(net "PVPP_ABC")
		)
		(pad "140" smd rect
			(at 0 123.249944 270)
			(size 1.8034 0.508)
			(layers "B.Cu" "B.Mask" "B.Paste")
			(net "GND")
		)
		(pad "141" smd rect
			(at 0 124.100082 270)
			(size 1.8034 0.508)
			(layers "B.Cu" "B.Mask" "B.Paste")
			(net "SMB_DDR_ABC_VPP_SCL")
		)
		(pad "142" smd rect
			(at 0 124.949966 270)
			(size 1.8034 0.508)
			(layers "B.Cu" "B.Mask" "B.Paste")
			(net "PVPP_ABC")
		)
		(pad "143" smd rect
			(at 0 125.800104 270)
			(size 1.8034 0.508)
			(layers "B.Cu" "B.Mask" "B.Paste")
			(net "PVPP_ABC")
		)
		(pad "144" smd rect
			(at 0 126.649988 270)
			(size 1.8034 0.508)
			(layers "B.Cu" "B.Mask" "B.Paste")
			(net "TP_CH_C_DIMM_C1_RFU_2")
		)
		(pad "145" smd rect
			(at -4.59994 0 270)
			(size 1.8034 0.508)
			(layers "B.Cu" "B.Mask" "B.Paste")
			(net "P12V_NVDIMM_ABC")
		)
		(pad "146" smd rect
			(at -4.59994 0.849884 270)
			(size 1.8034 0.508)
			(layers "B.Cu" "B.Mask" "B.Paste")
			(net "M_C_VREF")
		)
		(pad "147" smd rect
			(at -4.59994 1.700022 270)
			(size 1.8034 0.508)
			(layers "B.Cu" "B.Mask" "B.Paste")
			(net "GND")
		)
		(pad "148" smd rect
			(at -4.59994 2.549906 270)
			(size 1.8034 0.508)
			(layers "B.Cu" "B.Mask" "B.Paste")
			(net "M_C_DQ<5>")
		)
		(pad "149" smd rect
			(at -4.59994 3.400044 270)
			(size 1.8034 0.508)
			(layers "B.Cu" "B.Mask" "B.Paste")
			(net "GND")
		)
		(pad "150" smd rect
			(at -4.59994 4.249928 270)
			(size 1.8034 0.508)
			(layers "B.Cu" "B.Mask" "B.Paste")
			(net "M_C_DQ<1>")
		)
		(pad "151" smd rect
			(at -4.59994 5.100066 270)
			(size 1.8034 0.508)
			(layers "B.Cu" "B.Mask" "B.Paste")
			(net "GND")
		)
		(pad "152" smd rect
			(at -4.59994 5.94995 270)
			(size 1.8034 0.508)
			(layers "B.Cu" "B.Mask" "B.Paste")
			(net "M_C_DQS_DN<0>")
		)
		(pad "153" smd rect
			(at -4.59994 6.800088 270)
			(size 1.8034 0.508)
			(layers "B.Cu" "B.Mask" "B.Paste")
			(net "M_C_DQS_DP<0>")
		)
		(pad "154" smd rect
			(at -4.59994 7.649972 270)
			(size 1.8034 0.508)
			(layers "B.Cu" "B.Mask" "B.Paste")
			(net "GND")
		)
		(pad "155" smd rect
			(at -4.59994 8.50011 270)
			(size 1.8034 0.508)
			(layers "B.Cu" "B.Mask" "B.Paste")
			(net "M_C_DQ<7>")
		)
		(pad "156" smd rect
			(at -4.59994 9.349994 270)
			(size 1.8034 0.508)
			(layers "B.Cu" "B.Mask" "B.Paste")
			(net "GND")
		)
		(pad "157" smd rect
			(at -4.59994 10.199878 270)
			(size 1.8034 0.508)
			(layers "B.Cu" "B.Mask" "B.Paste")
			(net "M_C_DQ<3>")
		)
		(pad "158" smd rect
			(at -4.59994 11.050016 270)
			(size 1.8034 0.508)
			(layers "B.Cu" "B.Mask" "B.Paste")
			(net "GND")
		)
		(pad "159" smd rect
			(at -4.59994 11.8999 270)
			(size 1.8034 0.508)
			(layers "B.Cu" "B.Mask" "B.Paste")
			(net "M_C_DQ<13>")
		)
		(pad "160" smd rect
			(at -4.59994 12.750038 270)
			(size 1.8034 0.508)
			(layers "B.Cu" "B.Mask" "B.Paste")
			(net "GND")
		)
		(pad "161" smd rect
			(at -4.59994 13.599922 270)
			(size 1.8034 0.508)
			(layers "B.Cu" "B.Mask" "B.Paste")
			(net "M_C_DQ<9>")
		)
		(pad "162" smd rect
			(at -4.59994 14.45006 270)
			(size 1.8034 0.508)
			(layers "B.Cu" "B.Mask" "B.Paste")
			(net "GND")
		)
		(pad "163" smd rect
			(at -4.59994 15.299944 270)
			(size 1.8034 0.508)
			(layers "B.Cu" "B.Mask" "B.Paste")
			(net "M_C_DQS_DN<1>")
		)
		(pad "164" smd rect
			(at -4.59994 16.150082 270)
			(size 1.8034 0.508)
			(layers "B.Cu" "B.Mask" "B.Paste")
			(net "M_C_DQS_DP<1>")
		)
		(pad "165" smd rect
			(at -4.59994 16.999966 270)
			(size 1.8034 0.508)
			(layers "B.Cu" "B.Mask" "B.Paste")
			(net "GND")
		)
		(pad "166" smd rect
			(at -4.59994 17.850104 270)
			(size 1.8034 0.508)
			(layers "B.Cu" "B.Mask" "B.Paste")
			(net "M_C_DQ<15>")
		)
		(pad "167" smd rect
			(at -4.59994 18.699988 270)
			(size 1.8034 0.508)
			(layers "B.Cu" "B.Mask" "B.Paste")
			(net "GND")
		)
		(pad "168" smd rect
			(at -4.59994 19.550126 270)
			(size 1.8034 0.508)
			(layers "B.Cu" "B.Mask" "B.Paste")
			(net "M_C_DQ<11>")
		)
		(pad "169" smd rect
			(at -4.59994 20.40001 270)
			(size 1.8034 0.508)
			(layers "B.Cu" "B.Mask" "B.Paste")
			(net "GND")
		)
		(pad "170" smd rect
			(at -4.59994 21.249894 270)
			(size 1.8034 0.508)
			(layers "B.Cu" "B.Mask" "B.Paste")
			(net "M_C_DQ<21>")
		)
		(pad "171" smd rect
			(at -4.59994 22.100032 270)
			(size 1.8034 0.508)
			(layers "B.Cu" "B.Mask" "B.Paste")
			(net "GND")
		)
		(pad "172" smd rect
			(at -4.59994 22.949916 270)
			(size 1.8034 0.508)
			(layers "B.Cu" "B.Mask" "B.Paste")
			(net "M_C_DQ<17>")
		)
		(pad "173" smd rect
			(at -4.59994 23.800054 270)
			(size 1.8034 0.508)
			(layers "B.Cu" "B.Mask" "B.Paste")
			(net "GND")
		)
		(pad "174" smd rect
			(at -4.59994 24.649938 270)
			(size 1.8034 0.508)
			(layers "B.Cu" "B.Mask" "B.Paste")
			(net "M_C_DQS_DN<2>")
		)
		(pad "175" smd rect
			(at -4.59994 25.500076 270)
			(size 1.8034 0.508)
			(layers "B.Cu" "B.Mask" "B.Paste")
			(net "M_C_DQS_DP<2>")
		)
		(pad "176" smd rect
			(at -4.59994 26.34996 270)
			(size 1.8034 0.508)
			(layers "B.Cu" "B.Mask" "B.Paste")
			(net "GND")
		)
		(pad "177" smd rect
			(at -4.59994 27.200098 270)
			(size 1.8034 0.508)
			(layers "B.Cu" "B.Mask" "B.Paste")
			(net "M_C_DQ<23>")
		)
		(pad "178" smd rect
			(at -4.59994 28.049982 270)
			(size 1.8034 0.508)
			(layers "B.Cu" "B.Mask" "B.Paste")
			(net "GND")
		)
		(pad "179" smd rect
			(at -4.59994 28.90012 270)
			(size 1.8034 0.508)
			(layers "B.Cu" "B.Mask" "B.Paste")
			(net "M_C_DQ<19>")
		)
		(pad "180" smd rect
			(at -4.59994 29.750004 270)
			(size 1.8034 0.508)
			(layers "B.Cu" "B.Mask" "B.Paste")
			(net "GND")
		)
		(pad "181" smd rect
			(at -4.59994 30.599888 270)
			(size 1.8034 0.508)
			(layers "B.Cu" "B.Mask" "B.Paste")
			(net "M_C_DQ<29>")
		)
		(pad "182" smd rect
			(at -4.59994 31.450026 270)
			(size 1.8034 0.508)
			(layers "B.Cu" "B.Mask" "B.Paste")
			(net "GND")
		)
		(pad "183" smd rect
			(at -4.59994 32.29991 270)
			(size 1.8034 0.508)
			(layers "B.Cu" "B.Mask" "B.Paste")
			(net "M_C_DQ<25>")
		)
		(pad "184" smd rect
			(at -4.59994 33.150048 270)
			(size 1.8034 0.508)
			(layers "B.Cu" "B.Mask" "B.Paste")
			(net "GND")
		)
		(pad "185" smd rect
			(at -4.59994 33.999932 270)
			(size 1.8034 0.508)
			(layers "B.Cu" "B.Mask" "B.Paste")
			(net "M_C_DQS_DN<3>")
		)
		(pad "186" smd rect
			(at -4.59994 34.85007 270)
			(size 1.8034 0.508)
			(layers "B.Cu" "B.Mask" "B.Paste")
			(net "M_C_DQS_DP<3>")
		)
		(pad "187" smd rect
			(at -4.59994 35.699954 270)
			(size 1.8034 0.508)
			(layers "B.Cu" "B.Mask" "B.Paste")
			(net "GND")
		)
		(pad "188" smd rect
			(at -4.59994 36.550092 270)
			(size 1.8034 0.508)
			(layers "B.Cu" "B.Mask" "B.Paste")
			(net "M_C_DQ<31>")
		)
		(pad "189" smd rect
			(at -4.59994 37.399976 270)
			(size 1.8034 0.508)
			(layers "B.Cu" "B.Mask" "B.Paste")
			(net "GND")
		)
		(pad "190" smd rect
			(at -4.59994 38.250114 270)
			(size 1.8034 0.508)
			(layers "B.Cu" "B.Mask" "B.Paste")
			(net "M_C_DQ<27>")
		)
		(pad "191" smd rect
			(at -4.59994 39.099998 270)
			(size 1.8034 0.508)
			(layers "B.Cu" "B.Mask" "B.Paste")
			(net "GND")
		)
		(pad "192" smd rect
			(at -4.59994 39.949882 270)
			(size 1.8034 0.508)
			(layers "B.Cu" "B.Mask" "B.Paste")
			(net "M_C_ECC<5>")
		)
		(pad "193" smd rect
			(at -4.59994 40.80002 270)
			(size 1.8034 0.508)
			(layers "B.Cu" "B.Mask" "B.Paste")
			(net "GND")
		)
		(pad "194" smd rect
			(at -4.59994 41.649904 270)
			(size 1.8034 0.508)
			(layers "B.Cu" "B.Mask" "B.Paste")
			(net "M_C_ECC<1>")
		)
		(pad "195" smd rect
			(at -4.59994 42.500042 270)
			(size 1.8034 0.508)
			(layers "B.Cu" "B.Mask" "B.Paste")
			(net "GND")
		)
		(pad "196" smd rect
			(at -4.59994 43.349926 270)
			(size 1.8034 0.508)
			(layers "B.Cu" "B.Mask" "B.Paste")
			(net "M_C_DQS_DN<8>")
		)
		(pad "197" smd rect
			(at -4.59994 44.200064 270)
			(size 1.8034 0.508)
			(layers "B.Cu" "B.Mask" "B.Paste")
			(net "M_C_DQS_DP<8>")
		)
		(pad "198" smd rect
			(at -4.59994 45.049948 270)
			(size 1.8034 0.508)
			(layers "B.Cu" "B.Mask" "B.Paste")
			(net "GND")
		)
		(pad "199" smd rect
			(at -4.59994 45.900086 270)
			(size 1.8034 0.508)
			(layers "B.Cu" "B.Mask" "B.Paste")
			(net "M_C_ECC<7>")
		)
		(pad "200" smd rect
			(at -4.59994 46.74997 270)
			(size 1.8034 0.508)
			(layers "B.Cu" "B.Mask" "B.Paste")
			(net "GND")
		)
		(pad "201" smd rect
			(at -4.59994 47.600108 270)
			(size 1.8034 0.508)
			(layers "B.Cu" "B.Mask" "B.Paste")
			(net "M_C_ECC<3>")
		)
		(pad "202" smd rect
			(at -4.59994 48.449992 270)
			(size 1.8034 0.508)
			(layers "B.Cu" "B.Mask" "B.Paste")
			(net "GND")
		)
		(pad "203" smd rect
			(at -4.59994 49.299876 270)
			(size 1.8034 0.508)
			(layers "B.Cu" "B.Mask" "B.Paste")
			(net "M_C_CKE<3>")
		)
		(pad "204" smd rect
			(at -4.59994 50.150014 270)
			(size 1.8034 0.508)
			(layers "B.Cu" "B.Mask" "B.Paste")
			(net "PVDDQ_ABC")
		)
		(pad "205" smd rect
			(at -4.59994 50.999898 270)
			(size 1.8034 0.508)
			(layers "B.Cu" "B.Mask" "B.Paste")
			(net "TP_CH_C_DIMM_C1_RFU_0")
		)
		(pad "206" smd rect
			(at -4.59994 51.850036 270)
			(size 1.8034 0.508)
			(layers "B.Cu" "B.Mask" "B.Paste")
			(net "PVDDQ_ABC")
		)
		(pad "207" smd rect
			(at -4.59994 52.69992 270)
			(size 1.8034 0.508)
			(layers "B.Cu" "B.Mask" "B.Paste")
			(net "M_C_BG<1>")
		)
		(pad "208" smd rect
			(at -4.59994 53.550058 270)
			(size 1.8034 0.508)
			(layers "B.Cu" "B.Mask" "B.Paste")
			(net "M_C_ALERT_N")
		)
		(pad "209" smd rect
			(at -4.59994 54.399942 270)
			(size 1.8034 0.508)
			(layers "B.Cu" "B.Mask" "B.Paste")
			(net "PVDDQ_ABC")
		)
		(pad "210" smd rect
			(at -4.59994 55.25008 270)
			(size 1.8034 0.508)
			(layers "B.Cu" "B.Mask" "B.Paste")
			(net "M_C_MA<11>")
		)
		(pad "211" smd rect
			(at -4.59994 56.099964 270)
			(size 1.8034 0.508)
			(layers "B.Cu" "B.Mask" "B.Paste")
			(net "M_C_MA<7>")
		)
		(pad "212" smd rect
			(at -4.59994 56.950102 270)
			(size 1.8034 0.508)
			(layers "B.Cu" "B.Mask" "B.Paste")
			(net "PVDDQ_ABC")
		)
		(pad "213" smd rect
			(at -4.59994 57.799986 270)
			(size 1.8034 0.508)
			(layers "B.Cu" "B.Mask" "B.Paste")
			(net "M_C_MA<5>")
		)
		(pad "214" smd rect
			(at -4.59994 58.650124 270)
			(size 1.8034 0.508)
			(layers "B.Cu" "B.Mask" "B.Paste")
			(net "M_C_MA<4>")
		)
		(pad "215" smd rect
			(at -4.59994 59.500008 270)
			(size 1.8034 0.508)
			(layers "B.Cu" "B.Mask" "B.Paste")
			(net "PVDDQ_ABC")
		)
		(pad "216" smd rect
			(at -4.59994 60.349892 270)
			(size 1.8034 0.508)
			(layers "B.Cu" "B.Mask" "B.Paste")
			(net "M_C_MA<2>")
		)
		(pad "217" smd rect
			(at -4.59994 61.20003 270)
			(size 1.8034 0.508)
			(layers "B.Cu" "B.Mask" "B.Paste")
			(net "PVDDQ_ABC")
		)
		(pad "218" smd rect
			(at -4.59994 62.049914 270)
			(size 1.8034 0.508)
			(layers "B.Cu" "B.Mask" "B.Paste")
			(net "M_C_CLK_DP<3>")
		)
		(pad "219" smd rect
			(at -4.59994 62.900052 270)
			(size 1.8034 0.508)
			(layers "B.Cu" "B.Mask" "B.Paste")
			(net "M_C_CLK_DN<3>")
		)
		(pad "220" smd rect
			(at -4.59994 63.749936 270)
			(size 1.8034 0.508)
			(layers "B.Cu" "B.Mask" "B.Paste")
			(net "PVDDQ_ABC")
		)
		(pad "221" smd rect
			(at -4.59994 64.600074 270)
			(size 1.8034 0.508)
			(layers "B.Cu" "B.Mask" "B.Paste")
			(net "PVTT_ABC")
		)
		(pad "222" smd rect
			(at -4.59994 70.550024 270)
			(size 1.8034 0.508)
			(layers "B.Cu" "B.Mask" "B.Paste")
			(net "M_C_PAR")
		)
		(pad "223" smd rect
			(at -4.59994 71.399908 270)
			(size 1.8034 0.508)
			(layers "B.Cu" "B.Mask" "B.Paste")
			(net "PVDDQ_ABC")
		)
		(pad "224" smd rect
			(at -4.59994 72.250046 270)
			(size 1.8034 0.508)
			(layers "B.Cu" "B.Mask" "B.Paste")
			(net "M_C_BA<1>")
		)
		(pad "225" smd rect
			(at -4.59994 73.09993 270)
			(size 1.8034 0.508)
			(layers "B.Cu" "B.Mask" "B.Paste")
			(net "M_C_MA<10>")
		)
		(pad "226" smd rect
			(at -4.59994 73.950068 270)
			(size 1.8034 0.508)
			(layers "B.Cu" "B.Mask" "B.Paste")
			(net "PVDDQ_ABC")
		)
		(pad "227" smd rect
			(at -4.59994 74.799952 270)
			(size 1.8034 0.508)
			(layers "B.Cu" "B.Mask" "B.Paste")
			(net "TP_CH_C_DIMM_C1_RFU_1")
		)
		(pad "228" smd rect
			(at -4.59994 75.65009 270)
			(size 1.8034 0.508)
			(layers "B.Cu" "B.Mask" "B.Paste")
			(net "M_C_MA<14>")
		)
		(pad "229" smd rect
			(at -4.59994 76.499974 270)
			(size 1.8034 0.508)
			(layers "B.Cu" "B.Mask" "B.Paste")
			(net "PVDDQ_ABC")
		)
		(pad "230" smd rect
			(at -4.59994 77.350112 270)
			(size 1.8034 0.508)
			(layers "B.Cu" "B.Mask" "B.Paste")
			(net "FM_ADR_COMPLETE_ABC_N")
		)
		(pad "231" smd rect
			(at -4.59994 78.199996 270)
			(size 1.8034 0.508)
			(layers "B.Cu" "B.Mask" "B.Paste")
			(net "PVDDQ_ABC")
		)
		(pad "232" smd rect
			(at -4.59994 79.04988 270)
			(size 1.8034 0.508)
			(layers "B.Cu" "B.Mask" "B.Paste")
			(net "M_C_MA<13>")
		)
		(pad "233" smd rect
			(at -4.59994 79.900018 270)
			(size 1.8034 0.508)
			(layers "B.Cu" "B.Mask" "B.Paste")
			(net "PVDDQ_ABC")
		)
		(pad "234" smd rect
			(at -4.59994 80.749902 270)
			(size 1.8034 0.508)
			(layers "B.Cu" "B.Mask" "B.Paste")
			(net "M_C_MA<17>")
		)
		(pad "235" smd rect
			(at -4.59994 81.60004 270)
			(size 1.8034 0.508)
			(layers "B.Cu" "B.Mask" "B.Paste")
			(net "M_C_C<2>")
		)
		(pad "236" smd rect
			(at -4.59994 82.449924 270)
			(size 1.8034 0.508)
			(layers "B.Cu" "B.Mask" "B.Paste")
			(net "PVDDQ_ABC")
		)
		(pad "237" smd rect
			(at -4.59994 83.300062 270)
			(size 1.8034 0.508)
			(layers "B.Cu" "B.Mask" "B.Paste")
			(net "M_C_CS_N<7>")
		)
		(pad "238" smd rect
			(at -4.59994 84.149946 270)
			(size 1.8034 0.508)
			(layers "B.Cu" "B.Mask" "B.Paste")
			(net "PVPP_ABC")
		)
		(pad "239" smd rect
			(at -4.59994 85.000084 270)
			(size 1.8034 0.508)
			(layers "B.Cu" "B.Mask" "B.Paste")
			(net "GND")
		)
		(pad "240" smd rect
			(at -4.59994 85.849968 270)
			(size 1.8034 0.508)
			(layers "B.Cu" "B.Mask" "B.Paste")
			(net "M_C_DQ<37>")
		)
		(pad "241" smd rect
			(at -4.59994 86.700106 270)
			(size 1.8034 0.508)
			(layers "B.Cu" "B.Mask" "B.Paste")
			(net "GND")
		)
		(pad "242" smd rect
			(at -4.59994 87.54999 270)
			(size 1.8034 0.508)
			(layers "B.Cu" "B.Mask" "B.Paste")
			(net "M_C_DQ<33>")
		)
		(pad "243" smd rect
			(at -4.59994 88.399874 270)
			(size 1.8034 0.508)
			(layers "B.Cu" "B.Mask" "B.Paste")
			(net "GND")
		)
		(pad "244" smd rect
			(at -4.59994 89.250012 270)
			(size 1.8034 0.508)
			(layers "B.Cu" "B.Mask" "B.Paste")
			(net "M_C_DQS_DN<4>")
		)
		(pad "245" smd rect
			(at -4.59994 90.099896 270)
			(size 1.8034 0.508)
			(layers "B.Cu" "B.Mask" "B.Paste")
			(net "M_C_DQS_DP<4>")
		)
		(pad "246" smd rect
			(at -4.59994 90.950034 270)
			(size 1.8034 0.508)
			(layers "B.Cu" "B.Mask" "B.Paste")
			(net "GND")
		)
		(pad "247" smd rect
			(at -4.59994 91.799918 270)
			(size 1.8034 0.508)
			(layers "B.Cu" "B.Mask" "B.Paste")
			(net "M_C_DQ<39>")
		)
		(pad "248" smd rect
			(at -4.59994 92.650056 270)
			(size 1.8034 0.508)
			(layers "B.Cu" "B.Mask" "B.Paste")
			(net "GND")
		)
		(pad "249" smd rect
			(at -4.59994 93.49994 270)
			(size 1.8034 0.508)
			(layers "B.Cu" "B.Mask" "B.Paste")
			(net "M_C_DQ<35>")
		)
		(pad "250" smd rect
			(at -4.59994 94.350078 270)
			(size 1.8034 0.508)
			(layers "B.Cu" "B.Mask" "B.Paste")
			(net "GND")
		)
		(pad "251" smd rect
			(at -4.59994 95.199962 270)
			(size 1.8034 0.508)
			(layers "B.Cu" "B.Mask" "B.Paste")
			(net "M_C_DQ<45>")
		)
		(pad "252" smd rect
			(at -4.59994 96.0501 270)
			(size 1.8034 0.508)
			(layers "B.Cu" "B.Mask" "B.Paste")
			(net "GND")
		)
		(pad "253" smd rect
			(at -4.59994 96.899984 270)
			(size 1.8034 0.508)
			(layers "B.Cu" "B.Mask" "B.Paste")
			(net "M_C_DQ<41>")
		)
		(pad "254" smd rect
			(at -4.59994 97.750122 270)
			(size 1.8034 0.508)
			(layers "B.Cu" "B.Mask" "B.Paste")
			(net "GND")
		)
		(pad "255" smd rect
			(at -4.59994 98.600006 270)
			(size 1.8034 0.508)
			(layers "B.Cu" "B.Mask" "B.Paste")
			(net "M_C_DQS_DN<5>")
		)
		(pad "256" smd rect
			(at -4.59994 99.44989 270)
			(size 1.8034 0.508)
			(layers "B.Cu" "B.Mask" "B.Paste")
			(net "M_C_DQS_DP<5>")
		)
		(pad "257" smd rect
			(at -4.59994 100.300028 270)
			(size 1.8034 0.508)
			(layers "B.Cu" "B.Mask" "B.Paste")
			(net "GND")
		)
		(pad "258" smd rect
			(at -4.59994 101.149912 270)
			(size 1.8034 0.508)
			(layers "B.Cu" "B.Mask" "B.Paste")
			(net "M_C_DQ<47>")
		)
		(pad "259" smd rect
			(at -4.59994 102.00005 270)
			(size 1.8034 0.508)
			(layers "B.Cu" "B.Mask" "B.Paste")
			(net "GND")
		)
		(pad "260" smd rect
			(at -4.59994 102.849934 270)
			(size 1.8034 0.508)
			(layers "B.Cu" "B.Mask" "B.Paste")
			(net "M_C_DQ<43>")
		)
		(pad "261" smd rect
			(at -4.59994 103.700072 270)
			(size 1.8034 0.508)
			(layers "B.Cu" "B.Mask" "B.Paste")
			(net "GND")
		)
		(pad "262" smd rect
			(at -4.59994 104.549956 270)
			(size 1.8034 0.508)
			(layers "B.Cu" "B.Mask" "B.Paste")
			(net "M_C_DQ<53>")
		)
		(pad "263" smd rect
			(at -4.59994 105.400094 270)
			(size 1.8034 0.508)
			(layers "B.Cu" "B.Mask" "B.Paste")
			(net "GND")
		)
		(pad "264" smd rect
			(at -4.59994 106.249978 270)
			(size 1.8034 0.508)
			(layers "B.Cu" "B.Mask" "B.Paste")
			(net "M_C_DQ<49>")
		)
		(pad "265" smd rect
			(at -4.59994 107.100116 270)
			(size 1.8034 0.508)
			(layers "B.Cu" "B.Mask" "B.Paste")
			(net "GND")
		)
		(pad "266" smd rect
			(at -4.59994 107.95 270)
			(size 1.8034 0.508)
			(layers "B.Cu" "B.Mask" "B.Paste")
			(net "M_C_DQS_DN<6>")
		)
		(pad "267" smd rect
			(at -4.59994 108.799884 270)
			(size 1.8034 0.508)
			(layers "B.Cu" "B.Mask" "B.Paste")
			(net "M_C_DQS_DP<6>")
		)
		(pad "268" smd rect
			(at -4.59994 109.650022 270)
			(size 1.8034 0.508)
			(layers "B.Cu" "B.Mask" "B.Paste")
			(net "GND")
		)
		(pad "269" smd rect
			(at -4.59994 110.499906 270)
			(size 1.8034 0.508)
			(layers "B.Cu" "B.Mask" "B.Paste")
			(net "M_C_DQ<55>")
		)
		(pad "270" smd rect
			(at -4.59994 111.350044 270)
			(size 1.8034 0.508)
			(layers "B.Cu" "B.Mask" "B.Paste")
			(net "GND")
		)
		(pad "271" smd rect
			(at -4.59994 112.199928 270)
			(size 1.8034 0.508)
			(layers "B.Cu" "B.Mask" "B.Paste")
			(net "M_C_DQ<51>")
		)
		(pad "272" smd rect
			(at -4.59994 113.050066 270)
			(size 1.8034 0.508)
			(layers "B.Cu" "B.Mask" "B.Paste")
			(net "GND")
		)
		(pad "273" smd rect
			(at -4.59994 113.89995 270)
			(size 1.8034 0.508)
			(layers "B.Cu" "B.Mask" "B.Paste")
			(net "M_C_DQ<61>")
		)
		(pad "274" smd rect
			(at -4.59994 114.750088 270)
			(size 1.8034 0.508)
			(layers "B.Cu" "B.Mask" "B.Paste")
			(net "GND")
		)
		(pad "275" smd rect
			(at -4.59994 115.599972 270)
			(size 1.8034 0.508)
			(layers "B.Cu" "B.Mask" "B.Paste")
			(net "M_C_DQ<57>")
		)
		(pad "276" smd rect
			(at -4.59994 116.45011 270)
			(size 1.8034 0.508)
			(layers "B.Cu" "B.Mask" "B.Paste")
			(net "GND")
		)
		(pad "277" smd rect
			(at -4.59994 117.299994 270)
			(size 1.8034 0.508)
			(layers "B.Cu" "B.Mask" "B.Paste")
			(net "M_C_DQS_DN<7>")
		)
		(pad "278" smd rect
			(at -4.59994 118.149878 270)
			(size 1.8034 0.508)
			(layers "B.Cu" "B.Mask" "B.Paste")
			(net "M_C_DQS_DP<7>")
		)
		(pad "279" smd rect
			(at -4.59994 119.000016 270)
			(size 1.8034 0.508)
			(layers "B.Cu" "B.Mask" "B.Paste")
			(net "GND")
		)
		(pad "280" smd rect
			(at -4.59994 119.8499 270)
			(size 1.8034 0.508)
			(layers "B.Cu" "B.Mask" "B.Paste")
			(net "M_C_DQ<63>")
		)
		(pad "281" smd rect
			(at -4.59994 120.700038 270)
			(size 1.8034 0.508)
			(layers "B.Cu" "B.Mask" "B.Paste")
			(net "GND")
		)
		(pad "282" smd rect
			(at -4.59994 121.549922 270)
			(size 1.8034 0.508)
			(layers "B.Cu" "B.Mask" "B.Paste")
			(net "M_C_DQ<59>")
		)
		(pad "283" smd rect
			(at -4.59994 122.40006 270)
			(size 1.8034 0.508)
			(layers "B.Cu" "B.Mask" "B.Paste")
			(net "GND")
		)
		(pad "284" smd rect
			(at -4.59994 123.249944 270)
			(size 1.8034 0.508)
			(layers "B.Cu" "B.Mask" "B.Paste")
			(net "PVPP_ABC")
		)
		(pad "285" smd rect
			(at -4.59994 124.100082 270)
			(size 1.8034 0.508)
			(layers "B.Cu" "B.Mask" "B.Paste")
			(net "SMB_DDR_ABC_VPP_SDA")
		)
		(pad "286" smd rect
			(at -4.59994 124.949966 270)
			(size 1.8034 0.508)
			(layers "B.Cu" "B.Mask" "B.Paste")
			(net "PVPP_ABC")
		)
		(pad "287" smd rect
			(at -4.59994 125.800104 270)
			(size 1.8034 0.508)
			(layers "B.Cu" "B.Mask" "B.Paste")
			(net "PVPP_ABC")
		)
		(pad "288" smd rect
			(at -4.59994 126.649988 270)
			(size 1.8034 0.508)
			(layers "B.Cu" "B.Mask" "B.Paste")
			(net "PVPP_ABC")
		)
	)
	(footprint ""
		(layer "B.Cu")
		(at 411.861 -145.415 -90)
		(property "Reference" "C2L27"
			(at 0 0 90)
			(layer "B.SilkS")
			(hide yes)
			(effects
				(font
					(size 1.27 1.27)
				)
				(justify mirror)
			)
		)
		(property "Value" ""
			(at 0 0 90)
			(layer "B.Fab")
			(effects
				(font
					(size 1.27 1.27)
				)
				(justify mirror)
			)
		)
		(duplicate_pad_numbers_are_jumpers no)
		(fp_poly
			(pts
				(xy -0.3048 -0.1016) (xy -0.3048 0.9906) (xy 0.3048 0.9906) (xy 0.3048 -0.1016)
			)
			(stroke
				(width 0)
				(type default)
			)
			(fill no)
			(layer "B.CrtYd")
		)
		(fp_line
			(start -0.3048 0.9906)
			(end -0.3048 -0.1016)
			(stroke
				(width 0.1)
				(type default)
			)
			(layer "B.Fab")
		)
		(fp_line
			(start 0.3048 0.9906)
			(end -0.3048 0.9906)
			(stroke
				(width 0.1)
				(type default)
			)
			(layer "B.Fab")
		)
		(fp_line
			(start -0.3048 -0.1016)
			(end 0.3048 -0.1016)
			(stroke
				(width 0.1)
				(type default)
			)
			(layer "B.Fab")
		)
		(fp_line
			(start 0.3048 -0.1016)
			(end 0.3048 0.9906)
			(stroke
				(width 0.1)
				(type default)
			)
			(layer "B.Fab")
		)
		(pad "1" smd rect
			(at 0 0 90)
			(size 0.508 0.508)
			(layers "B.Cu" "B.Mask" "B.Paste")
			(net "SATA6G_P5_TX_C_DP")
		)
		(pad "2" smd rect
			(at 0 0.889 90)
			(size 0.508 0.508)
			(layers "B.Cu" "B.Mask" "B.Paste")
			(net "SATA6G_PCH_PCIE_UP_SATA_TXP<5>")
		)
		(zone
			(layer "B.Cu")
			(hatch none 0.5)
			(connect_pads
				(clearance 0)
			)
			(min_thickness 0.25)
			(keepout
				(tracks not_allowed)
				(vias allowed)
				(pads allowed)
				(copperpour not_allowed)
				(footprints allowed)
			)
			(placement
				(enabled no)
				(sheetname "")
			)
			(fill
				(thermal_gap 0.5)
				(thermal_bridge_width 0.5)
				(island_removal_mode 0)
			)
			(polygon
				(pts
					(xy 411.226 -145.161) (xy 411.226 -145.669) (xy 411.607 -145.669) (xy 411.607 -145.161)
				)
			)
		)
		(zone
			(layer "B.Cu")
			(hatch none 0.5)
			(connect_pads
				(clearance 0)
			)
			(min_thickness 0.25)
			(keepout
				(tracks allowed)
				(vias not_allowed)
				(pads allowed)
				(copperpour not_allowed)
				(footprints allowed)
			)
			(placement
				(enabled no)
				(sheetname "")
			)
			(fill
				(thermal_gap 0.5)
				(thermal_bridge_width 0.5)
				(island_removal_mode 0)
			)
			(polygon
				(pts
					(xy 411.607 -145.161) (xy 411.607 -145.669) (xy 411.226 -145.669) (xy 411.226 -145.161)
				)
			)
		)
	)
	(footprint ""
		(layer "B.Cu")
		(at 352.904806 -61.257434)
		(property "Reference" "C2U17"
			(at 0 0 0)
			(layer "B.SilkS")
			(hide yes)
			(effects
				(font
					(size 1.27 1.27)
				)
				(justify mirror)
			)
		)
		(property "Value" ""
			(at 0 0 0)
			(layer "B.Fab")
			(effects
				(font
					(size 1.27 1.27)
				)
				(justify mirror)
			)
		)
		(duplicate_pad_numbers_are_jumpers no)
		(fp_poly
			(pts
				(xy -0.3048 -0.1016) (xy -0.3048 0.9906) (xy 0.3048 0.9906) (xy 0.3048 -0.1016)
			)
			(stroke
				(width 0)
				(type default)
			)
			(fill no)
			(layer "B.CrtYd")
		)
		(fp_line
			(start -0.3048 -0.1016)
			(end 0.3048 -0.1016)
			(stroke
				(width 0.1)
				(type default)
			)
			(layer "B.Fab")
		)
		(fp_line
			(start -0.3048 0.9906)
			(end -0.3048 -0.1016)
			(stroke
				(width 0.1)
				(type default)
			)
			(layer "B.Fab")
		)
		(fp_line
			(start 0.3048 -0.1016)
			(end 0.3048 0.9906)
			(stroke
				(width 0.1)
				(type default)
			)
			(layer "B.Fab")
		)
		(fp_line
			(start 0.3048 0.9906)
			(end -0.3048 0.9906)
			(stroke
				(width 0.1)
				(type default)
			)
			(layer "B.Fab")
		)
		(pad "1" smd rect
			(at 0 0 180)
			(size 0.508 0.508)
			(layers "B.Cu" "B.Mask" "B.Paste")
			(net "P3E_CPU0_PE1_PCH_RXP<7>")
		)
		(pad "2" smd rect
			(at 0 0.889 180)
			(size 0.508 0.508)
			(layers "B.Cu" "B.Mask" "B.Paste")
			(net "P3E_CPU0_PE1_SS_RXP<7>")
		)
		(zone
			(layer "B.Cu")
			(hatch none 0.5)
			(connect_pads
				(clearance 0)
			)
			(min_thickness 0.25)
			(keepout
				(tracks allowed)
				(vias not_allowed)
				(pads allowed)
				(copperpour not_allowed)
				(footprints allowed)
			)
			(placement
				(enabled no)
				(sheetname "")
			)
			(fill
				(thermal_gap 0.5)
				(thermal_bridge_width 0.5)
				(island_removal_mode 0)
			)
			(polygon
				(pts
					(xy 353.158806 -61.003434) (xy 352.650806 -61.003434) (xy 352.650806 -60.622434) (xy 353.158806 -60.622434)
				)
			)
		)
		(zone
			(layer "B.Cu")
			(hatch none 0.5)
			(connect_pads
				(clearance 0)
			)
			(min_thickness 0.25)
			(keepout
				(tracks not_allowed)
				(vias allowed)
				(pads allowed)
				(copperpour not_allowed)
				(footprints allowed)
			)
			(placement
				(enabled no)
				(sheetname "")
			)
			(fill
				(thermal_gap 0.5)
				(thermal_bridge_width 0.5)
				(island_removal_mode 0)
			)
			(polygon
				(pts
					(xy 353.158806 -60.622434) (xy 352.650806 -60.622434) (xy 352.650806 -61.003434) (xy 353.158806 -61.003434)
				)
			)
		)
	)
	(footprint ""
		(layer "B.Cu")
		(at 282.259024 -78.801214 -90)
		(property "Reference" "R4P2"
			(at 0 0 90)
			(layer "B.SilkS")
			(hide yes)
			(effects
				(font
					(size 1.27 1.27)
				)
				(justify mirror)
			)
		)
		(property "Value" ""
			(at 0 0 90)
			(layer "B.Fab")
			(effects
				(font
					(size 1.27 1.27)
				)
				(justify mirror)
			)
		)
		(duplicate_pad_numbers_are_jumpers no)
		(fp_rect
			(start 0.2794 0.9906)
			(end -0.2794 -0.1016)
			(stroke
				(width 0)
				(type default)
			)
			(fill no)
			(layer "B.CrtYd")
		)
		(fp_line
			(start -0.2794 0.9906)
			(end -0.2794 -0.1016)
			(stroke
				(width 0.1)
				(type default)
			)
			(layer "B.Fab")
		)
		(fp_line
			(start 0.2794 0.9906)
			(end -0.2794 0.9906)
			(stroke
				(width 0.1)
				(type default)
			)
			(layer "B.Fab")
		)
		(fp_line
			(start -0.2794 -0.1016)
			(end 0.2794 -0.1016)
			(stroke
				(width 0.1)
				(type default)
			)
			(layer "B.Fab")
		)
		(fp_line
			(start 0.2794 -0.1016)
			(end 0.2794 0.9906)
			(stroke
				(width 0.1)
				(type default)
			)
			(layer "B.Fab")
		)
		(pad "1" smd rect
			(at 0 0 90)
			(size 0.508 0.508)
			(layers "B.Cu" "B.Mask" "B.Paste")
			(net "A_CPU0_PE3_RBIAS")
		)
		(pad "2" smd rect
			(at 0 0.889 90)
			(size 0.508 0.508)
			(layers "B.Cu" "B.Mask" "B.Paste")
			(net "GND")
		)
		(zone
			(layer "B.Cu")
			(hatch none 0.5)
			(connect_pads
				(clearance 0)
			)
			(min_thickness 0.25)
			(keepout
				(tracks not_allowed)
				(vias allowed)
				(pads allowed)
				(copperpour not_allowed)
				(footprints allowed)
			)
			(placement
				(enabled no)
				(sheetname "")
			)
			(fill
				(thermal_gap 0.5)
				(thermal_bridge_width 0.5)
				(island_removal_mode 0)
			)
			(polygon
				(pts
					(xy 281.624024 -78.547214) (xy 282.005024 -78.547214) (xy 282.005024 -79.055214) (xy 281.624024 -79.055214)
				)
			)
		)
		(zone
			(layer "B.Cu")
			(hatch none 0.5)
			(connect_pads
				(clearance 0)
			)
			(min_thickness 0.25)
			(keepout
				(tracks allowed)
				(vias not_allowed)
				(pads allowed)
				(copperpour not_allowed)
				(footprints allowed)
			)
			(placement
				(enabled no)
				(sheetname "")
			)
			(fill
				(thermal_gap 0.5)
				(thermal_bridge_width 0.5)
				(island_removal_mode 0)
			)
			(polygon
				(pts
					(xy 281.624024 -78.547214) (xy 282.005024 -78.547214) (xy 282.005024 -79.055214) (xy 281.624024 -79.055214)
				)
			)
		)
	)
	(footprint ""
		(layer "B.Cu")
		(at -1.06426 -115.3668 -90)
		(property "Reference" "C9M10"
			(at 0 0 90)
			(layer "B.SilkS")
			(hide yes)
			(effects
				(font
					(size 1.27 1.27)
				)
				(justify mirror)
			)
		)
		(property "Value" ""
			(at 0 0 90)
			(layer "B.Fab")
			(effects
				(font
					(size 1.27 1.27)
				)
				(justify mirror)
			)
		)
		(duplicate_pad_numbers_are_jumpers no)
		(fp_poly
			(pts
				(xy 0.7239 -0.2159) (xy -0.7239 -0.2159) (xy -0.7239 1.9939) (xy 0.7239 1.9939)
			)
			(stroke
				(width 0)
				(type default)
			)
			(fill no)
			(layer "B.CrtYd")
		)
		(fp_line
			(start -0.7239 1.9939)
			(end -0.7239 -0.2159)
			(stroke
				(width 0.1)
				(type default)
			)
			(layer "B.Fab")
		)
		(fp_line
			(start 0.7239 1.9939)
			(end -0.7239 1.9939)
			(stroke
				(width 0.1)
				(type default)
			)
			(layer "B.Fab")
		)
		(fp_line
			(start -0.7239 -0.2159)
			(end 0.7239 -0.2159)
			(stroke
				(width 0.1)
				(type default)
			)
			(layer "B.Fab")
		)
		(fp_line
			(start 0.7239 -0.2159)
			(end 0.7239 1.9939)
			(stroke
				(width 0.1)
				(type default)
			)
			(layer "B.Fab")
		)
		(pad "1" smd rect
			(at 0 0 90)
			(size 1.27 1.016)
			(layers "B.Cu" "B.Mask" "B.Paste")
			(net "P12V_STBY")
		)
		(pad "2" smd rect
			(at 0 1.778 90)
			(size 1.27 1.016)
			(layers "B.Cu" "B.Mask" "B.Paste")
			(net "GND")
		)
		(zone
			(layer "B.Cu")
			(hatch none 0.5)
			(connect_pads
				(clearance 0)
			)
			(min_thickness 0.25)
			(keepout
				(tracks not_allowed)
				(vias allowed)
				(pads allowed)
				(copperpour not_allowed)
				(footprints allowed)
			)
			(placement
				(enabled no)
				(sheetname "")
			)
			(fill
				(thermal_gap 0.5)
				(thermal_bridge_width 0.5)
				(island_removal_mode 0)
			)
			(polygon
				(pts
					(xy -1.57226 -114.7318) (xy -1.57226 -116.0018) (xy -2.33426 -116.0018) (xy -2.33426 -114.7318)
				)
			)
		)
	)
	(footprint ""
		(layer "B.Cu")
		(at 406.654 -93.280992 90)
		(property "Reference" "C8C4"
			(at 0 0 90)
			(layer "B.SilkS")
			(hide yes)
			(effects
				(font
					(size 1.27 1.27)
				)
				(justify mirror)
			)
		)
		(property "Value" ""
			(at 0 0 90)
			(layer "B.Fab")
			(effects
				(font
					(size 1.27 1.27)
				)
				(justify mirror)
			)
		)
		(duplicate_pad_numbers_are_jumpers no)
		(fp_poly
			(pts
				(xy 0.4953 -0.2032) (xy -0.4953 -0.2032) (xy -0.4953 1.6002) (xy 0.4953 1.6002)
			)
			(stroke
				(width 0)
				(type default)
			)
			(fill no)
			(layer "B.CrtYd")
		)
		(fp_line
			(start 0.4953 -0.2032)
			(end -0.4953 -0.2032)
			(stroke
				(width 0.1)
				(type default)
			)
			(layer "B.Fab")
		)
		(fp_line
			(start -0.4953 -0.2032)
			(end -0.4953 1.6002)
			(stroke
				(width 0.1)
				(type default)
			)
			(layer "B.Fab")
		)
		(fp_line
			(start 0.4953 1.6002)
			(end 0.4953 -0.2032)
			(stroke
				(width 0.1)
				(type default)
			)
			(layer "B.Fab")
		)
		(fp_line
			(start -0.4953 1.6002)
			(end 0.4953 1.6002)
			(stroke
				(width 0.1)
				(type default)
			)
			(layer "B.Fab")
		)
		(pad "1" smd rect
			(at 0 0 270)
			(size 0.762 0.889)
			(layers "B.Cu" "B.Mask" "B.Paste")
			(net "P3V3_STBY")
		)
		(pad "2" smd rect
			(at 0 1.397 270)
			(size 0.762 0.889)
			(layers "B.Cu" "B.Mask" "B.Paste")
			(net "GND")
		)
		(zone
			(layer "B.Cu")
			(hatch none 0.5)
			(connect_pads
				(clearance 0)
			)
			(min_thickness 0.25)
			(keepout
				(tracks not_allowed)
				(vias allowed)
				(pads allowed)
				(copperpour not_allowed)
				(footprints allowed)
			)
			(placement
				(enabled no)
				(sheetname "")
			)
			(fill
				(thermal_gap 0.5)
				(thermal_bridge_width 0.5)
				(island_removal_mode 0)
			)
			(polygon
				(pts
					(xy 407.0985 -93.661992) (xy 407.0985 -92.899992) (xy 407.6065 -92.899992) (xy 407.6065 -93.661992)
				)
			)
		)
	)
	(footprint ""
		(layer "B.Cu")
		(at 495.45748 -130.52552)
		(property "Reference" "C1M32"
			(at 0 0 0)
			(layer "B.SilkS")
			(hide yes)
			(effects
				(font
					(size 1.27 1.27)
				)
				(justify mirror)
			)
		)
		(property "Value" ""
			(at 0 0 0)
			(layer "B.Fab")
			(effects
				(font
					(size 1.27 1.27)
				)
				(justify mirror)
			)
		)
		(duplicate_pad_numbers_are_jumpers no)
		(fp_poly
			(pts
				(xy -0.3048 -0.1016) (xy -0.3048 0.9906) (xy 0.3048 0.9906) (xy 0.3048 -0.1016)
			)
			(stroke
				(width 0)
				(type default)
			)
			(fill no)
			(layer "B.CrtYd")
		)
		(fp_line
			(start -0.3048 -0.1016)
			(end 0.3048 -0.1016)
			(stroke
				(width 0.1)
				(type default)
			)
			(layer "B.Fab")
		)
		(fp_line
			(start -0.3048 0.9906)
			(end -0.3048 -0.1016)
			(stroke
				(width 0.1)
				(type default)
			)
			(layer "B.Fab")
		)
		(fp_line
			(start 0.3048 -0.1016)
			(end 0.3048 0.9906)
			(stroke
				(width 0.1)
				(type default)
			)
			(layer "B.Fab")
		)
		(fp_line
			(start 0.3048 0.9906)
			(end -0.3048 0.9906)
			(stroke
				(width 0.1)
				(type default)
			)
			(layer "B.Fab")
		)
		(pad "1" smd rect
			(at 0 0 180)
			(size 0.508 0.508)
			(layers "B.Cu" "B.Mask" "B.Paste")
			(net "P3V3_STBY")
		)
		(pad "2" smd rect
			(at 0 0.889 180)
			(size 0.508 0.508)
			(layers "B.Cu" "B.Mask" "B.Paste")
			(net "GND")
		)
		(zone
			(layer "B.Cu")
			(hatch none 0.5)
			(connect_pads
				(clearance 0)
			)
			(min_thickness 0.25)
			(keepout
				(tracks allowed)
				(vias not_allowed)
				(pads allowed)
				(copperpour not_allowed)
				(footprints allowed)
			)
			(placement
				(enabled no)
				(sheetname "")
			)
			(fill
				(thermal_gap 0.5)
				(thermal_bridge_width 0.5)
				(island_removal_mode 0)
			)
			(polygon
				(pts
					(xy 495.71148 -130.27152) (xy 495.20348 -130.27152) (xy 495.20348 -129.89052) (xy 495.71148 -129.89052)
				)
			)
		)
		(zone
			(layer "B.Cu")
			(hatch none 0.5)
			(connect_pads
				(clearance 0)
			)
			(min_thickness 0.25)
			(keepout
				(tracks not_allowed)
				(vias allowed)
				(pads allowed)
				(copperpour not_allowed)
				(footprints allowed)
			)
			(placement
				(enabled no)
				(sheetname "")
			)
			(fill
				(thermal_gap 0.5)
				(thermal_bridge_width 0.5)
				(island_removal_mode 0)
			)
			(polygon
				(pts
					(xy 495.71148 -129.89052) (xy 495.20348 -129.89052) (xy 495.20348 -130.27152) (xy 495.71148 -130.27152)
				)
			)
		)
	)
	(footprint ""
		(layer "B.Cu")
		(at 327.914 -61.849 -90)
		(property "Reference" "R4R2"
			(at 0 0 90)
			(layer "B.SilkS")
			(hide yes)
			(effects
				(font
					(size 1.27 1.27)
				)
				(justify mirror)
			)
		)
		(property "Value" ""
			(at 0 0 90)
			(layer "B.Fab")
			(effects
				(font
					(size 1.27 1.27)
				)
				(justify mirror)
			)
		)
		(duplicate_pad_numbers_are_jumpers no)
		(fp_poly
			(pts
				(xy 0.2794 -0.1016) (xy -0.2794 -0.1016) (xy -0.2794 0.9906) (xy 0.2794 0.9906)
			)
			(stroke
				(width 0)
				(type default)
			)
			(fill no)
			(layer "B.CrtYd")
		)
		(fp_line
			(start -0.2794 0.9906)
			(end -0.2794 -0.1016)
			(stroke
				(width 0.1)
				(type default)
			)
			(layer "B.Fab")
		)
		(fp_line
			(start 0.2794 0.9906)
			(end -0.2794 0.9906)
			(stroke
				(width 0.1)
				(type default)
			)
			(layer "B.Fab")
		)
		(fp_line
			(start -0.2794 -0.1016)
			(end 0.2794 -0.1016)
			(stroke
				(width 0.1)
				(type default)
			)
			(layer "B.Fab")
		)
		(fp_line
			(start 0.2794 -0.1016)
			(end 0.2794 0.9906)
			(stroke
				(width 0.1)
				(type default)
			)
			(layer "B.Fab")
		)
		(pad "1" smd rect
			(at 0 0 90)
			(size 0.508 0.508)
			(layers "B.Cu" "B.Mask" "B.Paste")
			(net "PVCCIO_CPU0")
		)
		(pad "2" smd rect
			(at 0 0.889 90)
			(size 0.508 0.508)
			(layers "B.Cu" "B.Mask" "B.Paste")
			(net "H_CPU0_CATERR_G_N")
		)
		(zone
			(layer "B.Cu")
			(hatch none 0.5)
			(connect_pads
				(clearance 0)
			)
			(min_thickness 0.25)
			(keepout
				(tracks not_allowed)
				(vias allowed)
				(pads allowed)
				(copperpour not_allowed)
				(footprints allowed)
			)
			(placement
				(enabled no)
				(sheetname "")
			)
			(fill
				(thermal_gap 0.5)
				(thermal_bridge_width 0.5)
				(island_removal_mode 0)
			)
			(polygon
				(pts
					(xy 327.279 -61.595) (xy 327.279 -62.103) (xy 327.66 -62.103) (xy 327.66 -61.595)
				)
			)
		)
		(zone
			(layer "B.Cu")
			(hatch none 0.5)
			(connect_pads
				(clearance 0)
			)
			(min_thickness 0.25)
			(keepout
				(tracks allowed)
				(vias not_allowed)
				(pads allowed)
				(copperpour not_allowed)
				(footprints allowed)
			)
			(placement
				(enabled no)
				(sheetname "")
			)
			(fill
				(thermal_gap 0.5)
				(thermal_bridge_width 0.5)
				(island_removal_mode 0)
			)
			(polygon
				(pts
					(xy 327.66 -61.595) (xy 327.66 -62.103) (xy 327.279 -62.103) (xy 327.279 -61.595)
				)
			)
		)
	)
	(footprint ""
		(layer "B.Cu")
		(at 259.999734 4.003548 90)
		(property "Reference" "C5U16"
			(at -1.47828 0.78994 180)
			(unlocked yes)
			(layer "B.SilkS")
			(effects
				(font
					(size 0.4064 0.254)
					(thickness 0.1524)
				)
				(justify mirror)
			)
		)
		(property "Value" ""
			(at 0 0 90)
			(layer "B.Fab")
			(effects
				(font
					(size 1.27 1.27)
				)
				(justify mirror)
			)
		)
		(duplicate_pad_numbers_are_jumpers no)
		(fp_poly
			(pts
				(xy 0.7239 -0.2159) (xy -0.7239 -0.2159) (xy -0.7239 1.9939) (xy 0.7239 1.9939)
			)
			(stroke
				(width 0)
				(type default)
			)
			(fill no)
			(layer "B.CrtYd")
		)
		(fp_line
			(start 0.7239 -0.2159)
			(end 0.7239 1.9939)
			(stroke
				(width 0.1)
				(type default)
			)
			(layer "B.Fab")
		)
		(fp_line
			(start -0.7239 -0.2159)
			(end 0.7239 -0.2159)
			(stroke
				(width 0.1)
				(type default)
			)
			(layer "B.Fab")
		)
		(fp_line
			(start 0.7239 1.9939)
			(end -0.7239 1.9939)
			(stroke
				(width 0.1)
				(type default)
			)
			(layer "B.Fab")
		)
		(fp_line
			(start -0.7239 1.9939)
			(end -0.7239 -0.2159)
			(stroke
				(width 0.1)
				(type default)
			)
			(layer "B.Fab")
		)
		(pad "1" smd rect
			(at 0 0 270)
			(size 1.27 1.016)
			(layers "B.Cu" "B.Mask" "B.Paste")
			(net "PVTT_ABC")
		)
		(pad "2" smd rect
			(at 0 1.778 270)
			(size 1.27 1.016)
			(layers "B.Cu" "B.Mask" "B.Paste")
			(net "GND")
		)
		(zone
			(layer "B.Cu")
			(hatch none 0.5)
			(connect_pads
				(clearance 0)
			)
			(min_thickness 0.25)
			(keepout
				(tracks not_allowed)
				(vias allowed)
				(pads allowed)
				(copperpour not_allowed)
				(footprints allowed)
			)
			(placement
				(enabled no)
				(sheetname "")
			)
			(fill
				(thermal_gap 0.5)
				(thermal_bridge_width 0.5)
				(island_removal_mode 0)
			)
			(polygon
				(pts
					(xy 260.507734 3.368548) (xy 260.507734 4.638548) (xy 261.269734 4.638548) (xy 261.269734 3.368548)
				)
			)
		)
	)
	(footprint ""
		(layer "B.Cu")
		(at 482.2825 -47.625 90)
		(property "Reference" "C1R15"
			(at 0 0 90)
			(layer "B.SilkS")
			(hide yes)
			(effects
				(font
					(size 1.27 1.27)
				)
				(justify mirror)
			)
		)
		(property "Value" ""
			(at 0 0 90)
			(layer "B.Fab")
			(effects
				(font
					(size 1.27 1.27)
				)
				(justify mirror)
			)
		)
		(duplicate_pad_numbers_are_jumpers no)
		(fp_poly
			(pts
				(xy -0.3048 -0.1016) (xy -0.3048 0.9906) (xy 0.3048 0.9906) (xy 0.3048 -0.1016)
			)
			(stroke
				(width 0)
				(type default)
			)
			(fill no)
			(layer "B.CrtYd")
		)
		(fp_line
			(start 0.3048 -0.1016)
			(end 0.3048 0.9906)
			(stroke
				(width 0.1)
				(type default)
			)
			(layer "B.Fab")
		)
		(fp_line
			(start -0.3048 -0.1016)
			(end 0.3048 -0.1016)
			(stroke
				(width 0.1)
				(type default)
			)
			(layer "B.Fab")
		)
		(fp_line
			(start 0.3048 0.9906)
			(end -0.3048 0.9906)
			(stroke
				(width 0.1)
				(type default)
			)
			(layer "B.Fab")
		)
		(fp_line
			(start -0.3048 0.9906)
			(end -0.3048 -0.1016)
			(stroke
				(width 0.1)
				(type default)
			)
			(layer "B.Fab")
		)
		(pad "1" smd rect
			(at 0 0 270)
			(size 0.508 0.508)
			(layers "B.Cu" "B.Mask" "B.Paste")
			(net "P0V9_LAN")
		)
		(pad "2" smd rect
			(at 0 0.889 270)
			(size 0.508 0.508)
			(layers "B.Cu" "B.Mask" "B.Paste")
			(net "GND")
		)
		(zone
			(layer "B.Cu")
			(hatch none 0.5)
			(connect_pads
				(clearance 0)
			)
			(min_thickness 0.25)
			(keepout
				(tracks allowed)
				(vias not_allowed)
				(pads allowed)
				(copperpour not_allowed)
				(footprints allowed)
			)
			(placement
				(enabled no)
				(sheetname "")
			)
			(fill
				(thermal_gap 0.5)
				(thermal_bridge_width 0.5)
				(island_removal_mode 0)
			)
			(polygon
				(pts
					(xy 482.5365 -47.879) (xy 482.5365 -47.371) (xy 482.9175 -47.371) (xy 482.9175 -47.879)
				)
			)
		)
		(zone
			(layer "B.Cu")
			(hatch none 0.5)
			(connect_pads
				(clearance 0)
			)
			(min_thickness 0.25)
			(keepout
				(tracks not_allowed)
				(vias allowed)
				(pads allowed)
				(copperpour not_allowed)
				(footprints allowed)
			)
			(placement
				(enabled no)
				(sheetname "")
			)
			(fill
				(thermal_gap 0.5)
				(thermal_bridge_width 0.5)
				(island_removal_mode 0)
			)
			(polygon
				(pts
					(xy 482.9175 -47.879) (xy 482.9175 -47.371) (xy 482.5365 -47.371) (xy 482.5365 -47.879)
				)
			)
		)
	)
	(footprint ""
		(layer "B.Cu")
		(at 464.625944 -7.48792 180)
		(property "Reference" "C2U22"
			(at 0 0 0)
			(layer "B.SilkS")
			(hide yes)
			(effects
				(font
					(size 1.27 1.27)
				)
				(justify mirror)
			)
		)
		(property "Value" ""
			(at 0 0 0)
			(layer "B.Fab")
			(effects
				(font
					(size 1.27 1.27)
				)
				(justify mirror)
			)
		)
		(duplicate_pad_numbers_are_jumpers no)
		(fp_poly
			(pts
				(xy -0.3048 -0.1016) (xy -0.3048 0.9906) (xy 0.3048 0.9906) (xy 0.3048 -0.1016)
			)
			(stroke
				(width 0)
				(type default)
			)
			(fill no)
			(layer "B.CrtYd")
		)
		(fp_line
			(start 0.3048 0.9906)
			(end -0.3048 0.9906)
			(stroke
				(width 0.1)
				(type default)
			)
			(layer "B.Fab")
		)
		(fp_line
			(start 0.3048 -0.1016)
			(end 0.3048 0.9906)
			(stroke
				(width 0.1)
				(type default)
			)
			(layer "B.Fab")
		)
		(fp_line
			(start -0.3048 0.9906)
			(end -0.3048 -0.1016)
			(stroke
				(width 0.1)
				(type default)
			)
			(layer "B.Fab")
		)
		(fp_line
			(start -0.3048 -0.1016)
			(end 0.3048 -0.1016)
			(stroke
				(width 0.1)
				(type default)
			)
			(layer "B.Fab")
		)
		(pad "1" smd rect
			(at 0 0)
			(size 0.508 0.508)
			(layers "B.Cu" "B.Mask" "B.Paste")
			(net "P3V3_STBY")
		)
		(pad "2" smd rect
			(at 0 0.889)
			(size 0.508 0.508)
			(layers "B.Cu" "B.Mask" "B.Paste")
			(net "GND")
		)
		(zone
			(layer "B.Cu")
			(hatch none 0.5)
			(connect_pads
				(clearance 0)
			)
			(min_thickness 0.25)
			(keepout
				(tracks not_allowed)
				(vias allowed)
				(pads allowed)
				(copperpour not_allowed)
				(footprints allowed)
			)
			(placement
				(enabled no)
				(sheetname "")
			)
			(fill
				(thermal_gap 0.5)
				(thermal_bridge_width 0.5)
				(island_removal_mode 0)
			)
			(polygon
				(pts
					(xy 464.371944 -8.12292) (xy 464.879944 -8.12292) (xy 464.879944 -7.74192) (xy 464.371944 -7.74192)
				)
			)
		)
		(zone
			(layer "B.Cu")
			(hatch none 0.5)
			(connect_pads
				(clearance 0)
			)
			(min_thickness 0.25)
			(keepout
				(tracks allowed)
				(vias not_allowed)
				(pads allowed)
				(copperpour not_allowed)
				(footprints allowed)
			)
			(placement
				(enabled no)
				(sheetname "")
			)
			(fill
				(thermal_gap 0.5)
				(thermal_bridge_width 0.5)
				(island_removal_mode 0)
			)
			(polygon
				(pts
					(xy 464.371944 -7.74192) (xy 464.879944 -7.74192) (xy 464.879944 -8.12292) (xy 464.371944 -8.12292)
				)
			)
		)
	)
	(footprint ""
		(layer "B.Cu")
		(at 385.33705 -108.65485 90)
		(property "Reference" "C3N15"
			(at 0 0 90)
			(layer "B.SilkS")
			(hide yes)
			(effects
				(font
					(size 1.27 1.27)
				)
				(justify mirror)
			)
		)
		(property "Value" ""
			(at 0 0 90)
			(layer "B.Fab")
			(effects
				(font
					(size 1.27 1.27)
				)
				(justify mirror)
			)
		)
		(duplicate_pad_numbers_are_jumpers no)
		(fp_rect
			(start 0.2794 0.9144)
			(end -0.2794 -0.1143)
			(stroke
				(width 0)
				(type default)
			)
			(fill no)
			(layer "B.CrtYd")
		)
		(fp_line
			(start 0.2794 -0.1143)
			(end -0.2794 -0.1143)
			(stroke
				(width 0.1)
				(type default)
			)
			(layer "B.Fab")
		)
		(fp_line
			(start -0.2794 -0.1143)
			(end -0.2794 0.9144)
			(stroke
				(width 0.1)
				(type default)
			)
			(layer "B.Fab")
		)
		(fp_line
			(start 0.2794 0.9144)
			(end 0.2794 -0.1143)
			(stroke
				(width 0.1)
				(type default)
			)
			(layer "B.Fab")
		)
		(fp_line
			(start -0.2794 0.9144)
			(end 0.2794 0.9144)
			(stroke
				(width 0.1)
				(type default)
			)
			(layer "B.Fab")
		)
		(pad "1" smd custom
			(at 0 0)
			(size 0.10414 0.10414)
			(layers "B.Cu" "B.Mask" "B.Paste")
			(net "PVNN_PCH_STBY")
			(options
				(clearance outline)
				(anchor circle)
			)
			(primitives
				(gr_poly
					(pts
						(xy -0.20828 -0.08636) (xy -0.20828 0.08636) (xy -0.08636 0.20828) (xy 0.086614 0.20828) (xy 0.20828 0.086614)
						(xy 0.20828 -0.08636) (xy 0.08636 -0.20828) (xy -0.08636 -0.20828)
					)
					(width 0)
					(fill yes)
				)
			)
		)
		(pad "2" smd custom
			(at 0 0.8001)
			(size 0.10414 0.10414)
			(layers "B.Cu" "B.Mask" "B.Paste")
			(net "GND")
			(options
				(clearance outline)
				(anchor circle)
			)
			(primitives
				(gr_poly
					(pts
						(xy -0.20828 -0.08636) (xy -0.20828 0.08636) (xy -0.08636 0.20828) (xy 0.086614 0.20828) (xy 0.20828 0.086614)
						(xy 0.20828 -0.08636) (xy 0.08636 -0.20828) (xy -0.08636 -0.20828)
					)
					(width 0)
					(fill yes)
				)
			)
		)
		(zone
			(layer "B.Cu")
			(hatch none 0.5)
			(connect_pads
				(clearance 0)
			)
			(min_thickness 0.25)
			(keepout
				(tracks allowed)
				(vias not_allowed)
				(pads allowed)
				(copperpour not_allowed)
				(footprints allowed)
			)
			(placement
				(enabled no)
				(sheetname "")
			)
			(fill
				(thermal_gap 0.5)
				(thermal_bridge_width 0.5)
				(island_removal_mode 0)
			)
			(polygon
				(pts
					(xy 385.5466 -108.74248) (xy 385.9276 -108.74248) (xy 385.9276 -108.56722) (xy 385.5466 -108.566966)
				)
			)
		)
		(zone
			(layer "B.Cu")
			(hatch none 0.5)
			(connect_pads
				(clearance 0)
			)
			(min_thickness 0.25)
			(keepout
				(tracks not_allowed)
				(vias allowed)
				(pads allowed)
				(copperpour not_allowed)
				(footprints allowed)
			)
			(placement
				(enabled no)
				(sheetname "")
			)
			(fill
				(thermal_gap 0.5)
				(thermal_bridge_width 0.5)
				(island_removal_mode 0)
			)
			(polygon
				(pts
					(xy 385.5466 -108.74248) (xy 385.9276 -108.74248) (xy 385.9276 -108.56722) (xy 385.5466 -108.566966)
				)
			)
		)
	)
	(footprint ""
		(layer "B.Cu")
		(at 370.9924 -131.4704 180)
		(property "Reference" "C3M31"
			(at 0 0 0)
			(layer "B.SilkS")
			(hide yes)
			(effects
				(font
					(size 1.27 1.27)
				)
				(justify mirror)
			)
		)
		(property "Value" ""
			(at 0 0 0)
			(layer "B.Fab")
			(effects
				(font
					(size 1.27 1.27)
				)
				(justify mirror)
			)
		)
		(duplicate_pad_numbers_are_jumpers no)
		(fp_rect
			(start 0.3048 -0.1016)
			(end -0.3048 0.9906)
			(stroke
				(width 0)
				(type default)
			)
			(fill no)
			(layer "B.CrtYd")
		)
		(fp_line
			(start 0.3048 0.9906)
			(end -0.3048 0.9906)
			(stroke
				(width 0.1)
				(type default)
			)
			(layer "B.Fab")
		)
		(fp_line
			(start 0.3048 -0.1016)
			(end 0.3048 0.9906)
			(stroke
				(width 0.1)
				(type default)
			)
			(layer "B.Fab")
		)
		(fp_line
			(start -0.3048 0.9906)
			(end -0.3048 -0.1016)
			(stroke
				(width 0.1)
				(type default)
			)
			(layer "B.Fab")
		)
		(fp_line
			(start -0.3048 -0.1016)
			(end 0.3048 -0.1016)
			(stroke
				(width 0.1)
				(type default)
			)
			(layer "B.Fab")
		)
		(pad "1" smd rect
			(at 0 0)
			(size 0.508 0.508)
			(layers "B.Cu" "B.Mask" "B.Paste")
			(net "P1V05_PCH_STBY")
		)
		(pad "2" smd rect
			(at 0 0.889)
			(size 0.508 0.508)
			(layers "B.Cu" "B.Mask" "B.Paste")
			(net "GND")
		)
		(zone
			(layer "B.Cu")
			(hatch none 0.5)
			(connect_pads
				(clearance 0)
			)
			(min_thickness 0.25)
			(keepout
				(tracks not_allowed)
				(vias allowed)
				(pads allowed)
				(copperpour not_allowed)
				(footprints allowed)
			)
			(placement
				(enabled no)
				(sheetname "")
			)
			(fill
				(thermal_gap 0.5)
				(thermal_bridge_width 0.5)
				(island_removal_mode 0)
			)
			(polygon
				(pts
					(xy 370.7384 -131.7244) (xy 371.2464 -131.7244) (xy 371.2464 -132.1054) (xy 370.7384 -132.1054)
				)
			)
		)
		(zone
			(layer "B.Cu")
			(hatch none 0.5)
			(connect_pads
				(clearance 0)
			)
			(min_thickness 0.25)
			(keepout
				(tracks allowed)
				(vias not_allowed)
				(pads allowed)
				(copperpour not_allowed)
				(footprints allowed)
			)
			(placement
				(enabled no)
				(sheetname "")
			)
			(fill
				(thermal_gap 0.5)
				(thermal_bridge_width 0.5)
				(island_removal_mode 0)
			)
			(polygon
				(pts
					(xy 370.7384 -131.7244) (xy 371.2464 -131.7244) (xy 371.2464 -132.1054) (xy 370.7384 -132.1054)
				)
			)
		)
	)
	(footprint ""
		(layer "B.Cu")
		(at 439.478928 -157.152848 -90)
		(property "Reference" "C25W99"
			(at 0.8382 -0.67818 270)
			(unlocked yes)
			(layer "B.SilkS")
			(effects
				(font
					(size 0.4064 0.254)
					(thickness 0.1524)
				)
				(justify left mirror)
			)
		)
		(property "Value" ""
			(at 0 0 90)
			(layer "B.Fab")
			(effects
				(font
					(size 1.27 1.27)
				)
				(justify mirror)
			)
		)
		(duplicate_pad_numbers_are_jumpers no)
		(fp_poly
			(pts
				(xy -0.3048 -0.1016) (xy -0.3048 0.9906) (xy 0.3048 0.9906) (xy 0.3048 -0.1016)
			)
			(stroke
				(width 0)
				(type default)
			)
			(fill no)
			(layer "B.CrtYd")
		)
		(fp_line
			(start -0.3048 0.9906)
			(end -0.3048 -0.1016)
			(stroke
				(width 0.1)
				(type default)
			)
			(layer "B.Fab")
		)
		(fp_line
			(start 0.3048 0.9906)
			(end -0.3048 0.9906)
			(stroke
				(width 0.1)
				(type default)
			)
			(layer "B.Fab")
		)
		(fp_line
			(start -0.3048 -0.1016)
			(end 0.3048 -0.1016)
			(stroke
				(width 0.1)
				(type default)
			)
			(layer "B.Fab")
		)
		(fp_line
			(start 0.3048 -0.1016)
			(end 0.3048 0.9906)
			(stroke
				(width 0.1)
				(type default)
			)
			(layer "B.Fab")
		)
		(pad "1" smd rect
			(at 0 0 90)
			(size 0.508 0.508)
			(layers "B.Cu" "B.Mask" "B.Paste")
			(net "P3V3_STBY")
		)
		(pad "2" smd rect
			(at 0 0.889 90)
			(size 0.508 0.508)
			(layers "B.Cu" "B.Mask" "B.Paste")
			(net "GND")
		)
		(zone
			(layer "B.Cu")
			(hatch none 0.5)
			(connect_pads
				(clearance 0)
			)
			(min_thickness 0.25)
			(keepout
				(tracks not_allowed)
				(vias allowed)
				(pads allowed)
				(copperpour not_allowed)
				(footprints allowed)
			)
			(placement
				(enabled no)
				(sheetname "")
			)
			(fill
				(thermal_gap 0.5)
				(thermal_bridge_width 0.5)
				(island_removal_mode 0)
			)
			(polygon
				(pts
					(xy 438.843928 -156.898848) (xy 438.843928 -157.406848) (xy 439.224928 -157.406848) (xy 439.224928 -156.898848)
				)
			)
		)
		(zone
			(layer "B.Cu")
			(hatch none 0.5)
			(connect_pads
				(clearance 0)
			)
			(min_thickness 0.25)
			(keepout
				(tracks allowed)
				(vias not_allowed)
				(pads allowed)
				(copperpour not_allowed)
				(footprints allowed)
			)
			(placement
				(enabled no)
				(sheetname "")
			)
			(fill
				(thermal_gap 0.5)
				(thermal_bridge_width 0.5)
				(island_removal_mode 0)
			)
			(polygon
				(pts
					(xy 439.224928 -156.898848) (xy 439.224928 -157.406848) (xy 438.843928 -157.406848) (xy 438.843928 -156.898848)
				)
			)
		)
	)
	(footprint ""
		(layer "B.Cu")
		(at 451.9422 -130.9624 180)
		(property "Reference" "R1M22"
			(at 0 0 0)
			(layer "B.SilkS")
			(hide yes)
			(effects
				(font
					(size 1.27 1.27)
				)
				(justify mirror)
			)
		)
		(property "Value" ""
			(at 0 0 0)
			(layer "B.Fab")
			(effects
				(font
					(size 1.27 1.27)
				)
				(justify mirror)
			)
		)
		(duplicate_pad_numbers_are_jumpers no)
		(fp_poly
			(pts
				(xy 0.2794 -0.1016) (xy -0.2794 -0.1016) (xy -0.2794 0.9906) (xy 0.2794 0.9906)
			)
			(stroke
				(width 0)
				(type default)
			)
			(fill no)
			(layer "B.CrtYd")
		)
		(fp_line
			(start 0.2794 0.9906)
			(end -0.2794 0.9906)
			(stroke
				(width 0.1)
				(type default)
			)
			(layer "B.Fab")
		)
		(fp_line
			(start 0.2794 -0.1016)
			(end 0.2794 0.9906)
			(stroke
				(width 0.1)
				(type default)
			)
			(layer "B.Fab")
		)
		(fp_line
			(start -0.2794 0.9906)
			(end -0.2794 -0.1016)
			(stroke
				(width 0.1)
				(type default)
			)
			(layer "B.Fab")
		)
		(fp_line
			(start -0.2794 -0.1016)
			(end 0.2794 -0.1016)
			(stroke
				(width 0.1)
				(type default)
			)
			(layer "B.Fab")
		)
		(pad "1" smd rect
			(at 0 0)
			(size 0.508 0.508)
			(layers "B.Cu" "B.Mask" "B.Paste")
			(net "JTAG_MCP_TMS_R1")
		)
		(pad "2" smd rect
			(at 0 0.889)
			(size 0.508 0.508)
			(layers "B.Cu" "B.Mask" "B.Paste")
			(net "JTAG_MCP_TMS")
		)
		(zone
			(layer "B.Cu")
			(hatch none 0.5)
			(connect_pads
				(clearance 0)
			)
			(min_thickness 0.25)
			(keepout
				(tracks not_allowed)
				(vias allowed)
				(pads allowed)
				(copperpour not_allowed)
				(footprints allowed)
			)
			(placement
				(enabled no)
				(sheetname "")
			)
			(fill
				(thermal_gap 0.5)
				(thermal_bridge_width 0.5)
				(island_removal_mode 0)
			)
			(polygon
				(pts
					(xy 451.6882 -131.5974) (xy 452.1962 -131.5974) (xy 452.1962 -131.2164) (xy 451.6882 -131.2164)
				)
			)
		)
		(zone
			(layer "B.Cu")
			(hatch none 0.5)
			(connect_pads
				(clearance 0)
			)
			(min_thickness 0.25)
			(keepout
				(tracks allowed)
				(vias not_allowed)
				(pads allowed)
				(copperpour not_allowed)
				(footprints allowed)
			)
			(placement
				(enabled no)
				(sheetname "")
			)
			(fill
				(thermal_gap 0.5)
				(thermal_bridge_width 0.5)
				(island_removal_mode 0)
			)
			(polygon
				(pts
					(xy 451.6882 -131.2164) (xy 452.1962 -131.2164) (xy 452.1962 -131.5974) (xy 451.6882 -131.5974)
				)
			)
		)
	)
	(footprint ""
		(layer "B.Cu")
		(at 401.55114 -76.66736 -90)
		(property "Reference" "U6W2"
			(at 0 0 90)
			(layer "B.SilkS")
			(hide yes)
			(effects
				(font
					(size 1.27 1.27)
				)
				(justify mirror)
			)
		)
		(property "Value" "*"
			(at 0.1143 -9.3091 270)
			(unlocked yes)
			(layer "B.Fab")
			(hide yes)
			(effects
				(font
					(size 1.27 1.016)
					(thickness 0.1524)
				)
				(justify mirror)
			)
		)
		(property "Device Type" "TCA9517DGKR-GP_DISCRET-G8-TCA9A"
			(at 0.1143 -10.9093 270)
			(unlocked yes)
			(layer "B.Fab")
			(hide yes)
			(effects
				(font
					(size 1.27 1.016)
					(thickness 0.1524)
				)
				(justify mirror)
			)
		)
		(duplicate_pad_numbers_are_jumpers no)
		(fp_line
			(start 1.778 1.0922)
			(end 1.778 3.048)
			(stroke
				(width 0.508)
				(type default)
			)
			(layer "B.SilkS")
		)
		(fp_line
			(start -1.0795 1.016)
			(end -1.0795 -1.016)
			(stroke
				(width 0.1524)
				(type default)
			)
			(layer "B.SilkS")
		)
		(fp_line
			(start 1.9558 1.016)
			(end -1.0795 1.016)
			(stroke
				(width 0.1524)
				(type default)
			)
			(layer "B.SilkS")
		)
		(fp_line
			(start 1.4478 -0.0381)
			(end 1.9558 0.4699)
			(stroke
				(width 0.1524)
				(type default)
			)
			(layer "B.SilkS")
		)
		(fp_line
			(start 1.9558 -0.5461)
			(end 1.4478 -0.0381)
			(stroke
				(width 0.1524)
				(type default)
			)
			(layer "B.SilkS")
		)
		(fp_line
			(start -1.0795 -1.016)
			(end 1.9558 -1.016)
			(stroke
				(width 0.1524)
				(type default)
			)
			(layer "B.SilkS")
		)
		(fp_line
			(start 1.9558 -1.016)
			(end 1.9558 1.016)
			(stroke
				(width 0.1524)
				(type default)
			)
			(layer "B.SilkS")
		)
		(fp_poly
			(pts
				(xy 1.1557 -1.016) (xy 1.1557 1.016) (xy -1.1557 1.016) (xy -1.1557 -1.016)
			)
			(stroke
				(width 0)
				(type default)
			)
			(fill yes)
			(layer "B.SilkS")
		)
		(fp_rect
			(start 1.4986 2.4511)
			(end -1.4986 -2.4511)
			(stroke
				(width 0)
				(type default)
			)
			(fill no)
			(layer "B.CrtYd")
		)
		(fp_poly
			(pts
				(xy 2.032 3.302) (xy 2.032 -3.302) (xy -2.032 -3.302) (xy -2.032 -2.1209) (xy -1.4986 -2.1209) (xy -1.4986 -2.4511)
				(xy 1.4986 -2.4511) (xy 1.4986 2.4511) (xy -1.4986 2.4511) (xy -1.4986 -2.1082) (xy -2.032 -2.1082)
				(xy -2.032 3.302)
			)
			(stroke
				(width 0)
				(type default)
			)
			(fill no)
			(layer "B.CrtYd")
		)
		(fp_rect
			(start 2.032 3.302)
			(end -2.032 -3.302)
			(stroke
				(width 0)
				(type default)
			)
			(fill no)
			(layer "B.Fab")
		)
		(pad "1" smd rect
			(at 0.97536 2.05486 90)
			(size 0.3556 1.524)
			(layers "B.Cu" "B.Mask" "B.Paste")
			(net "P3V3_STBY")
		)
		(pad "2" smd rect
			(at 0.32512 2.05486 90)
			(size 0.3556 1.524)
			(layers "B.Cu" "B.Mask" "B.Paste")
			(net "SMB_PMBUS_BMC_STBY_LVC3_SCL_R1")
		)
		(pad "3" smd rect
			(at -0.32512 2.05486 90)
			(size 0.3556 1.524)
			(layers "B.Cu" "B.Mask" "B.Paste")
			(net "SMB_PMBUS_BMC_STBY_LVC3_SDA_R1")
		)
		(pad "4" smd rect
			(at -0.97536 2.05486 90)
			(size 0.3556 1.524)
			(layers "B.Cu" "B.Mask" "B.Paste")
			(net "GND")
		)
		(pad "5" smd rect
			(at -0.97536 -2.05486 90)
			(size 0.3556 1.524)
			(layers "B.Cu" "B.Mask" "B.Paste")
			(net "HSC_SMBUS_SWITCH_EN")
		)
		(pad "6" smd rect
			(at -0.32512 -2.05486 90)
			(size 0.3556 1.524)
			(layers "B.Cu" "B.Mask" "B.Paste")
			(net "SMB_BMC_PMBUS_STBY_LVC3_SDA")
		)
		(pad "7" smd rect
			(at 0.32512 -2.05486 90)
			(size 0.3556 1.524)
			(layers "B.Cu" "B.Mask" "B.Paste")
			(net "SMB_BMC_PMBUS_STBY_LVC3_SCL")
		)
		(pad "8" smd rect
			(at 0.97536 -2.05486 90)
			(size 0.3556 1.524)
			(layers "B.Cu" "B.Mask" "B.Paste")
			(net "P3V3_STBY")
		)
	)
	(footprint ""
		(layer "B.Cu")
		(at 367.637314 -35.364166 180)
		(property "Reference" "R8F12"
			(at 0 0 0)
			(layer "B.SilkS")
			(hide yes)
			(effects
				(font
					(size 1.27 1.27)
				)
				(justify mirror)
			)
		)
		(property "Value" ""
			(at 0 0 0)
			(layer "B.Fab")
			(effects
				(font
					(size 1.27 1.27)
				)
				(justify mirror)
			)
		)
		(duplicate_pad_numbers_are_jumpers no)
		(fp_poly
			(pts
				(xy 0.2794 -0.1016) (xy -0.2794 -0.1016) (xy -0.2794 0.9906) (xy 0.2794 0.9906)
			)
			(stroke
				(width 0)
				(type default)
			)
			(fill no)
			(layer "B.CrtYd")
		)
		(fp_line
			(start 0.2794 0.9906)
			(end -0.2794 0.9906)
			(stroke
				(width 0.1)
				(type default)
			)
			(layer "B.Fab")
		)
		(fp_line
			(start 0.2794 -0.1016)
			(end 0.2794 0.9906)
			(stroke
				(width 0.1)
				(type default)
			)
			(layer "B.Fab")
		)
		(fp_line
			(start -0.2794 0.9906)
			(end -0.2794 -0.1016)
			(stroke
				(width 0.1)
				(type default)
			)
			(layer "B.Fab")
		)
		(fp_line
			(start -0.2794 -0.1016)
			(end 0.2794 -0.1016)
			(stroke
				(width 0.1)
				(type default)
			)
			(layer "B.Fab")
		)
		(pad "1" smd rect
			(at 0 0)
			(size 0.508 0.508)
			(layers "B.Cu" "B.Mask" "B.Paste")
			(net "SPI_BMC_BT_DI")
		)
		(pad "2" smd rect
			(at 0 0.889)
			(size 0.508 0.508)
			(layers "B.Cu" "B.Mask" "B.Paste")
			(net "SPI_BMC_BT_DI_R")
		)
		(zone
			(layer "B.Cu")
			(hatch none 0.5)
			(connect_pads
				(clearance 0)
			)
			(min_thickness 0.25)
			(keepout
				(tracks not_allowed)
				(vias allowed)
				(pads allowed)
				(copperpour not_allowed)
				(footprints allowed)
			)
			(placement
				(enabled no)
				(sheetname "")
			)
			(fill
				(thermal_gap 0.5)
				(thermal_bridge_width 0.5)
				(island_removal_mode 0)
			)
			(polygon
				(pts
					(xy 367.383314 -35.999166) (xy 367.891314 -35.999166) (xy 367.891314 -35.618166) (xy 367.383314 -35.618166)
				)
			)
		)
		(zone
			(layer "B.Cu")
			(hatch none 0.5)
			(connect_pads
				(clearance 0)
			)
			(min_thickness 0.25)
			(keepout
				(tracks allowed)
				(vias not_allowed)
				(pads allowed)
				(copperpour not_allowed)
				(footprints allowed)
			)
			(placement
				(enabled no)
				(sheetname "")
			)
			(fill
				(thermal_gap 0.5)
				(thermal_bridge_width 0.5)
				(island_removal_mode 0)
			)
			(polygon
				(pts
					(xy 367.383314 -35.618166) (xy 367.891314 -35.618166) (xy 367.891314 -35.999166) (xy 367.383314 -35.999166)
				)
			)
		)
	)
	(footprint ""
		(layer "B.Cu")
		(at 390.635744 -25.794716 -90)
		(property "Reference" "C2T15"
			(at 0 0 90)
			(layer "B.SilkS")
			(hide yes)
			(effects
				(font
					(size 1.27 1.27)
				)
				(justify mirror)
			)
		)
		(property "Value" ""
			(at 0 0 90)
			(layer "B.Fab")
			(effects
				(font
					(size 1.27 1.27)
				)
				(justify mirror)
			)
		)
		(duplicate_pad_numbers_are_jumpers no)
		(fp_poly
			(pts
				(xy -0.3048 -0.1016) (xy -0.3048 0.9906) (xy 0.3048 0.9906) (xy 0.3048 -0.1016)
			)
			(stroke
				(width 0)
				(type default)
			)
			(fill no)
			(layer "B.CrtYd")
		)
		(fp_line
			(start -0.3048 0.9906)
			(end -0.3048 -0.1016)
			(stroke
				(width 0.1)
				(type default)
			)
			(layer "B.Fab")
		)
		(fp_line
			(start 0.3048 0.9906)
			(end -0.3048 0.9906)
			(stroke
				(width 0.1)
				(type default)
			)
			(layer "B.Fab")
		)
		(fp_line
			(start -0.3048 -0.1016)
			(end 0.3048 -0.1016)
			(stroke
				(width 0.1)
				(type default)
			)
			(layer "B.Fab")
		)
		(fp_line
			(start 0.3048 -0.1016)
			(end 0.3048 0.9906)
			(stroke
				(width 0.1)
				(type default)
			)
			(layer "B.Fab")
		)
		(pad "1" smd rect
			(at 0 0 90)
			(size 0.508 0.508)
			(layers "B.Cu" "B.Mask" "B.Paste")
			(net "P3V3")
		)
		(pad "2" smd rect
			(at 0 0.889 90)
			(size 0.508 0.508)
			(layers "B.Cu" "B.Mask" "B.Paste")
			(net "GND")
		)
		(zone
			(layer "B.Cu")
			(hatch none 0.5)
			(connect_pads
				(clearance 0)
			)
			(min_thickness 0.25)
			(keepout
				(tracks not_allowed)
				(vias allowed)
				(pads allowed)
				(copperpour not_allowed)
				(footprints allowed)
			)
			(placement
				(enabled no)
				(sheetname "")
			)
			(fill
				(thermal_gap 0.5)
				(thermal_bridge_width 0.5)
				(island_removal_mode 0)
			)
			(polygon
				(pts
					(xy 390.000744 -25.540716) (xy 390.000744 -26.048716) (xy 390.381744 -26.048716) (xy 390.381744 -25.540716)
				)
			)
		)
		(zone
			(layer "B.Cu")
			(hatch none 0.5)
			(connect_pads
				(clearance 0)
			)
			(min_thickness 0.25)
			(keepout
				(tracks allowed)
				(vias not_allowed)
				(pads allowed)
				(copperpour not_allowed)
				(footprints allowed)
			)
			(placement
				(enabled no)
				(sheetname "")
			)
			(fill
				(thermal_gap 0.5)
				(thermal_bridge_width 0.5)
				(island_removal_mode 0)
			)
			(polygon
				(pts
					(xy 390.381744 -25.540716) (xy 390.381744 -26.048716) (xy 390.000744 -26.048716) (xy 390.000744 -25.540716)
				)
			)
		)
	)
	(footprint ""
		(layer "B.Cu")
		(at 156.06522 -124.0917)
		(property "Reference" "R7M3"
			(at 0 0 0)
			(layer "B.SilkS")
			(hide yes)
			(effects
				(font
					(size 1.27 1.27)
				)
				(justify mirror)
			)
		)
		(property "Value" ""
			(at 0 0 0)
			(layer "B.Fab")
			(effects
				(font
					(size 1.27 1.27)
				)
				(justify mirror)
			)
		)
		(duplicate_pad_numbers_are_jumpers no)
		(fp_poly
			(pts
				(xy 0.2794 -0.1016) (xy -0.2794 -0.1016) (xy -0.2794 0.9906) (xy 0.2794 0.9906)
			)
			(stroke
				(width 0)
				(type default)
			)
			(fill no)
			(layer "B.CrtYd")
		)
		(fp_line
			(start -0.2794 -0.1016)
			(end 0.2794 -0.1016)
			(stroke
				(width 0.1)
				(type default)
			)
			(layer "B.Fab")
		)
		(fp_line
			(start -0.2794 0.9906)
			(end -0.2794 -0.1016)
			(stroke
				(width 0.1)
				(type default)
			)
			(layer "B.Fab")
		)
		(fp_line
			(start 0.2794 -0.1016)
			(end 0.2794 0.9906)
			(stroke
				(width 0.1)
				(type default)
			)
			(layer "B.Fab")
		)
		(fp_line
			(start 0.2794 0.9906)
			(end -0.2794 0.9906)
			(stroke
				(width 0.1)
				(type default)
			)
			(layer "B.Fab")
		)
		(pad "1" smd rect
			(at 0 0 180)
			(size 0.508 0.508)
			(layers "B.Cu" "B.Mask" "B.Paste")
			(net "SMB_DDR_KLM_SCL_G_R")
		)
		(pad "2" smd rect
			(at 0 0.889 180)
			(size 0.508 0.508)
			(layers "B.Cu" "B.Mask" "B.Paste")
			(net "SMB_DDR_KLM_SCL_G")
		)
		(zone
			(layer "B.Cu")
			(hatch none 0.5)
			(connect_pads
				(clearance 0)
			)
			(min_thickness 0.25)
			(keepout
				(tracks allowed)
				(vias not_allowed)
				(pads allowed)
				(copperpour not_allowed)
				(footprints allowed)
			)
			(placement
				(enabled no)
				(sheetname "")
			)
			(fill
				(thermal_gap 0.5)
				(thermal_bridge_width 0.5)
				(island_removal_mode 0)
			)
			(polygon
				(pts
					(xy 156.31922 -123.8377) (xy 155.81122 -123.8377) (xy 155.81122 -123.4567) (xy 156.31922 -123.4567)
				)
			)
		)
		(zone
			(layer "B.Cu")
			(hatch none 0.5)
			(connect_pads
				(clearance 0)
			)
			(min_thickness 0.25)
			(keepout
				(tracks not_allowed)
				(vias allowed)
				(pads allowed)
				(copperpour not_allowed)
				(footprints allowed)
			)
			(placement
				(enabled no)
				(sheetname "")
			)
			(fill
				(thermal_gap 0.5)
				(thermal_bridge_width 0.5)
				(island_removal_mode 0)
			)
			(polygon
				(pts
					(xy 156.31922 -123.4567) (xy 155.81122 -123.4567) (xy 155.81122 -123.8377) (xy 156.31922 -123.8377)
				)
			)
		)
	)
	(footprint ""
		(layer "B.Cu")
		(at 252.1585 -3.3528 -90)
		(property "Reference" "C5G52"
			(at -1.14681 0.76708 0)
			(unlocked yes)
			(layer "B.SilkS")
			(effects
				(font
					(size 0.7874 0.5842)
					(thickness 0.1524)
				)
				(justify mirror)
			)
		)
		(property "Value" ""
			(at 0 0 90)
			(layer "B.Fab")
			(effects
				(font
					(size 1.27 1.27)
				)
				(justify mirror)
			)
		)
		(duplicate_pad_numbers_are_jumpers no)
		(fp_rect
			(start 0.4953 1.6002)
			(end -0.4953 -0.2032)
			(stroke
				(width 0)
				(type default)
			)
			(fill no)
			(layer "B.CrtYd")
		)
		(fp_line
			(start -0.4953 1.6002)
			(end 0.4953 1.6002)
			(stroke
				(width 0.1)
				(type default)
			)
			(layer "B.Fab")
		)
		(fp_line
			(start 0.4953 1.6002)
			(end 0.4953 -0.2032)
			(stroke
				(width 0.1)
				(type default)
			)
			(layer "B.Fab")
		)
		(fp_line
			(start -0.4953 -0.2032)
			(end -0.4953 1.6002)
			(stroke
				(width 0.1)
				(type default)
			)
			(layer "B.Fab")
		)
		(fp_line
			(start 0.4953 -0.2032)
			(end -0.4953 -0.2032)
			(stroke
				(width 0.1)
				(type default)
			)
			(layer "B.Fab")
		)
		(pad "1" smd rect
			(at 0 0 90)
			(size 0.762 0.889)
			(layers "B.Cu" "B.Mask" "B.Paste")
			(net "PVDDQ_ABC")
		)
		(pad "2" smd rect
			(at 0 1.397 90)
			(size 0.762 0.889)
			(layers "B.Cu" "B.Mask" "B.Paste")
			(net "GND")
		)
		(zone
			(layer "B.Cu")
			(hatch none 0.5)
			(connect_pads
				(clearance 0)
			)
			(min_thickness 0.25)
			(keepout
				(tracks not_allowed)
				(vias allowed)
				(pads allowed)
				(copperpour not_allowed)
				(footprints allowed)
			)
			(placement
				(enabled no)
				(sheetname "")
			)
			(fill
				(thermal_gap 0.5)
				(thermal_bridge_width 0.5)
				(island_removal_mode 0)
			)
			(polygon
				(pts
					(xy 251.206 -2.9718) (xy 251.714 -2.9718) (xy 251.714 -3.7338) (xy 251.206 -3.7338)
				)
			)
		)
	)
	(footprint ""
		(layer "B.Cu")
		(at 401.992846 -27.124152)
		(property "Reference" "C9G17"
			(at 0 0 0)
			(layer "B.SilkS")
			(hide yes)
			(effects
				(font
					(size 1.27 1.27)
				)
				(justify mirror)
			)
		)
		(property "Value" ""
			(at 0 0 0)
			(layer "B.Fab")
			(effects
				(font
					(size 1.27 1.27)
				)
				(justify mirror)
			)
		)
		(duplicate_pad_numbers_are_jumpers no)
		(fp_poly
			(pts
				(xy -0.3048 -0.1016) (xy -0.3048 0.9906) (xy 0.3048 0.9906) (xy 0.3048 -0.1016)
			)
			(stroke
				(width 0)
				(type default)
			)
			(fill no)
			(layer "B.CrtYd")
		)
		(fp_line
			(start -0.3048 -0.1016)
			(end 0.3048 -0.1016)
			(stroke
				(width 0.1)
				(type default)
			)
			(layer "B.Fab")
		)
		(fp_line
			(start -0.3048 0.9906)
			(end -0.3048 -0.1016)
			(stroke
				(width 0.1)
				(type default)
			)
			(layer "B.Fab")
		)
		(fp_line
			(start 0.3048 -0.1016)
			(end 0.3048 0.9906)
			(stroke
				(width 0.1)
				(type default)
			)
			(layer "B.Fab")
		)
		(fp_line
			(start 0.3048 0.9906)
			(end -0.3048 0.9906)
			(stroke
				(width 0.1)
				(type default)
			)
			(layer "B.Fab")
		)
		(pad "1" smd rect
			(at 0 0 180)
			(size 0.508 0.508)
			(layers "B.Cu" "B.Mask" "B.Paste")
			(net "A_P12V_STBY_SCALED")
		)
		(pad "2" smd rect
			(at 0 0.889 180)
			(size 0.508 0.508)
			(layers "B.Cu" "B.Mask" "B.Paste")
			(net "GND")
		)
		(zone
			(layer "B.Cu")
			(hatch none 0.5)
			(connect_pads
				(clearance 0)
			)
			(min_thickness 0.25)
			(keepout
				(tracks allowed)
				(vias not_allowed)
				(pads allowed)
				(copperpour not_allowed)
				(footprints allowed)
			)
			(placement
				(enabled no)
				(sheetname "")
			)
			(fill
				(thermal_gap 0.5)
				(thermal_bridge_width 0.5)
				(island_removal_mode 0)
			)
			(polygon
				(pts
					(xy 402.246846 -26.870152) (xy 401.738846 -26.870152) (xy 401.738846 -26.489152) (xy 402.246846 -26.489152)
				)
			)
		)
		(zone
			(layer "B.Cu")
			(hatch none 0.5)
			(connect_pads
				(clearance 0)
			)
			(min_thickness 0.25)
			(keepout
				(tracks not_allowed)
				(vias allowed)
				(pads allowed)
				(copperpour not_allowed)
				(footprints allowed)
			)
			(placement
				(enabled no)
				(sheetname "")
			)
			(fill
				(thermal_gap 0.5)
				(thermal_bridge_width 0.5)
				(island_removal_mode 0)
			)
			(polygon
				(pts
					(xy 402.246846 -26.489152) (xy 401.738846 -26.489152) (xy 401.738846 -26.870152) (xy 402.246846 -26.870152)
				)
			)
		)
	)
	(footprint ""
		(layer "B.Cu")
		(at 401.25777 -127.659384 90)
		(property "Reference" "C2M23"
			(at 0 0 90)
			(layer "B.SilkS")
			(hide yes)
			(effects
				(font
					(size 1.27 1.27)
				)
				(justify mirror)
			)
		)
		(property "Value" ""
			(at 0 0 90)
			(layer "B.Fab")
			(effects
				(font
					(size 1.27 1.27)
				)
				(justify mirror)
			)
		)
		(duplicate_pad_numbers_are_jumpers no)
		(fp_poly
			(pts
				(xy -0.3048 -0.1016) (xy -0.3048 0.9906) (xy 0.3048 0.9906) (xy 0.3048 -0.1016)
			)
			(stroke
				(width 0)
				(type default)
			)
			(fill no)
			(layer "B.CrtYd")
		)
		(fp_line
			(start 0.3048 -0.1016)
			(end 0.3048 0.9906)
			(stroke
				(width 0.1)
				(type default)
			)
			(layer "B.Fab")
		)
		(fp_line
			(start -0.3048 -0.1016)
			(end 0.3048 -0.1016)
			(stroke
				(width 0.1)
				(type default)
			)
			(layer "B.Fab")
		)
		(fp_line
			(start 0.3048 0.9906)
			(end -0.3048 0.9906)
			(stroke
				(width 0.1)
				(type default)
			)
			(layer "B.Fab")
		)
		(fp_line
			(start -0.3048 0.9906)
			(end -0.3048 -0.1016)
			(stroke
				(width 0.1)
				(type default)
			)
			(layer "B.Fab")
		)
		(pad "1" smd rect
			(at 0 0 270)
			(size 0.508 0.508)
			(layers "B.Cu" "B.Mask" "B.Paste")
			(net "PE_PCH_SPRV_TX_DP")
		)
		(pad "2" smd rect
			(at 0 0.889 270)
			(size 0.508 0.508)
			(layers "B.Cu" "B.Mask" "B.Paste")
			(net "PE_PCH_SPRV_TX_C_DP")
		)
		(zone
			(layer "B.Cu")
			(hatch none 0.5)
			(connect_pads
				(clearance 0)
			)
			(min_thickness 0.25)
			(keepout
				(tracks allowed)
				(vias not_allowed)
				(pads allowed)
				(copperpour not_allowed)
				(footprints allowed)
			)
			(placement
				(enabled no)
				(sheetname "")
			)
			(fill
				(thermal_gap 0.5)
				(thermal_bridge_width 0.5)
				(island_removal_mode 0)
			)
			(polygon
				(pts
					(xy 401.51177 -127.913384) (xy 401.51177 -127.405384) (xy 401.89277 -127.405384) (xy 401.89277 -127.913384)
				)
			)
		)
		(zone
			(layer "B.Cu")
			(hatch none 0.5)
			(connect_pads
				(clearance 0)
			)
			(min_thickness 0.25)
			(keepout
				(tracks not_allowed)
				(vias allowed)
				(pads allowed)
				(copperpour not_allowed)
				(footprints allowed)
			)
			(placement
				(enabled no)
				(sheetname "")
			)
			(fill
				(thermal_gap 0.5)
				(thermal_bridge_width 0.5)
				(island_removal_mode 0)
			)
			(polygon
				(pts
					(xy 401.89277 -127.913384) (xy 401.89277 -127.405384) (xy 401.51177 -127.405384) (xy 401.51177 -127.913384)
				)
			)
		)
	)
	(footprint ""
		(layer "B.Cu")
		(at 422.70172 -149.987 90)
		(property "Reference" "C2L17"
			(at 0 0 90)
			(layer "B.SilkS")
			(hide yes)
			(effects
				(font
					(size 1.27 1.27)
				)
				(justify mirror)
			)
		)
		(property "Value" ""
			(at 0 0 90)
			(layer "B.Fab")
			(effects
				(font
					(size 1.27 1.27)
				)
				(justify mirror)
			)
		)
		(duplicate_pad_numbers_are_jumpers no)
		(fp_poly
			(pts
				(xy -0.3048 -0.1016) (xy -0.3048 0.9906) (xy 0.3048 0.9906) (xy 0.3048 -0.1016)
			)
			(stroke
				(width 0)
				(type default)
			)
			(fill no)
			(layer "B.CrtYd")
		)
		(fp_line
			(start 0.3048 -0.1016)
			(end 0.3048 0.9906)
			(stroke
				(width 0.1)
				(type default)
			)
			(layer "B.Fab")
		)
		(fp_line
			(start -0.3048 -0.1016)
			(end 0.3048 -0.1016)
			(stroke
				(width 0.1)
				(type default)
			)
			(layer "B.Fab")
		)
		(fp_line
			(start 0.3048 0.9906)
			(end -0.3048 0.9906)
			(stroke
				(width 0.1)
				(type default)
			)
			(layer "B.Fab")
		)
		(fp_line
			(start -0.3048 0.9906)
			(end -0.3048 -0.1016)
			(stroke
				(width 0.1)
				(type default)
			)
			(layer "B.Fab")
		)
		(pad "1" smd rect
			(at 0 0 270)
			(size 0.508 0.508)
			(layers "B.Cu" "B.Mask" "B.Paste")
			(net "SATA6G_PCH_PCIE_UP_SATA_RXN<0>")
		)
		(pad "2" smd rect
			(at 0 0.889 270)
			(size 0.508 0.508)
			(layers "B.Cu" "B.Mask" "B.Paste")
			(net "SATA6G_P0_RX_C_DN")
		)
		(zone
			(layer "B.Cu")
			(hatch none 0.5)
			(connect_pads
				(clearance 0)
			)
			(min_thickness 0.25)
			(keepout
				(tracks allowed)
				(vias not_allowed)
				(pads allowed)
				(copperpour not_allowed)
				(footprints allowed)
			)
			(placement
				(enabled no)
				(sheetname "")
			)
			(fill
				(thermal_gap 0.5)
				(thermal_bridge_width 0.5)
				(island_removal_mode 0)
			)
			(polygon
				(pts
					(xy 422.95572 -150.241) (xy 422.95572 -149.733) (xy 423.33672 -149.733) (xy 423.33672 -150.241)
				)
			)
		)
		(zone
			(layer "B.Cu")
			(hatch none 0.5)
			(connect_pads
				(clearance 0)
			)
			(min_thickness 0.25)
			(keepout
				(tracks not_allowed)
				(vias allowed)
				(pads allowed)
				(copperpour not_allowed)
				(footprints allowed)
			)
			(placement
				(enabled no)
				(sheetname "")
			)
			(fill
				(thermal_gap 0.5)
				(thermal_bridge_width 0.5)
				(island_removal_mode 0)
			)
			(polygon
				(pts
					(xy 423.33672 -150.241) (xy 423.33672 -149.733) (xy 422.95572 -149.733) (xy 422.95572 -150.241)
				)
			)
		)
	)
	(footprint ""
		(layer "B.Cu")
		(at 486.300526 -55.853584)
		(property "Reference" "C30W9"
			(at 0 0 0)
			(layer "B.SilkS")
			(hide yes)
			(effects
				(font
					(size 1.27 1.27)
				)
				(justify mirror)
			)
		)
		(property "Value" "*"
			(at 0.0762 -6.2357 0)
			(unlocked yes)
			(layer "B.Fab")
			(hide yes)
			(effects
				(font
					(size 1.27 1.016)
					(thickness 0.1524)
				)
				(justify mirror)
			)
		)
		(property "Device Type" "SC22U16V5MX-4-GP_SMD-BCG5-SC22A"
			(at 0.0762 -8.2677 0)
			(unlocked yes)
			(layer "B.Fab")
			(hide yes)
			(effects
				(font
					(size 1.27 1.016)
					(thickness 0.1524)
				)
				(justify mirror)
			)
		)
		(duplicate_pad_numbers_are_jumpers no)
		(fp_line
			(start -0.635 0)
			(end 0.635 0)
			(stroke
				(width 0.508)
				(type default)
			)
			(layer "B.SilkS")
		)
		(fp_rect
			(start 0.9652 1.778)
			(end -0.9652 -1.778)
			(stroke
				(width 0)
				(type default)
			)
			(fill no)
			(layer "B.CrtYd")
		)
		(fp_poly
			(pts
				(xy 0.9652 -1.778) (xy -0.9652 -1.778) (xy -0.9652 1.778) (xy 0.9652 1.778)
			)
			(stroke
				(width 0)
				(type default)
			)
			(fill no)
			(layer "B.Fab")
		)
		(pad "1" smd rect
			(at 0 -0.9652 180)
			(size 1.397 1.143)
			(layers "B.Cu" "B.Mask" "B.Paste")
			(net "P5V_STBY_USBC")
		)
		(pad "2" smd rect
			(at 0 0.9652 180)
			(size 1.397 1.143)
			(layers "B.Cu" "B.Mask" "B.Paste")
			(net "GND")
		)
	)
	(footprint ""
		(layer "B.Cu")
		(at 162.7886 -79.248 90)
		(property "Reference" "R7P7"
			(at 0 0 90)
			(layer "B.SilkS")
			(hide yes)
			(effects
				(font
					(size 1.27 1.27)
				)
				(justify mirror)
			)
		)
		(property "Value" ""
			(at 0 0 90)
			(layer "B.Fab")
			(effects
				(font
					(size 1.27 1.27)
				)
				(justify mirror)
			)
		)
		(duplicate_pad_numbers_are_jumpers no)
		(fp_poly
			(pts
				(xy 0.2794 -0.1016) (xy -0.2794 -0.1016) (xy -0.2794 0.9906) (xy 0.2794 0.9906)
			)
			(stroke
				(width 0)
				(type default)
			)
			(fill no)
			(layer "B.CrtYd")
		)
		(fp_line
			(start 0.2794 -0.1016)
			(end 0.2794 0.9906)
			(stroke
				(width 0.1)
				(type default)
			)
			(layer "B.Fab")
		)
		(fp_line
			(start -0.2794 -0.1016)
			(end 0.2794 -0.1016)
			(stroke
				(width 0.1)
				(type default)
			)
			(layer "B.Fab")
		)
		(fp_line
			(start 0.2794 0.9906)
			(end -0.2794 0.9906)
			(stroke
				(width 0.1)
				(type default)
			)
			(layer "B.Fab")
		)
		(fp_line
			(start -0.2794 0.9906)
			(end -0.2794 -0.1016)
			(stroke
				(width 0.1)
				(type default)
			)
			(layer "B.Fab")
		)
		(pad "1" smd rect
			(at 0 0 270)
			(size 0.508 0.508)
			(layers "B.Cu" "B.Mask" "B.Paste")
			(net "CLK_100M_CPU1_RC_REFCLK0_DN")
		)
		(pad "2" smd rect
			(at 0 0.889 270)
			(size 0.508 0.508)
			(layers "B.Cu" "B.Mask" "B.Paste")
			(net "GND")
		)
		(zone
			(layer "B.Cu")
			(hatch none 0.5)
			(connect_pads
				(clearance 0)
			)
			(min_thickness 0.25)
			(keepout
				(tracks allowed)
				(vias not_allowed)
				(pads allowed)
				(copperpour not_allowed)
				(footprints allowed)
			)
			(placement
				(enabled no)
				(sheetname "")
			)
			(fill
				(thermal_gap 0.5)
				(thermal_bridge_width 0.5)
				(island_removal_mode 0)
			)
			(polygon
				(pts
					(xy 163.0426 -79.502) (xy 163.0426 -78.994) (xy 163.4236 -78.994) (xy 163.4236 -79.502)
				)
			)
		)
		(zone
			(layer "B.Cu")
			(hatch none 0.5)
			(connect_pads
				(clearance 0)
			)
			(min_thickness 0.25)
			(keepout
				(tracks not_allowed)
				(vias allowed)
				(pads allowed)
				(copperpour not_allowed)
				(footprints allowed)
			)
			(placement
				(enabled no)
				(sheetname "")
			)
			(fill
				(thermal_gap 0.5)
				(thermal_bridge_width 0.5)
				(island_removal_mode 0)
			)
			(polygon
				(pts
					(xy 163.4236 -79.502) (xy 163.4236 -78.994) (xy 163.0426 -78.994) (xy 163.0426 -79.502)
				)
			)
		)
	)
	(footprint ""
		(layer "B.Cu")
		(at 12.40282 -101.57968 90)
		(property "Reference" "C9N10"
			(at 0 0 90)
			(layer "B.SilkS")
			(hide yes)
			(effects
				(font
					(size 1.27 1.27)
				)
				(justify mirror)
			)
		)
		(property "Value" ""
			(at 0 0 90)
			(layer "B.Fab")
			(effects
				(font
					(size 1.27 1.27)
				)
				(justify mirror)
			)
		)
		(duplicate_pad_numbers_are_jumpers no)
		(fp_poly
			(pts
				(xy -0.3048 -0.1016) (xy -0.3048 0.9906) (xy 0.3048 0.9906) (xy 0.3048 -0.1016)
			)
			(stroke
				(width 0)
				(type default)
			)
			(fill no)
			(layer "B.CrtYd")
		)
		(fp_line
			(start 0.3048 -0.1016)
			(end 0.3048 0.9906)
			(stroke
				(width 0.1)
				(type default)
			)
			(layer "B.Fab")
		)
		(fp_line
			(start -0.3048 -0.1016)
			(end 0.3048 -0.1016)
			(stroke
				(width 0.1)
				(type default)
			)
			(layer "B.Fab")
		)
		(fp_line
			(start 0.3048 0.9906)
			(end -0.3048 0.9906)
			(stroke
				(width 0.1)
				(type default)
			)
			(layer "B.Fab")
		)
		(fp_line
			(start -0.3048 0.9906)
			(end -0.3048 -0.1016)
			(stroke
				(width 0.1)
				(type default)
			)
			(layer "B.Fab")
		)
		(pad "1" smd rect
			(at 0 0 270)
			(size 0.508 0.508)
			(layers "B.Cu" "B.Mask" "B.Paste")
			(net "P3E_CPU1_PE3_MP_C_TXP<14>")
		)
		(pad "2" smd rect
			(at 0 0.889 270)
			(size 0.508 0.508)
			(layers "B.Cu" "B.Mask" "B.Paste")
			(net "P3E_CPU1_PE3_MP_TXP<14>")
		)
		(zone
			(layer "B.Cu")
			(hatch none 0.5)
			(connect_pads
				(clearance 0)
			)
			(min_thickness 0.25)
			(keepout
				(tracks allowed)
				(vias not_allowed)
				(pads allowed)
				(copperpour not_allowed)
				(footprints allowed)
			)
			(placement
				(enabled no)
				(sheetname "")
			)
			(fill
				(thermal_gap 0.5)
				(thermal_bridge_width 0.5)
				(island_removal_mode 0)
			)
			(polygon
				(pts
					(xy 12.65682 -101.83368) (xy 12.65682 -101.32568) (xy 13.03782 -101.32568) (xy 13.03782 -101.83368)
				)
			)
		)
		(zone
			(layer "B.Cu")
			(hatch none 0.5)
			(connect_pads
				(clearance 0)
			)
			(min_thickness 0.25)
			(keepout
				(tracks not_allowed)
				(vias allowed)
				(pads allowed)
				(copperpour not_allowed)
				(footprints allowed)
			)
			(placement
				(enabled no)
				(sheetname "")
			)
			(fill
				(thermal_gap 0.5)
				(thermal_bridge_width 0.5)
				(island_removal_mode 0)
			)
			(polygon
				(pts
					(xy 13.03782 -101.83368) (xy 13.03782 -101.32568) (xy 12.65682 -101.32568) (xy 12.65682 -101.83368)
				)
			)
		)
	)
	(footprint ""
		(layer "B.Cu")
		(at 418.719 -9.017 -90)
		(property "Reference" "R3P48"
			(at 0 0 90)
			(layer "B.SilkS")
			(hide yes)
			(effects
				(font
					(size 1.27 1.27)
				)
				(justify mirror)
			)
		)
		(property "Value" ""
			(at 0 0 90)
			(layer "B.Fab")
			(effects
				(font
					(size 1.27 1.27)
				)
				(justify mirror)
			)
		)
		(duplicate_pad_numbers_are_jumpers no)
		(fp_rect
			(start -0.2794 0.9906)
			(end 0.2794 -0.1016)
			(stroke
				(width 0)
				(type default)
			)
			(fill no)
			(layer "B.CrtYd")
		)
		(fp_line
			(start -0.2794 0.9906)
			(end -0.2794 -0.1016)
			(stroke
				(width 0.1)
				(type default)
			)
			(layer "B.Fab")
		)
		(fp_line
			(start 0.2794 0.9906)
			(end -0.2794 0.9906)
			(stroke
				(width 0.1)
				(type default)
			)
			(layer "B.Fab")
		)
		(fp_line
			(start -0.2794 -0.1016)
			(end 0.2794 -0.1016)
			(stroke
				(width 0.1)
				(type default)
			)
			(layer "B.Fab")
		)
		(fp_line
			(start 0.2794 -0.1016)
			(end 0.2794 0.9906)
			(stroke
				(width 0.1)
				(type default)
			)
			(layer "B.Fab")
		)
		(pad "1" smd rect
			(at 0 0 90)
			(size 0.508 0.508)
			(layers "B.Cu" "B.Mask" "B.Paste")
			(net "P12V_STBY")
		)
		(pad "2" smd rect
			(at 0 0.889 90)
			(size 0.508 0.508)
			(layers "B.Cu" "B.Mask" "B.Paste")
			(net "VSENSE_P12V_ADM1085")
		)
		(zone
			(layer "B.Cu")
			(hatch none 0.5)
			(connect_pads
				(clearance 0)
			)
			(min_thickness 0.25)
			(keepout
				(tracks allowed)
				(vias not_allowed)
				(pads allowed)
				(copperpour not_allowed)
				(footprints allowed)
			)
			(placement
				(enabled no)
				(sheetname "")
			)
			(fill
				(thermal_gap 0.5)
				(thermal_bridge_width 0.5)
				(island_removal_mode 0)
			)
			(polygon
				(pts
					(xy 418.084 -9.271) (xy 418.084 -8.763) (xy 418.465 -8.763) (xy 418.465 -9.271)
				)
			)
		)
		(zone
			(layer "B.Cu")
			(hatch none 0.5)
			(connect_pads
				(clearance 0)
			)
			(min_thickness 0.25)
			(keepout
				(tracks not_allowed)
				(vias allowed)
				(pads allowed)
				(copperpour not_allowed)
				(footprints allowed)
			)
			(placement
				(enabled no)
				(sheetname "")
			)
			(fill
				(thermal_gap 0.5)
				(thermal_bridge_width 0.5)
				(island_removal_mode 0)
			)
			(polygon
				(pts
					(xy 418.084 -9.271) (xy 418.084 -8.763) (xy 418.465 -8.763) (xy 418.465 -9.271)
				)
			)
		)
	)
	(footprint ""
		(layer "B.Cu")
		(at 475.412816 -145.470372 180)
		(property "Reference" "R6W11"
			(at 0.8382 -0.67818 180)
			(unlocked yes)
			(layer "B.SilkS")
			(effects
				(font
					(size 0.4064 0.254)
					(thickness 0.1524)
				)
				(justify left mirror)
			)
		)
		(property "Value" ""
			(at 0 0 0)
			(layer "B.Fab")
			(effects
				(font
					(size 1.27 1.27)
				)
				(justify mirror)
			)
		)
		(duplicate_pad_numbers_are_jumpers no)
		(fp_poly
			(pts
				(xy 0.2794 -0.1016) (xy -0.2794 -0.1016) (xy -0.2794 0.9906) (xy 0.2794 0.9906)
			)
			(stroke
				(width 0)
				(type default)
			)
			(fill no)
			(layer "B.CrtYd")
		)
		(fp_line
			(start 0.2794 0.9906)
			(end -0.2794 0.9906)
			(stroke
				(width 0.1)
				(type default)
			)
			(layer "B.Fab")
		)
		(fp_line
			(start 0.2794 -0.1016)
			(end 0.2794 0.9906)
			(stroke
				(width 0.1)
				(type default)
			)
			(layer "B.Fab")
		)
		(fp_line
			(start -0.2794 0.9906)
			(end -0.2794 -0.1016)
			(stroke
				(width 0.1)
				(type default)
			)
			(layer "B.Fab")
		)
		(fp_line
			(start -0.2794 -0.1016)
			(end 0.2794 -0.1016)
			(stroke
				(width 0.1)
				(type default)
			)
			(layer "B.Fab")
		)
		(pad "1" smd rect
			(at 0 0)
			(size 0.508 0.508)
			(layers "B.Cu" "B.Mask" "B.Paste")
			(net "SMB_DEBUG_STBY_LVC3_SCL")
		)
		(pad "2" smd rect
			(at 0 0.889)
			(size 0.508 0.508)
			(layers "B.Cu" "B.Mask" "B.Paste")
			(net "P3V3_STBY")
		)
		(zone
			(layer "B.Cu")
			(hatch none 0.5)
			(connect_pads
				(clearance 0)
			)
			(min_thickness 0.25)
			(keepout
				(tracks not_allowed)
				(vias allowed)
				(pads allowed)
				(copperpour not_allowed)
				(footprints allowed)
			)
			(placement
				(enabled no)
				(sheetname "")
			)
			(fill
				(thermal_gap 0.5)
				(thermal_bridge_width 0.5)
				(island_removal_mode 0)
			)
			(polygon
				(pts
					(xy 475.158816 -146.105372) (xy 475.666816 -146.105372) (xy 475.666816 -145.724372) (xy 475.158816 -145.724372)
				)
			)
		)
		(zone
			(layer "B.Cu")
			(hatch none 0.5)
			(connect_pads
				(clearance 0)
			)
			(min_thickness 0.25)
			(keepout
				(tracks allowed)
				(vias not_allowed)
				(pads allowed)
				(copperpour not_allowed)
				(footprints allowed)
			)
			(placement
				(enabled no)
				(sheetname "")
			)
			(fill
				(thermal_gap 0.5)
				(thermal_bridge_width 0.5)
				(island_removal_mode 0)
			)
			(polygon
				(pts
					(xy 475.158816 -145.724372) (xy 475.666816 -145.724372) (xy 475.666816 -146.105372) (xy 475.158816 -146.105372)
				)
			)
		)
	)
	(footprint ""
		(layer "B.Cu")
		(at 429.046894 -15.280894 -90)
		(property "Reference" "R1U57"
			(at 0 0 90)
			(layer "B.SilkS")
			(hide yes)
			(effects
				(font
					(size 1.27 1.27)
				)
				(justify mirror)
			)
		)
		(property "Value" ""
			(at 0 0 90)
			(layer "B.Fab")
			(effects
				(font
					(size 1.27 1.27)
				)
				(justify mirror)
			)
		)
		(duplicate_pad_numbers_are_jumpers no)
		(fp_poly
			(pts
				(xy 0.2794 -0.1016) (xy -0.2794 -0.1016) (xy -0.2794 0.9906) (xy 0.2794 0.9906)
			)
			(stroke
				(width 0)
				(type default)
			)
			(fill no)
			(layer "B.CrtYd")
		)
		(fp_line
			(start -0.2794 0.9906)
			(end -0.2794 -0.1016)
			(stroke
				(width 0.1)
				(type default)
			)
			(layer "B.Fab")
		)
		(fp_line
			(start 0.2794 0.9906)
			(end -0.2794 0.9906)
			(stroke
				(width 0.1)
				(type default)
			)
			(layer "B.Fab")
		)
		(fp_line
			(start -0.2794 -0.1016)
			(end 0.2794 -0.1016)
			(stroke
				(width 0.1)
				(type default)
			)
			(layer "B.Fab")
		)
		(fp_line
			(start 0.2794 -0.1016)
			(end 0.2794 0.9906)
			(stroke
				(width 0.1)
				(type default)
			)
			(layer "B.Fab")
		)
		(pad "1" smd rect
			(at 0 0 90)
			(size 0.508 0.508)
			(layers "B.Cu" "B.Mask" "B.Paste")
			(net "H_CPU1_MEMGHJ_MEMHOT_LVT3_K_N")
		)
		(pad "2" smd rect
			(at 0 0.889 90)
			(size 0.508 0.508)
			(layers "B.Cu" "B.Mask" "B.Paste")
			(net "H_CPU1_MEMGHJ_MEMHOT_G_PCH_N")
		)
		(zone
			(layer "B.Cu")
			(hatch none 0.5)
			(connect_pads
				(clearance 0)
			)
			(min_thickness 0.25)
			(keepout
				(tracks not_allowed)
				(vias allowed)
				(pads allowed)
				(copperpour not_allowed)
				(footprints allowed)
			)
			(placement
				(enabled no)
				(sheetname "")
			)
			(fill
				(thermal_gap 0.5)
				(thermal_bridge_width 0.5)
				(island_removal_mode 0)
			)
			(polygon
				(pts
					(xy 428.411894 -15.026894) (xy 428.411894 -15.534894) (xy 428.792894 -15.534894) (xy 428.792894 -15.026894)
				)
			)
		)
		(zone
			(layer "B.Cu")
			(hatch none 0.5)
			(connect_pads
				(clearance 0)
			)
			(min_thickness 0.25)
			(keepout
				(tracks allowed)
				(vias not_allowed)
				(pads allowed)
				(copperpour not_allowed)
				(footprints allowed)
			)
			(placement
				(enabled no)
				(sheetname "")
			)
			(fill
				(thermal_gap 0.5)
				(thermal_bridge_width 0.5)
				(island_removal_mode 0)
			)
			(polygon
				(pts
					(xy 428.792894 -15.026894) (xy 428.792894 -15.534894) (xy 428.411894 -15.534894) (xy 428.411894 -15.026894)
				)
			)
		)
	)
	(footprint ""
		(layer "B.Cu")
		(at 448.2846 -129.3622 180)
		(property "Reference" "C1M35"
			(at 0 0 0)
			(layer "B.SilkS")
			(hide yes)
			(effects
				(font
					(size 1.27 1.27)
				)
				(justify mirror)
			)
		)
		(property "Value" ""
			(at 0 0 0)
			(layer "B.Fab")
			(effects
				(font
					(size 1.27 1.27)
				)
				(justify mirror)
			)
		)
		(duplicate_pad_numbers_are_jumpers no)
		(fp_poly
			(pts
				(xy -0.3048 -0.1016) (xy -0.3048 0.9906) (xy 0.3048 0.9906) (xy 0.3048 -0.1016)
			)
			(stroke
				(width 0)
				(type default)
			)
			(fill no)
			(layer "B.CrtYd")
		)
		(fp_line
			(start 0.3048 0.9906)
			(end -0.3048 0.9906)
			(stroke
				(width 0.1)
				(type default)
			)
			(layer "B.Fab")
		)
		(fp_line
			(start 0.3048 -0.1016)
			(end 0.3048 0.9906)
			(stroke
				(width 0.1)
				(type default)
			)
			(layer "B.Fab")
		)
		(fp_line
			(start -0.3048 0.9906)
			(end -0.3048 -0.1016)
			(stroke
				(width 0.1)
				(type default)
			)
			(layer "B.Fab")
		)
		(fp_line
			(start -0.3048 -0.1016)
			(end 0.3048 -0.1016)
			(stroke
				(width 0.1)
				(type default)
			)
			(layer "B.Fab")
		)
		(pad "1" smd rect
			(at 0 0)
			(size 0.508 0.508)
			(layers "B.Cu" "B.Mask" "B.Paste")
			(net "P3V3_STBY")
		)
		(pad "2" smd rect
			(at 0 0.889)
			(size 0.508 0.508)
			(layers "B.Cu" "B.Mask" "B.Paste")
			(net "GND")
		)
		(zone
			(layer "B.Cu")
			(hatch none 0.5)
			(connect_pads
				(clearance 0)
			)
			(min_thickness 0.25)
			(keepout
				(tracks not_allowed)
				(vias allowed)
				(pads allowed)
				(copperpour not_allowed)
				(footprints allowed)
			)
			(placement
				(enabled no)
				(sheetname "")
			)
			(fill
				(thermal_gap 0.5)
				(thermal_bridge_width 0.5)
				(island_removal_mode 0)
			)
			(polygon
				(pts
					(xy 448.0306 -129.9972) (xy 448.5386 -129.9972) (xy 448.5386 -129.6162) (xy 448.0306 -129.6162)
				)
			)
		)
		(zone
			(layer "B.Cu")
			(hatch none 0.5)
			(connect_pads
				(clearance 0)
			)
			(min_thickness 0.25)
			(keepout
				(tracks allowed)
				(vias not_allowed)
				(pads allowed)
				(copperpour not_allowed)
				(footprints allowed)
			)
			(placement
				(enabled no)
				(sheetname "")
			)
			(fill
				(thermal_gap 0.5)
				(thermal_bridge_width 0.5)
				(island_removal_mode 0)
			)
			(polygon
				(pts
					(xy 448.0306 -129.6162) (xy 448.5386 -129.6162) (xy 448.5386 -129.9972) (xy 448.0306 -129.9972)
				)
			)
		)
	)
	(footprint ""
		(layer "B.Cu")
		(at 373.6975 -57.658 -90)
		(property "Reference" "R3P58"
			(at 0 0 90)
			(layer "B.SilkS")
			(hide yes)
			(effects
				(font
					(size 1.27 1.27)
				)
				(justify mirror)
			)
		)
		(property "Value" ""
			(at 0 0 90)
			(layer "B.Fab")
			(effects
				(font
					(size 1.27 1.27)
				)
				(justify mirror)
			)
		)
		(duplicate_pad_numbers_are_jumpers no)
		(fp_poly
			(pts
				(xy 0.2794 -0.1016) (xy -0.2794 -0.1016) (xy -0.2794 0.9906) (xy 0.2794 0.9906)
			)
			(stroke
				(width 0)
				(type default)
			)
			(fill no)
			(layer "B.CrtYd")
		)
		(fp_line
			(start -0.2794 0.9906)
			(end -0.2794 -0.1016)
			(stroke
				(width 0.1)
				(type default)
			)
			(layer "B.Fab")
		)
		(fp_line
			(start 0.2794 0.9906)
			(end -0.2794 0.9906)
			(stroke
				(width 0.1)
				(type default)
			)
			(layer "B.Fab")
		)
		(fp_line
			(start -0.2794 -0.1016)
			(end 0.2794 -0.1016)
			(stroke
				(width 0.1)
				(type default)
			)
			(layer "B.Fab")
		)
		(fp_line
			(start 0.2794 -0.1016)
			(end 0.2794 0.9906)
			(stroke
				(width 0.1)
				(type default)
			)
			(layer "B.Fab")
		)
		(pad "1" smd rect
			(at 0 0 90)
			(size 0.508 0.508)
			(layers "B.Cu" "B.Mask" "B.Paste")
			(net "H_CPU1_CATERR_G_N")
		)
		(pad "2" smd rect
			(at 0 0.889 90)
			(size 0.508 0.508)
			(layers "B.Cu" "B.Mask" "B.Paste")
			(net "H_CPU_CATERR_G_N")
		)
		(zone
			(layer "B.Cu")
			(hatch none 0.5)
			(connect_pads
				(clearance 0)
			)
			(min_thickness 0.25)
			(keepout
				(tracks not_allowed)
				(vias allowed)
				(pads allowed)
				(copperpour not_allowed)
				(footprints allowed)
			)
			(placement
				(enabled no)
				(sheetname "")
			)
			(fill
				(thermal_gap 0.5)
				(thermal_bridge_width 0.5)
				(island_removal_mode 0)
			)
			(polygon
				(pts
					(xy 373.0625 -57.404) (xy 373.0625 -57.912) (xy 373.4435 -57.912) (xy 373.4435 -57.404)
				)
			)
		)
		(zone
			(layer "B.Cu")
			(hatch none 0.5)
			(connect_pads
				(clearance 0)
			)
			(min_thickness 0.25)
			(keepout
				(tracks allowed)
				(vias not_allowed)
				(pads allowed)
				(copperpour not_allowed)
				(footprints allowed)
			)
			(placement
				(enabled no)
				(sheetname "")
			)
			(fill
				(thermal_gap 0.5)
				(thermal_bridge_width 0.5)
				(island_removal_mode 0)
			)
			(polygon
				(pts
					(xy 373.4435 -57.404) (xy 373.4435 -57.912) (xy 373.0625 -57.912) (xy 373.0625 -57.404)
				)
			)
		)
	)
	(footprint ""
		(layer "B.Cu")
		(at 340.331806 -61.257434)
		(property "Reference" "C2U8"
			(at 0 0 0)
			(layer "B.SilkS")
			(hide yes)
			(effects
				(font
					(size 1.27 1.27)
				)
				(justify mirror)
			)
		)
		(property "Value" ""
			(at 0 0 0)
			(layer "B.Fab")
			(effects
				(font
					(size 1.27 1.27)
				)
				(justify mirror)
			)
		)
		(duplicate_pad_numbers_are_jumpers no)
		(fp_poly
			(pts
				(xy -0.3048 -0.1016) (xy -0.3048 0.9906) (xy 0.3048 0.9906) (xy 0.3048 -0.1016)
			)
			(stroke
				(width 0)
				(type default)
			)
			(fill no)
			(layer "B.CrtYd")
		)
		(fp_line
			(start -0.3048 -0.1016)
			(end 0.3048 -0.1016)
			(stroke
				(width 0.1)
				(type default)
			)
			(layer "B.Fab")
		)
		(fp_line
			(start -0.3048 0.9906)
			(end -0.3048 -0.1016)
			(stroke
				(width 0.1)
				(type default)
			)
			(layer "B.Fab")
		)
		(fp_line
			(start 0.3048 -0.1016)
			(end 0.3048 0.9906)
			(stroke
				(width 0.1)
				(type default)
			)
			(layer "B.Fab")
		)
		(fp_line
			(start 0.3048 0.9906)
			(end -0.3048 0.9906)
			(stroke
				(width 0.1)
				(type default)
			)
			(layer "B.Fab")
		)
		(pad "1" smd rect
			(at 0 0 180)
			(size 0.508 0.508)
			(layers "B.Cu" "B.Mask" "B.Paste")
			(net "P3E_CPU0_PE1_PCH_RXN<2>")
		)
		(pad "2" smd rect
			(at 0 0.889 180)
			(size 0.508 0.508)
			(layers "B.Cu" "B.Mask" "B.Paste")
			(net "P3E_CPU0_PE1_SS_RXN<2>")
		)
		(zone
			(layer "B.Cu")
			(hatch none 0.5)
			(connect_pads
				(clearance 0)
			)
			(min_thickness 0.25)
			(keepout
				(tracks allowed)
				(vias not_allowed)
				(pads allowed)
				(copperpour not_allowed)
				(footprints allowed)
			)
			(placement
				(enabled no)
				(sheetname "")
			)
			(fill
				(thermal_gap 0.5)
				(thermal_bridge_width 0.5)
				(island_removal_mode 0)
			)
			(polygon
				(pts
					(xy 340.585806 -61.003434) (xy 340.077806 -61.003434) (xy 340.077806 -60.622434) (xy 340.585806 -60.622434)
				)
			)
		)
		(zone
			(layer "B.Cu")
			(hatch none 0.5)
			(connect_pads
				(clearance 0)
			)
			(min_thickness 0.25)
			(keepout
				(tracks not_allowed)
				(vias allowed)
				(pads allowed)
				(copperpour not_allowed)
				(footprints allowed)
			)
			(placement
				(enabled no)
				(sheetname "")
			)
			(fill
				(thermal_gap 0.5)
				(thermal_bridge_width 0.5)
				(island_removal_mode 0)
			)
			(polygon
				(pts
					(xy 340.585806 -60.622434) (xy 340.077806 -60.622434) (xy 340.077806 -61.003434) (xy 340.585806 -61.003434)
				)
			)
		)
	)
	(footprint ""
		(layer "B.Cu")
		(at 93.444568 -8.0772 -90)
		(property "Reference" "C8U9"
			(at 0 0 90)
			(layer "B.SilkS")
			(hide yes)
			(effects
				(font
					(size 1.27 1.27)
				)
				(justify mirror)
			)
		)
		(property "Value" ""
			(at 0 0 90)
			(layer "B.Fab")
			(effects
				(font
					(size 1.27 1.27)
				)
				(justify mirror)
			)
		)
		(duplicate_pad_numbers_are_jumpers no)
		(fp_rect
			(start 0.500126 1.598422)
			(end -0.500126 -0.201422)
			(stroke
				(width 0)
				(type default)
			)
			(fill no)
			(layer "B.CrtYd")
		)
		(fp_line
			(start -0.500126 1.598422)
			(end 0.500126 1.598422)
			(stroke
				(width 0.1)
				(type default)
			)
			(layer "B.Fab")
		)
		(fp_line
			(start 0.500126 1.598422)
			(end 0.500126 -0.201422)
			(stroke
				(width 0.1)
				(type default)
			)
			(layer "B.Fab")
		)
		(fp_line
			(start -0.500126 -0.201422)
			(end -0.500126 1.598422)
			(stroke
				(width 0.1)
				(type default)
			)
			(layer "B.Fab")
		)
		(fp_line
			(start 0.500126 -0.201422)
			(end -0.500126 -0.201422)
			(stroke
				(width 0.1)
				(type default)
			)
			(layer "B.Fab")
		)
		(pad "1" smd rect
			(at 0 0 180)
			(size 0.889 0.9906)
			(layers "B.Cu" "B.Mask" "B.Paste")
			(net "PVDDQ_GHJ")
		)
		(pad "2" smd rect
			(at 0 1.397 180)
			(size 0.889 0.9906)
			(layers "B.Cu" "B.Mask" "B.Paste")
			(net "GND")
		)
		(zone
			(layer "B.Cu")
			(hatch none 0.5)
			(connect_pads
				(clearance 0)
			)
			(min_thickness 0.25)
			(keepout
				(tracks allowed)
				(vias not_allowed)
				(pads allowed)
				(copperpour not_allowed)
				(footprints allowed)
			)
			(placement
				(enabled no)
				(sheetname "")
			)
			(fill
				(thermal_gap 0.5)
				(thermal_bridge_width 0.5)
				(island_removal_mode 0)
			)
			(polygon
				(pts
					(xy 92.492068 -7.5819) (xy 93.000068 -7.5819) (xy 93.000068 -8.5725) (xy 92.492068 -8.5725)
				)
			)
		)
		(zone
			(layer "B.Cu")
			(hatch none 0.5)
			(connect_pads
				(clearance 0)
			)
			(min_thickness 0.25)
			(keepout
				(tracks not_allowed)
				(vias allowed)
				(pads allowed)
				(copperpour not_allowed)
				(footprints allowed)
			)
			(placement
				(enabled no)
				(sheetname "")
			)
			(fill
				(thermal_gap 0.5)
				(thermal_bridge_width 0.5)
				(island_removal_mode 0)
			)
			(polygon
				(pts
					(xy 92.492068 -7.5819) (xy 93.000068 -7.5819) (xy 93.000068 -8.5725) (xy 92.492068 -8.5725)
				)
			)
		)
	)
	(footprint ""
		(layer "B.Cu")
		(at 458.08773 -18.55724)
		(property "Reference" "C2T9"
			(at 0 0 0)
			(layer "B.SilkS")
			(hide yes)
			(effects
				(font
					(size 1.27 1.27)
				)
				(justify mirror)
			)
		)
		(property "Value" ""
			(at 0 0 0)
			(layer "B.Fab")
			(effects
				(font
					(size 1.27 1.27)
				)
				(justify mirror)
			)
		)
		(duplicate_pad_numbers_are_jumpers no)
		(fp_poly
			(pts
				(xy 0.7239 -0.2159) (xy -0.7239 -0.2159) (xy -0.7239 1.9939) (xy 0.7239 1.9939)
			)
			(stroke
				(width 0)
				(type default)
			)
			(fill no)
			(layer "B.CrtYd")
		)
		(fp_line
			(start -0.7239 -0.2159)
			(end 0.7239 -0.2159)
			(stroke
				(width 0.1)
				(type default)
			)
			(layer "B.Fab")
		)
		(fp_line
			(start -0.7239 1.9939)
			(end -0.7239 -0.2159)
			(stroke
				(width 0.1)
				(type default)
			)
			(layer "B.Fab")
		)
		(fp_line
			(start 0.7239 -0.2159)
			(end 0.7239 1.9939)
			(stroke
				(width 0.1)
				(type default)
			)
			(layer "B.Fab")
		)
		(fp_line
			(start 0.7239 1.9939)
			(end -0.7239 1.9939)
			(stroke
				(width 0.1)
				(type default)
			)
			(layer "B.Fab")
		)
		(pad "1" smd rect
			(at 0 0 180)
			(size 1.27 1.016)
			(layers "B.Cu" "B.Mask" "B.Paste")
			(net "P3V3_STBY")
		)
		(pad "2" smd rect
			(at 0 1.778 180)
			(size 1.27 1.016)
			(layers "B.Cu" "B.Mask" "B.Paste")
			(net "GND")
		)
		(zone
			(layer "B.Cu")
			(hatch none 0.5)
			(connect_pads
				(clearance 0)
			)
			(min_thickness 0.25)
			(keepout
				(tracks not_allowed)
				(vias allowed)
				(pads allowed)
				(copperpour not_allowed)
				(footprints allowed)
			)
			(placement
				(enabled no)
				(sheetname "")
			)
			(fill
				(thermal_gap 0.5)
				(thermal_bridge_width 0.5)
				(island_removal_mode 0)
			)
			(polygon
				(pts
					(xy 458.72273 -18.04924) (xy 457.45273 -18.04924) (xy 457.45273 -17.28724) (xy 458.72273 -17.28724)
				)
			)
		)
	)
	(footprint ""
		(layer "B.Cu")
		(at 473.719652 -145.477484 -90)
		(property "Reference" "C6W1"
			(at 0.8382 -0.67818 270)
			(unlocked yes)
			(layer "B.SilkS")
			(effects
				(font
					(size 0.4064 0.254)
					(thickness 0.1524)
				)
				(justify left mirror)
			)
		)
		(property "Value" ""
			(at 0 0 90)
			(layer "B.Fab")
			(effects
				(font
					(size 1.27 1.27)
				)
				(justify mirror)
			)
		)
		(duplicate_pad_numbers_are_jumpers no)
		(fp_poly
			(pts
				(xy -0.3048 -0.1016) (xy -0.3048 0.9906) (xy 0.3048 0.9906) (xy 0.3048 -0.1016)
			)
			(stroke
				(width 0)
				(type default)
			)
			(fill no)
			(layer "B.CrtYd")
		)
		(fp_line
			(start -0.3048 0.9906)
			(end -0.3048 -0.1016)
			(stroke
				(width 0.1)
				(type default)
			)
			(layer "B.Fab")
		)
		(fp_line
			(start 0.3048 0.9906)
			(end -0.3048 0.9906)
			(stroke
				(width 0.1)
				(type default)
			)
			(layer "B.Fab")
		)
		(fp_line
			(start -0.3048 -0.1016)
			(end 0.3048 -0.1016)
			(stroke
				(width 0.1)
				(type default)
			)
			(layer "B.Fab")
		)
		(fp_line
			(start 0.3048 -0.1016)
			(end 0.3048 0.9906)
			(stroke
				(width 0.1)
				(type default)
			)
			(layer "B.Fab")
		)
		(pad "1" smd rect
			(at 0 0 90)
			(size 0.508 0.508)
			(layers "B.Cu" "B.Mask" "B.Paste")
			(net "P3V3_STBY")
		)
		(pad "2" smd rect
			(at 0 0.889 90)
			(size 0.508 0.508)
			(layers "B.Cu" "B.Mask" "B.Paste")
			(net "GND")
		)
		(zone
			(layer "B.Cu")
			(hatch none 0.5)
			(connect_pads
				(clearance 0)
			)
			(min_thickness 0.25)
			(keepout
				(tracks not_allowed)
				(vias allowed)
				(pads allowed)
				(copperpour not_allowed)
				(footprints allowed)
			)
			(placement
				(enabled no)
				(sheetname "")
			)
			(fill
				(thermal_gap 0.5)
				(thermal_bridge_width 0.5)
				(island_removal_mode 0)
			)
			(polygon
				(pts
					(xy 473.084652 -145.223484) (xy 473.084652 -145.731484) (xy 473.465652 -145.731484) (xy 473.465652 -145.223484)
				)
			)
		)
		(zone
			(layer "B.Cu")
			(hatch none 0.5)
			(connect_pads
				(clearance 0)
			)
			(min_thickness 0.25)
			(keepout
				(tracks allowed)
				(vias not_allowed)
				(pads allowed)
				(copperpour not_allowed)
				(footprints allowed)
			)
			(placement
				(enabled no)
				(sheetname "")
			)
			(fill
				(thermal_gap 0.5)
				(thermal_bridge_width 0.5)
				(island_removal_mode 0)
			)
			(polygon
				(pts
					(xy 473.465652 -145.223484) (xy 473.465652 -145.731484) (xy 473.084652 -145.731484) (xy 473.084652 -145.223484)
				)
			)
		)
	)
	(footprint ""
		(layer "B.Cu")
		(at 383.42824 -81.06918 90)
		(property "Reference" "R7D15"
			(at 0.8382 -0.67818 90)
			(unlocked yes)
			(layer "B.SilkS")
			(effects
				(font
					(size 0.4064 0.254)
					(thickness 0.1524)
				)
				(justify left mirror)
			)
		)
		(property "Value" ""
			(at 0 0 90)
			(layer "B.Fab")
			(effects
				(font
					(size 1.27 1.27)
				)
				(justify mirror)
			)
		)
		(duplicate_pad_numbers_are_jumpers no)
		(fp_poly
			(pts
				(xy 0.2794 -0.1016) (xy -0.2794 -0.1016) (xy -0.2794 0.9906) (xy 0.2794 0.9906)
			)
			(stroke
				(width 0)
				(type default)
			)
			(fill no)
			(layer "B.CrtYd")
		)
		(fp_line
			(start 0.2794 -0.1016)
			(end 0.2794 0.9906)
			(stroke
				(width 0.1)
				(type default)
			)
			(layer "B.Fab")
		)
		(fp_line
			(start -0.2794 -0.1016)
			(end 0.2794 -0.1016)
			(stroke
				(width 0.1)
				(type default)
			)
			(layer "B.Fab")
		)
		(fp_line
			(start 0.2794 0.9906)
			(end -0.2794 0.9906)
			(stroke
				(width 0.1)
				(type default)
			)
			(layer "B.Fab")
		)
		(fp_line
			(start -0.2794 0.9906)
			(end -0.2794 -0.1016)
			(stroke
				(width 0.1)
				(type default)
			)
			(layer "B.Fab")
		)
		(pad "1" smd rect
			(at 0 0 270)
			(size 0.508 0.508)
			(layers "B.Cu" "B.Mask" "B.Paste")
			(net "PECI_PCH")
		)
		(pad "2" smd rect
			(at 0 0.889 270)
			(size 0.508 0.508)
			(layers "B.Cu" "B.Mask" "B.Paste")
			(net "GND")
		)
		(zone
			(layer "B.Cu")
			(hatch none 0.5)
			(connect_pads
				(clearance 0)
			)
			(min_thickness 0.25)
			(keepout
				(tracks allowed)
				(vias not_allowed)
				(pads allowed)
				(copperpour not_allowed)
				(footprints allowed)
			)
			(placement
				(enabled no)
				(sheetname "")
			)
			(fill
				(thermal_gap 0.5)
				(thermal_bridge_width 0.5)
				(island_removal_mode 0)
			)
			(polygon
				(pts
					(xy 383.68224 -81.32318) (xy 383.68224 -80.81518) (xy 384.06324 -80.81518) (xy 384.06324 -81.32318)
				)
			)
		)
		(zone
			(layer "B.Cu")
			(hatch none 0.5)
			(connect_pads
				(clearance 0)
			)
			(min_thickness 0.25)
			(keepout
				(tracks not_allowed)
				(vias allowed)
				(pads allowed)
				(copperpour not_allowed)
				(footprints allowed)
			)
			(placement
				(enabled no)
				(sheetname "")
			)
			(fill
				(thermal_gap 0.5)
				(thermal_bridge_width 0.5)
				(island_removal_mode 0)
			)
			(polygon
				(pts
					(xy 384.06324 -81.32318) (xy 384.06324 -80.81518) (xy 383.68224 -80.81518) (xy 383.68224 -81.32318)
				)
			)
		)
	)
	(footprint ""
		(layer "B.Cu")
		(at 354.36429 -77.915516)
		(property "Reference" "C3P33"
			(at 0 0 0)
			(layer "B.SilkS")
			(hide yes)
			(effects
				(font
					(size 1.27 1.27)
				)
				(justify mirror)
			)
		)
		(property "Value" ""
			(at 0 0 0)
			(layer "B.Fab")
			(effects
				(font
					(size 1.27 1.27)
				)
				(justify mirror)
			)
		)
		(duplicate_pad_numbers_are_jumpers no)
		(fp_poly
			(pts
				(xy -0.3048 -0.1016) (xy -0.3048 0.9906) (xy 0.3048 0.9906) (xy 0.3048 -0.1016)
			)
			(stroke
				(width 0)
				(type default)
			)
			(fill no)
			(layer "B.CrtYd")
		)
		(fp_line
			(start -0.3048 -0.1016)
			(end 0.3048 -0.1016)
			(stroke
				(width 0.1)
				(type default)
			)
			(layer "B.Fab")
		)
		(fp_line
			(start -0.3048 0.9906)
			(end -0.3048 -0.1016)
			(stroke
				(width 0.1)
				(type default)
			)
			(layer "B.Fab")
		)
		(fp_line
			(start 0.3048 -0.1016)
			(end 0.3048 0.9906)
			(stroke
				(width 0.1)
				(type default)
			)
			(layer "B.Fab")
		)
		(fp_line
			(start 0.3048 0.9906)
			(end -0.3048 0.9906)
			(stroke
				(width 0.1)
				(type default)
			)
			(layer "B.Fab")
		)
		(pad "1" smd rect
			(at 0 0 180)
			(size 0.508 0.508)
			(layers "B.Cu" "B.Mask" "B.Paste")
			(net "P3E_CPU0_PE1_SS_TXN<5>")
		)
		(pad "2" smd rect
			(at 0 0.889 180)
			(size 0.508 0.508)
			(layers "B.Cu" "B.Mask" "B.Paste")
			(net "P3E_CPU0_PE1_SS_C_TXN<5>")
		)
		(zone
			(layer "B.Cu")
			(hatch none 0.5)
			(connect_pads
				(clearance 0)
			)
			(min_thickness 0.25)
			(keepout
				(tracks allowed)
				(vias not_allowed)
				(pads allowed)
				(copperpour not_allowed)
				(footprints allowed)
			)
			(placement
				(enabled no)
				(sheetname "")
			)
			(fill
				(thermal_gap 0.5)
				(thermal_bridge_width 0.5)
				(island_removal_mode 0)
			)
			(polygon
				(pts
					(xy 354.61829 -77.661516) (xy 354.11029 -77.661516) (xy 354.11029 -77.280516) (xy 354.61829 -77.280516)
				)
			)
		)
		(zone
			(layer "B.Cu")
			(hatch none 0.5)
			(connect_pads
				(clearance 0)
			)
			(min_thickness 0.25)
			(keepout
				(tracks not_allowed)
				(vias allowed)
				(pads allowed)
				(copperpour not_allowed)
				(footprints allowed)
			)
			(placement
				(enabled no)
				(sheetname "")
			)
			(fill
				(thermal_gap 0.5)
				(thermal_bridge_width 0.5)
				(island_removal_mode 0)
			)
			(polygon
				(pts
					(xy 354.61829 -77.280516) (xy 354.11029 -77.280516) (xy 354.11029 -77.661516) (xy 354.61829 -77.661516)
				)
			)
		)
	)
	(footprint ""
		(layer "B.Cu")
		(at 482.9556 -38.4429 180)
		(property "Reference" "R1T32"
			(at 0 0 0)
			(layer "B.SilkS")
			(hide yes)
			(effects
				(font
					(size 1.27 1.27)
				)
				(justify mirror)
			)
		)
		(property "Value" ""
			(at 0 0 0)
			(layer "B.Fab")
			(effects
				(font
					(size 1.27 1.27)
				)
				(justify mirror)
			)
		)
		(duplicate_pad_numbers_are_jumpers no)
		(fp_poly
			(pts
				(xy 0.4953 -0.2032) (xy -0.4953 -0.2032) (xy -0.4953 1.6002) (xy 0.4953 1.6002)
			)
			(stroke
				(width 0)
				(type default)
			)
			(fill no)
			(layer "B.CrtYd")
		)
		(fp_line
			(start 0.4953 1.6002)
			(end 0.4953 -0.2032)
			(stroke
				(width 0.1)
				(type default)
			)
			(layer "B.Fab")
		)
		(fp_line
			(start 0.4953 -0.2032)
			(end -0.4953 -0.2032)
			(stroke
				(width 0.1)
				(type default)
			)
			(layer "B.Fab")
		)
		(fp_line
			(start -0.4953 1.6002)
			(end 0.4953 1.6002)
			(stroke
				(width 0.1)
				(type default)
			)
			(layer "B.Fab")
		)
		(fp_line
			(start -0.4953 -0.2032)
			(end -0.4953 1.6002)
			(stroke
				(width 0.1)
				(type default)
			)
			(layer "B.Fab")
		)
		(pad "1" smd rect
			(at 0 0)
			(size 0.762 0.889)
			(layers "B.Cu" "B.Mask" "B.Paste")
			(net "P1V5_LAN")
		)
		(pad "2" smd rect
			(at 0 1.397)
			(size 0.762 0.889)
			(layers "B.Cu" "B.Mask" "B.Paste")
			(net "P1V5_LAN_I210")
		)
		(zone
			(layer "B.Cu")
			(hatch none 0.5)
			(connect_pads
				(clearance 0)
			)
			(min_thickness 0.25)
			(keepout
				(tracks not_allowed)
				(vias allowed)
				(pads allowed)
				(copperpour not_allowed)
				(footprints allowed)
			)
			(placement
				(enabled no)
				(sheetname "")
			)
			(fill
				(thermal_gap 0.5)
				(thermal_bridge_width 0.5)
				(island_removal_mode 0)
			)
			(polygon
				(pts
					(xy 482.5746 -39.3954) (xy 482.5746 -38.8874) (xy 483.3366 -38.8874) (xy 483.3366 -39.3954)
				)
			)
		)
		(zone
			(layer "B.Cu")
			(hatch none 0.5)
			(connect_pads
				(clearance 0)
			)
			(min_thickness 0.25)
			(keepout
				(tracks allowed)
				(vias not_allowed)
				(pads allowed)
				(copperpour not_allowed)
				(footprints allowed)
			)
			(placement
				(enabled no)
				(sheetname "")
			)
			(fill
				(thermal_gap 0.5)
				(thermal_bridge_width 0.5)
				(island_removal_mode 0)
			)
			(polygon
				(pts
					(xy 483.3366 -39.3954) (xy 483.3366 -38.8874) (xy 482.5746 -38.8874) (xy 482.5746 -39.3954)
				)
			)
		)
	)
	(footprint ""
		(layer "B.Cu")
		(at 375.285 -56.6039)
		(property "Reference" "R8F6"
			(at 0 0 0)
			(layer "B.SilkS")
			(hide yes)
			(effects
				(font
					(size 1.27 1.27)
				)
				(justify mirror)
			)
		)
		(property "Value" ""
			(at 0 0 0)
			(layer "B.Fab")
			(effects
				(font
					(size 1.27 1.27)
				)
				(justify mirror)
			)
		)
		(duplicate_pad_numbers_are_jumpers no)
		(fp_poly
			(pts
				(xy 0.2794 -0.1016) (xy -0.2794 -0.1016) (xy -0.2794 0.9906) (xy 0.2794 0.9906)
			)
			(stroke
				(width 0)
				(type default)
			)
			(fill no)
			(layer "B.CrtYd")
		)
		(fp_line
			(start -0.2794 -0.1016)
			(end 0.2794 -0.1016)
			(stroke
				(width 0.1)
				(type default)
			)
			(layer "B.Fab")
		)
		(fp_line
			(start -0.2794 0.9906)
			(end -0.2794 -0.1016)
			(stroke
				(width 0.1)
				(type default)
			)
			(layer "B.Fab")
		)
		(fp_line
			(start 0.2794 -0.1016)
			(end 0.2794 0.9906)
			(stroke
				(width 0.1)
				(type default)
			)
			(layer "B.Fab")
		)
		(fp_line
			(start 0.2794 0.9906)
			(end -0.2794 0.9906)
			(stroke
				(width 0.1)
				(type default)
			)
			(layer "B.Fab")
		)
		(pad "1" smd rect
			(at 0 0 180)
			(size 0.508 0.508)
			(layers "B.Cu" "B.Mask" "B.Paste")
			(net "SPI_PCH_MISO")
		)
		(pad "2" smd rect
			(at 0 0.889 180)
			(size 0.508 0.508)
			(layers "B.Cu" "B.Mask" "B.Paste")
			(net "SPI_PCH_MISO_R")
		)
		(zone
			(layer "B.Cu")
			(hatch none 0.5)
			(connect_pads
				(clearance 0)
			)
			(min_thickness 0.25)
			(keepout
				(tracks allowed)
				(vias not_allowed)
				(pads allowed)
				(copperpour not_allowed)
				(footprints allowed)
			)
			(placement
				(enabled no)
				(sheetname "")
			)
			(fill
				(thermal_gap 0.5)
				(thermal_bridge_width 0.5)
				(island_removal_mode 0)
			)
			(polygon
				(pts
					(xy 375.539 -56.3499) (xy 375.031 -56.3499) (xy 375.031 -55.9689) (xy 375.539 -55.9689)
				)
			)
		)
		(zone
			(layer "B.Cu")
			(hatch none 0.5)
			(connect_pads
				(clearance 0)
			)
			(min_thickness 0.25)
			(keepout
				(tracks not_allowed)
				(vias allowed)
				(pads allowed)
				(copperpour not_allowed)
				(footprints allowed)
			)
			(placement
				(enabled no)
				(sheetname "")
			)
			(fill
				(thermal_gap 0.5)
				(thermal_bridge_width 0.5)
				(island_removal_mode 0)
			)
			(polygon
				(pts
					(xy 375.539 -55.9689) (xy 375.031 -55.9689) (xy 375.031 -56.3499) (xy 375.539 -56.3499)
				)
			)
		)
	)
	(footprint ""
		(layer "B.Cu")
		(at 28.0924 -8.122412 -90)
		(property "Reference" "C9U8"
			(at 0 0 90)
			(layer "B.SilkS")
			(hide yes)
			(effects
				(font
					(size 1.27 1.27)
				)
				(justify mirror)
			)
		)
		(property "Value" ""
			(at 0 0 90)
			(layer "B.Fab")
			(effects
				(font
					(size 1.27 1.27)
				)
				(justify mirror)
			)
		)
		(duplicate_pad_numbers_are_jumpers no)
		(fp_rect
			(start 0.7239 -0.2159)
			(end -0.7239 1.9939)
			(stroke
				(width 0)
				(type default)
			)
			(fill no)
			(layer "B.CrtYd")
		)
		(fp_line
			(start -0.7239 1.9939)
			(end -0.7239 -0.2159)
			(stroke
				(width 0.1)
				(type default)
			)
			(layer "B.Fab")
		)
		(fp_line
			(start 0.7239 1.9939)
			(end -0.7239 1.9939)
			(stroke
				(width 0.1)
				(type default)
			)
			(layer "B.Fab")
		)
		(fp_line
			(start -0.7239 -0.2159)
			(end 0.7239 -0.2159)
			(stroke
				(width 0.1)
				(type default)
			)
			(layer "B.Fab")
		)
		(fp_line
			(start 0.7239 -0.2159)
			(end 0.7239 1.9939)
			(stroke
				(width 0.1)
				(type default)
			)
			(layer "B.Fab")
		)
		(pad "1" smd rect
			(at 0 0 90)
			(size 1.27 1.016)
			(layers "B.Cu" "B.Mask" "B.Paste")
			(net "P12V_NVDIMM_GHJ")
		)
		(pad "2" smd rect
			(at 0 1.778 90)
			(size 1.27 1.016)
			(layers "B.Cu" "B.Mask" "B.Paste")
			(net "GND")
		)
		(zone
			(layer "B.Cu")
			(hatch none 0.5)
			(connect_pads
				(clearance 0)
			)
			(min_thickness 0.25)
			(keepout
				(tracks not_allowed)
				(vias allowed)
				(pads allowed)
				(copperpour not_allowed)
				(footprints allowed)
			)
			(placement
				(enabled no)
				(sheetname "")
			)
			(fill
				(thermal_gap 0.5)
				(thermal_bridge_width 0.5)
				(island_removal_mode 0)
			)
			(polygon
				(pts
					(xy 27.5844 -7.487412) (xy 27.5844 -8.757412) (xy 26.8224 -8.757412) (xy 26.8224 -7.487412)
				)
			)
		)
	)
	(footprint ""
		(layer "B.Cu")
		(at 195.453 -154.6352 90)
		(property "Reference" "C6L1"
			(at 0 0 90)
			(layer "B.SilkS")
			(hide yes)
			(effects
				(font
					(size 1.27 1.27)
				)
				(justify mirror)
			)
		)
		(property "Value" ""
			(at 0 0 90)
			(layer "B.Fab")
			(effects
				(font
					(size 1.27 1.27)
				)
				(justify mirror)
			)
		)
		(duplicate_pad_numbers_are_jumpers no)
		(fp_poly
			(pts
				(xy -0.3048 -0.1016) (xy -0.3048 0.9906) (xy 0.3048 0.9906) (xy 0.3048 -0.1016)
			)
			(stroke
				(width 0)
				(type default)
			)
			(fill no)
			(layer "B.CrtYd")
		)
		(fp_line
			(start 0.3048 -0.1016)
			(end 0.3048 0.9906)
			(stroke
				(width 0.1)
				(type default)
			)
			(layer "B.Fab")
		)
		(fp_line
			(start -0.3048 -0.1016)
			(end 0.3048 -0.1016)
			(stroke
				(width 0.1)
				(type default)
			)
			(layer "B.Fab")
		)
		(fp_line
			(start 0.3048 0.9906)
			(end -0.3048 0.9906)
			(stroke
				(width 0.1)
				(type default)
			)
			(layer "B.Fab")
		)
		(fp_line
			(start -0.3048 0.9906)
			(end -0.3048 -0.1016)
			(stroke
				(width 0.1)
				(type default)
			)
			(layer "B.Fab")
		)
		(pad "1" smd rect
			(at 0 0 270)
			(size 0.508 0.508)
			(layers "B.Cu" "B.Mask" "B.Paste")
			(net "M_F_VREF")
		)
		(pad "2" smd rect
			(at 0 0.889 270)
			(size 0.508 0.508)
			(layers "B.Cu" "B.Mask" "B.Paste")
			(net "GND")
		)
		(zone
			(layer "B.Cu")
			(hatch none 0.5)
			(connect_pads
				(clearance 0)
			)
			(min_thickness 0.25)
			(keepout
				(tracks allowed)
				(vias not_allowed)
				(pads allowed)
				(copperpour not_allowed)
				(footprints allowed)
			)
			(placement
				(enabled no)
				(sheetname "")
			)
			(fill
				(thermal_gap 0.5)
				(thermal_bridge_width 0.5)
				(island_removal_mode 0)
			)
			(polygon
				(pts
					(xy 195.707 -154.8892) (xy 195.707 -154.3812) (xy 196.088 -154.3812) (xy 196.088 -154.8892)
				)
			)
		)
		(zone
			(layer "B.Cu")
			(hatch none 0.5)
			(connect_pads
				(clearance 0)
			)
			(min_thickness 0.25)
			(keepout
				(tracks not_allowed)
				(vias allowed)
				(pads allowed)
				(copperpour not_allowed)
				(footprints allowed)
			)
			(placement
				(enabled no)
				(sheetname "")
			)
			(fill
				(thermal_gap 0.5)
				(thermal_bridge_width 0.5)
				(island_removal_mode 0)
			)
			(polygon
				(pts
					(xy 196.088 -154.8892) (xy 196.088 -154.3812) (xy 195.707 -154.3812) (xy 195.707 -154.8892)
				)
			)
		)
	)
	(footprint ""
		(layer "B.Cu")
		(at 258.318 -135.3312 -90)
		(property "Reference" "C5M9"
			(at 0 0 90)
			(layer "B.SilkS")
			(hide yes)
			(effects
				(font
					(size 1.27 1.27)
				)
				(justify mirror)
			)
		)
		(property "Value" ""
			(at 0 0 90)
			(layer "B.Fab")
			(effects
				(font
					(size 1.27 1.27)
				)
				(justify mirror)
			)
		)
		(duplicate_pad_numbers_are_jumpers no)
		(fp_rect
			(start 0.500126 1.598422)
			(end -0.500126 -0.201422)
			(stroke
				(width 0)
				(type default)
			)
			(fill no)
			(layer "B.CrtYd")
		)
		(fp_line
			(start -0.500126 1.598422)
			(end 0.500126 1.598422)
			(stroke
				(width 0.1)
				(type default)
			)
			(layer "B.Fab")
		)
		(fp_line
			(start 0.500126 1.598422)
			(end 0.500126 -0.201422)
			(stroke
				(width 0.1)
				(type default)
			)
			(layer "B.Fab")
		)
		(fp_line
			(start -0.500126 -0.201422)
			(end -0.500126 1.598422)
			(stroke
				(width 0.1)
				(type default)
			)
			(layer "B.Fab")
		)
		(fp_line
			(start 0.500126 -0.201422)
			(end -0.500126 -0.201422)
			(stroke
				(width 0.1)
				(type default)
			)
			(layer "B.Fab")
		)
		(pad "1" smd rect
			(at 0 0 180)
			(size 0.889 0.9906)
			(layers "B.Cu" "B.Mask" "B.Paste")
			(net "PVDDQ_DEF")
		)
		(pad "2" smd rect
			(at 0 1.397 180)
			(size 0.889 0.9906)
			(layers "B.Cu" "B.Mask" "B.Paste")
			(net "GND")
		)
		(zone
			(layer "B.Cu")
			(hatch none 0.5)
			(connect_pads
				(clearance 0)
			)
			(min_thickness 0.25)
			(keepout
				(tracks allowed)
				(vias not_allowed)
				(pads allowed)
				(copperpour not_allowed)
				(footprints allowed)
			)
			(placement
				(enabled no)
				(sheetname "")
			)
			(fill
				(thermal_gap 0.5)
				(thermal_bridge_width 0.5)
				(island_removal_mode 0)
			)
			(polygon
				(pts
					(xy 257.3655 -134.8359) (xy 257.8735 -134.8359) (xy 257.8735 -135.8265) (xy 257.3655 -135.8265)
				)
			)
		)
		(zone
			(layer "B.Cu")
			(hatch none 0.5)
			(connect_pads
				(clearance 0)
			)
			(min_thickness 0.25)
			(keepout
				(tracks not_allowed)
				(vias allowed)
				(pads allowed)
				(copperpour not_allowed)
				(footprints allowed)
			)
			(placement
				(enabled no)
				(sheetname "")
			)
			(fill
				(thermal_gap 0.5)
				(thermal_bridge_width 0.5)
				(island_removal_mode 0)
			)
			(polygon
				(pts
					(xy 257.3655 -134.8359) (xy 257.8735 -134.8359) (xy 257.8735 -135.8265) (xy 257.3655 -135.8265)
				)
			)
		)
	)
	(footprint ""
		(layer "B.Cu")
		(at 398.146778 -157.11297 -90)
		(property "Reference" "CF23"
			(at 0 0 90)
			(layer "B.SilkS")
			(hide yes)
			(effects
				(font
					(size 1.27 1.27)
				)
				(justify mirror)
			)
		)
		(property "Value" "*"
			(at -1.1811 -2.8194 270)
			(unlocked yes)
			(layer "B.Fab")
			(hide yes)
			(effects
				(font
					(size 1.27 1.016)
					(thickness 0.1524)
				)
				(justify mirror)
			)
		)
		(property "Device Type" "SC22P50V2JN-4GP_SMD-BCG-SC22P5A"
			(at -1.1811 -4.3434 270)
			(unlocked yes)
			(layer "B.Fab")
			(hide yes)
			(effects
				(font
					(size 1.27 1.016)
					(thickness 0.1524)
				)
				(justify mirror)
			)
		)
		(duplicate_pad_numbers_are_jumpers no)
		(fp_rect
			(start 0.4318 0.9525)
			(end -0.4318 -0.9525)
			(stroke
				(width 0)
				(type default)
			)
			(fill no)
			(layer "B.CrtYd")
		)
		(fp_rect
			(start 0.4318 0.9525)
			(end -0.4318 -0.9525)
			(stroke
				(width 0)
				(type default)
			)
			(fill no)
			(layer "B.Fab")
		)
		(pad "1" smd custom
			(at 0 -0.4445 90)
			(size 0.1524 0.1524)
			(layers "B.Cu" "B.Mask" "B.Paste")
			(net "VR_PVNN_PCH_AIREF1")
			(options
				(clearance outline)
				(anchor circle)
			)
			(primitives
				(gr_poly
					(pts
						(arc
							(start 0.3048 0.2032)
							(mid 0.275042 0.275042)
							(end 0.2032 0.3048)
						)
						(arc
							(start -0.2032 0.3048)
							(mid -0.275042 0.275042)
							(end -0.3048 0.2032)
						)
						(arc
							(start -0.3048 -0.2032)
							(mid -0.275042 -0.275042)
							(end -0.2032 -0.3048)
						)
						(arc
							(start 0.2032 -0.3048)
							(mid 0.275042 -0.275042)
							(end 0.3048 -0.2032)
						)
					)
					(width 0)
					(fill yes)
				)
			)
		)
		(pad "2" smd custom
			(at 0 0.4445 90)
			(size 0.1524 0.1524)
			(layers "B.Cu" "B.Mask" "B.Paste")
			(net "ISENSE_PVNN_PCH_PH1_IMON")
			(options
				(clearance outline)
				(anchor circle)
			)
			(primitives
				(gr_poly
					(pts
						(arc
							(start 0.3048 0.2032)
							(mid 0.275042 0.275042)
							(end 0.2032 0.3048)
						)
						(arc
							(start -0.2032 0.3048)
							(mid -0.275042 0.275042)
							(end -0.3048 0.2032)
						)
						(arc
							(start -0.3048 -0.2032)
							(mid -0.275042 -0.275042)
							(end -0.2032 -0.3048)
						)
						(arc
							(start 0.2032 -0.3048)
							(mid 0.275042 -0.275042)
							(end 0.3048 -0.2032)
						)
					)
					(width 0)
					(fill yes)
				)
			)
		)
	)
	(footprint ""
		(layer "B.Cu")
		(at 381.5842 -2.448814)
		(property "Reference" "C8W5"
			(at 0.8382 -0.67818 0)
			(unlocked yes)
			(layer "B.SilkS")
			(effects
				(font
					(size 0.4064 0.254)
					(thickness 0.1524)
				)
				(justify left mirror)
			)
		)
		(property "Value" ""
			(at 0 0 0)
			(layer "B.Fab")
			(effects
				(font
					(size 1.27 1.27)
				)
				(justify mirror)
			)
		)
		(duplicate_pad_numbers_are_jumpers no)
		(fp_poly
			(pts
				(xy -0.3048 -0.1016) (xy -0.3048 0.9906) (xy 0.3048 0.9906) (xy 0.3048 -0.1016)
			)
			(stroke
				(width 0)
				(type default)
			)
			(fill no)
			(layer "B.CrtYd")
		)
		(fp_line
			(start -0.3048 -0.1016)
			(end 0.3048 -0.1016)
			(stroke
				(width 0.1)
				(type default)
			)
			(layer "B.Fab")
		)
		(fp_line
			(start -0.3048 0.9906)
			(end -0.3048 -0.1016)
			(stroke
				(width 0.1)
				(type default)
			)
			(layer "B.Fab")
		)
		(fp_line
			(start 0.3048 -0.1016)
			(end 0.3048 0.9906)
			(stroke
				(width 0.1)
				(type default)
			)
			(layer "B.Fab")
		)
		(fp_line
			(start 0.3048 0.9906)
			(end -0.3048 0.9906)
			(stroke
				(width 0.1)
				(type default)
			)
			(layer "B.Fab")
		)
		(pad "1" smd rect
			(at 0 0 180)
			(size 0.508 0.508)
			(layers "B.Cu" "B.Mask" "B.Paste")
			(net "P3V3_STBY")
		)
		(pad "2" smd rect
			(at 0 0.889 180)
			(size 0.508 0.508)
			(layers "B.Cu" "B.Mask" "B.Paste")
			(net "GND")
		)
		(zone
			(layer "B.Cu")
			(hatch none 0.5)
			(connect_pads
				(clearance 0)
			)
			(min_thickness 0.25)
			(keepout
				(tracks allowed)
				(vias not_allowed)
				(pads allowed)
				(copperpour not_allowed)
				(footprints allowed)
			)
			(placement
				(enabled no)
				(sheetname "")
			)
			(fill
				(thermal_gap 0.5)
				(thermal_bridge_width 0.5)
				(island_removal_mode 0)
			)
			(polygon
				(pts
					(xy 381.8382 -2.194814) (xy 381.3302 -2.194814) (xy 381.3302 -1.813814) (xy 381.8382 -1.813814)
				)
			)
		)
		(zone
			(layer "B.Cu")
			(hatch none 0.5)
			(connect_pads
				(clearance 0)
			)
			(min_thickness 0.25)
			(keepout
				(tracks not_allowed)
				(vias allowed)
				(pads allowed)
				(copperpour not_allowed)
				(footprints allowed)
			)
			(placement
				(enabled no)
				(sheetname "")
			)
			(fill
				(thermal_gap 0.5)
				(thermal_bridge_width 0.5)
				(island_removal_mode 0)
			)
			(polygon
				(pts
					(xy 381.8382 -1.813814) (xy 381.3302 -1.813814) (xy 381.3302 -2.194814) (xy 381.8382 -2.194814)
				)
			)
		)
	)
	(footprint ""
		(layer "B.Cu")
		(at 449.707 -141.097 90)
		(property "Reference" "R25W158"
			(at 0.8382 -0.67818 90)
			(unlocked yes)
			(layer "B.SilkS")
			(effects
				(font
					(size 0.4064 0.254)
					(thickness 0.1524)
				)
				(justify left mirror)
			)
		)
		(property "Value" ""
			(at 0 0 90)
			(layer "B.Fab")
			(effects
				(font
					(size 1.27 1.27)
				)
				(justify mirror)
			)
		)
		(duplicate_pad_numbers_are_jumpers no)
		(fp_poly
			(pts
				(xy 0.2794 -0.1016) (xy -0.2794 -0.1016) (xy -0.2794 0.9906) (xy 0.2794 0.9906)
			)
			(stroke
				(width 0)
				(type default)
			)
			(fill no)
			(layer "B.CrtYd")
		)
		(fp_line
			(start 0.2794 -0.1016)
			(end 0.2794 0.9906)
			(stroke
				(width 0.1)
				(type default)
			)
			(layer "B.Fab")
		)
		(fp_line
			(start -0.2794 -0.1016)
			(end 0.2794 -0.1016)
			(stroke
				(width 0.1)
				(type default)
			)
			(layer "B.Fab")
		)
		(fp_line
			(start 0.2794 0.9906)
			(end -0.2794 0.9906)
			(stroke
				(width 0.1)
				(type default)
			)
			(layer "B.Fab")
		)
		(fp_line
			(start -0.2794 0.9906)
			(end -0.2794 -0.1016)
			(stroke
				(width 0.1)
				(type default)
			)
			(layer "B.Fab")
		)
		(pad "1" smd rect
			(at 0 0 270)
			(size 0.508 0.508)
			(layers "B.Cu" "B.Mask" "B.Paste")
			(net "P3V3_STBY")
		)
		(pad "2" smd rect
			(at 0 0.889 270)
			(size 0.508 0.508)
			(layers "B.Cu" "B.Mask" "B.Paste")
			(net "PU_GTL2014_3_DIR")
		)
		(zone
			(layer "B.Cu")
			(hatch none 0.5)
			(connect_pads
				(clearance 0)
			)
			(min_thickness 0.25)
			(keepout
				(tracks allowed)
				(vias not_allowed)
				(pads allowed)
				(copperpour not_allowed)
				(footprints allowed)
			)
			(placement
				(enabled no)
				(sheetname "")
			)
			(fill
				(thermal_gap 0.5)
				(thermal_bridge_width 0.5)
				(island_removal_mode 0)
			)
			(polygon
				(pts
					(xy 449.961 -141.351) (xy 449.961 -140.843) (xy 450.342 -140.843) (xy 450.342 -141.351)
				)
			)
		)
		(zone
			(layer "B.Cu")
			(hatch none 0.5)
			(connect_pads
				(clearance 0)
			)
			(min_thickness 0.25)
			(keepout
				(tracks not_allowed)
				(vias allowed)
				(pads allowed)
				(copperpour not_allowed)
				(footprints allowed)
			)
			(placement
				(enabled no)
				(sheetname "")
			)
			(fill
				(thermal_gap 0.5)
				(thermal_bridge_width 0.5)
				(island_removal_mode 0)
			)
			(polygon
				(pts
					(xy 450.342 -141.351) (xy 450.342 -140.843) (xy 449.961 -140.843) (xy 449.961 -141.351)
				)
			)
		)
	)
	(footprint ""
		(layer "B.Cu")
		(at 27.658568 -144.4752 180)
		(property "Reference" "R9L8"
			(at 0 0 0)
			(layer "B.SilkS")
			(hide yes)
			(effects
				(font
					(size 1.27 1.27)
				)
				(justify mirror)
			)
		)
		(property "Value" ""
			(at 0 0 0)
			(layer "B.Fab")
			(effects
				(font
					(size 1.27 1.27)
				)
				(justify mirror)
			)
		)
		(duplicate_pad_numbers_are_jumpers no)
		(fp_poly
			(pts
				(xy 0.2794 -0.1016) (xy -0.2794 -0.1016) (xy -0.2794 0.9906) (xy 0.2794 0.9906)
			)
			(stroke
				(width 0)
				(type default)
			)
			(fill no)
			(layer "B.CrtYd")
		)
		(fp_line
			(start 0.2794 0.9906)
			(end -0.2794 0.9906)
			(stroke
				(width 0.1)
				(type default)
			)
			(layer "B.Fab")
		)
		(fp_line
			(start 0.2794 -0.1016)
			(end 0.2794 0.9906)
			(stroke
				(width 0.1)
				(type default)
			)
			(layer "B.Fab")
		)
		(fp_line
			(start -0.2794 0.9906)
			(end -0.2794 -0.1016)
			(stroke
				(width 0.1)
				(type default)
			)
			(layer "B.Fab")
		)
		(fp_line
			(start -0.2794 -0.1016)
			(end 0.2794 -0.1016)
			(stroke
				(width 0.1)
				(type default)
			)
			(layer "B.Fab")
		)
		(pad "1" smd rect
			(at 0 0)
			(size 0.508 0.508)
			(layers "B.Cu" "B.Mask" "B.Paste")
			(net "M_L_CPU_VREF")
		)
		(pad "2" smd rect
			(at 0 0.889)
			(size 0.508 0.508)
			(layers "B.Cu" "B.Mask" "B.Paste")
			(net "M_L_VREF")
		)
		(zone
			(layer "B.Cu")
			(hatch none 0.5)
			(connect_pads
				(clearance 0)
			)
			(min_thickness 0.25)
			(keepout
				(tracks not_allowed)
				(vias allowed)
				(pads allowed)
				(copperpour not_allowed)
				(footprints allowed)
			)
			(placement
				(enabled no)
				(sheetname "")
			)
			(fill
				(thermal_gap 0.5)
				(thermal_bridge_width 0.5)
				(island_removal_mode 0)
			)
			(polygon
				(pts
					(xy 27.404568 -145.1102) (xy 27.912568 -145.1102) (xy 27.912568 -144.7292) (xy 27.404568 -144.7292)
				)
			)
		)
		(zone
			(layer "B.Cu")
			(hatch none 0.5)
			(connect_pads
				(clearance 0)
			)
			(min_thickness 0.25)
			(keepout
				(tracks allowed)
				(vias not_allowed)
				(pads allowed)
				(copperpour not_allowed)
				(footprints allowed)
			)
			(placement
				(enabled no)
				(sheetname "")
			)
			(fill
				(thermal_gap 0.5)
				(thermal_bridge_width 0.5)
				(island_removal_mode 0)
			)
			(polygon
				(pts
					(xy 27.404568 -144.7292) (xy 27.912568 -144.7292) (xy 27.912568 -145.1102) (xy 27.404568 -145.1102)
				)
			)
		)
	)
	(footprint ""
		(layer "B.Cu")
		(at 259.4864 -13.0556 90)
		(property "Reference" "C5G22"
			(at -1.64973 0.78994 180)
			(unlocked yes)
			(layer "B.SilkS")
			(effects
				(font
					(size 0.7874 0.5842)
					(thickness 0.1524)
				)
				(justify mirror)
			)
		)
		(property "Value" ""
			(at 0 0 90)
			(layer "B.Fab")
			(effects
				(font
					(size 1.27 1.27)
				)
				(justify mirror)
			)
		)
		(duplicate_pad_numbers_are_jumpers no)
		(fp_rect
			(start -0.7239 -0.2159)
			(end 0.7239 1.9939)
			(stroke
				(width 0)
				(type default)
			)
			(fill no)
			(layer "B.CrtYd")
		)
		(fp_line
			(start 0.7239 -0.2159)
			(end 0.7239 1.9939)
			(stroke
				(width 0.1)
				(type default)
			)
			(layer "B.Fab")
		)
		(fp_line
			(start -0.7239 -0.2159)
			(end 0.7239 -0.2159)
			(stroke
				(width 0.1)
				(type default)
			)
			(layer "B.Fab")
		)
		(fp_line
			(start 0.7239 1.9939)
			(end -0.7239 1.9939)
			(stroke
				(width 0.1)
				(type default)
			)
			(layer "B.Fab")
		)
		(fp_line
			(start -0.7239 1.9939)
			(end -0.7239 -0.2159)
			(stroke
				(width 0.1)
				(type default)
			)
			(layer "B.Fab")
		)
		(pad "1" smd rect
			(at 0 0 270)
			(size 1.27 1.016)
			(layers "B.Cu" "B.Mask" "B.Paste")
			(net "PVDDQ_ABC")
		)
		(pad "2" smd rect
			(at 0 1.778 270)
			(size 1.27 1.016)
			(layers "B.Cu" "B.Mask" "B.Paste")
			(net "GND")
		)
		(zone
			(layer "B.Cu")
			(hatch none 0.5)
			(connect_pads
				(clearance 0)
			)
			(min_thickness 0.25)
			(keepout
				(tracks not_allowed)
				(vias allowed)
				(pads allowed)
				(copperpour not_allowed)
				(footprints allowed)
			)
			(placement
				(enabled no)
				(sheetname "")
			)
			(fill
				(thermal_gap 0.5)
				(thermal_bridge_width 0.5)
				(island_removal_mode 0)
			)
			(polygon
				(pts
					(xy 259.9944 -12.4206) (xy 260.7564 -12.4206) (xy 260.7564 -13.6906) (xy 259.9944 -13.6906)
				)
			)
		)
	)
	(footprint ""
		(layer "B.Cu")
		(at 474.14942 -134.00024 90)
		(property "Reference" "U1W3"
			(at -2.2733 -1.09728 90)
			(unlocked yes)
			(layer "B.SilkS")
			(effects
				(font
					(size 0.4064 0.254)
					(thickness 0.1524)
				)
				(justify mirror)
			)
		)
		(property "Value" ""
			(at 0 0 90)
			(layer "B.Fab")
			(effects
				(font
					(size 1.27 1.27)
				)
				(justify mirror)
			)
		)
		(duplicate_pad_numbers_are_jumpers no)
		(fp_line
			(start -3.225292 -0.57404)
			(end -1.352804 -0.57404)
			(stroke
				(width 0.1524)
				(type default)
			)
			(layer "B.SilkS")
		)
		(fp_line
			(start -3.225038 2.52476)
			(end -1.348486 2.52476)
			(stroke
				(width 0.1524)
				(type default)
			)
			(layer "B.SilkS")
		)
		(fp_circle
			(center 1.971802 -0.212852)
			(end 1.971802 -0.085852)
			(stroke
				(width 0.254)
				(type default)
			)
			(fill no)
			(layer "B.SilkS")
		)
		(fp_poly
			(pts
				(xy -0.7366 -0.57404) (xy -3.8354 -0.57404) (xy -3.8354 2.52476) (xy -0.7366 2.52476)
			)
			(stroke
				(width 0)
				(type default)
			)
			(fill no)
			(layer "B.CrtYd")
		)
		(fp_line
			(start -0.7366 -0.57404)
			(end -3.8354 -0.57404)
			(stroke
				(width 0.1)
				(type default)
			)
			(layer "B.Fab")
		)
		(fp_line
			(start -3.8354 -0.57404)
			(end -3.8354 2.52476)
			(stroke
				(width 0.1)
				(type default)
			)
			(layer "B.Fab")
		)
		(fp_line
			(start -0.7366 2.52476)
			(end -0.7366 -0.57404)
			(stroke
				(width 0.1)
				(type default)
			)
			(layer "B.Fab")
		)
		(fp_line
			(start -3.8354 2.52476)
			(end -0.7366 2.52476)
			(stroke
				(width 0.1)
				(type default)
			)
			(layer "B.Fab")
		)
		(fp_circle
			(center 1.454404 -0.556514)
			(end 1.454404 -0.429514)
			(stroke
				(width 0.254)
				(type default)
			)
			(fill no)
			(layer "B.Fab")
		)
		(pad "1" smd rect
			(at 0 0 270)
			(size 1.778 0.4572)
			(layers "B.Cu" "B.Mask" "B.Paste")
			(net "P3V3_STBY")
		)
		(pad "2" smd rect
			(at 0 0.65024 270)
			(size 1.778 0.4572)
			(layers "B.Cu" "B.Mask" "B.Paste")
			(net "SMB_DEBUG_STBY_LVC3_SCL_CONN")
		)
		(pad "3" smd rect
			(at 0 1.30048 270)
			(size 1.778 0.4572)
			(layers "B.Cu" "B.Mask" "B.Paste")
			(net "SMB_DEBUG_STBY_LVC3_SDA_CONN")
		)
		(pad "4" smd rect
			(at 0 1.95072 270)
			(size 1.778 0.4572)
			(layers "B.Cu" "B.Mask" "B.Paste")
			(net "GND")
		)
		(pad "5" smd rect
			(at -4.572 1.95072 270)
			(size 1.778 0.4572)
			(layers "B.Cu" "B.Mask" "B.Paste")
			(net "DEBUG_CARD2_PRSNT")
		)
		(pad "6" smd rect
			(at -4.572 1.30048 270)
			(size 1.778 0.4572)
			(layers "B.Cu" "B.Mask" "B.Paste")
			(net "SMB_DEBUG_STBY_LVC3_SDA_R1")
		)
		(pad "7" smd rect
			(at -4.572 0.65024 270)
			(size 1.778 0.4572)
			(layers "B.Cu" "B.Mask" "B.Paste")
			(net "SMB_DEBUG_STBY_LVC3_SCL_R1")
		)
		(pad "8" smd rect
			(at -4.572 0 270)
			(size 1.778 0.4572)
			(layers "B.Cu" "B.Mask" "B.Paste")
			(net "P3V3_STBY")
		)
	)
	(footprint ""
		(layer "B.Cu")
		(at 408.6225 -109.22 -90)
		(property "Reference" "R6W24"
			(at 0.8382 -0.67818 270)
			(unlocked yes)
			(layer "B.SilkS")
			(effects
				(font
					(size 0.4064 0.254)
					(thickness 0.1524)
				)
				(justify left mirror)
			)
		)
		(property "Value" ""
			(at 0 0 90)
			(layer "B.Fab")
			(effects
				(font
					(size 1.27 1.27)
				)
				(justify mirror)
			)
		)
		(duplicate_pad_numbers_are_jumpers no)
		(fp_poly
			(pts
				(xy 0.2794 -0.1016) (xy -0.2794 -0.1016) (xy -0.2794 0.9906) (xy 0.2794 0.9906)
			)
			(stroke
				(width 0)
				(type default)
			)
			(fill no)
			(layer "B.CrtYd")
		)
		(fp_line
			(start -0.2794 0.9906)
			(end -0.2794 -0.1016)
			(stroke
				(width 0.1)
				(type default)
			)
			(layer "B.Fab")
		)
		(fp_line
			(start 0.2794 0.9906)
			(end -0.2794 0.9906)
			(stroke
				(width 0.1)
				(type default)
			)
			(layer "B.Fab")
		)
		(fp_line
			(start -0.2794 -0.1016)
			(end 0.2794 -0.1016)
			(stroke
				(width 0.1)
				(type default)
			)
			(layer "B.Fab")
		)
		(fp_line
			(start 0.2794 -0.1016)
			(end 0.2794 0.9906)
			(stroke
				(width 0.1)
				(type default)
			)
			(layer "B.Fab")
		)
		(pad "1" smd rect
			(at 0 0 90)
			(size 0.508 0.508)
			(layers "B.Cu" "B.Mask" "B.Paste")
			(net "P3V3_STBY")
		)
		(pad "2" smd rect
			(at 0 0.889 90)
			(size 0.508 0.508)
			(layers "B.Cu" "B.Mask" "B.Paste")
			(net "SMB_PMBUS_BMC_STBY_LVC3_SDA_R1")
		)
		(zone
			(layer "B.Cu")
			(hatch none 0.5)
			(connect_pads
				(clearance 0)
			)
			(min_thickness 0.25)
			(keepout
				(tracks not_allowed)
				(vias allowed)
				(pads allowed)
				(copperpour not_allowed)
				(footprints allowed)
			)
			(placement
				(enabled no)
				(sheetname "")
			)
			(fill
				(thermal_gap 0.5)
				(thermal_bridge_width 0.5)
				(island_removal_mode 0)
			)
			(polygon
				(pts
					(xy 407.9875 -108.966) (xy 407.9875 -109.474) (xy 408.3685 -109.474) (xy 408.3685 -108.966)
				)
			)
		)
		(zone
			(layer "B.Cu")
			(hatch none 0.5)
			(connect_pads
				(clearance 0)
			)
			(min_thickness 0.25)
			(keepout
				(tracks allowed)
				(vias not_allowed)
				(pads allowed)
				(copperpour not_allowed)
				(footprints allowed)
			)
			(placement
				(enabled no)
				(sheetname "")
			)
			(fill
				(thermal_gap 0.5)
				(thermal_bridge_width 0.5)
				(island_removal_mode 0)
			)
			(polygon
				(pts
					(xy 408.3685 -108.966) (xy 408.3685 -109.474) (xy 407.9875 -109.474) (xy 407.9875 -108.966)
				)
			)
		)
	)
	(footprint ""
		(layer "B.Cu")
		(at 372.869968 -51.34229 180)
		(property "Reference" "R3P38"
			(at 0 0 0)
			(layer "B.SilkS")
			(hide yes)
			(effects
				(font
					(size 1.27 1.27)
				)
				(justify mirror)
			)
		)
		(property "Value" ""
			(at 0 0 0)
			(layer "B.Fab")
			(effects
				(font
					(size 1.27 1.27)
				)
				(justify mirror)
			)
		)
		(duplicate_pad_numbers_are_jumpers no)
		(fp_poly
			(pts
				(xy 0.2794 -0.1016) (xy -0.2794 -0.1016) (xy -0.2794 0.9906) (xy 0.2794 0.9906)
			)
			(stroke
				(width 0)
				(type default)
			)
			(fill no)
			(layer "B.CrtYd")
		)
		(fp_line
			(start 0.2794 0.9906)
			(end -0.2794 0.9906)
			(stroke
				(width 0.1)
				(type default)
			)
			(layer "B.Fab")
		)
		(fp_line
			(start 0.2794 -0.1016)
			(end 0.2794 0.9906)
			(stroke
				(width 0.1)
				(type default)
			)
			(layer "B.Fab")
		)
		(fp_line
			(start -0.2794 0.9906)
			(end -0.2794 -0.1016)
			(stroke
				(width 0.1)
				(type default)
			)
			(layer "B.Fab")
		)
		(fp_line
			(start -0.2794 -0.1016)
			(end 0.2794 -0.1016)
			(stroke
				(width 0.1)
				(type default)
			)
			(layer "B.Fab")
		)
		(pad "1" smd rect
			(at 0 0)
			(size 0.508 0.508)
			(layers "B.Cu" "B.Mask" "B.Paste")
			(net "PVDDQ_ABC")
		)
		(pad "2" smd rect
			(at 0 0.889)
			(size 0.508 0.508)
			(layers "B.Cu" "B.Mask" "B.Paste")
			(net "PWRGD_CPU0_DRAMPWROK_ABC_G")
		)
		(zone
			(layer "B.Cu")
			(hatch none 0.5)
			(connect_pads
				(clearance 0)
			)
			(min_thickness 0.25)
			(keepout
				(tracks not_allowed)
				(vias allowed)
				(pads allowed)
				(copperpour not_allowed)
				(footprints allowed)
			)
			(placement
				(enabled no)
				(sheetname "")
			)
			(fill
				(thermal_gap 0.5)
				(thermal_bridge_width 0.5)
				(island_removal_mode 0)
			)
			(polygon
				(pts
					(xy 372.615968 -51.97729) (xy 373.123968 -51.97729) (xy 373.123968 -51.59629) (xy 372.615968 -51.59629)
				)
			)
		)
		(zone
			(layer "B.Cu")
			(hatch none 0.5)
			(connect_pads
				(clearance 0)
			)
			(min_thickness 0.25)
			(keepout
				(tracks allowed)
				(vias not_allowed)
				(pads allowed)
				(copperpour not_allowed)
				(footprints allowed)
			)
			(placement
				(enabled no)
				(sheetname "")
			)
			(fill
				(thermal_gap 0.5)
				(thermal_bridge_width 0.5)
				(island_removal_mode 0)
			)
			(polygon
				(pts
					(xy 372.615968 -51.59629) (xy 373.123968 -51.59629) (xy 373.123968 -51.97729) (xy 372.615968 -51.97729)
				)
			)
		)
	)
	(footprint ""
		(layer "B.Cu")
		(at 260.377686 -73.51014)
		(property "Reference" "C5P36"
			(at 0 0 0)
			(layer "B.SilkS")
			(hide yes)
			(effects
				(font
					(size 1.27 1.27)
				)
				(justify mirror)
			)
		)
		(property "Value" ""
			(at 0 0 0)
			(layer "B.Fab")
			(effects
				(font
					(size 1.27 1.27)
				)
				(justify mirror)
			)
		)
		(duplicate_pad_numbers_are_jumpers no)
		(fp_poly
			(pts
				(xy 0.7239 -0.2159) (xy -0.7239 -0.2159) (xy -0.7239 1.9939) (xy 0.7239 1.9939)
			)
			(stroke
				(width 0)
				(type default)
			)
			(fill no)
			(layer "B.CrtYd")
		)
		(fp_line
			(start -0.7239 -0.2159)
			(end 0.7239 -0.2159)
			(stroke
				(width 0.1)
				(type default)
			)
			(layer "B.Fab")
		)
		(fp_line
			(start -0.7239 1.9939)
			(end -0.7239 -0.2159)
			(stroke
				(width 0.1)
				(type default)
			)
			(layer "B.Fab")
		)
		(fp_line
			(start 0.7239 -0.2159)
			(end 0.7239 1.9939)
			(stroke
				(width 0.1)
				(type default)
			)
			(layer "B.Fab")
		)
		(fp_line
			(start 0.7239 1.9939)
			(end -0.7239 1.9939)
			(stroke
				(width 0.1)
				(type default)
			)
			(layer "B.Fab")
		)
		(pad "1" smd rect
			(at 0 0 180)
			(size 1.27 1.016)
			(layers "B.Cu" "B.Mask" "B.Paste")
			(net "PVCCIN_CPU0")
		)
		(pad "2" smd rect
			(at 0 1.778 180)
			(size 1.27 1.016)
			(layers "B.Cu" "B.Mask" "B.Paste")
			(net "GND")
		)
		(zone
			(layer "B.Cu")
			(hatch none 0.5)
			(connect_pads
				(clearance 0)
			)
			(min_thickness 0.25)
			(keepout
				(tracks not_allowed)
				(vias allowed)
				(pads allowed)
				(copperpour not_allowed)
				(footprints allowed)
			)
			(placement
				(enabled no)
				(sheetname "")
			)
			(fill
				(thermal_gap 0.5)
				(thermal_bridge_width 0.5)
				(island_removal_mode 0)
			)
			(polygon
				(pts
					(xy 261.012686 -73.00214) (xy 259.742686 -73.00214) (xy 259.742686 -72.24014) (xy 261.012686 -72.24014)
				)
			)
		)
	)
	(footprint ""
		(layer "B.Cu")
		(at 374.8278 -102.0826 90)
		(property "Reference" "R3N3"
			(at 0 0 90)
			(layer "B.SilkS")
			(hide yes)
			(effects
				(font
					(size 1.27 1.27)
				)
				(justify mirror)
			)
		)
		(property "Value" ""
			(at 0 0 90)
			(layer "B.Fab")
			(effects
				(font
					(size 1.27 1.27)
				)
				(justify mirror)
			)
		)
		(duplicate_pad_numbers_are_jumpers no)
		(fp_poly
			(pts
				(xy 0.2794 -0.1016) (xy -0.2794 -0.1016) (xy -0.2794 0.9906) (xy 0.2794 0.9906)
			)
			(stroke
				(width 0)
				(type default)
			)
			(fill no)
			(layer "B.CrtYd")
		)
		(fp_line
			(start 0.2794 -0.1016)
			(end 0.2794 0.9906)
			(stroke
				(width 0.1)
				(type default)
			)
			(layer "B.Fab")
		)
		(fp_line
			(start -0.2794 -0.1016)
			(end 0.2794 -0.1016)
			(stroke
				(width 0.1)
				(type default)
			)
			(layer "B.Fab")
		)
		(fp_line
			(start 0.2794 0.9906)
			(end -0.2794 0.9906)
			(stroke
				(width 0.1)
				(type default)
			)
			(layer "B.Fab")
		)
		(fp_line
			(start -0.2794 0.9906)
			(end -0.2794 -0.1016)
			(stroke
				(width 0.1)
				(type default)
			)
			(layer "B.Fab")
		)
		(pad "1" smd rect
			(at 0 0 270)
			(size 0.508 0.508)
			(layers "B.Cu" "B.Mask" "B.Paste")
			(net "GND")
		)
		(pad "2" smd rect
			(at 0 0.889 270)
			(size 0.508 0.508)
			(layers "B.Cu" "B.Mask" "B.Paste")
			(net "PWRGD_PCH_PWROK")
		)
		(zone
			(layer "B.Cu")
			(hatch none 0.5)
			(connect_pads
				(clearance 0)
			)
			(min_thickness 0.25)
			(keepout
				(tracks allowed)
				(vias not_allowed)
				(pads allowed)
				(copperpour not_allowed)
				(footprints allowed)
			)
			(placement
				(enabled no)
				(sheetname "")
			)
			(fill
				(thermal_gap 0.5)
				(thermal_bridge_width 0.5)
				(island_removal_mode 0)
			)
			(polygon
				(pts
					(xy 375.0818 -102.3366) (xy 375.0818 -101.8286) (xy 375.4628 -101.8286) (xy 375.4628 -102.3366)
				)
			)
		)
		(zone
			(layer "B.Cu")
			(hatch none 0.5)
			(connect_pads
				(clearance 0)
			)
			(min_thickness 0.25)
			(keepout
				(tracks not_allowed)
				(vias allowed)
				(pads allowed)
				(copperpour not_allowed)
				(footprints allowed)
			)
			(placement
				(enabled no)
				(sheetname "")
			)
			(fill
				(thermal_gap 0.5)
				(thermal_bridge_width 0.5)
				(island_removal_mode 0)
			)
			(polygon
				(pts
					(xy 375.4628 -102.3366) (xy 375.4628 -101.8286) (xy 375.0818 -101.8286) (xy 375.0818 -102.3366)
				)
			)
		)
	)
	(footprint ""
		(layer "B.Cu")
		(at 368.7064 -5.3467 180)
		(property "Reference" "R3T14"
			(at 0 0 0)
			(layer "B.SilkS")
			(hide yes)
			(effects
				(font
					(size 1.27 1.27)
				)
				(justify mirror)
			)
		)
		(property "Value" ""
			(at 0 0 0)
			(layer "B.Fab")
			(effects
				(font
					(size 1.27 1.27)
				)
				(justify mirror)
			)
		)
		(duplicate_pad_numbers_are_jumpers no)
		(fp_poly
			(pts
				(xy 0.2794 -0.1016) (xy -0.2794 -0.1016) (xy -0.2794 0.9906) (xy 0.2794 0.9906)
			)
			(stroke
				(width 0)
				(type default)
			)
			(fill no)
			(layer "B.CrtYd")
		)
		(fp_line
			(start 0.2794 0.9906)
			(end -0.2794 0.9906)
			(stroke
				(width 0.1)
				(type default)
			)
			(layer "B.Fab")
		)
		(fp_line
			(start 0.2794 -0.1016)
			(end 0.2794 0.9906)
			(stroke
				(width 0.1)
				(type default)
			)
			(layer "B.Fab")
		)
		(fp_line
			(start -0.2794 0.9906)
			(end -0.2794 -0.1016)
			(stroke
				(width 0.1)
				(type default)
			)
			(layer "B.Fab")
		)
		(fp_line
			(start -0.2794 -0.1016)
			(end 0.2794 -0.1016)
			(stroke
				(width 0.1)
				(type default)
			)
			(layer "B.Fab")
		)
		(pad "1" smd rect
			(at 0 0)
			(size 0.508 0.508)
			(layers "B.Cu" "B.Mask" "B.Paste")
			(net "FM_BIOS_USB_RECOVERY")
		)
		(pad "2" smd rect
			(at 0 0.889)
			(size 0.508 0.508)
			(layers "B.Cu" "B.Mask" "B.Paste")
			(net "GND")
		)
		(zone
			(layer "B.Cu")
			(hatch none 0.5)
			(connect_pads
				(clearance 0)
			)
			(min_thickness 0.25)
			(keepout
				(tracks not_allowed)
				(vias allowed)
				(pads allowed)
				(copperpour not_allowed)
				(footprints allowed)
			)
			(placement
				(enabled no)
				(sheetname "")
			)
			(fill
				(thermal_gap 0.5)
				(thermal_bridge_width 0.5)
				(island_removal_mode 0)
			)
			(polygon
				(pts
					(xy 368.4524 -5.9817) (xy 368.9604 -5.9817) (xy 368.9604 -5.6007) (xy 368.4524 -5.6007)
				)
			)
		)
		(zone
			(layer "B.Cu")
			(hatch none 0.5)
			(connect_pads
				(clearance 0)
			)
			(min_thickness 0.25)
			(keepout
				(tracks allowed)
				(vias not_allowed)
				(pads allowed)
				(copperpour not_allowed)
				(footprints allowed)
			)
			(placement
				(enabled no)
				(sheetname "")
			)
			(fill
				(thermal_gap 0.5)
				(thermal_bridge_width 0.5)
				(island_removal_mode 0)
			)
			(polygon
				(pts
					(xy 368.4524 -5.6007) (xy 368.9604 -5.6007) (xy 368.9604 -5.9817) (xy 368.4524 -5.9817)
				)
			)
		)
	)
	(footprint ""
		(layer "B.Cu")
		(at 347.316806 -61.257434)
		(property "Reference" "C2U13"
			(at 0 0 0)
			(layer "B.SilkS")
			(hide yes)
			(effects
				(font
					(size 1.27 1.27)
				)
				(justify mirror)
			)
		)
		(property "Value" ""
			(at 0 0 0)
			(layer "B.Fab")
			(effects
				(font
					(size 1.27 1.27)
				)
				(justify mirror)
			)
		)
		(duplicate_pad_numbers_are_jumpers no)
		(fp_poly
			(pts
				(xy -0.3048 -0.1016) (xy -0.3048 0.9906) (xy 0.3048 0.9906) (xy 0.3048 -0.1016)
			)
			(stroke
				(width 0)
				(type default)
			)
			(fill no)
			(layer "B.CrtYd")
		)
		(fp_line
			(start -0.3048 -0.1016)
			(end 0.3048 -0.1016)
			(stroke
				(width 0.1)
				(type default)
			)
			(layer "B.Fab")
		)
		(fp_line
			(start -0.3048 0.9906)
			(end -0.3048 -0.1016)
			(stroke
				(width 0.1)
				(type default)
			)
			(layer "B.Fab")
		)
		(fp_line
			(start 0.3048 -0.1016)
			(end 0.3048 0.9906)
			(stroke
				(width 0.1)
				(type default)
			)
			(layer "B.Fab")
		)
		(fp_line
			(start 0.3048 0.9906)
			(end -0.3048 0.9906)
			(stroke
				(width 0.1)
				(type default)
			)
			(layer "B.Fab")
		)
		(pad "1" smd rect
			(at 0 0 180)
			(size 0.508 0.508)
			(layers "B.Cu" "B.Mask" "B.Paste")
			(net "P3E_CPU0_PE1_PCH_RXP<5>")
		)
		(pad "2" smd rect
			(at 0 0.889 180)
			(size 0.508 0.508)
			(layers "B.Cu" "B.Mask" "B.Paste")
			(net "P3E_CPU0_PE1_SS_RXP<5>")
		)
		(zone
			(layer "B.Cu")
			(hatch none 0.5)
			(connect_pads
				(clearance 0)
			)
			(min_thickness 0.25)
			(keepout
				(tracks allowed)
				(vias not_allowed)
				(pads allowed)
				(copperpour not_allowed)
				(footprints allowed)
			)
			(placement
				(enabled no)
				(sheetname "")
			)
			(fill
				(thermal_gap 0.5)
				(thermal_bridge_width 0.5)
				(island_removal_mode 0)
			)
			(polygon
				(pts
					(xy 347.570806 -61.003434) (xy 347.062806 -61.003434) (xy 347.062806 -60.622434) (xy 347.570806 -60.622434)
				)
			)
		)
	)
	(footprint ""
		(layer "B.Cu")
		(at 375.285 -89.4715)
		(property "Reference" "R3N9"
			(at 0.8382 -0.67818 0)
			(unlocked yes)
			(layer "B.SilkS")
			(effects
				(font
					(size 0.4064 0.254)
					(thickness 0.1524)
				)
				(justify left mirror)
			)
		)
		(property "Value" ""
			(at 0 0 0)
			(layer "B.Fab")
			(effects
				(font
					(size 1.27 1.27)
				)
				(justify mirror)
			)
		)
		(duplicate_pad_numbers_are_jumpers no)
		(fp_poly
			(pts
				(xy 0.2794 -0.1016) (xy -0.2794 -0.1016) (xy -0.2794 0.9906) (xy 0.2794 0.9906)
			)
			(stroke
				(width 0)
				(type default)
			)
			(fill no)
			(layer "B.CrtYd")
		)
		(fp_line
			(start -0.2794 -0.1016)
			(end 0.2794 -0.1016)
			(stroke
				(width 0.1)
				(type default)
			)
			(layer "B.Fab")
		)
		(fp_line
			(start -0.2794 0.9906)
			(end -0.2794 -0.1016)
			(stroke
				(width 0.1)
				(type default)
			)
			(layer "B.Fab")
		)
		(fp_line
			(start 0.2794 -0.1016)
			(end 0.2794 0.9906)
			(stroke
				(width 0.1)
				(type default)
			)
			(layer "B.Fab")
		)
		(fp_line
			(start 0.2794 0.9906)
			(end -0.2794 0.9906)
			(stroke
				(width 0.1)
				(type default)
			)
			(layer "B.Fab")
		)
		(pad "1" smd rect
			(at 0 0 180)
			(size 0.508 0.508)
			(layers "B.Cu" "B.Mask" "B.Paste")
			(net "H_PM_SYNC1_GTL_R")
		)
		(pad "2" smd rect
			(at 0 0.889 180)
			(size 0.508 0.508)
			(layers "B.Cu" "B.Mask" "B.Paste")
			(net "H_PM_SYNC_GTL")
		)
		(zone
			(layer "B.Cu")
			(hatch none 0.5)
			(connect_pads
				(clearance 0)
			)
			(min_thickness 0.25)
			(keepout
				(tracks allowed)
				(vias not_allowed)
				(pads allowed)
				(copperpour not_allowed)
				(footprints allowed)
			)
			(placement
				(enabled no)
				(sheetname "")
			)
			(fill
				(thermal_gap 0.5)
				(thermal_bridge_width 0.5)
				(island_removal_mode 0)
			)
			(polygon
				(pts
					(xy 375.539 -89.2175) (xy 375.031 -89.2175) (xy 375.031 -88.8365) (xy 375.539 -88.8365)
				)
			)
		)
		(zone
			(layer "B.Cu")
			(hatch none 0.5)
			(connect_pads
				(clearance 0)
			)
			(min_thickness 0.25)
			(keepout
				(tracks not_allowed)
				(vias allowed)
				(pads allowed)
				(copperpour not_allowed)
				(footprints allowed)
			)
			(placement
				(enabled no)
				(sheetname "")
			)
			(fill
				(thermal_gap 0.5)
				(thermal_bridge_width 0.5)
				(island_removal_mode 0)
			)
			(polygon
				(pts
					(xy 375.539 -88.8365) (xy 375.031 -88.8365) (xy 375.031 -89.2175) (xy 375.539 -89.2175)
				)
			)
		)
	)
	(footprint ""
		(layer "B.Cu")
		(at 173.4947 -5.551424 -90)
		(property "Reference" "C6U11"
			(at 0 0 90)
			(layer "B.SilkS")
			(hide yes)
			(effects
				(font
					(size 1.27 1.27)
				)
				(justify mirror)
			)
		)
		(property "Value" ""
			(at 0 0 90)
			(layer "B.Fab")
			(effects
				(font
					(size 1.27 1.27)
				)
				(justify mirror)
			)
		)
		(duplicate_pad_numbers_are_jumpers no)
		(fp_poly
			(pts
				(xy 0.4953 -0.2032) (xy -0.4953 -0.2032) (xy -0.4953 1.6002) (xy 0.4953 1.6002)
			)
			(stroke
				(width 0)
				(type default)
			)
			(fill no)
			(layer "B.CrtYd")
		)
		(fp_line
			(start -0.4953 1.6002)
			(end 0.4953 1.6002)
			(stroke
				(width 0.1)
				(type default)
			)
			(layer "B.Fab")
		)
		(fp_line
			(start 0.4953 1.6002)
			(end 0.4953 -0.2032)
			(stroke
				(width 0.1)
				(type default)
			)
			(layer "B.Fab")
		)
		(fp_line
			(start -0.4953 -0.2032)
			(end -0.4953 1.6002)
			(stroke
				(width 0.1)
				(type default)
			)
			(layer "B.Fab")
		)
		(fp_line
			(start 0.4953 -0.2032)
			(end -0.4953 -0.2032)
			(stroke
				(width 0.1)
				(type default)
			)
			(layer "B.Fab")
		)
		(pad "1" smd rect
			(at 0 0 90)
			(size 0.762 0.889)
			(layers "B.Cu" "B.Mask" "B.Paste")
			(net "VSENSE_PVDDQ_GHJ_VTT")
		)
		(pad "2" smd rect
			(at 0 1.397 90)
			(size 0.762 0.889)
			(layers "B.Cu" "B.Mask" "B.Paste")
			(net "GND")
		)
		(zone
			(layer "B.Cu")
			(hatch none 0.5)
			(connect_pads
				(clearance 0)
			)
			(min_thickness 0.25)
			(keepout
				(tracks not_allowed)
				(vias allowed)
				(pads allowed)
				(copperpour not_allowed)
				(footprints allowed)
			)
			(placement
				(enabled no)
				(sheetname "")
			)
			(fill
				(thermal_gap 0.5)
				(thermal_bridge_width 0.5)
				(island_removal_mode 0)
			)
			(polygon
				(pts
					(xy 173.0502 -5.170424) (xy 173.0502 -5.932424) (xy 172.5422 -5.932424) (xy 172.5422 -5.170424)
				)
			)
		)
	)
	(footprint ""
		(layer "B.Cu")
		(at 488.191302 -48.124872 -90)
		(property "Reference" "C9E12"
			(at 0 0 90)
			(layer "B.SilkS")
			(hide yes)
			(effects
				(font
					(size 1.27 1.27)
				)
				(justify mirror)
			)
		)
		(property "Value" ""
			(at 0 0 90)
			(layer "B.Fab")
			(effects
				(font
					(size 1.27 1.27)
				)
				(justify mirror)
			)
		)
		(duplicate_pad_numbers_are_jumpers no)
		(fp_poly
			(pts
				(xy 0.4953 -0.2032) (xy -0.4953 -0.2032) (xy -0.4953 1.6002) (xy 0.4953 1.6002)
			)
			(stroke
				(width 0)
				(type default)
			)
			(fill no)
			(layer "B.CrtYd")
		)
		(fp_line
			(start -0.4953 1.6002)
			(end 0.4953 1.6002)
			(stroke
				(width 0.1)
				(type default)
			)
			(layer "B.Fab")
		)
		(fp_line
			(start 0.4953 1.6002)
			(end 0.4953 -0.2032)
			(stroke
				(width 0.1)
				(type default)
			)
			(layer "B.Fab")
		)
		(fp_line
			(start -0.4953 -0.2032)
			(end -0.4953 1.6002)
			(stroke
				(width 0.1)
				(type default)
			)
			(layer "B.Fab")
		)
		(fp_line
			(start 0.4953 -0.2032)
			(end -0.4953 -0.2032)
			(stroke
				(width 0.1)
				(type default)
			)
			(layer "B.Fab")
		)
		(pad "1" smd rect
			(at 0 0 90)
			(size 0.762 0.889)
			(layers "B.Cu" "B.Mask" "B.Paste")
			(net "P0V9_LAN")
		)
		(pad "2" smd rect
			(at 0 1.397 90)
			(size 0.762 0.889)
			(layers "B.Cu" "B.Mask" "B.Paste")
			(net "GND")
		)
		(zone
			(layer "B.Cu")
			(hatch none 0.5)
			(connect_pads
				(clearance 0)
			)
			(min_thickness 0.25)
			(keepout
				(tracks not_allowed)
				(vias allowed)
				(pads allowed)
				(copperpour not_allowed)
				(footprints allowed)
			)
			(placement
				(enabled no)
				(sheetname "")
			)
			(fill
				(thermal_gap 0.5)
				(thermal_bridge_width 0.5)
				(island_removal_mode 0)
			)
			(polygon
				(pts
					(xy 487.746802 -47.743872) (xy 487.746802 -48.505872) (xy 487.238802 -48.505872) (xy 487.238802 -47.743872)
				)
			)
		)
	)
	(footprint ""
		(layer "B.Cu")
		(at 347.17736 -77.788516)
		(property "Reference" "C3P22"
			(at 0 0 0)
			(layer "B.SilkS")
			(hide yes)
			(effects
				(font
					(size 1.27 1.27)
				)
				(justify mirror)
			)
		)
		(property "Value" ""
			(at 0 0 0)
			(layer "B.Fab")
			(effects
				(font
					(size 1.27 1.27)
				)
				(justify mirror)
			)
		)
		(duplicate_pad_numbers_are_jumpers no)
		(fp_poly
			(pts
				(xy -0.3048 -0.1016) (xy -0.3048 0.9906) (xy 0.3048 0.9906) (xy 0.3048 -0.1016)
			)
			(stroke
				(width 0)
				(type default)
			)
			(fill no)
			(layer "B.CrtYd")
		)
		(fp_line
			(start -0.3048 -0.1016)
			(end 0.3048 -0.1016)
			(stroke
				(width 0.1)
				(type default)
			)
			(layer "B.Fab")
		)
		(fp_line
			(start -0.3048 0.9906)
			(end -0.3048 -0.1016)
			(stroke
				(width 0.1)
				(type default)
			)
			(layer "B.Fab")
		)
		(fp_line
			(start 0.3048 -0.1016)
			(end 0.3048 0.9906)
			(stroke
				(width 0.1)
				(type default)
			)
			(layer "B.Fab")
		)
		(fp_line
			(start 0.3048 0.9906)
			(end -0.3048 0.9906)
			(stroke
				(width 0.1)
				(type default)
			)
			(layer "B.Fab")
		)
		(pad "1" smd rect
			(at 0 0 180)
			(size 0.508 0.508)
			(layers "B.Cu" "B.Mask" "B.Paste")
			(net "P3E_CPU0_PE1_SS_TXP<3>")
		)
		(pad "2" smd rect
			(at 0 0.889 180)
			(size 0.508 0.508)
			(layers "B.Cu" "B.Mask" "B.Paste")
			(net "P3E_CPU0_PE1_SS_C_TXP<3>")
		)
		(zone
			(layer "B.Cu")
			(hatch none 0.5)
			(connect_pads
				(clearance 0)
			)
			(min_thickness 0.25)
			(keepout
				(tracks allowed)
				(vias not_allowed)
				(pads allowed)
				(copperpour not_allowed)
				(footprints allowed)
			)
			(placement
				(enabled no)
				(sheetname "")
			)
			(fill
				(thermal_gap 0.5)
				(thermal_bridge_width 0.5)
				(island_removal_mode 0)
			)
			(polygon
				(pts
					(xy 347.43136 -77.534516) (xy 346.92336 -77.534516) (xy 346.92336 -77.153516) (xy 347.43136 -77.153516)
				)
			)
		)
		(zone
			(layer "B.Cu")
			(hatch none 0.5)
			(connect_pads
				(clearance 0)
			)
			(min_thickness 0.25)
			(keepout
				(tracks not_allowed)
				(vias allowed)
				(pads allowed)
				(copperpour not_allowed)
				(footprints allowed)
			)
			(placement
				(enabled no)
				(sheetname "")
			)
			(fill
				(thermal_gap 0.5)
				(thermal_bridge_width 0.5)
				(island_removal_mode 0)
			)
			(polygon
				(pts
					(xy 347.43136 -77.153516) (xy 346.92336 -77.153516) (xy 346.92336 -77.534516) (xy 347.43136 -77.534516)
				)
			)
		)
	)
	(footprint ""
		(layer "B.Cu")
		(at 480.00666 -27.70632 180)
		(property "Reference" "C2T19"
			(at 0 0 0)
			(layer "B.SilkS")
			(hide yes)
			(effects
				(font
					(size 1.27 1.27)
				)
				(justify mirror)
			)
		)
		(property "Value" ""
			(at 0 0 0)
			(layer "B.Fab")
			(effects
				(font
					(size 1.27 1.27)
				)
				(justify mirror)
			)
		)
		(duplicate_pad_numbers_are_jumpers no)
		(fp_poly
			(pts
				(xy -0.3048 -0.1016) (xy -0.3048 0.9906) (xy 0.3048 0.9906) (xy 0.3048 -0.1016)
			)
			(stroke
				(width 0)
				(type default)
			)
			(fill no)
			(layer "B.CrtYd")
		)
		(fp_line
			(start 0.3048 0.9906)
			(end -0.3048 0.9906)
			(stroke
				(width 0.1)
				(type default)
			)
			(layer "B.Fab")
		)
		(fp_line
			(start 0.3048 -0.1016)
			(end 0.3048 0.9906)
			(stroke
				(width 0.1)
				(type default)
			)
			(layer "B.Fab")
		)
		(fp_line
			(start -0.3048 0.9906)
			(end -0.3048 -0.1016)
			(stroke
				(width 0.1)
				(type default)
			)
			(layer "B.Fab")
		)
		(fp_line
			(start -0.3048 -0.1016)
			(end 0.3048 -0.1016)
			(stroke
				(width 0.1)
				(type default)
			)
			(layer "B.Fab")
		)
		(pad "1" smd rect
			(at 0 0)
			(size 0.508 0.508)
			(layers "B.Cu" "B.Mask" "B.Paste")
			(net "P3V3_STBY_MNG_CPU")
		)
		(pad "2" smd rect
			(at 0 0.889)
			(size 0.508 0.508)
			(layers "B.Cu" "B.Mask" "B.Paste")
			(net "GND")
		)
		(zone
			(layer "B.Cu")
			(hatch none 0.5)
			(connect_pads
				(clearance 0)
			)
			(min_thickness 0.25)
			(keepout
				(tracks not_allowed)
				(vias allowed)
				(pads allowed)
				(copperpour not_allowed)
				(footprints allowed)
			)
			(placement
				(enabled no)
				(sheetname "")
			)
			(fill
				(thermal_gap 0.5)
				(thermal_bridge_width 0.5)
				(island_removal_mode 0)
			)
			(polygon
				(pts
					(xy 479.75266 -28.34132) (xy 480.26066 -28.34132) (xy 480.26066 -27.96032) (xy 479.75266 -27.96032)
				)
			)
		)
		(zone
			(layer "B.Cu")
			(hatch none 0.5)
			(connect_pads
				(clearance 0)
			)
			(min_thickness 0.25)
			(keepout
				(tracks allowed)
				(vias not_allowed)
				(pads allowed)
				(copperpour not_allowed)
				(footprints allowed)
			)
			(placement
				(enabled no)
				(sheetname "")
			)
			(fill
				(thermal_gap 0.5)
				(thermal_bridge_width 0.5)
				(island_removal_mode 0)
			)
			(polygon
				(pts
					(xy 479.75266 -27.96032) (xy 480.26066 -27.96032) (xy 480.26066 -28.34132) (xy 479.75266 -28.34132)
				)
			)
		)
	)
	(footprint ""
		(layer "B.Cu")
		(at 473.084906 -19.085052 90)
		(property "Reference" "C8F3"
			(at 0 0 90)
			(layer "B.SilkS")
			(hide yes)
			(effects
				(font
					(size 1.27 1.27)
				)
				(justify mirror)
			)
		)
		(property "Value" ""
			(at 0 0 90)
			(layer "B.Fab")
			(effects
				(font
					(size 1.27 1.27)
				)
				(justify mirror)
			)
		)
		(duplicate_pad_numbers_are_jumpers no)
		(fp_rect
			(start -0.3048 -0.1016)
			(end 0.3048 0.9906)
			(stroke
				(width 0)
				(type default)
			)
			(fill no)
			(layer "B.CrtYd")
		)
		(fp_line
			(start 0.3048 -0.1016)
			(end 0.3048 0.9906)
			(stroke
				(width 0.1)
				(type default)
			)
			(layer "B.Fab")
		)
		(fp_line
			(start -0.3048 -0.1016)
			(end 0.3048 -0.1016)
			(stroke
				(width 0.1)
				(type default)
			)
			(layer "B.Fab")
		)
		(fp_line
			(start 0.3048 0.9906)
			(end -0.3048 0.9906)
			(stroke
				(width 0.1)
				(type default)
			)
			(layer "B.Fab")
		)
		(fp_line
			(start -0.3048 0.9906)
			(end -0.3048 -0.1016)
			(stroke
				(width 0.1)
				(type default)
			)
			(layer "B.Fab")
		)
		(pad "1" smd rect
			(at 0 0 270)
			(size 0.508 0.508)
			(layers "B.Cu" "B.Mask" "B.Paste")
			(net "VR_P3V3_STBY_PHASE")
		)
		(pad "2" smd rect
			(at 0 0.889 270)
			(size 0.508 0.508)
			(layers "B.Cu" "B.Mask" "B.Paste")
			(net "VR_P3V3_STBY_SNUB")
		)
		(zone
			(layer "B.Cu")
			(hatch none 0.5)
			(connect_pads
				(clearance 0)
			)
			(min_thickness 0.25)
			(keepout
				(tracks not_allowed)
				(vias allowed)
				(pads allowed)
				(copperpour not_allowed)
				(footprints allowed)
			)
			(placement
				(enabled no)
				(sheetname "")
			)
			(fill
				(thermal_gap 0.5)
				(thermal_bridge_width 0.5)
				(island_removal_mode 0)
			)
			(polygon
				(pts
					(xy 473.338906 -18.831052) (xy 473.719906 -18.831052) (xy 473.719906 -19.339052) (xy 473.338906 -19.339052)
				)
			)
		)
		(zone
			(layer "B.Cu")
			(hatch none 0.5)
			(connect_pads
				(clearance 0)
			)
			(min_thickness 0.25)
			(keepout
				(tracks allowed)
				(vias not_allowed)
				(pads allowed)
				(copperpour not_allowed)
				(footprints allowed)
			)
			(placement
				(enabled no)
				(sheetname "")
			)
			(fill
				(thermal_gap 0.5)
				(thermal_bridge_width 0.5)
				(island_removal_mode 0)
			)
			(polygon
				(pts
					(xy 473.338906 -18.831052) (xy 473.719906 -18.831052) (xy 473.719906 -19.339052) (xy 473.338906 -19.339052)
				)
			)
		)
	)
	(footprint ""
		(layer "B.Cu")
		(at 449.6435 -24.003 90)
		(property "Reference" "R6W22"
			(at 0.8382 -0.67818 90)
			(unlocked yes)
			(layer "B.SilkS")
			(effects
				(font
					(size 0.4064 0.254)
					(thickness 0.1524)
				)
				(justify left mirror)
			)
		)
		(property "Value" ""
			(at 0 0 90)
			(layer "B.Fab")
			(effects
				(font
					(size 1.27 1.27)
				)
				(justify mirror)
			)
		)
		(duplicate_pad_numbers_are_jumpers no)
		(fp_poly
			(pts
				(xy 0.2794 -0.1016) (xy -0.2794 -0.1016) (xy -0.2794 0.9906) (xy 0.2794 0.9906)
			)
			(stroke
				(width 0)
				(type default)
			)
			(fill no)
			(layer "B.CrtYd")
		)
		(fp_line
			(start 0.2794 -0.1016)
			(end 0.2794 0.9906)
			(stroke
				(width 0.1)
				(type default)
			)
			(layer "B.Fab")
		)
		(fp_line
			(start -0.2794 -0.1016)
			(end 0.2794 -0.1016)
			(stroke
				(width 0.1)
				(type default)
			)
			(layer "B.Fab")
		)
		(fp_line
			(start 0.2794 0.9906)
			(end -0.2794 0.9906)
			(stroke
				(width 0.1)
				(type default)
			)
			(layer "B.Fab")
		)
		(fp_line
			(start -0.2794 0.9906)
			(end -0.2794 -0.1016)
			(stroke
				(width 0.1)
				(type default)
			)
			(layer "B.Fab")
		)
		(pad "1" smd rect
			(at 0 0 270)
			(size 0.508 0.508)
			(layers "B.Cu" "B.Mask" "B.Paste")
			(net "SMB_HOST_STBY_LVC3_SCL")
		)
		(pad "2" smd rect
			(at 0 0.889 270)
			(size 0.508 0.508)
			(layers "B.Cu" "B.Mask" "B.Paste")
			(net "SMB_HOST_STBY_LVC3_SCL_R3")
		)
		(zone
			(layer "B.Cu")
			(hatch none 0.5)
			(connect_pads
				(clearance 0)
			)
			(min_thickness 0.25)
			(keepout
				(tracks allowed)
				(vias not_allowed)
				(pads allowed)
				(copperpour not_allowed)
				(footprints allowed)
			)
			(placement
				(enabled no)
				(sheetname "")
			)
			(fill
				(thermal_gap 0.5)
				(thermal_bridge_width 0.5)
				(island_removal_mode 0)
			)
			(polygon
				(pts
					(xy 449.8975 -24.257) (xy 449.8975 -23.749) (xy 450.2785 -23.749) (xy 450.2785 -24.257)
				)
			)
		)
		(zone
			(layer "B.Cu")
			(hatch none 0.5)
			(connect_pads
				(clearance 0)
			)
			(min_thickness 0.25)
			(keepout
				(tracks not_allowed)
				(vias allowed)
				(pads allowed)
				(copperpour not_allowed)
				(footprints allowed)
			)
			(placement
				(enabled no)
				(sheetname "")
			)
			(fill
				(thermal_gap 0.5)
				(thermal_bridge_width 0.5)
				(island_removal_mode 0)
			)
			(polygon
				(pts
					(xy 450.2785 -24.257) (xy 450.2785 -23.749) (xy 449.8975 -23.749) (xy 449.8975 -24.257)
				)
			)
		)
	)
	(footprint ""
		(layer "B.Cu")
		(at 382.93675 -106.25455)
		(property "Reference" "C3N20"
			(at 0 0 0)
			(layer "B.SilkS")
			(hide yes)
			(effects
				(font
					(size 1.27 1.27)
				)
				(justify mirror)
			)
		)
		(property "Value" ""
			(at 0 0 0)
			(layer "B.Fab")
			(effects
				(font
					(size 1.27 1.27)
				)
				(justify mirror)
			)
		)
		(duplicate_pad_numbers_are_jumpers no)
		(fp_rect
			(start 0.2794 0.9144)
			(end -0.2794 -0.1143)
			(stroke
				(width 0)
				(type default)
			)
			(fill no)
			(layer "B.CrtYd")
		)
		(fp_line
			(start -0.2794 -0.1143)
			(end -0.2794 0.9144)
			(stroke
				(width 0.1)
				(type default)
			)
			(layer "B.Fab")
		)
		(fp_line
			(start -0.2794 0.9144)
			(end 0.2794 0.9144)
			(stroke
				(width 0.1)
				(type default)
			)
			(layer "B.Fab")
		)
		(fp_line
			(start 0.2794 -0.1143)
			(end -0.2794 -0.1143)
			(stroke
				(width 0.1)
				(type default)
			)
			(layer "B.Fab")
		)
		(fp_line
			(start 0.2794 0.9144)
			(end 0.2794 -0.1143)
			(stroke
				(width 0.1)
				(type default)
			)
			(layer "B.Fab")
		)
		(pad "1" smd custom
			(at 0 0 270)
			(size 0.10414 0.10414)
			(layers "B.Cu" "B.Mask" "B.Paste")
			(net "PVNN_PCH_STBY")
			(options
				(clearance outline)
				(anchor circle)
			)
			(primitives
				(gr_poly
					(pts
						(xy -0.20828 -0.08636) (xy -0.20828 0.08636) (xy -0.08636 0.20828) (xy 0.086614 0.20828) (xy 0.20828 0.086614)
						(xy 0.20828 -0.08636) (xy 0.08636 -0.20828) (xy -0.08636 -0.20828)
					)
					(width 0)
					(fill yes)
				)
			)
		)
		(pad "2" smd custom
			(at 0 0.8001 270)
			(size 0.10414 0.10414)
			(layers "B.Cu" "B.Mask" "B.Paste")
			(net "GND")
			(options
				(clearance outline)
				(anchor circle)
			)
			(primitives
				(gr_poly
					(pts
						(xy -0.20828 -0.08636) (xy -0.20828 0.08636) (xy -0.08636 0.20828) (xy 0.086614 0.20828) (xy 0.20828 0.086614)
						(xy 0.20828 -0.08636) (xy 0.08636 -0.20828) (xy -0.08636 -0.20828)
					)
					(width 0)
					(fill yes)
				)
			)
		)
		(zone
			(layer "B.Cu")
			(hatch none 0.5)
			(connect_pads
				(clearance 0)
			)
			(min_thickness 0.25)
			(keepout
				(tracks not_allowed)
				(vias allowed)
				(pads allowed)
				(copperpour not_allowed)
				(footprints allowed)
			)
			(placement
				(enabled no)
				(sheetname "")
			)
			(fill
				(thermal_gap 0.5)
				(thermal_bridge_width 0.5)
				(island_removal_mode 0)
			)
			(polygon
				(pts
					(xy 383.02438 -106.045) (xy 383.02438 -105.664) (xy 382.84912 -105.664) (xy 382.848866 -106.045)
				)
			)
		)
		(zone
			(layer "B.Cu")
			(hatch none 0.5)
			(connect_pads
				(clearance 0)
			)
			(min_thickness 0.25)
			(keepout
				(tracks allowed)
				(vias not_allowed)
				(pads allowed)
				(copperpour not_allowed)
				(footprints allowed)
			)
			(placement
				(enabled no)
				(sheetname "")
			)
			(fill
				(thermal_gap 0.5)
				(thermal_bridge_width 0.5)
				(island_removal_mode 0)
			)
			(polygon
				(pts
					(xy 383.02438 -106.045) (xy 383.02438 -105.664) (xy 382.84912 -105.664) (xy 382.848866 -106.045)
				)
			)
		)
	)
	(footprint ""
		(layer "B.Cu")
		(at 410.3624 -14.097 90)
		(property "Reference" "U2R1"
			(at 0 0 90)
			(layer "B.SilkS")
			(hide yes)
			(effects
				(font
					(size 1.27 1.27)
				)
				(justify mirror)
			)
		)
		(property "Value" "*"
			(at 2.3622 -8.3185 90)
			(unlocked yes)
			(layer "B.Fab")
			(hide yes)
			(effects
				(font
					(size 1.27 1.016)
					(thickness 0.1524)
				)
				(justify mirror)
			)
		)
		(property "Device Type" "TC7PZ14FU-GP_DISCRET-GA1-TC7PZA"
			(at 2.3622 -10.2235 90)
			(unlocked yes)
			(layer "B.Fab")
			(hide yes)
			(effects
				(font
					(size 1.27 1.016)
					(thickness 0.1524)
				)
				(justify mirror)
			)
		)
		(duplicate_pad_numbers_are_jumpers no)
		(fp_line
			(start 1.4478 -1.7018)
			(end 1.4478 1.7018)
			(stroke
				(width 0.1524)
				(type default)
			)
			(layer "B.SilkS")
		)
		(fp_line
			(start -1.4478 -1.7018)
			(end 1.4478 -1.7018)
			(stroke
				(width 0.1524)
				(type default)
			)
			(layer "B.SilkS")
		)
		(fp_line
			(start 1.4478 1.7018)
			(end -1.4478 1.7018)
			(stroke
				(width 0.1524)
				(type default)
			)
			(layer "B.SilkS")
		)
		(fp_line
			(start -1.4478 1.7018)
			(end -1.4478 -1.7018)
			(stroke
				(width 0.1524)
				(type default)
			)
			(layer "B.SilkS")
		)
		(fp_line
			(start 1.5494 1.7907)
			(end 1.5494 0.8255)
			(stroke
				(width 0.3302)
				(type default)
			)
			(layer "B.SilkS")
		)
		(fp_line
			(start 0.5715 1.7907)
			(end 1.5494 1.7907)
			(stroke
				(width 0.3302)
				(type default)
			)
			(layer "B.SilkS")
		)
		(fp_poly
			(pts
				(xy 0.6604 1.7272) (xy 1.016 2.0828) (xy 0.3048 2.0828)
			)
			(stroke
				(width 0)
				(type default)
			)
			(fill yes)
			(layer "B.SilkS")
		)
		(fp_poly
			(pts
				(xy 1.524 -1.778) (xy -1.524 -1.778) (xy -1.524 1.778) (xy 1.524 1.778)
			)
			(stroke
				(width 0)
				(type default)
			)
			(fill no)
			(layer "B.CrtYd")
		)
		(fp_poly
			(pts
				(xy 1.524 -1.778) (xy -1.524 -1.778) (xy -1.524 1.778) (xy 1.524 1.778)
			)
			(stroke
				(width 0)
				(type default)
			)
			(fill no)
			(layer "B.Fab")
		)
		(pad "1" smd rect
			(at 0.65024 0.9398 270)
			(size 0.4064 1.016)
			(layers "B.Cu" "B.Mask" "B.Paste")
			(net "FP_NMI_BTN")
		)
		(pad "2" smd rect
			(at 0 0.9398 270)
			(size 0.4064 1.016)
			(layers "B.Cu" "B.Mask" "B.Paste")
			(net "GND")
		)
		(pad "3" smd rect
			(at -0.65024 0.9398 270)
			(size 0.4064 1.016)
			(layers "B.Cu" "B.Mask" "B.Paste")
			(net "FP_NMI_BTN_OUT_N")
		)
		(pad "4" smd rect
			(at -0.65024 -0.9398 270)
			(size 0.4064 1.016)
			(layers "B.Cu" "B.Mask" "B.Paste")
			(net "FP_NMI_BTN")
		)
		(pad "5" smd rect
			(at 0 -0.9398 270)
			(size 0.4064 1.016)
			(layers "B.Cu" "B.Mask" "B.Paste")
			(net "P3V3_STBY")
		)
		(pad "6" smd rect
			(at 0.65024 -0.9398 270)
			(size 0.4064 1.016)
			(layers "B.Cu" "B.Mask" "B.Paste")
			(net "FP_NMI_BTN_R_N")
		)
	)
	(footprint ""
		(layer "B.Cu")
		(at 253.392432 -140.208 90)
		(property "Reference" "C5G67"
			(at -1.14681 0.76708 180)
			(unlocked yes)
			(layer "B.SilkS")
			(effects
				(font
					(size 0.7874 0.5842)
					(thickness 0.1524)
				)
				(justify mirror)
			)
		)
		(property "Value" ""
			(at 0 0 90)
			(layer "B.Fab")
			(effects
				(font
					(size 1.27 1.27)
				)
				(justify mirror)
			)
		)
		(duplicate_pad_numbers_are_jumpers no)
		(fp_rect
			(start -0.4953 -0.2032)
			(end 0.4953 1.6002)
			(stroke
				(width 0)
				(type default)
			)
			(fill no)
			(layer "B.CrtYd")
		)
		(fp_line
			(start 0.4953 -0.2032)
			(end -0.4953 -0.2032)
			(stroke
				(width 0.1)
				(type default)
			)
			(layer "B.Fab")
		)
		(fp_line
			(start -0.4953 -0.2032)
			(end -0.4953 1.6002)
			(stroke
				(width 0.1)
				(type default)
			)
			(layer "B.Fab")
		)
		(fp_line
			(start 0.4953 1.6002)
			(end 0.4953 -0.2032)
			(stroke
				(width 0.1)
				(type default)
			)
			(layer "B.Fab")
		)
		(fp_line
			(start -0.4953 1.6002)
			(end 0.4953 1.6002)
			(stroke
				(width 0.1)
				(type default)
			)
			(layer "B.Fab")
		)
		(pad "1" smd rect
			(at 0 0 270)
			(size 0.762 0.889)
			(layers "B.Cu" "B.Mask" "B.Paste")
			(net "PVDDQ_DEF")
		)
		(pad "2" smd rect
			(at 0 1.397 270)
			(size 0.762 0.889)
			(layers "B.Cu" "B.Mask" "B.Paste")
			(net "GND")
		)
		(zone
			(layer "B.Cu")
			(hatch none 0.5)
			(connect_pads
				(clearance 0)
			)
			(min_thickness 0.25)
			(keepout
				(tracks not_allowed)
				(vias allowed)
				(pads allowed)
				(copperpour not_allowed)
				(footprints allowed)
			)
			(placement
				(enabled no)
				(sheetname "")
			)
			(fill
				(thermal_gap 0.5)
				(thermal_bridge_width 0.5)
				(island_removal_mode 0)
			)
			(polygon
				(pts
					(xy 253.836932 -139.827) (xy 254.344932 -139.827) (xy 254.344932 -140.589) (xy 253.836932 -140.589)
				)
			)
		)
	)
	(footprint ""
		(layer "B.Cu")
		(at 337.537806 -60.368434)
		(property "Reference" "R2U17"
			(at 0 0 0)
			(layer "B.SilkS")
			(hide yes)
			(effects
				(font
					(size 1.27 1.27)
				)
				(justify mirror)
			)
		)
		(property "Value" ""
			(at 0 0 0)
			(layer "B.Fab")
			(effects
				(font
					(size 1.27 1.27)
				)
				(justify mirror)
			)
		)
		(duplicate_pad_numbers_are_jumpers no)
		(fp_poly
			(pts
				(xy 0.2794 -0.1016) (xy -0.2794 -0.1016) (xy -0.2794 0.9906) (xy 0.2794 0.9906)
			)
			(stroke
				(width 0)
				(type default)
			)
			(fill no)
			(layer "B.CrtYd")
		)
		(fp_line
			(start -0.2794 -0.1016)
			(end 0.2794 -0.1016)
			(stroke
				(width 0.1)
				(type default)
			)
			(layer "B.Fab")
		)
		(fp_line
			(start -0.2794 0.9906)
			(end -0.2794 -0.1016)
			(stroke
				(width 0.1)
				(type default)
			)
			(layer "B.Fab")
		)
		(fp_line
			(start 0.2794 -0.1016)
			(end 0.2794 0.9906)
			(stroke
				(width 0.1)
				(type default)
			)
			(layer "B.Fab")
		)
		(fp_line
			(start 0.2794 0.9906)
			(end -0.2794 0.9906)
			(stroke
				(width 0.1)
				(type default)
			)
			(layer "B.Fab")
		)
		(pad "1" smd rect
			(at 0 0 180)
			(size 0.508 0.508)
			(layers "B.Cu" "B.Mask" "B.Paste")
			(net "P3E_CPU0_PE1_SS_RXN<1>")
		)
		(pad "2" smd rect
			(at 0 0.889 180)
			(size 0.508 0.508)
			(layers "B.Cu" "B.Mask" "B.Paste")
			(net "P3E_CPU0_PE1_SS_R_RXN<1>")
		)
		(zone
			(layer "B.Cu")
			(hatch none 0.5)
			(connect_pads
				(clearance 0)
			)
			(min_thickness 0.25)
			(keepout
				(tracks allowed)
				(vias not_allowed)
				(pads allowed)
				(copperpour not_allowed)
				(footprints allowed)
			)
			(placement
				(enabled no)
				(sheetname "")
			)
			(fill
				(thermal_gap 0.5)
				(thermal_bridge_width 0.5)
				(island_removal_mode 0)
			)
			(polygon
				(pts
					(xy 337.791806 -60.114434) (xy 337.283806 -60.114434) (xy 337.283806 -59.733434) (xy 337.791806 -59.733434)
				)
			)
		)
		(zone
			(layer "B.Cu")
			(hatch none 0.5)
			(connect_pads
				(clearance 0)
			)
			(min_thickness 0.25)
			(keepout
				(tracks not_allowed)
				(vias allowed)
				(pads allowed)
				(copperpour not_allowed)
				(footprints allowed)
			)
			(placement
				(enabled no)
				(sheetname "")
			)
			(fill
				(thermal_gap 0.5)
				(thermal_bridge_width 0.5)
				(island_removal_mode 0)
			)
			(polygon
				(pts
					(xy 337.791806 -59.733434) (xy 337.283806 -59.733434) (xy 337.283806 -60.114434) (xy 337.791806 -60.114434)
				)
			)
		)
	)
	(footprint ""
		(layer "B.Cu")
		(at 19.05 -45.72)
		(property "Reference" "C9R13"
			(at 0 0 0)
			(layer "B.SilkS")
			(hide yes)
			(effects
				(font
					(size 1.27 1.27)
				)
				(justify mirror)
			)
		)
		(property "Value" ""
			(at 0 0 0)
			(layer "B.Fab")
			(effects
				(font
					(size 1.27 1.27)
				)
				(justify mirror)
			)
		)
		(duplicate_pad_numbers_are_jumpers no)
		(fp_poly
			(pts
				(xy -0.3048 -0.1016) (xy -0.3048 0.9906) (xy 0.3048 0.9906) (xy 0.3048 -0.1016)
			)
			(stroke
				(width 0)
				(type default)
			)
			(fill no)
			(layer "B.CrtYd")
		)
		(fp_line
			(start -0.3048 -0.1016)
			(end 0.3048 -0.1016)
			(stroke
				(width 0.1)
				(type default)
			)
			(layer "B.Fab")
		)
		(fp_line
			(start -0.3048 0.9906)
			(end -0.3048 -0.1016)
			(stroke
				(width 0.1)
				(type default)
			)
			(layer "B.Fab")
		)
		(fp_line
			(start 0.3048 -0.1016)
			(end 0.3048 0.9906)
			(stroke
				(width 0.1)
				(type default)
			)
			(layer "B.Fab")
		)
		(fp_line
			(start 0.3048 0.9906)
			(end -0.3048 0.9906)
			(stroke
				(width 0.1)
				(type default)
			)
			(layer "B.Fab")
		)
		(pad "1" smd rect
			(at 0 0 180)
			(size 0.508 0.508)
			(layers "B.Cu" "B.Mask" "B.Paste")
			(net "P3V3_STBY")
		)
		(pad "2" smd rect
			(at 0 0.889 180)
			(size 0.508 0.508)
			(layers "B.Cu" "B.Mask" "B.Paste")
			(net "GND")
		)
		(zone
			(layer "B.Cu")
			(hatch none 0.5)
			(connect_pads
				(clearance 0)
			)
			(min_thickness 0.25)
			(keepout
				(tracks allowed)
				(vias not_allowed)
				(pads allowed)
				(copperpour not_allowed)
				(footprints allowed)
			)
			(placement
				(enabled no)
				(sheetname "")
			)
			(fill
				(thermal_gap 0.5)
				(thermal_bridge_width 0.5)
				(island_removal_mode 0)
			)
			(polygon
				(pts
					(xy 19.304 -45.466) (xy 18.796 -45.466) (xy 18.796 -45.085) (xy 19.304 -45.085)
				)
			)
		)
		(zone
			(layer "B.Cu")
			(hatch none 0.5)
			(connect_pads
				(clearance 0)
			)
			(min_thickness 0.25)
			(keepout
				(tracks not_allowed)
				(vias allowed)
				(pads allowed)
				(copperpour not_allowed)
				(footprints allowed)
			)
			(placement
				(enabled no)
				(sheetname "")
			)
			(fill
				(thermal_gap 0.5)
				(thermal_bridge_width 0.5)
				(island_removal_mode 0)
			)
			(polygon
				(pts
					(xy 19.304 -45.085) (xy 18.796 -45.085) (xy 18.796 -45.466) (xy 19.304 -45.466)
				)
			)
		)
	)
	(footprint ""
		(layer "B.Cu")
		(at 438.6199 -141.097 180)
		(property "Reference" "R25W174"
			(at 0.8382 -0.67818 180)
			(unlocked yes)
			(layer "B.SilkS")
			(effects
				(font
					(size 0.4064 0.254)
					(thickness 0.1524)
				)
				(justify left mirror)
			)
		)
		(property "Value" ""
			(at 0 0 0)
			(layer "B.Fab")
			(effects
				(font
					(size 1.27 1.27)
				)
				(justify mirror)
			)
		)
		(duplicate_pad_numbers_are_jumpers no)
		(fp_poly
			(pts
				(xy 0.2794 -0.1016) (xy -0.2794 -0.1016) (xy -0.2794 0.9906) (xy 0.2794 0.9906)
			)
			(stroke
				(width 0)
				(type default)
			)
			(fill no)
			(layer "B.CrtYd")
		)
		(fp_line
			(start 0.2794 0.9906)
			(end -0.2794 0.9906)
			(stroke
				(width 0.1)
				(type default)
			)
			(layer "B.Fab")
		)
		(fp_line
			(start 0.2794 -0.1016)
			(end 0.2794 0.9906)
			(stroke
				(width 0.1)
				(type default)
			)
			(layer "B.Fab")
		)
		(fp_line
			(start -0.2794 0.9906)
			(end -0.2794 -0.1016)
			(stroke
				(width 0.1)
				(type default)
			)
			(layer "B.Fab")
		)
		(fp_line
			(start -0.2794 -0.1016)
			(end 0.2794 -0.1016)
			(stroke
				(width 0.1)
				(type default)
			)
			(layer "B.Fab")
		)
		(pad "1" smd rect
			(at 0 0)
			(size 0.508 0.508)
			(layers "B.Cu" "B.Mask" "B.Paste")
			(net "P3V3_STBY")
		)
		(pad "2" smd rect
			(at 0 0.889)
			(size 0.508 0.508)
			(layers "B.Cu" "B.Mask" "B.Paste")
			(net "BMC_JTAG_SEL_N")
		)
		(zone
			(layer "B.Cu")
			(hatch none 0.5)
			(connect_pads
				(clearance 0)
			)
			(min_thickness 0.25)
			(keepout
				(tracks not_allowed)
				(vias allowed)
				(pads allowed)
				(copperpour not_allowed)
				(footprints allowed)
			)
			(placement
				(enabled no)
				(sheetname "")
			)
			(fill
				(thermal_gap 0.5)
				(thermal_bridge_width 0.5)
				(island_removal_mode 0)
			)
			(polygon
				(pts
					(xy 438.3659 -141.732) (xy 438.8739 -141.732) (xy 438.8739 -141.351) (xy 438.3659 -141.351)
				)
			)
		)
		(zone
			(layer "B.Cu")
			(hatch none 0.5)
			(connect_pads
				(clearance 0)
			)
			(min_thickness 0.25)
			(keepout
				(tracks allowed)
				(vias not_allowed)
				(pads allowed)
				(copperpour not_allowed)
				(footprints allowed)
			)
			(placement
				(enabled no)
				(sheetname "")
			)
			(fill
				(thermal_gap 0.5)
				(thermal_bridge_width 0.5)
				(island_removal_mode 0)
			)
			(polygon
				(pts
					(xy 438.3659 -141.351) (xy 438.8739 -141.351) (xy 438.8739 -141.732) (xy 438.3659 -141.732)
				)
			)
		)
	)
	(footprint ""
		(layer "B.Cu")
		(at 8.0264 -132.3594)
		(property "Reference" "R9M3"
			(at 0 0 0)
			(layer "B.SilkS")
			(hide yes)
			(effects
				(font
					(size 1.27 1.27)
				)
				(justify mirror)
			)
		)
		(property "Value" ""
			(at 0 0 0)
			(layer "B.Fab")
			(effects
				(font
					(size 1.27 1.27)
				)
				(justify mirror)
			)
		)
		(duplicate_pad_numbers_are_jumpers no)
		(fp_rect
			(start -0.2794 0.9906)
			(end 0.2794 -0.1016)
			(stroke
				(width 0)
				(type default)
			)
			(fill no)
			(layer "B.CrtYd")
		)
		(fp_line
			(start -0.2794 -0.1016)
			(end 0.2794 -0.1016)
			(stroke
				(width 0.1)
				(type default)
			)
			(layer "B.Fab")
		)
		(fp_line
			(start -0.2794 0.9906)
			(end -0.2794 -0.1016)
			(stroke
				(width 0.1)
				(type default)
			)
			(layer "B.Fab")
		)
		(fp_line
			(start 0.2794 -0.1016)
			(end 0.2794 0.9906)
			(stroke
				(width 0.1)
				(type default)
			)
			(layer "B.Fab")
		)
		(fp_line
			(start 0.2794 0.9906)
			(end -0.2794 0.9906)
			(stroke
				(width 0.1)
				(type default)
			)
			(layer "B.Fab")
		)
		(pad "1" smd rect
			(at 0 0 180)
			(size 0.508 0.508)
			(layers "B.Cu" "B.Mask" "B.Paste")
			(net "P3V3_STBY")
		)
		(pad "2" smd rect
			(at 0 0.889 180)
			(size 0.508 0.508)
			(layers "B.Cu" "B.Mask" "B.Paste")
			(net "VR_PVDDQ_KLM_VDD")
		)
		(zone
			(layer "B.Cu")
			(hatch none 0.5)
			(connect_pads
				(clearance 0)
			)
			(min_thickness 0.25)
			(keepout
				(tracks not_allowed)
				(vias allowed)
				(pads allowed)
				(copperpour not_allowed)
				(footprints allowed)
			)
			(placement
				(enabled no)
				(sheetname "")
			)
			(fill
				(thermal_gap 0.5)
				(thermal_bridge_width 0.5)
				(island_removal_mode 0)
			)
			(polygon
				(pts
					(xy 7.7724 -131.7244) (xy 8.2804 -131.7244) (xy 8.2804 -132.1054) (xy 7.7724 -132.1054)
				)
			)
		)
		(zone
			(layer "B.Cu")
			(hatch none 0.5)
			(connect_pads
				(clearance 0)
			)
			(min_thickness 0.25)
			(keepout
				(tracks allowed)
				(vias not_allowed)
				(pads allowed)
				(copperpour not_allowed)
				(footprints allowed)
			)
			(placement
				(enabled no)
				(sheetname "")
			)
			(fill
				(thermal_gap 0.5)
				(thermal_bridge_width 0.5)
				(island_removal_mode 0)
			)
			(polygon
				(pts
					(xy 7.7724 -131.7244) (xy 8.2804 -131.7244) (xy 8.2804 -132.1054) (xy 7.7724 -132.1054)
				)
			)
		)
	)
	(footprint ""
		(layer "B.Cu")
		(at 396.216886 -16.438372 180)
		(property "Reference" "R32W6"
			(at 0.8382 -0.67818 180)
			(unlocked yes)
			(layer "B.SilkS")
			(effects
				(font
					(size 0.4064 0.254)
					(thickness 0.1524)
				)
				(justify left mirror)
			)
		)
		(property "Value" ""
			(at 0 0 0)
			(layer "B.Fab")
			(effects
				(font
					(size 1.27 1.27)
				)
				(justify mirror)
			)
		)
		(duplicate_pad_numbers_are_jumpers no)
		(fp_poly
			(pts
				(xy 0.2794 -0.1016) (xy -0.2794 -0.1016) (xy -0.2794 0.9906) (xy 0.2794 0.9906)
			)
			(stroke
				(width 0)
				(type default)
			)
			(fill no)
			(layer "B.CrtYd")
		)
		(fp_line
			(start 0.2794 0.9906)
			(end -0.2794 0.9906)
			(stroke
				(width 0.1)
				(type default)
			)
			(layer "B.Fab")
		)
		(fp_line
			(start 0.2794 -0.1016)
			(end 0.2794 0.9906)
			(stroke
				(width 0.1)
				(type default)
			)
			(layer "B.Fab")
		)
		(fp_line
			(start -0.2794 0.9906)
			(end -0.2794 -0.1016)
			(stroke
				(width 0.1)
				(type default)
			)
			(layer "B.Fab")
		)
		(fp_line
			(start -0.2794 -0.1016)
			(end 0.2794 -0.1016)
			(stroke
				(width 0.1)
				(type default)
			)
			(layer "B.Fab")
		)
		(pad "1" smd rect
			(at 0 0)
			(size 0.508 0.508)
			(layers "B.Cu" "B.Mask" "B.Paste")
			(net "P1V8_M2")
		)
		(pad "2" smd rect
			(at 0 0.889)
			(size 0.508 0.508)
			(layers "B.Cu" "B.Mask" "B.Paste")
			(net "SMB_M2_SDA")
		)
		(zone
			(layer "B.Cu")
			(hatch none 0.5)
			(connect_pads
				(clearance 0)
			)
			(min_thickness 0.25)
			(keepout
				(tracks not_allowed)
				(vias allowed)
				(pads allowed)
				(copperpour not_allowed)
				(footprints allowed)
			)
			(placement
				(enabled no)
				(sheetname "")
			)
			(fill
				(thermal_gap 0.5)
				(thermal_bridge_width 0.5)
				(island_removal_mode 0)
			)
			(polygon
				(pts
					(xy 395.962886 -17.073372) (xy 396.470886 -17.073372) (xy 396.470886 -16.692372) (xy 395.962886 -16.692372)
				)
			)
		)
		(zone
			(layer "B.Cu")
			(hatch none 0.5)
			(connect_pads
				(clearance 0)
			)
			(min_thickness 0.25)
			(keepout
				(tracks allowed)
				(vias not_allowed)
				(pads allowed)
				(copperpour not_allowed)
				(footprints allowed)
			)
			(placement
				(enabled no)
				(sheetname "")
			)
			(fill
				(thermal_gap 0.5)
				(thermal_bridge_width 0.5)
				(island_removal_mode 0)
			)
			(polygon
				(pts
					(xy 395.962886 -16.692372) (xy 396.470886 -16.692372) (xy 396.470886 -17.073372) (xy 395.962886 -17.073372)
				)
			)
		)
	)
	(footprint ""
		(layer "B.Cu")
		(at 104.902254 -79.60614 180)
		(property "Reference" "C8P9"
			(at 0 0 0)
			(layer "B.SilkS")
			(hide yes)
			(effects
				(font
					(size 1.27 1.27)
				)
				(justify mirror)
			)
		)
		(property "Value" ""
			(at 0 0 0)
			(layer "B.Fab")
			(effects
				(font
					(size 1.27 1.27)
				)
				(justify mirror)
			)
		)
		(duplicate_pad_numbers_are_jumpers no)
		(fp_poly
			(pts
				(xy 0.7239 -0.2159) (xy -0.7239 -0.2159) (xy -0.7239 1.9939) (xy 0.7239 1.9939)
			)
			(stroke
				(width 0)
				(type default)
			)
			(fill no)
			(layer "B.CrtYd")
		)
		(fp_line
			(start 0.7239 1.9939)
			(end -0.7239 1.9939)
			(stroke
				(width 0.1)
				(type default)
			)
			(layer "B.Fab")
		)
		(fp_line
			(start 0.7239 -0.2159)
			(end 0.7239 1.9939)
			(stroke
				(width 0.1)
				(type default)
			)
			(layer "B.Fab")
		)
		(fp_line
			(start -0.7239 1.9939)
			(end -0.7239 -0.2159)
			(stroke
				(width 0.1)
				(type default)
			)
			(layer "B.Fab")
		)
		(fp_line
			(start -0.7239 -0.2159)
			(end 0.7239 -0.2159)
			(stroke
				(width 0.1)
				(type default)
			)
			(layer "B.Fab")
		)
		(pad "1" smd rect
			(at 0 0)
			(size 1.27 1.016)
			(layers "B.Cu" "B.Mask" "B.Paste")
			(net "PVCCMCP_CPU1")
		)
		(pad "2" smd rect
			(at 0 1.778)
			(size 1.27 1.016)
			(layers "B.Cu" "B.Mask" "B.Paste")
			(net "GND")
		)
		(zone
			(layer "B.Cu")
			(hatch none 0.5)
			(connect_pads
				(clearance 0)
			)
			(min_thickness 0.25)
			(keepout
				(tracks not_allowed)
				(vias allowed)
				(pads allowed)
				(copperpour not_allowed)
				(footprints allowed)
			)
			(placement
				(enabled no)
				(sheetname "")
			)
			(fill
				(thermal_gap 0.5)
				(thermal_bridge_width 0.5)
				(island_removal_mode 0)
			)
			(polygon
				(pts
					(xy 104.267254 -80.11414) (xy 105.537254 -80.11414) (xy 105.537254 -80.87614) (xy 104.267254 -80.87614)
				)
			)
		)
	)
	(footprint ""
		(layer "B.Cu")
		(at 63.2968 -92.1512 90)
		(property "Reference" "R8N2"
			(at 0 0 90)
			(layer "B.SilkS")
			(hide yes)
			(effects
				(font
					(size 1.27 1.27)
				)
				(justify mirror)
			)
		)
		(property "Value" ""
			(at 0 0 90)
			(layer "B.Fab")
			(effects
				(font
					(size 1.27 1.27)
				)
				(justify mirror)
			)
		)
		(duplicate_pad_numbers_are_jumpers no)
		(fp_poly
			(pts
				(xy 0.2794 -0.1016) (xy -0.2794 -0.1016) (xy -0.2794 0.9906) (xy 0.2794 0.9906)
			)
			(stroke
				(width 0)
				(type default)
			)
			(fill no)
			(layer "B.CrtYd")
		)
		(fp_line
			(start 0.2794 -0.1016)
			(end 0.2794 0.9906)
			(stroke
				(width 0.1)
				(type default)
			)
			(layer "B.Fab")
		)
		(fp_line
			(start -0.2794 -0.1016)
			(end 0.2794 -0.1016)
			(stroke
				(width 0.1)
				(type default)
			)
			(layer "B.Fab")
		)
		(fp_line
			(start 0.2794 0.9906)
			(end -0.2794 0.9906)
			(stroke
				(width 0.1)
				(type default)
			)
			(layer "B.Fab")
		)
		(fp_line
			(start -0.2794 0.9906)
			(end -0.2794 -0.1016)
			(stroke
				(width 0.1)
				(type default)
			)
			(layer "B.Fab")
		)
		(pad "1" smd rect
			(at 0 0 270)
			(size 0.508 0.508)
			(layers "B.Cu" "B.Mask" "B.Paste")
			(net "P3V3_STBY")
		)
		(pad "2" smd rect
			(at 0 0.889 270)
			(size 0.508 0.508)
			(layers "B.Cu" "B.Mask" "B.Paste")
			(net "FM_CPU1_PKGID0")
		)
		(zone
			(layer "B.Cu")
			(hatch none 0.5)
			(connect_pads
				(clearance 0)
			)
			(min_thickness 0.25)
			(keepout
				(tracks allowed)
				(vias not_allowed)
				(pads allowed)
				(copperpour not_allowed)
				(footprints allowed)
			)
			(placement
				(enabled no)
				(sheetname "")
			)
			(fill
				(thermal_gap 0.5)
				(thermal_bridge_width 0.5)
				(island_removal_mode 0)
			)
			(polygon
				(pts
					(xy 63.5508 -92.4052) (xy 63.5508 -91.8972) (xy 63.9318 -91.8972) (xy 63.9318 -92.4052)
				)
			)
		)
		(zone
			(layer "B.Cu")
			(hatch none 0.5)
			(connect_pads
				(clearance 0)
			)
			(min_thickness 0.25)
			(keepout
				(tracks not_allowed)
				(vias allowed)
				(pads allowed)
				(copperpour not_allowed)
				(footprints allowed)
			)
			(placement
				(enabled no)
				(sheetname "")
			)
			(fill
				(thermal_gap 0.5)
				(thermal_bridge_width 0.5)
				(island_removal_mode 0)
			)
			(polygon
				(pts
					(xy 63.9318 -92.4052) (xy 63.9318 -91.8972) (xy 63.5508 -91.8972) (xy 63.5508 -92.4052)
				)
			)
		)
	)
	(footprint ""
		(layer "B.Cu")
		(at -3.102864 -11.551412 -90)
		(property "Reference" "C22W4"
			(at 0 0 90)
			(layer "B.SilkS")
			(hide yes)
			(effects
				(font
					(size 1.27 1.27)
				)
				(justify mirror)
			)
		)
		(property "Value" "*"
			(at 0.0762 -6.2357 270)
			(unlocked yes)
			(layer "B.Fab")
			(hide yes)
			(effects
				(font
					(size 1.27 1.016)
					(thickness 0.1524)
				)
				(justify mirror)
			)
		)
		(property "Device Type" "SC22U16V5MX-4-GP_SMD-BCG5-SC22A"
			(at 0.0762 -8.2677 270)
			(unlocked yes)
			(layer "B.Fab")
			(hide yes)
			(effects
				(font
					(size 1.27 1.016)
					(thickness 0.1524)
				)
				(justify mirror)
			)
		)
		(duplicate_pad_numbers_are_jumpers no)
		(fp_line
			(start -0.635 0)
			(end 0.635 0)
			(stroke
				(width 0.508)
				(type default)
			)
			(layer "B.SilkS")
		)
		(fp_rect
			(start 0.9652 1.778)
			(end -0.9652 -1.778)
			(stroke
				(width 0)
				(type default)
			)
			(fill no)
			(layer "B.CrtYd")
		)
		(fp_poly
			(pts
				(xy 0.9652 -1.778) (xy -0.9652 -1.778) (xy -0.9652 1.778) (xy 0.9652 1.778)
			)
			(stroke
				(width 0)
				(type default)
			)
			(fill no)
			(layer "B.Fab")
		)
		(pad "1" smd rect
			(at 0 -0.9652 90)
			(size 1.397 1.143)
			(layers "B.Cu" "B.Mask" "B.Paste")
			(net "VR_FET_SW_P12V_STBY_PVDDQ_GHJ")
		)
		(pad "2" smd rect
			(at 0 0.9652 90)
			(size 1.397 1.143)
			(layers "B.Cu" "B.Mask" "B.Paste")
			(net "GND")
		)
	)
	(footprint ""
		(layer "B.Cu")
		(at 422.656 -153.924 90)
		(property "Reference" "C2L6"
			(at 0 0 90)
			(layer "B.SilkS")
			(hide yes)
			(effects
				(font
					(size 1.27 1.27)
				)
				(justify mirror)
			)
		)
		(property "Value" ""
			(at 0 0 90)
			(layer "B.Fab")
			(effects
				(font
					(size 1.27 1.27)
				)
				(justify mirror)
			)
		)
		(duplicate_pad_numbers_are_jumpers no)
		(fp_poly
			(pts
				(xy -0.3048 -0.1016) (xy -0.3048 0.9906) (xy 0.3048 0.9906) (xy 0.3048 -0.1016)
			)
			(stroke
				(width 0)
				(type default)
			)
			(fill no)
			(layer "B.CrtYd")
		)
		(fp_line
			(start 0.3048 -0.1016)
			(end 0.3048 0.9906)
			(stroke
				(width 0.1)
				(type default)
			)
			(layer "B.Fab")
		)
		(fp_line
			(start -0.3048 -0.1016)
			(end 0.3048 -0.1016)
			(stroke
				(width 0.1)
				(type default)
			)
			(layer "B.Fab")
		)
		(fp_line
			(start 0.3048 0.9906)
			(end -0.3048 0.9906)
			(stroke
				(width 0.1)
				(type default)
			)
			(layer "B.Fab")
		)
		(fp_line
			(start -0.3048 0.9906)
			(end -0.3048 -0.1016)
			(stroke
				(width 0.1)
				(type default)
			)
			(layer "B.Fab")
		)
		(pad "1" smd rect
			(at 0 0 270)
			(size 0.508 0.508)
			(layers "B.Cu" "B.Mask" "B.Paste")
			(net "SATA6G_PCH_PCIE_UP_SATA_RXN<1>")
		)
		(pad "2" smd rect
			(at 0 0.889 270)
			(size 0.508 0.508)
			(layers "B.Cu" "B.Mask" "B.Paste")
			(net "SATA6G_P1_RX_C_DN")
		)
		(zone
			(layer "B.Cu")
			(hatch none 0.5)
			(connect_pads
				(clearance 0)
			)
			(min_thickness 0.25)
			(keepout
				(tracks allowed)
				(vias not_allowed)
				(pads allowed)
				(copperpour not_allowed)
				(footprints allowed)
			)
			(placement
				(enabled no)
				(sheetname "")
			)
			(fill
				(thermal_gap 0.5)
				(thermal_bridge_width 0.5)
				(island_removal_mode 0)
			)
			(polygon
				(pts
					(xy 422.91 -154.178) (xy 422.91 -153.67) (xy 423.291 -153.67) (xy 423.291 -154.178)
				)
			)
		)
		(zone
			(layer "B.Cu")
			(hatch none 0.5)
			(connect_pads
				(clearance 0)
			)
			(min_thickness 0.25)
			(keepout
				(tracks not_allowed)
				(vias allowed)
				(pads allowed)
				(copperpour not_allowed)
				(footprints allowed)
			)
			(placement
				(enabled no)
				(sheetname "")
			)
			(fill
				(thermal_gap 0.5)
				(thermal_bridge_width 0.5)
				(island_removal_mode 0)
			)
			(polygon
				(pts
					(xy 423.291 -154.178) (xy 423.291 -153.67) (xy 422.91 -153.67) (xy 422.91 -154.178)
				)
			)
		)
	)
	(footprint ""
		(layer "B.Cu")
		(at 452.5645 -19.177 -90)
		(property "Reference" "Q9W1"
			(at 0.229362 -1.2065 270)
			(unlocked yes)
			(layer "B.SilkS")
			(effects
				(font
					(size 0.4064 0.254)
					(thickness 0.1524)
				)
				(justify left mirror)
			)
		)
		(property "Value" ""
			(at 0 0 90)
			(layer "B.Fab")
			(effects
				(font
					(size 1.27 1.27)
				)
				(justify mirror)
			)
		)
		(duplicate_pad_numbers_are_jumpers no)
		(fp_line
			(start -1.778 2.4765)
			(end -1.778 1.5875)
			(stroke
				(width 0.1524)
				(type default)
			)
			(layer "B.SilkS")
		)
		(fp_line
			(start -0.9525 2.4765)
			(end -1.778 2.4765)
			(stroke
				(width 0.1524)
				(type default)
			)
			(layer "B.SilkS")
		)
		(fp_line
			(start -0.381 0.635)
			(end -0.381 1.27)
			(stroke
				(width 0.1524)
				(type default)
			)
			(layer "B.SilkS")
		)
		(fp_line
			(start -1.778 -0.5715)
			(end -1.778 0.3175)
			(stroke
				(width 0.1524)
				(type default)
			)
			(layer "B.SilkS")
		)
		(fp_line
			(start -0.9525 -0.5715)
			(end -1.778 -0.5715)
			(stroke
				(width 0.1524)
				(type default)
			)
			(layer "B.SilkS")
		)
		(fp_circle
			(center 0.9525 -0.9271)
			(end 0.9525 -1.0541)
			(stroke
				(width 0.254)
				(type default)
			)
			(fill no)
			(layer "B.SilkS")
		)
		(fp_poly
			(pts
				(xy -1.778 2.4765) (xy -0.381 2.4765) (xy -0.381 -0.5715) (xy -1.778 -0.5715)
			)
			(stroke
				(width 0)
				(type default)
			)
			(fill no)
			(layer "B.CrtYd")
		)
		(fp_line
			(start -1.778 2.4765)
			(end -1.778 -0.5715)
			(stroke
				(width 0.1)
				(type default)
			)
			(layer "B.Fab")
		)
		(fp_line
			(start -0.381 2.4765)
			(end -1.778 2.4765)
			(stroke
				(width 0.1)
				(type default)
			)
			(layer "B.Fab")
		)
		(fp_line
			(start -1.778 -0.5715)
			(end -0.381 -0.5715)
			(stroke
				(width 0.1)
				(type default)
			)
			(layer "B.Fab")
		)
		(fp_line
			(start -0.381 -0.5715)
			(end -0.381 2.4765)
			(stroke
				(width 0.1)
				(type default)
			)
			(layer "B.Fab")
		)
		(fp_circle
			(center 0.9525 -0.9271)
			(end 0.9525 -1.0541)
			(stroke
				(width 0.254)
				(type default)
			)
			(fill no)
			(layer "B.Fab")
		)
		(pad "1" smd rect
			(at 0 0 90)
			(size 1.143 0.508)
			(layers "B.Cu" "B.Mask" "B.Paste")
			(net "BMC_TPM_HW_C_RST")
		)
		(pad "2" smd rect
			(at 0 1.905 90)
			(size 1.143 0.508)
			(layers "B.Cu" "B.Mask" "B.Paste")
			(net "GND")
		)
		(pad "3" smd rect
			(at -2.159 0.9525 90)
			(size 1.143 0.508)
			(layers "B.Cu" "B.Mask" "B.Paste")
			(net "FM_TPM_PRES_RST_N")
		)
	)
	(footprint ""
		(layer "B.Cu")
		(at 404.3172 -30.861 90)
		(property "Reference" "R25W115"
			(at 0.8382 -0.67818 90)
			(unlocked yes)
			(layer "B.SilkS")
			(effects
				(font
					(size 0.4064 0.254)
					(thickness 0.1524)
				)
				(justify left mirror)
			)
		)
		(property "Value" ""
			(at 0 0 90)
			(layer "B.Fab")
			(effects
				(font
					(size 1.27 1.27)
				)
				(justify mirror)
			)
		)
		(duplicate_pad_numbers_are_jumpers no)
		(fp_poly
			(pts
				(xy 0.2794 -0.1016) (xy -0.2794 -0.1016) (xy -0.2794 0.9906) (xy 0.2794 0.9906)
			)
			(stroke
				(width 0)
				(type default)
			)
			(fill no)
			(layer "B.CrtYd")
		)
		(fp_line
			(start 0.2794 -0.1016)
			(end 0.2794 0.9906)
			(stroke
				(width 0.1)
				(type default)
			)
			(layer "B.Fab")
		)
		(fp_line
			(start -0.2794 -0.1016)
			(end 0.2794 -0.1016)
			(stroke
				(width 0.1)
				(type default)
			)
			(layer "B.Fab")
		)
		(fp_line
			(start 0.2794 0.9906)
			(end -0.2794 0.9906)
			(stroke
				(width 0.1)
				(type default)
			)
			(layer "B.Fab")
		)
		(fp_line
			(start -0.2794 0.9906)
			(end -0.2794 -0.1016)
			(stroke
				(width 0.1)
				(type default)
			)
			(layer "B.Fab")
		)
		(pad "1" smd rect
			(at 0 0 270)
			(size 0.508 0.508)
			(layers "B.Cu" "B.Mask" "B.Paste")
			(net "P3V3_STBY")
		)
		(pad "2" smd rect
			(at 0 0.889 270)
			(size 0.508 0.508)
			(layers "B.Cu" "B.Mask" "B.Paste")
			(net "TP_RGMII1TXD3_GPIOT5")
		)
		(zone
			(layer "B.Cu")
			(hatch none 0.5)
			(connect_pads
				(clearance 0)
			)
			(min_thickness 0.25)
			(keepout
				(tracks allowed)
				(vias not_allowed)
				(pads allowed)
				(copperpour not_allowed)
				(footprints allowed)
			)
			(placement
				(enabled no)
				(sheetname "")
			)
			(fill
				(thermal_gap 0.5)
				(thermal_bridge_width 0.5)
				(island_removal_mode 0)
			)
			(polygon
				(pts
					(xy 404.5712 -31.115) (xy 404.5712 -30.607) (xy 404.9522 -30.607) (xy 404.9522 -31.115)
				)
			)
		)
		(zone
			(layer "B.Cu")
			(hatch none 0.5)
			(connect_pads
				(clearance 0)
			)
			(min_thickness 0.25)
			(keepout
				(tracks not_allowed)
				(vias allowed)
				(pads allowed)
				(copperpour not_allowed)
				(footprints allowed)
			)
			(placement
				(enabled no)
				(sheetname "")
			)
			(fill
				(thermal_gap 0.5)
				(thermal_bridge_width 0.5)
				(island_removal_mode 0)
			)
			(polygon
				(pts
					(xy 404.9522 -31.115) (xy 404.9522 -30.607) (xy 404.5712 -30.607) (xy 404.5712 -31.115)
				)
			)
		)
	)
	(footprint ""
		(layer "B.Cu")
		(at 463.15122 -13.215366 -90)
		(property "Reference" "R2T4"
			(at 0 0 90)
			(layer "B.SilkS")
			(hide yes)
			(effects
				(font
					(size 1.27 1.27)
				)
				(justify mirror)
			)
		)
		(property "Value" ""
			(at 0 0 90)
			(layer "B.Fab")
			(effects
				(font
					(size 1.27 1.27)
				)
				(justify mirror)
			)
		)
		(duplicate_pad_numbers_are_jumpers no)
		(fp_rect
			(start 0.2794 -0.1016)
			(end -0.2794 0.9906)
			(stroke
				(width 0)
				(type default)
			)
			(fill no)
			(layer "B.CrtYd")
		)
		(fp_line
			(start -0.2794 0.9906)
			(end -0.2794 -0.1016)
			(stroke
				(width 0.1)
				(type default)
			)
			(layer "B.Fab")
		)
		(fp_line
			(start 0.2794 0.9906)
			(end -0.2794 0.9906)
			(stroke
				(width 0.1)
				(type default)
			)
			(layer "B.Fab")
		)
		(fp_line
			(start -0.2794 -0.1016)
			(end 0.2794 -0.1016)
			(stroke
				(width 0.1)
				(type default)
			)
			(layer "B.Fab")
		)
		(fp_line
			(start 0.2794 -0.1016)
			(end 0.2794 0.9906)
			(stroke
				(width 0.1)
				(type default)
			)
			(layer "B.Fab")
		)
		(pad "1" smd rect
			(at 0 0 90)
			(size 0.508 0.508)
			(layers "B.Cu" "B.Mask" "B.Paste")
			(net "P3V3_STBY")
		)
		(pad "2" smd rect
			(at 0 0.889 90)
			(size 0.508 0.508)
			(layers "B.Cu" "B.Mask" "B.Paste")
			(net "GND")
		)
		(zone
			(layer "B.Cu")
			(hatch none 0.5)
			(connect_pads
				(clearance 0)
			)
			(min_thickness 0.25)
			(keepout
				(tracks allowed)
				(vias not_allowed)
				(pads allowed)
				(copperpour not_allowed)
				(footprints allowed)
			)
			(placement
				(enabled no)
				(sheetname "")
			)
			(fill
				(thermal_gap 0.5)
				(thermal_bridge_width 0.5)
				(island_removal_mode 0)
			)
			(polygon
				(pts
					(xy 462.89722 -12.961366) (xy 462.89722 -13.469366) (xy 462.51622 -13.469366) (xy 462.51622 -12.961366)
				)
			)
		)
		(zone
			(layer "B.Cu")
			(hatch none 0.5)
			(connect_pads
				(clearance 0)
			)
			(min_thickness 0.25)
			(keepout
				(tracks not_allowed)
				(vias allowed)
				(pads allowed)
				(copperpour not_allowed)
				(footprints allowed)
			)
			(placement
				(enabled no)
				(sheetname "")
			)
			(fill
				(thermal_gap 0.5)
				(thermal_bridge_width 0.5)
				(island_removal_mode 0)
			)
			(polygon
				(pts
					(xy 462.89722 -12.961366) (xy 462.89722 -13.469366) (xy 462.51622 -13.469366) (xy 462.51622 -12.961366)
				)
			)
		)
	)
	(footprint ""
		(layer "B.Cu")
		(at 402.881846 -24.838152)
		(property "Reference" "C9G21"
			(at 0 0 0)
			(layer "B.SilkS")
			(hide yes)
			(effects
				(font
					(size 1.27 1.27)
				)
				(justify mirror)
			)
		)
		(property "Value" ""
			(at 0 0 0)
			(layer "B.Fab")
			(effects
				(font
					(size 1.27 1.27)
				)
				(justify mirror)
			)
		)
		(duplicate_pad_numbers_are_jumpers no)
		(fp_poly
			(pts
				(xy -0.3048 -0.1016) (xy -0.3048 0.9906) (xy 0.3048 0.9906) (xy 0.3048 -0.1016)
			)
			(stroke
				(width 0)
				(type default)
			)
			(fill no)
			(layer "B.CrtYd")
		)
		(fp_line
			(start -0.3048 -0.1016)
			(end 0.3048 -0.1016)
			(stroke
				(width 0.1)
				(type default)
			)
			(layer "B.Fab")
		)
		(fp_line
			(start -0.3048 0.9906)
			(end -0.3048 -0.1016)
			(stroke
				(width 0.1)
				(type default)
			)
			(layer "B.Fab")
		)
		(fp_line
			(start 0.3048 -0.1016)
			(end 0.3048 0.9906)
			(stroke
				(width 0.1)
				(type default)
			)
			(layer "B.Fab")
		)
		(fp_line
			(start 0.3048 0.9906)
			(end -0.3048 0.9906)
			(stroke
				(width 0.1)
				(type default)
			)
			(layer "B.Fab")
		)
		(pad "1" smd rect
			(at 0 0 180)
			(size 0.508 0.508)
			(layers "B.Cu" "B.Mask" "B.Paste")
			(net "A_P5V_STBY_SCALED")
		)
		(pad "2" smd rect
			(at 0 0.889 180)
			(size 0.508 0.508)
			(layers "B.Cu" "B.Mask" "B.Paste")
			(net "GND")
		)
		(zone
			(layer "B.Cu")
			(hatch none 0.5)
			(connect_pads
				(clearance 0)
			)
			(min_thickness 0.25)
			(keepout
				(tracks allowed)
				(vias not_allowed)
				(pads allowed)
				(copperpour not_allowed)
				(footprints allowed)
			)
			(placement
				(enabled no)
				(sheetname "")
			)
			(fill
				(thermal_gap 0.5)
				(thermal_bridge_width 0.5)
				(island_removal_mode 0)
			)
			(polygon
				(pts
					(xy 403.135846 -24.584152) (xy 402.627846 -24.584152) (xy 402.627846 -24.203152) (xy 403.135846 -24.203152)
				)
			)
		)
		(zone
			(layer "B.Cu")
			(hatch none 0.5)
			(connect_pads
				(clearance 0)
			)
			(min_thickness 0.25)
			(keepout
				(tracks not_allowed)
				(vias allowed)
				(pads allowed)
				(copperpour not_allowed)
				(footprints allowed)
			)
			(placement
				(enabled no)
				(sheetname "")
			)
			(fill
				(thermal_gap 0.5)
				(thermal_bridge_width 0.5)
				(island_removal_mode 0)
			)
			(polygon
				(pts
					(xy 403.135846 -24.203152) (xy 402.627846 -24.203152) (xy 402.627846 -24.584152) (xy 403.135846 -24.584152)
				)
			)
		)
	)
	(footprint ""
		(layer "B.Cu")
		(at 252.1585 -8.1534 -90)
		(property "Reference" "C5U7"
			(at -1.848866 0.752348 270)
			(unlocked yes)
			(layer "B.SilkS")
			(effects
				(font
					(size 1.27 0.9652)
					(thickness 0.1524)
				)
				(justify mirror)
			)
		)
		(property "Value" ""
			(at 0 0 90)
			(layer "B.Fab")
			(effects
				(font
					(size 1.27 1.27)
				)
				(justify mirror)
			)
		)
		(duplicate_pad_numbers_are_jumpers no)
		(fp_rect
			(start 0.500126 1.598422)
			(end -0.500126 -0.201422)
			(stroke
				(width 0)
				(type default)
			)
			(fill no)
			(layer "B.CrtYd")
		)
		(fp_line
			(start -0.500126 1.598422)
			(end 0.500126 1.598422)
			(stroke
				(width 0.1)
				(type default)
			)
			(layer "B.Fab")
		)
		(fp_line
			(start 0.500126 1.598422)
			(end 0.500126 -0.201422)
			(stroke
				(width 0.1)
				(type default)
			)
			(layer "B.Fab")
		)
		(fp_line
			(start -0.500126 -0.201422)
			(end -0.500126 1.598422)
			(stroke
				(width 0.1)
				(type default)
			)
			(layer "B.Fab")
		)
		(fp_line
			(start 0.500126 -0.201422)
			(end -0.500126 -0.201422)
			(stroke
				(width 0.1)
				(type default)
			)
			(layer "B.Fab")
		)
		(pad "1" smd rect
			(at 0 0 180)
			(size 0.889 0.9906)
			(layers "B.Cu" "B.Mask" "B.Paste")
			(net "PVDDQ_ABC")
		)
		(pad "2" smd rect
			(at 0 1.397 180)
			(size 0.889 0.9906)
			(layers "B.Cu" "B.Mask" "B.Paste")
			(net "GND")
		)
		(zone
			(layer "B.Cu")
			(hatch none 0.5)
			(connect_pads
				(clearance 0)
			)
			(min_thickness 0.25)
			(keepout
				(tracks not_allowed)
				(vias allowed)
				(pads allowed)
				(copperpour not_allowed)
				(footprints allowed)
			)
			(placement
				(enabled no)
				(sheetname "")
			)
			(fill
				(thermal_gap 0.5)
				(thermal_bridge_width 0.5)
				(island_removal_mode 0)
			)
			(polygon
				(pts
					(xy 251.206 -7.6581) (xy 251.714 -7.6581) (xy 251.714 -8.6487) (xy 251.206 -8.6487)
				)
			)
		)
		(zone
			(layer "B.Cu")
			(hatch none 0.5)
			(connect_pads
				(clearance 0)
			)
			(min_thickness 0.25)
			(keepout
				(tracks allowed)
				(vias not_allowed)
				(pads allowed)
				(copperpour not_allowed)
				(footprints allowed)
			)
			(placement
				(enabled no)
				(sheetname "")
			)
			(fill
				(thermal_gap 0.5)
				(thermal_bridge_width 0.5)
				(island_removal_mode 0)
			)
			(polygon
				(pts
					(xy 251.206 -7.6581) (xy 251.714 -7.6581) (xy 251.714 -8.6487) (xy 251.206 -8.6487)
				)
			)
		)
	)
	(footprint ""
		(layer "B.Cu")
		(at 354.289614 -126.624842 -90)
		(property "Reference" "R767"
			(at 0.8382 -0.67818 270)
			(unlocked yes)
			(layer "B.SilkS")
			(effects
				(font
					(size 0.4064 0.254)
					(thickness 0.1524)
				)
				(justify left mirror)
			)
		)
		(property "Value" ""
			(at 0 0 90)
			(layer "B.Fab")
			(effects
				(font
					(size 1.27 1.27)
				)
				(justify mirror)
			)
		)
		(duplicate_pad_numbers_are_jumpers no)
		(fp_poly
			(pts
				(xy 0.2794 -0.1016) (xy -0.2794 -0.1016) (xy -0.2794 0.9906) (xy 0.2794 0.9906)
			)
			(stroke
				(width 0)
				(type default)
			)
			(fill no)
			(layer "B.CrtYd")
		)
		(fp_line
			(start -0.2794 0.9906)
			(end -0.2794 -0.1016)
			(stroke
				(width 0.1)
				(type default)
			)
			(layer "B.Fab")
		)
		(fp_line
			(start 0.2794 0.9906)
			(end -0.2794 0.9906)
			(stroke
				(width 0.1)
				(type default)
			)
			(layer "B.Fab")
		)
		(fp_line
			(start -0.2794 -0.1016)
			(end 0.2794 -0.1016)
			(stroke
				(width 0.1)
				(type default)
			)
			(layer "B.Fab")
		)
		(fp_line
			(start 0.2794 -0.1016)
			(end 0.2794 0.9906)
			(stroke
				(width 0.1)
				(type default)
			)
			(layer "B.Fab")
		)
		(pad "1" smd rect
			(at 0 0 90)
			(size 0.508 0.508)
			(layers "B.Cu" "B.Mask" "B.Paste")
			(net "P3E_CPU0_PE1_PCH_RXP<15>")
		)
		(pad "2" smd rect
			(at 0 0.889 90)
			(size 0.508 0.508)
			(layers "B.Cu" "B.Mask" "B.Paste")
			(net "P3E_CPU0_PE1_PCH_CON_RXP<15>")
		)
		(zone
			(layer "B.Cu")
			(hatch none 0.5)
			(connect_pads
				(clearance 0)
			)
			(min_thickness 0.25)
			(keepout
				(tracks not_allowed)
				(vias allowed)
				(pads allowed)
				(copperpour not_allowed)
				(footprints allowed)
			)
			(placement
				(enabled no)
				(sheetname "")
			)
			(fill
				(thermal_gap 0.5)
				(thermal_bridge_width 0.5)
				(island_removal_mode 0)
			)
			(polygon
				(pts
					(xy 353.654614 -126.370842) (xy 353.654614 -126.878842) (xy 354.035614 -126.878842) (xy 354.035614 -126.370842)
				)
			)
		)
		(zone
			(layer "B.Cu")
			(hatch none 0.5)
			(connect_pads
				(clearance 0)
			)
			(min_thickness 0.25)
			(keepout
				(tracks allowed)
				(vias not_allowed)
				(pads allowed)
				(copperpour not_allowed)
				(footprints allowed)
			)
			(placement
				(enabled no)
				(sheetname "")
			)
			(fill
				(thermal_gap 0.5)
				(thermal_bridge_width 0.5)
				(island_removal_mode 0)
			)
			(polygon
				(pts
					(xy 354.035614 -126.370842) (xy 354.035614 -126.878842) (xy 353.654614 -126.878842) (xy 353.654614 -126.370842)
				)
			)
		)
	)
	(footprint ""
		(layer "B.Cu")
		(at 446.8876 -62.5856 -90)
		(property "Reference" "R1W43"
			(at 0.8382 -0.67818 270)
			(unlocked yes)
			(layer "B.SilkS")
			(effects
				(font
					(size 0.4064 0.254)
					(thickness 0.1524)
				)
				(justify left mirror)
			)
		)
		(property "Value" ""
			(at 0 0 90)
			(layer "B.Fab")
			(effects
				(font
					(size 1.27 1.27)
				)
				(justify mirror)
			)
		)
		(duplicate_pad_numbers_are_jumpers no)
		(fp_poly
			(pts
				(xy 0.2794 -0.1016) (xy -0.2794 -0.1016) (xy -0.2794 0.9906) (xy 0.2794 0.9906)
			)
			(stroke
				(width 0)
				(type default)
			)
			(fill no)
			(layer "B.CrtYd")
		)
		(fp_line
			(start -0.2794 0.9906)
			(end -0.2794 -0.1016)
			(stroke
				(width 0.1)
				(type default)
			)
			(layer "B.Fab")
		)
		(fp_line
			(start 0.2794 0.9906)
			(end -0.2794 0.9906)
			(stroke
				(width 0.1)
				(type default)
			)
			(layer "B.Fab")
		)
		(fp_line
			(start -0.2794 -0.1016)
			(end 0.2794 -0.1016)
			(stroke
				(width 0.1)
				(type default)
			)
			(layer "B.Fab")
		)
		(fp_line
			(start 0.2794 -0.1016)
			(end 0.2794 0.9906)
			(stroke
				(width 0.1)
				(type default)
			)
			(layer "B.Fab")
		)
		(pad "1" smd rect
			(at 0 0 90)
			(size 0.508 0.508)
			(layers "B.Cu" "B.Mask" "B.Paste")
			(net "P3V3_STBY")
		)
		(pad "2" smd rect
			(at 0 0.889 90)
			(size 0.508 0.508)
			(layers "B.Cu" "B.Mask" "B.Paste")
			(net "FM_GBE1_LVC3_MOD_ABS")
		)
		(zone
			(layer "B.Cu")
			(hatch none 0.5)
			(connect_pads
				(clearance 0)
			)
			(min_thickness 0.25)
			(keepout
				(tracks not_allowed)
				(vias allowed)
				(pads allowed)
				(copperpour not_allowed)
				(footprints allowed)
			)
			(placement
				(enabled no)
				(sheetname "")
			)
			(fill
				(thermal_gap 0.5)
				(thermal_bridge_width 0.5)
				(island_removal_mode 0)
			)
			(polygon
				(pts
					(xy 446.2526 -62.3316) (xy 446.2526 -62.8396) (xy 446.6336 -62.8396) (xy 446.6336 -62.3316)
				)
			)
		)
		(zone
			(layer "B.Cu")
			(hatch none 0.5)
			(connect_pads
				(clearance 0)
			)
			(min_thickness 0.25)
			(keepout
				(tracks allowed)
				(vias not_allowed)
				(pads allowed)
				(copperpour not_allowed)
				(footprints allowed)
			)
			(placement
				(enabled no)
				(sheetname "")
			)
			(fill
				(thermal_gap 0.5)
				(thermal_bridge_width 0.5)
				(island_removal_mode 0)
			)
			(polygon
				(pts
					(xy 446.6336 -62.3316) (xy 446.6336 -62.8396) (xy 446.2526 -62.8396) (xy 446.2526 -62.3316)
				)
			)
		)
	)
	(footprint ""
		(layer "B.Cu")
		(at 129.786888 -64.934338 -90)
		(property "Reference" "R7P29"
			(at 0 0 90)
			(layer "B.SilkS")
			(hide yes)
			(effects
				(font
					(size 1.27 1.27)
				)
				(justify mirror)
			)
		)
		(property "Value" ""
			(at 0 0 90)
			(layer "B.Fab")
			(effects
				(font
					(size 1.27 1.27)
				)
				(justify mirror)
			)
		)
		(duplicate_pad_numbers_are_jumpers no)
		(fp_rect
			(start -0.2794 0.9906)
			(end 0.2794 -0.1016)
			(stroke
				(width 0)
				(type default)
			)
			(fill no)
			(layer "B.CrtYd")
		)
		(fp_line
			(start -0.2794 0.9906)
			(end -0.2794 -0.1016)
			(stroke
				(width 0.1)
				(type default)
			)
			(layer "B.Fab")
		)
		(fp_line
			(start 0.2794 0.9906)
			(end -0.2794 0.9906)
			(stroke
				(width 0.1)
				(type default)
			)
			(layer "B.Fab")
		)
		(fp_line
			(start -0.2794 -0.1016)
			(end 0.2794 -0.1016)
			(stroke
				(width 0.1)
				(type default)
			)
			(layer "B.Fab")
		)
		(fp_line
			(start 0.2794 -0.1016)
			(end 0.2794 0.9906)
			(stroke
				(width 0.1)
				(type default)
			)
			(layer "B.Fab")
		)
		(pad "1" smd rect
			(at 0 0 90)
			(size 0.508 0.508)
			(layers "B.Cu" "B.Mask" "B.Paste")
			(net "XDP_CPU_TCK0")
		)
		(pad "2" smd rect
			(at 0 0.889 90)
			(size 0.508 0.508)
			(layers "B.Cu" "B.Mask" "B.Paste")
			(net "GND")
		)
		(zone
			(layer "B.Cu")
			(hatch none 0.5)
			(connect_pads
				(clearance 0)
			)
			(min_thickness 0.25)
			(keepout
				(tracks allowed)
				(vias not_allowed)
				(pads allowed)
				(copperpour not_allowed)
				(footprints allowed)
			)
			(placement
				(enabled no)
				(sheetname "")
			)
			(fill
				(thermal_gap 0.5)
				(thermal_bridge_width 0.5)
				(island_removal_mode 0)
			)
			(polygon
				(pts
					(xy 129.151888 -65.188338) (xy 129.151888 -64.680338) (xy 129.532888 -64.680338) (xy 129.532888 -65.188338)
				)
			)
		)
		(zone
			(layer "B.Cu")
			(hatch none 0.5)
			(connect_pads
				(clearance 0)
			)
			(min_thickness 0.25)
			(keepout
				(tracks not_allowed)
				(vias allowed)
				(pads allowed)
				(copperpour not_allowed)
				(footprints allowed)
			)
			(placement
				(enabled no)
				(sheetname "")
			)
			(fill
				(thermal_gap 0.5)
				(thermal_bridge_width 0.5)
				(island_removal_mode 0)
			)
			(polygon
				(pts
					(xy 129.151888 -65.188338) (xy 129.151888 -64.680338) (xy 129.532888 -64.680338) (xy 129.532888 -65.188338)
				)
			)
		)
	)
	(footprint ""
		(layer "B.Cu")
		(at 387.5278 -129.99974 180)
		(property "Reference" "R3M9"
			(at 0 0 0)
			(layer "B.SilkS")
			(hide yes)
			(effects
				(font
					(size 1.27 1.27)
				)
				(justify mirror)
			)
		)
		(property "Value" ""
			(at 0 0 0)
			(layer "B.Fab")
			(effects
				(font
					(size 1.27 1.27)
				)
				(justify mirror)
			)
		)
		(duplicate_pad_numbers_are_jumpers no)
		(fp_poly
			(pts
				(xy 0.2794 -0.1016) (xy -0.2794 -0.1016) (xy -0.2794 0.9906) (xy 0.2794 0.9906)
			)
			(stroke
				(width 0)
				(type default)
			)
			(fill no)
			(layer "B.CrtYd")
		)
		(fp_line
			(start 0.2794 0.9906)
			(end -0.2794 0.9906)
			(stroke
				(width 0.1)
				(type default)
			)
			(layer "B.Fab")
		)
		(fp_line
			(start 0.2794 -0.1016)
			(end 0.2794 0.9906)
			(stroke
				(width 0.1)
				(type default)
			)
			(layer "B.Fab")
		)
		(fp_line
			(start -0.2794 0.9906)
			(end -0.2794 -0.1016)
			(stroke
				(width 0.1)
				(type default)
			)
			(layer "B.Fab")
		)
		(fp_line
			(start -0.2794 -0.1016)
			(end 0.2794 -0.1016)
			(stroke
				(width 0.1)
				(type default)
			)
			(layer "B.Fab")
		)
		(pad "1" smd rect
			(at 0 0)
			(size 0.508 0.508)
			(layers "B.Cu" "B.Mask" "B.Paste")
			(net "P2E_SSB_BMC_RX_C_DN")
		)
		(pad "2" smd rect
			(at 0 0.889)
			(size 0.508 0.508)
			(layers "B.Cu" "B.Mask" "B.Paste")
			(net "GND")
		)
		(zone
			(layer "B.Cu")
			(hatch none 0.5)
			(connect_pads
				(clearance 0)
			)
			(min_thickness 0.25)
			(keepout
				(tracks not_allowed)
				(vias allowed)
				(pads allowed)
				(copperpour not_allowed)
				(footprints allowed)
			)
			(placement
				(enabled no)
				(sheetname "")
			)
			(fill
				(thermal_gap 0.5)
				(thermal_bridge_width 0.5)
				(island_removal_mode 0)
			)
			(polygon
				(pts
					(xy 387.2738 -130.63474) (xy 387.7818 -130.63474) (xy 387.7818 -130.25374) (xy 387.2738 -130.25374)
				)
			)
		)
		(zone
			(layer "B.Cu")
			(hatch none 0.5)
			(connect_pads
				(clearance 0)
			)
			(min_thickness 0.25)
			(keepout
				(tracks allowed)
				(vias not_allowed)
				(pads allowed)
				(copperpour not_allowed)
				(footprints allowed)
			)
			(placement
				(enabled no)
				(sheetname "")
			)
			(fill
				(thermal_gap 0.5)
				(thermal_bridge_width 0.5)
				(island_removal_mode 0)
			)
			(polygon
				(pts
					(xy 387.2738 -130.25374) (xy 387.7818 -130.25374) (xy 387.7818 -130.63474) (xy 387.2738 -130.63474)
				)
			)
		)
	)
	(footprint ""
		(layer "B.Cu")
		(at 12.40282 -102.46868 90)
		(property "Reference" "C9N8"
			(at 0 0 90)
			(layer "B.SilkS")
			(hide yes)
			(effects
				(font
					(size 1.27 1.27)
				)
				(justify mirror)
			)
		)
		(property "Value" ""
			(at 0 0 90)
			(layer "B.Fab")
			(effects
				(font
					(size 1.27 1.27)
				)
				(justify mirror)
			)
		)
		(duplicate_pad_numbers_are_jumpers no)
		(fp_poly
			(pts
				(xy -0.3048 -0.1016) (xy -0.3048 0.9906) (xy 0.3048 0.9906) (xy 0.3048 -0.1016)
			)
			(stroke
				(width 0)
				(type default)
			)
			(fill no)
			(layer "B.CrtYd")
		)
		(fp_line
			(start 0.3048 -0.1016)
			(end 0.3048 0.9906)
			(stroke
				(width 0.1)
				(type default)
			)
			(layer "B.Fab")
		)
		(fp_line
			(start -0.3048 -0.1016)
			(end 0.3048 -0.1016)
			(stroke
				(width 0.1)
				(type default)
			)
			(layer "B.Fab")
		)
		(fp_line
			(start 0.3048 0.9906)
			(end -0.3048 0.9906)
			(stroke
				(width 0.1)
				(type default)
			)
			(layer "B.Fab")
		)
		(fp_line
			(start -0.3048 0.9906)
			(end -0.3048 -0.1016)
			(stroke
				(width 0.1)
				(type default)
			)
			(layer "B.Fab")
		)
		(pad "1" smd rect
			(at 0 0 270)
			(size 0.508 0.508)
			(layers "B.Cu" "B.Mask" "B.Paste")
			(net "P3E_CPU1_PE3_MP_C_TXN<14>")
		)
		(pad "2" smd rect
			(at 0 0.889 270)
			(size 0.508 0.508)
			(layers "B.Cu" "B.Mask" "B.Paste")
			(net "P3E_CPU1_PE3_MP_TXN<14>")
		)
		(zone
			(layer "B.Cu")
			(hatch none 0.5)
			(connect_pads
				(clearance 0)
			)
			(min_thickness 0.25)
			(keepout
				(tracks allowed)
				(vias not_allowed)
				(pads allowed)
				(copperpour not_allowed)
				(footprints allowed)
			)
			(placement
				(enabled no)
				(sheetname "")
			)
			(fill
				(thermal_gap 0.5)
				(thermal_bridge_width 0.5)
				(island_removal_mode 0)
			)
			(polygon
				(pts
					(xy 12.65682 -102.72268) (xy 12.65682 -102.21468) (xy 13.03782 -102.21468) (xy 13.03782 -102.72268)
				)
			)
		)
		(zone
			(layer "B.Cu")
			(hatch none 0.5)
			(connect_pads
				(clearance 0)
			)
			(min_thickness 0.25)
			(keepout
				(tracks not_allowed)
				(vias allowed)
				(pads allowed)
				(copperpour not_allowed)
				(footprints allowed)
			)
			(placement
				(enabled no)
				(sheetname "")
			)
			(fill
				(thermal_gap 0.5)
				(thermal_bridge_width 0.5)
				(island_removal_mode 0)
			)
			(polygon
				(pts
					(xy 13.03782 -102.72268) (xy 13.03782 -102.21468) (xy 12.65682 -102.21468) (xy 12.65682 -102.72268)
				)
			)
		)
	)
	(footprint ""
		(layer "B.Cu")
		(at 383.4384 -137.541)
		(property "Reference" "C3L25"
			(at 0 0 0)
			(layer "B.SilkS")
			(hide yes)
			(effects
				(font
					(size 1.27 1.27)
				)
				(justify mirror)
			)
		)
		(property "Value" ""
			(at 0 0 0)
			(layer "B.Fab")
			(effects
				(font
					(size 1.27 1.27)
				)
				(justify mirror)
			)
		)
		(duplicate_pad_numbers_are_jumpers no)
		(fp_poly
			(pts
				(xy 0.4953 -0.2032) (xy -0.4953 -0.2032) (xy -0.4953 1.6002) (xy 0.4953 1.6002)
			)
			(stroke
				(width 0)
				(type default)
			)
			(fill no)
			(layer "B.CrtYd")
		)
		(fp_line
			(start -0.4953 -0.2032)
			(end -0.4953 1.6002)
			(stroke
				(width 0.1)
				(type default)
			)
			(layer "B.Fab")
		)
		(fp_line
			(start -0.4953 1.6002)
			(end 0.4953 1.6002)
			(stroke
				(width 0.1)
				(type default)
			)
			(layer "B.Fab")
		)
		(fp_line
			(start 0.4953 -0.2032)
			(end -0.4953 -0.2032)
			(stroke
				(width 0.1)
				(type default)
			)
			(layer "B.Fab")
		)
		(fp_line
			(start 0.4953 1.6002)
			(end 0.4953 -0.2032)
			(stroke
				(width 0.1)
				(type default)
			)
			(layer "B.Fab")
		)
		(pad "1" smd rect
			(at 0 0 180)
			(size 0.762 0.889)
			(layers "B.Cu" "B.Mask" "B.Paste")
			(net "PVNN_PCH_STBY")
		)
		(pad "2" smd rect
			(at 0 1.397 180)
			(size 0.762 0.889)
			(layers "B.Cu" "B.Mask" "B.Paste")
			(net "GND")
		)
		(zone
			(layer "B.Cu")
			(hatch none 0.5)
			(connect_pads
				(clearance 0)
			)
			(min_thickness 0.25)
			(keepout
				(tracks not_allowed)
				(vias allowed)
				(pads allowed)
				(copperpour not_allowed)
				(footprints allowed)
			)
			(placement
				(enabled no)
				(sheetname "")
			)
			(fill
				(thermal_gap 0.5)
				(thermal_bridge_width 0.5)
				(island_removal_mode 0)
			)
			(polygon
				(pts
					(xy 383.8194 -137.0965) (xy 383.0574 -137.0965) (xy 383.0574 -136.5885) (xy 383.8194 -136.5885)
				)
			)
		)
	)
	(footprint ""
		(layer "B.Cu")
		(at 444.09995 -29.6164)
		(property "Reference" "C25W13"
			(at 0.8382 -0.67818 0)
			(unlocked yes)
			(layer "B.SilkS")
			(effects
				(font
					(size 0.4064 0.254)
					(thickness 0.1524)
				)
				(justify left mirror)
			)
		)
		(property "Value" ""
			(at 0 0 0)
			(layer "B.Fab")
			(effects
				(font
					(size 1.27 1.27)
				)
				(justify mirror)
			)
		)
		(duplicate_pad_numbers_are_jumpers no)
		(fp_poly
			(pts
				(xy -0.3048 -0.1016) (xy -0.3048 0.9906) (xy 0.3048 0.9906) (xy 0.3048 -0.1016)
			)
			(stroke
				(width 0)
				(type default)
			)
			(fill no)
			(layer "B.CrtYd")
		)
		(fp_line
			(start -0.3048 -0.1016)
			(end 0.3048 -0.1016)
			(stroke
				(width 0.1)
				(type default)
			)
			(layer "B.Fab")
		)
		(fp_line
			(start -0.3048 0.9906)
			(end -0.3048 -0.1016)
			(stroke
				(width 0.1)
				(type default)
			)
			(layer "B.Fab")
		)
		(fp_line
			(start 0.3048 -0.1016)
			(end 0.3048 0.9906)
			(stroke
				(width 0.1)
				(type default)
			)
			(layer "B.Fab")
		)
		(fp_line
			(start 0.3048 0.9906)
			(end -0.3048 0.9906)
			(stroke
				(width 0.1)
				(type default)
			)
			(layer "B.Fab")
		)
		(pad "1" smd rect
			(at 0 0 180)
			(size 0.508 0.508)
			(layers "B.Cu" "B.Mask" "B.Paste")
			(net "BMC_M_VREFCA")
		)
		(pad "2" smd rect
			(at 0 0.889 180)
			(size 0.508 0.508)
			(layers "B.Cu" "B.Mask" "B.Paste")
			(net "GND")
		)
		(zone
			(layer "B.Cu")
			(hatch none 0.5)
			(connect_pads
				(clearance 0)
			)
			(min_thickness 0.25)
			(keepout
				(tracks allowed)
				(vias not_allowed)
				(pads allowed)
				(copperpour not_allowed)
				(footprints allowed)
			)
			(placement
				(enabled no)
				(sheetname "")
			)
			(fill
				(thermal_gap 0.5)
				(thermal_bridge_width 0.5)
				(island_removal_mode 0)
			)
			(polygon
				(pts
					(xy 444.35395 -29.3624) (xy 443.84595 -29.3624) (xy 443.84595 -28.9814) (xy 444.35395 -28.9814)
				)
			)
		)
		(zone
			(layer "B.Cu")
			(hatch none 0.5)
			(connect_pads
				(clearance 0)
			)
			(min_thickness 0.25)
			(keepout
				(tracks not_allowed)
				(vias allowed)
				(pads allowed)
				(copperpour not_allowed)
				(footprints allowed)
			)
			(placement
				(enabled no)
				(sheetname "")
			)
			(fill
				(thermal_gap 0.5)
				(thermal_bridge_width 0.5)
				(island_removal_mode 0)
			)
			(polygon
				(pts
					(xy 444.35395 -28.9814) (xy 443.84595 -28.9814) (xy 443.84595 -29.3624) (xy 444.35395 -29.3624)
				)
			)
		)
	)
	(footprint ""
		(layer "B.Cu")
		(at 469.7095 -137.795 -90)
		(property "Reference" "C1L18"
			(at 0 0 90)
			(layer "B.SilkS")
			(hide yes)
			(effects
				(font
					(size 1.27 1.27)
				)
				(justify mirror)
			)
		)
		(property "Value" ""
			(at 0 0 90)
			(layer "B.Fab")
			(effects
				(font
					(size 1.27 1.27)
				)
				(justify mirror)
			)
		)
		(duplicate_pad_numbers_are_jumpers no)
		(fp_poly
			(pts
				(xy -0.3048 -0.1016) (xy -0.3048 0.9906) (xy 0.3048 0.9906) (xy 0.3048 -0.1016)
			)
			(stroke
				(width 0)
				(type default)
			)
			(fill no)
			(layer "B.CrtYd")
		)
		(fp_line
			(start -0.3048 0.9906)
			(end -0.3048 -0.1016)
			(stroke
				(width 0.1)
				(type default)
			)
			(layer "B.Fab")
		)
		(fp_line
			(start 0.3048 0.9906)
			(end -0.3048 0.9906)
			(stroke
				(width 0.1)
				(type default)
			)
			(layer "B.Fab")
		)
		(fp_line
			(start -0.3048 -0.1016)
			(end 0.3048 -0.1016)
			(stroke
				(width 0.1)
				(type default)
			)
			(layer "B.Fab")
		)
		(fp_line
			(start 0.3048 -0.1016)
			(end 0.3048 0.9906)
			(stroke
				(width 0.1)
				(type default)
			)
			(layer "B.Fab")
		)
		(pad "1" smd rect
			(at 0 0 90)
			(size 0.508 0.508)
			(layers "B.Cu" "B.Mask" "B.Paste")
			(net "FP_PWR_BTN_R1_N")
		)
		(pad "2" smd rect
			(at 0 0.889 90)
			(size 0.508 0.508)
			(layers "B.Cu" "B.Mask" "B.Paste")
			(net "GND")
		)
		(zone
			(layer "B.Cu")
			(hatch none 0.5)
			(connect_pads
				(clearance 0)
			)
			(min_thickness 0.25)
			(keepout
				(tracks not_allowed)
				(vias allowed)
				(pads allowed)
				(copperpour not_allowed)
				(footprints allowed)
			)
			(placement
				(enabled no)
				(sheetname "")
			)
			(fill
				(thermal_gap 0.5)
				(thermal_bridge_width 0.5)
				(island_removal_mode 0)
			)
			(polygon
				(pts
					(xy 469.0745 -137.541) (xy 469.0745 -138.049) (xy 469.4555 -138.049) (xy 469.4555 -137.541)
				)
			)
		)
		(zone
			(layer "B.Cu")
			(hatch none 0.5)
			(connect_pads
				(clearance 0)
			)
			(min_thickness 0.25)
			(keepout
				(tracks allowed)
				(vias not_allowed)
				(pads allowed)
				(copperpour not_allowed)
				(footprints allowed)
			)
			(placement
				(enabled no)
				(sheetname "")
			)
			(fill
				(thermal_gap 0.5)
				(thermal_bridge_width 0.5)
				(island_removal_mode 0)
			)
			(polygon
				(pts
					(xy 469.4555 -137.541) (xy 469.4555 -138.049) (xy 469.0745 -138.049) (xy 469.0745 -137.541)
				)
			)
		)
	)
	(footprint ""
		(layer "B.Cu")
		(at 385.051808 -84.729828 180)
		(property "Reference" "R3P5"
			(at 0.8382 -0.67818 180)
			(unlocked yes)
			(layer "B.SilkS")
			(effects
				(font
					(size 0.4064 0.254)
					(thickness 0.1524)
				)
				(justify left mirror)
			)
		)
		(property "Value" ""
			(at 0 0 0)
			(layer "B.Fab")
			(effects
				(font
					(size 1.27 1.27)
				)
				(justify mirror)
			)
		)
		(duplicate_pad_numbers_are_jumpers no)
		(fp_poly
			(pts
				(xy 0.2794 -0.1016) (xy -0.2794 -0.1016) (xy -0.2794 0.9906) (xy 0.2794 0.9906)
			)
			(stroke
				(width 0)
				(type default)
			)
			(fill no)
			(layer "B.CrtYd")
		)
		(fp_line
			(start 0.2794 0.9906)
			(end -0.2794 0.9906)
			(stroke
				(width 0.1)
				(type default)
			)
			(layer "B.Fab")
		)
		(fp_line
			(start 0.2794 -0.1016)
			(end 0.2794 0.9906)
			(stroke
				(width 0.1)
				(type default)
			)
			(layer "B.Fab")
		)
		(fp_line
			(start -0.2794 0.9906)
			(end -0.2794 -0.1016)
			(stroke
				(width 0.1)
				(type default)
			)
			(layer "B.Fab")
		)
		(fp_line
			(start -0.2794 -0.1016)
			(end 0.2794 -0.1016)
			(stroke
				(width 0.1)
				(type default)
			)
			(layer "B.Fab")
		)
		(pad "1" smd rect
			(at 0 0)
			(size 0.508 0.508)
			(layers "B.Cu" "B.Mask" "B.Paste")
			(net "P1V05_PCH_STBY")
		)
		(pad "2" smd rect
			(at 0 0.889)
			(size 0.508 0.508)
			(layers "B.Cu" "B.Mask" "B.Paste")
			(net "FM_PRSNT_2_2_N")
		)
		(zone
			(layer "B.Cu")
			(hatch none 0.5)
			(connect_pads
				(clearance 0)
			)
			(min_thickness 0.25)
			(keepout
				(tracks not_allowed)
				(vias allowed)
				(pads allowed)
				(copperpour not_allowed)
				(footprints allowed)
			)
			(placement
				(enabled no)
				(sheetname "")
			)
			(fill
				(thermal_gap 0.5)
				(thermal_bridge_width 0.5)
				(island_removal_mode 0)
			)
			(polygon
				(pts
					(xy 384.797808 -85.364828) (xy 385.305808 -85.364828) (xy 385.305808 -84.983828) (xy 384.797808 -84.983828)
				)
			)
		)
		(zone
			(layer "B.Cu")
			(hatch none 0.5)
			(connect_pads
				(clearance 0)
			)
			(min_thickness 0.25)
			(keepout
				(tracks allowed)
				(vias not_allowed)
				(pads allowed)
				(copperpour not_allowed)
				(footprints allowed)
			)
			(placement
				(enabled no)
				(sheetname "")
			)
			(fill
				(thermal_gap 0.5)
				(thermal_bridge_width 0.5)
				(island_removal_mode 0)
			)
			(polygon
				(pts
					(xy 384.797808 -84.983828) (xy 385.305808 -84.983828) (xy 385.305808 -85.364828) (xy 384.797808 -85.364828)
				)
			)
		)
	)
	(footprint ""
		(layer "B.Cu")
		(at 459.0034 -127.9144 -90)
		(property "Reference" "U1M7"
			(at 1.40843 -0.70866 0)
			(unlocked yes)
			(layer "B.SilkS")
			(effects
				(font
					(size 0.7874 0.5842)
					(thickness 0.1524)
				)
				(justify left mirror)
			)
		)
		(property "Value" ""
			(at 0 0 90)
			(layer "B.Fab")
			(effects
				(font
					(size 1.27 1.27)
				)
				(justify mirror)
			)
		)
		(duplicate_pad_numbers_are_jumpers no)
		(fp_circle
			(center 0.858266 0.002032)
			(end 0.858266 -0.124968)
			(stroke
				(width 0.254)
				(type default)
			)
			(fill no)
			(layer "B.SilkS")
		)
		(fp_poly
			(pts
				(xy -0.21463 -0.450088) (xy -1.56337 -0.450088) (xy -1.56337 1.75006) (xy -0.21463 1.75006)
			)
			(stroke
				(width 0)
				(type default)
			)
			(fill no)
			(layer "B.CrtYd")
		)
		(fp_line
			(start -1.56337 1.75006)
			(end -0.21463 1.75006)
			(stroke
				(width 0.1)
				(type default)
			)
			(layer "B.Fab")
		)
		(fp_line
			(start -0.21463 1.75006)
			(end -0.21463 -0.450088)
			(stroke
				(width 0.1)
				(type default)
			)
			(layer "B.Fab")
		)
		(fp_line
			(start -1.56337 -0.450088)
			(end -1.56337 1.75006)
			(stroke
				(width 0.1)
				(type default)
			)
			(layer "B.Fab")
		)
		(fp_line
			(start -0.21463 -0.450088)
			(end -1.56337 -0.450088)
			(stroke
				(width 0.1)
				(type default)
			)
			(layer "B.Fab")
		)
		(fp_circle
			(center 0.848614 -0.6477)
			(end 0.848614 -0.7747)
			(stroke
				(width 0.254)
				(type default)
			)
			(fill no)
			(layer "B.Fab")
		)
		(pad "1" smd rect
			(at 0 0 90)
			(size 1.016 0.381)
			(layers "B.Cu" "B.Mask" "B.Paste")
			(net "XDP_CPU0_TDO")
		)
		(pad "2" smd rect
			(at 0 0.649986 90)
			(size 1.016 0.381)
			(layers "B.Cu" "B.Mask" "B.Paste")
			(net "GND")
		)
		(pad "3" smd rect
			(at 0 1.299972 90)
			(size 1.016 0.381)
			(layers "B.Cu" "B.Mask" "B.Paste")
			(net "XDP_CPU1_TDO")
		)
		(pad "4" smd rect
			(at -1.778 1.299972 90)
			(size 1.016 0.381)
			(layers "B.Cu" "B.Mask" "B.Paste")
			(net "XDP_CPU_TDO")
		)
		(pad "5" smd rect
			(at -1.778 0.649986 90)
			(size 1.016 0.381)
			(layers "B.Cu" "B.Mask" "B.Paste")
			(net "P3V3_STBY")
		)
		(pad "6" smd rect
			(at -1.778 0 90)
			(size 1.016 0.381)
			(layers "B.Cu" "B.Mask" "B.Paste")
			(net "FM_CPU1_SKTOCC_LVT3_N")
		)
	)
	(footprint ""
		(layer "B.Cu")
		(at 340.741 -84.5058 90)
		(property "Reference" "R3P18"
			(at 0 0 90)
			(layer "B.SilkS")
			(hide yes)
			(effects
				(font
					(size 1.27 1.27)
				)
				(justify mirror)
			)
		)
		(property "Value" ""
			(at 0 0 90)
			(layer "B.Fab")
			(effects
				(font
					(size 1.27 1.27)
				)
				(justify mirror)
			)
		)
		(duplicate_pad_numbers_are_jumpers no)
		(fp_poly
			(pts
				(xy 0.2794 -0.1016) (xy -0.2794 -0.1016) (xy -0.2794 0.9906) (xy 0.2794 0.9906)
			)
			(stroke
				(width 0)
				(type default)
			)
			(fill no)
			(layer "B.CrtYd")
		)
		(fp_line
			(start 0.2794 -0.1016)
			(end 0.2794 0.9906)
			(stroke
				(width 0.1)
				(type default)
			)
			(layer "B.Fab")
		)
		(fp_line
			(start -0.2794 -0.1016)
			(end 0.2794 -0.1016)
			(stroke
				(width 0.1)
				(type default)
			)
			(layer "B.Fab")
		)
		(fp_line
			(start 0.2794 0.9906)
			(end -0.2794 0.9906)
			(stroke
				(width 0.1)
				(type default)
			)
			(layer "B.Fab")
		)
		(fp_line
			(start -0.2794 0.9906)
			(end -0.2794 -0.1016)
			(stroke
				(width 0.1)
				(type default)
			)
			(layer "B.Fab")
		)
		(pad "1" smd rect
			(at 0 0 270)
			(size 0.508 0.508)
			(layers "B.Cu" "B.Mask" "B.Paste")
			(net "P3V3_STBY")
		)
		(pad "2" smd rect
			(at 0 0.889 270)
			(size 0.508 0.508)
			(layers "B.Cu" "B.Mask" "B.Paste")
			(net "IRQ_PVCCIO_CPU0_VRHOT_N")
		)
		(zone
			(layer "B.Cu")
			(hatch none 0.5)
			(connect_pads
				(clearance 0)
			)
			(min_thickness 0.25)
			(keepout
				(tracks allowed)
				(vias not_allowed)
				(pads allowed)
				(copperpour not_allowed)
				(footprints allowed)
			)
			(placement
				(enabled no)
				(sheetname "")
			)
			(fill
				(thermal_gap 0.5)
				(thermal_bridge_width 0.5)
				(island_removal_mode 0)
			)
			(polygon
				(pts
					(xy 340.995 -84.7598) (xy 340.995 -84.2518) (xy 341.376 -84.2518) (xy 341.376 -84.7598)
				)
			)
		)
		(zone
			(layer "B.Cu")
			(hatch none 0.5)
			(connect_pads
				(clearance 0)
			)
			(min_thickness 0.25)
			(keepout
				(tracks not_allowed)
				(vias allowed)
				(pads allowed)
				(copperpour not_allowed)
				(footprints allowed)
			)
			(placement
				(enabled no)
				(sheetname "")
			)
			(fill
				(thermal_gap 0.5)
				(thermal_bridge_width 0.5)
				(island_removal_mode 0)
			)
			(polygon
				(pts
					(xy 341.376 -84.7598) (xy 341.376 -84.2518) (xy 340.995 -84.2518) (xy 340.995 -84.7598)
				)
			)
		)
	)
	(footprint ""
		(layer "B.Cu")
		(at 164.973 -68.199 -90)
		(property "Reference" "R6P35"
			(at 0 0 90)
			(layer "B.SilkS")
			(hide yes)
			(effects
				(font
					(size 1.27 1.27)
				)
				(justify mirror)
			)
		)
		(property "Value" ""
			(at 0 0 90)
			(layer "B.Fab")
			(effects
				(font
					(size 1.27 1.27)
				)
				(justify mirror)
			)
		)
		(duplicate_pad_numbers_are_jumpers no)
		(fp_poly
			(pts
				(xy 0.2794 -0.1016) (xy -0.2794 -0.1016) (xy -0.2794 0.9906) (xy 0.2794 0.9906)
			)
			(stroke
				(width 0)
				(type default)
			)
			(fill no)
			(layer "B.CrtYd")
		)
		(fp_line
			(start -0.2794 0.9906)
			(end -0.2794 -0.1016)
			(stroke
				(width 0.1)
				(type default)
			)
			(layer "B.Fab")
		)
		(fp_line
			(start 0.2794 0.9906)
			(end -0.2794 0.9906)
			(stroke
				(width 0.1)
				(type default)
			)
			(layer "B.Fab")
		)
		(fp_line
			(start -0.2794 -0.1016)
			(end 0.2794 -0.1016)
			(stroke
				(width 0.1)
				(type default)
			)
			(layer "B.Fab")
		)
		(fp_line
			(start 0.2794 -0.1016)
			(end 0.2794 0.9906)
			(stroke
				(width 0.1)
				(type default)
			)
			(layer "B.Fab")
		)
		(pad "1" smd rect
			(at 0 0 90)
			(size 0.508 0.508)
			(layers "B.Cu" "B.Mask" "B.Paste")
			(net "PVCCIO_CPU1")
		)
		(pad "2" smd rect
			(at 0 0.889 90)
			(size 0.508 0.508)
			(layers "B.Cu" "B.Mask" "B.Paste")
			(net "SVID_DIO0_CPU1_R")
		)
		(zone
			(layer "B.Cu")
			(hatch none 0.5)
			(connect_pads
				(clearance 0)
			)
			(min_thickness 0.25)
			(keepout
				(tracks not_allowed)
				(vias allowed)
				(pads allowed)
				(copperpour not_allowed)
				(footprints allowed)
			)
			(placement
				(enabled no)
				(sheetname "")
			)
			(fill
				(thermal_gap 0.5)
				(thermal_bridge_width 0.5)
				(island_removal_mode 0)
			)
			(polygon
				(pts
					(xy 164.338 -67.945) (xy 164.338 -68.453) (xy 164.719 -68.453) (xy 164.719 -67.945)
				)
			)
		)
		(zone
			(layer "B.Cu")
			(hatch none 0.5)
			(connect_pads
				(clearance 0)
			)
			(min_thickness 0.25)
			(keepout
				(tracks allowed)
				(vias not_allowed)
				(pads allowed)
				(copperpour not_allowed)
				(footprints allowed)
			)
			(placement
				(enabled no)
				(sheetname "")
			)
			(fill
				(thermal_gap 0.5)
				(thermal_bridge_width 0.5)
				(island_removal_mode 0)
			)
			(polygon
				(pts
					(xy 164.719 -67.945) (xy 164.719 -68.453) (xy 164.338 -68.453) (xy 164.338 -67.945)
				)
			)
		)
	)
	(footprint ""
		(layer "B.Cu")
		(at 248.8565 -3.3528 -90)
		(property "Reference" "C5G51"
			(at -1.14681 0.76708 0)
			(unlocked yes)
			(layer "B.SilkS")
			(effects
				(font
					(size 0.7874 0.5842)
					(thickness 0.1524)
				)
				(justify mirror)
			)
		)
		(property "Value" ""
			(at 0 0 90)
			(layer "B.Fab")
			(effects
				(font
					(size 1.27 1.27)
				)
				(justify mirror)
			)
		)
		(duplicate_pad_numbers_are_jumpers no)
		(fp_rect
			(start 0.4953 1.6002)
			(end -0.4953 -0.2032)
			(stroke
				(width 0)
				(type default)
			)
			(fill no)
			(layer "B.CrtYd")
		)
		(fp_line
			(start -0.4953 1.6002)
			(end 0.4953 1.6002)
			(stroke
				(width 0.1)
				(type default)
			)
			(layer "B.Fab")
		)
		(fp_line
			(start 0.4953 1.6002)
			(end 0.4953 -0.2032)
			(stroke
				(width 0.1)
				(type default)
			)
			(layer "B.Fab")
		)
		(fp_line
			(start -0.4953 -0.2032)
			(end -0.4953 1.6002)
			(stroke
				(width 0.1)
				(type default)
			)
			(layer "B.Fab")
		)
		(fp_line
			(start 0.4953 -0.2032)
			(end -0.4953 -0.2032)
			(stroke
				(width 0.1)
				(type default)
			)
			(layer "B.Fab")
		)
		(pad "1" smd rect
			(at 0 0 90)
			(size 0.762 0.889)
			(layers "B.Cu" "B.Mask" "B.Paste")
			(net "PVDDQ_ABC")
		)
		(pad "2" smd rect
			(at 0 1.397 90)
			(size 0.762 0.889)
			(layers "B.Cu" "B.Mask" "B.Paste")
			(net "GND")
		)
		(zone
			(layer "B.Cu")
			(hatch none 0.5)
			(connect_pads
				(clearance 0)
			)
			(min_thickness 0.25)
			(keepout
				(tracks not_allowed)
				(vias allowed)
				(pads allowed)
				(copperpour not_allowed)
				(footprints allowed)
			)
			(placement
				(enabled no)
				(sheetname "")
			)
			(fill
				(thermal_gap 0.5)
				(thermal_bridge_width 0.5)
				(island_removal_mode 0)
			)
			(polygon
				(pts
					(xy 247.904 -2.9718) (xy 248.412 -2.9718) (xy 248.412 -3.7338) (xy 247.904 -3.7338)
				)
			)
		)
	)
	(footprint ""
		(layer "B.Cu")
		(at 471.9447 -128.39954 -90)
		(property "Reference" "R1M23"
			(at 0 0 90)
			(layer "B.SilkS")
			(hide yes)
			(effects
				(font
					(size 1.27 1.27)
				)
				(justify mirror)
			)
		)
		(property "Value" ""
			(at 0 0 90)
			(layer "B.Fab")
			(effects
				(font
					(size 1.27 1.27)
				)
				(justify mirror)
			)
		)
		(duplicate_pad_numbers_are_jumpers no)
		(fp_poly
			(pts
				(xy 0.2794 -0.1016) (xy -0.2794 -0.1016) (xy -0.2794 0.9906) (xy 0.2794 0.9906)
			)
			(stroke
				(width 0)
				(type default)
			)
			(fill no)
			(layer "B.CrtYd")
		)
		(fp_line
			(start -0.2794 0.9906)
			(end -0.2794 -0.1016)
			(stroke
				(width 0.1)
				(type default)
			)
			(layer "B.Fab")
		)
		(fp_line
			(start 0.2794 0.9906)
			(end -0.2794 0.9906)
			(stroke
				(width 0.1)
				(type default)
			)
			(layer "B.Fab")
		)
		(fp_line
			(start -0.2794 -0.1016)
			(end 0.2794 -0.1016)
			(stroke
				(width 0.1)
				(type default)
			)
			(layer "B.Fab")
		)
		(fp_line
			(start 0.2794 -0.1016)
			(end 0.2794 0.9906)
			(stroke
				(width 0.1)
				(type default)
			)
			(layer "B.Fab")
		)
		(pad "1" smd rect
			(at 0 0 90)
			(size 0.508 0.508)
			(layers "B.Cu" "B.Mask" "B.Paste")
			(net "JTAG_MCP_TRST_N")
		)
		(pad "2" smd rect
			(at 0 0.889 90)
			(size 0.508 0.508)
			(layers "B.Cu" "B.Mask" "B.Paste")
			(net "GND")
		)
		(zone
			(layer "B.Cu")
			(hatch none 0.5)
			(connect_pads
				(clearance 0)
			)
			(min_thickness 0.25)
			(keepout
				(tracks not_allowed)
				(vias allowed)
				(pads allowed)
				(copperpour not_allowed)
				(footprints allowed)
			)
			(placement
				(enabled no)
				(sheetname "")
			)
			(fill
				(thermal_gap 0.5)
				(thermal_bridge_width 0.5)
				(island_removal_mode 0)
			)
			(polygon
				(pts
					(xy 471.3097 -128.14554) (xy 471.3097 -128.65354) (xy 471.6907 -128.65354) (xy 471.6907 -128.14554)
				)
			)
		)
		(zone
			(layer "B.Cu")
			(hatch none 0.5)
			(connect_pads
				(clearance 0)
			)
			(min_thickness 0.25)
			(keepout
				(tracks allowed)
				(vias not_allowed)
				(pads allowed)
				(copperpour not_allowed)
				(footprints allowed)
			)
			(placement
				(enabled no)
				(sheetname "")
			)
			(fill
				(thermal_gap 0.5)
				(thermal_bridge_width 0.5)
				(island_removal_mode 0)
			)
			(polygon
				(pts
					(xy 471.6907 -128.14554) (xy 471.6907 -128.65354) (xy 471.3097 -128.65354) (xy 471.3097 -128.14554)
				)
			)
		)
	)
	(footprint ""
		(layer "B.Cu")
		(at 417.232846 -44.650152 180)
		(property "Reference" "R25W63"
			(at 0.8382 -0.67818 180)
			(unlocked yes)
			(layer "B.SilkS")
			(effects
				(font
					(size 0.4064 0.254)
					(thickness 0.1524)
				)
				(justify left mirror)
			)
		)
		(property "Value" ""
			(at 0 0 0)
			(layer "B.Fab")
			(effects
				(font
					(size 1.27 1.27)
				)
				(justify mirror)
			)
		)
		(duplicate_pad_numbers_are_jumpers no)
		(fp_poly
			(pts
				(xy 0.2794 -0.1016) (xy -0.2794 -0.1016) (xy -0.2794 0.9906) (xy 0.2794 0.9906)
			)
			(stroke
				(width 0)
				(type default)
			)
			(fill no)
			(layer "B.CrtYd")
		)
		(fp_line
			(start 0.2794 0.9906)
			(end -0.2794 0.9906)
			(stroke
				(width 0.1)
				(type default)
			)
			(layer "B.Fab")
		)
		(fp_line
			(start 0.2794 -0.1016)
			(end 0.2794 0.9906)
			(stroke
				(width 0.1)
				(type default)
			)
			(layer "B.Fab")
		)
		(fp_line
			(start -0.2794 0.9906)
			(end -0.2794 -0.1016)
			(stroke
				(width 0.1)
				(type default)
			)
			(layer "B.Fab")
		)
		(fp_line
			(start -0.2794 -0.1016)
			(end 0.2794 -0.1016)
			(stroke
				(width 0.1)
				(type default)
			)
			(layer "B.Fab")
		)
		(pad "1" smd rect
			(at 0 0)
			(size 0.508 0.508)
			(layers "B.Cu" "B.Mask" "B.Paste")
			(net "FM_PE_BMC_WAKE_N")
		)
		(pad "2" smd rect
			(at 0 0.889)
			(size 0.508 0.508)
			(layers "B.Cu" "B.Mask" "B.Paste")
			(net "GND")
		)
		(zone
			(layer "B.Cu")
			(hatch none 0.5)
			(connect_pads
				(clearance 0)
			)
			(min_thickness 0.25)
			(keepout
				(tracks not_allowed)
				(vias allowed)
				(pads allowed)
				(copperpour not_allowed)
				(footprints allowed)
			)
			(placement
				(enabled no)
				(sheetname "")
			)
			(fill
				(thermal_gap 0.5)
				(thermal_bridge_width 0.5)
				(island_removal_mode 0)
			)
			(polygon
				(pts
					(xy 416.978846 -45.285152) (xy 417.486846 -45.285152) (xy 417.486846 -44.904152) (xy 416.978846 -44.904152)
				)
			)
		)
		(zone
			(layer "B.Cu")
			(hatch none 0.5)
			(connect_pads
				(clearance 0)
			)
			(min_thickness 0.25)
			(keepout
				(tracks allowed)
				(vias not_allowed)
				(pads allowed)
				(copperpour not_allowed)
				(footprints allowed)
			)
			(placement
				(enabled no)
				(sheetname "")
			)
			(fill
				(thermal_gap 0.5)
				(thermal_bridge_width 0.5)
				(island_removal_mode 0)
			)
			(polygon
				(pts
					(xy 416.978846 -44.904152) (xy 417.486846 -44.904152) (xy 417.486846 -45.285152) (xy 416.978846 -45.285152)
				)
			)
		)
	)
	(footprint ""
		(layer "B.Cu")
		(at 348.5896 -153.8732 -90)
		(property "Reference" "C3L2"
			(at 0 0 90)
			(layer "B.SilkS")
			(hide yes)
			(effects
				(font
					(size 1.27 1.27)
				)
				(justify mirror)
			)
		)
		(property "Value" ""
			(at 0 0 90)
			(layer "B.Fab")
			(effects
				(font
					(size 1.27 1.27)
				)
				(justify mirror)
			)
		)
		(duplicate_pad_numbers_are_jumpers no)
		(fp_poly
			(pts
				(xy 0.7239 -0.2159) (xy -0.7239 -0.2159) (xy -0.7239 1.9939) (xy 0.7239 1.9939)
			)
			(stroke
				(width 0)
				(type default)
			)
			(fill no)
			(layer "B.CrtYd")
		)
		(fp_line
			(start -0.7239 1.9939)
			(end -0.7239 -0.2159)
			(stroke
				(width 0.1)
				(type default)
			)
			(layer "B.Fab")
		)
		(fp_line
			(start 0.7239 1.9939)
			(end -0.7239 1.9939)
			(stroke
				(width 0.1)
				(type default)
			)
			(layer "B.Fab")
		)
		(fp_line
			(start -0.7239 -0.2159)
			(end 0.7239 -0.2159)
			(stroke
				(width 0.1)
				(type default)
			)
			(layer "B.Fab")
		)
		(fp_line
			(start 0.7239 -0.2159)
			(end 0.7239 1.9939)
			(stroke
				(width 0.1)
				(type default)
			)
			(layer "B.Fab")
		)
		(pad "1" smd rect
			(at 0 0 90)
			(size 1.27 1.016)
			(layers "B.Cu" "B.Mask" "B.Paste")
			(net "VR_FET_SW_P12V_STBY_PVDDQ_DEF")
		)
		(pad "2" smd rect
			(at 0 1.778 90)
			(size 1.27 1.016)
			(layers "B.Cu" "B.Mask" "B.Paste")
			(net "GND")
		)
		(zone
			(layer "B.Cu")
			(hatch none 0.5)
			(connect_pads
				(clearance 0)
			)
			(min_thickness 0.25)
			(keepout
				(tracks not_allowed)
				(vias allowed)
				(pads allowed)
				(copperpour not_allowed)
				(footprints allowed)
			)
			(placement
				(enabled no)
				(sheetname "")
			)
			(fill
				(thermal_gap 0.5)
				(thermal_bridge_width 0.5)
				(island_removal_mode 0)
			)
			(polygon
				(pts
					(xy 348.0816 -153.2382) (xy 348.0816 -154.5082) (xy 347.3196 -154.5082) (xy 347.3196 -153.2382)
				)
			)
		)
	)
	(footprint ""
		(layer "B.Cu")
		(at 385.6482 -109.8804 90)
		(property "Reference" "C3N10"
			(at 0 0 90)
			(layer "B.SilkS")
			(hide yes)
			(effects
				(font
					(size 1.27 1.27)
				)
				(justify mirror)
			)
		)
		(property "Value" ""
			(at 0 0 90)
			(layer "B.Fab")
			(effects
				(font
					(size 1.27 1.27)
				)
				(justify mirror)
			)
		)
		(duplicate_pad_numbers_are_jumpers no)
		(fp_rect
			(start 0.499872 1.522476)
			(end -0.500126 -0.277622)
			(stroke
				(width 0)
				(type default)
			)
			(fill no)
			(layer "B.CrtYd")
		)
		(fp_line
			(start 0.499872 -0.277622)
			(end -0.500126 -0.277622)
			(stroke
				(width 0.1)
				(type default)
			)
			(layer "B.Fab")
		)
		(fp_line
			(start -0.500126 -0.277622)
			(end -0.500126 1.522476)
			(stroke
				(width 0.1)
				(type default)
			)
			(layer "B.Fab")
		)
		(fp_line
			(start 0.499872 1.522476)
			(end 0.499872 -0.277622)
			(stroke
				(width 0.1)
				(type default)
			)
			(layer "B.Fab")
		)
		(fp_line
			(start -0.500126 1.522476)
			(end 0.499872 1.522476)
			(stroke
				(width 0.1)
				(type default)
			)
			(layer "B.Fab")
		)
		(pad "1" smd custom
			(at 0 0)
			(size 0.18415 0.18415)
			(layers "B.Cu" "B.Mask" "B.Paste")
			(net "PVNN_PCH_STBY")
			(options
				(clearance outline)
				(anchor circle)
			)
			(primitives
				(gr_poly
					(pts
						(arc
							(start -0.3683 0.2794)
							(mid -0.338542 0.351242)
							(end -0.2667 0.381)
						)
						(arc
							(start 0.2667 0.381)
							(mid 0.338542 0.351242)
							(end 0.3683 0.2794)
						)
						(arc
							(start 0.3683 -0.2794)
							(mid 0.338542 -0.351242)
							(end 0.2667 -0.381)
						)
						(arc
							(start -0.2667 -0.381)
							(mid -0.338542 -0.351242)
							(end -0.3683 -0.2794)
						)
					)
					(width 0)
					(fill yes)
				)
			)
		)
		(pad "2" smd custom
			(at 0 1.2446)
			(size 0.18415 0.18415)
			(layers "B.Cu" "B.Mask" "B.Paste")
			(net "GND")
			(options
				(clearance outline)
				(anchor circle)
			)
			(primitives
				(gr_poly
					(pts
						(arc
							(start -0.3683 0.2794)
							(mid -0.338542 0.351242)
							(end -0.2667 0.381)
						)
						(arc
							(start 0.2667 0.381)
							(mid 0.338542 0.351242)
							(end 0.3683 0.2794)
						)
						(arc
							(start 0.3683 -0.2794)
							(mid 0.338542 -0.351242)
							(end 0.2667 -0.381)
						)
						(arc
							(start -0.2667 -0.381)
							(mid -0.338542 -0.351242)
							(end -0.3683 -0.2794)
						)
					)
					(width 0)
					(fill yes)
				)
			)
		)
		(zone
			(layer "B.Cu")
			(hatch none 0.5)
			(connect_pads
				(clearance 0)
			)
			(min_thickness 0.25)
			(keepout
				(tracks not_allowed)
				(vias allowed)
				(pads allowed)
				(copperpour not_allowed)
				(footprints allowed)
			)
			(placement
				(enabled no)
				(sheetname "")
			)
			(fill
				(thermal_gap 0.5)
				(thermal_bridge_width 0.5)
				(island_removal_mode 0)
			)
			(polygon
				(pts
					(xy 386.5245 -110.2614) (xy 386.0165 -110.2614) (xy 386.0165 -109.4994) (xy 386.5245 -109.4994)
				)
			)
		)
		(zone
			(layer "B.Cu")
			(hatch none 0.5)
			(connect_pads
				(clearance 0)
			)
			(min_thickness 0.25)
			(keepout
				(tracks allowed)
				(vias not_allowed)
				(pads allowed)
				(copperpour not_allowed)
				(footprints allowed)
			)
			(placement
				(enabled no)
				(sheetname "")
			)
			(fill
				(thermal_gap 0.5)
				(thermal_bridge_width 0.5)
				(island_removal_mode 0)
			)
			(polygon
				(pts
					(xy 386.5245 -110.2614) (xy 386.0165 -110.2614) (xy 386.0165 -109.4994) (xy 386.5245 -109.4994)
				)
			)
		)
	)
	(footprint ""
		(layer "B.Cu")
		(at 174.371 -65.024 -90)
		(property "Reference" "R6P49"
			(at 0 0 90)
			(layer "B.SilkS")
			(hide yes)
			(effects
				(font
					(size 1.27 1.27)
				)
				(justify mirror)
			)
		)
		(property "Value" ""
			(at 0 0 90)
			(layer "B.Fab")
			(effects
				(font
					(size 1.27 1.27)
				)
				(justify mirror)
			)
		)
		(duplicate_pad_numbers_are_jumpers no)
		(fp_poly
			(pts
				(xy 0.2794 -0.1016) (xy -0.2794 -0.1016) (xy -0.2794 0.9906) (xy 0.2794 0.9906)
			)
			(stroke
				(width 0)
				(type default)
			)
			(fill no)
			(layer "B.CrtYd")
		)
		(fp_line
			(start -0.2794 0.9906)
			(end -0.2794 -0.1016)
			(stroke
				(width 0.1)
				(type default)
			)
			(layer "B.Fab")
		)
		(fp_line
			(start 0.2794 0.9906)
			(end -0.2794 0.9906)
			(stroke
				(width 0.1)
				(type default)
			)
			(layer "B.Fab")
		)
		(fp_line
			(start -0.2794 -0.1016)
			(end 0.2794 -0.1016)
			(stroke
				(width 0.1)
				(type default)
			)
			(layer "B.Fab")
		)
		(fp_line
			(start 0.2794 -0.1016)
			(end 0.2794 0.9906)
			(stroke
				(width 0.1)
				(type default)
			)
			(layer "B.Fab")
		)
		(pad "1" smd rect
			(at 0 0 90)
			(size 0.508 0.508)
			(layers "B.Cu" "B.Mask" "B.Paste")
			(net "P3V3_STBY")
		)
		(pad "2" smd rect
			(at 0 0.889 90)
			(size 0.508 0.508)
			(layers "B.Cu" "B.Mask" "B.Paste")
			(net "PU_VR_PVCCIO_CPU1_FAULT1")
		)
		(zone
			(layer "B.Cu")
			(hatch none 0.5)
			(connect_pads
				(clearance 0)
			)
			(min_thickness 0.25)
			(keepout
				(tracks not_allowed)
				(vias allowed)
				(pads allowed)
				(copperpour not_allowed)
				(footprints allowed)
			)
			(placement
				(enabled no)
				(sheetname "")
			)
			(fill
				(thermal_gap 0.5)
				(thermal_bridge_width 0.5)
				(island_removal_mode 0)
			)
			(polygon
				(pts
					(xy 173.736 -64.77) (xy 173.736 -65.278) (xy 174.117 -65.278) (xy 174.117 -64.77)
				)
			)
		)
		(zone
			(layer "B.Cu")
			(hatch none 0.5)
			(connect_pads
				(clearance 0)
			)
			(min_thickness 0.25)
			(keepout
				(tracks allowed)
				(vias not_allowed)
				(pads allowed)
				(copperpour not_allowed)
				(footprints allowed)
			)
			(placement
				(enabled no)
				(sheetname "")
			)
			(fill
				(thermal_gap 0.5)
				(thermal_bridge_width 0.5)
				(island_removal_mode 0)
			)
			(polygon
				(pts
					(xy 174.117 -64.77) (xy 174.117 -65.278) (xy 173.736 -65.278) (xy 173.736 -64.77)
				)
			)
		)
	)
	(footprint ""
		(layer "B.Cu")
		(at 418.4142 -74.0537)
		(property "Reference" "R2T3"
			(at 0 0 0)
			(layer "B.SilkS")
			(hide yes)
			(effects
				(font
					(size 1.27 1.27)
				)
				(justify mirror)
			)
		)
		(property "Value" ""
			(at 0 0 0)
			(layer "B.Fab")
			(effects
				(font
					(size 1.27 1.27)
				)
				(justify mirror)
			)
		)
		(duplicate_pad_numbers_are_jumpers no)
		(fp_poly
			(pts
				(xy 0.2794 -0.1016) (xy -0.2794 -0.1016) (xy -0.2794 0.9906) (xy 0.2794 0.9906)
			)
			(stroke
				(width 0)
				(type default)
			)
			(fill no)
			(layer "B.CrtYd")
		)
		(fp_line
			(start -0.2794 -0.1016)
			(end 0.2794 -0.1016)
			(stroke
				(width 0.1)
				(type default)
			)
			(layer "B.Fab")
		)
		(fp_line
			(start -0.2794 0.9906)
			(end -0.2794 -0.1016)
			(stroke
				(width 0.1)
				(type default)
			)
			(layer "B.Fab")
		)
		(fp_line
			(start 0.2794 -0.1016)
			(end 0.2794 0.9906)
			(stroke
				(width 0.1)
				(type default)
			)
			(layer "B.Fab")
		)
		(fp_line
			(start 0.2794 0.9906)
			(end -0.2794 0.9906)
			(stroke
				(width 0.1)
				(type default)
			)
			(layer "B.Fab")
		)
		(pad "1" smd rect
			(at 0 0 180)
			(size 0.508 0.508)
			(layers "B.Cu" "B.Mask" "B.Paste")
			(net "P3V3_STBY")
		)
		(pad "2" smd rect
			(at 0 0.889 180)
			(size 0.508 0.508)
			(layers "B.Cu" "B.Mask" "B.Paste")
			(net "FM_FAST_PROCHOT_EN_N")
		)
		(zone
			(layer "B.Cu")
			(hatch none 0.5)
			(connect_pads
				(clearance 0)
			)
			(min_thickness 0.25)
			(keepout
				(tracks allowed)
				(vias not_allowed)
				(pads allowed)
				(copperpour not_allowed)
				(footprints allowed)
			)
			(placement
				(enabled no)
				(sheetname "")
			)
			(fill
				(thermal_gap 0.5)
				(thermal_bridge_width 0.5)
				(island_removal_mode 0)
			)
			(polygon
				(pts
					(xy 418.6682 -73.7997) (xy 418.1602 -73.7997) (xy 418.1602 -73.4187) (xy 418.6682 -73.4187)
				)
			)
		)
		(zone
			(layer "B.Cu")
			(hatch none 0.5)
			(connect_pads
				(clearance 0)
			)
			(min_thickness 0.25)
			(keepout
				(tracks not_allowed)
				(vias allowed)
				(pads allowed)
				(copperpour not_allowed)
				(footprints allowed)
			)
			(placement
				(enabled no)
				(sheetname "")
			)
			(fill
				(thermal_gap 0.5)
				(thermal_bridge_width 0.5)
				(island_removal_mode 0)
			)
			(polygon
				(pts
					(xy 418.6682 -73.4187) (xy 418.1602 -73.4187) (xy 418.1602 -73.7997) (xy 418.6682 -73.7997)
				)
			)
		)
	)
	(footprint ""
		(layer "B.Cu")
		(at 245.018306 -65.1764 -90)
		(property "Reference" "R5P4"
			(at 0 0 90)
			(layer "B.SilkS")
			(hide yes)
			(effects
				(font
					(size 1.27 1.27)
				)
				(justify mirror)
			)
		)
		(property "Value" ""
			(at 0 0 90)
			(layer "B.Fab")
			(effects
				(font
					(size 1.27 1.27)
				)
				(justify mirror)
			)
		)
		(duplicate_pad_numbers_are_jumpers no)
		(fp_poly
			(pts
				(xy 0.2794 -0.1016) (xy -0.2794 -0.1016) (xy -0.2794 0.9906) (xy 0.2794 0.9906)
			)
			(stroke
				(width 0)
				(type default)
			)
			(fill no)
			(layer "B.CrtYd")
		)
		(fp_line
			(start -0.2794 0.9906)
			(end -0.2794 -0.1016)
			(stroke
				(width 0.1)
				(type default)
			)
			(layer "B.Fab")
		)
		(fp_line
			(start 0.2794 0.9906)
			(end -0.2794 0.9906)
			(stroke
				(width 0.1)
				(type default)
			)
			(layer "B.Fab")
		)
		(fp_line
			(start -0.2794 -0.1016)
			(end 0.2794 -0.1016)
			(stroke
				(width 0.1)
				(type default)
			)
			(layer "B.Fab")
		)
		(fp_line
			(start 0.2794 -0.1016)
			(end 0.2794 0.9906)
			(stroke
				(width 0.1)
				(type default)
			)
			(layer "B.Fab")
		)
		(pad "1" smd rect
			(at 0 0 90)
			(size 0.508 0.508)
			(layers "B.Cu" "B.Mask" "B.Paste")
			(net "PD_CPU0_RSVD_TEST_2")
		)
		(pad "2" smd rect
			(at 0 0.889 90)
			(size 0.508 0.508)
			(layers "B.Cu" "B.Mask" "B.Paste")
			(net "GND")
		)
		(zone
			(layer "B.Cu")
			(hatch none 0.5)
			(connect_pads
				(clearance 0)
			)
			(min_thickness 0.25)
			(keepout
				(tracks not_allowed)
				(vias allowed)
				(pads allowed)
				(copperpour not_allowed)
				(footprints allowed)
			)
			(placement
				(enabled no)
				(sheetname "")
			)
			(fill
				(thermal_gap 0.5)
				(thermal_bridge_width 0.5)
				(island_removal_mode 0)
			)
			(polygon
				(pts
					(xy 244.383306 -64.9224) (xy 244.383306 -65.4304) (xy 244.764306 -65.4304) (xy 244.764306 -64.9224)
				)
			)
		)
		(zone
			(layer "B.Cu")
			(hatch none 0.5)
			(connect_pads
				(clearance 0)
			)
			(min_thickness 0.25)
			(keepout
				(tracks allowed)
				(vias not_allowed)
				(pads allowed)
				(copperpour not_allowed)
				(footprints allowed)
			)
			(placement
				(enabled no)
				(sheetname "")
			)
			(fill
				(thermal_gap 0.5)
				(thermal_bridge_width 0.5)
				(island_removal_mode 0)
			)
			(polygon
				(pts
					(xy 244.764306 -64.9224) (xy 244.764306 -65.4304) (xy 244.383306 -65.4304) (xy 244.383306 -64.9224)
				)
			)
		)
	)
	(footprint ""
		(layer "B.Cu")
		(at 460.388208 -132.842254 -90)
		(property "Reference" "R1M4"
			(at 0 0 90)
			(layer "B.SilkS")
			(hide yes)
			(effects
				(font
					(size 1.27 1.27)
				)
				(justify mirror)
			)
		)
		(property "Value" ""
			(at 0 0 90)
			(layer "B.Fab")
			(effects
				(font
					(size 1.27 1.27)
				)
				(justify mirror)
			)
		)
		(duplicate_pad_numbers_are_jumpers no)
		(fp_poly
			(pts
				(xy 0.2794 -0.1016) (xy -0.2794 -0.1016) (xy -0.2794 0.9906) (xy 0.2794 0.9906)
			)
			(stroke
				(width 0)
				(type default)
			)
			(fill no)
			(layer "B.CrtYd")
		)
		(fp_line
			(start -0.2794 0.9906)
			(end -0.2794 -0.1016)
			(stroke
				(width 0.1)
				(type default)
			)
			(layer "B.Fab")
		)
		(fp_line
			(start 0.2794 0.9906)
			(end -0.2794 0.9906)
			(stroke
				(width 0.1)
				(type default)
			)
			(layer "B.Fab")
		)
		(fp_line
			(start -0.2794 -0.1016)
			(end 0.2794 -0.1016)
			(stroke
				(width 0.1)
				(type default)
			)
			(layer "B.Fab")
		)
		(fp_line
			(start 0.2794 -0.1016)
			(end 0.2794 0.9906)
			(stroke
				(width 0.1)
				(type default)
			)
			(layer "B.Fab")
		)
		(pad "1" smd rect
			(at 0 0 90)
			(size 0.508 0.508)
			(layers "B.Cu" "B.Mask" "B.Paste")
			(net "PVCCIO_CPU0")
		)
		(pad "2" smd rect
			(at 0 0.889 90)
			(size 0.508 0.508)
			(layers "B.Cu" "B.Mask" "B.Paste")
			(net "XDP_CPU_PREQ_N")
		)
		(zone
			(layer "B.Cu")
			(hatch none 0.5)
			(connect_pads
				(clearance 0)
			)
			(min_thickness 0.25)
			(keepout
				(tracks not_allowed)
				(vias allowed)
				(pads allowed)
				(copperpour not_allowed)
				(footprints allowed)
			)
			(placement
				(enabled no)
				(sheetname "")
			)
			(fill
				(thermal_gap 0.5)
				(thermal_bridge_width 0.5)
				(island_removal_mode 0)
			)
			(polygon
				(pts
					(xy 459.753208 -132.588254) (xy 459.753208 -133.096254) (xy 460.134208 -133.096254) (xy 460.134208 -132.588254)
				)
			)
		)
		(zone
			(layer "B.Cu")
			(hatch none 0.5)
			(connect_pads
				(clearance 0)
			)
			(min_thickness 0.25)
			(keepout
				(tracks allowed)
				(vias not_allowed)
				(pads allowed)
				(copperpour not_allowed)
				(footprints allowed)
			)
			(placement
				(enabled no)
				(sheetname "")
			)
			(fill
				(thermal_gap 0.5)
				(thermal_bridge_width 0.5)
				(island_removal_mode 0)
			)
			(polygon
				(pts
					(xy 460.134208 -132.588254) (xy 460.134208 -133.096254) (xy 459.753208 -133.096254) (xy 459.753208 -132.588254)
				)
			)
		)
	)
	(footprint ""
		(layer "B.Cu")
		(at 466.852 -140.3604 90)
		(property "Reference" "C1L20"
			(at 0 0 90)
			(layer "B.SilkS")
			(hide yes)
			(effects
				(font
					(size 1.27 1.27)
				)
				(justify mirror)
			)
		)
		(property "Value" ""
			(at 0 0 90)
			(layer "B.Fab")
			(effects
				(font
					(size 1.27 1.27)
				)
				(justify mirror)
			)
		)
		(duplicate_pad_numbers_are_jumpers no)
		(fp_poly
			(pts
				(xy -0.3048 -0.1016) (xy -0.3048 0.9906) (xy 0.3048 0.9906) (xy 0.3048 -0.1016)
			)
			(stroke
				(width 0)
				(type default)
			)
			(fill no)
			(layer "B.CrtYd")
		)
		(fp_line
			(start 0.3048 -0.1016)
			(end 0.3048 0.9906)
			(stroke
				(width 0.1)
				(type default)
			)
			(layer "B.Fab")
		)
		(fp_line
			(start -0.3048 -0.1016)
			(end 0.3048 -0.1016)
			(stroke
				(width 0.1)
				(type default)
			)
			(layer "B.Fab")
		)
		(fp_line
			(start 0.3048 0.9906)
			(end -0.3048 0.9906)
			(stroke
				(width 0.1)
				(type default)
			)
			(layer "B.Fab")
		)
		(fp_line
			(start -0.3048 0.9906)
			(end -0.3048 -0.1016)
			(stroke
				(width 0.1)
				(type default)
			)
			(layer "B.Fab")
		)
		(pad "1" smd rect
			(at 0 0 270)
			(size 0.508 0.508)
			(layers "B.Cu" "B.Mask" "B.Paste")
			(net "P3V3_STBY")
		)
		(pad "2" smd rect
			(at 0 0.889 270)
			(size 0.508 0.508)
			(layers "B.Cu" "B.Mask" "B.Paste")
			(net "GND")
		)
		(zone
			(layer "B.Cu")
			(hatch none 0.5)
			(connect_pads
				(clearance 0)
			)
			(min_thickness 0.25)
			(keepout
				(tracks allowed)
				(vias not_allowed)
				(pads allowed)
				(copperpour not_allowed)
				(footprints allowed)
			)
			(placement
				(enabled no)
				(sheetname "")
			)
			(fill
				(thermal_gap 0.5)
				(thermal_bridge_width 0.5)
				(island_removal_mode 0)
			)
			(polygon
				(pts
					(xy 467.106 -140.6144) (xy 467.106 -140.1064) (xy 467.487 -140.1064) (xy 467.487 -140.6144)
				)
			)
		)
		(zone
			(layer "B.Cu")
			(hatch none 0.5)
			(connect_pads
				(clearance 0)
			)
			(min_thickness 0.25)
			(keepout
				(tracks not_allowed)
				(vias allowed)
				(pads allowed)
				(copperpour not_allowed)
				(footprints allowed)
			)
			(placement
				(enabled no)
				(sheetname "")
			)
			(fill
				(thermal_gap 0.5)
				(thermal_bridge_width 0.5)
				(island_removal_mode 0)
			)
			(polygon
				(pts
					(xy 467.487 -140.6144) (xy 467.487 -140.1064) (xy 467.106 -140.1064) (xy 467.106 -140.6144)
				)
			)
		)
	)
	(footprint ""
		(layer "B.Cu")
		(at 448.19189 -29.6164 -90)
		(property "Reference" "R1T30"
			(at 0 0 90)
			(layer "B.SilkS")
			(hide yes)
			(effects
				(font
					(size 1.27 1.27)
				)
				(justify mirror)
			)
		)
		(property "Value" ""
			(at 0 0 90)
			(layer "B.Fab")
			(effects
				(font
					(size 1.27 1.27)
				)
				(justify mirror)
			)
		)
		(duplicate_pad_numbers_are_jumpers no)
		(fp_poly
			(pts
				(xy 0.2794 -0.1016) (xy -0.2794 -0.1016) (xy -0.2794 0.9906) (xy 0.2794 0.9906)
			)
			(stroke
				(width 0)
				(type default)
			)
			(fill no)
			(layer "B.CrtYd")
		)
		(fp_line
			(start -0.2794 0.9906)
			(end -0.2794 -0.1016)
			(stroke
				(width 0.1)
				(type default)
			)
			(layer "B.Fab")
		)
		(fp_line
			(start 0.2794 0.9906)
			(end -0.2794 0.9906)
			(stroke
				(width 0.1)
				(type default)
			)
			(layer "B.Fab")
		)
		(fp_line
			(start -0.2794 -0.1016)
			(end 0.2794 -0.1016)
			(stroke
				(width 0.1)
				(type default)
			)
			(layer "B.Fab")
		)
		(fp_line
			(start 0.2794 -0.1016)
			(end 0.2794 0.9906)
			(stroke
				(width 0.1)
				(type default)
			)
			(layer "B.Fab")
		)
		(pad "1" smd rect
			(at 0 0 90)
			(size 0.508 0.508)
			(layers "B.Cu" "B.Mask" "B.Paste")
			(net "P1V2_AUX_BMC")
		)
		(pad "2" smd rect
			(at 0 0.889 90)
			(size 0.508 0.508)
			(layers "B.Cu" "B.Mask" "B.Paste")
			(net "BMC_M_VREFCA")
		)
		(zone
			(layer "B.Cu")
			(hatch none 0.5)
			(connect_pads
				(clearance 0)
			)
			(min_thickness 0.25)
			(keepout
				(tracks not_allowed)
				(vias allowed)
				(pads allowed)
				(copperpour not_allowed)
				(footprints allowed)
			)
			(placement
				(enabled no)
				(sheetname "")
			)
			(fill
				(thermal_gap 0.5)
				(thermal_bridge_width 0.5)
				(island_removal_mode 0)
			)
			(polygon
				(pts
					(xy 447.55689 -29.3624) (xy 447.55689 -29.8704) (xy 447.93789 -29.8704) (xy 447.93789 -29.3624)
				)
			)
		)
		(zone
			(layer "B.Cu")
			(hatch none 0.5)
			(connect_pads
				(clearance 0)
			)
			(min_thickness 0.25)
			(keepout
				(tracks allowed)
				(vias not_allowed)
				(pads allowed)
				(copperpour not_allowed)
				(footprints allowed)
			)
			(placement
				(enabled no)
				(sheetname "")
			)
			(fill
				(thermal_gap 0.5)
				(thermal_bridge_width 0.5)
				(island_removal_mode 0)
			)
			(polygon
				(pts
					(xy 447.93789 -29.3624) (xy 447.93789 -29.8704) (xy 447.55689 -29.8704) (xy 447.55689 -29.3624)
				)
			)
		)
	)
	(footprint ""
		(layer "B.Cu")
		(at 20.888706 -81.520792 -90)
		(property "Reference" "R9P13"
			(at 0 0 90)
			(layer "B.SilkS")
			(hide yes)
			(effects
				(font
					(size 1.27 1.27)
				)
				(justify mirror)
			)
		)
		(property "Value" "*"
			(at -0.064008 -4.108196 270)
			(unlocked yes)
			(layer "B.Fab")
			(hide yes)
			(effects
				(font
					(size 1.27 1.016)
					(thickness 0.1524)
				)
				(justify mirror)
			)
		)
		(property "Device Type" "270KR2F-GP_RCL_GP-270KR2F-GP,6A"
			(at -0.064008 -5.632196 270)
			(unlocked yes)
			(layer "B.Fab")
			(hide yes)
			(effects
				(font
					(size 1.27 1.016)
					(thickness 0.1524)
				)
				(justify mirror)
			)
		)
		(duplicate_pad_numbers_are_jumpers no)
		(fp_line
			(start -0.508 -0.9398)
			(end 0.508 -0.9398)
			(stroke
				(width 0.1524)
				(type default)
			)
			(layer "B.SilkS")
		)
		(fp_line
			(start 0.508 -0.9398)
			(end 0.508 0.9398)
			(stroke
				(width 0.1524)
				(type default)
			)
			(layer "B.SilkS")
		)
		(fp_rect
			(start 0.508 0.9398)
			(end -0.508 -0.9398)
			(stroke
				(width 0)
				(type default)
			)
			(fill no)
			(layer "B.CrtYd")
		)
		(fp_rect
			(start 0.508 0.9398)
			(end -0.508 -0.9398)
			(stroke
				(width 0)
				(type default)
			)
			(fill no)
			(layer "B.Fab")
		)
		(pad "1" smd custom
			(at 0 -0.4445 90)
			(size 0.1397 0.1397)
			(layers "B.Cu" "B.Mask" "B.Paste")
			(net "P12V_STBY")
			(options
				(clearance outline)
				(anchor circle)
			)
			(primitives
				(gr_poly
					(pts
						(arc
							(start -0.1778 0.2794)
							(mid -0.249642 0.249642)
							(end -0.2794 0.1778)
						)
						(arc
							(start -0.2794 -0.1778)
							(mid -0.249642 -0.249642)
							(end -0.1778 -0.2794)
						)
						(arc
							(start 0.1778 -0.2794)
							(mid 0.249642 -0.249642)
							(end 0.2794 -0.1778)
						)
						(arc
							(start 0.2794 0.1778)
							(mid 0.249642 0.249642)
							(end 0.1778 0.2794)
						)
					)
					(width 0)
					(fill yes)
				)
			)
		)
		(pad "2" smd custom
			(at 0 0.4445 90)
			(size 0.1397 0.1397)
			(layers "B.Cu" "B.Mask" "B.Paste")
			(net "A_P12V_STBY_FP_TRIGGER")
			(options
				(clearance outline)
				(anchor circle)
			)
			(primitives
				(gr_poly
					(pts
						(arc
							(start -0.1778 0.2794)
							(mid -0.249642 0.249642)
							(end -0.2794 0.1778)
						)
						(arc
							(start -0.2794 -0.1778)
							(mid -0.249642 -0.249642)
							(end -0.1778 -0.2794)
						)
						(arc
							(start 0.1778 -0.2794)
							(mid 0.249642 -0.249642)
							(end 0.2794 -0.1778)
						)
						(arc
							(start 0.2794 0.1778)
							(mid 0.249642 0.249642)
							(end 0.1778 0.2794)
						)
					)
					(width 0)
					(fill yes)
				)
			)
		)
	)
	(footprint ""
		(layer "B.Cu")
		(at 168.088818 -73.653396 180)
		(property "Reference" "R4W6"
			(at 0.8382 -0.67818 180)
			(unlocked yes)
			(layer "B.SilkS")
			(effects
				(font
					(size 0.4064 0.254)
					(thickness 0.1524)
				)
				(justify left mirror)
			)
		)
		(property "Value" ""
			(at 0 0 0)
			(layer "B.Fab")
			(effects
				(font
					(size 1.27 1.27)
				)
				(justify mirror)
			)
		)
		(duplicate_pad_numbers_are_jumpers no)
		(fp_poly
			(pts
				(xy 0.2794 -0.1016) (xy -0.2794 -0.1016) (xy -0.2794 0.9906) (xy 0.2794 0.9906)
			)
			(stroke
				(width 0)
				(type default)
			)
			(fill no)
			(layer "B.CrtYd")
		)
		(fp_line
			(start 0.2794 0.9906)
			(end -0.2794 0.9906)
			(stroke
				(width 0.1)
				(type default)
			)
			(layer "B.Fab")
		)
		(fp_line
			(start 0.2794 -0.1016)
			(end 0.2794 0.9906)
			(stroke
				(width 0.1)
				(type default)
			)
			(layer "B.Fab")
		)
		(fp_line
			(start -0.2794 0.9906)
			(end -0.2794 -0.1016)
			(stroke
				(width 0.1)
				(type default)
			)
			(layer "B.Fab")
		)
		(fp_line
			(start -0.2794 -0.1016)
			(end 0.2794 -0.1016)
			(stroke
				(width 0.1)
				(type default)
			)
			(layer "B.Fab")
		)
		(pad "1" smd rect
			(at 0 0)
			(size 0.508 0.508)
			(layers "B.Cu" "B.Mask" "B.Paste")
			(net "P3V3_DB1200")
		)
		(pad "2" smd rect
			(at 0 0.889)
			(size 0.508 0.508)
			(layers "B.Cu" "B.Mask" "B.Paste")
			(net "FM_DB1200_PWRGD_R")
		)
		(zone
			(layer "B.Cu")
			(hatch none 0.5)
			(connect_pads
				(clearance 0)
			)
			(min_thickness 0.25)
			(keepout
				(tracks not_allowed)
				(vias allowed)
				(pads allowed)
				(copperpour not_allowed)
				(footprints allowed)
			)
			(placement
				(enabled no)
				(sheetname "")
			)
			(fill
				(thermal_gap 0.5)
				(thermal_bridge_width 0.5)
				(island_removal_mode 0)
			)
			(polygon
				(pts
					(xy 167.834818 -74.288396) (xy 168.342818 -74.288396) (xy 168.342818 -73.907396) (xy 167.834818 -73.907396)
				)
			)
		)
		(zone
			(layer "B.Cu")
			(hatch none 0.5)
			(connect_pads
				(clearance 0)
			)
			(min_thickness 0.25)
			(keepout
				(tracks allowed)
				(vias not_allowed)
				(pads allowed)
				(copperpour not_allowed)
				(footprints allowed)
			)
			(placement
				(enabled no)
				(sheetname "")
			)
			(fill
				(thermal_gap 0.5)
				(thermal_bridge_width 0.5)
				(island_removal_mode 0)
			)
			(polygon
				(pts
					(xy 167.834818 -73.907396) (xy 168.342818 -73.907396) (xy 168.342818 -74.288396) (xy 167.834818 -74.288396)
				)
			)
		)
	)
	(footprint ""
		(layer "B.Cu")
		(at -0.6604 -137.7696)
		(property "Reference" "CT8"
			(at 0.8382 -0.84963 0)
			(unlocked yes)
			(layer "B.SilkS")
			(effects
				(font
					(size 0.7874 0.5842)
					(thickness 0.1524)
				)
				(justify left mirror)
			)
		)
		(property "Value" ""
			(at 0 0 0)
			(layer "B.Fab")
			(effects
				(font
					(size 1.27 1.27)
				)
				(justify mirror)
			)
		)
		(duplicate_pad_numbers_are_jumpers no)
		(fp_poly
			(pts
				(xy -0.3048 -0.1016) (xy -0.3048 0.9906) (xy 0.3048 0.9906) (xy 0.3048 -0.1016)
			)
			(stroke
				(width 0)
				(type default)
			)
			(fill no)
			(layer "B.CrtYd")
		)
		(fp_line
			(start -0.3048 -0.1016)
			(end 0.3048 -0.1016)
			(stroke
				(width 0.1)
				(type default)
			)
			(layer "B.Fab")
		)
		(fp_line
			(start -0.3048 0.9906)
			(end -0.3048 -0.1016)
			(stroke
				(width 0.1)
				(type default)
			)
			(layer "B.Fab")
		)
		(fp_line
			(start 0.3048 -0.1016)
			(end 0.3048 0.9906)
			(stroke
				(width 0.1)
				(type default)
			)
			(layer "B.Fab")
		)
		(fp_line
			(start 0.3048 0.9906)
			(end -0.3048 0.9906)
			(stroke
				(width 0.1)
				(type default)
			)
			(layer "B.Fab")
		)
		(pad "1" smd rect
			(at 0 0 180)
			(size 0.508 0.508)
			(layers "B.Cu" "B.Mask" "B.Paste")
			(net "A_TSENSE_PVDDQ_KLM")
		)
		(pad "2" smd rect
			(at 0 0.889 180)
			(size 0.508 0.508)
			(layers "B.Cu" "B.Mask" "B.Paste")
			(net "GND")
		)
		(zone
			(layer "B.Cu")
			(hatch none 0.5)
			(connect_pads
				(clearance 0)
			)
			(min_thickness 0.25)
			(keepout
				(tracks allowed)
				(vias not_allowed)
				(pads allowed)
				(copperpour not_allowed)
				(footprints allowed)
			)
			(placement
				(enabled no)
				(sheetname "")
			)
			(fill
				(thermal_gap 0.5)
				(thermal_bridge_width 0.5)
				(island_removal_mode 0)
			)
			(polygon
				(pts
					(xy -0.4064 -137.5156) (xy -0.9144 -137.5156) (xy -0.9144 -137.1346) (xy -0.4064 -137.1346)
				)
			)
		)
		(zone
			(layer "B.Cu")
			(hatch none 0.5)
			(connect_pads
				(clearance 0)
			)
			(min_thickness 0.25)
			(keepout
				(tracks not_allowed)
				(vias allowed)
				(pads allowed)
				(copperpour not_allowed)
				(footprints allowed)
			)
			(placement
				(enabled no)
				(sheetname "")
			)
			(fill
				(thermal_gap 0.5)
				(thermal_bridge_width 0.5)
				(island_removal_mode 0)
			)
			(polygon
				(pts
					(xy -0.4064 -137.1346) (xy -0.9144 -137.1346) (xy -0.9144 -137.5156) (xy -0.4064 -137.5156)
				)
			)
		)
	)
	(footprint ""
		(layer "B.Cu")
		(at 340.3092 -86.4362)
		(property "Reference" "R3P17"
			(at 0 0 0)
			(layer "B.SilkS")
			(hide yes)
			(effects
				(font
					(size 1.27 1.27)
				)
				(justify mirror)
			)
		)
		(property "Value" ""
			(at 0 0 0)
			(layer "B.Fab")
			(effects
				(font
					(size 1.27 1.27)
				)
				(justify mirror)
			)
		)
		(duplicate_pad_numbers_are_jumpers no)
		(fp_poly
			(pts
				(xy 0.2794 -0.1016) (xy -0.2794 -0.1016) (xy -0.2794 0.9906) (xy 0.2794 0.9906)
			)
			(stroke
				(width 0)
				(type default)
			)
			(fill no)
			(layer "B.CrtYd")
		)
		(fp_line
			(start -0.2794 -0.1016)
			(end 0.2794 -0.1016)
			(stroke
				(width 0.1)
				(type default)
			)
			(layer "B.Fab")
		)
		(fp_line
			(start -0.2794 0.9906)
			(end -0.2794 -0.1016)
			(stroke
				(width 0.1)
				(type default)
			)
			(layer "B.Fab")
		)
		(fp_line
			(start 0.2794 -0.1016)
			(end 0.2794 0.9906)
			(stroke
				(width 0.1)
				(type default)
			)
			(layer "B.Fab")
		)
		(fp_line
			(start 0.2794 0.9906)
			(end -0.2794 0.9906)
			(stroke
				(width 0.1)
				(type default)
			)
			(layer "B.Fab")
		)
		(pad "1" smd rect
			(at 0 0 180)
			(size 0.508 0.508)
			(layers "B.Cu" "B.Mask" "B.Paste")
			(net "PVCCIO_CPU0")
		)
		(pad "2" smd rect
			(at 0 0.889 180)
			(size 0.508 0.508)
			(layers "B.Cu" "B.Mask" "B.Paste")
			(net "SVID_CLK0_CPU0_R")
		)
		(zone
			(layer "B.Cu")
			(hatch none 0.5)
			(connect_pads
				(clearance 0)
			)
			(min_thickness 0.25)
			(keepout
				(tracks allowed)
				(vias not_allowed)
				(pads allowed)
				(copperpour not_allowed)
				(footprints allowed)
			)
			(placement
				(enabled no)
				(sheetname "")
			)
			(fill
				(thermal_gap 0.5)
				(thermal_bridge_width 0.5)
				(island_removal_mode 0)
			)
			(polygon
				(pts
					(xy 340.5632 -86.1822) (xy 340.0552 -86.1822) (xy 340.0552 -85.8012) (xy 340.5632 -85.8012)
				)
			)
		)
		(zone
			(layer "B.Cu")
			(hatch none 0.5)
			(connect_pads
				(clearance 0)
			)
			(min_thickness 0.25)
			(keepout
				(tracks not_allowed)
				(vias allowed)
				(pads allowed)
				(copperpour not_allowed)
				(footprints allowed)
			)
			(placement
				(enabled no)
				(sheetname "")
			)
			(fill
				(thermal_gap 0.5)
				(thermal_bridge_width 0.5)
				(island_removal_mode 0)
			)
			(polygon
				(pts
					(xy 340.5632 -85.8012) (xy 340.0552 -85.8012) (xy 340.0552 -86.1822) (xy 340.5632 -86.1822)
				)
			)
		)
	)
	(footprint ""
		(layer "B.Cu")
		(at 378.5362 -5.7658 -90)
		(property "Reference" "CR3U1"
			(at -1.6764 0.1524 0)
			(unlocked yes)
			(layer "B.SilkS")
			(effects
				(font
					(size 0.4064 0.254)
					(thickness 0.1524)
				)
				(justify left mirror)
			)
		)
		(property "Value" ""
			(at 0 0 90)
			(layer "B.Fab")
			(effects
				(font
					(size 1.27 1.27)
				)
				(justify mirror)
			)
		)
		(duplicate_pad_numbers_are_jumpers no)
		(fp_line
			(start -0.9144 2.9464)
			(end -0.8382 2.9464)
			(stroke
				(width 0.1524)
				(type default)
			)
			(layer "B.SilkS")
		)
		(fp_line
			(start 0.9144 2.9464)
			(end 0.8382 2.9464)
			(stroke
				(width 0.1524)
				(type default)
			)
			(layer "B.SilkS")
		)
		(fp_line
			(start -0.9144 0.1016)
			(end -0.9144 2.9464)
			(stroke
				(width 0.1524)
				(type default)
			)
			(layer "B.SilkS")
		)
		(fp_line
			(start -0.8382 0.1016)
			(end -0.9144 0.1016)
			(stroke
				(width 0.1524)
				(type default)
			)
			(layer "B.SilkS")
		)
		(fp_line
			(start 0.8382 0.1016)
			(end 0.9144 0.1016)
			(stroke
				(width 0.1524)
				(type default)
			)
			(layer "B.SilkS")
		)
		(fp_line
			(start 0.9144 0.1016)
			(end 0.9144 2.9464)
			(stroke
				(width 0.1524)
				(type default)
			)
			(layer "B.SilkS")
		)
		(fp_circle
			(center -1.128776 -0.907288)
			(end -1.128776 -1.034288)
			(stroke
				(width 0.254)
				(type default)
			)
			(fill no)
			(layer "B.SilkS")
		)
		(fp_poly
			(pts
				(xy 0 0.1016) (xy -0.5334 0.1016) (xy -0.7366 0.1016) (xy -0.9144 0.1016) (xy -0.9144 2.9464) (xy -0.8382 2.9464)
				(xy -0.762 2.9464) (xy 0.9144 2.9464) (xy 0.9144 2.7686) (xy 0.9144 2.159) (xy 0.9144 0.1016) (xy 0.7366 0.1016)
				(xy 0.5842 0.1016)
			)
			(stroke
				(width 0)
				(type default)
			)
			(fill no)
			(layer "B.CrtYd")
		)
		(fp_line
			(start -0.9144 2.9464)
			(end -0.9144 0.1016)
			(stroke
				(width 0.1)
				(type default)
			)
			(layer "B.Fab")
		)
		(fp_line
			(start 0.9144 2.9464)
			(end -0.9144 2.9464)
			(stroke
				(width 0.1)
				(type default)
			)
			(layer "B.Fab")
		)
		(fp_line
			(start -0.9144 0.1016)
			(end 0.9144 0.1016)
			(stroke
				(width 0.1)
				(type default)
			)
			(layer "B.Fab")
		)
		(fp_line
			(start 0.9144 0.1016)
			(end 0.9144 2.9464)
			(stroke
				(width 0.1)
				(type default)
			)
			(layer "B.Fab")
		)
		(fp_circle
			(center -1.128776 -0.907288)
			(end -1.128776 -1.034288)
			(stroke
				(width 0.254)
				(type default)
			)
			(fill no)
			(layer "B.Fab")
		)
		(pad "1" smd rect
			(at 0 0 180)
			(size 1.524 0.762)
			(layers "B.Cu" "B.Mask" "B.Paste")
			(net "P3V3_STBY_PLD_D")
		)
		(pad "2" smd rect
			(at 0 3.048)
			(size 1.524 0.762)
			(layers "B.Cu" "B.Mask" "B.Paste")
			(net "P3V3_STBY")
		)
	)
	(footprint ""
		(layer "B.Cu")
		(at 410.464 -153.162 90)
		(property "Reference" "C2L9"
			(at 0 0 90)
			(layer "B.SilkS")
			(hide yes)
			(effects
				(font
					(size 1.27 1.27)
				)
				(justify mirror)
			)
		)
		(property "Value" ""
			(at 0 0 90)
			(layer "B.Fab")
			(effects
				(font
					(size 1.27 1.27)
				)
				(justify mirror)
			)
		)
		(duplicate_pad_numbers_are_jumpers no)
		(fp_poly
			(pts
				(xy -0.3048 -0.1016) (xy -0.3048 0.9906) (xy 0.3048 0.9906) (xy 0.3048 -0.1016)
			)
			(stroke
				(width 0)
				(type default)
			)
			(fill no)
			(layer "B.CrtYd")
		)
		(fp_line
			(start 0.3048 -0.1016)
			(end 0.3048 0.9906)
			(stroke
				(width 0.1)
				(type default)
			)
			(layer "B.Fab")
		)
		(fp_line
			(start -0.3048 -0.1016)
			(end 0.3048 -0.1016)
			(stroke
				(width 0.1)
				(type default)
			)
			(layer "B.Fab")
		)
		(fp_line
			(start 0.3048 0.9906)
			(end -0.3048 0.9906)
			(stroke
				(width 0.1)
				(type default)
			)
			(layer "B.Fab")
		)
		(fp_line
			(start -0.3048 0.9906)
			(end -0.3048 -0.1016)
			(stroke
				(width 0.1)
				(type default)
			)
			(layer "B.Fab")
		)
		(pad "1" smd rect
			(at 0 0 270)
			(size 0.508 0.508)
			(layers "B.Cu" "B.Mask" "B.Paste")
			(net "SATA6G_PCH_PCIE_UP_SATA_RXN<5>")
		)
		(pad "2" smd rect
			(at 0 0.889 270)
			(size 0.508 0.508)
			(layers "B.Cu" "B.Mask" "B.Paste")
			(net "SATA6G_P5_RX_C_DN")
		)
		(zone
			(layer "B.Cu")
			(hatch none 0.5)
			(connect_pads
				(clearance 0)
			)
			(min_thickness 0.25)
			(keepout
				(tracks allowed)
				(vias not_allowed)
				(pads allowed)
				(copperpour not_allowed)
				(footprints allowed)
			)
			(placement
				(enabled no)
				(sheetname "")
			)
			(fill
				(thermal_gap 0.5)
				(thermal_bridge_width 0.5)
				(island_removal_mode 0)
			)
			(polygon
				(pts
					(xy 410.718 -153.416) (xy 410.718 -152.908) (xy 411.099 -152.908) (xy 411.099 -153.416)
				)
			)
		)
		(zone
			(layer "B.Cu")
			(hatch none 0.5)
			(connect_pads
				(clearance 0)
			)
			(min_thickness 0.25)
			(keepout
				(tracks not_allowed)
				(vias allowed)
				(pads allowed)
				(copperpour not_allowed)
				(footprints allowed)
			)
			(placement
				(enabled no)
				(sheetname "")
			)
			(fill
				(thermal_gap 0.5)
				(thermal_bridge_width 0.5)
				(island_removal_mode 0)
			)
			(polygon
				(pts
					(xy 411.099 -153.416) (xy 411.099 -152.908) (xy 410.718 -152.908) (xy 410.718 -153.416)
				)
			)
		)
	)
	(footprint ""
		(layer "B.Cu")
		(at 312.786268 -31.69285)
		(property "Reference" "R8D30"
			(at 0 0 0)
			(layer "B.SilkS")
			(hide yes)
			(effects
				(font
					(size 1.27 1.27)
				)
				(justify mirror)
			)
		)
		(property "Value" ""
			(at 0 0 0)
			(layer "B.Fab")
			(effects
				(font
					(size 1.27 1.27)
				)
				(justify mirror)
			)
		)
		(duplicate_pad_numbers_are_jumpers no)
		(fp_poly
			(pts
				(xy 0.2794 -0.1016) (xy -0.2794 -0.1016) (xy -0.2794 0.9906) (xy 0.2794 0.9906)
			)
			(stroke
				(width 0)
				(type default)
			)
			(fill no)
			(layer "B.CrtYd")
		)
		(fp_line
			(start -0.2794 -0.1016)
			(end 0.2794 -0.1016)
			(stroke
				(width 0.1)
				(type default)
			)
			(layer "B.Fab")
		)
		(fp_line
			(start -0.2794 0.9906)
			(end -0.2794 -0.1016)
			(stroke
				(width 0.1)
				(type default)
			)
			(layer "B.Fab")
		)
		(fp_line
			(start 0.2794 -0.1016)
			(end 0.2794 0.9906)
			(stroke
				(width 0.1)
				(type default)
			)
			(layer "B.Fab")
		)
		(fp_line
			(start 0.2794 0.9906)
			(end -0.2794 0.9906)
			(stroke
				(width 0.1)
				(type default)
			)
			(layer "B.Fab")
		)
		(pad "1" smd rect
			(at 0 0 180)
			(size 0.508 0.508)
			(layers "B.Cu" "B.Mask" "B.Paste")
			(net "IRQ_DIMM_SAVE_N")
		)
		(pad "2" smd rect
			(at 0 0.889 180)
			(size 0.508 0.508)
			(layers "B.Cu" "B.Mask" "B.Paste")
			(net "IRQ_DIMM_SAVE_R_N")
		)
		(zone
			(layer "B.Cu")
			(hatch none 0.5)
			(connect_pads
				(clearance 0)
			)
			(min_thickness 0.25)
			(keepout
				(tracks allowed)
				(vias not_allowed)
				(pads allowed)
				(copperpour not_allowed)
				(footprints allowed)
			)
			(placement
				(enabled no)
				(sheetname "")
			)
			(fill
				(thermal_gap 0.5)
				(thermal_bridge_width 0.5)
				(island_removal_mode 0)
			)
			(polygon
				(pts
					(xy 313.040268 -31.43885) (xy 312.532268 -31.43885) (xy 312.532268 -31.05785) (xy 313.040268 -31.05785)
				)
			)
		)
		(zone
			(layer "B.Cu")
			(hatch none 0.5)
			(connect_pads
				(clearance 0)
			)
			(min_thickness 0.25)
			(keepout
				(tracks not_allowed)
				(vias allowed)
				(pads allowed)
				(copperpour not_allowed)
				(footprints allowed)
			)
			(placement
				(enabled no)
				(sheetname "")
			)
			(fill
				(thermal_gap 0.5)
				(thermal_bridge_width 0.5)
				(island_removal_mode 0)
			)
			(polygon
				(pts
					(xy 313.040268 -31.05785) (xy 312.532268 -31.05785) (xy 312.532268 -31.43885) (xy 313.040268 -31.43885)
				)
			)
		)
	)
	(footprint ""
		(layer "B.Cu")
		(at 391.65022 -153.46172 -90)
		(property "Reference" "C4W3"
			(at 0.8382 -0.67818 270)
			(unlocked yes)
			(layer "B.SilkS")
			(effects
				(font
					(size 0.4064 0.254)
					(thickness 0.1524)
				)
				(justify left mirror)
			)
		)
		(property "Value" ""
			(at 0 0 90)
			(layer "B.Fab")
			(effects
				(font
					(size 1.27 1.27)
				)
				(justify mirror)
			)
		)
		(duplicate_pad_numbers_are_jumpers no)
		(fp_poly
			(pts
				(xy -0.3048 -0.1016) (xy -0.3048 0.9906) (xy 0.3048 0.9906) (xy 0.3048 -0.1016)
			)
			(stroke
				(width 0)
				(type default)
			)
			(fill no)
			(layer "B.CrtYd")
		)
		(fp_line
			(start -0.3048 0.9906)
			(end -0.3048 -0.1016)
			(stroke
				(width 0.1)
				(type default)
			)
			(layer "B.Fab")
		)
		(fp_line
			(start 0.3048 0.9906)
			(end -0.3048 0.9906)
			(stroke
				(width 0.1)
				(type default)
			)
			(layer "B.Fab")
		)
		(fp_line
			(start -0.3048 -0.1016)
			(end 0.3048 -0.1016)
			(stroke
				(width 0.1)
				(type default)
			)
			(layer "B.Fab")
		)
		(fp_line
			(start 0.3048 -0.1016)
			(end 0.3048 0.9906)
			(stroke
				(width 0.1)
				(type default)
			)
			(layer "B.Fab")
		)
		(pad "1" smd rect
			(at 0 0 90)
			(size 0.508 0.508)
			(layers "B.Cu" "B.Mask" "B.Paste")
			(net "A_TSENSE_PVNN_PCH_TMON")
		)
		(pad "2" smd rect
			(at 0 0.889 90)
			(size 0.508 0.508)
			(layers "B.Cu" "B.Mask" "B.Paste")
			(net "GND")
		)
		(zone
			(layer "B.Cu")
			(hatch none 0.5)
			(connect_pads
				(clearance 0)
			)
			(min_thickness 0.25)
			(keepout
				(tracks not_allowed)
				(vias allowed)
				(pads allowed)
				(copperpour not_allowed)
				(footprints allowed)
			)
			(placement
				(enabled no)
				(sheetname "")
			)
			(fill
				(thermal_gap 0.5)
				(thermal_bridge_width 0.5)
				(island_removal_mode 0)
			)
			(polygon
				(pts
					(xy 391.01522 -153.20772) (xy 391.01522 -153.71572) (xy 391.39622 -153.71572) (xy 391.39622 -153.20772)
				)
			)
		)
		(zone
			(layer "B.Cu")
			(hatch none 0.5)
			(connect_pads
				(clearance 0)
			)
			(min_thickness 0.25)
			(keepout
				(tracks allowed)
				(vias not_allowed)
				(pads allowed)
				(copperpour not_allowed)
				(footprints allowed)
			)
			(placement
				(enabled no)
				(sheetname "")
			)
			(fill
				(thermal_gap 0.5)
				(thermal_bridge_width 0.5)
				(island_removal_mode 0)
			)
			(polygon
				(pts
					(xy 391.39622 -153.20772) (xy 391.39622 -153.71572) (xy 391.01522 -153.71572) (xy 391.01522 -153.20772)
				)
			)
		)
	)
	(footprint ""
		(layer "B.Cu")
		(at 265.672824 -85.075014)
		(property "Reference" "C5P2"
			(at 0 0 0)
			(layer "B.SilkS")
			(hide yes)
			(effects
				(font
					(size 1.27 1.27)
				)
				(justify mirror)
			)
		)
		(property "Value" ""
			(at 0 0 0)
			(layer "B.Fab")
			(effects
				(font
					(size 1.27 1.27)
				)
				(justify mirror)
			)
		)
		(duplicate_pad_numbers_are_jumpers no)
		(fp_poly
			(pts
				(xy 0.7239 -0.2159) (xy -0.7239 -0.2159) (xy -0.7239 1.9939) (xy 0.7239 1.9939)
			)
			(stroke
				(width 0)
				(type default)
			)
			(fill no)
			(layer "B.CrtYd")
		)
		(fp_line
			(start -0.7239 -0.2159)
			(end 0.7239 -0.2159)
			(stroke
				(width 0.1)
				(type default)
			)
			(layer "B.Fab")
		)
		(fp_line
			(start -0.7239 1.9939)
			(end -0.7239 -0.2159)
			(stroke
				(width 0.1)
				(type default)
			)
			(layer "B.Fab")
		)
		(fp_line
			(start 0.7239 -0.2159)
			(end 0.7239 1.9939)
			(stroke
				(width 0.1)
				(type default)
			)
			(layer "B.Fab")
		)
		(fp_line
			(start 0.7239 1.9939)
			(end -0.7239 1.9939)
			(stroke
				(width 0.1)
				(type default)
			)
			(layer "B.Fab")
		)
		(pad "1" smd rect
			(at 0 0 180)
			(size 1.27 1.016)
			(layers "B.Cu" "B.Mask" "B.Paste")
			(net "PVDDQ_DEF")
		)
		(pad "2" smd rect
			(at 0 1.778 180)
			(size 1.27 1.016)
			(layers "B.Cu" "B.Mask" "B.Paste")
			(net "GND")
		)
		(zone
			(layer "B.Cu")
			(hatch none 0.5)
			(connect_pads
				(clearance 0)
			)
			(min_thickness 0.25)
			(keepout
				(tracks not_allowed)
				(vias allowed)
				(pads allowed)
				(copperpour not_allowed)
				(footprints allowed)
			)
			(placement
				(enabled no)
				(sheetname "")
			)
			(fill
				(thermal_gap 0.5)
				(thermal_bridge_width 0.5)
				(island_removal_mode 0)
			)
			(polygon
				(pts
					(xy 266.307824 -84.567014) (xy 265.037824 -84.567014) (xy 265.037824 -83.805014) (xy 266.307824 -83.805014)
				)
			)
		)
	)
	(footprint ""
		(layer "B.Cu")
		(at 394.13815 -110.25505 90)
		(property "Reference" "C2N7"
			(at 0 0 90)
			(layer "B.SilkS")
			(hide yes)
			(effects
				(font
					(size 1.27 1.27)
				)
				(justify mirror)
			)
		)
		(property "Value" ""
			(at 0 0 90)
			(layer "B.Fab")
			(effects
				(font
					(size 1.27 1.27)
				)
				(justify mirror)
			)
		)
		(duplicate_pad_numbers_are_jumpers no)
		(fp_rect
			(start 0.2794 0.9144)
			(end -0.2794 -0.1143)
			(stroke
				(width 0)
				(type default)
			)
			(fill no)
			(layer "B.CrtYd")
		)
		(fp_line
			(start 0.2794 -0.1143)
			(end -0.2794 -0.1143)
			(stroke
				(width 0.1)
				(type default)
			)
			(layer "B.Fab")
		)
		(fp_line
			(start -0.2794 -0.1143)
			(end -0.2794 0.9144)
			(stroke
				(width 0.1)
				(type default)
			)
			(layer "B.Fab")
		)
		(fp_line
			(start 0.2794 0.9144)
			(end 0.2794 -0.1143)
			(stroke
				(width 0.1)
				(type default)
			)
			(layer "B.Fab")
		)
		(fp_line
			(start -0.2794 0.9144)
			(end 0.2794 0.9144)
			(stroke
				(width 0.1)
				(type default)
			)
			(layer "B.Fab")
		)
		(pad "1" smd custom
			(at 0 0)
			(size 0.10414 0.10414)
			(layers "B.Cu" "B.Mask" "B.Paste")
			(net "P1V05_PCH_STBY")
			(options
				(clearance outline)
				(anchor circle)
			)
			(primitives
				(gr_poly
					(pts
						(xy -0.20828 -0.08636) (xy -0.20828 0.08636) (xy -0.08636 0.20828) (xy 0.086614 0.20828) (xy 0.20828 0.086614)
						(xy 0.20828 -0.08636) (xy 0.08636 -0.20828) (xy -0.08636 -0.20828)
					)
					(width 0)
					(fill yes)
				)
			)
		)
		(pad "2" smd custom
			(at 0 0.8001)
			(size 0.10414 0.10414)
			(layers "B.Cu" "B.Mask" "B.Paste")
			(net "GND")
			(options
				(clearance outline)
				(anchor circle)
			)
			(primitives
				(gr_poly
					(pts
						(xy -0.20828 -0.08636) (xy -0.20828 0.08636) (xy -0.08636 0.20828) (xy 0.086614 0.20828) (xy 0.20828 0.086614)
						(xy 0.20828 -0.08636) (xy 0.08636 -0.20828) (xy -0.08636 -0.20828)
					)
					(width 0)
					(fill yes)
				)
			)
		)
		(zone
			(layer "B.Cu")
			(hatch none 0.5)
			(connect_pads
				(clearance 0)
			)
			(min_thickness 0.25)
			(keepout
				(tracks not_allowed)
				(vias allowed)
				(pads allowed)
				(copperpour not_allowed)
				(footprints allowed)
			)
			(placement
				(enabled no)
				(sheetname "")
			)
			(fill
				(thermal_gap 0.5)
				(thermal_bridge_width 0.5)
				(island_removal_mode 0)
			)
			(polygon
				(pts
					(xy 394.3477 -110.34268) (xy 394.7287 -110.34268) (xy 394.7287 -110.16742) (xy 394.3477 -110.167166)
				)
			)
		)
		(zone
			(layer "B.Cu")
			(hatch none 0.5)
			(connect_pads
				(clearance 0)
			)
			(min_thickness 0.25)
			(keepout
				(tracks allowed)
				(vias not_allowed)
				(pads allowed)
				(copperpour not_allowed)
				(footprints allowed)
			)
			(placement
				(enabled no)
				(sheetname "")
			)
			(fill
				(thermal_gap 0.5)
				(thermal_bridge_width 0.5)
				(island_removal_mode 0)
			)
			(polygon
				(pts
					(xy 394.3477 -110.34268) (xy 394.7287 -110.34268) (xy 394.7287 -110.16742) (xy 394.3477 -110.167166)
				)
			)
		)
	)
	(footprint ""
		(layer "B.Cu")
		(at 358.3432 -4.2418 180)
		(property "Reference" "R8W12"
			(at 0.8382 -0.67818 180)
			(unlocked yes)
			(layer "B.SilkS")
			(effects
				(font
					(size 0.4064 0.254)
					(thickness 0.1524)
				)
				(justify left mirror)
			)
		)
		(property "Value" ""
			(at 0 0 0)
			(layer "B.Fab")
			(effects
				(font
					(size 1.27 1.27)
				)
				(justify mirror)
			)
		)
		(duplicate_pad_numbers_are_jumpers no)
		(fp_poly
			(pts
				(xy 0.2794 -0.1016) (xy -0.2794 -0.1016) (xy -0.2794 0.9906) (xy 0.2794 0.9906)
			)
			(stroke
				(width 0)
				(type default)
			)
			(fill no)
			(layer "B.CrtYd")
		)
		(fp_line
			(start 0.2794 0.9906)
			(end -0.2794 0.9906)
			(stroke
				(width 0.1)
				(type default)
			)
			(layer "B.Fab")
		)
		(fp_line
			(start 0.2794 -0.1016)
			(end 0.2794 0.9906)
			(stroke
				(width 0.1)
				(type default)
			)
			(layer "B.Fab")
		)
		(fp_line
			(start -0.2794 0.9906)
			(end -0.2794 -0.1016)
			(stroke
				(width 0.1)
				(type default)
			)
			(layer "B.Fab")
		)
		(fp_line
			(start -0.2794 -0.1016)
			(end 0.2794 -0.1016)
			(stroke
				(width 0.1)
				(type default)
			)
			(layer "B.Fab")
		)
		(pad "1" smd rect
			(at 0 0)
			(size 0.508 0.508)
			(layers "B.Cu" "B.Mask" "B.Paste")
			(net "JTAG_RISER_TRST")
		)
		(pad "2" smd rect
			(at 0 0.889)
			(size 0.508 0.508)
			(layers "B.Cu" "B.Mask" "B.Paste")
			(net "JTAG_BMC_TRST_N")
		)
		(zone
			(layer "B.Cu")
			(hatch none 0.5)
			(connect_pads
				(clearance 0)
			)
			(min_thickness 0.25)
			(keepout
				(tracks not_allowed)
				(vias allowed)
				(pads allowed)
				(copperpour not_allowed)
				(footprints allowed)
			)
			(placement
				(enabled no)
				(sheetname "")
			)
			(fill
				(thermal_gap 0.5)
				(thermal_bridge_width 0.5)
				(island_removal_mode 0)
			)
			(polygon
				(pts
					(xy 358.0892 -4.8768) (xy 358.5972 -4.8768) (xy 358.5972 -4.4958) (xy 358.0892 -4.4958)
				)
			)
		)
		(zone
			(layer "B.Cu")
			(hatch none 0.5)
			(connect_pads
				(clearance 0)
			)
			(min_thickness 0.25)
			(keepout
				(tracks allowed)
				(vias not_allowed)
				(pads allowed)
				(copperpour not_allowed)
				(footprints allowed)
			)
			(placement
				(enabled no)
				(sheetname "")
			)
			(fill
				(thermal_gap 0.5)
				(thermal_bridge_width 0.5)
				(island_removal_mode 0)
			)
			(polygon
				(pts
					(xy 358.0892 -4.4958) (xy 358.5972 -4.4958) (xy 358.5972 -4.8768) (xy 358.0892 -4.8768)
				)
			)
		)
	)
	(footprint ""
		(layer "B.Cu")
		(at 406.654 -94.474792 90)
		(property "Reference" "C8C3"
			(at 0 0 90)
			(layer "B.SilkS")
			(hide yes)
			(effects
				(font
					(size 1.27 1.27)
				)
				(justify mirror)
			)
		)
		(property "Value" ""
			(at 0 0 90)
			(layer "B.Fab")
			(effects
				(font
					(size 1.27 1.27)
				)
				(justify mirror)
			)
		)
		(duplicate_pad_numbers_are_jumpers no)
		(fp_poly
			(pts
				(xy 0.4953 -0.2032) (xy -0.4953 -0.2032) (xy -0.4953 1.6002) (xy 0.4953 1.6002)
			)
			(stroke
				(width 0)
				(type default)
			)
			(fill no)
			(layer "B.CrtYd")
		)
		(fp_line
			(start 0.4953 -0.2032)
			(end -0.4953 -0.2032)
			(stroke
				(width 0.1)
				(type default)
			)
			(layer "B.Fab")
		)
		(fp_line
			(start -0.4953 -0.2032)
			(end -0.4953 1.6002)
			(stroke
				(width 0.1)
				(type default)
			)
			(layer "B.Fab")
		)
		(fp_line
			(start 0.4953 1.6002)
			(end 0.4953 -0.2032)
			(stroke
				(width 0.1)
				(type default)
			)
			(layer "B.Fab")
		)
		(fp_line
			(start -0.4953 1.6002)
			(end 0.4953 1.6002)
			(stroke
				(width 0.1)
				(type default)
			)
			(layer "B.Fab")
		)
		(pad "1" smd rect
			(at 0 0 270)
			(size 0.762 0.889)
			(layers "B.Cu" "B.Mask" "B.Paste")
			(net "P3V3_STBY")
		)
		(pad "2" smd rect
			(at 0 1.397 270)
			(size 0.762 0.889)
			(layers "B.Cu" "B.Mask" "B.Paste")
			(net "GND")
		)
		(zone
			(layer "B.Cu")
			(hatch none 0.5)
			(connect_pads
				(clearance 0)
			)
			(min_thickness 0.25)
			(keepout
				(tracks not_allowed)
				(vias allowed)
				(pads allowed)
				(copperpour not_allowed)
				(footprints allowed)
			)
			(placement
				(enabled no)
				(sheetname "")
			)
			(fill
				(thermal_gap 0.5)
				(thermal_bridge_width 0.5)
				(island_removal_mode 0)
			)
			(polygon
				(pts
					(xy 407.0985 -94.855792) (xy 407.0985 -94.093792) (xy 407.6065 -94.093792) (xy 407.6065 -94.855792)
				)
			)
		)
	)
	(footprint ""
		(layer "B.Cu")
		(at 331.343 -155.829 180)
		(property "Reference" "R4L4"
			(at 0 0 0)
			(layer "B.SilkS")
			(hide yes)
			(effects
				(font
					(size 1.27 1.27)
				)
				(justify mirror)
			)
		)
		(property "Value" ""
			(at 0 0 0)
			(layer "B.Fab")
			(effects
				(font
					(size 1.27 1.27)
				)
				(justify mirror)
			)
		)
		(duplicate_pad_numbers_are_jumpers no)
		(fp_rect
			(start -0.4953 -0.2032)
			(end 0.4953 1.6002)
			(stroke
				(width 0)
				(type default)
			)
			(fill no)
			(layer "B.CrtYd")
		)
		(fp_line
			(start 0.4953 1.6002)
			(end 0.4953 -0.2032)
			(stroke
				(width 0.1)
				(type default)
			)
			(layer "B.Fab")
		)
		(fp_line
			(start 0.4953 -0.2032)
			(end -0.4953 -0.2032)
			(stroke
				(width 0.1)
				(type default)
			)
			(layer "B.Fab")
		)
		(fp_line
			(start -0.4953 1.6002)
			(end 0.4953 1.6002)
			(stroke
				(width 0.1)
				(type default)
			)
			(layer "B.Fab")
		)
		(fp_line
			(start -0.4953 -0.2032)
			(end -0.4953 1.6002)
			(stroke
				(width 0.1)
				(type default)
			)
			(layer "B.Fab")
		)
		(pad "1" smd rect
			(at 0 0)
			(size 0.762 0.889)
			(layers "B.Cu" "B.Mask" "B.Paste")
			(net "PVDDQ_DEF")
		)
		(pad "2" smd rect
			(at 0 1.397)
			(size 0.762 0.889)
			(layers "B.Cu" "B.Mask" "B.Paste")
			(net "GND")
		)
		(zone
			(layer "B.Cu")
			(hatch none 0.5)
			(connect_pads
				(clearance 0)
			)
			(min_thickness 0.25)
			(keepout
				(tracks not_allowed)
				(vias allowed)
				(pads allowed)
				(copperpour not_allowed)
				(footprints allowed)
			)
			(placement
				(enabled no)
				(sheetname "")
			)
			(fill
				(thermal_gap 0.5)
				(thermal_bridge_width 0.5)
				(island_removal_mode 0)
			)
			(polygon
				(pts
					(xy 331.724 -156.2735) (xy 331.724 -156.7815) (xy 330.962 -156.7815) (xy 330.962 -156.2735)
				)
			)
		)
		(zone
			(layer "B.Cu")
			(hatch none 0.5)
			(connect_pads
				(clearance 0)
			)
			(min_thickness 0.25)
			(keepout
				(tracks allowed)
				(vias not_allowed)
				(pads allowed)
				(copperpour not_allowed)
				(footprints allowed)
			)
			(placement
				(enabled no)
				(sheetname "")
			)
			(fill
				(thermal_gap 0.5)
				(thermal_bridge_width 0.5)
				(island_removal_mode 0)
			)
			(polygon
				(pts
					(xy 331.724 -156.2735) (xy 331.724 -156.7815) (xy 330.962 -156.7815) (xy 330.962 -156.2735)
				)
			)
		)
	)
	(footprint ""
		(layer "B.Cu")
		(at 340.741 -83.5914 90)
		(property "Reference" "R3P21"
			(at 0 0 90)
			(layer "B.SilkS")
			(hide yes)
			(effects
				(font
					(size 1.27 1.27)
				)
				(justify mirror)
			)
		)
		(property "Value" ""
			(at 0 0 90)
			(layer "B.Fab")
			(effects
				(font
					(size 1.27 1.27)
				)
				(justify mirror)
			)
		)
		(duplicate_pad_numbers_are_jumpers no)
		(fp_poly
			(pts
				(xy 0.2794 -0.1016) (xy -0.2794 -0.1016) (xy -0.2794 0.9906) (xy 0.2794 0.9906)
			)
			(stroke
				(width 0)
				(type default)
			)
			(fill no)
			(layer "B.CrtYd")
		)
		(fp_line
			(start 0.2794 -0.1016)
			(end 0.2794 0.9906)
			(stroke
				(width 0.1)
				(type default)
			)
			(layer "B.Fab")
		)
		(fp_line
			(start -0.2794 -0.1016)
			(end 0.2794 -0.1016)
			(stroke
				(width 0.1)
				(type default)
			)
			(layer "B.Fab")
		)
		(fp_line
			(start 0.2794 0.9906)
			(end -0.2794 0.9906)
			(stroke
				(width 0.1)
				(type default)
			)
			(layer "B.Fab")
		)
		(fp_line
			(start -0.2794 0.9906)
			(end -0.2794 -0.1016)
			(stroke
				(width 0.1)
				(type default)
			)
			(layer "B.Fab")
		)
		(pad "1" smd rect
			(at 0 0 270)
			(size 0.508 0.508)
			(layers "B.Cu" "B.Mask" "B.Paste")
			(net "P3V3_STBY")
		)
		(pad "2" smd rect
			(at 0 0.889 270)
			(size 0.508 0.508)
			(layers "B.Cu" "B.Mask" "B.Paste")
			(net "VR_PVCCIO_CPU0_EN")
		)
		(zone
			(layer "B.Cu")
			(hatch none 0.5)
			(connect_pads
				(clearance 0)
			)
			(min_thickness 0.25)
			(keepout
				(tracks allowed)
				(vias not_allowed)
				(pads allowed)
				(copperpour not_allowed)
				(footprints allowed)
			)
			(placement
				(enabled no)
				(sheetname "")
			)
			(fill
				(thermal_gap 0.5)
				(thermal_bridge_width 0.5)
				(island_removal_mode 0)
			)
			(polygon
				(pts
					(xy 340.995 -83.8454) (xy 340.995 -83.3374) (xy 341.376 -83.3374) (xy 341.376 -83.8454)
				)
			)
		)
		(zone
			(layer "B.Cu")
			(hatch none 0.5)
			(connect_pads
				(clearance 0)
			)
			(min_thickness 0.25)
			(keepout
				(tracks not_allowed)
				(vias allowed)
				(pads allowed)
				(copperpour not_allowed)
				(footprints allowed)
			)
			(placement
				(enabled no)
				(sheetname "")
			)
			(fill
				(thermal_gap 0.5)
				(thermal_bridge_width 0.5)
				(island_removal_mode 0)
			)
			(polygon
				(pts
					(xy 341.376 -83.8454) (xy 341.376 -83.3374) (xy 340.995 -83.3374) (xy 340.995 -83.8454)
				)
			)
		)
	)
	(footprint ""
		(layer "B.Cu")
		(at 31.0134 -72.1614 180)
		(property "Reference" "CTI7"
			(at 0.8382 -0.84963 180)
			(unlocked yes)
			(layer "B.SilkS")
			(effects
				(font
					(size 0.7874 0.5842)
					(thickness 0.1524)
				)
				(justify left mirror)
			)
		)
		(property "Value" ""
			(at 0 0 0)
			(layer "B.Fab")
			(effects
				(font
					(size 1.27 1.27)
				)
				(justify mirror)
			)
		)
		(duplicate_pad_numbers_are_jumpers no)
		(fp_poly
			(pts
				(xy -0.3048 -0.1016) (xy -0.3048 0.9906) (xy 0.3048 0.9906) (xy 0.3048 -0.1016)
			)
			(stroke
				(width 0)
				(type default)
			)
			(fill no)
			(layer "B.CrtYd")
		)
		(fp_line
			(start 0.3048 0.9906)
			(end -0.3048 0.9906)
			(stroke
				(width 0.1)
				(type default)
			)
			(layer "B.Fab")
		)
		(fp_line
			(start 0.3048 -0.1016)
			(end 0.3048 0.9906)
			(stroke
				(width 0.1)
				(type default)
			)
			(layer "B.Fab")
		)
		(fp_line
			(start -0.3048 0.9906)
			(end -0.3048 -0.1016)
			(stroke
				(width 0.1)
				(type default)
			)
			(layer "B.Fab")
		)
		(fp_line
			(start -0.3048 -0.1016)
			(end 0.3048 -0.1016)
			(stroke
				(width 0.1)
				(type default)
			)
			(layer "B.Fab")
		)
		(pad "1" smd rect
			(at 0 0)
			(size 0.508 0.508)
			(layers "B.Cu" "B.Mask" "B.Paste")
			(net "A_TSENSE_PVCCIN_CPU1")
		)
		(pad "2" smd rect
			(at 0 0.889)
			(size 0.508 0.508)
			(layers "B.Cu" "B.Mask" "B.Paste")
			(net "GND")
		)
		(zone
			(layer "B.Cu")
			(hatch none 0.5)
			(connect_pads
				(clearance 0)
			)
			(min_thickness 0.25)
			(keepout
				(tracks not_allowed)
				(vias allowed)
				(pads allowed)
				(copperpour not_allowed)
				(footprints allowed)
			)
			(placement
				(enabled no)
				(sheetname "")
			)
			(fill
				(thermal_gap 0.5)
				(thermal_bridge_width 0.5)
				(island_removal_mode 0)
			)
			(polygon
				(pts
					(xy 30.7594 -72.7964) (xy 31.2674 -72.7964) (xy 31.2674 -72.4154) (xy 30.7594 -72.4154)
				)
			)
		)
		(zone
			(layer "B.Cu")
			(hatch none 0.5)
			(connect_pads
				(clearance 0)
			)
			(min_thickness 0.25)
			(keepout
				(tracks allowed)
				(vias not_allowed)
				(pads allowed)
				(copperpour not_allowed)
				(footprints allowed)
			)
			(placement
				(enabled no)
				(sheetname "")
			)
			(fill
				(thermal_gap 0.5)
				(thermal_bridge_width 0.5)
				(island_removal_mode 0)
			)
			(polygon
				(pts
					(xy 30.7594 -72.4154) (xy 31.2674 -72.4154) (xy 31.2674 -72.7964) (xy 30.7594 -72.7964)
				)
			)
		)
	)
	(footprint ""
		(layer "B.Cu")
		(at 30.452568 -144.977612 90)
		(property "Reference" "C9L7"
			(at 0 0 90)
			(layer "B.SilkS")
			(hide yes)
			(effects
				(font
					(size 1.27 1.27)
				)
				(justify mirror)
			)
		)
		(property "Value" ""
			(at 0 0 90)
			(layer "B.Fab")
			(effects
				(font
					(size 1.27 1.27)
				)
				(justify mirror)
			)
		)
		(duplicate_pad_numbers_are_jumpers no)
		(fp_poly
			(pts
				(xy -0.3048 -0.1016) (xy -0.3048 0.9906) (xy 0.3048 0.9906) (xy 0.3048 -0.1016)
			)
			(stroke
				(width 0)
				(type default)
			)
			(fill no)
			(layer "B.CrtYd")
		)
		(fp_line
			(start 0.3048 -0.1016)
			(end 0.3048 0.9906)
			(stroke
				(width 0.1)
				(type default)
			)
			(layer "B.Fab")
		)
		(fp_line
			(start -0.3048 -0.1016)
			(end 0.3048 -0.1016)
			(stroke
				(width 0.1)
				(type default)
			)
			(layer "B.Fab")
		)
		(fp_line
			(start 0.3048 0.9906)
			(end -0.3048 0.9906)
			(stroke
				(width 0.1)
				(type default)
			)
			(layer "B.Fab")
		)
		(fp_line
			(start -0.3048 0.9906)
			(end -0.3048 -0.1016)
			(stroke
				(width 0.1)
				(type default)
			)
			(layer "B.Fab")
		)
		(pad "1" smd rect
			(at 0 0 270)
			(size 0.508 0.508)
			(layers "B.Cu" "B.Mask" "B.Paste")
			(net "M_L_VREF")
		)
		(pad "2" smd rect
			(at 0 0.889 270)
			(size 0.508 0.508)
			(layers "B.Cu" "B.Mask" "B.Paste")
			(net "GND")
		)
		(zone
			(layer "B.Cu")
			(hatch none 0.5)
			(connect_pads
				(clearance 0)
			)
			(min_thickness 0.25)
			(keepout
				(tracks allowed)
				(vias not_allowed)
				(pads allowed)
				(copperpour not_allowed)
				(footprints allowed)
			)
			(placement
				(enabled no)
				(sheetname "")
			)
			(fill
				(thermal_gap 0.5)
				(thermal_bridge_width 0.5)
				(island_removal_mode 0)
			)
			(polygon
				(pts
					(xy 30.706568 -145.231612) (xy 30.706568 -144.723612) (xy 31.087568 -144.723612) (xy 31.087568 -145.231612)
				)
			)
		)
		(zone
			(layer "B.Cu")
			(hatch none 0.5)
			(connect_pads
				(clearance 0)
			)
			(min_thickness 0.25)
			(keepout
				(tracks not_allowed)
				(vias allowed)
				(pads allowed)
				(copperpour not_allowed)
				(footprints allowed)
			)
			(placement
				(enabled no)
				(sheetname "")
			)
			(fill
				(thermal_gap 0.5)
				(thermal_bridge_width 0.5)
				(island_removal_mode 0)
			)
			(polygon
				(pts
					(xy 31.087568 -145.231612) (xy 31.087568 -144.723612) (xy 30.706568 -144.723612) (xy 30.706568 -145.231612)
				)
			)
		)
	)
	(footprint ""
		(layer "B.Cu")
		(at 389.1915 -61.341 -90)
		(property "Reference" "R2T11"
			(at 0 0 90)
			(layer "B.SilkS")
			(hide yes)
			(effects
				(font
					(size 1.27 1.27)
				)
				(justify mirror)
			)
		)
		(property "Value" ""
			(at 0 0 90)
			(layer "B.Fab")
			(effects
				(font
					(size 1.27 1.27)
				)
				(justify mirror)
			)
		)
		(duplicate_pad_numbers_are_jumpers no)
		(fp_poly
			(pts
				(xy 0.2794 -0.1016) (xy -0.2794 -0.1016) (xy -0.2794 0.9906) (xy 0.2794 0.9906)
			)
			(stroke
				(width 0)
				(type default)
			)
			(fill no)
			(layer "B.CrtYd")
		)
		(fp_line
			(start -0.2794 0.9906)
			(end -0.2794 -0.1016)
			(stroke
				(width 0.1)
				(type default)
			)
			(layer "B.Fab")
		)
		(fp_line
			(start 0.2794 0.9906)
			(end -0.2794 0.9906)
			(stroke
				(width 0.1)
				(type default)
			)
			(layer "B.Fab")
		)
		(fp_line
			(start -0.2794 -0.1016)
			(end 0.2794 -0.1016)
			(stroke
				(width 0.1)
				(type default)
			)
			(layer "B.Fab")
		)
		(fp_line
			(start 0.2794 -0.1016)
			(end 0.2794 0.9906)
			(stroke
				(width 0.1)
				(type default)
			)
			(layer "B.Fab")
		)
		(pad "1" smd rect
			(at 0 0 90)
			(size 0.508 0.508)
			(layers "B.Cu" "B.Mask" "B.Paste")
			(net "P3V3_STBY")
		)
		(pad "2" smd rect
			(at 0 0.889 90)
			(size 0.508 0.508)
			(layers "B.Cu" "B.Mask" "B.Paste")
			(net "FM_DUAL_BIOS_SEL_N")
		)
		(zone
			(layer "B.Cu")
			(hatch none 0.5)
			(connect_pads
				(clearance 0)
			)
			(min_thickness 0.25)
			(keepout
				(tracks not_allowed)
				(vias allowed)
				(pads allowed)
				(copperpour not_allowed)
				(footprints allowed)
			)
			(placement
				(enabled no)
				(sheetname "")
			)
			(fill
				(thermal_gap 0.5)
				(thermal_bridge_width 0.5)
				(island_removal_mode 0)
			)
			(polygon
				(pts
					(xy 388.5565 -61.087) (xy 388.5565 -61.595) (xy 388.9375 -61.595) (xy 388.9375 -61.087)
				)
			)
		)
		(zone
			(layer "B.Cu")
			(hatch none 0.5)
			(connect_pads
				(clearance 0)
			)
			(min_thickness 0.25)
			(keepout
				(tracks allowed)
				(vias not_allowed)
				(pads allowed)
				(copperpour not_allowed)
				(footprints allowed)
			)
			(placement
				(enabled no)
				(sheetname "")
			)
			(fill
				(thermal_gap 0.5)
				(thermal_bridge_width 0.5)
				(island_removal_mode 0)
			)
			(polygon
				(pts
					(xy 388.9375 -61.087) (xy 388.9375 -61.595) (xy 388.5565 -61.595) (xy 388.5565 -61.087)
				)
			)
		)
	)
	(footprint ""
		(layer "B.Cu")
		(at 336.042 -99.314 90)
		(property "Reference" "C3N35"
			(at 1.62433 -3.81 0)
			(unlocked yes)
			(layer "B.SilkS")
			(effects
				(font
					(size 0.7874 0.5842)
					(thickness 0.1524)
				)
				(justify mirror)
			)
		)
		(property "Value" ""
			(at 0 0 90)
			(layer "B.Fab")
			(effects
				(font
					(size 1.27 1.27)
				)
				(justify mirror)
			)
		)
		(duplicate_pad_numbers_are_jumpers no)
		(fp_line
			(start 2.563114 -1.616456)
			(end 2.563114 1.633728)
			(stroke
				(width 0.1524)
				(type default)
			)
			(layer "B.SilkS")
		)
		(fp_line
			(start 1.6002 -1.616456)
			(end 2.563114 -1.616456)
			(stroke
				(width 0.1524)
				(type default)
			)
			(layer "B.SilkS")
		)
		(fp_line
			(start -1.6002 -1.616456)
			(end -2.504948 -1.616456)
			(stroke
				(width 0.1524)
				(type default)
			)
			(layer "B.SilkS")
		)
		(fp_line
			(start -2.504948 -1.616456)
			(end -2.504948 1.633728)
			(stroke
				(width 0.1524)
				(type default)
			)
			(layer "B.SilkS")
		)
		(fp_line
			(start 2.563114 1.633728)
			(end 1.6002 1.633728)
			(stroke
				(width 0.1524)
				(type default)
			)
			(layer "B.SilkS")
		)
		(fp_line
			(start -2.504948 1.633728)
			(end -1.6002 1.633728)
			(stroke
				(width 0.1524)
				(type default)
			)
			(layer "B.SilkS")
		)
		(fp_line
			(start 2.286 7.366)
			(end 2.286 1.632712)
			(stroke
				(width 0.1524)
				(type default)
			)
			(layer "B.SilkS")
		)
		(fp_line
			(start 2.286 7.366)
			(end 1.60147 7.366)
			(stroke
				(width 0.1524)
				(type default)
			)
			(layer "B.SilkS")
		)
		(fp_line
			(start -2.286 7.366)
			(end -2.286 1.63195)
			(stroke
				(width 0.1524)
				(type default)
			)
			(layer "B.SilkS")
		)
		(fp_line
			(start -2.286 7.366)
			(end -1.600708 7.366)
			(stroke
				(width 0.1524)
				(type default)
			)
			(layer "B.SilkS")
		)
		(fp_rect
			(start 2.286 7.366)
			(end -2.286 -0.254)
			(stroke
				(width 0)
				(type default)
			)
			(fill no)
			(layer "B.CrtYd")
		)
		(fp_line
			(start 2.286 -0.254)
			(end -2.286 -0.254)
			(stroke
				(width 0.1)
				(type default)
			)
			(layer "B.Fab")
		)
		(fp_line
			(start -2.286 -0.254)
			(end -2.286 7.366)
			(stroke
				(width 0.1)
				(type default)
			)
			(layer "B.Fab")
		)
		(fp_line
			(start 2.286 7.366)
			(end 2.286 -0.254)
			(stroke
				(width 0.1)
				(type default)
			)
			(layer "B.Fab")
		)
		(fp_line
			(start -2.286 7.366)
			(end 2.286 7.366)
			(stroke
				(width 0.1)
				(type default)
			)
			(layer "B.Fab")
		)
		(pad "1" smd rect
			(at 0 0 270)
			(size 2.54 3.048)
			(layers "B.Cu" "B.Mask" "B.Paste")
			(net "PVCCIO_CPU0")
		)
		(pad "2" smd rect
			(at 0 7.112 270)
			(size 2.54 3.048)
			(layers "B.Cu" "B.Mask" "B.Paste")
			(net "GND")
		)
	)
	(footprint ""
		(layer "B.Cu")
		(at 273.560286 -79.60614 180)
		(property "Reference" "C5P11"
			(at 0 0 0)
			(layer "B.SilkS")
			(hide yes)
			(effects
				(font
					(size 1.27 1.27)
				)
				(justify mirror)
			)
		)
		(property "Value" ""
			(at 0 0 0)
			(layer "B.Fab")
			(effects
				(font
					(size 1.27 1.27)
				)
				(justify mirror)
			)
		)
		(duplicate_pad_numbers_are_jumpers no)
		(fp_poly
			(pts
				(xy 0.7239 -0.2159) (xy -0.7239 -0.2159) (xy -0.7239 1.9939) (xy 0.7239 1.9939)
			)
			(stroke
				(width 0)
				(type default)
			)
			(fill no)
			(layer "B.CrtYd")
		)
		(fp_line
			(start 0.7239 1.9939)
			(end -0.7239 1.9939)
			(stroke
				(width 0.1)
				(type default)
			)
			(layer "B.Fab")
		)
		(fp_line
			(start 0.7239 -0.2159)
			(end 0.7239 1.9939)
			(stroke
				(width 0.1)
				(type default)
			)
			(layer "B.Fab")
		)
		(fp_line
			(start -0.7239 1.9939)
			(end -0.7239 -0.2159)
			(stroke
				(width 0.1)
				(type default)
			)
			(layer "B.Fab")
		)
		(fp_line
			(start -0.7239 -0.2159)
			(end 0.7239 -0.2159)
			(stroke
				(width 0.1)
				(type default)
			)
			(layer "B.Fab")
		)
		(pad "1" smd rect
			(at 0 0)
			(size 1.27 1.016)
			(layers "B.Cu" "B.Mask" "B.Paste")
			(net "PVCCMCP_CPU0")
		)
		(pad "2" smd rect
			(at 0 1.778)
			(size 1.27 1.016)
			(layers "B.Cu" "B.Mask" "B.Paste")
			(net "GND")
		)
		(zone
			(layer "B.Cu")
			(hatch none 0.5)
			(connect_pads
				(clearance 0)
			)
			(min_thickness 0.25)
			(keepout
				(tracks not_allowed)
				(vias allowed)
				(pads allowed)
				(copperpour not_allowed)
				(footprints allowed)
			)
			(placement
				(enabled no)
				(sheetname "")
			)
			(fill
				(thermal_gap 0.5)
				(thermal_bridge_width 0.5)
				(island_removal_mode 0)
			)
			(polygon
				(pts
					(xy 272.925286 -80.11414) (xy 274.195286 -80.11414) (xy 274.195286 -80.87614) (xy 272.925286 -80.87614)
				)
			)
		)
	)
	(footprint ""
		(layer "B.Cu")
		(at 214.503 -63.11392)
		(property "Reference" "C6R2"
			(at 0 0 0)
			(layer "B.SilkS")
			(hide yes)
			(effects
				(font
					(size 1.27 1.27)
				)
				(justify mirror)
			)
		)
		(property "Value" ""
			(at 0 0 0)
			(layer "B.Fab")
			(effects
				(font
					(size 1.27 1.27)
				)
				(justify mirror)
			)
		)
		(duplicate_pad_numbers_are_jumpers no)
		(fp_poly
			(pts
				(xy 0.4953 -0.2032) (xy -0.4953 -0.2032) (xy -0.4953 1.6002) (xy 0.4953 1.6002)
			)
			(stroke
				(width 0)
				(type default)
			)
			(fill no)
			(layer "B.CrtYd")
		)
		(fp_line
			(start -0.4953 -0.2032)
			(end -0.4953 1.6002)
			(stroke
				(width 0.1)
				(type default)
			)
			(layer "B.Fab")
		)
		(fp_line
			(start -0.4953 1.6002)
			(end 0.4953 1.6002)
			(stroke
				(width 0.1)
				(type default)
			)
			(layer "B.Fab")
		)
		(fp_line
			(start 0.4953 -0.2032)
			(end -0.4953 -0.2032)
			(stroke
				(width 0.1)
				(type default)
			)
			(layer "B.Fab")
		)
		(fp_line
			(start 0.4953 1.6002)
			(end 0.4953 -0.2032)
			(stroke
				(width 0.1)
				(type default)
			)
			(layer "B.Fab")
		)
		(pad "1" smd rect
			(at 0 0 180)
			(size 0.762 0.889)
			(layers "B.Cu" "B.Mask" "B.Paste")
			(net "PVCCIN_CPU0")
		)
		(pad "2" smd rect
			(at 0 1.397 180)
			(size 0.762 0.889)
			(layers "B.Cu" "B.Mask" "B.Paste")
			(net "GND")
		)
		(zone
			(layer "B.Cu")
			(hatch none 0.5)
			(connect_pads
				(clearance 0)
			)
			(min_thickness 0.25)
			(keepout
				(tracks not_allowed)
				(vias allowed)
				(pads allowed)
				(copperpour not_allowed)
				(footprints allowed)
			)
			(placement
				(enabled no)
				(sheetname "")
			)
			(fill
				(thermal_gap 0.5)
				(thermal_bridge_width 0.5)
				(island_removal_mode 0)
			)
			(polygon
				(pts
					(xy 214.884 -62.66942) (xy 214.122 -62.66942) (xy 214.122 -62.16142) (xy 214.884 -62.16142)
				)
			)
		)
	)
	(footprint ""
		(layer "B.Cu")
		(at 375.544842 -77.894434)
		(property "Reference" "C2P2"
			(at 0 0 0)
			(layer "B.SilkS")
			(hide yes)
			(effects
				(font
					(size 1.27 1.27)
				)
				(justify mirror)
			)
		)
		(property "Value" ""
			(at 0 0 0)
			(layer "B.Fab")
			(effects
				(font
					(size 1.27 1.27)
				)
				(justify mirror)
			)
		)
		(duplicate_pad_numbers_are_jumpers no)
		(fp_rect
			(start 0.2794 0.9144)
			(end -0.2794 -0.1143)
			(stroke
				(width 0)
				(type default)
			)
			(fill no)
			(layer "B.CrtYd")
		)
		(fp_line
			(start -0.2794 -0.1143)
			(end -0.2794 0.9144)
			(stroke
				(width 0.1)
				(type default)
			)
			(layer "B.Fab")
		)
		(fp_line
			(start -0.2794 0.9144)
			(end 0.2794 0.9144)
			(stroke
				(width 0.1)
				(type default)
			)
			(layer "B.Fab")
		)
		(fp_line
			(start 0.2794 -0.1143)
			(end -0.2794 -0.1143)
			(stroke
				(width 0.1)
				(type default)
			)
			(layer "B.Fab")
		)
		(fp_line
			(start 0.2794 0.9144)
			(end 0.2794 -0.1143)
			(stroke
				(width 0.1)
				(type default)
			)
			(layer "B.Fab")
		)
		(pad "1" smd custom
			(at 0 0 270)
			(size 0.10414 0.10414)
			(layers "B.Cu" "B.Mask" "B.Paste")
			(net "P3V3_STBY")
			(options
				(clearance outline)
				(anchor circle)
			)
			(primitives
				(gr_poly
					(pts
						(xy -0.20828 -0.08636) (xy -0.20828 0.08636) (xy -0.08636 0.20828) (xy 0.086614 0.20828) (xy 0.20828 0.086614)
						(xy 0.20828 -0.08636) (xy 0.08636 -0.20828) (xy -0.08636 -0.20828)
					)
					(width 0)
					(fill yes)
				)
			)
		)
		(pad "2" smd custom
			(at 0 0.8001 270)
			(size 0.10414 0.10414)
			(layers "B.Cu" "B.Mask" "B.Paste")
			(net "GND")
			(options
				(clearance outline)
				(anchor circle)
			)
			(primitives
				(gr_poly
					(pts
						(xy -0.20828 -0.08636) (xy -0.20828 0.08636) (xy -0.08636 0.20828) (xy 0.086614 0.20828) (xy 0.20828 0.086614)
						(xy 0.20828 -0.08636) (xy 0.08636 -0.20828) (xy -0.08636 -0.20828)
					)
					(width 0)
					(fill yes)
				)
			)
		)
		(zone
			(layer "B.Cu")
			(hatch none 0.5)
			(connect_pads
				(clearance 0)
			)
			(min_thickness 0.25)
			(keepout
				(tracks not_allowed)
				(vias allowed)
				(pads allowed)
				(copperpour not_allowed)
				(footprints allowed)
			)
			(placement
				(enabled no)
				(sheetname "")
			)
			(fill
				(thermal_gap 0.5)
				(thermal_bridge_width 0.5)
				(island_removal_mode 0)
			)
			(polygon
				(pts
					(xy 375.632472 -77.684884) (xy 375.632472 -77.303884) (xy 375.457212 -77.303884) (xy 375.456958 -77.684884)
				)
			)
		)
		(zone
			(layer "B.Cu")
			(hatch none 0.5)
			(connect_pads
				(clearance 0)
			)
			(min_thickness 0.25)
			(keepout
				(tracks allowed)
				(vias not_allowed)
				(pads allowed)
				(copperpour not_allowed)
				(footprints allowed)
			)
			(placement
				(enabled no)
				(sheetname "")
			)
			(fill
				(thermal_gap 0.5)
				(thermal_bridge_width 0.5)
				(island_removal_mode 0)
			)
			(polygon
				(pts
					(xy 375.632472 -77.684884) (xy 375.632472 -77.303884) (xy 375.457212 -77.303884) (xy 375.456958 -77.684884)
				)
			)
		)
	)
	(footprint ""
		(layer "B.Cu")
		(at 327.914 -61.087 -90)
		(property "Reference" "R4R4"
			(at 0 0 90)
			(layer "B.SilkS")
			(hide yes)
			(effects
				(font
					(size 1.27 1.27)
				)
				(justify mirror)
			)
		)
		(property "Value" ""
			(at 0 0 90)
			(layer "B.Fab")
			(effects
				(font
					(size 1.27 1.27)
				)
				(justify mirror)
			)
		)
		(duplicate_pad_numbers_are_jumpers no)
		(fp_poly
			(pts
				(xy 0.2794 -0.1016) (xy -0.2794 -0.1016) (xy -0.2794 0.9906) (xy 0.2794 0.9906)
			)
			(stroke
				(width 0)
				(type default)
			)
			(fill no)
			(layer "B.CrtYd")
		)
		(fp_line
			(start -0.2794 0.9906)
			(end -0.2794 -0.1016)
			(stroke
				(width 0.1)
				(type default)
			)
			(layer "B.Fab")
		)
		(fp_line
			(start 0.2794 0.9906)
			(end -0.2794 0.9906)
			(stroke
				(width 0.1)
				(type default)
			)
			(layer "B.Fab")
		)
		(fp_line
			(start -0.2794 -0.1016)
			(end 0.2794 -0.1016)
			(stroke
				(width 0.1)
				(type default)
			)
			(layer "B.Fab")
		)
		(fp_line
			(start 0.2794 -0.1016)
			(end 0.2794 0.9906)
			(stroke
				(width 0.1)
				(type default)
			)
			(layer "B.Fab")
		)
		(pad "1" smd rect
			(at 0 0 90)
			(size 0.508 0.508)
			(layers "B.Cu" "B.Mask" "B.Paste")
			(net "PVCCIO_CPU0")
		)
		(pad "2" smd rect
			(at 0 0.889 90)
			(size 0.508 0.508)
			(layers "B.Cu" "B.Mask" "B.Paste")
			(net "H_CPU0_FAST_WAKE_N")
		)
		(zone
			(layer "B.Cu")
			(hatch none 0.5)
			(connect_pads
				(clearance 0)
			)
			(min_thickness 0.25)
			(keepout
				(tracks not_allowed)
				(vias allowed)
				(pads allowed)
				(copperpour not_allowed)
				(footprints allowed)
			)
			(placement
				(enabled no)
				(sheetname "")
			)
			(fill
				(thermal_gap 0.5)
				(thermal_bridge_width 0.5)
				(island_removal_mode 0)
			)
			(polygon
				(pts
					(xy 327.279 -60.833) (xy 327.279 -61.341) (xy 327.66 -61.341) (xy 327.66 -60.833)
				)
			)
		)
		(zone
			(layer "B.Cu")
			(hatch none 0.5)
			(connect_pads
				(clearance 0)
			)
			(min_thickness 0.25)
			(keepout
				(tracks allowed)
				(vias not_allowed)
				(pads allowed)
				(copperpour not_allowed)
				(footprints allowed)
			)
			(placement
				(enabled no)
				(sheetname "")
			)
			(fill
				(thermal_gap 0.5)
				(thermal_bridge_width 0.5)
				(island_removal_mode 0)
			)
			(polygon
				(pts
					(xy 327.66 -60.833) (xy 327.66 -61.341) (xy 327.279 -61.341) (xy 327.279 -60.833)
				)
			)
		)
	)
	(footprint ""
		(layer "B.Cu")
		(at 445.4906 -64.7446 180)
		(property "Reference" "C2P13"
			(at 0 0 0)
			(layer "B.SilkS")
			(hide yes)
			(effects
				(font
					(size 1.27 1.27)
				)
				(justify mirror)
			)
		)
		(property "Value" ""
			(at 0 0 0)
			(layer "B.Fab")
			(effects
				(font
					(size 1.27 1.27)
				)
				(justify mirror)
			)
		)
		(duplicate_pad_numbers_are_jumpers no)
		(fp_poly
			(pts
				(xy -0.3048 -0.1016) (xy -0.3048 0.9906) (xy 0.3048 0.9906) (xy 0.3048 -0.1016)
			)
			(stroke
				(width 0)
				(type default)
			)
			(fill no)
			(layer "B.CrtYd")
		)
		(fp_line
			(start 0.3048 0.9906)
			(end -0.3048 0.9906)
			(stroke
				(width 0.1)
				(type default)
			)
			(layer "B.Fab")
		)
		(fp_line
			(start 0.3048 -0.1016)
			(end 0.3048 0.9906)
			(stroke
				(width 0.1)
				(type default)
			)
			(layer "B.Fab")
		)
		(fp_line
			(start -0.3048 0.9906)
			(end -0.3048 -0.1016)
			(stroke
				(width 0.1)
				(type default)
			)
			(layer "B.Fab")
		)
		(fp_line
			(start -0.3048 -0.1016)
			(end 0.3048 -0.1016)
			(stroke
				(width 0.1)
				(type default)
			)
			(layer "B.Fab")
		)
		(pad "1" smd rect
			(at 0 0)
			(size 0.508 0.508)
			(layers "B.Cu" "B.Mask" "B.Paste")
			(net "P12V_STBY")
		)
		(pad "2" smd rect
			(at 0 0.889)
			(size 0.508 0.508)
			(layers "B.Cu" "B.Mask" "B.Paste")
			(net "GND")
		)
		(zone
			(layer "B.Cu")
			(hatch none 0.5)
			(connect_pads
				(clearance 0)
			)
			(min_thickness 0.25)
			(keepout
				(tracks not_allowed)
				(vias allowed)
				(pads allowed)
				(copperpour not_allowed)
				(footprints allowed)
			)
			(placement
				(enabled no)
				(sheetname "")
			)
			(fill
				(thermal_gap 0.5)
				(thermal_bridge_width 0.5)
				(island_removal_mode 0)
			)
			(polygon
				(pts
					(xy 445.2366 -65.3796) (xy 445.7446 -65.3796) (xy 445.7446 -64.9986) (xy 445.2366 -64.9986)
				)
			)
		)
		(zone
			(layer "B.Cu")
			(hatch none 0.5)
			(connect_pads
				(clearance 0)
			)
			(min_thickness 0.25)
			(keepout
				(tracks allowed)
				(vias not_allowed)
				(pads allowed)
				(copperpour not_allowed)
				(footprints allowed)
			)
			(placement
				(enabled no)
				(sheetname "")
			)
			(fill
				(thermal_gap 0.5)
				(thermal_bridge_width 0.5)
				(island_removal_mode 0)
			)
			(polygon
				(pts
					(xy 445.2366 -64.9986) (xy 445.7446 -64.9986) (xy 445.7446 -65.3796) (xy 445.2366 -65.3796)
				)
			)
		)
	)
	(footprint ""
		(layer "B.Cu")
		(at 370.290852 -46.788578)
		(property "Reference" "U2T4"
			(at -5.093716 -1.536192 180)
			(unlocked yes)
			(layer "B.SilkS")
			(effects
				(font
					(size 0.7874 0.5842)
					(thickness 0.1524)
				)
				(justify left mirror)
			)
		)
		(property "Value" ""
			(at 0 0 0)
			(layer "B.Fab")
			(effects
				(font
					(size 1.27 1.27)
				)
				(justify mirror)
			)
		)
		(duplicate_pad_numbers_are_jumpers no)
		(fp_line
			(start -4.4323 -0.64008)
			(end -4.4323 4.52628)
			(stroke
				(width 0.1524)
				(type default)
			)
			(layer "B.SilkS")
		)
		(fp_line
			(start -4.4323 4.52628)
			(end -1.5367 4.52628)
			(stroke
				(width 0.1524)
				(type default)
			)
			(layer "B.SilkS")
		)
		(fp_line
			(start -3.302 0.49022)
			(end -3.302 -0.64008)
			(stroke
				(width 0.1524)
				(type default)
			)
			(layer "B.SilkS")
		)
		(fp_line
			(start -2.667 -0.64008)
			(end -2.667 0.49022)
			(stroke
				(width 0.1524)
				(type default)
			)
			(layer "B.SilkS")
		)
		(fp_line
			(start -2.667 0.49022)
			(end -3.302 0.49022)
			(stroke
				(width 0.1524)
				(type default)
			)
			(layer "B.SilkS")
		)
		(fp_line
			(start -1.5367 -0.64008)
			(end -4.4323 -0.64008)
			(stroke
				(width 0.1524)
				(type default)
			)
			(layer "B.SilkS")
		)
		(fp_line
			(start -1.5367 4.52628)
			(end -1.5367 -0.64008)
			(stroke
				(width 0.1524)
				(type default)
			)
			(layer "B.SilkS")
		)
		(fp_circle
			(center 1.324102 -0.479552)
			(end 1.451102 -0.479552)
			(stroke
				(width 0.254)
				(type default)
			)
			(fill no)
			(layer "B.SilkS")
		)
		(fp_poly
			(pts
				(xy -0.7366 4.54152) (xy -0.7366 -0.64008) (xy -4.7244 -0.64008) (xy -5.2324 -0.64008) (xy -5.2324 4.54152)
				(xy -4.7244 4.54152)
			)
			(stroke
				(width 0)
				(type default)
			)
			(fill no)
			(layer "B.CrtYd")
		)
		(fp_line
			(start -5.2324 -0.64008)
			(end -5.2324 4.54152)
			(stroke
				(width 0.1)
				(type default)
			)
			(layer "B.Fab")
		)
		(fp_line
			(start -5.2324 4.54152)
			(end -0.7366 4.54152)
			(stroke
				(width 0.1)
				(type default)
			)
			(layer "B.Fab")
		)
		(fp_line
			(start -3.302 0.49022)
			(end -3.302 -0.64008)
			(stroke
				(width 0.1)
				(type default)
			)
			(layer "B.Fab")
		)
		(fp_line
			(start -2.667 -0.64008)
			(end -2.667 0.49022)
			(stroke
				(width 0.1)
				(type default)
			)
			(layer "B.Fab")
		)
		(fp_line
			(start -2.667 0.49022)
			(end -3.302 0.49022)
			(stroke
				(width 0.1)
				(type default)
			)
			(layer "B.Fab")
		)
		(fp_line
			(start -0.7366 -0.64008)
			(end -5.2324 -0.64008)
			(stroke
				(width 0.1)
				(type default)
			)
			(layer "B.Fab")
		)
		(fp_line
			(start -0.7366 4.54152)
			(end -0.7366 -0.64008)
			(stroke
				(width 0.1)
				(type default)
			)
			(layer "B.Fab")
		)
		(fp_circle
			(center 1.612138 -0.684784)
			(end 1.739138 -0.684784)
			(stroke
				(width 0.254)
				(type default)
			)
			(fill no)
			(layer "B.Fab")
		)
		(pad "1" smd rect
			(at 0 0 180)
			(size 2.159 0.381)
			(layers "B.Cu" "B.Mask" "B.Paste")
			(net "PD_GTL2104_4_DIR")
		)
		(pad "2" smd rect
			(at 0 0.65024 180)
			(size 2.159 0.381)
			(layers "B.Cu" "B.Mask" "B.Paste")
			(net "H_CPU1_PROCHOT_G_R_N")
		)
		(pad "3" smd rect
			(at 0 1.30048 180)
			(size 2.159 0.381)
			(layers "B.Cu" "B.Mask" "B.Paste")
			(net "H_CPU0_PROCHOT_G_R_N")
		)
		(pad "4" smd rect
			(at 0 1.95072 180)
			(size 2.159 0.381)
			(layers "B.Cu" "B.Mask" "B.Paste")
			(net "P0V7_GTL2104_5_VREF")
		)
		(pad "5" smd rect
			(at 0 2.60096 180)
			(size 2.159 0.381)
			(layers "B.Cu" "B.Mask" "B.Paste")
			(net "H_CPU_ERR1_GTL_N")
		)
		(pad "6" smd rect
			(at 0 3.2512 180)
			(size 2.159 0.381)
			(layers "B.Cu" "B.Mask" "B.Paste")
			(net "H_CPU_ERR0_GTL_N")
		)
		(pad "7" smd rect
			(at 0 3.90144 180)
			(size 2.159 0.381)
			(layers "B.Cu" "B.Mask" "B.Paste")
			(net "GND")
		)
		(pad "8" smd rect
			(at -5.969 3.90144 180)
			(size 2.159 0.381)
			(layers "B.Cu" "B.Mask" "B.Paste")
			(net "GND")
		)
		(pad "9" smd rect
			(at -5.969 3.2512 180)
			(size 2.159 0.381)
			(layers "B.Cu" "B.Mask" "B.Paste")
			(net "FM_CPU_ERR0_LVT3_R_N")
		)
		(pad "10" smd rect
			(at -5.969 2.60096 180)
			(size 2.159 0.381)
			(layers "B.Cu" "B.Mask" "B.Paste")
			(net "FM_CPU_ERR1_LVT3_R_N")
		)
		(pad "11" smd rect
			(at -5.969 1.95072 180)
			(size 2.159 0.381)
			(layers "B.Cu" "B.Mask" "B.Paste")
			(net "GND")
		)
		(pad "12" smd rect
			(at -5.969 1.30048 180)
			(size 2.159 0.381)
			(layers "B.Cu" "B.Mask" "B.Paste")
			(net "FM_CPU0_PROCHOT_LVT3_R_N")
		)
		(pad "13" smd rect
			(at -5.969 0.65024 180)
			(size 2.159 0.381)
			(layers "B.Cu" "B.Mask" "B.Paste")
			(net "FM_CPU1_PROCHOT_LVT3_R_N")
		)
		(pad "14" smd rect
			(at -5.969 0 180)
			(size 2.159 0.381)
			(layers "B.Cu" "B.Mask" "B.Paste")
			(net "P3V3")
		)
	)
	(footprint ""
		(layer "B.Cu")
		(at 406.7556 -29.6164)
		(property "Reference" "R25W152"
			(at 0.8382 -0.67818 0)
			(unlocked yes)
			(layer "B.SilkS")
			(effects
				(font
					(size 0.4064 0.254)
					(thickness 0.1524)
				)
				(justify left mirror)
			)
		)
		(property "Value" ""
			(at 0 0 0)
			(layer "B.Fab")
			(effects
				(font
					(size 1.27 1.27)
				)
				(justify mirror)
			)
		)
		(duplicate_pad_numbers_are_jumpers no)
		(fp_poly
			(pts
				(xy 0.2794 -0.1016) (xy -0.2794 -0.1016) (xy -0.2794 0.9906) (xy 0.2794 0.9906)
			)
			(stroke
				(width 0)
				(type default)
			)
			(fill no)
			(layer "B.CrtYd")
		)
		(fp_line
			(start -0.2794 -0.1016)
			(end 0.2794 -0.1016)
			(stroke
				(width 0.1)
				(type default)
			)
			(layer "B.Fab")
		)
		(fp_line
			(start -0.2794 0.9906)
			(end -0.2794 -0.1016)
			(stroke
				(width 0.1)
				(type default)
			)
			(layer "B.Fab")
		)
		(fp_line
			(start 0.2794 -0.1016)
			(end 0.2794 0.9906)
			(stroke
				(width 0.1)
				(type default)
			)
			(layer "B.Fab")
		)
		(fp_line
			(start 0.2794 0.9906)
			(end -0.2794 0.9906)
			(stroke
				(width 0.1)
				(type default)
			)
			(layer "B.Fab")
		)
		(pad "1" smd rect
			(at 0 0 180)
			(size 0.508 0.508)
			(layers "B.Cu" "B.Mask" "B.Paste")
			(net "GND")
		)
		(pad "2" smd rect
			(at 0 0.889 180)
			(size 0.508 0.508)
			(layers "B.Cu" "B.Mask" "B.Paste")
			(net "TP_RGMII2TXD2_GPIOU2")
		)
		(zone
			(layer "B.Cu")
			(hatch none 0.5)
			(connect_pads
				(clearance 0)
			)
			(min_thickness 0.25)
			(keepout
				(tracks allowed)
				(vias not_allowed)
				(pads allowed)
				(copperpour not_allowed)
				(footprints allowed)
			)
			(placement
				(enabled no)
				(sheetname "")
			)
			(fill
				(thermal_gap 0.5)
				(thermal_bridge_width 0.5)
				(island_removal_mode 0)
			)
			(polygon
				(pts
					(xy 407.0096 -29.3624) (xy 406.5016 -29.3624) (xy 406.5016 -28.9814) (xy 407.0096 -28.9814)
				)
			)
		)
		(zone
			(layer "B.Cu")
			(hatch none 0.5)
			(connect_pads
				(clearance 0)
			)
			(min_thickness 0.25)
			(keepout
				(tracks not_allowed)
				(vias allowed)
				(pads allowed)
				(copperpour not_allowed)
				(footprints allowed)
			)
			(placement
				(enabled no)
				(sheetname "")
			)
			(fill
				(thermal_gap 0.5)
				(thermal_bridge_width 0.5)
				(island_removal_mode 0)
			)
			(polygon
				(pts
					(xy 407.0096 -28.9814) (xy 406.5016 -28.9814) (xy 406.5016 -29.3624) (xy 407.0096 -29.3624)
				)
			)
		)
	)
	(footprint ""
		(layer "B.Cu")
		(at 318.797432 1.7018 -90)
		(property "Reference" "C4U4"
			(at 0 0 90)
			(layer "B.SilkS")
			(hide yes)
			(effects
				(font
					(size 1.27 1.27)
				)
				(justify mirror)
			)
		)
		(property "Value" ""
			(at 0 0 90)
			(layer "B.Fab")
			(effects
				(font
					(size 1.27 1.27)
				)
				(justify mirror)
			)
		)
		(duplicate_pad_numbers_are_jumpers no)
		(fp_poly
			(pts
				(xy 0.4953 -0.2032) (xy -0.4953 -0.2032) (xy -0.4953 1.6002) (xy 0.4953 1.6002)
			)
			(stroke
				(width 0)
				(type default)
			)
			(fill no)
			(layer "B.CrtYd")
		)
		(fp_line
			(start -0.4953 1.6002)
			(end 0.4953 1.6002)
			(stroke
				(width 0.1)
				(type default)
			)
			(layer "B.Fab")
		)
		(fp_line
			(start 0.4953 1.6002)
			(end 0.4953 -0.2032)
			(stroke
				(width 0.1)
				(type default)
			)
			(layer "B.Fab")
		)
		(fp_line
			(start -0.4953 -0.2032)
			(end -0.4953 1.6002)
			(stroke
				(width 0.1)
				(type default)
			)
			(layer "B.Fab")
		)
		(fp_line
			(start 0.4953 -0.2032)
			(end -0.4953 -0.2032)
			(stroke
				(width 0.1)
				(type default)
			)
			(layer "B.Fab")
		)
		(pad "1" smd rect
			(at 0 0 90)
			(size 0.762 0.889)
			(layers "B.Cu" "B.Mask" "B.Paste")
			(net "PVPP_ABC")
		)
		(pad "2" smd rect
			(at 0 1.397 90)
			(size 0.762 0.889)
			(layers "B.Cu" "B.Mask" "B.Paste")
			(net "GND")
		)
		(zone
			(layer "B.Cu")
			(hatch none 0.5)
			(connect_pads
				(clearance 0)
			)
			(min_thickness 0.25)
			(keepout
				(tracks not_allowed)
				(vias allowed)
				(pads allowed)
				(copperpour not_allowed)
				(footprints allowed)
			)
			(placement
				(enabled no)
				(sheetname "")
			)
			(fill
				(thermal_gap 0.5)
				(thermal_bridge_width 0.5)
				(island_removal_mode 0)
			)
			(polygon
				(pts
					(xy 318.352932 2.0828) (xy 318.352932 1.3208) (xy 317.844932 1.3208) (xy 317.844932 2.0828)
				)
			)
		)
	)
	(footprint ""
		(layer "B.Cu")
		(at 168.656 -87.757)
		(property "Reference" "R6P5"
			(at 0 0 0)
			(layer "B.SilkS")
			(hide yes)
			(effects
				(font
					(size 1.27 1.27)
				)
				(justify mirror)
			)
		)
		(property "Value" ""
			(at 0 0 0)
			(layer "B.Fab")
			(effects
				(font
					(size 1.27 1.27)
				)
				(justify mirror)
			)
		)
		(duplicate_pad_numbers_are_jumpers no)
		(fp_poly
			(pts
				(xy 0.2794 -0.1016) (xy -0.2794 -0.1016) (xy -0.2794 0.9906) (xy 0.2794 0.9906)
			)
			(stroke
				(width 0)
				(type default)
			)
			(fill no)
			(layer "B.CrtYd")
		)
		(fp_line
			(start -0.2794 -0.1016)
			(end 0.2794 -0.1016)
			(stroke
				(width 0.1)
				(type default)
			)
			(layer "B.Fab")
		)
		(fp_line
			(start -0.2794 0.9906)
			(end -0.2794 -0.1016)
			(stroke
				(width 0.1)
				(type default)
			)
			(layer "B.Fab")
		)
		(fp_line
			(start 0.2794 -0.1016)
			(end 0.2794 0.9906)
			(stroke
				(width 0.1)
				(type default)
			)
			(layer "B.Fab")
		)
		(fp_line
			(start 0.2794 0.9906)
			(end -0.2794 0.9906)
			(stroke
				(width 0.1)
				(type default)
			)
			(layer "B.Fab")
		)
		(pad "1" smd rect
			(at 0 0 180)
			(size 0.508 0.508)
			(layers "B.Cu" "B.Mask" "B.Paste")
			(net "CLK_100M_CPU1_BCLK0_DP")
		)
		(pad "2" smd rect
			(at 0 0.889 180)
			(size 0.508 0.508)
			(layers "B.Cu" "B.Mask" "B.Paste")
			(net "GND")
		)
		(zone
			(layer "B.Cu")
			(hatch none 0.5)
			(connect_pads
				(clearance 0)
			)
			(min_thickness 0.25)
			(keepout
				(tracks allowed)
				(vias not_allowed)
				(pads allowed)
				(copperpour not_allowed)
				(footprints allowed)
			)
			(placement
				(enabled no)
				(sheetname "")
			)
			(fill
				(thermal_gap 0.5)
				(thermal_bridge_width 0.5)
				(island_removal_mode 0)
			)
			(polygon
				(pts
					(xy 168.91 -87.503) (xy 168.402 -87.503) (xy 168.402 -87.122) (xy 168.91 -87.122)
				)
			)
		)
		(zone
			(layer "B.Cu")
			(hatch none 0.5)
			(connect_pads
				(clearance 0)
			)
			(min_thickness 0.25)
			(keepout
				(tracks not_allowed)
				(vias allowed)
				(pads allowed)
				(copperpour not_allowed)
				(footprints allowed)
			)
			(placement
				(enabled no)
				(sheetname "")
			)
			(fill
				(thermal_gap 0.5)
				(thermal_bridge_width 0.5)
				(island_removal_mode 0)
			)
			(polygon
				(pts
					(xy 168.91 -87.122) (xy 168.402 -87.122) (xy 168.402 -87.503) (xy 168.91 -87.503)
				)
			)
		)
	)
	(footprint ""
		(layer "B.Cu")
		(at 178.562 -54.991 -90)
		(property "Reference" "C6R8"
			(at 0 0 90)
			(layer "B.SilkS")
			(hide yes)
			(effects
				(font
					(size 1.27 1.27)
				)
				(justify mirror)
			)
		)
		(property "Value" ""
			(at 0 0 90)
			(layer "B.Fab")
			(effects
				(font
					(size 1.27 1.27)
				)
				(justify mirror)
			)
		)
		(duplicate_pad_numbers_are_jumpers no)
		(fp_poly
			(pts
				(xy 0.7239 -0.2159) (xy -0.7239 -0.2159) (xy -0.7239 1.9939) (xy 0.7239 1.9939)
			)
			(stroke
				(width 0)
				(type default)
			)
			(fill no)
			(layer "B.CrtYd")
		)
		(fp_line
			(start -0.7239 1.9939)
			(end -0.7239 -0.2159)
			(stroke
				(width 0.1)
				(type default)
			)
			(layer "B.Fab")
		)
		(fp_line
			(start 0.7239 1.9939)
			(end -0.7239 1.9939)
			(stroke
				(width 0.1)
				(type default)
			)
			(layer "B.Fab")
		)
		(fp_line
			(start -0.7239 -0.2159)
			(end 0.7239 -0.2159)
			(stroke
				(width 0.1)
				(type default)
			)
			(layer "B.Fab")
		)
		(fp_line
			(start 0.7239 -0.2159)
			(end 0.7239 1.9939)
			(stroke
				(width 0.1)
				(type default)
			)
			(layer "B.Fab")
		)
		(pad "1" smd rect
			(at 0 0 90)
			(size 1.27 1.016)
			(layers "B.Cu" "B.Mask" "B.Paste")
			(net "VR_FET_SW_P12V_STBY_PVCCIN_CPU0")
		)
		(pad "2" smd rect
			(at 0 1.778 90)
			(size 1.27 1.016)
			(layers "B.Cu" "B.Mask" "B.Paste")
			(net "GND")
		)
		(zone
			(layer "B.Cu")
			(hatch none 0.5)
			(connect_pads
				(clearance 0)
			)
			(min_thickness 0.25)
			(keepout
				(tracks not_allowed)
				(vias allowed)
				(pads allowed)
				(copperpour not_allowed)
				(footprints allowed)
			)
			(placement
				(enabled no)
				(sheetname "")
			)
			(fill
				(thermal_gap 0.5)
				(thermal_bridge_width 0.5)
				(island_removal_mode 0)
			)
			(polygon
				(pts
					(xy 178.054 -54.356) (xy 178.054 -55.626) (xy 177.292 -55.626) (xy 177.292 -54.356)
				)
			)
		)
	)
	(footprint ""
		(layer "B.Cu")
		(at 80.757268 -17.7546 -90)
		(property "Reference" "C8T10"
			(at -1.848866 0.752348 270)
			(unlocked yes)
			(layer "B.SilkS")
			(effects
				(font
					(size 1.27 0.9652)
					(thickness 0.1524)
				)
				(justify mirror)
			)
		)
		(property "Value" ""
			(at 0 0 90)
			(layer "B.Fab")
			(effects
				(font
					(size 1.27 1.27)
				)
				(justify mirror)
			)
		)
		(duplicate_pad_numbers_are_jumpers no)
		(fp_rect
			(start 0.500126 1.598422)
			(end -0.500126 -0.201422)
			(stroke
				(width 0)
				(type default)
			)
			(fill no)
			(layer "B.CrtYd")
		)
		(fp_line
			(start -0.500126 1.598422)
			(end 0.500126 1.598422)
			(stroke
				(width 0.1)
				(type default)
			)
			(layer "B.Fab")
		)
		(fp_line
			(start 0.500126 1.598422)
			(end 0.500126 -0.201422)
			(stroke
				(width 0.1)
				(type default)
			)
			(layer "B.Fab")
		)
		(fp_line
			(start -0.500126 -0.201422)
			(end -0.500126 1.598422)
			(stroke
				(width 0.1)
				(type default)
			)
			(layer "B.Fab")
		)
		(fp_line
			(start 0.500126 -0.201422)
			(end -0.500126 -0.201422)
			(stroke
				(width 0.1)
				(type default)
			)
			(layer "B.Fab")
		)
		(pad "1" smd rect
			(at 0 0 180)
			(size 0.889 0.9906)
			(layers "B.Cu" "B.Mask" "B.Paste")
			(net "PVDDQ_GHJ")
		)
		(pad "2" smd rect
			(at 0 1.397 180)
			(size 0.889 0.9906)
			(layers "B.Cu" "B.Mask" "B.Paste")
			(net "GND")
		)
		(zone
			(layer "B.Cu")
			(hatch none 0.5)
			(connect_pads
				(clearance 0)
			)
			(min_thickness 0.25)
			(keepout
				(tracks not_allowed)
				(vias allowed)
				(pads allowed)
				(copperpour not_allowed)
				(footprints allowed)
			)
			(placement
				(enabled no)
				(sheetname "")
			)
			(fill
				(thermal_gap 0.5)
				(thermal_bridge_width 0.5)
				(island_removal_mode 0)
			)
			(polygon
				(pts
					(xy 79.804768 -17.2593) (xy 80.312768 -17.2593) (xy 80.312768 -18.2499) (xy 79.804768 -18.2499)
				)
			)
		)
		(zone
			(layer "B.Cu")
			(hatch none 0.5)
			(connect_pads
				(clearance 0)
			)
			(min_thickness 0.25)
			(keepout
				(tracks allowed)
				(vias not_allowed)
				(pads allowed)
				(copperpour not_allowed)
				(footprints allowed)
			)
			(placement
				(enabled no)
				(sheetname "")
			)
			(fill
				(thermal_gap 0.5)
				(thermal_bridge_width 0.5)
				(island_removal_mode 0)
			)
			(polygon
				(pts
					(xy 79.804768 -17.2593) (xy 80.312768 -17.2593) (xy 80.312768 -18.2499) (xy 79.804768 -18.2499)
				)
			)
		)
	)
	(footprint ""
		(layer "B.Cu")
		(at 32.832802 -66.425064 90)
		(property "Reference" "C9P25"
			(at 0 0 90)
			(layer "B.SilkS")
			(hide yes)
			(effects
				(font
					(size 1.27 1.27)
				)
				(justify mirror)
			)
		)
		(property "Value" ""
			(at 0 0 90)
			(layer "B.Fab")
			(effects
				(font
					(size 1.27 1.27)
				)
				(justify mirror)
			)
		)
		(duplicate_pad_numbers_are_jumpers no)
		(fp_poly
			(pts
				(xy 0.7239 -0.2159) (xy -0.7239 -0.2159) (xy -0.7239 1.9939) (xy 0.7239 1.9939)
			)
			(stroke
				(width 0)
				(type default)
			)
			(fill no)
			(layer "B.CrtYd")
		)
		(fp_line
			(start 0.7239 -0.2159)
			(end 0.7239 1.9939)
			(stroke
				(width 0.1)
				(type default)
			)
			(layer "B.Fab")
		)
		(fp_line
			(start -0.7239 -0.2159)
			(end 0.7239 -0.2159)
			(stroke
				(width 0.1)
				(type default)
			)
			(layer "B.Fab")
		)
		(fp_line
			(start 0.7239 1.9939)
			(end -0.7239 1.9939)
			(stroke
				(width 0.1)
				(type default)
			)
			(layer "B.Fab")
		)
		(fp_line
			(start -0.7239 1.9939)
			(end -0.7239 -0.2159)
			(stroke
				(width 0.1)
				(type default)
			)
			(layer "B.Fab")
		)
		(pad "1" smd rect
			(at 0 0 270)
			(size 1.27 1.016)
			(layers "B.Cu" "B.Mask" "B.Paste")
			(net "VR_FET_SW_P12V_STBY_PVCCIN_CPU1")
		)
		(pad "2" smd rect
			(at 0 1.778 270)
			(size 1.27 1.016)
			(layers "B.Cu" "B.Mask" "B.Paste")
			(net "GND")
		)
		(zone
			(layer "B.Cu")
			(hatch none 0.5)
			(connect_pads
				(clearance 0)
			)
			(min_thickness 0.25)
			(keepout
				(tracks not_allowed)
				(vias allowed)
				(pads allowed)
				(copperpour not_allowed)
				(footprints allowed)
			)
			(placement
				(enabled no)
				(sheetname "")
			)
			(fill
				(thermal_gap 0.5)
				(thermal_bridge_width 0.5)
				(island_removal_mode 0)
			)
			(polygon
				(pts
					(xy 33.340802 -67.060064) (xy 33.340802 -65.790064) (xy 34.102802 -65.790064) (xy 34.102802 -67.060064)
				)
			)
		)
	)
	(footprint ""
		(layer "B.Cu")
		(at 402.4503 -38.7604 -90)
		(property "Reference" "R2U7"
			(at 0 0 90)
			(layer "B.SilkS")
			(hide yes)
			(effects
				(font
					(size 1.27 1.27)
				)
				(justify mirror)
			)
		)
		(property "Value" ""
			(at 0 0 90)
			(layer "B.Fab")
			(effects
				(font
					(size 1.27 1.27)
				)
				(justify mirror)
			)
		)
		(duplicate_pad_numbers_are_jumpers no)
		(fp_poly
			(pts
				(xy 0.2794 -0.1016) (xy -0.2794 -0.1016) (xy -0.2794 0.9906) (xy 0.2794 0.9906)
			)
			(stroke
				(width 0)
				(type default)
			)
			(fill no)
			(layer "B.CrtYd")
		)
		(fp_line
			(start -0.2794 0.9906)
			(end -0.2794 -0.1016)
			(stroke
				(width 0.1)
				(type default)
			)
			(layer "B.Fab")
		)
		(fp_line
			(start 0.2794 0.9906)
			(end -0.2794 0.9906)
			(stroke
				(width 0.1)
				(type default)
			)
			(layer "B.Fab")
		)
		(fp_line
			(start -0.2794 -0.1016)
			(end 0.2794 -0.1016)
			(stroke
				(width 0.1)
				(type default)
			)
			(layer "B.Fab")
		)
		(fp_line
			(start 0.2794 -0.1016)
			(end 0.2794 0.9906)
			(stroke
				(width 0.1)
				(type default)
			)
			(layer "B.Fab")
		)
		(pad "1" smd rect
			(at 0 0 90)
			(size 0.508 0.508)
			(layers "B.Cu" "B.Mask" "B.Paste")
			(net "SMB_OCP_FRU_STBY_LVC3_SCL_R")
		)
		(pad "2" smd rect
			(at 0 0.889 90)
			(size 0.508 0.508)
			(layers "B.Cu" "B.Mask" "B.Paste")
			(net "SMB_OCP_FRU_STBY_LVC3_SCL")
		)
		(zone
			(layer "B.Cu")
			(hatch none 0.5)
			(connect_pads
				(clearance 0)
			)
			(min_thickness 0.25)
			(keepout
				(tracks not_allowed)
				(vias allowed)
				(pads allowed)
				(copperpour not_allowed)
				(footprints allowed)
			)
			(placement
				(enabled no)
				(sheetname "")
			)
			(fill
				(thermal_gap 0.5)
				(thermal_bridge_width 0.5)
				(island_removal_mode 0)
			)
			(polygon
				(pts
					(xy 401.8153 -38.5064) (xy 401.8153 -39.0144) (xy 402.1963 -39.0144) (xy 402.1963 -38.5064)
				)
			)
		)
		(zone
			(layer "B.Cu")
			(hatch none 0.5)
			(connect_pads
				(clearance 0)
			)
			(min_thickness 0.25)
			(keepout
				(tracks allowed)
				(vias not_allowed)
				(pads allowed)
				(copperpour not_allowed)
				(footprints allowed)
			)
			(placement
				(enabled no)
				(sheetname "")
			)
			(fill
				(thermal_gap 0.5)
				(thermal_bridge_width 0.5)
				(island_removal_mode 0)
			)
			(polygon
				(pts
					(xy 402.1963 -38.5064) (xy 402.1963 -39.0144) (xy 401.8153 -39.0144) (xy 401.8153 -38.5064)
				)
			)
		)
	)
	(footprint ""
		(layer "B.Cu")
		(at 197.848728 -64.676782 90)
		(property "Reference" "C6R4"
			(at 0 0 90)
			(layer "B.SilkS")
			(hide yes)
			(effects
				(font
					(size 1.27 1.27)
				)
				(justify mirror)
			)
		)
		(property "Value" ""
			(at 0 0 90)
			(layer "B.Fab")
			(effects
				(font
					(size 1.27 1.27)
				)
				(justify mirror)
			)
		)
		(duplicate_pad_numbers_are_jumpers no)
		(fp_rect
			(start -0.7239 -0.2159)
			(end 0.7239 1.9939)
			(stroke
				(width 0)
				(type default)
			)
			(fill no)
			(layer "B.CrtYd")
		)
		(fp_line
			(start 0.7239 -0.2159)
			(end 0.7239 1.9939)
			(stroke
				(width 0.1)
				(type default)
			)
			(layer "B.Fab")
		)
		(fp_line
			(start -0.7239 -0.2159)
			(end 0.7239 -0.2159)
			(stroke
				(width 0.1)
				(type default)
			)
			(layer "B.Fab")
		)
		(fp_line
			(start 0.7239 1.9939)
			(end -0.7239 1.9939)
			(stroke
				(width 0.1)
				(type default)
			)
			(layer "B.Fab")
		)
		(fp_line
			(start -0.7239 1.9939)
			(end -0.7239 -0.2159)
			(stroke
				(width 0.1)
				(type default)
			)
			(layer "B.Fab")
		)
		(pad "1" smd rect
			(at 0 0 270)
			(size 1.27 1.016)
			(layers "B.Cu" "B.Mask" "B.Paste")
			(net "VR_FET_SW_P12V_STBY_PVCCIN_CPU0")
		)
		(pad "2" smd rect
			(at 0 1.778 270)
			(size 1.27 1.016)
			(layers "B.Cu" "B.Mask" "B.Paste")
			(net "GND")
		)
		(zone
			(layer "B.Cu")
			(hatch none 0.5)
			(connect_pads
				(clearance 0)
			)
			(min_thickness 0.25)
			(keepout
				(tracks not_allowed)
				(vias allowed)
				(pads allowed)
				(copperpour not_allowed)
				(footprints allowed)
			)
			(placement
				(enabled no)
				(sheetname "")
			)
			(fill
				(thermal_gap 0.5)
				(thermal_bridge_width 0.5)
				(island_removal_mode 0)
			)
			(polygon
				(pts
					(xy 198.356728 -64.041782) (xy 199.118728 -64.041782) (xy 199.118728 -65.311782) (xy 198.356728 -65.311782)
				)
			)
		)
	)
	(footprint ""
		(layer "B.Cu")
		(at 450.317362 -29.314648)
		(property "Reference" "C25W17"
			(at 0 0 0)
			(layer "B.SilkS")
			(hide yes)
			(effects
				(font
					(size 1.27 1.27)
				)
				(justify mirror)
			)
		)
		(property "Value" "*"
			(at 0 -2.9337 0)
			(unlocked yes)
			(layer "B.Fab")
			(hide yes)
			(effects
				(font
					(size 1.27 1.016)
					(thickness 0.1524)
				)
				(justify mirror)
			)
		)
		(property "Device Type" "SC1U16V3KX-2GP_SMD-BCG-SC1U16VA"
			(at 0 -4.4577 0)
			(unlocked yes)
			(layer "B.Fab")
			(hide yes)
			(effects
				(font
					(size 1.27 1.016)
					(thickness 0.1524)
				)
				(justify mirror)
			)
		)
		(duplicate_pad_numbers_are_jumpers no)
		(fp_line
			(start -0.508 0)
			(end 0.508 0)
			(stroke
				(width 0.2032)
				(type default)
			)
			(layer "B.SilkS")
		)
		(fp_rect
			(start 0.5842 1.3335)
			(end -0.5842 -1.3335)
			(stroke
				(width 0)
				(type default)
			)
			(fill no)
			(layer "B.CrtYd")
		)
		(fp_rect
			(start 0.5842 1.3335)
			(end -0.5842 -1.3335)
			(stroke
				(width 0)
				(type default)
			)
			(fill no)
			(layer "B.Fab")
		)
		(pad "1" smd custom
			(at 0 -0.762 180)
			(size 0.2159 0.2159)
			(layers "B.Cu" "B.Mask" "B.Paste")
			(net "P1V2_AUX_BMC")
			(options
				(clearance outline)
				(anchor circle)
			)
			(primitives
				(gr_poly
					(pts
						(arc
							(start -0.3302 0.4318)
							(mid -0.402042 0.402042)
							(end -0.4318 0.3302)
						)
						(arc
							(start -0.4318 -0.3302)
							(mid -0.402042 -0.402042)
							(end -0.3302 -0.4318)
						)
						(arc
							(start 0.3302 -0.4318)
							(mid 0.402042 -0.402042)
							(end 0.4318 -0.3302)
						)
						(arc
							(start 0.4318 0.3302)
							(mid 0.402042 0.402042)
							(end 0.3302 0.4318)
						)
					)
					(width 0)
					(fill yes)
				)
			)
		)
		(pad "2" smd custom
			(at 0 0.762 180)
			(size 0.2159 0.2159)
			(layers "B.Cu" "B.Mask" "B.Paste")
			(net "GND")
			(options
				(clearance outline)
				(anchor circle)
			)
			(primitives
				(gr_poly
					(pts
						(arc
							(start -0.3302 0.4318)
							(mid -0.402042 0.402042)
							(end -0.4318 0.3302)
						)
						(arc
							(start -0.4318 -0.3302)
							(mid -0.402042 -0.402042)
							(end -0.3302 -0.4318)
						)
						(arc
							(start 0.3302 -0.4318)
							(mid 0.402042 -0.402042)
							(end 0.4318 -0.3302)
						)
						(arc
							(start 0.4318 0.3302)
							(mid 0.402042 0.402042)
							(end 0.3302 0.4318)
						)
					)
					(width 0)
					(fill yes)
				)
			)
		)
	)
	(footprint ""
		(layer "B.Cu")
		(at 350.110806 -61.257434)
		(property "Reference" "C2U15"
			(at 0 0 0)
			(layer "B.SilkS")
			(hide yes)
			(effects
				(font
					(size 1.27 1.27)
				)
				(justify mirror)
			)
		)
		(property "Value" ""
			(at 0 0 0)
			(layer "B.Fab")
			(effects
				(font
					(size 1.27 1.27)
				)
				(justify mirror)
			)
		)
		(duplicate_pad_numbers_are_jumpers no)
		(fp_poly
			(pts
				(xy -0.3048 -0.1016) (xy -0.3048 0.9906) (xy 0.3048 0.9906) (xy 0.3048 -0.1016)
			)
			(stroke
				(width 0)
				(type default)
			)
			(fill no)
			(layer "B.CrtYd")
		)
		(fp_line
			(start -0.3048 -0.1016)
			(end 0.3048 -0.1016)
			(stroke
				(width 0.1)
				(type default)
			)
			(layer "B.Fab")
		)
		(fp_line
			(start -0.3048 0.9906)
			(end -0.3048 -0.1016)
			(stroke
				(width 0.1)
				(type default)
			)
			(layer "B.Fab")
		)
		(fp_line
			(start 0.3048 -0.1016)
			(end 0.3048 0.9906)
			(stroke
				(width 0.1)
				(type default)
			)
			(layer "B.Fab")
		)
		(fp_line
			(start 0.3048 0.9906)
			(end -0.3048 0.9906)
			(stroke
				(width 0.1)
				(type default)
			)
			(layer "B.Fab")
		)
		(pad "1" smd rect
			(at 0 0 180)
			(size 0.508 0.508)
			(layers "B.Cu" "B.Mask" "B.Paste")
			(net "P3E_CPU0_PE1_PCH_RXP<6>")
		)
		(pad "2" smd rect
			(at 0 0.889 180)
			(size 0.508 0.508)
			(layers "B.Cu" "B.Mask" "B.Paste")
			(net "P3E_CPU0_PE1_SS_RXP<6>")
		)
		(zone
			(layer "B.Cu")
			(hatch none 0.5)
			(connect_pads
				(clearance 0)
			)
			(min_thickness 0.25)
			(keepout
				(tracks allowed)
				(vias not_allowed)
				(pads allowed)
				(copperpour not_allowed)
				(footprints allowed)
			)
			(placement
				(enabled no)
				(sheetname "")
			)
			(fill
				(thermal_gap 0.5)
				(thermal_bridge_width 0.5)
				(island_removal_mode 0)
			)
			(polygon
				(pts
					(xy 350.364806 -61.003434) (xy 349.856806 -61.003434) (xy 349.856806 -60.622434) (xy 350.364806 -60.622434)
				)
			)
		)
		(zone
			(layer "B.Cu")
			(hatch none 0.5)
			(connect_pads
				(clearance 0)
			)
			(min_thickness 0.25)
			(keepout
				(tracks not_allowed)
				(vias allowed)
				(pads allowed)
				(copperpour not_allowed)
				(footprints allowed)
			)
			(placement
				(enabled no)
				(sheetname "")
			)
			(fill
				(thermal_gap 0.5)
				(thermal_bridge_width 0.5)
				(island_removal_mode 0)
			)
			(polygon
				(pts
					(xy 350.364806 -60.622434) (xy 349.856806 -60.622434) (xy 349.856806 -61.003434) (xy 350.364806 -61.003434)
				)
			)
		)
	)
	(footprint ""
		(layer "B.Cu")
		(at 183.16702 -10.91057 90)
		(property "Reference" "C6U7"
			(at -1.47828 0.78994 180)
			(unlocked yes)
			(layer "B.SilkS")
			(effects
				(font
					(size 0.4064 0.254)
					(thickness 0.1524)
				)
				(justify mirror)
			)
		)
		(property "Value" ""
			(at 0 0 90)
			(layer "B.Fab")
			(effects
				(font
					(size 1.27 1.27)
				)
				(justify mirror)
			)
		)
		(duplicate_pad_numbers_are_jumpers no)
		(fp_poly
			(pts
				(xy 0.7239 -0.2159) (xy -0.7239 -0.2159) (xy -0.7239 1.9939) (xy 0.7239 1.9939)
			)
			(stroke
				(width 0)
				(type default)
			)
			(fill no)
			(layer "B.CrtYd")
		)
		(fp_line
			(start 0.7239 -0.2159)
			(end 0.7239 1.9939)
			(stroke
				(width 0.1)
				(type default)
			)
			(layer "B.Fab")
		)
		(fp_line
			(start -0.7239 -0.2159)
			(end 0.7239 -0.2159)
			(stroke
				(width 0.1)
				(type default)
			)
			(layer "B.Fab")
		)
		(fp_line
			(start 0.7239 1.9939)
			(end -0.7239 1.9939)
			(stroke
				(width 0.1)
				(type default)
			)
			(layer "B.Fab")
		)
		(fp_line
			(start -0.7239 1.9939)
			(end -0.7239 -0.2159)
			(stroke
				(width 0.1)
				(type default)
			)
			(layer "B.Fab")
		)
		(pad "1" smd rect
			(at 0 0 270)
			(size 1.27 1.016)
			(layers "B.Cu" "B.Mask" "B.Paste")
			(net "VR_FET_SW_P12V_STBY_PVPP_GHJ")
		)
		(pad "2" smd rect
			(at 0 1.778 270)
			(size 1.27 1.016)
			(layers "B.Cu" "B.Mask" "B.Paste")
			(net "GND")
		)
		(zone
			(layer "B.Cu")
			(hatch none 0.5)
			(connect_pads
				(clearance 0)
			)
			(min_thickness 0.25)
			(keepout
				(tracks not_allowed)
				(vias allowed)
				(pads allowed)
				(copperpour not_allowed)
				(footprints allowed)
			)
			(placement
				(enabled no)
				(sheetname "")
			)
			(fill
				(thermal_gap 0.5)
				(thermal_bridge_width 0.5)
				(island_removal_mode 0)
			)
			(polygon
				(pts
					(xy 183.67502 -11.54557) (xy 183.67502 -10.27557) (xy 184.43702 -10.27557) (xy 184.43702 -11.54557)
				)
			)
		)
	)
	(footprint ""
		(layer "B.Cu")
		(at 389.382 -87.4395)
		(property "Reference" "R2N31"
			(at 0 0 0)
			(layer "B.SilkS")
			(hide yes)
			(effects
				(font
					(size 1.27 1.27)
				)
				(justify mirror)
			)
		)
		(property "Value" ""
			(at 0 0 0)
			(layer "B.Fab")
			(effects
				(font
					(size 1.27 1.27)
				)
				(justify mirror)
			)
		)
		(duplicate_pad_numbers_are_jumpers no)
		(fp_poly
			(pts
				(xy 0.2794 -0.1016) (xy -0.2794 -0.1016) (xy -0.2794 0.9906) (xy 0.2794 0.9906)
			)
			(stroke
				(width 0)
				(type default)
			)
			(fill no)
			(layer "B.CrtYd")
		)
		(fp_line
			(start -0.2794 -0.1016)
			(end 0.2794 -0.1016)
			(stroke
				(width 0.1)
				(type default)
			)
			(layer "B.Fab")
		)
		(fp_line
			(start -0.2794 0.9906)
			(end -0.2794 -0.1016)
			(stroke
				(width 0.1)
				(type default)
			)
			(layer "B.Fab")
		)
		(fp_line
			(start 0.2794 -0.1016)
			(end 0.2794 0.9906)
			(stroke
				(width 0.1)
				(type default)
			)
			(layer "B.Fab")
		)
		(fp_line
			(start 0.2794 0.9906)
			(end -0.2794 0.9906)
			(stroke
				(width 0.1)
				(type default)
			)
			(layer "B.Fab")
		)
		(pad "1" smd rect
			(at 0 0 180)
			(size 0.508 0.508)
			(layers "B.Cu" "B.Mask" "B.Paste")
			(net "SGPIO_PCH_SATA_CLOCK")
		)
		(pad "2" smd rect
			(at 0 0.889 180)
			(size 0.508 0.508)
			(layers "B.Cu" "B.Mask" "B.Paste")
			(net "SGPIO_PCH_SATA_CLOCK_R")
		)
		(zone
			(layer "B.Cu")
			(hatch none 0.5)
			(connect_pads
				(clearance 0)
			)
			(min_thickness 0.25)
			(keepout
				(tracks allowed)
				(vias not_allowed)
				(pads allowed)
				(copperpour not_allowed)
				(footprints allowed)
			)
			(placement
				(enabled no)
				(sheetname "")
			)
			(fill
				(thermal_gap 0.5)
				(thermal_bridge_width 0.5)
				(island_removal_mode 0)
			)
			(polygon
				(pts
					(xy 389.636 -87.1855) (xy 389.128 -87.1855) (xy 389.128 -86.8045) (xy 389.636 -86.8045)
				)
			)
		)
		(zone
			(layer "B.Cu")
			(hatch none 0.5)
			(connect_pads
				(clearance 0)
			)
			(min_thickness 0.25)
			(keepout
				(tracks not_allowed)
				(vias allowed)
				(pads allowed)
				(copperpour not_allowed)
				(footprints allowed)
			)
			(placement
				(enabled no)
				(sheetname "")
			)
			(fill
				(thermal_gap 0.5)
				(thermal_bridge_width 0.5)
				(island_removal_mode 0)
			)
			(polygon
				(pts
					(xy 389.636 -86.8045) (xy 389.128 -86.8045) (xy 389.128 -87.1855) (xy 389.636 -87.1855)
				)
			)
		)
	)
	(footprint ""
		(layer "B.Cu")
		(at 390.7155 -39.51351 -90)
		(property "Reference" "C2T2"
			(at 0 0 90)
			(layer "B.SilkS")
			(hide yes)
			(effects
				(font
					(size 1.27 1.27)
				)
				(justify mirror)
			)
		)
		(property "Value" ""
			(at 0 0 90)
			(layer "B.Fab")
			(effects
				(font
					(size 1.27 1.27)
				)
				(justify mirror)
			)
		)
		(duplicate_pad_numbers_are_jumpers no)
		(fp_poly
			(pts
				(xy -0.3048 -0.1016) (xy -0.3048 0.9906) (xy 0.3048 0.9906) (xy 0.3048 -0.1016)
			)
			(stroke
				(width 0)
				(type default)
			)
			(fill no)
			(layer "B.CrtYd")
		)
		(fp_line
			(start -0.3048 0.9906)
			(end -0.3048 -0.1016)
			(stroke
				(width 0.1)
				(type default)
			)
			(layer "B.Fab")
		)
		(fp_line
			(start 0.3048 0.9906)
			(end -0.3048 0.9906)
			(stroke
				(width 0.1)
				(type default)
			)
			(layer "B.Fab")
		)
		(fp_line
			(start -0.3048 -0.1016)
			(end 0.3048 -0.1016)
			(stroke
				(width 0.1)
				(type default)
			)
			(layer "B.Fab")
		)
		(fp_line
			(start 0.3048 -0.1016)
			(end 0.3048 0.9906)
			(stroke
				(width 0.1)
				(type default)
			)
			(layer "B.Fab")
		)
		(pad "1" smd rect
			(at 0 0 90)
			(size 0.508 0.508)
			(layers "B.Cu" "B.Mask" "B.Paste")
			(net "P3V3")
		)
		(pad "2" smd rect
			(at 0 0.889 90)
			(size 0.508 0.508)
			(layers "B.Cu" "B.Mask" "B.Paste")
			(net "GND")
		)
		(zone
			(layer "B.Cu")
			(hatch none 0.5)
			(connect_pads
				(clearance 0)
			)
			(min_thickness 0.25)
			(keepout
				(tracks not_allowed)
				(vias allowed)
				(pads allowed)
				(copperpour not_allowed)
				(footprints allowed)
			)
			(placement
				(enabled no)
				(sheetname "")
			)
			(fill
				(thermal_gap 0.5)
				(thermal_bridge_width 0.5)
				(island_removal_mode 0)
			)
			(polygon
				(pts
					(xy 390.0805 -39.25951) (xy 390.0805 -39.76751) (xy 390.4615 -39.76751) (xy 390.4615 -39.25951)
				)
			)
		)
		(zone
			(layer "B.Cu")
			(hatch none 0.5)
			(connect_pads
				(clearance 0)
			)
			(min_thickness 0.25)
			(keepout
				(tracks allowed)
				(vias not_allowed)
				(pads allowed)
				(copperpour not_allowed)
				(footprints allowed)
			)
			(placement
				(enabled no)
				(sheetname "")
			)
			(fill
				(thermal_gap 0.5)
				(thermal_bridge_width 0.5)
				(island_removal_mode 0)
			)
			(polygon
				(pts
					(xy 390.4615 -39.25951) (xy 390.4615 -39.76751) (xy 390.0805 -39.76751) (xy 390.0805 -39.25951)
				)
			)
		)
	)
	(footprint ""
		(layer "B.Cu")
		(at 499.442994 -40.624506)
		(property "Reference" "U25W8"
			(at 0 0 0)
			(layer "B.SilkS")
			(hide yes)
			(effects
				(font
					(size 1.27 1.27)
				)
				(justify mirror)
			)
		)
		(property "Value" "*"
			(at 0 -10.7315 0)
			(unlocked yes)
			(layer "B.Fab")
			(hide yes)
			(effects
				(font
					(size 1.27 1.016)
					(thickness 0.1524)
				)
				(justify mirror)
			)
		)
		(property "Device Type" "U74AHCT1G125G-AL5-R-GP-U_TTL-GA"
			(at 0 -12.2555 0)
			(unlocked yes)
			(layer "B.Fab")
			(hide yes)
			(effects
				(font
					(size 1.27 1.016)
					(thickness 0.1524)
				)
				(justify mirror)
			)
		)
		(duplicate_pad_numbers_are_jumpers no)
		(fp_line
			(start -1.24714 -1.79832)
			(end -1.24714 1.82372)
			(stroke
				(width 0.1524)
				(type default)
			)
			(layer "B.SilkS")
		)
		(fp_line
			(start -1.2446 1.81102)
			(end -1.25476 1.82118)
			(stroke
				(width 0.1524)
				(type default)
			)
			(layer "B.SilkS")
		)
		(fp_line
			(start -1.08712 -1.80848)
			(end 1.23952 -1.80848)
			(stroke
				(width 0.1524)
				(type default)
			)
			(layer "B.SilkS")
		)
		(fp_line
			(start -1.08204 -1.80848)
			(end -1.26492 -1.80848)
			(stroke
				(width 0.1524)
				(type default)
			)
			(layer "B.SilkS")
		)
		(fp_line
			(start -1.08204 1.81102)
			(end 1.4859 1.81102)
			(stroke
				(width 0.1524)
				(type default)
			)
			(layer "B.SilkS")
		)
		(fp_line
			(start -1.06934 1.81102)
			(end -1.2446 1.81102)
			(stroke
				(width 0.1524)
				(type default)
			)
			(layer "B.SilkS")
		)
		(fp_line
			(start 1.2446 1.8034)
			(end 1.2446 -1.8161)
			(stroke
				(width 0.1524)
				(type default)
			)
			(layer "B.SilkS")
		)
		(fp_line
			(start 1.3081 0.49022)
			(end 1.3081 1.7907)
			(stroke
				(width 0.508)
				(type default)
			)
			(layer "B.SilkS")
		)
		(fp_poly
			(pts
				(xy 0.82804 0.10922) (xy -0.82804 0.10922) (xy -0.82804 -0.10795) (xy 0.82804 -0.10795)
			)
			(stroke
				(width 0)
				(type default)
			)
			(fill yes)
			(layer "B.SilkS")
		)
		(fp_poly
			(pts
				(xy 1.5621 2.0447) (xy -1.5621 2.0447) (xy -1.5621 -2.0447) (xy 1.5621 -2.0447)
			)
			(stroke
				(width 0)
				(type default)
			)
			(fill no)
			(layer "B.CrtYd")
		)
		(fp_poly
			(pts
				(xy 1.5621 -2.0447) (xy -1.5621 -2.0447) (xy -1.5621 2.0447) (xy 1.5621 2.0447)
			)
			(stroke
				(width 0)
				(type default)
			)
			(fill no)
			(layer "B.Fab")
		)
		(pad "1" smd rect
			(at 0.65024 0.92202 180)
			(size 0.3556 1.2192)
			(layers "B.Cu" "B.Mask" "B.Paste")
			(net "GND")
		)
		(pad "2" smd rect
			(at 0 0.92202 180)
			(size 0.3556 1.2192)
			(layers "B.Cu" "B.Mask" "B.Paste")
			(net "BMC_VGA_VSYNC")
		)
		(pad "3" smd rect
			(at -0.65024 0.92202 180)
			(size 0.3556 1.2192)
			(layers "B.Cu" "B.Mask" "B.Paste")
			(net "GND")
		)
		(pad "4" smd rect
			(at -0.65024 -0.92075 180)
			(size 0.3556 1.2192)
			(layers "B.Cu" "B.Mask" "B.Paste")
			(net "VGA_REAR_VSYNC_S")
		)
		(pad "5" smd rect
			(at 0.65024 -0.92075 180)
			(size 0.3556 1.2192)
			(layers "B.Cu" "B.Mask" "B.Paste")
			(net "P5V_VGA_D")
		)
	)
	(footprint ""
		(layer "B.Cu")
		(at 4.70408 -13.52296 90)
		(property "Reference" "C1F21"
			(at 0 0 90)
			(layer "B.SilkS")
			(hide yes)
			(effects
				(font
					(size 1.27 1.27)
				)
				(justify mirror)
			)
		)
		(property "Value" "*"
			(at -1.1811 -2.8194 90)
			(unlocked yes)
			(layer "B.Fab")
			(hide yes)
			(effects
				(font
					(size 1.27 1.016)
					(thickness 0.1524)
				)
				(justify mirror)
			)
		)
		(property "Device Type" "SC1U10V2KX-4-GP_SMD-BCG6-SC1U1A"
			(at -1.1811 -4.3434 90)
			(unlocked yes)
			(layer "B.Fab")
			(hide yes)
			(effects
				(font
					(size 1.27 1.016)
					(thickness 0.1524)
				)
				(justify mirror)
			)
		)
		(duplicate_pad_numbers_are_jumpers no)
		(fp_rect
			(start 0.4318 0.9525)
			(end -0.4318 -0.9525)
			(stroke
				(width 0)
				(type default)
			)
			(fill no)
			(layer "B.CrtYd")
		)
		(fp_rect
			(start 0.4318 0.9525)
			(end -0.4318 -0.9525)
			(stroke
				(width 0)
				(type default)
			)
			(fill no)
			(layer "B.Fab")
		)
		(pad "1" smd custom
			(at 0 -0.4445 270)
			(size 0.1524 0.1524)
			(layers "B.Cu" "B.Mask" "B.Paste")
			(net "P5V_STBY")
			(options
				(clearance outline)
				(anchor circle)
			)
			(primitives
				(gr_poly
					(pts
						(arc
							(start 0.3048 0.2032)
							(mid 0.275042 0.275042)
							(end 0.2032 0.3048)
						)
						(arc
							(start -0.2032 0.3048)
							(mid -0.275042 0.275042)
							(end -0.3048 0.2032)
						)
						(arc
							(start -0.3048 -0.2032)
							(mid -0.275042 -0.275042)
							(end -0.2032 -0.3048)
						)
						(arc
							(start 0.2032 -0.3048)
							(mid 0.275042 -0.275042)
							(end 0.3048 -0.2032)
						)
					)
					(width 0)
					(fill yes)
				)
			)
		)
		(pad "2" smd custom
			(at 0 0.4445 270)
			(size 0.1524 0.1524)
			(layers "B.Cu" "B.Mask" "B.Paste")
			(net "GND")
			(options
				(clearance outline)
				(anchor circle)
			)
			(primitives
				(gr_poly
					(pts
						(arc
							(start 0.3048 0.2032)
							(mid 0.275042 0.275042)
							(end 0.2032 0.3048)
						)
						(arc
							(start -0.2032 0.3048)
							(mid -0.275042 0.275042)
							(end -0.3048 0.2032)
						)
						(arc
							(start -0.3048 -0.2032)
							(mid -0.275042 -0.275042)
							(end -0.2032 -0.3048)
						)
						(arc
							(start 0.2032 -0.3048)
							(mid 0.275042 -0.275042)
							(end 0.3048 -0.2032)
						)
					)
					(width 0)
					(fill yes)
				)
			)
		)
	)
	(footprint ""
		(layer "B.Cu")
		(at 411.0355 -129.413 90)
		(property "Reference" "C2M2"
			(at 0 0 90)
			(layer "B.SilkS")
			(hide yes)
			(effects
				(font
					(size 1.27 1.27)
				)
				(justify mirror)
			)
		)
		(property "Value" ""
			(at 0 0 90)
			(layer "B.Fab")
			(effects
				(font
					(size 1.27 1.27)
				)
				(justify mirror)
			)
		)
		(duplicate_pad_numbers_are_jumpers no)
		(fp_poly
			(pts
				(xy 0.4953 -0.2032) (xy -0.4953 -0.2032) (xy -0.4953 1.6002) (xy 0.4953 1.6002)
			)
			(stroke
				(width 0)
				(type default)
			)
			(fill no)
			(layer "B.CrtYd")
		)
		(fp_line
			(start 0.4953 -0.2032)
			(end -0.4953 -0.2032)
			(stroke
				(width 0.1)
				(type default)
			)
			(layer "B.Fab")
		)
		(fp_line
			(start -0.4953 -0.2032)
			(end -0.4953 1.6002)
			(stroke
				(width 0.1)
				(type default)
			)
			(layer "B.Fab")
		)
		(fp_line
			(start 0.4953 1.6002)
			(end 0.4953 -0.2032)
			(stroke
				(width 0.1)
				(type default)
			)
			(layer "B.Fab")
		)
		(fp_line
			(start -0.4953 1.6002)
			(end 0.4953 1.6002)
			(stroke
				(width 0.1)
				(type default)
			)
			(layer "B.Fab")
		)
		(pad "1" smd rect
			(at 0 0 270)
			(size 0.762 0.889)
			(layers "B.Cu" "B.Mask" "B.Paste")
			(net "P1V8_PCH_STBY")
		)
		(pad "2" smd rect
			(at 0 1.397 270)
			(size 0.762 0.889)
			(layers "B.Cu" "B.Mask" "B.Paste")
			(net "GND")
		)
		(zone
			(layer "B.Cu")
			(hatch none 0.5)
			(connect_pads
				(clearance 0)
			)
			(min_thickness 0.25)
			(keepout
				(tracks not_allowed)
				(vias allowed)
				(pads allowed)
				(copperpour not_allowed)
				(footprints allowed)
			)
			(placement
				(enabled no)
				(sheetname "")
			)
			(fill
				(thermal_gap 0.5)
				(thermal_bridge_width 0.5)
				(island_removal_mode 0)
			)
			(polygon
				(pts
					(xy 411.48 -129.794) (xy 411.48 -129.032) (xy 411.988 -129.032) (xy 411.988 -129.794)
				)
			)
		)
	)
	(footprint ""
		(layer "B.Cu")
		(at 404.913846 -26.489152)
		(property "Reference" "C9G20"
			(at 0 0 0)
			(layer "B.SilkS")
			(hide yes)
			(effects
				(font
					(size 1.27 1.27)
				)
				(justify mirror)
			)
		)
		(property "Value" ""
			(at 0 0 0)
			(layer "B.Fab")
			(effects
				(font
					(size 1.27 1.27)
				)
				(justify mirror)
			)
		)
		(duplicate_pad_numbers_are_jumpers no)
		(fp_poly
			(pts
				(xy -0.3048 -0.1016) (xy -0.3048 0.9906) (xy 0.3048 0.9906) (xy 0.3048 -0.1016)
			)
			(stroke
				(width 0)
				(type default)
			)
			(fill no)
			(layer "B.CrtYd")
		)
		(fp_line
			(start -0.3048 -0.1016)
			(end 0.3048 -0.1016)
			(stroke
				(width 0.1)
				(type default)
			)
			(layer "B.Fab")
		)
		(fp_line
			(start -0.3048 0.9906)
			(end -0.3048 -0.1016)
			(stroke
				(width 0.1)
				(type default)
			)
			(layer "B.Fab")
		)
		(fp_line
			(start 0.3048 -0.1016)
			(end 0.3048 0.9906)
			(stroke
				(width 0.1)
				(type default)
			)
			(layer "B.Fab")
		)
		(fp_line
			(start 0.3048 0.9906)
			(end -0.3048 0.9906)
			(stroke
				(width 0.1)
				(type default)
			)
			(layer "B.Fab")
		)
		(pad "1" smd rect
			(at 0 0 180)
			(size 0.508 0.508)
			(layers "B.Cu" "B.Mask" "B.Paste")
			(net "A_P3V3_STBY_SCALED")
		)
		(pad "2" smd rect
			(at 0 0.889 180)
			(size 0.508 0.508)
			(layers "B.Cu" "B.Mask" "B.Paste")
			(net "GND")
		)
		(zone
			(layer "B.Cu")
			(hatch none 0.5)
			(connect_pads
				(clearance 0)
			)
			(min_thickness 0.25)
			(keepout
				(tracks allowed)
				(vias not_allowed)
				(pads allowed)
				(copperpour not_allowed)
				(footprints allowed)
			)
			(placement
				(enabled no)
				(sheetname "")
			)
			(fill
				(thermal_gap 0.5)
				(thermal_bridge_width 0.5)
				(island_removal_mode 0)
			)
			(polygon
				(pts
					(xy 405.167846 -26.235152) (xy 404.659846 -26.235152) (xy 404.659846 -25.854152) (xy 405.167846 -25.854152)
				)
			)
		)
		(zone
			(layer "B.Cu")
			(hatch none 0.5)
			(connect_pads
				(clearance 0)
			)
			(min_thickness 0.25)
			(keepout
				(tracks not_allowed)
				(vias allowed)
				(pads allowed)
				(copperpour not_allowed)
				(footprints allowed)
			)
			(placement
				(enabled no)
				(sheetname "")
			)
			(fill
				(thermal_gap 0.5)
				(thermal_bridge_width 0.5)
				(island_removal_mode 0)
			)
			(polygon
				(pts
					(xy 405.167846 -25.854152) (xy 404.659846 -25.854152) (xy 404.659846 -26.235152) (xy 405.167846 -26.235152)
				)
			)
		)
	)
	(footprint ""
		(layer "B.Cu")
		(at 418.6936 -15.296134 180)
		(property "Reference" "Q2T2"
			(at 1.26873 2.4638 90)
			(unlocked yes)
			(layer "B.SilkS")
			(effects
				(font
					(size 0.7874 0.5842)
					(thickness 0.1524)
				)
				(justify left mirror)
			)
		)
		(property "Value" ""
			(at 0 0 0)
			(layer "B.Fab")
			(effects
				(font
					(size 1.27 1.27)
				)
				(justify mirror)
			)
		)
		(duplicate_pad_numbers_are_jumpers no)
		(fp_line
			(start -0.381 0.635)
			(end -0.381 1.27)
			(stroke
				(width 0.1524)
				(type default)
			)
			(layer "B.SilkS")
		)
		(fp_line
			(start -0.9525 2.4765)
			(end -1.778 2.4765)
			(stroke
				(width 0.1524)
				(type default)
			)
			(layer "B.SilkS")
		)
		(fp_line
			(start -0.9525 -0.5715)
			(end -1.778 -0.5715)
			(stroke
				(width 0.1524)
				(type default)
			)
			(layer "B.SilkS")
		)
		(fp_line
			(start -1.778 2.4765)
			(end -1.778 1.5875)
			(stroke
				(width 0.1524)
				(type default)
			)
			(layer "B.SilkS")
		)
		(fp_line
			(start -1.778 -0.5715)
			(end -1.778 0.3175)
			(stroke
				(width 0.1524)
				(type default)
			)
			(layer "B.SilkS")
		)
		(fp_circle
			(center 0.9525 -0.9271)
			(end 0.8255 -0.9271)
			(stroke
				(width 0.254)
				(type default)
			)
			(fill no)
			(layer "B.SilkS")
		)
		(fp_poly
			(pts
				(xy -1.778 2.4765) (xy -0.381 2.4765) (xy -0.381 -0.5715) (xy -1.778 -0.5715)
			)
			(stroke
				(width 0)
				(type default)
			)
			(fill no)
			(layer "B.CrtYd")
		)
		(fp_line
			(start -0.381 2.4765)
			(end -1.778 2.4765)
			(stroke
				(width 0.1)
				(type default)
			)
			(layer "B.Fab")
		)
		(fp_line
			(start -0.381 -0.5715)
			(end -0.381 2.4765)
			(stroke
				(width 0.1)
				(type default)
			)
			(layer "B.Fab")
		)
		(fp_line
			(start -1.778 2.4765)
			(end -1.778 -0.5715)
			(stroke
				(width 0.1)
				(type default)
			)
			(layer "B.Fab")
		)
		(fp_line
			(start -1.778 -0.5715)
			(end -0.381 -0.5715)
			(stroke
				(width 0.1)
				(type default)
			)
			(layer "B.Fab")
		)
		(fp_circle
			(center 0.9525 -0.9271)
			(end 0.8255 -0.9271)
			(stroke
				(width 0.254)
				(type default)
			)
			(fill no)
			(layer "B.Fab")
		)
		(pad "1" smd rect
			(at 0 0)
			(size 1.143 0.508)
			(layers "B.Cu" "B.Mask" "B.Paste")
			(net "H_CPU0_FAST_WAKE")
		)
		(pad "2" smd rect
			(at 0 1.905)
			(size 1.143 0.508)
			(layers "B.Cu" "B.Mask" "B.Paste")
			(net "GND")
		)
		(pad "3" smd rect
			(at -2.159 0.9525)
			(size 1.143 0.508)
			(layers "B.Cu" "B.Mask" "B.Paste")
			(net "H_CPU0_FAST_WAKE_LVT3_N")
		)
	)
	(footprint ""
		(layer "B.Cu")
		(at 32.2834 -87.0204 90)
		(property "Reference" "R9P32"
			(at 0 0 90)
			(layer "B.SilkS")
			(hide yes)
			(effects
				(font
					(size 1.27 1.27)
				)
				(justify mirror)
			)
		)
		(property "Value" ""
			(at 0 0 90)
			(layer "B.Fab")
			(effects
				(font
					(size 1.27 1.27)
				)
				(justify mirror)
			)
		)
		(duplicate_pad_numbers_are_jumpers no)
		(fp_poly
			(pts
				(xy 0.2794 -0.1016) (xy -0.2794 -0.1016) (xy -0.2794 0.9906) (xy 0.2794 0.9906)
			)
			(stroke
				(width 0)
				(type default)
			)
			(fill no)
			(layer "B.CrtYd")
		)
		(fp_line
			(start 0.2794 -0.1016)
			(end 0.2794 0.9906)
			(stroke
				(width 0.1)
				(type default)
			)
			(layer "B.Fab")
		)
		(fp_line
			(start -0.2794 -0.1016)
			(end 0.2794 -0.1016)
			(stroke
				(width 0.1)
				(type default)
			)
			(layer "B.Fab")
		)
		(fp_line
			(start 0.2794 0.9906)
			(end -0.2794 0.9906)
			(stroke
				(width 0.1)
				(type default)
			)
			(layer "B.Fab")
		)
		(fp_line
			(start -0.2794 0.9906)
			(end -0.2794 -0.1016)
			(stroke
				(width 0.1)
				(type default)
			)
			(layer "B.Fab")
		)
		(pad "1" smd rect
			(at 0 0 270)
			(size 0.508 0.508)
			(layers "B.Cu" "B.Mask" "B.Paste")
			(net "VR_PVCCIN_CPU1_PH5_VCIN")
		)
		(pad "2" smd rect
			(at 0 0.889 270)
			(size 0.508 0.508)
			(layers "B.Cu" "B.Mask" "B.Paste")
			(net "P5V_STBY")
		)
		(zone
			(layer "B.Cu")
			(hatch none 0.5)
			(connect_pads
				(clearance 0)
			)
			(min_thickness 0.25)
			(keepout
				(tracks allowed)
				(vias not_allowed)
				(pads allowed)
				(copperpour not_allowed)
				(footprints allowed)
			)
			(placement
				(enabled no)
				(sheetname "")
			)
			(fill
				(thermal_gap 0.5)
				(thermal_bridge_width 0.5)
				(island_removal_mode 0)
			)
			(polygon
				(pts
					(xy 32.5374 -87.2744) (xy 32.5374 -86.7664) (xy 32.9184 -86.7664) (xy 32.9184 -87.2744)
				)
			)
		)
		(zone
			(layer "B.Cu")
			(hatch none 0.5)
			(connect_pads
				(clearance 0)
			)
			(min_thickness 0.25)
			(keepout
				(tracks not_allowed)
				(vias allowed)
				(pads allowed)
				(copperpour not_allowed)
				(footprints allowed)
			)
			(placement
				(enabled no)
				(sheetname "")
			)
			(fill
				(thermal_gap 0.5)
				(thermal_bridge_width 0.5)
				(island_removal_mode 0)
			)
			(polygon
				(pts
					(xy 32.9184 -87.2744) (xy 32.9184 -86.7664) (xy 32.5374 -86.7664) (xy 32.5374 -87.2744)
				)
			)
		)
	)
	(footprint ""
		(layer "B.Cu")
		(at 391.3251 -64.381888 180)
		(property "Reference" "U2T2"
			(at 0.67564 -2.27203 180)
			(unlocked yes)
			(layer "B.SilkS")
			(effects
				(font
					(size 0.7874 0.5842)
					(thickness 0.1524)
				)
				(justify left mirror)
			)
		)
		(property "Value" ""
			(at 0 0 0)
			(layer "B.Fab")
			(effects
				(font
					(size 1.27 1.27)
				)
				(justify mirror)
			)
		)
		(duplicate_pad_numbers_are_jumpers no)
		(fp_circle
			(center 0.4699 -0.8382)
			(end 0.3429 -0.8382)
			(stroke
				(width 0.254)
				(type default)
			)
			(fill no)
			(layer "B.SilkS")
		)
		(fp_poly
			(pts
				(xy -0.21463 -0.450088) (xy -1.56337 -0.450088) (xy -1.56337 1.75006) (xy -0.21463 1.75006)
			)
			(stroke
				(width 0)
				(type default)
			)
			(fill no)
			(layer "B.CrtYd")
		)
		(fp_line
			(start -0.21463 1.75006)
			(end -0.21463 -0.450088)
			(stroke
				(width 0.1)
				(type default)
			)
			(layer "B.Fab")
		)
		(fp_line
			(start -0.21463 -0.450088)
			(end -1.56337 -0.450088)
			(stroke
				(width 0.1)
				(type default)
			)
			(layer "B.Fab")
		)
		(fp_line
			(start -1.56337 1.75006)
			(end -0.21463 1.75006)
			(stroke
				(width 0.1)
				(type default)
			)
			(layer "B.Fab")
		)
		(fp_line
			(start -1.56337 -0.450088)
			(end -1.56337 1.75006)
			(stroke
				(width 0.1)
				(type default)
			)
			(layer "B.Fab")
		)
		(fp_circle
			(center 0.4699 -0.8382)
			(end 0.3429 -0.8382)
			(stroke
				(width 0.254)
				(type default)
			)
			(fill no)
			(layer "B.Fab")
		)
		(pad "1" smd rect
			(at 0 0)
			(size 1.016 0.381)
			(layers "B.Cu" "B.Mask" "B.Paste")
			(net "FM_BACKUP_BIOS_SEL_N")
		)
		(pad "2" smd rect
			(at 0 0.649986)
			(size 1.016 0.381)
			(layers "B.Cu" "B.Mask" "B.Paste")
			(net "SPI_SWITCH_CS0_N")
		)
		(pad "3" smd rect
			(at 0 1.299972)
			(size 1.016 0.381)
			(layers "B.Cu" "B.Mask" "B.Paste")
			(net "GND")
		)
		(pad "4" smd rect
			(at -1.778 1.299972)
			(size 1.016 0.381)
			(layers "B.Cu" "B.Mask" "B.Paste")
			(net "SPI_CS0_SECONDARY_N")
		)
		(pad "5" smd rect
			(at -1.778 0)
			(size 1.016 0.381)
			(layers "B.Cu" "B.Mask" "B.Paste")
			(net "P3V3_STBY")
		)
	)
	(footprint ""
		(layer "B.Cu")
		(at 369.944904 -69.894196 180)
		(property "Reference" "C2R4"
			(at 0 0 0)
			(layer "B.SilkS")
			(hide yes)
			(effects
				(font
					(size 1.27 1.27)
				)
				(justify mirror)
			)
		)
		(property "Value" ""
			(at 0 0 0)
			(layer "B.Fab")
			(effects
				(font
					(size 1.27 1.27)
				)
				(justify mirror)
			)
		)
		(duplicate_pad_numbers_are_jumpers no)
		(fp_rect
			(start 0.2794 0.9144)
			(end -0.2794 -0.1143)
			(stroke
				(width 0)
				(type default)
			)
			(fill no)
			(layer "B.CrtYd")
		)
		(fp_line
			(start 0.2794 0.9144)
			(end 0.2794 -0.1143)
			(stroke
				(width 0.1)
				(type default)
			)
			(layer "B.Fab")
		)
		(fp_line
			(start 0.2794 -0.1143)
			(end -0.2794 -0.1143)
			(stroke
				(width 0.1)
				(type default)
			)
			(layer "B.Fab")
		)
		(fp_line
			(start -0.2794 0.9144)
			(end 0.2794 0.9144)
			(stroke
				(width 0.1)
				(type default)
			)
			(layer "B.Fab")
		)
		(fp_line
			(start -0.2794 -0.1143)
			(end -0.2794 0.9144)
			(stroke
				(width 0.1)
				(type default)
			)
			(layer "B.Fab")
		)
		(pad "1" smd custom
			(at 0 0 90)
			(size 0.10414 0.10414)
			(layers "B.Cu" "B.Mask" "B.Paste")
			(net "P3V3_STBY")
			(options
				(clearance outline)
				(anchor circle)
			)
			(primitives
				(gr_poly
					(pts
						(xy -0.20828 -0.08636) (xy -0.20828 0.08636) (xy -0.08636 0.20828) (xy 0.086614 0.20828) (xy 0.20828 0.086614)
						(xy 0.20828 -0.08636) (xy 0.08636 -0.20828) (xy -0.08636 -0.20828)
					)
					(width 0)
					(fill yes)
				)
			)
		)
		(pad "2" smd custom
			(at 0 0.8001 90)
			(size 0.10414 0.10414)
			(layers "B.Cu" "B.Mask" "B.Paste")
			(net "GND")
			(options
				(clearance outline)
				(anchor circle)
			)
			(primitives
				(gr_poly
					(pts
						(xy -0.20828 -0.08636) (xy -0.20828 0.08636) (xy -0.08636 0.20828) (xy 0.086614 0.20828) (xy 0.20828 0.086614)
						(xy 0.20828 -0.08636) (xy 0.08636 -0.20828) (xy -0.08636 -0.20828)
					)
					(width 0)
					(fill yes)
				)
			)
		)
		(zone
			(layer "B.Cu")
			(hatch none 0.5)
			(connect_pads
				(clearance 0)
			)
			(min_thickness 0.25)
			(keepout
				(tracks not_allowed)
				(vias allowed)
				(pads allowed)
				(copperpour not_allowed)
				(footprints allowed)
			)
			(placement
				(enabled no)
				(sheetname "")
			)
			(fill
				(thermal_gap 0.5)
				(thermal_bridge_width 0.5)
				(island_removal_mode 0)
			)
			(polygon
				(pts
					(xy 369.857274 -70.103746) (xy 369.857274 -70.484746) (xy 370.032534 -70.484746) (xy 370.032788 -70.103746)
				)
			)
		)
		(zone
			(layer "B.Cu")
			(hatch none 0.5)
			(connect_pads
				(clearance 0)
			)
			(min_thickness 0.25)
			(keepout
				(tracks allowed)
				(vias not_allowed)
				(pads allowed)
				(copperpour not_allowed)
				(footprints allowed)
			)
			(placement
				(enabled no)
				(sheetname "")
			)
			(fill
				(thermal_gap 0.5)
				(thermal_bridge_width 0.5)
				(island_removal_mode 0)
			)
			(polygon
				(pts
					(xy 369.857274 -70.103746) (xy 369.857274 -70.484746) (xy 370.032534 -70.484746) (xy 370.032788 -70.103746)
				)
			)
		)
	)
	(footprint ""
		(layer "B.Cu")
		(at 482.981 -114.554 90)
		(property "Reference" "C1M20"
			(at 0 0 90)
			(layer "B.SilkS")
			(hide yes)
			(effects
				(font
					(size 1.27 1.27)
				)
				(justify mirror)
			)
		)
		(property "Value" ""
			(at 0 0 90)
			(layer "B.Fab")
			(effects
				(font
					(size 1.27 1.27)
				)
				(justify mirror)
			)
		)
		(duplicate_pad_numbers_are_jumpers no)
		(fp_rect
			(start -0.3048 -0.1016)
			(end 0.3048 0.9906)
			(stroke
				(width 0)
				(type default)
			)
			(fill no)
			(layer "B.CrtYd")
		)
		(fp_line
			(start 0.3048 -0.1016)
			(end 0.3048 0.9906)
			(stroke
				(width 0.1)
				(type default)
			)
			(layer "B.Fab")
		)
		(fp_line
			(start -0.3048 -0.1016)
			(end 0.3048 -0.1016)
			(stroke
				(width 0.1)
				(type default)
			)
			(layer "B.Fab")
		)
		(fp_line
			(start 0.3048 0.9906)
			(end -0.3048 0.9906)
			(stroke
				(width 0.1)
				(type default)
			)
			(layer "B.Fab")
		)
		(fp_line
			(start -0.3048 0.9906)
			(end -0.3048 -0.1016)
			(stroke
				(width 0.1)
				(type default)
			)
			(layer "B.Fab")
		)
		(pad "1" smd rect
			(at 0 0 270)
			(size 0.508 0.508)
			(layers "B.Cu" "B.Mask" "B.Paste")
			(net "P3V3_STBY")
		)
		(pad "2" smd rect
			(at 0 0.889 270)
			(size 0.508 0.508)
			(layers "B.Cu" "B.Mask" "B.Paste")
			(net "GND")
		)
		(zone
			(layer "B.Cu")
			(hatch none 0.5)
			(connect_pads
				(clearance 0)
			)
			(min_thickness 0.25)
			(keepout
				(tracks allowed)
				(vias not_allowed)
				(pads allowed)
				(copperpour not_allowed)
				(footprints allowed)
			)
			(placement
				(enabled no)
				(sheetname "")
			)
			(fill
				(thermal_gap 0.5)
				(thermal_bridge_width 0.5)
				(island_removal_mode 0)
			)
			(polygon
				(pts
					(xy 483.235 -114.3) (xy 483.616 -114.3) (xy 483.616 -114.808) (xy 483.235 -114.808)
				)
			)
		)
		(zone
			(layer "B.Cu")
			(hatch none 0.5)
			(connect_pads
				(clearance 0)
			)
			(min_thickness 0.25)
			(keepout
				(tracks not_allowed)
				(vias allowed)
				(pads allowed)
				(copperpour not_allowed)
				(footprints allowed)
			)
			(placement
				(enabled no)
				(sheetname "")
			)
			(fill
				(thermal_gap 0.5)
				(thermal_bridge_width 0.5)
				(island_removal_mode 0)
			)
			(polygon
				(pts
					(xy 483.235 -114.3) (xy 483.616 -114.3) (xy 483.616 -114.808) (xy 483.235 -114.808)
				)
			)
		)
	)
	(footprint ""
		(layer "B.Cu")
		(at 111.605568 -27.305 90)
		(property "Reference" "C7T1"
			(at 0 0 90)
			(layer "B.SilkS")
			(hide yes)
			(effects
				(font
					(size 1.27 1.27)
				)
				(justify mirror)
			)
		)
		(property "Value" ""
			(at 0 0 90)
			(layer "B.Fab")
			(effects
				(font
					(size 1.27 1.27)
				)
				(justify mirror)
			)
		)
		(duplicate_pad_numbers_are_jumpers no)
		(fp_poly
			(pts
				(xy 0.7239 -0.2159) (xy -0.7239 -0.2159) (xy -0.7239 1.9939) (xy 0.7239 1.9939)
			)
			(stroke
				(width 0)
				(type default)
			)
			(fill no)
			(layer "B.CrtYd")
		)
		(fp_line
			(start 0.7239 -0.2159)
			(end 0.7239 1.9939)
			(stroke
				(width 0.1)
				(type default)
			)
			(layer "B.Fab")
		)
		(fp_line
			(start -0.7239 -0.2159)
			(end 0.7239 -0.2159)
			(stroke
				(width 0.1)
				(type default)
			)
			(layer "B.Fab")
		)
		(fp_line
			(start 0.7239 1.9939)
			(end -0.7239 1.9939)
			(stroke
				(width 0.1)
				(type default)
			)
			(layer "B.Fab")
		)
		(fp_line
			(start -0.7239 1.9939)
			(end -0.7239 -0.2159)
			(stroke
				(width 0.1)
				(type default)
			)
			(layer "B.Fab")
		)
		(pad "1" smd rect
			(at 0 0 270)
			(size 1.27 1.016)
			(layers "B.Cu" "B.Mask" "B.Paste")
			(net "PVDDQ_GHJ")
		)
		(pad "2" smd rect
			(at 0 1.778 270)
			(size 1.27 1.016)
			(layers "B.Cu" "B.Mask" "B.Paste")
			(net "GND")
		)
		(zone
			(layer "B.Cu")
			(hatch none 0.5)
			(connect_pads
				(clearance 0)
			)
			(min_thickness 0.25)
			(keepout
				(tracks not_allowed)
				(vias allowed)
				(pads allowed)
				(copperpour not_allowed)
				(footprints allowed)
			)
			(placement
				(enabled no)
				(sheetname "")
			)
			(fill
				(thermal_gap 0.5)
				(thermal_bridge_width 0.5)
				(island_removal_mode 0)
			)
			(polygon
				(pts
					(xy 112.113568 -27.94) (xy 112.113568 -26.67) (xy 112.875568 -26.67) (xy 112.875568 -27.94)
				)
			)
		)
	)
	(footprint ""
		(layer "B.Cu")
		(at 450.3674 -4.7498)
		(property "Reference" "R6W1"
			(at 0.8382 -0.67818 0)
			(unlocked yes)
			(layer "B.SilkS")
			(effects
				(font
					(size 0.4064 0.254)
					(thickness 0.1524)
				)
				(justify left mirror)
			)
		)
		(property "Value" ""
			(at 0 0 0)
			(layer "B.Fab")
			(effects
				(font
					(size 1.27 1.27)
				)
				(justify mirror)
			)
		)
		(duplicate_pad_numbers_are_jumpers no)
		(fp_poly
			(pts
				(xy 0.2794 -0.1016) (xy -0.2794 -0.1016) (xy -0.2794 0.9906) (xy 0.2794 0.9906)
			)
			(stroke
				(width 0)
				(type default)
			)
			(fill no)
			(layer "B.CrtYd")
		)
		(fp_line
			(start -0.2794 -0.1016)
			(end 0.2794 -0.1016)
			(stroke
				(width 0.1)
				(type default)
			)
			(layer "B.Fab")
		)
		(fp_line
			(start -0.2794 0.9906)
			(end -0.2794 -0.1016)
			(stroke
				(width 0.1)
				(type default)
			)
			(layer "B.Fab")
		)
		(fp_line
			(start 0.2794 -0.1016)
			(end 0.2794 0.9906)
			(stroke
				(width 0.1)
				(type default)
			)
			(layer "B.Fab")
		)
		(fp_line
			(start 0.2794 0.9906)
			(end -0.2794 0.9906)
			(stroke
				(width 0.1)
				(type default)
			)
			(layer "B.Fab")
		)
		(pad "1" smd rect
			(at 0 0 180)
			(size 0.508 0.508)
			(layers "B.Cu" "B.Mask" "B.Paste")
			(net "P3V3_STBY")
		)
		(pad "2" smd rect
			(at 0 0.889 180)
			(size 0.508 0.508)
			(layers "B.Cu" "B.Mask" "B.Paste")
			(net "PU_UV_HIGH_SET")
		)
		(zone
			(layer "B.Cu")
			(hatch none 0.5)
			(connect_pads
				(clearance 0)
			)
			(min_thickness 0.25)
			(keepout
				(tracks allowed)
				(vias not_allowed)
				(pads allowed)
				(copperpour not_allowed)
				(footprints allowed)
			)
			(placement
				(enabled no)
				(sheetname "")
			)
			(fill
				(thermal_gap 0.5)
				(thermal_bridge_width 0.5)
				(island_removal_mode 0)
			)
			(polygon
				(pts
					(xy 450.6214 -4.4958) (xy 450.1134 -4.4958) (xy 450.1134 -4.1148) (xy 450.6214 -4.1148)
				)
			)
		)
		(zone
			(layer "B.Cu")
			(hatch none 0.5)
			(connect_pads
				(clearance 0)
			)
			(min_thickness 0.25)
			(keepout
				(tracks not_allowed)
				(vias allowed)
				(pads allowed)
				(copperpour not_allowed)
				(footprints allowed)
			)
			(placement
				(enabled no)
				(sheetname "")
			)
			(fill
				(thermal_gap 0.5)
				(thermal_bridge_width 0.5)
				(island_removal_mode 0)
			)
			(polygon
				(pts
					(xy 450.6214 -4.1148) (xy 450.1134 -4.1148) (xy 450.1134 -4.4958) (xy 450.6214 -4.4958)
				)
			)
		)
	)
	(footprint ""
		(layer "B.Cu")
		(at 484.124 -150.0378 90)
		(property "Reference" "CR1L1"
			(at 0 0 90)
			(layer "B.SilkS")
			(hide yes)
			(effects
				(font
					(size 1.27 1.27)
				)
				(justify mirror)
			)
		)
		(property "Value" ""
			(at 0 0 90)
			(layer "B.Fab")
			(effects
				(font
					(size 1.27 1.27)
				)
				(justify mirror)
			)
		)
		(duplicate_pad_numbers_are_jumpers no)
		(fp_line
			(start 0.9144 0.1016)
			(end 0.9144 2.9464)
			(stroke
				(width 0.1524)
				(type default)
			)
			(layer "B.SilkS")
		)
		(fp_line
			(start 0.8382 0.1016)
			(end 0.9144 0.1016)
			(stroke
				(width 0.1524)
				(type default)
			)
			(layer "B.SilkS")
		)
		(fp_line
			(start -0.8382 0.1016)
			(end -0.9144 0.1016)
			(stroke
				(width 0.1524)
				(type default)
			)
			(layer "B.SilkS")
		)
		(fp_line
			(start -0.9144 0.1016)
			(end -0.9144 2.9464)
			(stroke
				(width 0.1524)
				(type default)
			)
			(layer "B.SilkS")
		)
		(fp_line
			(start 0.9144 2.9464)
			(end 0.8382 2.9464)
			(stroke
				(width 0.1524)
				(type default)
			)
			(layer "B.SilkS")
		)
		(fp_line
			(start -0.9144 2.9464)
			(end -0.8382 2.9464)
			(stroke
				(width 0.1524)
				(type default)
			)
			(layer "B.SilkS")
		)
		(fp_circle
			(center -1.128776 -0.907288)
			(end -1.128776 -0.780288)
			(stroke
				(width 0.254)
				(type default)
			)
			(fill no)
			(layer "B.SilkS")
		)
		(fp_poly
			(pts
				(xy 0 0.1016) (xy -0.5334 0.1016) (xy -0.7366 0.1016) (xy -0.9144 0.1016) (xy -0.9144 2.9464) (xy -0.8382 2.9464)
				(xy -0.762 2.9464) (xy 0.9144 2.9464) (xy 0.9144 2.7686) (xy 0.9144 2.159) (xy 0.9144 0.1016) (xy 0.7366 0.1016)
				(xy 0.5842 0.1016)
			)
			(stroke
				(width 0)
				(type default)
			)
			(fill no)
			(layer "B.CrtYd")
		)
		(fp_line
			(start 0.9144 0.1016)
			(end 0.9144 2.9464)
			(stroke
				(width 0.1)
				(type default)
			)
			(layer "B.Fab")
		)
		(fp_line
			(start -0.9144 0.1016)
			(end 0.9144 0.1016)
			(stroke
				(width 0.1)
				(type default)
			)
			(layer "B.Fab")
		)
		(fp_line
			(start 0.9144 2.9464)
			(end -0.9144 2.9464)
			(stroke
				(width 0.1)
				(type default)
			)
			(layer "B.Fab")
		)
		(fp_line
			(start -0.9144 2.9464)
			(end -0.9144 0.1016)
			(stroke
				(width 0.1)
				(type default)
			)
			(layer "B.Fab")
		)
		(fp_circle
			(center -1.128776 -0.907288)
			(end -1.128776 -0.780288)
			(stroke
				(width 0.254)
				(type default)
			)
			(fill no)
			(layer "B.Fab")
		)
		(pad "1" smd rect
			(at 0 0)
			(size 1.524 0.762)
			(layers "B.Cu" "B.Mask" "B.Paste")
			(net "FM_DB_UART_SEL1_N")
		)
		(pad "2" smd rect
			(at 0 3.048 180)
			(size 1.524 0.762)
			(layers "B.Cu" "B.Mask" "B.Paste")
			(net "FM_DB_UART_SEL0_N")
		)
	)
	(footprint ""
		(layer "B.Cu")
		(at 194.700398 -15.222982 90)
		(property "Reference" "J6U1"
			(at 2.530348 39.10711 0)
			(unlocked yes)
			(layer "B.SilkS")
			(effects
				(font
					(size 0.7874 0.5842)
					(thickness 0.1524)
				)
				(justify left mirror)
			)
		)
		(property "Value" ""
			(at 0 0 90)
			(layer "B.Fab")
			(effects
				(font
					(size 1.27 1.27)
				)
				(justify mirror)
			)
		)
		(duplicate_pad_numbers_are_jumpers no)
		(fp_line
			(start 0.94996 -7.675118)
			(end -5.5499 -7.675118)
			(stroke
				(width 0.1524)
				(type default)
			)
			(layer "B.SilkS")
		)
		(fp_line
			(start -5.5499 -7.675118)
			(end -5.5499 -1.480058)
			(stroke
				(width 0.1524)
				(type default)
			)
			(layer "B.SilkS")
		)
		(fp_line
			(start 0.94996 -1.480058)
			(end 0.94996 -7.675118)
			(stroke
				(width 0.1524)
				(type default)
			)
			(layer "B.SilkS")
		)
		(fp_line
			(start -5.5499 128.130046)
			(end -5.5499 134.325106)
			(stroke
				(width 0.1524)
				(type default)
			)
			(layer "B.SilkS")
		)
		(fp_line
			(start 0.94996 134.325106)
			(end 0.94996 128.130046)
			(stroke
				(width 0.1524)
				(type default)
			)
			(layer "B.SilkS")
		)
		(fp_line
			(start -5.5499 134.325106)
			(end 0.94996 134.325106)
			(stroke
				(width 0.1524)
				(type default)
			)
			(layer "B.SilkS")
		)
		(fp_poly
			(pts
				(xy 2.828544 -0.60071) (xy 2.828544 0.41529) (xy 1.558544 -0.09271)
			)
			(stroke
				(width 0)
				(type default)
			)
			(fill yes)
			(layer "B.SilkS")
		)
		(fp_poly
			(pts
				(xy 0.94996 -7.675118) (xy 0.94996 134.325106) (xy -5.5499 134.325106) (xy -5.5499 -7.675118)
			)
			(stroke
				(width 0)
				(type default)
			)
			(fill no)
			(layer "B.CrtYd")
		)
		(fp_line
			(start 0.94996 -7.675118)
			(end -5.5499 -7.675118)
			(stroke
				(width 0.1)
				(type default)
			)
			(layer "B.Fab")
		)
		(fp_line
			(start -5.5499 -7.675118)
			(end -5.5499 134.325106)
			(stroke
				(width 0.1)
				(type default)
			)
			(layer "B.Fab")
		)
		(fp_line
			(start 0.94996 134.325106)
			(end 0.94996 -7.675118)
			(stroke
				(width 0.1)
				(type default)
			)
			(layer "B.Fab")
		)
		(fp_line
			(start -5.5499 134.325106)
			(end 0.94996 134.325106)
			(stroke
				(width 0.1)
				(type default)
			)
			(layer "B.Fab")
		)
		(fp_poly
			(pts
				(xy 2.984246 -0.461264) (xy 2.984246 0.554736) (xy 1.714246 0.046736)
			)
			(stroke
				(width 0)
				(type default)
			)
			(fill yes)
			(layer "B.Fab")
		)
		(fp_text user "145"
			(at -6.105652 1.26111 0)
			(unlocked yes)
			(layer "B.SilkS")
			(effects
				(font
					(size 0.7874 0.5842)
					(thickness 0.1524)
				)
				(justify left mirror)
			)
		)
		(fp_text user "77"
			(at 0.879348 66.41211 0)
			(unlocked yes)
			(layer "B.SilkS")
			(effects
				(font
					(size 0.7874 0.5842)
					(thickness 0.1524)
				)
				(justify left mirror)
			)
		)
		(fp_text user "221"
			(at -5.724652 67.17411 0)
			(unlocked yes)
			(layer "B.SilkS")
			(effects
				(font
					(size 0.7874 0.5842)
					(thickness 0.1524)
				)
				(justify left mirror)
			)
		)
		(fp_text user "78"
			(at 1.514348 71.23811 0)
			(unlocked yes)
			(layer "B.SilkS")
			(effects
				(font
					(size 0.7874 0.5842)
					(thickness 0.1524)
				)
				(justify left mirror)
			)
		)
		(fp_text user "222"
			(at -6.105652 72.00011 0)
			(unlocked yes)
			(layer "B.SilkS")
			(effects
				(font
					(size 0.7874 0.5842)
					(thickness 0.1524)
				)
				(justify left mirror)
			)
		)
		(fp_text user "144"
			(at 3.419348 129.65811 0)
			(unlocked yes)
			(layer "B.SilkS")
			(effects
				(font
					(size 0.7874 0.5842)
					(thickness 0.1524)
				)
				(justify left mirror)
			)
		)
		(fp_text user "288"
			(at -8.010652 129.65811 0)
			(unlocked yes)
			(layer "B.SilkS")
			(effects
				(font
					(size 0.7874 0.5842)
					(thickness 0.1524)
				)
				(justify left mirror)
			)
		)
		(fp_text user "145"
			(at -3.157982 -1.37922 90)
			(unlocked yes)
			(layer "B.Fab")
			(effects
				(font
					(size 0.7874 0.5842)
					(thickness 0.1524)
				)
				(justify left mirror)
			)
		)
		(fp_text user "77"
			(at 0.652018 65.93078 90)
			(unlocked yes)
			(layer "B.Fab")
			(effects
				(font
					(size 0.7874 0.5842)
					(thickness 0.1524)
				)
				(justify left mirror)
			)
		)
		(fp_text user "221"
			(at -3.157982 65.93078 90)
			(unlocked yes)
			(layer "B.Fab")
			(effects
				(font
					(size 0.7874 0.5842)
					(thickness 0.1524)
				)
				(justify left mirror)
			)
		)
		(fp_text user "222"
			(at -3.157982 69.10578 90)
			(unlocked yes)
			(layer "B.Fab")
			(effects
				(font
					(size 0.7874 0.5842)
					(thickness 0.1524)
				)
				(justify left mirror)
			)
		)
		(fp_text user "78"
			(at 0.652018 69.74078 90)
			(unlocked yes)
			(layer "B.Fab")
			(effects
				(font
					(size 0.7874 0.5842)
					(thickness 0.1524)
				)
				(justify left mirror)
			)
		)
		(fp_text user "144"
			(at 0.652018 128.16078 90)
			(unlocked yes)
			(layer "B.Fab")
			(effects
				(font
					(size 0.7874 0.5842)
					(thickness 0.1524)
				)
				(justify left mirror)
			)
		)
		(fp_text user "288"
			(at -3.157982 128.16078 90)
			(unlocked yes)
			(layer "B.Fab")
			(effects
				(font
					(size 0.7874 0.5842)
					(thickness 0.1524)
				)
				(justify left mirror)
			)
		)
		(pad "" thru_hole circle
			(at -2.29997 -5.649976 270)
			(size 2.8194 2.8194)
			(drill 2.4384)
			(layers "*.Cu" "*.Mask")
			(remove_unused_layers no)
			(clearance 0.127)
			(thermal_gap 0.127)
		)
		(pad "" thru_hole oval
			(at -2.29997 68.90004 270)
			(size 2.8194 1.5748)
			(drill oval 2.4384 1.1938)
			(layers "*.Cu" "*.Mask")
			(remove_unused_layers no)
			(clearance 0.127)
			(thermal_gap 0.127)
		)
		(pad "" thru_hole circle
			(at -2.29997 132.299964 270)
			(size 2.8194 2.8194)
			(drill 2.4384)
			(layers "*.Cu" "*.Mask")
			(remove_unused_layers no)
			(clearance 0.127)
			(thermal_gap 0.127)
		)
		(pad "1" smd rect
			(at 0 0 270)
			(size 1.8034 0.508)
			(layers "B.Cu" "B.Mask" "B.Paste")
			(net "P12V_NVDIMM_ABC")
		)
		(pad "2" smd rect
			(at 0 0.849884 270)
			(size 1.8034 0.508)
			(layers "B.Cu" "B.Mask" "B.Paste")
			(net "GND")
		)
		(pad "3" smd rect
			(at 0 1.700022 270)
			(size 1.8034 0.508)
			(layers "B.Cu" "B.Mask" "B.Paste")
			(net "M_B_DQ<4>")
		)
		(pad "4" smd rect
			(at 0 2.549906 270)
			(size 1.8034 0.508)
			(layers "B.Cu" "B.Mask" "B.Paste")
			(net "GND")
		)
		(pad "5" smd rect
			(at 0 3.400044 270)
			(size 1.8034 0.508)
			(layers "B.Cu" "B.Mask" "B.Paste")
			(net "M_B_DQ<0>")
		)
		(pad "6" smd rect
			(at 0 4.249928 270)
			(size 1.8034 0.508)
			(layers "B.Cu" "B.Mask" "B.Paste")
			(net "GND")
		)
		(pad "7" smd rect
			(at 0 5.100066 270)
			(size 1.8034 0.508)
			(layers "B.Cu" "B.Mask" "B.Paste")
			(net "M_B_DQS_DP<9>")
		)
		(pad "8" smd rect
			(at 0 5.94995 270)
			(size 1.8034 0.508)
			(layers "B.Cu" "B.Mask" "B.Paste")
			(net "M_B_DQS_DN<9>")
		)
		(pad "9" smd rect
			(at 0 6.800088 270)
			(size 1.8034 0.508)
			(layers "B.Cu" "B.Mask" "B.Paste")
			(net "GND")
		)
		(pad "10" smd rect
			(at 0 7.649972 270)
			(size 1.8034 0.508)
			(layers "B.Cu" "B.Mask" "B.Paste")
			(net "M_B_DQ<6>")
		)
		(pad "11" smd rect
			(at 0 8.50011 270)
			(size 1.8034 0.508)
			(layers "B.Cu" "B.Mask" "B.Paste")
			(net "GND")
		)
		(pad "12" smd rect
			(at 0 9.349994 270)
			(size 1.8034 0.508)
			(layers "B.Cu" "B.Mask" "B.Paste")
			(net "M_B_DQ<2>")
		)
		(pad "13" smd rect
			(at 0 10.199878 270)
			(size 1.8034 0.508)
			(layers "B.Cu" "B.Mask" "B.Paste")
			(net "GND")
		)
		(pad "14" smd rect
			(at 0 11.050016 270)
			(size 1.8034 0.508)
			(layers "B.Cu" "B.Mask" "B.Paste")
			(net "M_B_DQ<12>")
		)
		(pad "15" smd rect
			(at 0 11.8999 270)
			(size 1.8034 0.508)
			(layers "B.Cu" "B.Mask" "B.Paste")
			(net "GND")
		)
		(pad "16" smd rect
			(at 0 12.750038 270)
			(size 1.8034 0.508)
			(layers "B.Cu" "B.Mask" "B.Paste")
			(net "M_B_DQ<8>")
		)
		(pad "17" smd rect
			(at 0 13.599922 270)
			(size 1.8034 0.508)
			(layers "B.Cu" "B.Mask" "B.Paste")
			(net "GND")
		)
		(pad "18" smd rect
			(at 0 14.45006 270)
			(size 1.8034 0.508)
			(layers "B.Cu" "B.Mask" "B.Paste")
			(net "M_B_DQS_DP<10>")
		)
		(pad "19" smd rect
			(at 0 15.299944 270)
			(size 1.8034 0.508)
			(layers "B.Cu" "B.Mask" "B.Paste")
			(net "M_B_DQS_DN<10>")
		)
		(pad "20" smd rect
			(at 0 16.150082 270)
			(size 1.8034 0.508)
			(layers "B.Cu" "B.Mask" "B.Paste")
			(net "GND")
		)
		(pad "21" smd rect
			(at 0 16.999966 270)
			(size 1.8034 0.508)
			(layers "B.Cu" "B.Mask" "B.Paste")
			(net "M_B_DQ<14>")
		)
		(pad "22" smd rect
			(at 0 17.850104 270)
			(size 1.8034 0.508)
			(layers "B.Cu" "B.Mask" "B.Paste")
			(net "GND")
		)
		(pad "23" smd rect
			(at 0 18.699988 270)
			(size 1.8034 0.508)
			(layers "B.Cu" "B.Mask" "B.Paste")
			(net "M_B_DQ<10>")
		)
		(pad "24" smd rect
			(at 0 19.550126 270)
			(size 1.8034 0.508)
			(layers "B.Cu" "B.Mask" "B.Paste")
			(net "GND")
		)
		(pad "25" smd rect
			(at 0 20.40001 270)
			(size 1.8034 0.508)
			(layers "B.Cu" "B.Mask" "B.Paste")
			(net "M_B_DQ<20>")
		)
		(pad "26" smd rect
			(at 0 21.249894 270)
			(size 1.8034 0.508)
			(layers "B.Cu" "B.Mask" "B.Paste")
			(net "GND")
		)
		(pad "27" smd rect
			(at 0 22.100032 270)
			(size 1.8034 0.508)
			(layers "B.Cu" "B.Mask" "B.Paste")
			(net "M_B_DQ<16>")
		)
		(pad "28" smd rect
			(at 0 22.949916 270)
			(size 1.8034 0.508)
			(layers "B.Cu" "B.Mask" "B.Paste")
			(net "GND")
		)
		(pad "29" smd rect
			(at 0 23.800054 270)
			(size 1.8034 0.508)
			(layers "B.Cu" "B.Mask" "B.Paste")
			(net "M_B_DQS_DP<11>")
		)
		(pad "30" smd rect
			(at 0 24.649938 270)
			(size 1.8034 0.508)
			(layers "B.Cu" "B.Mask" "B.Paste")
			(net "M_B_DQS_DN<11>")
		)
		(pad "31" smd rect
			(at 0 25.500076 270)
			(size 1.8034 0.508)
			(layers "B.Cu" "B.Mask" "B.Paste")
			(net "GND")
		)
		(pad "32" smd rect
			(at 0 26.34996 270)
			(size 1.8034 0.508)
			(layers "B.Cu" "B.Mask" "B.Paste")
			(net "M_B_DQ<22>")
		)
		(pad "33" smd rect
			(at 0 27.200098 270)
			(size 1.8034 0.508)
			(layers "B.Cu" "B.Mask" "B.Paste")
			(net "GND")
		)
		(pad "34" smd rect
			(at 0 28.049982 270)
			(size 1.8034 0.508)
			(layers "B.Cu" "B.Mask" "B.Paste")
			(net "M_B_DQ<18>")
		)
		(pad "35" smd rect
			(at 0 28.90012 270)
			(size 1.8034 0.508)
			(layers "B.Cu" "B.Mask" "B.Paste")
			(net "GND")
		)
		(pad "36" smd rect
			(at 0 29.750004 270)
			(size 1.8034 0.508)
			(layers "B.Cu" "B.Mask" "B.Paste")
			(net "M_B_DQ<28>")
		)
		(pad "37" smd rect
			(at 0 30.599888 270)
			(size 1.8034 0.508)
			(layers "B.Cu" "B.Mask" "B.Paste")
			(net "GND")
		)
		(pad "38" smd rect
			(at 0 31.450026 270)
			(size 1.8034 0.508)
			(layers "B.Cu" "B.Mask" "B.Paste")
			(net "M_B_DQ<24>")
		)
		(pad "39" smd rect
			(at 0 32.29991 270)
			(size 1.8034 0.508)
			(layers "B.Cu" "B.Mask" "B.Paste")
			(net "GND")
		)
		(pad "40" smd rect
			(at 0 33.150048 270)
			(size 1.8034 0.508)
			(layers "B.Cu" "B.Mask" "B.Paste")
			(net "M_B_DQS_DP<12>")
		)
		(pad "41" smd rect
			(at 0 33.999932 270)
			(size 1.8034 0.508)
			(layers "B.Cu" "B.Mask" "B.Paste")
			(net "M_B_DQS_DN<12>")
		)
		(pad "42" smd rect
			(at 0 34.85007 270)
			(size 1.8034 0.508)
			(layers "B.Cu" "B.Mask" "B.Paste")
			(net "GND")
		)
		(pad "43" smd rect
			(at 0 35.699954 270)
			(size 1.8034 0.508)
			(layers "B.Cu" "B.Mask" "B.Paste")
			(net "M_B_DQ<30>")
		)
		(pad "44" smd rect
			(at 0 36.550092 270)
			(size 1.8034 0.508)
			(layers "B.Cu" "B.Mask" "B.Paste")
			(net "GND")
		)
		(pad "45" smd rect
			(at 0 37.399976 270)
			(size 1.8034 0.508)
			(layers "B.Cu" "B.Mask" "B.Paste")
			(net "M_B_DQ<26>")
		)
		(pad "46" smd rect
			(at 0 38.250114 270)
			(size 1.8034 0.508)
			(layers "B.Cu" "B.Mask" "B.Paste")
			(net "GND")
		)
		(pad "47" smd rect
			(at 0 39.099998 270)
			(size 1.8034 0.508)
			(layers "B.Cu" "B.Mask" "B.Paste")
			(net "M_B_ECC<4>")
		)
		(pad "48" smd rect
			(at 0 39.949882 270)
			(size 1.8034 0.508)
			(layers "B.Cu" "B.Mask" "B.Paste")
			(net "GND")
		)
		(pad "49" smd rect
			(at 0 40.80002 270)
			(size 1.8034 0.508)
			(layers "B.Cu" "B.Mask" "B.Paste")
			(net "M_B_ECC<0>")
		)
		(pad "50" smd rect
			(at 0 41.649904 270)
			(size 1.8034 0.508)
			(layers "B.Cu" "B.Mask" "B.Paste")
			(net "GND")
		)
		(pad "51" smd rect
			(at 0 42.500042 270)
			(size 1.8034 0.508)
			(layers "B.Cu" "B.Mask" "B.Paste")
			(net "M_B_DQS_DP<17>")
		)
		(pad "52" smd rect
			(at 0 43.349926 270)
			(size 1.8034 0.508)
			(layers "B.Cu" "B.Mask" "B.Paste")
			(net "M_B_DQS_DN<17>")
		)
		(pad "53" smd rect
			(at 0 44.200064 270)
			(size 1.8034 0.508)
			(layers "B.Cu" "B.Mask" "B.Paste")
			(net "GND")
		)
		(pad "54" smd rect
			(at 0 45.049948 270)
			(size 1.8034 0.508)
			(layers "B.Cu" "B.Mask" "B.Paste")
			(net "M_B_ECC<6>")
		)
		(pad "55" smd rect
			(at 0 45.900086 270)
			(size 1.8034 0.508)
			(layers "B.Cu" "B.Mask" "B.Paste")
			(net "GND")
		)
		(pad "56" smd rect
			(at 0 46.74997 270)
			(size 1.8034 0.508)
			(layers "B.Cu" "B.Mask" "B.Paste")
			(net "M_B_ECC<2>")
		)
		(pad "57" smd rect
			(at 0 47.600108 270)
			(size 1.8034 0.508)
			(layers "B.Cu" "B.Mask" "B.Paste")
			(net "GND")
		)
		(pad "58" smd rect
			(at 0 48.449992 270)
			(size 1.8034 0.508)
			(layers "B.Cu" "B.Mask" "B.Paste")
			(net "M_ABC_RST_N")
		)
		(pad "59" smd rect
			(at 0 49.299876 270)
			(size 1.8034 0.508)
			(layers "B.Cu" "B.Mask" "B.Paste")
			(net "PVDDQ_ABC")
		)
		(pad "60" smd rect
			(at 0 50.150014 270)
			(size 1.8034 0.508)
			(layers "B.Cu" "B.Mask" "B.Paste")
			(net "M_B_CKE<2>")
		)
		(pad "61" smd rect
			(at 0 50.999898 270)
			(size 1.8034 0.508)
			(layers "B.Cu" "B.Mask" "B.Paste")
			(net "PVDDQ_ABC")
		)
		(pad "62" smd rect
			(at 0 51.850036 270)
			(size 1.8034 0.508)
			(layers "B.Cu" "B.Mask" "B.Paste")
			(net "M_B_ACT_N")
		)
		(pad "63" smd rect
			(at 0 52.69992 270)
			(size 1.8034 0.508)
			(layers "B.Cu" "B.Mask" "B.Paste")
			(net "M_B_BG<0>")
		)
		(pad "64" smd rect
			(at 0 53.550058 270)
			(size 1.8034 0.508)
			(layers "B.Cu" "B.Mask" "B.Paste")
			(net "PVDDQ_ABC")
		)
		(pad "65" smd rect
			(at 0 54.399942 270)
			(size 1.8034 0.508)
			(layers "B.Cu" "B.Mask" "B.Paste")
			(net "M_B_MA<12>")
		)
		(pad "66" smd rect
			(at 0 55.25008 270)
			(size 1.8034 0.508)
			(layers "B.Cu" "B.Mask" "B.Paste")
			(net "M_B_MA<9>")
		)
		(pad "67" smd rect
			(at 0 56.099964 270)
			(size 1.8034 0.508)
			(layers "B.Cu" "B.Mask" "B.Paste")
			(net "PVDDQ_ABC")
		)
		(pad "68" smd rect
			(at 0 56.950102 270)
			(size 1.8034 0.508)
			(layers "B.Cu" "B.Mask" "B.Paste")
			(net "M_B_MA<8>")
		)
		(pad "69" smd rect
			(at 0 57.799986 270)
			(size 1.8034 0.508)
			(layers "B.Cu" "B.Mask" "B.Paste")
			(net "M_B_MA<6>")
		)
		(pad "70" smd rect
			(at 0 58.650124 270)
			(size 1.8034 0.508)
			(layers "B.Cu" "B.Mask" "B.Paste")
			(net "PVDDQ_ABC")
		)
		(pad "71" smd rect
			(at 0 59.500008 270)
			(size 1.8034 0.508)
			(layers "B.Cu" "B.Mask" "B.Paste")
			(net "M_B_MA<3>")
		)
		(pad "72" smd rect
			(at 0 60.349892 270)
			(size 1.8034 0.508)
			(layers "B.Cu" "B.Mask" "B.Paste")
			(net "M_B_MA<1>")
		)
		(pad "73" smd rect
			(at 0 61.20003 270)
			(size 1.8034 0.508)
			(layers "B.Cu" "B.Mask" "B.Paste")
			(net "PVDDQ_ABC")
		)
		(pad "74" smd rect
			(at 0 62.049914 270)
			(size 1.8034 0.508)
			(layers "B.Cu" "B.Mask" "B.Paste")
			(net "M_B_CLK_DP<2>")
		)
		(pad "75" smd rect
			(at 0 62.900052 270)
			(size 1.8034 0.508)
			(layers "B.Cu" "B.Mask" "B.Paste")
			(net "M_B_CLK_DN<2>")
		)
		(pad "76" smd rect
			(at 0 63.749936 270)
			(size 1.8034 0.508)
			(layers "B.Cu" "B.Mask" "B.Paste")
			(net "PVDDQ_ABC")
		)
		(pad "77" smd rect
			(at 0 64.600074 270)
			(size 1.8034 0.508)
			(layers "B.Cu" "B.Mask" "B.Paste")
			(net "PVTT_ABC")
		)
		(pad "78" smd rect
			(at 0 70.550024 270)
			(size 1.8034 0.508)
			(layers "B.Cu" "B.Mask" "B.Paste")
			(net "FM_DIMM_EVENT_COD_N")
		)
		(pad "79" smd rect
			(at 0 71.399908 270)
			(size 1.8034 0.508)
			(layers "B.Cu" "B.Mask" "B.Paste")
			(net "M_B_MA<0>")
		)
		(pad "80" smd rect
			(at 0 72.250046 270)
			(size 1.8034 0.508)
			(layers "B.Cu" "B.Mask" "B.Paste")
			(net "PVDDQ_ABC")
		)
		(pad "81" smd rect
			(at 0 73.09993 270)
			(size 1.8034 0.508)
			(layers "B.Cu" "B.Mask" "B.Paste")
			(net "M_B_BA<0>")
		)
		(pad "82" smd rect
			(at 0 73.950068 270)
			(size 1.8034 0.508)
			(layers "B.Cu" "B.Mask" "B.Paste")
			(net "M_B_MA<16>")
		)
		(pad "83" smd rect
			(at 0 74.799952 270)
			(size 1.8034 0.508)
			(layers "B.Cu" "B.Mask" "B.Paste")
			(net "PVDDQ_ABC")
		)
		(pad "84" smd rect
			(at 0 75.65009 270)
			(size 1.8034 0.508)
			(layers "B.Cu" "B.Mask" "B.Paste")
			(net "M_B_CS_N<4>")
		)
		(pad "85" smd rect
			(at 0 76.499974 270)
			(size 1.8034 0.508)
			(layers "B.Cu" "B.Mask" "B.Paste")
			(net "PVDDQ_ABC")
		)
		(pad "86" smd rect
			(at 0 77.350112 270)
			(size 1.8034 0.508)
			(layers "B.Cu" "B.Mask" "B.Paste")
			(net "M_B_MA<15>")
		)
		(pad "87" smd rect
			(at 0 78.199996 270)
			(size 1.8034 0.508)
			(layers "B.Cu" "B.Mask" "B.Paste")
			(net "M_B_ODT<2>")
		)
		(pad "88" smd rect
			(at 0 79.04988 270)
			(size 1.8034 0.508)
			(layers "B.Cu" "B.Mask" "B.Paste")
			(net "PVDDQ_ABC")
		)
		(pad "89" smd rect
			(at 0 79.900018 270)
			(size 1.8034 0.508)
			(layers "B.Cu" "B.Mask" "B.Paste")
			(net "M_B_CS_N<5>")
		)
		(pad "90" smd rect
			(at 0 80.749902 270)
			(size 1.8034 0.508)
			(layers "B.Cu" "B.Mask" "B.Paste")
			(net "PVDDQ_ABC")
		)
		(pad "91" smd rect
			(at 0 81.60004 270)
			(size 1.8034 0.508)
			(layers "B.Cu" "B.Mask" "B.Paste")
			(net "M_B_ODT<3>")
		)
		(pad "92" smd rect
			(at 0 82.449924 270)
			(size 1.8034 0.508)
			(layers "B.Cu" "B.Mask" "B.Paste")
			(net "PVDDQ_ABC")
		)
		(pad "93" smd rect
			(at 0 83.300062 270)
			(size 1.8034 0.508)
			(layers "B.Cu" "B.Mask" "B.Paste")
			(net "M_B_CS_N<6>")
		)
		(pad "94" smd rect
			(at 0 84.149946 270)
			(size 1.8034 0.508)
			(layers "B.Cu" "B.Mask" "B.Paste")
			(net "GND")
		)
		(pad "95" smd rect
			(at 0 85.000084 270)
			(size 1.8034 0.508)
			(layers "B.Cu" "B.Mask" "B.Paste")
			(net "M_B_DQ<36>")
		)
		(pad "96" smd rect
			(at 0 85.849968 270)
			(size 1.8034 0.508)
			(layers "B.Cu" "B.Mask" "B.Paste")
			(net "GND")
		)
		(pad "97" smd rect
			(at 0 86.700106 270)
			(size 1.8034 0.508)
			(layers "B.Cu" "B.Mask" "B.Paste")
			(net "M_B_DQ<32>")
		)
		(pad "98" smd rect
			(at 0 87.54999 270)
			(size 1.8034 0.508)
			(layers "B.Cu" "B.Mask" "B.Paste")
			(net "GND")
		)
		(pad "99" smd rect
			(at 0 88.399874 270)
			(size 1.8034 0.508)
			(layers "B.Cu" "B.Mask" "B.Paste")
			(net "M_B_DQS_DP<13>")
		)
		(pad "100" smd rect
			(at 0 89.250012 270)
			(size 1.8034 0.508)
			(layers "B.Cu" "B.Mask" "B.Paste")
			(net "M_B_DQS_DN<13>")
		)
		(pad "101" smd rect
			(at 0 90.099896 270)
			(size 1.8034 0.508)
			(layers "B.Cu" "B.Mask" "B.Paste")
			(net "GND")
		)
		(pad "102" smd rect
			(at 0 90.950034 270)
			(size 1.8034 0.508)
			(layers "B.Cu" "B.Mask" "B.Paste")
			(net "M_B_DQ<38>")
		)
		(pad "103" smd rect
			(at 0 91.799918 270)
			(size 1.8034 0.508)
			(layers "B.Cu" "B.Mask" "B.Paste")
			(net "GND")
		)
		(pad "104" smd rect
			(at 0 92.650056 270)
			(size 1.8034 0.508)
			(layers "B.Cu" "B.Mask" "B.Paste")
			(net "M_B_DQ<34>")
		)
		(pad "105" smd rect
			(at 0 93.49994 270)
			(size 1.8034 0.508)
			(layers "B.Cu" "B.Mask" "B.Paste")
			(net "GND")
		)
		(pad "106" smd rect
			(at 0 94.350078 270)
			(size 1.8034 0.508)
			(layers "B.Cu" "B.Mask" "B.Paste")
			(net "M_B_DQ<44>")
		)
		(pad "107" smd rect
			(at 0 95.199962 270)
			(size 1.8034 0.508)
			(layers "B.Cu" "B.Mask" "B.Paste")
			(net "GND")
		)
		(pad "108" smd rect
			(at 0 96.0501 270)
			(size 1.8034 0.508)
			(layers "B.Cu" "B.Mask" "B.Paste")
			(net "M_B_DQ<40>")
		)
		(pad "109" smd rect
			(at 0 96.899984 270)
			(size 1.8034 0.508)
			(layers "B.Cu" "B.Mask" "B.Paste")
			(net "GND")
		)
		(pad "110" smd rect
			(at 0 97.750122 270)
			(size 1.8034 0.508)
			(layers "B.Cu" "B.Mask" "B.Paste")
			(net "M_B_DQS_DP<14>")
		)
		(pad "111" smd rect
			(at 0 98.600006 270)
			(size 1.8034 0.508)
			(layers "B.Cu" "B.Mask" "B.Paste")
			(net "M_B_DQS_DN<14>")
		)
		(pad "112" smd rect
			(at 0 99.44989 270)
			(size 1.8034 0.508)
			(layers "B.Cu" "B.Mask" "B.Paste")
			(net "GND")
		)
		(pad "113" smd rect
			(at 0 100.300028 270)
			(size 1.8034 0.508)
			(layers "B.Cu" "B.Mask" "B.Paste")
			(net "M_B_DQ<46>")
		)
		(pad "114" smd rect
			(at 0 101.149912 270)
			(size 1.8034 0.508)
			(layers "B.Cu" "B.Mask" "B.Paste")
			(net "GND")
		)
		(pad "115" smd rect
			(at 0 102.00005 270)
			(size 1.8034 0.508)
			(layers "B.Cu" "B.Mask" "B.Paste")
			(net "M_B_DQ<42>")
		)
		(pad "116" smd rect
			(at 0 102.849934 270)
			(size 1.8034 0.508)
			(layers "B.Cu" "B.Mask" "B.Paste")
			(net "GND")
		)
		(pad "117" smd rect
			(at 0 103.700072 270)
			(size 1.8034 0.508)
			(layers "B.Cu" "B.Mask" "B.Paste")
			(net "M_B_DQ<52>")
		)
		(pad "118" smd rect
			(at 0 104.549956 270)
			(size 1.8034 0.508)
			(layers "B.Cu" "B.Mask" "B.Paste")
			(net "GND")
		)
		(pad "119" smd rect
			(at 0 105.400094 270)
			(size 1.8034 0.508)
			(layers "B.Cu" "B.Mask" "B.Paste")
			(net "M_B_DQ<48>")
		)
		(pad "120" smd rect
			(at 0 106.249978 270)
			(size 1.8034 0.508)
			(layers "B.Cu" "B.Mask" "B.Paste")
			(net "GND")
		)
		(pad "121" smd rect
			(at 0 107.100116 270)
			(size 1.8034 0.508)
			(layers "B.Cu" "B.Mask" "B.Paste")
			(net "M_B_DQS_DP<15>")
		)
		(pad "122" smd rect
			(at 0 107.95 270)
			(size 1.8034 0.508)
			(layers "B.Cu" "B.Mask" "B.Paste")
			(net "M_B_DQS_DN<15>")
		)
		(pad "123" smd rect
			(at 0 108.799884 270)
			(size 1.8034 0.508)
			(layers "B.Cu" "B.Mask" "B.Paste")
			(net "GND")
		)
		(pad "124" smd rect
			(at 0 109.650022 270)
			(size 1.8034 0.508)
			(layers "B.Cu" "B.Mask" "B.Paste")
			(net "M_B_DQ<54>")
		)
		(pad "125" smd rect
			(at 0 110.499906 270)
			(size 1.8034 0.508)
			(layers "B.Cu" "B.Mask" "B.Paste")
			(net "GND")
		)
		(pad "126" smd rect
			(at 0 111.350044 270)
			(size 1.8034 0.508)
			(layers "B.Cu" "B.Mask" "B.Paste")
			(net "M_B_DQ<50>")
		)
		(pad "127" smd rect
			(at 0 112.199928 270)
			(size 1.8034 0.508)
			(layers "B.Cu" "B.Mask" "B.Paste")
			(net "GND")
		)
		(pad "128" smd rect
			(at 0 113.050066 270)
			(size 1.8034 0.508)
			(layers "B.Cu" "B.Mask" "B.Paste")
			(net "M_B_DQ<60>")
		)
		(pad "129" smd rect
			(at 0 113.89995 270)
			(size 1.8034 0.508)
			(layers "B.Cu" "B.Mask" "B.Paste")
			(net "GND")
		)
		(pad "130" smd rect
			(at 0 114.750088 270)
			(size 1.8034 0.508)
			(layers "B.Cu" "B.Mask" "B.Paste")
			(net "M_B_DQ<56>")
		)
		(pad "131" smd rect
			(at 0 115.599972 270)
			(size 1.8034 0.508)
			(layers "B.Cu" "B.Mask" "B.Paste")
			(net "GND")
		)
		(pad "132" smd rect
			(at 0 116.45011 270)
			(size 1.8034 0.508)
			(layers "B.Cu" "B.Mask" "B.Paste")
			(net "M_B_DQS_DP<16>")
		)
		(pad "133" smd rect
			(at 0 117.299994 270)
			(size 1.8034 0.508)
			(layers "B.Cu" "B.Mask" "B.Paste")
			(net "M_B_DQS_DN<16>")
		)
		(pad "134" smd rect
			(at 0 118.149878 270)
			(size 1.8034 0.508)
			(layers "B.Cu" "B.Mask" "B.Paste")
			(net "GND")
		)
		(pad "135" smd rect
			(at 0 119.000016 270)
			(size 1.8034 0.508)
			(layers "B.Cu" "B.Mask" "B.Paste")
			(net "M_B_DQ<62>")
		)
		(pad "136" smd rect
			(at 0 119.8499 270)
			(size 1.8034 0.508)
			(layers "B.Cu" "B.Mask" "B.Paste")
			(net "GND")
		)
		(pad "137" smd rect
			(at 0 120.700038 270)
			(size 1.8034 0.508)
			(layers "B.Cu" "B.Mask" "B.Paste")
			(net "M_B_DQ<58>")
		)
		(pad "138" smd rect
			(at 0 121.549922 270)
			(size 1.8034 0.508)
			(layers "B.Cu" "B.Mask" "B.Paste")
			(net "GND")
		)
		(pad "139" smd rect
			(at 0 122.40006 270)
			(size 1.8034 0.508)
			(layers "B.Cu" "B.Mask" "B.Paste")
			(net "PVPP_ABC")
		)
		(pad "140" smd rect
			(at 0 123.249944 270)
			(size 1.8034 0.508)
			(layers "B.Cu" "B.Mask" "B.Paste")
			(net "PVPP_ABC")
		)
		(pad "141" smd rect
			(at 0 124.100082 270)
			(size 1.8034 0.508)
			(layers "B.Cu" "B.Mask" "B.Paste")
			(net "SMB_DDR_ABC_VPP_SCL")
		)
		(pad "142" smd rect
			(at 0 124.949966 270)
			(size 1.8034 0.508)
			(layers "B.Cu" "B.Mask" "B.Paste")
			(net "PVPP_ABC")
		)
		(pad "143" smd rect
			(at 0 125.800104 270)
			(size 1.8034 0.508)
			(layers "B.Cu" "B.Mask" "B.Paste")
			(net "PVPP_ABC")
		)
		(pad "144" smd rect
			(at 0 126.649988 270)
			(size 1.8034 0.508)
			(layers "B.Cu" "B.Mask" "B.Paste")
			(net "TP_CH_B_DIMM_B1_RFU_2")
		)
		(pad "145" smd rect
			(at -4.59994 0 270)
			(size 1.8034 0.508)
			(layers "B.Cu" "B.Mask" "B.Paste")
			(net "P12V_NVDIMM_ABC")
		)
		(pad "146" smd rect
			(at -4.59994 0.849884 270)
			(size 1.8034 0.508)
			(layers "B.Cu" "B.Mask" "B.Paste")
			(net "M_B_VREF")
		)
		(pad "147" smd rect
			(at -4.59994 1.700022 270)
			(size 1.8034 0.508)
			(layers "B.Cu" "B.Mask" "B.Paste")
			(net "GND")
		)
		(pad "148" smd rect
			(at -4.59994 2.549906 270)
			(size 1.8034 0.508)
			(layers "B.Cu" "B.Mask" "B.Paste")
			(net "M_B_DQ<5>")
		)
		(pad "149" smd rect
			(at -4.59994 3.400044 270)
			(size 1.8034 0.508)
			(layers "B.Cu" "B.Mask" "B.Paste")
			(net "GND")
		)
		(pad "150" smd rect
			(at -4.59994 4.249928 270)
			(size 1.8034 0.508)
			(layers "B.Cu" "B.Mask" "B.Paste")
			(net "M_B_DQ<1>")
		)
		(pad "151" smd rect
			(at -4.59994 5.100066 270)
			(size 1.8034 0.508)
			(layers "B.Cu" "B.Mask" "B.Paste")
			(net "GND")
		)
		(pad "152" smd rect
			(at -4.59994 5.94995 270)
			(size 1.8034 0.508)
			(layers "B.Cu" "B.Mask" "B.Paste")
			(net "M_B_DQS_DN<0>")
		)
		(pad "153" smd rect
			(at -4.59994 6.800088 270)
			(size 1.8034 0.508)
			(layers "B.Cu" "B.Mask" "B.Paste")
			(net "M_B_DQS_DP<0>")
		)
		(pad "154" smd rect
			(at -4.59994 7.649972 270)
			(size 1.8034 0.508)
			(layers "B.Cu" "B.Mask" "B.Paste")
			(net "GND")
		)
		(pad "155" smd rect
			(at -4.59994 8.50011 270)
			(size 1.8034 0.508)
			(layers "B.Cu" "B.Mask" "B.Paste")
			(net "M_B_DQ<7>")
		)
		(pad "156" smd rect
			(at -4.59994 9.349994 270)
			(size 1.8034 0.508)
			(layers "B.Cu" "B.Mask" "B.Paste")
			(net "GND")
		)
		(pad "157" smd rect
			(at -4.59994 10.199878 270)
			(size 1.8034 0.508)
			(layers "B.Cu" "B.Mask" "B.Paste")
			(net "M_B_DQ<3>")
		)
		(pad "158" smd rect
			(at -4.59994 11.050016 270)
			(size 1.8034 0.508)
			(layers "B.Cu" "B.Mask" "B.Paste")
			(net "GND")
		)
		(pad "159" smd rect
			(at -4.59994 11.8999 270)
			(size 1.8034 0.508)
			(layers "B.Cu" "B.Mask" "B.Paste")
			(net "M_B_DQ<13>")
		)
		(pad "160" smd rect
			(at -4.59994 12.750038 270)
			(size 1.8034 0.508)
			(layers "B.Cu" "B.Mask" "B.Paste")
			(net "GND")
		)
		(pad "161" smd rect
			(at -4.59994 13.599922 270)
			(size 1.8034 0.508)
			(layers "B.Cu" "B.Mask" "B.Paste")
			(net "M_B_DQ<9>")
		)
		(pad "162" smd rect
			(at -4.59994 14.45006 270)
			(size 1.8034 0.508)
			(layers "B.Cu" "B.Mask" "B.Paste")
			(net "GND")
		)
		(pad "163" smd rect
			(at -4.59994 15.299944 270)
			(size 1.8034 0.508)
			(layers "B.Cu" "B.Mask" "B.Paste")
			(net "M_B_DQS_DN<1>")
		)
		(pad "164" smd rect
			(at -4.59994 16.150082 270)
			(size 1.8034 0.508)
			(layers "B.Cu" "B.Mask" "B.Paste")
			(net "M_B_DQS_DP<1>")
		)
		(pad "165" smd rect
			(at -4.59994 16.999966 270)
			(size 1.8034 0.508)
			(layers "B.Cu" "B.Mask" "B.Paste")
			(net "GND")
		)
		(pad "166" smd rect
			(at -4.59994 17.850104 270)
			(size 1.8034 0.508)
			(layers "B.Cu" "B.Mask" "B.Paste")
			(net "M_B_DQ<15>")
		)
		(pad "167" smd rect
			(at -4.59994 18.699988 270)
			(size 1.8034 0.508)
			(layers "B.Cu" "B.Mask" "B.Paste")
			(net "GND")
		)
		(pad "168" smd rect
			(at -4.59994 19.550126 270)
			(size 1.8034 0.508)
			(layers "B.Cu" "B.Mask" "B.Paste")
			(net "M_B_DQ<11>")
		)
		(pad "169" smd rect
			(at -4.59994 20.40001 270)
			(size 1.8034 0.508)
			(layers "B.Cu" "B.Mask" "B.Paste")
			(net "GND")
		)
		(pad "170" smd rect
			(at -4.59994 21.249894 270)
			(size 1.8034 0.508)
			(layers "B.Cu" "B.Mask" "B.Paste")
			(net "M_B_DQ<21>")
		)
		(pad "171" smd rect
			(at -4.59994 22.100032 270)
			(size 1.8034 0.508)
			(layers "B.Cu" "B.Mask" "B.Paste")
			(net "GND")
		)
		(pad "172" smd rect
			(at -4.59994 22.949916 270)
			(size 1.8034 0.508)
			(layers "B.Cu" "B.Mask" "B.Paste")
			(net "M_B_DQ<17>")
		)
		(pad "173" smd rect
			(at -4.59994 23.800054 270)
			(size 1.8034 0.508)
			(layers "B.Cu" "B.Mask" "B.Paste")
			(net "GND")
		)
		(pad "174" smd rect
			(at -4.59994 24.649938 270)
			(size 1.8034 0.508)
			(layers "B.Cu" "B.Mask" "B.Paste")
			(net "M_B_DQS_DN<2>")
		)
		(pad "175" smd rect
			(at -4.59994 25.500076 270)
			(size 1.8034 0.508)
			(layers "B.Cu" "B.Mask" "B.Paste")
			(net "M_B_DQS_DP<2>")
		)
		(pad "176" smd rect
			(at -4.59994 26.34996 270)
			(size 1.8034 0.508)
			(layers "B.Cu" "B.Mask" "B.Paste")
			(net "GND")
		)
		(pad "177" smd rect
			(at -4.59994 27.200098 270)
			(size 1.8034 0.508)
			(layers "B.Cu" "B.Mask" "B.Paste")
			(net "M_B_DQ<23>")
		)
		(pad "178" smd rect
			(at -4.59994 28.049982 270)
			(size 1.8034 0.508)
			(layers "B.Cu" "B.Mask" "B.Paste")
			(net "GND")
		)
		(pad "179" smd rect
			(at -4.59994 28.90012 270)
			(size 1.8034 0.508)
			(layers "B.Cu" "B.Mask" "B.Paste")
			(net "M_B_DQ<19>")
		)
		(pad "180" smd rect
			(at -4.59994 29.750004 270)
			(size 1.8034 0.508)
			(layers "B.Cu" "B.Mask" "B.Paste")
			(net "GND")
		)
		(pad "181" smd rect
			(at -4.59994 30.599888 270)
			(size 1.8034 0.508)
			(layers "B.Cu" "B.Mask" "B.Paste")
			(net "M_B_DQ<29>")
		)
		(pad "182" smd rect
			(at -4.59994 31.450026 270)
			(size 1.8034 0.508)
			(layers "B.Cu" "B.Mask" "B.Paste")
			(net "GND")
		)
		(pad "183" smd rect
			(at -4.59994 32.29991 270)
			(size 1.8034 0.508)
			(layers "B.Cu" "B.Mask" "B.Paste")
			(net "M_B_DQ<25>")
		)
		(pad "184" smd rect
			(at -4.59994 33.150048 270)
			(size 1.8034 0.508)
			(layers "B.Cu" "B.Mask" "B.Paste")
			(net "GND")
		)
		(pad "185" smd rect
			(at -4.59994 33.999932 270)
			(size 1.8034 0.508)
			(layers "B.Cu" "B.Mask" "B.Paste")
			(net "M_B_DQS_DN<3>")
		)
		(pad "186" smd rect
			(at -4.59994 34.85007 270)
			(size 1.8034 0.508)
			(layers "B.Cu" "B.Mask" "B.Paste")
			(net "M_B_DQS_DP<3>")
		)
		(pad "187" smd rect
			(at -4.59994 35.699954 270)
			(size 1.8034 0.508)
			(layers "B.Cu" "B.Mask" "B.Paste")
			(net "GND")
		)
		(pad "188" smd rect
			(at -4.59994 36.550092 270)
			(size 1.8034 0.508)
			(layers "B.Cu" "B.Mask" "B.Paste")
			(net "M_B_DQ<31>")
		)
		(pad "189" smd rect
			(at -4.59994 37.399976 270)
			(size 1.8034 0.508)
			(layers "B.Cu" "B.Mask" "B.Paste")
			(net "GND")
		)
		(pad "190" smd rect
			(at -4.59994 38.250114 270)
			(size 1.8034 0.508)
			(layers "B.Cu" "B.Mask" "B.Paste")
			(net "M_B_DQ<27>")
		)
		(pad "191" smd rect
			(at -4.59994 39.099998 270)
			(size 1.8034 0.508)
			(layers "B.Cu" "B.Mask" "B.Paste")
			(net "GND")
		)
		(pad "192" smd rect
			(at -4.59994 39.949882 270)
			(size 1.8034 0.508)
			(layers "B.Cu" "B.Mask" "B.Paste")
			(net "M_B_ECC<5>")
		)
		(pad "193" smd rect
			(at -4.59994 40.80002 270)
			(size 1.8034 0.508)
			(layers "B.Cu" "B.Mask" "B.Paste")
			(net "GND")
		)
		(pad "194" smd rect
			(at -4.59994 41.649904 270)
			(size 1.8034 0.508)
			(layers "B.Cu" "B.Mask" "B.Paste")
			(net "M_B_ECC<1>")
		)
		(pad "195" smd rect
			(at -4.59994 42.500042 270)
			(size 1.8034 0.508)
			(layers "B.Cu" "B.Mask" "B.Paste")
			(net "GND")
		)
		(pad "196" smd rect
			(at -4.59994 43.349926 270)
			(size 1.8034 0.508)
			(layers "B.Cu" "B.Mask" "B.Paste")
			(net "M_B_DQS_DN<8>")
		)
		(pad "197" smd rect
			(at -4.59994 44.200064 270)
			(size 1.8034 0.508)
			(layers "B.Cu" "B.Mask" "B.Paste")
			(net "M_B_DQS_DP<8>")
		)
		(pad "198" smd rect
			(at -4.59994 45.049948 270)
			(size 1.8034 0.508)
			(layers "B.Cu" "B.Mask" "B.Paste")
			(net "GND")
		)
		(pad "199" smd rect
			(at -4.59994 45.900086 270)
			(size 1.8034 0.508)
			(layers "B.Cu" "B.Mask" "B.Paste")
			(net "M_B_ECC<7>")
		)
		(pad "200" smd rect
			(at -4.59994 46.74997 270)
			(size 1.8034 0.508)
			(layers "B.Cu" "B.Mask" "B.Paste")
			(net "GND")
		)
		(pad "201" smd rect
			(at -4.59994 47.600108 270)
			(size 1.8034 0.508)
			(layers "B.Cu" "B.Mask" "B.Paste")
			(net "M_B_ECC<3>")
		)
		(pad "202" smd rect
			(at -4.59994 48.449992 270)
			(size 1.8034 0.508)
			(layers "B.Cu" "B.Mask" "B.Paste")
			(net "GND")
		)
		(pad "203" smd rect
			(at -4.59994 49.299876 270)
			(size 1.8034 0.508)
			(layers "B.Cu" "B.Mask" "B.Paste")
			(net "M_B_CKE<3>")
		)
		(pad "204" smd rect
			(at -4.59994 50.150014 270)
			(size 1.8034 0.508)
			(layers "B.Cu" "B.Mask" "B.Paste")
			(net "PVDDQ_ABC")
		)
		(pad "205" smd rect
			(at -4.59994 50.999898 270)
			(size 1.8034 0.508)
			(layers "B.Cu" "B.Mask" "B.Paste")
			(net "TP_CH_B_DIMM_B1_RFU_0")
		)
		(pad "206" smd rect
			(at -4.59994 51.850036 270)
			(size 1.8034 0.508)
			(layers "B.Cu" "B.Mask" "B.Paste")
			(net "PVDDQ_ABC")
		)
		(pad "207" smd rect
			(at -4.59994 52.69992 270)
			(size 1.8034 0.508)
			(layers "B.Cu" "B.Mask" "B.Paste")
			(net "M_B_BG<1>")
		)
		(pad "208" smd rect
			(at -4.59994 53.550058 270)
			(size 1.8034 0.508)
			(layers "B.Cu" "B.Mask" "B.Paste")
			(net "M_B_ALERT_N")
		)
		(pad "209" smd rect
			(at -4.59994 54.399942 270)
			(size 1.8034 0.508)
			(layers "B.Cu" "B.Mask" "B.Paste")
			(net "PVDDQ_ABC")
		)
		(pad "210" smd rect
			(at -4.59994 55.25008 270)
			(size 1.8034 0.508)
			(layers "B.Cu" "B.Mask" "B.Paste")
			(net "M_B_MA<11>")
		)
		(pad "211" smd rect
			(at -4.59994 56.099964 270)
			(size 1.8034 0.508)
			(layers "B.Cu" "B.Mask" "B.Paste")
			(net "M_B_MA<7>")
		)
		(pad "212" smd rect
			(at -4.59994 56.950102 270)
			(size 1.8034 0.508)
			(layers "B.Cu" "B.Mask" "B.Paste")
			(net "PVDDQ_ABC")
		)
		(pad "213" smd rect
			(at -4.59994 57.799986 270)
			(size 1.8034 0.508)
			(layers "B.Cu" "B.Mask" "B.Paste")
			(net "M_B_MA<5>")
		)
		(pad "214" smd rect
			(at -4.59994 58.650124 270)
			(size 1.8034 0.508)
			(layers "B.Cu" "B.Mask" "B.Paste")
			(net "M_B_MA<4>")
		)
		(pad "215" smd rect
			(at -4.59994 59.500008 270)
			(size 1.8034 0.508)
			(layers "B.Cu" "B.Mask" "B.Paste")
			(net "PVDDQ_ABC")
		)
		(pad "216" smd rect
			(at -4.59994 60.349892 270)
			(size 1.8034 0.508)
			(layers "B.Cu" "B.Mask" "B.Paste")
			(net "M_B_MA<2>")
		)
		(pad "217" smd rect
			(at -4.59994 61.20003 270)
			(size 1.8034 0.508)
			(layers "B.Cu" "B.Mask" "B.Paste")
			(net "PVDDQ_ABC")
		)
		(pad "218" smd rect
			(at -4.59994 62.049914 270)
			(size 1.8034 0.508)
			(layers "B.Cu" "B.Mask" "B.Paste")
			(net "M_B_CLK_DP<3>")
		)
		(pad "219" smd rect
			(at -4.59994 62.900052 270)
			(size 1.8034 0.508)
			(layers "B.Cu" "B.Mask" "B.Paste")
			(net "M_B_CLK_DN<3>")
		)
		(pad "220" smd rect
			(at -4.59994 63.749936 270)
			(size 1.8034 0.508)
			(layers "B.Cu" "B.Mask" "B.Paste")
			(net "PVDDQ_ABC")
		)
		(pad "221" smd rect
			(at -4.59994 64.600074 270)
			(size 1.8034 0.508)
			(layers "B.Cu" "B.Mask" "B.Paste")
			(net "PVTT_ABC")
		)
		(pad "222" smd rect
			(at -4.59994 70.550024 270)
			(size 1.8034 0.508)
			(layers "B.Cu" "B.Mask" "B.Paste")
			(net "M_B_PAR")
		)
		(pad "223" smd rect
			(at -4.59994 71.399908 270)
			(size 1.8034 0.508)
			(layers "B.Cu" "B.Mask" "B.Paste")
			(net "PVDDQ_ABC")
		)
		(pad "224" smd rect
			(at -4.59994 72.250046 270)
			(size 1.8034 0.508)
			(layers "B.Cu" "B.Mask" "B.Paste")
			(net "M_B_BA<1>")
		)
		(pad "225" smd rect
			(at -4.59994 73.09993 270)
			(size 1.8034 0.508)
			(layers "B.Cu" "B.Mask" "B.Paste")
			(net "M_B_MA<10>")
		)
		(pad "226" smd rect
			(at -4.59994 73.950068 270)
			(size 1.8034 0.508)
			(layers "B.Cu" "B.Mask" "B.Paste")
			(net "PVDDQ_ABC")
		)
		(pad "227" smd rect
			(at -4.59994 74.799952 270)
			(size 1.8034 0.508)
			(layers "B.Cu" "B.Mask" "B.Paste")
			(net "TP_CH_B_DIMM_B1_RFU_1")
		)
		(pad "228" smd rect
			(at -4.59994 75.65009 270)
			(size 1.8034 0.508)
			(layers "B.Cu" "B.Mask" "B.Paste")
			(net "M_B_MA<14>")
		)
		(pad "229" smd rect
			(at -4.59994 76.499974 270)
			(size 1.8034 0.508)
			(layers "B.Cu" "B.Mask" "B.Paste")
			(net "PVDDQ_ABC")
		)
		(pad "230" smd rect
			(at -4.59994 77.350112 270)
			(size 1.8034 0.508)
			(layers "B.Cu" "B.Mask" "B.Paste")
			(net "FM_ADR_COMPLETE_ABC_N")
		)
		(pad "231" smd rect
			(at -4.59994 78.199996 270)
			(size 1.8034 0.508)
			(layers "B.Cu" "B.Mask" "B.Paste")
			(net "PVDDQ_ABC")
		)
		(pad "232" smd rect
			(at -4.59994 79.04988 270)
			(size 1.8034 0.508)
			(layers "B.Cu" "B.Mask" "B.Paste")
			(net "M_B_MA<13>")
		)
		(pad "233" smd rect
			(at -4.59994 79.900018 270)
			(size 1.8034 0.508)
			(layers "B.Cu" "B.Mask" "B.Paste")
			(net "PVDDQ_ABC")
		)
		(pad "234" smd rect
			(at -4.59994 80.749902 270)
			(size 1.8034 0.508)
			(layers "B.Cu" "B.Mask" "B.Paste")
			(net "M_B_MA<17>")
		)
		(pad "235" smd rect
			(at -4.59994 81.60004 270)
			(size 1.8034 0.508)
			(layers "B.Cu" "B.Mask" "B.Paste")
			(net "M_B_C<2>")
		)
		(pad "236" smd rect
			(at -4.59994 82.449924 270)
			(size 1.8034 0.508)
			(layers "B.Cu" "B.Mask" "B.Paste")
			(net "PVDDQ_ABC")
		)
		(pad "237" smd rect
			(at -4.59994 83.300062 270)
			(size 1.8034 0.508)
			(layers "B.Cu" "B.Mask" "B.Paste")
			(net "M_B_CS_N<7>")
		)
		(pad "238" smd rect
			(at -4.59994 84.149946 270)
			(size 1.8034 0.508)
			(layers "B.Cu" "B.Mask" "B.Paste")
			(net "GND")
		)
		(pad "239" smd rect
			(at -4.59994 85.000084 270)
			(size 1.8034 0.508)
			(layers "B.Cu" "B.Mask" "B.Paste")
			(net "GND")
		)
		(pad "240" smd rect
			(at -4.59994 85.849968 270)
			(size 1.8034 0.508)
			(layers "B.Cu" "B.Mask" "B.Paste")
			(net "M_B_DQ<37>")
		)
		(pad "241" smd rect
			(at -4.59994 86.700106 270)
			(size 1.8034 0.508)
			(layers "B.Cu" "B.Mask" "B.Paste")
			(net "GND")
		)
		(pad "242" smd rect
			(at -4.59994 87.54999 270)
			(size 1.8034 0.508)
			(layers "B.Cu" "B.Mask" "B.Paste")
			(net "M_B_DQ<33>")
		)
		(pad "243" smd rect
			(at -4.59994 88.399874 270)
			(size 1.8034 0.508)
			(layers "B.Cu" "B.Mask" "B.Paste")
			(net "GND")
		)
		(pad "244" smd rect
			(at -4.59994 89.250012 270)
			(size 1.8034 0.508)
			(layers "B.Cu" "B.Mask" "B.Paste")
			(net "M_B_DQS_DN<4>")
		)
		(pad "245" smd rect
			(at -4.59994 90.099896 270)
			(size 1.8034 0.508)
			(layers "B.Cu" "B.Mask" "B.Paste")
			(net "M_B_DQS_DP<4>")
		)
		(pad "246" smd rect
			(at -4.59994 90.950034 270)
			(size 1.8034 0.508)
			(layers "B.Cu" "B.Mask" "B.Paste")
			(net "GND")
		)
		(pad "247" smd rect
			(at -4.59994 91.799918 270)
			(size 1.8034 0.508)
			(layers "B.Cu" "B.Mask" "B.Paste")
			(net "M_B_DQ<39>")
		)
		(pad "248" smd rect
			(at -4.59994 92.650056 270)
			(size 1.8034 0.508)
			(layers "B.Cu" "B.Mask" "B.Paste")
			(net "GND")
		)
		(pad "249" smd rect
			(at -4.59994 93.49994 270)
			(size 1.8034 0.508)
			(layers "B.Cu" "B.Mask" "B.Paste")
			(net "M_B_DQ<35>")
		)
		(pad "250" smd rect
			(at -4.59994 94.350078 270)
			(size 1.8034 0.508)
			(layers "B.Cu" "B.Mask" "B.Paste")
			(net "GND")
		)
		(pad "251" smd rect
			(at -4.59994 95.199962 270)
			(size 1.8034 0.508)
			(layers "B.Cu" "B.Mask" "B.Paste")
			(net "M_B_DQ<45>")
		)
		(pad "252" smd rect
			(at -4.59994 96.0501 270)
			(size 1.8034 0.508)
			(layers "B.Cu" "B.Mask" "B.Paste")
			(net "GND")
		)
		(pad "253" smd rect
			(at -4.59994 96.899984 270)
			(size 1.8034 0.508)
			(layers "B.Cu" "B.Mask" "B.Paste")
			(net "M_B_DQ<41>")
		)
		(pad "254" smd rect
			(at -4.59994 97.750122 270)
			(size 1.8034 0.508)
			(layers "B.Cu" "B.Mask" "B.Paste")
			(net "GND")
		)
		(pad "255" smd rect
			(at -4.59994 98.600006 270)
			(size 1.8034 0.508)
			(layers "B.Cu" "B.Mask" "B.Paste")
			(net "M_B_DQS_DN<5>")
		)
		(pad "256" smd rect
			(at -4.59994 99.44989 270)
			(size 1.8034 0.508)
			(layers "B.Cu" "B.Mask" "B.Paste")
			(net "M_B_DQS_DP<5>")
		)
		(pad "257" smd rect
			(at -4.59994 100.300028 270)
			(size 1.8034 0.508)
			(layers "B.Cu" "B.Mask" "B.Paste")
			(net "GND")
		)
		(pad "258" smd rect
			(at -4.59994 101.149912 270)
			(size 1.8034 0.508)
			(layers "B.Cu" "B.Mask" "B.Paste")
			(net "M_B_DQ<47>")
		)
		(pad "259" smd rect
			(at -4.59994 102.00005 270)
			(size 1.8034 0.508)
			(layers "B.Cu" "B.Mask" "B.Paste")
			(net "GND")
		)
		(pad "260" smd rect
			(at -4.59994 102.849934 270)
			(size 1.8034 0.508)
			(layers "B.Cu" "B.Mask" "B.Paste")
			(net "M_B_DQ<43>")
		)
		(pad "261" smd rect
			(at -4.59994 103.700072 270)
			(size 1.8034 0.508)
			(layers "B.Cu" "B.Mask" "B.Paste")
			(net "GND")
		)
		(pad "262" smd rect
			(at -4.59994 104.549956 270)
			(size 1.8034 0.508)
			(layers "B.Cu" "B.Mask" "B.Paste")
			(net "M_B_DQ<53>")
		)
		(pad "263" smd rect
			(at -4.59994 105.400094 270)
			(size 1.8034 0.508)
			(layers "B.Cu" "B.Mask" "B.Paste")
			(net "GND")
		)
		(pad "264" smd rect
			(at -4.59994 106.249978 270)
			(size 1.8034 0.508)
			(layers "B.Cu" "B.Mask" "B.Paste")
			(net "M_B_DQ<49>")
		)
		(pad "265" smd rect
			(at -4.59994 107.100116 270)
			(size 1.8034 0.508)
			(layers "B.Cu" "B.Mask" "B.Paste")
			(net "GND")
		)
		(pad "266" smd rect
			(at -4.59994 107.95 270)
			(size 1.8034 0.508)
			(layers "B.Cu" "B.Mask" "B.Paste")
			(net "M_B_DQS_DN<6>")
		)
		(pad "267" smd rect
			(at -4.59994 108.799884 270)
			(size 1.8034 0.508)
			(layers "B.Cu" "B.Mask" "B.Paste")
			(net "M_B_DQS_DP<6>")
		)
		(pad "268" smd rect
			(at -4.59994 109.650022 270)
			(size 1.8034 0.508)
			(layers "B.Cu" "B.Mask" "B.Paste")
			(net "GND")
		)
		(pad "269" smd rect
			(at -4.59994 110.499906 270)
			(size 1.8034 0.508)
			(layers "B.Cu" "B.Mask" "B.Paste")
			(net "M_B_DQ<55>")
		)
		(pad "270" smd rect
			(at -4.59994 111.350044 270)
			(size 1.8034 0.508)
			(layers "B.Cu" "B.Mask" "B.Paste")
			(net "GND")
		)
		(pad "271" smd rect
			(at -4.59994 112.199928 270)
			(size 1.8034 0.508)
			(layers "B.Cu" "B.Mask" "B.Paste")
			(net "M_B_DQ<51>")
		)
		(pad "272" smd rect
			(at -4.59994 113.050066 270)
			(size 1.8034 0.508)
			(layers "B.Cu" "B.Mask" "B.Paste")
			(net "GND")
		)
		(pad "273" smd rect
			(at -4.59994 113.89995 270)
			(size 1.8034 0.508)
			(layers "B.Cu" "B.Mask" "B.Paste")
			(net "M_B_DQ<61>")
		)
		(pad "274" smd rect
			(at -4.59994 114.750088 270)
			(size 1.8034 0.508)
			(layers "B.Cu" "B.Mask" "B.Paste")
			(net "GND")
		)
		(pad "275" smd rect
			(at -4.59994 115.599972 270)
			(size 1.8034 0.508)
			(layers "B.Cu" "B.Mask" "B.Paste")
			(net "M_B_DQ<57>")
		)
		(pad "276" smd rect
			(at -4.59994 116.45011 270)
			(size 1.8034 0.508)
			(layers "B.Cu" "B.Mask" "B.Paste")
			(net "GND")
		)
		(pad "277" smd rect
			(at -4.59994 117.299994 270)
			(size 1.8034 0.508)
			(layers "B.Cu" "B.Mask" "B.Paste")
			(net "M_B_DQS_DN<7>")
		)
		(pad "278" smd rect
			(at -4.59994 118.149878 270)
			(size 1.8034 0.508)
			(layers "B.Cu" "B.Mask" "B.Paste")
			(net "M_B_DQS_DP<7>")
		)
		(pad "279" smd rect
			(at -4.59994 119.000016 270)
			(size 1.8034 0.508)
			(layers "B.Cu" "B.Mask" "B.Paste")
			(net "GND")
		)
		(pad "280" smd rect
			(at -4.59994 119.8499 270)
			(size 1.8034 0.508)
			(layers "B.Cu" "B.Mask" "B.Paste")
			(net "M_B_DQ<63>")
		)
		(pad "281" smd rect
			(at -4.59994 120.700038 270)
			(size 1.8034 0.508)
			(layers "B.Cu" "B.Mask" "B.Paste")
			(net "GND")
		)
		(pad "282" smd rect
			(at -4.59994 121.549922 270)
			(size 1.8034 0.508)
			(layers "B.Cu" "B.Mask" "B.Paste")
			(net "M_B_DQ<59>")
		)
		(pad "283" smd rect
			(at -4.59994 122.40006 270)
			(size 1.8034 0.508)
			(layers "B.Cu" "B.Mask" "B.Paste")
			(net "GND")
		)
		(pad "284" smd rect
			(at -4.59994 123.249944 270)
			(size 1.8034 0.508)
			(layers "B.Cu" "B.Mask" "B.Paste")
			(net "PVPP_ABC")
		)
		(pad "285" smd rect
			(at -4.59994 124.100082 270)
			(size 1.8034 0.508)
			(layers "B.Cu" "B.Mask" "B.Paste")
			(net "SMB_DDR_ABC_VPP_SDA")
		)
		(pad "286" smd rect
			(at -4.59994 124.949966 270)
			(size 1.8034 0.508)
			(layers "B.Cu" "B.Mask" "B.Paste")
			(net "PVPP_ABC")
		)
		(pad "287" smd rect
			(at -4.59994 125.800104 270)
			(size 1.8034 0.508)
			(layers "B.Cu" "B.Mask" "B.Paste")
			(net "PVPP_ABC")
		)
		(pad "288" smd rect
			(at -4.59994 126.649988 270)
			(size 1.8034 0.508)
			(layers "B.Cu" "B.Mask" "B.Paste")
			(net "PVPP_ABC")
		)
	)
	(footprint ""
		(layer "B.Cu")
		(at 369.864386 -47.827184 -90)
		(property "Reference" "R2T50"
			(at 0 0 90)
			(layer "B.SilkS")
			(hide yes)
			(effects
				(font
					(size 1.27 1.27)
				)
				(justify mirror)
			)
		)
		(property "Value" ""
			(at 0 0 90)
			(layer "B.Fab")
			(effects
				(font
					(size 1.27 1.27)
				)
				(justify mirror)
			)
		)
		(duplicate_pad_numbers_are_jumpers no)
		(fp_poly
			(pts
				(xy 0.2794 -0.1016) (xy -0.2794 -0.1016) (xy -0.2794 0.9906) (xy 0.2794 0.9906)
			)
			(stroke
				(width 0)
				(type default)
			)
			(fill no)
			(layer "B.CrtYd")
		)
		(fp_line
			(start -0.2794 0.9906)
			(end -0.2794 -0.1016)
			(stroke
				(width 0.1)
				(type default)
			)
			(layer "B.Fab")
		)
		(fp_line
			(start 0.2794 0.9906)
			(end -0.2794 0.9906)
			(stroke
				(width 0.1)
				(type default)
			)
			(layer "B.Fab")
		)
		(fp_line
			(start -0.2794 -0.1016)
			(end 0.2794 -0.1016)
			(stroke
				(width 0.1)
				(type default)
			)
			(layer "B.Fab")
		)
		(fp_line
			(start 0.2794 -0.1016)
			(end 0.2794 0.9906)
			(stroke
				(width 0.1)
				(type default)
			)
			(layer "B.Fab")
		)
		(pad "1" smd rect
			(at 0 0 90)
			(size 0.508 0.508)
			(layers "B.Cu" "B.Mask" "B.Paste")
			(net "PD_GTL2104_4_DIR")
		)
		(pad "2" smd rect
			(at 0 0.889 90)
			(size 0.508 0.508)
			(layers "B.Cu" "B.Mask" "B.Paste")
			(net "GND")
		)
		(zone
			(layer "B.Cu")
			(hatch none 0.5)
			(connect_pads
				(clearance 0)
			)
			(min_thickness 0.25)
			(keepout
				(tracks not_allowed)
				(vias allowed)
				(pads allowed)
				(copperpour not_allowed)
				(footprints allowed)
			)
			(placement
				(enabled no)
				(sheetname "")
			)
			(fill
				(thermal_gap 0.5)
				(thermal_bridge_width 0.5)
				(island_removal_mode 0)
			)
			(polygon
				(pts
					(xy 369.229386 -47.573184) (xy 369.229386 -48.081184) (xy 369.610386 -48.081184) (xy 369.610386 -47.573184)
				)
			)
		)
		(zone
			(layer "B.Cu")
			(hatch none 0.5)
			(connect_pads
				(clearance 0)
			)
			(min_thickness 0.25)
			(keepout
				(tracks allowed)
				(vias not_allowed)
				(pads allowed)
				(copperpour not_allowed)
				(footprints allowed)
			)
			(placement
				(enabled no)
				(sheetname "")
			)
			(fill
				(thermal_gap 0.5)
				(thermal_bridge_width 0.5)
				(island_removal_mode 0)
			)
			(polygon
				(pts
					(xy 369.610386 -47.573184) (xy 369.610386 -48.081184) (xy 369.229386 -48.081184) (xy 369.229386 -47.573184)
				)
			)
		)
	)
	(footprint ""
		(layer "B.Cu")
		(at 153.543 -17.78 -90)
		(property "Reference" "C7T3"
			(at 0 0 90)
			(layer "B.SilkS")
			(hide yes)
			(effects
				(font
					(size 1.27 1.27)
				)
				(justify mirror)
			)
		)
		(property "Value" ""
			(at 0 0 90)
			(layer "B.Fab")
			(effects
				(font
					(size 1.27 1.27)
				)
				(justify mirror)
			)
		)
		(duplicate_pad_numbers_are_jumpers no)
		(fp_poly
			(pts
				(xy 0.4953 -0.2032) (xy -0.4953 -0.2032) (xy -0.4953 1.6002) (xy 0.4953 1.6002)
			)
			(stroke
				(width 0)
				(type default)
			)
			(fill no)
			(layer "B.CrtYd")
		)
		(fp_line
			(start -0.4953 1.6002)
			(end 0.4953 1.6002)
			(stroke
				(width 0.1)
				(type default)
			)
			(layer "B.Fab")
		)
		(fp_line
			(start 0.4953 1.6002)
			(end 0.4953 -0.2032)
			(stroke
				(width 0.1)
				(type default)
			)
			(layer "B.Fab")
		)
		(fp_line
			(start -0.4953 -0.2032)
			(end -0.4953 1.6002)
			(stroke
				(width 0.1)
				(type default)
			)
			(layer "B.Fab")
		)
		(fp_line
			(start 0.4953 -0.2032)
			(end -0.4953 -0.2032)
			(stroke
				(width 0.1)
				(type default)
			)
			(layer "B.Fab")
		)
		(pad "1" smd rect
			(at 0 0 90)
			(size 0.762 0.889)
			(layers "B.Cu" "B.Mask" "B.Paste")
			(net "PVPP_GHJ")
		)
		(pad "2" smd rect
			(at 0 1.397 90)
			(size 0.762 0.889)
			(layers "B.Cu" "B.Mask" "B.Paste")
			(net "GND")
		)
		(zone
			(layer "B.Cu")
			(hatch none 0.5)
			(connect_pads
				(clearance 0)
			)
			(min_thickness 0.25)
			(keepout
				(tracks not_allowed)
				(vias allowed)
				(pads allowed)
				(copperpour not_allowed)
				(footprints allowed)
			)
			(placement
				(enabled no)
				(sheetname "")
			)
			(fill
				(thermal_gap 0.5)
				(thermal_bridge_width 0.5)
				(island_removal_mode 0)
			)
			(polygon
				(pts
					(xy 153.0985 -17.399) (xy 153.0985 -18.161) (xy 152.5905 -18.161) (xy 152.5905 -17.399)
				)
			)
		)
	)
	(footprint ""
		(layer "B.Cu")
		(at 171.069 -74.93)
		(property "Reference" "R6P21"
			(at 0 0 0)
			(layer "B.SilkS")
			(hide yes)
			(effects
				(font
					(size 1.27 1.27)
				)
				(justify mirror)
			)
		)
		(property "Value" ""
			(at 0 0 0)
			(layer "B.Fab")
			(effects
				(font
					(size 1.27 1.27)
				)
				(justify mirror)
			)
		)
		(duplicate_pad_numbers_are_jumpers no)
		(fp_poly
			(pts
				(xy 0.2794 -0.1016) (xy -0.2794 -0.1016) (xy -0.2794 0.9906) (xy 0.2794 0.9906)
			)
			(stroke
				(width 0)
				(type default)
			)
			(fill no)
			(layer "B.CrtYd")
		)
		(fp_line
			(start -0.2794 -0.1016)
			(end 0.2794 -0.1016)
			(stroke
				(width 0.1)
				(type default)
			)
			(layer "B.Fab")
		)
		(fp_line
			(start -0.2794 0.9906)
			(end -0.2794 -0.1016)
			(stroke
				(width 0.1)
				(type default)
			)
			(layer "B.Fab")
		)
		(fp_line
			(start 0.2794 -0.1016)
			(end 0.2794 0.9906)
			(stroke
				(width 0.1)
				(type default)
			)
			(layer "B.Fab")
		)
		(fp_line
			(start 0.2794 0.9906)
			(end -0.2794 0.9906)
			(stroke
				(width 0.1)
				(type default)
			)
			(layer "B.Fab")
		)
		(pad "1" smd rect
			(at 0 0 180)
			(size 0.508 0.508)
			(layers "B.Cu" "B.Mask" "B.Paste")
			(net "FM_DB1200_SMB_SA0")
		)
		(pad "2" smd rect
			(at 0 0.889 180)
			(size 0.508 0.508)
			(layers "B.Cu" "B.Mask" "B.Paste")
			(net "GND")
		)
		(zone
			(layer "B.Cu")
			(hatch none 0.5)
			(connect_pads
				(clearance 0)
			)
			(min_thickness 0.25)
			(keepout
				(tracks allowed)
				(vias not_allowed)
				(pads allowed)
				(copperpour not_allowed)
				(footprints allowed)
			)
			(placement
				(enabled no)
				(sheetname "")
			)
			(fill
				(thermal_gap 0.5)
				(thermal_bridge_width 0.5)
				(island_removal_mode 0)
			)
			(polygon
				(pts
					(xy 171.323 -74.676) (xy 170.815 -74.676) (xy 170.815 -74.295) (xy 171.323 -74.295)
				)
			)
		)
		(zone
			(layer "B.Cu")
			(hatch none 0.5)
			(connect_pads
				(clearance 0)
			)
			(min_thickness 0.25)
			(keepout
				(tracks not_allowed)
				(vias allowed)
				(pads allowed)
				(copperpour not_allowed)
				(footprints allowed)
			)
			(placement
				(enabled no)
				(sheetname "")
			)
			(fill
				(thermal_gap 0.5)
				(thermal_bridge_width 0.5)
				(island_removal_mode 0)
			)
			(polygon
				(pts
					(xy 171.323 -74.295) (xy 170.815 -74.295) (xy 170.815 -74.676) (xy 171.323 -74.676)
				)
			)
		)
	)
	(footprint ""
		(layer "B.Cu")
		(at 409.067 -48.768)
		(property "Reference" "R1T6"
			(at 0 0 0)
			(layer "B.SilkS")
			(hide yes)
			(effects
				(font
					(size 1.27 1.27)
				)
				(justify mirror)
			)
		)
		(property "Value" ""
			(at 0 0 0)
			(layer "B.Fab")
			(effects
				(font
					(size 1.27 1.27)
				)
				(justify mirror)
			)
		)
		(duplicate_pad_numbers_are_jumpers no)
		(fp_poly
			(pts
				(xy 0.2794 -0.1016) (xy -0.2794 -0.1016) (xy -0.2794 0.9906) (xy 0.2794 0.9906)
			)
			(stroke
				(width 0)
				(type default)
			)
			(fill no)
			(layer "B.CrtYd")
		)
		(fp_line
			(start -0.2794 -0.1016)
			(end 0.2794 -0.1016)
			(stroke
				(width 0.1)
				(type default)
			)
			(layer "B.Fab")
		)
		(fp_line
			(start -0.2794 0.9906)
			(end -0.2794 -0.1016)
			(stroke
				(width 0.1)
				(type default)
			)
			(layer "B.Fab")
		)
		(fp_line
			(start 0.2794 -0.1016)
			(end 0.2794 0.9906)
			(stroke
				(width 0.1)
				(type default)
			)
			(layer "B.Fab")
		)
		(fp_line
			(start 0.2794 0.9906)
			(end -0.2794 0.9906)
			(stroke
				(width 0.1)
				(type default)
			)
			(layer "B.Fab")
		)
		(pad "1" smd rect
			(at 0 0 180)
			(size 0.508 0.508)
			(layers "B.Cu" "B.Mask" "B.Paste")
			(net "P3V3_STBY")
		)
		(pad "2" smd rect
			(at 0 0.889 180)
			(size 0.508 0.508)
			(layers "B.Cu" "B.Mask" "B.Paste")
			(net "FM_BOARD_REV_ID1")
		)
	)
	(footprint ""
		(layer "B.Cu")
		(at 480.1108 -57.1754 90)
		(property "Reference" "R8E30"
			(at 0 0 90)
			(layer "B.SilkS")
			(hide yes)
			(effects
				(font
					(size 1.27 1.27)
				)
				(justify mirror)
			)
		)
		(property "Value" "*"
			(at -0.064008 -4.108196 90)
			(unlocked yes)
			(layer "B.Fab")
			(hide yes)
			(effects
				(font
					(size 1.27 1.016)
					(thickness 0.1524)
				)
				(justify mirror)
			)
		)
		(property "Device Type" "2K15R2F-1-GP_SMD-RG1-2K15R2F-1A"
			(at -0.064008 -5.632196 90)
			(unlocked yes)
			(layer "B.Fab")
			(hide yes)
			(effects
				(font
					(size 1.27 1.016)
					(thickness 0.1524)
				)
				(justify mirror)
			)
		)
		(duplicate_pad_numbers_are_jumpers no)
		(fp_line
			(start 0.508 -0.9398)
			(end 0.508 0.9398)
			(stroke
				(width 0.1524)
				(type default)
			)
			(layer "B.SilkS")
		)
		(fp_line
			(start -0.508 -0.9398)
			(end 0.508 -0.9398)
			(stroke
				(width 0.1524)
				(type default)
			)
			(layer "B.SilkS")
		)
		(fp_rect
			(start 0.508 0.9398)
			(end -0.508 -0.9398)
			(stroke
				(width 0)
				(type default)
			)
			(fill no)
			(layer "B.CrtYd")
		)
		(fp_rect
			(start 0.508 0.9398)
			(end -0.508 -0.9398)
			(stroke
				(width 0)
				(type default)
			)
			(fill no)
			(layer "B.Fab")
		)
		(pad "1" smd custom
			(at 0 -0.4445 270)
			(size 0.1397 0.1397)
			(layers "B.Cu" "B.Mask" "B.Paste")
			(net "P3V3_STBY")
			(options
				(clearance outline)
				(anchor circle)
			)
			(primitives
				(gr_poly
					(pts
						(arc
							(start -0.1778 0.2794)
							(mid -0.249642 0.249642)
							(end -0.2794 0.1778)
						)
						(arc
							(start -0.2794 -0.1778)
							(mid -0.249642 -0.249642)
							(end -0.1778 -0.2794)
						)
						(arc
							(start 0.1778 -0.2794)
							(mid 0.249642 -0.249642)
							(end 0.2794 -0.1778)
						)
						(arc
							(start 0.2794 0.1778)
							(mid 0.249642 0.249642)
							(end 0.1778 0.2794)
						)
					)
					(width 0)
					(fill yes)
				)
			)
		)
		(pad "2" smd custom
			(at 0 0.4445 270)
			(size 0.1397 0.1397)
			(layers "B.Cu" "B.Mask" "B.Paste")
			(net "FM_ALL_WAKE_N")
			(options
				(clearance outline)
				(anchor circle)
			)
			(primitives
				(gr_poly
					(pts
						(arc
							(start -0.1778 0.2794)
							(mid -0.249642 0.249642)
							(end -0.2794 0.1778)
						)
						(arc
							(start -0.2794 -0.1778)
							(mid -0.249642 -0.249642)
							(end -0.1778 -0.2794)
						)
						(arc
							(start 0.1778 -0.2794)
							(mid 0.249642 -0.249642)
							(end 0.2794 -0.1778)
						)
						(arc
							(start 0.2794 0.1778)
							(mid 0.249642 0.249642)
							(end 0.1778 0.2794)
						)
					)
					(width 0)
					(fill yes)
				)
			)
		)
	)
	(footprint ""
		(layer "B.Cu")
		(at 53.80228 -165.01618 90)
		(property "Reference" "T1D11"
			(at 0 0 90)
			(layer "B.SilkS")
			(hide yes)
			(effects
				(font
					(size 1.27 1.27)
				)
				(justify mirror)
			)
		)
		(property "Value" "*"
			(at 3.4036 -4.46405 90)
			(unlocked yes)
			(layer "B.Fab")
			(hide yes)
			(effects
				(font
					(size 0.889 0.889)
					(thickness 0.1524)
				)
				(justify mirror)
			)
		)
		(property "Device Type" "TEST-PAD-12P-1-GP-U_DISCRET-GBA"
			(at 3.4036 -5.98805 90)
			(unlocked yes)
			(layer "B.Fab")
			(hide yes)
			(effects
				(font
					(size 0.889 0.889)
					(thickness 0.1524)
				)
				(justify mirror)
			)
		)
		(duplicate_pad_numbers_are_jumpers no)
		(fp_line
			(start 2.3876 -4.826)
			(end -2.3622 -4.826)
			(stroke
				(width 0.1524)
				(type default)
			)
			(layer "B.SilkS")
		)
		(fp_line
			(start -2.3622 -4.826)
			(end -2.3622 3.4798)
			(stroke
				(width 0.1524)
				(type default)
			)
			(layer "B.SilkS")
		)
		(fp_line
			(start 2.3876 3.4798)
			(end 2.3876 -4.826)
			(stroke
				(width 0.1524)
				(type default)
			)
			(layer "B.SilkS")
		)
		(fp_line
			(start -2.3622 3.4798)
			(end 2.3876 3.4798)
			(stroke
				(width 0.1524)
				(type default)
			)
			(layer "B.SilkS")
		)
		(fp_rect
			(start 2.6416 3.7338)
			(end -2.6162 -5.08)
			(stroke
				(width 0)
				(type default)
			)
			(fill no)
			(layer "B.CrtYd")
		)
		(fp_rect
			(start 2.6416 3.7338)
			(end -2.6162 -5.08)
			(stroke
				(width 0)
				(type default)
			)
			(fill no)
			(layer "B.Fab")
		)
		(pad "1" smd circle
			(at -0.496824 -1.301496 270)
			(size 0.6604 0.6604)
			(layers "B.Cu" "B.Mask" "B.Paste")
			(net "L14_85OHM_5INCH_DP")
		)
		(pad "2" smd circle
			(at 0.503936 -1.301496 270)
			(size 0.6604 0.6604)
			(layers "B.Cu" "B.Mask" "B.Paste")
			(net "L14_85OHM_5INCH_DN")
		)
		(pad "3" smd custom
			(at 0.00889 0.370078 270)
			(size 0.74295 0.74295)
			(layers "B.Cu" "B.Mask" "B.Paste")
			(net "GND")
			(options
				(clearance outline)
				(anchor circle)
			)
			(primitives
				(gr_poly
					(pts
						(xy -2.1209 -1.4859) (xy 2.1209 -1.4859) (xy 2.1209 1.4859) (xy 1.08585 1.4859) (xy 1.08585 0.4699)
						(xy -1.08585 0.4699) (xy -1.08585 1.4859) (xy -2.1209 1.4859)
					)
					(width 0)
					(fill yes)
				)
			)
		)
		(pad "4" thru_hole circle
			(at -1.266444 -3.851656 270)
			(size 1.4478 1.4478)
			(drill 1.0414)
			(layers "*.Cu" "*.Mask")
			(remove_unused_layers no)
			(net "GND")
			(clearance 0.1524)
			(thermal_gap 0.1524)
		)
		(pad "5" thru_hole circle
			(at 1.273556 -3.851656 270)
			(size 1.4478 1.4478)
			(drill 1.0414)
			(layers "*.Cu" "*.Mask")
			(remove_unused_layers no)
			(net "GND")
			(clearance 0.1524)
			(thermal_gap 0.1524)
		)
		(pad "6" thru_hole circle
			(at -1.266444 2.498344 270)
			(size 1.4478 1.4478)
			(drill 1.0414)
			(layers "*.Cu" "*.Mask")
			(remove_unused_layers no)
			(net "GND")
			(clearance 0.1524)
			(thermal_gap 0.1524)
		)
		(pad "7" thru_hole circle
			(at 1.273556 2.498344 270)
			(size 1.4478 1.4478)
			(drill 1.0414)
			(layers "*.Cu" "*.Mask")
			(remove_unused_layers no)
			(net "GND")
			(clearance 0.1524)
			(thermal_gap 0.1524)
		)
		(pad "8" thru_hole circle
			(at -1.27 -0.4572 270)
			(size 0.7112 0.7112)
			(drill 0.4064)
			(layers "*.Cu" "*.Mask")
			(remove_unused_layers no)
			(net "GND")
			(clearance 0.1016)
			(thermal_gap 0.1016)
		)
		(pad "9" thru_hole circle
			(at -1.27 0.762 270)
			(size 0.7112 0.7112)
			(drill 0.4064)
			(layers "*.Cu" "*.Mask")
			(remove_unused_layers no)
			(net "GND")
			(clearance 0.1016)
			(thermal_gap 0.1016)
		)
		(pad "10" thru_hole circle
			(at 0.0254 0.762 270)
			(size 0.7112 0.7112)
			(drill 0.4064)
			(layers "*.Cu" "*.Mask")
			(remove_unused_layers no)
			(net "GND")
			(clearance 0.1016)
			(thermal_gap 0.1016)
		)
		(pad "11" thru_hole circle
			(at 1.27 0.762 270)
			(size 0.7112 0.7112)
			(drill 0.4064)
			(layers "*.Cu" "*.Mask")
			(remove_unused_layers no)
			(net "GND")
			(clearance 0.1016)
			(thermal_gap 0.1016)
		)
		(pad "12" thru_hole circle
			(at 1.27 -0.4572 270)
			(size 0.7112 0.7112)
			(drill 0.4064)
			(layers "*.Cu" "*.Mask")
			(remove_unused_layers no)
			(net "GND")
			(clearance 0.1016)
			(thermal_gap 0.1016)
		)
	)
	(footprint ""
		(layer "B.Cu")
		(at 117.221 -77.216 -90)
		(property "Reference" "R7P11"
			(at 0 0 90)
			(layer "B.SilkS")
			(hide yes)
			(effects
				(font
					(size 1.27 1.27)
				)
				(justify mirror)
			)
		)
		(property "Value" ""
			(at 0 0 90)
			(layer "B.Fab")
			(effects
				(font
					(size 1.27 1.27)
				)
				(justify mirror)
			)
		)
		(duplicate_pad_numbers_are_jumpers no)
		(fp_poly
			(pts
				(xy 0.2794 -0.1016) (xy -0.2794 -0.1016) (xy -0.2794 0.9906) (xy 0.2794 0.9906)
			)
			(stroke
				(width 0)
				(type default)
			)
			(fill no)
			(layer "B.CrtYd")
		)
		(fp_line
			(start -0.2794 0.9906)
			(end -0.2794 -0.1016)
			(stroke
				(width 0.1)
				(type default)
			)
			(layer "B.Fab")
		)
		(fp_line
			(start 0.2794 0.9906)
			(end -0.2794 0.9906)
			(stroke
				(width 0.1)
				(type default)
			)
			(layer "B.Fab")
		)
		(fp_line
			(start -0.2794 -0.1016)
			(end 0.2794 -0.1016)
			(stroke
				(width 0.1)
				(type default)
			)
			(layer "B.Fab")
		)
		(fp_line
			(start 0.2794 -0.1016)
			(end 0.2794 0.9906)
			(stroke
				(width 0.1)
				(type default)
			)
			(layer "B.Fab")
		)
		(pad "1" smd rect
			(at 0 0 90)
			(size 0.508 0.508)
			(layers "B.Cu" "B.Mask" "B.Paste")
			(net "A_CPU1_UPI2_RBIAS")
		)
		(pad "2" smd rect
			(at 0 0.889 90)
			(size 0.508 0.508)
			(layers "B.Cu" "B.Mask" "B.Paste")
			(net "GND")
		)
		(zone
			(layer "B.Cu")
			(hatch none 0.5)
			(connect_pads
				(clearance 0)
			)
			(min_thickness 0.25)
			(keepout
				(tracks not_allowed)
				(vias allowed)
				(pads allowed)
				(copperpour not_allowed)
				(footprints allowed)
			)
			(placement
				(enabled no)
				(sheetname "")
			)
			(fill
				(thermal_gap 0.5)
				(thermal_bridge_width 0.5)
				(island_removal_mode 0)
			)
			(polygon
				(pts
					(xy 116.586 -76.962) (xy 116.586 -77.47) (xy 116.967 -77.47) (xy 116.967 -76.962)
				)
			)
		)
		(zone
			(layer "B.Cu")
			(hatch none 0.5)
			(connect_pads
				(clearance 0)
			)
			(min_thickness 0.25)
			(keepout
				(tracks allowed)
				(vias not_allowed)
				(pads allowed)
				(copperpour not_allowed)
				(footprints allowed)
			)
			(placement
				(enabled no)
				(sheetname "")
			)
			(fill
				(thermal_gap 0.5)
				(thermal_bridge_width 0.5)
				(island_removal_mode 0)
			)
			(polygon
				(pts
					(xy 116.967 -76.962) (xy 116.967 -77.47) (xy 116.586 -77.47) (xy 116.586 -76.962)
				)
			)
		)
	)
	(footprint ""
		(layer "B.Cu")
		(at 451.517512 -15.84833 -90)
		(property "Reference" "CR3W1"
			(at -1.06934 -0.39116 0)
			(unlocked yes)
			(layer "B.SilkS")
			(effects
				(font
					(size 0.4064 0.254)
					(thickness 0.1524)
				)
				(justify left mirror)
			)
		)
		(property "Value" ""
			(at 0 0 90)
			(layer "B.Fab")
			(effects
				(font
					(size 1.27 1.27)
				)
				(justify mirror)
			)
		)
		(duplicate_pad_numbers_are_jumpers no)
		(fp_line
			(start 1.335278 2.576068)
			(end 1.335278 1.664462)
			(stroke
				(width 0.1524)
				(type default)
			)
			(layer "B.SilkS")
		)
		(fp_line
			(start 0.854456 1.664462)
			(end 1.335278 1.664462)
			(stroke
				(width 0.1524)
				(type default)
			)
			(layer "B.SilkS")
		)
		(fp_line
			(start 1.335278 1.664462)
			(end 1.8161 1.664462)
			(stroke
				(width 0.1524)
				(type default)
			)
			(layer "B.SilkS")
		)
		(fp_line
			(start 1.8161 1.664462)
			(end 1.335278 0.831596)
			(stroke
				(width 0.1524)
				(type default)
			)
			(layer "B.SilkS")
		)
		(fp_line
			(start 0.854456 0.831596)
			(end 1.8161 0.831596)
			(stroke
				(width 0.1524)
				(type default)
			)
			(layer "B.SilkS")
		)
		(fp_line
			(start 1.335278 0.831596)
			(end 0.854456 1.664462)
			(stroke
				(width 0.1524)
				(type default)
			)
			(layer "B.SilkS")
		)
		(fp_line
			(start 1.335278 -0.291846)
			(end 1.335278 0.831596)
			(stroke
				(width 0.1524)
				(type default)
			)
			(layer "B.SilkS")
		)
		(fp_poly
			(pts
				(xy 0.67437 0.24384) (xy 0.67437 2.04216) (xy -0.67437 2.04216) (xy -0.67437 0.24384)
			)
			(stroke
				(width 0)
				(type default)
			)
			(fill no)
			(layer "B.CrtYd")
		)
		(fp_line
			(start -0.67437 2.04216)
			(end -0.67437 0.24384)
			(stroke
				(width 0.1)
				(type default)
			)
			(layer "B.Fab")
		)
		(fp_line
			(start 0.67437 2.04216)
			(end -0.67437 2.04216)
			(stroke
				(width 0.1)
				(type default)
			)
			(layer "B.Fab")
		)
		(fp_line
			(start 0.854456 1.664462)
			(end 1.8161 1.664462)
			(stroke
				(width 0.1)
				(type default)
			)
			(layer "B.Fab")
		)
		(fp_line
			(start 1.335278 1.664462)
			(end 1.335278 2.576068)
			(stroke
				(width 0.1)
				(type default)
			)
			(layer "B.Fab")
		)
		(fp_line
			(start 1.8161 1.664462)
			(end 1.335278 0.831596)
			(stroke
				(width 0.1)
				(type default)
			)
			(layer "B.Fab")
		)
		(fp_line
			(start 0.854456 0.831596)
			(end 1.8161 0.831596)
			(stroke
				(width 0.1)
				(type default)
			)
			(layer "B.Fab")
		)
		(fp_line
			(start 1.335278 0.831596)
			(end 0.854456 1.664462)
			(stroke
				(width 0.1)
				(type default)
			)
			(layer "B.Fab")
		)
		(fp_line
			(start 1.335278 0.831596)
			(end 1.335278 -0.291846)
			(stroke
				(width 0.1)
				(type default)
			)
			(layer "B.Fab")
		)
		(fp_line
			(start -0.67437 0.24384)
			(end 0.67437 0.24384)
			(stroke
				(width 0.1)
				(type default)
			)
			(layer "B.Fab")
		)
		(fp_line
			(start 0.67437 0.24384)
			(end 0.67437 2.04216)
			(stroke
				(width 0.1)
				(type default)
			)
			(layer "B.Fab")
		)
		(pad "1" smd rect
			(at 0 0 90)
			(size 0.4064 1.016)
			(layers "B.Cu" "B.Mask" "B.Paste")
			(net "BMC_SELF_HW_D_RST")
		)
		(pad "2" smd rect
			(at 0 2.286 90)
			(size 0.4064 1.016)
			(layers "B.Cu" "B.Mask" "B.Paste")
			(net "BMC_SELF_HW_RST")
		)
	)
	(footprint ""
		(layer "B.Cu")
		(at 174.6123 -3.683 -90)
		(property "Reference" "R6U7"
			(at 0 0 90)
			(layer "B.SilkS")
			(hide yes)
			(effects
				(font
					(size 1.27 1.27)
				)
				(justify mirror)
			)
		)
		(property "Value" ""
			(at 0 0 90)
			(layer "B.Fab")
			(effects
				(font
					(size 1.27 1.27)
				)
				(justify mirror)
			)
		)
		(duplicate_pad_numbers_are_jumpers no)
		(fp_rect
			(start -0.2794 -0.1016)
			(end 0.2794 0.9906)
			(stroke
				(width 0)
				(type default)
			)
			(fill no)
			(layer "B.CrtYd")
		)
		(fp_line
			(start -0.2794 0.9906)
			(end -0.2794 -0.1016)
			(stroke
				(width 0.1)
				(type default)
			)
			(layer "B.Fab")
		)
		(fp_line
			(start 0.2794 0.9906)
			(end -0.2794 0.9906)
			(stroke
				(width 0.1)
				(type default)
			)
			(layer "B.Fab")
		)
		(fp_line
			(start -0.2794 -0.1016)
			(end 0.2794 -0.1016)
			(stroke
				(width 0.1)
				(type default)
			)
			(layer "B.Fab")
		)
		(fp_line
			(start 0.2794 -0.1016)
			(end 0.2794 0.9906)
			(stroke
				(width 0.1)
				(type default)
			)
			(layer "B.Fab")
		)
		(pad "1" smd rect
			(at 0 0 90)
			(size 0.508 0.508)
			(layers "B.Cu" "B.Mask" "B.Paste")
			(net "P3V3")
		)
		(pad "2" smd rect
			(at 0 0.889 90)
			(size 0.508 0.508)
			(layers "B.Cu" "B.Mask" "B.Paste")
			(net "VR_PVTT_GHJ_BIAS")
		)
		(zone
			(layer "B.Cu")
			(hatch none 0.5)
			(connect_pads
				(clearance 0)
			)
			(min_thickness 0.25)
			(keepout
				(tracks not_allowed)
				(vias allowed)
				(pads allowed)
				(copperpour not_allowed)
				(footprints allowed)
			)
			(placement
				(enabled no)
				(sheetname "")
			)
			(fill
				(thermal_gap 0.5)
				(thermal_bridge_width 0.5)
				(island_removal_mode 0)
			)
			(polygon
				(pts
					(xy 174.3583 -3.937) (xy 173.9773 -3.937) (xy 173.9773 -3.429) (xy 174.3583 -3.429)
				)
			)
		)
		(zone
			(layer "B.Cu")
			(hatch none 0.5)
			(connect_pads
				(clearance 0)
			)
			(min_thickness 0.25)
			(keepout
				(tracks allowed)
				(vias not_allowed)
				(pads allowed)
				(copperpour not_allowed)
				(footprints allowed)
			)
			(placement
				(enabled no)
				(sheetname "")
			)
			(fill
				(thermal_gap 0.5)
				(thermal_bridge_width 0.5)
				(island_removal_mode 0)
			)
			(polygon
				(pts
					(xy 174.3583 -3.937) (xy 173.9773 -3.937) (xy 173.9773 -3.429) (xy 174.3583 -3.429)
				)
			)
		)
	)
	(footprint ""
		(layer "B.Cu")
		(at 392.43 -87.4395)
		(property "Reference" "R8D20"
			(at 0.8382 -0.67818 0)
			(unlocked yes)
			(layer "B.SilkS")
			(effects
				(font
					(size 0.4064 0.254)
					(thickness 0.1524)
				)
				(justify left mirror)
			)
		)
		(property "Value" ""
			(at 0 0 0)
			(layer "B.Fab")
			(effects
				(font
					(size 1.27 1.27)
				)
				(justify mirror)
			)
		)
		(duplicate_pad_numbers_are_jumpers no)
		(fp_poly
			(pts
				(xy 0.2794 -0.1016) (xy -0.2794 -0.1016) (xy -0.2794 0.9906) (xy 0.2794 0.9906)
			)
			(stroke
				(width 0)
				(type default)
			)
			(fill no)
			(layer "B.CrtYd")
		)
		(fp_line
			(start -0.2794 -0.1016)
			(end 0.2794 -0.1016)
			(stroke
				(width 0.1)
				(type default)
			)
			(layer "B.Fab")
		)
		(fp_line
			(start -0.2794 0.9906)
			(end -0.2794 -0.1016)
			(stroke
				(width 0.1)
				(type default)
			)
			(layer "B.Fab")
		)
		(fp_line
			(start 0.2794 -0.1016)
			(end 0.2794 0.9906)
			(stroke
				(width 0.1)
				(type default)
			)
			(layer "B.Fab")
		)
		(fp_line
			(start 0.2794 0.9906)
			(end -0.2794 0.9906)
			(stroke
				(width 0.1)
				(type default)
			)
			(layer "B.Fab")
		)
		(pad "1" smd rect
			(at 0 0 180)
			(size 0.508 0.508)
			(layers "B.Cu" "B.Mask" "B.Paste")
			(net "SGPIO_PCH_SATA_LOAD")
		)
		(pad "2" smd rect
			(at 0 0.889 180)
			(size 0.508 0.508)
			(layers "B.Cu" "B.Mask" "B.Paste")
			(net "SGPIO_PCH_SATA_LOAD_R")
		)
		(zone
			(layer "B.Cu")
			(hatch none 0.5)
			(connect_pads
				(clearance 0)
			)
			(min_thickness 0.25)
			(keepout
				(tracks allowed)
				(vias not_allowed)
				(pads allowed)
				(copperpour not_allowed)
				(footprints allowed)
			)
			(placement
				(enabled no)
				(sheetname "")
			)
			(fill
				(thermal_gap 0.5)
				(thermal_bridge_width 0.5)
				(island_removal_mode 0)
			)
			(polygon
				(pts
					(xy 392.684 -87.1855) (xy 392.176 -87.1855) (xy 392.176 -86.8045) (xy 392.684 -86.8045)
				)
			)
		)
		(zone
			(layer "B.Cu")
			(hatch none 0.5)
			(connect_pads
				(clearance 0)
			)
			(min_thickness 0.25)
			(keepout
				(tracks not_allowed)
				(vias allowed)
				(pads allowed)
				(copperpour not_allowed)
				(footprints allowed)
			)
			(placement
				(enabled no)
				(sheetname "")
			)
			(fill
				(thermal_gap 0.5)
				(thermal_bridge_width 0.5)
				(island_removal_mode 0)
			)
			(polygon
				(pts
					(xy 392.684 -86.8045) (xy 392.176 -86.8045) (xy 392.176 -87.1855) (xy 392.684 -87.1855)
				)
			)
		)
	)
	(footprint ""
		(layer "B.Cu")
		(at 348.574614 -123.576842 -90)
		(property "Reference" "R774"
			(at 0.8382 -0.67818 270)
			(unlocked yes)
			(layer "B.SilkS")
			(effects
				(font
					(size 0.4064 0.254)
					(thickness 0.1524)
				)
				(justify left mirror)
			)
		)
		(property "Value" ""
			(at 0 0 90)
			(layer "B.Fab")
			(effects
				(font
					(size 1.27 1.27)
				)
				(justify mirror)
			)
		)
		(duplicate_pad_numbers_are_jumpers no)
		(fp_poly
			(pts
				(xy 0.2794 -0.1016) (xy -0.2794 -0.1016) (xy -0.2794 0.9906) (xy 0.2794 0.9906)
			)
			(stroke
				(width 0)
				(type default)
			)
			(fill no)
			(layer "B.CrtYd")
		)
		(fp_line
			(start -0.2794 0.9906)
			(end -0.2794 -0.1016)
			(stroke
				(width 0.1)
				(type default)
			)
			(layer "B.Fab")
		)
		(fp_line
			(start 0.2794 0.9906)
			(end -0.2794 0.9906)
			(stroke
				(width 0.1)
				(type default)
			)
			(layer "B.Fab")
		)
		(fp_line
			(start -0.2794 -0.1016)
			(end 0.2794 -0.1016)
			(stroke
				(width 0.1)
				(type default)
			)
			(layer "B.Fab")
		)
		(fp_line
			(start 0.2794 -0.1016)
			(end 0.2794 0.9906)
			(stroke
				(width 0.1)
				(type default)
			)
			(layer "B.Fab")
		)
		(pad "1" smd rect
			(at 0 0 90)
			(size 0.508 0.508)
			(layers "B.Cu" "B.Mask" "B.Paste")
			(net "P3E_CPU0_PE1_PCH_RXP<13>")
		)
		(pad "2" smd rect
			(at 0 0.889 90)
			(size 0.508 0.508)
			(layers "B.Cu" "B.Mask" "B.Paste")
			(net "P3E_CPU0_PE1_PCH_CON_RXP<13>")
		)
		(zone
			(layer "B.Cu")
			(hatch none 0.5)
			(connect_pads
				(clearance 0)
			)
			(min_thickness 0.25)
			(keepout
				(tracks not_allowed)
				(vias allowed)
				(pads allowed)
				(copperpour not_allowed)
				(footprints allowed)
			)
			(placement
				(enabled no)
				(sheetname "")
			)
			(fill
				(thermal_gap 0.5)
				(thermal_bridge_width 0.5)
				(island_removal_mode 0)
			)
			(polygon
				(pts
					(xy 347.939614 -123.322842) (xy 347.939614 -123.830842) (xy 348.320614 -123.830842) (xy 348.320614 -123.322842)
				)
			)
		)
		(zone
			(layer "B.Cu")
			(hatch none 0.5)
			(connect_pads
				(clearance 0)
			)
			(min_thickness 0.25)
			(keepout
				(tracks allowed)
				(vias not_allowed)
				(pads allowed)
				(copperpour not_allowed)
				(footprints allowed)
			)
			(placement
				(enabled no)
				(sheetname "")
			)
			(fill
				(thermal_gap 0.5)
				(thermal_bridge_width 0.5)
				(island_removal_mode 0)
			)
			(polygon
				(pts
					(xy 348.320614 -123.322842) (xy 348.320614 -123.830842) (xy 347.939614 -123.830842) (xy 347.939614 -123.322842)
				)
			)
		)
	)
	(footprint ""
		(layer "B.Cu")
		(at 401.472146 -40.598852 90)
		(property "Reference" "R2U4"
			(at 0 0 90)
			(layer "B.SilkS")
			(hide yes)
			(effects
				(font
					(size 1.27 1.27)
				)
				(justify mirror)
			)
		)
		(property "Value" ""
			(at 0 0 90)
			(layer "B.Fab")
			(effects
				(font
					(size 1.27 1.27)
				)
				(justify mirror)
			)
		)
		(duplicate_pad_numbers_are_jumpers no)
		(fp_poly
			(pts
				(xy 0.2794 -0.1016) (xy -0.2794 -0.1016) (xy -0.2794 0.9906) (xy 0.2794 0.9906)
			)
			(stroke
				(width 0)
				(type default)
			)
			(fill no)
			(layer "B.CrtYd")
		)
		(fp_line
			(start 0.2794 -0.1016)
			(end 0.2794 0.9906)
			(stroke
				(width 0.1)
				(type default)
			)
			(layer "B.Fab")
		)
		(fp_line
			(start -0.2794 -0.1016)
			(end 0.2794 -0.1016)
			(stroke
				(width 0.1)
				(type default)
			)
			(layer "B.Fab")
		)
		(fp_line
			(start 0.2794 0.9906)
			(end -0.2794 0.9906)
			(stroke
				(width 0.1)
				(type default)
			)
			(layer "B.Fab")
		)
		(fp_line
			(start -0.2794 0.9906)
			(end -0.2794 -0.1016)
			(stroke
				(width 0.1)
				(type default)
			)
			(layer "B.Fab")
		)
		(pad "1" smd rect
			(at 0 0 270)
			(size 0.508 0.508)
			(layers "B.Cu" "B.Mask" "B.Paste")
			(net "P3V3_STBY")
		)
		(pad "2" smd rect
			(at 0 0.889 270)
			(size 0.508 0.508)
			(layers "B.Cu" "B.Mask" "B.Paste")
			(net "FM_CPLD_BMC_PWRDN_N")
		)
		(zone
			(layer "B.Cu")
			(hatch none 0.5)
			(connect_pads
				(clearance 0)
			)
			(min_thickness 0.25)
			(keepout
				(tracks allowed)
				(vias not_allowed)
				(pads allowed)
				(copperpour not_allowed)
				(footprints allowed)
			)
			(placement
				(enabled no)
				(sheetname "")
			)
			(fill
				(thermal_gap 0.5)
				(thermal_bridge_width 0.5)
				(island_removal_mode 0)
			)
			(polygon
				(pts
					(xy 401.726146 -40.852852) (xy 401.726146 -40.344852) (xy 402.107146 -40.344852) (xy 402.107146 -40.852852)
				)
			)
		)
		(zone
			(layer "B.Cu")
			(hatch none 0.5)
			(connect_pads
				(clearance 0)
			)
			(min_thickness 0.25)
			(keepout
				(tracks not_allowed)
				(vias allowed)
				(pads allowed)
				(copperpour not_allowed)
				(footprints allowed)
			)
			(placement
				(enabled no)
				(sheetname "")
			)
			(fill
				(thermal_gap 0.5)
				(thermal_bridge_width 0.5)
				(island_removal_mode 0)
			)
			(polygon
				(pts
					(xy 402.107146 -40.852852) (xy 402.107146 -40.344852) (xy 401.726146 -40.344852) (xy 401.726146 -40.852852)
				)
			)
		)
	)
	(footprint ""
		(layer "B.Cu")
		(at 348.1578 -98.2218 -90)
		(property "Reference" "C3N34"
			(at 0 0 90)
			(layer "B.SilkS")
			(hide yes)
			(effects
				(font
					(size 1.27 1.27)
				)
				(justify mirror)
			)
		)
		(property "Value" ""
			(at 0 0 90)
			(layer "B.Fab")
			(effects
				(font
					(size 1.27 1.27)
				)
				(justify mirror)
			)
		)
		(duplicate_pad_numbers_are_jumpers no)
		(fp_poly
			(pts
				(xy 0.7239 -0.2159) (xy -0.7239 -0.2159) (xy -0.7239 1.9939) (xy 0.7239 1.9939)
			)
			(stroke
				(width 0)
				(type default)
			)
			(fill no)
			(layer "B.CrtYd")
		)
		(fp_line
			(start -0.7239 1.9939)
			(end -0.7239 -0.2159)
			(stroke
				(width 0.1)
				(type default)
			)
			(layer "B.Fab")
		)
		(fp_line
			(start 0.7239 1.9939)
			(end -0.7239 1.9939)
			(stroke
				(width 0.1)
				(type default)
			)
			(layer "B.Fab")
		)
		(fp_line
			(start -0.7239 -0.2159)
			(end 0.7239 -0.2159)
			(stroke
				(width 0.1)
				(type default)
			)
			(layer "B.Fab")
		)
		(fp_line
			(start 0.7239 -0.2159)
			(end 0.7239 1.9939)
			(stroke
				(width 0.1)
				(type default)
			)
			(layer "B.Fab")
		)
		(pad "1" smd rect
			(at 0 0 90)
			(size 1.27 1.016)
			(layers "B.Cu" "B.Mask" "B.Paste")
			(net "VR_FET_SW_P12V_STBY_PVCCIO_CPU0")
		)
		(pad "2" smd rect
			(at 0 1.778 90)
			(size 1.27 1.016)
			(layers "B.Cu" "B.Mask" "B.Paste")
			(net "GND")
		)
		(zone
			(layer "B.Cu")
			(hatch none 0.5)
			(connect_pads
				(clearance 0)
			)
			(min_thickness 0.25)
			(keepout
				(tracks not_allowed)
				(vias allowed)
				(pads allowed)
				(copperpour not_allowed)
				(footprints allowed)
			)
			(placement
				(enabled no)
				(sheetname "")
			)
			(fill
				(thermal_gap 0.5)
				(thermal_bridge_width 0.5)
				(island_removal_mode 0)
			)
			(polygon
				(pts
					(xy 347.6498 -97.5868) (xy 347.6498 -98.8568) (xy 346.8878 -98.8568) (xy 346.8878 -97.5868)
				)
			)
		)
	)
	(footprint ""
		(layer "B.Cu")
		(at 390.13765 -111.05515 180)
		(property "Reference" "C2N3"
			(at 0 0 0)
			(layer "B.SilkS")
			(hide yes)
			(effects
				(font
					(size 1.27 1.27)
				)
				(justify mirror)
			)
		)
		(property "Value" ""
			(at 0 0 0)
			(layer "B.Fab")
			(effects
				(font
					(size 1.27 1.27)
				)
				(justify mirror)
			)
		)
		(duplicate_pad_numbers_are_jumpers no)
		(fp_rect
			(start 0.2794 0.9144)
			(end -0.2794 -0.1143)
			(stroke
				(width 0)
				(type default)
			)
			(fill no)
			(layer "B.CrtYd")
		)
		(fp_line
			(start 0.2794 0.9144)
			(end 0.2794 -0.1143)
			(stroke
				(width 0.1)
				(type default)
			)
			(layer "B.Fab")
		)
		(fp_line
			(start 0.2794 -0.1143)
			(end -0.2794 -0.1143)
			(stroke
				(width 0.1)
				(type default)
			)
			(layer "B.Fab")
		)
		(fp_line
			(start -0.2794 0.9144)
			(end 0.2794 0.9144)
			(stroke
				(width 0.1)
				(type default)
			)
			(layer "B.Fab")
		)
		(fp_line
			(start -0.2794 -0.1143)
			(end -0.2794 0.9144)
			(stroke
				(width 0.1)
				(type default)
			)
			(layer "B.Fab")
		)
		(pad "1" smd custom
			(at 0 0 90)
			(size 0.10414 0.10414)
			(layers "B.Cu" "B.Mask" "B.Paste")
			(net "PVNN_PCH_STBY")
			(options
				(clearance outline)
				(anchor circle)
			)
			(primitives
				(gr_poly
					(pts
						(xy -0.20828 -0.08636) (xy -0.20828 0.08636) (xy -0.08636 0.20828) (xy 0.086614 0.20828) (xy 0.20828 0.086614)
						(xy 0.20828 -0.08636) (xy 0.08636 -0.20828) (xy -0.08636 -0.20828)
					)
					(width 0)
					(fill yes)
				)
			)
		)
		(pad "2" smd custom
			(at 0 0.8001 90)
			(size 0.10414 0.10414)
			(layers "B.Cu" "B.Mask" "B.Paste")
			(net "GND")
			(options
				(clearance outline)
				(anchor circle)
			)
			(primitives
				(gr_poly
					(pts
						(xy -0.20828 -0.08636) (xy -0.20828 0.08636) (xy -0.08636 0.20828) (xy 0.086614 0.20828) (xy 0.20828 0.086614)
						(xy 0.20828 -0.08636) (xy 0.08636 -0.20828) (xy -0.08636 -0.20828)
					)
					(width 0)
					(fill yes)
				)
			)
		)
		(zone
			(layer "B.Cu")
			(hatch none 0.5)
			(connect_pads
				(clearance 0)
			)
			(min_thickness 0.25)
			(keepout
				(tracks allowed)
				(vias not_allowed)
				(pads allowed)
				(copperpour not_allowed)
				(footprints allowed)
			)
			(placement
				(enabled no)
				(sheetname "")
			)
			(fill
				(thermal_gap 0.5)
				(thermal_bridge_width 0.5)
				(island_removal_mode 0)
			)
			(polygon
				(pts
					(xy 390.05002 -111.2647) (xy 390.05002 -111.6457) (xy 390.22528 -111.6457) (xy 390.225534 -111.2647)
				)
			)
		)
		(zone
			(layer "B.Cu")
			(hatch none 0.5)
			(connect_pads
				(clearance 0)
			)
			(min_thickness 0.25)
			(keepout
				(tracks not_allowed)
				(vias allowed)
				(pads allowed)
				(copperpour not_allowed)
				(footprints allowed)
			)
			(placement
				(enabled no)
				(sheetname "")
			)
			(fill
				(thermal_gap 0.5)
				(thermal_bridge_width 0.5)
				(island_removal_mode 0)
			)
			(polygon
				(pts
					(xy 390.05002 -111.2647) (xy 390.05002 -111.6457) (xy 390.22528 -111.6457) (xy 390.225534 -111.2647)
				)
			)
		)
	)
	(footprint ""
		(layer "B.Cu")
		(at 348.361 -133.604 180)
		(property "Reference" "C3M9"
			(at 0 0 0)
			(layer "B.SilkS")
			(hide yes)
			(effects
				(font
					(size 1.27 1.27)
				)
				(justify mirror)
			)
		)
		(property "Value" ""
			(at 0 0 0)
			(layer "B.Fab")
			(effects
				(font
					(size 1.27 1.27)
				)
				(justify mirror)
			)
		)
		(duplicate_pad_numbers_are_jumpers no)
		(fp_poly
			(pts
				(xy -0.3048 -0.1016) (xy -0.3048 0.9906) (xy 0.3048 0.9906) (xy 0.3048 -0.1016)
			)
			(stroke
				(width 0)
				(type default)
			)
			(fill no)
			(layer "B.CrtYd")
		)
		(fp_line
			(start 0.3048 0.9906)
			(end -0.3048 0.9906)
			(stroke
				(width 0.1)
				(type default)
			)
			(layer "B.Fab")
		)
		(fp_line
			(start 0.3048 -0.1016)
			(end 0.3048 0.9906)
			(stroke
				(width 0.1)
				(type default)
			)
			(layer "B.Fab")
		)
		(fp_line
			(start -0.3048 0.9906)
			(end -0.3048 -0.1016)
			(stroke
				(width 0.1)
				(type default)
			)
			(layer "B.Fab")
		)
		(fp_line
			(start -0.3048 -0.1016)
			(end 0.3048 -0.1016)
			(stroke
				(width 0.1)
				(type default)
			)
			(layer "B.Fab")
		)
		(pad "1" smd rect
			(at 0 0)
			(size 0.508 0.508)
			(layers "B.Cu" "B.Mask" "B.Paste")
			(net "VR_FET_SW_P12V_STBY_PVPP_DEF")
		)
		(pad "2" smd rect
			(at 0 0.889)
			(size 0.508 0.508)
			(layers "B.Cu" "B.Mask" "B.Paste")
			(net "GND")
		)
		(zone
			(layer "B.Cu")
			(hatch none 0.5)
			(connect_pads
				(clearance 0)
			)
			(min_thickness 0.25)
			(keepout
				(tracks not_allowed)
				(vias allowed)
				(pads allowed)
				(copperpour not_allowed)
				(footprints allowed)
			)
			(placement
				(enabled no)
				(sheetname "")
			)
			(fill
				(thermal_gap 0.5)
				(thermal_bridge_width 0.5)
				(island_removal_mode 0)
			)
			(polygon
				(pts
					(xy 348.107 -134.239) (xy 348.615 -134.239) (xy 348.615 -133.858) (xy 348.107 -133.858)
				)
			)
		)
		(zone
			(layer "B.Cu")
			(hatch none 0.5)
			(connect_pads
				(clearance 0)
			)
			(min_thickness 0.25)
			(keepout
				(tracks allowed)
				(vias not_allowed)
				(pads allowed)
				(copperpour not_allowed)
				(footprints allowed)
			)
			(placement
				(enabled no)
				(sheetname "")
			)
			(fill
				(thermal_gap 0.5)
				(thermal_bridge_width 0.5)
				(island_removal_mode 0)
			)
			(polygon
				(pts
					(xy 348.107 -133.858) (xy 348.615 -133.858) (xy 348.615 -134.239) (xy 348.107 -134.239)
				)
			)
		)
	)
	(footprint ""
		(layer "B.Cu")
		(at 450.98335 -52.407058)
		(property "Reference" "C1R9"
			(at 0 0 0)
			(layer "B.SilkS")
			(hide yes)
			(effects
				(font
					(size 1.27 1.27)
				)
				(justify mirror)
			)
		)
		(property "Value" ""
			(at 0 0 0)
			(layer "B.Fab")
			(effects
				(font
					(size 1.27 1.27)
				)
				(justify mirror)
			)
		)
		(duplicate_pad_numbers_are_jumpers no)
		(fp_poly
			(pts
				(xy -0.3048 -0.1016) (xy -0.3048 0.9906) (xy 0.3048 0.9906) (xy 0.3048 -0.1016)
			)
			(stroke
				(width 0)
				(type default)
			)
			(fill no)
			(layer "B.CrtYd")
		)
		(fp_line
			(start -0.3048 -0.1016)
			(end 0.3048 -0.1016)
			(stroke
				(width 0.1)
				(type default)
			)
			(layer "B.Fab")
		)
		(fp_line
			(start -0.3048 0.9906)
			(end -0.3048 -0.1016)
			(stroke
				(width 0.1)
				(type default)
			)
			(layer "B.Fab")
		)
		(fp_line
			(start 0.3048 -0.1016)
			(end 0.3048 0.9906)
			(stroke
				(width 0.1)
				(type default)
			)
			(layer "B.Fab")
		)
		(fp_line
			(start 0.3048 0.9906)
			(end -0.3048 0.9906)
			(stroke
				(width 0.1)
				(type default)
			)
			(layer "B.Fab")
		)
		(pad "1" smd rect
			(at 0 0 180)
			(size 0.508 0.508)
			(layers "B.Cu" "B.Mask" "B.Paste")
			(net "P3E_CPU0_PE3_OCP_TXN<4>")
		)
		(pad "2" smd rect
			(at 0 0.889 180)
			(size 0.508 0.508)
			(layers "B.Cu" "B.Mask" "B.Paste")
			(net "P3E_OCP_CPU0_PE3_C_TXN<4>")
		)
		(zone
			(layer "B.Cu")
			(hatch none 0.5)
			(connect_pads
				(clearance 0)
			)
			(min_thickness 0.25)
			(keepout
				(tracks allowed)
				(vias not_allowed)
				(pads allowed)
				(copperpour not_allowed)
				(footprints allowed)
			)
			(placement
				(enabled no)
				(sheetname "")
			)
			(fill
				(thermal_gap 0.5)
				(thermal_bridge_width 0.5)
				(island_removal_mode 0)
			)
			(polygon
				(pts
					(xy 451.23735 -52.153058) (xy 450.72935 -52.153058) (xy 450.72935 -51.772058) (xy 451.23735 -51.772058)
				)
			)
		)
		(zone
			(layer "B.Cu")
			(hatch none 0.5)
			(connect_pads
				(clearance 0)
			)
			(min_thickness 0.25)
			(keepout
				(tracks not_allowed)
				(vias allowed)
				(pads allowed)
				(copperpour not_allowed)
				(footprints allowed)
			)
			(placement
				(enabled no)
				(sheetname "")
			)
			(fill
				(thermal_gap 0.5)
				(thermal_bridge_width 0.5)
				(island_removal_mode 0)
			)
			(polygon
				(pts
					(xy 451.23735 -51.772058) (xy 450.72935 -51.772058) (xy 450.72935 -52.153058) (xy 451.23735 -52.153058)
				)
			)
		)
	)
	(footprint ""
		(layer "B.Cu")
		(at 354.543614 -122.662442 -90)
		(property "Reference" "C3M3"
			(at 0 0 90)
			(layer "B.SilkS")
			(hide yes)
			(effects
				(font
					(size 1.27 1.27)
				)
				(justify mirror)
			)
		)
		(property "Value" ""
			(at 0 0 90)
			(layer "B.Fab")
			(effects
				(font
					(size 1.27 1.27)
				)
				(justify mirror)
			)
		)
		(duplicate_pad_numbers_are_jumpers no)
		(fp_poly
			(pts
				(xy -0.3048 -0.1016) (xy -0.3048 0.9906) (xy 0.3048 0.9906) (xy 0.3048 -0.1016)
			)
			(stroke
				(width 0)
				(type default)
			)
			(fill no)
			(layer "B.CrtYd")
		)
		(fp_line
			(start -0.3048 0.9906)
			(end -0.3048 -0.1016)
			(stroke
				(width 0.1)
				(type default)
			)
			(layer "B.Fab")
		)
		(fp_line
			(start 0.3048 0.9906)
			(end -0.3048 0.9906)
			(stroke
				(width 0.1)
				(type default)
			)
			(layer "B.Fab")
		)
		(fp_line
			(start -0.3048 -0.1016)
			(end 0.3048 -0.1016)
			(stroke
				(width 0.1)
				(type default)
			)
			(layer "B.Fab")
		)
		(fp_line
			(start 0.3048 -0.1016)
			(end 0.3048 0.9906)
			(stroke
				(width 0.1)
				(type default)
			)
			(layer "B.Fab")
		)
		(pad "1" smd rect
			(at 0 0 90)
			(size 0.508 0.508)
			(layers "B.Cu" "B.Mask" "B.Paste")
			(net "P3E_CPU0_PE1_PCH_R_RXP<12>")
		)
		(pad "2" smd rect
			(at 0 0.889 90)
			(size 0.508 0.508)
			(layers "B.Cu" "B.Mask" "B.Paste")
			(net "P3E_CPU0_PE1_PCH_RXP<12>")
		)
		(zone
			(layer "B.Cu")
			(hatch none 0.5)
			(connect_pads
				(clearance 0)
			)
			(min_thickness 0.25)
			(keepout
				(tracks not_allowed)
				(vias allowed)
				(pads allowed)
				(copperpour not_allowed)
				(footprints allowed)
			)
			(placement
				(enabled no)
				(sheetname "")
			)
			(fill
				(thermal_gap 0.5)
				(thermal_bridge_width 0.5)
				(island_removal_mode 0)
			)
			(polygon
				(pts
					(xy 353.908614 -122.408442) (xy 353.908614 -122.916442) (xy 354.289614 -122.916442) (xy 354.289614 -122.408442)
				)
			)
		)
		(zone
			(layer "B.Cu")
			(hatch none 0.5)
			(connect_pads
				(clearance 0)
			)
			(min_thickness 0.25)
			(keepout
				(tracks allowed)
				(vias not_allowed)
				(pads allowed)
				(copperpour not_allowed)
				(footprints allowed)
			)
			(placement
				(enabled no)
				(sheetname "")
			)
			(fill
				(thermal_gap 0.5)
				(thermal_bridge_width 0.5)
				(island_removal_mode 0)
			)
			(polygon
				(pts
					(xy 354.289614 -122.408442) (xy 354.289614 -122.916442) (xy 353.908614 -122.916442) (xy 353.908614 -122.408442)
				)
			)
		)
	)
	(footprint ""
		(layer "B.Cu")
		(at 100.863654 -77.82814)
		(property "Reference" "C8P17"
			(at 0 0 0)
			(layer "B.SilkS")
			(hide yes)
			(effects
				(font
					(size 1.27 1.27)
				)
				(justify mirror)
			)
		)
		(property "Value" ""
			(at 0 0 0)
			(layer "B.Fab")
			(effects
				(font
					(size 1.27 1.27)
				)
				(justify mirror)
			)
		)
		(duplicate_pad_numbers_are_jumpers no)
		(fp_poly
			(pts
				(xy 0.7239 -0.2159) (xy -0.7239 -0.2159) (xy -0.7239 1.9939) (xy 0.7239 1.9939)
			)
			(stroke
				(width 0)
				(type default)
			)
			(fill no)
			(layer "B.CrtYd")
		)
		(fp_line
			(start -0.7239 -0.2159)
			(end 0.7239 -0.2159)
			(stroke
				(width 0.1)
				(type default)
			)
			(layer "B.Fab")
		)
		(fp_line
			(start -0.7239 1.9939)
			(end -0.7239 -0.2159)
			(stroke
				(width 0.1)
				(type default)
			)
			(layer "B.Fab")
		)
		(fp_line
			(start 0.7239 -0.2159)
			(end 0.7239 1.9939)
			(stroke
				(width 0.1)
				(type default)
			)
			(layer "B.Fab")
		)
		(fp_line
			(start 0.7239 1.9939)
			(end -0.7239 1.9939)
			(stroke
				(width 0.1)
				(type default)
			)
			(layer "B.Fab")
		)
		(pad "1" smd rect
			(at 0 0 180)
			(size 1.27 1.016)
			(layers "B.Cu" "B.Mask" "B.Paste")
			(net "PVCCIN_CPU1")
		)
		(pad "2" smd rect
			(at 0 1.778 180)
			(size 1.27 1.016)
			(layers "B.Cu" "B.Mask" "B.Paste")
			(net "GND")
		)
		(zone
			(layer "B.Cu")
			(hatch none 0.5)
			(connect_pads
				(clearance 0)
			)
			(min_thickness 0.25)
			(keepout
				(tracks not_allowed)
				(vias allowed)
				(pads allowed)
				(copperpour not_allowed)
				(footprints allowed)
			)
			(placement
				(enabled no)
				(sheetname "")
			)
			(fill
				(thermal_gap 0.5)
				(thermal_bridge_width 0.5)
				(island_removal_mode 0)
			)
			(polygon
				(pts
					(xy 101.498654 -77.32014) (xy 100.228654 -77.32014) (xy 100.228654 -76.55814) (xy 101.498654 -76.55814)
				)
			)
		)
	)
	(footprint ""
		(layer "B.Cu")
		(at 359.84688 -77.923136)
		(property "Reference" "C3P38"
			(at 0 0 0)
			(layer "B.SilkS")
			(hide yes)
			(effects
				(font
					(size 1.27 1.27)
				)
				(justify mirror)
			)
		)
		(property "Value" ""
			(at 0 0 0)
			(layer "B.Fab")
			(effects
				(font
					(size 1.27 1.27)
				)
				(justify mirror)
			)
		)
		(duplicate_pad_numbers_are_jumpers no)
		(fp_poly
			(pts
				(xy -0.3048 -0.1016) (xy -0.3048 0.9906) (xy 0.3048 0.9906) (xy 0.3048 -0.1016)
			)
			(stroke
				(width 0)
				(type default)
			)
			(fill no)
			(layer "B.CrtYd")
		)
		(fp_line
			(start -0.3048 -0.1016)
			(end 0.3048 -0.1016)
			(stroke
				(width 0.1)
				(type default)
			)
			(layer "B.Fab")
		)
		(fp_line
			(start -0.3048 0.9906)
			(end -0.3048 -0.1016)
			(stroke
				(width 0.1)
				(type default)
			)
			(layer "B.Fab")
		)
		(fp_line
			(start 0.3048 -0.1016)
			(end 0.3048 0.9906)
			(stroke
				(width 0.1)
				(type default)
			)
			(layer "B.Fab")
		)
		(fp_line
			(start 0.3048 0.9906)
			(end -0.3048 0.9906)
			(stroke
				(width 0.1)
				(type default)
			)
			(layer "B.Fab")
		)
		(pad "1" smd rect
			(at 0 0 180)
			(size 0.508 0.508)
			(layers "B.Cu" "B.Mask" "B.Paste")
			(net "P3E_CPU0_PE1_SS_TXP<7>")
		)
		(pad "2" smd rect
			(at 0 0.889 180)
			(size 0.508 0.508)
			(layers "B.Cu" "B.Mask" "B.Paste")
			(net "P3E_CPU0_PE1_SS_C_TXP<7>")
		)
		(zone
			(layer "B.Cu")
			(hatch none 0.5)
			(connect_pads
				(clearance 0)
			)
			(min_thickness 0.25)
			(keepout
				(tracks allowed)
				(vias not_allowed)
				(pads allowed)
				(copperpour not_allowed)
				(footprints allowed)
			)
			(placement
				(enabled no)
				(sheetname "")
			)
			(fill
				(thermal_gap 0.5)
				(thermal_bridge_width 0.5)
				(island_removal_mode 0)
			)
			(polygon
				(pts
					(xy 360.10088 -77.669136) (xy 359.59288 -77.669136) (xy 359.59288 -77.288136) (xy 360.10088 -77.288136)
				)
			)
		)
		(zone
			(layer "B.Cu")
			(hatch none 0.5)
			(connect_pads
				(clearance 0)
			)
			(min_thickness 0.25)
			(keepout
				(tracks not_allowed)
				(vias allowed)
				(pads allowed)
				(copperpour not_allowed)
				(footprints allowed)
			)
			(placement
				(enabled no)
				(sheetname "")
			)
			(fill
				(thermal_gap 0.5)
				(thermal_bridge_width 0.5)
				(island_removal_mode 0)
			)
			(polygon
				(pts
					(xy 360.10088 -77.288136) (xy 359.59288 -77.288136) (xy 359.59288 -77.669136) (xy 360.10088 -77.669136)
				)
			)
		)
	)
	(footprint ""
		(layer "B.Cu")
		(at 191.77 -144.4752 180)
		(property "Reference" "C6L7"
			(at 0 0 0)
			(layer "B.SilkS")
			(hide yes)
			(effects
				(font
					(size 1.27 1.27)
				)
				(justify mirror)
			)
		)
		(property "Value" ""
			(at 0 0 0)
			(layer "B.Fab")
			(effects
				(font
					(size 1.27 1.27)
				)
				(justify mirror)
			)
		)
		(duplicate_pad_numbers_are_jumpers no)
		(fp_poly
			(pts
				(xy -0.3048 -0.1016) (xy -0.3048 0.9906) (xy 0.3048 0.9906) (xy 0.3048 -0.1016)
			)
			(stroke
				(width 0)
				(type default)
			)
			(fill no)
			(layer "B.CrtYd")
		)
		(fp_line
			(start 0.3048 0.9906)
			(end -0.3048 0.9906)
			(stroke
				(width 0.1)
				(type default)
			)
			(layer "B.Fab")
		)
		(fp_line
			(start 0.3048 -0.1016)
			(end 0.3048 0.9906)
			(stroke
				(width 0.1)
				(type default)
			)
			(layer "B.Fab")
		)
		(fp_line
			(start -0.3048 0.9906)
			(end -0.3048 -0.1016)
			(stroke
				(width 0.1)
				(type default)
			)
			(layer "B.Fab")
		)
		(fp_line
			(start -0.3048 -0.1016)
			(end 0.3048 -0.1016)
			(stroke
				(width 0.1)
				(type default)
			)
			(layer "B.Fab")
		)
		(pad "1" smd rect
			(at 0 0)
			(size 0.508 0.508)
			(layers "B.Cu" "B.Mask" "B.Paste")
			(net "M_E_CPU_VREF")
		)
		(pad "2" smd rect
			(at 0 0.889)
			(size 0.508 0.508)
			(layers "B.Cu" "B.Mask" "B.Paste")
			(net "GND")
		)
		(zone
			(layer "B.Cu")
			(hatch none 0.5)
			(connect_pads
				(clearance 0)
			)
			(min_thickness 0.25)
			(keepout
				(tracks not_allowed)
				(vias allowed)
				(pads allowed)
				(copperpour not_allowed)
				(footprints allowed)
			)
			(placement
				(enabled no)
				(sheetname "")
			)
			(fill
				(thermal_gap 0.5)
				(thermal_bridge_width 0.5)
				(island_removal_mode 0)
			)
			(polygon
				(pts
					(xy 191.516 -145.1102) (xy 192.024 -145.1102) (xy 192.024 -144.7292) (xy 191.516 -144.7292)
				)
			)
		)
		(zone
			(layer "B.Cu")
			(hatch none 0.5)
			(connect_pads
				(clearance 0)
			)
			(min_thickness 0.25)
			(keepout
				(tracks allowed)
				(vias not_allowed)
				(pads allowed)
				(copperpour not_allowed)
				(footprints allowed)
			)
			(placement
				(enabled no)
				(sheetname "")
			)
			(fill
				(thermal_gap 0.5)
				(thermal_bridge_width 0.5)
				(island_removal_mode 0)
			)
			(polygon
				(pts
					(xy 191.516 -144.7292) (xy 192.024 -144.7292) (xy 192.024 -145.1102) (xy 191.516 -145.1102)
				)
			)
		)
	)
	(footprint ""
		(layer "B.Cu")
		(at 282.0162 -81.6102)
		(property "Reference" "R4P1"
			(at 0 0 0)
			(layer "B.SilkS")
			(hide yes)
			(effects
				(font
					(size 1.27 1.27)
				)
				(justify mirror)
			)
		)
		(property "Value" ""
			(at 0 0 0)
			(layer "B.Fab")
			(effects
				(font
					(size 1.27 1.27)
				)
				(justify mirror)
			)
		)
		(duplicate_pad_numbers_are_jumpers no)
		(fp_poly
			(pts
				(xy 0.2794 -0.1016) (xy -0.2794 -0.1016) (xy -0.2794 0.9906) (xy 0.2794 0.9906)
			)
			(stroke
				(width 0)
				(type default)
			)
			(fill no)
			(layer "B.CrtYd")
		)
		(fp_line
			(start -0.2794 -0.1016)
			(end 0.2794 -0.1016)
			(stroke
				(width 0.1)
				(type default)
			)
			(layer "B.Fab")
		)
		(fp_line
			(start -0.2794 0.9906)
			(end -0.2794 -0.1016)
			(stroke
				(width 0.1)
				(type default)
			)
			(layer "B.Fab")
		)
		(fp_line
			(start 0.2794 -0.1016)
			(end 0.2794 0.9906)
			(stroke
				(width 0.1)
				(type default)
			)
			(layer "B.Fab")
		)
		(fp_line
			(start 0.2794 0.9906)
			(end -0.2794 0.9906)
			(stroke
				(width 0.1)
				(type default)
			)
			(layer "B.Fab")
		)
		(pad "1" smd rect
			(at 0 0 180)
			(size 0.508 0.508)
			(layers "B.Cu" "B.Mask" "B.Paste")
			(net "GND")
		)
		(pad "2" smd rect
			(at 0 0.889 180)
			(size 0.508 0.508)
			(layers "B.Cu" "B.Mask" "B.Paste")
			(net "PD_CPU0_BIST_ENABLE")
		)
		(zone
			(layer "B.Cu")
			(hatch none 0.5)
			(connect_pads
				(clearance 0)
			)
			(min_thickness 0.25)
			(keepout
				(tracks allowed)
				(vias not_allowed)
				(pads allowed)
				(copperpour not_allowed)
				(footprints allowed)
			)
			(placement
				(enabled no)
				(sheetname "")
			)
			(fill
				(thermal_gap 0.5)
				(thermal_bridge_width 0.5)
				(island_removal_mode 0)
			)
			(polygon
				(pts
					(xy 282.2702 -81.3562) (xy 281.7622 -81.3562) (xy 281.7622 -80.9752) (xy 282.2702 -80.9752)
				)
			)
		)
		(zone
			(layer "B.Cu")
			(hatch none 0.5)
			(connect_pads
				(clearance 0)
			)
			(min_thickness 0.25)
			(keepout
				(tracks not_allowed)
				(vias allowed)
				(pads allowed)
				(copperpour not_allowed)
				(footprints allowed)
			)
			(placement
				(enabled no)
				(sheetname "")
			)
			(fill
				(thermal_gap 0.5)
				(thermal_bridge_width 0.5)
				(island_removal_mode 0)
			)
			(polygon
				(pts
					(xy 282.2702 -80.9752) (xy 281.7622 -80.9752) (xy 281.7622 -81.3562) (xy 282.2702 -81.3562)
				)
			)
		)
	)
	(footprint ""
		(layer "B.Cu")
		(at 318.9732 -33.1978 -90)
		(property "Reference" "R4T2"
			(at 0 0 90)
			(layer "B.SilkS")
			(hide yes)
			(effects
				(font
					(size 1.27 1.27)
				)
				(justify mirror)
			)
		)
		(property "Value" ""
			(at 0 0 90)
			(layer "B.Fab")
			(effects
				(font
					(size 1.27 1.27)
				)
				(justify mirror)
			)
		)
		(duplicate_pad_numbers_are_jumpers no)
		(fp_poly
			(pts
				(xy 0.2794 -0.1016) (xy -0.2794 -0.1016) (xy -0.2794 0.9906) (xy 0.2794 0.9906)
			)
			(stroke
				(width 0)
				(type default)
			)
			(fill no)
			(layer "B.CrtYd")
		)
		(fp_line
			(start -0.2794 0.9906)
			(end -0.2794 -0.1016)
			(stroke
				(width 0.1)
				(type default)
			)
			(layer "B.Fab")
		)
		(fp_line
			(start 0.2794 0.9906)
			(end -0.2794 0.9906)
			(stroke
				(width 0.1)
				(type default)
			)
			(layer "B.Fab")
		)
		(fp_line
			(start -0.2794 -0.1016)
			(end 0.2794 -0.1016)
			(stroke
				(width 0.1)
				(type default)
			)
			(layer "B.Fab")
		)
		(fp_line
			(start 0.2794 -0.1016)
			(end 0.2794 0.9906)
			(stroke
				(width 0.1)
				(type default)
			)
			(layer "B.Fab")
		)
		(pad "1" smd rect
			(at 0 0 90)
			(size 0.508 0.508)
			(layers "B.Cu" "B.Mask" "B.Paste")
			(net "FM_ADR_COMPLETE")
		)
		(pad "2" smd rect
			(at 0 0.889 90)
			(size 0.508 0.508)
			(layers "B.Cu" "B.Mask" "B.Paste")
			(net "FM_ADR_COMPLETE_R")
		)
		(zone
			(layer "B.Cu")
			(hatch none 0.5)
			(connect_pads
				(clearance 0)
			)
			(min_thickness 0.25)
			(keepout
				(tracks not_allowed)
				(vias allowed)
				(pads allowed)
				(copperpour not_allowed)
				(footprints allowed)
			)
			(placement
				(enabled no)
				(sheetname "")
			)
			(fill
				(thermal_gap 0.5)
				(thermal_bridge_width 0.5)
				(island_removal_mode 0)
			)
			(polygon
				(pts
					(xy 318.3382 -32.9438) (xy 318.3382 -33.4518) (xy 318.7192 -33.4518) (xy 318.7192 -32.9438)
				)
			)
		)
		(zone
			(layer "B.Cu")
			(hatch none 0.5)
			(connect_pads
				(clearance 0)
			)
			(min_thickness 0.25)
			(keepout
				(tracks allowed)
				(vias not_allowed)
				(pads allowed)
				(copperpour not_allowed)
				(footprints allowed)
			)
			(placement
				(enabled no)
				(sheetname "")
			)
			(fill
				(thermal_gap 0.5)
				(thermal_bridge_width 0.5)
				(island_removal_mode 0)
			)
			(polygon
				(pts
					(xy 318.7192 -32.9438) (xy 318.7192 -33.4518) (xy 318.3382 -33.4518) (xy 318.3382 -32.9438)
				)
			)
		)
	)
	(footprint ""
		(layer "B.Cu")
		(at 386.503672 -154.721306)
		(property "Reference" "C3L9"
			(at 0 0 0)
			(layer "B.SilkS")
			(hide yes)
			(effects
				(font
					(size 1.27 1.27)
				)
				(justify mirror)
			)
		)
		(property "Value" ""
			(at 0 0 0)
			(layer "B.Fab")
			(effects
				(font
					(size 1.27 1.27)
				)
				(justify mirror)
			)
		)
		(duplicate_pad_numbers_are_jumpers no)
		(fp_poly
			(pts
				(xy 0.7239 -0.2159) (xy -0.7239 -0.2159) (xy -0.7239 1.9939) (xy 0.7239 1.9939)
			)
			(stroke
				(width 0)
				(type default)
			)
			(fill no)
			(layer "B.CrtYd")
		)
		(fp_line
			(start -0.7239 -0.2159)
			(end 0.7239 -0.2159)
			(stroke
				(width 0.1)
				(type default)
			)
			(layer "B.Fab")
		)
		(fp_line
			(start -0.7239 1.9939)
			(end -0.7239 -0.2159)
			(stroke
				(width 0.1)
				(type default)
			)
			(layer "B.Fab")
		)
		(fp_line
			(start 0.7239 -0.2159)
			(end 0.7239 1.9939)
			(stroke
				(width 0.1)
				(type default)
			)
			(layer "B.Fab")
		)
		(fp_line
			(start 0.7239 1.9939)
			(end -0.7239 1.9939)
			(stroke
				(width 0.1)
				(type default)
			)
			(layer "B.Fab")
		)
		(pad "1" smd rect
			(at 0 0 180)
			(size 1.27 1.016)
			(layers "B.Cu" "B.Mask" "B.Paste")
			(net "VR_FET_SW_P12V_STBY_PVDDQ_DEF")
		)
		(pad "2" smd rect
			(at 0 1.778 180)
			(size 1.27 1.016)
			(layers "B.Cu" "B.Mask" "B.Paste")
			(net "GND")
		)
		(zone
			(layer "B.Cu")
			(hatch none 0.5)
			(connect_pads
				(clearance 0)
			)
			(min_thickness 0.25)
			(keepout
				(tracks not_allowed)
				(vias allowed)
				(pads allowed)
				(copperpour not_allowed)
				(footprints allowed)
			)
			(placement
				(enabled no)
				(sheetname "")
			)
			(fill
				(thermal_gap 0.5)
				(thermal_bridge_width 0.5)
				(island_removal_mode 0)
			)
			(polygon
				(pts
					(xy 387.138672 -154.213306) (xy 385.868672 -154.213306) (xy 385.868672 -153.451306) (xy 387.138672 -153.451306)
				)
			)
		)
	)
	(footprint ""
		(layer "B.Cu")
		(at 350.52 -104.267 180)
		(property "Reference" "C22W32"
			(at 0 0 0)
			(layer "B.SilkS")
			(hide yes)
			(effects
				(font
					(size 1.27 1.27)
				)
				(justify mirror)
			)
		)
		(property "Value" "*"
			(at 0.0762 -6.2357 180)
			(unlocked yes)
			(layer "B.Fab")
			(hide yes)
			(effects
				(font
					(size 1.27 1.016)
					(thickness 0.1524)
				)
				(justify mirror)
			)
		)
		(property "Device Type" "SC22U16V5MX-4-GP_SMD-BCG5-SC22A"
			(at 0.0762 -8.2677 180)
			(unlocked yes)
			(layer "B.Fab")
			(hide yes)
			(effects
				(font
					(size 1.27 1.016)
					(thickness 0.1524)
				)
				(justify mirror)
			)
		)
		(duplicate_pad_numbers_are_jumpers no)
		(fp_line
			(start -0.635 0)
			(end 0.635 0)
			(stroke
				(width 0.508)
				(type default)
			)
			(layer "B.SilkS")
		)
		(fp_rect
			(start 0.9652 1.778)
			(end -0.9652 -1.778)
			(stroke
				(width 0)
				(type default)
			)
			(fill no)
			(layer "B.CrtYd")
		)
		(fp_poly
			(pts
				(xy 0.9652 -1.778) (xy -0.9652 -1.778) (xy -0.9652 1.778) (xy 0.9652 1.778)
			)
			(stroke
				(width 0)
				(type default)
			)
			(fill no)
			(layer "B.Fab")
		)
		(pad "1" smd rect
			(at 0 -0.9652)
			(size 1.397 1.143)
			(layers "B.Cu" "B.Mask" "B.Paste")
			(net "VR_FET_SW_P12V_STBY_PVCCIO_CPU0")
		)
		(pad "2" smd rect
			(at 0 0.9652)
			(size 1.397 1.143)
			(layers "B.Cu" "B.Mask" "B.Paste")
			(net "GND")
		)
	)
	(footprint ""
		(layer "B.Cu")
		(at 401.5613 -39.5224 90)
		(property "Reference" "R2U5"
			(at 0 0 90)
			(layer "B.SilkS")
			(hide yes)
			(effects
				(font
					(size 1.27 1.27)
				)
				(justify mirror)
			)
		)
		(property "Value" ""
			(at 0 0 90)
			(layer "B.Fab")
			(effects
				(font
					(size 1.27 1.27)
				)
				(justify mirror)
			)
		)
		(duplicate_pad_numbers_are_jumpers no)
		(fp_poly
			(pts
				(xy 0.2794 -0.1016) (xy -0.2794 -0.1016) (xy -0.2794 0.9906) (xy 0.2794 0.9906)
			)
			(stroke
				(width 0)
				(type default)
			)
			(fill no)
			(layer "B.CrtYd")
		)
		(fp_line
			(start 0.2794 -0.1016)
			(end 0.2794 0.9906)
			(stroke
				(width 0.1)
				(type default)
			)
			(layer "B.Fab")
		)
		(fp_line
			(start -0.2794 -0.1016)
			(end 0.2794 -0.1016)
			(stroke
				(width 0.1)
				(type default)
			)
			(layer "B.Fab")
		)
		(fp_line
			(start 0.2794 0.9906)
			(end -0.2794 0.9906)
			(stroke
				(width 0.1)
				(type default)
			)
			(layer "B.Fab")
		)
		(fp_line
			(start -0.2794 0.9906)
			(end -0.2794 -0.1016)
			(stroke
				(width 0.1)
				(type default)
			)
			(layer "B.Fab")
		)
		(pad "1" smd rect
			(at 0 0 270)
			(size 0.508 0.508)
			(layers "B.Cu" "B.Mask" "B.Paste")
			(net "P3V3_STBY")
		)
		(pad "2" smd rect
			(at 0 0.889 270)
			(size 0.508 0.508)
			(layers "B.Cu" "B.Mask" "B.Paste")
			(net "SMB_OCP_FRU_STBY_LVC3_SCL_R")
		)
		(zone
			(layer "B.Cu")
			(hatch none 0.5)
			(connect_pads
				(clearance 0)
			)
			(min_thickness 0.25)
			(keepout
				(tracks allowed)
				(vias not_allowed)
				(pads allowed)
				(copperpour not_allowed)
				(footprints allowed)
			)
			(placement
				(enabled no)
				(sheetname "")
			)
			(fill
				(thermal_gap 0.5)
				(thermal_bridge_width 0.5)
				(island_removal_mode 0)
			)
			(polygon
				(pts
					(xy 401.8153 -39.7764) (xy 401.8153 -39.2684) (xy 402.1963 -39.2684) (xy 402.1963 -39.7764)
				)
			)
		)
		(zone
			(layer "B.Cu")
			(hatch none 0.5)
			(connect_pads
				(clearance 0)
			)
			(min_thickness 0.25)
			(keepout
				(tracks not_allowed)
				(vias allowed)
				(pads allowed)
				(copperpour not_allowed)
				(footprints allowed)
			)
			(placement
				(enabled no)
				(sheetname "")
			)
			(fill
				(thermal_gap 0.5)
				(thermal_bridge_width 0.5)
				(island_removal_mode 0)
			)
			(polygon
				(pts
					(xy 402.1963 -39.7764) (xy 402.1963 -39.2684) (xy 401.8153 -39.2684) (xy 401.8153 -39.7764)
				)
			)
		)
	)
	(footprint ""
		(layer "B.Cu")
		(at 390.93775 -105.45445)
		(property "Reference" "C2N18"
			(at 0 0 0)
			(layer "B.SilkS")
			(hide yes)
			(effects
				(font
					(size 1.27 1.27)
				)
				(justify mirror)
			)
		)
		(property "Value" ""
			(at 0 0 0)
			(layer "B.Fab")
			(effects
				(font
					(size 1.27 1.27)
				)
				(justify mirror)
			)
		)
		(duplicate_pad_numbers_are_jumpers no)
		(fp_rect
			(start 0.2794 0.9144)
			(end -0.2794 -0.1143)
			(stroke
				(width 0)
				(type default)
			)
			(fill no)
			(layer "B.CrtYd")
		)
		(fp_line
			(start -0.2794 -0.1143)
			(end -0.2794 0.9144)
			(stroke
				(width 0.1)
				(type default)
			)
			(layer "B.Fab")
		)
		(fp_line
			(start -0.2794 0.9144)
			(end 0.2794 0.9144)
			(stroke
				(width 0.1)
				(type default)
			)
			(layer "B.Fab")
		)
		(fp_line
			(start 0.2794 -0.1143)
			(end -0.2794 -0.1143)
			(stroke
				(width 0.1)
				(type default)
			)
			(layer "B.Fab")
		)
		(fp_line
			(start 0.2794 0.9144)
			(end 0.2794 -0.1143)
			(stroke
				(width 0.1)
				(type default)
			)
			(layer "B.Fab")
		)
		(pad "1" smd custom
			(at 0 0 270)
			(size 0.10414 0.10414)
			(layers "B.Cu" "B.Mask" "B.Paste")
			(net "P3V3_STBY")
			(options
				(clearance outline)
				(anchor circle)
			)
			(primitives
				(gr_poly
					(pts
						(xy -0.20828 -0.08636) (xy -0.20828 0.08636) (xy -0.08636 0.20828) (xy 0.086614 0.20828) (xy 0.20828 0.086614)
						(xy 0.20828 -0.08636) (xy 0.08636 -0.20828) (xy -0.08636 -0.20828)
					)
					(width 0)
					(fill yes)
				)
			)
		)
		(pad "2" smd custom
			(at 0 0.8001 270)
			(size 0.10414 0.10414)
			(layers "B.Cu" "B.Mask" "B.Paste")
			(net "GND")
			(options
				(clearance outline)
				(anchor circle)
			)
			(primitives
				(gr_poly
					(pts
						(xy -0.20828 -0.08636) (xy -0.20828 0.08636) (xy -0.08636 0.20828) (xy 0.086614 0.20828) (xy 0.20828 0.086614)
						(xy 0.20828 -0.08636) (xy 0.08636 -0.20828) (xy -0.08636 -0.20828)
					)
					(width 0)
					(fill yes)
				)
			)
		)
		(zone
			(layer "B.Cu")
			(hatch none 0.5)
			(connect_pads
				(clearance 0)
			)
			(min_thickness 0.25)
			(keepout
				(tracks not_allowed)
				(vias allowed)
				(pads allowed)
				(copperpour not_allowed)
				(footprints allowed)
			)
			(placement
				(enabled no)
				(sheetname "")
			)
			(fill
				(thermal_gap 0.5)
				(thermal_bridge_width 0.5)
				(island_removal_mode 0)
			)
			(polygon
				(pts
					(xy 391.02538 -105.2449) (xy 391.02538 -104.8639) (xy 390.85012 -104.8639) (xy 390.849866 -105.2449)
				)
			)
		)
		(zone
			(layer "B.Cu")
			(hatch none 0.5)
			(connect_pads
				(clearance 0)
			)
			(min_thickness 0.25)
			(keepout
				(tracks allowed)
				(vias not_allowed)
				(pads allowed)
				(copperpour not_allowed)
				(footprints allowed)
			)
			(placement
				(enabled no)
				(sheetname "")
			)
			(fill
				(thermal_gap 0.5)
				(thermal_bridge_width 0.5)
				(island_removal_mode 0)
			)
			(polygon
				(pts
					(xy 391.02538 -105.2449) (xy 391.02538 -104.8639) (xy 390.85012 -104.8639) (xy 390.849866 -105.2449)
				)
			)
		)
	)
	(footprint ""
		(layer "B.Cu")
		(at 401.108418 -26.471372 180)
		(property "Reference" "R1U32"
			(at 0 0 0)
			(layer "B.SilkS")
			(hide yes)
			(effects
				(font
					(size 1.27 1.27)
				)
				(justify mirror)
			)
		)
		(property "Value" ""
			(at 0 0 0)
			(layer "B.Fab")
			(effects
				(font
					(size 1.27 1.27)
				)
				(justify mirror)
			)
		)
		(duplicate_pad_numbers_are_jumpers no)
		(fp_poly
			(pts
				(xy 0.2794 -0.1016) (xy -0.2794 -0.1016) (xy -0.2794 0.9906) (xy 0.2794 0.9906)
			)
			(stroke
				(width 0)
				(type default)
			)
			(fill no)
			(layer "B.CrtYd")
		)
		(fp_line
			(start 0.2794 0.9906)
			(end -0.2794 0.9906)
			(stroke
				(width 0.1)
				(type default)
			)
			(layer "B.Fab")
		)
		(fp_line
			(start 0.2794 -0.1016)
			(end 0.2794 0.9906)
			(stroke
				(width 0.1)
				(type default)
			)
			(layer "B.Fab")
		)
		(fp_line
			(start -0.2794 0.9906)
			(end -0.2794 -0.1016)
			(stroke
				(width 0.1)
				(type default)
			)
			(layer "B.Fab")
		)
		(fp_line
			(start -0.2794 -0.1016)
			(end 0.2794 -0.1016)
			(stroke
				(width 0.1)
				(type default)
			)
			(layer "B.Fab")
		)
		(pad "1" smd rect
			(at 0 0)
			(size 0.508 0.508)
			(layers "B.Cu" "B.Mask" "B.Paste")
			(net "P12V_STBY")
		)
		(pad "2" smd rect
			(at 0 0.889)
			(size 0.508 0.508)
			(layers "B.Cu" "B.Mask" "B.Paste")
			(net "A_P12V_STBY_SCALED")
		)
		(zone
			(layer "B.Cu")
			(hatch none 0.5)
			(connect_pads
				(clearance 0)
			)
			(min_thickness 0.25)
			(keepout
				(tracks not_allowed)
				(vias allowed)
				(pads allowed)
				(copperpour not_allowed)
				(footprints allowed)
			)
			(placement
				(enabled no)
				(sheetname "")
			)
			(fill
				(thermal_gap 0.5)
				(thermal_bridge_width 0.5)
				(island_removal_mode 0)
			)
			(polygon
				(pts
					(xy 400.854418 -27.106372) (xy 401.362418 -27.106372) (xy 401.362418 -26.725372) (xy 400.854418 -26.725372)
				)
			)
		)
		(zone
			(layer "B.Cu")
			(hatch none 0.5)
			(connect_pads
				(clearance 0)
			)
			(min_thickness 0.25)
			(keepout
				(tracks allowed)
				(vias not_allowed)
				(pads allowed)
				(copperpour not_allowed)
				(footprints allowed)
			)
			(placement
				(enabled no)
				(sheetname "")
			)
			(fill
				(thermal_gap 0.5)
				(thermal_bridge_width 0.5)
				(island_removal_mode 0)
			)
			(polygon
				(pts
					(xy 400.854418 -26.725372) (xy 401.362418 -26.725372) (xy 401.362418 -27.106372) (xy 400.854418 -27.106372)
				)
			)
		)
	)
	(footprint ""
		(layer "B.Cu")
		(at 384.289808 -84.729828 180)
		(property "Reference" "R3P53"
			(at 0 0 0)
			(layer "B.SilkS")
			(hide yes)
			(effects
				(font
					(size 1.27 1.27)
				)
				(justify mirror)
			)
		)
		(property "Value" ""
			(at 0 0 0)
			(layer "B.Fab")
			(effects
				(font
					(size 1.27 1.27)
				)
				(justify mirror)
			)
		)
		(duplicate_pad_numbers_are_jumpers no)
		(fp_poly
			(pts
				(xy 0.2794 -0.1016) (xy -0.2794 -0.1016) (xy -0.2794 0.9906) (xy 0.2794 0.9906)
			)
			(stroke
				(width 0)
				(type default)
			)
			(fill no)
			(layer "B.CrtYd")
		)
		(fp_line
			(start 0.2794 0.9906)
			(end -0.2794 0.9906)
			(stroke
				(width 0.1)
				(type default)
			)
			(layer "B.Fab")
		)
		(fp_line
			(start 0.2794 -0.1016)
			(end 0.2794 0.9906)
			(stroke
				(width 0.1)
				(type default)
			)
			(layer "B.Fab")
		)
		(fp_line
			(start -0.2794 0.9906)
			(end -0.2794 -0.1016)
			(stroke
				(width 0.1)
				(type default)
			)
			(layer "B.Fab")
		)
		(fp_line
			(start -0.2794 -0.1016)
			(end 0.2794 -0.1016)
			(stroke
				(width 0.1)
				(type default)
			)
			(layer "B.Fab")
		)
		(pad "1" smd rect
			(at 0 0)
			(size 0.508 0.508)
			(layers "B.Cu" "B.Mask" "B.Paste")
			(net "P1V05_PCH_STBY")
		)
		(pad "2" smd rect
			(at 0 0.889)
			(size 0.508 0.508)
			(layers "B.Cu" "B.Mask" "B.Paste")
			(net "FM_OCP_MEZZC_PRES_1V05_PCH_N")
		)
		(zone
			(layer "B.Cu")
			(hatch none 0.5)
			(connect_pads
				(clearance 0)
			)
			(min_thickness 0.25)
			(keepout
				(tracks not_allowed)
				(vias allowed)
				(pads allowed)
				(copperpour not_allowed)
				(footprints allowed)
			)
			(placement
				(enabled no)
				(sheetname "")
			)
			(fill
				(thermal_gap 0.5)
				(thermal_bridge_width 0.5)
				(island_removal_mode 0)
			)
			(polygon
				(pts
					(xy 384.035808 -85.364828) (xy 384.543808 -85.364828) (xy 384.543808 -84.983828) (xy 384.035808 -84.983828)
				)
			)
		)
		(zone
			(layer "B.Cu")
			(hatch none 0.5)
			(connect_pads
				(clearance 0)
			)
			(min_thickness 0.25)
			(keepout
				(tracks allowed)
				(vias not_allowed)
				(pads allowed)
				(copperpour not_allowed)
				(footprints allowed)
			)
			(placement
				(enabled no)
				(sheetname "")
			)
			(fill
				(thermal_gap 0.5)
				(thermal_bridge_width 0.5)
				(island_removal_mode 0)
			)
			(polygon
				(pts
					(xy 384.035808 -84.983828) (xy 384.543808 -84.983828) (xy 384.543808 -85.364828) (xy 384.035808 -85.364828)
				)
			)
		)
	)
	(footprint ""
		(layer "B.Cu")
		(at 384.725672 -154.721306)
		(property "Reference" "C3L7"
			(at 0 0 0)
			(layer "B.SilkS")
			(hide yes)
			(effects
				(font
					(size 1.27 1.27)
				)
				(justify mirror)
			)
		)
		(property "Value" ""
			(at 0 0 0)
			(layer "B.Fab")
			(effects
				(font
					(size 1.27 1.27)
				)
				(justify mirror)
			)
		)
		(duplicate_pad_numbers_are_jumpers no)
		(fp_poly
			(pts
				(xy 0.7239 -0.2159) (xy -0.7239 -0.2159) (xy -0.7239 1.9939) (xy 0.7239 1.9939)
			)
			(stroke
				(width 0)
				(type default)
			)
			(fill no)
			(layer "B.CrtYd")
		)
		(fp_line
			(start -0.7239 -0.2159)
			(end 0.7239 -0.2159)
			(stroke
				(width 0.1)
				(type default)
			)
			(layer "B.Fab")
		)
		(fp_line
			(start -0.7239 1.9939)
			(end -0.7239 -0.2159)
			(stroke
				(width 0.1)
				(type default)
			)
			(layer "B.Fab")
		)
		(fp_line
			(start 0.7239 -0.2159)
			(end 0.7239 1.9939)
			(stroke
				(width 0.1)
				(type default)
			)
			(layer "B.Fab")
		)
		(fp_line
			(start 0.7239 1.9939)
			(end -0.7239 1.9939)
			(stroke
				(width 0.1)
				(type default)
			)
			(layer "B.Fab")
		)
		(pad "1" smd rect
			(at 0 0 180)
			(size 1.27 1.016)
			(layers "B.Cu" "B.Mask" "B.Paste")
			(net "VR_FET_SW_P12V_STBY_PVDDQ_DEF")
		)
		(pad "2" smd rect
			(at 0 1.778 180)
			(size 1.27 1.016)
			(layers "B.Cu" "B.Mask" "B.Paste")
			(net "GND")
		)
		(zone
			(layer "B.Cu")
			(hatch none 0.5)
			(connect_pads
				(clearance 0)
			)
			(min_thickness 0.25)
			(keepout
				(tracks not_allowed)
				(vias allowed)
				(pads allowed)
				(copperpour not_allowed)
				(footprints allowed)
			)
			(placement
				(enabled no)
				(sheetname "")
			)
			(fill
				(thermal_gap 0.5)
				(thermal_bridge_width 0.5)
				(island_removal_mode 0)
			)
			(polygon
				(pts
					(xy 385.360672 -154.213306) (xy 384.090672 -154.213306) (xy 384.090672 -153.451306) (xy 385.360672 -153.451306)
				)
			)
		)
	)
	(footprint ""
		(layer "B.Cu")
		(at 379.74905 -68.707 -90)
		(property "Reference" "C2P3"
			(at 0 0 90)
			(layer "B.SilkS")
			(hide yes)
			(effects
				(font
					(size 1.27 1.27)
				)
				(justify mirror)
			)
		)
		(property "Value" ""
			(at 0 0 90)
			(layer "B.Fab")
			(effects
				(font
					(size 1.27 1.27)
				)
				(justify mirror)
			)
		)
		(duplicate_pad_numbers_are_jumpers no)
		(fp_rect
			(start 0.2794 0.9144)
			(end -0.2794 -0.1143)
			(stroke
				(width 0)
				(type default)
			)
			(fill no)
			(layer "B.CrtYd")
		)
		(fp_line
			(start -0.2794 0.9144)
			(end 0.2794 0.9144)
			(stroke
				(width 0.1)
				(type default)
			)
			(layer "B.Fab")
		)
		(fp_line
			(start 0.2794 0.9144)
			(end 0.2794 -0.1143)
			(stroke
				(width 0.1)
				(type default)
			)
			(layer "B.Fab")
		)
		(fp_line
			(start -0.2794 -0.1143)
			(end -0.2794 0.9144)
			(stroke
				(width 0.1)
				(type default)
			)
			(layer "B.Fab")
		)
		(fp_line
			(start 0.2794 -0.1143)
			(end -0.2794 -0.1143)
			(stroke
				(width 0.1)
				(type default)
			)
			(layer "B.Fab")
		)
		(pad "1" smd custom
			(at 0 0 180)
			(size 0.10414 0.10414)
			(layers "B.Cu" "B.Mask" "B.Paste")
			(net "P3V3_STBY")
			(options
				(clearance outline)
				(anchor circle)
			)
			(primitives
				(gr_poly
					(pts
						(xy -0.20828 -0.08636) (xy -0.20828 0.08636) (xy -0.08636 0.20828) (xy 0.086614 0.20828) (xy 0.20828 0.086614)
						(xy 0.20828 -0.08636) (xy 0.08636 -0.20828) (xy -0.08636 -0.20828)
					)
					(width 0)
					(fill yes)
				)
			)
		)
		(pad "2" smd custom
			(at 0 0.8001 180)
			(size 0.10414 0.10414)
			(layers "B.Cu" "B.Mask" "B.Paste")
			(net "GND")
			(options
				(clearance outline)
				(anchor circle)
			)
			(primitives
				(gr_poly
					(pts
						(xy -0.20828 -0.08636) (xy -0.20828 0.08636) (xy -0.08636 0.20828) (xy 0.086614 0.20828) (xy 0.20828 0.086614)
						(xy 0.20828 -0.08636) (xy 0.08636 -0.20828) (xy -0.08636 -0.20828)
					)
					(width 0)
					(fill yes)
				)
			)
		)
		(zone
			(layer "B.Cu")
			(hatch none 0.5)
			(connect_pads
				(clearance 0)
			)
			(min_thickness 0.25)
			(keepout
				(tracks not_allowed)
				(vias allowed)
				(pads allowed)
				(copperpour not_allowed)
				(footprints allowed)
			)
			(placement
				(enabled no)
				(sheetname "")
			)
			(fill
				(thermal_gap 0.5)
				(thermal_bridge_width 0.5)
				(island_removal_mode 0)
			)
			(polygon
				(pts
					(xy 379.5395 -68.61937) (xy 379.1585 -68.61937) (xy 379.1585 -68.79463) (xy 379.5395 -68.794884)
				)
			)
		)
		(zone
			(layer "B.Cu")
			(hatch none 0.5)
			(connect_pads
				(clearance 0)
			)
			(min_thickness 0.25)
			(keepout
				(tracks allowed)
				(vias not_allowed)
				(pads allowed)
				(copperpour not_allowed)
				(footprints allowed)
			)
			(placement
				(enabled no)
				(sheetname "")
			)
			(fill
				(thermal_gap 0.5)
				(thermal_bridge_width 0.5)
				(island_removal_mode 0)
			)
			(polygon
				(pts
					(xy 379.5395 -68.61937) (xy 379.1585 -68.61937) (xy 379.1585 -68.79463) (xy 379.5395 -68.794884)
				)
			)
		)
	)
	(footprint ""
		(layer "B.Cu")
		(at 83.856068 -140.208 -90)
		(property "Reference" "C5G113"
			(at -1.14681 0.76708 0)
			(unlocked yes)
			(layer "B.SilkS")
			(effects
				(font
					(size 0.7874 0.5842)
					(thickness 0.1524)
				)
				(justify mirror)
			)
		)
		(property "Value" ""
			(at 0 0 90)
			(layer "B.Fab")
			(effects
				(font
					(size 1.27 1.27)
				)
				(justify mirror)
			)
		)
		(duplicate_pad_numbers_are_jumpers no)
		(fp_rect
			(start 0.4953 1.6002)
			(end -0.4953 -0.2032)
			(stroke
				(width 0)
				(type default)
			)
			(fill no)
			(layer "B.CrtYd")
		)
		(fp_line
			(start -0.4953 1.6002)
			(end 0.4953 1.6002)
			(stroke
				(width 0.1)
				(type default)
			)
			(layer "B.Fab")
		)
		(fp_line
			(start 0.4953 1.6002)
			(end 0.4953 -0.2032)
			(stroke
				(width 0.1)
				(type default)
			)
			(layer "B.Fab")
		)
		(fp_line
			(start -0.4953 -0.2032)
			(end -0.4953 1.6002)
			(stroke
				(width 0.1)
				(type default)
			)
			(layer "B.Fab")
		)
		(fp_line
			(start 0.4953 -0.2032)
			(end -0.4953 -0.2032)
			(stroke
				(width 0.1)
				(type default)
			)
			(layer "B.Fab")
		)
		(pad "1" smd rect
			(at 0 0 90)
			(size 0.762 0.889)
			(layers "B.Cu" "B.Mask" "B.Paste")
			(net "PVDDQ_KLM")
		)
		(pad "2" smd rect
			(at 0 1.397 90)
			(size 0.762 0.889)
			(layers "B.Cu" "B.Mask" "B.Paste")
			(net "GND")
		)
		(zone
			(layer "B.Cu")
			(hatch none 0.5)
			(connect_pads
				(clearance 0)
			)
			(min_thickness 0.25)
			(keepout
				(tracks not_allowed)
				(vias allowed)
				(pads allowed)
				(copperpour not_allowed)
				(footprints allowed)
			)
			(placement
				(enabled no)
				(sheetname "")
			)
			(fill
				(thermal_gap 0.5)
				(thermal_bridge_width 0.5)
				(island_removal_mode 0)
			)
			(polygon
				(pts
					(xy 82.903568 -139.827) (xy 83.411568 -139.827) (xy 83.411568 -140.589) (xy 82.903568 -140.589)
				)
			)
		)
	)
	(footprint ""
		(layer "B.Cu")
		(at 464.5025 -4.445 90)
		(property "Reference" "R2U48"
			(at 0 0 90)
			(layer "B.SilkS")
			(hide yes)
			(effects
				(font
					(size 1.27 1.27)
				)
				(justify mirror)
			)
		)
		(property "Value" ""
			(at 0 0 90)
			(layer "B.Fab")
			(effects
				(font
					(size 1.27 1.27)
				)
				(justify mirror)
			)
		)
		(duplicate_pad_numbers_are_jumpers no)
		(fp_poly
			(pts
				(xy 0.2794 -0.1016) (xy -0.2794 -0.1016) (xy -0.2794 0.9906) (xy 0.2794 0.9906)
			)
			(stroke
				(width 0)
				(type default)
			)
			(fill no)
			(layer "B.CrtYd")
		)
		(fp_line
			(start 0.2794 -0.1016)
			(end 0.2794 0.9906)
			(stroke
				(width 0.1)
				(type default)
			)
			(layer "B.Fab")
		)
		(fp_line
			(start -0.2794 -0.1016)
			(end 0.2794 -0.1016)
			(stroke
				(width 0.1)
				(type default)
			)
			(layer "B.Fab")
		)
		(fp_line
			(start 0.2794 0.9906)
			(end -0.2794 0.9906)
			(stroke
				(width 0.1)
				(type default)
			)
			(layer "B.Fab")
		)
		(fp_line
			(start -0.2794 0.9906)
			(end -0.2794 -0.1016)
			(stroke
				(width 0.1)
				(type default)
			)
			(layer "B.Fab")
		)
		(pad "1" smd rect
			(at 0 0 270)
			(size 0.508 0.508)
			(layers "B.Cu" "B.Mask" "B.Paste")
			(net "P3V3_STBY")
		)
		(pad "2" smd rect
			(at 0 0.889 270)
			(size 0.508 0.508)
			(layers "B.Cu" "B.Mask" "B.Paste")
			(net "FM_SLT_CFG2_R")
		)
		(zone
			(layer "B.Cu")
			(hatch none 0.5)
			(connect_pads
				(clearance 0)
			)
			(min_thickness 0.25)
			(keepout
				(tracks allowed)
				(vias not_allowed)
				(pads allowed)
				(copperpour not_allowed)
				(footprints allowed)
			)
			(placement
				(enabled no)
				(sheetname "")
			)
			(fill
				(thermal_gap 0.5)
				(thermal_bridge_width 0.5)
				(island_removal_mode 0)
			)
			(polygon
				(pts
					(xy 464.7565 -4.699) (xy 464.7565 -4.191) (xy 465.1375 -4.191) (xy 465.1375 -4.699)
				)
			)
		)
		(zone
			(layer "B.Cu")
			(hatch none 0.5)
			(connect_pads
				(clearance 0)
			)
			(min_thickness 0.25)
			(keepout
				(tracks not_allowed)
				(vias allowed)
				(pads allowed)
				(copperpour not_allowed)
				(footprints allowed)
			)
			(placement
				(enabled no)
				(sheetname "")
			)
			(fill
				(thermal_gap 0.5)
				(thermal_bridge_width 0.5)
				(island_removal_mode 0)
			)
			(polygon
				(pts
					(xy 465.1375 -4.699) (xy 465.1375 -4.191) (xy 464.7565 -4.191) (xy 464.7565 -4.699)
				)
			)
		)
	)
	(footprint ""
		(layer "B.Cu")
		(at 489.0008 -117.7798 -90)
		(property "Reference" "C1M5"
			(at -3.09753 4.2926 0)
			(unlocked yes)
			(layer "B.SilkS")
			(effects
				(font
					(size 0.7874 0.5842)
					(thickness 0.1524)
				)
				(justify mirror)
			)
		)
		(property "Value" ""
			(at 0 0 90)
			(layer "B.Fab")
			(effects
				(font
					(size 1.27 1.27)
				)
				(justify mirror)
			)
		)
		(duplicate_pad_numbers_are_jumpers no)
		(fp_line
			(start -2.286 7.366)
			(end -1.600708 7.366)
			(stroke
				(width 0.1524)
				(type default)
			)
			(layer "B.SilkS")
		)
		(fp_line
			(start -2.286 7.366)
			(end -2.286 1.63195)
			(stroke
				(width 0.1524)
				(type default)
			)
			(layer "B.SilkS")
		)
		(fp_line
			(start 2.286 7.366)
			(end 1.60147 7.366)
			(stroke
				(width 0.1524)
				(type default)
			)
			(layer "B.SilkS")
		)
		(fp_line
			(start 2.286 7.366)
			(end 2.286 1.632712)
			(stroke
				(width 0.1524)
				(type default)
			)
			(layer "B.SilkS")
		)
		(fp_line
			(start -2.504948 1.633728)
			(end -1.6002 1.633728)
			(stroke
				(width 0.1524)
				(type default)
			)
			(layer "B.SilkS")
		)
		(fp_line
			(start 2.563114 1.633728)
			(end 1.6002 1.633728)
			(stroke
				(width 0.1524)
				(type default)
			)
			(layer "B.SilkS")
		)
		(fp_line
			(start -2.504948 -1.616456)
			(end -2.504948 1.633728)
			(stroke
				(width 0.1524)
				(type default)
			)
			(layer "B.SilkS")
		)
		(fp_line
			(start -1.6002 -1.616456)
			(end -2.504948 -1.616456)
			(stroke
				(width 0.1524)
				(type default)
			)
			(layer "B.SilkS")
		)
		(fp_line
			(start 1.6002 -1.616456)
			(end 2.563114 -1.616456)
			(stroke
				(width 0.1524)
				(type default)
			)
			(layer "B.SilkS")
		)
		(fp_line
			(start 2.563114 -1.616456)
			(end 2.563114 1.633728)
			(stroke
				(width 0.1524)
				(type default)
			)
			(layer "B.SilkS")
		)
		(fp_rect
			(start 2.286 7.366)
			(end -2.286 -0.254)
			(stroke
				(width 0)
				(type default)
			)
			(fill no)
			(layer "B.CrtYd")
		)
		(fp_line
			(start -2.286 7.366)
			(end 2.286 7.366)
			(stroke
				(width 0.1)
				(type default)
			)
			(layer "B.Fab")
		)
		(fp_line
			(start 2.286 7.366)
			(end 2.286 -0.254)
			(stroke
				(width 0.1)
				(type default)
			)
			(layer "B.Fab")
		)
		(fp_line
			(start -2.286 -0.254)
			(end -2.286 7.366)
			(stroke
				(width 0.1)
				(type default)
			)
			(layer "B.Fab")
		)
		(fp_line
			(start 2.286 -0.254)
			(end -2.286 -0.254)
			(stroke
				(width 0.1)
				(type default)
			)
			(layer "B.Fab")
		)
		(pad "1" smd rect
			(at 0 0 90)
			(size 2.54 3.048)
			(layers "B.Cu" "B.Mask" "B.Paste")
			(net "P12V_STBY")
		)
		(pad "2" smd rect
			(at 0 7.112 90)
			(size 2.54 3.048)
			(layers "B.Cu" "B.Mask" "B.Paste")
			(net "GND")
		)
	)
	(footprint ""
		(layer "B.Cu")
		(at 335.89722 -84.82584 180)
		(property "Reference" "R3P56"
			(at 0 0 0)
			(layer "B.SilkS")
			(hide yes)
			(effects
				(font
					(size 1.27 1.27)
				)
				(justify mirror)
			)
		)
		(property "Value" ""
			(at 0 0 0)
			(layer "B.Fab")
			(effects
				(font
					(size 1.27 1.27)
				)
				(justify mirror)
			)
		)
		(duplicate_pad_numbers_are_jumpers no)
		(fp_poly
			(pts
				(xy 0.2794 -0.1016) (xy -0.2794 -0.1016) (xy -0.2794 0.9906) (xy 0.2794 0.9906)
			)
			(stroke
				(width 0)
				(type default)
			)
			(fill no)
			(layer "B.CrtYd")
		)
		(fp_line
			(start 0.2794 0.9906)
			(end -0.2794 0.9906)
			(stroke
				(width 0.1)
				(type default)
			)
			(layer "B.Fab")
		)
		(fp_line
			(start 0.2794 -0.1016)
			(end 0.2794 0.9906)
			(stroke
				(width 0.1)
				(type default)
			)
			(layer "B.Fab")
		)
		(fp_line
			(start -0.2794 0.9906)
			(end -0.2794 -0.1016)
			(stroke
				(width 0.1)
				(type default)
			)
			(layer "B.Fab")
		)
		(fp_line
			(start -0.2794 -0.1016)
			(end 0.2794 -0.1016)
			(stroke
				(width 0.1)
				(type default)
			)
			(layer "B.Fab")
		)
		(pad "1" smd rect
			(at 0 0)
			(size 0.508 0.508)
			(layers "B.Cu" "B.Mask" "B.Paste")
			(net "FM_CPU0_SM_WP")
		)
		(pad "2" smd rect
			(at 0 0.889)
			(size 0.508 0.508)
			(layers "B.Cu" "B.Mask" "B.Paste")
			(net "GND")
		)
		(zone
			(layer "B.Cu")
			(hatch none 0.5)
			(connect_pads
				(clearance 0)
			)
			(min_thickness 0.25)
			(keepout
				(tracks not_allowed)
				(vias allowed)
				(pads allowed)
				(copperpour not_allowed)
				(footprints allowed)
			)
			(placement
				(enabled no)
				(sheetname "")
			)
			(fill
				(thermal_gap 0.5)
				(thermal_bridge_width 0.5)
				(island_removal_mode 0)
			)
			(polygon
				(pts
					(xy 335.64322 -85.46084) (xy 336.15122 -85.46084) (xy 336.15122 -85.07984) (xy 335.64322 -85.07984)
				)
			)
		)
		(zone
			(layer "B.Cu")
			(hatch none 0.5)
			(connect_pads
				(clearance 0)
			)
			(min_thickness 0.25)
			(keepout
				(tracks allowed)
				(vias not_allowed)
				(pads allowed)
				(copperpour not_allowed)
				(footprints allowed)
			)
			(placement
				(enabled no)
				(sheetname "")
			)
			(fill
				(thermal_gap 0.5)
				(thermal_bridge_width 0.5)
				(island_removal_mode 0)
			)
			(polygon
				(pts
					(xy 335.64322 -85.07984) (xy 336.15122 -85.07984) (xy 336.15122 -85.46084) (xy 335.64322 -85.46084)
				)
			)
		)
	)
	(footprint ""
		(layer "B.Cu")
		(at 347.5736 -3.8608 -90)
		(property "Reference" "C3U4"
			(at 0 0 90)
			(layer "B.SilkS")
			(hide yes)
			(effects
				(font
					(size 1.27 1.27)
				)
				(justify mirror)
			)
		)
		(property "Value" ""
			(at 0 0 90)
			(layer "B.Fab")
			(effects
				(font
					(size 1.27 1.27)
				)
				(justify mirror)
			)
		)
		(duplicate_pad_numbers_are_jumpers no)
		(fp_rect
			(start 0.7239 1.9939)
			(end -0.7239 -0.2159)
			(stroke
				(width 0)
				(type default)
			)
			(fill no)
			(layer "B.CrtYd")
		)
		(fp_line
			(start -0.7239 1.9939)
			(end -0.7239 -0.2159)
			(stroke
				(width 0.1)
				(type default)
			)
			(layer "B.Fab")
		)
		(fp_line
			(start 0.7239 1.9939)
			(end -0.7239 1.9939)
			(stroke
				(width 0.1)
				(type default)
			)
			(layer "B.Fab")
		)
		(fp_line
			(start -0.7239 -0.2159)
			(end 0.7239 -0.2159)
			(stroke
				(width 0.1)
				(type default)
			)
			(layer "B.Fab")
		)
		(fp_line
			(start 0.7239 -0.2159)
			(end 0.7239 1.9939)
			(stroke
				(width 0.1)
				(type default)
			)
			(layer "B.Fab")
		)
		(pad "1" smd rect
			(at 0 0 90)
			(size 1.27 1.016)
			(layers "B.Cu" "B.Mask" "B.Paste")
			(net "VR_FET_SW_P12V_STBY_PVDDQ_ABC")
		)
		(pad "2" smd rect
			(at 0 1.778 90)
			(size 1.27 1.016)
			(layers "B.Cu" "B.Mask" "B.Paste")
			(net "GND")
		)
		(zone
			(layer "B.Cu")
			(hatch none 0.5)
			(connect_pads
				(clearance 0)
			)
			(min_thickness 0.25)
			(keepout
				(tracks not_allowed)
				(vias allowed)
				(pads allowed)
				(copperpour not_allowed)
				(footprints allowed)
			)
			(placement
				(enabled no)
				(sheetname "")
			)
			(fill
				(thermal_gap 0.5)
				(thermal_bridge_width 0.5)
				(island_removal_mode 0)
			)
			(polygon
				(pts
					(xy 346.3036 -3.2258) (xy 347.0656 -3.2258) (xy 347.0656 -4.4958) (xy 346.3036 -4.4958)
				)
			)
		)
	)
	(footprint ""
		(layer "B.Cu")
		(at 413.0675 -24.384 -90)
		(property "Reference" "C25W32"
			(at 0.8382 -0.67818 270)
			(unlocked yes)
			(layer "B.SilkS")
			(effects
				(font
					(size 0.4064 0.254)
					(thickness 0.1524)
				)
				(justify left mirror)
			)
		)
		(property "Value" ""
			(at 0 0 90)
			(layer "B.Fab")
			(effects
				(font
					(size 1.27 1.27)
				)
				(justify mirror)
			)
		)
		(duplicate_pad_numbers_are_jumpers no)
		(fp_poly
			(pts
				(xy -0.3048 -0.1016) (xy -0.3048 0.9906) (xy 0.3048 0.9906) (xy 0.3048 -0.1016)
			)
			(stroke
				(width 0)
				(type default)
			)
			(fill no)
			(layer "B.CrtYd")
		)
		(fp_line
			(start -0.3048 0.9906)
			(end -0.3048 -0.1016)
			(stroke
				(width 0.1)
				(type default)
			)
			(layer "B.Fab")
		)
		(fp_line
			(start 0.3048 0.9906)
			(end -0.3048 0.9906)
			(stroke
				(width 0.1)
				(type default)
			)
			(layer "B.Fab")
		)
		(fp_line
			(start -0.3048 -0.1016)
			(end 0.3048 -0.1016)
			(stroke
				(width 0.1)
				(type default)
			)
			(layer "B.Fab")
		)
		(fp_line
			(start 0.3048 -0.1016)
			(end 0.3048 0.9906)
			(stroke
				(width 0.1)
				(type default)
			)
			(layer "B.Fab")
		)
		(pad "1" smd rect
			(at 0 0 90)
			(size 0.508 0.508)
			(layers "B.Cu" "B.Mask" "B.Paste")
			(net "VCC_ADCAV3V3")
		)
		(pad "2" smd rect
			(at 0 0.889 90)
			(size 0.508 0.508)
			(layers "B.Cu" "B.Mask" "B.Paste")
			(net "GND")
		)
		(zone
			(layer "B.Cu")
			(hatch none 0.5)
			(connect_pads
				(clearance 0)
			)
			(min_thickness 0.25)
			(keepout
				(tracks not_allowed)
				(vias allowed)
				(pads allowed)
				(copperpour not_allowed)
				(footprints allowed)
			)
			(placement
				(enabled no)
				(sheetname "")
			)
			(fill
				(thermal_gap 0.5)
				(thermal_bridge_width 0.5)
				(island_removal_mode 0)
			)
			(polygon
				(pts
					(xy 412.4325 -24.13) (xy 412.4325 -24.638) (xy 412.8135 -24.638) (xy 412.8135 -24.13)
				)
			)
		)
		(zone
			(layer "B.Cu")
			(hatch none 0.5)
			(connect_pads
				(clearance 0)
			)
			(min_thickness 0.25)
			(keepout
				(tracks allowed)
				(vias not_allowed)
				(pads allowed)
				(copperpour not_allowed)
				(footprints allowed)
			)
			(placement
				(enabled no)
				(sheetname "")
			)
			(fill
				(thermal_gap 0.5)
				(thermal_bridge_width 0.5)
				(island_removal_mode 0)
			)
			(polygon
				(pts
					(xy 412.8135 -24.13) (xy 412.8135 -24.638) (xy 412.4325 -24.638) (xy 412.4325 -24.13)
				)
			)
		)
	)
	(footprint ""
		(layer "B.Cu")
		(at 441.833 -13.1064 90)
		(property "Reference" "R1U37"
			(at 0 0 90)
			(layer "B.SilkS")
			(hide yes)
			(effects
				(font
					(size 1.27 1.27)
				)
				(justify mirror)
			)
		)
		(property "Value" ""
			(at 0 0 90)
			(layer "B.Fab")
			(effects
				(font
					(size 1.27 1.27)
				)
				(justify mirror)
			)
		)
		(duplicate_pad_numbers_are_jumpers no)
		(fp_poly
			(pts
				(xy 0.2794 -0.1016) (xy -0.2794 -0.1016) (xy -0.2794 0.9906) (xy 0.2794 0.9906)
			)
			(stroke
				(width 0)
				(type default)
			)
			(fill no)
			(layer "B.CrtYd")
		)
		(fp_line
			(start 0.2794 -0.1016)
			(end 0.2794 0.9906)
			(stroke
				(width 0.1)
				(type default)
			)
			(layer "B.Fab")
		)
		(fp_line
			(start -0.2794 -0.1016)
			(end 0.2794 -0.1016)
			(stroke
				(width 0.1)
				(type default)
			)
			(layer "B.Fab")
		)
		(fp_line
			(start 0.2794 0.9906)
			(end -0.2794 0.9906)
			(stroke
				(width 0.1)
				(type default)
			)
			(layer "B.Fab")
		)
		(fp_line
			(start -0.2794 0.9906)
			(end -0.2794 -0.1016)
			(stroke
				(width 0.1)
				(type default)
			)
			(layer "B.Fab")
		)
		(pad "1" smd rect
			(at 0 0 270)
			(size 0.508 0.508)
			(layers "B.Cu" "B.Mask" "B.Paste")
			(net "P0V7_GTL2014_2")
		)
		(pad "2" smd rect
			(at 0 0.889 270)
			(size 0.508 0.508)
			(layers "B.Cu" "B.Mask" "B.Paste")
			(net "GND")
		)
		(zone
			(layer "B.Cu")
			(hatch none 0.5)
			(connect_pads
				(clearance 0)
			)
			(min_thickness 0.25)
			(keepout
				(tracks allowed)
				(vias not_allowed)
				(pads allowed)
				(copperpour not_allowed)
				(footprints allowed)
			)
			(placement
				(enabled no)
				(sheetname "")
			)
			(fill
				(thermal_gap 0.5)
				(thermal_bridge_width 0.5)
				(island_removal_mode 0)
			)
			(polygon
				(pts
					(xy 442.087 -13.3604) (xy 442.087 -12.8524) (xy 442.468 -12.8524) (xy 442.468 -13.3604)
				)
			)
		)
		(zone
			(layer "B.Cu")
			(hatch none 0.5)
			(connect_pads
				(clearance 0)
			)
			(min_thickness 0.25)
			(keepout
				(tracks not_allowed)
				(vias allowed)
				(pads allowed)
				(copperpour not_allowed)
				(footprints allowed)
			)
			(placement
				(enabled no)
				(sheetname "")
			)
			(fill
				(thermal_gap 0.5)
				(thermal_bridge_width 0.5)
				(island_removal_mode 0)
			)
			(polygon
				(pts
					(xy 442.468 -13.3604) (xy 442.468 -12.8524) (xy 442.087 -12.8524) (xy 442.087 -13.3604)
				)
			)
		)
	)
	(footprint ""
		(layer "B.Cu")
		(at 411.4165 -4.318 -90)
		(property "Reference" "C8D4"
			(at 0 0 90)
			(layer "B.SilkS")
			(hide yes)
			(effects
				(font
					(size 1.27 1.27)
				)
				(justify mirror)
			)
		)
		(property "Value" ""
			(at 0 0 90)
			(layer "B.Fab")
			(effects
				(font
					(size 1.27 1.27)
				)
				(justify mirror)
			)
		)
		(duplicate_pad_numbers_are_jumpers no)
		(fp_poly
			(pts
				(xy -0.3048 -0.1016) (xy -0.3048 0.9906) (xy 0.3048 0.9906) (xy 0.3048 -0.1016)
			)
			(stroke
				(width 0)
				(type default)
			)
			(fill no)
			(layer "B.CrtYd")
		)
		(fp_line
			(start -0.3048 0.9906)
			(end -0.3048 -0.1016)
			(stroke
				(width 0.1)
				(type default)
			)
			(layer "B.Fab")
		)
		(fp_line
			(start 0.3048 0.9906)
			(end -0.3048 0.9906)
			(stroke
				(width 0.1)
				(type default)
			)
			(layer "B.Fab")
		)
		(fp_line
			(start -0.3048 -0.1016)
			(end 0.3048 -0.1016)
			(stroke
				(width 0.1)
				(type default)
			)
			(layer "B.Fab")
		)
		(fp_line
			(start 0.3048 -0.1016)
			(end 0.3048 0.9906)
			(stroke
				(width 0.1)
				(type default)
			)
			(layer "B.Fab")
		)
		(pad "1" smd rect
			(at 0 0 90)
			(size 0.508 0.508)
			(layers "B.Cu" "B.Mask" "B.Paste")
			(net "P3V3_STBY")
		)
		(pad "2" smd rect
			(at 0 0.889 90)
			(size 0.508 0.508)
			(layers "B.Cu" "B.Mask" "B.Paste")
			(net "GND")
		)
		(zone
			(layer "B.Cu")
			(hatch none 0.5)
			(connect_pads
				(clearance 0)
			)
			(min_thickness 0.25)
			(keepout
				(tracks not_allowed)
				(vias allowed)
				(pads allowed)
				(copperpour not_allowed)
				(footprints allowed)
			)
			(placement
				(enabled no)
				(sheetname "")
			)
			(fill
				(thermal_gap 0.5)
				(thermal_bridge_width 0.5)
				(island_removal_mode 0)
			)
			(polygon
				(pts
					(xy 410.7815 -4.064) (xy 410.7815 -4.572) (xy 411.1625 -4.572) (xy 411.1625 -4.064)
				)
			)
		)
		(zone
			(layer "B.Cu")
			(hatch none 0.5)
			(connect_pads
				(clearance 0)
			)
			(min_thickness 0.25)
			(keepout
				(tracks allowed)
				(vias not_allowed)
				(pads allowed)
				(copperpour not_allowed)
				(footprints allowed)
			)
			(placement
				(enabled no)
				(sheetname "")
			)
			(fill
				(thermal_gap 0.5)
				(thermal_bridge_width 0.5)
				(island_removal_mode 0)
			)
			(polygon
				(pts
					(xy 411.1625 -4.064) (xy 411.1625 -4.572) (xy 410.7815 -4.572) (xy 410.7815 -4.064)
				)
			)
		)
	)
	(footprint ""
		(layer "B.Cu")
		(at 461.277208 -147.650454 90)
		(property "Reference" "R1L15"
			(at 0 0 90)
			(layer "B.SilkS")
			(hide yes)
			(effects
				(font
					(size 1.27 1.27)
				)
				(justify mirror)
			)
		)
		(property "Value" ""
			(at 0 0 90)
			(layer "B.Fab")
			(effects
				(font
					(size 1.27 1.27)
				)
				(justify mirror)
			)
		)
		(duplicate_pad_numbers_are_jumpers no)
		(fp_poly
			(pts
				(xy 0.2794 -0.1016) (xy -0.2794 -0.1016) (xy -0.2794 0.9906) (xy 0.2794 0.9906)
			)
			(stroke
				(width 0)
				(type default)
			)
			(fill no)
			(layer "B.CrtYd")
		)
		(fp_line
			(start 0.2794 -0.1016)
			(end 0.2794 0.9906)
			(stroke
				(width 0.1)
				(type default)
			)
			(layer "B.Fab")
		)
		(fp_line
			(start -0.2794 -0.1016)
			(end 0.2794 -0.1016)
			(stroke
				(width 0.1)
				(type default)
			)
			(layer "B.Fab")
		)
		(fp_line
			(start 0.2794 0.9906)
			(end -0.2794 0.9906)
			(stroke
				(width 0.1)
				(type default)
			)
			(layer "B.Fab")
		)
		(fp_line
			(start -0.2794 0.9906)
			(end -0.2794 -0.1016)
			(stroke
				(width 0.1)
				(type default)
			)
			(layer "B.Fab")
		)
		(pad "1" smd rect
			(at 0 0 270)
			(size 0.508 0.508)
			(layers "B.Cu" "B.Mask" "B.Paste")
			(net "PVCCIO_CPU0")
		)
		(pad "2" smd rect
			(at 0 0.889 270)
			(size 0.508 0.508)
			(layers "B.Cu" "B.Mask" "B.Paste")
			(net "XDP_CPU_TMS")
		)
		(zone
			(layer "B.Cu")
			(hatch none 0.5)
			(connect_pads
				(clearance 0)
			)
			(min_thickness 0.25)
			(keepout
				(tracks allowed)
				(vias not_allowed)
				(pads allowed)
				(copperpour not_allowed)
				(footprints allowed)
			)
			(placement
				(enabled no)
				(sheetname "")
			)
			(fill
				(thermal_gap 0.5)
				(thermal_bridge_width 0.5)
				(island_removal_mode 0)
			)
			(polygon
				(pts
					(xy 461.531208 -147.904454) (xy 461.531208 -147.396454) (xy 461.912208 -147.396454) (xy 461.912208 -147.904454)
				)
			)
		)
		(zone
			(layer "B.Cu")
			(hatch none 0.5)
			(connect_pads
				(clearance 0)
			)
			(min_thickness 0.25)
			(keepout
				(tracks not_allowed)
				(vias allowed)
				(pads allowed)
				(copperpour not_allowed)
				(footprints allowed)
			)
			(placement
				(enabled no)
				(sheetname "")
			)
			(fill
				(thermal_gap 0.5)
				(thermal_bridge_width 0.5)
				(island_removal_mode 0)
			)
			(polygon
				(pts
					(xy 461.912208 -147.904454) (xy 461.912208 -147.396454) (xy 461.531208 -147.396454) (xy 461.531208 -147.904454)
				)
			)
		)
	)
	(footprint ""
		(layer "B.Cu")
		(at -3.1242 -6.4008 -90)
		(property "Reference" "C22W2"
			(at 0 0 90)
			(layer "B.SilkS")
			(hide yes)
			(effects
				(font
					(size 1.27 1.27)
				)
				(justify mirror)
			)
		)
		(property "Value" "*"
			(at 0.0762 -6.2357 270)
			(unlocked yes)
			(layer "B.Fab")
			(hide yes)
			(effects
				(font
					(size 1.27 1.016)
					(thickness 0.1524)
				)
				(justify mirror)
			)
		)
		(property "Device Type" "SC22U16V5MX-4-GP_SMD-BCG5-SC22A"
			(at 0.0762 -8.2677 270)
			(unlocked yes)
			(layer "B.Fab")
			(hide yes)
			(effects
				(font
					(size 1.27 1.016)
					(thickness 0.1524)
				)
				(justify mirror)
			)
		)
		(duplicate_pad_numbers_are_jumpers no)
		(fp_line
			(start -0.635 0)
			(end 0.635 0)
			(stroke
				(width 0.508)
				(type default)
			)
			(layer "B.SilkS")
		)
		(fp_rect
			(start 0.9652 1.778)
			(end -0.9652 -1.778)
			(stroke
				(width 0)
				(type default)
			)
			(fill no)
			(layer "B.CrtYd")
		)
		(fp_poly
			(pts
				(xy 0.9652 -1.778) (xy -0.9652 -1.778) (xy -0.9652 1.778) (xy 0.9652 1.778)
			)
			(stroke
				(width 0)
				(type default)
			)
			(fill no)
			(layer "B.Fab")
		)
		(pad "1" smd rect
			(at 0 -0.9652 90)
			(size 1.397 1.143)
			(layers "B.Cu" "B.Mask" "B.Paste")
			(net "VR_FET_SW_P12V_STBY_PVDDQ_GHJ")
		)
		(pad "2" smd rect
			(at 0 0.9652 90)
			(size 1.397 1.143)
			(layers "B.Cu" "B.Mask" "B.Paste")
			(net "GND")
		)
	)
	(footprint ""
		(layer "B.Cu")
		(at 111.094012 -29.94152 -90)
		(property "Reference" "SH7U1"
			(at 0 0 90)
			(layer "B.SilkS")
			(hide yes)
			(effects
				(font
					(size 1.27 1.27)
				)
				(justify mirror)
			)
		)
		(property "Value" ""
			(at 0 0 90)
			(layer "B.Fab")
			(effects
				(font
					(size 1.27 1.27)
				)
				(justify mirror)
			)
		)
		(duplicate_pad_numbers_are_jumpers no)
		(fp_poly
			(pts
				(xy 0.1651 -0.0508) (xy 0.1651 0.5842) (xy -0.1651 0.5842) (xy -0.1651 -0.0508)
			)
			(stroke
				(width 0)
				(type default)
			)
			(fill no)
			(layer "B.CrtYd")
		)
		(fp_line
			(start -0.1651 0.5842)
			(end 0.1651 0.5842)
			(stroke
				(width 0.1)
				(type default)
			)
			(layer "B.Fab")
		)
		(fp_line
			(start 0.1651 0.5842)
			(end 0.1651 -0.0508)
			(stroke
				(width 0.1)
				(type default)
			)
			(layer "B.Fab")
		)
		(fp_line
			(start -0.1651 -0.0508)
			(end -0.1651 0.5842)
			(stroke
				(width 0.1)
				(type default)
			)
			(layer "B.Fab")
		)
		(fp_line
			(start 0.1651 -0.0508)
			(end -0.1651 -0.0508)
			(stroke
				(width 0.1)
				(type default)
			)
			(layer "B.Fab")
		)
		(pad "1" smd custom
			(at 0 0 270)
			(size 0.0762 0.0762)
			(layers "B.Cu" "B.Mask" "B.Paste")
			(net "VSENSE_PVDDQ_GHJ_P")
			(options
				(clearance outline)
				(anchor circle)
			)
			(primitives
				(gr_poly
					(pts
						(arc
							(start -0.1524 0.10795)
							(mid -0.098518 0.130268)
							(end -0.0762 0.18415)
						)
						(xy -0.0762 0.22225) (xy 0.0762 0.22225)
						(arc
							(start 0.0762 0.18415)
							(mid 0.098518 0.130268)
							(end 0.1524 0.10795)
						)
						(xy 0.1524 -0.22225) (xy -0.1524 -0.22225)
					)
					(width 0)
					(fill yes)
				)
			)
		)
		(pad "2" smd custom
			(at 0 0.5334 90)
			(size 0.0762 0.0762)
			(layers "B.Cu" "B.Mask" "B.Paste")
			(net "PVDDQ_GHJ")
			(options
				(clearance outline)
				(anchor circle)
			)
			(primitives
				(gr_poly
					(pts
						(arc
							(start -0.1524 0.10795)
							(mid -0.098518 0.130268)
							(end -0.0762 0.18415)
						)
						(xy -0.0762 0.22225) (xy 0.0762 0.22225)
						(arc
							(start 0.0762 0.18415)
							(mid 0.098518 0.130268)
							(end 0.1524 0.10795)
						)
						(xy 0.1524 -0.22225) (xy -0.1524 -0.22225)
					)
					(width 0)
					(fill yes)
				)
			)
		)
	)
	(footprint ""
		(layer "B.Cu")
		(at 378.46 -83.4644 180)
		(property "Reference" "R7W3"
			(at 0.8382 -0.67818 180)
			(unlocked yes)
			(layer "B.SilkS")
			(effects
				(font
					(size 0.4064 0.254)
					(thickness 0.1524)
				)
				(justify left mirror)
			)
		)
		(property "Value" ""
			(at 0 0 0)
			(layer "B.Fab")
			(effects
				(font
					(size 1.27 1.27)
				)
				(justify mirror)
			)
		)
		(duplicate_pad_numbers_are_jumpers no)
		(fp_poly
			(pts
				(xy 0.2794 -0.1016) (xy -0.2794 -0.1016) (xy -0.2794 0.9906) (xy 0.2794 0.9906)
			)
			(stroke
				(width 0)
				(type default)
			)
			(fill no)
			(layer "B.CrtYd")
		)
		(fp_line
			(start 0.2794 0.9906)
			(end -0.2794 0.9906)
			(stroke
				(width 0.1)
				(type default)
			)
			(layer "B.Fab")
		)
		(fp_line
			(start 0.2794 -0.1016)
			(end 0.2794 0.9906)
			(stroke
				(width 0.1)
				(type default)
			)
			(layer "B.Fab")
		)
		(fp_line
			(start -0.2794 0.9906)
			(end -0.2794 -0.1016)
			(stroke
				(width 0.1)
				(type default)
			)
			(layer "B.Fab")
		)
		(fp_line
			(start -0.2794 -0.1016)
			(end 0.2794 -0.1016)
			(stroke
				(width 0.1)
				(type default)
			)
			(layer "B.Fab")
		)
		(pad "1" smd rect
			(at 0 0)
			(size 0.508 0.508)
			(layers "B.Cu" "B.Mask" "B.Paste")
			(net "P3V3_STBY")
		)
		(pad "2" smd rect
			(at 0 0.889)
			(size 0.508 0.508)
			(layers "B.Cu" "B.Mask" "B.Paste")
			(net "PECI_SEL")
		)
		(zone
			(layer "B.Cu")
			(hatch none 0.5)
			(connect_pads
				(clearance 0)
			)
			(min_thickness 0.25)
			(keepout
				(tracks not_allowed)
				(vias allowed)
				(pads allowed)
				(copperpour not_allowed)
				(footprints allowed)
			)
			(placement
				(enabled no)
				(sheetname "")
			)
			(fill
				(thermal_gap 0.5)
				(thermal_bridge_width 0.5)
				(island_removal_mode 0)
			)
			(polygon
				(pts
					(xy 378.206 -84.0994) (xy 378.714 -84.0994) (xy 378.714 -83.7184) (xy 378.206 -83.7184)
				)
			)
		)
		(zone
			(layer "B.Cu")
			(hatch none 0.5)
			(connect_pads
				(clearance 0)
			)
			(min_thickness 0.25)
			(keepout
				(tracks allowed)
				(vias not_allowed)
				(pads allowed)
				(copperpour not_allowed)
				(footprints allowed)
			)
			(placement
				(enabled no)
				(sheetname "")
			)
			(fill
				(thermal_gap 0.5)
				(thermal_bridge_width 0.5)
				(island_removal_mode 0)
			)
			(polygon
				(pts
					(xy 378.206 -83.7184) (xy 378.714 -83.7184) (xy 378.714 -84.0994) (xy 378.206 -84.0994)
				)
			)
		)
	)
	(footprint ""
		(layer "B.Cu")
		(at 407.86304 -56.15686 180)
		(property "Reference" "R1W4"
			(at 0.8382 -0.67818 180)
			(unlocked yes)
			(layer "B.SilkS")
			(effects
				(font
					(size 0.4064 0.254)
					(thickness 0.1524)
				)
				(justify left mirror)
			)
		)
		(property "Value" ""
			(at 0 0 0)
			(layer "B.Fab")
			(effects
				(font
					(size 1.27 1.27)
				)
				(justify mirror)
			)
		)
		(duplicate_pad_numbers_are_jumpers no)
		(fp_poly
			(pts
				(xy 0.2794 -0.1016) (xy -0.2794 -0.1016) (xy -0.2794 0.9906) (xy 0.2794 0.9906)
			)
			(stroke
				(width 0)
				(type default)
			)
			(fill no)
			(layer "B.CrtYd")
		)
		(fp_line
			(start 0.2794 0.9906)
			(end -0.2794 0.9906)
			(stroke
				(width 0.1)
				(type default)
			)
			(layer "B.Fab")
		)
		(fp_line
			(start 0.2794 -0.1016)
			(end 0.2794 0.9906)
			(stroke
				(width 0.1)
				(type default)
			)
			(layer "B.Fab")
		)
		(fp_line
			(start -0.2794 0.9906)
			(end -0.2794 -0.1016)
			(stroke
				(width 0.1)
				(type default)
			)
			(layer "B.Fab")
		)
		(fp_line
			(start -0.2794 -0.1016)
			(end 0.2794 -0.1016)
			(stroke
				(width 0.1)
				(type default)
			)
			(layer "B.Fab")
		)
		(pad "1" smd rect
			(at 0 0)
			(size 0.508 0.508)
			(layers "B.Cu" "B.Mask" "B.Paste")
			(net "FM_OCP_MEZZB_PRES_LVT3_BMC")
		)
		(pad "2" smd rect
			(at 0 0.889)
			(size 0.508 0.508)
			(layers "B.Cu" "B.Mask" "B.Paste")
			(net "P3V3_STBY")
		)
		(zone
			(layer "B.Cu")
			(hatch none 0.5)
			(connect_pads
				(clearance 0)
			)
			(min_thickness 0.25)
			(keepout
				(tracks not_allowed)
				(vias allowed)
				(pads allowed)
				(copperpour not_allowed)
				(footprints allowed)
			)
			(placement
				(enabled no)
				(sheetname "")
			)
			(fill
				(thermal_gap 0.5)
				(thermal_bridge_width 0.5)
				(island_removal_mode 0)
			)
			(polygon
				(pts
					(xy 407.60904 -56.79186) (xy 408.11704 -56.79186) (xy 408.11704 -56.41086) (xy 407.60904 -56.41086)
				)
			)
		)
		(zone
			(layer "B.Cu")
			(hatch none 0.5)
			(connect_pads
				(clearance 0)
			)
			(min_thickness 0.25)
			(keepout
				(tracks allowed)
				(vias not_allowed)
				(pads allowed)
				(copperpour not_allowed)
				(footprints allowed)
			)
			(placement
				(enabled no)
				(sheetname "")
			)
			(fill
				(thermal_gap 0.5)
				(thermal_bridge_width 0.5)
				(island_removal_mode 0)
			)
			(polygon
				(pts
					(xy 407.60904 -56.41086) (xy 408.11704 -56.41086) (xy 408.11704 -56.79186) (xy 407.60904 -56.79186)
				)
			)
		)
	)
	(footprint ""
		(layer "B.Cu")
		(at 403.568408 -93.755718 -90)
		(property "Reference" "R2N24"
			(at 0 0 90)
			(layer "B.SilkS")
			(hide yes)
			(effects
				(font
					(size 1.27 1.27)
				)
				(justify mirror)
			)
		)
		(property "Value" ""
			(at 0 0 90)
			(layer "B.Fab")
			(effects
				(font
					(size 1.27 1.27)
				)
				(justify mirror)
			)
		)
		(duplicate_pad_numbers_are_jumpers no)
		(fp_poly
			(pts
				(xy 0.2794 -0.1016) (xy -0.2794 -0.1016) (xy -0.2794 0.9906) (xy 0.2794 0.9906)
			)
			(stroke
				(width 0)
				(type default)
			)
			(fill no)
			(layer "B.CrtYd")
		)
		(fp_line
			(start -0.2794 0.9906)
			(end -0.2794 -0.1016)
			(stroke
				(width 0.1)
				(type default)
			)
			(layer "B.Fab")
		)
		(fp_line
			(start 0.2794 0.9906)
			(end -0.2794 0.9906)
			(stroke
				(width 0.1)
				(type default)
			)
			(layer "B.Fab")
		)
		(fp_line
			(start -0.2794 -0.1016)
			(end 0.2794 -0.1016)
			(stroke
				(width 0.1)
				(type default)
			)
			(layer "B.Fab")
		)
		(fp_line
			(start 0.2794 -0.1016)
			(end 0.2794 0.9906)
			(stroke
				(width 0.1)
				(type default)
			)
			(layer "B.Fab")
		)
		(pad "1" smd rect
			(at 0 0 90)
			(size 0.508 0.508)
			(layers "B.Cu" "B.Mask" "B.Paste")
			(net "FM_QAT_EN_N")
		)
		(pad "2" smd rect
			(at 0 0.889 90)
			(size 0.508 0.508)
			(layers "B.Cu" "B.Mask" "B.Paste")
			(net "GND")
		)
		(zone
			(layer "B.Cu")
			(hatch none 0.5)
			(connect_pads
				(clearance 0)
			)
			(min_thickness 0.25)
			(keepout
				(tracks not_allowed)
				(vias allowed)
				(pads allowed)
				(copperpour not_allowed)
				(footprints allowed)
			)
			(placement
				(enabled no)
				(sheetname "")
			)
			(fill
				(thermal_gap 0.5)
				(thermal_bridge_width 0.5)
				(island_removal_mode 0)
			)
			(polygon
				(pts
					(xy 402.933408 -93.501718) (xy 402.933408 -94.009718) (xy 403.314408 -94.009718) (xy 403.314408 -93.501718)
				)
			)
		)
		(zone
			(layer "B.Cu")
			(hatch none 0.5)
			(connect_pads
				(clearance 0)
			)
			(min_thickness 0.25)
			(keepout
				(tracks allowed)
				(vias not_allowed)
				(pads allowed)
				(copperpour not_allowed)
				(footprints allowed)
			)
			(placement
				(enabled no)
				(sheetname "")
			)
			(fill
				(thermal_gap 0.5)
				(thermal_bridge_width 0.5)
				(island_removal_mode 0)
			)
			(polygon
				(pts
					(xy 403.314408 -93.501718) (xy 403.314408 -94.009718) (xy 402.933408 -94.009718) (xy 402.933408 -93.501718)
				)
			)
		)
	)
	(footprint ""
		(layer "B.Cu")
		(at 253.392432 -135.4074 90)
		(property "Reference" "C5M4"
			(at -1.848866 0.752348 90)
			(unlocked yes)
			(layer "B.SilkS")
			(effects
				(font
					(size 1.27 0.9652)
					(thickness 0.1524)
				)
				(justify mirror)
			)
		)
		(property "Value" ""
			(at 0 0 90)
			(layer "B.Fab")
			(effects
				(font
					(size 1.27 1.27)
				)
				(justify mirror)
			)
		)
		(duplicate_pad_numbers_are_jumpers no)
		(fp_rect
			(start 0.500126 1.598422)
			(end -0.500126 -0.201422)
			(stroke
				(width 0)
				(type default)
			)
			(fill no)
			(layer "B.CrtYd")
		)
		(fp_line
			(start 0.500126 -0.201422)
			(end -0.500126 -0.201422)
			(stroke
				(width 0.1)
				(type default)
			)
			(layer "B.Fab")
		)
		(fp_line
			(start -0.500126 -0.201422)
			(end -0.500126 1.598422)
			(stroke
				(width 0.1)
				(type default)
			)
			(layer "B.Fab")
		)
		(fp_line
			(start 0.500126 1.598422)
			(end 0.500126 -0.201422)
			(stroke
				(width 0.1)
				(type default)
			)
			(layer "B.Fab")
		)
		(fp_line
			(start -0.500126 1.598422)
			(end 0.500126 1.598422)
			(stroke
				(width 0.1)
				(type default)
			)
			(layer "B.Fab")
		)
		(pad "1" smd rect
			(at 0 0)
			(size 0.889 0.9906)
			(layers "B.Cu" "B.Mask" "B.Paste")
			(net "PVDDQ_DEF")
		)
		(pad "2" smd rect
			(at 0 1.397)
			(size 0.889 0.9906)
			(layers "B.Cu" "B.Mask" "B.Paste")
			(net "GND")
		)
		(zone
			(layer "B.Cu")
			(hatch none 0.5)
			(connect_pads
				(clearance 0)
			)
			(min_thickness 0.25)
			(keepout
				(tracks not_allowed)
				(vias allowed)
				(pads allowed)
				(copperpour not_allowed)
				(footprints allowed)
			)
			(placement
				(enabled no)
				(sheetname "")
			)
			(fill
				(thermal_gap 0.5)
				(thermal_bridge_width 0.5)
				(island_removal_mode 0)
			)
			(polygon
				(pts
					(xy 254.344932 -135.9027) (xy 253.836932 -135.9027) (xy 253.836932 -134.9121) (xy 254.344932 -134.9121)
				)
			)
		)
		(zone
			(layer "B.Cu")
			(hatch none 0.5)
			(connect_pads
				(clearance 0)
			)
			(min_thickness 0.25)
			(keepout
				(tracks allowed)
				(vias not_allowed)
				(pads allowed)
				(copperpour not_allowed)
				(footprints allowed)
			)
			(placement
				(enabled no)
				(sheetname "")
			)
			(fill
				(thermal_gap 0.5)
				(thermal_bridge_width 0.5)
				(island_removal_mode 0)
			)
			(polygon
				(pts
					(xy 254.344932 -135.9027) (xy 253.836932 -135.9027) (xy 253.836932 -134.9121) (xy 254.344932 -134.9121)
				)
			)
		)
	)
	(footprint ""
		(layer "B.Cu")
		(at 253.392432 -12.954 90)
		(property "Reference" "C5G44"
			(at -1.14681 0.76708 180)
			(unlocked yes)
			(layer "B.SilkS")
			(effects
				(font
					(size 0.7874 0.5842)
					(thickness 0.1524)
				)
				(justify mirror)
			)
		)
		(property "Value" ""
			(at 0 0 90)
			(layer "B.Fab")
			(effects
				(font
					(size 1.27 1.27)
				)
				(justify mirror)
			)
		)
		(duplicate_pad_numbers_are_jumpers no)
		(fp_rect
			(start -0.4953 -0.2032)
			(end 0.4953 1.6002)
			(stroke
				(width 0)
				(type default)
			)
			(fill no)
			(layer "B.CrtYd")
		)
		(fp_line
			(start 0.4953 -0.2032)
			(end -0.4953 -0.2032)
			(stroke
				(width 0.1)
				(type default)
			)
			(layer "B.Fab")
		)
		(fp_line
			(start -0.4953 -0.2032)
			(end -0.4953 1.6002)
			(stroke
				(width 0.1)
				(type default)
			)
			(layer "B.Fab")
		)
		(fp_line
			(start 0.4953 1.6002)
			(end 0.4953 -0.2032)
			(stroke
				(width 0.1)
				(type default)
			)
			(layer "B.Fab")
		)
		(fp_line
			(start -0.4953 1.6002)
			(end 0.4953 1.6002)
			(stroke
				(width 0.1)
				(type default)
			)
			(layer "B.Fab")
		)
		(pad "1" smd rect
			(at 0 0 270)
			(size 0.762 0.889)
			(layers "B.Cu" "B.Mask" "B.Paste")
			(net "PVDDQ_ABC")
		)
		(pad "2" smd rect
			(at 0 1.397 270)
			(size 0.762 0.889)
			(layers "B.Cu" "B.Mask" "B.Paste")
			(net "GND")
		)
		(zone
			(layer "B.Cu")
			(hatch none 0.5)
			(connect_pads
				(clearance 0)
			)
			(min_thickness 0.25)
			(keepout
				(tracks not_allowed)
				(vias allowed)
				(pads allowed)
				(copperpour not_allowed)
				(footprints allowed)
			)
			(placement
				(enabled no)
				(sheetname "")
			)
			(fill
				(thermal_gap 0.5)
				(thermal_bridge_width 0.5)
				(island_removal_mode 0)
			)
			(polygon
				(pts
					(xy 253.836932 -12.573) (xy 254.344932 -12.573) (xy 254.344932 -13.335) (xy 253.836932 -13.335)
				)
			)
		)
	)
	(footprint ""
		(layer "B.Cu")
		(at 87.158068 -8.1534 -90)
		(property "Reference" "C8U5"
			(at -1.848866 0.752348 270)
			(unlocked yes)
			(layer "B.SilkS")
			(effects
				(font
					(size 1.27 0.9652)
					(thickness 0.1524)
				)
				(justify mirror)
			)
		)
		(property "Value" ""
			(at 0 0 90)
			(layer "B.Fab")
			(effects
				(font
					(size 1.27 1.27)
				)
				(justify mirror)
			)
		)
		(duplicate_pad_numbers_are_jumpers no)
		(fp_rect
			(start 0.500126 1.598422)
			(end -0.500126 -0.201422)
			(stroke
				(width 0)
				(type default)
			)
			(fill no)
			(layer "B.CrtYd")
		)
		(fp_line
			(start -0.500126 1.598422)
			(end 0.500126 1.598422)
			(stroke
				(width 0.1)
				(type default)
			)
			(layer "B.Fab")
		)
		(fp_line
			(start 0.500126 1.598422)
			(end 0.500126 -0.201422)
			(stroke
				(width 0.1)
				(type default)
			)
			(layer "B.Fab")
		)
		(fp_line
			(start -0.500126 -0.201422)
			(end -0.500126 1.598422)
			(stroke
				(width 0.1)
				(type default)
			)
			(layer "B.Fab")
		)
		(fp_line
			(start 0.500126 -0.201422)
			(end -0.500126 -0.201422)
			(stroke
				(width 0.1)
				(type default)
			)
			(layer "B.Fab")
		)
		(pad "1" smd rect
			(at 0 0 180)
			(size 0.889 0.9906)
			(layers "B.Cu" "B.Mask" "B.Paste")
			(net "PVDDQ_GHJ")
		)
		(pad "2" smd rect
			(at 0 1.397 180)
			(size 0.889 0.9906)
			(layers "B.Cu" "B.Mask" "B.Paste")
			(net "GND")
		)
		(zone
			(layer "B.Cu")
			(hatch none 0.5)
			(connect_pads
				(clearance 0)
			)
			(min_thickness 0.25)
			(keepout
				(tracks not_allowed)
				(vias allowed)
				(pads allowed)
				(copperpour not_allowed)
				(footprints allowed)
			)
			(placement
				(enabled no)
				(sheetname "")
			)
			(fill
				(thermal_gap 0.5)
				(thermal_bridge_width 0.5)
				(island_removal_mode 0)
			)
			(polygon
				(pts
					(xy 86.205568 -7.6581) (xy 86.713568 -7.6581) (xy 86.713568 -8.6487) (xy 86.205568 -8.6487)
				)
			)
		)
		(zone
			(layer "B.Cu")
			(hatch none 0.5)
			(connect_pads
				(clearance 0)
			)
			(min_thickness 0.25)
			(keepout
				(tracks allowed)
				(vias not_allowed)
				(pads allowed)
				(copperpour not_allowed)
				(footprints allowed)
			)
			(placement
				(enabled no)
				(sheetname "")
			)
			(fill
				(thermal_gap 0.5)
				(thermal_bridge_width 0.5)
				(island_removal_mode 0)
			)
			(polygon
				(pts
					(xy 86.205568 -7.6581) (xy 86.713568 -7.6581) (xy 86.713568 -8.6487) (xy 86.205568 -8.6487)
				)
			)
		)
	)
	(footprint ""
		(layer "B.Cu")
		(at 457.454 -4.2164 90)
		(property "Reference" "R1U50"
			(at 0 0 90)
			(layer "B.SilkS")
			(hide yes)
			(effects
				(font
					(size 1.27 1.27)
				)
				(justify mirror)
			)
		)
		(property "Value" ""
			(at 0 0 90)
			(layer "B.Fab")
			(effects
				(font
					(size 1.27 1.27)
				)
				(justify mirror)
			)
		)
		(duplicate_pad_numbers_are_jumpers no)
		(fp_poly
			(pts
				(xy 0.2794 -0.1016) (xy -0.2794 -0.1016) (xy -0.2794 0.9906) (xy 0.2794 0.9906)
			)
			(stroke
				(width 0)
				(type default)
			)
			(fill no)
			(layer "B.CrtYd")
		)
		(fp_line
			(start 0.2794 -0.1016)
			(end 0.2794 0.9906)
			(stroke
				(width 0.1)
				(type default)
			)
			(layer "B.Fab")
		)
		(fp_line
			(start -0.2794 -0.1016)
			(end 0.2794 -0.1016)
			(stroke
				(width 0.1)
				(type default)
			)
			(layer "B.Fab")
		)
		(fp_line
			(start 0.2794 0.9906)
			(end -0.2794 0.9906)
			(stroke
				(width 0.1)
				(type default)
			)
			(layer "B.Fab")
		)
		(fp_line
			(start -0.2794 0.9906)
			(end -0.2794 -0.1016)
			(stroke
				(width 0.1)
				(type default)
			)
			(layer "B.Fab")
		)
		(pad "1" smd rect
			(at 0 0 270)
			(size 0.508 0.508)
			(layers "B.Cu" "B.Mask" "B.Paste")
			(net "A_P3V_BAT_R")
		)
		(pad "2" smd rect
			(at 0 0.889 270)
			(size 0.508 0.508)
			(layers "B.Cu" "B.Mask" "B.Paste")
			(net "P3V_BAT_SOURCE_R")
		)
		(zone
			(layer "B.Cu")
			(hatch none 0.5)
			(connect_pads
				(clearance 0)
			)
			(min_thickness 0.25)
			(keepout
				(tracks allowed)
				(vias not_allowed)
				(pads allowed)
				(copperpour not_allowed)
				(footprints allowed)
			)
			(placement
				(enabled no)
				(sheetname "")
			)
			(fill
				(thermal_gap 0.5)
				(thermal_bridge_width 0.5)
				(island_removal_mode 0)
			)
			(polygon
				(pts
					(xy 457.708 -4.4704) (xy 457.708 -3.9624) (xy 458.089 -3.9624) (xy 458.089 -4.4704)
				)
			)
		)
		(zone
			(layer "B.Cu")
			(hatch none 0.5)
			(connect_pads
				(clearance 0)
			)
			(min_thickness 0.25)
			(keepout
				(tracks not_allowed)
				(vias allowed)
				(pads allowed)
				(copperpour not_allowed)
				(footprints allowed)
			)
			(placement
				(enabled no)
				(sheetname "")
			)
			(fill
				(thermal_gap 0.5)
				(thermal_bridge_width 0.5)
				(island_removal_mode 0)
			)
			(polygon
				(pts
					(xy 458.089 -4.4704) (xy 458.089 -3.9624) (xy 457.708 -3.9624) (xy 457.708 -4.4704)
				)
			)
		)
	)
	(footprint ""
		(layer "B.Cu")
		(at 453.517 -116.49202)
		(property "Reference" "C1M14"
			(at 0 0 0)
			(layer "B.SilkS")
			(hide yes)
			(effects
				(font
					(size 1.27 1.27)
				)
				(justify mirror)
			)
		)
		(property "Value" ""
			(at 0 0 0)
			(layer "B.Fab")
			(effects
				(font
					(size 1.27 1.27)
				)
				(justify mirror)
			)
		)
		(duplicate_pad_numbers_are_jumpers no)
		(fp_rect
			(start -0.3048 0.9906)
			(end 0.3048 -0.1016)
			(stroke
				(width 0)
				(type default)
			)
			(fill no)
			(layer "B.CrtYd")
		)
		(fp_line
			(start -0.3048 -0.1016)
			(end 0.3048 -0.1016)
			(stroke
				(width 0.1)
				(type default)
			)
			(layer "B.Fab")
		)
		(fp_line
			(start -0.3048 0.9906)
			(end -0.3048 -0.1016)
			(stroke
				(width 0.1)
				(type default)
			)
			(layer "B.Fab")
		)
		(fp_line
			(start 0.3048 -0.1016)
			(end 0.3048 0.9906)
			(stroke
				(width 0.1)
				(type default)
			)
			(layer "B.Fab")
		)
		(fp_line
			(start 0.3048 0.9906)
			(end -0.3048 0.9906)
			(stroke
				(width 0.1)
				(type default)
			)
			(layer "B.Fab")
		)
		(pad "1" smd rect
			(at 0 0 180)
			(size 0.508 0.508)
			(layers "B.Cu" "B.Mask" "B.Paste")
			(net "P3E_CPU0_PE3_OCP_TXP<11>")
		)
		(pad "2" smd rect
			(at 0 0.889 180)
			(size 0.508 0.508)
			(layers "B.Cu" "B.Mask" "B.Paste")
			(net "P3E_OCP_CPU0_PE3_C_TXP<11>")
		)
		(zone
			(layer "B.Cu")
			(hatch none 0.5)
			(connect_pads
				(clearance 0)
			)
			(min_thickness 0.25)
			(keepout
				(tracks allowed)
				(vias not_allowed)
				(pads allowed)
				(copperpour not_allowed)
				(footprints allowed)
			)
			(placement
				(enabled no)
				(sheetname "")
			)
			(fill
				(thermal_gap 0.5)
				(thermal_bridge_width 0.5)
				(island_removal_mode 0)
			)
			(polygon
				(pts
					(xy 453.263 -115.85702) (xy 453.771 -115.85702) (xy 453.771 -116.23802) (xy 453.263 -116.23802)
				)
			)
		)
		(zone
			(layer "B.Cu")
			(hatch none 0.5)
			(connect_pads
				(clearance 0)
			)
			(min_thickness 0.25)
			(keepout
				(tracks not_allowed)
				(vias allowed)
				(pads allowed)
				(copperpour not_allowed)
				(footprints allowed)
			)
			(placement
				(enabled no)
				(sheetname "")
			)
			(fill
				(thermal_gap 0.5)
				(thermal_bridge_width 0.5)
				(island_removal_mode 0)
			)
			(polygon
				(pts
					(xy 453.263 -115.85702) (xy 453.771 -115.85702) (xy 453.771 -116.23802) (xy 453.263 -116.23802)
				)
			)
		)
	)
	(footprint ""
		(layer "B.Cu")
		(at -2.5146 -127.7112 -90)
		(property "Reference" "R9M7"
			(at 0 0 90)
			(layer "B.SilkS")
			(hide yes)
			(effects
				(font
					(size 1.27 1.27)
				)
				(justify mirror)
			)
		)
		(property "Value" ""
			(at 0 0 90)
			(layer "B.Fab")
			(effects
				(font
					(size 1.27 1.27)
				)
				(justify mirror)
			)
		)
		(duplicate_pad_numbers_are_jumpers no)
		(fp_rect
			(start 0.2794 0.9906)
			(end -0.2794 -0.1016)
			(stroke
				(width 0)
				(type default)
			)
			(fill no)
			(layer "B.CrtYd")
		)
		(fp_line
			(start -0.2794 0.9906)
			(end -0.2794 -0.1016)
			(stroke
				(width 0.1)
				(type default)
			)
			(layer "B.Fab")
		)
		(fp_line
			(start 0.2794 0.9906)
			(end -0.2794 0.9906)
			(stroke
				(width 0.1)
				(type default)
			)
			(layer "B.Fab")
		)
		(fp_line
			(start -0.2794 -0.1016)
			(end 0.2794 -0.1016)
			(stroke
				(width 0.1)
				(type default)
			)
			(layer "B.Fab")
		)
		(fp_line
			(start 0.2794 -0.1016)
			(end 0.2794 0.9906)
			(stroke
				(width 0.1)
				(type default)
			)
			(layer "B.Fab")
		)
		(pad "1" smd rect
			(at 0 0 90)
			(size 0.508 0.508)
			(layers "B.Cu" "B.Mask" "B.Paste")
			(net "PVCCIO_CPU1")
		)
		(pad "2" smd rect
			(at 0 0.889 90)
			(size 0.508 0.508)
			(layers "B.Cu" "B.Mask" "B.Paste")
			(net "SVID_DIO1_CPU1_R")
		)
		(zone
			(layer "B.Cu")
			(hatch none 0.5)
			(connect_pads
				(clearance 0)
			)
			(min_thickness 0.25)
			(keepout
				(tracks not_allowed)
				(vias allowed)
				(pads allowed)
				(copperpour not_allowed)
				(footprints allowed)
			)
			(placement
				(enabled no)
				(sheetname "")
			)
			(fill
				(thermal_gap 0.5)
				(thermal_bridge_width 0.5)
				(island_removal_mode 0)
			)
			(polygon
				(pts
					(xy -3.1496 -127.4572) (xy -2.7686 -127.4572) (xy -2.7686 -127.9652) (xy -3.1496 -127.9652)
				)
			)
		)
		(zone
			(layer "B.Cu")
			(hatch none 0.5)
			(connect_pads
				(clearance 0)
			)
			(min_thickness 0.25)
			(keepout
				(tracks allowed)
				(vias not_allowed)
				(pads allowed)
				(copperpour not_allowed)
				(footprints allowed)
			)
			(placement
				(enabled no)
				(sheetname "")
			)
			(fill
				(thermal_gap 0.5)
				(thermal_bridge_width 0.5)
				(island_removal_mode 0)
			)
			(polygon
				(pts
					(xy -3.1496 -127.4572) (xy -2.7686 -127.4572) (xy -2.7686 -127.9652) (xy -3.1496 -127.9652)
				)
			)
		)
	)
	(footprint ""
		(layer "B.Cu")
		(at 32.832802 -56.646064 90)
		(property "Reference" "C9R11"
			(at 0 0 90)
			(layer "B.SilkS")
			(hide yes)
			(effects
				(font
					(size 1.27 1.27)
				)
				(justify mirror)
			)
		)
		(property "Value" ""
			(at 0 0 90)
			(layer "B.Fab")
			(effects
				(font
					(size 1.27 1.27)
				)
				(justify mirror)
			)
		)
		(duplicate_pad_numbers_are_jumpers no)
		(fp_poly
			(pts
				(xy 0.7239 -0.2159) (xy -0.7239 -0.2159) (xy -0.7239 1.9939) (xy 0.7239 1.9939)
			)
			(stroke
				(width 0)
				(type default)
			)
			(fill no)
			(layer "B.CrtYd")
		)
		(fp_line
			(start 0.7239 -0.2159)
			(end 0.7239 1.9939)
			(stroke
				(width 0.1)
				(type default)
			)
			(layer "B.Fab")
		)
		(fp_line
			(start -0.7239 -0.2159)
			(end 0.7239 -0.2159)
			(stroke
				(width 0.1)
				(type default)
			)
			(layer "B.Fab")
		)
		(fp_line
			(start 0.7239 1.9939)
			(end -0.7239 1.9939)
			(stroke
				(width 0.1)
				(type default)
			)
			(layer "B.Fab")
		)
		(fp_line
			(start -0.7239 1.9939)
			(end -0.7239 -0.2159)
			(stroke
				(width 0.1)
				(type default)
			)
			(layer "B.Fab")
		)
		(pad "1" smd rect
			(at 0 0 270)
			(size 1.27 1.016)
			(layers "B.Cu" "B.Mask" "B.Paste")
			(net "VR_FET_SW_P12V_STBY_PVCCIN_CPU1")
		)
		(pad "2" smd rect
			(at 0 1.778 270)
			(size 1.27 1.016)
			(layers "B.Cu" "B.Mask" "B.Paste")
			(net "GND")
		)
		(zone
			(layer "B.Cu")
			(hatch none 0.5)
			(connect_pads
				(clearance 0)
			)
			(min_thickness 0.25)
			(keepout
				(tracks not_allowed)
				(vias allowed)
				(pads allowed)
				(copperpour not_allowed)
				(footprints allowed)
			)
			(placement
				(enabled no)
				(sheetname "")
			)
			(fill
				(thermal_gap 0.5)
				(thermal_bridge_width 0.5)
				(island_removal_mode 0)
			)
			(polygon
				(pts
					(xy 33.340802 -57.281064) (xy 33.340802 -56.011064) (xy 34.102802 -56.011064) (xy 34.102802 -57.281064)
				)
			)
		)
	)
	(footprint ""
		(layer "B.Cu")
		(at 15.77848 -75.35672 90)
		(property "Reference" "R9P24"
			(at 0 0 90)
			(layer "B.SilkS")
			(hide yes)
			(effects
				(font
					(size 1.27 1.27)
				)
				(justify mirror)
			)
		)
		(property "Value" ""
			(at 0 0 90)
			(layer "B.Fab")
			(effects
				(font
					(size 1.27 1.27)
				)
				(justify mirror)
			)
		)
		(duplicate_pad_numbers_are_jumpers no)
		(fp_rect
			(start -0.2794 -0.1016)
			(end 0.2794 0.9906)
			(stroke
				(width 0)
				(type default)
			)
			(fill no)
			(layer "B.CrtYd")
		)
		(fp_line
			(start 0.2794 -0.1016)
			(end 0.2794 0.9906)
			(stroke
				(width 0.1)
				(type default)
			)
			(layer "B.Fab")
		)
		(fp_line
			(start -0.2794 -0.1016)
			(end 0.2794 -0.1016)
			(stroke
				(width 0.1)
				(type default)
			)
			(layer "B.Fab")
		)
		(fp_line
			(start 0.2794 0.9906)
			(end -0.2794 0.9906)
			(stroke
				(width 0.1)
				(type default)
			)
			(layer "B.Fab")
		)
		(fp_line
			(start -0.2794 0.9906)
			(end -0.2794 -0.1016)
			(stroke
				(width 0.1)
				(type default)
			)
			(layer "B.Fab")
		)
		(pad "1" smd rect
			(at 0 0 270)
			(size 0.508 0.508)
			(layers "B.Cu" "B.Mask" "B.Paste")
			(net "A_HSC_PWGIN")
		)
		(pad "2" smd rect
			(at 0 0.889 270)
			(size 0.508 0.508)
			(layers "B.Cu" "B.Mask" "B.Paste")
			(net "AGND_HSC")
		)
		(zone
			(layer "B.Cu")
			(hatch none 0.5)
			(connect_pads
				(clearance 0)
			)
			(min_thickness 0.25)
			(keepout
				(tracks allowed)
				(vias not_allowed)
				(pads allowed)
				(copperpour not_allowed)
				(footprints allowed)
			)
			(placement
				(enabled no)
				(sheetname "")
			)
			(fill
				(thermal_gap 0.5)
				(thermal_bridge_width 0.5)
				(island_removal_mode 0)
			)
			(polygon
				(pts
					(xy 16.03248 -75.10272) (xy 16.41348 -75.10272) (xy 16.41348 -75.61072) (xy 16.03248 -75.61072)
				)
			)
		)
		(zone
			(layer "B.Cu")
			(hatch none 0.5)
			(connect_pads
				(clearance 0)
			)
			(min_thickness 0.25)
			(keepout
				(tracks not_allowed)
				(vias allowed)
				(pads allowed)
				(copperpour not_allowed)
				(footprints allowed)
			)
			(placement
				(enabled no)
				(sheetname "")
			)
			(fill
				(thermal_gap 0.5)
				(thermal_bridge_width 0.5)
				(island_removal_mode 0)
			)
			(polygon
				(pts
					(xy 16.03248 -75.10272) (xy 16.41348 -75.10272) (xy 16.41348 -75.61072) (xy 16.03248 -75.61072)
				)
			)
		)
	)
	(footprint ""
		(layer "B.Cu")
		(at 405.219408 -93.755718 -90)
		(property "Reference" "R2N23"
			(at 0 0 90)
			(layer "B.SilkS")
			(hide yes)
			(effects
				(font
					(size 1.27 1.27)
				)
				(justify mirror)
			)
		)
		(property "Value" ""
			(at 0 0 90)
			(layer "B.Fab")
			(effects
				(font
					(size 1.27 1.27)
				)
				(justify mirror)
			)
		)
		(duplicate_pad_numbers_are_jumpers no)
		(fp_poly
			(pts
				(xy 0.2794 -0.1016) (xy -0.2794 -0.1016) (xy -0.2794 0.9906) (xy 0.2794 0.9906)
			)
			(stroke
				(width 0)
				(type default)
			)
			(fill no)
			(layer "B.CrtYd")
		)
		(fp_line
			(start -0.2794 0.9906)
			(end -0.2794 -0.1016)
			(stroke
				(width 0.1)
				(type default)
			)
			(layer "B.Fab")
		)
		(fp_line
			(start 0.2794 0.9906)
			(end -0.2794 0.9906)
			(stroke
				(width 0.1)
				(type default)
			)
			(layer "B.Fab")
		)
		(fp_line
			(start -0.2794 -0.1016)
			(end 0.2794 -0.1016)
			(stroke
				(width 0.1)
				(type default)
			)
			(layer "B.Fab")
		)
		(fp_line
			(start 0.2794 -0.1016)
			(end 0.2794 0.9906)
			(stroke
				(width 0.1)
				(type default)
			)
			(layer "B.Fab")
		)
		(pad "1" smd rect
			(at 0 0 90)
			(size 0.508 0.508)
			(layers "B.Cu" "B.Mask" "B.Paste")
			(net "P3V3_STBY")
		)
		(pad "2" smd rect
			(at 0 0.889 90)
			(size 0.508 0.508)
			(layers "B.Cu" "B.Mask" "B.Paste")
			(net "FM_QAT_EN_N")
		)
		(zone
			(layer "B.Cu")
			(hatch none 0.5)
			(connect_pads
				(clearance 0)
			)
			(min_thickness 0.25)
			(keepout
				(tracks not_allowed)
				(vias allowed)
				(pads allowed)
				(copperpour not_allowed)
				(footprints allowed)
			)
			(placement
				(enabled no)
				(sheetname "")
			)
			(fill
				(thermal_gap 0.5)
				(thermal_bridge_width 0.5)
				(island_removal_mode 0)
			)
			(polygon
				(pts
					(xy 404.584408 -93.501718) (xy 404.584408 -94.009718) (xy 404.965408 -94.009718) (xy 404.965408 -93.501718)
				)
			)
		)
		(zone
			(layer "B.Cu")
			(hatch none 0.5)
			(connect_pads
				(clearance 0)
			)
			(min_thickness 0.25)
			(keepout
				(tracks allowed)
				(vias not_allowed)
				(pads allowed)
				(copperpour not_allowed)
				(footprints allowed)
			)
			(placement
				(enabled no)
				(sheetname "")
			)
			(fill
				(thermal_gap 0.5)
				(thermal_bridge_width 0.5)
				(island_removal_mode 0)
			)
			(polygon
				(pts
					(xy 404.965408 -93.501718) (xy 404.965408 -94.009718) (xy 404.584408 -94.009718) (xy 404.584408 -93.501718)
				)
			)
		)
	)
	(footprint ""
		(layer "B.Cu")
		(at 380.492 -131.953 -90)
		(property "Reference" "FB3M3"
			(at 0 0 90)
			(layer "B.SilkS")
			(hide yes)
			(effects
				(font
					(size 1.27 1.27)
				)
				(justify mirror)
			)
		)
		(property "Value" ""
			(at 0 0 90)
			(layer "B.Fab")
			(effects
				(font
					(size 1.27 1.27)
				)
				(justify mirror)
			)
		)
		(duplicate_pad_numbers_are_jumpers no)
		(fp_poly
			(pts
				(xy 0.15113 -0.47498) (xy -1.59893 -0.47498) (xy -1.59893 0.47498) (xy 0.15113 0.47498)
			)
			(stroke
				(width 0)
				(type default)
			)
			(fill no)
			(layer "B.CrtYd")
		)
		(fp_line
			(start -1.59893 0.47498)
			(end 0.15113 0.47498)
			(stroke
				(width 0.1)
				(type default)
			)
			(layer "B.Fab")
		)
		(fp_line
			(start 0.15113 0.47498)
			(end 0.15113 -0.47498)
			(stroke
				(width 0.1)
				(type default)
			)
			(layer "B.Fab")
		)
		(fp_line
			(start -1.59893 -0.47498)
			(end -1.59893 0.47498)
			(stroke
				(width 0.1)
				(type default)
			)
			(layer "B.Fab")
		)
		(fp_line
			(start 0.15113 -0.47498)
			(end -1.59893 -0.47498)
			(stroke
				(width 0.1)
				(type default)
			)
			(layer "B.Fab")
		)
		(pad "1" smd rect
			(at 0 0 90)
			(size 0.9398 0.9398)
			(layers "B.Cu" "B.Mask" "B.Paste")
			(net "P1V05_PCH_STBY")
		)
		(pad "2" smd rect
			(at -1.4478 0 90)
			(size 0.9398 0.9398)
			(layers "B.Cu" "B.Mask" "B.Paste")
			(net "P1V05_PCH_STBY_VCCA_XTAL")
		)
		(zone
			(layer "B.Cu")
			(hatch none 0.5)
			(connect_pads
				(clearance 0)
			)
			(min_thickness 0.25)
			(keepout
				(tracks allowed)
				(vias not_allowed)
				(pads allowed)
				(copperpour not_allowed)
				(footprints allowed)
			)
			(placement
				(enabled no)
				(sheetname "")
			)
			(fill
				(thermal_gap 0.5)
				(thermal_bridge_width 0.5)
				(island_removal_mode 0)
			)
			(polygon
				(pts
					(xy 380.0221 -132.4229) (xy 380.9619 -132.4229) (xy 380.9619 -132.9309) (xy 380.0221 -132.9309)
				)
			)
		)
	)
	(footprint ""
		(layer "B.Cu")
		(at 476.310198 -124.756926)
		(property "Reference" "CR1M2"
			(at 1.082802 -1.040384 0)
			(unlocked yes)
			(layer "B.SilkS")
			(effects
				(font
					(size 0.7874 0.5842)
					(thickness 0.1524)
				)
				(justify left mirror)
			)
		)
		(property "Value" ""
			(at 0 0 0)
			(layer "B.Fab")
			(effects
				(font
					(size 1.27 1.27)
				)
				(justify mirror)
			)
		)
		(duplicate_pad_numbers_are_jumpers no)
		(fp_circle
			(center 0.690626 -0.00254)
			(end 0.817626 -0.00254)
			(stroke
				(width 0.254)
				(type default)
			)
			(fill no)
			(layer "B.SilkS")
		)
		(fp_rect
			(start 0.225552 2.167382)
			(end -0.809498 -0.167386)
			(stroke
				(width 0)
				(type default)
			)
			(fill no)
			(layer "B.CrtYd")
		)
		(fp_line
			(start -0.809498 -0.167386)
			(end -0.809498 2.167382)
			(stroke
				(width 0.1)
				(type default)
			)
			(layer "B.Fab")
		)
		(fp_line
			(start -0.809498 2.167382)
			(end 0.225552 2.167382)
			(stroke
				(width 0.1)
				(type default)
			)
			(layer "B.Fab")
		)
		(fp_line
			(start 0.225552 -0.167386)
			(end -0.809498 -0.167386)
			(stroke
				(width 0.1)
				(type default)
			)
			(layer "B.Fab")
		)
		(fp_line
			(start 0.225552 2.167382)
			(end 0.225552 -0.167386)
			(stroke
				(width 0.1)
				(type default)
			)
			(layer "B.Fab")
		)
		(fp_circle
			(center 0.589026 -0.5334)
			(end 0.716026 -0.5334)
			(stroke
				(width 0.254)
				(type default)
			)
			(fill no)
			(layer "B.Fab")
		)
		(pad "1" smd rect
			(at 0 0 180)
			(size 0.3556 0.2032)
			(layers "B.Cu" "B.Mask" "B.Paste")
			(net "USB2_P01_ESD_DP")
		)
		(pad "2" smd rect
			(at 0 0.500126 180)
			(size 0.3556 0.2032)
			(layers "B.Cu" "B.Mask" "B.Paste")
			(net "USB2_P01_ESD_DN")
		)
		(pad "3" smd rect
			(at -0.2921 0.999998 180)
			(size 0.9398 0.4064)
			(layers "B.Cu" "B.Mask" "B.Paste")
			(net "GND")
		)
		(pad "4" smd rect
			(at 0 1.500124 180)
			(size 0.3556 0.2032)
			(layers "B.Cu" "B.Mask" "B.Paste")
			(net "TP_USB_ESD_AC2")
		)
		(pad "5" smd rect
			(at 0 1.999996 180)
			(size 0.3556 0.2032)
			(layers "B.Cu" "B.Mask" "B.Paste")
			(net "TP_USB_ESD_AC3")
		)
		(pad "6" smd rect
			(at -0.583946 1.999996 180)
			(size 0.3556 0.2032)
			(layers "B.Cu" "B.Mask" "B.Paste")
			(net "TP_USB_ESD_OUT3")
		)
		(pad "7" smd rect
			(at -0.583946 1.500124 180)
			(size 0.3556 0.2032)
			(layers "B.Cu" "B.Mask" "B.Paste")
			(net "TP_USB_ESD_OUT2")
		)
		(pad "8" smd rect
			(at -0.583946 0.500126 180)
			(size 0.3556 0.2032)
			(layers "B.Cu" "B.Mask" "B.Paste")
			(net "USB2_P01_ESD_DN")
		)
		(pad "9" smd rect
			(at -0.583946 0 180)
			(size 0.3556 0.2032)
			(layers "B.Cu" "B.Mask" "B.Paste")
			(net "USB2_P01_ESD_DP")
		)
	)
	(footprint ""
		(layer "B.Cu")
		(at 492.540798 -26.257758 90)
		(property "Reference" "C1R25"
			(at 0.8382 -0.67818 90)
			(unlocked yes)
			(layer "B.SilkS")
			(effects
				(font
					(size 0.4064 0.254)
					(thickness 0.1524)
				)
				(justify left mirror)
			)
		)
		(property "Value" ""
			(at 0 0 90)
			(layer "B.Fab")
			(effects
				(font
					(size 1.27 1.27)
				)
				(justify mirror)
			)
		)
		(duplicate_pad_numbers_are_jumpers no)
		(fp_poly
			(pts
				(xy -0.3048 -0.1016) (xy -0.3048 0.9906) (xy 0.3048 0.9906) (xy 0.3048 -0.1016)
			)
			(stroke
				(width 0)
				(type default)
			)
			(fill no)
			(layer "B.CrtYd")
		)
		(fp_line
			(start 0.3048 -0.1016)
			(end 0.3048 0.9906)
			(stroke
				(width 0.1)
				(type default)
			)
			(layer "B.Fab")
		)
		(fp_line
			(start -0.3048 -0.1016)
			(end 0.3048 -0.1016)
			(stroke
				(width 0.1)
				(type default)
			)
			(layer "B.Fab")
		)
		(fp_line
			(start 0.3048 0.9906)
			(end -0.3048 0.9906)
			(stroke
				(width 0.1)
				(type default)
			)
			(layer "B.Fab")
		)
		(fp_line
			(start -0.3048 0.9906)
			(end -0.3048 -0.1016)
			(stroke
				(width 0.1)
				(type default)
			)
			(layer "B.Fab")
		)
		(pad "1" smd rect
			(at 0 0 270)
			(size 0.508 0.508)
			(layers "B.Cu" "B.Mask" "B.Paste")
			(net "P3V3_STBY")
		)
		(pad "2" smd rect
			(at 0 0.889 270)
			(size 0.508 0.508)
			(layers "B.Cu" "B.Mask" "B.Paste")
			(net "GND")
		)
		(zone
			(layer "B.Cu")
			(hatch none 0.5)
			(connect_pads
				(clearance 0)
			)
			(min_thickness 0.25)
			(keepout
				(tracks allowed)
				(vias not_allowed)
				(pads allowed)
				(copperpour not_allowed)
				(footprints allowed)
			)
			(placement
				(enabled no)
				(sheetname "")
			)
			(fill
				(thermal_gap 0.5)
				(thermal_bridge_width 0.5)
				(island_removal_mode 0)
			)
			(polygon
				(pts
					(xy 492.794798 -26.511758) (xy 492.794798 -26.003758) (xy 493.175798 -26.003758) (xy 493.175798 -26.511758)
				)
			)
		)
		(zone
			(layer "B.Cu")
			(hatch none 0.5)
			(connect_pads
				(clearance 0)
			)
			(min_thickness 0.25)
			(keepout
				(tracks not_allowed)
				(vias allowed)
				(pads allowed)
				(copperpour not_allowed)
				(footprints allowed)
			)
			(placement
				(enabled no)
				(sheetname "")
			)
			(fill
				(thermal_gap 0.5)
				(thermal_bridge_width 0.5)
				(island_removal_mode 0)
			)
			(polygon
				(pts
					(xy 493.175798 -26.511758) (xy 493.175798 -26.003758) (xy 492.794798 -26.003758) (xy 492.794798 -26.511758)
				)
			)
		)
	)
	(footprint ""
		(layer "B.Cu")
		(at 39.031164 -35.658552 180)
		(property "Reference" "C9T3"
			(at -3.10007 3.24612 270)
			(unlocked yes)
			(layer "B.SilkS")
			(effects
				(font
					(size 0.7874 0.5842)
					(thickness 0.1524)
				)
				(justify mirror)
			)
		)
		(property "Value" ""
			(at 0 0 0)
			(layer "B.Fab")
			(effects
				(font
					(size 1.27 1.27)
				)
				(justify mirror)
			)
		)
		(duplicate_pad_numbers_are_jumpers no)
		(fp_line
			(start 2.563114 1.633728)
			(end 1.6002 1.633728)
			(stroke
				(width 0.1524)
				(type default)
			)
			(layer "B.SilkS")
		)
		(fp_line
			(start 2.563114 -1.616456)
			(end 2.563114 1.633728)
			(stroke
				(width 0.1524)
				(type default)
			)
			(layer "B.SilkS")
		)
		(fp_line
			(start 2.286 7.366)
			(end 2.286 1.632712)
			(stroke
				(width 0.1524)
				(type default)
			)
			(layer "B.SilkS")
		)
		(fp_line
			(start 2.286 7.366)
			(end 1.60147 7.366)
			(stroke
				(width 0.1524)
				(type default)
			)
			(layer "B.SilkS")
		)
		(fp_line
			(start 1.6002 -1.616456)
			(end 2.563114 -1.616456)
			(stroke
				(width 0.1524)
				(type default)
			)
			(layer "B.SilkS")
		)
		(fp_line
			(start -1.6002 -1.616456)
			(end -2.504948 -1.616456)
			(stroke
				(width 0.1524)
				(type default)
			)
			(layer "B.SilkS")
		)
		(fp_line
			(start -2.286 7.366)
			(end -1.600708 7.366)
			(stroke
				(width 0.1524)
				(type default)
			)
			(layer "B.SilkS")
		)
		(fp_line
			(start -2.286 7.366)
			(end -2.286 1.63195)
			(stroke
				(width 0.1524)
				(type default)
			)
			(layer "B.SilkS")
		)
		(fp_line
			(start -2.504948 1.633728)
			(end -1.6002 1.633728)
			(stroke
				(width 0.1524)
				(type default)
			)
			(layer "B.SilkS")
		)
		(fp_line
			(start -2.504948 -1.616456)
			(end -2.504948 1.633728)
			(stroke
				(width 0.1524)
				(type default)
			)
			(layer "B.SilkS")
		)
		(fp_rect
			(start 2.286 7.366)
			(end -2.286 -0.254)
			(stroke
				(width 0)
				(type default)
			)
			(fill no)
			(layer "B.CrtYd")
		)
		(fp_line
			(start 2.286 7.366)
			(end 2.286 -0.254)
			(stroke
				(width 0.1)
				(type default)
			)
			(layer "B.Fab")
		)
		(fp_line
			(start 2.286 -0.254)
			(end -2.286 -0.254)
			(stroke
				(width 0.1)
				(type default)
			)
			(layer "B.Fab")
		)
		(fp_line
			(start -2.286 7.366)
			(end 2.286 7.366)
			(stroke
				(width 0.1)
				(type default)
			)
			(layer "B.Fab")
		)
		(fp_line
			(start -2.286 -0.254)
			(end -2.286 7.366)
			(stroke
				(width 0.1)
				(type default)
			)
			(layer "B.Fab")
		)
		(pad "1" smd rect
			(at 0 0)
			(size 2.54 3.048)
			(layers "B.Cu" "B.Mask" "B.Paste")
			(net "P12V_STBY")
		)
		(pad "2" smd rect
			(at 0 7.112)
			(size 2.54 3.048)
			(layers "B.Cu" "B.Mask" "B.Paste")
			(net "GND")
		)
	)
	(footprint ""
		(layer "B.Cu")
		(at 472.354402 -38.340792 -90)
		(property "Reference" "R1T9"
			(at 0 0 90)
			(layer "B.SilkS")
			(hide yes)
			(effects
				(font
					(size 1.27 1.27)
				)
				(justify mirror)
			)
		)
		(property "Value" ""
			(at 0 0 90)
			(layer "B.Fab")
			(effects
				(font
					(size 1.27 1.27)
				)
				(justify mirror)
			)
		)
		(duplicate_pad_numbers_are_jumpers no)
		(fp_poly
			(pts
				(xy 0.2794 -0.1016) (xy -0.2794 -0.1016) (xy -0.2794 0.9906) (xy 0.2794 0.9906)
			)
			(stroke
				(width 0)
				(type default)
			)
			(fill no)
			(layer "B.CrtYd")
		)
		(fp_line
			(start -0.2794 0.9906)
			(end -0.2794 -0.1016)
			(stroke
				(width 0.1)
				(type default)
			)
			(layer "B.Fab")
		)
		(fp_line
			(start 0.2794 0.9906)
			(end -0.2794 0.9906)
			(stroke
				(width 0.1)
				(type default)
			)
			(layer "B.Fab")
		)
		(fp_line
			(start -0.2794 -0.1016)
			(end 0.2794 -0.1016)
			(stroke
				(width 0.1)
				(type default)
			)
			(layer "B.Fab")
		)
		(fp_line
			(start 0.2794 -0.1016)
			(end 0.2794 0.9906)
			(stroke
				(width 0.1)
				(type default)
			)
			(layer "B.Fab")
		)
		(pad "1" smd rect
			(at 0 0 90)
			(size 0.508 0.508)
			(layers "B.Cu" "B.Mask" "B.Paste")
			(net "PWRGD_P1V2_BMC_STBY_R")
		)
		(pad "2" smd rect
			(at 0 0.889 90)
			(size 0.508 0.508)
			(layers "B.Cu" "B.Mask" "B.Paste")
			(net "PWRGD_P1V2_BMC_STBY")
		)
		(zone
			(layer "B.Cu")
			(hatch none 0.5)
			(connect_pads
				(clearance 0)
			)
			(min_thickness 0.25)
			(keepout
				(tracks not_allowed)
				(vias allowed)
				(pads allowed)
				(copperpour not_allowed)
				(footprints allowed)
			)
			(placement
				(enabled no)
				(sheetname "")
			)
			(fill
				(thermal_gap 0.5)
				(thermal_bridge_width 0.5)
				(island_removal_mode 0)
			)
			(polygon
				(pts
					(xy 471.719402 -38.086792) (xy 471.719402 -38.594792) (xy 472.100402 -38.594792) (xy 472.100402 -38.086792)
				)
			)
		)
		(zone
			(layer "B.Cu")
			(hatch none 0.5)
			(connect_pads
				(clearance 0)
			)
			(min_thickness 0.25)
			(keepout
				(tracks allowed)
				(vias not_allowed)
				(pads allowed)
				(copperpour not_allowed)
				(footprints allowed)
			)
			(placement
				(enabled no)
				(sheetname "")
			)
			(fill
				(thermal_gap 0.5)
				(thermal_bridge_width 0.5)
				(island_removal_mode 0)
			)
			(polygon
				(pts
					(xy 472.100402 -38.086792) (xy 472.100402 -38.594792) (xy 471.719402 -38.594792) (xy 471.719402 -38.086792)
				)
			)
		)
	)
	(footprint ""
		(layer "B.Cu")
		(at 481.321872 -56.090058 90)
		(property "Reference" "U8E4"
			(at -0.183896 1.760982 180)
			(unlocked yes)
			(layer "B.SilkS")
			(effects
				(font
					(size 0.7874 0.5842)
					(thickness 0.1524)
				)
				(justify left mirror)
			)
		)
		(property "Value" ""
			(at 0 0 90)
			(layer "B.Fab")
			(effects
				(font
					(size 1.27 1.27)
				)
				(justify mirror)
			)
		)
		(duplicate_pad_numbers_are_jumpers no)
		(fp_circle
			(center 0.4699 -0.8382)
			(end 0.4699 -0.7112)
			(stroke
				(width 0.254)
				(type default)
			)
			(fill no)
			(layer "B.SilkS")
		)
		(fp_poly
			(pts
				(xy -0.21463 -0.450088) (xy -1.56337 -0.450088) (xy -1.56337 1.75006) (xy -0.21463 1.75006)
			)
			(stroke
				(width 0)
				(type default)
			)
			(fill no)
			(layer "B.CrtYd")
		)
		(fp_line
			(start -0.21463 -0.450088)
			(end -1.56337 -0.450088)
			(stroke
				(width 0.1)
				(type default)
			)
			(layer "B.Fab")
		)
		(fp_line
			(start -1.56337 -0.450088)
			(end -1.56337 1.75006)
			(stroke
				(width 0.1)
				(type default)
			)
			(layer "B.Fab")
		)
		(fp_line
			(start -0.21463 1.75006)
			(end -0.21463 -0.450088)
			(stroke
				(width 0.1)
				(type default)
			)
			(layer "B.Fab")
		)
		(fp_line
			(start -1.56337 1.75006)
			(end -0.21463 1.75006)
			(stroke
				(width 0.1)
				(type default)
			)
			(layer "B.Fab")
		)
		(fp_circle
			(center 0.4699 -0.8382)
			(end 0.4699 -0.7112)
			(stroke
				(width 0.254)
				(type default)
			)
			(fill no)
			(layer "B.Fab")
		)
		(pad "1" smd rect
			(at 0 0 270)
			(size 1.016 0.381)
			(layers "B.Cu" "B.Mask" "B.Paste")
			(net "PU_TRI_STATE_EN")
		)
		(pad "2" smd rect
			(at 0 0.649986 270)
			(size 1.016 0.381)
			(layers "B.Cu" "B.Mask" "B.Paste")
			(net "FM_ALL_WAKE_N")
		)
		(pad "3" smd rect
			(at 0 1.299972 270)
			(size 1.016 0.381)
			(layers "B.Cu" "B.Mask" "B.Paste")
			(net "GND")
		)
		(pad "4" smd rect
			(at -1.778 1.299972 270)
			(size 1.016 0.381)
			(layers "B.Cu" "B.Mask" "B.Paste")
			(net "IRQ_LVC3_WAKE_R_N")
		)
		(pad "5" smd rect
			(at -1.778 0 270)
			(size 1.016 0.381)
			(layers "B.Cu" "B.Mask" "B.Paste")
			(net "P3V3_STBY")
		)
	)
	(footprint ""
		(layer "B.Cu")
		(at 425.196 -141.986)
		(property "Reference" "C2L41"
			(at 0 0 0)
			(layer "B.SilkS")
			(hide yes)
			(effects
				(font
					(size 1.27 1.27)
				)
				(justify mirror)
			)
		)
		(property "Value" ""
			(at 0 0 0)
			(layer "B.Fab")
			(effects
				(font
					(size 1.27 1.27)
				)
				(justify mirror)
			)
		)
		(duplicate_pad_numbers_are_jumpers no)
		(fp_poly
			(pts
				(xy -0.3048 -0.1016) (xy -0.3048 0.9906) (xy 0.3048 0.9906) (xy 0.3048 -0.1016)
			)
			(stroke
				(width 0)
				(type default)
			)
			(fill no)
			(layer "B.CrtYd")
		)
		(fp_line
			(start -0.3048 -0.1016)
			(end 0.3048 -0.1016)
			(stroke
				(width 0.1)
				(type default)
			)
			(layer "B.Fab")
		)
		(fp_line
			(start -0.3048 0.9906)
			(end -0.3048 -0.1016)
			(stroke
				(width 0.1)
				(type default)
			)
			(layer "B.Fab")
		)
		(fp_line
			(start 0.3048 -0.1016)
			(end 0.3048 0.9906)
			(stroke
				(width 0.1)
				(type default)
			)
			(layer "B.Fab")
		)
		(fp_line
			(start 0.3048 0.9906)
			(end -0.3048 0.9906)
			(stroke
				(width 0.1)
				(type default)
			)
			(layer "B.Fab")
		)
		(pad "1" smd rect
			(at 0 0 180)
			(size 0.508 0.508)
			(layers "B.Cu" "B.Mask" "B.Paste")
			(net "SATA6G_P2_TX_C_DP")
		)
		(pad "2" smd rect
			(at 0 0.889 180)
			(size 0.508 0.508)
			(layers "B.Cu" "B.Mask" "B.Paste")
			(net "SATA6G_PCH_PCIE_UP_SATA_TXP<2>")
		)
		(zone
			(layer "B.Cu")
			(hatch none 0.5)
			(connect_pads
				(clearance 0)
			)
			(min_thickness 0.25)
			(keepout
				(tracks allowed)
				(vias not_allowed)
				(pads allowed)
				(copperpour not_allowed)
				(footprints allowed)
			)
			(placement
				(enabled no)
				(sheetname "")
			)
			(fill
				(thermal_gap 0.5)
				(thermal_bridge_width 0.5)
				(island_removal_mode 0)
			)
			(polygon
				(pts
					(xy 425.45 -141.732) (xy 424.942 -141.732) (xy 424.942 -141.351) (xy 425.45 -141.351)
				)
			)
		)
		(zone
			(layer "B.Cu")
			(hatch none 0.5)
			(connect_pads
				(clearance 0)
			)
			(min_thickness 0.25)
			(keepout
				(tracks not_allowed)
				(vias allowed)
				(pads allowed)
				(copperpour not_allowed)
				(footprints allowed)
			)
			(placement
				(enabled no)
				(sheetname "")
			)
			(fill
				(thermal_gap 0.5)
				(thermal_bridge_width 0.5)
				(island_removal_mode 0)
			)
			(polygon
				(pts
					(xy 425.45 -141.351) (xy 424.942 -141.351) (xy 424.942 -141.732) (xy 425.45 -141.732)
				)
			)
		)
	)
	(footprint ""
		(layer "B.Cu")
		(at 107.8611 -135.4074 90)
		(property "Reference" "C7M2"
			(at -1.848866 0.752348 90)
			(unlocked yes)
			(layer "B.SilkS")
			(effects
				(font
					(size 1.27 0.9652)
					(thickness 0.1524)
				)
				(justify mirror)
			)
		)
		(property "Value" ""
			(at 0 0 90)
			(layer "B.Fab")
			(effects
				(font
					(size 1.27 1.27)
				)
				(justify mirror)
			)
		)
		(duplicate_pad_numbers_are_jumpers no)
		(fp_rect
			(start 0.500126 1.598422)
			(end -0.500126 -0.201422)
			(stroke
				(width 0)
				(type default)
			)
			(fill no)
			(layer "B.CrtYd")
		)
		(fp_line
			(start 0.500126 -0.201422)
			(end -0.500126 -0.201422)
			(stroke
				(width 0.1)
				(type default)
			)
			(layer "B.Fab")
		)
		(fp_line
			(start -0.500126 -0.201422)
			(end -0.500126 1.598422)
			(stroke
				(width 0.1)
				(type default)
			)
			(layer "B.Fab")
		)
		(fp_line
			(start 0.500126 1.598422)
			(end 0.500126 -0.201422)
			(stroke
				(width 0.1)
				(type default)
			)
			(layer "B.Fab")
		)
		(fp_line
			(start -0.500126 1.598422)
			(end 0.500126 1.598422)
			(stroke
				(width 0.1)
				(type default)
			)
			(layer "B.Fab")
		)
		(pad "1" smd rect
			(at 0 0)
			(size 0.889 0.9906)
			(layers "B.Cu" "B.Mask" "B.Paste")
			(net "PVDDQ_KLM")
		)
		(pad "2" smd rect
			(at 0 1.397)
			(size 0.889 0.9906)
			(layers "B.Cu" "B.Mask" "B.Paste")
			(net "GND")
		)
		(zone
			(layer "B.Cu")
			(hatch none 0.5)
			(connect_pads
				(clearance 0)
			)
			(min_thickness 0.25)
			(keepout
				(tracks allowed)
				(vias not_allowed)
				(pads allowed)
				(copperpour not_allowed)
				(footprints allowed)
			)
			(placement
				(enabled no)
				(sheetname "")
			)
			(fill
				(thermal_gap 0.5)
				(thermal_bridge_width 0.5)
				(island_removal_mode 0)
			)
			(polygon
				(pts
					(xy 108.8136 -135.9027) (xy 108.3056 -135.9027) (xy 108.3056 -134.9121) (xy 108.8136 -134.9121)
				)
			)
		)
		(zone
			(layer "B.Cu")
			(hatch none 0.5)
			(connect_pads
				(clearance 0)
			)
			(min_thickness 0.25)
			(keepout
				(tracks not_allowed)
				(vias allowed)
				(pads allowed)
				(copperpour not_allowed)
				(footprints allowed)
			)
			(placement
				(enabled no)
				(sheetname "")
			)
			(fill
				(thermal_gap 0.5)
				(thermal_bridge_width 0.5)
				(island_removal_mode 0)
			)
			(polygon
				(pts
					(xy 108.8136 -135.9027) (xy 108.3056 -135.9027) (xy 108.3056 -134.9121) (xy 108.8136 -134.9121)
				)
			)
		)
	)
	(footprint ""
		(layer "B.Cu")
		(at 313.424062 -27.727148 -90)
		(property "Reference" "Q8D1"
			(at 0 -1.2065 270)
			(unlocked yes)
			(layer "B.SilkS")
			(effects
				(font
					(size 1.27 0.9652)
					(thickness 0.1524)
				)
				(justify left mirror)
			)
		)
		(property "Value" ""
			(at 0 0 90)
			(layer "B.Fab")
			(effects
				(font
					(size 1.27 1.27)
				)
				(justify mirror)
			)
		)
		(duplicate_pad_numbers_are_jumpers no)
		(fp_circle
			(center 0.848614 -0.6477)
			(end 0.848614 -0.7747)
			(stroke
				(width 0.254)
				(type default)
			)
			(fill no)
			(layer "B.SilkS")
		)
		(fp_poly
			(pts
				(xy -0.21463 -0.450088) (xy -1.56337 -0.450088) (xy -1.56337 1.75006) (xy -0.21463 1.75006)
			)
			(stroke
				(width 0)
				(type default)
			)
			(fill no)
			(layer "B.CrtYd")
		)
		(fp_line
			(start -1.56337 1.75006)
			(end -0.21463 1.75006)
			(stroke
				(width 0.1)
				(type default)
			)
			(layer "B.Fab")
		)
		(fp_line
			(start -0.21463 1.75006)
			(end -0.21463 -0.450088)
			(stroke
				(width 0.1)
				(type default)
			)
			(layer "B.Fab")
		)
		(fp_line
			(start -1.56337 -0.450088)
			(end -1.56337 1.75006)
			(stroke
				(width 0.1)
				(type default)
			)
			(layer "B.Fab")
		)
		(fp_line
			(start -0.21463 -0.450088)
			(end -1.56337 -0.450088)
			(stroke
				(width 0.1)
				(type default)
			)
			(layer "B.Fab")
		)
		(fp_circle
			(center 0.848614 -0.6477)
			(end 0.848614 -0.7747)
			(stroke
				(width 0.254)
				(type default)
			)
			(fill no)
			(layer "B.Fab")
		)
		(pad "1" smd rect
			(at 0 0 90)
			(size 1.016 0.381)
			(layers "B.Cu" "B.Mask" "B.Paste")
			(net "GND")
		)
		(pad "2" smd rect
			(at 0 0.649986 90)
			(size 1.016 0.381)
			(layers "B.Cu" "B.Mask" "B.Paste")
			(net "IRQ_DIMM_SAVE_LVT3")
		)
		(pad "3" smd rect
			(at 0 1.299972 90)
			(size 1.016 0.381)
			(layers "B.Cu" "B.Mask" "B.Paste")
			(net "IRQ_DIMM_SAVE_LVT3")
		)
		(pad "4" smd rect
			(at -1.778 1.299972 90)
			(size 1.016 0.381)
			(layers "B.Cu" "B.Mask" "B.Paste")
			(net "GND")
		)
		(pad "5" smd rect
			(at -1.778 0.649986 90)
			(size 1.016 0.381)
			(layers "B.Cu" "B.Mask" "B.Paste")
			(net "IRQ_DIMM_SAVE_R_N")
		)
		(pad "6" smd rect
			(at -1.778 0 90)
			(size 1.016 0.381)
			(layers "B.Cu" "B.Mask" "B.Paste")
			(net "IRQ_DIMM_SAVE_LVT3_N")
		)
	)
	(footprint ""
		(layer "B.Cu")
		(at 469.197944 -11.42492)
		(property "Reference" "R2U31"
			(at 0 0 0)
			(layer "B.SilkS")
			(hide yes)
			(effects
				(font
					(size 1.27 1.27)
				)
				(justify mirror)
			)
		)
		(property "Value" ""
			(at 0 0 0)
			(layer "B.Fab")
			(effects
				(font
					(size 1.27 1.27)
				)
				(justify mirror)
			)
		)
		(duplicate_pad_numbers_are_jumpers no)
		(fp_poly
			(pts
				(xy 0.2794 -0.1016) (xy -0.2794 -0.1016) (xy -0.2794 0.9906) (xy 0.2794 0.9906)
			)
			(stroke
				(width 0)
				(type default)
			)
			(fill no)
			(layer "B.CrtYd")
		)
		(fp_line
			(start -0.2794 -0.1016)
			(end 0.2794 -0.1016)
			(stroke
				(width 0.1)
				(type default)
			)
			(layer "B.Fab")
		)
		(fp_line
			(start -0.2794 0.9906)
			(end -0.2794 -0.1016)
			(stroke
				(width 0.1)
				(type default)
			)
			(layer "B.Fab")
		)
		(fp_line
			(start 0.2794 -0.1016)
			(end 0.2794 0.9906)
			(stroke
				(width 0.1)
				(type default)
			)
			(layer "B.Fab")
		)
		(fp_line
			(start 0.2794 0.9906)
			(end -0.2794 0.9906)
			(stroke
				(width 0.1)
				(type default)
			)
			(layer "B.Fab")
		)
		(pad "1" smd rect
			(at 0 0 180)
			(size 0.508 0.508)
			(layers "B.Cu" "B.Mask" "B.Paste")
			(net "SMB_SLOTX24_BMC_STBY_LVC3_SDA")
		)
		(pad "2" smd rect
			(at 0 0.889 180)
			(size 0.508 0.508)
			(layers "B.Cu" "B.Mask" "B.Paste")
			(net "SMB_SLOTX24_STBY_LVC3_SDA_R2")
		)
		(zone
			(layer "B.Cu")
			(hatch none 0.5)
			(connect_pads
				(clearance 0)
			)
			(min_thickness 0.25)
			(keepout
				(tracks allowed)
				(vias not_allowed)
				(pads allowed)
				(copperpour not_allowed)
				(footprints allowed)
			)
			(placement
				(enabled no)
				(sheetname "")
			)
			(fill
				(thermal_gap 0.5)
				(thermal_bridge_width 0.5)
				(island_removal_mode 0)
			)
			(polygon
				(pts
					(xy 469.451944 -11.17092) (xy 468.943944 -11.17092) (xy 468.943944 -10.78992) (xy 469.451944 -10.78992)
				)
			)
		)
		(zone
			(layer "B.Cu")
			(hatch none 0.5)
			(connect_pads
				(clearance 0)
			)
			(min_thickness 0.25)
			(keepout
				(tracks not_allowed)
				(vias allowed)
				(pads allowed)
				(copperpour not_allowed)
				(footprints allowed)
			)
			(placement
				(enabled no)
				(sheetname "")
			)
			(fill
				(thermal_gap 0.5)
				(thermal_bridge_width 0.5)
				(island_removal_mode 0)
			)
			(polygon
				(pts
					(xy 469.451944 -10.78992) (xy 468.943944 -10.78992) (xy 468.943944 -11.17092) (xy 469.451944 -11.17092)
				)
			)
		)
	)
	(footprint ""
		(layer "B.Cu")
		(at 338.76996 -77.694536)
		(property "Reference" "C3P10"
			(at 0 0 0)
			(layer "B.SilkS")
			(hide yes)
			(effects
				(font
					(size 1.27 1.27)
				)
				(justify mirror)
			)
		)
		(property "Value" ""
			(at 0 0 0)
			(layer "B.Fab")
			(effects
				(font
					(size 1.27 1.27)
				)
				(justify mirror)
			)
		)
		(duplicate_pad_numbers_are_jumpers no)
		(fp_poly
			(pts
				(xy -0.3048 -0.1016) (xy -0.3048 0.9906) (xy 0.3048 0.9906) (xy 0.3048 -0.1016)
			)
			(stroke
				(width 0)
				(type default)
			)
			(fill no)
			(layer "B.CrtYd")
		)
		(fp_line
			(start -0.3048 -0.1016)
			(end 0.3048 -0.1016)
			(stroke
				(width 0.1)
				(type default)
			)
			(layer "B.Fab")
		)
		(fp_line
			(start -0.3048 0.9906)
			(end -0.3048 -0.1016)
			(stroke
				(width 0.1)
				(type default)
			)
			(layer "B.Fab")
		)
		(fp_line
			(start 0.3048 -0.1016)
			(end 0.3048 0.9906)
			(stroke
				(width 0.1)
				(type default)
			)
			(layer "B.Fab")
		)
		(fp_line
			(start 0.3048 0.9906)
			(end -0.3048 0.9906)
			(stroke
				(width 0.1)
				(type default)
			)
			(layer "B.Fab")
		)
		(pad "1" smd rect
			(at 0 0 180)
			(size 0.508 0.508)
			(layers "B.Cu" "B.Mask" "B.Paste")
			(net "P3E_CPU0_PE1_SS_TXP<0>")
		)
		(pad "2" smd rect
			(at 0 0.889 180)
			(size 0.508 0.508)
			(layers "B.Cu" "B.Mask" "B.Paste")
			(net "P3E_CPU0_PE1_SS_C_TXP<0>")
		)
		(zone
			(layer "B.Cu")
			(hatch none 0.5)
			(connect_pads
				(clearance 0)
			)
			(min_thickness 0.25)
			(keepout
				(tracks allowed)
				(vias not_allowed)
				(pads allowed)
				(copperpour not_allowed)
				(footprints allowed)
			)
			(placement
				(enabled no)
				(sheetname "")
			)
			(fill
				(thermal_gap 0.5)
				(thermal_bridge_width 0.5)
				(island_removal_mode 0)
			)
			(polygon
				(pts
					(xy 339.02396 -77.440536) (xy 338.51596 -77.440536) (xy 338.51596 -77.059536) (xy 339.02396 -77.059536)
				)
			)
		)
		(zone
			(layer "B.Cu")
			(hatch none 0.5)
			(connect_pads
				(clearance 0)
			)
			(min_thickness 0.25)
			(keepout
				(tracks not_allowed)
				(vias allowed)
				(pads allowed)
				(copperpour not_allowed)
				(footprints allowed)
			)
			(placement
				(enabled no)
				(sheetname "")
			)
			(fill
				(thermal_gap 0.5)
				(thermal_bridge_width 0.5)
				(island_removal_mode 0)
			)
			(polygon
				(pts
					(xy 339.02396 -77.059536) (xy 338.51596 -77.059536) (xy 338.51596 -77.440536) (xy 339.02396 -77.440536)
				)
			)
		)
	)
	(footprint ""
		(layer "B.Cu")
		(at 459.880208 -150.876254)
		(property "Reference" "U1L1"
			(at 6.400292 -0.849376 0)
			(unlocked yes)
			(layer "B.SilkS")
			(effects
				(font
					(size 0.7874 0.5842)
					(thickness 0.1524)
				)
				(justify left mirror)
			)
		)
		(property "Value" ""
			(at 0 0 0)
			(layer "B.Fab")
			(effects
				(font
					(size 1.27 1.27)
				)
				(justify mirror)
			)
		)
		(duplicate_pad_numbers_are_jumpers no)
		(fp_circle
			(center 1.17856 -2.466086)
			(end 1.30556 -2.466086)
			(stroke
				(width 0.254)
				(type default)
			)
			(fill no)
			(layer "B.SilkS")
		)
		(fp_rect
			(start 0.9144 0.9144)
			(end -0.9144 -0.9144)
			(stroke
				(width 0)
				(type default)
			)
			(fill yes)
			(layer "B.Paste")
		)
		(fp_rect
			(start 1.82499 1.82499)
			(end -1.82499 -1.82499)
			(stroke
				(width 0)
				(type default)
			)
			(fill no)
			(layer "B.CrtYd")
		)
		(fp_line
			(start -1.82499 -1.82499)
			(end -1.82499 1.82499)
			(stroke
				(width 0.1)
				(type default)
			)
			(layer "B.Fab")
		)
		(fp_line
			(start -1.82499 1.82499)
			(end 1.82499 1.82499)
			(stroke
				(width 0.1)
				(type default)
			)
			(layer "B.Fab")
		)
		(fp_line
			(start 1.82499 -1.82499)
			(end -1.82499 -1.82499)
			(stroke
				(width 0.1)
				(type default)
			)
			(layer "B.Fab")
		)
		(fp_line
			(start 1.82499 1.82499)
			(end 1.82499 -1.82499)
			(stroke
				(width 0.1)
				(type default)
			)
			(layer "B.Fab")
		)
		(fp_circle
			(center 1.17856 -2.466086)
			(end 1.30556 -2.466086)
			(stroke
				(width 0.254)
				(type default)
			)
			(fill no)
			(layer "B.Fab")
		)
		(pad "1" smd custom
			(at 0.750062 -1.549908 180)
			(size 0.0762 0.0762)
			(layers "B.Cu" "B.Mask" "B.Paste")
			(net "PWRGD_PVCCIN_CPU0")
			(options
				(clearance outline)
				(anchor circle)
			)
			(primitives
				(gr_poly
					(pts
						(xy 0.1524 0.381)
						(arc
							(start 0.1524 -0.2286)
							(mid 0 -0.381)
							(end -0.1524 -0.2286)
						)
						(xy -0.1524 0.381)
					)
					(width 0)
					(fill yes)
				)
			)
		)
		(pad "2" smd custom
			(at 1.549908 -0.999998 180)
			(size 0.0762 0.0762)
			(layers "B.Cu" "B.Mask" "B.Paste")
			(net "XDP_TRST_N")
			(options
				(clearance outline)
				(anchor circle)
			)
			(primitives
				(gr_poly
					(pts
						(xy -0.381 0.1524)
						(arc
							(start 0.2286 0.1524)
							(mid 0.381 0)
							(end 0.2286 -0.1524)
						)
						(xy -0.381 -0.1524)
					)
					(width 0)
					(fill yes)
				)
			)
		)
		(pad "3" smd custom
			(at 1.549908 -0.500126 180)
			(size 0.0762 0.0762)
			(layers "B.Cu" "B.Mask" "B.Paste")
			(net "XDP_CPU_TRST_N")
			(options
				(clearance outline)
				(anchor circle)
			)
			(primitives
				(gr_poly
					(pts
						(xy -0.381 0.1524)
						(arc
							(start 0.2286 0.1524)
							(mid 0.381 0)
							(end 0.2286 -0.1524)
						)
						(xy -0.381 -0.1524)
					)
					(width 0)
					(fill yes)
				)
			)
		)
		(pad "4" smd custom
			(at 1.549908 0 180)
			(size 0.0762 0.0762)
			(layers "B.Cu" "B.Mask" "B.Paste")
			(net "PWRGD_PVCCIN_CPU0")
			(options
				(clearance outline)
				(anchor circle)
			)
			(primitives
				(gr_poly
					(pts
						(xy -0.381 0.1524)
						(arc
							(start 0.2286 0.1524)
							(mid 0.381 0)
							(end 0.2286 -0.1524)
						)
						(xy -0.381 -0.1524)
					)
					(width 0)
					(fill yes)
				)
			)
		)
		(pad "5" smd custom
			(at 1.549908 0.500126 180)
			(size 0.0762 0.0762)
			(layers "B.Cu" "B.Mask" "B.Paste")
			(net "XDP_TMS")
			(options
				(clearance outline)
				(anchor circle)
			)
			(primitives
				(gr_poly
					(pts
						(xy -0.381 0.1524)
						(arc
							(start 0.2286 0.1524)
							(mid 0.381 0)
							(end 0.2286 -0.1524)
						)
						(xy -0.381 -0.1524)
					)
					(width 0)
					(fill yes)
				)
			)
		)
		(pad "6" smd custom
			(at 1.549908 0.999998 180)
			(size 0.0762 0.0762)
			(layers "B.Cu" "B.Mask" "B.Paste")
			(net "XDP_CPU_TMS")
			(options
				(clearance outline)
				(anchor circle)
			)
			(primitives
				(gr_poly
					(pts
						(xy -0.381 0.1524)
						(arc
							(start 0.2286 0.1524)
							(mid 0.381 0)
							(end 0.2286 -0.1524)
						)
						(xy -0.381 -0.1524)
					)
					(width 0)
					(fill yes)
				)
			)
		)
		(pad "7" smd custom
			(at 0.750062 1.549908 180)
			(size 0.0762 0.0762)
			(layers "B.Cu" "B.Mask" "B.Paste")
			(net "GND")
			(options
				(clearance outline)
				(anchor circle)
			)
			(primitives
				(gr_poly
					(pts
						(xy -0.1524 -0.381)
						(arc
							(start -0.1524 0.2286)
							(mid 0 0.381)
							(end 0.1524 0.2286)
						)
						(xy 0.1524 -0.381)
					)
					(width 0)
					(fill yes)
				)
			)
		)
		(pad "8" smd custom
			(at -0.769874 1.549908 180)
			(size 0.0762 0.0762)
			(layers "B.Cu" "B.Mask" "B.Paste")
			(net "XDP_CPU_TDO")
			(options
				(clearance outline)
				(anchor circle)
			)
			(primitives
				(gr_poly
					(pts
						(xy -0.1524 -0.381)
						(arc
							(start -0.1524 0.2286)
							(mid 0 0.381)
							(end 0.1524 0.2286)
						)
						(xy 0.1524 -0.381)
					)
					(width 0)
					(fill yes)
				)
			)
		)
		(pad "9" smd custom
			(at -1.549908 0.999998 180)
			(size 0.0762 0.0762)
			(layers "B.Cu" "B.Mask" "B.Paste")
			(net "XDP_TDO")
			(options
				(clearance outline)
				(anchor circle)
			)
			(primitives
				(gr_poly
					(pts
						(xy 0.381 -0.1524)
						(arc
							(start -0.2286 -0.1524)
							(mid -0.381 0)
							(end -0.2286 0.1524)
						)
						(xy 0.381 0.1524)
					)
					(width 0)
					(fill yes)
				)
			)
		)
		(pad "10" smd custom
			(at -1.549908 0.500126 180)
			(size 0.0762 0.0762)
			(layers "B.Cu" "B.Mask" "B.Paste")
			(net "PWRGD_PVCCIN_CPU0")
			(options
				(clearance outline)
				(anchor circle)
			)
			(primitives
				(gr_poly
					(pts
						(xy 0.381 -0.1524)
						(arc
							(start -0.2286 -0.1524)
							(mid -0.381 0)
							(end -0.2286 0.1524)
						)
						(xy 0.381 0.1524)
					)
					(width 0)
					(fill yes)
				)
			)
		)
		(pad "11" smd custom
			(at -1.549908 0 180)
			(size 0.0762 0.0762)
			(layers "B.Cu" "B.Mask" "B.Paste")
			(net "XDP_CPU_TDI")
			(options
				(clearance outline)
				(anchor circle)
			)
			(primitives
				(gr_poly
					(pts
						(xy 0.381 -0.1524)
						(arc
							(start -0.2286 -0.1524)
							(mid -0.381 0)
							(end -0.2286 0.1524)
						)
						(xy 0.381 0.1524)
					)
					(width 0)
					(fill yes)
				)
			)
		)
		(pad "12" smd custom
			(at -1.549908 -0.500126 180)
			(size 0.0762 0.0762)
			(layers "B.Cu" "B.Mask" "B.Paste")
			(net "XDP_TDI")
			(options
				(clearance outline)
				(anchor circle)
			)
			(primitives
				(gr_poly
					(pts
						(xy 0.381 -0.1524)
						(arc
							(start -0.2286 -0.1524)
							(mid -0.381 0)
							(end -0.2286 0.1524)
						)
						(xy 0.381 0.1524)
					)
					(width 0)
					(fill yes)
				)
			)
		)
		(pad "13" smd custom
			(at -1.549908 -0.999998 180)
			(size 0.0762 0.0762)
			(layers "B.Cu" "B.Mask" "B.Paste")
			(net "PWRGD_PVCCIN_CPU0")
			(options
				(clearance outline)
				(anchor circle)
			)
			(primitives
				(gr_poly
					(pts
						(xy 0.381 -0.1524)
						(arc
							(start -0.2286 -0.1524)
							(mid -0.381 0)
							(end -0.2286 0.1524)
						)
						(xy 0.381 0.1524)
					)
					(width 0)
					(fill yes)
				)
			)
		)
		(pad "14" smd custom
			(at -0.750062 -1.549908 180)
			(size 0.0762 0.0762)
			(layers "B.Cu" "B.Mask" "B.Paste")
			(net "P3V3_STBY")
			(options
				(clearance outline)
				(anchor circle)
			)
			(primitives
				(gr_poly
					(pts
						(xy 0.1524 0.381)
						(arc
							(start 0.1524 -0.2286)
							(mid 0 -0.381)
							(end -0.1524 -0.2286)
						)
						(xy -0.1524 0.381)
					)
					(width 0)
					(fill yes)
				)
			)
		)
		(pad "15" smd rect
			(at 0 0 180)
			(size 1.8288 1.8288)
			(layers "B.Cu" "B.Mask" "B.Paste")
			(net "GND")
		)
	)
	(footprint ""
		(layer "B.Cu")
		(at 393.581128 -89.622884 -90)
		(property "Reference" "R2W4"
			(at 0.8382 -0.67818 270)
			(unlocked yes)
			(layer "B.SilkS")
			(effects
				(font
					(size 0.4064 0.254)
					(thickness 0.1524)
				)
				(justify left mirror)
			)
		)
		(property "Value" ""
			(at 0 0 90)
			(layer "B.Fab")
			(effects
				(font
					(size 1.27 1.27)
				)
				(justify mirror)
			)
		)
		(duplicate_pad_numbers_are_jumpers no)
		(fp_poly
			(pts
				(xy 0.2794 -0.1016) (xy -0.2794 -0.1016) (xy -0.2794 0.9906) (xy 0.2794 0.9906)
			)
			(stroke
				(width 0)
				(type default)
			)
			(fill no)
			(layer "B.CrtYd")
		)
		(fp_line
			(start -0.2794 0.9906)
			(end -0.2794 -0.1016)
			(stroke
				(width 0.1)
				(type default)
			)
			(layer "B.Fab")
		)
		(fp_line
			(start 0.2794 0.9906)
			(end -0.2794 0.9906)
			(stroke
				(width 0.1)
				(type default)
			)
			(layer "B.Fab")
		)
		(fp_line
			(start -0.2794 -0.1016)
			(end 0.2794 -0.1016)
			(stroke
				(width 0.1)
				(type default)
			)
			(layer "B.Fab")
		)
		(fp_line
			(start 0.2794 -0.1016)
			(end 0.2794 0.9906)
			(stroke
				(width 0.1)
				(type default)
			)
			(layer "B.Fab")
		)
		(pad "1" smd rect
			(at 0 0 90)
			(size 0.508 0.508)
			(layers "B.Cu" "B.Mask" "B.Paste")
			(net "FM_PMBUS_ALERT_BUF_EN_N")
		)
		(pad "2" smd rect
			(at 0 0.889 90)
			(size 0.508 0.508)
			(layers "B.Cu" "B.Mask" "B.Paste")
			(net "FM_PMBUS_ALERT_BUF_EN_R2_N")
		)
		(zone
			(layer "B.Cu")
			(hatch none 0.5)
			(connect_pads
				(clearance 0)
			)
			(min_thickness 0.25)
			(keepout
				(tracks not_allowed)
				(vias allowed)
				(pads allowed)
				(copperpour not_allowed)
				(footprints allowed)
			)
			(placement
				(enabled no)
				(sheetname "")
			)
			(fill
				(thermal_gap 0.5)
				(thermal_bridge_width 0.5)
				(island_removal_mode 0)
			)
			(polygon
				(pts
					(xy 392.946128 -89.368884) (xy 392.946128 -89.876884) (xy 393.327128 -89.876884) (xy 393.327128 -89.368884)
				)
			)
		)
		(zone
			(layer "B.Cu")
			(hatch none 0.5)
			(connect_pads
				(clearance 0)
			)
			(min_thickness 0.25)
			(keepout
				(tracks allowed)
				(vias not_allowed)
				(pads allowed)
				(copperpour not_allowed)
				(footprints allowed)
			)
			(placement
				(enabled no)
				(sheetname "")
			)
			(fill
				(thermal_gap 0.5)
				(thermal_bridge_width 0.5)
				(island_removal_mode 0)
			)
			(polygon
				(pts
					(xy 393.327128 -89.368884) (xy 393.327128 -89.876884) (xy 392.946128 -89.876884) (xy 392.946128 -89.368884)
				)
			)
		)
	)
	(footprint ""
		(layer "B.Cu")
		(at 446.129918 -143.21536 90)
		(property "Reference" "U25W16"
			(at 1.743964 -3.834638 90)
			(unlocked yes)
			(layer "B.SilkS")
			(effects
				(font
					(size 3.048 1.524)
					(thickness 0.000001)
				)
				(justify left mirror)
			)
		)
		(property "Value" ""
			(at 0 0 90)
			(layer "B.Fab")
			(effects
				(font
					(size 1.27 1.27)
				)
				(justify mirror)
			)
		)
		(duplicate_pad_numbers_are_jumpers no)
		(fp_circle
			(center 1.17856 -2.466086)
			(end 1.17856 -2.339086)
			(stroke
				(width 0.254)
				(type default)
			)
			(fill no)
			(layer "B.SilkS")
		)
		(fp_rect
			(start 0.9144 0.9144)
			(end -0.9144 -0.9144)
			(stroke
				(width 0)
				(type default)
			)
			(fill yes)
			(layer "B.Paste")
		)
		(fp_rect
			(start 1.82499 1.82499)
			(end -1.82499 -1.82499)
			(stroke
				(width 0)
				(type default)
			)
			(fill no)
			(layer "B.CrtYd")
		)
		(fp_line
			(start 1.82499 -1.82499)
			(end -1.82499 -1.82499)
			(stroke
				(width 0.1)
				(type default)
			)
			(layer "B.Fab")
		)
		(fp_line
			(start -1.82499 -1.82499)
			(end -1.82499 1.82499)
			(stroke
				(width 0.1)
				(type default)
			)
			(layer "B.Fab")
		)
		(fp_line
			(start 1.82499 1.82499)
			(end 1.82499 -1.82499)
			(stroke
				(width 0.1)
				(type default)
			)
			(layer "B.Fab")
		)
		(fp_line
			(start -1.82499 1.82499)
			(end 1.82499 1.82499)
			(stroke
				(width 0.1)
				(type default)
			)
			(layer "B.Fab")
		)
		(fp_circle
			(center 1.17856 -2.466086)
			(end 1.17856 -2.339086)
			(stroke
				(width 0.254)
				(type default)
			)
			(fill no)
			(layer "B.Fab")
		)
		(pad "1" smd custom
			(at 0.750062 -1.549908 270)
			(size 0.0762 0.0762)
			(layers "B.Cu" "B.Mask" "B.Paste")
			(net "BMC_JTAG_SEL_BUF")
			(options
				(clearance outline)
				(anchor circle)
			)
			(primitives
				(gr_poly
					(pts
						(xy 0.1524 0.381)
						(arc
							(start 0.1524 -0.2286)
							(mid 0 -0.381)
							(end -0.1524 -0.2286)
						)
						(xy -0.1524 0.381)
					)
					(width 0)
					(fill yes)
				)
			)
		)
		(pad "2" smd custom
			(at 1.549908 -0.999998 270)
			(size 0.0762 0.0762)
			(layers "B.Cu" "B.Mask" "B.Paste")
			(net "JTAG_BMC_TDI")
			(options
				(clearance outline)
				(anchor circle)
			)
			(primitives
				(gr_poly
					(pts
						(xy -0.381 0.1524)
						(arc
							(start 0.2286 0.1524)
							(mid 0.381 0)
							(end 0.2286 -0.1524)
						)
						(xy -0.381 -0.1524)
					)
					(width 0)
					(fill yes)
				)
			)
		)
		(pad "3" smd custom
			(at 1.549908 -0.500126 270)
			(size 0.0762 0.0762)
			(layers "B.Cu" "B.Mask" "B.Paste")
			(net "JTAG_BMC_BUF_TDI")
			(options
				(clearance outline)
				(anchor circle)
			)
			(primitives
				(gr_poly
					(pts
						(xy -0.381 0.1524)
						(arc
							(start 0.2286 0.1524)
							(mid 0.381 0)
							(end 0.2286 -0.1524)
						)
						(xy -0.381 -0.1524)
					)
					(width 0)
					(fill yes)
				)
			)
		)
		(pad "4" smd custom
			(at 1.549908 0 270)
			(size 0.0762 0.0762)
			(layers "B.Cu" "B.Mask" "B.Paste")
			(net "BMC_JTAG_SEL_BUF")
			(options
				(clearance outline)
				(anchor circle)
			)
			(primitives
				(gr_poly
					(pts
						(xy -0.381 0.1524)
						(arc
							(start 0.2286 0.1524)
							(mid 0.381 0)
							(end 0.2286 -0.1524)
						)
						(xy -0.381 -0.1524)
					)
					(width 0)
					(fill yes)
				)
			)
		)
		(pad "5" smd custom
			(at 1.549908 0.500126 270)
			(size 0.0762 0.0762)
			(layers "B.Cu" "B.Mask" "B.Paste")
			(net "JTAG_BMC_TMS")
			(options
				(clearance outline)
				(anchor circle)
			)
			(primitives
				(gr_poly
					(pts
						(xy -0.381 0.1524)
						(arc
							(start 0.2286 0.1524)
							(mid 0.381 0)
							(end 0.2286 -0.1524)
						)
						(xy -0.381 -0.1524)
					)
					(width 0)
					(fill yes)
				)
			)
		)
		(pad "6" smd custom
			(at 1.549908 0.999998 270)
			(size 0.0762 0.0762)
			(layers "B.Cu" "B.Mask" "B.Paste")
			(net "JTAG_BMC_BUF_TMS")
			(options
				(clearance outline)
				(anchor circle)
			)
			(primitives
				(gr_poly
					(pts
						(xy -0.381 0.1524)
						(arc
							(start 0.2286 0.1524)
							(mid 0.381 0)
							(end 0.2286 -0.1524)
						)
						(xy -0.381 -0.1524)
					)
					(width 0)
					(fill yes)
				)
			)
		)
		(pad "7" smd custom
			(at 0.750062 1.549908 270)
			(size 0.0762 0.0762)
			(layers "B.Cu" "B.Mask" "B.Paste")
			(net "GND")
			(options
				(clearance outline)
				(anchor circle)
			)
			(primitives
				(gr_poly
					(pts
						(xy -0.1524 -0.381)
						(arc
							(start -0.1524 0.2286)
							(mid 0 0.381)
							(end 0.1524 0.2286)
						)
						(xy 0.1524 -0.381)
					)
					(width 0)
					(fill yes)
				)
			)
		)
		(pad "8" smd custom
			(at -0.769874 1.549908 270)
			(size 0.0762 0.0762)
			(layers "B.Cu" "B.Mask" "B.Paste")
			(net "JTAG_BMC_BUF_TDO")
			(options
				(clearance outline)
				(anchor circle)
			)
			(primitives
				(gr_poly
					(pts
						(xy -0.1524 -0.381)
						(arc
							(start -0.1524 0.2286)
							(mid 0 0.381)
							(end 0.1524 0.2286)
						)
						(xy 0.1524 -0.381)
					)
					(width 0)
					(fill yes)
				)
			)
		)
		(pad "9" smd custom
			(at -1.549908 0.999998 270)
			(size 0.0762 0.0762)
			(layers "B.Cu" "B.Mask" "B.Paste")
			(net "JTAG_BMC_TDO")
			(options
				(clearance outline)
				(anchor circle)
			)
			(primitives
				(gr_poly
					(pts
						(xy 0.381 -0.1524)
						(arc
							(start -0.2286 -0.1524)
							(mid -0.381 0)
							(end -0.2286 0.1524)
						)
						(xy 0.381 0.1524)
					)
					(width 0)
					(fill yes)
				)
			)
		)
		(pad "10" smd custom
			(at -1.549908 0.500126 270)
			(size 0.0762 0.0762)
			(layers "B.Cu" "B.Mask" "B.Paste")
			(net "BMC_JTAG_SEL_BUF")
			(options
				(clearance outline)
				(anchor circle)
			)
			(primitives
				(gr_poly
					(pts
						(xy 0.381 -0.1524)
						(arc
							(start -0.2286 -0.1524)
							(mid -0.381 0)
							(end -0.2286 0.1524)
						)
						(xy 0.381 0.1524)
					)
					(width 0)
					(fill yes)
				)
			)
		)
		(pad "11" smd custom
			(at -1.549908 0 270)
			(size 0.0762 0.0762)
			(layers "B.Cu" "B.Mask" "B.Paste")
			(net "BMC_PWR_DEBUG_BUF_N")
			(options
				(clearance outline)
				(anchor circle)
			)
			(primitives
				(gr_poly
					(pts
						(xy 0.381 -0.1524)
						(arc
							(start -0.2286 -0.1524)
							(mid -0.381 0)
							(end -0.2286 0.1524)
						)
						(xy 0.381 0.1524)
					)
					(width 0)
					(fill yes)
				)
			)
		)
		(pad "12" smd custom
			(at -1.549908 -0.500126 270)
			(size 0.0762 0.0762)
			(layers "B.Cu" "B.Mask" "B.Paste")
			(net "BMC_PWR_DEBUG_N")
			(options
				(clearance outline)
				(anchor circle)
			)
			(primitives
				(gr_poly
					(pts
						(xy 0.381 -0.1524)
						(arc
							(start -0.2286 -0.1524)
							(mid -0.381 0)
							(end -0.2286 0.1524)
						)
						(xy 0.381 0.1524)
					)
					(width 0)
					(fill yes)
				)
			)
		)
		(pad "13" smd custom
			(at -1.549908 -0.999998 270)
			(size 0.0762 0.0762)
			(layers "B.Cu" "B.Mask" "B.Paste")
			(net "BMC_JTAG_SEL_BUF")
			(options
				(clearance outline)
				(anchor circle)
			)
			(primitives
				(gr_poly
					(pts
						(xy 0.381 -0.1524)
						(arc
							(start -0.2286 -0.1524)
							(mid -0.381 0)
							(end -0.2286 0.1524)
						)
						(xy 0.381 0.1524)
					)
					(width 0)
					(fill yes)
				)
			)
		)
		(pad "14" smd custom
			(at -0.750062 -1.549908 270)
			(size 0.0762 0.0762)
			(layers "B.Cu" "B.Mask" "B.Paste")
			(net "P3V3_STBY")
			(options
				(clearance outline)
				(anchor circle)
			)
			(primitives
				(gr_poly
					(pts
						(xy 0.1524 0.381)
						(arc
							(start 0.1524 -0.2286)
							(mid 0 -0.381)
							(end -0.1524 -0.2286)
						)
						(xy -0.1524 0.381)
					)
					(width 0)
					(fill yes)
				)
			)
		)
		(pad "15" smd rect
			(at 0 0 270)
			(size 1.8288 1.8288)
			(layers "B.Cu" "B.Mask" "B.Paste")
			(net "GND")
		)
	)
	(footprint ""
		(layer "B.Cu")
		(at 484.6574 -39.5986 180)
		(property "Reference" "C1T5"
			(at 0 0 0)
			(layer "B.SilkS")
			(hide yes)
			(effects
				(font
					(size 1.27 1.27)
				)
				(justify mirror)
			)
		)
		(property "Value" ""
			(at 0 0 0)
			(layer "B.Fab")
			(effects
				(font
					(size 1.27 1.27)
				)
				(justify mirror)
			)
		)
		(duplicate_pad_numbers_are_jumpers no)
		(fp_poly
			(pts
				(xy -0.3048 -0.1016) (xy -0.3048 0.9906) (xy 0.3048 0.9906) (xy 0.3048 -0.1016)
			)
			(stroke
				(width 0)
				(type default)
			)
			(fill no)
			(layer "B.CrtYd")
		)
		(fp_line
			(start 0.3048 0.9906)
			(end -0.3048 0.9906)
			(stroke
				(width 0.1)
				(type default)
			)
			(layer "B.Fab")
		)
		(fp_line
			(start 0.3048 -0.1016)
			(end 0.3048 0.9906)
			(stroke
				(width 0.1)
				(type default)
			)
			(layer "B.Fab")
		)
		(fp_line
			(start -0.3048 0.9906)
			(end -0.3048 -0.1016)
			(stroke
				(width 0.1)
				(type default)
			)
			(layer "B.Fab")
		)
		(fp_line
			(start -0.3048 -0.1016)
			(end 0.3048 -0.1016)
			(stroke
				(width 0.1)
				(type default)
			)
			(layer "B.Fab")
		)
		(pad "1" smd rect
			(at 0 0)
			(size 0.508 0.508)
			(layers "B.Cu" "B.Mask" "B.Paste")
			(net "P0V9_LAN")
		)
		(pad "2" smd rect
			(at 0 0.889)
			(size 0.508 0.508)
			(layers "B.Cu" "B.Mask" "B.Paste")
			(net "GND")
		)
		(zone
			(layer "B.Cu")
			(hatch none 0.5)
			(connect_pads
				(clearance 0)
			)
			(min_thickness 0.25)
			(keepout
				(tracks not_allowed)
				(vias allowed)
				(pads allowed)
				(copperpour not_allowed)
				(footprints allowed)
			)
			(placement
				(enabled no)
				(sheetname "")
			)
			(fill
				(thermal_gap 0.5)
				(thermal_bridge_width 0.5)
				(island_removal_mode 0)
			)
			(polygon
				(pts
					(xy 484.4034 -40.2336) (xy 484.9114 -40.2336) (xy 484.9114 -39.8526) (xy 484.4034 -39.8526)
				)
			)
		)
		(zone
			(layer "B.Cu")
			(hatch none 0.5)
			(connect_pads
				(clearance 0)
			)
			(min_thickness 0.25)
			(keepout
				(tracks allowed)
				(vias not_allowed)
				(pads allowed)
				(copperpour not_allowed)
				(footprints allowed)
			)
			(placement
				(enabled no)
				(sheetname "")
			)
			(fill
				(thermal_gap 0.5)
				(thermal_bridge_width 0.5)
				(island_removal_mode 0)
			)
			(polygon
				(pts
					(xy 484.4034 -39.8526) (xy 484.9114 -39.8526) (xy 484.9114 -40.2336) (xy 484.4034 -40.2336)
				)
			)
		)
	)
	(footprint ""
		(layer "B.Cu")
		(at 472.2368 -124.079 90)
		(property "Reference" "R1M6"
			(at 0 0 90)
			(layer "B.SilkS")
			(hide yes)
			(effects
				(font
					(size 1.27 1.27)
				)
				(justify mirror)
			)
		)
		(property "Value" ""
			(at 0 0 90)
			(layer "B.Fab")
			(effects
				(font
					(size 1.27 1.27)
				)
				(justify mirror)
			)
		)
		(duplicate_pad_numbers_are_jumpers no)
		(fp_rect
			(start -0.2794 -0.1016)
			(end 0.2794 0.9906)
			(stroke
				(width 0)
				(type default)
			)
			(fill no)
			(layer "B.CrtYd")
		)
		(fp_line
			(start 0.2794 -0.1016)
			(end 0.2794 0.9906)
			(stroke
				(width 0.1)
				(type default)
			)
			(layer "B.Fab")
		)
		(fp_line
			(start -0.2794 -0.1016)
			(end 0.2794 -0.1016)
			(stroke
				(width 0.1)
				(type default)
			)
			(layer "B.Fab")
		)
		(fp_line
			(start 0.2794 0.9906)
			(end -0.2794 0.9906)
			(stroke
				(width 0.1)
				(type default)
			)
			(layer "B.Fab")
		)
		(fp_line
			(start -0.2794 0.9906)
			(end -0.2794 -0.1016)
			(stroke
				(width 0.1)
				(type default)
			)
			(layer "B.Fab")
		)
		(pad "1" smd rect
			(at 0 0 270)
			(size 0.508 0.508)
			(layers "B.Cu" "B.Mask" "B.Paste")
			(net "USB2_P01_DN")
		)
		(pad "2" smd rect
			(at 0 0.889 270)
			(size 0.508 0.508)
			(layers "B.Cu" "B.Mask" "B.Paste")
			(net "USB2_P01_ESD_DN")
		)
		(zone
			(layer "B.Cu")
			(hatch none 0.5)
			(connect_pads
				(clearance 0)
			)
			(min_thickness 0.25)
			(keepout
				(tracks allowed)
				(vias not_allowed)
				(pads allowed)
				(copperpour not_allowed)
				(footprints allowed)
			)
			(placement
				(enabled no)
				(sheetname "")
			)
			(fill
				(thermal_gap 0.5)
				(thermal_bridge_width 0.5)
				(island_removal_mode 0)
			)
			(polygon
				(pts
					(xy 472.4908 -123.825) (xy 472.8718 -123.825) (xy 472.8718 -124.333) (xy 472.4908 -124.333)
				)
			)
		)
		(zone
			(layer "B.Cu")
			(hatch none 0.5)
			(connect_pads
				(clearance 0)
			)
			(min_thickness 0.25)
			(keepout
				(tracks not_allowed)
				(vias allowed)
				(pads allowed)
				(copperpour not_allowed)
				(footprints allowed)
			)
			(placement
				(enabled no)
				(sheetname "")
			)
			(fill
				(thermal_gap 0.5)
				(thermal_bridge_width 0.5)
				(island_removal_mode 0)
			)
			(polygon
				(pts
					(xy 472.4908 -123.825) (xy 472.8718 -123.825) (xy 472.8718 -124.333) (xy 472.4908 -124.333)
				)
			)
		)
	)
	(footprint ""
		(layer "B.Cu")
		(at 24.765 -30.099 -90)
		(property "Reference" "R9T6"
			(at 0 0 90)
			(layer "B.SilkS")
			(hide yes)
			(effects
				(font
					(size 1.27 1.27)
				)
				(justify mirror)
			)
		)
		(property "Value" ""
			(at 0 0 90)
			(layer "B.Fab")
			(effects
				(font
					(size 1.27 1.27)
				)
				(justify mirror)
			)
		)
		(duplicate_pad_numbers_are_jumpers no)
		(fp_rect
			(start 0.2794 0.9906)
			(end -0.2794 -0.1016)
			(stroke
				(width 0)
				(type default)
			)
			(fill no)
			(layer "B.CrtYd")
		)
		(fp_line
			(start -0.2794 0.9906)
			(end -0.2794 -0.1016)
			(stroke
				(width 0.1)
				(type default)
			)
			(layer "B.Fab")
		)
		(fp_line
			(start 0.2794 0.9906)
			(end -0.2794 0.9906)
			(stroke
				(width 0.1)
				(type default)
			)
			(layer "B.Fab")
		)
		(fp_line
			(start -0.2794 -0.1016)
			(end 0.2794 -0.1016)
			(stroke
				(width 0.1)
				(type default)
			)
			(layer "B.Fab")
		)
		(fp_line
			(start 0.2794 -0.1016)
			(end 0.2794 0.9906)
			(stroke
				(width 0.1)
				(type default)
			)
			(layer "B.Fab")
		)
		(pad "1" smd rect
			(at 0 0 90)
			(size 0.508 0.508)
			(layers "B.Cu" "B.Mask" "B.Paste")
			(net "P12V_PSU")
		)
		(pad "2" smd rect
			(at 0 0.889 90)
			(size 0.508 0.508)
			(layers "B.Cu" "B.Mask" "B.Paste")
			(net "FM_P12V_HOTSWAP0_EN")
		)
		(zone
			(layer "B.Cu")
			(hatch none 0.5)
			(connect_pads
				(clearance 0)
			)
			(min_thickness 0.25)
			(keepout
				(tracks not_allowed)
				(vias allowed)
				(pads allowed)
				(copperpour not_allowed)
				(footprints allowed)
			)
			(placement
				(enabled no)
				(sheetname "")
			)
			(fill
				(thermal_gap 0.5)
				(thermal_bridge_width 0.5)
				(island_removal_mode 0)
			)
			(polygon
				(pts
					(xy 24.13 -29.845) (xy 24.511 -29.845) (xy 24.511 -30.353) (xy 24.13 -30.353)
				)
			)
		)
		(zone
			(layer "B.Cu")
			(hatch none 0.5)
			(connect_pads
				(clearance 0)
			)
			(min_thickness 0.25)
			(keepout
				(tracks allowed)
				(vias not_allowed)
				(pads allowed)
				(copperpour not_allowed)
				(footprints allowed)
			)
			(placement
				(enabled no)
				(sheetname "")
			)
			(fill
				(thermal_gap 0.5)
				(thermal_bridge_width 0.5)
				(island_removal_mode 0)
			)
			(polygon
				(pts
					(xy 24.13 -29.845) (xy 24.511 -29.845) (xy 24.511 -30.353) (xy 24.13 -30.353)
				)
			)
		)
	)
	(footprint ""
		(layer "B.Cu")
		(at 368.346228 -70.696074)
		(property "Reference" "C2R3"
			(at 0 0 0)
			(layer "B.SilkS")
			(hide yes)
			(effects
				(font
					(size 1.27 1.27)
				)
				(justify mirror)
			)
		)
		(property "Value" ""
			(at 0 0 0)
			(layer "B.Fab")
			(effects
				(font
					(size 1.27 1.27)
				)
				(justify mirror)
			)
		)
		(duplicate_pad_numbers_are_jumpers no)
		(fp_rect
			(start 0.2794 0.9144)
			(end -0.2794 -0.1143)
			(stroke
				(width 0)
				(type default)
			)
			(fill no)
			(layer "B.CrtYd")
		)
		(fp_line
			(start -0.2794 -0.1143)
			(end -0.2794 0.9144)
			(stroke
				(width 0.1)
				(type default)
			)
			(layer "B.Fab")
		)
		(fp_line
			(start -0.2794 0.9144)
			(end 0.2794 0.9144)
			(stroke
				(width 0.1)
				(type default)
			)
			(layer "B.Fab")
		)
		(fp_line
			(start 0.2794 -0.1143)
			(end -0.2794 -0.1143)
			(stroke
				(width 0.1)
				(type default)
			)
			(layer "B.Fab")
		)
		(fp_line
			(start 0.2794 0.9144)
			(end 0.2794 -0.1143)
			(stroke
				(width 0.1)
				(type default)
			)
			(layer "B.Fab")
		)
		(pad "1" smd custom
			(at 0 0 270)
			(size 0.10414 0.10414)
			(layers "B.Cu" "B.Mask" "B.Paste")
			(net "P3V3_STBY")
			(options
				(clearance outline)
				(anchor circle)
			)
			(primitives
				(gr_poly
					(pts
						(xy -0.20828 -0.08636) (xy -0.20828 0.08636) (xy -0.08636 0.20828) (xy 0.086614 0.20828) (xy 0.20828 0.086614)
						(xy 0.20828 -0.08636) (xy 0.08636 -0.20828) (xy -0.08636 -0.20828)
					)
					(width 0)
					(fill yes)
				)
			)
		)
		(pad "2" smd custom
			(at 0 0.8001 270)
			(size 0.10414 0.10414)
			(layers "B.Cu" "B.Mask" "B.Paste")
			(net "GND")
			(options
				(clearance outline)
				(anchor circle)
			)
			(primitives
				(gr_poly
					(pts
						(xy -0.20828 -0.08636) (xy -0.20828 0.08636) (xy -0.08636 0.20828) (xy 0.086614 0.20828) (xy 0.20828 0.086614)
						(xy 0.20828 -0.08636) (xy 0.08636 -0.20828) (xy -0.08636 -0.20828)
					)
					(width 0)
					(fill yes)
				)
			)
		)
		(zone
			(layer "B.Cu")
			(hatch none 0.5)
			(connect_pads
				(clearance 0)
			)
			(min_thickness 0.25)
			(keepout
				(tracks allowed)
				(vias not_allowed)
				(pads allowed)
				(copperpour not_allowed)
				(footprints allowed)
			)
			(placement
				(enabled no)
				(sheetname "")
			)
			(fill
				(thermal_gap 0.5)
				(thermal_bridge_width 0.5)
				(island_removal_mode 0)
			)
			(polygon
				(pts
					(xy 368.433858 -70.486524) (xy 368.433858 -70.105524) (xy 368.258598 -70.105524) (xy 368.258344 -70.486524)
				)
			)
		)
		(zone
			(layer "B.Cu")
			(hatch none 0.5)
			(connect_pads
				(clearance 0)
			)
			(min_thickness 0.25)
			(keepout
				(tracks not_allowed)
				(vias allowed)
				(pads allowed)
				(copperpour not_allowed)
				(footprints allowed)
			)
			(placement
				(enabled no)
				(sheetname "")
			)
			(fill
				(thermal_gap 0.5)
				(thermal_bridge_width 0.5)
				(island_removal_mode 0)
			)
			(polygon
				(pts
					(xy 368.433858 -70.486524) (xy 368.433858 -70.105524) (xy 368.258598 -70.105524) (xy 368.258344 -70.486524)
				)
			)
		)
	)
	(footprint ""
		(layer "B.Cu")
		(at 474.41866 -30.85592 90)
		(property "Reference" "C2T31"
			(at 0 0 90)
			(layer "B.SilkS")
			(hide yes)
			(effects
				(font
					(size 1.27 1.27)
				)
				(justify mirror)
			)
		)
		(property "Value" ""
			(at 0 0 90)
			(layer "B.Fab")
			(effects
				(font
					(size 1.27 1.27)
				)
				(justify mirror)
			)
		)
		(duplicate_pad_numbers_are_jumpers no)
		(fp_poly
			(pts
				(xy -0.3048 -0.1016) (xy -0.3048 0.9906) (xy 0.3048 0.9906) (xy 0.3048 -0.1016)
			)
			(stroke
				(width 0)
				(type default)
			)
			(fill no)
			(layer "B.CrtYd")
		)
		(fp_line
			(start 0.3048 -0.1016)
			(end 0.3048 0.9906)
			(stroke
				(width 0.1)
				(type default)
			)
			(layer "B.Fab")
		)
		(fp_line
			(start -0.3048 -0.1016)
			(end 0.3048 -0.1016)
			(stroke
				(width 0.1)
				(type default)
			)
			(layer "B.Fab")
		)
		(fp_line
			(start 0.3048 0.9906)
			(end -0.3048 0.9906)
			(stroke
				(width 0.1)
				(type default)
			)
			(layer "B.Fab")
		)
		(fp_line
			(start -0.3048 0.9906)
			(end -0.3048 -0.1016)
			(stroke
				(width 0.1)
				(type default)
			)
			(layer "B.Fab")
		)
		(pad "1" smd rect
			(at 0 0 270)
			(size 0.508 0.508)
			(layers "B.Cu" "B.Mask" "B.Paste")
			(net "P3V3_STBY_MNG_RGMII")
		)
		(pad "2" smd rect
			(at 0 0.889 270)
			(size 0.508 0.508)
			(layers "B.Cu" "B.Mask" "B.Paste")
			(net "GND")
		)
		(zone
			(layer "B.Cu")
			(hatch none 0.5)
			(connect_pads
				(clearance 0)
			)
			(min_thickness 0.25)
			(keepout
				(tracks allowed)
				(vias not_allowed)
				(pads allowed)
				(copperpour not_allowed)
				(footprints allowed)
			)
			(placement
				(enabled no)
				(sheetname "")
			)
			(fill
				(thermal_gap 0.5)
				(thermal_bridge_width 0.5)
				(island_removal_mode 0)
			)
			(polygon
				(pts
					(xy 474.67266 -31.10992) (xy 474.67266 -30.60192) (xy 475.05366 -30.60192) (xy 475.05366 -31.10992)
				)
			)
		)
		(zone
			(layer "B.Cu")
			(hatch none 0.5)
			(connect_pads
				(clearance 0)
			)
			(min_thickness 0.25)
			(keepout
				(tracks not_allowed)
				(vias allowed)
				(pads allowed)
				(copperpour not_allowed)
				(footprints allowed)
			)
			(placement
				(enabled no)
				(sheetname "")
			)
			(fill
				(thermal_gap 0.5)
				(thermal_bridge_width 0.5)
				(island_removal_mode 0)
			)
			(polygon
				(pts
					(xy 475.05366 -31.10992) (xy 475.05366 -30.60192) (xy 474.67266 -30.60192) (xy 474.67266 -31.10992)
				)
			)
		)
	)
	(footprint ""
		(layer "B.Cu")
		(at 426.9105 -11.176 90)
		(property "Reference" "R2U49"
			(at 0 0 90)
			(layer "B.SilkS")
			(hide yes)
			(effects
				(font
					(size 1.27 1.27)
				)
				(justify mirror)
			)
		)
		(property "Value" ""
			(at 0 0 90)
			(layer "B.Fab")
			(effects
				(font
					(size 1.27 1.27)
				)
				(justify mirror)
			)
		)
		(duplicate_pad_numbers_are_jumpers no)
		(fp_poly
			(pts
				(xy 0.2794 -0.1016) (xy -0.2794 -0.1016) (xy -0.2794 0.9906) (xy 0.2794 0.9906)
			)
			(stroke
				(width 0)
				(type default)
			)
			(fill no)
			(layer "B.CrtYd")
		)
		(fp_line
			(start 0.2794 -0.1016)
			(end 0.2794 0.9906)
			(stroke
				(width 0.1)
				(type default)
			)
			(layer "B.Fab")
		)
		(fp_line
			(start -0.2794 -0.1016)
			(end 0.2794 -0.1016)
			(stroke
				(width 0.1)
				(type default)
			)
			(layer "B.Fab")
		)
		(fp_line
			(start 0.2794 0.9906)
			(end -0.2794 0.9906)
			(stroke
				(width 0.1)
				(type default)
			)
			(layer "B.Fab")
		)
		(fp_line
			(start -0.2794 0.9906)
			(end -0.2794 -0.1016)
			(stroke
				(width 0.1)
				(type default)
			)
			(layer "B.Fab")
		)
		(pad "1" smd rect
			(at 0 0 270)
			(size 0.508 0.508)
			(layers "B.Cu" "B.Mask" "B.Paste")
			(net "H_CPU0_MEMABC_MEMHOT_G_PCH_N")
		)
		(pad "2" smd rect
			(at 0 0.889 270)
			(size 0.508 0.508)
			(layers "B.Cu" "B.Mask" "B.Paste")
			(net "H_CPU0_MEMABC_MEMHOT_LVT3_K_N")
		)
		(zone
			(layer "B.Cu")
			(hatch none 0.5)
			(connect_pads
				(clearance 0)
			)
			(min_thickness 0.25)
			(keepout
				(tracks allowed)
				(vias not_allowed)
				(pads allowed)
				(copperpour not_allowed)
				(footprints allowed)
			)
			(placement
				(enabled no)
				(sheetname "")
			)
			(fill
				(thermal_gap 0.5)
				(thermal_bridge_width 0.5)
				(island_removal_mode 0)
			)
			(polygon
				(pts
					(xy 427.1645 -11.43) (xy 427.1645 -10.922) (xy 427.5455 -10.922) (xy 427.5455 -11.43)
				)
			)
		)
		(zone
			(layer "B.Cu")
			(hatch none 0.5)
			(connect_pads
				(clearance 0)
			)
			(min_thickness 0.25)
			(keepout
				(tracks not_allowed)
				(vias allowed)
				(pads allowed)
				(copperpour not_allowed)
				(footprints allowed)
			)
			(placement
				(enabled no)
				(sheetname "")
			)
			(fill
				(thermal_gap 0.5)
				(thermal_bridge_width 0.5)
				(island_removal_mode 0)
			)
			(polygon
				(pts
					(xy 427.5455 -11.43) (xy 427.5455 -10.922) (xy 427.1645 -10.922) (xy 427.1645 -11.43)
				)
			)
		)
	)
	(footprint ""
		(layer "B.Cu")
		(at 416.9664 -26.035)
		(property "Reference" "R25W125"
			(at 0.8382 -0.67818 0)
			(unlocked yes)
			(layer "B.SilkS")
			(effects
				(font
					(size 0.4064 0.254)
					(thickness 0.1524)
				)
				(justify left mirror)
			)
		)
		(property "Value" ""
			(at 0 0 0)
			(layer "B.Fab")
			(effects
				(font
					(size 1.27 1.27)
				)
				(justify mirror)
			)
		)
		(duplicate_pad_numbers_are_jumpers no)
		(fp_poly
			(pts
				(xy 0.2794 -0.1016) (xy -0.2794 -0.1016) (xy -0.2794 0.9906) (xy 0.2794 0.9906)
			)
			(stroke
				(width 0)
				(type default)
			)
			(fill no)
			(layer "B.CrtYd")
		)
		(fp_line
			(start -0.2794 -0.1016)
			(end 0.2794 -0.1016)
			(stroke
				(width 0.1)
				(type default)
			)
			(layer "B.Fab")
		)
		(fp_line
			(start -0.2794 0.9906)
			(end -0.2794 -0.1016)
			(stroke
				(width 0.1)
				(type default)
			)
			(layer "B.Fab")
		)
		(fp_line
			(start 0.2794 -0.1016)
			(end 0.2794 0.9906)
			(stroke
				(width 0.1)
				(type default)
			)
			(layer "B.Fab")
		)
		(fp_line
			(start 0.2794 0.9906)
			(end -0.2794 0.9906)
			(stroke
				(width 0.1)
				(type default)
			)
			(layer "B.Fab")
		)
		(pad "1" smd rect
			(at 0 0 180)
			(size 0.508 0.508)
			(layers "B.Cu" "B.Mask" "B.Paste")
			(net "BMC_VGA_RED")
		)
		(pad "2" smd rect
			(at 0 0.889 180)
			(size 0.508 0.508)
			(layers "B.Cu" "B.Mask" "B.Paste")
			(net "GND")
		)
		(zone
			(layer "B.Cu")
			(hatch none 0.5)
			(connect_pads
				(clearance 0)
			)
			(min_thickness 0.25)
			(keepout
				(tracks allowed)
				(vias not_allowed)
				(pads allowed)
				(copperpour not_allowed)
				(footprints allowed)
			)
			(placement
				(enabled no)
				(sheetname "")
			)
			(fill
				(thermal_gap 0.5)
				(thermal_bridge_width 0.5)
				(island_removal_mode 0)
			)
			(polygon
				(pts
					(xy 417.2204 -25.781) (xy 416.7124 -25.781) (xy 416.7124 -25.4) (xy 417.2204 -25.4)
				)
			)
		)
		(zone
			(layer "B.Cu")
			(hatch none 0.5)
			(connect_pads
				(clearance 0)
			)
			(min_thickness 0.25)
			(keepout
				(tracks not_allowed)
				(vias allowed)
				(pads allowed)
				(copperpour not_allowed)
				(footprints allowed)
			)
			(placement
				(enabled no)
				(sheetname "")
			)
			(fill
				(thermal_gap 0.5)
				(thermal_bridge_width 0.5)
				(island_removal_mode 0)
			)
			(polygon
				(pts
					(xy 417.2204 -25.4) (xy 416.7124 -25.4) (xy 416.7124 -25.781) (xy 417.2204 -25.781)
				)
			)
		)
	)
	(footprint ""
		(layer "B.Cu")
		(at 333.6798 -30.3403 90)
		(property "Reference" "C3T7"
			(at 0 0 90)
			(layer "B.SilkS")
			(hide yes)
			(effects
				(font
					(size 1.27 1.27)
				)
				(justify mirror)
			)
		)
		(property "Value" ""
			(at 0 0 90)
			(layer "B.Fab")
			(effects
				(font
					(size 1.27 1.27)
				)
				(justify mirror)
			)
		)
		(duplicate_pad_numbers_are_jumpers no)
		(fp_rect
			(start -0.7239 -0.2159)
			(end 0.7239 1.9939)
			(stroke
				(width 0)
				(type default)
			)
			(fill no)
			(layer "B.CrtYd")
		)
		(fp_line
			(start 0.7239 -0.2159)
			(end 0.7239 1.9939)
			(stroke
				(width 0.1)
				(type default)
			)
			(layer "B.Fab")
		)
		(fp_line
			(start -0.7239 -0.2159)
			(end 0.7239 -0.2159)
			(stroke
				(width 0.1)
				(type default)
			)
			(layer "B.Fab")
		)
		(fp_line
			(start 0.7239 1.9939)
			(end -0.7239 1.9939)
			(stroke
				(width 0.1)
				(type default)
			)
			(layer "B.Fab")
		)
		(fp_line
			(start -0.7239 1.9939)
			(end -0.7239 -0.2159)
			(stroke
				(width 0.1)
				(type default)
			)
			(layer "B.Fab")
		)
		(pad "1" smd rect
			(at 0 0 270)
			(size 1.27 1.016)
			(layers "B.Cu" "B.Mask" "B.Paste")
			(net "PVPP_ABC")
		)
		(pad "2" smd rect
			(at 0 1.778 270)
			(size 1.27 1.016)
			(layers "B.Cu" "B.Mask" "B.Paste")
			(net "GND")
		)
		(zone
			(layer "B.Cu")
			(hatch none 0.5)
			(connect_pads
				(clearance 0)
			)
			(min_thickness 0.25)
			(keepout
				(tracks not_allowed)
				(vias allowed)
				(pads allowed)
				(copperpour not_allowed)
				(footprints allowed)
			)
			(placement
				(enabled no)
				(sheetname "")
			)
			(fill
				(thermal_gap 0.5)
				(thermal_bridge_width 0.5)
				(island_removal_mode 0)
			)
			(polygon
				(pts
					(xy 334.1878 -29.7053) (xy 334.9498 -29.7053) (xy 334.9498 -30.9753) (xy 334.1878 -30.9753)
				)
			)
		)
	)
	(footprint ""
		(layer "B.Cu")
		(at 348.1832 -96.5708 -90)
		(property "Reference" "C3N33"
			(at 0 0 90)
			(layer "B.SilkS")
			(hide yes)
			(effects
				(font
					(size 1.27 1.27)
				)
				(justify mirror)
			)
		)
		(property "Value" ""
			(at 0 0 90)
			(layer "B.Fab")
			(effects
				(font
					(size 1.27 1.27)
				)
				(justify mirror)
			)
		)
		(duplicate_pad_numbers_are_jumpers no)
		(fp_poly
			(pts
				(xy 0.7239 -0.2159) (xy -0.7239 -0.2159) (xy -0.7239 1.9939) (xy 0.7239 1.9939)
			)
			(stroke
				(width 0)
				(type default)
			)
			(fill no)
			(layer "B.CrtYd")
		)
		(fp_line
			(start -0.7239 1.9939)
			(end -0.7239 -0.2159)
			(stroke
				(width 0.1)
				(type default)
			)
			(layer "B.Fab")
		)
		(fp_line
			(start 0.7239 1.9939)
			(end -0.7239 1.9939)
			(stroke
				(width 0.1)
				(type default)
			)
			(layer "B.Fab")
		)
		(fp_line
			(start -0.7239 -0.2159)
			(end 0.7239 -0.2159)
			(stroke
				(width 0.1)
				(type default)
			)
			(layer "B.Fab")
		)
		(fp_line
			(start 0.7239 -0.2159)
			(end 0.7239 1.9939)
			(stroke
				(width 0.1)
				(type default)
			)
			(layer "B.Fab")
		)
		(pad "1" smd rect
			(at 0 0 90)
			(size 1.27 1.016)
			(layers "B.Cu" "B.Mask" "B.Paste")
			(net "VR_FET_SW_P12V_STBY_PVCCIO_CPU0")
		)
		(pad "2" smd rect
			(at 0 1.778 90)
			(size 1.27 1.016)
			(layers "B.Cu" "B.Mask" "B.Paste")
			(net "GND")
		)
		(zone
			(layer "B.Cu")
			(hatch none 0.5)
			(connect_pads
				(clearance 0)
			)
			(min_thickness 0.25)
			(keepout
				(tracks not_allowed)
				(vias allowed)
				(pads allowed)
				(copperpour not_allowed)
				(footprints allowed)
			)
			(placement
				(enabled no)
				(sheetname "")
			)
			(fill
				(thermal_gap 0.5)
				(thermal_bridge_width 0.5)
				(island_removal_mode 0)
			)
			(polygon
				(pts
					(xy 347.6752 -95.9358) (xy 347.6752 -97.2058) (xy 346.9132 -97.2058) (xy 346.9132 -95.9358)
				)
			)
		)
	)
	(footprint ""
		(layer "B.Cu")
		(at 404.204424 -32.801052)
		(property "Reference" "C25W34"
			(at 0.8382 -0.67818 0)
			(unlocked yes)
			(layer "B.SilkS")
			(effects
				(font
					(size 0.4064 0.254)
					(thickness 0.1524)
				)
				(justify left mirror)
			)
		)
		(property "Value" ""
			(at 0 0 0)
			(layer "B.Fab")
			(effects
				(font
					(size 1.27 1.27)
				)
				(justify mirror)
			)
		)
		(duplicate_pad_numbers_are_jumpers no)
		(fp_poly
			(pts
				(xy -0.3048 -0.1016) (xy -0.3048 0.9906) (xy 0.3048 0.9906) (xy 0.3048 -0.1016)
			)
			(stroke
				(width 0)
				(type default)
			)
			(fill no)
			(layer "B.CrtYd")
		)
		(fp_line
			(start -0.3048 -0.1016)
			(end 0.3048 -0.1016)
			(stroke
				(width 0.1)
				(type default)
			)
			(layer "B.Fab")
		)
		(fp_line
			(start -0.3048 0.9906)
			(end -0.3048 -0.1016)
			(stroke
				(width 0.1)
				(type default)
			)
			(layer "B.Fab")
		)
		(fp_line
			(start 0.3048 -0.1016)
			(end 0.3048 0.9906)
			(stroke
				(width 0.1)
				(type default)
			)
			(layer "B.Fab")
		)
		(fp_line
			(start 0.3048 0.9906)
			(end -0.3048 0.9906)
			(stroke
				(width 0.1)
				(type default)
			)
			(layer "B.Fab")
		)
		(pad "1" smd rect
			(at 0 0 180)
			(size 0.508 0.508)
			(layers "B.Cu" "B.Mask" "B.Paste")
			(net "VCC_DACAV3V3")
		)
		(pad "2" smd rect
			(at 0 0.889 180)
			(size 0.508 0.508)
			(layers "B.Cu" "B.Mask" "B.Paste")
			(net "GND")
		)
		(zone
			(layer "B.Cu")
			(hatch none 0.5)
			(connect_pads
				(clearance 0)
			)
			(min_thickness 0.25)
			(keepout
				(tracks allowed)
				(vias not_allowed)
				(pads allowed)
				(copperpour not_allowed)
				(footprints allowed)
			)
			(placement
				(enabled no)
				(sheetname "")
			)
			(fill
				(thermal_gap 0.5)
				(thermal_bridge_width 0.5)
				(island_removal_mode 0)
			)
			(polygon
				(pts
					(xy 404.458424 -32.547052) (xy 403.950424 -32.547052) (xy 403.950424 -32.166052) (xy 404.458424 -32.166052)
				)
			)
		)
		(zone
			(layer "B.Cu")
			(hatch none 0.5)
			(connect_pads
				(clearance 0)
			)
			(min_thickness 0.25)
			(keepout
				(tracks not_allowed)
				(vias allowed)
				(pads allowed)
				(copperpour not_allowed)
				(footprints allowed)
			)
			(placement
				(enabled no)
				(sheetname "")
			)
			(fill
				(thermal_gap 0.5)
				(thermal_bridge_width 0.5)
				(island_removal_mode 0)
			)
			(polygon
				(pts
					(xy 404.458424 -32.166052) (xy 403.950424 -32.166052) (xy 403.950424 -32.547052) (xy 404.458424 -32.547052)
				)
			)
		)
	)
	(footprint ""
		(layer "B.Cu")
		(at 425.5008 -14.1732 -90)
		(property "Reference" "R9G29"
			(at 0 0 90)
			(layer "B.SilkS")
			(hide yes)
			(effects
				(font
					(size 1.27 1.27)
				)
				(justify mirror)
			)
		)
		(property "Value" ""
			(at 0 0 90)
			(layer "B.Fab")
			(effects
				(font
					(size 1.27 1.27)
				)
				(justify mirror)
			)
		)
		(duplicate_pad_numbers_are_jumpers no)
		(fp_poly
			(pts
				(xy 0.2794 -0.101854) (xy -0.279654 -0.101854) (xy -0.2794 0.990346) (xy 0.279146 0.990346)
			)
			(stroke
				(width 0)
				(type default)
			)
			(fill no)
			(layer "B.CrtYd")
		)
		(fp_line
			(start -0.2794 0.990346)
			(end -0.279654 -0.101854)
			(stroke
				(width 0.1)
				(type default)
			)
			(layer "B.Fab")
		)
		(fp_line
			(start 0.279146 0.990346)
			(end -0.2794 0.990346)
			(stroke
				(width 0.1)
				(type default)
			)
			(layer "B.Fab")
		)
		(fp_line
			(start -0.279654 -0.101854)
			(end 0.2794 -0.101854)
			(stroke
				(width 0.1)
				(type default)
			)
			(layer "B.Fab")
		)
		(fp_line
			(start 0.2794 -0.101854)
			(end 0.279146 0.990346)
			(stroke
				(width 0.1)
				(type default)
			)
			(layer "B.Fab")
		)
		(pad "1" smd rect
			(at 0 0 90)
			(size 0.508 0.508)
			(layers "B.Cu" "B.Mask" "B.Paste")
			(net "H_CPU0_MEMDEF_MEMHOT_LVT3_N")
		)
		(pad "2" smd rect
			(at 0 0.889 90)
			(size 0.508 0.508)
			(layers "B.Cu" "B.Mask" "B.Paste")
			(net "H_CPU0_MEMDEF_MEMHOT_LVT3_BMC_N")
		)
		(zone
			(layer "B.Cu")
			(hatch none 0.5)
			(connect_pads
				(clearance 0)
			)
			(min_thickness 0.25)
			(keepout
				(tracks not_allowed)
				(vias allowed)
				(pads allowed)
				(copperpour not_allowed)
				(footprints allowed)
			)
			(placement
				(enabled no)
				(sheetname "")
			)
			(fill
				(thermal_gap 0.5)
				(thermal_bridge_width 0.5)
				(island_removal_mode 0)
			)
			(polygon
				(pts
					(xy 424.866054 -13.9192) (xy 424.866054 -14.427454) (xy 425.247054 -14.4272) (xy 425.247054 -13.9192)
				)
			)
		)
		(zone
			(layer "B.Cu")
			(hatch none 0.5)
			(connect_pads
				(clearance 0)
			)
			(min_thickness 0.25)
			(keepout
				(tracks allowed)
				(vias not_allowed)
				(pads allowed)
				(copperpour not_allowed)
				(footprints allowed)
			)
			(placement
				(enabled no)
				(sheetname "")
			)
			(fill
				(thermal_gap 0.5)
				(thermal_bridge_width 0.5)
				(island_removal_mode 0)
			)
			(polygon
				(pts
					(xy 425.247054 -13.9192) (xy 425.247054 -14.4272) (xy 424.866054 -14.427454) (xy 424.866054 -13.9192)
				)
			)
		)
	)
	(footprint ""
		(layer "B.Cu")
		(at 480.2251 -45.3644 90)
		(property "Reference" "C1R17"
			(at 0 0 90)
			(layer "B.SilkS")
			(hide yes)
			(effects
				(font
					(size 1.27 1.27)
				)
				(justify mirror)
			)
		)
		(property "Value" ""
			(at 0 0 90)
			(layer "B.Fab")
			(effects
				(font
					(size 1.27 1.27)
				)
				(justify mirror)
			)
		)
		(duplicate_pad_numbers_are_jumpers no)
		(fp_poly
			(pts
				(xy 0.4953 -0.2032) (xy -0.4953 -0.2032) (xy -0.4953 1.6002) (xy 0.4953 1.6002)
			)
			(stroke
				(width 0)
				(type default)
			)
			(fill no)
			(layer "B.CrtYd")
		)
		(fp_line
			(start 0.4953 -0.2032)
			(end -0.4953 -0.2032)
			(stroke
				(width 0.1)
				(type default)
			)
			(layer "B.Fab")
		)
		(fp_line
			(start -0.4953 -0.2032)
			(end -0.4953 1.6002)
			(stroke
				(width 0.1)
				(type default)
			)
			(layer "B.Fab")
		)
		(fp_line
			(start 0.4953 1.6002)
			(end 0.4953 -0.2032)
			(stroke
				(width 0.1)
				(type default)
			)
			(layer "B.Fab")
		)
		(fp_line
			(start -0.4953 1.6002)
			(end 0.4953 1.6002)
			(stroke
				(width 0.1)
				(type default)
			)
			(layer "B.Fab")
		)
		(pad "1" smd rect
			(at 0 0 270)
			(size 0.762 0.889)
			(layers "B.Cu" "B.Mask" "B.Paste")
			(net "P1V5_LAN")
		)
		(pad "2" smd rect
			(at 0 1.397 270)
			(size 0.762 0.889)
			(layers "B.Cu" "B.Mask" "B.Paste")
			(net "GND")
		)
		(zone
			(layer "B.Cu")
			(hatch none 0.5)
			(connect_pads
				(clearance 0)
			)
			(min_thickness 0.25)
			(keepout
				(tracks not_allowed)
				(vias allowed)
				(pads allowed)
				(copperpour not_allowed)
				(footprints allowed)
			)
			(placement
				(enabled no)
				(sheetname "")
			)
			(fill
				(thermal_gap 0.5)
				(thermal_bridge_width 0.5)
				(island_removal_mode 0)
			)
			(polygon
				(pts
					(xy 480.6696 -45.7454) (xy 480.6696 -44.9834) (xy 481.1776 -44.9834) (xy 481.1776 -45.7454)
				)
			)
		)
	)
	(footprint ""
		(layer "B.Cu")
		(at 107.8611 -145.0086 90)
		(property "Reference" "C7L5"
			(at -1.848866 0.752348 90)
			(unlocked yes)
			(layer "B.SilkS")
			(effects
				(font
					(size 1.27 0.9652)
					(thickness 0.1524)
				)
				(justify mirror)
			)
		)
		(property "Value" ""
			(at 0 0 90)
			(layer "B.Fab")
			(effects
				(font
					(size 1.27 1.27)
				)
				(justify mirror)
			)
		)
		(duplicate_pad_numbers_are_jumpers no)
		(fp_rect
			(start 0.500126 1.598422)
			(end -0.500126 -0.201422)
			(stroke
				(width 0)
				(type default)
			)
			(fill no)
			(layer "B.CrtYd")
		)
		(fp_line
			(start 0.500126 -0.201422)
			(end -0.500126 -0.201422)
			(stroke
				(width 0.1)
				(type default)
			)
			(layer "B.Fab")
		)
		(fp_line
			(start -0.500126 -0.201422)
			(end -0.500126 1.598422)
			(stroke
				(width 0.1)
				(type default)
			)
			(layer "B.Fab")
		)
		(fp_line
			(start 0.500126 1.598422)
			(end 0.500126 -0.201422)
			(stroke
				(width 0.1)
				(type default)
			)
			(layer "B.Fab")
		)
		(fp_line
			(start -0.500126 1.598422)
			(end 0.500126 1.598422)
			(stroke
				(width 0.1)
				(type default)
			)
			(layer "B.Fab")
		)
		(pad "1" smd rect
			(at 0 0)
			(size 0.889 0.9906)
			(layers "B.Cu" "B.Mask" "B.Paste")
			(net "PVDDQ_KLM")
		)
		(pad "2" smd rect
			(at 0 1.397)
			(size 0.889 0.9906)
			(layers "B.Cu" "B.Mask" "B.Paste")
			(net "GND")
		)
		(zone
			(layer "B.Cu")
			(hatch none 0.5)
			(connect_pads
				(clearance 0)
			)
			(min_thickness 0.25)
			(keepout
				(tracks not_allowed)
				(vias allowed)
				(pads allowed)
				(copperpour not_allowed)
				(footprints allowed)
			)
			(placement
				(enabled no)
				(sheetname "")
			)
			(fill
				(thermal_gap 0.5)
				(thermal_bridge_width 0.5)
				(island_removal_mode 0)
			)
			(polygon
				(pts
					(xy 108.8136 -145.5039) (xy 108.3056 -145.5039) (xy 108.3056 -144.5133) (xy 108.8136 -144.5133)
				)
			)
		)
		(zone
			(layer "B.Cu")
			(hatch none 0.5)
			(connect_pads
				(clearance 0)
			)
			(min_thickness 0.25)
			(keepout
				(tracks allowed)
				(vias not_allowed)
				(pads allowed)
				(copperpour not_allowed)
				(footprints allowed)
			)
			(placement
				(enabled no)
				(sheetname "")
			)
			(fill
				(thermal_gap 0.5)
				(thermal_bridge_width 0.5)
				(island_removal_mode 0)
			)
			(polygon
				(pts
					(xy 108.8136 -145.5039) (xy 108.3056 -145.5039) (xy 108.3056 -144.5133) (xy 108.8136 -144.5133)
				)
			)
		)
	)
	(footprint ""
		(layer "B.Cu")
		(at 437.0197 -149.7965)
		(property "Reference" "C25W94"
			(at 0.8382 -0.67818 0)
			(unlocked yes)
			(layer "B.SilkS")
			(effects
				(font
					(size 0.4064 0.254)
					(thickness 0.1524)
				)
				(justify left mirror)
			)
		)
		(property "Value" ""
			(at 0 0 0)
			(layer "B.Fab")
			(effects
				(font
					(size 1.27 1.27)
				)
				(justify mirror)
			)
		)
		(duplicate_pad_numbers_are_jumpers no)
		(fp_poly
			(pts
				(xy -0.3048 -0.1016) (xy -0.3048 0.9906) (xy 0.3048 0.9906) (xy 0.3048 -0.1016)
			)
			(stroke
				(width 0)
				(type default)
			)
			(fill no)
			(layer "B.CrtYd")
		)
		(fp_line
			(start -0.3048 -0.1016)
			(end 0.3048 -0.1016)
			(stroke
				(width 0.1)
				(type default)
			)
			(layer "B.Fab")
		)
		(fp_line
			(start -0.3048 0.9906)
			(end -0.3048 -0.1016)
			(stroke
				(width 0.1)
				(type default)
			)
			(layer "B.Fab")
		)
		(fp_line
			(start 0.3048 -0.1016)
			(end 0.3048 0.9906)
			(stroke
				(width 0.1)
				(type default)
			)
			(layer "B.Fab")
		)
		(fp_line
			(start 0.3048 0.9906)
			(end -0.3048 0.9906)
			(stroke
				(width 0.1)
				(type default)
			)
			(layer "B.Fab")
		)
		(pad "1" smd rect
			(at 0 0 180)
			(size 0.508 0.508)
			(layers "B.Cu" "B.Mask" "B.Paste")
			(net "P3V3_STBY")
		)
		(pad "2" smd rect
			(at 0 0.889 180)
			(size 0.508 0.508)
			(layers "B.Cu" "B.Mask" "B.Paste")
			(net "GND")
		)
		(zone
			(layer "B.Cu")
			(hatch none 0.5)
			(connect_pads
				(clearance 0)
			)
			(min_thickness 0.25)
			(keepout
				(tracks allowed)
				(vias not_allowed)
				(pads allowed)
				(copperpour not_allowed)
				(footprints allowed)
			)
			(placement
				(enabled no)
				(sheetname "")
			)
			(fill
				(thermal_gap 0.5)
				(thermal_bridge_width 0.5)
				(island_removal_mode 0)
			)
			(polygon
				(pts
					(xy 437.2737 -149.5425) (xy 436.7657 -149.5425) (xy 436.7657 -149.1615) (xy 437.2737 -149.1615)
				)
			)
		)
		(zone
			(layer "B.Cu")
			(hatch none 0.5)
			(connect_pads
				(clearance 0)
			)
			(min_thickness 0.25)
			(keepout
				(tracks not_allowed)
				(vias allowed)
				(pads allowed)
				(copperpour not_allowed)
				(footprints allowed)
			)
			(placement
				(enabled no)
				(sheetname "")
			)
			(fill
				(thermal_gap 0.5)
				(thermal_bridge_width 0.5)
				(island_removal_mode 0)
			)
			(polygon
				(pts
					(xy 437.2737 -149.1615) (xy 436.7657 -149.1615) (xy 436.7657 -149.5425) (xy 437.2737 -149.5425)
				)
			)
		)
	)
	(footprint ""
		(layer "B.Cu")
		(at 272.861532 -149.8092 90)
		(property "Reference" "C5G71"
			(at -1.14681 0.76708 180)
			(unlocked yes)
			(layer "B.SilkS")
			(effects
				(font
					(size 0.7874 0.5842)
					(thickness 0.1524)
				)
				(justify mirror)
			)
		)
		(property "Value" ""
			(at 0 0 90)
			(layer "B.Fab")
			(effects
				(font
					(size 1.27 1.27)
				)
				(justify mirror)
			)
		)
		(duplicate_pad_numbers_are_jumpers no)
		(fp_rect
			(start -0.4953 -0.2032)
			(end 0.4953 1.6002)
			(stroke
				(width 0)
				(type default)
			)
			(fill no)
			(layer "B.CrtYd")
		)
		(fp_line
			(start 0.4953 -0.2032)
			(end -0.4953 -0.2032)
			(stroke
				(width 0.1)
				(type default)
			)
			(layer "B.Fab")
		)
		(fp_line
			(start -0.4953 -0.2032)
			(end -0.4953 1.6002)
			(stroke
				(width 0.1)
				(type default)
			)
			(layer "B.Fab")
		)
		(fp_line
			(start 0.4953 1.6002)
			(end 0.4953 -0.2032)
			(stroke
				(width 0.1)
				(type default)
			)
			(layer "B.Fab")
		)
		(fp_line
			(start -0.4953 1.6002)
			(end 0.4953 1.6002)
			(stroke
				(width 0.1)
				(type default)
			)
			(layer "B.Fab")
		)
		(pad "1" smd rect
			(at 0 0 270)
			(size 0.762 0.889)
			(layers "B.Cu" "B.Mask" "B.Paste")
			(net "PVDDQ_DEF")
		)
		(pad "2" smd rect
			(at 0 1.397 270)
			(size 0.762 0.889)
			(layers "B.Cu" "B.Mask" "B.Paste")
			(net "GND")
		)
		(zone
			(layer "B.Cu")
			(hatch none 0.5)
			(connect_pads
				(clearance 0)
			)
			(min_thickness 0.25)
			(keepout
				(tracks not_allowed)
				(vias allowed)
				(pads allowed)
				(copperpour not_allowed)
				(footprints allowed)
			)
			(placement
				(enabled no)
				(sheetname "")
			)
			(fill
				(thermal_gap 0.5)
				(thermal_bridge_width 0.5)
				(island_removal_mode 0)
			)
			(polygon
				(pts
					(xy 273.306032 -149.4282) (xy 273.814032 -149.4282) (xy 273.814032 -150.1902) (xy 273.306032 -150.1902)
				)
			)
		)
	)
	(footprint ""
		(layer "B.Cu")
		(at 499.3894 -140.843)
		(property "Reference" "R1L33"
			(at 0 0 0)
			(layer "B.SilkS")
			(hide yes)
			(effects
				(font
					(size 1.27 1.27)
				)
				(justify mirror)
			)
		)
		(property "Value" ""
			(at 0 0 0)
			(layer "B.Fab")
			(effects
				(font
					(size 1.27 1.27)
				)
				(justify mirror)
			)
		)
		(duplicate_pad_numbers_are_jumpers no)
		(fp_poly
			(pts
				(xy 0.2794 -0.1016) (xy -0.2794 -0.1016) (xy -0.2794 0.9906) (xy 0.2794 0.9906)
			)
			(stroke
				(width 0)
				(type default)
			)
			(fill no)
			(layer "B.CrtYd")
		)
		(fp_line
			(start -0.2794 -0.1016)
			(end 0.2794 -0.1016)
			(stroke
				(width 0.1)
				(type default)
			)
			(layer "B.Fab")
		)
		(fp_line
			(start -0.2794 0.9906)
			(end -0.2794 -0.1016)
			(stroke
				(width 0.1)
				(type default)
			)
			(layer "B.Fab")
		)
		(fp_line
			(start 0.2794 -0.1016)
			(end 0.2794 0.9906)
			(stroke
				(width 0.1)
				(type default)
			)
			(layer "B.Fab")
		)
		(fp_line
			(start 0.2794 0.9906)
			(end -0.2794 0.9906)
			(stroke
				(width 0.1)
				(type default)
			)
			(layer "B.Fab")
		)
		(pad "1" smd rect
			(at 0 0 180)
			(size 0.508 0.508)
			(layers "B.Cu" "B.Mask" "B.Paste")
			(net "FM_BEEP_LED_P")
		)
		(pad "2" smd rect
			(at 0 0.889 180)
			(size 0.508 0.508)
			(layers "B.Cu" "B.Mask" "B.Paste")
			(net "P3V3_STBY")
		)
		(zone
			(layer "B.Cu")
			(hatch none 0.5)
			(connect_pads
				(clearance 0)
			)
			(min_thickness 0.25)
			(keepout
				(tracks allowed)
				(vias not_allowed)
				(pads allowed)
				(copperpour not_allowed)
				(footprints allowed)
			)
			(placement
				(enabled no)
				(sheetname "")
			)
			(fill
				(thermal_gap 0.5)
				(thermal_bridge_width 0.5)
				(island_removal_mode 0)
			)
			(polygon
				(pts
					(xy 499.6434 -140.589) (xy 499.1354 -140.589) (xy 499.1354 -140.208) (xy 499.6434 -140.208)
				)
			)
		)
		(zone
			(layer "B.Cu")
			(hatch none 0.5)
			(connect_pads
				(clearance 0)
			)
			(min_thickness 0.25)
			(keepout
				(tracks not_allowed)
				(vias allowed)
				(pads allowed)
				(copperpour not_allowed)
				(footprints allowed)
			)
			(placement
				(enabled no)
				(sheetname "")
			)
			(fill
				(thermal_gap 0.5)
				(thermal_bridge_width 0.5)
				(island_removal_mode 0)
			)
			(polygon
				(pts
					(xy 499.6434 -140.208) (xy 499.1354 -140.208) (xy 499.1354 -140.589) (xy 499.6434 -140.589)
				)
			)
		)
	)
	(footprint ""
		(layer "B.Cu")
		(at 248.8565 -12.954 -90)
		(property "Reference" "C5G42"
			(at -1.14681 0.76708 0)
			(unlocked yes)
			(layer "B.SilkS")
			(effects
				(font
					(size 0.7874 0.5842)
					(thickness 0.1524)
				)
				(justify mirror)
			)
		)
		(property "Value" ""
			(at 0 0 90)
			(layer "B.Fab")
			(effects
				(font
					(size 1.27 1.27)
				)
				(justify mirror)
			)
		)
		(duplicate_pad_numbers_are_jumpers no)
		(fp_rect
			(start 0.4953 1.6002)
			(end -0.4953 -0.2032)
			(stroke
				(width 0)
				(type default)
			)
			(fill no)
			(layer "B.CrtYd")
		)
		(fp_line
			(start -0.4953 1.6002)
			(end 0.4953 1.6002)
			(stroke
				(width 0.1)
				(type default)
			)
			(layer "B.Fab")
		)
		(fp_line
			(start 0.4953 1.6002)
			(end 0.4953 -0.2032)
			(stroke
				(width 0.1)
				(type default)
			)
			(layer "B.Fab")
		)
		(fp_line
			(start -0.4953 -0.2032)
			(end -0.4953 1.6002)
			(stroke
				(width 0.1)
				(type default)
			)
			(layer "B.Fab")
		)
		(fp_line
			(start 0.4953 -0.2032)
			(end -0.4953 -0.2032)
			(stroke
				(width 0.1)
				(type default)
			)
			(layer "B.Fab")
		)
		(pad "1" smd rect
			(at 0 0 90)
			(size 0.762 0.889)
			(layers "B.Cu" "B.Mask" "B.Paste")
			(net "PVDDQ_ABC")
		)
		(pad "2" smd rect
			(at 0 1.397 90)
			(size 0.762 0.889)
			(layers "B.Cu" "B.Mask" "B.Paste")
			(net "GND")
		)
		(zone
			(layer "B.Cu")
			(hatch none 0.5)
			(connect_pads
				(clearance 0)
			)
			(min_thickness 0.25)
			(keepout
				(tracks not_allowed)
				(vias allowed)
				(pads allowed)
				(copperpour not_allowed)
				(footprints allowed)
			)
			(placement
				(enabled no)
				(sheetname "")
			)
			(fill
				(thermal_gap 0.5)
				(thermal_bridge_width 0.5)
				(island_removal_mode 0)
			)
			(polygon
				(pts
					(xy 247.904 -12.573) (xy 248.412 -12.573) (xy 248.412 -13.335) (xy 247.904 -13.335)
				)
			)
		)
	)
	(footprint ""
		(layer "B.Cu")
		(at 408.305 -151.511 90)
		(property "Reference" "C2L14"
			(at 0 0 90)
			(layer "B.SilkS")
			(hide yes)
			(effects
				(font
					(size 1.27 1.27)
				)
				(justify mirror)
			)
		)
		(property "Value" ""
			(at 0 0 90)
			(layer "B.Fab")
			(effects
				(font
					(size 1.27 1.27)
				)
				(justify mirror)
			)
		)
		(duplicate_pad_numbers_are_jumpers no)
		(fp_poly
			(pts
				(xy -0.3048 -0.1016) (xy -0.3048 0.9906) (xy 0.3048 0.9906) (xy 0.3048 -0.1016)
			)
			(stroke
				(width 0)
				(type default)
			)
			(fill no)
			(layer "B.CrtYd")
		)
		(fp_line
			(start 0.3048 -0.1016)
			(end 0.3048 0.9906)
			(stroke
				(width 0.1)
				(type default)
			)
			(layer "B.Fab")
		)
		(fp_line
			(start -0.3048 -0.1016)
			(end 0.3048 -0.1016)
			(stroke
				(width 0.1)
				(type default)
			)
			(layer "B.Fab")
		)
		(fp_line
			(start 0.3048 0.9906)
			(end -0.3048 0.9906)
			(stroke
				(width 0.1)
				(type default)
			)
			(layer "B.Fab")
		)
		(fp_line
			(start -0.3048 0.9906)
			(end -0.3048 -0.1016)
			(stroke
				(width 0.1)
				(type default)
			)
			(layer "B.Fab")
		)
		(pad "1" smd rect
			(at 0 0 270)
			(size 0.508 0.508)
			(layers "B.Cu" "B.Mask" "B.Paste")
			(net "SATA6G_PCH_PCIE_UP_SATA_RXN<6>")
		)
		(pad "2" smd rect
			(at 0 0.889 270)
			(size 0.508 0.508)
			(layers "B.Cu" "B.Mask" "B.Paste")
			(net "SATA6G_P6_RX_C_DN")
		)
		(zone
			(layer "B.Cu")
			(hatch none 0.5)
			(connect_pads
				(clearance 0)
			)
			(min_thickness 0.25)
			(keepout
				(tracks allowed)
				(vias not_allowed)
				(pads allowed)
				(copperpour not_allowed)
				(footprints allowed)
			)
			(placement
				(enabled no)
				(sheetname "")
			)
			(fill
				(thermal_gap 0.5)
				(thermal_bridge_width 0.5)
				(island_removal_mode 0)
			)
			(polygon
				(pts
					(xy 408.559 -151.765) (xy 408.559 -151.257) (xy 408.94 -151.257) (xy 408.94 -151.765)
				)
			)
		)
		(zone
			(layer "B.Cu")
			(hatch none 0.5)
			(connect_pads
				(clearance 0)
			)
			(min_thickness 0.25)
			(keepout
				(tracks not_allowed)
				(vias allowed)
				(pads allowed)
				(copperpour not_allowed)
				(footprints allowed)
			)
			(placement
				(enabled no)
				(sheetname "")
			)
			(fill
				(thermal_gap 0.5)
				(thermal_bridge_width 0.5)
				(island_removal_mode 0)
			)
			(polygon
				(pts
					(xy 408.94 -151.765) (xy 408.94 -151.257) (xy 408.559 -151.257) (xy 408.559 -151.765)
				)
			)
		)
	)
	(footprint ""
		(layer "B.Cu")
		(at 330.091288 -64.17564 90)
		(property "Reference" "R3R13"
			(at 0 0 90)
			(layer "B.SilkS")
			(hide yes)
			(effects
				(font
					(size 1.27 1.27)
				)
				(justify mirror)
			)
		)
		(property "Value" ""
			(at 0 0 90)
			(layer "B.Fab")
			(effects
				(font
					(size 1.27 1.27)
				)
				(justify mirror)
			)
		)
		(duplicate_pad_numbers_are_jumpers no)
		(fp_poly
			(pts
				(xy 0.2794 -0.1016) (xy -0.2794 -0.1016) (xy -0.2794 0.9906) (xy 0.2794 0.9906)
			)
			(stroke
				(width 0)
				(type default)
			)
			(fill no)
			(layer "B.CrtYd")
		)
		(fp_line
			(start 0.2794 -0.1016)
			(end 0.2794 0.9906)
			(stroke
				(width 0.1)
				(type default)
			)
			(layer "B.Fab")
		)
		(fp_line
			(start -0.2794 -0.1016)
			(end 0.2794 -0.1016)
			(stroke
				(width 0.1)
				(type default)
			)
			(layer "B.Fab")
		)
		(fp_line
			(start 0.2794 0.9906)
			(end -0.2794 0.9906)
			(stroke
				(width 0.1)
				(type default)
			)
			(layer "B.Fab")
		)
		(fp_line
			(start -0.2794 0.9906)
			(end -0.2794 -0.1016)
			(stroke
				(width 0.1)
				(type default)
			)
			(layer "B.Fab")
		)
		(pad "1" smd rect
			(at 0 0 270)
			(size 0.508 0.508)
			(layers "B.Cu" "B.Mask" "B.Paste")
			(net "PVCCIO_CPU0")
		)
		(pad "2" smd rect
			(at 0 0.889 270)
			(size 0.508 0.508)
			(layers "B.Cu" "B.Mask" "B.Paste")
			(net "SMB_DDR_DEF_SDA_G")
		)
		(zone
			(layer "B.Cu")
			(hatch none 0.5)
			(connect_pads
				(clearance 0)
			)
			(min_thickness 0.25)
			(keepout
				(tracks allowed)
				(vias not_allowed)
				(pads allowed)
				(copperpour not_allowed)
				(footprints allowed)
			)
			(placement
				(enabled no)
				(sheetname "")
			)
			(fill
				(thermal_gap 0.5)
				(thermal_bridge_width 0.5)
				(island_removal_mode 0)
			)
			(polygon
				(pts
					(xy 330.345288 -64.42964) (xy 330.345288 -63.92164) (xy 330.726288 -63.92164) (xy 330.726288 -64.42964)
				)
			)
		)
		(zone
			(layer "B.Cu")
			(hatch none 0.5)
			(connect_pads
				(clearance 0)
			)
			(min_thickness 0.25)
			(keepout
				(tracks not_allowed)
				(vias allowed)
				(pads allowed)
				(copperpour not_allowed)
				(footprints allowed)
			)
			(placement
				(enabled no)
				(sheetname "")
			)
			(fill
				(thermal_gap 0.5)
				(thermal_bridge_width 0.5)
				(island_removal_mode 0)
			)
			(polygon
				(pts
					(xy 330.726288 -64.42964) (xy 330.726288 -63.92164) (xy 330.345288 -63.92164) (xy 330.345288 -64.42964)
				)
			)
		)
	)
	(footprint ""
		(layer "B.Cu")
		(at 173.279816 -68.650104 180)
		(property "Reference" "Q4W2"
			(at 0.229362 -1.59512 180)
			(unlocked yes)
			(layer "B.SilkS")
			(effects
				(font
					(size 1.27 0.9652)
					(thickness 0.1524)
				)
				(justify left mirror)
			)
		)
		(property "Value" ""
			(at 0 0 0)
			(layer "B.Fab")
			(effects
				(font
					(size 1.27 1.27)
				)
				(justify mirror)
			)
		)
		(duplicate_pad_numbers_are_jumpers no)
		(fp_line
			(start -0.381 0.635)
			(end -0.381 1.27)
			(stroke
				(width 0.1524)
				(type default)
			)
			(layer "B.SilkS")
		)
		(fp_line
			(start -0.9525 2.4765)
			(end -1.778 2.4765)
			(stroke
				(width 0.1524)
				(type default)
			)
			(layer "B.SilkS")
		)
		(fp_line
			(start -0.9525 -0.5715)
			(end -1.778 -0.5715)
			(stroke
				(width 0.1524)
				(type default)
			)
			(layer "B.SilkS")
		)
		(fp_line
			(start -1.778 2.4765)
			(end -1.778 1.5875)
			(stroke
				(width 0.1524)
				(type default)
			)
			(layer "B.SilkS")
		)
		(fp_line
			(start -1.778 -0.5715)
			(end -1.778 0.3175)
			(stroke
				(width 0.1524)
				(type default)
			)
			(layer "B.SilkS")
		)
		(fp_circle
			(center 0.9525 -0.9271)
			(end 0.8255 -0.9271)
			(stroke
				(width 0.254)
				(type default)
			)
			(fill no)
			(layer "B.SilkS")
		)
		(fp_poly
			(pts
				(xy -1.778 2.4765) (xy -0.381 2.4765) (xy -0.381 -0.5715) (xy -1.778 -0.5715)
			)
			(stroke
				(width 0)
				(type default)
			)
			(fill no)
			(layer "B.CrtYd")
		)
		(fp_line
			(start -0.381 2.4765)
			(end -1.778 2.4765)
			(stroke
				(width 0.1)
				(type default)
			)
			(layer "B.Fab")
		)
		(fp_line
			(start -0.381 -0.5715)
			(end -0.381 2.4765)
			(stroke
				(width 0.1)
				(type default)
			)
			(layer "B.Fab")
		)
		(fp_line
			(start -1.778 2.4765)
			(end -1.778 -0.5715)
			(stroke
				(width 0.1)
				(type default)
			)
			(layer "B.Fab")
		)
		(fp_line
			(start -1.778 -0.5715)
			(end -0.381 -0.5715)
			(stroke
				(width 0.1)
				(type default)
			)
			(layer "B.Fab")
		)
		(fp_circle
			(center 0.9525 -0.9271)
			(end 0.8255 -0.9271)
			(stroke
				(width 0.254)
				(type default)
			)
			(fill no)
			(layer "B.Fab")
		)
		(pad "1" smd rect
			(at 0 0)
			(size 1.143 0.508)
			(layers "B.Cu" "B.Mask" "B.Paste")
			(net "FM_DB1200_PWRGD")
		)
		(pad "2" smd rect
			(at 0 1.905)
			(size 1.143 0.508)
			(layers "B.Cu" "B.Mask" "B.Paste")
			(net "GND")
		)
		(pad "3" smd rect
			(at -2.159 0.9525)
			(size 1.143 0.508)
			(layers "B.Cu" "B.Mask" "B.Paste")
			(net "FM_DB1200_PWRGD_R")
		)
	)
	(footprint ""
		(layer "B.Cu")
		(at 245.7577 -135.4074 -90)
		(property "Reference" "C5M7"
			(at -1.848866 0.752348 270)
			(unlocked yes)
			(layer "B.SilkS")
			(effects
				(font
					(size 1.27 0.9652)
					(thickness 0.1524)
				)
				(justify mirror)
			)
		)
		(property "Value" ""
			(at 0 0 90)
			(layer "B.Fab")
			(effects
				(font
					(size 1.27 1.27)
				)
				(justify mirror)
			)
		)
		(duplicate_pad_numbers_are_jumpers no)
		(fp_rect
			(start 0.500126 1.598422)
			(end -0.500126 -0.201422)
			(stroke
				(width 0)
				(type default)
			)
			(fill no)
			(layer "B.CrtYd")
		)
		(fp_line
			(start -0.500126 1.598422)
			(end 0.500126 1.598422)
			(stroke
				(width 0.1)
				(type default)
			)
			(layer "B.Fab")
		)
		(fp_line
			(start 0.500126 1.598422)
			(end 0.500126 -0.201422)
			(stroke
				(width 0.1)
				(type default)
			)
			(layer "B.Fab")
		)
		(fp_line
			(start -0.500126 -0.201422)
			(end -0.500126 1.598422)
			(stroke
				(width 0.1)
				(type default)
			)
			(layer "B.Fab")
		)
		(fp_line
			(start 0.500126 -0.201422)
			(end -0.500126 -0.201422)
			(stroke
				(width 0.1)
				(type default)
			)
			(layer "B.Fab")
		)
		(pad "1" smd rect
			(at 0 0 180)
			(size 0.889 0.9906)
			(layers "B.Cu" "B.Mask" "B.Paste")
			(net "PVDDQ_DEF")
		)
		(pad "2" smd rect
			(at 0 1.397 180)
			(size 0.889 0.9906)
			(layers "B.Cu" "B.Mask" "B.Paste")
			(net "GND")
		)
		(zone
			(layer "B.Cu")
			(hatch none 0.5)
			(connect_pads
				(clearance 0)
			)
			(min_thickness 0.25)
			(keepout
				(tracks not_allowed)
				(vias allowed)
				(pads allowed)
				(copperpour not_allowed)
				(footprints allowed)
			)
			(placement
				(enabled no)
				(sheetname "")
			)
			(fill
				(thermal_gap 0.5)
				(thermal_bridge_width 0.5)
				(island_removal_mode 0)
			)
			(polygon
				(pts
					(xy 244.8052 -134.9121) (xy 245.3132 -134.9121) (xy 245.3132 -135.9027) (xy 244.8052 -135.9027)
				)
			)
		)
		(zone
			(layer "B.Cu")
			(hatch none 0.5)
			(connect_pads
				(clearance 0)
			)
			(min_thickness 0.25)
			(keepout
				(tracks allowed)
				(vias not_allowed)
				(pads allowed)
				(copperpour not_allowed)
				(footprints allowed)
			)
			(placement
				(enabled no)
				(sheetname "")
			)
			(fill
				(thermal_gap 0.5)
				(thermal_bridge_width 0.5)
				(island_removal_mode 0)
			)
			(polygon
				(pts
					(xy 244.8052 -134.9121) (xy 245.3132 -134.9121) (xy 245.3132 -135.9027) (xy 244.8052 -135.9027)
				)
			)
		)
	)
	(footprint ""
		(layer "B.Cu")
		(at 197.848728 -58.428382 90)
		(property "Reference" "C6R11"
			(at 0 0 90)
			(layer "B.SilkS")
			(hide yes)
			(effects
				(font
					(size 1.27 1.27)
				)
				(justify mirror)
			)
		)
		(property "Value" ""
			(at 0 0 90)
			(layer "B.Fab")
			(effects
				(font
					(size 1.27 1.27)
				)
				(justify mirror)
			)
		)
		(duplicate_pad_numbers_are_jumpers no)
		(fp_rect
			(start 0.7239 1.9939)
			(end -0.7239 -0.2159)
			(stroke
				(width 0)
				(type default)
			)
			(fill no)
			(layer "B.CrtYd")
		)
		(fp_line
			(start 0.7239 -0.2159)
			(end 0.7239 1.9939)
			(stroke
				(width 0.1)
				(type default)
			)
			(layer "B.Fab")
		)
		(fp_line
			(start -0.7239 -0.2159)
			(end 0.7239 -0.2159)
			(stroke
				(width 0.1)
				(type default)
			)
			(layer "B.Fab")
		)
		(fp_line
			(start 0.7239 1.9939)
			(end -0.7239 1.9939)
			(stroke
				(width 0.1)
				(type default)
			)
			(layer "B.Fab")
		)
		(fp_line
			(start -0.7239 1.9939)
			(end -0.7239 -0.2159)
			(stroke
				(width 0.1)
				(type default)
			)
			(layer "B.Fab")
		)
		(pad "1" smd rect
			(at 0 0 270)
			(size 1.27 1.016)
			(layers "B.Cu" "B.Mask" "B.Paste")
			(net "VR_FET_SW_P12V_STBY_PVCCIN_CPU0")
		)
		(pad "2" smd rect
			(at 0 1.778 270)
			(size 1.27 1.016)
			(layers "B.Cu" "B.Mask" "B.Paste")
			(net "GND")
		)
		(zone
			(layer "B.Cu")
			(hatch none 0.5)
			(connect_pads
				(clearance 0)
			)
			(min_thickness 0.25)
			(keepout
				(tracks not_allowed)
				(vias allowed)
				(pads allowed)
				(copperpour not_allowed)
				(footprints allowed)
			)
			(placement
				(enabled no)
				(sheetname "")
			)
			(fill
				(thermal_gap 0.5)
				(thermal_bridge_width 0.5)
				(island_removal_mode 0)
			)
			(polygon
				(pts
					(xy 199.118728 -59.063382) (xy 198.356728 -59.063382) (xy 198.356728 -57.793382) (xy 199.118728 -57.793382)
				)
			)
		)
	)
	(footprint ""
		(layer "B.Cu")
		(at 111.836454 -77.82814)
		(property "Reference" "C7P8"
			(at 0 0 0)
			(layer "B.SilkS")
			(hide yes)
			(effects
				(font
					(size 1.27 1.27)
				)
				(justify mirror)
			)
		)
		(property "Value" ""
			(at 0 0 0)
			(layer "B.Fab")
			(effects
				(font
					(size 1.27 1.27)
				)
				(justify mirror)
			)
		)
		(duplicate_pad_numbers_are_jumpers no)
		(fp_poly
			(pts
				(xy 0.7239 -0.2159) (xy -0.7239 -0.2159) (xy -0.7239 1.9939) (xy 0.7239 1.9939)
			)
			(stroke
				(width 0)
				(type default)
			)
			(fill no)
			(layer "B.CrtYd")
		)
		(fp_line
			(start -0.7239 -0.2159)
			(end 0.7239 -0.2159)
			(stroke
				(width 0.1)
				(type default)
			)
			(layer "B.Fab")
		)
		(fp_line
			(start -0.7239 1.9939)
			(end -0.7239 -0.2159)
			(stroke
				(width 0.1)
				(type default)
			)
			(layer "B.Fab")
		)
		(fp_line
			(start 0.7239 -0.2159)
			(end 0.7239 1.9939)
			(stroke
				(width 0.1)
				(type default)
			)
			(layer "B.Fab")
		)
		(fp_line
			(start 0.7239 1.9939)
			(end -0.7239 1.9939)
			(stroke
				(width 0.1)
				(type default)
			)
			(layer "B.Fab")
		)
		(pad "1" smd rect
			(at 0 0 180)
			(size 1.27 1.016)
			(layers "B.Cu" "B.Mask" "B.Paste")
			(net "PVCCMCP_CPU1")
		)
		(pad "2" smd rect
			(at 0 1.778 180)
			(size 1.27 1.016)
			(layers "B.Cu" "B.Mask" "B.Paste")
			(net "GND")
		)
		(zone
			(layer "B.Cu")
			(hatch none 0.5)
			(connect_pads
				(clearance 0)
			)
			(min_thickness 0.25)
			(keepout
				(tracks not_allowed)
				(vias allowed)
				(pads allowed)
				(copperpour not_allowed)
				(footprints allowed)
			)
			(placement
				(enabled no)
				(sheetname "")
			)
			(fill
				(thermal_gap 0.5)
				(thermal_bridge_width 0.5)
				(island_removal_mode 0)
			)
			(polygon
				(pts
					(xy 112.471454 -77.32014) (xy 111.201454 -77.32014) (xy 111.201454 -76.55814) (xy 112.471454 -76.55814)
				)
			)
		)
	)
	(footprint ""
		(layer "B.Cu")
		(at 399.182336 -141.226286 180)
		(property "Reference" "C7B17"
			(at 0 0 0)
			(layer "B.SilkS")
			(hide yes)
			(effects
				(font
					(size 1.27 1.27)
				)
				(justify mirror)
			)
		)
		(property "Value" ""
			(at 0 0 0)
			(layer "B.Fab")
			(effects
				(font
					(size 1.27 1.27)
				)
				(justify mirror)
			)
		)
		(duplicate_pad_numbers_are_jumpers no)
		(fp_rect
			(start 0.4953 1.6002)
			(end -0.4953 -0.2032)
			(stroke
				(width 0)
				(type default)
			)
			(fill no)
			(layer "B.CrtYd")
		)
		(fp_line
			(start 0.4953 1.6002)
			(end 0.4953 -0.2032)
			(stroke
				(width 0.1)
				(type default)
			)
			(layer "B.Fab")
		)
		(fp_line
			(start 0.4953 -0.2032)
			(end -0.4953 -0.2032)
			(stroke
				(width 0.1)
				(type default)
			)
			(layer "B.Fab")
		)
		(fp_line
			(start -0.4953 1.6002)
			(end 0.4953 1.6002)
			(stroke
				(width 0.1)
				(type default)
			)
			(layer "B.Fab")
		)
		(fp_line
			(start -0.4953 -0.2032)
			(end -0.4953 1.6002)
			(stroke
				(width 0.1)
				(type default)
			)
			(layer "B.Fab")
		)
		(pad "1" smd rect
			(at 0 0)
			(size 0.762 0.889)
			(layers "B.Cu" "B.Mask" "B.Paste")
			(net "P1V05_PCH_STBY")
		)
		(pad "2" smd rect
			(at 0 1.397)
			(size 0.762 0.889)
			(layers "B.Cu" "B.Mask" "B.Paste")
			(net "GND")
		)
		(zone
			(layer "B.Cu")
			(hatch none 0.5)
			(connect_pads
				(clearance 0)
			)
			(min_thickness 0.25)
			(keepout
				(tracks not_allowed)
				(vias allowed)
				(pads allowed)
				(copperpour not_allowed)
				(footprints allowed)
			)
			(placement
				(enabled no)
				(sheetname "")
			)
			(fill
				(thermal_gap 0.5)
				(thermal_bridge_width 0.5)
				(island_removal_mode 0)
			)
			(polygon
				(pts
					(xy 398.801336 -142.178786) (xy 398.801336 -141.670786) (xy 399.563336 -141.670786) (xy 399.563336 -142.178786)
				)
			)
		)
	)
	(footprint ""
		(layer "B.Cu")
		(at 343.789 -83.566)
		(property "Reference" "R3P20"
			(at 0 0 0)
			(layer "B.SilkS")
			(hide yes)
			(effects
				(font
					(size 1.27 1.27)
				)
				(justify mirror)
			)
		)
		(property "Value" ""
			(at 0 0 0)
			(layer "B.Fab")
			(effects
				(font
					(size 1.27 1.27)
				)
				(justify mirror)
			)
		)
		(duplicate_pad_numbers_are_jumpers no)
		(fp_poly
			(pts
				(xy 0.2794 -0.1016) (xy -0.2794 -0.1016) (xy -0.2794 0.9906) (xy 0.2794 0.9906)
			)
			(stroke
				(width 0)
				(type default)
			)
			(fill no)
			(layer "B.CrtYd")
		)
		(fp_line
			(start -0.2794 -0.1016)
			(end 0.2794 -0.1016)
			(stroke
				(width 0.1)
				(type default)
			)
			(layer "B.Fab")
		)
		(fp_line
			(start -0.2794 0.9906)
			(end -0.2794 -0.1016)
			(stroke
				(width 0.1)
				(type default)
			)
			(layer "B.Fab")
		)
		(fp_line
			(start 0.2794 -0.1016)
			(end 0.2794 0.9906)
			(stroke
				(width 0.1)
				(type default)
			)
			(layer "B.Fab")
		)
		(fp_line
			(start 0.2794 0.9906)
			(end -0.2794 0.9906)
			(stroke
				(width 0.1)
				(type default)
			)
			(layer "B.Fab")
		)
		(pad "1" smd rect
			(at 0 0 180)
			(size 0.508 0.508)
			(layers "B.Cu" "B.Mask" "B.Paste")
			(net "PWRGD_PVCCIO_CPU0_R")
		)
		(pad "2" smd rect
			(at 0 0.889 180)
			(size 0.508 0.508)
			(layers "B.Cu" "B.Mask" "B.Paste")
			(net "PWRGD_PVCCIO_CPU0")
		)
		(zone
			(layer "B.Cu")
			(hatch none 0.5)
			(connect_pads
				(clearance 0)
			)
			(min_thickness 0.25)
			(keepout
				(tracks allowed)
				(vias not_allowed)
				(pads allowed)
				(copperpour not_allowed)
				(footprints allowed)
			)
			(placement
				(enabled no)
				(sheetname "")
			)
			(fill
				(thermal_gap 0.5)
				(thermal_bridge_width 0.5)
				(island_removal_mode 0)
			)
			(polygon
				(pts
					(xy 344.043 -83.312) (xy 343.535 -83.312) (xy 343.535 -82.931) (xy 344.043 -82.931)
				)
			)
		)
		(zone
			(layer "B.Cu")
			(hatch none 0.5)
			(connect_pads
				(clearance 0)
			)
			(min_thickness 0.25)
			(keepout
				(tracks not_allowed)
				(vias allowed)
				(pads allowed)
				(copperpour not_allowed)
				(footprints allowed)
			)
			(placement
				(enabled no)
				(sheetname "")
			)
			(fill
				(thermal_gap 0.5)
				(thermal_bridge_width 0.5)
				(island_removal_mode 0)
			)
			(polygon
				(pts
					(xy 344.043 -82.931) (xy 343.535 -82.931) (xy 343.535 -83.312) (xy 344.043 -83.312)
				)
			)
		)
	)
	(footprint ""
		(layer "B.Cu")
		(at 370.74348 -73.095358 90)
		(property "Reference" "C2R1"
			(at 0 0 90)
			(layer "B.SilkS")
			(hide yes)
			(effects
				(font
					(size 1.27 1.27)
				)
				(justify mirror)
			)
		)
		(property "Value" ""
			(at 0 0 90)
			(layer "B.Fab")
			(effects
				(font
					(size 1.27 1.27)
				)
				(justify mirror)
			)
		)
		(duplicate_pad_numbers_are_jumpers no)
		(fp_rect
			(start 0.2794 0.9144)
			(end -0.2794 -0.1143)
			(stroke
				(width 0)
				(type default)
			)
			(fill no)
			(layer "B.CrtYd")
		)
		(fp_line
			(start 0.2794 -0.1143)
			(end -0.2794 -0.1143)
			(stroke
				(width 0.1)
				(type default)
			)
			(layer "B.Fab")
		)
		(fp_line
			(start -0.2794 -0.1143)
			(end -0.2794 0.9144)
			(stroke
				(width 0.1)
				(type default)
			)
			(layer "B.Fab")
		)
		(fp_line
			(start 0.2794 0.9144)
			(end 0.2794 -0.1143)
			(stroke
				(width 0.1)
				(type default)
			)
			(layer "B.Fab")
		)
		(fp_line
			(start -0.2794 0.9144)
			(end 0.2794 0.9144)
			(stroke
				(width 0.1)
				(type default)
			)
			(layer "B.Fab")
		)
		(pad "1" smd custom
			(at 0 0)
			(size 0.10414 0.10414)
			(layers "B.Cu" "B.Mask" "B.Paste")
			(net "P3V3_STBY")
			(options
				(clearance outline)
				(anchor circle)
			)
			(primitives
				(gr_poly
					(pts
						(xy -0.20828 -0.08636) (xy -0.20828 0.08636) (xy -0.08636 0.20828) (xy 0.086614 0.20828) (xy 0.20828 0.086614)
						(xy 0.20828 -0.08636) (xy 0.08636 -0.20828) (xy -0.08636 -0.20828)
					)
					(width 0)
					(fill yes)
				)
			)
		)
		(pad "2" smd custom
			(at 0 0.8001)
			(size 0.10414 0.10414)
			(layers "B.Cu" "B.Mask" "B.Paste")
			(net "GND")
			(options
				(clearance outline)
				(anchor circle)
			)
			(primitives
				(gr_poly
					(pts
						(xy -0.20828 -0.08636) (xy -0.20828 0.08636) (xy -0.08636 0.20828) (xy 0.086614 0.20828) (xy 0.20828 0.086614)
						(xy 0.20828 -0.08636) (xy 0.08636 -0.20828) (xy -0.08636 -0.20828)
					)
					(width 0)
					(fill yes)
				)
			)
		)
		(zone
			(layer "B.Cu")
			(hatch none 0.5)
			(connect_pads
				(clearance 0)
			)
			(min_thickness 0.25)
			(keepout
				(tracks not_allowed)
				(vias allowed)
				(pads allowed)
				(copperpour not_allowed)
				(footprints allowed)
			)
			(placement
				(enabled no)
				(sheetname "")
			)
			(fill
				(thermal_gap 0.5)
				(thermal_bridge_width 0.5)
				(island_removal_mode 0)
			)
			(polygon
				(pts
					(xy 370.95303 -73.182988) (xy 371.33403 -73.182988) (xy 371.33403 -73.007728) (xy 370.95303 -73.007474)
				)
			)
		)
		(zone
			(layer "B.Cu")
			(hatch none 0.5)
			(connect_pads
				(clearance 0)
			)
			(min_thickness 0.25)
			(keepout
				(tracks allowed)
				(vias not_allowed)
				(pads allowed)
				(copperpour not_allowed)
				(footprints allowed)
			)
			(placement
				(enabled no)
				(sheetname "")
			)
			(fill
				(thermal_gap 0.5)
				(thermal_bridge_width 0.5)
				(island_removal_mode 0)
			)
			(polygon
				(pts
					(xy 370.95303 -73.182988) (xy 371.33403 -73.182988) (xy 371.33403 -73.007728) (xy 370.95303 -73.007474)
				)
			)
		)
	)
	(footprint ""
		(layer "B.Cu")
		(at 88.214708 -125.99162 90)
		(property "Reference" "SH7L1"
			(at 0 0 90)
			(layer "B.SilkS")
			(hide yes)
			(effects
				(font
					(size 1.27 1.27)
				)
				(justify mirror)
			)
		)
		(property "Value" ""
			(at 0 0 90)
			(layer "B.Fab")
			(effects
				(font
					(size 1.27 1.27)
				)
				(justify mirror)
			)
		)
		(duplicate_pad_numbers_are_jumpers no)
		(fp_poly
			(pts
				(xy 0.1651 -0.0508) (xy 0.1651 0.5842) (xy -0.1651 0.5842) (xy -0.1651 -0.0508)
			)
			(stroke
				(width 0)
				(type default)
			)
			(fill no)
			(layer "B.CrtYd")
		)
		(fp_line
			(start 0.1651 -0.0508)
			(end -0.1651 -0.0508)
			(stroke
				(width 0.1)
				(type default)
			)
			(layer "B.Fab")
		)
		(fp_line
			(start -0.1651 -0.0508)
			(end -0.1651 0.5842)
			(stroke
				(width 0.1)
				(type default)
			)
			(layer "B.Fab")
		)
		(fp_line
			(start 0.1651 0.5842)
			(end 0.1651 -0.0508)
			(stroke
				(width 0.1)
				(type default)
			)
			(layer "B.Fab")
		)
		(fp_line
			(start -0.1651 0.5842)
			(end 0.1651 0.5842)
			(stroke
				(width 0.1)
				(type default)
			)
			(layer "B.Fab")
		)
		(pad "1" smd custom
			(at 0 0 90)
			(size 0.0762 0.0762)
			(layers "B.Cu" "B.Mask" "B.Paste")
			(net "VSENSE_PVDDQ_KLM_N")
			(options
				(clearance outline)
				(anchor circle)
			)
			(primitives
				(gr_poly
					(pts
						(arc
							(start -0.1524 0.10795)
							(mid -0.098518 0.130268)
							(end -0.0762 0.18415)
						)
						(xy -0.0762 0.22225) (xy 0.0762 0.22225)
						(arc
							(start 0.0762 0.18415)
							(mid 0.098518 0.130268)
							(end 0.1524 0.10795)
						)
						(xy 0.1524 -0.22225) (xy -0.1524 -0.22225)
					)
					(width 0)
					(fill yes)
				)
			)
		)
		(pad "2" smd custom
			(at 0 0.5334 270)
			(size 0.0762 0.0762)
			(layers "B.Cu" "B.Mask" "B.Paste")
			(net "GND")
			(options
				(clearance outline)
				(anchor circle)
			)
			(primitives
				(gr_poly
					(pts
						(arc
							(start -0.1524 0.10795)
							(mid -0.098518 0.130268)
							(end -0.0762 0.18415)
						)
						(xy -0.0762 0.22225) (xy 0.0762 0.22225)
						(arc
							(start 0.0762 0.18415)
							(mid 0.098518 0.130268)
							(end 0.1524 0.10795)
						)
						(xy 0.1524 -0.22225) (xy -0.1524 -0.22225)
					)
					(width 0)
					(fill yes)
				)
			)
		)
	)
	(footprint ""
		(layer "B.Cu")
		(at 26.0096 -30.988)
		(property "Reference" "R9T9"
			(at 0 0 0)
			(layer "B.SilkS")
			(hide yes)
			(effects
				(font
					(size 1.27 1.27)
				)
				(justify mirror)
			)
		)
		(property "Value" ""
			(at 0 0 0)
			(layer "B.Fab")
			(effects
				(font
					(size 1.27 1.27)
				)
				(justify mirror)
			)
		)
		(duplicate_pad_numbers_are_jumpers no)
		(fp_rect
			(start -0.2794 0.9906)
			(end 0.2794 -0.1016)
			(stroke
				(width 0)
				(type default)
			)
			(fill no)
			(layer "B.CrtYd")
		)
		(fp_line
			(start -0.2794 -0.1016)
			(end 0.2794 -0.1016)
			(stroke
				(width 0.1)
				(type default)
			)
			(layer "B.Fab")
		)
		(fp_line
			(start -0.2794 0.9906)
			(end -0.2794 -0.1016)
			(stroke
				(width 0.1)
				(type default)
			)
			(layer "B.Fab")
		)
		(fp_line
			(start 0.2794 -0.1016)
			(end 0.2794 0.9906)
			(stroke
				(width 0.1)
				(type default)
			)
			(layer "B.Fab")
		)
		(fp_line
			(start 0.2794 0.9906)
			(end -0.2794 0.9906)
			(stroke
				(width 0.1)
				(type default)
			)
			(layer "B.Fab")
		)
		(pad "1" smd rect
			(at 0 0 180)
			(size 0.508 0.508)
			(layers "B.Cu" "B.Mask" "B.Paste")
			(net "P12V_PSU")
		)
		(pad "2" smd rect
			(at 0 0.889 180)
			(size 0.508 0.508)
			(layers "B.Cu" "B.Mask" "B.Paste")
			(net "FM_MATED_IN_N")
		)
		(zone
			(layer "B.Cu")
			(hatch none 0.5)
			(connect_pads
				(clearance 0)
			)
			(min_thickness 0.25)
			(keepout
				(tracks not_allowed)
				(vias allowed)
				(pads allowed)
				(copperpour not_allowed)
				(footprints allowed)
			)
			(placement
				(enabled no)
				(sheetname "")
			)
			(fill
				(thermal_gap 0.5)
				(thermal_bridge_width 0.5)
				(island_removal_mode 0)
			)
			(polygon
				(pts
					(xy 25.7556 -30.353) (xy 26.2636 -30.353) (xy 26.2636 -30.734) (xy 25.7556 -30.734)
				)
			)
		)
		(zone
			(layer "B.Cu")
			(hatch none 0.5)
			(connect_pads
				(clearance 0)
			)
			(min_thickness 0.25)
			(keepout
				(tracks allowed)
				(vias not_allowed)
				(pads allowed)
				(copperpour not_allowed)
				(footprints allowed)
			)
			(placement
				(enabled no)
				(sheetname "")
			)
			(fill
				(thermal_gap 0.5)
				(thermal_bridge_width 0.5)
				(island_removal_mode 0)
			)
			(polygon
				(pts
					(xy 25.7556 -30.353) (xy 26.2636 -30.353) (xy 26.2636 -30.734) (xy 25.7556 -30.734)
				)
			)
		)
	)
	(footprint ""
		(layer "B.Cu")
		(at 24.1046 -84.5312 90)
		(property "Reference" "CR9P2"
			(at 0 0 90)
			(layer "B.SilkS")
			(hide yes)
			(effects
				(font
					(size 1.27 1.27)
				)
				(justify mirror)
			)
		)
		(property "Value" ""
			(at 0 0 90)
			(layer "B.Fab")
			(effects
				(font
					(size 1.27 1.27)
				)
				(justify mirror)
			)
		)
		(duplicate_pad_numbers_are_jumpers no)
		(fp_line
			(start -0.623062 -0.352806)
			(end -0.623062 0.770636)
			(stroke
				(width 0.1524)
				(type default)
			)
			(layer "B.SilkS")
		)
		(fp_line
			(start -0.623062 0.770636)
			(end -1.103884 1.603502)
			(stroke
				(width 0.1524)
				(type default)
			)
			(layer "B.SilkS")
		)
		(fp_line
			(start -1.103884 0.770636)
			(end -0.14224 0.770636)
			(stroke
				(width 0.1524)
				(type default)
			)
			(layer "B.SilkS")
		)
		(fp_line
			(start -0.14224 1.603502)
			(end -0.623062 0.770636)
			(stroke
				(width 0.1524)
				(type default)
			)
			(layer "B.SilkS")
		)
		(fp_line
			(start -0.623062 1.603502)
			(end -0.14224 1.603502)
			(stroke
				(width 0.1524)
				(type default)
			)
			(layer "B.SilkS")
		)
		(fp_line
			(start -1.103884 1.603502)
			(end -0.623062 1.603502)
			(stroke
				(width 0.1524)
				(type default)
			)
			(layer "B.SilkS")
		)
		(fp_line
			(start -0.623062 2.515108)
			(end -0.623062 1.603502)
			(stroke
				(width 0.1524)
				(type default)
			)
			(layer "B.SilkS")
		)
		(fp_poly
			(pts
				(xy 0.67437 0.24384) (xy 0.67437 2.04216) (xy -0.67437 2.04216) (xy -0.67437 0.24384)
			)
			(stroke
				(width 0)
				(type default)
			)
			(fill no)
			(layer "B.CrtYd")
		)
		(fp_line
			(start 0.67437 0.24384)
			(end 0.67437 2.04216)
			(stroke
				(width 0.1)
				(type default)
			)
			(layer "B.Fab")
		)
		(fp_line
			(start -0.67437 0.24384)
			(end 0.67437 0.24384)
			(stroke
				(width 0.1)
				(type default)
			)
			(layer "B.Fab")
		)
		(fp_line
			(start -0.623062 0.770636)
			(end -0.623062 -0.352806)
			(stroke
				(width 0.1)
				(type default)
			)
			(layer "B.Fab")
		)
		(fp_line
			(start -0.623062 0.770636)
			(end -1.103884 1.603502)
			(stroke
				(width 0.1)
				(type default)
			)
			(layer "B.Fab")
		)
		(fp_line
			(start -1.103884 0.770636)
			(end -0.14224 0.770636)
			(stroke
				(width 0.1)
				(type default)
			)
			(layer "B.Fab")
		)
		(fp_line
			(start -0.14224 1.603502)
			(end -0.623062 0.770636)
			(stroke
				(width 0.1)
				(type default)
			)
			(layer "B.Fab")
		)
		(fp_line
			(start -0.623062 1.603502)
			(end -0.623062 2.515108)
			(stroke
				(width 0.1)
				(type default)
			)
			(layer "B.Fab")
		)
		(fp_line
			(start -1.103884 1.603502)
			(end -0.14224 1.603502)
			(stroke
				(width 0.1)
				(type default)
			)
			(layer "B.Fab")
		)
		(fp_line
			(start 0.67437 2.04216)
			(end -0.67437 2.04216)
			(stroke
				(width 0.1)
				(type default)
			)
			(layer "B.Fab")
		)
		(fp_line
			(start -0.67437 2.04216)
			(end -0.67437 0.24384)
			(stroke
				(width 0.1)
				(type default)
			)
			(layer "B.Fab")
		)
		(pad "1" smd rect
			(at 0 0 270)
			(size 0.4064 1.016)
			(layers "B.Cu" "B.Mask" "B.Paste")
			(net "FM_UV_ADR_TRIGGER_N")
		)
		(pad "2" smd rect
			(at 0 2.286 270)
			(size 0.4064 1.016)
			(layers "B.Cu" "B.Mask" "B.Paste")
			(net "FM_DISABLE_FAN_N")
		)
	)
	(footprint ""
		(layer "B.Cu")
		(at 107.8611 -8.1534 90)
		(property "Reference" "C7U2"
			(at -1.848866 0.752348 90)
			(unlocked yes)
			(layer "B.SilkS")
			(effects
				(font
					(size 1.27 0.9652)
					(thickness 0.1524)
				)
				(justify mirror)
			)
		)
		(property "Value" ""
			(at 0 0 90)
			(layer "B.Fab")
			(effects
				(font
					(size 1.27 1.27)
				)
				(justify mirror)
			)
		)
		(duplicate_pad_numbers_are_jumpers no)
		(fp_rect
			(start 0.500126 1.598422)
			(end -0.500126 -0.201422)
			(stroke
				(width 0)
				(type default)
			)
			(fill no)
			(layer "B.CrtYd")
		)
		(fp_line
			(start 0.500126 -0.201422)
			(end -0.500126 -0.201422)
			(stroke
				(width 0.1)
				(type default)
			)
			(layer "B.Fab")
		)
		(fp_line
			(start -0.500126 -0.201422)
			(end -0.500126 1.598422)
			(stroke
				(width 0.1)
				(type default)
			)
			(layer "B.Fab")
		)
		(fp_line
			(start 0.500126 1.598422)
			(end 0.500126 -0.201422)
			(stroke
				(width 0.1)
				(type default)
			)
			(layer "B.Fab")
		)
		(fp_line
			(start -0.500126 1.598422)
			(end 0.500126 1.598422)
			(stroke
				(width 0.1)
				(type default)
			)
			(layer "B.Fab")
		)
		(pad "1" smd rect
			(at 0 0)
			(size 0.889 0.9906)
			(layers "B.Cu" "B.Mask" "B.Paste")
			(net "PVDDQ_GHJ")
		)
		(pad "2" smd rect
			(at 0 1.397)
			(size 0.889 0.9906)
			(layers "B.Cu" "B.Mask" "B.Paste")
			(net "GND")
		)
		(zone
			(layer "B.Cu")
			(hatch none 0.5)
			(connect_pads
				(clearance 0)
			)
			(min_thickness 0.25)
			(keepout
				(tracks allowed)
				(vias not_allowed)
				(pads allowed)
				(copperpour not_allowed)
				(footprints allowed)
			)
			(placement
				(enabled no)
				(sheetname "")
			)
			(fill
				(thermal_gap 0.5)
				(thermal_bridge_width 0.5)
				(island_removal_mode 0)
			)
			(polygon
				(pts
					(xy 108.8136 -8.6487) (xy 108.3056 -8.6487) (xy 108.3056 -7.6581) (xy 108.8136 -7.6581)
				)
			)
		)
		(zone
			(layer "B.Cu")
			(hatch none 0.5)
			(connect_pads
				(clearance 0)
			)
			(min_thickness 0.25)
			(keepout
				(tracks not_allowed)
				(vias allowed)
				(pads allowed)
				(copperpour not_allowed)
				(footprints allowed)
			)
			(placement
				(enabled no)
				(sheetname "")
			)
			(fill
				(thermal_gap 0.5)
				(thermal_bridge_width 0.5)
				(island_removal_mode 0)
			)
			(polygon
				(pts
					(xy 108.8136 -8.6487) (xy 108.3056 -8.6487) (xy 108.3056 -7.6581) (xy 108.8136 -7.6581)
				)
			)
		)
	)
	(footprint ""
		(layer "B.Cu")
		(at 376.174 -88.0745)
		(property "Reference" "R7C21"
			(at 0.8382 -0.67818 0)
			(unlocked yes)
			(layer "B.SilkS")
			(effects
				(font
					(size 0.4064 0.254)
					(thickness 0.1524)
				)
				(justify left mirror)
			)
		)
		(property "Value" ""
			(at 0 0 0)
			(layer "B.Fab")
			(effects
				(font
					(size 1.27 1.27)
				)
				(justify mirror)
			)
		)
		(duplicate_pad_numbers_are_jumpers no)
		(fp_poly
			(pts
				(xy 0.2794 -0.1016) (xy -0.2794 -0.1016) (xy -0.2794 0.9906) (xy 0.2794 0.9906)
			)
			(stroke
				(width 0)
				(type default)
			)
			(fill no)
			(layer "B.CrtYd")
		)
		(fp_line
			(start -0.2794 -0.1016)
			(end 0.2794 -0.1016)
			(stroke
				(width 0.1)
				(type default)
			)
			(layer "B.Fab")
		)
		(fp_line
			(start -0.2794 0.9906)
			(end -0.2794 -0.1016)
			(stroke
				(width 0.1)
				(type default)
			)
			(layer "B.Fab")
		)
		(fp_line
			(start 0.2794 -0.1016)
			(end 0.2794 0.9906)
			(stroke
				(width 0.1)
				(type default)
			)
			(layer "B.Fab")
		)
		(fp_line
			(start 0.2794 0.9906)
			(end -0.2794 0.9906)
			(stroke
				(width 0.1)
				(type default)
			)
			(layer "B.Fab")
		)
		(pad "1" smd rect
			(at 0 0 180)
			(size 0.508 0.508)
			(layers "B.Cu" "B.Mask" "B.Paste")
			(net "P1V05_PCH_STBY")
		)
		(pad "2" smd rect
			(at 0 0.889 180)
			(size 0.508 0.508)
			(layers "B.Cu" "B.Mask" "B.Paste")
			(net "FM_PCH_LVC1_THERMTRIP_N")
		)
		(zone
			(layer "B.Cu")
			(hatch none 0.5)
			(connect_pads
				(clearance 0)
			)
			(min_thickness 0.25)
			(keepout
				(tracks allowed)
				(vias not_allowed)
				(pads allowed)
				(copperpour not_allowed)
				(footprints allowed)
			)
			(placement
				(enabled no)
				(sheetname "")
			)
			(fill
				(thermal_gap 0.5)
				(thermal_bridge_width 0.5)
				(island_removal_mode 0)
			)
			(polygon
				(pts
					(xy 376.428 -87.8205) (xy 375.92 -87.8205) (xy 375.92 -87.4395) (xy 376.428 -87.4395)
				)
			)
		)
		(zone
			(layer "B.Cu")
			(hatch none 0.5)
			(connect_pads
				(clearance 0)
			)
			(min_thickness 0.25)
			(keepout
				(tracks not_allowed)
				(vias allowed)
				(pads allowed)
				(copperpour not_allowed)
				(footprints allowed)
			)
			(placement
				(enabled no)
				(sheetname "")
			)
			(fill
				(thermal_gap 0.5)
				(thermal_bridge_width 0.5)
				(island_removal_mode 0)
			)
			(polygon
				(pts
					(xy 376.428 -87.4395) (xy 375.92 -87.4395) (xy 375.92 -87.8205) (xy 376.428 -87.8205)
				)
			)
		)
	)
	(footprint ""
		(layer "B.Cu")
		(at 316.2808 -120.3198 90)
		(property "Reference" "R3R12"
			(at 0 0 90)
			(layer "B.SilkS")
			(hide yes)
			(effects
				(font
					(size 1.27 1.27)
				)
				(justify mirror)
			)
		)
		(property "Value" ""
			(at 0 0 90)
			(layer "B.Fab")
			(effects
				(font
					(size 1.27 1.27)
				)
				(justify mirror)
			)
		)
		(duplicate_pad_numbers_are_jumpers no)
		(fp_poly
			(pts
				(xy 0.2794 -0.1016) (xy -0.2794 -0.1016) (xy -0.2794 0.9906) (xy 0.2794 0.9906)
			)
			(stroke
				(width 0)
				(type default)
			)
			(fill no)
			(layer "B.CrtYd")
		)
		(fp_line
			(start 0.2794 -0.1016)
			(end 0.2794 0.9906)
			(stroke
				(width 0.1)
				(type default)
			)
			(layer "B.Fab")
		)
		(fp_line
			(start -0.2794 -0.1016)
			(end 0.2794 -0.1016)
			(stroke
				(width 0.1)
				(type default)
			)
			(layer "B.Fab")
		)
		(fp_line
			(start 0.2794 0.9906)
			(end -0.2794 0.9906)
			(stroke
				(width 0.1)
				(type default)
			)
			(layer "B.Fab")
		)
		(fp_line
			(start -0.2794 0.9906)
			(end -0.2794 -0.1016)
			(stroke
				(width 0.1)
				(type default)
			)
			(layer "B.Fab")
		)
		(pad "1" smd rect
			(at 0 0 270)
			(size 0.508 0.508)
			(layers "B.Cu" "B.Mask" "B.Paste")
			(net "PVPP_DEF")
		)
		(pad "2" smd rect
			(at 0 0.889 270)
			(size 0.508 0.508)
			(layers "B.Cu" "B.Mask" "B.Paste")
			(net "SMB_DDR_DEF_VPP_SDA_R")
		)
		(zone
			(layer "B.Cu")
			(hatch none 0.5)
			(connect_pads
				(clearance 0)
			)
			(min_thickness 0.25)
			(keepout
				(tracks allowed)
				(vias not_allowed)
				(pads allowed)
				(copperpour not_allowed)
				(footprints allowed)
			)
			(placement
				(enabled no)
				(sheetname "")
			)
			(fill
				(thermal_gap 0.5)
				(thermal_bridge_width 0.5)
				(island_removal_mode 0)
			)
			(polygon
				(pts
					(xy 316.5348 -120.5738) (xy 316.5348 -120.0658) (xy 316.9158 -120.0658) (xy 316.9158 -120.5738)
				)
			)
		)
		(zone
			(layer "B.Cu")
			(hatch none 0.5)
			(connect_pads
				(clearance 0)
			)
			(min_thickness 0.25)
			(keepout
				(tracks not_allowed)
				(vias allowed)
				(pads allowed)
				(copperpour not_allowed)
				(footprints allowed)
			)
			(placement
				(enabled no)
				(sheetname "")
			)
			(fill
				(thermal_gap 0.5)
				(thermal_bridge_width 0.5)
				(island_removal_mode 0)
			)
			(polygon
				(pts
					(xy 316.9158 -120.5738) (xy 316.9158 -120.0658) (xy 316.5348 -120.0658) (xy 316.5348 -120.5738)
				)
			)
		)
	)
	(footprint ""
		(layer "B.Cu")
		(at 351.86112 -90.639392 -90)
		(property "Reference" "R3N23"
			(at 0 0 90)
			(layer "B.SilkS")
			(hide yes)
			(effects
				(font
					(size 1.27 1.27)
				)
				(justify mirror)
			)
		)
		(property "Value" ""
			(at 0 0 90)
			(layer "B.Fab")
			(effects
				(font
					(size 1.27 1.27)
				)
				(justify mirror)
			)
		)
		(duplicate_pad_numbers_are_jumpers no)
		(fp_poly
			(pts
				(xy 0.2794 -0.1016) (xy -0.2794 -0.1016) (xy -0.2794 0.9906) (xy 0.2794 0.9906)
			)
			(stroke
				(width 0)
				(type default)
			)
			(fill no)
			(layer "B.CrtYd")
		)
		(fp_line
			(start -0.2794 0.9906)
			(end -0.2794 -0.1016)
			(stroke
				(width 0.1)
				(type default)
			)
			(layer "B.Fab")
		)
		(fp_line
			(start 0.2794 0.9906)
			(end -0.2794 0.9906)
			(stroke
				(width 0.1)
				(type default)
			)
			(layer "B.Fab")
		)
		(fp_line
			(start -0.2794 -0.1016)
			(end 0.2794 -0.1016)
			(stroke
				(width 0.1)
				(type default)
			)
			(layer "B.Fab")
		)
		(fp_line
			(start 0.2794 -0.1016)
			(end 0.2794 0.9906)
			(stroke
				(width 0.1)
				(type default)
			)
			(layer "B.Fab")
		)
		(pad "1" smd rect
			(at 0 0 90)
			(size 0.508 0.508)
			(layers "B.Cu" "B.Mask" "B.Paste")
			(net "P3V3_STBY")
		)
		(pad "2" smd rect
			(at 0 0.889 90)
			(size 0.508 0.508)
			(layers "B.Cu" "B.Mask" "B.Paste")
			(net "PU_VR_PVCCIO_CPU0_FAULT1")
		)
		(zone
			(layer "B.Cu")
			(hatch none 0.5)
			(connect_pads
				(clearance 0)
			)
			(min_thickness 0.25)
			(keepout
				(tracks not_allowed)
				(vias allowed)
				(pads allowed)
				(copperpour not_allowed)
				(footprints allowed)
			)
			(placement
				(enabled no)
				(sheetname "")
			)
			(fill
				(thermal_gap 0.5)
				(thermal_bridge_width 0.5)
				(island_removal_mode 0)
			)
			(polygon
				(pts
					(xy 351.22612 -90.385392) (xy 351.22612 -90.893392) (xy 351.60712 -90.893392) (xy 351.60712 -90.385392)
				)
			)
		)
		(zone
			(layer "B.Cu")
			(hatch none 0.5)
			(connect_pads
				(clearance 0)
			)
			(min_thickness 0.25)
			(keepout
				(tracks allowed)
				(vias not_allowed)
				(pads allowed)
				(copperpour not_allowed)
				(footprints allowed)
			)
			(placement
				(enabled no)
				(sheetname "")
			)
			(fill
				(thermal_gap 0.5)
				(thermal_bridge_width 0.5)
				(island_removal_mode 0)
			)
			(polygon
				(pts
					(xy 351.60712 -90.385392) (xy 351.60712 -90.893392) (xy 351.22612 -90.893392) (xy 351.22612 -90.385392)
				)
			)
		)
	)
	(footprint ""
		(layer "B.Cu")
		(at 368.716814 -124.389642 -90)
		(property "Reference" "C3M36"
			(at 0 0 90)
			(layer "B.SilkS")
			(hide yes)
			(effects
				(font
					(size 1.27 1.27)
				)
				(justify mirror)
			)
		)
		(property "Value" ""
			(at 0 0 90)
			(layer "B.Fab")
			(effects
				(font
					(size 1.27 1.27)
				)
				(justify mirror)
			)
		)
		(duplicate_pad_numbers_are_jumpers no)
		(fp_poly
			(pts
				(xy -0.3048 -0.1016) (xy -0.3048 0.9906) (xy 0.3048 0.9906) (xy 0.3048 -0.1016)
			)
			(stroke
				(width 0)
				(type default)
			)
			(fill no)
			(layer "B.CrtYd")
		)
		(fp_line
			(start -0.3048 0.9906)
			(end -0.3048 -0.1016)
			(stroke
				(width 0.1)
				(type default)
			)
			(layer "B.Fab")
		)
		(fp_line
			(start 0.3048 0.9906)
			(end -0.3048 0.9906)
			(stroke
				(width 0.1)
				(type default)
			)
			(layer "B.Fab")
		)
		(fp_line
			(start -0.3048 -0.1016)
			(end 0.3048 -0.1016)
			(stroke
				(width 0.1)
				(type default)
			)
			(layer "B.Fab")
		)
		(fp_line
			(start 0.3048 -0.1016)
			(end 0.3048 0.9906)
			(stroke
				(width 0.1)
				(type default)
			)
			(layer "B.Fab")
		)
		(pad "1" smd rect
			(at 0 0 90)
			(size 0.508 0.508)
			(layers "B.Cu" "B.Mask" "B.Paste")
			(net "P3E_CPU0_PE1_PCH_R_RXP<9>")
		)
		(pad "2" smd rect
			(at 0 0.889 90)
			(size 0.508 0.508)
			(layers "B.Cu" "B.Mask" "B.Paste")
			(net "P3E_CPU0_PE1_PCH_RXP<9>")
		)
		(zone
			(layer "B.Cu")
			(hatch none 0.5)
			(connect_pads
				(clearance 0)
			)
			(min_thickness 0.25)
			(keepout
				(tracks not_allowed)
				(vias allowed)
				(pads allowed)
				(copperpour not_allowed)
				(footprints allowed)
			)
			(placement
				(enabled no)
				(sheetname "")
			)
			(fill
				(thermal_gap 0.5)
				(thermal_bridge_width 0.5)
				(island_removal_mode 0)
			)
			(polygon
				(pts
					(xy 368.081814 -124.135642) (xy 368.081814 -124.643642) (xy 368.462814 -124.643642) (xy 368.462814 -124.135642)
				)
			)
		)
		(zone
			(layer "B.Cu")
			(hatch none 0.5)
			(connect_pads
				(clearance 0)
			)
			(min_thickness 0.25)
			(keepout
				(tracks allowed)
				(vias not_allowed)
				(pads allowed)
				(copperpour not_allowed)
				(footprints allowed)
			)
			(placement
				(enabled no)
				(sheetname "")
			)
			(fill
				(thermal_gap 0.5)
				(thermal_bridge_width 0.5)
				(island_removal_mode 0)
			)
			(polygon
				(pts
					(xy 368.462814 -124.135642) (xy 368.462814 -124.643642) (xy 368.081814 -124.643642) (xy 368.081814 -124.135642)
				)
			)
		)
	)
	(footprint ""
		(layer "B.Cu")
		(at 321.2338 -124.115322 180)
		(property "Reference" "C7E2"
			(at 0 0 0)
			(layer "B.SilkS")
			(hide yes)
			(effects
				(font
					(size 1.27 1.27)
				)
				(justify mirror)
			)
		)
		(property "Value" ""
			(at 0 0 0)
			(layer "B.Fab")
			(effects
				(font
					(size 1.27 1.27)
				)
				(justify mirror)
			)
		)
		(duplicate_pad_numbers_are_jumpers no)
		(fp_poly
			(pts
				(xy -0.3048 -0.1016) (xy -0.3048 0.9906) (xy 0.3048 0.9906) (xy 0.3048 -0.1016)
			)
			(stroke
				(width 0)
				(type default)
			)
			(fill no)
			(layer "B.CrtYd")
		)
		(fp_line
			(start 0.3048 0.9906)
			(end -0.3048 0.9906)
			(stroke
				(width 0.1)
				(type default)
			)
			(layer "B.Fab")
		)
		(fp_line
			(start 0.3048 -0.1016)
			(end 0.3048 0.9906)
			(stroke
				(width 0.1)
				(type default)
			)
			(layer "B.Fab")
		)
		(fp_line
			(start -0.3048 0.9906)
			(end -0.3048 -0.1016)
			(stroke
				(width 0.1)
				(type default)
			)
			(layer "B.Fab")
		)
		(fp_line
			(start -0.3048 -0.1016)
			(end 0.3048 -0.1016)
			(stroke
				(width 0.1)
				(type default)
			)
			(layer "B.Fab")
		)
		(pad "1" smd rect
			(at 0 0)
			(size 0.508 0.508)
			(layers "B.Cu" "B.Mask" "B.Paste")
			(net "PVPP_DEF")
		)
		(pad "2" smd rect
			(at 0 0.889)
			(size 0.508 0.508)
			(layers "B.Cu" "B.Mask" "B.Paste")
			(net "GND")
		)
		(zone
			(layer "B.Cu")
			(hatch none 0.5)
			(connect_pads
				(clearance 0)
			)
			(min_thickness 0.25)
			(keepout
				(tracks not_allowed)
				(vias allowed)
				(pads allowed)
				(copperpour not_allowed)
				(footprints allowed)
			)
			(placement
				(enabled no)
				(sheetname "")
			)
			(fill
				(thermal_gap 0.5)
				(thermal_bridge_width 0.5)
				(island_removal_mode 0)
			)
			(polygon
				(pts
					(xy 320.9798 -124.750322) (xy 321.4878 -124.750322) (xy 321.4878 -124.369322) (xy 320.9798 -124.369322)
				)
			)
		)
		(zone
			(layer "B.Cu")
			(hatch none 0.5)
			(connect_pads
				(clearance 0)
			)
			(min_thickness 0.25)
			(keepout
				(tracks allowed)
				(vias not_allowed)
				(pads allowed)
				(copperpour not_allowed)
				(footprints allowed)
			)
			(placement
				(enabled no)
				(sheetname "")
			)
			(fill
				(thermal_gap 0.5)
				(thermal_bridge_width 0.5)
				(island_removal_mode 0)
			)
			(polygon
				(pts
					(xy 320.9798 -124.369322) (xy 321.4878 -124.369322) (xy 321.4878 -124.750322) (xy 320.9798 -124.750322)
				)
			)
		)
	)
	(footprint ""
		(layer "B.Cu")
		(at 409.884118 -90.193114 180)
		(property "Reference" "Q7E1"
			(at -0.11938 -0.97663 180)
			(unlocked yes)
			(layer "B.SilkS")
			(effects
				(font
					(size 0.7874 0.5842)
					(thickness 0.1524)
				)
				(justify left mirror)
			)
		)
		(property "Value" ""
			(at 0 0 0)
			(layer "B.Fab")
			(effects
				(font
					(size 1.27 1.27)
				)
				(justify mirror)
			)
		)
		(duplicate_pad_numbers_are_jumpers no)
		(fp_circle
			(center 0.508 -0.7874)
			(end 0.381 -0.7874)
			(stroke
				(width 0.254)
				(type default)
			)
			(fill no)
			(layer "B.SilkS")
		)
		(fp_poly
			(pts
				(xy -0.2159 1.7526) (xy -1.5621 1.7526) (xy -1.5621 -0.4572) (xy -0.2159 -0.4572)
			)
			(stroke
				(width 0)
				(type default)
			)
			(fill no)
			(layer "B.CrtYd")
		)
		(fp_line
			(start -0.2159 1.75514)
			(end -1.5621 1.75514)
			(stroke
				(width 0.1)
				(type default)
			)
			(layer "B.Fab")
		)
		(fp_line
			(start -0.2159 -0.45466)
			(end -0.2159 1.75514)
			(stroke
				(width 0.1)
				(type default)
			)
			(layer "B.Fab")
		)
		(fp_line
			(start -1.5621 1.75514)
			(end -1.5621 -0.45466)
			(stroke
				(width 0.1)
				(type default)
			)
			(layer "B.Fab")
		)
		(fp_line
			(start -1.5621 -0.45466)
			(end -0.2159 -0.45466)
			(stroke
				(width 0.1)
				(type default)
			)
			(layer "B.Fab")
		)
		(fp_circle
			(center 0.508 -0.7874)
			(end 0.381 -0.7874)
			(stroke
				(width 0.254)
				(type default)
			)
			(fill no)
			(layer "B.Fab")
		)
		(pad "1" smd rect
			(at 0 0)
			(size 1.016 0.381)
			(layers "B.Cu" "B.Mask" "B.Paste")
			(net "GND")
		)
		(pad "2" smd rect
			(at 0 0.65024)
			(size 1.016 0.381)
			(layers "B.Cu" "B.Mask" "B.Paste")
			(net "IRQ_PVDDQ_DEF_VRHOT_LVT3_N")
		)
		(pad "3" smd rect
			(at 0 1.30048)
			(size 1.016 0.381)
			(layers "B.Cu" "B.Mask" "B.Paste")
			(net "H_CPU0_MEMDEF_MEMHOT_G_N")
		)
		(pad "4" smd rect
			(at -1.778 1.30048)
			(size 1.016 0.381)
			(layers "B.Cu" "B.Mask" "B.Paste")
			(net "GND")
		)
		(pad "5" smd rect
			(at -1.778 0.65024)
			(size 1.016 0.381)
			(layers "B.Cu" "B.Mask" "B.Paste")
			(net "H_CPU0_MEMDEF_MEMHOT")
		)
		(pad "6" smd rect
			(at -1.778 0)
			(size 1.016 0.381)
			(layers "B.Cu" "B.Mask" "B.Paste")
			(net "H_CPU0_MEMDEF_MEMHOT")
		)
		(zone
			(layer "B.Cu")
			(hatch none 0.5)
			(connect_pads
				(clearance 0)
			)
			(min_thickness 0.25)
			(keepout
				(tracks allowed)
				(vias not_allowed)
				(pads allowed)
				(copperpour not_allowed)
				(footprints allowed)
			)
			(placement
				(enabled no)
				(sheetname "")
			)
			(fill
				(thermal_gap 0.5)
				(thermal_bridge_width 0.5)
				(island_removal_mode 0)
			)
			(polygon
				(pts
					(xy 409.376118 -90.002614) (xy 410.392118 -90.002614) (xy 410.392118 -91.691714) (xy 409.376118 -91.691714)
				)
			)
		)
		(zone
			(layer "B.Cu")
			(hatch none 0.5)
			(connect_pads
				(clearance 0)
			)
			(min_thickness 0.25)
			(keepout
				(tracks allowed)
				(vias not_allowed)
				(pads allowed)
				(copperpour not_allowed)
				(footprints allowed)
			)
			(placement
				(enabled no)
				(sheetname "")
			)
			(fill
				(thermal_gap 0.5)
				(thermal_bridge_width 0.5)
				(island_removal_mode 0)
			)
			(polygon
				(pts
					(xy 411.154118 -90.002614) (xy 412.170118 -90.002614) (xy 412.170118 -91.691714) (xy 411.154118 -91.691714)
				)
			)
		)
	)
	(footprint ""
		(layer "B.Cu")
		(at 195.2752 -64.008 90)
		(property "Reference" "CT4"
			(at 0.8382 -0.84963 90)
			(unlocked yes)
			(layer "B.SilkS")
			(effects
				(font
					(size 0.7874 0.5842)
					(thickness 0.1524)
				)
				(justify left mirror)
			)
		)
		(property "Value" ""
			(at 0 0 90)
			(layer "B.Fab")
			(effects
				(font
					(size 1.27 1.27)
				)
				(justify mirror)
			)
		)
		(duplicate_pad_numbers_are_jumpers no)
		(fp_poly
			(pts
				(xy -0.3048 -0.1016) (xy -0.3048 0.9906) (xy 0.3048 0.9906) (xy 0.3048 -0.1016)
			)
			(stroke
				(width 0)
				(type default)
			)
			(fill no)
			(layer "B.CrtYd")
		)
		(fp_line
			(start 0.3048 -0.1016)
			(end 0.3048 0.9906)
			(stroke
				(width 0.1)
				(type default)
			)
			(layer "B.Fab")
		)
		(fp_line
			(start -0.3048 -0.1016)
			(end 0.3048 -0.1016)
			(stroke
				(width 0.1)
				(type default)
			)
			(layer "B.Fab")
		)
		(fp_line
			(start 0.3048 0.9906)
			(end -0.3048 0.9906)
			(stroke
				(width 0.1)
				(type default)
			)
			(layer "B.Fab")
		)
		(fp_line
			(start -0.3048 0.9906)
			(end -0.3048 -0.1016)
			(stroke
				(width 0.1)
				(type default)
			)
			(layer "B.Fab")
		)
		(pad "1" smd rect
			(at 0 0 270)
			(size 0.508 0.508)
			(layers "B.Cu" "B.Mask" "B.Paste")
			(net "A_TSENSE_PVCCIN_CPU0")
		)
		(pad "2" smd rect
			(at 0 0.889 270)
			(size 0.508 0.508)
			(layers "B.Cu" "B.Mask" "B.Paste")
			(net "GND")
		)
		(zone
			(layer "B.Cu")
			(hatch none 0.5)
			(connect_pads
				(clearance 0)
			)
			(min_thickness 0.25)
			(keepout
				(tracks allowed)
				(vias not_allowed)
				(pads allowed)
				(copperpour not_allowed)
				(footprints allowed)
			)
			(placement
				(enabled no)
				(sheetname "")
			)
			(fill
				(thermal_gap 0.5)
				(thermal_bridge_width 0.5)
				(island_removal_mode 0)
			)
			(polygon
				(pts
					(xy 195.5292 -64.262) (xy 195.5292 -63.754) (xy 195.9102 -63.754) (xy 195.9102 -64.262)
				)
			)
		)
		(zone
			(layer "B.Cu")
			(hatch none 0.5)
			(connect_pads
				(clearance 0)
			)
			(min_thickness 0.25)
			(keepout
				(tracks not_allowed)
				(vias allowed)
				(pads allowed)
				(copperpour not_allowed)
				(footprints allowed)
			)
			(placement
				(enabled no)
				(sheetname "")
			)
			(fill
				(thermal_gap 0.5)
				(thermal_bridge_width 0.5)
				(island_removal_mode 0)
			)
			(polygon
				(pts
					(xy 195.9102 -64.262) (xy 195.9102 -63.754) (xy 195.5292 -63.754) (xy 195.5292 -64.262)
				)
			)
		)
	)
	(footprint ""
		(layer "B.Cu")
		(at 385.774692 -44.215812)
		(property "Reference" "Q7E4"
			(at -0.22733 -3.73888 90)
			(unlocked yes)
			(layer "B.SilkS")
			(effects
				(font
					(size 0.7874 0.5842)
					(thickness 0.1524)
				)
				(justify left mirror)
			)
		)
		(property "Value" ""
			(at 0 0 0)
			(layer "B.Fab")
			(effects
				(font
					(size 1.27 1.27)
				)
				(justify mirror)
			)
		)
		(duplicate_pad_numbers_are_jumpers no)
		(fp_line
			(start -1.778 -0.5715)
			(end -1.778 0.3175)
			(stroke
				(width 0.1524)
				(type default)
			)
			(layer "B.SilkS")
		)
		(fp_line
			(start -1.778 2.4765)
			(end -1.778 1.5875)
			(stroke
				(width 0.1524)
				(type default)
			)
			(layer "B.SilkS")
		)
		(fp_line
			(start -0.9525 -0.5715)
			(end -1.778 -0.5715)
			(stroke
				(width 0.1524)
				(type default)
			)
			(layer "B.SilkS")
		)
		(fp_line
			(start -0.9525 2.4765)
			(end -1.778 2.4765)
			(stroke
				(width 0.1524)
				(type default)
			)
			(layer "B.SilkS")
		)
		(fp_line
			(start -0.381 0.635)
			(end -0.381 1.27)
			(stroke
				(width 0.1524)
				(type default)
			)
			(layer "B.SilkS")
		)
		(fp_circle
			(center 0.9525 -0.9271)
			(end 1.0795 -0.9271)
			(stroke
				(width 0.254)
				(type default)
			)
			(fill no)
			(layer "B.SilkS")
		)
		(fp_poly
			(pts
				(xy -1.778 2.4765) (xy -0.381 2.4765) (xy -0.381 -0.5715) (xy -1.778 -0.5715)
			)
			(stroke
				(width 0)
				(type default)
			)
			(fill no)
			(layer "B.CrtYd")
		)
		(fp_line
			(start -1.778 -0.5715)
			(end -0.381 -0.5715)
			(stroke
				(width 0.1)
				(type default)
			)
			(layer "B.Fab")
		)
		(fp_line
			(start -1.778 2.4765)
			(end -1.778 -0.5715)
			(stroke
				(width 0.1)
				(type default)
			)
			(layer "B.Fab")
		)
		(fp_line
			(start -0.381 -0.5715)
			(end -0.381 2.4765)
			(stroke
				(width 0.1)
				(type default)
			)
			(layer "B.Fab")
		)
		(fp_line
			(start -0.381 2.4765)
			(end -1.778 2.4765)
			(stroke
				(width 0.1)
				(type default)
			)
			(layer "B.Fab")
		)
		(fp_circle
			(center 0.9525 -0.9271)
			(end 1.0795 -0.9271)
			(stroke
				(width 0.254)
				(type default)
			)
			(fill no)
			(layer "B.Fab")
		)
		(pad "1" smd rect
			(at 0 0 180)
			(size 1.143 0.508)
			(layers "B.Cu" "B.Mask" "B.Paste")
			(net "FM_THROTTLE_R_N")
		)
		(pad "2" smd rect
			(at 0 1.905 180)
			(size 1.143 0.508)
			(layers "B.Cu" "B.Mask" "B.Paste")
			(net "GND")
		)
		(pad "3" smd rect
			(at -2.159 0.9525 180)
			(size 1.143 0.508)
			(layers "B.Cu" "B.Mask" "B.Paste")
			(net "FM_SYS_THROTTLE_LVC3")
		)
	)
	(footprint ""
		(layer "B.Cu")
		(at 342.9 -83.566)
		(property "Reference" "C3P6"
			(at 0 0 0)
			(layer "B.SilkS")
			(hide yes)
			(effects
				(font
					(size 1.27 1.27)
				)
				(justify mirror)
			)
		)
		(property "Value" ""
			(at 0 0 0)
			(layer "B.Fab")
			(effects
				(font
					(size 1.27 1.27)
				)
				(justify mirror)
			)
		)
		(duplicate_pad_numbers_are_jumpers no)
		(fp_poly
			(pts
				(xy -0.3048 -0.1016) (xy -0.3048 0.9906) (xy 0.3048 0.9906) (xy 0.3048 -0.1016)
			)
			(stroke
				(width 0)
				(type default)
			)
			(fill no)
			(layer "B.CrtYd")
		)
		(fp_line
			(start -0.3048 -0.1016)
			(end 0.3048 -0.1016)
			(stroke
				(width 0.1)
				(type default)
			)
			(layer "B.Fab")
		)
		(fp_line
			(start -0.3048 0.9906)
			(end -0.3048 -0.1016)
			(stroke
				(width 0.1)
				(type default)
			)
			(layer "B.Fab")
		)
		(fp_line
			(start 0.3048 -0.1016)
			(end 0.3048 0.9906)
			(stroke
				(width 0.1)
				(type default)
			)
			(layer "B.Fab")
		)
		(fp_line
			(start 0.3048 0.9906)
			(end -0.3048 0.9906)
			(stroke
				(width 0.1)
				(type default)
			)
			(layer "B.Fab")
		)
		(pad "1" smd rect
			(at 0 0 180)
			(size 0.508 0.508)
			(layers "B.Cu" "B.Mask" "B.Paste")
			(net "PWRGD_PVCCIO_CPU0_R")
		)
		(pad "2" smd rect
			(at 0 0.889 180)
			(size 0.508 0.508)
			(layers "B.Cu" "B.Mask" "B.Paste")
			(net "GND")
		)
		(zone
			(layer "B.Cu")
			(hatch none 0.5)
			(connect_pads
				(clearance 0)
			)
			(min_thickness 0.25)
			(keepout
				(tracks allowed)
				(vias not_allowed)
				(pads allowed)
				(copperpour not_allowed)
				(footprints allowed)
			)
			(placement
				(enabled no)
				(sheetname "")
			)
			(fill
				(thermal_gap 0.5)
				(thermal_bridge_width 0.5)
				(island_removal_mode 0)
			)
			(polygon
				(pts
					(xy 343.154 -83.312) (xy 342.646 -83.312) (xy 342.646 -82.931) (xy 343.154 -82.931)
				)
			)
		)
		(zone
			(layer "B.Cu")
			(hatch none 0.5)
			(connect_pads
				(clearance 0)
			)
			(min_thickness 0.25)
			(keepout
				(tracks not_allowed)
				(vias allowed)
				(pads allowed)
				(copperpour not_allowed)
				(footprints allowed)
			)
			(placement
				(enabled no)
				(sheetname "")
			)
			(fill
				(thermal_gap 0.5)
				(thermal_bridge_width 0.5)
				(island_removal_mode 0)
			)
			(polygon
				(pts
					(xy 343.154 -82.931) (xy 342.646 -82.931) (xy 342.646 -83.312) (xy 343.154 -83.312)
				)
			)
		)
	)
	(footprint ""
		(layer "B.Cu")
		(at 210.847432 -89.6112 -90)
		(property "Reference" "C6N9"
			(at -1.54813 -3.655568 0)
			(unlocked yes)
			(layer "B.SilkS")
			(effects
				(font
					(size 0.7874 0.5842)
					(thickness 0.1524)
				)
				(justify mirror)
			)
		)
		(property "Value" ""
			(at 0 0 90)
			(layer "B.Fab")
			(effects
				(font
					(size 1.27 1.27)
				)
				(justify mirror)
			)
		)
		(duplicate_pad_numbers_are_jumpers no)
		(fp_line
			(start -2.286 7.366)
			(end -1.600708 7.366)
			(stroke
				(width 0.1524)
				(type default)
			)
			(layer "B.SilkS")
		)
		(fp_line
			(start -2.286 7.366)
			(end -2.286 1.63195)
			(stroke
				(width 0.1524)
				(type default)
			)
			(layer "B.SilkS")
		)
		(fp_line
			(start 2.286 7.366)
			(end 1.60147 7.366)
			(stroke
				(width 0.1524)
				(type default)
			)
			(layer "B.SilkS")
		)
		(fp_line
			(start 2.286 7.366)
			(end 2.286 1.632712)
			(stroke
				(width 0.1524)
				(type default)
			)
			(layer "B.SilkS")
		)
		(fp_line
			(start -2.504948 1.633728)
			(end -1.6002 1.633728)
			(stroke
				(width 0.1524)
				(type default)
			)
			(layer "B.SilkS")
		)
		(fp_line
			(start 2.563114 1.633728)
			(end 1.6002 1.633728)
			(stroke
				(width 0.1524)
				(type default)
			)
			(layer "B.SilkS")
		)
		(fp_line
			(start -2.504948 -1.616456)
			(end -2.504948 1.633728)
			(stroke
				(width 0.1524)
				(type default)
			)
			(layer "B.SilkS")
		)
		(fp_line
			(start -1.6002 -1.616456)
			(end -2.504948 -1.616456)
			(stroke
				(width 0.1524)
				(type default)
			)
			(layer "B.SilkS")
		)
		(fp_line
			(start 1.6002 -1.616456)
			(end 2.563114 -1.616456)
			(stroke
				(width 0.1524)
				(type default)
			)
			(layer "B.SilkS")
		)
		(fp_line
			(start 2.563114 -1.616456)
			(end 2.563114 1.633728)
			(stroke
				(width 0.1524)
				(type default)
			)
			(layer "B.SilkS")
		)
		(fp_rect
			(start 2.286 7.366)
			(end -2.286 -0.254)
			(stroke
				(width 0)
				(type default)
			)
			(fill no)
			(layer "B.CrtYd")
		)
		(fp_line
			(start -2.286 7.366)
			(end 2.286 7.366)
			(stroke
				(width 0.1)
				(type default)
			)
			(layer "B.Fab")
		)
		(fp_line
			(start 2.286 7.366)
			(end 2.286 -0.254)
			(stroke
				(width 0.1)
				(type default)
			)
			(layer "B.Fab")
		)
		(fp_line
			(start -2.286 -0.254)
			(end -2.286 7.366)
			(stroke
				(width 0.1)
				(type default)
			)
			(layer "B.Fab")
		)
		(fp_line
			(start 2.286 -0.254)
			(end -2.286 -0.254)
			(stroke
				(width 0.1)
				(type default)
			)
			(layer "B.Fab")
		)
		(pad "1" smd rect
			(at 0 0 90)
			(size 2.54 3.048)
			(layers "B.Cu" "B.Mask" "B.Paste")
			(net "PVCCIN_CPU0")
		)
		(pad "2" smd rect
			(at 0 7.112 90)
			(size 2.54 3.048)
			(layers "B.Cu" "B.Mask" "B.Paste")
			(net "GND")
		)
	)
	(footprint ""
		(layer "B.Cu")
		(at 362.229654 -141.84249 -90)
		(property "Reference" "CF17"
			(at 0 0 90)
			(layer "B.SilkS")
			(hide yes)
			(effects
				(font
					(size 1.27 1.27)
				)
				(justify mirror)
			)
		)
		(property "Value" "*"
			(at -1.1811 -2.8194 270)
			(unlocked yes)
			(layer "B.Fab")
			(hide yes)
			(effects
				(font
					(size 1.27 1.016)
					(thickness 0.1524)
				)
				(justify mirror)
			)
		)
		(property "Device Type" "SC22P50V2JN-4GP_SMD-BCG-SC22P5A"
			(at -1.1811 -4.3434 270)
			(unlocked yes)
			(layer "B.Fab")
			(hide yes)
			(effects
				(font
					(size 1.27 1.016)
					(thickness 0.1524)
				)
				(justify mirror)
			)
		)
		(duplicate_pad_numbers_are_jumpers no)
		(fp_rect
			(start 0.4318 0.9525)
			(end -0.4318 -0.9525)
			(stroke
				(width 0)
				(type default)
			)
			(fill no)
			(layer "B.CrtYd")
		)
		(fp_rect
			(start 0.4318 0.9525)
			(end -0.4318 -0.9525)
			(stroke
				(width 0)
				(type default)
			)
			(fill no)
			(layer "B.Fab")
		)
		(pad "1" smd custom
			(at 0 -0.4445 90)
			(size 0.1524 0.1524)
			(layers "B.Cu" "B.Mask" "B.Paste")
			(net "VR_PVDDQ_DEF_AIREF1")
			(options
				(clearance outline)
				(anchor circle)
			)
			(primitives
				(gr_poly
					(pts
						(arc
							(start 0.3048 0.2032)
							(mid 0.275042 0.275042)
							(end 0.2032 0.3048)
						)
						(arc
							(start -0.2032 0.3048)
							(mid -0.275042 0.275042)
							(end -0.3048 0.2032)
						)
						(arc
							(start -0.3048 -0.2032)
							(mid -0.275042 -0.275042)
							(end -0.2032 -0.3048)
						)
						(arc
							(start 0.2032 -0.3048)
							(mid 0.275042 -0.275042)
							(end 0.3048 -0.2032)
						)
					)
					(width 0)
					(fill yes)
				)
			)
		)
		(pad "2" smd custom
			(at 0 0.4445 90)
			(size 0.1524 0.1524)
			(layers "B.Cu" "B.Mask" "B.Paste")
			(net "ISENSE_PVDDQ_DEF_PH1_IMON")
			(options
				(clearance outline)
				(anchor circle)
			)
			(primitives
				(gr_poly
					(pts
						(arc
							(start 0.3048 0.2032)
							(mid 0.275042 0.275042)
							(end 0.2032 0.3048)
						)
						(arc
							(start -0.2032 0.3048)
							(mid -0.275042 0.275042)
							(end -0.3048 0.2032)
						)
						(arc
							(start -0.3048 -0.2032)
							(mid -0.275042 -0.275042)
							(end -0.2032 -0.3048)
						)
						(arc
							(start 0.2032 -0.3048)
							(mid 0.275042 -0.275042)
							(end 0.3048 -0.2032)
						)
					)
					(width 0)
					(fill yes)
				)
			)
		)
	)
	(footprint ""
		(layer "B.Cu")
		(at 491.9345 -40.0304 -90)
		(property "Reference" "R1T1"
			(at 0 0 90)
			(layer "B.SilkS")
			(hide yes)
			(effects
				(font
					(size 1.27 1.27)
				)
				(justify mirror)
			)
		)
		(property "Value" ""
			(at 0 0 90)
			(layer "B.Fab")
			(effects
				(font
					(size 1.27 1.27)
				)
				(justify mirror)
			)
		)
		(duplicate_pad_numbers_are_jumpers no)
		(fp_poly
			(pts
				(xy 0.2794 -0.1016) (xy -0.2794 -0.1016) (xy -0.2794 0.9906) (xy 0.2794 0.9906)
			)
			(stroke
				(width 0)
				(type default)
			)
			(fill no)
			(layer "B.CrtYd")
		)
		(fp_line
			(start -0.2794 0.9906)
			(end -0.2794 -0.1016)
			(stroke
				(width 0.1)
				(type default)
			)
			(layer "B.Fab")
		)
		(fp_line
			(start 0.2794 0.9906)
			(end -0.2794 0.9906)
			(stroke
				(width 0.1)
				(type default)
			)
			(layer "B.Fab")
		)
		(fp_line
			(start -0.2794 -0.1016)
			(end 0.2794 -0.1016)
			(stroke
				(width 0.1)
				(type default)
			)
			(layer "B.Fab")
		)
		(fp_line
			(start 0.2794 -0.1016)
			(end 0.2794 0.9906)
			(stroke
				(width 0.1)
				(type default)
			)
			(layer "B.Fab")
		)
		(pad "1" smd rect
			(at 0 0 90)
			(size 0.508 0.508)
			(layers "B.Cu" "B.Mask" "B.Paste")
			(net "RMII_BMC_PCH_SPRNGVLLE_CRSDV")
		)
		(pad "2" smd rect
			(at 0 0.889 90)
			(size 0.508 0.508)
			(layers "B.Cu" "B.Mask" "B.Paste")
			(net "GND")
		)
		(zone
			(layer "B.Cu")
			(hatch none 0.5)
			(connect_pads
				(clearance 0)
			)
			(min_thickness 0.25)
			(keepout
				(tracks not_allowed)
				(vias allowed)
				(pads allowed)
				(copperpour not_allowed)
				(footprints allowed)
			)
			(placement
				(enabled no)
				(sheetname "")
			)
			(fill
				(thermal_gap 0.5)
				(thermal_bridge_width 0.5)
				(island_removal_mode 0)
			)
			(polygon
				(pts
					(xy 491.2995 -39.7764) (xy 491.2995 -40.2844) (xy 491.6805 -40.2844) (xy 491.6805 -39.7764)
				)
			)
		)
		(zone
			(layer "B.Cu")
			(hatch none 0.5)
			(connect_pads
				(clearance 0)
			)
			(min_thickness 0.25)
			(keepout
				(tracks allowed)
				(vias not_allowed)
				(pads allowed)
				(copperpour not_allowed)
				(footprints allowed)
			)
			(placement
				(enabled no)
				(sheetname "")
			)
			(fill
				(thermal_gap 0.5)
				(thermal_bridge_width 0.5)
				(island_removal_mode 0)
			)
			(polygon
				(pts
					(xy 491.6805 -39.7764) (xy 491.6805 -40.2844) (xy 491.2995 -40.2844) (xy 491.2995 -39.7764)
				)
			)
		)
	)
	(footprint ""
		(layer "B.Cu")
		(at 331.0255 -61.341 -90)
		(property "Reference" "R3P60"
			(at 0 0 90)
			(layer "B.SilkS")
			(hide yes)
			(effects
				(font
					(size 1.27 1.27)
				)
				(justify mirror)
			)
		)
		(property "Value" ""
			(at 0 0 90)
			(layer "B.Fab")
			(effects
				(font
					(size 1.27 1.27)
				)
				(justify mirror)
			)
		)
		(duplicate_pad_numbers_are_jumpers no)
		(fp_poly
			(pts
				(xy 0.2794 -0.1016) (xy -0.2794 -0.1016) (xy -0.2794 0.9906) (xy 0.2794 0.9906)
			)
			(stroke
				(width 0)
				(type default)
			)
			(fill no)
			(layer "B.CrtYd")
		)
		(fp_line
			(start -0.2794 0.9906)
			(end -0.2794 -0.1016)
			(stroke
				(width 0.1)
				(type default)
			)
			(layer "B.Fab")
		)
		(fp_line
			(start 0.2794 0.9906)
			(end -0.2794 0.9906)
			(stroke
				(width 0.1)
				(type default)
			)
			(layer "B.Fab")
		)
		(fp_line
			(start -0.2794 -0.1016)
			(end 0.2794 -0.1016)
			(stroke
				(width 0.1)
				(type default)
			)
			(layer "B.Fab")
		)
		(fp_line
			(start 0.2794 -0.1016)
			(end 0.2794 0.9906)
			(stroke
				(width 0.1)
				(type default)
			)
			(layer "B.Fab")
		)
		(pad "1" smd rect
			(at 0 0 90)
			(size 0.508 0.508)
			(layers "B.Cu" "B.Mask" "B.Paste")
			(net "PVCCIO_CPU0")
		)
		(pad "2" smd rect
			(at 0 0.889 90)
			(size 0.508 0.508)
			(layers "B.Cu" "B.Mask" "B.Paste")
			(net "SMB_DDR_DEF_SCL_G")
		)
		(zone
			(layer "B.Cu")
			(hatch none 0.5)
			(connect_pads
				(clearance 0)
			)
			(min_thickness 0.25)
			(keepout
				(tracks not_allowed)
				(vias allowed)
				(pads allowed)
				(copperpour not_allowed)
				(footprints allowed)
			)
			(placement
				(enabled no)
				(sheetname "")
			)
			(fill
				(thermal_gap 0.5)
				(thermal_bridge_width 0.5)
				(island_removal_mode 0)
			)
			(polygon
				(pts
					(xy 330.3905 -61.087) (xy 330.3905 -61.595) (xy 330.7715 -61.595) (xy 330.7715 -61.087)
				)
			)
		)
		(zone
			(layer "B.Cu")
			(hatch none 0.5)
			(connect_pads
				(clearance 0)
			)
			(min_thickness 0.25)
			(keepout
				(tracks allowed)
				(vias not_allowed)
				(pads allowed)
				(copperpour not_allowed)
				(footprints allowed)
			)
			(placement
				(enabled no)
				(sheetname "")
			)
			(fill
				(thermal_gap 0.5)
				(thermal_bridge_width 0.5)
				(island_removal_mode 0)
			)
			(polygon
				(pts
					(xy 330.7715 -61.087) (xy 330.7715 -61.595) (xy 330.3905 -61.595) (xy 330.3905 -61.087)
				)
			)
		)
	)
	(footprint ""
		(layer "B.Cu")
		(at 17.9832 -14.3002 -90)
		(property "Reference" "C9U2"
			(at -1.87833 9.144 0)
			(unlocked yes)
			(layer "B.SilkS")
			(effects
				(font
					(size 0.7874 0.5842)
					(thickness 0.1524)
				)
				(justify mirror)
			)
		)
		(property "Value" ""
			(at 0 0 90)
			(layer "B.Fab")
			(effects
				(font
					(size 1.27 1.27)
				)
				(justify mirror)
			)
		)
		(duplicate_pad_numbers_are_jumpers no)
		(fp_line
			(start -2.286 7.366)
			(end -1.600708 7.366)
			(stroke
				(width 0.1524)
				(type default)
			)
			(layer "B.SilkS")
		)
		(fp_line
			(start -2.286 7.366)
			(end -2.286 1.63195)
			(stroke
				(width 0.1524)
				(type default)
			)
			(layer "B.SilkS")
		)
		(fp_line
			(start 2.286 7.366)
			(end 1.60147 7.366)
			(stroke
				(width 0.1524)
				(type default)
			)
			(layer "B.SilkS")
		)
		(fp_line
			(start 2.286 7.366)
			(end 2.286 1.632712)
			(stroke
				(width 0.1524)
				(type default)
			)
			(layer "B.SilkS")
		)
		(fp_line
			(start -2.504948 1.633728)
			(end -1.6002 1.633728)
			(stroke
				(width 0.1524)
				(type default)
			)
			(layer "B.SilkS")
		)
		(fp_line
			(start 2.563114 1.633728)
			(end 1.6002 1.633728)
			(stroke
				(width 0.1524)
				(type default)
			)
			(layer "B.SilkS")
		)
		(fp_line
			(start -2.504948 -1.616456)
			(end -2.504948 1.633728)
			(stroke
				(width 0.1524)
				(type default)
			)
			(layer "B.SilkS")
		)
		(fp_line
			(start -1.6002 -1.616456)
			(end -2.504948 -1.616456)
			(stroke
				(width 0.1524)
				(type default)
			)
			(layer "B.SilkS")
		)
		(fp_line
			(start 1.6002 -1.616456)
			(end 2.563114 -1.616456)
			(stroke
				(width 0.1524)
				(type default)
			)
			(layer "B.SilkS")
		)
		(fp_line
			(start 2.563114 -1.616456)
			(end 2.563114 1.633728)
			(stroke
				(width 0.1524)
				(type default)
			)
			(layer "B.SilkS")
		)
		(fp_rect
			(start 2.286 -0.254)
			(end -2.286 7.366)
			(stroke
				(width 0)
				(type default)
			)
			(fill no)
			(layer "B.CrtYd")
		)
		(fp_line
			(start -2.286 7.366)
			(end 2.286 7.366)
			(stroke
				(width 0.1)
				(type default)
			)
			(layer "B.Fab")
		)
		(fp_line
			(start 2.286 7.366)
			(end 2.286 -0.254)
			(stroke
				(width 0.1)
				(type default)
			)
			(layer "B.Fab")
		)
		(fp_line
			(start -2.286 -0.254)
			(end -2.286 7.366)
			(stroke
				(width 0.1)
				(type default)
			)
			(layer "B.Fab")
		)
		(fp_line
			(start 2.286 -0.254)
			(end -2.286 -0.254)
			(stroke
				(width 0.1)
				(type default)
			)
			(layer "B.Fab")
		)
		(pad "1" smd rect
			(at 0 0 90)
			(size 2.54 3.048)
			(layers "B.Cu" "B.Mask" "B.Paste")
			(net "PVDDQ_GHJ")
		)
		(pad "2" smd rect
			(at 0 7.112 90)
			(size 2.54 3.048)
			(layers "B.Cu" "B.Mask" "B.Paste")
			(net "GND")
		)
	)
	(footprint ""
		(layer "B.Cu")
		(at 21.717 -69.85 180)
		(property "Reference" "R9P28"
			(at 0 0 0)
			(layer "B.SilkS")
			(hide yes)
			(effects
				(font
					(size 1.27 1.27)
				)
				(justify mirror)
			)
		)
		(property "Value" ""
			(at 0 0 0)
			(layer "B.Fab")
			(effects
				(font
					(size 1.27 1.27)
				)
				(justify mirror)
			)
		)
		(duplicate_pad_numbers_are_jumpers no)
		(fp_poly
			(pts
				(xy 0.2794 -0.1016) (xy -0.2794 -0.1016) (xy -0.2794 0.9906) (xy 0.2794 0.9906)
			)
			(stroke
				(width 0)
				(type default)
			)
			(fill no)
			(layer "B.CrtYd")
		)
		(fp_line
			(start 0.2794 0.9906)
			(end -0.2794 0.9906)
			(stroke
				(width 0.1)
				(type default)
			)
			(layer "B.Fab")
		)
		(fp_line
			(start 0.2794 -0.1016)
			(end 0.2794 0.9906)
			(stroke
				(width 0.1)
				(type default)
			)
			(layer "B.Fab")
		)
		(fp_line
			(start -0.2794 0.9906)
			(end -0.2794 -0.1016)
			(stroke
				(width 0.1)
				(type default)
			)
			(layer "B.Fab")
		)
		(fp_line
			(start -0.2794 -0.1016)
			(end 0.2794 -0.1016)
			(stroke
				(width 0.1)
				(type default)
			)
			(layer "B.Fab")
		)
		(pad "1" smd rect
			(at 0 0)
			(size 0.508 0.508)
			(layers "B.Cu" "B.Mask" "B.Paste")
			(net "P12V_PSU")
		)
		(pad "2" smd rect
			(at 0 0.889)
			(size 0.508 0.508)
			(layers "B.Cu" "B.Mask" "B.Paste")
			(net "A_HSC_OV")
		)
		(zone
			(layer "B.Cu")
			(hatch none 0.5)
			(connect_pads
				(clearance 0)
			)
			(min_thickness 0.25)
			(keepout
				(tracks not_allowed)
				(vias allowed)
				(pads allowed)
				(copperpour not_allowed)
				(footprints allowed)
			)
			(placement
				(enabled no)
				(sheetname "")
			)
			(fill
				(thermal_gap 0.5)
				(thermal_bridge_width 0.5)
				(island_removal_mode 0)
			)
			(polygon
				(pts
					(xy 21.463 -70.485) (xy 21.971 -70.485) (xy 21.971 -70.104) (xy 21.463 -70.104)
				)
			)
		)
		(zone
			(layer "B.Cu")
			(hatch none 0.5)
			(connect_pads
				(clearance 0)
			)
			(min_thickness 0.25)
			(keepout
				(tracks allowed)
				(vias not_allowed)
				(pads allowed)
				(copperpour not_allowed)
				(footprints allowed)
			)
			(placement
				(enabled no)
				(sheetname "")
			)
			(fill
				(thermal_gap 0.5)
				(thermal_bridge_width 0.5)
				(island_removal_mode 0)
			)
			(polygon
				(pts
					(xy 21.463 -70.104) (xy 21.971 -70.104) (xy 21.971 -70.485) (xy 21.463 -70.485)
				)
			)
		)
	)
	(footprint ""
		(layer "B.Cu")
		(at 349.123 -83.5406)
		(property "Reference" "C3P5"
			(at 0 0 0)
			(layer "B.SilkS")
			(hide yes)
			(effects
				(font
					(size 1.27 1.27)
				)
				(justify mirror)
			)
		)
		(property "Value" ""
			(at 0 0 0)
			(layer "B.Fab")
			(effects
				(font
					(size 1.27 1.27)
				)
				(justify mirror)
			)
		)
		(duplicate_pad_numbers_are_jumpers no)
		(fp_poly
			(pts
				(xy -0.3048 -0.1016) (xy -0.3048 0.9906) (xy 0.3048 0.9906) (xy 0.3048 -0.1016)
			)
			(stroke
				(width 0)
				(type default)
			)
			(fill no)
			(layer "B.CrtYd")
		)
		(fp_line
			(start -0.3048 -0.1016)
			(end 0.3048 -0.1016)
			(stroke
				(width 0.1)
				(type default)
			)
			(layer "B.Fab")
		)
		(fp_line
			(start -0.3048 0.9906)
			(end -0.3048 -0.1016)
			(stroke
				(width 0.1)
				(type default)
			)
			(layer "B.Fab")
		)
		(fp_line
			(start 0.3048 -0.1016)
			(end 0.3048 0.9906)
			(stroke
				(width 0.1)
				(type default)
			)
			(layer "B.Fab")
		)
		(fp_line
			(start 0.3048 0.9906)
			(end -0.3048 0.9906)
			(stroke
				(width 0.1)
				(type default)
			)
			(layer "B.Fab")
		)
		(pad "1" smd rect
			(at 0 0 180)
			(size 0.508 0.508)
			(layers "B.Cu" "B.Mask" "B.Paste")
			(net "VR_PVCCIO_CPU0_VD12")
		)
		(pad "2" smd rect
			(at 0 0.889 180)
			(size 0.508 0.508)
			(layers "B.Cu" "B.Mask" "B.Paste")
			(net "GND")
		)
		(zone
			(layer "B.Cu")
			(hatch none 0.5)
			(connect_pads
				(clearance 0)
			)
			(min_thickness 0.25)
			(keepout
				(tracks allowed)
				(vias not_allowed)
				(pads allowed)
				(copperpour not_allowed)
				(footprints allowed)
			)
			(placement
				(enabled no)
				(sheetname "")
			)
			(fill
				(thermal_gap 0.5)
				(thermal_bridge_width 0.5)
				(island_removal_mode 0)
			)
			(polygon
				(pts
					(xy 349.377 -83.2866) (xy 348.869 -83.2866) (xy 348.869 -82.9056) (xy 349.377 -82.9056)
				)
			)
		)
		(zone
			(layer "B.Cu")
			(hatch none 0.5)
			(connect_pads
				(clearance 0)
			)
			(min_thickness 0.25)
			(keepout
				(tracks not_allowed)
				(vias allowed)
				(pads allowed)
				(copperpour not_allowed)
				(footprints allowed)
			)
			(placement
				(enabled no)
				(sheetname "")
			)
			(fill
				(thermal_gap 0.5)
				(thermal_bridge_width 0.5)
				(island_removal_mode 0)
			)
			(polygon
				(pts
					(xy 349.377 -82.9056) (xy 348.869 -82.9056) (xy 348.869 -83.2866) (xy 349.377 -83.2866)
				)
			)
		)
	)
	(footprint ""
		(layer "B.Cu")
		(at 425.8056 -16.764 180)
		(property "Reference" "R1U54"
			(at 0 0 0)
			(layer "B.SilkS")
			(hide yes)
			(effects
				(font
					(size 1.27 1.27)
				)
				(justify mirror)
			)
		)
		(property "Value" ""
			(at 0 0 0)
			(layer "B.Fab")
			(effects
				(font
					(size 1.27 1.27)
				)
				(justify mirror)
			)
		)
		(duplicate_pad_numbers_are_jumpers no)
		(fp_poly
			(pts
				(xy 0.2794 -0.1016) (xy -0.2794 -0.1016) (xy -0.2794 0.9906) (xy 0.2794 0.9906)
			)
			(stroke
				(width 0)
				(type default)
			)
			(fill no)
			(layer "B.CrtYd")
		)
		(fp_line
			(start 0.2794 0.9906)
			(end -0.2794 0.9906)
			(stroke
				(width 0.1)
				(type default)
			)
			(layer "B.Fab")
		)
		(fp_line
			(start 0.2794 -0.1016)
			(end 0.2794 0.9906)
			(stroke
				(width 0.1)
				(type default)
			)
			(layer "B.Fab")
		)
		(fp_line
			(start -0.2794 0.9906)
			(end -0.2794 -0.1016)
			(stroke
				(width 0.1)
				(type default)
			)
			(layer "B.Fab")
		)
		(fp_line
			(start -0.2794 -0.1016)
			(end 0.2794 -0.1016)
			(stroke
				(width 0.1)
				(type default)
			)
			(layer "B.Fab")
		)
		(pad "1" smd rect
			(at 0 0)
			(size 0.508 0.508)
			(layers "B.Cu" "B.Mask" "B.Paste")
			(net "H_CPU1_MEMGHJ_MEMHOT_LVT3_N")
		)
		(pad "2" smd rect
			(at 0 0.889)
			(size 0.508 0.508)
			(layers "B.Cu" "B.Mask" "B.Paste")
			(net "H_CPU1_MEMGHJ_MEMHOT_LVT3_BMC_N")
		)
		(zone
			(layer "B.Cu")
			(hatch none 0.5)
			(connect_pads
				(clearance 0)
			)
			(min_thickness 0.25)
			(keepout
				(tracks not_allowed)
				(vias allowed)
				(pads allowed)
				(copperpour not_allowed)
				(footprints allowed)
			)
			(placement
				(enabled no)
				(sheetname "")
			)
			(fill
				(thermal_gap 0.5)
				(thermal_bridge_width 0.5)
				(island_removal_mode 0)
			)
			(polygon
				(pts
					(xy 425.5516 -17.399) (xy 426.0596 -17.399) (xy 426.0596 -17.018) (xy 425.5516 -17.018)
				)
			)
		)
		(zone
			(layer "B.Cu")
			(hatch none 0.5)
			(connect_pads
				(clearance 0)
			)
			(min_thickness 0.25)
			(keepout
				(tracks allowed)
				(vias not_allowed)
				(pads allowed)
				(copperpour not_allowed)
				(footprints allowed)
			)
			(placement
				(enabled no)
				(sheetname "")
			)
			(fill
				(thermal_gap 0.5)
				(thermal_bridge_width 0.5)
				(island_removal_mode 0)
			)
			(polygon
				(pts
					(xy 425.5516 -17.018) (xy 426.0596 -17.018) (xy 426.0596 -17.399) (xy 425.5516 -17.399)
				)
			)
		)
	)
	(footprint ""
		(layer "B.Cu")
		(at 349.631 -133.223 180)
		(property "Reference" "C3M8"
			(at 0 0 0)
			(layer "B.SilkS")
			(hide yes)
			(effects
				(font
					(size 1.27 1.27)
				)
				(justify mirror)
			)
		)
		(property "Value" ""
			(at 0 0 0)
			(layer "B.Fab")
			(effects
				(font
					(size 1.27 1.27)
				)
				(justify mirror)
			)
		)
		(duplicate_pad_numbers_are_jumpers no)
		(fp_poly
			(pts
				(xy 0.7239 -0.2159) (xy -0.7239 -0.2159) (xy -0.7239 1.9939) (xy 0.7239 1.9939)
			)
			(stroke
				(width 0)
				(type default)
			)
			(fill no)
			(layer "B.CrtYd")
		)
		(fp_line
			(start 0.7239 1.9939)
			(end -0.7239 1.9939)
			(stroke
				(width 0.1)
				(type default)
			)
			(layer "B.Fab")
		)
		(fp_line
			(start 0.7239 -0.2159)
			(end 0.7239 1.9939)
			(stroke
				(width 0.1)
				(type default)
			)
			(layer "B.Fab")
		)
		(fp_line
			(start -0.7239 1.9939)
			(end -0.7239 -0.2159)
			(stroke
				(width 0.1)
				(type default)
			)
			(layer "B.Fab")
		)
		(fp_line
			(start -0.7239 -0.2159)
			(end 0.7239 -0.2159)
			(stroke
				(width 0.1)
				(type default)
			)
			(layer "B.Fab")
		)
		(pad "1" smd rect
			(at 0 0)
			(size 1.27 1.016)
			(layers "B.Cu" "B.Mask" "B.Paste")
			(net "VR_FET_SW_P12V_STBY_PVPP_DEF")
		)
		(pad "2" smd rect
			(at 0 1.778)
			(size 1.27 1.016)
			(layers "B.Cu" "B.Mask" "B.Paste")
			(net "GND")
		)
		(zone
			(layer "B.Cu")
			(hatch none 0.5)
			(connect_pads
				(clearance 0)
			)
			(min_thickness 0.25)
			(keepout
				(tracks not_allowed)
				(vias allowed)
				(pads allowed)
				(copperpour not_allowed)
				(footprints allowed)
			)
			(placement
				(enabled no)
				(sheetname "")
			)
			(fill
				(thermal_gap 0.5)
				(thermal_bridge_width 0.5)
				(island_removal_mode 0)
			)
			(polygon
				(pts
					(xy 348.996 -133.731) (xy 350.266 -133.731) (xy 350.266 -134.493) (xy 348.996 -134.493)
				)
			)
		)
	)
	(footprint ""
		(layer "B.Cu")
		(at 387.457188 -57.81675 90)
		(property "Reference" "R8F7"
			(at 0 0 90)
			(layer "B.SilkS")
			(hide yes)
			(effects
				(font
					(size 1.27 1.27)
				)
				(justify mirror)
			)
		)
		(property "Value" ""
			(at 0 0 90)
			(layer "B.Fab")
			(effects
				(font
					(size 1.27 1.27)
				)
				(justify mirror)
			)
		)
		(duplicate_pad_numbers_are_jumpers no)
		(fp_poly
			(pts
				(xy 0.2794 -0.1016) (xy -0.2794 -0.1016) (xy -0.2794 0.9906) (xy 0.2794 0.9906)
			)
			(stroke
				(width 0)
				(type default)
			)
			(fill no)
			(layer "B.CrtYd")
		)
		(fp_line
			(start 0.2794 -0.1016)
			(end 0.2794 0.9906)
			(stroke
				(width 0.1)
				(type default)
			)
			(layer "B.Fab")
		)
		(fp_line
			(start -0.2794 -0.1016)
			(end 0.2794 -0.1016)
			(stroke
				(width 0.1)
				(type default)
			)
			(layer "B.Fab")
		)
		(fp_line
			(start 0.2794 0.9906)
			(end -0.2794 0.9906)
			(stroke
				(width 0.1)
				(type default)
			)
			(layer "B.Fab")
		)
		(fp_line
			(start -0.2794 0.9906)
			(end -0.2794 -0.1016)
			(stroke
				(width 0.1)
				(type default)
			)
			(layer "B.Fab")
		)
		(pad "1" smd rect
			(at 0 0 270)
			(size 0.508 0.508)
			(layers "B.Cu" "B.Mask" "B.Paste")
			(net "SPI_SWITCH_CLK")
		)
		(pad "2" smd rect
			(at 0 0.889 270)
			(size 0.508 0.508)
			(layers "B.Cu" "B.Mask" "B.Paste")
			(net "SPI_CLK_R1")
		)
		(zone
			(layer "B.Cu")
			(hatch none 0.5)
			(connect_pads
				(clearance 0)
			)
			(min_thickness 0.25)
			(keepout
				(tracks allowed)
				(vias not_allowed)
				(pads allowed)
				(copperpour not_allowed)
				(footprints allowed)
			)
			(placement
				(enabled no)
				(sheetname "")
			)
			(fill
				(thermal_gap 0.5)
				(thermal_bridge_width 0.5)
				(island_removal_mode 0)
			)
			(polygon
				(pts
					(xy 387.711188 -58.07075) (xy 387.711188 -57.56275) (xy 388.092188 -57.56275) (xy 388.092188 -58.07075)
				)
			)
		)
		(zone
			(layer "B.Cu")
			(hatch none 0.5)
			(connect_pads
				(clearance 0)
			)
			(min_thickness 0.25)
			(keepout
				(tracks not_allowed)
				(vias allowed)
				(pads allowed)
				(copperpour not_allowed)
				(footprints allowed)
			)
			(placement
				(enabled no)
				(sheetname "")
			)
			(fill
				(thermal_gap 0.5)
				(thermal_bridge_width 0.5)
				(island_removal_mode 0)
			)
			(polygon
				(pts
					(xy 388.092188 -58.07075) (xy 388.092188 -57.56275) (xy 387.711188 -57.56275) (xy 387.711188 -58.07075)
				)
			)
		)
	)
	(footprint ""
		(layer "B.Cu")
		(at 63.2968 -89.9922 90)
		(property "Reference" "R8N4"
			(at 0 0 90)
			(layer "B.SilkS")
			(hide yes)
			(effects
				(font
					(size 1.27 1.27)
				)
				(justify mirror)
			)
		)
		(property "Value" ""
			(at 0 0 90)
			(layer "B.Fab")
			(effects
				(font
					(size 1.27 1.27)
				)
				(justify mirror)
			)
		)
		(duplicate_pad_numbers_are_jumpers no)
		(fp_poly
			(pts
				(xy 0.2794 -0.1016) (xy -0.2794 -0.1016) (xy -0.2794 0.9906) (xy 0.2794 0.9906)
			)
			(stroke
				(width 0)
				(type default)
			)
			(fill no)
			(layer "B.CrtYd")
		)
		(fp_line
			(start 0.2794 -0.1016)
			(end 0.2794 0.9906)
			(stroke
				(width 0.1)
				(type default)
			)
			(layer "B.Fab")
		)
		(fp_line
			(start -0.2794 -0.1016)
			(end 0.2794 -0.1016)
			(stroke
				(width 0.1)
				(type default)
			)
			(layer "B.Fab")
		)
		(fp_line
			(start 0.2794 0.9906)
			(end -0.2794 0.9906)
			(stroke
				(width 0.1)
				(type default)
			)
			(layer "B.Fab")
		)
		(fp_line
			(start -0.2794 0.9906)
			(end -0.2794 -0.1016)
			(stroke
				(width 0.1)
				(type default)
			)
			(layer "B.Fab")
		)
		(pad "1" smd rect
			(at 0 0 270)
			(size 0.508 0.508)
			(layers "B.Cu" "B.Mask" "B.Paste")
			(net "P3V3_STBY")
		)
		(pad "2" smd rect
			(at 0 0.889 270)
			(size 0.508 0.508)
			(layers "B.Cu" "B.Mask" "B.Paste")
			(net "FM_CPU1_PROC_ID0")
		)
		(zone
			(layer "B.Cu")
			(hatch none 0.5)
			(connect_pads
				(clearance 0)
			)
			(min_thickness 0.25)
			(keepout
				(tracks allowed)
				(vias not_allowed)
				(pads allowed)
				(copperpour not_allowed)
				(footprints allowed)
			)
			(placement
				(enabled no)
				(sheetname "")
			)
			(fill
				(thermal_gap 0.5)
				(thermal_bridge_width 0.5)
				(island_removal_mode 0)
			)
			(polygon
				(pts
					(xy 63.5508 -90.2462) (xy 63.5508 -89.7382) (xy 63.9318 -89.7382) (xy 63.9318 -90.2462)
				)
			)
		)
		(zone
			(layer "B.Cu")
			(hatch none 0.5)
			(connect_pads
				(clearance 0)
			)
			(min_thickness 0.25)
			(keepout
				(tracks not_allowed)
				(vias allowed)
				(pads allowed)
				(copperpour not_allowed)
				(footprints allowed)
			)
			(placement
				(enabled no)
				(sheetname "")
			)
			(fill
				(thermal_gap 0.5)
				(thermal_bridge_width 0.5)
				(island_removal_mode 0)
			)
			(polygon
				(pts
					(xy 63.9318 -90.2462) (xy 63.9318 -89.7382) (xy 63.5508 -89.7382) (xy 63.5508 -90.2462)
				)
			)
		)
	)
	(footprint ""
		(layer "B.Cu")
		(at 427.736 -142.0876)
		(property "Reference" "C2L39"
			(at 0 0 0)
			(layer "B.SilkS")
			(hide yes)
			(effects
				(font
					(size 1.27 1.27)
				)
				(justify mirror)
			)
		)
		(property "Value" ""
			(at 0 0 0)
			(layer "B.Fab")
			(effects
				(font
					(size 1.27 1.27)
				)
				(justify mirror)
			)
		)
		(duplicate_pad_numbers_are_jumpers no)
		(fp_poly
			(pts
				(xy -0.3048 -0.1016) (xy -0.3048 0.9906) (xy 0.3048 0.9906) (xy 0.3048 -0.1016)
			)
			(stroke
				(width 0)
				(type default)
			)
			(fill no)
			(layer "B.CrtYd")
		)
		(fp_line
			(start -0.3048 -0.1016)
			(end 0.3048 -0.1016)
			(stroke
				(width 0.1)
				(type default)
			)
			(layer "B.Fab")
		)
		(fp_line
			(start -0.3048 0.9906)
			(end -0.3048 -0.1016)
			(stroke
				(width 0.1)
				(type default)
			)
			(layer "B.Fab")
		)
		(fp_line
			(start 0.3048 -0.1016)
			(end 0.3048 0.9906)
			(stroke
				(width 0.1)
				(type default)
			)
			(layer "B.Fab")
		)
		(fp_line
			(start 0.3048 0.9906)
			(end -0.3048 0.9906)
			(stroke
				(width 0.1)
				(type default)
			)
			(layer "B.Fab")
		)
		(pad "1" smd rect
			(at 0 0 180)
			(size 0.508 0.508)
			(layers "B.Cu" "B.Mask" "B.Paste")
			(net "SATA6G_P0_TX_C_DP")
		)
		(pad "2" smd rect
			(at 0 0.889 180)
			(size 0.508 0.508)
			(layers "B.Cu" "B.Mask" "B.Paste")
			(net "SATA6G_PCH_PCIE_UP_SATA_TXP<0>")
		)
		(zone
			(layer "B.Cu")
			(hatch none 0.5)
			(connect_pads
				(clearance 0)
			)
			(min_thickness 0.25)
			(keepout
				(tracks allowed)
				(vias not_allowed)
				(pads allowed)
				(copperpour not_allowed)
				(footprints allowed)
			)
			(placement
				(enabled no)
				(sheetname "")
			)
			(fill
				(thermal_gap 0.5)
				(thermal_bridge_width 0.5)
				(island_removal_mode 0)
			)
			(polygon
				(pts
					(xy 427.99 -141.8336) (xy 427.482 -141.8336) (xy 427.482 -141.4526) (xy 427.99 -141.4526)
				)
			)
		)
		(zone
			(layer "B.Cu")
			(hatch none 0.5)
			(connect_pads
				(clearance 0)
			)
			(min_thickness 0.25)
			(keepout
				(tracks not_allowed)
				(vias allowed)
				(pads allowed)
				(copperpour not_allowed)
				(footprints allowed)
			)
			(placement
				(enabled no)
				(sheetname "")
			)
			(fill
				(thermal_gap 0.5)
				(thermal_bridge_width 0.5)
				(island_removal_mode 0)
			)
			(polygon
				(pts
					(xy 427.99 -141.4526) (xy 427.482 -141.4526) (xy 427.482 -141.8336) (xy 427.99 -141.8336)
				)
			)
		)
	)
	(footprint ""
		(layer "B.Cu")
		(at 22.57298 -74.42708 90)
		(property "Reference" "C9P15"
			(at 0 0 90)
			(layer "B.SilkS")
			(hide yes)
			(effects
				(font
					(size 1.27 1.27)
				)
				(justify mirror)
			)
		)
		(property "Value" ""
			(at 0 0 90)
			(layer "B.Fab")
			(effects
				(font
					(size 1.27 1.27)
				)
				(justify mirror)
			)
		)
		(duplicate_pad_numbers_are_jumpers no)
		(fp_poly
			(pts
				(xy -0.3048 -0.1016) (xy -0.3048 0.9906) (xy 0.3048 0.9906) (xy 0.3048 -0.1016)
			)
			(stroke
				(width 0)
				(type default)
			)
			(fill no)
			(layer "B.CrtYd")
		)
		(fp_line
			(start 0.3048 -0.1016)
			(end 0.3048 0.9906)
			(stroke
				(width 0.1)
				(type default)
			)
			(layer "B.Fab")
		)
		(fp_line
			(start -0.3048 -0.1016)
			(end 0.3048 -0.1016)
			(stroke
				(width 0.1)
				(type default)
			)
			(layer "B.Fab")
		)
		(fp_line
			(start 0.3048 0.9906)
			(end -0.3048 0.9906)
			(stroke
				(width 0.1)
				(type default)
			)
			(layer "B.Fab")
		)
		(fp_line
			(start -0.3048 0.9906)
			(end -0.3048 -0.1016)
			(stroke
				(width 0.1)
				(type default)
			)
			(layer "B.Fab")
		)
		(pad "1" smd rect
			(at 0 0 270)
			(size 0.508 0.508)
			(layers "B.Cu" "B.Mask" "B.Paste")
			(net "A_HSC_ISET")
		)
		(pad "2" smd rect
			(at 0 0.889 270)
			(size 0.508 0.508)
			(layers "B.Cu" "B.Mask" "B.Paste")
			(net "AGND_HSC")
		)
		(zone
			(layer "B.Cu")
			(hatch none 0.5)
			(connect_pads
				(clearance 0)
			)
			(min_thickness 0.25)
			(keepout
				(tracks allowed)
				(vias not_allowed)
				(pads allowed)
				(copperpour not_allowed)
				(footprints allowed)
			)
			(placement
				(enabled no)
				(sheetname "")
			)
			(fill
				(thermal_gap 0.5)
				(thermal_bridge_width 0.5)
				(island_removal_mode 0)
			)
			(polygon
				(pts
					(xy 22.82698 -74.68108) (xy 22.82698 -74.17308) (xy 23.20798 -74.17308) (xy 23.20798 -74.68108)
				)
			)
		)
		(zone
			(layer "B.Cu")
			(hatch none 0.5)
			(connect_pads
				(clearance 0)
			)
			(min_thickness 0.25)
			(keepout
				(tracks not_allowed)
				(vias allowed)
				(pads allowed)
				(copperpour not_allowed)
				(footprints allowed)
			)
			(placement
				(enabled no)
				(sheetname "")
			)
			(fill
				(thermal_gap 0.5)
				(thermal_bridge_width 0.5)
				(island_removal_mode 0)
			)
			(polygon
				(pts
					(xy 23.20798 -74.68108) (xy 23.20798 -74.17308) (xy 22.82698 -74.17308) (xy 22.82698 -74.68108)
				)
			)
		)
	)
	(footprint ""
		(layer "B.Cu")
		(at 30.952948 -96.7994)
		(property "Reference" "CT55"
			(at 0.8382 -0.84963 0)
			(unlocked yes)
			(layer "B.SilkS")
			(effects
				(font
					(size 0.7874 0.5842)
					(thickness 0.1524)
				)
				(justify left mirror)
			)
		)
		(property "Value" ""
			(at 0 0 0)
			(layer "B.Fab")
			(effects
				(font
					(size 1.27 1.27)
				)
				(justify mirror)
			)
		)
		(duplicate_pad_numbers_are_jumpers no)
		(fp_poly
			(pts
				(xy -0.3048 -0.1016) (xy -0.3048 0.9906) (xy 0.3048 0.9906) (xy 0.3048 -0.1016)
			)
			(stroke
				(width 0)
				(type default)
			)
			(fill no)
			(layer "B.CrtYd")
		)
		(fp_line
			(start -0.3048 -0.1016)
			(end 0.3048 -0.1016)
			(stroke
				(width 0.1)
				(type default)
			)
			(layer "B.Fab")
		)
		(fp_line
			(start -0.3048 0.9906)
			(end -0.3048 -0.1016)
			(stroke
				(width 0.1)
				(type default)
			)
			(layer "B.Fab")
		)
		(fp_line
			(start 0.3048 -0.1016)
			(end 0.3048 0.9906)
			(stroke
				(width 0.1)
				(type default)
			)
			(layer "B.Fab")
		)
		(fp_line
			(start 0.3048 0.9906)
			(end -0.3048 0.9906)
			(stroke
				(width 0.1)
				(type default)
			)
			(layer "B.Fab")
		)
		(pad "1" smd rect
			(at 0 0 180)
			(size 0.508 0.508)
			(layers "B.Cu" "B.Mask" "B.Paste")
			(net "A_TSENSE_PVSA_CPU1")
		)
		(pad "2" smd rect
			(at 0 0.889 180)
			(size 0.508 0.508)
			(layers "B.Cu" "B.Mask" "B.Paste")
			(net "GND")
		)
		(zone
			(layer "B.Cu")
			(hatch none 0.5)
			(connect_pads
				(clearance 0)
			)
			(min_thickness 0.25)
			(keepout
				(tracks allowed)
				(vias not_allowed)
				(pads allowed)
				(copperpour not_allowed)
				(footprints allowed)
			)
			(placement
				(enabled no)
				(sheetname "")
			)
			(fill
				(thermal_gap 0.5)
				(thermal_bridge_width 0.5)
				(island_removal_mode 0)
			)
			(polygon
				(pts
					(xy 31.206948 -96.5454) (xy 30.698948 -96.5454) (xy 30.698948 -96.1644) (xy 31.206948 -96.1644)
				)
			)
		)
		(zone
			(layer "B.Cu")
			(hatch none 0.5)
			(connect_pads
				(clearance 0)
			)
			(min_thickness 0.25)
			(keepout
				(tracks not_allowed)
				(vias allowed)
				(pads allowed)
				(copperpour not_allowed)
				(footprints allowed)
			)
			(placement
				(enabled no)
				(sheetname "")
			)
			(fill
				(thermal_gap 0.5)
				(thermal_bridge_width 0.5)
				(island_removal_mode 0)
			)
			(polygon
				(pts
					(xy 31.206948 -96.1644) (xy 30.698948 -96.1644) (xy 30.698948 -96.5454) (xy 31.206948 -96.5454)
				)
			)
		)
	)
	(footprint ""
		(layer "B.Cu")
		(at 393.4079 -20.6248 90)
		(property "Reference" "R32W2"
			(at 0.8382 -0.67818 90)
			(unlocked yes)
			(layer "B.SilkS")
			(effects
				(font
					(size 0.4064 0.254)
					(thickness 0.1524)
				)
				(justify left mirror)
			)
		)
		(property "Value" ""
			(at 0 0 90)
			(layer "B.Fab")
			(effects
				(font
					(size 1.27 1.27)
				)
				(justify mirror)
			)
		)
		(duplicate_pad_numbers_are_jumpers no)
		(fp_poly
			(pts
				(xy 0.2794 -0.1016) (xy -0.2794 -0.1016) (xy -0.2794 0.9906) (xy 0.2794 0.9906)
			)
			(stroke
				(width 0)
				(type default)
			)
			(fill no)
			(layer "B.CrtYd")
		)
		(fp_line
			(start 0.2794 -0.1016)
			(end 0.2794 0.9906)
			(stroke
				(width 0.1)
				(type default)
			)
			(layer "B.Fab")
		)
		(fp_line
			(start -0.2794 -0.1016)
			(end 0.2794 -0.1016)
			(stroke
				(width 0.1)
				(type default)
			)
			(layer "B.Fab")
		)
		(fp_line
			(start 0.2794 0.9906)
			(end -0.2794 0.9906)
			(stroke
				(width 0.1)
				(type default)
			)
			(layer "B.Fab")
		)
		(fp_line
			(start -0.2794 0.9906)
			(end -0.2794 -0.1016)
			(stroke
				(width 0.1)
				(type default)
			)
			(layer "B.Fab")
		)
		(pad "1" smd rect
			(at 0 0 270)
			(size 0.508 0.508)
			(layers "B.Cu" "B.Mask" "B.Paste")
			(net "P1V8_M2")
		)
		(pad "2" smd rect
			(at 0 0.889 270)
			(size 0.508 0.508)
			(layers "B.Cu" "B.Mask" "B.Paste")
			(net "VREF_LMV431_1V42")
		)
		(zone
			(layer "B.Cu")
			(hatch none 0.5)
			(connect_pads
				(clearance 0)
			)
			(min_thickness 0.25)
			(keepout
				(tracks allowed)
				(vias not_allowed)
				(pads allowed)
				(copperpour not_allowed)
				(footprints allowed)
			)
			(placement
				(enabled no)
				(sheetname "")
			)
			(fill
				(thermal_gap 0.5)
				(thermal_bridge_width 0.5)
				(island_removal_mode 0)
			)
			(polygon
				(pts
					(xy 393.6619 -20.8788) (xy 393.6619 -20.3708) (xy 394.0429 -20.3708) (xy 394.0429 -20.8788)
				)
			)
		)
		(zone
			(layer "B.Cu")
			(hatch none 0.5)
			(connect_pads
				(clearance 0)
			)
			(min_thickness 0.25)
			(keepout
				(tracks not_allowed)
				(vias allowed)
				(pads allowed)
				(copperpour not_allowed)
				(footprints allowed)
			)
			(placement
				(enabled no)
				(sheetname "")
			)
			(fill
				(thermal_gap 0.5)
				(thermal_bridge_width 0.5)
				(island_removal_mode 0)
			)
			(polygon
				(pts
					(xy 394.0429 -20.8788) (xy 394.0429 -20.3708) (xy 393.6619 -20.3708) (xy 393.6619 -20.8788)
				)
			)
		)
	)
	(footprint ""
		(layer "B.Cu")
		(at 379.222 -87.3125 180)
		(property "Reference" "R7D5"
			(at 0 0 0)
			(layer "B.SilkS")
			(hide yes)
			(effects
				(font
					(size 1.27 1.27)
				)
				(justify mirror)
			)
		)
		(property "Value" ""
			(at 0 0 0)
			(layer "B.Fab")
			(effects
				(font
					(size 1.27 1.27)
				)
				(justify mirror)
			)
		)
		(duplicate_pad_numbers_are_jumpers no)
		(fp_poly
			(pts
				(xy 0.2794 -0.1016) (xy -0.2794 -0.1016) (xy -0.2794 0.9906) (xy 0.2794 0.9906)
			)
			(stroke
				(width 0)
				(type default)
			)
			(fill no)
			(layer "B.CrtYd")
		)
		(fp_line
			(start 0.2794 0.9906)
			(end -0.2794 0.9906)
			(stroke
				(width 0.1)
				(type default)
			)
			(layer "B.Fab")
		)
		(fp_line
			(start 0.2794 -0.1016)
			(end 0.2794 0.9906)
			(stroke
				(width 0.1)
				(type default)
			)
			(layer "B.Fab")
		)
		(fp_line
			(start -0.2794 0.9906)
			(end -0.2794 -0.1016)
			(stroke
				(width 0.1)
				(type default)
			)
			(layer "B.Fab")
		)
		(fp_line
			(start -0.2794 -0.1016)
			(end 0.2794 -0.1016)
			(stroke
				(width 0.1)
				(type default)
			)
			(layer "B.Fab")
		)
		(pad "1" smd rect
			(at 0 0)
			(size 0.508 0.508)
			(layers "B.Cu" "B.Mask" "B.Paste")
			(net "P3V3_STBY")
		)
		(pad "2" smd rect
			(at 0 0.889)
			(size 0.508 0.508)
			(layers "B.Cu" "B.Mask" "B.Paste")
			(net "FM_MB_SLOT_ID0")
		)
		(zone
			(layer "B.Cu")
			(hatch none 0.5)
			(connect_pads
				(clearance 0)
			)
			(min_thickness 0.25)
			(keepout
				(tracks not_allowed)
				(vias allowed)
				(pads allowed)
				(copperpour not_allowed)
				(footprints allowed)
			)
			(placement
				(enabled no)
				(sheetname "")
			)
			(fill
				(thermal_gap 0.5)
				(thermal_bridge_width 0.5)
				(island_removal_mode 0)
			)
			(polygon
				(pts
					(xy 378.968 -87.9475) (xy 379.476 -87.9475) (xy 379.476 -87.5665) (xy 378.968 -87.5665)
				)
			)
		)
		(zone
			(layer "B.Cu")
			(hatch none 0.5)
			(connect_pads
				(clearance 0)
			)
			(min_thickness 0.25)
			(keepout
				(tracks allowed)
				(vias not_allowed)
				(pads allowed)
				(copperpour not_allowed)
				(footprints allowed)
			)
			(placement
				(enabled no)
				(sheetname "")
			)
			(fill
				(thermal_gap 0.5)
				(thermal_bridge_width 0.5)
				(island_removal_mode 0)
			)
			(polygon
				(pts
					(xy 378.968 -87.5665) (xy 379.476 -87.5665) (xy 379.476 -87.9475) (xy 378.968 -87.9475)
				)
			)
		)
	)
	(footprint ""
		(layer "B.Cu")
		(at 445.02324 -24.28494)
		(property "Reference" "C25W1"
			(at 0.8382 -0.67818 0)
			(unlocked yes)
			(layer "B.SilkS")
			(effects
				(font
					(size 0.4064 0.254)
					(thickness 0.1524)
				)
				(justify left mirror)
			)
		)
		(property "Value" ""
			(at 0 0 0)
			(layer "B.Fab")
			(effects
				(font
					(size 1.27 1.27)
				)
				(justify mirror)
			)
		)
		(duplicate_pad_numbers_are_jumpers no)
		(fp_poly
			(pts
				(xy -0.3048 -0.1016) (xy -0.3048 0.9906) (xy 0.3048 0.9906) (xy 0.3048 -0.1016)
			)
			(stroke
				(width 0)
				(type default)
			)
			(fill no)
			(layer "B.CrtYd")
		)
		(fp_line
			(start -0.3048 -0.1016)
			(end 0.3048 -0.1016)
			(stroke
				(width 0.1)
				(type default)
			)
			(layer "B.Fab")
		)
		(fp_line
			(start -0.3048 0.9906)
			(end -0.3048 -0.1016)
			(stroke
				(width 0.1)
				(type default)
			)
			(layer "B.Fab")
		)
		(fp_line
			(start 0.3048 -0.1016)
			(end 0.3048 0.9906)
			(stroke
				(width 0.1)
				(type default)
			)
			(layer "B.Fab")
		)
		(fp_line
			(start 0.3048 0.9906)
			(end -0.3048 0.9906)
			(stroke
				(width 0.1)
				(type default)
			)
			(layer "B.Fab")
		)
		(pad "1" smd rect
			(at 0 0 180)
			(size 0.508 0.508)
			(layers "B.Cu" "B.Mask" "B.Paste")
			(net "P1V2_AUX_BMC")
		)
		(pad "2" smd rect
			(at 0 0.889 180)
			(size 0.508 0.508)
			(layers "B.Cu" "B.Mask" "B.Paste")
			(net "GND")
		)
		(zone
			(layer "B.Cu")
			(hatch none 0.5)
			(connect_pads
				(clearance 0)
			)
			(min_thickness 0.25)
			(keepout
				(tracks allowed)
				(vias not_allowed)
				(pads allowed)
				(copperpour not_allowed)
				(footprints allowed)
			)
			(placement
				(enabled no)
				(sheetname "")
			)
			(fill
				(thermal_gap 0.5)
				(thermal_bridge_width 0.5)
				(island_removal_mode 0)
			)
			(polygon
				(pts
					(xy 445.27724 -24.03094) (xy 444.76924 -24.03094) (xy 444.76924 -23.64994) (xy 445.27724 -23.64994)
				)
			)
		)
		(zone
			(layer "B.Cu")
			(hatch none 0.5)
			(connect_pads
				(clearance 0)
			)
			(min_thickness 0.25)
			(keepout
				(tracks not_allowed)
				(vias allowed)
				(pads allowed)
				(copperpour not_allowed)
				(footprints allowed)
			)
			(placement
				(enabled no)
				(sheetname "")
			)
			(fill
				(thermal_gap 0.5)
				(thermal_bridge_width 0.5)
				(island_removal_mode 0)
			)
			(polygon
				(pts
					(xy 445.27724 -23.64994) (xy 444.76924 -23.64994) (xy 444.76924 -24.03094) (xy 445.27724 -24.03094)
				)
			)
		)
	)
	(footprint ""
		(layer "B.Cu")
		(at 413.639 -121.92 180)
		(property "Reference" "C8B15"
			(at 0 0 0)
			(layer "B.SilkS")
			(hide yes)
			(effects
				(font
					(size 1.27 1.27)
				)
				(justify mirror)
			)
		)
		(property "Value" ""
			(at 0 0 0)
			(layer "B.Fab")
			(effects
				(font
					(size 1.27 1.27)
				)
				(justify mirror)
			)
		)
		(duplicate_pad_numbers_are_jumpers no)
		(fp_poly
			(pts
				(xy 0.7239 -0.2159) (xy -0.7239 -0.2159) (xy -0.7239 1.9939) (xy 0.7239 1.9939)
			)
			(stroke
				(width 0)
				(type default)
			)
			(fill no)
			(layer "B.CrtYd")
		)
		(fp_line
			(start 0.7239 1.9939)
			(end -0.7239 1.9939)
			(stroke
				(width 0.1)
				(type default)
			)
			(layer "B.Fab")
		)
		(fp_line
			(start 0.7239 -0.2159)
			(end 0.7239 1.9939)
			(stroke
				(width 0.1)
				(type default)
			)
			(layer "B.Fab")
		)
		(fp_line
			(start -0.7239 1.9939)
			(end -0.7239 -0.2159)
			(stroke
				(width 0.1)
				(type default)
			)
			(layer "B.Fab")
		)
		(fp_line
			(start -0.7239 -0.2159)
			(end 0.7239 -0.2159)
			(stroke
				(width 0.1)
				(type default)
			)
			(layer "B.Fab")
		)
		(pad "1" smd rect
			(at 0 0)
			(size 1.27 1.016)
			(layers "B.Cu" "B.Mask" "B.Paste")
			(net "P1V05_PCH_STBY")
		)
		(pad "2" smd rect
			(at 0 1.778)
			(size 1.27 1.016)
			(layers "B.Cu" "B.Mask" "B.Paste")
			(net "GND")
		)
		(zone
			(layer "B.Cu")
			(hatch none 0.5)
			(connect_pads
				(clearance 0)
			)
			(min_thickness 0.25)
			(keepout
				(tracks not_allowed)
				(vias allowed)
				(pads allowed)
				(copperpour not_allowed)
				(footprints allowed)
			)
			(placement
				(enabled no)
				(sheetname "")
			)
			(fill
				(thermal_gap 0.5)
				(thermal_bridge_width 0.5)
				(island_removal_mode 0)
			)
			(polygon
				(pts
					(xy 413.004 -122.428) (xy 414.274 -122.428) (xy 414.274 -123.19) (xy 413.004 -123.19)
				)
			)
		)
	)
	(footprint ""
		(layer "B.Cu")
		(at 375.0945 -45.72 90)
		(property "Reference" "R2T39"
			(at 0 0 90)
			(layer "B.SilkS")
			(hide yes)
			(effects
				(font
					(size 1.27 1.27)
				)
				(justify mirror)
			)
		)
		(property "Value" ""
			(at 0 0 90)
			(layer "B.Fab")
			(effects
				(font
					(size 1.27 1.27)
				)
				(justify mirror)
			)
		)
		(duplicate_pad_numbers_are_jumpers no)
		(fp_poly
			(pts
				(xy 0.2794 -0.1016) (xy -0.2794 -0.1016) (xy -0.2794 0.9906) (xy 0.2794 0.9906)
			)
			(stroke
				(width 0)
				(type default)
			)
			(fill no)
			(layer "B.CrtYd")
		)
		(fp_line
			(start 0.2794 -0.1016)
			(end 0.2794 0.9906)
			(stroke
				(width 0.1)
				(type default)
			)
			(layer "B.Fab")
		)
		(fp_line
			(start -0.2794 -0.1016)
			(end 0.2794 -0.1016)
			(stroke
				(width 0.1)
				(type default)
			)
			(layer "B.Fab")
		)
		(fp_line
			(start 0.2794 0.9906)
			(end -0.2794 0.9906)
			(stroke
				(width 0.1)
				(type default)
			)
			(layer "B.Fab")
		)
		(fp_line
			(start -0.2794 0.9906)
			(end -0.2794 -0.1016)
			(stroke
				(width 0.1)
				(type default)
			)
			(layer "B.Fab")
		)
		(pad "1" smd rect
			(at 0 0 270)
			(size 0.508 0.508)
			(layers "B.Cu" "B.Mask" "B.Paste")
			(net "P0V7_GTL2104_5_VREF")
		)
		(pad "2" smd rect
			(at 0 0.889 270)
			(size 0.508 0.508)
			(layers "B.Cu" "B.Mask" "B.Paste")
			(net "GND")
		)
		(zone
			(layer "B.Cu")
			(hatch none 0.5)
			(connect_pads
				(clearance 0)
			)
			(min_thickness 0.25)
			(keepout
				(tracks allowed)
				(vias not_allowed)
				(pads allowed)
				(copperpour not_allowed)
				(footprints allowed)
			)
			(placement
				(enabled no)
				(sheetname "")
			)
			(fill
				(thermal_gap 0.5)
				(thermal_bridge_width 0.5)
				(island_removal_mode 0)
			)
			(polygon
				(pts
					(xy 375.3485 -45.974) (xy 375.3485 -45.466) (xy 375.7295 -45.466) (xy 375.7295 -45.974)
				)
			)
		)
		(zone
			(layer "B.Cu")
			(hatch none 0.5)
			(connect_pads
				(clearance 0)
			)
			(min_thickness 0.25)
			(keepout
				(tracks not_allowed)
				(vias allowed)
				(pads allowed)
				(copperpour not_allowed)
				(footprints allowed)
			)
			(placement
				(enabled no)
				(sheetname "")
			)
			(fill
				(thermal_gap 0.5)
				(thermal_bridge_width 0.5)
				(island_removal_mode 0)
			)
			(polygon
				(pts
					(xy 375.7295 -45.974) (xy 375.7295 -45.466) (xy 375.3485 -45.466) (xy 375.3485 -45.974)
				)
			)
		)
	)
	(footprint ""
		(layer "B.Cu")
		(at 29.699458 -15.222982 90)
		(property "Reference" "J9U1"
			(at 2.276348 37.991542 0)
			(unlocked yes)
			(layer "B.SilkS")
			(effects
				(font
					(size 0.7874 0.5842)
					(thickness 0.1524)
				)
				(justify left mirror)
			)
		)
		(property "Value" ""
			(at 0 0 90)
			(layer "B.Fab")
			(effects
				(font
					(size 1.27 1.27)
				)
				(justify mirror)
			)
		)
		(duplicate_pad_numbers_are_jumpers no)
		(fp_line
			(start 0.94996 -7.675118)
			(end -5.5499 -7.675118)
			(stroke
				(width 0.1524)
				(type default)
			)
			(layer "B.SilkS")
		)
		(fp_line
			(start -5.5499 -7.675118)
			(end -5.5499 -1.480058)
			(stroke
				(width 0.1524)
				(type default)
			)
			(layer "B.SilkS")
		)
		(fp_line
			(start 0.94996 -1.480058)
			(end 0.94996 -7.675118)
			(stroke
				(width 0.1524)
				(type default)
			)
			(layer "B.SilkS")
		)
		(fp_line
			(start -5.5499 128.130046)
			(end -5.5499 134.325106)
			(stroke
				(width 0.1524)
				(type default)
			)
			(layer "B.SilkS")
		)
		(fp_line
			(start 0.94996 134.325106)
			(end 0.94996 128.130046)
			(stroke
				(width 0.1524)
				(type default)
			)
			(layer "B.SilkS")
		)
		(fp_line
			(start -5.5499 134.325106)
			(end 0.94996 134.325106)
			(stroke
				(width 0.1524)
				(type default)
			)
			(layer "B.SilkS")
		)
		(fp_poly
			(pts
				(xy 2.278888 -0.584454) (xy 2.278888 0.431546) (xy 1.008888 -0.076454)
			)
			(stroke
				(width 0)
				(type default)
			)
			(fill yes)
			(layer "B.SilkS")
		)
		(fp_poly
			(pts
				(xy 0.94996 -7.675118) (xy 0.94996 134.325106) (xy -5.5499 134.325106) (xy -5.5499 -7.675118)
			)
			(stroke
				(width 0)
				(type default)
			)
			(fill no)
			(layer "B.CrtYd")
		)
		(fp_line
			(start 0.94996 -7.675118)
			(end -5.5499 -7.675118)
			(stroke
				(width 0.1)
				(type default)
			)
			(layer "B.Fab")
		)
		(fp_line
			(start -5.5499 -7.675118)
			(end -5.5499 134.325106)
			(stroke
				(width 0.1)
				(type default)
			)
			(layer "B.Fab")
		)
		(fp_line
			(start 0.94996 134.325106)
			(end 0.94996 -7.675118)
			(stroke
				(width 0.1)
				(type default)
			)
			(layer "B.Fab")
		)
		(fp_line
			(start -5.5499 134.325106)
			(end 0.94996 134.325106)
			(stroke
				(width 0.1)
				(type default)
			)
			(layer "B.Fab")
		)
		(fp_poly
			(pts
				(xy 2.984246 -0.461264) (xy 2.984246 0.554736) (xy 1.714246 0.046736)
			)
			(stroke
				(width 0)
				(type default)
			)
			(fill yes)
			(layer "B.Fab")
		)
		(fp_text user "145"
			(at -6.105652 1.288542 0)
			(unlocked yes)
			(layer "B.SilkS")
			(effects
				(font
					(size 0.7874 0.5842)
					(thickness 0.1524)
				)
				(justify left mirror)
			)
		)
		(fp_text user "77"
			(at 0.752348 66.439542 0)
			(unlocked yes)
			(layer "B.SilkS")
			(effects
				(font
					(size 0.7874 0.5842)
					(thickness 0.1524)
				)
				(justify left mirror)
			)
		)
		(fp_text user "221"
			(at -5.597652 67.201542 0)
			(unlocked yes)
			(layer "B.SilkS")
			(effects
				(font
					(size 0.7874 0.5842)
					(thickness 0.1524)
				)
				(justify left mirror)
			)
		)
		(fp_text user "78"
			(at 1.514348 71.138542 0)
			(unlocked yes)
			(layer "B.SilkS")
			(effects
				(font
					(size 0.7874 0.5842)
					(thickness 0.1524)
				)
				(justify left mirror)
			)
		)
		(fp_text user "222"
			(at -6.105652 71.900542 0)
			(unlocked yes)
			(layer "B.SilkS")
			(effects
				(font
					(size 0.7874 0.5842)
					(thickness 0.1524)
				)
				(justify left mirror)
			)
		)
		(fp_text user "144"
			(at 1.641348 129.812542 0)
			(unlocked yes)
			(layer "B.SilkS")
			(effects
				(font
					(size 0.7874 0.5842)
					(thickness 0.1524)
				)
				(justify left mirror)
			)
		)
		(fp_text user "288"
			(at -6.232652 129.812542 0)
			(unlocked yes)
			(layer "B.SilkS")
			(effects
				(font
					(size 0.7874 0.5842)
					(thickness 0.1524)
				)
				(justify left mirror)
			)
		)
		(fp_text user "145"
			(at -3.157982 -1.478788 90)
			(unlocked yes)
			(layer "B.Fab")
			(effects
				(font
					(size 0.7874 0.5842)
					(thickness 0.1524)
				)
				(justify left mirror)
			)
		)
		(fp_text user "77"
			(at 0.652018 65.831212 90)
			(unlocked yes)
			(layer "B.Fab")
			(effects
				(font
					(size 0.7874 0.5842)
					(thickness 0.1524)
				)
				(justify left mirror)
			)
		)
		(fp_text user "221"
			(at -3.157982 65.831212 90)
			(unlocked yes)
			(layer "B.Fab")
			(effects
				(font
					(size 0.7874 0.5842)
					(thickness 0.1524)
				)
				(justify left mirror)
			)
		)
		(fp_text user "78"
			(at 0.652018 69.641212 90)
			(unlocked yes)
			(layer "B.Fab")
			(effects
				(font
					(size 0.7874 0.5842)
					(thickness 0.1524)
				)
				(justify left mirror)
			)
		)
		(fp_text user "222"
			(at -3.792982 69.641212 90)
			(unlocked yes)
			(layer "B.Fab")
			(effects
				(font
					(size 0.7874 0.5842)
					(thickness 0.1524)
				)
				(justify left mirror)
			)
		)
		(fp_text user "144"
			(at 0.652018 128.061212 90)
			(unlocked yes)
			(layer "B.Fab")
			(effects
				(font
					(size 0.7874 0.5842)
					(thickness 0.1524)
				)
				(justify left mirror)
			)
		)
		(fp_text user "288"
			(at -3.157982 128.061212 90)
			(unlocked yes)
			(layer "B.Fab")
			(effects
				(font
					(size 0.7874 0.5842)
					(thickness 0.1524)
				)
				(justify left mirror)
			)
		)
		(pad "" thru_hole circle
			(at -2.29997 -5.649976 270)
			(size 2.8194 2.8194)
			(drill 2.4384)
			(layers "*.Cu" "*.Mask")
			(remove_unused_layers no)
			(clearance 0.127)
			(thermal_gap 0.127)
		)
		(pad "" thru_hole oval
			(at -2.29997 68.90004 270)
			(size 2.8194 1.5748)
			(drill oval 2.4384 1.1938)
			(layers "*.Cu" "*.Mask")
			(remove_unused_layers no)
			(clearance 0.127)
			(thermal_gap 0.127)
		)
		(pad "" thru_hole circle
			(at -2.29997 132.299964 270)
			(size 2.8194 2.8194)
			(drill 2.4384)
			(layers "*.Cu" "*.Mask")
			(remove_unused_layers no)
			(clearance 0.127)
			(thermal_gap 0.127)
		)
		(pad "1" smd rect
			(at 0 0 270)
			(size 1.8034 0.508)
			(layers "B.Cu" "B.Mask" "B.Paste")
			(net "P12V_NVDIMM_GHJ")
		)
		(pad "2" smd rect
			(at 0 0.849884 270)
			(size 1.8034 0.508)
			(layers "B.Cu" "B.Mask" "B.Paste")
			(net "GND")
		)
		(pad "3" smd rect
			(at 0 1.700022 270)
			(size 1.8034 0.508)
			(layers "B.Cu" "B.Mask" "B.Paste")
			(net "M_H_DQ<4>")
		)
		(pad "4" smd rect
			(at 0 2.549906 270)
			(size 1.8034 0.508)
			(layers "B.Cu" "B.Mask" "B.Paste")
			(net "GND")
		)
		(pad "5" smd rect
			(at 0 3.400044 270)
			(size 1.8034 0.508)
			(layers "B.Cu" "B.Mask" "B.Paste")
			(net "M_H_DQ<0>")
		)
		(pad "6" smd rect
			(at 0 4.249928 270)
			(size 1.8034 0.508)
			(layers "B.Cu" "B.Mask" "B.Paste")
			(net "GND")
		)
		(pad "7" smd rect
			(at 0 5.100066 270)
			(size 1.8034 0.508)
			(layers "B.Cu" "B.Mask" "B.Paste")
			(net "M_H_DQS_DP<9>")
		)
		(pad "8" smd rect
			(at 0 5.94995 270)
			(size 1.8034 0.508)
			(layers "B.Cu" "B.Mask" "B.Paste")
			(net "M_H_DQS_DN<9>")
		)
		(pad "9" smd rect
			(at 0 6.800088 270)
			(size 1.8034 0.508)
			(layers "B.Cu" "B.Mask" "B.Paste")
			(net "GND")
		)
		(pad "10" smd rect
			(at 0 7.649972 270)
			(size 1.8034 0.508)
			(layers "B.Cu" "B.Mask" "B.Paste")
			(net "M_H_DQ<6>")
		)
		(pad "11" smd rect
			(at 0 8.50011 270)
			(size 1.8034 0.508)
			(layers "B.Cu" "B.Mask" "B.Paste")
			(net "GND")
		)
		(pad "12" smd rect
			(at 0 9.349994 270)
			(size 1.8034 0.508)
			(layers "B.Cu" "B.Mask" "B.Paste")
			(net "M_H_DQ<2>")
		)
		(pad "13" smd rect
			(at 0 10.199878 270)
			(size 1.8034 0.508)
			(layers "B.Cu" "B.Mask" "B.Paste")
			(net "GND")
		)
		(pad "14" smd rect
			(at 0 11.050016 270)
			(size 1.8034 0.508)
			(layers "B.Cu" "B.Mask" "B.Paste")
			(net "M_H_DQ<12>")
		)
		(pad "15" smd rect
			(at 0 11.8999 270)
			(size 1.8034 0.508)
			(layers "B.Cu" "B.Mask" "B.Paste")
			(net "GND")
		)
		(pad "16" smd rect
			(at 0 12.750038 270)
			(size 1.8034 0.508)
			(layers "B.Cu" "B.Mask" "B.Paste")
			(net "M_H_DQ<8>")
		)
		(pad "17" smd rect
			(at 0 13.599922 270)
			(size 1.8034 0.508)
			(layers "B.Cu" "B.Mask" "B.Paste")
			(net "GND")
		)
		(pad "18" smd rect
			(at 0 14.45006 270)
			(size 1.8034 0.508)
			(layers "B.Cu" "B.Mask" "B.Paste")
			(net "M_H_DQS_DP<10>")
		)
		(pad "19" smd rect
			(at 0 15.299944 270)
			(size 1.8034 0.508)
			(layers "B.Cu" "B.Mask" "B.Paste")
			(net "M_H_DQS_DN<10>")
		)
		(pad "20" smd rect
			(at 0 16.150082 270)
			(size 1.8034 0.508)
			(layers "B.Cu" "B.Mask" "B.Paste")
			(net "GND")
		)
		(pad "21" smd rect
			(at 0 16.999966 270)
			(size 1.8034 0.508)
			(layers "B.Cu" "B.Mask" "B.Paste")
			(net "M_H_DQ<14>")
		)
		(pad "22" smd rect
			(at 0 17.850104 270)
			(size 1.8034 0.508)
			(layers "B.Cu" "B.Mask" "B.Paste")
			(net "GND")
		)
		(pad "23" smd rect
			(at 0 18.699988 270)
			(size 1.8034 0.508)
			(layers "B.Cu" "B.Mask" "B.Paste")
			(net "M_H_DQ<10>")
		)
		(pad "24" smd rect
			(at 0 19.550126 270)
			(size 1.8034 0.508)
			(layers "B.Cu" "B.Mask" "B.Paste")
			(net "GND")
		)
		(pad "25" smd rect
			(at 0 20.40001 270)
			(size 1.8034 0.508)
			(layers "B.Cu" "B.Mask" "B.Paste")
			(net "M_H_DQ<20>")
		)
		(pad "26" smd rect
			(at 0 21.249894 270)
			(size 1.8034 0.508)
			(layers "B.Cu" "B.Mask" "B.Paste")
			(net "GND")
		)
		(pad "27" smd rect
			(at 0 22.100032 270)
			(size 1.8034 0.508)
			(layers "B.Cu" "B.Mask" "B.Paste")
			(net "M_H_DQ<16>")
		)
		(pad "28" smd rect
			(at 0 22.949916 270)
			(size 1.8034 0.508)
			(layers "B.Cu" "B.Mask" "B.Paste")
			(net "GND")
		)
		(pad "29" smd rect
			(at 0 23.800054 270)
			(size 1.8034 0.508)
			(layers "B.Cu" "B.Mask" "B.Paste")
			(net "M_H_DQS_DP<11>")
		)
		(pad "30" smd rect
			(at 0 24.649938 270)
			(size 1.8034 0.508)
			(layers "B.Cu" "B.Mask" "B.Paste")
			(net "M_H_DQS_DN<11>")
		)
		(pad "31" smd rect
			(at 0 25.500076 270)
			(size 1.8034 0.508)
			(layers "B.Cu" "B.Mask" "B.Paste")
			(net "GND")
		)
		(pad "32" smd rect
			(at 0 26.34996 270)
			(size 1.8034 0.508)
			(layers "B.Cu" "B.Mask" "B.Paste")
			(net "M_H_DQ<22>")
		)
		(pad "33" smd rect
			(at 0 27.200098 270)
			(size 1.8034 0.508)
			(layers "B.Cu" "B.Mask" "B.Paste")
			(net "GND")
		)
		(pad "34" smd rect
			(at 0 28.049982 270)
			(size 1.8034 0.508)
			(layers "B.Cu" "B.Mask" "B.Paste")
			(net "M_H_DQ<18>")
		)
		(pad "35" smd rect
			(at 0 28.90012 270)
			(size 1.8034 0.508)
			(layers "B.Cu" "B.Mask" "B.Paste")
			(net "GND")
		)
		(pad "36" smd rect
			(at 0 29.750004 270)
			(size 1.8034 0.508)
			(layers "B.Cu" "B.Mask" "B.Paste")
			(net "M_H_DQ<28>")
		)
		(pad "37" smd rect
			(at 0 30.599888 270)
			(size 1.8034 0.508)
			(layers "B.Cu" "B.Mask" "B.Paste")
			(net "GND")
		)
		(pad "38" smd rect
			(at 0 31.450026 270)
			(size 1.8034 0.508)
			(layers "B.Cu" "B.Mask" "B.Paste")
			(net "M_H_DQ<24>")
		)
		(pad "39" smd rect
			(at 0 32.29991 270)
			(size 1.8034 0.508)
			(layers "B.Cu" "B.Mask" "B.Paste")
			(net "GND")
		)
		(pad "40" smd rect
			(at 0 33.150048 270)
			(size 1.8034 0.508)
			(layers "B.Cu" "B.Mask" "B.Paste")
			(net "M_H_DQS_DP<12>")
		)
		(pad "41" smd rect
			(at 0 33.999932 270)
			(size 1.8034 0.508)
			(layers "B.Cu" "B.Mask" "B.Paste")
			(net "M_H_DQS_DN<12>")
		)
		(pad "42" smd rect
			(at 0 34.85007 270)
			(size 1.8034 0.508)
			(layers "B.Cu" "B.Mask" "B.Paste")
			(net "GND")
		)
		(pad "43" smd rect
			(at 0 35.699954 270)
			(size 1.8034 0.508)
			(layers "B.Cu" "B.Mask" "B.Paste")
			(net "M_H_DQ<30>")
		)
		(pad "44" smd rect
			(at 0 36.550092 270)
			(size 1.8034 0.508)
			(layers "B.Cu" "B.Mask" "B.Paste")
			(net "GND")
		)
		(pad "45" smd rect
			(at 0 37.399976 270)
			(size 1.8034 0.508)
			(layers "B.Cu" "B.Mask" "B.Paste")
			(net "M_H_DQ<26>")
		)
		(pad "46" smd rect
			(at 0 38.250114 270)
			(size 1.8034 0.508)
			(layers "B.Cu" "B.Mask" "B.Paste")
			(net "GND")
		)
		(pad "47" smd rect
			(at 0 39.099998 270)
			(size 1.8034 0.508)
			(layers "B.Cu" "B.Mask" "B.Paste")
			(net "M_H_ECC<4>")
		)
		(pad "48" smd rect
			(at 0 39.949882 270)
			(size 1.8034 0.508)
			(layers "B.Cu" "B.Mask" "B.Paste")
			(net "GND")
		)
		(pad "49" smd rect
			(at 0 40.80002 270)
			(size 1.8034 0.508)
			(layers "B.Cu" "B.Mask" "B.Paste")
			(net "M_H_ECC<0>")
		)
		(pad "50" smd rect
			(at 0 41.649904 270)
			(size 1.8034 0.508)
			(layers "B.Cu" "B.Mask" "B.Paste")
			(net "GND")
		)
		(pad "51" smd rect
			(at 0 42.500042 270)
			(size 1.8034 0.508)
			(layers "B.Cu" "B.Mask" "B.Paste")
			(net "M_H_DQS_DP<17>")
		)
		(pad "52" smd rect
			(at 0 43.349926 270)
			(size 1.8034 0.508)
			(layers "B.Cu" "B.Mask" "B.Paste")
			(net "M_H_DQS_DN<17>")
		)
		(pad "53" smd rect
			(at 0 44.200064 270)
			(size 1.8034 0.508)
			(layers "B.Cu" "B.Mask" "B.Paste")
			(net "GND")
		)
		(pad "54" smd rect
			(at 0 45.049948 270)
			(size 1.8034 0.508)
			(layers "B.Cu" "B.Mask" "B.Paste")
			(net "M_H_ECC<6>")
		)
		(pad "55" smd rect
			(at 0 45.900086 270)
			(size 1.8034 0.508)
			(layers "B.Cu" "B.Mask" "B.Paste")
			(net "GND")
		)
		(pad "56" smd rect
			(at 0 46.74997 270)
			(size 1.8034 0.508)
			(layers "B.Cu" "B.Mask" "B.Paste")
			(net "M_H_ECC<2>")
		)
		(pad "57" smd rect
			(at 0 47.600108 270)
			(size 1.8034 0.508)
			(layers "B.Cu" "B.Mask" "B.Paste")
			(net "GND")
		)
		(pad "58" smd rect
			(at 0 48.449992 270)
			(size 1.8034 0.508)
			(layers "B.Cu" "B.Mask" "B.Paste")
			(net "M_GHJ_RST_N")
		)
		(pad "59" smd rect
			(at 0 49.299876 270)
			(size 1.8034 0.508)
			(layers "B.Cu" "B.Mask" "B.Paste")
			(net "PVDDQ_GHJ")
		)
		(pad "60" smd rect
			(at 0 50.150014 270)
			(size 1.8034 0.508)
			(layers "B.Cu" "B.Mask" "B.Paste")
			(net "M_H_CKE<2>")
		)
		(pad "61" smd rect
			(at 0 50.999898 270)
			(size 1.8034 0.508)
			(layers "B.Cu" "B.Mask" "B.Paste")
			(net "PVDDQ_GHJ")
		)
		(pad "62" smd rect
			(at 0 51.850036 270)
			(size 1.8034 0.508)
			(layers "B.Cu" "B.Mask" "B.Paste")
			(net "M_H_ACT_N")
		)
		(pad "63" smd rect
			(at 0 52.69992 270)
			(size 1.8034 0.508)
			(layers "B.Cu" "B.Mask" "B.Paste")
			(net "M_H_BG<0>")
		)
		(pad "64" smd rect
			(at 0 53.550058 270)
			(size 1.8034 0.508)
			(layers "B.Cu" "B.Mask" "B.Paste")
			(net "PVDDQ_GHJ")
		)
		(pad "65" smd rect
			(at 0 54.399942 270)
			(size 1.8034 0.508)
			(layers "B.Cu" "B.Mask" "B.Paste")
			(net "M_H_MA<12>")
		)
		(pad "66" smd rect
			(at 0 55.25008 270)
			(size 1.8034 0.508)
			(layers "B.Cu" "B.Mask" "B.Paste")
			(net "M_H_MA<9>")
		)
		(pad "67" smd rect
			(at 0 56.099964 270)
			(size 1.8034 0.508)
			(layers "B.Cu" "B.Mask" "B.Paste")
			(net "PVDDQ_GHJ")
		)
		(pad "68" smd rect
			(at 0 56.950102 270)
			(size 1.8034 0.508)
			(layers "B.Cu" "B.Mask" "B.Paste")
			(net "M_H_MA<8>")
		)
		(pad "69" smd rect
			(at 0 57.799986 270)
			(size 1.8034 0.508)
			(layers "B.Cu" "B.Mask" "B.Paste")
			(net "M_H_MA<6>")
		)
		(pad "70" smd rect
			(at 0 58.650124 270)
			(size 1.8034 0.508)
			(layers "B.Cu" "B.Mask" "B.Paste")
			(net "PVDDQ_GHJ")
		)
		(pad "71" smd rect
			(at 0 59.500008 270)
			(size 1.8034 0.508)
			(layers "B.Cu" "B.Mask" "B.Paste")
			(net "M_H_MA<3>")
		)
		(pad "72" smd rect
			(at 0 60.349892 270)
			(size 1.8034 0.508)
			(layers "B.Cu" "B.Mask" "B.Paste")
			(net "M_H_MA<1>")
		)
		(pad "73" smd rect
			(at 0 61.20003 270)
			(size 1.8034 0.508)
			(layers "B.Cu" "B.Mask" "B.Paste")
			(net "PVDDQ_GHJ")
		)
		(pad "74" smd rect
			(at 0 62.049914 270)
			(size 1.8034 0.508)
			(layers "B.Cu" "B.Mask" "B.Paste")
			(net "M_H_CLK_DP<2>")
		)
		(pad "75" smd rect
			(at 0 62.900052 270)
			(size 1.8034 0.508)
			(layers "B.Cu" "B.Mask" "B.Paste")
			(net "M_H_CLK_DN<2>")
		)
		(pad "76" smd rect
			(at 0 63.749936 270)
			(size 1.8034 0.508)
			(layers "B.Cu" "B.Mask" "B.Paste")
			(net "PVDDQ_GHJ")
		)
		(pad "77" smd rect
			(at 0 64.600074 270)
			(size 1.8034 0.508)
			(layers "B.Cu" "B.Mask" "B.Paste")
			(net "PVTT_GHJ")
		)
		(pad "78" smd rect
			(at 0 70.550024 270)
			(size 1.8034 0.508)
			(layers "B.Cu" "B.Mask" "B.Paste")
			(net "FM_DIMM_EVENT_COD_N")
		)
		(pad "79" smd rect
			(at 0 71.399908 270)
			(size 1.8034 0.508)
			(layers "B.Cu" "B.Mask" "B.Paste")
			(net "M_H_MA<0>")
		)
		(pad "80" smd rect
			(at 0 72.250046 270)
			(size 1.8034 0.508)
			(layers "B.Cu" "B.Mask" "B.Paste")
			(net "PVDDQ_GHJ")
		)
		(pad "81" smd rect
			(at 0 73.09993 270)
			(size 1.8034 0.508)
			(layers "B.Cu" "B.Mask" "B.Paste")
			(net "M_H_BA<0>")
		)
		(pad "82" smd rect
			(at 0 73.950068 270)
			(size 1.8034 0.508)
			(layers "B.Cu" "B.Mask" "B.Paste")
			(net "M_H_MA<16>")
		)
		(pad "83" smd rect
			(at 0 74.799952 270)
			(size 1.8034 0.508)
			(layers "B.Cu" "B.Mask" "B.Paste")
			(net "PVDDQ_GHJ")
		)
		(pad "84" smd rect
			(at 0 75.65009 270)
			(size 1.8034 0.508)
			(layers "B.Cu" "B.Mask" "B.Paste")
			(net "M_H_CS_N<4>")
		)
		(pad "85" smd rect
			(at 0 76.499974 270)
			(size 1.8034 0.508)
			(layers "B.Cu" "B.Mask" "B.Paste")
			(net "PVDDQ_GHJ")
		)
		(pad "86" smd rect
			(at 0 77.350112 270)
			(size 1.8034 0.508)
			(layers "B.Cu" "B.Mask" "B.Paste")
			(net "M_H_MA<15>")
		)
		(pad "87" smd rect
			(at 0 78.199996 270)
			(size 1.8034 0.508)
			(layers "B.Cu" "B.Mask" "B.Paste")
			(net "M_H_ODT<2>")
		)
		(pad "88" smd rect
			(at 0 79.04988 270)
			(size 1.8034 0.508)
			(layers "B.Cu" "B.Mask" "B.Paste")
			(net "PVDDQ_GHJ")
		)
		(pad "89" smd rect
			(at 0 79.900018 270)
			(size 1.8034 0.508)
			(layers "B.Cu" "B.Mask" "B.Paste")
			(net "M_H_CS_N<5>")
		)
		(pad "90" smd rect
			(at 0 80.749902 270)
			(size 1.8034 0.508)
			(layers "B.Cu" "B.Mask" "B.Paste")
			(net "PVDDQ_GHJ")
		)
		(pad "91" smd rect
			(at 0 81.60004 270)
			(size 1.8034 0.508)
			(layers "B.Cu" "B.Mask" "B.Paste")
			(net "M_H_ODT<3>")
		)
		(pad "92" smd rect
			(at 0 82.449924 270)
			(size 1.8034 0.508)
			(layers "B.Cu" "B.Mask" "B.Paste")
			(net "PVDDQ_GHJ")
		)
		(pad "93" smd rect
			(at 0 83.300062 270)
			(size 1.8034 0.508)
			(layers "B.Cu" "B.Mask" "B.Paste")
			(net "M_H_CS_N<6>")
		)
		(pad "94" smd rect
			(at 0 84.149946 270)
			(size 1.8034 0.508)
			(layers "B.Cu" "B.Mask" "B.Paste")
			(net "GND")
		)
		(pad "95" smd rect
			(at 0 85.000084 270)
			(size 1.8034 0.508)
			(layers "B.Cu" "B.Mask" "B.Paste")
			(net "M_H_DQ<36>")
		)
		(pad "96" smd rect
			(at 0 85.849968 270)
			(size 1.8034 0.508)
			(layers "B.Cu" "B.Mask" "B.Paste")
			(net "GND")
		)
		(pad "97" smd rect
			(at 0 86.700106 270)
			(size 1.8034 0.508)
			(layers "B.Cu" "B.Mask" "B.Paste")
			(net "M_H_DQ<32>")
		)
		(pad "98" smd rect
			(at 0 87.54999 270)
			(size 1.8034 0.508)
			(layers "B.Cu" "B.Mask" "B.Paste")
			(net "GND")
		)
		(pad "99" smd rect
			(at 0 88.399874 270)
			(size 1.8034 0.508)
			(layers "B.Cu" "B.Mask" "B.Paste")
			(net "M_H_DQS_DP<13>")
		)
		(pad "100" smd rect
			(at 0 89.250012 270)
			(size 1.8034 0.508)
			(layers "B.Cu" "B.Mask" "B.Paste")
			(net "M_H_DQS_DN<13>")
		)
		(pad "101" smd rect
			(at 0 90.099896 270)
			(size 1.8034 0.508)
			(layers "B.Cu" "B.Mask" "B.Paste")
			(net "GND")
		)
		(pad "102" smd rect
			(at 0 90.950034 270)
			(size 1.8034 0.508)
			(layers "B.Cu" "B.Mask" "B.Paste")
			(net "M_H_DQ<38>")
		)
		(pad "103" smd rect
			(at 0 91.799918 270)
			(size 1.8034 0.508)
			(layers "B.Cu" "B.Mask" "B.Paste")
			(net "GND")
		)
		(pad "104" smd rect
			(at 0 92.650056 270)
			(size 1.8034 0.508)
			(layers "B.Cu" "B.Mask" "B.Paste")
			(net "M_H_DQ<34>")
		)
		(pad "105" smd rect
			(at 0 93.49994 270)
			(size 1.8034 0.508)
			(layers "B.Cu" "B.Mask" "B.Paste")
			(net "GND")
		)
		(pad "106" smd rect
			(at 0 94.350078 270)
			(size 1.8034 0.508)
			(layers "B.Cu" "B.Mask" "B.Paste")
			(net "M_H_DQ<44>")
		)
		(pad "107" smd rect
			(at 0 95.199962 270)
			(size 1.8034 0.508)
			(layers "B.Cu" "B.Mask" "B.Paste")
			(net "GND")
		)
		(pad "108" smd rect
			(at 0 96.0501 270)
			(size 1.8034 0.508)
			(layers "B.Cu" "B.Mask" "B.Paste")
			(net "M_H_DQ<40>")
		)
		(pad "109" smd rect
			(at 0 96.899984 270)
			(size 1.8034 0.508)
			(layers "B.Cu" "B.Mask" "B.Paste")
			(net "GND")
		)
		(pad "110" smd rect
			(at 0 97.750122 270)
			(size 1.8034 0.508)
			(layers "B.Cu" "B.Mask" "B.Paste")
			(net "M_H_DQS_DP<14>")
		)
		(pad "111" smd rect
			(at 0 98.600006 270)
			(size 1.8034 0.508)
			(layers "B.Cu" "B.Mask" "B.Paste")
			(net "M_H_DQS_DN<14>")
		)
		(pad "112" smd rect
			(at 0 99.44989 270)
			(size 1.8034 0.508)
			(layers "B.Cu" "B.Mask" "B.Paste")
			(net "GND")
		)
		(pad "113" smd rect
			(at 0 100.300028 270)
			(size 1.8034 0.508)
			(layers "B.Cu" "B.Mask" "B.Paste")
			(net "M_H_DQ<46>")
		)
		(pad "114" smd rect
			(at 0 101.149912 270)
			(size 1.8034 0.508)
			(layers "B.Cu" "B.Mask" "B.Paste")
			(net "GND")
		)
		(pad "115" smd rect
			(at 0 102.00005 270)
			(size 1.8034 0.508)
			(layers "B.Cu" "B.Mask" "B.Paste")
			(net "M_H_DQ<42>")
		)
		(pad "116" smd rect
			(at 0 102.849934 270)
			(size 1.8034 0.508)
			(layers "B.Cu" "B.Mask" "B.Paste")
			(net "GND")
		)
		(pad "117" smd rect
			(at 0 103.700072 270)
			(size 1.8034 0.508)
			(layers "B.Cu" "B.Mask" "B.Paste")
			(net "M_H_DQ<52>")
		)
		(pad "118" smd rect
			(at 0 104.549956 270)
			(size 1.8034 0.508)
			(layers "B.Cu" "B.Mask" "B.Paste")
			(net "GND")
		)
		(pad "119" smd rect
			(at 0 105.400094 270)
			(size 1.8034 0.508)
			(layers "B.Cu" "B.Mask" "B.Paste")
			(net "M_H_DQ<48>")
		)
		(pad "120" smd rect
			(at 0 106.249978 270)
			(size 1.8034 0.508)
			(layers "B.Cu" "B.Mask" "B.Paste")
			(net "GND")
		)
		(pad "121" smd rect
			(at 0 107.100116 270)
			(size 1.8034 0.508)
			(layers "B.Cu" "B.Mask" "B.Paste")
			(net "M_H_DQS_DP<15>")
		)
		(pad "122" smd rect
			(at 0 107.95 270)
			(size 1.8034 0.508)
			(layers "B.Cu" "B.Mask" "B.Paste")
			(net "M_H_DQS_DN<15>")
		)
		(pad "123" smd rect
			(at 0 108.799884 270)
			(size 1.8034 0.508)
			(layers "B.Cu" "B.Mask" "B.Paste")
			(net "GND")
		)
		(pad "124" smd rect
			(at 0 109.650022 270)
			(size 1.8034 0.508)
			(layers "B.Cu" "B.Mask" "B.Paste")
			(net "M_H_DQ<54>")
		)
		(pad "125" smd rect
			(at 0 110.499906 270)
			(size 1.8034 0.508)
			(layers "B.Cu" "B.Mask" "B.Paste")
			(net "GND")
		)
		(pad "126" smd rect
			(at 0 111.350044 270)
			(size 1.8034 0.508)
			(layers "B.Cu" "B.Mask" "B.Paste")
			(net "M_H_DQ<50>")
		)
		(pad "127" smd rect
			(at 0 112.199928 270)
			(size 1.8034 0.508)
			(layers "B.Cu" "B.Mask" "B.Paste")
			(net "GND")
		)
		(pad "128" smd rect
			(at 0 113.050066 270)
			(size 1.8034 0.508)
			(layers "B.Cu" "B.Mask" "B.Paste")
			(net "M_H_DQ<60>")
		)
		(pad "129" smd rect
			(at 0 113.89995 270)
			(size 1.8034 0.508)
			(layers "B.Cu" "B.Mask" "B.Paste")
			(net "GND")
		)
		(pad "130" smd rect
			(at 0 114.750088 270)
			(size 1.8034 0.508)
			(layers "B.Cu" "B.Mask" "B.Paste")
			(net "M_H_DQ<56>")
		)
		(pad "131" smd rect
			(at 0 115.599972 270)
			(size 1.8034 0.508)
			(layers "B.Cu" "B.Mask" "B.Paste")
			(net "GND")
		)
		(pad "132" smd rect
			(at 0 116.45011 270)
			(size 1.8034 0.508)
			(layers "B.Cu" "B.Mask" "B.Paste")
			(net "M_H_DQS_DP<16>")
		)
		(pad "133" smd rect
			(at 0 117.299994 270)
			(size 1.8034 0.508)
			(layers "B.Cu" "B.Mask" "B.Paste")
			(net "M_H_DQS_DN<16>")
		)
		(pad "134" smd rect
			(at 0 118.149878 270)
			(size 1.8034 0.508)
			(layers "B.Cu" "B.Mask" "B.Paste")
			(net "GND")
		)
		(pad "135" smd rect
			(at 0 119.000016 270)
			(size 1.8034 0.508)
			(layers "B.Cu" "B.Mask" "B.Paste")
			(net "M_H_DQ<62>")
		)
		(pad "136" smd rect
			(at 0 119.8499 270)
			(size 1.8034 0.508)
			(layers "B.Cu" "B.Mask" "B.Paste")
			(net "GND")
		)
		(pad "137" smd rect
			(at 0 120.700038 270)
			(size 1.8034 0.508)
			(layers "B.Cu" "B.Mask" "B.Paste")
			(net "M_H_DQ<58>")
		)
		(pad "138" smd rect
			(at 0 121.549922 270)
			(size 1.8034 0.508)
			(layers "B.Cu" "B.Mask" "B.Paste")
			(net "GND")
		)
		(pad "139" smd rect
			(at 0 122.40006 270)
			(size 1.8034 0.508)
			(layers "B.Cu" "B.Mask" "B.Paste")
			(net "PVPP_GHJ")
		)
		(pad "140" smd rect
			(at 0 123.249944 270)
			(size 1.8034 0.508)
			(layers "B.Cu" "B.Mask" "B.Paste")
			(net "PVPP_GHJ")
		)
		(pad "141" smd rect
			(at 0 124.100082 270)
			(size 1.8034 0.508)
			(layers "B.Cu" "B.Mask" "B.Paste")
			(net "SMB_DDR_GHJ_VPP_SCL")
		)
		(pad "142" smd rect
			(at 0 124.949966 270)
			(size 1.8034 0.508)
			(layers "B.Cu" "B.Mask" "B.Paste")
			(net "PVPP_GHJ")
		)
		(pad "143" smd rect
			(at 0 125.800104 270)
			(size 1.8034 0.508)
			(layers "B.Cu" "B.Mask" "B.Paste")
			(net "PVPP_GHJ")
		)
		(pad "144" smd rect
			(at 0 126.649988 270)
			(size 1.8034 0.508)
			(layers "B.Cu" "B.Mask" "B.Paste")
			(net "TP_CH_H_DIMM0_RFU_2")
		)
		(pad "145" smd rect
			(at -4.59994 0 270)
			(size 1.8034 0.508)
			(layers "B.Cu" "B.Mask" "B.Paste")
			(net "P12V_NVDIMM_GHJ")
		)
		(pad "146" smd rect
			(at -4.59994 0.849884 270)
			(size 1.8034 0.508)
			(layers "B.Cu" "B.Mask" "B.Paste")
			(net "M_H_VREF")
		)
		(pad "147" smd rect
			(at -4.59994 1.700022 270)
			(size 1.8034 0.508)
			(layers "B.Cu" "B.Mask" "B.Paste")
			(net "GND")
		)
		(pad "148" smd rect
			(at -4.59994 2.549906 270)
			(size 1.8034 0.508)
			(layers "B.Cu" "B.Mask" "B.Paste")
			(net "M_H_DQ<5>")
		)
		(pad "149" smd rect
			(at -4.59994 3.400044 270)
			(size 1.8034 0.508)
			(layers "B.Cu" "B.Mask" "B.Paste")
			(net "GND")
		)
		(pad "150" smd rect
			(at -4.59994 4.249928 270)
			(size 1.8034 0.508)
			(layers "B.Cu" "B.Mask" "B.Paste")
			(net "M_H_DQ<1>")
		)
		(pad "151" smd rect
			(at -4.59994 5.100066 270)
			(size 1.8034 0.508)
			(layers "B.Cu" "B.Mask" "B.Paste")
			(net "GND")
		)
		(pad "152" smd rect
			(at -4.59994 5.94995 270)
			(size 1.8034 0.508)
			(layers "B.Cu" "B.Mask" "B.Paste")
			(net "M_H_DQS_DN<0>")
		)
		(pad "153" smd rect
			(at -4.59994 6.800088 270)
			(size 1.8034 0.508)
			(layers "B.Cu" "B.Mask" "B.Paste")
			(net "M_H_DQS_DP<0>")
		)
		(pad "154" smd rect
			(at -4.59994 7.649972 270)
			(size 1.8034 0.508)
			(layers "B.Cu" "B.Mask" "B.Paste")
			(net "GND")
		)
		(pad "155" smd rect
			(at -4.59994 8.50011 270)
			(size 1.8034 0.508)
			(layers "B.Cu" "B.Mask" "B.Paste")
			(net "M_H_DQ<7>")
		)
		(pad "156" smd rect
			(at -4.59994 9.349994 270)
			(size 1.8034 0.508)
			(layers "B.Cu" "B.Mask" "B.Paste")
			(net "GND")
		)
		(pad "157" smd rect
			(at -4.59994 10.199878 270)
			(size 1.8034 0.508)
			(layers "B.Cu" "B.Mask" "B.Paste")
			(net "M_H_DQ<3>")
		)
		(pad "158" smd rect
			(at -4.59994 11.050016 270)
			(size 1.8034 0.508)
			(layers "B.Cu" "B.Mask" "B.Paste")
			(net "GND")
		)
		(pad "159" smd rect
			(at -4.59994 11.8999 270)
			(size 1.8034 0.508)
			(layers "B.Cu" "B.Mask" "B.Paste")
			(net "M_H_DQ<13>")
		)
		(pad "160" smd rect
			(at -4.59994 12.750038 270)
			(size 1.8034 0.508)
			(layers "B.Cu" "B.Mask" "B.Paste")
			(net "GND")
		)
		(pad "161" smd rect
			(at -4.59994 13.599922 270)
			(size 1.8034 0.508)
			(layers "B.Cu" "B.Mask" "B.Paste")
			(net "M_H_DQ<9>")
		)
		(pad "162" smd rect
			(at -4.59994 14.45006 270)
			(size 1.8034 0.508)
			(layers "B.Cu" "B.Mask" "B.Paste")
			(net "GND")
		)
		(pad "163" smd rect
			(at -4.59994 15.299944 270)
			(size 1.8034 0.508)
			(layers "B.Cu" "B.Mask" "B.Paste")
			(net "M_H_DQS_DN<1>")
		)
		(pad "164" smd rect
			(at -4.59994 16.150082 270)
			(size 1.8034 0.508)
			(layers "B.Cu" "B.Mask" "B.Paste")
			(net "M_H_DQS_DP<1>")
		)
		(pad "165" smd rect
			(at -4.59994 16.999966 270)
			(size 1.8034 0.508)
			(layers "B.Cu" "B.Mask" "B.Paste")
			(net "GND")
		)
		(pad "166" smd rect
			(at -4.59994 17.850104 270)
			(size 1.8034 0.508)
			(layers "B.Cu" "B.Mask" "B.Paste")
			(net "M_H_DQ<15>")
		)
		(pad "167" smd rect
			(at -4.59994 18.699988 270)
			(size 1.8034 0.508)
			(layers "B.Cu" "B.Mask" "B.Paste")
			(net "GND")
		)
		(pad "168" smd rect
			(at -4.59994 19.550126 270)
			(size 1.8034 0.508)
			(layers "B.Cu" "B.Mask" "B.Paste")
			(net "M_H_DQ<11>")
		)
		(pad "169" smd rect
			(at -4.59994 20.40001 270)
			(size 1.8034 0.508)
			(layers "B.Cu" "B.Mask" "B.Paste")
			(net "GND")
		)
		(pad "170" smd rect
			(at -4.59994 21.249894 270)
			(size 1.8034 0.508)
			(layers "B.Cu" "B.Mask" "B.Paste")
			(net "M_H_DQ<21>")
		)
		(pad "171" smd rect
			(at -4.59994 22.100032 270)
			(size 1.8034 0.508)
			(layers "B.Cu" "B.Mask" "B.Paste")
			(net "GND")
		)
		(pad "172" smd rect
			(at -4.59994 22.949916 270)
			(size 1.8034 0.508)
			(layers "B.Cu" "B.Mask" "B.Paste")
			(net "M_H_DQ<17>")
		)
		(pad "173" smd rect
			(at -4.59994 23.800054 270)
			(size 1.8034 0.508)
			(layers "B.Cu" "B.Mask" "B.Paste")
			(net "GND")
		)
		(pad "174" smd rect
			(at -4.59994 24.649938 270)
			(size 1.8034 0.508)
			(layers "B.Cu" "B.Mask" "B.Paste")
			(net "M_H_DQS_DN<2>")
		)
		(pad "175" smd rect
			(at -4.59994 25.500076 270)
			(size 1.8034 0.508)
			(layers "B.Cu" "B.Mask" "B.Paste")
			(net "M_H_DQS_DP<2>")
		)
		(pad "176" smd rect
			(at -4.59994 26.34996 270)
			(size 1.8034 0.508)
			(layers "B.Cu" "B.Mask" "B.Paste")
			(net "GND")
		)
		(pad "177" smd rect
			(at -4.59994 27.200098 270)
			(size 1.8034 0.508)
			(layers "B.Cu" "B.Mask" "B.Paste")
			(net "M_H_DQ<23>")
		)
		(pad "178" smd rect
			(at -4.59994 28.049982 270)
			(size 1.8034 0.508)
			(layers "B.Cu" "B.Mask" "B.Paste")
			(net "GND")
		)
		(pad "179" smd rect
			(at -4.59994 28.90012 270)
			(size 1.8034 0.508)
			(layers "B.Cu" "B.Mask" "B.Paste")
			(net "M_H_DQ<19>")
		)
		(pad "180" smd rect
			(at -4.59994 29.750004 270)
			(size 1.8034 0.508)
			(layers "B.Cu" "B.Mask" "B.Paste")
			(net "GND")
		)
		(pad "181" smd rect
			(at -4.59994 30.599888 270)
			(size 1.8034 0.508)
			(layers "B.Cu" "B.Mask" "B.Paste")
			(net "M_H_DQ<29>")
		)
		(pad "182" smd rect
			(at -4.59994 31.450026 270)
			(size 1.8034 0.508)
			(layers "B.Cu" "B.Mask" "B.Paste")
			(net "GND")
		)
		(pad "183" smd rect
			(at -4.59994 32.29991 270)
			(size 1.8034 0.508)
			(layers "B.Cu" "B.Mask" "B.Paste")
			(net "M_H_DQ<25>")
		)
		(pad "184" smd rect
			(at -4.59994 33.150048 270)
			(size 1.8034 0.508)
			(layers "B.Cu" "B.Mask" "B.Paste")
			(net "GND")
		)
		(pad "185" smd rect
			(at -4.59994 33.999932 270)
			(size 1.8034 0.508)
			(layers "B.Cu" "B.Mask" "B.Paste")
			(net "M_H_DQS_DN<3>")
		)
		(pad "186" smd rect
			(at -4.59994 34.85007 270)
			(size 1.8034 0.508)
			(layers "B.Cu" "B.Mask" "B.Paste")
			(net "M_H_DQS_DP<3>")
		)
		(pad "187" smd rect
			(at -4.59994 35.699954 270)
			(size 1.8034 0.508)
			(layers "B.Cu" "B.Mask" "B.Paste")
			(net "GND")
		)
		(pad "188" smd rect
			(at -4.59994 36.550092 270)
			(size 1.8034 0.508)
			(layers "B.Cu" "B.Mask" "B.Paste")
			(net "M_H_DQ<31>")
		)
		(pad "189" smd rect
			(at -4.59994 37.399976 270)
			(size 1.8034 0.508)
			(layers "B.Cu" "B.Mask" "B.Paste")
			(net "GND")
		)
		(pad "190" smd rect
			(at -4.59994 38.250114 270)
			(size 1.8034 0.508)
			(layers "B.Cu" "B.Mask" "B.Paste")
			(net "M_H_DQ<27>")
		)
		(pad "191" smd rect
			(at -4.59994 39.099998 270)
			(size 1.8034 0.508)
			(layers "B.Cu" "B.Mask" "B.Paste")
			(net "GND")
		)
		(pad "192" smd rect
			(at -4.59994 39.949882 270)
			(size 1.8034 0.508)
			(layers "B.Cu" "B.Mask" "B.Paste")
			(net "M_H_ECC<5>")
		)
		(pad "193" smd rect
			(at -4.59994 40.80002 270)
			(size 1.8034 0.508)
			(layers "B.Cu" "B.Mask" "B.Paste")
			(net "GND")
		)
		(pad "194" smd rect
			(at -4.59994 41.649904 270)
			(size 1.8034 0.508)
			(layers "B.Cu" "B.Mask" "B.Paste")
			(net "M_H_ECC<1>")
		)
		(pad "195" smd rect
			(at -4.59994 42.500042 270)
			(size 1.8034 0.508)
			(layers "B.Cu" "B.Mask" "B.Paste")
			(net "GND")
		)
		(pad "196" smd rect
			(at -4.59994 43.349926 270)
			(size 1.8034 0.508)
			(layers "B.Cu" "B.Mask" "B.Paste")
			(net "M_H_DQS_DN<8>")
		)
		(pad "197" smd rect
			(at -4.59994 44.200064 270)
			(size 1.8034 0.508)
			(layers "B.Cu" "B.Mask" "B.Paste")
			(net "M_H_DQS_DP<8>")
		)
		(pad "198" smd rect
			(at -4.59994 45.049948 270)
			(size 1.8034 0.508)
			(layers "B.Cu" "B.Mask" "B.Paste")
			(net "GND")
		)
		(pad "199" smd rect
			(at -4.59994 45.900086 270)
			(size 1.8034 0.508)
			(layers "B.Cu" "B.Mask" "B.Paste")
			(net "M_H_ECC<7>")
		)
		(pad "200" smd rect
			(at -4.59994 46.74997 270)
			(size 1.8034 0.508)
			(layers "B.Cu" "B.Mask" "B.Paste")
			(net "GND")
		)
		(pad "201" smd rect
			(at -4.59994 47.600108 270)
			(size 1.8034 0.508)
			(layers "B.Cu" "B.Mask" "B.Paste")
			(net "M_H_ECC<3>")
		)
		(pad "202" smd rect
			(at -4.59994 48.449992 270)
			(size 1.8034 0.508)
			(layers "B.Cu" "B.Mask" "B.Paste")
			(net "GND")
		)
		(pad "203" smd rect
			(at -4.59994 49.299876 270)
			(size 1.8034 0.508)
			(layers "B.Cu" "B.Mask" "B.Paste")
			(net "M_H_CKE<3>")
		)
		(pad "204" smd rect
			(at -4.59994 50.150014 270)
			(size 1.8034 0.508)
			(layers "B.Cu" "B.Mask" "B.Paste")
			(net "PVDDQ_GHJ")
		)
		(pad "205" smd rect
			(at -4.59994 50.999898 270)
			(size 1.8034 0.508)
			(layers "B.Cu" "B.Mask" "B.Paste")
			(net "TP_CH_H_DIMM0_RFU_0")
		)
		(pad "206" smd rect
			(at -4.59994 51.850036 270)
			(size 1.8034 0.508)
			(layers "B.Cu" "B.Mask" "B.Paste")
			(net "PVDDQ_GHJ")
		)
		(pad "207" smd rect
			(at -4.59994 52.69992 270)
			(size 1.8034 0.508)
			(layers "B.Cu" "B.Mask" "B.Paste")
			(net "M_H_BG<1>")
		)
		(pad "208" smd rect
			(at -4.59994 53.550058 270)
			(size 1.8034 0.508)
			(layers "B.Cu" "B.Mask" "B.Paste")
			(net "M_H_ALERT_N")
		)
		(pad "209" smd rect
			(at -4.59994 54.399942 270)
			(size 1.8034 0.508)
			(layers "B.Cu" "B.Mask" "B.Paste")
			(net "PVDDQ_GHJ")
		)
		(pad "210" smd rect
			(at -4.59994 55.25008 270)
			(size 1.8034 0.508)
			(layers "B.Cu" "B.Mask" "B.Paste")
			(net "M_H_MA<11>")
		)
		(pad "211" smd rect
			(at -4.59994 56.099964 270)
			(size 1.8034 0.508)
			(layers "B.Cu" "B.Mask" "B.Paste")
			(net "M_H_MA<7>")
		)
		(pad "212" smd rect
			(at -4.59994 56.950102 270)
			(size 1.8034 0.508)
			(layers "B.Cu" "B.Mask" "B.Paste")
			(net "PVDDQ_GHJ")
		)
		(pad "213" smd rect
			(at -4.59994 57.799986 270)
			(size 1.8034 0.508)
			(layers "B.Cu" "B.Mask" "B.Paste")
			(net "M_H_MA<5>")
		)
		(pad "214" smd rect
			(at -4.59994 58.650124 270)
			(size 1.8034 0.508)
			(layers "B.Cu" "B.Mask" "B.Paste")
			(net "M_H_MA<4>")
		)
		(pad "215" smd rect
			(at -4.59994 59.500008 270)
			(size 1.8034 0.508)
			(layers "B.Cu" "B.Mask" "B.Paste")
			(net "PVDDQ_GHJ")
		)
		(pad "216" smd rect
			(at -4.59994 60.349892 270)
			(size 1.8034 0.508)
			(layers "B.Cu" "B.Mask" "B.Paste")
			(net "M_H_MA<2>")
		)
		(pad "217" smd rect
			(at -4.59994 61.20003 270)
			(size 1.8034 0.508)
			(layers "B.Cu" "B.Mask" "B.Paste")
			(net "PVDDQ_GHJ")
		)
		(pad "218" smd rect
			(at -4.59994 62.049914 270)
			(size 1.8034 0.508)
			(layers "B.Cu" "B.Mask" "B.Paste")
			(net "M_H_CLK_DP<3>")
		)
		(pad "219" smd rect
			(at -4.59994 62.900052 270)
			(size 1.8034 0.508)
			(layers "B.Cu" "B.Mask" "B.Paste")
			(net "M_H_CLK_DN<3>")
		)
		(pad "220" smd rect
			(at -4.59994 63.749936 270)
			(size 1.8034 0.508)
			(layers "B.Cu" "B.Mask" "B.Paste")
			(net "PVDDQ_GHJ")
		)
		(pad "221" smd rect
			(at -4.59994 64.600074 270)
			(size 1.8034 0.508)
			(layers "B.Cu" "B.Mask" "B.Paste")
			(net "PVTT_GHJ")
		)
		(pad "222" smd rect
			(at -4.59994 70.550024 270)
			(size 1.8034 0.508)
			(layers "B.Cu" "B.Mask" "B.Paste")
			(net "M_H_PAR")
		)
		(pad "223" smd rect
			(at -4.59994 71.399908 270)
			(size 1.8034 0.508)
			(layers "B.Cu" "B.Mask" "B.Paste")
			(net "PVDDQ_GHJ")
		)
		(pad "224" smd rect
			(at -4.59994 72.250046 270)
			(size 1.8034 0.508)
			(layers "B.Cu" "B.Mask" "B.Paste")
			(net "M_H_BA<1>")
		)
		(pad "225" smd rect
			(at -4.59994 73.09993 270)
			(size 1.8034 0.508)
			(layers "B.Cu" "B.Mask" "B.Paste")
			(net "M_H_MA<10>")
		)
		(pad "226" smd rect
			(at -4.59994 73.950068 270)
			(size 1.8034 0.508)
			(layers "B.Cu" "B.Mask" "B.Paste")
			(net "PVDDQ_GHJ")
		)
		(pad "227" smd rect
			(at -4.59994 74.799952 270)
			(size 1.8034 0.508)
			(layers "B.Cu" "B.Mask" "B.Paste")
			(net "TP_CH_H_DIMM0_RFU_1")
		)
		(pad "228" smd rect
			(at -4.59994 75.65009 270)
			(size 1.8034 0.508)
			(layers "B.Cu" "B.Mask" "B.Paste")
			(net "M_H_MA<14>")
		)
		(pad "229" smd rect
			(at -4.59994 76.499974 270)
			(size 1.8034 0.508)
			(layers "B.Cu" "B.Mask" "B.Paste")
			(net "PVDDQ_GHJ")
		)
		(pad "230" smd rect
			(at -4.59994 77.350112 270)
			(size 1.8034 0.508)
			(layers "B.Cu" "B.Mask" "B.Paste")
			(net "FM_ADR_COMPLETE_GHJ_N")
		)
		(pad "231" smd rect
			(at -4.59994 78.199996 270)
			(size 1.8034 0.508)
			(layers "B.Cu" "B.Mask" "B.Paste")
			(net "PVDDQ_GHJ")
		)
		(pad "232" smd rect
			(at -4.59994 79.04988 270)
			(size 1.8034 0.508)
			(layers "B.Cu" "B.Mask" "B.Paste")
			(net "M_H_MA<13>")
		)
		(pad "233" smd rect
			(at -4.59994 79.900018 270)
			(size 1.8034 0.508)
			(layers "B.Cu" "B.Mask" "B.Paste")
			(net "PVDDQ_GHJ")
		)
		(pad "234" smd rect
			(at -4.59994 80.749902 270)
			(size 1.8034 0.508)
			(layers "B.Cu" "B.Mask" "B.Paste")
			(net "M_H_MA<17>")
		)
		(pad "235" smd rect
			(at -4.59994 81.60004 270)
			(size 1.8034 0.508)
			(layers "B.Cu" "B.Mask" "B.Paste")
			(net "M_H_C<2>")
		)
		(pad "236" smd rect
			(at -4.59994 82.449924 270)
			(size 1.8034 0.508)
			(layers "B.Cu" "B.Mask" "B.Paste")
			(net "PVDDQ_GHJ")
		)
		(pad "237" smd rect
			(at -4.59994 83.300062 270)
			(size 1.8034 0.508)
			(layers "B.Cu" "B.Mask" "B.Paste")
			(net "M_H_CS_N<7>")
		)
		(pad "238" smd rect
			(at -4.59994 84.149946 270)
			(size 1.8034 0.508)
			(layers "B.Cu" "B.Mask" "B.Paste")
			(net "GND")
		)
		(pad "239" smd rect
			(at -4.59994 85.000084 270)
			(size 1.8034 0.508)
			(layers "B.Cu" "B.Mask" "B.Paste")
			(net "GND")
		)
		(pad "240" smd rect
			(at -4.59994 85.849968 270)
			(size 1.8034 0.508)
			(layers "B.Cu" "B.Mask" "B.Paste")
			(net "M_H_DQ<37>")
		)
		(pad "241" smd rect
			(at -4.59994 86.700106 270)
			(size 1.8034 0.508)
			(layers "B.Cu" "B.Mask" "B.Paste")
			(net "GND")
		)
		(pad "242" smd rect
			(at -4.59994 87.54999 270)
			(size 1.8034 0.508)
			(layers "B.Cu" "B.Mask" "B.Paste")
			(net "M_H_DQ<33>")
		)
		(pad "243" smd rect
			(at -4.59994 88.399874 270)
			(size 1.8034 0.508)
			(layers "B.Cu" "B.Mask" "B.Paste")
			(net "GND")
		)
		(pad "244" smd rect
			(at -4.59994 89.250012 270)
			(size 1.8034 0.508)
			(layers "B.Cu" "B.Mask" "B.Paste")
			(net "M_H_DQS_DN<4>")
		)
		(pad "245" smd rect
			(at -4.59994 90.099896 270)
			(size 1.8034 0.508)
			(layers "B.Cu" "B.Mask" "B.Paste")
			(net "M_H_DQS_DP<4>")
		)
		(pad "246" smd rect
			(at -4.59994 90.950034 270)
			(size 1.8034 0.508)
			(layers "B.Cu" "B.Mask" "B.Paste")
			(net "GND")
		)
		(pad "247" smd rect
			(at -4.59994 91.799918 270)
			(size 1.8034 0.508)
			(layers "B.Cu" "B.Mask" "B.Paste")
			(net "M_H_DQ<39>")
		)
		(pad "248" smd rect
			(at -4.59994 92.650056 270)
			(size 1.8034 0.508)
			(layers "B.Cu" "B.Mask" "B.Paste")
			(net "GND")
		)
		(pad "249" smd rect
			(at -4.59994 93.49994 270)
			(size 1.8034 0.508)
			(layers "B.Cu" "B.Mask" "B.Paste")
			(net "M_H_DQ<35>")
		)
		(pad "250" smd rect
			(at -4.59994 94.350078 270)
			(size 1.8034 0.508)
			(layers "B.Cu" "B.Mask" "B.Paste")
			(net "GND")
		)
		(pad "251" smd rect
			(at -4.59994 95.199962 270)
			(size 1.8034 0.508)
			(layers "B.Cu" "B.Mask" "B.Paste")
			(net "M_H_DQ<45>")
		)
		(pad "252" smd rect
			(at -4.59994 96.0501 270)
			(size 1.8034 0.508)
			(layers "B.Cu" "B.Mask" "B.Paste")
			(net "GND")
		)
		(pad "253" smd rect
			(at -4.59994 96.899984 270)
			(size 1.8034 0.508)
			(layers "B.Cu" "B.Mask" "B.Paste")
			(net "M_H_DQ<41>")
		)
		(pad "254" smd rect
			(at -4.59994 97.750122 270)
			(size 1.8034 0.508)
			(layers "B.Cu" "B.Mask" "B.Paste")
			(net "GND")
		)
		(pad "255" smd rect
			(at -4.59994 98.600006 270)
			(size 1.8034 0.508)
			(layers "B.Cu" "B.Mask" "B.Paste")
			(net "M_H_DQS_DN<5>")
		)
		(pad "256" smd rect
			(at -4.59994 99.44989 270)
			(size 1.8034 0.508)
			(layers "B.Cu" "B.Mask" "B.Paste")
			(net "M_H_DQS_DP<5>")
		)
		(pad "257" smd rect
			(at -4.59994 100.300028 270)
			(size 1.8034 0.508)
			(layers "B.Cu" "B.Mask" "B.Paste")
			(net "GND")
		)
		(pad "258" smd rect
			(at -4.59994 101.149912 270)
			(size 1.8034 0.508)
			(layers "B.Cu" "B.Mask" "B.Paste")
			(net "M_H_DQ<47>")
		)
		(pad "259" smd rect
			(at -4.59994 102.00005 270)
			(size 1.8034 0.508)
			(layers "B.Cu" "B.Mask" "B.Paste")
			(net "GND")
		)
		(pad "260" smd rect
			(at -4.59994 102.849934 270)
			(size 1.8034 0.508)
			(layers "B.Cu" "B.Mask" "B.Paste")
			(net "M_H_DQ<43>")
		)
		(pad "261" smd rect
			(at -4.59994 103.700072 270)
			(size 1.8034 0.508)
			(layers "B.Cu" "B.Mask" "B.Paste")
			(net "GND")
		)
		(pad "262" smd rect
			(at -4.59994 104.549956 270)
			(size 1.8034 0.508)
			(layers "B.Cu" "B.Mask" "B.Paste")
			(net "M_H_DQ<53>")
		)
		(pad "263" smd rect
			(at -4.59994 105.400094 270)
			(size 1.8034 0.508)
			(layers "B.Cu" "B.Mask" "B.Paste")
			(net "GND")
		)
		(pad "264" smd rect
			(at -4.59994 106.249978 270)
			(size 1.8034 0.508)
			(layers "B.Cu" "B.Mask" "B.Paste")
			(net "M_H_DQ<49>")
		)
		(pad "265" smd rect
			(at -4.59994 107.100116 270)
			(size 1.8034 0.508)
			(layers "B.Cu" "B.Mask" "B.Paste")
			(net "GND")
		)
		(pad "266" smd rect
			(at -4.59994 107.95 270)
			(size 1.8034 0.508)
			(layers "B.Cu" "B.Mask" "B.Paste")
			(net "M_H_DQS_DN<6>")
		)
		(pad "267" smd rect
			(at -4.59994 108.799884 270)
			(size 1.8034 0.508)
			(layers "B.Cu" "B.Mask" "B.Paste")
			(net "M_H_DQS_DP<6>")
		)
		(pad "268" smd rect
			(at -4.59994 109.650022 270)
			(size 1.8034 0.508)
			(layers "B.Cu" "B.Mask" "B.Paste")
			(net "GND")
		)
		(pad "269" smd rect
			(at -4.59994 110.499906 270)
			(size 1.8034 0.508)
			(layers "B.Cu" "B.Mask" "B.Paste")
			(net "M_H_DQ<55>")
		)
		(pad "270" smd rect
			(at -4.59994 111.350044 270)
			(size 1.8034 0.508)
			(layers "B.Cu" "B.Mask" "B.Paste")
			(net "GND")
		)
		(pad "271" smd rect
			(at -4.59994 112.199928 270)
			(size 1.8034 0.508)
			(layers "B.Cu" "B.Mask" "B.Paste")
			(net "M_H_DQ<51>")
		)
		(pad "272" smd rect
			(at -4.59994 113.050066 270)
			(size 1.8034 0.508)
			(layers "B.Cu" "B.Mask" "B.Paste")
			(net "GND")
		)
		(pad "273" smd rect
			(at -4.59994 113.89995 270)
			(size 1.8034 0.508)
			(layers "B.Cu" "B.Mask" "B.Paste")
			(net "M_H_DQ<61>")
		)
		(pad "274" smd rect
			(at -4.59994 114.750088 270)
			(size 1.8034 0.508)
			(layers "B.Cu" "B.Mask" "B.Paste")
			(net "GND")
		)
		(pad "275" smd rect
			(at -4.59994 115.599972 270)
			(size 1.8034 0.508)
			(layers "B.Cu" "B.Mask" "B.Paste")
			(net "M_H_DQ<57>")
		)
		(pad "276" smd rect
			(at -4.59994 116.45011 270)
			(size 1.8034 0.508)
			(layers "B.Cu" "B.Mask" "B.Paste")
			(net "GND")
		)
		(pad "277" smd rect
			(at -4.59994 117.299994 270)
			(size 1.8034 0.508)
			(layers "B.Cu" "B.Mask" "B.Paste")
			(net "M_H_DQS_DN<7>")
		)
		(pad "278" smd rect
			(at -4.59994 118.149878 270)
			(size 1.8034 0.508)
			(layers "B.Cu" "B.Mask" "B.Paste")
			(net "M_H_DQS_DP<7>")
		)
		(pad "279" smd rect
			(at -4.59994 119.000016 270)
			(size 1.8034 0.508)
			(layers "B.Cu" "B.Mask" "B.Paste")
			(net "GND")
		)
		(pad "280" smd rect
			(at -4.59994 119.8499 270)
			(size 1.8034 0.508)
			(layers "B.Cu" "B.Mask" "B.Paste")
			(net "M_H_DQ<63>")
		)
		(pad "281" smd rect
			(at -4.59994 120.700038 270)
			(size 1.8034 0.508)
			(layers "B.Cu" "B.Mask" "B.Paste")
			(net "GND")
		)
		(pad "282" smd rect
			(at -4.59994 121.549922 270)
			(size 1.8034 0.508)
			(layers "B.Cu" "B.Mask" "B.Paste")
			(net "M_H_DQ<59>")
		)
		(pad "283" smd rect
			(at -4.59994 122.40006 270)
			(size 1.8034 0.508)
			(layers "B.Cu" "B.Mask" "B.Paste")
			(net "GND")
		)
		(pad "284" smd rect
			(at -4.59994 123.249944 270)
			(size 1.8034 0.508)
			(layers "B.Cu" "B.Mask" "B.Paste")
			(net "PVPP_GHJ")
		)
		(pad "285" smd rect
			(at -4.59994 124.100082 270)
			(size 1.8034 0.508)
			(layers "B.Cu" "B.Mask" "B.Paste")
			(net "SMB_DDR_GHJ_VPP_SDA")
		)
		(pad "286" smd rect
			(at -4.59994 124.949966 270)
			(size 1.8034 0.508)
			(layers "B.Cu" "B.Mask" "B.Paste")
			(net "PVPP_GHJ")
		)
		(pad "287" smd rect
			(at -4.59994 125.800104 270)
			(size 1.8034 0.508)
			(layers "B.Cu" "B.Mask" "B.Paste")
			(net "PVPP_GHJ")
		)
		(pad "288" smd rect
			(at -4.59994 126.649988 270)
			(size 1.8034 0.508)
			(layers "B.Cu" "B.Mask" "B.Paste")
			(net "PVPP_GHJ")
		)
	)
	(footprint ""
		(layer "B.Cu")
		(at 361.444794 -42.305986 -90)
		(property "Reference" "R2T30"
			(at 0 0 90)
			(layer "B.SilkS")
			(hide yes)
			(effects
				(font
					(size 1.27 1.27)
				)
				(justify mirror)
			)
		)
		(property "Value" ""
			(at 0 0 90)
			(layer "B.Fab")
			(effects
				(font
					(size 1.27 1.27)
				)
				(justify mirror)
			)
		)
		(duplicate_pad_numbers_are_jumpers no)
		(fp_poly
			(pts
				(xy 0.2794 -0.1016) (xy -0.2794 -0.1016) (xy -0.2794 0.9906) (xy 0.2794 0.9906)
			)
			(stroke
				(width 0)
				(type default)
			)
			(fill no)
			(layer "B.CrtYd")
		)
		(fp_line
			(start -0.2794 0.9906)
			(end -0.2794 -0.1016)
			(stroke
				(width 0.1)
				(type default)
			)
			(layer "B.Fab")
		)
		(fp_line
			(start 0.2794 0.9906)
			(end -0.2794 0.9906)
			(stroke
				(width 0.1)
				(type default)
			)
			(layer "B.Fab")
		)
		(fp_line
			(start -0.2794 -0.1016)
			(end 0.2794 -0.1016)
			(stroke
				(width 0.1)
				(type default)
			)
			(layer "B.Fab")
		)
		(fp_line
			(start 0.2794 -0.1016)
			(end 0.2794 0.9906)
			(stroke
				(width 0.1)
				(type default)
			)
			(layer "B.Fab")
		)
		(pad "1" smd rect
			(at 0 0 90)
			(size 0.508 0.508)
			(layers "B.Cu" "B.Mask" "B.Paste")
			(net "FM_CPU_ERR0_LVT3_K_N")
		)
		(pad "2" smd rect
			(at 0 0.889 90)
			(size 0.508 0.508)
			(layers "B.Cu" "B.Mask" "B.Paste")
			(net "FM_CPU_ERR0_LVT3_N")
		)
		(zone
			(layer "B.Cu")
			(hatch none 0.5)
			(connect_pads
				(clearance 0)
			)
			(min_thickness 0.25)
			(keepout
				(tracks not_allowed)
				(vias allowed)
				(pads allowed)
				(copperpour not_allowed)
				(footprints allowed)
			)
			(placement
				(enabled no)
				(sheetname "")
			)
			(fill
				(thermal_gap 0.5)
				(thermal_bridge_width 0.5)
				(island_removal_mode 0)
			)
			(polygon
				(pts
					(xy 360.809794 -42.051986) (xy 360.809794 -42.559986) (xy 361.190794 -42.559986) (xy 361.190794 -42.051986)
				)
			)
		)
		(zone
			(layer "B.Cu")
			(hatch none 0.5)
			(connect_pads
				(clearance 0)
			)
			(min_thickness 0.25)
			(keepout
				(tracks allowed)
				(vias not_allowed)
				(pads allowed)
				(copperpour not_allowed)
				(footprints allowed)
			)
			(placement
				(enabled no)
				(sheetname "")
			)
			(fill
				(thermal_gap 0.5)
				(thermal_bridge_width 0.5)
				(island_removal_mode 0)
			)
			(polygon
				(pts
					(xy 361.190794 -42.051986) (xy 361.190794 -42.559986) (xy 360.809794 -42.559986) (xy 360.809794 -42.051986)
				)
			)
		)
	)
	(footprint ""
		(layer "B.Cu")
		(at 317.1952 -121.2342 -90)
		(property "Reference" "R3R9"
			(at 0 0 90)
			(layer "B.SilkS")
			(hide yes)
			(effects
				(font
					(size 1.27 1.27)
				)
				(justify mirror)
			)
		)
		(property "Value" ""
			(at 0 0 90)
			(layer "B.Fab")
			(effects
				(font
					(size 1.27 1.27)
				)
				(justify mirror)
			)
		)
		(duplicate_pad_numbers_are_jumpers no)
		(fp_poly
			(pts
				(xy 0.2794 -0.1016) (xy -0.2794 -0.1016) (xy -0.2794 0.9906) (xy 0.2794 0.9906)
			)
			(stroke
				(width 0)
				(type default)
			)
			(fill no)
			(layer "B.CrtYd")
		)
		(fp_line
			(start -0.2794 0.9906)
			(end -0.2794 -0.1016)
			(stroke
				(width 0.1)
				(type default)
			)
			(layer "B.Fab")
		)
		(fp_line
			(start 0.2794 0.9906)
			(end -0.2794 0.9906)
			(stroke
				(width 0.1)
				(type default)
			)
			(layer "B.Fab")
		)
		(fp_line
			(start -0.2794 -0.1016)
			(end 0.2794 -0.1016)
			(stroke
				(width 0.1)
				(type default)
			)
			(layer "B.Fab")
		)
		(fp_line
			(start 0.2794 -0.1016)
			(end 0.2794 0.9906)
			(stroke
				(width 0.1)
				(type default)
			)
			(layer "B.Fab")
		)
		(pad "1" smd rect
			(at 0 0 90)
			(size 0.508 0.508)
			(layers "B.Cu" "B.Mask" "B.Paste")
			(net "SMB_DDR_DEF_VPP_SDA_R")
		)
		(pad "2" smd rect
			(at 0 0.889 90)
			(size 0.508 0.508)
			(layers "B.Cu" "B.Mask" "B.Paste")
			(net "SMB_DDR_DEF_VPP_SDA")
		)
		(zone
			(layer "B.Cu")
			(hatch none 0.5)
			(connect_pads
				(clearance 0)
			)
			(min_thickness 0.25)
			(keepout
				(tracks not_allowed)
				(vias allowed)
				(pads allowed)
				(copperpour not_allowed)
				(footprints allowed)
			)
			(placement
				(enabled no)
				(sheetname "")
			)
			(fill
				(thermal_gap 0.5)
				(thermal_bridge_width 0.5)
				(island_removal_mode 0)
			)
			(polygon
				(pts
					(xy 316.5602 -120.9802) (xy 316.5602 -121.4882) (xy 316.9412 -121.4882) (xy 316.9412 -120.9802)
				)
			)
		)
		(zone
			(layer "B.Cu")
			(hatch none 0.5)
			(connect_pads
				(clearance 0)
			)
			(min_thickness 0.25)
			(keepout
				(tracks allowed)
				(vias not_allowed)
				(pads allowed)
				(copperpour not_allowed)
				(footprints allowed)
			)
			(placement
				(enabled no)
				(sheetname "")
			)
			(fill
				(thermal_gap 0.5)
				(thermal_bridge_width 0.5)
				(island_removal_mode 0)
			)
			(polygon
				(pts
					(xy 316.9412 -120.9802) (xy 316.9412 -121.4882) (xy 316.5602 -121.4882) (xy 316.5602 -120.9802)
				)
			)
		)
	)
	(footprint ""
		(layer "B.Cu")
		(at 462.801208 -137.414254 90)
		(property "Reference" "R1L39"
			(at 0 0 90)
			(layer "B.SilkS")
			(hide yes)
			(effects
				(font
					(size 1.27 1.27)
				)
				(justify mirror)
			)
		)
		(property "Value" ""
			(at 0 0 90)
			(layer "B.Fab")
			(effects
				(font
					(size 1.27 1.27)
				)
				(justify mirror)
			)
		)
		(duplicate_pad_numbers_are_jumpers no)
		(fp_poly
			(pts
				(xy 0.2794 -0.1016) (xy -0.2794 -0.1016) (xy -0.2794 0.9906) (xy 0.2794 0.9906)
			)
			(stroke
				(width 0)
				(type default)
			)
			(fill no)
			(layer "B.CrtYd")
		)
		(fp_line
			(start 0.2794 -0.1016)
			(end 0.2794 0.9906)
			(stroke
				(width 0.1)
				(type default)
			)
			(layer "B.Fab")
		)
		(fp_line
			(start -0.2794 -0.1016)
			(end 0.2794 -0.1016)
			(stroke
				(width 0.1)
				(type default)
			)
			(layer "B.Fab")
		)
		(fp_line
			(start 0.2794 0.9906)
			(end -0.2794 0.9906)
			(stroke
				(width 0.1)
				(type default)
			)
			(layer "B.Fab")
		)
		(fp_line
			(start -0.2794 0.9906)
			(end -0.2794 -0.1016)
			(stroke
				(width 0.1)
				(type default)
			)
			(layer "B.Fab")
		)
		(pad "1" smd rect
			(at 0 0 270)
			(size 0.508 0.508)
			(layers "B.Cu" "B.Mask" "B.Paste")
			(net "P1V05_PCH_STBY")
		)
		(pad "2" smd rect
			(at 0 0.889 270)
			(size 0.508 0.508)
			(layers "B.Cu" "B.Mask" "B.Paste")
			(net "XDP_PRDY_N")
		)
		(zone
			(layer "B.Cu")
			(hatch none 0.5)
			(connect_pads
				(clearance 0)
			)
			(min_thickness 0.25)
			(keepout
				(tracks allowed)
				(vias not_allowed)
				(pads allowed)
				(copperpour not_allowed)
				(footprints allowed)
			)
			(placement
				(enabled no)
				(sheetname "")
			)
			(fill
				(thermal_gap 0.5)
				(thermal_bridge_width 0.5)
				(island_removal_mode 0)
			)
			(polygon
				(pts
					(xy 463.055208 -137.668254) (xy 463.055208 -137.160254) (xy 463.436208 -137.160254) (xy 463.436208 -137.668254)
				)
			)
		)
		(zone
			(layer "B.Cu")
			(hatch none 0.5)
			(connect_pads
				(clearance 0)
			)
			(min_thickness 0.25)
			(keepout
				(tracks not_allowed)
				(vias allowed)
				(pads allowed)
				(copperpour not_allowed)
				(footprints allowed)
			)
			(placement
				(enabled no)
				(sheetname "")
			)
			(fill
				(thermal_gap 0.5)
				(thermal_bridge_width 0.5)
				(island_removal_mode 0)
			)
			(polygon
				(pts
					(xy 463.436208 -137.668254) (xy 463.436208 -137.160254) (xy 463.055208 -137.160254) (xy 463.055208 -137.668254)
				)
			)
		)
	)
	(footprint ""
		(layer "B.Cu")
		(at 164.973 -60.6552 90)
		(property "Reference" "C6R5"
			(at -0.02667 10.541 0)
			(unlocked yes)
			(layer "B.SilkS")
			(effects
				(font
					(size 0.7874 0.5842)
					(thickness 0.1524)
				)
				(justify mirror)
			)
		)
		(property "Value" ""
			(at 0 0 90)
			(layer "B.Fab")
			(effects
				(font
					(size 1.27 1.27)
				)
				(justify mirror)
			)
		)
		(duplicate_pad_numbers_are_jumpers no)
		(fp_line
			(start 2.563114 -1.616456)
			(end 2.563114 1.633728)
			(stroke
				(width 0.1524)
				(type default)
			)
			(layer "B.SilkS")
		)
		(fp_line
			(start 1.6002 -1.616456)
			(end 2.563114 -1.616456)
			(stroke
				(width 0.1524)
				(type default)
			)
			(layer "B.SilkS")
		)
		(fp_line
			(start -1.6002 -1.616456)
			(end -2.504948 -1.616456)
			(stroke
				(width 0.1524)
				(type default)
			)
			(layer "B.SilkS")
		)
		(fp_line
			(start -2.504948 -1.616456)
			(end -2.504948 1.633728)
			(stroke
				(width 0.1524)
				(type default)
			)
			(layer "B.SilkS")
		)
		(fp_line
			(start 2.563114 1.633728)
			(end 1.6002 1.633728)
			(stroke
				(width 0.1524)
				(type default)
			)
			(layer "B.SilkS")
		)
		(fp_line
			(start -2.504948 1.633728)
			(end -1.6002 1.633728)
			(stroke
				(width 0.1524)
				(type default)
			)
			(layer "B.SilkS")
		)
		(fp_line
			(start 2.286 7.366)
			(end 2.286 1.632712)
			(stroke
				(width 0.1524)
				(type default)
			)
			(layer "B.SilkS")
		)
		(fp_line
			(start 2.286 7.366)
			(end 1.60147 7.366)
			(stroke
				(width 0.1524)
				(type default)
			)
			(layer "B.SilkS")
		)
		(fp_line
			(start -2.286 7.366)
			(end -2.286 1.63195)
			(stroke
				(width 0.1524)
				(type default)
			)
			(layer "B.SilkS")
		)
		(fp_line
			(start -2.286 7.366)
			(end -1.600708 7.366)
			(stroke
				(width 0.1524)
				(type default)
			)
			(layer "B.SilkS")
		)
		(fp_rect
			(start 2.286 7.366)
			(end -2.286 -0.254)
			(stroke
				(width 0)
				(type default)
			)
			(fill no)
			(layer "B.CrtYd")
		)
		(fp_line
			(start 2.286 -0.254)
			(end -2.286 -0.254)
			(stroke
				(width 0.1)
				(type default)
			)
			(layer "B.Fab")
		)
		(fp_line
			(start -2.286 -0.254)
			(end -2.286 7.366)
			(stroke
				(width 0.1)
				(type default)
			)
			(layer "B.Fab")
		)
		(fp_line
			(start 2.286 7.366)
			(end 2.286 -0.254)
			(stroke
				(width 0.1)
				(type default)
			)
			(layer "B.Fab")
		)
		(fp_line
			(start -2.286 7.366)
			(end 2.286 7.366)
			(stroke
				(width 0.1)
				(type default)
			)
			(layer "B.Fab")
		)
		(pad "1" smd rect
			(at 0 0 270)
			(size 2.54 3.048)
			(layers "B.Cu" "B.Mask" "B.Paste")
			(net "PVCCIO_CPU1")
		)
		(pad "2" smd rect
			(at 0 7.112 270)
			(size 2.54 3.048)
			(layers "B.Cu" "B.Mask" "B.Paste")
			(net "GND")
		)
	)
	(footprint ""
		(layer "B.Cu")
		(at -3.47726 -117.89156)
		(property "Reference" "R9M19"
			(at 0 0 0)
			(layer "B.SilkS")
			(hide yes)
			(effects
				(font
					(size 1.27 1.27)
				)
				(justify mirror)
			)
		)
		(property "Value" ""
			(at 0 0 0)
			(layer "B.Fab")
			(effects
				(font
					(size 1.27 1.27)
				)
				(justify mirror)
			)
		)
		(duplicate_pad_numbers_are_jumpers no)
		(fp_rect
			(start -0.2794 0.9906)
			(end 0.2794 -0.1016)
			(stroke
				(width 0)
				(type default)
			)
			(fill no)
			(layer "B.CrtYd")
		)
		(fp_line
			(start -0.2794 -0.1016)
			(end 0.2794 -0.1016)
			(stroke
				(width 0.1)
				(type default)
			)
			(layer "B.Fab")
		)
		(fp_line
			(start -0.2794 0.9906)
			(end -0.2794 -0.1016)
			(stroke
				(width 0.1)
				(type default)
			)
			(layer "B.Fab")
		)
		(fp_line
			(start 0.2794 -0.1016)
			(end 0.2794 0.9906)
			(stroke
				(width 0.1)
				(type default)
			)
			(layer "B.Fab")
		)
		(fp_line
			(start 0.2794 0.9906)
			(end -0.2794 0.9906)
			(stroke
				(width 0.1)
				(type default)
			)
			(layer "B.Fab")
		)
		(pad "1" smd rect
			(at 0 0 180)
			(size 0.508 0.508)
			(layers "B.Cu" "B.Mask" "B.Paste")
			(net "PVCCIO_CPU1")
		)
		(pad "2" smd rect
			(at 0 0.889 180)
			(size 0.508 0.508)
			(layers "B.Cu" "B.Mask" "B.Paste")
			(net "SMB_CPU1_PE_HP_GTL_R_SCL")
		)
		(zone
			(layer "B.Cu")
			(hatch none 0.5)
			(connect_pads
				(clearance 0)
			)
			(min_thickness 0.25)
			(keepout
				(tracks allowed)
				(vias not_allowed)
				(pads allowed)
				(copperpour not_allowed)
				(footprints allowed)
			)
			(placement
				(enabled no)
				(sheetname "")
			)
			(fill
				(thermal_gap 0.5)
				(thermal_bridge_width 0.5)
				(island_removal_mode 0)
			)
			(polygon
				(pts
					(xy -3.73126 -117.25656) (xy -3.22326 -117.25656) (xy -3.22326 -117.63756) (xy -3.73126 -117.63756)
				)
			)
		)
		(zone
			(layer "B.Cu")
			(hatch none 0.5)
			(connect_pads
				(clearance 0)
			)
			(min_thickness 0.25)
			(keepout
				(tracks not_allowed)
				(vias allowed)
				(pads allowed)
				(copperpour not_allowed)
				(footprints allowed)
			)
			(placement
				(enabled no)
				(sheetname "")
			)
			(fill
				(thermal_gap 0.5)
				(thermal_bridge_width 0.5)
				(island_removal_mode 0)
			)
			(polygon
				(pts
					(xy -3.73126 -117.25656) (xy -3.22326 -117.25656) (xy -3.22326 -117.63756) (xy -3.73126 -117.63756)
				)
			)
		)
	)
	(footprint ""
		(layer "B.Cu")
		(at 111.000032 -149.8092 90)
		(property "Reference" "C5G105"
			(at -1.14681 0.76708 180)
			(unlocked yes)
			(layer "B.SilkS")
			(effects
				(font
					(size 0.7874 0.5842)
					(thickness 0.1524)
				)
				(justify mirror)
			)
		)
		(property "Value" ""
			(at 0 0 90)
			(layer "B.Fab")
			(effects
				(font
					(size 1.27 1.27)
				)
				(justify mirror)
			)
		)
		(duplicate_pad_numbers_are_jumpers no)
		(fp_rect
			(start -0.4953 -0.2032)
			(end 0.4953 1.6002)
			(stroke
				(width 0)
				(type default)
			)
			(fill no)
			(layer "B.CrtYd")
		)
		(fp_line
			(start 0.4953 -0.2032)
			(end -0.4953 -0.2032)
			(stroke
				(width 0.1)
				(type default)
			)
			(layer "B.Fab")
		)
		(fp_line
			(start -0.4953 -0.2032)
			(end -0.4953 1.6002)
			(stroke
				(width 0.1)
				(type default)
			)
			(layer "B.Fab")
		)
		(fp_line
			(start 0.4953 1.6002)
			(end 0.4953 -0.2032)
			(stroke
				(width 0.1)
				(type default)
			)
			(layer "B.Fab")
		)
		(fp_line
			(start -0.4953 1.6002)
			(end 0.4953 1.6002)
			(stroke
				(width 0.1)
				(type default)
			)
			(layer "B.Fab")
		)
		(pad "1" smd rect
			(at 0 0 270)
			(size 0.762 0.889)
			(layers "B.Cu" "B.Mask" "B.Paste")
			(net "PVDDQ_KLM")
		)
		(pad "2" smd rect
			(at 0 1.397 270)
			(size 0.762 0.889)
			(layers "B.Cu" "B.Mask" "B.Paste")
			(net "GND")
		)
		(zone
			(layer "B.Cu")
			(hatch none 0.5)
			(connect_pads
				(clearance 0)
			)
			(min_thickness 0.25)
			(keepout
				(tracks not_allowed)
				(vias allowed)
				(pads allowed)
				(copperpour not_allowed)
				(footprints allowed)
			)
			(placement
				(enabled no)
				(sheetname "")
			)
			(fill
				(thermal_gap 0.5)
				(thermal_bridge_width 0.5)
				(island_removal_mode 0)
			)
			(polygon
				(pts
					(xy 111.444532 -149.4282) (xy 111.952532 -149.4282) (xy 111.952532 -150.1902) (xy 111.444532 -150.1902)
				)
			)
		)
	)
	(footprint ""
		(layer "B.Cu")
		(at 483.616 -113.06302)
		(property "Reference" "C1M25"
			(at 0 0 0)
			(layer "B.SilkS")
			(hide yes)
			(effects
				(font
					(size 1.27 1.27)
				)
				(justify mirror)
			)
		)
		(property "Value" ""
			(at 0 0 0)
			(layer "B.Fab")
			(effects
				(font
					(size 1.27 1.27)
				)
				(justify mirror)
			)
		)
		(duplicate_pad_numbers_are_jumpers no)
		(fp_rect
			(start -0.3048 0.9906)
			(end 0.3048 -0.1016)
			(stroke
				(width 0)
				(type default)
			)
			(fill no)
			(layer "B.CrtYd")
		)
		(fp_line
			(start -0.3048 -0.1016)
			(end 0.3048 -0.1016)
			(stroke
				(width 0.1)
				(type default)
			)
			(layer "B.Fab")
		)
		(fp_line
			(start -0.3048 0.9906)
			(end -0.3048 -0.1016)
			(stroke
				(width 0.1)
				(type default)
			)
			(layer "B.Fab")
		)
		(fp_line
			(start 0.3048 -0.1016)
			(end 0.3048 0.9906)
			(stroke
				(width 0.1)
				(type default)
			)
			(layer "B.Fab")
		)
		(fp_line
			(start 0.3048 0.9906)
			(end -0.3048 0.9906)
			(stroke
				(width 0.1)
				(type default)
			)
			(layer "B.Fab")
		)
		(pad "1" smd rect
			(at 0 0 180)
			(size 0.508 0.508)
			(layers "B.Cu" "B.Mask" "B.Paste")
			(net "P3V3_STBY")
		)
		(pad "2" smd rect
			(at 0 0.889 180)
			(size 0.508 0.508)
			(layers "B.Cu" "B.Mask" "B.Paste")
			(net "GND")
		)
		(zone
			(layer "B.Cu")
			(hatch none 0.5)
			(connect_pads
				(clearance 0)
			)
			(min_thickness 0.25)
			(keepout
				(tracks not_allowed)
				(vias allowed)
				(pads allowed)
				(copperpour not_allowed)
				(footprints allowed)
			)
			(placement
				(enabled no)
				(sheetname "")
			)
			(fill
				(thermal_gap 0.5)
				(thermal_bridge_width 0.5)
				(island_removal_mode 0)
			)
			(polygon
				(pts
					(xy 483.362 -112.42802) (xy 483.87 -112.42802) (xy 483.87 -112.80902) (xy 483.362 -112.80902)
				)
			)
		)
		(zone
			(layer "B.Cu")
			(hatch none 0.5)
			(connect_pads
				(clearance 0)
			)
			(min_thickness 0.25)
			(keepout
				(tracks allowed)
				(vias not_allowed)
				(pads allowed)
				(copperpour not_allowed)
				(footprints allowed)
			)
			(placement
				(enabled no)
				(sheetname "")
			)
			(fill
				(thermal_gap 0.5)
				(thermal_bridge_width 0.5)
				(island_removal_mode 0)
			)
			(polygon
				(pts
					(xy 483.362 -112.42802) (xy 483.87 -112.42802) (xy 483.87 -112.80902) (xy 483.362 -112.80902)
				)
			)
		)
	)
	(footprint ""
		(layer "B.Cu")
		(at 261.7978 -157.0228 -90)
		(property "Reference" "C5L5"
			(at -1.47828 0.78994 0)
			(unlocked yes)
			(layer "B.SilkS")
			(effects
				(font
					(size 0.4064 0.254)
					(thickness 0.1524)
				)
				(justify mirror)
			)
		)
		(property "Value" ""
			(at 0 0 90)
			(layer "B.Fab")
			(effects
				(font
					(size 1.27 1.27)
				)
				(justify mirror)
			)
		)
		(duplicate_pad_numbers_are_jumpers no)
		(fp_poly
			(pts
				(xy 0.7239 -0.2159) (xy -0.7239 -0.2159) (xy -0.7239 1.9939) (xy 0.7239 1.9939)
			)
			(stroke
				(width 0)
				(type default)
			)
			(fill no)
			(layer "B.CrtYd")
		)
		(fp_line
			(start -0.7239 1.9939)
			(end -0.7239 -0.2159)
			(stroke
				(width 0.1)
				(type default)
			)
			(layer "B.Fab")
		)
		(fp_line
			(start 0.7239 1.9939)
			(end -0.7239 1.9939)
			(stroke
				(width 0.1)
				(type default)
			)
			(layer "B.Fab")
		)
		(fp_line
			(start -0.7239 -0.2159)
			(end 0.7239 -0.2159)
			(stroke
				(width 0.1)
				(type default)
			)
			(layer "B.Fab")
		)
		(fp_line
			(start 0.7239 -0.2159)
			(end 0.7239 1.9939)
			(stroke
				(width 0.1)
				(type default)
			)
			(layer "B.Fab")
		)
		(pad "1" smd rect
			(at 0 0 90)
			(size 1.27 1.016)
			(layers "B.Cu" "B.Mask" "B.Paste")
			(net "PVTT_DEF")
		)
		(pad "2" smd rect
			(at 0 1.778 90)
			(size 1.27 1.016)
			(layers "B.Cu" "B.Mask" "B.Paste")
			(net "GND")
		)
		(zone
			(layer "B.Cu")
			(hatch none 0.5)
			(connect_pads
				(clearance 0)
			)
			(min_thickness 0.25)
			(keepout
				(tracks not_allowed)
				(vias allowed)
				(pads allowed)
				(copperpour not_allowed)
				(footprints allowed)
			)
			(placement
				(enabled no)
				(sheetname "")
			)
			(fill
				(thermal_gap 0.5)
				(thermal_bridge_width 0.5)
				(island_removal_mode 0)
			)
			(polygon
				(pts
					(xy 261.2898 -156.3878) (xy 261.2898 -157.6578) (xy 260.5278 -157.6578) (xy 260.5278 -156.3878)
				)
			)
		)
	)
	(footprint ""
		(layer "B.Cu")
		(at 390.635744 -21.679916 -90)
		(property "Reference" "C2T29"
			(at 0 0 90)
			(layer "B.SilkS")
			(hide yes)
			(effects
				(font
					(size 1.27 1.27)
				)
				(justify mirror)
			)
		)
		(property "Value" ""
			(at 0 0 90)
			(layer "B.Fab")
			(effects
				(font
					(size 1.27 1.27)
				)
				(justify mirror)
			)
		)
		(duplicate_pad_numbers_are_jumpers no)
		(fp_poly
			(pts
				(xy -0.3048 -0.1016) (xy -0.3048 0.9906) (xy 0.3048 0.9906) (xy 0.3048 -0.1016)
			)
			(stroke
				(width 0)
				(type default)
			)
			(fill no)
			(layer "B.CrtYd")
		)
		(fp_line
			(start -0.3048 0.9906)
			(end -0.3048 -0.1016)
			(stroke
				(width 0.1)
				(type default)
			)
			(layer "B.Fab")
		)
		(fp_line
			(start 0.3048 0.9906)
			(end -0.3048 0.9906)
			(stroke
				(width 0.1)
				(type default)
			)
			(layer "B.Fab")
		)
		(fp_line
			(start -0.3048 -0.1016)
			(end 0.3048 -0.1016)
			(stroke
				(width 0.1)
				(type default)
			)
			(layer "B.Fab")
		)
		(fp_line
			(start 0.3048 -0.1016)
			(end 0.3048 0.9906)
			(stroke
				(width 0.1)
				(type default)
			)
			(layer "B.Fab")
		)
		(pad "1" smd rect
			(at 0 0 90)
			(size 0.508 0.508)
			(layers "B.Cu" "B.Mask" "B.Paste")
			(net "P3V3")
		)
		(pad "2" smd rect
			(at 0 0.889 90)
			(size 0.508 0.508)
			(layers "B.Cu" "B.Mask" "B.Paste")
			(net "GND")
		)
		(zone
			(layer "B.Cu")
			(hatch none 0.5)
			(connect_pads
				(clearance 0)
			)
			(min_thickness 0.25)
			(keepout
				(tracks not_allowed)
				(vias allowed)
				(pads allowed)
				(copperpour not_allowed)
				(footprints allowed)
			)
			(placement
				(enabled no)
				(sheetname "")
			)
			(fill
				(thermal_gap 0.5)
				(thermal_bridge_width 0.5)
				(island_removal_mode 0)
			)
			(polygon
				(pts
					(xy 390.000744 -21.425916) (xy 390.000744 -21.933916) (xy 390.381744 -21.933916) (xy 390.381744 -21.425916)
				)
			)
		)
		(zone
			(layer "B.Cu")
			(hatch none 0.5)
			(connect_pads
				(clearance 0)
			)
			(min_thickness 0.25)
			(keepout
				(tracks allowed)
				(vias not_allowed)
				(pads allowed)
				(copperpour not_allowed)
				(footprints allowed)
			)
			(placement
				(enabled no)
				(sheetname "")
			)
			(fill
				(thermal_gap 0.5)
				(thermal_bridge_width 0.5)
				(island_removal_mode 0)
			)
			(polygon
				(pts
					(xy 390.381744 -21.425916) (xy 390.381744 -21.933916) (xy 390.000744 -21.933916) (xy 390.000744 -21.425916)
				)
			)
		)
	)
	(footprint ""
		(layer "B.Cu")
		(at 185.039 -72.898)
		(property "Reference" "R6P27"
			(at 0 0 0)
			(layer "B.SilkS")
			(hide yes)
			(effects
				(font
					(size 1.27 1.27)
				)
				(justify mirror)
			)
		)
		(property "Value" ""
			(at 0 0 0)
			(layer "B.Fab")
			(effects
				(font
					(size 1.27 1.27)
				)
				(justify mirror)
			)
		)
		(duplicate_pad_numbers_are_jumpers no)
		(fp_rect
			(start -0.2794 0.9906)
			(end 0.2794 -0.1016)
			(stroke
				(width 0)
				(type default)
			)
			(fill no)
			(layer "B.CrtYd")
		)
		(fp_line
			(start -0.2794 -0.1016)
			(end 0.2794 -0.1016)
			(stroke
				(width 0.1)
				(type default)
			)
			(layer "B.Fab")
		)
		(fp_line
			(start -0.2794 0.9906)
			(end -0.2794 -0.1016)
			(stroke
				(width 0.1)
				(type default)
			)
			(layer "B.Fab")
		)
		(fp_line
			(start 0.2794 -0.1016)
			(end 0.2794 0.9906)
			(stroke
				(width 0.1)
				(type default)
			)
			(layer "B.Fab")
		)
		(fp_line
			(start 0.2794 0.9906)
			(end -0.2794 0.9906)
			(stroke
				(width 0.1)
				(type default)
			)
			(layer "B.Fab")
		)
		(pad "1" smd rect
			(at 0 0 180)
			(size 0.508 0.508)
			(layers "B.Cu" "B.Mask" "B.Paste")
			(net "VR_PVCCIN_CPU0_XADDR2")
		)
		(pad "2" smd rect
			(at 0 0.889 180)
			(size 0.508 0.508)
			(layers "B.Cu" "B.Mask" "B.Paste")
			(net "GND")
		)
		(zone
			(layer "B.Cu")
			(hatch none 0.5)
			(connect_pads
				(clearance 0)
			)
			(min_thickness 0.25)
			(keepout
				(tracks not_allowed)
				(vias allowed)
				(pads allowed)
				(copperpour not_allowed)
				(footprints allowed)
			)
			(placement
				(enabled no)
				(sheetname "")
			)
			(fill
				(thermal_gap 0.5)
				(thermal_bridge_width 0.5)
				(island_removal_mode 0)
			)
			(polygon
				(pts
					(xy 184.785 -72.263) (xy 185.293 -72.263) (xy 185.293 -72.644) (xy 184.785 -72.644)
				)
			)
		)
		(zone
			(layer "B.Cu")
			(hatch none 0.5)
			(connect_pads
				(clearance 0)
			)
			(min_thickness 0.25)
			(keepout
				(tracks allowed)
				(vias not_allowed)
				(pads allowed)
				(copperpour not_allowed)
				(footprints allowed)
			)
			(placement
				(enabled no)
				(sheetname "")
			)
			(fill
				(thermal_gap 0.5)
				(thermal_bridge_width 0.5)
				(island_removal_mode 0)
			)
			(polygon
				(pts
					(xy 184.785 -72.263) (xy 185.293 -72.263) (xy 185.293 -72.644) (xy 184.785 -72.644)
				)
			)
		)
	)
	(footprint ""
		(layer "B.Cu")
		(at 405.2062 -105.8545 180)
		(property "Reference" "C2N22"
			(at 0 0 0)
			(layer "B.SilkS")
			(hide yes)
			(effects
				(font
					(size 1.27 1.27)
				)
				(justify mirror)
			)
		)
		(property "Value" ""
			(at 0 0 0)
			(layer "B.Fab")
			(effects
				(font
					(size 1.27 1.27)
				)
				(justify mirror)
			)
		)
		(duplicate_pad_numbers_are_jumpers no)
		(fp_poly
			(pts
				(xy 0.4953 -0.2032) (xy -0.4953 -0.2032) (xy -0.4953 1.6002) (xy 0.4953 1.6002)
			)
			(stroke
				(width 0)
				(type default)
			)
			(fill no)
			(layer "B.CrtYd")
		)
		(fp_line
			(start 0.4953 1.6002)
			(end 0.4953 -0.2032)
			(stroke
				(width 0.1)
				(type default)
			)
			(layer "B.Fab")
		)
		(fp_line
			(start 0.4953 -0.2032)
			(end -0.4953 -0.2032)
			(stroke
				(width 0.1)
				(type default)
			)
			(layer "B.Fab")
		)
		(fp_line
			(start -0.4953 1.6002)
			(end 0.4953 1.6002)
			(stroke
				(width 0.1)
				(type default)
			)
			(layer "B.Fab")
		)
		(fp_line
			(start -0.4953 -0.2032)
			(end -0.4953 1.6002)
			(stroke
				(width 0.1)
				(type default)
			)
			(layer "B.Fab")
		)
		(pad "1" smd rect
			(at 0 0)
			(size 0.762 0.889)
			(layers "B.Cu" "B.Mask" "B.Paste")
			(net "P3V3_STBY")
		)
		(pad "2" smd rect
			(at 0 1.397)
			(size 0.762 0.889)
			(layers "B.Cu" "B.Mask" "B.Paste")
			(net "GND")
		)
		(zone
			(layer "B.Cu")
			(hatch none 0.5)
			(connect_pads
				(clearance 0)
			)
			(min_thickness 0.25)
			(keepout
				(tracks not_allowed)
				(vias allowed)
				(pads allowed)
				(copperpour not_allowed)
				(footprints allowed)
			)
			(placement
				(enabled no)
				(sheetname "")
			)
			(fill
				(thermal_gap 0.5)
				(thermal_bridge_width 0.5)
				(island_removal_mode 0)
			)
			(polygon
				(pts
					(xy 404.8252 -106.299) (xy 405.5872 -106.299) (xy 405.5872 -106.807) (xy 404.8252 -106.807)
				)
			)
		)
	)
	(footprint ""
		(layer "B.Cu")
		(at 408.432 -119.391684)
		(property "Reference" "C2M10"
			(at 0 0 0)
			(layer "B.SilkS")
			(hide yes)
			(effects
				(font
					(size 1.27 1.27)
				)
				(justify mirror)
			)
		)
		(property "Value" ""
			(at 0 0 0)
			(layer "B.Fab")
			(effects
				(font
					(size 1.27 1.27)
				)
				(justify mirror)
			)
		)
		(duplicate_pad_numbers_are_jumpers no)
		(fp_poly
			(pts
				(xy 0.4953 -0.2032) (xy -0.4953 -0.2032) (xy -0.4953 1.6002) (xy 0.4953 1.6002)
			)
			(stroke
				(width 0)
				(type default)
			)
			(fill no)
			(layer "B.CrtYd")
		)
		(fp_line
			(start -0.4953 -0.2032)
			(end -0.4953 1.6002)
			(stroke
				(width 0.1)
				(type default)
			)
			(layer "B.Fab")
		)
		(fp_line
			(start -0.4953 1.6002)
			(end 0.4953 1.6002)
			(stroke
				(width 0.1)
				(type default)
			)
			(layer "B.Fab")
		)
		(fp_line
			(start 0.4953 -0.2032)
			(end -0.4953 -0.2032)
			(stroke
				(width 0.1)
				(type default)
			)
			(layer "B.Fab")
		)
		(fp_line
			(start 0.4953 1.6002)
			(end 0.4953 -0.2032)
			(stroke
				(width 0.1)
				(type default)
			)
			(layer "B.Fab")
		)
		(pad "1" smd rect
			(at 0 0 180)
			(size 0.762 0.889)
			(layers "B.Cu" "B.Mask" "B.Paste")
			(net "P1V05_PCH_STBY_WM26_PLL")
		)
		(pad "2" smd rect
			(at 0 1.397 180)
			(size 0.762 0.889)
			(layers "B.Cu" "B.Mask" "B.Paste")
			(net "GND")
		)
		(zone
			(layer "B.Cu")
			(hatch none 0.5)
			(connect_pads
				(clearance 0)
			)
			(min_thickness 0.25)
			(keepout
				(tracks not_allowed)
				(vias allowed)
				(pads allowed)
				(copperpour not_allowed)
				(footprints allowed)
			)
			(placement
				(enabled no)
				(sheetname "")
			)
			(fill
				(thermal_gap 0.5)
				(thermal_bridge_width 0.5)
				(island_removal_mode 0)
			)
			(polygon
				(pts
					(xy 408.813 -118.947184) (xy 408.051 -118.947184) (xy 408.051 -118.439184) (xy 408.813 -118.439184)
				)
			)
		)
	)
	(footprint ""
		(layer "B.Cu")
		(at 451.030594 -17.9451 -90)
		(property "Reference" "R3W2"
			(at 0.8382 -0.67818 270)
			(unlocked yes)
			(layer "B.SilkS")
			(effects
				(font
					(size 0.4064 0.254)
					(thickness 0.1524)
				)
				(justify left mirror)
			)
		)
		(property "Value" ""
			(at 0 0 90)
			(layer "B.Fab")
			(effects
				(font
					(size 1.27 1.27)
				)
				(justify mirror)
			)
		)
		(duplicate_pad_numbers_are_jumpers no)
		(fp_poly
			(pts
				(xy 0.2794 -0.1016) (xy -0.2794 -0.1016) (xy -0.2794 0.9906) (xy 0.2794 0.9906)
			)
			(stroke
				(width 0)
				(type default)
			)
			(fill no)
			(layer "B.CrtYd")
		)
		(fp_line
			(start -0.2794 0.9906)
			(end -0.2794 -0.1016)
			(stroke
				(width 0.1)
				(type default)
			)
			(layer "B.Fab")
		)
		(fp_line
			(start 0.2794 0.9906)
			(end -0.2794 0.9906)
			(stroke
				(width 0.1)
				(type default)
			)
			(layer "B.Fab")
		)
		(fp_line
			(start -0.2794 -0.1016)
			(end 0.2794 -0.1016)
			(stroke
				(width 0.1)
				(type default)
			)
			(layer "B.Fab")
		)
		(fp_line
			(start 0.2794 -0.1016)
			(end 0.2794 0.9906)
			(stroke
				(width 0.1)
				(type default)
			)
			(layer "B.Fab")
		)
		(pad "1" smd rect
			(at 0 0 90)
			(size 0.508 0.508)
			(layers "B.Cu" "B.Mask" "B.Paste")
			(net "BMC_TPM_HW_C_RST")
		)
		(pad "2" smd rect
			(at 0 0.889 90)
			(size 0.508 0.508)
			(layers "B.Cu" "B.Mask" "B.Paste")
			(net "GND")
		)
		(zone
			(layer "B.Cu")
			(hatch none 0.5)
			(connect_pads
				(clearance 0)
			)
			(min_thickness 0.25)
			(keepout
				(tracks not_allowed)
				(vias allowed)
				(pads allowed)
				(copperpour not_allowed)
				(footprints allowed)
			)
			(placement
				(enabled no)
				(sheetname "")
			)
			(fill
				(thermal_gap 0.5)
				(thermal_bridge_width 0.5)
				(island_removal_mode 0)
			)
			(polygon
				(pts
					(xy 450.395594 -17.6911) (xy 450.395594 -18.1991) (xy 450.776594 -18.1991) (xy 450.776594 -17.6911)
				)
			)
		)
		(zone
			(layer "B.Cu")
			(hatch none 0.5)
			(connect_pads
				(clearance 0)
			)
			(min_thickness 0.25)
			(keepout
				(tracks allowed)
				(vias not_allowed)
				(pads allowed)
				(copperpour not_allowed)
				(footprints allowed)
			)
			(placement
				(enabled no)
				(sheetname "")
			)
			(fill
				(thermal_gap 0.5)
				(thermal_bridge_width 0.5)
				(island_removal_mode 0)
			)
			(polygon
				(pts
					(xy 450.776594 -17.6911) (xy 450.776594 -18.1991) (xy 450.395594 -18.1991) (xy 450.395594 -17.6911)
				)
			)
		)
	)
	(footprint ""
		(layer "B.Cu")
		(at 460.9846 -35.7124 -90)
		(property "Reference" "R1U21"
			(at 0 0 90)
			(layer "B.SilkS")
			(hide yes)
			(effects
				(font
					(size 1.27 1.27)
				)
				(justify mirror)
			)
		)
		(property "Value" ""
			(at 0 0 90)
			(layer "B.Fab")
			(effects
				(font
					(size 1.27 1.27)
				)
				(justify mirror)
			)
		)
		(duplicate_pad_numbers_are_jumpers no)
		(fp_poly
			(pts
				(xy 0.2794 -0.1016) (xy -0.2794 -0.1016) (xy -0.2794 0.9906) (xy 0.2794 0.9906)
			)
			(stroke
				(width 0)
				(type default)
			)
			(fill no)
			(layer "B.CrtYd")
		)
		(fp_line
			(start -0.2794 0.9906)
			(end -0.2794 -0.1016)
			(stroke
				(width 0.1)
				(type default)
			)
			(layer "B.Fab")
		)
		(fp_line
			(start 0.2794 0.9906)
			(end -0.2794 0.9906)
			(stroke
				(width 0.1)
				(type default)
			)
			(layer "B.Fab")
		)
		(fp_line
			(start -0.2794 -0.1016)
			(end 0.2794 -0.1016)
			(stroke
				(width 0.1)
				(type default)
			)
			(layer "B.Fab")
		)
		(fp_line
			(start 0.2794 -0.1016)
			(end 0.2794 0.9906)
			(stroke
				(width 0.1)
				(type default)
			)
			(layer "B.Fab")
		)
		(pad "1" smd rect
			(at 0 0 90)
			(size 0.508 0.508)
			(layers "B.Cu" "B.Mask" "B.Paste")
			(net "P3V3_STBY")
		)
		(pad "2" smd rect
			(at 0 0.889 90)
			(size 0.508 0.508)
			(layers "B.Cu" "B.Mask" "B.Paste")
			(net "FM_BOARD_SKU_ID3")
		)
		(zone
			(layer "B.Cu")
			(hatch none 0.5)
			(connect_pads
				(clearance 0)
			)
			(min_thickness 0.25)
			(keepout
				(tracks not_allowed)
				(vias allowed)
				(pads allowed)
				(copperpour not_allowed)
				(footprints allowed)
			)
			(placement
				(enabled no)
				(sheetname "")
			)
			(fill
				(thermal_gap 0.5)
				(thermal_bridge_width 0.5)
				(island_removal_mode 0)
			)
			(polygon
				(pts
					(xy 460.3496 -35.4584) (xy 460.3496 -35.9664) (xy 460.7306 -35.9664) (xy 460.7306 -35.4584)
				)
			)
		)
		(zone
			(layer "B.Cu")
			(hatch none 0.5)
			(connect_pads
				(clearance 0)
			)
			(min_thickness 0.25)
			(keepout
				(tracks allowed)
				(vias not_allowed)
				(pads allowed)
				(copperpour not_allowed)
				(footprints allowed)
			)
			(placement
				(enabled no)
				(sheetname "")
			)
			(fill
				(thermal_gap 0.5)
				(thermal_bridge_width 0.5)
				(island_removal_mode 0)
			)
			(polygon
				(pts
					(xy 460.7306 -35.4584) (xy 460.7306 -35.9664) (xy 460.3496 -35.9664) (xy 460.3496 -35.4584)
				)
			)
		)
	)
	(footprint ""
		(layer "B.Cu")
		(at 245.14302 -86.57336 -90)
		(property "Reference" "R5P3"
			(at 0 0 90)
			(layer "B.SilkS")
			(hide yes)
			(effects
				(font
					(size 1.27 1.27)
				)
				(justify mirror)
			)
		)
		(property "Value" ""
			(at 0 0 90)
			(layer "B.Fab")
			(effects
				(font
					(size 1.27 1.27)
				)
				(justify mirror)
			)
		)
		(duplicate_pad_numbers_are_jumpers no)
		(fp_poly
			(pts
				(xy 0.2794 -0.1016) (xy -0.2794 -0.1016) (xy -0.2794 0.9906) (xy 0.2794 0.9906)
			)
			(stroke
				(width 0)
				(type default)
			)
			(fill no)
			(layer "B.CrtYd")
		)
		(fp_line
			(start -0.2794 0.9906)
			(end -0.2794 -0.1016)
			(stroke
				(width 0.1)
				(type default)
			)
			(layer "B.Fab")
		)
		(fp_line
			(start 0.2794 0.9906)
			(end -0.2794 0.9906)
			(stroke
				(width 0.1)
				(type default)
			)
			(layer "B.Fab")
		)
		(fp_line
			(start -0.2794 -0.1016)
			(end 0.2794 -0.1016)
			(stroke
				(width 0.1)
				(type default)
			)
			(layer "B.Fab")
		)
		(fp_line
			(start 0.2794 -0.1016)
			(end 0.2794 0.9906)
			(stroke
				(width 0.1)
				(type default)
			)
			(layer "B.Fab")
		)
		(pad "1" smd rect
			(at 0 0 90)
			(size 0.508 0.508)
			(layers "B.Cu" "B.Mask" "B.Paste")
			(net "PD_CPU0_TEST13")
		)
		(pad "2" smd rect
			(at 0 0.889 90)
			(size 0.508 0.508)
			(layers "B.Cu" "B.Mask" "B.Paste")
			(net "GND")
		)
		(zone
			(layer "B.Cu")
			(hatch none 0.5)
			(connect_pads
				(clearance 0)
			)
			(min_thickness 0.25)
			(keepout
				(tracks not_allowed)
				(vias allowed)
				(pads allowed)
				(copperpour not_allowed)
				(footprints allowed)
			)
			(placement
				(enabled no)
				(sheetname "")
			)
			(fill
				(thermal_gap 0.5)
				(thermal_bridge_width 0.5)
				(island_removal_mode 0)
			)
			(polygon
				(pts
					(xy 244.50802 -86.31936) (xy 244.50802 -86.82736) (xy 244.88902 -86.82736) (xy 244.88902 -86.31936)
				)
			)
		)
		(zone
			(layer "B.Cu")
			(hatch none 0.5)
			(connect_pads
				(clearance 0)
			)
			(min_thickness 0.25)
			(keepout
				(tracks allowed)
				(vias not_allowed)
				(pads allowed)
				(copperpour not_allowed)
				(footprints allowed)
			)
			(placement
				(enabled no)
				(sheetname "")
			)
			(fill
				(thermal_gap 0.5)
				(thermal_bridge_width 0.5)
				(island_removal_mode 0)
			)
			(polygon
				(pts
					(xy 244.88902 -86.31936) (xy 244.88902 -86.82736) (xy 244.50802 -86.82736) (xy 244.50802 -86.31936)
				)
			)
		)
	)
	(footprint ""
		(layer "B.Cu")
		(at 439.301636 -144.935956 180)
		(property "Reference" "U25W13"
			(at 0 0 0)
			(layer "B.SilkS")
			(hide yes)
			(effects
				(font
					(size 1.27 1.27)
				)
				(justify mirror)
			)
		)
		(property "Value" "*"
			(at 5.08 -8.52805 180)
			(unlocked yes)
			(layer "B.Fab")
			(hide yes)
			(effects
				(font
					(size 0.889 0.889)
					(thickness 0.1524)
				)
				(justify mirror)
			)
		)
		(property "Device Type" "MAX4564EKA-GP_SCRET-GC1-MAX456A"
			(at 5.08 -10.05205 180)
			(unlocked yes)
			(layer "B.Fab")
			(hide yes)
			(effects
				(font
					(size 0.889 0.889)
					(thickness 0.1524)
				)
				(justify mirror)
			)
		)
		(duplicate_pad_numbers_are_jumpers no)
		(fp_line
			(start 1.8796 0.5588)
			(end 1.8796 -0.5588)
			(stroke
				(width 0.1524)
				(type default)
			)
			(layer "B.SilkS")
		)
		(fp_line
			(start 1.8796 -0.254)
			(end 1.6256 0)
			(stroke
				(width 0.1524)
				(type default)
			)
			(layer "B.SilkS")
		)
		(fp_line
			(start 1.8796 -0.5588)
			(end -1.8796 -0.5588)
			(stroke
				(width 0.1524)
				(type default)
			)
			(layer "B.SilkS")
		)
		(fp_line
			(start 1.7018 0.5588)
			(end 1.7018 2.1082)
			(stroke
				(width 0.508)
				(type default)
			)
			(layer "B.SilkS")
		)
		(fp_line
			(start 1.6256 0)
			(end 1.8796 0.254)
			(stroke
				(width 0.1524)
				(type default)
			)
			(layer "B.SilkS")
		)
		(fp_line
			(start -1.8796 0.5588)
			(end 1.8796 0.5588)
			(stroke
				(width 0.1524)
				(type default)
			)
			(layer "B.SilkS")
		)
		(fp_line
			(start -1.8796 -0.5588)
			(end -1.8796 0.5588)
			(stroke
				(width 0.1524)
				(type default)
			)
			(layer "B.SilkS")
		)
		(fp_poly
			(pts
				(xy 1.15316 0.5588) (xy -1.8796 0.5588) (xy -1.8796 -0.5588) (xy 1.15316 -0.5588)
			)
			(stroke
				(width 0)
				(type default)
			)
			(fill yes)
			(layer "B.SilkS")
		)
		(fp_rect
			(start 1.9558 2.3622)
			(end -1.9558 -2.3622)
			(stroke
				(width 0)
				(type default)
			)
			(fill no)
			(layer "B.CrtYd")
		)
		(fp_poly
			(pts
				(xy 1.9558 -2.3622) (xy -1.9558 -2.3622) (xy -1.9558 2.3622) (xy 1.9558 2.3622)
			)
			(stroke
				(width 0)
				(type default)
			)
			(fill no)
			(layer "B.Fab")
		)
		(pad "1" smd rect
			(at 0.97536 1.3462)
			(size 0.3556 1.016)
			(layers "B.Cu" "B.Mask" "B.Paste")
			(net "JTAG_BMC_TCK0")
		)
		(pad "2" smd rect
			(at 0.32512 1.3462)
			(size 0.3556 1.016)
			(layers "B.Cu" "B.Mask" "B.Paste")
			(net "P3V3_STBY")
		)
		(pad "3" smd rect
			(at -0.32512 1.3462)
			(size 0.3556 1.016)
			(layers "B.Cu" "B.Mask" "B.Paste")
			(net "BMC_TCK_MUX_SEL")
		)
		(pad "4" smd rect
			(at -0.97409 1.3462)
			(size 0.3556 1.016)
			(layers "B.Cu" "B.Mask" "B.Paste")
			(net "JTAG_BMC_TCK1")
		)
		(pad "5" smd rect
			(at -0.97409 -1.3462)
			(size 0.3556 1.016)
			(layers "B.Cu" "B.Mask" "B.Paste")
			(net "GND")
		)
		(pad "6" smd rect
			(at -0.32512 -1.3462)
			(size 0.3556 1.016)
			(layers "B.Cu" "B.Mask" "B.Paste")
			(net "GND")
		)
		(pad "7" smd rect
			(at 0.32512 -1.3462)
			(size 0.3556 1.016)
			(layers "B.Cu" "B.Mask" "B.Paste")
			(net "BMC_JTAG_SEL_N")
		)
		(pad "8" smd rect
			(at 0.97536 -1.3462)
			(size 0.3556 1.016)
			(layers "B.Cu" "B.Mask" "B.Paste")
			(net "JTAG_BMC_TCK_BUF")
		)
	)
	(footprint ""
		(layer "B.Cu")
		(at 104.5591 -17.7546 90)
		(property "Reference" "C8T5"
			(at -1.848866 0.752348 90)
			(unlocked yes)
			(layer "B.SilkS")
			(effects
				(font
					(size 1.27 0.9652)
					(thickness 0.1524)
				)
				(justify mirror)
			)
		)
		(property "Value" ""
			(at 0 0 90)
			(layer "B.Fab")
			(effects
				(font
					(size 1.27 1.27)
				)
				(justify mirror)
			)
		)
		(duplicate_pad_numbers_are_jumpers no)
		(fp_rect
			(start 0.500126 1.598422)
			(end -0.500126 -0.201422)
			(stroke
				(width 0)
				(type default)
			)
			(fill no)
			(layer "B.CrtYd")
		)
		(fp_line
			(start 0.500126 -0.201422)
			(end -0.500126 -0.201422)
			(stroke
				(width 0.1)
				(type default)
			)
			(layer "B.Fab")
		)
		(fp_line
			(start -0.500126 -0.201422)
			(end -0.500126 1.598422)
			(stroke
				(width 0.1)
				(type default)
			)
			(layer "B.Fab")
		)
		(fp_line
			(start 0.500126 1.598422)
			(end 0.500126 -0.201422)
			(stroke
				(width 0.1)
				(type default)
			)
			(layer "B.Fab")
		)
		(fp_line
			(start -0.500126 1.598422)
			(end 0.500126 1.598422)
			(stroke
				(width 0.1)
				(type default)
			)
			(layer "B.Fab")
		)
		(pad "1" smd rect
			(at 0 0)
			(size 0.889 0.9906)
			(layers "B.Cu" "B.Mask" "B.Paste")
			(net "PVDDQ_GHJ")
		)
		(pad "2" smd rect
			(at 0 1.397)
			(size 0.889 0.9906)
			(layers "B.Cu" "B.Mask" "B.Paste")
			(net "GND")
		)
		(zone
			(layer "B.Cu")
			(hatch none 0.5)
			(connect_pads
				(clearance 0)
			)
			(min_thickness 0.25)
			(keepout
				(tracks not_allowed)
				(vias allowed)
				(pads allowed)
				(copperpour not_allowed)
				(footprints allowed)
			)
			(placement
				(enabled no)
				(sheetname "")
			)
			(fill
				(thermal_gap 0.5)
				(thermal_bridge_width 0.5)
				(island_removal_mode 0)
			)
			(polygon
				(pts
					(xy 105.5116 -18.2499) (xy 105.0036 -18.2499) (xy 105.0036 -17.2593) (xy 105.5116 -17.2593)
				)
			)
		)
		(zone
			(layer "B.Cu")
			(hatch none 0.5)
			(connect_pads
				(clearance 0)
			)
			(min_thickness 0.25)
			(keepout
				(tracks allowed)
				(vias not_allowed)
				(pads allowed)
				(copperpour not_allowed)
				(footprints allowed)
			)
			(placement
				(enabled no)
				(sheetname "")
			)
			(fill
				(thermal_gap 0.5)
				(thermal_bridge_width 0.5)
				(island_removal_mode 0)
			)
			(polygon
				(pts
					(xy 105.5116 -18.2499) (xy 105.0036 -18.2499) (xy 105.0036 -17.2593) (xy 105.5116 -17.2593)
				)
			)
		)
	)
	(footprint ""
		(layer "B.Cu")
		(at 365.936276 -156.15158 180)
		(property "Reference" "C22W26"
			(at 0 0 0)
			(layer "B.SilkS")
			(hide yes)
			(effects
				(font
					(size 1.27 1.27)
				)
				(justify mirror)
			)
		)
		(property "Value" "*"
			(at 0.0762 -6.2357 180)
			(unlocked yes)
			(layer "B.Fab")
			(hide yes)
			(effects
				(font
					(size 1.27 1.016)
					(thickness 0.1524)
				)
				(justify mirror)
			)
		)
		(property "Device Type" "SC22U16V5MX-4-GP_SMD-BCG5-SC22A"
			(at 0.0762 -8.2677 180)
			(unlocked yes)
			(layer "B.Fab")
			(hide yes)
			(effects
				(font
					(size 1.27 1.016)
					(thickness 0.1524)
				)
				(justify mirror)
			)
		)
		(duplicate_pad_numbers_are_jumpers no)
		(fp_line
			(start -0.635 0)
			(end 0.635 0)
			(stroke
				(width 0.508)
				(type default)
			)
			(layer "B.SilkS")
		)
		(fp_rect
			(start 0.9652 1.778)
			(end -0.9652 -1.778)
			(stroke
				(width 0)
				(type default)
			)
			(fill no)
			(layer "B.CrtYd")
		)
		(fp_poly
			(pts
				(xy 0.9652 -1.778) (xy -0.9652 -1.778) (xy -0.9652 1.778) (xy 0.9652 1.778)
			)
			(stroke
				(width 0)
				(type default)
			)
			(fill no)
			(layer "B.Fab")
		)
		(pad "1" smd rect
			(at 0 -0.9652)
			(size 1.397 1.143)
			(layers "B.Cu" "B.Mask" "B.Paste")
			(net "VR_FET_SW_P12V_STBY_PVDDQ_DEF")
		)
		(pad "2" smd rect
			(at 0 0.9652)
			(size 1.397 1.143)
			(layers "B.Cu" "B.Mask" "B.Paste")
			(net "GND")
		)
	)
	(footprint ""
		(layer "B.Cu")
		(at 88.392 -140.208 90)
		(property "Reference" "C5G111"
			(at -1.14681 0.76708 180)
			(unlocked yes)
			(layer "B.SilkS")
			(effects
				(font
					(size 0.7874 0.5842)
					(thickness 0.1524)
				)
				(justify mirror)
			)
		)
		(property "Value" ""
			(at 0 0 90)
			(layer "B.Fab")
			(effects
				(font
					(size 1.27 1.27)
				)
				(justify mirror)
			)
		)
		(duplicate_pad_numbers_are_jumpers no)
		(fp_rect
			(start -0.4953 -0.2032)
			(end 0.4953 1.6002)
			(stroke
				(width 0)
				(type default)
			)
			(fill no)
			(layer "B.CrtYd")
		)
		(fp_line
			(start 0.4953 -0.2032)
			(end -0.4953 -0.2032)
			(stroke
				(width 0.1)
				(type default)
			)
			(layer "B.Fab")
		)
		(fp_line
			(start -0.4953 -0.2032)
			(end -0.4953 1.6002)
			(stroke
				(width 0.1)
				(type default)
			)
			(layer "B.Fab")
		)
		(fp_line
			(start 0.4953 1.6002)
			(end 0.4953 -0.2032)
			(stroke
				(width 0.1)
				(type default)
			)
			(layer "B.Fab")
		)
		(fp_line
			(start -0.4953 1.6002)
			(end 0.4953 1.6002)
			(stroke
				(width 0.1)
				(type default)
			)
			(layer "B.Fab")
		)
		(pad "1" smd rect
			(at 0 0 270)
			(size 0.762 0.889)
			(layers "B.Cu" "B.Mask" "B.Paste")
			(net "PVDDQ_KLM")
		)
		(pad "2" smd rect
			(at 0 1.397 270)
			(size 0.762 0.889)
			(layers "B.Cu" "B.Mask" "B.Paste")
			(net "GND")
		)
		(zone
			(layer "B.Cu")
			(hatch none 0.5)
			(connect_pads
				(clearance 0)
			)
			(min_thickness 0.25)
			(keepout
				(tracks not_allowed)
				(vias allowed)
				(pads allowed)
				(copperpour not_allowed)
				(footprints allowed)
			)
			(placement
				(enabled no)
				(sheetname "")
			)
			(fill
				(thermal_gap 0.5)
				(thermal_bridge_width 0.5)
				(island_removal_mode 0)
			)
			(polygon
				(pts
					(xy 88.8365 -139.827) (xy 89.3445 -139.827) (xy 89.3445 -140.589) (xy 88.8365 -140.589)
				)
			)
		)
	)
	(footprint ""
		(layer "B.Cu")
		(at 467.20506 -16.392144)
		(property "Reference" "Q8G1"
			(at -1.9812 -1.92405 0)
			(unlocked yes)
			(layer "B.SilkS")
			(effects
				(font
					(size 0.7874 0.5842)
					(thickness 0.1524)
				)
				(justify left mirror)
			)
		)
		(property "Value" ""
			(at 0 0 0)
			(layer "B.Fab")
			(effects
				(font
					(size 1.27 1.27)
				)
				(justify mirror)
			)
		)
		(duplicate_pad_numbers_are_jumpers no)
		(fp_line
			(start 0.245364 -1.379982)
			(end -3.15468 -1.379982)
			(stroke
				(width 0.1524)
				(type default)
			)
			(layer "B.SilkS")
		)
		(fp_line
			(start 0.245364 2.020062)
			(end -3.15468 2.020062)
			(stroke
				(width 0.1524)
				(type default)
			)
			(layer "B.SilkS")
		)
		(fp_circle
			(center 0.84455 -0.216154)
			(end 0.97155 -0.216154)
			(stroke
				(width 0.254)
				(type default)
			)
			(fill no)
			(layer "B.SilkS")
		)
		(fp_poly
			(pts
				(xy -0.890016 -0.82296) (xy -0.890016 1.46304) (xy -3.404616 1.46304) (xy -3.404616 1.13284) (xy -2.617216 1.13284)
				(xy -2.617216 0.811022) (xy -3.404616 0.811022) (xy -3.404616 0.480822) (xy -2.617216 0.480822)
				(xy -2.617216 0.159258) (xy -3.404616 0.159258) (xy -3.404616 -0.170942) (xy -2.617216 -0.170942)
				(xy -2.617216 -0.49276) (xy -3.404616 -0.49276) (xy -3.404616 -0.82296)
			)
			(stroke
				(width 0)
				(type default)
			)
			(fill yes)
			(layer "B.Paste")
		)
		(fp_poly
			(pts
				(xy 0.245364 -1.379982) (xy 0.245364 2.020062) (xy -3.15468 2.020062) (xy -3.15468 -1.379982)
			)
			(stroke
				(width 0)
				(type default)
			)
			(fill no)
			(layer "B.CrtYd")
		)
		(fp_line
			(start -3.15468 -1.379982)
			(end -3.15468 2.020062)
			(stroke
				(width 0.1)
				(type default)
			)
			(layer "B.Fab")
		)
		(fp_line
			(start -3.15468 2.020062)
			(end 0.245364 2.020062)
			(stroke
				(width 0.1)
				(type default)
			)
			(layer "B.Fab")
		)
		(fp_line
			(start 0.245364 -1.379982)
			(end -3.15468 -1.379982)
			(stroke
				(width 0.1)
				(type default)
			)
			(layer "B.Fab")
		)
		(fp_line
			(start 0.245364 2.020062)
			(end 0.245364 -1.379982)
			(stroke
				(width 0.1)
				(type default)
			)
			(layer "B.Fab")
		)
		(fp_circle
			(center 0.94996 -1.512316)
			(end 1.07696 -1.512316)
			(stroke
				(width 0.254)
				(type default)
			)
			(fill no)
			(layer "B.Fab")
		)
		(pad "1" smd custom
			(at 0 0 180)
			(size 0.24765 0.24765)
			(layers "B.Cu" "B.Mask" "B.Paste")
			(net "P3V3")
			(options
				(clearance outline)
				(anchor circle)
			)
			(primitives
				(gr_poly
					(pts
						(xy 0.4953 -0.8255) (xy 0.4953 0.8255) (xy -0.4953 0.8255) (xy -0.4953 0.4953) (xy 0.0127 0.4953)
						(xy 0.0127 0.1651) (xy -0.4953 0.1651) (xy -0.4953 -0.1651) (xy 0.0127 -0.1651) (xy 0.0127 -0.4953)
						(xy -0.4953 -0.4953) (xy -0.4953 -0.8255)
					)
					(width 0)
					(fill yes)
				)
			)
		)
		(pad "4" smd rect
			(at 0 1.30048 180)
			(size 0.9906 0.3302)
			(layers "B.Cu" "B.Mask" "B.Paste")
			(net "P3V3_SWITCH_G")
		)
		(pad "5" smd custom
			(at -2.147316 0.32004 180)
			(size 0.5715 0.5715)
			(layers "B.Cu" "B.Mask" "B.Paste")
			(net "P3V3_STBY")
			(options
				(clearance outline)
				(anchor circle)
			)
			(primitives
				(gr_poly
					(pts
						(xy -1.2573 1.143) (xy -1.2573 -1.143) (xy 1.2573 -1.143) (xy 1.2573 -0.8128) (xy 0.4699 -0.8128)
						(xy 0.4699 -0.490982) (xy 1.2573 -0.490982) (xy 1.2573 -0.160782) (xy 0.4699 -0.160782) (xy 0.4699 0.160782)
						(xy 1.2573 0.160782) (xy 1.2573 0.490982) (xy 0.4699 0.490982) (xy 0.4699 0.8128) (xy 1.2573 0.8128)
						(xy 1.2573 1.143)
					)
					(width 0)
					(fill yes)
				)
			)
		)
	)
	(footprint ""
		(layer "B.Cu")
		(at 198.623428 -61.285882 90)
		(property "Reference" "C4E25"
			(at 0 0 90)
			(layer "B.SilkS")
			(hide yes)
			(effects
				(font
					(size 1.27 1.27)
				)
				(justify mirror)
			)
		)
		(property "Value" "*"
			(at -1.1811 -2.8194 90)
			(unlocked yes)
			(layer "B.Fab")
			(hide yes)
			(effects
				(font
					(size 1.27 1.016)
					(thickness 0.1524)
				)
				(justify mirror)
			)
		)
		(property "Device Type" "SC1U10V2KX-4-GP_SMD-BCG6-SC1U1A"
			(at -1.1811 -4.3434 90)
			(unlocked yes)
			(layer "B.Fab")
			(hide yes)
			(effects
				(font
					(size 1.27 1.016)
					(thickness 0.1524)
				)
				(justify mirror)
			)
		)
		(duplicate_pad_numbers_are_jumpers no)
		(fp_rect
			(start 0.4318 0.9525)
			(end -0.4318 -0.9525)
			(stroke
				(width 0)
				(type default)
			)
			(fill no)
			(layer "B.CrtYd")
		)
		(fp_rect
			(start 0.4318 0.9525)
			(end -0.4318 -0.9525)
			(stroke
				(width 0)
				(type default)
			)
			(fill no)
			(layer "B.Fab")
		)
		(pad "1" smd custom
			(at 0 -0.4445 270)
			(size 0.1524 0.1524)
			(layers "B.Cu" "B.Mask" "B.Paste")
			(net "P5V_STBY")
			(options
				(clearance outline)
				(anchor circle)
			)
			(primitives
				(gr_poly
					(pts
						(arc
							(start 0.3048 0.2032)
							(mid 0.275042 0.275042)
							(end 0.2032 0.3048)
						)
						(arc
							(start -0.2032 0.3048)
							(mid -0.275042 0.275042)
							(end -0.3048 0.2032)
						)
						(arc
							(start -0.3048 -0.2032)
							(mid -0.275042 -0.275042)
							(end -0.2032 -0.3048)
						)
						(arc
							(start 0.2032 -0.3048)
							(mid 0.275042 -0.275042)
							(end 0.3048 -0.2032)
						)
					)
					(width 0)
					(fill yes)
				)
			)
		)
		(pad "2" smd custom
			(at 0 0.4445 270)
			(size 0.1524 0.1524)
			(layers "B.Cu" "B.Mask" "B.Paste")
			(net "GND")
			(options
				(clearance outline)
				(anchor circle)
			)
			(primitives
				(gr_poly
					(pts
						(arc
							(start 0.3048 0.2032)
							(mid 0.275042 0.275042)
							(end 0.2032 0.3048)
						)
						(arc
							(start -0.2032 0.3048)
							(mid -0.275042 0.275042)
							(end -0.3048 0.2032)
						)
						(arc
							(start -0.3048 -0.2032)
							(mid -0.275042 -0.275042)
							(end -0.2032 -0.3048)
						)
						(arc
							(start 0.2032 -0.3048)
							(mid 0.275042 -0.275042)
							(end 0.3048 -0.2032)
						)
					)
					(width 0)
					(fill yes)
				)
			)
		)
	)
	(footprint ""
		(layer "B.Cu")
		(at 372.411752 -42.615358 180)
		(property "Reference" "R2T31"
			(at 0 0 0)
			(layer "B.SilkS")
			(hide yes)
			(effects
				(font
					(size 1.27 1.27)
				)
				(justify mirror)
			)
		)
		(property "Value" ""
			(at 0 0 0)
			(layer "B.Fab")
			(effects
				(font
					(size 1.27 1.27)
				)
				(justify mirror)
			)
		)
		(duplicate_pad_numbers_are_jumpers no)
		(fp_poly
			(pts
				(xy 0.2794 -0.1016) (xy -0.2794 -0.1016) (xy -0.2794 0.9906) (xy 0.2794 0.9906)
			)
			(stroke
				(width 0)
				(type default)
			)
			(fill no)
			(layer "B.CrtYd")
		)
		(fp_line
			(start 0.2794 0.9906)
			(end -0.2794 0.9906)
			(stroke
				(width 0.1)
				(type default)
			)
			(layer "B.Fab")
		)
		(fp_line
			(start 0.2794 -0.1016)
			(end 0.2794 0.9906)
			(stroke
				(width 0.1)
				(type default)
			)
			(layer "B.Fab")
		)
		(fp_line
			(start -0.2794 0.9906)
			(end -0.2794 -0.1016)
			(stroke
				(width 0.1)
				(type default)
			)
			(layer "B.Fab")
		)
		(fp_line
			(start -0.2794 -0.1016)
			(end 0.2794 -0.1016)
			(stroke
				(width 0.1)
				(type default)
			)
			(layer "B.Fab")
		)
		(pad "1" smd rect
			(at 0 0)
			(size 0.508 0.508)
			(layers "B.Cu" "B.Mask" "B.Paste")
			(net "H_CPU_ERR1_GTL_R_N")
		)
		(pad "2" smd rect
			(at 0 0.889)
			(size 0.508 0.508)
			(layers "B.Cu" "B.Mask" "B.Paste")
			(net "H_CPU_ERR1_GTL_N")
		)
		(zone
			(layer "B.Cu")
			(hatch none 0.5)
			(connect_pads
				(clearance 0)
			)
			(min_thickness 0.25)
			(keepout
				(tracks not_allowed)
				(vias allowed)
				(pads allowed)
				(copperpour not_allowed)
				(footprints allowed)
			)
			(placement
				(enabled no)
				(sheetname "")
			)
			(fill
				(thermal_gap 0.5)
				(thermal_bridge_width 0.5)
				(island_removal_mode 0)
			)
			(polygon
				(pts
					(xy 372.157752 -43.250358) (xy 372.665752 -43.250358) (xy 372.665752 -42.869358) (xy 372.157752 -42.869358)
				)
			)
		)
		(zone
			(layer "B.Cu")
			(hatch none 0.5)
			(connect_pads
				(clearance 0)
			)
			(min_thickness 0.25)
			(keepout
				(tracks allowed)
				(vias not_allowed)
				(pads allowed)
				(copperpour not_allowed)
				(footprints allowed)
			)
			(placement
				(enabled no)
				(sheetname "")
			)
			(fill
				(thermal_gap 0.5)
				(thermal_bridge_width 0.5)
				(island_removal_mode 0)
			)
			(polygon
				(pts
					(xy 372.157752 -42.869358) (xy 372.665752 -42.869358) (xy 372.665752 -43.250358) (xy 372.157752 -43.250358)
				)
			)
		)
	)
	(footprint ""
		(layer "B.Cu")
		(at 499.745 -153.1874 90)
		(property "Reference" "R6W36"
			(at 0.8382 -0.67818 90)
			(unlocked yes)
			(layer "B.SilkS")
			(effects
				(font
					(size 0.4064 0.254)
					(thickness 0.1524)
				)
				(justify left mirror)
			)
		)
		(property "Value" ""
			(at 0 0 90)
			(layer "B.Fab")
			(effects
				(font
					(size 1.27 1.27)
				)
				(justify mirror)
			)
		)
		(duplicate_pad_numbers_are_jumpers no)
		(fp_poly
			(pts
				(xy 0.2794 -0.1016) (xy -0.2794 -0.1016) (xy -0.2794 0.9906) (xy 0.2794 0.9906)
			)
			(stroke
				(width 0)
				(type default)
			)
			(fill no)
			(layer "B.CrtYd")
		)
		(fp_line
			(start 0.2794 -0.1016)
			(end 0.2794 0.9906)
			(stroke
				(width 0.1)
				(type default)
			)
			(layer "B.Fab")
		)
		(fp_line
			(start -0.2794 -0.1016)
			(end 0.2794 -0.1016)
			(stroke
				(width 0.1)
				(type default)
			)
			(layer "B.Fab")
		)
		(fp_line
			(start 0.2794 0.9906)
			(end -0.2794 0.9906)
			(stroke
				(width 0.1)
				(type default)
			)
			(layer "B.Fab")
		)
		(fp_line
			(start -0.2794 0.9906)
			(end -0.2794 -0.1016)
			(stroke
				(width 0.1)
				(type default)
			)
			(layer "B.Fab")
		)
		(pad "1" smd rect
			(at 0 0 270)
			(size 0.508 0.508)
			(layers "B.Cu" "B.Mask" "B.Paste")
			(net "SPA_MID_DBG1_TX_R")
		)
		(pad "2" smd rect
			(at 0 0.889 270)
			(size 0.508 0.508)
			(layers "B.Cu" "B.Mask" "B.Paste")
			(net "SPA_MID_DBG1_TX")
		)
		(zone
			(layer "B.Cu")
			(hatch none 0.5)
			(connect_pads
				(clearance 0)
			)
			(min_thickness 0.25)
			(keepout
				(tracks allowed)
				(vias not_allowed)
				(pads allowed)
				(copperpour not_allowed)
				(footprints allowed)
			)
			(placement
				(enabled no)
				(sheetname "")
			)
			(fill
				(thermal_gap 0.5)
				(thermal_bridge_width 0.5)
				(island_removal_mode 0)
			)
			(polygon
				(pts
					(xy 499.999 -153.4414) (xy 499.999 -152.9334) (xy 500.38 -152.9334) (xy 500.38 -153.4414)
				)
			)
		)
		(zone
			(layer "B.Cu")
			(hatch none 0.5)
			(connect_pads
				(clearance 0)
			)
			(min_thickness 0.25)
			(keepout
				(tracks not_allowed)
				(vias allowed)
				(pads allowed)
				(copperpour not_allowed)
				(footprints allowed)
			)
			(placement
				(enabled no)
				(sheetname "")
			)
			(fill
				(thermal_gap 0.5)
				(thermal_bridge_width 0.5)
				(island_removal_mode 0)
			)
			(polygon
				(pts
					(xy 500.38 -153.4414) (xy 500.38 -152.9334) (xy 499.999 -152.9334) (xy 499.999 -153.4414)
				)
			)
		)
	)
	(footprint ""
		(layer "B.Cu")
		(at 367.820956 -121.443242 -90)
		(property "Reference" "R785"
			(at 0.8382 -0.67818 270)
			(unlocked yes)
			(layer "B.SilkS")
			(effects
				(font
					(size 0.4064 0.254)
					(thickness 0.1524)
				)
				(justify left mirror)
			)
		)
		(property "Value" ""
			(at 0 0 90)
			(layer "B.Fab")
			(effects
				(font
					(size 1.27 1.27)
				)
				(justify mirror)
			)
		)
		(duplicate_pad_numbers_are_jumpers no)
		(fp_poly
			(pts
				(xy 0.2794 -0.1016) (xy -0.2794 -0.1016) (xy -0.2794 0.9906) (xy 0.2794 0.9906)
			)
			(stroke
				(width 0)
				(type default)
			)
			(fill no)
			(layer "B.CrtYd")
		)
		(fp_line
			(start -0.2794 0.9906)
			(end -0.2794 -0.1016)
			(stroke
				(width 0.1)
				(type default)
			)
			(layer "B.Fab")
		)
		(fp_line
			(start 0.2794 0.9906)
			(end -0.2794 0.9906)
			(stroke
				(width 0.1)
				(type default)
			)
			(layer "B.Fab")
		)
		(fp_line
			(start -0.2794 -0.1016)
			(end 0.2794 -0.1016)
			(stroke
				(width 0.1)
				(type default)
			)
			(layer "B.Fab")
		)
		(fp_line
			(start 0.2794 -0.1016)
			(end 0.2794 0.9906)
			(stroke
				(width 0.1)
				(type default)
			)
			(layer "B.Fab")
		)
		(pad "1" smd rect
			(at 0 0 90)
			(size 0.508 0.508)
			(layers "B.Cu" "B.Mask" "B.Paste")
			(net "P3E_CPU0_PE1_PCH_RXP<8>")
		)
		(pad "2" smd rect
			(at 0 0.889 90)
			(size 0.508 0.508)
			(layers "B.Cu" "B.Mask" "B.Paste")
			(net "P3E_CPU0_PE1_PCH_CON_RXP<8>")
		)
		(zone
			(layer "B.Cu")
			(hatch none 0.5)
			(connect_pads
				(clearance 0)
			)
			(min_thickness 0.25)
			(keepout
				(tracks not_allowed)
				(vias allowed)
				(pads allowed)
				(copperpour not_allowed)
				(footprints allowed)
			)
			(placement
				(enabled no)
				(sheetname "")
			)
			(fill
				(thermal_gap 0.5)
				(thermal_bridge_width 0.5)
				(island_removal_mode 0)
			)
			(polygon
				(pts
					(xy 367.185956 -121.189242) (xy 367.185956 -121.697242) (xy 367.566956 -121.697242) (xy 367.566956 -121.189242)
				)
			)
		)
		(zone
			(layer "B.Cu")
			(hatch none 0.5)
			(connect_pads
				(clearance 0)
			)
			(min_thickness 0.25)
			(keepout
				(tracks allowed)
				(vias not_allowed)
				(pads allowed)
				(copperpour not_allowed)
				(footprints allowed)
			)
			(placement
				(enabled no)
				(sheetname "")
			)
			(fill
				(thermal_gap 0.5)
				(thermal_bridge_width 0.5)
				(island_removal_mode 0)
			)
			(polygon
				(pts
					(xy 367.566956 -121.189242) (xy 367.566956 -121.697242) (xy 367.185956 -121.697242) (xy 367.185956 -121.189242)
				)
			)
		)
	)
	(footprint ""
		(layer "B.Cu")
		(at 430.85512 -141.101318 90)
		(property "Reference" "C2L51"
			(at 0 0 90)
			(layer "B.SilkS")
			(hide yes)
			(effects
				(font
					(size 1.27 1.27)
				)
				(justify mirror)
			)
		)
		(property "Value" ""
			(at 0 0 90)
			(layer "B.Fab")
			(effects
				(font
					(size 1.27 1.27)
				)
				(justify mirror)
			)
		)
		(duplicate_pad_numbers_are_jumpers no)
		(fp_poly
			(pts
				(xy -0.3048 -0.1016) (xy -0.3048 0.9906) (xy 0.3048 0.9906) (xy 0.3048 -0.1016)
			)
			(stroke
				(width 0)
				(type default)
			)
			(fill no)
			(layer "B.CrtYd")
		)
		(fp_line
			(start 0.3048 -0.1016)
			(end 0.3048 0.9906)
			(stroke
				(width 0.1)
				(type default)
			)
			(layer "B.Fab")
		)
		(fp_line
			(start -0.3048 -0.1016)
			(end 0.3048 -0.1016)
			(stroke
				(width 0.1)
				(type default)
			)
			(layer "B.Fab")
		)
		(fp_line
			(start 0.3048 0.9906)
			(end -0.3048 0.9906)
			(stroke
				(width 0.1)
				(type default)
			)
			(layer "B.Fab")
		)
		(fp_line
			(start -0.3048 0.9906)
			(end -0.3048 -0.1016)
			(stroke
				(width 0.1)
				(type default)
			)
			(layer "B.Fab")
		)
		(pad "1" smd rect
			(at 0 0 270)
			(size 0.508 0.508)
			(layers "B.Cu" "B.Mask" "B.Paste")
			(net "SATA6G_S1_TX_C_DN")
		)
		(pad "2" smd rect
			(at 0 0.889 270)
			(size 0.508 0.508)
			(layers "B.Cu" "B.Mask" "B.Paste")
			(net "SATA6G_S1_TX_DN")
		)
		(zone
			(layer "B.Cu")
			(hatch none 0.5)
			(connect_pads
				(clearance 0)
			)
			(min_thickness 0.25)
			(keepout
				(tracks allowed)
				(vias not_allowed)
				(pads allowed)
				(copperpour not_allowed)
				(footprints allowed)
			)
			(placement
				(enabled no)
				(sheetname "")
			)
			(fill
				(thermal_gap 0.5)
				(thermal_bridge_width 0.5)
				(island_removal_mode 0)
			)
			(polygon
				(pts
					(xy 431.10912 -141.355318) (xy 431.10912 -140.847318) (xy 431.49012 -140.847318) (xy 431.49012 -141.355318)
				)
			)
		)
		(zone
			(layer "B.Cu")
			(hatch none 0.5)
			(connect_pads
				(clearance 0)
			)
			(min_thickness 0.25)
			(keepout
				(tracks not_allowed)
				(vias allowed)
				(pads allowed)
				(copperpour not_allowed)
				(footprints allowed)
			)
			(placement
				(enabled no)
				(sheetname "")
			)
			(fill
				(thermal_gap 0.5)
				(thermal_bridge_width 0.5)
				(island_removal_mode 0)
			)
			(polygon
				(pts
					(xy 431.49012 -141.355318) (xy 431.49012 -140.847318) (xy 431.10912 -140.847318) (xy 431.10912 -141.355318)
				)
			)
		)
	)
	(footprint ""
		(layer "B.Cu")
		(at 384.4036 -109.855 -90)
		(property "Reference" "C3N11"
			(at 0 0 90)
			(layer "B.SilkS")
			(hide yes)
			(effects
				(font
					(size 1.27 1.27)
				)
				(justify mirror)
			)
		)
		(property "Value" ""
			(at 0 0 90)
			(layer "B.Fab")
			(effects
				(font
					(size 1.27 1.27)
				)
				(justify mirror)
			)
		)
		(duplicate_pad_numbers_are_jumpers no)
		(fp_rect
			(start 0.499872 1.522476)
			(end -0.500126 -0.277622)
			(stroke
				(width 0)
				(type default)
			)
			(fill no)
			(layer "B.CrtYd")
		)
		(fp_line
			(start -0.500126 1.522476)
			(end 0.499872 1.522476)
			(stroke
				(width 0.1)
				(type default)
			)
			(layer "B.Fab")
		)
		(fp_line
			(start 0.499872 1.522476)
			(end 0.499872 -0.277622)
			(stroke
				(width 0.1)
				(type default)
			)
			(layer "B.Fab")
		)
		(fp_line
			(start -0.500126 -0.277622)
			(end -0.500126 1.522476)
			(stroke
				(width 0.1)
				(type default)
			)
			(layer "B.Fab")
		)
		(fp_line
			(start 0.499872 -0.277622)
			(end -0.500126 -0.277622)
			(stroke
				(width 0.1)
				(type default)
			)
			(layer "B.Fab")
		)
		(pad "1" smd custom
			(at 0 0 180)
			(size 0.18415 0.18415)
			(layers "B.Cu" "B.Mask" "B.Paste")
			(net "PVNN_PCH_STBY")
			(options
				(clearance outline)
				(anchor circle)
			)
			(primitives
				(gr_poly
					(pts
						(arc
							(start -0.3683 0.2794)
							(mid -0.338542 0.351242)
							(end -0.2667 0.381)
						)
						(arc
							(start 0.2667 0.381)
							(mid 0.338542 0.351242)
							(end 0.3683 0.2794)
						)
						(arc
							(start 0.3683 -0.2794)
							(mid 0.338542 -0.351242)
							(end 0.2667 -0.381)
						)
						(arc
							(start -0.2667 -0.381)
							(mid -0.338542 -0.351242)
							(end -0.3683 -0.2794)
						)
					)
					(width 0)
					(fill yes)
				)
			)
		)
		(pad "2" smd custom
			(at 0 1.2446 180)
			(size 0.18415 0.18415)
			(layers "B.Cu" "B.Mask" "B.Paste")
			(net "GND")
			(options
				(clearance outline)
				(anchor circle)
			)
			(primitives
				(gr_poly
					(pts
						(arc
							(start -0.3683 0.2794)
							(mid -0.338542 0.351242)
							(end -0.2667 0.381)
						)
						(arc
							(start 0.2667 0.381)
							(mid 0.338542 0.351242)
							(end 0.3683 0.2794)
						)
						(arc
							(start 0.3683 -0.2794)
							(mid 0.338542 -0.351242)
							(end 0.2667 -0.381)
						)
						(arc
							(start -0.2667 -0.381)
							(mid -0.338542 -0.351242)
							(end -0.3683 -0.2794)
						)
					)
					(width 0)
					(fill yes)
				)
			)
		)
		(zone
			(layer "B.Cu")
			(hatch none 0.5)
			(connect_pads
				(clearance 0)
			)
			(min_thickness 0.25)
			(keepout
				(tracks allowed)
				(vias not_allowed)
				(pads allowed)
				(copperpour not_allowed)
				(footprints allowed)
			)
			(placement
				(enabled no)
				(sheetname "")
			)
			(fill
				(thermal_gap 0.5)
				(thermal_bridge_width 0.5)
				(island_removal_mode 0)
			)
			(polygon
				(pts
					(xy 383.5273 -109.474) (xy 384.0353 -109.474) (xy 384.0353 -110.236) (xy 383.5273 -110.236)
				)
			)
		)
		(zone
			(layer "B.Cu")
			(hatch none 0.5)
			(connect_pads
				(clearance 0)
			)
			(min_thickness 0.25)
			(keepout
				(tracks not_allowed)
				(vias allowed)
				(pads allowed)
				(copperpour not_allowed)
				(footprints allowed)
			)
			(placement
				(enabled no)
				(sheetname "")
			)
			(fill
				(thermal_gap 0.5)
				(thermal_bridge_width 0.5)
				(island_removal_mode 0)
			)
			(polygon
				(pts
					(xy 383.5273 -109.474) (xy 384.0353 -109.474) (xy 384.0353 -110.236) (xy 383.5273 -110.236)
				)
			)
		)
	)
	(footprint ""
		(layer "B.Cu")
		(at 386.842 -87.3125 180)
		(property "Reference" "R3N12"
			(at 0 0 0)
			(layer "B.SilkS")
			(hide yes)
			(effects
				(font
					(size 1.27 1.27)
				)
				(justify mirror)
			)
		)
		(property "Value" ""
			(at 0 0 0)
			(layer "B.Fab")
			(effects
				(font
					(size 1.27 1.27)
				)
				(justify mirror)
			)
		)
		(duplicate_pad_numbers_are_jumpers no)
		(fp_poly
			(pts
				(xy 0.2794 -0.1016) (xy -0.2794 -0.1016) (xy -0.2794 0.9906) (xy 0.2794 0.9906)
			)
			(stroke
				(width 0)
				(type default)
			)
			(fill no)
			(layer "B.CrtYd")
		)
		(fp_line
			(start 0.2794 0.9906)
			(end -0.2794 0.9906)
			(stroke
				(width 0.1)
				(type default)
			)
			(layer "B.Fab")
		)
		(fp_line
			(start 0.2794 -0.1016)
			(end 0.2794 0.9906)
			(stroke
				(width 0.1)
				(type default)
			)
			(layer "B.Fab")
		)
		(fp_line
			(start -0.2794 0.9906)
			(end -0.2794 -0.1016)
			(stroke
				(width 0.1)
				(type default)
			)
			(layer "B.Fab")
		)
		(fp_line
			(start -0.2794 -0.1016)
			(end 0.2794 -0.1016)
			(stroke
				(width 0.1)
				(type default)
			)
			(layer "B.Fab")
		)
		(pad "1" smd rect
			(at 0 0)
			(size 0.508 0.508)
			(layers "B.Cu" "B.Mask" "B.Paste")
			(net "P3V3_STBY")
		)
		(pad "2" smd rect
			(at 0 0.889)
			(size 0.508 0.508)
			(layers "B.Cu" "B.Mask" "B.Paste")
			(net "FM_MP_PS_FAIL_N")
		)
		(zone
			(layer "B.Cu")
			(hatch none 0.5)
			(connect_pads
				(clearance 0)
			)
			(min_thickness 0.25)
			(keepout
				(tracks not_allowed)
				(vias allowed)
				(pads allowed)
				(copperpour not_allowed)
				(footprints allowed)
			)
			(placement
				(enabled no)
				(sheetname "")
			)
			(fill
				(thermal_gap 0.5)
				(thermal_bridge_width 0.5)
				(island_removal_mode 0)
			)
			(polygon
				(pts
					(xy 386.588 -87.9475) (xy 387.096 -87.9475) (xy 387.096 -87.5665) (xy 386.588 -87.5665)
				)
			)
		)
		(zone
			(layer "B.Cu")
			(hatch none 0.5)
			(connect_pads
				(clearance 0)
			)
			(min_thickness 0.25)
			(keepout
				(tracks allowed)
				(vias not_allowed)
				(pads allowed)
				(copperpour not_allowed)
				(footprints allowed)
			)
			(placement
				(enabled no)
				(sheetname "")
			)
			(fill
				(thermal_gap 0.5)
				(thermal_bridge_width 0.5)
				(island_removal_mode 0)
			)
			(polygon
				(pts
					(xy 386.588 -87.5665) (xy 387.096 -87.5665) (xy 387.096 -87.9475) (xy 386.588 -87.9475)
				)
			)
		)
	)
	(footprint ""
		(layer "B.Cu")
		(at 45.212 -89.408 -90)
		(property "Reference" "C9N24"
			(at -0.35433 -3.937 0)
			(unlocked yes)
			(layer "B.SilkS")
			(effects
				(font
					(size 0.7874 0.5842)
					(thickness 0.1524)
				)
				(justify mirror)
			)
		)
		(property "Value" ""
			(at 0 0 90)
			(layer "B.Fab")
			(effects
				(font
					(size 1.27 1.27)
				)
				(justify mirror)
			)
		)
		(duplicate_pad_numbers_are_jumpers no)
		(fp_line
			(start -2.286 7.366)
			(end -1.600708 7.366)
			(stroke
				(width 0.1524)
				(type default)
			)
			(layer "B.SilkS")
		)
		(fp_line
			(start -2.286 7.366)
			(end -2.286 1.63195)
			(stroke
				(width 0.1524)
				(type default)
			)
			(layer "B.SilkS")
		)
		(fp_line
			(start 2.286 7.366)
			(end 1.60147 7.366)
			(stroke
				(width 0.1524)
				(type default)
			)
			(layer "B.SilkS")
		)
		(fp_line
			(start 2.286 7.366)
			(end 2.286 1.632712)
			(stroke
				(width 0.1524)
				(type default)
			)
			(layer "B.SilkS")
		)
		(fp_line
			(start -2.504948 1.633728)
			(end -1.6002 1.633728)
			(stroke
				(width 0.1524)
				(type default)
			)
			(layer "B.SilkS")
		)
		(fp_line
			(start 2.563114 1.633728)
			(end 1.6002 1.633728)
			(stroke
				(width 0.1524)
				(type default)
			)
			(layer "B.SilkS")
		)
		(fp_line
			(start -2.504948 -1.616456)
			(end -2.504948 1.633728)
			(stroke
				(width 0.1524)
				(type default)
			)
			(layer "B.SilkS")
		)
		(fp_line
			(start -1.6002 -1.616456)
			(end -2.504948 -1.616456)
			(stroke
				(width 0.1524)
				(type default)
			)
			(layer "B.SilkS")
		)
		(fp_line
			(start 1.6002 -1.616456)
			(end 2.563114 -1.616456)
			(stroke
				(width 0.1524)
				(type default)
			)
			(layer "B.SilkS")
		)
		(fp_line
			(start 2.563114 -1.616456)
			(end 2.563114 1.633728)
			(stroke
				(width 0.1524)
				(type default)
			)
			(layer "B.SilkS")
		)
		(fp_rect
			(start 2.286 7.366)
			(end -2.286 -0.254)
			(stroke
				(width 0)
				(type default)
			)
			(fill no)
			(layer "B.CrtYd")
		)
		(fp_line
			(start -2.286 7.366)
			(end 2.286 7.366)
			(stroke
				(width 0.1)
				(type default)
			)
			(layer "B.Fab")
		)
		(fp_line
			(start 2.286 7.366)
			(end 2.286 -0.254)
			(stroke
				(width 0.1)
				(type default)
			)
			(layer "B.Fab")
		)
		(fp_line
			(start -2.286 -0.254)
			(end -2.286 7.366)
			(stroke
				(width 0.1)
				(type default)
			)
			(layer "B.Fab")
		)
		(fp_line
			(start 2.286 -0.254)
			(end -2.286 -0.254)
			(stroke
				(width 0.1)
				(type default)
			)
			(layer "B.Fab")
		)
		(pad "1" smd rect
			(at 0 0 90)
			(size 2.54 3.048)
			(layers "B.Cu" "B.Mask" "B.Paste")
			(net "PVCCIN_CPU1")
		)
		(pad "2" smd rect
			(at 0 7.112 90)
			(size 2.54 3.048)
			(layers "B.Cu" "B.Mask" "B.Paste")
			(net "GND")
		)
	)
	(footprint ""
		(layer "B.Cu")
		(at 327.158096 -54.597808 90)
		(property "Reference" "R5W1"
			(at 0.8382 -0.67818 90)
			(unlocked yes)
			(layer "B.SilkS")
			(effects
				(font
					(size 0.4064 0.254)
					(thickness 0.1524)
				)
				(justify left mirror)
			)
		)
		(property "Value" ""
			(at 0 0 90)
			(layer "B.Fab")
			(effects
				(font
					(size 1.27 1.27)
				)
				(justify mirror)
			)
		)
		(duplicate_pad_numbers_are_jumpers no)
		(fp_poly
			(pts
				(xy 0.2794 -0.1016) (xy -0.2794 -0.1016) (xy -0.2794 0.9906) (xy 0.2794 0.9906)
			)
			(stroke
				(width 0)
				(type default)
			)
			(fill no)
			(layer "B.CrtYd")
		)
		(fp_line
			(start 0.2794 -0.1016)
			(end 0.2794 0.9906)
			(stroke
				(width 0.1)
				(type default)
			)
			(layer "B.Fab")
		)
		(fp_line
			(start -0.2794 -0.1016)
			(end 0.2794 -0.1016)
			(stroke
				(width 0.1)
				(type default)
			)
			(layer "B.Fab")
		)
		(fp_line
			(start 0.2794 0.9906)
			(end -0.2794 0.9906)
			(stroke
				(width 0.1)
				(type default)
			)
			(layer "B.Fab")
		)
		(fp_line
			(start -0.2794 0.9906)
			(end -0.2794 -0.1016)
			(stroke
				(width 0.1)
				(type default)
			)
			(layer "B.Fab")
		)
		(pad "1" smd rect
			(at 0 0 270)
			(size 0.508 0.508)
			(layers "B.Cu" "B.Mask" "B.Paste")
			(net "P1V8_MCP_CPU0")
		)
		(pad "2" smd rect
			(at 0 0.889 270)
			(size 0.508 0.508)
			(layers "B.Cu" "B.Mask" "B.Paste")
			(net "JTAG_MCP_CPU0_TDI_R")
		)
		(zone
			(layer "B.Cu")
			(hatch none 0.5)
			(connect_pads
				(clearance 0)
			)
			(min_thickness 0.25)
			(keepout
				(tracks allowed)
				(vias not_allowed)
				(pads allowed)
				(copperpour not_allowed)
				(footprints allowed)
			)
			(placement
				(enabled no)
				(sheetname "")
			)
			(fill
				(thermal_gap 0.5)
				(thermal_bridge_width 0.5)
				(island_removal_mode 0)
			)
			(polygon
				(pts
					(xy 327.412096 -54.851808) (xy 327.412096 -54.343808) (xy 327.793096 -54.343808) (xy 327.793096 -54.851808)
				)
			)
		)
		(zone
			(layer "B.Cu")
			(hatch none 0.5)
			(connect_pads
				(clearance 0)
			)
			(min_thickness 0.25)
			(keepout
				(tracks not_allowed)
				(vias allowed)
				(pads allowed)
				(copperpour not_allowed)
				(footprints allowed)
			)
			(placement
				(enabled no)
				(sheetname "")
			)
			(fill
				(thermal_gap 0.5)
				(thermal_bridge_width 0.5)
				(island_removal_mode 0)
			)
			(polygon
				(pts
					(xy 327.793096 -54.851808) (xy 327.793096 -54.343808) (xy 327.412096 -54.343808) (xy 327.412096 -54.851808)
				)
			)
		)
	)
	(footprint ""
		(layer "B.Cu")
		(at 164.973 -81.407 90)
		(property "Reference" "C6P10"
			(at 0 0 90)
			(layer "B.SilkS")
			(hide yes)
			(effects
				(font
					(size 1.27 1.27)
				)
				(justify mirror)
			)
		)
		(property "Value" ""
			(at 0 0 90)
			(layer "B.Fab")
			(effects
				(font
					(size 1.27 1.27)
				)
				(justify mirror)
			)
		)
		(duplicate_pad_numbers_are_jumpers no)
		(fp_poly
			(pts
				(xy -0.3048 -0.1016) (xy -0.3048 0.9906) (xy 0.3048 0.9906) (xy 0.3048 -0.1016)
			)
			(stroke
				(width 0)
				(type default)
			)
			(fill no)
			(layer "B.CrtYd")
		)
		(fp_line
			(start 0.3048 -0.1016)
			(end 0.3048 0.9906)
			(stroke
				(width 0.1)
				(type default)
			)
			(layer "B.Fab")
		)
		(fp_line
			(start -0.3048 -0.1016)
			(end 0.3048 -0.1016)
			(stroke
				(width 0.1)
				(type default)
			)
			(layer "B.Fab")
		)
		(fp_line
			(start 0.3048 0.9906)
			(end -0.3048 0.9906)
			(stroke
				(width 0.1)
				(type default)
			)
			(layer "B.Fab")
		)
		(fp_line
			(start -0.3048 0.9906)
			(end -0.3048 -0.1016)
			(stroke
				(width 0.1)
				(type default)
			)
			(layer "B.Fab")
		)
		(pad "1" smd rect
			(at 0 0 270)
			(size 0.508 0.508)
			(layers "B.Cu" "B.Mask" "B.Paste")
			(net "P3V3_DB1200")
		)
		(pad "2" smd rect
			(at 0 0.889 270)
			(size 0.508 0.508)
			(layers "B.Cu" "B.Mask" "B.Paste")
			(net "GND")
		)
		(zone
			(layer "B.Cu")
			(hatch none 0.5)
			(connect_pads
				(clearance 0)
			)
			(min_thickness 0.25)
			(keepout
				(tracks allowed)
				(vias not_allowed)
				(pads allowed)
				(copperpour not_allowed)
				(footprints allowed)
			)
			(placement
				(enabled no)
				(sheetname "")
			)
			(fill
				(thermal_gap 0.5)
				(thermal_bridge_width 0.5)
				(island_removal_mode 0)
			)
			(polygon
				(pts
					(xy 165.227 -81.661) (xy 165.227 -81.153) (xy 165.608 -81.153) (xy 165.608 -81.661)
				)
			)
		)
		(zone
			(layer "B.Cu")
			(hatch none 0.5)
			(connect_pads
				(clearance 0)
			)
			(min_thickness 0.25)
			(keepout
				(tracks not_allowed)
				(vias allowed)
				(pads allowed)
				(copperpour not_allowed)
				(footprints allowed)
			)
			(placement
				(enabled no)
				(sheetname "")
			)
			(fill
				(thermal_gap 0.5)
				(thermal_bridge_width 0.5)
				(island_removal_mode 0)
			)
			(polygon
				(pts
					(xy 165.608 -81.661) (xy 165.608 -81.153) (xy 165.227 -81.153) (xy 165.227 -81.661)
				)
			)
		)
	)
	(footprint ""
		(layer "B.Cu")
		(at 95.922592 -82.001614)
		(property "Reference" "C8P6"
			(at 0 0 0)
			(layer "B.SilkS")
			(hide yes)
			(effects
				(font
					(size 1.27 1.27)
				)
				(justify mirror)
			)
		)
		(property "Value" ""
			(at 0 0 0)
			(layer "B.Fab")
			(effects
				(font
					(size 1.27 1.27)
				)
				(justify mirror)
			)
		)
		(duplicate_pad_numbers_are_jumpers no)
		(fp_poly
			(pts
				(xy 0.7239 -0.2159) (xy -0.7239 -0.2159) (xy -0.7239 1.9939) (xy 0.7239 1.9939)
			)
			(stroke
				(width 0)
				(type default)
			)
			(fill no)
			(layer "B.CrtYd")
		)
		(fp_line
			(start -0.7239 -0.2159)
			(end 0.7239 -0.2159)
			(stroke
				(width 0.1)
				(type default)
			)
			(layer "B.Fab")
		)
		(fp_line
			(start -0.7239 1.9939)
			(end -0.7239 -0.2159)
			(stroke
				(width 0.1)
				(type default)
			)
			(layer "B.Fab")
		)
		(fp_line
			(start 0.7239 -0.2159)
			(end 0.7239 1.9939)
			(stroke
				(width 0.1)
				(type default)
			)
			(layer "B.Fab")
		)
		(fp_line
			(start 0.7239 1.9939)
			(end -0.7239 1.9939)
			(stroke
				(width 0.1)
				(type default)
			)
			(layer "B.Fab")
		)
		(pad "1" smd rect
			(at 0 0 180)
			(size 1.27 1.016)
			(layers "B.Cu" "B.Mask" "B.Paste")
			(net "PVSA_CPU1")
		)
		(pad "2" smd rect
			(at 0 1.778 180)
			(size 1.27 1.016)
			(layers "B.Cu" "B.Mask" "B.Paste")
			(net "GND")
		)
		(zone
			(layer "B.Cu")
			(hatch none 0.5)
			(connect_pads
				(clearance 0)
			)
			(min_thickness 0.25)
			(keepout
				(tracks not_allowed)
				(vias allowed)
				(pads allowed)
				(copperpour not_allowed)
				(footprints allowed)
			)
			(placement
				(enabled no)
				(sheetname "")
			)
			(fill
				(thermal_gap 0.5)
				(thermal_bridge_width 0.5)
				(island_removal_mode 0)
			)
			(polygon
				(pts
					(xy 96.557592 -81.493614) (xy 95.287592 -81.493614) (xy 95.287592 -80.731614) (xy 96.557592 -80.731614)
				)
			)
		)
	)
	(footprint ""
		(layer "B.Cu")
		(at 403.568408 -92.993718 -90)
		(property "Reference" "R2N18"
			(at 0 0 90)
			(layer "B.SilkS")
			(hide yes)
			(effects
				(font
					(size 1.27 1.27)
				)
				(justify mirror)
			)
		)
		(property "Value" ""
			(at 0 0 90)
			(layer "B.Fab")
			(effects
				(font
					(size 1.27 1.27)
				)
				(justify mirror)
			)
		)
		(duplicate_pad_numbers_are_jumpers no)
		(fp_poly
			(pts
				(xy 0.2794 -0.1016) (xy -0.2794 -0.1016) (xy -0.2794 0.9906) (xy 0.2794 0.9906)
			)
			(stroke
				(width 0)
				(type default)
			)
			(fill no)
			(layer "B.CrtYd")
		)
		(fp_line
			(start -0.2794 0.9906)
			(end -0.2794 -0.1016)
			(stroke
				(width 0.1)
				(type default)
			)
			(layer "B.Fab")
		)
		(fp_line
			(start 0.2794 0.9906)
			(end -0.2794 0.9906)
			(stroke
				(width 0.1)
				(type default)
			)
			(layer "B.Fab")
		)
		(fp_line
			(start -0.2794 -0.1016)
			(end 0.2794 -0.1016)
			(stroke
				(width 0.1)
				(type default)
			)
			(layer "B.Fab")
		)
		(fp_line
			(start 0.2794 -0.1016)
			(end 0.2794 0.9906)
			(stroke
				(width 0.1)
				(type default)
			)
			(layer "B.Fab")
		)
		(pad "1" smd rect
			(at 0 0 90)
			(size 0.508 0.508)
			(layers "B.Cu" "B.Mask" "B.Paste")
			(net "FM_BOARD_SKU_ID4")
		)
		(pad "2" smd rect
			(at 0 0.889 90)
			(size 0.508 0.508)
			(layers "B.Cu" "B.Mask" "B.Paste")
			(net "GND")
		)
		(zone
			(layer "B.Cu")
			(hatch none 0.5)
			(connect_pads
				(clearance 0)
			)
			(min_thickness 0.25)
			(keepout
				(tracks not_allowed)
				(vias allowed)
				(pads allowed)
				(copperpour not_allowed)
				(footprints allowed)
			)
			(placement
				(enabled no)
				(sheetname "")
			)
			(fill
				(thermal_gap 0.5)
				(thermal_bridge_width 0.5)
				(island_removal_mode 0)
			)
			(polygon
				(pts
					(xy 402.933408 -92.739718) (xy 402.933408 -93.247718) (xy 403.314408 -93.247718) (xy 403.314408 -92.739718)
				)
			)
		)
		(zone
			(layer "B.Cu")
			(hatch none 0.5)
			(connect_pads
				(clearance 0)
			)
			(min_thickness 0.25)
			(keepout
				(tracks allowed)
				(vias not_allowed)
				(pads allowed)
				(copperpour not_allowed)
				(footprints allowed)
			)
			(placement
				(enabled no)
				(sheetname "")
			)
			(fill
				(thermal_gap 0.5)
				(thermal_bridge_width 0.5)
				(island_removal_mode 0)
			)
			(polygon
				(pts
					(xy 403.314408 -92.739718) (xy 403.314408 -93.247718) (xy 402.933408 -93.247718) (xy 402.933408 -92.739718)
				)
			)
		)
	)
	(footprint ""
		(layer "B.Cu")
		(at 474.345 -120.8278)
		(property "Reference" "R1M14"
			(at 0 0 0)
			(layer "B.SilkS")
			(hide yes)
			(effects
				(font
					(size 1.27 1.27)
				)
				(justify mirror)
			)
		)
		(property "Value" ""
			(at 0 0 0)
			(layer "B.Fab")
			(effects
				(font
					(size 1.27 1.27)
				)
				(justify mirror)
			)
		)
		(duplicate_pad_numbers_are_jumpers no)
		(fp_rect
			(start -0.2794 0.9906)
			(end 0.2794 -0.1016)
			(stroke
				(width 0)
				(type default)
			)
			(fill no)
			(layer "B.CrtYd")
		)
		(fp_line
			(start -0.2794 -0.1016)
			(end 0.2794 -0.1016)
			(stroke
				(width 0.1)
				(type default)
			)
			(layer "B.Fab")
		)
		(fp_line
			(start -0.2794 0.9906)
			(end -0.2794 -0.1016)
			(stroke
				(width 0.1)
				(type default)
			)
			(layer "B.Fab")
		)
		(fp_line
			(start 0.2794 -0.1016)
			(end 0.2794 0.9906)
			(stroke
				(width 0.1)
				(type default)
			)
			(layer "B.Fab")
		)
		(fp_line
			(start 0.2794 0.9906)
			(end -0.2794 0.9906)
			(stroke
				(width 0.1)
				(type default)
			)
			(layer "B.Fab")
		)
		(pad "1" smd rect
			(at 0 0 180)
			(size 0.508 0.508)
			(layers "B.Cu" "B.Mask" "B.Paste")
			(net "RST_PCIE_CPU_DEV0_N")
		)
		(pad "2" smd rect
			(at 0 0.889 180)
			(size 0.508 0.508)
			(layers "B.Cu" "B.Mask" "B.Paste")
			(net "RST_PCIE_CPU_DEV0_R_N")
		)
		(zone
			(layer "B.Cu")
			(hatch none 0.5)
			(connect_pads
				(clearance 0)
			)
			(min_thickness 0.25)
			(keepout
				(tracks not_allowed)
				(vias allowed)
				(pads allowed)
				(copperpour not_allowed)
				(footprints allowed)
			)
			(placement
				(enabled no)
				(sheetname "")
			)
			(fill
				(thermal_gap 0.5)
				(thermal_bridge_width 0.5)
				(island_removal_mode 0)
			)
			(polygon
				(pts
					(xy 474.091 -120.1928) (xy 474.599 -120.1928) (xy 474.599 -120.5738) (xy 474.091 -120.5738)
				)
			)
		)
		(zone
			(layer "B.Cu")
			(hatch none 0.5)
			(connect_pads
				(clearance 0)
			)
			(min_thickness 0.25)
			(keepout
				(tracks allowed)
				(vias not_allowed)
				(pads allowed)
				(copperpour not_allowed)
				(footprints allowed)
			)
			(placement
				(enabled no)
				(sheetname "")
			)
			(fill
				(thermal_gap 0.5)
				(thermal_bridge_width 0.5)
				(island_removal_mode 0)
			)
			(polygon
				(pts
					(xy 474.091 -120.1928) (xy 474.599 -120.1928) (xy 474.599 -120.5738) (xy 474.091 -120.5738)
				)
			)
		)
	)
	(footprint ""
		(layer "B.Cu")
		(at 210.847432 -83.947 -90)
		(property "Reference" "C6P8"
			(at 0.66167 -3.782568 0)
			(unlocked yes)
			(layer "B.SilkS")
			(effects
				(font
					(size 0.7874 0.5842)
					(thickness 0.1524)
				)
				(justify mirror)
			)
		)
		(property "Value" ""
			(at 0 0 90)
			(layer "B.Fab")
			(effects
				(font
					(size 1.27 1.27)
				)
				(justify mirror)
			)
		)
		(duplicate_pad_numbers_are_jumpers no)
		(fp_line
			(start -2.286 7.366)
			(end -1.600708 7.366)
			(stroke
				(width 0.1524)
				(type default)
			)
			(layer "B.SilkS")
		)
		(fp_line
			(start -2.286 7.366)
			(end -2.286 1.63195)
			(stroke
				(width 0.1524)
				(type default)
			)
			(layer "B.SilkS")
		)
		(fp_line
			(start 2.286 7.366)
			(end 1.60147 7.366)
			(stroke
				(width 0.1524)
				(type default)
			)
			(layer "B.SilkS")
		)
		(fp_line
			(start 2.286 7.366)
			(end 2.286 1.632712)
			(stroke
				(width 0.1524)
				(type default)
			)
			(layer "B.SilkS")
		)
		(fp_line
			(start -2.504948 1.633728)
			(end -1.6002 1.633728)
			(stroke
				(width 0.1524)
				(type default)
			)
			(layer "B.SilkS")
		)
		(fp_line
			(start 2.563114 1.633728)
			(end 1.6002 1.633728)
			(stroke
				(width 0.1524)
				(type default)
			)
			(layer "B.SilkS")
		)
		(fp_line
			(start -2.504948 -1.616456)
			(end -2.504948 1.633728)
			(stroke
				(width 0.1524)
				(type default)
			)
			(layer "B.SilkS")
		)
		(fp_line
			(start -1.6002 -1.616456)
			(end -2.504948 -1.616456)
			(stroke
				(width 0.1524)
				(type default)
			)
			(layer "B.SilkS")
		)
		(fp_line
			(start 1.6002 -1.616456)
			(end 2.563114 -1.616456)
			(stroke
				(width 0.1524)
				(type default)
			)
			(layer "B.SilkS")
		)
		(fp_line
			(start 2.563114 -1.616456)
			(end 2.563114 1.633728)
			(stroke
				(width 0.1524)
				(type default)
			)
			(layer "B.SilkS")
		)
		(fp_rect
			(start 2.286 7.366)
			(end -2.286 -0.254)
			(stroke
				(width 0)
				(type default)
			)
			(fill no)
			(layer "B.CrtYd")
		)
		(fp_line
			(start -2.286 7.366)
			(end 2.286 7.366)
			(stroke
				(width 0.1)
				(type default)
			)
			(layer "B.Fab")
		)
		(fp_line
			(start 2.286 7.366)
			(end 2.286 -0.254)
			(stroke
				(width 0.1)
				(type default)
			)
			(layer "B.Fab")
		)
		(fp_line
			(start -2.286 -0.254)
			(end -2.286 7.366)
			(stroke
				(width 0.1)
				(type default)
			)
			(layer "B.Fab")
		)
		(fp_line
			(start 2.286 -0.254)
			(end -2.286 -0.254)
			(stroke
				(width 0.1)
				(type default)
			)
			(layer "B.Fab")
		)
		(pad "1" smd rect
			(at 0 0 90)
			(size 2.54 3.048)
			(layers "B.Cu" "B.Mask" "B.Paste")
			(net "PVCCIN_CPU0")
		)
		(pad "2" smd rect
			(at 0 7.112 90)
			(size 2.54 3.048)
			(layers "B.Cu" "B.Mask" "B.Paste")
			(net "GND")
		)
	)
	(footprint ""
		(layer "B.Cu")
		(at 376.174 -66.929)
		(property "Reference" "R2R4"
			(at 0 0 0)
			(layer "B.SilkS")
			(hide yes)
			(effects
				(font
					(size 1.27 1.27)
				)
				(justify mirror)
			)
		)
		(property "Value" ""
			(at 0 0 0)
			(layer "B.Fab")
			(effects
				(font
					(size 1.27 1.27)
				)
				(justify mirror)
			)
		)
		(duplicate_pad_numbers_are_jumpers no)
		(fp_poly
			(pts
				(xy 0.2794 -0.1016) (xy -0.2794 -0.1016) (xy -0.2794 0.9906) (xy 0.2794 0.9906)
			)
			(stroke
				(width 0)
				(type default)
			)
			(fill no)
			(layer "B.CrtYd")
		)
		(fp_line
			(start -0.2794 -0.1016)
			(end 0.2794 -0.1016)
			(stroke
				(width 0.1)
				(type default)
			)
			(layer "B.Fab")
		)
		(fp_line
			(start -0.2794 0.9906)
			(end -0.2794 -0.1016)
			(stroke
				(width 0.1)
				(type default)
			)
			(layer "B.Fab")
		)
		(fp_line
			(start 0.2794 -0.1016)
			(end 0.2794 0.9906)
			(stroke
				(width 0.1)
				(type default)
			)
			(layer "B.Fab")
		)
		(fp_line
			(start 0.2794 0.9906)
			(end -0.2794 0.9906)
			(stroke
				(width 0.1)
				(type default)
			)
			(layer "B.Fab")
		)
		(pad "1" smd rect
			(at 0 0 180)
			(size 0.508 0.508)
			(layers "B.Cu" "B.Mask" "B.Paste")
			(net "FM_ADR_SMI_GPIO_R_N")
		)
		(pad "2" smd rect
			(at 0 0.889 180)
			(size 0.508 0.508)
			(layers "B.Cu" "B.Mask" "B.Paste")
			(net "FM_ADR_SMI_GPIO_N")
		)
		(zone
			(layer "B.Cu")
			(hatch none 0.5)
			(connect_pads
				(clearance 0)
			)
			(min_thickness 0.25)
			(keepout
				(tracks allowed)
				(vias not_allowed)
				(pads allowed)
				(copperpour not_allowed)
				(footprints allowed)
			)
			(placement
				(enabled no)
				(sheetname "")
			)
			(fill
				(thermal_gap 0.5)
				(thermal_bridge_width 0.5)
				(island_removal_mode 0)
			)
			(polygon
				(pts
					(xy 376.428 -66.675) (xy 375.92 -66.675) (xy 375.92 -66.294) (xy 376.428 -66.294)
				)
			)
		)
		(zone
			(layer "B.Cu")
			(hatch none 0.5)
			(connect_pads
				(clearance 0)
			)
			(min_thickness 0.25)
			(keepout
				(tracks not_allowed)
				(vias allowed)
				(pads allowed)
				(copperpour not_allowed)
				(footprints allowed)
			)
			(placement
				(enabled no)
				(sheetname "")
			)
			(fill
				(thermal_gap 0.5)
				(thermal_bridge_width 0.5)
				(island_removal_mode 0)
			)
			(polygon
				(pts
					(xy 376.428 -66.294) (xy 375.92 -66.294) (xy 375.92 -66.675) (xy 376.428 -66.675)
				)
			)
		)
	)
	(footprint ""
		(layer "B.Cu")
		(at 380.3904 -43.7515)
		(property "Reference" "Q7E8"
			(at 1.28143 0.59944 90)
			(unlocked yes)
			(layer "B.SilkS")
			(effects
				(font
					(size 0.7874 0.5842)
					(thickness 0.1524)
				)
				(justify left mirror)
			)
		)
		(property "Value" ""
			(at 0 0 0)
			(layer "B.Fab")
			(effects
				(font
					(size 1.27 1.27)
				)
				(justify mirror)
			)
		)
		(duplicate_pad_numbers_are_jumpers no)
		(fp_line
			(start -1.778 -0.5715)
			(end -1.778 0.3175)
			(stroke
				(width 0.1524)
				(type default)
			)
			(layer "B.SilkS")
		)
		(fp_line
			(start -1.778 2.4765)
			(end -1.778 1.5875)
			(stroke
				(width 0.1524)
				(type default)
			)
			(layer "B.SilkS")
		)
		(fp_line
			(start -0.9525 -0.5715)
			(end -1.778 -0.5715)
			(stroke
				(width 0.1524)
				(type default)
			)
			(layer "B.SilkS")
		)
		(fp_line
			(start -0.9525 2.4765)
			(end -1.778 2.4765)
			(stroke
				(width 0.1524)
				(type default)
			)
			(layer "B.SilkS")
		)
		(fp_line
			(start -0.381 0.635)
			(end -0.381 1.27)
			(stroke
				(width 0.1524)
				(type default)
			)
			(layer "B.SilkS")
		)
		(fp_circle
			(center 0.9525 -0.9271)
			(end 1.0795 -0.9271)
			(stroke
				(width 0.254)
				(type default)
			)
			(fill no)
			(layer "B.SilkS")
		)
		(fp_poly
			(pts
				(xy -1.778 2.4765) (xy -0.381 2.4765) (xy -0.381 -0.5715) (xy -1.778 -0.5715)
			)
			(stroke
				(width 0)
				(type default)
			)
			(fill no)
			(layer "B.CrtYd")
		)
		(fp_line
			(start -1.778 -0.5715)
			(end -0.381 -0.5715)
			(stroke
				(width 0.1)
				(type default)
			)
			(layer "B.Fab")
		)
		(fp_line
			(start -1.778 2.4765)
			(end -1.778 -0.5715)
			(stroke
				(width 0.1)
				(type default)
			)
			(layer "B.Fab")
		)
		(fp_line
			(start -0.381 -0.5715)
			(end -0.381 2.4765)
			(stroke
				(width 0.1)
				(type default)
			)
			(layer "B.Fab")
		)
		(fp_line
			(start -0.381 2.4765)
			(end -1.778 2.4765)
			(stroke
				(width 0.1)
				(type default)
			)
			(layer "B.Fab")
		)
		(fp_circle
			(center 0.9525 -0.9271)
			(end 1.0795 -0.9271)
			(stroke
				(width 0.254)
				(type default)
			)
			(fill no)
			(layer "B.Fab")
		)
		(pad "1" smd rect
			(at 0 0 180)
			(size 1.143 0.508)
			(layers "B.Cu" "B.Mask" "B.Paste")
			(net "FM_SYS_THROTTLE_LVC3")
		)
		(pad "2" smd rect
			(at 0 1.905 180)
			(size 1.143 0.508)
			(layers "B.Cu" "B.Mask" "B.Paste")
			(net "GND")
		)
		(pad "3" smd rect
			(at -2.159 0.9525 180)
			(size 1.143 0.508)
			(layers "B.Cu" "B.Mask" "B.Paste")
			(net "FM_PWRBRK_N")
		)
	)
	(footprint ""
		(layer "B.Cu")
		(at 17.83842 -103.34752 90)
		(property "Reference" "C9N7"
			(at 0 0 90)
			(layer "B.SilkS")
			(hide yes)
			(effects
				(font
					(size 1.27 1.27)
				)
				(justify mirror)
			)
		)
		(property "Value" ""
			(at 0 0 90)
			(layer "B.Fab")
			(effects
				(font
					(size 1.27 1.27)
				)
				(justify mirror)
			)
		)
		(duplicate_pad_numbers_are_jumpers no)
		(fp_poly
			(pts
				(xy -0.3048 -0.1016) (xy -0.3048 0.9906) (xy 0.3048 0.9906) (xy 0.3048 -0.1016)
			)
			(stroke
				(width 0)
				(type default)
			)
			(fill no)
			(layer "B.CrtYd")
		)
		(fp_line
			(start 0.3048 -0.1016)
			(end 0.3048 0.9906)
			(stroke
				(width 0.1)
				(type default)
			)
			(layer "B.Fab")
		)
		(fp_line
			(start -0.3048 -0.1016)
			(end 0.3048 -0.1016)
			(stroke
				(width 0.1)
				(type default)
			)
			(layer "B.Fab")
		)
		(fp_line
			(start 0.3048 0.9906)
			(end -0.3048 0.9906)
			(stroke
				(width 0.1)
				(type default)
			)
			(layer "B.Fab")
		)
		(fp_line
			(start -0.3048 0.9906)
			(end -0.3048 -0.1016)
			(stroke
				(width 0.1)
				(type default)
			)
			(layer "B.Fab")
		)
		(pad "1" smd rect
			(at 0 0 270)
			(size 0.508 0.508)
			(layers "B.Cu" "B.Mask" "B.Paste")
			(net "P3E_CPU1_PE3_MP_C_TXP<15>")
		)
		(pad "2" smd rect
			(at 0 0.889 270)
			(size 0.508 0.508)
			(layers "B.Cu" "B.Mask" "B.Paste")
			(net "P3E_CPU1_PE3_MP_TXP<15>")
		)
		(zone
			(layer "B.Cu")
			(hatch none 0.5)
			(connect_pads
				(clearance 0)
			)
			(min_thickness 0.25)
			(keepout
				(tracks allowed)
				(vias not_allowed)
				(pads allowed)
				(copperpour not_allowed)
				(footprints allowed)
			)
			(placement
				(enabled no)
				(sheetname "")
			)
			(fill
				(thermal_gap 0.5)
				(thermal_bridge_width 0.5)
				(island_removal_mode 0)
			)
			(polygon
				(pts
					(xy 18.09242 -103.60152) (xy 18.09242 -103.09352) (xy 18.47342 -103.09352) (xy 18.47342 -103.60152)
				)
			)
		)
		(zone
			(layer "B.Cu")
			(hatch none 0.5)
			(connect_pads
				(clearance 0)
			)
			(min_thickness 0.25)
			(keepout
				(tracks not_allowed)
				(vias allowed)
				(pads allowed)
				(copperpour not_allowed)
				(footprints allowed)
			)
			(placement
				(enabled no)
				(sheetname "")
			)
			(fill
				(thermal_gap 0.5)
				(thermal_bridge_width 0.5)
				(island_removal_mode 0)
			)
			(polygon
				(pts
					(xy 18.47342 -103.60152) (xy 18.47342 -103.09352) (xy 18.09242 -103.09352) (xy 18.09242 -103.60152)
				)
			)
		)
	)
	(footprint ""
		(layer "B.Cu")
		(at 245.018306 -64.2874 -90)
		(property "Reference" "R5R1"
			(at 0 0 90)
			(layer "B.SilkS")
			(hide yes)
			(effects
				(font
					(size 1.27 1.27)
				)
				(justify mirror)
			)
		)
		(property "Value" ""
			(at 0 0 90)
			(layer "B.Fab")
			(effects
				(font
					(size 1.27 1.27)
				)
				(justify mirror)
			)
		)
		(duplicate_pad_numbers_are_jumpers no)
		(fp_poly
			(pts
				(xy 0.2794 -0.1016) (xy -0.2794 -0.1016) (xy -0.2794 0.9906) (xy 0.2794 0.9906)
			)
			(stroke
				(width 0)
				(type default)
			)
			(fill no)
			(layer "B.CrtYd")
		)
		(fp_line
			(start -0.2794 0.9906)
			(end -0.2794 -0.1016)
			(stroke
				(width 0.1)
				(type default)
			)
			(layer "B.Fab")
		)
		(fp_line
			(start 0.2794 0.9906)
			(end -0.2794 0.9906)
			(stroke
				(width 0.1)
				(type default)
			)
			(layer "B.Fab")
		)
		(fp_line
			(start -0.2794 -0.1016)
			(end 0.2794 -0.1016)
			(stroke
				(width 0.1)
				(type default)
			)
			(layer "B.Fab")
		)
		(fp_line
			(start 0.2794 -0.1016)
			(end 0.2794 0.9906)
			(stroke
				(width 0.1)
				(type default)
			)
			(layer "B.Fab")
		)
		(pad "1" smd rect
			(at 0 0 90)
			(size 0.508 0.508)
			(layers "B.Cu" "B.Mask" "B.Paste")
			(net "PD_CPU0_RSVD_TEST_1")
		)
		(pad "2" smd rect
			(at 0 0.889 90)
			(size 0.508 0.508)
			(layers "B.Cu" "B.Mask" "B.Paste")
			(net "GND")
		)
		(zone
			(layer "B.Cu")
			(hatch none 0.5)
			(connect_pads
				(clearance 0)
			)
			(min_thickness 0.25)
			(keepout
				(tracks not_allowed)
				(vias allowed)
				(pads allowed)
				(copperpour not_allowed)
				(footprints allowed)
			)
			(placement
				(enabled no)
				(sheetname "")
			)
			(fill
				(thermal_gap 0.5)
				(thermal_bridge_width 0.5)
				(island_removal_mode 0)
			)
			(polygon
				(pts
					(xy 244.383306 -64.0334) (xy 244.383306 -64.5414) (xy 244.764306 -64.5414) (xy 244.764306 -64.0334)
				)
			)
		)
		(zone
			(layer "B.Cu")
			(hatch none 0.5)
			(connect_pads
				(clearance 0)
			)
			(min_thickness 0.25)
			(keepout
				(tracks allowed)
				(vias not_allowed)
				(pads allowed)
				(copperpour not_allowed)
				(footprints allowed)
			)
			(placement
				(enabled no)
				(sheetname "")
			)
			(fill
				(thermal_gap 0.5)
				(thermal_bridge_width 0.5)
				(island_removal_mode 0)
			)
			(polygon
				(pts
					(xy 244.764306 -64.0334) (xy 244.764306 -64.5414) (xy 244.383306 -64.5414) (xy 244.383306 -64.0334)
				)
			)
		)
	)
	(footprint ""
		(layer "B.Cu")
		(at 417.576 -8.1915)
		(property "Reference" "R3P51"
			(at 0 0 0)
			(layer "B.SilkS")
			(hide yes)
			(effects
				(font
					(size 1.27 1.27)
				)
				(justify mirror)
			)
		)
		(property "Value" ""
			(at 0 0 0)
			(layer "B.Fab")
			(effects
				(font
					(size 1.27 1.27)
				)
				(justify mirror)
			)
		)
		(duplicate_pad_numbers_are_jumpers no)
		(fp_rect
			(start 0.2794 -0.1016)
			(end -0.2794 0.9906)
			(stroke
				(width 0)
				(type default)
			)
			(fill no)
			(layer "B.CrtYd")
		)
		(fp_line
			(start -0.2794 -0.1016)
			(end 0.2794 -0.1016)
			(stroke
				(width 0.1)
				(type default)
			)
			(layer "B.Fab")
		)
		(fp_line
			(start -0.2794 0.9906)
			(end -0.2794 -0.1016)
			(stroke
				(width 0.1)
				(type default)
			)
			(layer "B.Fab")
		)
		(fp_line
			(start 0.2794 -0.1016)
			(end 0.2794 0.9906)
			(stroke
				(width 0.1)
				(type default)
			)
			(layer "B.Fab")
		)
		(fp_line
			(start 0.2794 0.9906)
			(end -0.2794 0.9906)
			(stroke
				(width 0.1)
				(type default)
			)
			(layer "B.Fab")
		)
		(pad "1" smd rect
			(at 0 0 180)
			(size 0.508 0.508)
			(layers "B.Cu" "B.Mask" "B.Paste")
			(net "VSENSE_P12V_ADM1085")
		)
		(pad "2" smd rect
			(at 0 0.889 180)
			(size 0.508 0.508)
			(layers "B.Cu" "B.Mask" "B.Paste")
			(net "GND")
		)
		(zone
			(layer "B.Cu")
			(hatch none 0.5)
			(connect_pads
				(clearance 0)
			)
			(min_thickness 0.25)
			(keepout
				(tracks not_allowed)
				(vias allowed)
				(pads allowed)
				(copperpour not_allowed)
				(footprints allowed)
			)
			(placement
				(enabled no)
				(sheetname "")
			)
			(fill
				(thermal_gap 0.5)
				(thermal_bridge_width 0.5)
				(island_removal_mode 0)
			)
			(polygon
				(pts
					(xy 417.83 -7.9375) (xy 417.322 -7.9375) (xy 417.322 -7.5565) (xy 417.83 -7.5565)
				)
			)
		)
		(zone
			(layer "B.Cu")
			(hatch none 0.5)
			(connect_pads
				(clearance 0)
			)
			(min_thickness 0.25)
			(keepout
				(tracks allowed)
				(vias not_allowed)
				(pads allowed)
				(copperpour not_allowed)
				(footprints allowed)
			)
			(placement
				(enabled no)
				(sheetname "")
			)
			(fill
				(thermal_gap 0.5)
				(thermal_bridge_width 0.5)
				(island_removal_mode 0)
			)
			(polygon
				(pts
					(xy 417.83 -7.9375) (xy 417.322 -7.9375) (xy 417.322 -7.5565) (xy 417.83 -7.5565)
				)
			)
		)
	)
	(footprint ""
		(layer "B.Cu")
		(at 321.1957 -31.92018 90)
		(property "Reference" "R4T6"
			(at 0 0 90)
			(layer "B.SilkS")
			(hide yes)
			(effects
				(font
					(size 1.27 1.27)
				)
				(justify mirror)
			)
		)
		(property "Value" ""
			(at 0 0 90)
			(layer "B.Fab")
			(effects
				(font
					(size 1.27 1.27)
				)
				(justify mirror)
			)
		)
		(duplicate_pad_numbers_are_jumpers no)
		(fp_poly
			(pts
				(xy 0.2794 -0.1016) (xy -0.2794 -0.1016) (xy -0.2794 0.9906) (xy 0.2794 0.9906)
			)
			(stroke
				(width 0)
				(type default)
			)
			(fill no)
			(layer "B.CrtYd")
		)
		(fp_line
			(start 0.2794 -0.1016)
			(end 0.2794 0.9906)
			(stroke
				(width 0.1)
				(type default)
			)
			(layer "B.Fab")
		)
		(fp_line
			(start -0.2794 -0.1016)
			(end 0.2794 -0.1016)
			(stroke
				(width 0.1)
				(type default)
			)
			(layer "B.Fab")
		)
		(fp_line
			(start 0.2794 0.9906)
			(end -0.2794 0.9906)
			(stroke
				(width 0.1)
				(type default)
			)
			(layer "B.Fab")
		)
		(fp_line
			(start -0.2794 0.9906)
			(end -0.2794 -0.1016)
			(stroke
				(width 0.1)
				(type default)
			)
			(layer "B.Fab")
		)
		(pad "1" smd rect
			(at 0 0 270)
			(size 0.508 0.508)
			(layers "B.Cu" "B.Mask" "B.Paste")
			(net "PVCCIO_CPU0")
		)
		(pad "2" smd rect
			(at 0 0.889 270)
			(size 0.508 0.508)
			(layers "B.Cu" "B.Mask" "B.Paste")
			(net "SMB_DDR_ABC_SDA_G")
		)
		(zone
			(layer "B.Cu")
			(hatch none 0.5)
			(connect_pads
				(clearance 0)
			)
			(min_thickness 0.25)
			(keepout
				(tracks allowed)
				(vias not_allowed)
				(pads allowed)
				(copperpour not_allowed)
				(footprints allowed)
			)
			(placement
				(enabled no)
				(sheetname "")
			)
			(fill
				(thermal_gap 0.5)
				(thermal_bridge_width 0.5)
				(island_removal_mode 0)
			)
			(polygon
				(pts
					(xy 321.4497 -32.17418) (xy 321.4497 -31.66618) (xy 321.8307 -31.66618) (xy 321.8307 -32.17418)
				)
			)
		)
		(zone
			(layer "B.Cu")
			(hatch none 0.5)
			(connect_pads
				(clearance 0)
			)
			(min_thickness 0.25)
			(keepout
				(tracks not_allowed)
				(vias allowed)
				(pads allowed)
				(copperpour not_allowed)
				(footprints allowed)
			)
			(placement
				(enabled no)
				(sheetname "")
			)
			(fill
				(thermal_gap 0.5)
				(thermal_bridge_width 0.5)
				(island_removal_mode 0)
			)
			(polygon
				(pts
					(xy 321.8307 -32.17418) (xy 321.8307 -31.66618) (xy 321.4497 -31.66618) (xy 321.4497 -32.17418)
				)
			)
		)
	)
	(footprint ""
		(layer "B.Cu")
		(at 110.261654 -68.17614 180)
		(property "Reference" "C7P19"
			(at 0 0 0)
			(layer "B.SilkS")
			(hide yes)
			(effects
				(font
					(size 1.27 1.27)
				)
				(justify mirror)
			)
		)
		(property "Value" ""
			(at 0 0 0)
			(layer "B.Fab")
			(effects
				(font
					(size 1.27 1.27)
				)
				(justify mirror)
			)
		)
		(duplicate_pad_numbers_are_jumpers no)
		(fp_poly
			(pts
				(xy 0.7239 -0.2159) (xy -0.7239 -0.2159) (xy -0.7239 1.9939) (xy 0.7239 1.9939)
			)
			(stroke
				(width 0)
				(type default)
			)
			(fill no)
			(layer "B.CrtYd")
		)
		(fp_line
			(start 0.7239 1.9939)
			(end -0.7239 1.9939)
			(stroke
				(width 0.1)
				(type default)
			)
			(layer "B.Fab")
		)
		(fp_line
			(start 0.7239 -0.2159)
			(end 0.7239 1.9939)
			(stroke
				(width 0.1)
				(type default)
			)
			(layer "B.Fab")
		)
		(fp_line
			(start -0.7239 1.9939)
			(end -0.7239 -0.2159)
			(stroke
				(width 0.1)
				(type default)
			)
			(layer "B.Fab")
		)
		(fp_line
			(start -0.7239 -0.2159)
			(end 0.7239 -0.2159)
			(stroke
				(width 0.1)
				(type default)
			)
			(layer "B.Fab")
		)
		(pad "1" smd rect
			(at 0 0)
			(size 1.27 1.016)
			(layers "B.Cu" "B.Mask" "B.Paste")
			(net "PVCCIN_CPU1")
		)
		(pad "2" smd rect
			(at 0 1.778)
			(size 1.27 1.016)
			(layers "B.Cu" "B.Mask" "B.Paste")
			(net "GND")
		)
		(zone
			(layer "B.Cu")
			(hatch none 0.5)
			(connect_pads
				(clearance 0)
			)
			(min_thickness 0.25)
			(keepout
				(tracks not_allowed)
				(vias allowed)
				(pads allowed)
				(copperpour not_allowed)
				(footprints allowed)
			)
			(placement
				(enabled no)
				(sheetname "")
			)
			(fill
				(thermal_gap 0.5)
				(thermal_bridge_width 0.5)
				(island_removal_mode 0)
			)
			(polygon
				(pts
					(xy 109.626654 -68.68414) (xy 110.896654 -68.68414) (xy 110.896654 -69.44614) (xy 109.626654 -69.44614)
				)
			)
		)
	)
	(footprint ""
		(layer "B.Cu")
		(at 273.179286 -77.82814)
		(property "Reference" "C5P19"
			(at 0 0 0)
			(layer "B.SilkS")
			(hide yes)
			(effects
				(font
					(size 1.27 1.27)
				)
				(justify mirror)
			)
		)
		(property "Value" ""
			(at 0 0 0)
			(layer "B.Fab")
			(effects
				(font
					(size 1.27 1.27)
				)
				(justify mirror)
			)
		)
		(duplicate_pad_numbers_are_jumpers no)
		(fp_poly
			(pts
				(xy 0.7239 -0.2159) (xy -0.7239 -0.2159) (xy -0.7239 1.9939) (xy 0.7239 1.9939)
			)
			(stroke
				(width 0)
				(type default)
			)
			(fill no)
			(layer "B.CrtYd")
		)
		(fp_line
			(start -0.7239 -0.2159)
			(end 0.7239 -0.2159)
			(stroke
				(width 0.1)
				(type default)
			)
			(layer "B.Fab")
		)
		(fp_line
			(start -0.7239 1.9939)
			(end -0.7239 -0.2159)
			(stroke
				(width 0.1)
				(type default)
			)
			(layer "B.Fab")
		)
		(fp_line
			(start 0.7239 -0.2159)
			(end 0.7239 1.9939)
			(stroke
				(width 0.1)
				(type default)
			)
			(layer "B.Fab")
		)
		(fp_line
			(start 0.7239 1.9939)
			(end -0.7239 1.9939)
			(stroke
				(width 0.1)
				(type default)
			)
			(layer "B.Fab")
		)
		(pad "1" smd rect
			(at 0 0 180)
			(size 1.27 1.016)
			(layers "B.Cu" "B.Mask" "B.Paste")
			(net "PVCCMCP_CPU0")
		)
		(pad "2" smd rect
			(at 0 1.778 180)
			(size 1.27 1.016)
			(layers "B.Cu" "B.Mask" "B.Paste")
			(net "GND")
		)
		(zone
			(layer "B.Cu")
			(hatch none 0.5)
			(connect_pads
				(clearance 0)
			)
			(min_thickness 0.25)
			(keepout
				(tracks not_allowed)
				(vias allowed)
				(pads allowed)
				(copperpour not_allowed)
				(footprints allowed)
			)
			(placement
				(enabled no)
				(sheetname "")
			)
			(fill
				(thermal_gap 0.5)
				(thermal_bridge_width 0.5)
				(island_removal_mode 0)
			)
			(polygon
				(pts
					(xy 273.814286 -77.32014) (xy 272.544286 -77.32014) (xy 272.544286 -76.55814) (xy 273.814286 -76.55814)
				)
			)
		)
	)
	(footprint ""
		(layer "B.Cu")
		(at 449.6816 -142.8623 90)
		(property "Reference" "R25W159"
			(at 0.8382 -0.67818 90)
			(unlocked yes)
			(layer "B.SilkS")
			(effects
				(font
					(size 0.4064 0.254)
					(thickness 0.1524)
				)
				(justify left mirror)
			)
		)
		(property "Value" ""
			(at 0 0 90)
			(layer "B.Fab")
			(effects
				(font
					(size 1.27 1.27)
				)
				(justify mirror)
			)
		)
		(duplicate_pad_numbers_are_jumpers no)
		(fp_poly
			(pts
				(xy 0.2794 -0.1016) (xy -0.2794 -0.1016) (xy -0.2794 0.9906) (xy 0.2794 0.9906)
			)
			(stroke
				(width 0)
				(type default)
			)
			(fill no)
			(layer "B.CrtYd")
		)
		(fp_line
			(start 0.2794 -0.1016)
			(end 0.2794 0.9906)
			(stroke
				(width 0.1)
				(type default)
			)
			(layer "B.Fab")
		)
		(fp_line
			(start -0.2794 -0.1016)
			(end 0.2794 -0.1016)
			(stroke
				(width 0.1)
				(type default)
			)
			(layer "B.Fab")
		)
		(fp_line
			(start 0.2794 0.9906)
			(end -0.2794 0.9906)
			(stroke
				(width 0.1)
				(type default)
			)
			(layer "B.Fab")
		)
		(fp_line
			(start -0.2794 0.9906)
			(end -0.2794 -0.1016)
			(stroke
				(width 0.1)
				(type default)
			)
			(layer "B.Fab")
		)
		(pad "1" smd rect
			(at 0 0 270)
			(size 0.508 0.508)
			(layers "B.Cu" "B.Mask" "B.Paste")
			(net "GND")
		)
		(pad "2" smd rect
			(at 0 0.889 270)
			(size 0.508 0.508)
			(layers "B.Cu" "B.Mask" "B.Paste")
			(net "PD_GTL2014_3_VREF")
		)
		(zone
			(layer "B.Cu")
			(hatch none 0.5)
			(connect_pads
				(clearance 0)
			)
			(min_thickness 0.25)
			(keepout
				(tracks allowed)
				(vias not_allowed)
				(pads allowed)
				(copperpour not_allowed)
				(footprints allowed)
			)
			(placement
				(enabled no)
				(sheetname "")
			)
			(fill
				(thermal_gap 0.5)
				(thermal_bridge_width 0.5)
				(island_removal_mode 0)
			)
			(polygon
				(pts
					(xy 449.9356 -143.1163) (xy 449.9356 -142.6083) (xy 450.3166 -142.6083) (xy 450.3166 -143.1163)
				)
			)
		)
		(zone
			(layer "B.Cu")
			(hatch none 0.5)
			(connect_pads
				(clearance 0)
			)
			(min_thickness 0.25)
			(keepout
				(tracks not_allowed)
				(vias allowed)
				(pads allowed)
				(copperpour not_allowed)
				(footprints allowed)
			)
			(placement
				(enabled no)
				(sheetname "")
			)
			(fill
				(thermal_gap 0.5)
				(thermal_bridge_width 0.5)
				(island_removal_mode 0)
			)
			(polygon
				(pts
					(xy 450.3166 -143.1163) (xy 450.3166 -142.6083) (xy 449.9356 -142.6083) (xy 449.9356 -143.1163)
				)
			)
		)
	)
	(footprint ""
		(layer "B.Cu")
		(at 405.60371 -37.940234)
		(property "Reference" "R2T41"
			(at 0.8382 -0.67818 0)
			(unlocked yes)
			(layer "B.SilkS")
			(effects
				(font
					(size 0.4064 0.254)
					(thickness 0.1524)
				)
				(justify left mirror)
			)
		)
		(property "Value" ""
			(at 0 0 0)
			(layer "B.Fab")
			(effects
				(font
					(size 1.27 1.27)
				)
				(justify mirror)
			)
		)
		(duplicate_pad_numbers_are_jumpers no)
		(fp_poly
			(pts
				(xy 0.2794 -0.1016) (xy -0.2794 -0.1016) (xy -0.2794 0.9906) (xy 0.2794 0.9906)
			)
			(stroke
				(width 0)
				(type default)
			)
			(fill no)
			(layer "B.CrtYd")
		)
		(fp_line
			(start -0.2794 -0.1016)
			(end 0.2794 -0.1016)
			(stroke
				(width 0.1)
				(type default)
			)
			(layer "B.Fab")
		)
		(fp_line
			(start -0.2794 0.9906)
			(end -0.2794 -0.1016)
			(stroke
				(width 0.1)
				(type default)
			)
			(layer "B.Fab")
		)
		(fp_line
			(start 0.2794 -0.1016)
			(end 0.2794 0.9906)
			(stroke
				(width 0.1)
				(type default)
			)
			(layer "B.Fab")
		)
		(fp_line
			(start 0.2794 0.9906)
			(end -0.2794 0.9906)
			(stroke
				(width 0.1)
				(type default)
			)
			(layer "B.Fab")
		)
		(pad "1" smd rect
			(at 0 0 180)
			(size 0.508 0.508)
			(layers "B.Cu" "B.Mask" "B.Paste")
			(net "IRQ_FORCE_NM_THROTTLE_N")
		)
		(pad "2" smd rect
			(at 0 0.889 180)
			(size 0.508 0.508)
			(layers "B.Cu" "B.Mask" "B.Paste")
			(net "FM_BMC_SYS_THROTTLE_R_N")
		)
		(zone
			(layer "B.Cu")
			(hatch none 0.5)
			(connect_pads
				(clearance 0)
			)
			(min_thickness 0.25)
			(keepout
				(tracks allowed)
				(vias not_allowed)
				(pads allowed)
				(copperpour not_allowed)
				(footprints allowed)
			)
			(placement
				(enabled no)
				(sheetname "")
			)
			(fill
				(thermal_gap 0.5)
				(thermal_bridge_width 0.5)
				(island_removal_mode 0)
			)
			(polygon
				(pts
					(xy 405.85771 -37.686234) (xy 405.34971 -37.686234) (xy 405.34971 -37.305234) (xy 405.85771 -37.305234)
				)
			)
		)
		(zone
			(layer "B.Cu")
			(hatch none 0.5)
			(connect_pads
				(clearance 0)
			)
			(min_thickness 0.25)
			(keepout
				(tracks not_allowed)
				(vias allowed)
				(pads allowed)
				(copperpour not_allowed)
				(footprints allowed)
			)
			(placement
				(enabled no)
				(sheetname "")
			)
			(fill
				(thermal_gap 0.5)
				(thermal_bridge_width 0.5)
				(island_removal_mode 0)
			)
			(polygon
				(pts
					(xy 405.85771 -37.305234) (xy 405.34971 -37.305234) (xy 405.34971 -37.686234) (xy 405.85771 -37.686234)
				)
			)
		)
	)
	(footprint ""
		(layer "B.Cu")
		(at 488.98429 -29.3116)
		(property "Reference" "R1R9"
			(at 0.8382 -0.67818 0)
			(unlocked yes)
			(layer "B.SilkS")
			(effects
				(font
					(size 0.4064 0.254)
					(thickness 0.1524)
				)
				(justify left mirror)
			)
		)
		(property "Value" ""
			(at 0 0 0)
			(layer "B.Fab")
			(effects
				(font
					(size 1.27 1.27)
				)
				(justify mirror)
			)
		)
		(duplicate_pad_numbers_are_jumpers no)
		(fp_poly
			(pts
				(xy 0.2794 -0.1016) (xy -0.2794 -0.1016) (xy -0.2794 0.9906) (xy 0.2794 0.9906)
			)
			(stroke
				(width 0)
				(type default)
			)
			(fill no)
			(layer "B.CrtYd")
		)
		(fp_line
			(start -0.2794 -0.1016)
			(end 0.2794 -0.1016)
			(stroke
				(width 0.1)
				(type default)
			)
			(layer "B.Fab")
		)
		(fp_line
			(start -0.2794 0.9906)
			(end -0.2794 -0.1016)
			(stroke
				(width 0.1)
				(type default)
			)
			(layer "B.Fab")
		)
		(fp_line
			(start 0.2794 -0.1016)
			(end 0.2794 0.9906)
			(stroke
				(width 0.1)
				(type default)
			)
			(layer "B.Fab")
		)
		(fp_line
			(start 0.2794 0.9906)
			(end -0.2794 0.9906)
			(stroke
				(width 0.1)
				(type default)
			)
			(layer "B.Fab")
		)
		(pad "1" smd rect
			(at 0 0 180)
			(size 0.508 0.508)
			(layers "B.Cu" "B.Mask" "B.Paste")
			(net "P3V3_STBY")
		)
		(pad "2" smd rect
			(at 0 0.889 180)
			(size 0.508 0.508)
			(layers "B.Cu" "B.Mask" "B.Paste")
			(net "PU_NV_HOLD_N")
		)
		(zone
			(layer "B.Cu")
			(hatch none 0.5)
			(connect_pads
				(clearance 0)
			)
			(min_thickness 0.25)
			(keepout
				(tracks allowed)
				(vias not_allowed)
				(pads allowed)
				(copperpour not_allowed)
				(footprints allowed)
			)
			(placement
				(enabled no)
				(sheetname "")
			)
			(fill
				(thermal_gap 0.5)
				(thermal_bridge_width 0.5)
				(island_removal_mode 0)
			)
			(polygon
				(pts
					(xy 489.23829 -29.0576) (xy 488.73029 -29.0576) (xy 488.73029 -28.6766) (xy 489.23829 -28.6766)
				)
			)
		)
		(zone
			(layer "B.Cu")
			(hatch none 0.5)
			(connect_pads
				(clearance 0)
			)
			(min_thickness 0.25)
			(keepout
				(tracks not_allowed)
				(vias allowed)
				(pads allowed)
				(copperpour not_allowed)
				(footprints allowed)
			)
			(placement
				(enabled no)
				(sheetname "")
			)
			(fill
				(thermal_gap 0.5)
				(thermal_bridge_width 0.5)
				(island_removal_mode 0)
			)
			(polygon
				(pts
					(xy 489.23829 -28.6766) (xy 488.73029 -28.6766) (xy 488.73029 -29.0576) (xy 489.23829 -29.0576)
				)
			)
		)
	)
	(footprint ""
		(layer "B.Cu")
		(at 245.7577 -8.1534 -90)
		(property "Reference" "C5U9"
			(at -1.848866 0.752348 270)
			(unlocked yes)
			(layer "B.SilkS")
			(effects
				(font
					(size 1.27 0.9652)
					(thickness 0.1524)
				)
				(justify mirror)
			)
		)
		(property "Value" ""
			(at 0 0 90)
			(layer "B.Fab")
			(effects
				(font
					(size 1.27 1.27)
				)
				(justify mirror)
			)
		)
		(duplicate_pad_numbers_are_jumpers no)
		(fp_rect
			(start 0.500126 1.598422)
			(end -0.500126 -0.201422)
			(stroke
				(width 0)
				(type default)
			)
			(fill no)
			(layer "B.CrtYd")
		)
		(fp_line
			(start -0.500126 1.598422)
			(end 0.500126 1.598422)
			(stroke
				(width 0.1)
				(type default)
			)
			(layer "B.Fab")
		)
		(fp_line
			(start 0.500126 1.598422)
			(end 0.500126 -0.201422)
			(stroke
				(width 0.1)
				(type default)
			)
			(layer "B.Fab")
		)
		(fp_line
			(start -0.500126 -0.201422)
			(end -0.500126 1.598422)
			(stroke
				(width 0.1)
				(type default)
			)
			(layer "B.Fab")
		)
		(fp_line
			(start 0.500126 -0.201422)
			(end -0.500126 -0.201422)
			(stroke
				(width 0.1)
				(type default)
			)
			(layer "B.Fab")
		)
		(pad "1" smd rect
			(at 0 0 180)
			(size 0.889 0.9906)
			(layers "B.Cu" "B.Mask" "B.Paste")
			(net "PVDDQ_ABC")
		)
		(pad "2" smd rect
			(at 0 1.397 180)
			(size 0.889 0.9906)
			(layers "B.Cu" "B.Mask" "B.Paste")
			(net "GND")
		)
		(zone
			(layer "B.Cu")
			(hatch none 0.5)
			(connect_pads
				(clearance 0)
			)
			(min_thickness 0.25)
			(keepout
				(tracks not_allowed)
				(vias allowed)
				(pads allowed)
				(copperpour not_allowed)
				(footprints allowed)
			)
			(placement
				(enabled no)
				(sheetname "")
			)
			(fill
				(thermal_gap 0.5)
				(thermal_bridge_width 0.5)
				(island_removal_mode 0)
			)
			(polygon
				(pts
					(xy 244.8052 -7.6581) (xy 245.3132 -7.6581) (xy 245.3132 -8.6487) (xy 244.8052 -8.6487)
				)
			)
		)
		(zone
			(layer "B.Cu")
			(hatch none 0.5)
			(connect_pads
				(clearance 0)
			)
			(min_thickness 0.25)
			(keepout
				(tracks allowed)
				(vias not_allowed)
				(pads allowed)
				(copperpour not_allowed)
				(footprints allowed)
			)
			(placement
				(enabled no)
				(sheetname "")
			)
			(fill
				(thermal_gap 0.5)
				(thermal_bridge_width 0.5)
				(island_removal_mode 0)
			)
			(polygon
				(pts
					(xy 244.8052 -7.6581) (xy 245.3132 -7.6581) (xy 245.3132 -8.6487) (xy 244.8052 -8.6487)
				)
			)
		)
	)
	(footprint ""
		(layer "B.Cu")
		(at 11.881358 3.20802)
		(property "Reference" "R12W11"
			(at 0 0 0)
			(layer "B.SilkS")
			(hide yes)
			(effects
				(font
					(size 1.27 1.27)
				)
				(justify mirror)
			)
		)
		(property "Value" "*"
			(at 0 -8.9535 0)
			(unlocked yes)
			(layer "B.Fab")
			(hide yes)
			(effects
				(font
					(size 1.27 1.016)
					(thickness 0.1524)
				)
				(justify mirror)
			)
		)
		(property "Device Type" "665KR5B-1-GP_SMD-RG3-665KR5B-1A"
			(at 0 -10.6299 0)
			(unlocked yes)
			(layer "B.Fab")
			(hide yes)
			(effects
				(font
					(size 1.27 1.016)
					(thickness 0.1524)
				)
				(justify mirror)
			)
		)
		(duplicate_pad_numbers_are_jumpers no)
		(fp_line
			(start -0.889 -1.7018)
			(end -0.889 -0.381)
			(stroke
				(width 0.1524)
				(type default)
			)
			(layer "B.SilkS")
		)
		(fp_line
			(start -0.889 -1.7018)
			(end 0.889 -1.7018)
			(stroke
				(width 0.1524)
				(type default)
			)
			(layer "B.SilkS")
		)
		(fp_line
			(start -0.889 1.7018)
			(end -0.889 -0.508)
			(stroke
				(width 0.1524)
				(type default)
			)
			(layer "B.SilkS")
		)
		(fp_line
			(start 0.889 -1.7018)
			(end 0.889 0.2794)
			(stroke
				(width 0.1524)
				(type default)
			)
			(layer "B.SilkS")
		)
		(fp_line
			(start 0.889 0.0762)
			(end 0.889 1.7018)
			(stroke
				(width 0.1524)
				(type default)
			)
			(layer "B.SilkS")
		)
		(fp_line
			(start 0.889 1.7018)
			(end -0.889 1.7018)
			(stroke
				(width 0.1524)
				(type default)
			)
			(layer "B.SilkS")
		)
		(fp_poly
			(pts
				(xy -0.9652 -1.778) (xy -0.9652 1.778) (xy 0.9652 1.778) (xy 0.9652 -1.778)
			)
			(stroke
				(width 0)
				(type default)
			)
			(fill no)
			(layer "B.CrtYd")
		)
		(fp_rect
			(start 0.9652 1.778)
			(end -0.9652 -1.778)
			(stroke
				(width 0)
				(type default)
			)
			(fill no)
			(layer "B.Fab")
		)
		(pad "1" smd rect
			(at 0 -0.9652 180)
			(size 1.397 1.143)
			(layers "B.Cu" "B.Mask" "B.Paste")
			(net "P12V_STBY")
		)
		(pad "2" smd rect
			(at 0 0.9652 180)
			(size 1.397 1.143)
			(layers "B.Cu" "B.Mask" "B.Paste")
			(net "VR_PVDDQ_GHJ_AIINSEN")
		)
	)
	(footprint ""
		(layer "B.Cu")
		(at 390.144 -87.4395)
		(property "Reference" "R2N22"
			(at 0.8382 -0.67818 0)
			(unlocked yes)
			(layer "B.SilkS")
			(effects
				(font
					(size 0.4064 0.254)
					(thickness 0.1524)
				)
				(justify left mirror)
			)
		)
		(property "Value" ""
			(at 0 0 0)
			(layer "B.Fab")
			(effects
				(font
					(size 1.27 1.27)
				)
				(justify mirror)
			)
		)
		(duplicate_pad_numbers_are_jumpers no)
		(fp_poly
			(pts
				(xy 0.2794 -0.1016) (xy -0.2794 -0.1016) (xy -0.2794 0.9906) (xy 0.2794 0.9906)
			)
			(stroke
				(width 0)
				(type default)
			)
			(fill no)
			(layer "B.CrtYd")
		)
		(fp_line
			(start -0.2794 -0.1016)
			(end 0.2794 -0.1016)
			(stroke
				(width 0.1)
				(type default)
			)
			(layer "B.Fab")
		)
		(fp_line
			(start -0.2794 0.9906)
			(end -0.2794 -0.1016)
			(stroke
				(width 0.1)
				(type default)
			)
			(layer "B.Fab")
		)
		(fp_line
			(start 0.2794 -0.1016)
			(end 0.2794 0.9906)
			(stroke
				(width 0.1)
				(type default)
			)
			(layer "B.Fab")
		)
		(fp_line
			(start 0.2794 0.9906)
			(end -0.2794 0.9906)
			(stroke
				(width 0.1)
				(type default)
			)
			(layer "B.Fab")
		)
		(pad "1" smd rect
			(at 0 0 180)
			(size 0.508 0.508)
			(layers "B.Cu" "B.Mask" "B.Paste")
			(net "SGPIO_PCH_SSATA_CLOCK")
		)
		(pad "2" smd rect
			(at 0 0.889 180)
			(size 0.508 0.508)
			(layers "B.Cu" "B.Mask" "B.Paste")
			(net "SGPIO_PCH_SSATA_CLOCK_R")
		)
		(zone
			(layer "B.Cu")
			(hatch none 0.5)
			(connect_pads
				(clearance 0)
			)
			(min_thickness 0.25)
			(keepout
				(tracks allowed)
				(vias not_allowed)
				(pads allowed)
				(copperpour not_allowed)
				(footprints allowed)
			)
			(placement
				(enabled no)
				(sheetname "")
			)
			(fill
				(thermal_gap 0.5)
				(thermal_bridge_width 0.5)
				(island_removal_mode 0)
			)
			(polygon
				(pts
					(xy 390.398 -87.1855) (xy 389.89 -87.1855) (xy 389.89 -86.8045) (xy 390.398 -86.8045)
				)
			)
		)
		(zone
			(layer "B.Cu")
			(hatch none 0.5)
			(connect_pads
				(clearance 0)
			)
			(min_thickness 0.25)
			(keepout
				(tracks not_allowed)
				(vias allowed)
				(pads allowed)
				(copperpour not_allowed)
				(footprints allowed)
			)
			(placement
				(enabled no)
				(sheetname "")
			)
			(fill
				(thermal_gap 0.5)
				(thermal_bridge_width 0.5)
				(island_removal_mode 0)
			)
			(polygon
				(pts
					(xy 390.398 -86.8045) (xy 389.89 -86.8045) (xy 389.89 -87.1855) (xy 390.398 -87.1855)
				)
			)
		)
	)
	(footprint ""
		(layer "B.Cu")
		(at 93.101668 -3.321812 -90)
		(property "Reference" "C5G84"
			(at -1.14681 0.76708 0)
			(unlocked yes)
			(layer "B.SilkS")
			(effects
				(font
					(size 0.7874 0.5842)
					(thickness 0.1524)
				)
				(justify mirror)
			)
		)
		(property "Value" ""
			(at 0 0 90)
			(layer "B.Fab")
			(effects
				(font
					(size 1.27 1.27)
				)
				(justify mirror)
			)
		)
		(duplicate_pad_numbers_are_jumpers no)
		(fp_rect
			(start 0.4953 1.6002)
			(end -0.4953 -0.2032)
			(stroke
				(width 0)
				(type default)
			)
			(fill no)
			(layer "B.CrtYd")
		)
		(fp_line
			(start -0.4953 1.6002)
			(end 0.4953 1.6002)
			(stroke
				(width 0.1)
				(type default)
			)
			(layer "B.Fab")
		)
		(fp_line
			(start 0.4953 1.6002)
			(end 0.4953 -0.2032)
			(stroke
				(width 0.1)
				(type default)
			)
			(layer "B.Fab")
		)
		(fp_line
			(start -0.4953 -0.2032)
			(end -0.4953 1.6002)
			(stroke
				(width 0.1)
				(type default)
			)
			(layer "B.Fab")
		)
		(fp_line
			(start 0.4953 -0.2032)
			(end -0.4953 -0.2032)
			(stroke
				(width 0.1)
				(type default)
			)
			(layer "B.Fab")
		)
		(pad "1" smd rect
			(at 0 0 90)
			(size 0.762 0.889)
			(layers "B.Cu" "B.Mask" "B.Paste")
			(net "PVDDQ_GHJ")
		)
		(pad "2" smd rect
			(at 0 1.397 90)
			(size 0.762 0.889)
			(layers "B.Cu" "B.Mask" "B.Paste")
			(net "GND")
		)
		(zone
			(layer "B.Cu")
			(hatch none 0.5)
			(connect_pads
				(clearance 0)
			)
			(min_thickness 0.25)
			(keepout
				(tracks not_allowed)
				(vias allowed)
				(pads allowed)
				(copperpour not_allowed)
				(footprints allowed)
			)
			(placement
				(enabled no)
				(sheetname "")
			)
			(fill
				(thermal_gap 0.5)
				(thermal_bridge_width 0.5)
				(island_removal_mode 0)
			)
			(polygon
				(pts
					(xy 92.149168 -2.940812) (xy 92.657168 -2.940812) (xy 92.657168 -3.702812) (xy 92.149168 -3.702812)
				)
			)
		)
	)
	(footprint ""
		(layer "B.Cu")
		(at 270.637 3.81 90)
		(property "Reference" "C5U14"
			(at 0 0 90)
			(layer "B.SilkS")
			(hide yes)
			(effects
				(font
					(size 1.27 1.27)
				)
				(justify mirror)
			)
		)
		(property "Value" ""
			(at 0 0 90)
			(layer "B.Fab")
			(effects
				(font
					(size 1.27 1.27)
				)
				(justify mirror)
			)
		)
		(duplicate_pad_numbers_are_jumpers no)
		(fp_rect
			(start -0.7239 -0.2159)
			(end 0.7239 1.9939)
			(stroke
				(width 0)
				(type default)
			)
			(fill no)
			(layer "B.CrtYd")
		)
		(fp_line
			(start 0.7239 -0.2159)
			(end 0.7239 1.9939)
			(stroke
				(width 0.1)
				(type default)
			)
			(layer "B.Fab")
		)
		(fp_line
			(start -0.7239 -0.2159)
			(end 0.7239 -0.2159)
			(stroke
				(width 0.1)
				(type default)
			)
			(layer "B.Fab")
		)
		(fp_line
			(start 0.7239 1.9939)
			(end -0.7239 1.9939)
			(stroke
				(width 0.1)
				(type default)
			)
			(layer "B.Fab")
		)
		(fp_line
			(start -0.7239 1.9939)
			(end -0.7239 -0.2159)
			(stroke
				(width 0.1)
				(type default)
			)
			(layer "B.Fab")
		)
		(pad "1" smd rect
			(at 0 0 270)
			(size 1.27 1.016)
			(layers "B.Cu" "B.Mask" "B.Paste")
			(net "PVDDQ_ABC")
		)
		(pad "2" smd rect
			(at 0 1.778 270)
			(size 1.27 1.016)
			(layers "B.Cu" "B.Mask" "B.Paste")
			(net "GND")
		)
		(zone
			(layer "B.Cu")
			(hatch none 0.5)
			(connect_pads
				(clearance 0)
			)
			(min_thickness 0.25)
			(keepout
				(tracks not_allowed)
				(vias allowed)
				(pads allowed)
				(copperpour not_allowed)
				(footprints allowed)
			)
			(placement
				(enabled no)
				(sheetname "")
			)
			(fill
				(thermal_gap 0.5)
				(thermal_bridge_width 0.5)
				(island_removal_mode 0)
			)
			(polygon
				(pts
					(xy 271.145 4.445) (xy 271.907 4.445) (xy 271.907 3.175) (xy 271.145 3.175)
				)
			)
		)
	)
	(footprint ""
		(layer "B.Cu")
		(at 405.257 -116.7765 180)
		(property "Reference" "C2M12"
			(at 0 0 0)
			(layer "B.SilkS")
			(hide yes)
			(effects
				(font
					(size 1.27 1.27)
				)
				(justify mirror)
			)
		)
		(property "Value" ""
			(at 0 0 0)
			(layer "B.Fab")
			(effects
				(font
					(size 1.27 1.27)
				)
				(justify mirror)
			)
		)
		(duplicate_pad_numbers_are_jumpers no)
		(fp_poly
			(pts
				(xy 0.4953 -0.2032) (xy -0.4953 -0.2032) (xy -0.4953 1.6002) (xy 0.4953 1.6002)
			)
			(stroke
				(width 0)
				(type default)
			)
			(fill no)
			(layer "B.CrtYd")
		)
		(fp_line
			(start 0.4953 1.6002)
			(end 0.4953 -0.2032)
			(stroke
				(width 0.1)
				(type default)
			)
			(layer "B.Fab")
		)
		(fp_line
			(start 0.4953 -0.2032)
			(end -0.4953 -0.2032)
			(stroke
				(width 0.1)
				(type default)
			)
			(layer "B.Fab")
		)
		(fp_line
			(start -0.4953 1.6002)
			(end 0.4953 1.6002)
			(stroke
				(width 0.1)
				(type default)
			)
			(layer "B.Fab")
		)
		(fp_line
			(start -0.4953 -0.2032)
			(end -0.4953 1.6002)
			(stroke
				(width 0.1)
				(type default)
			)
			(layer "B.Fab")
		)
		(pad "1" smd rect
			(at 0 0)
			(size 0.762 0.889)
			(layers "B.Cu" "B.Mask" "B.Paste")
			(net "P1V05_PCH_STBY")
		)
		(pad "2" smd rect
			(at 0 1.397)
			(size 0.762 0.889)
			(layers "B.Cu" "B.Mask" "B.Paste")
			(net "GND")
		)
		(zone
			(layer "B.Cu")
			(hatch none 0.5)
			(connect_pads
				(clearance 0)
			)
			(min_thickness 0.25)
			(keepout
				(tracks not_allowed)
				(vias allowed)
				(pads allowed)
				(copperpour not_allowed)
				(footprints allowed)
			)
			(placement
				(enabled no)
				(sheetname "")
			)
			(fill
				(thermal_gap 0.5)
				(thermal_bridge_width 0.5)
				(island_removal_mode 0)
			)
			(polygon
				(pts
					(xy 404.876 -117.221) (xy 405.638 -117.221) (xy 405.638 -117.729) (xy 404.876 -117.729)
				)
			)
		)
	)
	(footprint ""
		(layer "B.Cu")
		(at 17.526 -87.7062)
		(property "Reference" "R9P2"
			(at 0 0 0)
			(layer "B.SilkS")
			(hide yes)
			(effects
				(font
					(size 1.27 1.27)
				)
				(justify mirror)
			)
		)
		(property "Value" ""
			(at 0 0 0)
			(layer "B.Fab")
			(effects
				(font
					(size 1.27 1.27)
				)
				(justify mirror)
			)
		)
		(duplicate_pad_numbers_are_jumpers no)
		(fp_poly
			(pts
				(xy 0.2794 -0.1016) (xy -0.2794 -0.1016) (xy -0.2794 0.9906) (xy 0.2794 0.9906)
			)
			(stroke
				(width 0)
				(type default)
			)
			(fill no)
			(layer "B.CrtYd")
		)
		(fp_line
			(start -0.2794 -0.1016)
			(end 0.2794 -0.1016)
			(stroke
				(width 0.1)
				(type default)
			)
			(layer "B.Fab")
		)
		(fp_line
			(start -0.2794 0.9906)
			(end -0.2794 -0.1016)
			(stroke
				(width 0.1)
				(type default)
			)
			(layer "B.Fab")
		)
		(fp_line
			(start 0.2794 -0.1016)
			(end 0.2794 0.9906)
			(stroke
				(width 0.1)
				(type default)
			)
			(layer "B.Fab")
		)
		(fp_line
			(start 0.2794 0.9906)
			(end -0.2794 0.9906)
			(stroke
				(width 0.1)
				(type default)
			)
			(layer "B.Fab")
		)
		(pad "1" smd rect
			(at 0 0 180)
			(size 0.508 0.508)
			(layers "B.Cu" "B.Mask" "B.Paste")
			(net "PVCCIO_CPU1")
		)
		(pad "2" smd rect
			(at 0 0.889 180)
			(size 0.508 0.508)
			(layers "B.Cu" "B.Mask" "B.Paste")
			(net "SVID_CLK0_CPU1_R")
		)
		(zone
			(layer "B.Cu")
			(hatch none 0.5)
			(connect_pads
				(clearance 0)
			)
			(min_thickness 0.25)
			(keepout
				(tracks allowed)
				(vias not_allowed)
				(pads allowed)
				(copperpour not_allowed)
				(footprints allowed)
			)
			(placement
				(enabled no)
				(sheetname "")
			)
			(fill
				(thermal_gap 0.5)
				(thermal_bridge_width 0.5)
				(island_removal_mode 0)
			)
			(polygon
				(pts
					(xy 17.78 -87.4522) (xy 17.272 -87.4522) (xy 17.272 -87.0712) (xy 17.78 -87.0712)
				)
			)
		)
		(zone
			(layer "B.Cu")
			(hatch none 0.5)
			(connect_pads
				(clearance 0)
			)
			(min_thickness 0.25)
			(keepout
				(tracks not_allowed)
				(vias allowed)
				(pads allowed)
				(copperpour not_allowed)
				(footprints allowed)
			)
			(placement
				(enabled no)
				(sheetname "")
			)
			(fill
				(thermal_gap 0.5)
				(thermal_bridge_width 0.5)
				(island_removal_mode 0)
			)
			(polygon
				(pts
					(xy 17.78 -87.0712) (xy 17.272 -87.0712) (xy 17.272 -87.4522) (xy 17.78 -87.4522)
				)
			)
		)
	)
	(footprint ""
		(layer "B.Cu")
		(at 183.515 -145.796 180)
		(property "Reference" "R6L10"
			(at 0 0 0)
			(layer "B.SilkS")
			(hide yes)
			(effects
				(font
					(size 1.27 1.27)
				)
				(justify mirror)
			)
		)
		(property "Value" ""
			(at 0 0 0)
			(layer "B.Fab")
			(effects
				(font
					(size 1.27 1.27)
				)
				(justify mirror)
			)
		)
		(duplicate_pad_numbers_are_jumpers no)
		(fp_rect
			(start 0.2794 0.9906)
			(end -0.2794 -0.1016)
			(stroke
				(width 0)
				(type default)
			)
			(fill no)
			(layer "B.CrtYd")
		)
		(fp_line
			(start 0.2794 0.9906)
			(end -0.2794 0.9906)
			(stroke
				(width 0.1)
				(type default)
			)
			(layer "B.Fab")
		)
		(fp_line
			(start 0.2794 -0.1016)
			(end 0.2794 0.9906)
			(stroke
				(width 0.1)
				(type default)
			)
			(layer "B.Fab")
		)
		(fp_line
			(start -0.2794 0.9906)
			(end -0.2794 -0.1016)
			(stroke
				(width 0.1)
				(type default)
			)
			(layer "B.Fab")
		)
		(fp_line
			(start -0.2794 -0.1016)
			(end 0.2794 -0.1016)
			(stroke
				(width 0.1)
				(type default)
			)
			(layer "B.Fab")
		)
		(pad "1" smd rect
			(at 0 0)
			(size 0.508 0.508)
			(layers "B.Cu" "B.Mask" "B.Paste")
			(net "PVDDQ_DEF")
		)
		(pad "2" smd rect
			(at 0 0.889)
			(size 0.508 0.508)
			(layers "B.Cu" "B.Mask" "B.Paste")
			(net "VSENSE_PVDDQ_DEF_VTT")
		)
		(zone
			(layer "B.Cu")
			(hatch none 0.5)
			(connect_pads
				(clearance 0)
			)
			(min_thickness 0.25)
			(keepout
				(tracks not_allowed)
				(vias allowed)
				(pads allowed)
				(copperpour not_allowed)
				(footprints allowed)
			)
			(placement
				(enabled no)
				(sheetname "")
			)
			(fill
				(thermal_gap 0.5)
				(thermal_bridge_width 0.5)
				(island_removal_mode 0)
			)
			(polygon
				(pts
					(xy 183.261 -146.431) (xy 183.261 -146.05) (xy 183.769 -146.05) (xy 183.769 -146.431)
				)
			)
		)
		(zone
			(layer "B.Cu")
			(hatch none 0.5)
			(connect_pads
				(clearance 0)
			)
			(min_thickness 0.25)
			(keepout
				(tracks allowed)
				(vias not_allowed)
				(pads allowed)
				(copperpour not_allowed)
				(footprints allowed)
			)
			(placement
				(enabled no)
				(sheetname "")
			)
			(fill
				(thermal_gap 0.5)
				(thermal_bridge_width 0.5)
				(island_removal_mode 0)
			)
			(polygon
				(pts
					(xy 183.261 -146.431) (xy 183.261 -146.05) (xy 183.769 -146.05) (xy 183.769 -146.431)
				)
			)
		)
	)
	(footprint ""
		(layer "B.Cu")
		(at 115.734592 -80.096614 180)
		(property "Reference" "C7P3"
			(at 0 0 0)
			(layer "B.SilkS")
			(hide yes)
			(effects
				(font
					(size 1.27 1.27)
				)
				(justify mirror)
			)
		)
		(property "Value" ""
			(at 0 0 0)
			(layer "B.Fab")
			(effects
				(font
					(size 1.27 1.27)
				)
				(justify mirror)
			)
		)
		(duplicate_pad_numbers_are_jumpers no)
		(fp_poly
			(pts
				(xy 0.7239 -0.2159) (xy -0.7239 -0.2159) (xy -0.7239 1.9939) (xy 0.7239 1.9939)
			)
			(stroke
				(width 0)
				(type default)
			)
			(fill no)
			(layer "B.CrtYd")
		)
		(fp_line
			(start 0.7239 1.9939)
			(end -0.7239 1.9939)
			(stroke
				(width 0.1)
				(type default)
			)
			(layer "B.Fab")
		)
		(fp_line
			(start 0.7239 -0.2159)
			(end 0.7239 1.9939)
			(stroke
				(width 0.1)
				(type default)
			)
			(layer "B.Fab")
		)
		(fp_line
			(start -0.7239 1.9939)
			(end -0.7239 -0.2159)
			(stroke
				(width 0.1)
				(type default)
			)
			(layer "B.Fab")
		)
		(fp_line
			(start -0.7239 -0.2159)
			(end 0.7239 -0.2159)
			(stroke
				(width 0.1)
				(type default)
			)
			(layer "B.Fab")
		)
		(pad "1" smd rect
			(at 0 0)
			(size 1.27 1.016)
			(layers "B.Cu" "B.Mask" "B.Paste")
			(net "PVCCIO_CPU1")
		)
		(pad "2" smd rect
			(at 0 1.778)
			(size 1.27 1.016)
			(layers "B.Cu" "B.Mask" "B.Paste")
			(net "GND")
		)
		(zone
			(layer "B.Cu")
			(hatch none 0.5)
			(connect_pads
				(clearance 0)
			)
			(min_thickness 0.25)
			(keepout
				(tracks not_allowed)
				(vias allowed)
				(pads allowed)
				(copperpour not_allowed)
				(footprints allowed)
			)
			(placement
				(enabled no)
				(sheetname "")
			)
			(fill
				(thermal_gap 0.5)
				(thermal_bridge_width 0.5)
				(island_removal_mode 0)
			)
			(polygon
				(pts
					(xy 115.099592 -80.604614) (xy 116.369592 -80.604614) (xy 116.369592 -81.366614) (xy 115.099592 -81.366614)
				)
			)
		)
	)
	(footprint ""
		(layer "B.Cu")
		(at 195.3006 -88.4428 90)
		(property "Reference" "CT34"
			(at 0.8382 -0.84963 90)
			(unlocked yes)
			(layer "B.SilkS")
			(effects
				(font
					(size 0.7874 0.5842)
					(thickness 0.1524)
				)
				(justify left mirror)
			)
		)
		(property "Value" ""
			(at 0 0 90)
			(layer "B.Fab")
			(effects
				(font
					(size 1.27 1.27)
				)
				(justify mirror)
			)
		)
		(duplicate_pad_numbers_are_jumpers no)
		(fp_poly
			(pts
				(xy -0.3048 -0.1016) (xy -0.3048 0.9906) (xy 0.3048 0.9906) (xy 0.3048 -0.1016)
			)
			(stroke
				(width 0)
				(type default)
			)
			(fill no)
			(layer "B.CrtYd")
		)
		(fp_line
			(start 0.3048 -0.1016)
			(end 0.3048 0.9906)
			(stroke
				(width 0.1)
				(type default)
			)
			(layer "B.Fab")
		)
		(fp_line
			(start -0.3048 -0.1016)
			(end 0.3048 -0.1016)
			(stroke
				(width 0.1)
				(type default)
			)
			(layer "B.Fab")
		)
		(fp_line
			(start 0.3048 0.9906)
			(end -0.3048 0.9906)
			(stroke
				(width 0.1)
				(type default)
			)
			(layer "B.Fab")
		)
		(fp_line
			(start -0.3048 0.9906)
			(end -0.3048 -0.1016)
			(stroke
				(width 0.1)
				(type default)
			)
			(layer "B.Fab")
		)
		(pad "1" smd rect
			(at 0 0 270)
			(size 0.508 0.508)
			(layers "B.Cu" "B.Mask" "B.Paste")
			(net "A_TSENSE_PVCCIN_CPU0")
		)
		(pad "2" smd rect
			(at 0 0.889 270)
			(size 0.508 0.508)
			(layers "B.Cu" "B.Mask" "B.Paste")
			(net "GND")
		)
		(zone
			(layer "B.Cu")
			(hatch none 0.5)
			(connect_pads
				(clearance 0)
			)
			(min_thickness 0.25)
			(keepout
				(tracks allowed)
				(vias not_allowed)
				(pads allowed)
				(copperpour not_allowed)
				(footprints allowed)
			)
			(placement
				(enabled no)
				(sheetname "")
			)
			(fill
				(thermal_gap 0.5)
				(thermal_bridge_width 0.5)
				(island_removal_mode 0)
			)
			(polygon
				(pts
					(xy 195.5546 -88.6968) (xy 195.5546 -88.1888) (xy 195.9356 -88.1888) (xy 195.9356 -88.6968)
				)
			)
		)
		(zone
			(layer "B.Cu")
			(hatch none 0.5)
			(connect_pads
				(clearance 0)
			)
			(min_thickness 0.25)
			(keepout
				(tracks not_allowed)
				(vias allowed)
				(pads allowed)
				(copperpour not_allowed)
				(footprints allowed)
			)
			(placement
				(enabled no)
				(sheetname "")
			)
			(fill
				(thermal_gap 0.5)
				(thermal_bridge_width 0.5)
				(island_removal_mode 0)
			)
			(polygon
				(pts
					(xy 195.9356 -88.6968) (xy 195.9356 -88.1888) (xy 195.5546 -88.1888) (xy 195.5546 -88.6968)
				)
			)
		)
	)
	(footprint ""
		(layer "B.Cu")
		(at 399.923 -57.658)
		(property "Reference" "R3T1"
			(at 0 0 0)
			(layer "B.SilkS")
			(hide yes)
			(effects
				(font
					(size 1.27 1.27)
				)
				(justify mirror)
			)
		)
		(property "Value" ""
			(at 0 0 0)
			(layer "B.Fab")
			(effects
				(font
					(size 1.27 1.27)
				)
				(justify mirror)
			)
		)
		(duplicate_pad_numbers_are_jumpers no)
		(fp_poly
			(pts
				(xy 0.2794 -0.1016) (xy -0.2794 -0.1016) (xy -0.2794 0.9906) (xy 0.2794 0.9906)
			)
			(stroke
				(width 0)
				(type default)
			)
			(fill no)
			(layer "B.CrtYd")
		)
		(fp_line
			(start -0.2794 -0.1016)
			(end 0.2794 -0.1016)
			(stroke
				(width 0.1)
				(type default)
			)
			(layer "B.Fab")
		)
		(fp_line
			(start -0.2794 0.9906)
			(end -0.2794 -0.1016)
			(stroke
				(width 0.1)
				(type default)
			)
			(layer "B.Fab")
		)
		(fp_line
			(start 0.2794 -0.1016)
			(end 0.2794 0.9906)
			(stroke
				(width 0.1)
				(type default)
			)
			(layer "B.Fab")
		)
		(fp_line
			(start 0.2794 0.9906)
			(end -0.2794 0.9906)
			(stroke
				(width 0.1)
				(type default)
			)
			(layer "B.Fab")
		)
		(pad "1" smd rect
			(at 0 0 180)
			(size 0.508 0.508)
			(layers "B.Cu" "B.Mask" "B.Paste")
			(net "SPI_BIOS_SOCKET_IO3")
		)
		(pad "2" smd rect
			(at 0 0.889 180)
			(size 0.508 0.508)
			(layers "B.Cu" "B.Mask" "B.Paste")
			(net "PU_BIOS_SPI_HOLD1_N")
		)
		(zone
			(layer "B.Cu")
			(hatch none 0.5)
			(connect_pads
				(clearance 0)
			)
			(min_thickness 0.25)
			(keepout
				(tracks allowed)
				(vias not_allowed)
				(pads allowed)
				(copperpour not_allowed)
				(footprints allowed)
			)
			(placement
				(enabled no)
				(sheetname "")
			)
			(fill
				(thermal_gap 0.5)
				(thermal_bridge_width 0.5)
				(island_removal_mode 0)
			)
			(polygon
				(pts
					(xy 400.177 -57.404) (xy 399.669 -57.404) (xy 399.669 -57.023) (xy 400.177 -57.023)
				)
			)
		)
		(zone
			(layer "B.Cu")
			(hatch none 0.5)
			(connect_pads
				(clearance 0)
			)
			(min_thickness 0.25)
			(keepout
				(tracks not_allowed)
				(vias allowed)
				(pads allowed)
				(copperpour not_allowed)
				(footprints allowed)
			)
			(placement
				(enabled no)
				(sheetname "")
			)
			(fill
				(thermal_gap 0.5)
				(thermal_bridge_width 0.5)
				(island_removal_mode 0)
			)
			(polygon
				(pts
					(xy 400.177 -57.023) (xy 399.669 -57.023) (xy 399.669 -57.404) (xy 400.177 -57.404)
				)
			)
		)
	)
	(footprint ""
		(layer "B.Cu")
		(at 479.9076 -41.529 90)
		(property "Reference" "C1R30"
			(at 0 0 90)
			(layer "B.SilkS")
			(hide yes)
			(effects
				(font
					(size 1.27 1.27)
				)
				(justify mirror)
			)
		)
		(property "Value" ""
			(at 0 0 90)
			(layer "B.Fab")
			(effects
				(font
					(size 1.27 1.27)
				)
				(justify mirror)
			)
		)
		(duplicate_pad_numbers_are_jumpers no)
		(fp_poly
			(pts
				(xy 0.4953 -0.2032) (xy -0.4953 -0.2032) (xy -0.4953 1.6002) (xy 0.4953 1.6002)
			)
			(stroke
				(width 0)
				(type default)
			)
			(fill no)
			(layer "B.CrtYd")
		)
		(fp_line
			(start 0.4953 -0.2032)
			(end -0.4953 -0.2032)
			(stroke
				(width 0.1)
				(type default)
			)
			(layer "B.Fab")
		)
		(fp_line
			(start -0.4953 -0.2032)
			(end -0.4953 1.6002)
			(stroke
				(width 0.1)
				(type default)
			)
			(layer "B.Fab")
		)
		(fp_line
			(start 0.4953 1.6002)
			(end 0.4953 -0.2032)
			(stroke
				(width 0.1)
				(type default)
			)
			(layer "B.Fab")
		)
		(fp_line
			(start -0.4953 1.6002)
			(end 0.4953 1.6002)
			(stroke
				(width 0.1)
				(type default)
			)
			(layer "B.Fab")
		)
		(pad "1" smd rect
			(at 0 0 270)
			(size 0.762 0.889)
			(layers "B.Cu" "B.Mask" "B.Paste")
			(net "P1V5_LAN")
		)
		(pad "2" smd rect
			(at 0 1.397 270)
			(size 0.762 0.889)
			(layers "B.Cu" "B.Mask" "B.Paste")
			(net "GND")
		)
		(zone
			(layer "B.Cu")
			(hatch none 0.5)
			(connect_pads
				(clearance 0)
			)
			(min_thickness 0.25)
			(keepout
				(tracks not_allowed)
				(vias allowed)
				(pads allowed)
				(copperpour not_allowed)
				(footprints allowed)
			)
			(placement
				(enabled no)
				(sheetname "")
			)
			(fill
				(thermal_gap 0.5)
				(thermal_bridge_width 0.5)
				(island_removal_mode 0)
			)
			(polygon
				(pts
					(xy 480.3521 -41.91) (xy 480.3521 -41.148) (xy 480.8601 -41.148) (xy 480.8601 -41.91)
				)
			)
		)
	)
	(footprint ""
		(layer "B.Cu")
		(at 437.642 -141.986)
		(property "Reference" "R25W186"
			(at 0.8382 -0.67818 0)
			(unlocked yes)
			(layer "B.SilkS")
			(effects
				(font
					(size 0.4064 0.254)
					(thickness 0.1524)
				)
				(justify left mirror)
			)
		)
		(property "Value" ""
			(at 0 0 0)
			(layer "B.Fab")
			(effects
				(font
					(size 1.27 1.27)
				)
				(justify mirror)
			)
		)
		(duplicate_pad_numbers_are_jumpers no)
		(fp_poly
			(pts
				(xy 0.2794 -0.1016) (xy -0.2794 -0.1016) (xy -0.2794 0.9906) (xy 0.2794 0.9906)
			)
			(stroke
				(width 0)
				(type default)
			)
			(fill no)
			(layer "B.CrtYd")
		)
		(fp_line
			(start -0.2794 -0.1016)
			(end 0.2794 -0.1016)
			(stroke
				(width 0.1)
				(type default)
			)
			(layer "B.Fab")
		)
		(fp_line
			(start -0.2794 0.9906)
			(end -0.2794 -0.1016)
			(stroke
				(width 0.1)
				(type default)
			)
			(layer "B.Fab")
		)
		(fp_line
			(start 0.2794 -0.1016)
			(end 0.2794 0.9906)
			(stroke
				(width 0.1)
				(type default)
			)
			(layer "B.Fab")
		)
		(fp_line
			(start 0.2794 0.9906)
			(end -0.2794 0.9906)
			(stroke
				(width 0.1)
				(type default)
			)
			(layer "B.Fab")
		)
		(pad "1" smd rect
			(at 0 0 180)
			(size 0.508 0.508)
			(layers "B.Cu" "B.Mask" "B.Paste")
			(net "BMC_JTAG_SEL_N")
		)
		(pad "2" smd rect
			(at 0 0.889 180)
			(size 0.508 0.508)
			(layers "B.Cu" "B.Mask" "B.Paste")
			(net "FM_JTAG_PLD_EN_DEBUG")
		)
		(zone
			(layer "B.Cu")
			(hatch none 0.5)
			(connect_pads
				(clearance 0)
			)
			(min_thickness 0.25)
			(keepout
				(tracks allowed)
				(vias not_allowed)
				(pads allowed)
				(copperpour not_allowed)
				(footprints allowed)
			)
			(placement
				(enabled no)
				(sheetname "")
			)
			(fill
				(thermal_gap 0.5)
				(thermal_bridge_width 0.5)
				(island_removal_mode 0)
			)
			(polygon
				(pts
					(xy 437.896 -141.732) (xy 437.388 -141.732) (xy 437.388 -141.351) (xy 437.896 -141.351)
				)
			)
		)
		(zone
			(layer "B.Cu")
			(hatch none 0.5)
			(connect_pads
				(clearance 0)
			)
			(min_thickness 0.25)
			(keepout
				(tracks not_allowed)
				(vias allowed)
				(pads allowed)
				(copperpour not_allowed)
				(footprints allowed)
			)
			(placement
				(enabled no)
				(sheetname "")
			)
			(fill
				(thermal_gap 0.5)
				(thermal_bridge_width 0.5)
				(island_removal_mode 0)
			)
			(polygon
				(pts
					(xy 437.896 -141.351) (xy 437.388 -141.351) (xy 437.388 -141.732) (xy 437.896 -141.732)
				)
			)
		)
	)
	(footprint ""
		(layer "B.Cu")
		(at 448.6656 -151.384 180)
		(property "Reference" "Q25W5"
			(at 0.229362 -1.59512 180)
			(unlocked yes)
			(layer "B.SilkS")
			(effects
				(font
					(size 1.27 0.9652)
					(thickness 0.1524)
				)
				(justify left mirror)
			)
		)
		(property "Value" ""
			(at 0 0 0)
			(layer "B.Fab")
			(effects
				(font
					(size 1.27 1.27)
				)
				(justify mirror)
			)
		)
		(duplicate_pad_numbers_are_jumpers no)
		(fp_line
			(start -0.381 0.635)
			(end -0.381 1.27)
			(stroke
				(width 0.1524)
				(type default)
			)
			(layer "B.SilkS")
		)
		(fp_line
			(start -0.9525 2.4765)
			(end -1.778 2.4765)
			(stroke
				(width 0.1524)
				(type default)
			)
			(layer "B.SilkS")
		)
		(fp_line
			(start -0.9525 -0.5715)
			(end -1.778 -0.5715)
			(stroke
				(width 0.1524)
				(type default)
			)
			(layer "B.SilkS")
		)
		(fp_line
			(start -1.778 2.4765)
			(end -1.778 1.5875)
			(stroke
				(width 0.1524)
				(type default)
			)
			(layer "B.SilkS")
		)
		(fp_line
			(start -1.778 -0.5715)
			(end -1.778 0.3175)
			(stroke
				(width 0.1524)
				(type default)
			)
			(layer "B.SilkS")
		)
		(fp_circle
			(center 0.9525 -0.9271)
			(end 0.8255 -0.9271)
			(stroke
				(width 0.254)
				(type default)
			)
			(fill no)
			(layer "B.SilkS")
		)
		(fp_poly
			(pts
				(xy -1.778 2.4765) (xy -0.381 2.4765) (xy -0.381 -0.5715) (xy -1.778 -0.5715)
			)
			(stroke
				(width 0)
				(type default)
			)
			(fill no)
			(layer "B.CrtYd")
		)
		(fp_line
			(start -0.381 2.4765)
			(end -1.778 2.4765)
			(stroke
				(width 0.1)
				(type default)
			)
			(layer "B.Fab")
		)
		(fp_line
			(start -0.381 -0.5715)
			(end -0.381 2.4765)
			(stroke
				(width 0.1)
				(type default)
			)
			(layer "B.Fab")
		)
		(fp_line
			(start -1.778 2.4765)
			(end -1.778 -0.5715)
			(stroke
				(width 0.1)
				(type default)
			)
			(layer "B.Fab")
		)
		(fp_line
			(start -1.778 -0.5715)
			(end -0.381 -0.5715)
			(stroke
				(width 0.1)
				(type default)
			)
			(layer "B.Fab")
		)
		(fp_circle
			(center 0.9525 -0.9271)
			(end 0.8255 -0.9271)
			(stroke
				(width 0.254)
				(type default)
			)
			(fill no)
			(layer "B.Fab")
		)
		(pad "1" smd rect
			(at 0 0)
			(size 1.143 0.508)
			(layers "B.Cu" "B.Mask" "B.Paste")
			(net "BMC_JTAG_SEL_N")
		)
		(pad "2" smd rect
			(at 0 1.905)
			(size 1.143 0.508)
			(layers "B.Cu" "B.Mask" "B.Paste")
			(net "GND")
		)
		(pad "3" smd rect
			(at -2.159 0.9525)
			(size 1.143 0.508)
			(layers "B.Cu" "B.Mask" "B.Paste")
			(net "BMC_JTAG_SEL")
		)
	)
	(footprint ""
		(layer "B.Cu")
		(at 407.416 -31.6865 -90)
		(property "Reference" "C1W21"
			(at -0.97536 0.76708 0)
			(unlocked yes)
			(layer "B.SilkS")
			(effects
				(font
					(size 0.4064 0.254)
					(thickness 0.1524)
				)
				(justify mirror)
			)
		)
		(property "Value" ""
			(at 0 0 90)
			(layer "B.Fab")
			(effects
				(font
					(size 1.27 1.27)
				)
				(justify mirror)
			)
		)
		(duplicate_pad_numbers_are_jumpers no)
		(fp_poly
			(pts
				(xy 0.4953 -0.2032) (xy -0.4953 -0.2032) (xy -0.4953 1.6002) (xy 0.4953 1.6002)
			)
			(stroke
				(width 0)
				(type default)
			)
			(fill no)
			(layer "B.CrtYd")
		)
		(fp_line
			(start -0.4953 1.6002)
			(end 0.4953 1.6002)
			(stroke
				(width 0.1)
				(type default)
			)
			(layer "B.Fab")
		)
		(fp_line
			(start 0.4953 1.6002)
			(end 0.4953 -0.2032)
			(stroke
				(width 0.1)
				(type default)
			)
			(layer "B.Fab")
		)
		(fp_line
			(start -0.4953 -0.2032)
			(end -0.4953 1.6002)
			(stroke
				(width 0.1)
				(type default)
			)
			(layer "B.Fab")
		)
		(fp_line
			(start 0.4953 -0.2032)
			(end -0.4953 -0.2032)
			(stroke
				(width 0.1)
				(type default)
			)
			(layer "B.Fab")
		)
		(pad "1" smd rect
			(at 0 0 90)
			(size 0.762 0.889)
			(layers "B.Cu" "B.Mask" "B.Paste")
			(net "A_USB2AVRES")
		)
		(pad "2" smd rect
			(at 0 1.397 90)
			(size 0.762 0.889)
			(layers "B.Cu" "B.Mask" "B.Paste")
			(net "GND")
		)
		(zone
			(layer "B.Cu")
			(hatch none 0.5)
			(connect_pads
				(clearance 0)
			)
			(min_thickness 0.25)
			(keepout
				(tracks not_allowed)
				(vias allowed)
				(pads allowed)
				(copperpour not_allowed)
				(footprints allowed)
			)
			(placement
				(enabled no)
				(sheetname "")
			)
			(fill
				(thermal_gap 0.5)
				(thermal_bridge_width 0.5)
				(island_removal_mode 0)
			)
			(polygon
				(pts
					(xy 406.9715 -31.3055) (xy 406.9715 -32.0675) (xy 406.4635 -32.0675) (xy 406.4635 -31.3055)
				)
			)
		)
	)
	(footprint ""
		(layer "B.Cu")
		(at 341.728806 -61.257434)
		(property "Reference" "C2U9"
			(at 0 0 0)
			(layer "B.SilkS")
			(hide yes)
			(effects
				(font
					(size 1.27 1.27)
				)
				(justify mirror)
			)
		)
		(property "Value" ""
			(at 0 0 0)
			(layer "B.Fab")
			(effects
				(font
					(size 1.27 1.27)
				)
				(justify mirror)
			)
		)
		(duplicate_pad_numbers_are_jumpers no)
		(fp_poly
			(pts
				(xy -0.3048 -0.1016) (xy -0.3048 0.9906) (xy 0.3048 0.9906) (xy 0.3048 -0.1016)
			)
			(stroke
				(width 0)
				(type default)
			)
			(fill no)
			(layer "B.CrtYd")
		)
		(fp_line
			(start -0.3048 -0.1016)
			(end 0.3048 -0.1016)
			(stroke
				(width 0.1)
				(type default)
			)
			(layer "B.Fab")
		)
		(fp_line
			(start -0.3048 0.9906)
			(end -0.3048 -0.1016)
			(stroke
				(width 0.1)
				(type default)
			)
			(layer "B.Fab")
		)
		(fp_line
			(start 0.3048 -0.1016)
			(end 0.3048 0.9906)
			(stroke
				(width 0.1)
				(type default)
			)
			(layer "B.Fab")
		)
		(fp_line
			(start 0.3048 0.9906)
			(end -0.3048 0.9906)
			(stroke
				(width 0.1)
				(type default)
			)
			(layer "B.Fab")
		)
		(pad "1" smd rect
			(at 0 0 180)
			(size 0.508 0.508)
			(layers "B.Cu" "B.Mask" "B.Paste")
			(net "P3E_CPU0_PE1_PCH_RXP<3>")
		)
		(pad "2" smd rect
			(at 0 0.889 180)
			(size 0.508 0.508)
			(layers "B.Cu" "B.Mask" "B.Paste")
			(net "P3E_CPU0_PE1_SS_RXP<3>")
		)
		(zone
			(layer "B.Cu")
			(hatch none 0.5)
			(connect_pads
				(clearance 0)
			)
			(min_thickness 0.25)
			(keepout
				(tracks allowed)
				(vias not_allowed)
				(pads allowed)
				(copperpour not_allowed)
				(footprints allowed)
			)
			(placement
				(enabled no)
				(sheetname "")
			)
			(fill
				(thermal_gap 0.5)
				(thermal_bridge_width 0.5)
				(island_removal_mode 0)
			)
			(polygon
				(pts
					(xy 341.982806 -61.003434) (xy 341.474806 -61.003434) (xy 341.474806 -60.622434) (xy 341.982806 -60.622434)
				)
			)
		)
		(zone
			(layer "B.Cu")
			(hatch none 0.5)
			(connect_pads
				(clearance 0)
			)
			(min_thickness 0.25)
			(keepout
				(tracks not_allowed)
				(vias allowed)
				(pads allowed)
				(copperpour not_allowed)
				(footprints allowed)
			)
			(placement
				(enabled no)
				(sheetname "")
			)
			(fill
				(thermal_gap 0.5)
				(thermal_bridge_width 0.5)
				(island_removal_mode 0)
			)
			(polygon
				(pts
					(xy 341.982806 -60.622434) (xy 341.474806 -60.622434) (xy 341.474806 -61.003434) (xy 341.982806 -61.003434)
				)
			)
		)
	)
	(footprint ""
		(layer "B.Cu")
		(at 351.416874 -22.949916 90)
		(property "Reference" "C3T14"
			(at -1.47828 0.78994 180)
			(unlocked yes)
			(layer "B.SilkS")
			(effects
				(font
					(size 0.4064 0.254)
					(thickness 0.1524)
				)
				(justify mirror)
			)
		)
		(property "Value" ""
			(at 0 0 90)
			(layer "B.Fab")
			(effects
				(font
					(size 1.27 1.27)
				)
				(justify mirror)
			)
		)
		(duplicate_pad_numbers_are_jumpers no)
		(fp_poly
			(pts
				(xy 0.7239 -0.2159) (xy -0.7239 -0.2159) (xy -0.7239 1.9939) (xy 0.7239 1.9939)
			)
			(stroke
				(width 0)
				(type default)
			)
			(fill no)
			(layer "B.CrtYd")
		)
		(fp_line
			(start 0.7239 -0.2159)
			(end 0.7239 1.9939)
			(stroke
				(width 0.1)
				(type default)
			)
			(layer "B.Fab")
		)
		(fp_line
			(start -0.7239 -0.2159)
			(end 0.7239 -0.2159)
			(stroke
				(width 0.1)
				(type default)
			)
			(layer "B.Fab")
		)
		(fp_line
			(start 0.7239 1.9939)
			(end -0.7239 1.9939)
			(stroke
				(width 0.1)
				(type default)
			)
			(layer "B.Fab")
		)
		(fp_line
			(start -0.7239 1.9939)
			(end -0.7239 -0.2159)
			(stroke
				(width 0.1)
				(type default)
			)
			(layer "B.Fab")
		)
		(pad "1" smd rect
			(at 0 0 270)
			(size 1.27 1.016)
			(layers "B.Cu" "B.Mask" "B.Paste")
			(net "VR_FET_SW_P12V_STBY_PVPP_ABC")
		)
		(pad "2" smd rect
			(at 0 1.778 270)
			(size 1.27 1.016)
			(layers "B.Cu" "B.Mask" "B.Paste")
			(net "GND")
		)
		(zone
			(layer "B.Cu")
			(hatch none 0.5)
			(connect_pads
				(clearance 0)
			)
			(min_thickness 0.25)
			(keepout
				(tracks not_allowed)
				(vias allowed)
				(pads allowed)
				(copperpour not_allowed)
				(footprints allowed)
			)
			(placement
				(enabled no)
				(sheetname "")
			)
			(fill
				(thermal_gap 0.5)
				(thermal_bridge_width 0.5)
				(island_removal_mode 0)
			)
			(polygon
				(pts
					(xy 351.924874 -23.584916) (xy 351.924874 -22.314916) (xy 352.686874 -22.314916) (xy 352.686874 -23.584916)
				)
			)
		)
	)
	(footprint ""
		(layer "B.Cu")
		(at 447.079878 -152.842722)
		(property "Reference" "C25W96"
			(at 0.8382 -0.67818 0)
			(unlocked yes)
			(layer "B.SilkS")
			(effects
				(font
					(size 0.4064 0.254)
					(thickness 0.1524)
				)
				(justify left mirror)
			)
		)
		(property "Value" ""
			(at 0 0 0)
			(layer "B.Fab")
			(effects
				(font
					(size 1.27 1.27)
				)
				(justify mirror)
			)
		)
		(duplicate_pad_numbers_are_jumpers no)
		(fp_poly
			(pts
				(xy -0.3048 -0.1016) (xy -0.3048 0.9906) (xy 0.3048 0.9906) (xy 0.3048 -0.1016)
			)
			(stroke
				(width 0)
				(type default)
			)
			(fill no)
			(layer "B.CrtYd")
		)
		(fp_line
			(start -0.3048 -0.1016)
			(end 0.3048 -0.1016)
			(stroke
				(width 0.1)
				(type default)
			)
			(layer "B.Fab")
		)
		(fp_line
			(start -0.3048 0.9906)
			(end -0.3048 -0.1016)
			(stroke
				(width 0.1)
				(type default)
			)
			(layer "B.Fab")
		)
		(fp_line
			(start 0.3048 -0.1016)
			(end 0.3048 0.9906)
			(stroke
				(width 0.1)
				(type default)
			)
			(layer "B.Fab")
		)
		(fp_line
			(start 0.3048 0.9906)
			(end -0.3048 0.9906)
			(stroke
				(width 0.1)
				(type default)
			)
			(layer "B.Fab")
		)
		(pad "1" smd rect
			(at 0 0 180)
			(size 0.508 0.508)
			(layers "B.Cu" "B.Mask" "B.Paste")
			(net "P3V3_STBY")
		)
		(pad "2" smd rect
			(at 0 0.889 180)
			(size 0.508 0.508)
			(layers "B.Cu" "B.Mask" "B.Paste")
			(net "GND")
		)
		(zone
			(layer "B.Cu")
			(hatch none 0.5)
			(connect_pads
				(clearance 0)
			)
			(min_thickness 0.25)
			(keepout
				(tracks allowed)
				(vias not_allowed)
				(pads allowed)
				(copperpour not_allowed)
				(footprints allowed)
			)
			(placement
				(enabled no)
				(sheetname "")
			)
			(fill
				(thermal_gap 0.5)
				(thermal_bridge_width 0.5)
				(island_removal_mode 0)
			)
			(polygon
				(pts
					(xy 447.333878 -152.588722) (xy 446.825878 -152.588722) (xy 446.825878 -152.207722) (xy 447.333878 -152.207722)
				)
			)
		)
		(zone
			(layer "B.Cu")
			(hatch none 0.5)
			(connect_pads
				(clearance 0)
			)
			(min_thickness 0.25)
			(keepout
				(tracks not_allowed)
				(vias allowed)
				(pads allowed)
				(copperpour not_allowed)
				(footprints allowed)
			)
			(placement
				(enabled no)
				(sheetname "")
			)
			(fill
				(thermal_gap 0.5)
				(thermal_bridge_width 0.5)
				(island_removal_mode 0)
			)
			(polygon
				(pts
					(xy 447.333878 -152.207722) (xy 446.825878 -152.207722) (xy 446.825878 -152.588722) (xy 447.333878 -152.588722)
				)
			)
		)
	)
	(footprint ""
		(layer "B.Cu")
		(at 470.027 -60.96 -90)
		(property "Reference" "R1R18"
			(at 0 0 90)
			(layer "B.SilkS")
			(hide yes)
			(effects
				(font
					(size 1.27 1.27)
				)
				(justify mirror)
			)
		)
		(property "Value" ""
			(at 0 0 90)
			(layer "B.Fab")
			(effects
				(font
					(size 1.27 1.27)
				)
				(justify mirror)
			)
		)
		(duplicate_pad_numbers_are_jumpers no)
		(fp_poly
			(pts
				(xy 0.2794 -0.1016) (xy -0.2794 -0.1016) (xy -0.2794 0.9906) (xy 0.2794 0.9906)
			)
			(stroke
				(width 0)
				(type default)
			)
			(fill no)
			(layer "B.CrtYd")
		)
		(fp_line
			(start -0.2794 0.9906)
			(end -0.2794 -0.1016)
			(stroke
				(width 0.1)
				(type default)
			)
			(layer "B.Fab")
		)
		(fp_line
			(start 0.2794 0.9906)
			(end -0.2794 0.9906)
			(stroke
				(width 0.1)
				(type default)
			)
			(layer "B.Fab")
		)
		(fp_line
			(start -0.2794 -0.1016)
			(end 0.2794 -0.1016)
			(stroke
				(width 0.1)
				(type default)
			)
			(layer "B.Fab")
		)
		(fp_line
			(start 0.2794 -0.1016)
			(end 0.2794 0.9906)
			(stroke
				(width 0.1)
				(type default)
			)
			(layer "B.Fab")
		)
		(pad "1" smd rect
			(at 0 0 90)
			(size 0.508 0.508)
			(layers "B.Cu" "B.Mask" "B.Paste")
			(net "P3V3_STBY")
		)
		(pad "2" smd rect
			(at 0 0.889 90)
			(size 0.508 0.508)
			(layers "B.Cu" "B.Mask" "B.Paste")
			(net "SMB_PCH_MEZZ_LOM0_SCL")
		)
		(zone
			(layer "B.Cu")
			(hatch none 0.5)
			(connect_pads
				(clearance 0)
			)
			(min_thickness 0.25)
			(keepout
				(tracks not_allowed)
				(vias allowed)
				(pads allowed)
				(copperpour not_allowed)
				(footprints allowed)
			)
			(placement
				(enabled no)
				(sheetname "")
			)
			(fill
				(thermal_gap 0.5)
				(thermal_bridge_width 0.5)
				(island_removal_mode 0)
			)
			(polygon
				(pts
					(xy 469.392 -60.706) (xy 469.392 -61.214) (xy 469.773 -61.214) (xy 469.773 -60.706)
				)
			)
		)
		(zone
			(layer "B.Cu")
			(hatch none 0.5)
			(connect_pads
				(clearance 0)
			)
			(min_thickness 0.25)
			(keepout
				(tracks allowed)
				(vias not_allowed)
				(pads allowed)
				(copperpour not_allowed)
				(footprints allowed)
			)
			(placement
				(enabled no)
				(sheetname "")
			)
			(fill
				(thermal_gap 0.5)
				(thermal_bridge_width 0.5)
				(island_removal_mode 0)
			)
			(polygon
				(pts
					(xy 469.773 -60.706) (xy 469.773 -61.214) (xy 469.392 -61.214) (xy 469.392 -60.706)
				)
			)
		)
	)
	(footprint ""
		(layer "B.Cu")
		(at 329.2094 -27.6733 180)
		(property "Reference" "C4T3"
			(at -3.12293 2.9083 270)
			(unlocked yes)
			(layer "B.SilkS")
			(effects
				(font
					(size 0.7874 0.5842)
					(thickness 0.1524)
				)
				(justify left mirror)
			)
		)
		(property "Value" ""
			(at 0 0 0)
			(layer "B.Fab")
			(effects
				(font
					(size 1.27 1.27)
				)
				(justify mirror)
			)
		)
		(duplicate_pad_numbers_are_jumpers no)
		(fp_line
			(start 2.2987 7.3533)
			(end 1.7272 7.3533)
			(stroke
				(width 0.1524)
				(type default)
			)
			(layer "B.SilkS")
		)
		(fp_line
			(start 2.2987 -0.2413)
			(end 2.2987 7.3533)
			(stroke
				(width 0.1524)
				(type default)
			)
			(layer "B.SilkS")
		)
		(fp_line
			(start 2.032 1.524)
			(end 1.7272 1.524)
			(stroke
				(width 0.1524)
				(type default)
			)
			(layer "B.SilkS")
		)
		(fp_line
			(start 2.032 -0.2413)
			(end 2.2987 -0.2413)
			(stroke
				(width 0.1524)
				(type default)
			)
			(layer "B.SilkS")
		)
		(fp_line
			(start 2.032 -1.524)
			(end 2.032 1.524)
			(stroke
				(width 0.1524)
				(type default)
			)
			(layer "B.SilkS")
		)
		(fp_line
			(start 1.7272 -1.524)
			(end 2.032 -1.524)
			(stroke
				(width 0.1524)
				(type default)
			)
			(layer "B.SilkS")
		)
		(fp_line
			(start -1.7272 7.3533)
			(end -2.2987 7.3533)
			(stroke
				(width 0.1524)
				(type default)
			)
			(layer "B.SilkS")
		)
		(fp_line
			(start -1.7272 -1.524)
			(end -2.032 -1.524)
			(stroke
				(width 0.1524)
				(type default)
			)
			(layer "B.SilkS")
		)
		(fp_line
			(start -2.032 1.524)
			(end -1.7272 1.524)
			(stroke
				(width 0.1524)
				(type default)
			)
			(layer "B.SilkS")
		)
		(fp_line
			(start -2.032 -1.524)
			(end -2.032 1.524)
			(stroke
				(width 0.1524)
				(type default)
			)
			(layer "B.SilkS")
		)
		(fp_line
			(start -2.2987 7.3533)
			(end -2.2987 -0.2413)
			(stroke
				(width 0.1524)
				(type default)
			)
			(layer "B.SilkS")
		)
		(fp_line
			(start -2.2987 -0.2413)
			(end -2.032 -0.2413)
			(stroke
				(width 0.1524)
				(type default)
			)
			(layer "B.SilkS")
		)
		(fp_rect
			(start 2.2987 -0.2413)
			(end -2.2987 7.3533)
			(stroke
				(width 0)
				(type default)
			)
			(fill no)
			(layer "B.CrtYd")
		)
		(fp_line
			(start 2.2987 7.3533)
			(end 2.2987 -0.2413)
			(stroke
				(width 0.1)
				(type default)
			)
			(layer "B.Fab")
		)
		(fp_line
			(start 2.2987 -0.2413)
			(end -2.2987 -0.2413)
			(stroke
				(width 0.1)
				(type default)
			)
			(layer "B.Fab")
		)
		(fp_line
			(start -2.2987 7.3533)
			(end 2.2987 7.3533)
			(stroke
				(width 0.1)
				(type default)
			)
			(layer "B.Fab")
		)
		(fp_line
			(start -2.2987 -0.2413)
			(end -2.2987 7.3533)
			(stroke
				(width 0.1)
				(type default)
			)
			(layer "B.Fab")
		)
		(pad "1" smd rect
			(at 0 0)
			(size 2.54 3.048)
			(layers "B.Cu" "B.Mask" "B.Paste")
			(net "PVPP_ABC")
		)
		(pad "2" smd rect
			(at 0 7.112)
			(size 2.54 3.048)
			(layers "B.Cu" "B.Mask" "B.Paste")
			(net "GND")
		)
	)
	(footprint ""
		(layer "B.Cu")
		(at 347.5736 -5.5118 -90)
		(property "Reference" "C3U3"
			(at 0 0 90)
			(layer "B.SilkS")
			(hide yes)
			(effects
				(font
					(size 1.27 1.27)
				)
				(justify mirror)
			)
		)
		(property "Value" ""
			(at 0 0 90)
			(layer "B.Fab")
			(effects
				(font
					(size 1.27 1.27)
				)
				(justify mirror)
			)
		)
		(duplicate_pad_numbers_are_jumpers no)
		(fp_rect
			(start 0.7239 1.9939)
			(end -0.7239 -0.2159)
			(stroke
				(width 0)
				(type default)
			)
			(fill no)
			(layer "B.CrtYd")
		)
		(fp_line
			(start -0.7239 1.9939)
			(end -0.7239 -0.2159)
			(stroke
				(width 0.1)
				(type default)
			)
			(layer "B.Fab")
		)
		(fp_line
			(start 0.7239 1.9939)
			(end -0.7239 1.9939)
			(stroke
				(width 0.1)
				(type default)
			)
			(layer "B.Fab")
		)
		(fp_line
			(start -0.7239 -0.2159)
			(end 0.7239 -0.2159)
			(stroke
				(width 0.1)
				(type default)
			)
			(layer "B.Fab")
		)
		(fp_line
			(start 0.7239 -0.2159)
			(end 0.7239 1.9939)
			(stroke
				(width 0.1)
				(type default)
			)
			(layer "B.Fab")
		)
		(pad "1" smd rect
			(at 0 0 90)
			(size 1.27 1.016)
			(layers "B.Cu" "B.Mask" "B.Paste")
			(net "VR_FET_SW_P12V_STBY_PVDDQ_ABC")
		)
		(pad "2" smd rect
			(at 0 1.778 90)
			(size 1.27 1.016)
			(layers "B.Cu" "B.Mask" "B.Paste")
			(net "GND")
		)
		(zone
			(layer "B.Cu")
			(hatch none 0.5)
			(connect_pads
				(clearance 0)
			)
			(min_thickness 0.25)
			(keepout
				(tracks not_allowed)
				(vias allowed)
				(pads allowed)
				(copperpour not_allowed)
				(footprints allowed)
			)
			(placement
				(enabled no)
				(sheetname "")
			)
			(fill
				(thermal_gap 0.5)
				(thermal_bridge_width 0.5)
				(island_removal_mode 0)
			)
			(polygon
				(pts
					(xy 346.3036 -4.8768) (xy 347.0656 -4.8768) (xy 347.0656 -6.1468) (xy 346.3036 -6.1468)
				)
			)
		)
	)
	(footprint ""
		(layer "B.Cu")
		(at 179.804822 -20.014692 180)
		(property "Reference" "R6T9"
			(at 0 0 0)
			(layer "B.SilkS")
			(hide yes)
			(effects
				(font
					(size 1.27 1.27)
				)
				(justify mirror)
			)
		)
		(property "Value" ""
			(at 0 0 0)
			(layer "B.Fab")
			(effects
				(font
					(size 1.27 1.27)
				)
				(justify mirror)
			)
		)
		(duplicate_pad_numbers_are_jumpers no)
		(fp_rect
			(start 0.2794 0.9906)
			(end -0.2794 -0.1016)
			(stroke
				(width 0)
				(type default)
			)
			(fill no)
			(layer "B.CrtYd")
		)
		(fp_line
			(start 0.2794 0.9906)
			(end -0.2794 0.9906)
			(stroke
				(width 0.1)
				(type default)
			)
			(layer "B.Fab")
		)
		(fp_line
			(start 0.2794 -0.1016)
			(end 0.2794 0.9906)
			(stroke
				(width 0.1)
				(type default)
			)
			(layer "B.Fab")
		)
		(fp_line
			(start -0.2794 0.9906)
			(end -0.2794 -0.1016)
			(stroke
				(width 0.1)
				(type default)
			)
			(layer "B.Fab")
		)
		(fp_line
			(start -0.2794 -0.1016)
			(end 0.2794 -0.1016)
			(stroke
				(width 0.1)
				(type default)
			)
			(layer "B.Fab")
		)
		(pad "1" smd rect
			(at 0 0)
			(size 0.508 0.508)
			(layers "B.Cu" "B.Mask" "B.Paste")
			(net "PVCCIO_CPU0")
		)
		(pad "2" smd rect
			(at 0 0.889)
			(size 0.508 0.508)
			(layers "B.Cu" "B.Mask" "B.Paste")
			(net "XDP_CPU_OBSFN_B1_MBP7_N")
		)
		(zone
			(layer "B.Cu")
			(hatch none 0.5)
			(connect_pads
				(clearance 0)
			)
			(min_thickness 0.25)
			(keepout
				(tracks allowed)
				(vias not_allowed)
				(pads allowed)
				(copperpour not_allowed)
				(footprints allowed)
			)
			(placement
				(enabled no)
				(sheetname "")
			)
			(fill
				(thermal_gap 0.5)
				(thermal_bridge_width 0.5)
				(island_removal_mode 0)
			)
			(polygon
				(pts
					(xy 179.550822 -20.649692) (xy 179.550822 -20.268692) (xy 180.058822 -20.268692) (xy 180.058822 -20.649692)
				)
			)
		)
		(zone
			(layer "B.Cu")
			(hatch none 0.5)
			(connect_pads
				(clearance 0)
			)
			(min_thickness 0.25)
			(keepout
				(tracks not_allowed)
				(vias allowed)
				(pads allowed)
				(copperpour not_allowed)
				(footprints allowed)
			)
			(placement
				(enabled no)
				(sheetname "")
			)
			(fill
				(thermal_gap 0.5)
				(thermal_bridge_width 0.5)
				(island_removal_mode 0)
			)
			(polygon
				(pts
					(xy 179.550822 -20.649692) (xy 179.550822 -20.268692) (xy 180.058822 -20.268692) (xy 180.058822 -20.649692)
				)
			)
		)
	)
	(footprint ""
		(layer "B.Cu")
		(at 387.5786 -114.9096 90)
		(property "Reference" "C3M38"
			(at 0 0 90)
			(layer "B.SilkS")
			(hide yes)
			(effects
				(font
					(size 1.27 1.27)
				)
				(justify mirror)
			)
		)
		(property "Value" ""
			(at 0 0 90)
			(layer "B.Fab")
			(effects
				(font
					(size 1.27 1.27)
				)
				(justify mirror)
			)
		)
		(duplicate_pad_numbers_are_jumpers no)
		(fp_rect
			(start 0.2794 0.9144)
			(end -0.2794 -0.1143)
			(stroke
				(width 0)
				(type default)
			)
			(fill no)
			(layer "B.CrtYd")
		)
		(fp_line
			(start 0.2794 -0.1143)
			(end -0.2794 -0.1143)
			(stroke
				(width 0.1)
				(type default)
			)
			(layer "B.Fab")
		)
		(fp_line
			(start -0.2794 -0.1143)
			(end -0.2794 0.9144)
			(stroke
				(width 0.1)
				(type default)
			)
			(layer "B.Fab")
		)
		(fp_line
			(start 0.2794 0.9144)
			(end 0.2794 -0.1143)
			(stroke
				(width 0.1)
				(type default)
			)
			(layer "B.Fab")
		)
		(fp_line
			(start -0.2794 0.9144)
			(end 0.2794 0.9144)
			(stroke
				(width 0.1)
				(type default)
			)
			(layer "B.Fab")
		)
		(pad "1" smd custom
			(at 0 0)
			(size 0.10414 0.10414)
			(layers "B.Cu" "B.Mask" "B.Paste")
			(net "P1V05_PCH_STBY")
			(options
				(clearance outline)
				(anchor circle)
			)
			(primitives
				(gr_poly
					(pts
						(xy -0.20828 -0.08636) (xy -0.20828 0.08636) (xy -0.08636 0.20828) (xy 0.086614 0.20828) (xy 0.20828 0.086614)
						(xy 0.20828 -0.08636) (xy 0.08636 -0.20828) (xy -0.08636 -0.20828)
					)
					(width 0)
					(fill yes)
				)
			)
		)
		(pad "2" smd custom
			(at 0 0.8001)
			(size 0.10414 0.10414)
			(layers "B.Cu" "B.Mask" "B.Paste")
			(net "GND")
			(options
				(clearance outline)
				(anchor circle)
			)
			(primitives
				(gr_poly
					(pts
						(xy -0.20828 -0.08636) (xy -0.20828 0.08636) (xy -0.08636 0.20828) (xy 0.086614 0.20828) (xy 0.20828 0.086614)
						(xy 0.20828 -0.08636) (xy 0.08636 -0.20828) (xy -0.08636 -0.20828)
					)
					(width 0)
					(fill yes)
				)
			)
		)
		(zone
			(layer "B.Cu")
			(hatch none 0.5)
			(connect_pads
				(clearance 0)
			)
			(min_thickness 0.25)
			(keepout
				(tracks not_allowed)
				(vias allowed)
				(pads allowed)
				(copperpour not_allowed)
				(footprints allowed)
			)
			(placement
				(enabled no)
				(sheetname "")
			)
			(fill
				(thermal_gap 0.5)
				(thermal_bridge_width 0.5)
				(island_removal_mode 0)
			)
			(polygon
				(pts
					(xy 387.78815 -114.99723) (xy 388.16915 -114.99723) (xy 388.16915 -114.82197) (xy 387.78815 -114.821716)
				)
			)
		)
		(zone
			(layer "B.Cu")
			(hatch none 0.5)
			(connect_pads
				(clearance 0)
			)
			(min_thickness 0.25)
			(keepout
				(tracks allowed)
				(vias not_allowed)
				(pads allowed)
				(copperpour not_allowed)
				(footprints allowed)
			)
			(placement
				(enabled no)
				(sheetname "")
			)
			(fill
				(thermal_gap 0.5)
				(thermal_bridge_width 0.5)
				(island_removal_mode 0)
			)
			(polygon
				(pts
					(xy 387.78815 -114.99723) (xy 388.16915 -114.99723) (xy 388.16915 -114.82197) (xy 387.78815 -114.821716)
				)
			)
		)
	)
	(footprint ""
		(layer "B.Cu")
		(at 281.3812 -76.4794 90)
		(property "Reference" "R4P5"
			(at 0 0 90)
			(layer "B.SilkS")
			(hide yes)
			(effects
				(font
					(size 1.27 1.27)
				)
				(justify mirror)
			)
		)
		(property "Value" ""
			(at 0 0 90)
			(layer "B.Fab")
			(effects
				(font
					(size 1.27 1.27)
				)
				(justify mirror)
			)
		)
		(duplicate_pad_numbers_are_jumpers no)
		(fp_rect
			(start -0.2794 -0.1016)
			(end 0.2794 0.9906)
			(stroke
				(width 0)
				(type default)
			)
			(fill no)
			(layer "B.CrtYd")
		)
		(fp_line
			(start 0.2794 -0.1016)
			(end 0.2794 0.9906)
			(stroke
				(width 0.1)
				(type default)
			)
			(layer "B.Fab")
		)
		(fp_line
			(start -0.2794 -0.1016)
			(end 0.2794 -0.1016)
			(stroke
				(width 0.1)
				(type default)
			)
			(layer "B.Fab")
		)
		(fp_line
			(start 0.2794 0.9906)
			(end -0.2794 0.9906)
			(stroke
				(width 0.1)
				(type default)
			)
			(layer "B.Fab")
		)
		(fp_line
			(start -0.2794 0.9906)
			(end -0.2794 -0.1016)
			(stroke
				(width 0.1)
				(type default)
			)
			(layer "B.Fab")
		)
		(pad "1" smd rect
			(at 0 0 270)
			(size 0.508 0.508)
			(layers "B.Cu" "B.Mask" "B.Paste")
			(net "GND")
		)
		(pad "2" smd rect
			(at 0 0.889 270)
			(size 0.508 0.508)
			(layers "B.Cu" "B.Mask" "B.Paste")
			(net "PD_CPU0_MCP01_DMON")
		)
		(zone
			(layer "B.Cu")
			(hatch none 0.5)
			(connect_pads
				(clearance 0)
			)
			(min_thickness 0.25)
			(keepout
				(tracks allowed)
				(vias not_allowed)
				(pads allowed)
				(copperpour not_allowed)
				(footprints allowed)
			)
			(placement
				(enabled no)
				(sheetname "")
			)
			(fill
				(thermal_gap 0.5)
				(thermal_bridge_width 0.5)
				(island_removal_mode 0)
			)
			(polygon
				(pts
					(xy 281.6352 -76.2254) (xy 282.0162 -76.2254) (xy 282.0162 -76.7334) (xy 281.6352 -76.7334)
				)
			)
		)
		(zone
			(layer "B.Cu")
			(hatch none 0.5)
			(connect_pads
				(clearance 0)
			)
			(min_thickness 0.25)
			(keepout
				(tracks not_allowed)
				(vias allowed)
				(pads allowed)
				(copperpour not_allowed)
				(footprints allowed)
			)
			(placement
				(enabled no)
				(sheetname "")
			)
			(fill
				(thermal_gap 0.5)
				(thermal_bridge_width 0.5)
				(island_removal_mode 0)
			)
			(polygon
				(pts
					(xy 281.6352 -76.2254) (xy 282.0162 -76.2254) (xy 282.0162 -76.7334) (xy 281.6352 -76.7334)
				)
			)
		)
	)
	(footprint ""
		(layer "B.Cu")
		(at 115.353592 -77.366114)
		(property "Reference" "C7P12"
			(at 0 0 0)
			(layer "B.SilkS")
			(hide yes)
			(effects
				(font
					(size 1.27 1.27)
				)
				(justify mirror)
			)
		)
		(property "Value" ""
			(at 0 0 0)
			(layer "B.Fab")
			(effects
				(font
					(size 1.27 1.27)
				)
				(justify mirror)
			)
		)
		(duplicate_pad_numbers_are_jumpers no)
		(fp_poly
			(pts
				(xy 0.4953 -0.2032) (xy -0.4953 -0.2032) (xy -0.4953 1.6002) (xy 0.4953 1.6002)
			)
			(stroke
				(width 0)
				(type default)
			)
			(fill no)
			(layer "B.CrtYd")
		)
		(fp_line
			(start -0.4953 -0.2032)
			(end -0.4953 1.6002)
			(stroke
				(width 0.1)
				(type default)
			)
			(layer "B.Fab")
		)
		(fp_line
			(start -0.4953 1.6002)
			(end 0.4953 1.6002)
			(stroke
				(width 0.1)
				(type default)
			)
			(layer "B.Fab")
		)
		(fp_line
			(start 0.4953 -0.2032)
			(end -0.4953 -0.2032)
			(stroke
				(width 0.1)
				(type default)
			)
			(layer "B.Fab")
		)
		(fp_line
			(start 0.4953 1.6002)
			(end 0.4953 -0.2032)
			(stroke
				(width 0.1)
				(type default)
			)
			(layer "B.Fab")
		)
		(pad "1" smd rect
			(at 0 0 180)
			(size 0.762 0.889)
			(layers "B.Cu" "B.Mask" "B.Paste")
			(net "PVCCIO_CPU1")
		)
		(pad "2" smd rect
			(at 0 1.397 180)
			(size 0.762 0.889)
			(layers "B.Cu" "B.Mask" "B.Paste")
			(net "GND")
		)
		(zone
			(layer "B.Cu")
			(hatch none 0.5)
			(connect_pads
				(clearance 0)
			)
			(min_thickness 0.25)
			(keepout
				(tracks not_allowed)
				(vias allowed)
				(pads allowed)
				(copperpour not_allowed)
				(footprints allowed)
			)
			(placement
				(enabled no)
				(sheetname "")
			)
			(fill
				(thermal_gap 0.5)
				(thermal_bridge_width 0.5)
				(island_removal_mode 0)
			)
			(polygon
				(pts
					(xy 115.734592 -76.921614) (xy 114.972592 -76.921614) (xy 114.972592 -76.413614) (xy 115.734592 -76.413614)
				)
			)
		)
	)
	(footprint ""
		(layer "B.Cu")
		(at 442.0362 -24.2824)
		(property "Reference" "C25W16"
			(at 0.8382 -0.67818 0)
			(unlocked yes)
			(layer "B.SilkS")
			(effects
				(font
					(size 0.4064 0.254)
					(thickness 0.1524)
				)
				(justify left mirror)
			)
		)
		(property "Value" ""
			(at 0 0 0)
			(layer "B.Fab")
			(effects
				(font
					(size 1.27 1.27)
				)
				(justify mirror)
			)
		)
		(duplicate_pad_numbers_are_jumpers no)
		(fp_poly
			(pts
				(xy -0.3048 -0.1016) (xy -0.3048 0.9906) (xy 0.3048 0.9906) (xy 0.3048 -0.1016)
			)
			(stroke
				(width 0)
				(type default)
			)
			(fill no)
			(layer "B.CrtYd")
		)
		(fp_line
			(start -0.3048 -0.1016)
			(end 0.3048 -0.1016)
			(stroke
				(width 0.1)
				(type default)
			)
			(layer "B.Fab")
		)
		(fp_line
			(start -0.3048 0.9906)
			(end -0.3048 -0.1016)
			(stroke
				(width 0.1)
				(type default)
			)
			(layer "B.Fab")
		)
		(fp_line
			(start 0.3048 -0.1016)
			(end 0.3048 0.9906)
			(stroke
				(width 0.1)
				(type default)
			)
			(layer "B.Fab")
		)
		(fp_line
			(start 0.3048 0.9906)
			(end -0.3048 0.9906)
			(stroke
				(width 0.1)
				(type default)
			)
			(layer "B.Fab")
		)
		(pad "1" smd rect
			(at 0 0 180)
			(size 0.508 0.508)
			(layers "B.Cu" "B.Mask" "B.Paste")
			(net "P1V2_AUX_BMC")
		)
		(pad "2" smd rect
			(at 0 0.889 180)
			(size 0.508 0.508)
			(layers "B.Cu" "B.Mask" "B.Paste")
			(net "GND")
		)
		(zone
			(layer "B.Cu")
			(hatch none 0.5)
			(connect_pads
				(clearance 0)
			)
			(min_thickness 0.25)
			(keepout
				(tracks allowed)
				(vias not_allowed)
				(pads allowed)
				(copperpour not_allowed)
				(footprints allowed)
			)
			(placement
				(enabled no)
				(sheetname "")
			)
			(fill
				(thermal_gap 0.5)
				(thermal_bridge_width 0.5)
				(island_removal_mode 0)
			)
			(polygon
				(pts
					(xy 442.2902 -24.0284) (xy 441.7822 -24.0284) (xy 441.7822 -23.6474) (xy 442.2902 -23.6474)
				)
			)
		)
		(zone
			(layer "B.Cu")
			(hatch none 0.5)
			(connect_pads
				(clearance 0)
			)
			(min_thickness 0.25)
			(keepout
				(tracks not_allowed)
				(vias allowed)
				(pads allowed)
				(copperpour not_allowed)
				(footprints allowed)
			)
			(placement
				(enabled no)
				(sheetname "")
			)
			(fill
				(thermal_gap 0.5)
				(thermal_bridge_width 0.5)
				(island_removal_mode 0)
			)
			(polygon
				(pts
					(xy 442.2902 -23.6474) (xy 441.7822 -23.6474) (xy 441.7822 -24.0284) (xy 442.2902 -24.0284)
				)
			)
		)
	)
	(footprint ""
		(layer "B.Cu")
		(at 17.83842 -102.45852 90)
		(property "Reference" "C9N9"
			(at 0 0 90)
			(layer "B.SilkS")
			(hide yes)
			(effects
				(font
					(size 1.27 1.27)
				)
				(justify mirror)
			)
		)
		(property "Value" ""
			(at 0 0 90)
			(layer "B.Fab")
			(effects
				(font
					(size 1.27 1.27)
				)
				(justify mirror)
			)
		)
		(duplicate_pad_numbers_are_jumpers no)
		(fp_poly
			(pts
				(xy -0.3048 -0.1016) (xy -0.3048 0.9906) (xy 0.3048 0.9906) (xy 0.3048 -0.1016)
			)
			(stroke
				(width 0)
				(type default)
			)
			(fill no)
			(layer "B.CrtYd")
		)
		(fp_line
			(start 0.3048 -0.1016)
			(end 0.3048 0.9906)
			(stroke
				(width 0.1)
				(type default)
			)
			(layer "B.Fab")
		)
		(fp_line
			(start -0.3048 -0.1016)
			(end 0.3048 -0.1016)
			(stroke
				(width 0.1)
				(type default)
			)
			(layer "B.Fab")
		)
		(fp_line
			(start 0.3048 0.9906)
			(end -0.3048 0.9906)
			(stroke
				(width 0.1)
				(type default)
			)
			(layer "B.Fab")
		)
		(fp_line
			(start -0.3048 0.9906)
			(end -0.3048 -0.1016)
			(stroke
				(width 0.1)
				(type default)
			)
			(layer "B.Fab")
		)
		(pad "1" smd rect
			(at 0 0 270)
			(size 0.508 0.508)
			(layers "B.Cu" "B.Mask" "B.Paste")
			(net "P3E_CPU1_PE3_MP_C_TXN<15>")
		)
		(pad "2" smd rect
			(at 0 0.889 270)
			(size 0.508 0.508)
			(layers "B.Cu" "B.Mask" "B.Paste")
			(net "P3E_CPU1_PE3_MP_TXN<15>")
		)
		(zone
			(layer "B.Cu")
			(hatch none 0.5)
			(connect_pads
				(clearance 0)
			)
			(min_thickness 0.25)
			(keepout
				(tracks allowed)
				(vias not_allowed)
				(pads allowed)
				(copperpour not_allowed)
				(footprints allowed)
			)
			(placement
				(enabled no)
				(sheetname "")
			)
			(fill
				(thermal_gap 0.5)
				(thermal_bridge_width 0.5)
				(island_removal_mode 0)
			)
			(polygon
				(pts
					(xy 18.09242 -102.71252) (xy 18.09242 -102.20452) (xy 18.47342 -102.20452) (xy 18.47342 -102.71252)
				)
			)
		)
		(zone
			(layer "B.Cu")
			(hatch none 0.5)
			(connect_pads
				(clearance 0)
			)
			(min_thickness 0.25)
			(keepout
				(tracks not_allowed)
				(vias allowed)
				(pads allowed)
				(copperpour not_allowed)
				(footprints allowed)
			)
			(placement
				(enabled no)
				(sheetname "")
			)
			(fill
				(thermal_gap 0.5)
				(thermal_bridge_width 0.5)
				(island_removal_mode 0)
			)
			(polygon
				(pts
					(xy 18.47342 -102.71252) (xy 18.47342 -102.20452) (xy 18.09242 -102.20452) (xy 18.09242 -102.71252)
				)
			)
		)
	)
	(footprint ""
		(layer "B.Cu")
		(at 403.344634 -79.235808 90)
		(property "Reference" "R6W28"
			(at 0.8382 -0.67818 90)
			(unlocked yes)
			(layer "B.SilkS")
			(effects
				(font
					(size 0.4064 0.254)
					(thickness 0.1524)
				)
				(justify left mirror)
			)
		)
		(property "Value" ""
			(at 0 0 90)
			(layer "B.Fab")
			(effects
				(font
					(size 1.27 1.27)
				)
				(justify mirror)
			)
		)
		(duplicate_pad_numbers_are_jumpers no)
		(fp_poly
			(pts
				(xy 0.2794 -0.1016) (xy -0.2794 -0.1016) (xy -0.2794 0.9906) (xy 0.2794 0.9906)
			)
			(stroke
				(width 0)
				(type default)
			)
			(fill no)
			(layer "B.CrtYd")
		)
		(fp_line
			(start 0.2794 -0.1016)
			(end 0.2794 0.9906)
			(stroke
				(width 0.1)
				(type default)
			)
			(layer "B.Fab")
		)
		(fp_line
			(start -0.2794 -0.1016)
			(end 0.2794 -0.1016)
			(stroke
				(width 0.1)
				(type default)
			)
			(layer "B.Fab")
		)
		(fp_line
			(start 0.2794 0.9906)
			(end -0.2794 0.9906)
			(stroke
				(width 0.1)
				(type default)
			)
			(layer "B.Fab")
		)
		(fp_line
			(start -0.2794 0.9906)
			(end -0.2794 -0.1016)
			(stroke
				(width 0.1)
				(type default)
			)
			(layer "B.Fab")
		)
		(pad "1" smd rect
			(at 0 0 270)
			(size 0.508 0.508)
			(layers "B.Cu" "B.Mask" "B.Paste")
			(net "P3V3_STBY")
		)
		(pad "2" smd rect
			(at 0 0.889 270)
			(size 0.508 0.508)
			(layers "B.Cu" "B.Mask" "B.Paste")
			(net "HSC_SMBUS_SWITCH_EN")
		)
		(zone
			(layer "B.Cu")
			(hatch none 0.5)
			(connect_pads
				(clearance 0)
			)
			(min_thickness 0.25)
			(keepout
				(tracks allowed)
				(vias not_allowed)
				(pads allowed)
				(copperpour not_allowed)
				(footprints allowed)
			)
			(placement
				(enabled no)
				(sheetname "")
			)
			(fill
				(thermal_gap 0.5)
				(thermal_bridge_width 0.5)
				(island_removal_mode 0)
			)
			(polygon
				(pts
					(xy 403.598634 -79.489808) (xy 403.598634 -78.981808) (xy 403.979634 -78.981808) (xy 403.979634 -79.489808)
				)
			)
		)
		(zone
			(layer "B.Cu")
			(hatch none 0.5)
			(connect_pads
				(clearance 0)
			)
			(min_thickness 0.25)
			(keepout
				(tracks not_allowed)
				(vias allowed)
				(pads allowed)
				(copperpour not_allowed)
				(footprints allowed)
			)
			(placement
				(enabled no)
				(sheetname "")
			)
			(fill
				(thermal_gap 0.5)
				(thermal_bridge_width 0.5)
				(island_removal_mode 0)
			)
			(polygon
				(pts
					(xy 403.979634 -79.489808) (xy 403.979634 -78.981808) (xy 403.598634 -78.981808) (xy 403.598634 -79.489808)
				)
			)
		)
	)
	(footprint ""
		(layer "B.Cu")
		(at 347.5736 -7.1628 -90)
		(property "Reference" "C3U2"
			(at 0 0 90)
			(layer "B.SilkS")
			(hide yes)
			(effects
				(font
					(size 1.27 1.27)
				)
				(justify mirror)
			)
		)
		(property "Value" ""
			(at 0 0 90)
			(layer "B.Fab")
			(effects
				(font
					(size 1.27 1.27)
				)
				(justify mirror)
			)
		)
		(duplicate_pad_numbers_are_jumpers no)
		(fp_rect
			(start 0.7239 1.9939)
			(end -0.7239 -0.2159)
			(stroke
				(width 0)
				(type default)
			)
			(fill no)
			(layer "B.CrtYd")
		)
		(fp_line
			(start -0.7239 1.9939)
			(end -0.7239 -0.2159)
			(stroke
				(width 0.1)
				(type default)
			)
			(layer "B.Fab")
		)
		(fp_line
			(start 0.7239 1.9939)
			(end -0.7239 1.9939)
			(stroke
				(width 0.1)
				(type default)
			)
			(layer "B.Fab")
		)
		(fp_line
			(start -0.7239 -0.2159)
			(end 0.7239 -0.2159)
			(stroke
				(width 0.1)
				(type default)
			)
			(layer "B.Fab")
		)
		(fp_line
			(start 0.7239 -0.2159)
			(end 0.7239 1.9939)
			(stroke
				(width 0.1)
				(type default)
			)
			(layer "B.Fab")
		)
		(pad "1" smd rect
			(at 0 0 90)
			(size 1.27 1.016)
			(layers "B.Cu" "B.Mask" "B.Paste")
			(net "VR_FET_SW_P12V_STBY_PVDDQ_ABC")
		)
		(pad "2" smd rect
			(at 0 1.778 90)
			(size 1.27 1.016)
			(layers "B.Cu" "B.Mask" "B.Paste")
			(net "GND")
		)
		(zone
			(layer "B.Cu")
			(hatch none 0.5)
			(connect_pads
				(clearance 0)
			)
			(min_thickness 0.25)
			(keepout
				(tracks not_allowed)
				(vias allowed)
				(pads allowed)
				(copperpour not_allowed)
				(footprints allowed)
			)
			(placement
				(enabled no)
				(sheetname "")
			)
			(fill
				(thermal_gap 0.5)
				(thermal_bridge_width 0.5)
				(island_removal_mode 0)
			)
			(polygon
				(pts
					(xy 346.3036 -6.5278) (xy 347.0656 -6.5278) (xy 347.0656 -7.7978) (xy 346.3036 -7.7978)
				)
			)
		)
	)
	(footprint ""
		(layer "B.Cu")
		(at 420.3065 -79.9465)
		(property "Reference" "Q2P1"
			(at -1.27508 3.76555 180)
			(unlocked yes)
			(layer "B.SilkS")
			(effects
				(font
					(size 0.7874 0.5842)
					(thickness 0.1524)
				)
				(justify left mirror)
			)
		)
		(property "Value" ""
			(at 0 0 0)
			(layer "B.Fab")
			(effects
				(font
					(size 1.27 1.27)
				)
				(justify mirror)
			)
		)
		(duplicate_pad_numbers_are_jumpers no)
		(fp_line
			(start -1.778 -0.5715)
			(end -1.778 0.3175)
			(stroke
				(width 0.1524)
				(type default)
			)
			(layer "B.SilkS")
		)
		(fp_line
			(start -1.778 2.4765)
			(end -1.778 1.5875)
			(stroke
				(width 0.1524)
				(type default)
			)
			(layer "B.SilkS")
		)
		(fp_line
			(start -0.9525 -0.5715)
			(end -1.778 -0.5715)
			(stroke
				(width 0.1524)
				(type default)
			)
			(layer "B.SilkS")
		)
		(fp_line
			(start -0.9525 2.4765)
			(end -1.778 2.4765)
			(stroke
				(width 0.1524)
				(type default)
			)
			(layer "B.SilkS")
		)
		(fp_line
			(start -0.381 0.635)
			(end -0.381 1.27)
			(stroke
				(width 0.1524)
				(type default)
			)
			(layer "B.SilkS")
		)
		(fp_circle
			(center 0.52197 -0.800608)
			(end 0.64897 -0.800608)
			(stroke
				(width 0.254)
				(type default)
			)
			(fill no)
			(layer "B.SilkS")
		)
		(fp_poly
			(pts
				(xy -1.778 2.4765) (xy -0.381 2.4765) (xy -0.381 -0.5715) (xy -1.778 -0.5715)
			)
			(stroke
				(width 0)
				(type default)
			)
			(fill no)
			(layer "B.CrtYd")
		)
		(fp_line
			(start -1.778 -0.5715)
			(end -0.381 -0.5715)
			(stroke
				(width 0.1)
				(type default)
			)
			(layer "B.Fab")
		)
		(fp_line
			(start -1.778 2.4765)
			(end -1.778 -0.5715)
			(stroke
				(width 0.1)
				(type default)
			)
			(layer "B.Fab")
		)
		(fp_line
			(start -0.381 -0.5715)
			(end -0.381 2.4765)
			(stroke
				(width 0.1)
				(type default)
			)
			(layer "B.Fab")
		)
		(fp_line
			(start -0.381 2.4765)
			(end -1.778 2.4765)
			(stroke
				(width 0.1)
				(type default)
			)
			(layer "B.Fab")
		)
		(fp_circle
			(center 0.9525 -0.9271)
			(end 1.0795 -0.9271)
			(stroke
				(width 0.254)
				(type default)
			)
			(fill no)
			(layer "B.Fab")
		)
		(pad "1" smd rect
			(at 0 0 180)
			(size 1.143 0.508)
			(layers "B.Cu" "B.Mask" "B.Paste")
			(net "FM_PMBUS_ALERT_BUF_EN_N")
		)
		(pad "2" smd rect
			(at 0 1.905 180)
			(size 1.143 0.508)
			(layers "B.Cu" "B.Mask" "B.Paste")
			(net "GND")
		)
		(pad "3" smd rect
			(at -2.159 0.9525 180)
			(size 1.143 0.508)
			(layers "B.Cu" "B.Mask" "B.Paste")
			(net "FM_PMBUS_ALERT_BUF_EN")
		)
	)
	(footprint ""
		(layer "B.Cu")
		(at 229.23881 -164.911786 90)
		(property "Reference" "T1D24"
			(at 0 0 90)
			(layer "B.SilkS")
			(hide yes)
			(effects
				(font
					(size 1.27 1.27)
				)
				(justify mirror)
			)
		)
		(property "Value" "*"
			(at 3.4036 -4.46405 90)
			(unlocked yes)
			(layer "B.Fab")
			(hide yes)
			(effects
				(font
					(size 0.889 0.889)
					(thickness 0.1524)
				)
				(justify mirror)
			)
		)
		(property "Device Type" "TEST-PAD-12P-1-GP-U_DISCRET-GBA"
			(at 3.4036 -5.98805 90)
			(unlocked yes)
			(layer "B.Fab")
			(hide yes)
			(effects
				(font
					(size 0.889 0.889)
					(thickness 0.1524)
				)
				(justify mirror)
			)
		)
		(duplicate_pad_numbers_are_jumpers no)
		(fp_line
			(start 2.3876 -4.826)
			(end -2.3622 -4.826)
			(stroke
				(width 0.1524)
				(type default)
			)
			(layer "B.SilkS")
		)
		(fp_line
			(start -2.3622 -4.826)
			(end -2.3622 3.4798)
			(stroke
				(width 0.1524)
				(type default)
			)
			(layer "B.SilkS")
		)
		(fp_line
			(start 2.3876 3.4798)
			(end 2.3876 -4.826)
			(stroke
				(width 0.1524)
				(type default)
			)
			(layer "B.SilkS")
		)
		(fp_line
			(start -2.3622 3.4798)
			(end 2.3876 3.4798)
			(stroke
				(width 0.1524)
				(type default)
			)
			(layer "B.SilkS")
		)
		(fp_rect
			(start 2.6416 3.7338)
			(end -2.6162 -5.08)
			(stroke
				(width 0)
				(type default)
			)
			(fill no)
			(layer "B.CrtYd")
		)
		(fp_rect
			(start 2.6416 3.7338)
			(end -2.6162 -5.08)
			(stroke
				(width 0)
				(type default)
			)
			(fill no)
			(layer "B.Fab")
		)
		(pad "1" smd circle
			(at -0.496824 -1.301496 270)
			(size 0.6604 0.6604)
			(layers "B.Cu" "B.Mask" "B.Paste")
			(net "L14_85OHM_10INCH_DN")
		)
		(pad "2" smd circle
			(at 0.503936 -1.301496 270)
			(size 0.6604 0.6604)
			(layers "B.Cu" "B.Mask" "B.Paste")
			(net "L14_85OHM_10INCH_DP")
		)
		(pad "3" smd custom
			(at 0.00889 0.370078 270)
			(size 0.74295 0.74295)
			(layers "B.Cu" "B.Mask" "B.Paste")
			(net "GND")
			(options
				(clearance outline)
				(anchor circle)
			)
			(primitives
				(gr_poly
					(pts
						(xy -2.1209 -1.4859) (xy 2.1209 -1.4859) (xy 2.1209 1.4859) (xy 1.08585 1.4859) (xy 1.08585 0.4699)
						(xy -1.08585 0.4699) (xy -1.08585 1.4859) (xy -2.1209 1.4859)
					)
					(width 0)
					(fill yes)
				)
			)
		)
		(pad "4" thru_hole circle
			(at -1.266444 -3.851656 270)
			(size 1.4478 1.4478)
			(drill 1.0414)
			(layers "*.Cu" "*.Mask")
			(remove_unused_layers no)
			(net "GND")
			(clearance 0.1524)
			(thermal_gap 0.1524)
		)
		(pad "5" thru_hole circle
			(at 1.273556 -3.851656 270)
			(size 1.4478 1.4478)
			(drill 1.0414)
			(layers "*.Cu" "*.Mask")
			(remove_unused_layers no)
			(net "GND")
			(clearance 0.1524)
			(thermal_gap 0.1524)
		)
		(pad "6" thru_hole circle
			(at -1.266444 2.498344 270)
			(size 1.4478 1.4478)
			(drill 1.0414)
			(layers "*.Cu" "*.Mask")
			(remove_unused_layers no)
			(net "GND")
			(clearance 0.1524)
			(thermal_gap 0.1524)
		)
		(pad "7" thru_hole circle
			(at 1.273556 2.498344 270)
			(size 1.4478 1.4478)
			(drill 1.0414)
			(layers "*.Cu" "*.Mask")
			(remove_unused_layers no)
			(net "GND")
			(clearance 0.1524)
			(thermal_gap 0.1524)
		)
		(pad "8" thru_hole circle
			(at -1.27 -0.4572 270)
			(size 0.7112 0.7112)
			(drill 0.4064)
			(layers "*.Cu" "*.Mask")
			(remove_unused_layers no)
			(net "GND")
			(clearance 0.1016)
			(thermal_gap 0.1016)
		)
		(pad "9" thru_hole circle
			(at -1.27 0.762 270)
			(size 0.7112 0.7112)
			(drill 0.4064)
			(layers "*.Cu" "*.Mask")
			(remove_unused_layers no)
			(net "GND")
			(clearance 0.1016)
			(thermal_gap 0.1016)
		)
		(pad "10" thru_hole circle
			(at 0.0254 0.762 270)
			(size 0.7112 0.7112)
			(drill 0.4064)
			(layers "*.Cu" "*.Mask")
			(remove_unused_layers no)
			(net "GND")
			(clearance 0.1016)
			(thermal_gap 0.1016)
		)
		(pad "11" thru_hole circle
			(at 1.27 0.762 270)
			(size 0.7112 0.7112)
			(drill 0.4064)
			(layers "*.Cu" "*.Mask")
			(remove_unused_layers no)
			(net "GND")
			(clearance 0.1016)
			(thermal_gap 0.1016)
		)
		(pad "12" thru_hole circle
			(at 1.27 -0.4572 270)
			(size 0.7112 0.7112)
			(drill 0.4064)
			(layers "*.Cu" "*.Mask")
			(remove_unused_layers no)
			(net "GND")
			(clearance 0.1016)
			(thermal_gap 0.1016)
		)
	)
	(footprint ""
		(layer "B.Cu")
		(at 393.446 -18.9103 180)
		(property "Reference" "R32W1"
			(at 0.8382 -0.67818 180)
			(unlocked yes)
			(layer "B.SilkS")
			(effects
				(font
					(size 0.4064 0.254)
					(thickness 0.1524)
				)
				(justify left mirror)
			)
		)
		(property "Value" ""
			(at 0 0 0)
			(layer "B.Fab")
			(effects
				(font
					(size 1.27 1.27)
				)
				(justify mirror)
			)
		)
		(duplicate_pad_numbers_are_jumpers no)
		(fp_poly
			(pts
				(xy 0.2794 -0.1016) (xy -0.2794 -0.1016) (xy -0.2794 0.9906) (xy 0.2794 0.9906)
			)
			(stroke
				(width 0)
				(type default)
			)
			(fill no)
			(layer "B.CrtYd")
		)
		(fp_line
			(start 0.2794 0.9906)
			(end -0.2794 0.9906)
			(stroke
				(width 0.1)
				(type default)
			)
			(layer "B.Fab")
		)
		(fp_line
			(start 0.2794 -0.1016)
			(end 0.2794 0.9906)
			(stroke
				(width 0.1)
				(type default)
			)
			(layer "B.Fab")
		)
		(fp_line
			(start -0.2794 0.9906)
			(end -0.2794 -0.1016)
			(stroke
				(width 0.1)
				(type default)
			)
			(layer "B.Fab")
		)
		(fp_line
			(start -0.2794 -0.1016)
			(end 0.2794 -0.1016)
			(stroke
				(width 0.1)
				(type default)
			)
			(layer "B.Fab")
		)
		(pad "1" smd rect
			(at 0 0)
			(size 0.508 0.508)
			(layers "B.Cu" "B.Mask" "B.Paste")
			(net "P3V3")
		)
		(pad "2" smd rect
			(at 0 0.889)
			(size 0.508 0.508)
			(layers "B.Cu" "B.Mask" "B.Paste")
			(net "P1V8_M2")
		)
		(zone
			(layer "B.Cu")
			(hatch none 0.5)
			(connect_pads
				(clearance 0)
			)
			(min_thickness 0.25)
			(keepout
				(tracks not_allowed)
				(vias allowed)
				(pads allowed)
				(copperpour not_allowed)
				(footprints allowed)
			)
			(placement
				(enabled no)
				(sheetname "")
			)
			(fill
				(thermal_gap 0.5)
				(thermal_bridge_width 0.5)
				(island_removal_mode 0)
			)
			(polygon
				(pts
					(xy 393.192 -19.5453) (xy 393.7 -19.5453) (xy 393.7 -19.1643) (xy 393.192 -19.1643)
				)
			)
		)
		(zone
			(layer "B.Cu")
			(hatch none 0.5)
			(connect_pads
				(clearance 0)
			)
			(min_thickness 0.25)
			(keepout
				(tracks allowed)
				(vias not_allowed)
				(pads allowed)
				(copperpour not_allowed)
				(footprints allowed)
			)
			(placement
				(enabled no)
				(sheetname "")
			)
			(fill
				(thermal_gap 0.5)
				(thermal_bridge_width 0.5)
				(island_removal_mode 0)
			)
			(polygon
				(pts
					(xy 393.192 -19.1643) (xy 393.7 -19.1643) (xy 393.7 -19.5453) (xy 393.192 -19.5453)
				)
			)
		)
	)
	(footprint ""
		(layer "B.Cu")
		(at 457.8096 -142.9004)
		(property "Reference" "R1L28"
			(at 0 0 0)
			(layer "B.SilkS")
			(hide yes)
			(effects
				(font
					(size 1.27 1.27)
				)
				(justify mirror)
			)
		)
		(property "Value" ""
			(at 0 0 0)
			(layer "B.Fab")
			(effects
				(font
					(size 1.27 1.27)
				)
				(justify mirror)
			)
		)
		(duplicate_pad_numbers_are_jumpers no)
		(fp_poly
			(pts
				(xy 0.2794 -0.1016) (xy -0.2794 -0.1016) (xy -0.2794 0.9906) (xy 0.2794 0.9906)
			)
			(stroke
				(width 0)
				(type default)
			)
			(fill no)
			(layer "B.CrtYd")
		)
		(fp_line
			(start -0.2794 -0.1016)
			(end 0.2794 -0.1016)
			(stroke
				(width 0.1)
				(type default)
			)
			(layer "B.Fab")
		)
		(fp_line
			(start -0.2794 0.9906)
			(end -0.2794 -0.1016)
			(stroke
				(width 0.1)
				(type default)
			)
			(layer "B.Fab")
		)
		(fp_line
			(start 0.2794 -0.1016)
			(end 0.2794 0.9906)
			(stroke
				(width 0.1)
				(type default)
			)
			(layer "B.Fab")
		)
		(fp_line
			(start 0.2794 0.9906)
			(end -0.2794 0.9906)
			(stroke
				(width 0.1)
				(type default)
			)
			(layer "B.Fab")
		)
		(pad "1" smd rect
			(at 0 0 180)
			(size 0.508 0.508)
			(layers "B.Cu" "B.Mask" "B.Paste")
			(net "P3V3_STBY")
		)
		(pad "2" smd rect
			(at 0 0.889 180)
			(size 0.508 0.508)
			(layers "B.Cu" "B.Mask" "B.Paste")
			(net "FM_DEBUG_RST_BTN_R1_N")
		)
		(zone
			(layer "B.Cu")
			(hatch none 0.5)
			(connect_pads
				(clearance 0)
			)
			(min_thickness 0.25)
			(keepout
				(tracks allowed)
				(vias not_allowed)
				(pads allowed)
				(copperpour not_allowed)
				(footprints allowed)
			)
			(placement
				(enabled no)
				(sheetname "")
			)
			(fill
				(thermal_gap 0.5)
				(thermal_bridge_width 0.5)
				(island_removal_mode 0)
			)
			(polygon
				(pts
					(xy 458.0636 -142.6464) (xy 457.5556 -142.6464) (xy 457.5556 -142.2654) (xy 458.0636 -142.2654)
				)
			)
		)
		(zone
			(layer "B.Cu")
			(hatch none 0.5)
			(connect_pads
				(clearance 0)
			)
			(min_thickness 0.25)
			(keepout
				(tracks not_allowed)
				(vias allowed)
				(pads allowed)
				(copperpour not_allowed)
				(footprints allowed)
			)
			(placement
				(enabled no)
				(sheetname "")
			)
			(fill
				(thermal_gap 0.5)
				(thermal_bridge_width 0.5)
				(island_removal_mode 0)
			)
			(polygon
				(pts
					(xy 458.0636 -142.2654) (xy 457.5556 -142.2654) (xy 457.5556 -142.6464) (xy 458.0636 -142.6464)
				)
			)
		)
	)
	(footprint ""
		(layer "B.Cu")
		(at 403.8854 3.3782 -90)
		(property "Reference" "R2U44"
			(at 0 0 90)
			(layer "B.SilkS")
			(hide yes)
			(effects
				(font
					(size 1.27 1.27)
				)
				(justify mirror)
			)
		)
		(property "Value" ""
			(at 0 0 90)
			(layer "B.Fab")
			(effects
				(font
					(size 1.27 1.27)
				)
				(justify mirror)
			)
		)
		(duplicate_pad_numbers_are_jumpers no)
		(fp_poly
			(pts
				(xy 0.2794 -0.1016) (xy -0.2794 -0.1016) (xy -0.2794 0.9906) (xy 0.2794 0.9906)
			)
			(stroke
				(width 0)
				(type default)
			)
			(fill no)
			(layer "B.CrtYd")
		)
		(fp_line
			(start -0.2794 0.9906)
			(end -0.2794 -0.1016)
			(stroke
				(width 0.1)
				(type default)
			)
			(layer "B.Fab")
		)
		(fp_line
			(start 0.2794 0.9906)
			(end -0.2794 0.9906)
			(stroke
				(width 0.1)
				(type default)
			)
			(layer "B.Fab")
		)
		(fp_line
			(start -0.2794 -0.1016)
			(end 0.2794 -0.1016)
			(stroke
				(width 0.1)
				(type default)
			)
			(layer "B.Fab")
		)
		(fp_line
			(start 0.2794 -0.1016)
			(end 0.2794 0.9906)
			(stroke
				(width 0.1)
				(type default)
			)
			(layer "B.Fab")
		)
		(pad "1" smd rect
			(at 0 0 90)
			(size 0.508 0.508)
			(layers "B.Cu" "B.Mask" "B.Paste")
			(net "FAN_PWM_OUT_SYS1_BUF")
		)
		(pad "2" smd rect
			(at 0 0.889 90)
			(size 0.508 0.508)
			(layers "B.Cu" "B.Mask" "B.Paste")
			(net "FAN_PWM_OUT_SYS1_R")
		)
		(zone
			(layer "B.Cu")
			(hatch none 0.5)
			(connect_pads
				(clearance 0)
			)
			(min_thickness 0.25)
			(keepout
				(tracks not_allowed)
				(vias allowed)
				(pads allowed)
				(copperpour not_allowed)
				(footprints allowed)
			)
			(placement
				(enabled no)
				(sheetname "")
			)
			(fill
				(thermal_gap 0.5)
				(thermal_bridge_width 0.5)
				(island_removal_mode 0)
			)
			(polygon
				(pts
					(xy 403.2504 3.6322) (xy 403.2504 3.1242) (xy 403.6314 3.1242) (xy 403.6314 3.6322)
				)
			)
		)
		(zone
			(layer "B.Cu")
			(hatch none 0.5)
			(connect_pads
				(clearance 0)
			)
			(min_thickness 0.25)
			(keepout
				(tracks allowed)
				(vias not_allowed)
				(pads allowed)
				(copperpour not_allowed)
				(footprints allowed)
			)
			(placement
				(enabled no)
				(sheetname "")
			)
			(fill
				(thermal_gap 0.5)
				(thermal_bridge_width 0.5)
				(island_removal_mode 0)
			)
			(polygon
				(pts
					(xy 403.6314 3.6322) (xy 403.6314 3.1242) (xy 403.2504 3.1242) (xy 403.2504 3.6322)
				)
			)
		)
	)
	(footprint ""
		(layer "B.Cu")
		(at 421.66032 -73.962514)
		(property "Reference" "C1R28"
			(at 0 0 0)
			(layer "B.SilkS")
			(hide yes)
			(effects
				(font
					(size 1.27 1.27)
				)
				(justify mirror)
			)
		)
		(property "Value" ""
			(at 0 0 0)
			(layer "B.Fab")
			(effects
				(font
					(size 1.27 1.27)
				)
				(justify mirror)
			)
		)
		(duplicate_pad_numbers_are_jumpers no)
		(fp_poly
			(pts
				(xy -0.3048 -0.1016) (xy -0.3048 0.9906) (xy 0.3048 0.9906) (xy 0.3048 -0.1016)
			)
			(stroke
				(width 0)
				(type default)
			)
			(fill no)
			(layer "B.CrtYd")
		)
		(fp_line
			(start -0.3048 -0.1016)
			(end 0.3048 -0.1016)
			(stroke
				(width 0.1)
				(type default)
			)
			(layer "B.Fab")
		)
		(fp_line
			(start -0.3048 0.9906)
			(end -0.3048 -0.1016)
			(stroke
				(width 0.1)
				(type default)
			)
			(layer "B.Fab")
		)
		(fp_line
			(start 0.3048 -0.1016)
			(end 0.3048 0.9906)
			(stroke
				(width 0.1)
				(type default)
			)
			(layer "B.Fab")
		)
		(fp_line
			(start 0.3048 0.9906)
			(end -0.3048 0.9906)
			(stroke
				(width 0.1)
				(type default)
			)
			(layer "B.Fab")
		)
		(pad "1" smd rect
			(at 0 0 180)
			(size 0.508 0.508)
			(layers "B.Cu" "B.Mask" "B.Paste")
			(net "P3V3_STBY")
		)
		(pad "2" smd rect
			(at 0 0.889 180)
			(size 0.508 0.508)
			(layers "B.Cu" "B.Mask" "B.Paste")
			(net "GND")
		)
		(zone
			(layer "B.Cu")
			(hatch none 0.5)
			(connect_pads
				(clearance 0)
			)
			(min_thickness 0.25)
			(keepout
				(tracks allowed)
				(vias not_allowed)
				(pads allowed)
				(copperpour not_allowed)
				(footprints allowed)
			)
			(placement
				(enabled no)
				(sheetname "")
			)
			(fill
				(thermal_gap 0.5)
				(thermal_bridge_width 0.5)
				(island_removal_mode 0)
			)
			(polygon
				(pts
					(xy 421.91432 -73.708514) (xy 421.40632 -73.708514) (xy 421.40632 -73.327514) (xy 421.91432 -73.327514)
				)
			)
		)
		(zone
			(layer "B.Cu")
			(hatch none 0.5)
			(connect_pads
				(clearance 0)
			)
			(min_thickness 0.25)
			(keepout
				(tracks not_allowed)
				(vias allowed)
				(pads allowed)
				(copperpour not_allowed)
				(footprints allowed)
			)
			(placement
				(enabled no)
				(sheetname "")
			)
			(fill
				(thermal_gap 0.5)
				(thermal_bridge_width 0.5)
				(island_removal_mode 0)
			)
			(polygon
				(pts
					(xy 421.91432 -73.327514) (xy 421.40632 -73.327514) (xy 421.40632 -73.708514) (xy 421.91432 -73.708514)
				)
			)
		)
	)
	(footprint ""
		(layer "B.Cu")
		(at 117.1956 -72.644 -90)
		(property "Reference" "R7P17"
			(at 0 0 90)
			(layer "B.SilkS")
			(hide yes)
			(effects
				(font
					(size 1.27 1.27)
				)
				(justify mirror)
			)
		)
		(property "Value" ""
			(at 0 0 90)
			(layer "B.Fab")
			(effects
				(font
					(size 1.27 1.27)
				)
				(justify mirror)
			)
		)
		(duplicate_pad_numbers_are_jumpers no)
		(fp_poly
			(pts
				(xy 0.2794 -0.1016) (xy -0.2794 -0.1016) (xy -0.2794 0.9906) (xy 0.2794 0.9906)
			)
			(stroke
				(width 0)
				(type default)
			)
			(fill no)
			(layer "B.CrtYd")
		)
		(fp_line
			(start -0.2794 0.9906)
			(end -0.2794 -0.1016)
			(stroke
				(width 0.1)
				(type default)
			)
			(layer "B.Fab")
		)
		(fp_line
			(start 0.2794 0.9906)
			(end -0.2794 0.9906)
			(stroke
				(width 0.1)
				(type default)
			)
			(layer "B.Fab")
		)
		(fp_line
			(start -0.2794 -0.1016)
			(end 0.2794 -0.1016)
			(stroke
				(width 0.1)
				(type default)
			)
			(layer "B.Fab")
		)
		(fp_line
			(start 0.2794 -0.1016)
			(end 0.2794 0.9906)
			(stroke
				(width 0.1)
				(type default)
			)
			(layer "B.Fab")
		)
		(pad "1" smd rect
			(at 0 0 90)
			(size 0.508 0.508)
			(layers "B.Cu" "B.Mask" "B.Paste")
			(net "A_CPU1_GHJ_RCOMP1")
		)
		(pad "2" smd rect
			(at 0 0.889 90)
			(size 0.508 0.508)
			(layers "B.Cu" "B.Mask" "B.Paste")
			(net "GND")
		)
		(zone
			(layer "B.Cu")
			(hatch none 0.5)
			(connect_pads
				(clearance 0)
			)
			(min_thickness 0.25)
			(keepout
				(tracks not_allowed)
				(vias allowed)
				(pads allowed)
				(copperpour not_allowed)
				(footprints allowed)
			)
			(placement
				(enabled no)
				(sheetname "")
			)
			(fill
				(thermal_gap 0.5)
				(thermal_bridge_width 0.5)
				(island_removal_mode 0)
			)
			(polygon
				(pts
					(xy 116.5606 -72.39) (xy 116.5606 -72.898) (xy 116.9416 -72.898) (xy 116.9416 -72.39)
				)
			)
		)
		(zone
			(layer "B.Cu")
			(hatch none 0.5)
			(connect_pads
				(clearance 0)
			)
			(min_thickness 0.25)
			(keepout
				(tracks allowed)
				(vias not_allowed)
				(pads allowed)
				(copperpour not_allowed)
				(footprints allowed)
			)
			(placement
				(enabled no)
				(sheetname "")
			)
			(fill
				(thermal_gap 0.5)
				(thermal_bridge_width 0.5)
				(island_removal_mode 0)
			)
			(polygon
				(pts
					(xy 116.9416 -72.39) (xy 116.9416 -72.898) (xy 116.5606 -72.898) (xy 116.5606 -72.39)
				)
			)
		)
	)
	(footprint ""
		(layer "B.Cu")
		(at 93.105732 -12.888468 -90)
		(property "Reference" "C5G83"
			(at -1.14681 0.76708 0)
			(unlocked yes)
			(layer "B.SilkS")
			(effects
				(font
					(size 0.7874 0.5842)
					(thickness 0.1524)
				)
				(justify mirror)
			)
		)
		(property "Value" ""
			(at 0 0 90)
			(layer "B.Fab")
			(effects
				(font
					(size 1.27 1.27)
				)
				(justify mirror)
			)
		)
		(duplicate_pad_numbers_are_jumpers no)
		(fp_rect
			(start -0.4953 -0.2032)
			(end 0.4953 1.6002)
			(stroke
				(width 0)
				(type default)
			)
			(fill no)
			(layer "B.CrtYd")
		)
		(fp_line
			(start -0.4953 1.6002)
			(end 0.4953 1.6002)
			(stroke
				(width 0.1)
				(type default)
			)
			(layer "B.Fab")
		)
		(fp_line
			(start 0.4953 1.6002)
			(end 0.4953 -0.2032)
			(stroke
				(width 0.1)
				(type default)
			)
			(layer "B.Fab")
		)
		(fp_line
			(start -0.4953 -0.2032)
			(end -0.4953 1.6002)
			(stroke
				(width 0.1)
				(type default)
			)
			(layer "B.Fab")
		)
		(fp_line
			(start 0.4953 -0.2032)
			(end -0.4953 -0.2032)
			(stroke
				(width 0.1)
				(type default)
			)
			(layer "B.Fab")
		)
		(pad "1" smd rect
			(at 0 0 90)
			(size 0.762 0.889)
			(layers "B.Cu" "B.Mask" "B.Paste")
			(net "PVDDQ_GHJ")
		)
		(pad "2" smd rect
			(at 0 1.397 90)
			(size 0.762 0.889)
			(layers "B.Cu" "B.Mask" "B.Paste")
			(net "GND")
		)
		(zone
			(layer "B.Cu")
			(hatch none 0.5)
			(connect_pads
				(clearance 0)
			)
			(min_thickness 0.25)
			(keepout
				(tracks not_allowed)
				(vias allowed)
				(pads allowed)
				(copperpour not_allowed)
				(footprints allowed)
			)
			(placement
				(enabled no)
				(sheetname "")
			)
			(fill
				(thermal_gap 0.5)
				(thermal_bridge_width 0.5)
				(island_removal_mode 0)
			)
			(polygon
				(pts
					(xy 92.661232 -13.269468) (xy 92.153232 -13.269468) (xy 92.153232 -12.507468) (xy 92.661232 -12.507468)
				)
			)
		)
	)
	(footprint ""
		(layer "B.Cu")
		(at 378.53874 -67.21856)
		(property "Reference" "R2R2"
			(at 0 0 0)
			(layer "B.SilkS")
			(hide yes)
			(effects
				(font
					(size 1.27 1.27)
				)
				(justify mirror)
			)
		)
		(property "Value" ""
			(at 0 0 0)
			(layer "B.Fab")
			(effects
				(font
					(size 1.27 1.27)
				)
				(justify mirror)
			)
		)
		(duplicate_pad_numbers_are_jumpers no)
		(fp_poly
			(pts
				(xy 0.2794 -0.1016) (xy -0.2794 -0.1016) (xy -0.2794 0.9906) (xy 0.2794 0.9906)
			)
			(stroke
				(width 0)
				(type default)
			)
			(fill no)
			(layer "B.CrtYd")
		)
		(fp_line
			(start -0.2794 -0.1016)
			(end 0.2794 -0.1016)
			(stroke
				(width 0.1)
				(type default)
			)
			(layer "B.Fab")
		)
		(fp_line
			(start -0.2794 0.9906)
			(end -0.2794 -0.1016)
			(stroke
				(width 0.1)
				(type default)
			)
			(layer "B.Fab")
		)
		(fp_line
			(start 0.2794 -0.1016)
			(end 0.2794 0.9906)
			(stroke
				(width 0.1)
				(type default)
			)
			(layer "B.Fab")
		)
		(fp_line
			(start 0.2794 0.9906)
			(end -0.2794 0.9906)
			(stroke
				(width 0.1)
				(type default)
			)
			(layer "B.Fab")
		)
		(pad "1" smd rect
			(at 0 0 180)
			(size 0.508 0.508)
			(layers "B.Cu" "B.Mask" "B.Paste")
			(net "RST_RSMRST_R_N")
		)
		(pad "2" smd rect
			(at 0 0.889 180)
			(size 0.508 0.508)
			(layers "B.Cu" "B.Mask" "B.Paste")
			(net "RST_RSMRST_N")
		)
		(zone
			(layer "B.Cu")
			(hatch none 0.5)
			(connect_pads
				(clearance 0)
			)
			(min_thickness 0.25)
			(keepout
				(tracks allowed)
				(vias not_allowed)
				(pads allowed)
				(copperpour not_allowed)
				(footprints allowed)
			)
			(placement
				(enabled no)
				(sheetname "")
			)
			(fill
				(thermal_gap 0.5)
				(thermal_bridge_width 0.5)
				(island_removal_mode 0)
			)
			(polygon
				(pts
					(xy 378.79274 -66.96456) (xy 378.28474 -66.96456) (xy 378.28474 -66.58356) (xy 378.79274 -66.58356)
				)
			)
		)
		(zone
			(layer "B.Cu")
			(hatch none 0.5)
			(connect_pads
				(clearance 0)
			)
			(min_thickness 0.25)
			(keepout
				(tracks not_allowed)
				(vias allowed)
				(pads allowed)
				(copperpour not_allowed)
				(footprints allowed)
			)
			(placement
				(enabled no)
				(sheetname "")
			)
			(fill
				(thermal_gap 0.5)
				(thermal_bridge_width 0.5)
				(island_removal_mode 0)
			)
			(polygon
				(pts
					(xy 378.79274 -66.58356) (xy 378.28474 -66.58356) (xy 378.28474 -66.96456) (xy 378.79274 -66.96456)
				)
			)
		)
	)
	(footprint ""
		(layer "B.Cu")
		(at 169.770552 -23.562564 -90)
		(property "Reference" "R6T1"
			(at 0 0 90)
			(layer "B.SilkS")
			(hide yes)
			(effects
				(font
					(size 1.27 1.27)
				)
				(justify mirror)
			)
		)
		(property "Value" ""
			(at 0 0 90)
			(layer "B.Fab")
			(effects
				(font
					(size 1.27 1.27)
				)
				(justify mirror)
			)
		)
		(duplicate_pad_numbers_are_jumpers no)
		(fp_poly
			(pts
				(xy 0.2794 -0.1016) (xy -0.2794 -0.1016) (xy -0.2794 0.9906) (xy 0.2794 0.9906)
			)
			(stroke
				(width 0)
				(type default)
			)
			(fill no)
			(layer "B.CrtYd")
		)
		(fp_line
			(start -0.2794 0.9906)
			(end -0.2794 -0.1016)
			(stroke
				(width 0.1)
				(type default)
			)
			(layer "B.Fab")
		)
		(fp_line
			(start 0.2794 0.9906)
			(end -0.2794 0.9906)
			(stroke
				(width 0.1)
				(type default)
			)
			(layer "B.Fab")
		)
		(fp_line
			(start -0.2794 -0.1016)
			(end 0.2794 -0.1016)
			(stroke
				(width 0.1)
				(type default)
			)
			(layer "B.Fab")
		)
		(fp_line
			(start 0.2794 -0.1016)
			(end 0.2794 0.9906)
			(stroke
				(width 0.1)
				(type default)
			)
			(layer "B.Fab")
		)
		(pad "1" smd rect
			(at 0 0 90)
			(size 0.508 0.508)
			(layers "B.Cu" "B.Mask" "B.Paste")
			(net "PVCCIO_CPU1")
		)
		(pad "2" smd rect
			(at 0 0.889 90)
			(size 0.508 0.508)
			(layers "B.Cu" "B.Mask" "B.Paste")
			(net "SMB_DDR_GHJ_SDA_G")
		)
		(zone
			(layer "B.Cu")
			(hatch none 0.5)
			(connect_pads
				(clearance 0)
			)
			(min_thickness 0.25)
			(keepout
				(tracks not_allowed)
				(vias allowed)
				(pads allowed)
				(copperpour not_allowed)
				(footprints allowed)
			)
			(placement
				(enabled no)
				(sheetname "")
			)
			(fill
				(thermal_gap 0.5)
				(thermal_bridge_width 0.5)
				(island_removal_mode 0)
			)
			(polygon
				(pts
					(xy 169.135552 -23.308564) (xy 169.135552 -23.816564) (xy 169.516552 -23.816564) (xy 169.516552 -23.308564)
				)
			)
		)
		(zone
			(layer "B.Cu")
			(hatch none 0.5)
			(connect_pads
				(clearance 0)
			)
			(min_thickness 0.25)
			(keepout
				(tracks allowed)
				(vias not_allowed)
				(pads allowed)
				(copperpour not_allowed)
				(footprints allowed)
			)
			(placement
				(enabled no)
				(sheetname "")
			)
			(fill
				(thermal_gap 0.5)
				(thermal_bridge_width 0.5)
				(island_removal_mode 0)
			)
			(polygon
				(pts
					(xy 169.516552 -23.308564) (xy 169.516552 -23.816564) (xy 169.135552 -23.816564) (xy 169.135552 -23.308564)
				)
			)
		)
	)
	(footprint ""
		(layer "B.Cu")
		(at 460.8576 -126.7714)
		(property "Reference" "C1M37"
			(at 0 0 0)
			(layer "B.SilkS")
			(hide yes)
			(effects
				(font
					(size 1.27 1.27)
				)
				(justify mirror)
			)
		)
		(property "Value" ""
			(at 0 0 0)
			(layer "B.Fab")
			(effects
				(font
					(size 1.27 1.27)
				)
				(justify mirror)
			)
		)
		(duplicate_pad_numbers_are_jumpers no)
		(fp_poly
			(pts
				(xy -0.3048 -0.1016) (xy -0.3048 0.9906) (xy 0.3048 0.9906) (xy 0.3048 -0.1016)
			)
			(stroke
				(width 0)
				(type default)
			)
			(fill no)
			(layer "B.CrtYd")
		)
		(fp_line
			(start -0.3048 -0.1016)
			(end 0.3048 -0.1016)
			(stroke
				(width 0.1)
				(type default)
			)
			(layer "B.Fab")
		)
		(fp_line
			(start -0.3048 0.9906)
			(end -0.3048 -0.1016)
			(stroke
				(width 0.1)
				(type default)
			)
			(layer "B.Fab")
		)
		(fp_line
			(start 0.3048 -0.1016)
			(end 0.3048 0.9906)
			(stroke
				(width 0.1)
				(type default)
			)
			(layer "B.Fab")
		)
		(fp_line
			(start 0.3048 0.9906)
			(end -0.3048 0.9906)
			(stroke
				(width 0.1)
				(type default)
			)
			(layer "B.Fab")
		)
		(pad "1" smd rect
			(at 0 0 180)
			(size 0.508 0.508)
			(layers "B.Cu" "B.Mask" "B.Paste")
			(net "P3V3_STBY")
		)
		(pad "2" smd rect
			(at 0 0.889 180)
			(size 0.508 0.508)
			(layers "B.Cu" "B.Mask" "B.Paste")
			(net "GND")
		)
		(zone
			(layer "B.Cu")
			(hatch none 0.5)
			(connect_pads
				(clearance 0)
			)
			(min_thickness 0.25)
			(keepout
				(tracks allowed)
				(vias not_allowed)
				(pads allowed)
				(copperpour not_allowed)
				(footprints allowed)
			)
			(placement
				(enabled no)
				(sheetname "")
			)
			(fill
				(thermal_gap 0.5)
				(thermal_bridge_width 0.5)
				(island_removal_mode 0)
			)
			(polygon
				(pts
					(xy 461.1116 -126.5174) (xy 460.6036 -126.5174) (xy 460.6036 -126.1364) (xy 461.1116 -126.1364)
				)
			)
		)
		(zone
			(layer "B.Cu")
			(hatch none 0.5)
			(connect_pads
				(clearance 0)
			)
			(min_thickness 0.25)
			(keepout
				(tracks not_allowed)
				(vias allowed)
				(pads allowed)
				(copperpour not_allowed)
				(footprints allowed)
			)
			(placement
				(enabled no)
				(sheetname "")
			)
			(fill
				(thermal_gap 0.5)
				(thermal_bridge_width 0.5)
				(island_removal_mode 0)
			)
			(polygon
				(pts
					(xy 461.1116 -126.1364) (xy 460.6036 -126.1364) (xy 460.6036 -126.5174) (xy 461.1116 -126.5174)
				)
			)
		)
	)
	(footprint ""
		(layer "B.Cu")
		(at 351.421192 -77.834236)
		(property "Reference" "C3P29"
			(at 0 0 0)
			(layer "B.SilkS")
			(hide yes)
			(effects
				(font
					(size 1.27 1.27)
				)
				(justify mirror)
			)
		)
		(property "Value" ""
			(at 0 0 0)
			(layer "B.Fab")
			(effects
				(font
					(size 1.27 1.27)
				)
				(justify mirror)
			)
		)
		(duplicate_pad_numbers_are_jumpers no)
		(fp_poly
			(pts
				(xy -0.3048 -0.1016) (xy -0.3048 0.9906) (xy 0.3048 0.9906) (xy 0.3048 -0.1016)
			)
			(stroke
				(width 0)
				(type default)
			)
			(fill no)
			(layer "B.CrtYd")
		)
		(fp_line
			(start -0.3048 -0.1016)
			(end 0.3048 -0.1016)
			(stroke
				(width 0.1)
				(type default)
			)
			(layer "B.Fab")
		)
		(fp_line
			(start -0.3048 0.9906)
			(end -0.3048 -0.1016)
			(stroke
				(width 0.1)
				(type default)
			)
			(layer "B.Fab")
		)
		(fp_line
			(start 0.3048 -0.1016)
			(end 0.3048 0.9906)
			(stroke
				(width 0.1)
				(type default)
			)
			(layer "B.Fab")
		)
		(fp_line
			(start 0.3048 0.9906)
			(end -0.3048 0.9906)
			(stroke
				(width 0.1)
				(type default)
			)
			(layer "B.Fab")
		)
		(pad "1" smd rect
			(at 0 0 180)
			(size 0.508 0.508)
			(layers "B.Cu" "B.Mask" "B.Paste")
			(net "P3E_CPU0_PE1_SS_TXN<4>")
		)
		(pad "2" smd rect
			(at 0 0.889 180)
			(size 0.508 0.508)
			(layers "B.Cu" "B.Mask" "B.Paste")
			(net "P3E_CPU0_PE1_SS_C_TXN<4>")
		)
		(zone
			(layer "B.Cu")
			(hatch none 0.5)
			(connect_pads
				(clearance 0)
			)
			(min_thickness 0.25)
			(keepout
				(tracks allowed)
				(vias not_allowed)
				(pads allowed)
				(copperpour not_allowed)
				(footprints allowed)
			)
			(placement
				(enabled no)
				(sheetname "")
			)
			(fill
				(thermal_gap 0.5)
				(thermal_bridge_width 0.5)
				(island_removal_mode 0)
			)
			(polygon
				(pts
					(xy 351.675192 -77.580236) (xy 351.167192 -77.580236) (xy 351.167192 -77.199236) (xy 351.675192 -77.199236)
				)
			)
		)
		(zone
			(layer "B.Cu")
			(hatch none 0.5)
			(connect_pads
				(clearance 0)
			)
			(min_thickness 0.25)
			(keepout
				(tracks not_allowed)
				(vias allowed)
				(pads allowed)
				(copperpour not_allowed)
				(footprints allowed)
			)
			(placement
				(enabled no)
				(sheetname "")
			)
			(fill
				(thermal_gap 0.5)
				(thermal_bridge_width 0.5)
				(island_removal_mode 0)
			)
			(polygon
				(pts
					(xy 351.675192 -77.199236) (xy 351.167192 -77.199236) (xy 351.167192 -77.580236) (xy 351.675192 -77.580236)
				)
			)
		)
	)
	(footprint ""
		(layer "B.Cu")
		(at 441.833 -13.8938 90)
		(property "Reference" "C1U22"
			(at 0 0 90)
			(layer "B.SilkS")
			(hide yes)
			(effects
				(font
					(size 1.27 1.27)
				)
				(justify mirror)
			)
		)
		(property "Value" ""
			(at 0 0 90)
			(layer "B.Fab")
			(effects
				(font
					(size 1.27 1.27)
				)
				(justify mirror)
			)
		)
		(duplicate_pad_numbers_are_jumpers no)
		(fp_poly
			(pts
				(xy -0.3048 -0.1016) (xy -0.3048 0.9906) (xy 0.3048 0.9906) (xy 0.3048 -0.1016)
			)
			(stroke
				(width 0)
				(type default)
			)
			(fill no)
			(layer "B.CrtYd")
		)
		(fp_line
			(start 0.3048 -0.1016)
			(end 0.3048 0.9906)
			(stroke
				(width 0.1)
				(type default)
			)
			(layer "B.Fab")
		)
		(fp_line
			(start -0.3048 -0.1016)
			(end 0.3048 -0.1016)
			(stroke
				(width 0.1)
				(type default)
			)
			(layer "B.Fab")
		)
		(fp_line
			(start 0.3048 0.9906)
			(end -0.3048 0.9906)
			(stroke
				(width 0.1)
				(type default)
			)
			(layer "B.Fab")
		)
		(fp_line
			(start -0.3048 0.9906)
			(end -0.3048 -0.1016)
			(stroke
				(width 0.1)
				(type default)
			)
			(layer "B.Fab")
		)
		(pad "1" smd rect
			(at 0 0 270)
			(size 0.508 0.508)
			(layers "B.Cu" "B.Mask" "B.Paste")
			(net "P0V7_GTL2014_2")
		)
		(pad "2" smd rect
			(at 0 0.889 270)
			(size 0.508 0.508)
			(layers "B.Cu" "B.Mask" "B.Paste")
			(net "GND")
		)
		(zone
			(layer "B.Cu")
			(hatch none 0.5)
			(connect_pads
				(clearance 0)
			)
			(min_thickness 0.25)
			(keepout
				(tracks allowed)
				(vias not_allowed)
				(pads allowed)
				(copperpour not_allowed)
				(footprints allowed)
			)
			(placement
				(enabled no)
				(sheetname "")
			)
			(fill
				(thermal_gap 0.5)
				(thermal_bridge_width 0.5)
				(island_removal_mode 0)
			)
			(polygon
				(pts
					(xy 442.087 -14.1478) (xy 442.087 -13.6398) (xy 442.468 -13.6398) (xy 442.468 -14.1478)
				)
			)
		)
		(zone
			(layer "B.Cu")
			(hatch none 0.5)
			(connect_pads
				(clearance 0)
			)
			(min_thickness 0.25)
			(keepout
				(tracks not_allowed)
				(vias allowed)
				(pads allowed)
				(copperpour not_allowed)
				(footprints allowed)
			)
			(placement
				(enabled no)
				(sheetname "")
			)
			(fill
				(thermal_gap 0.5)
				(thermal_bridge_width 0.5)
				(island_removal_mode 0)
			)
			(polygon
				(pts
					(xy 442.468 -14.1478) (xy 442.468 -13.6398) (xy 442.087 -13.6398) (xy 442.087 -14.1478)
				)
			)
		)
	)
	(footprint ""
		(layer "B.Cu")
		(at 79.550768 -125.8824 -90)
		(property "Reference" "C8M9"
			(at 1.75387 0.874268 0)
			(unlocked yes)
			(layer "B.SilkS")
			(effects
				(font
					(size 0.7874 0.5842)
					(thickness 0.1524)
				)
				(justify mirror)
			)
		)
		(property "Value" ""
			(at 0 0 90)
			(layer "B.Fab")
			(effects
				(font
					(size 1.27 1.27)
				)
				(justify mirror)
			)
		)
		(duplicate_pad_numbers_are_jumpers no)
		(fp_rect
			(start 0.500126 1.598422)
			(end -0.500126 -0.201422)
			(stroke
				(width 0)
				(type default)
			)
			(fill no)
			(layer "B.CrtYd")
		)
		(fp_line
			(start -0.500126 1.598422)
			(end 0.500126 1.598422)
			(stroke
				(width 0.1)
				(type default)
			)
			(layer "B.Fab")
		)
		(fp_line
			(start 0.500126 1.598422)
			(end 0.500126 -0.201422)
			(stroke
				(width 0.1)
				(type default)
			)
			(layer "B.Fab")
		)
		(fp_line
			(start -0.500126 -0.201422)
			(end -0.500126 1.598422)
			(stroke
				(width 0.1)
				(type default)
			)
			(layer "B.Fab")
		)
		(fp_line
			(start 0.500126 -0.201422)
			(end -0.500126 -0.201422)
			(stroke
				(width 0.1)
				(type default)
			)
			(layer "B.Fab")
		)
		(pad "1" smd rect
			(at 0 0 180)
			(size 0.889 0.9906)
			(layers "B.Cu" "B.Mask" "B.Paste")
			(net "PVDDQ_KLM")
		)
		(pad "2" smd rect
			(at 0 1.397 180)
			(size 0.889 0.9906)
			(layers "B.Cu" "B.Mask" "B.Paste")
			(net "GND")
		)
		(zone
			(layer "B.Cu")
			(hatch none 0.5)
			(connect_pads
				(clearance 0)
			)
			(min_thickness 0.25)
			(keepout
				(tracks not_allowed)
				(vias allowed)
				(pads allowed)
				(copperpour not_allowed)
				(footprints allowed)
			)
			(placement
				(enabled no)
				(sheetname "")
			)
			(fill
				(thermal_gap 0.5)
				(thermal_bridge_width 0.5)
				(island_removal_mode 0)
			)
			(polygon
				(pts
					(xy 78.598268 -125.3871) (xy 79.106268 -125.3871) (xy 79.106268 -126.3777) (xy 78.598268 -126.3777)
				)
			)
		)
		(zone
			(layer "B.Cu")
			(hatch none 0.5)
			(connect_pads
				(clearance 0)
			)
			(min_thickness 0.25)
			(keepout
				(tracks allowed)
				(vias not_allowed)
				(pads allowed)
				(copperpour not_allowed)
				(footprints allowed)
			)
			(placement
				(enabled no)
				(sheetname "")
			)
			(fill
				(thermal_gap 0.5)
				(thermal_bridge_width 0.5)
				(island_removal_mode 0)
			)
			(polygon
				(pts
					(xy 78.598268 -125.3871) (xy 79.106268 -125.3871) (xy 79.106268 -126.3777) (xy 78.598268 -126.3777)
				)
			)
		)
	)
	(footprint ""
		(layer "B.Cu")
		(at 348.615 -146.343624 -90)
		(property "Reference" "C3L4"
			(at 0 0 90)
			(layer "B.SilkS")
			(hide yes)
			(effects
				(font
					(size 1.27 1.27)
				)
				(justify mirror)
			)
		)
		(property "Value" ""
			(at 0 0 90)
			(layer "B.Fab")
			(effects
				(font
					(size 1.27 1.27)
				)
				(justify mirror)
			)
		)
		(duplicate_pad_numbers_are_jumpers no)
		(fp_poly
			(pts
				(xy 0.7239 -0.2159) (xy -0.7239 -0.2159) (xy -0.7239 1.9939) (xy 0.7239 1.9939)
			)
			(stroke
				(width 0)
				(type default)
			)
			(fill no)
			(layer "B.CrtYd")
		)
		(fp_line
			(start -0.7239 1.9939)
			(end -0.7239 -0.2159)
			(stroke
				(width 0.1)
				(type default)
			)
			(layer "B.Fab")
		)
		(fp_line
			(start 0.7239 1.9939)
			(end -0.7239 1.9939)
			(stroke
				(width 0.1)
				(type default)
			)
			(layer "B.Fab")
		)
		(fp_line
			(start -0.7239 -0.2159)
			(end 0.7239 -0.2159)
			(stroke
				(width 0.1)
				(type default)
			)
			(layer "B.Fab")
		)
		(fp_line
			(start 0.7239 -0.2159)
			(end 0.7239 1.9939)
			(stroke
				(width 0.1)
				(type default)
			)
			(layer "B.Fab")
		)
		(pad "1" smd rect
			(at 0 0 90)
			(size 1.27 1.016)
			(layers "B.Cu" "B.Mask" "B.Paste")
			(net "VR_FET_SW_P12V_STBY_PVDDQ_DEF")
		)
		(pad "2" smd rect
			(at 0 1.778 90)
			(size 1.27 1.016)
			(layers "B.Cu" "B.Mask" "B.Paste")
			(net "GND")
		)
		(zone
			(layer "B.Cu")
			(hatch none 0.5)
			(connect_pads
				(clearance 0)
			)
			(min_thickness 0.25)
			(keepout
				(tracks not_allowed)
				(vias allowed)
				(pads allowed)
				(copperpour not_allowed)
				(footprints allowed)
			)
			(placement
				(enabled no)
				(sheetname "")
			)
			(fill
				(thermal_gap 0.5)
				(thermal_bridge_width 0.5)
				(island_removal_mode 0)
			)
			(polygon
				(pts
					(xy 348.107 -145.708624) (xy 348.107 -146.978624) (xy 347.345 -146.978624) (xy 347.345 -145.708624)
				)
			)
		)
	)
	(footprint ""
		(layer "B.Cu")
		(at 185.42 -49.7078 90)
		(property "Reference" "C6R16"
			(at -3.12547 4.191 0)
			(unlocked yes)
			(layer "B.SilkS")
			(effects
				(font
					(size 0.7874 0.5842)
					(thickness 0.1524)
				)
				(justify mirror)
			)
		)
		(property "Value" ""
			(at 0 0 90)
			(layer "B.Fab")
			(effects
				(font
					(size 1.27 1.27)
				)
				(justify mirror)
			)
		)
		(duplicate_pad_numbers_are_jumpers no)
		(fp_line
			(start 2.563114 -1.616456)
			(end 2.563114 1.633728)
			(stroke
				(width 0.1524)
				(type default)
			)
			(layer "B.SilkS")
		)
		(fp_line
			(start 1.6002 -1.616456)
			(end 2.563114 -1.616456)
			(stroke
				(width 0.1524)
				(type default)
			)
			(layer "B.SilkS")
		)
		(fp_line
			(start -1.6002 -1.616456)
			(end -2.504948 -1.616456)
			(stroke
				(width 0.1524)
				(type default)
			)
			(layer "B.SilkS")
		)
		(fp_line
			(start -2.504948 -1.616456)
			(end -2.504948 1.633728)
			(stroke
				(width 0.1524)
				(type default)
			)
			(layer "B.SilkS")
		)
		(fp_line
			(start 2.563114 1.633728)
			(end 1.6002 1.633728)
			(stroke
				(width 0.1524)
				(type default)
			)
			(layer "B.SilkS")
		)
		(fp_line
			(start -2.504948 1.633728)
			(end -1.6002 1.633728)
			(stroke
				(width 0.1524)
				(type default)
			)
			(layer "B.SilkS")
		)
		(fp_line
			(start 2.286 7.366)
			(end 2.286 1.632712)
			(stroke
				(width 0.1524)
				(type default)
			)
			(layer "B.SilkS")
		)
		(fp_line
			(start 2.286 7.366)
			(end 1.60147 7.366)
			(stroke
				(width 0.1524)
				(type default)
			)
			(layer "B.SilkS")
		)
		(fp_line
			(start -2.286 7.366)
			(end -2.286 1.63195)
			(stroke
				(width 0.1524)
				(type default)
			)
			(layer "B.SilkS")
		)
		(fp_line
			(start -2.286 7.366)
			(end -1.600708 7.366)
			(stroke
				(width 0.1524)
				(type default)
			)
			(layer "B.SilkS")
		)
		(fp_rect
			(start 2.286 7.366)
			(end -2.286 -0.254)
			(stroke
				(width 0)
				(type default)
			)
			(fill no)
			(layer "B.CrtYd")
		)
		(fp_line
			(start 2.286 -0.254)
			(end -2.286 -0.254)
			(stroke
				(width 0.1)
				(type default)
			)
			(layer "B.Fab")
		)
		(fp_line
			(start -2.286 -0.254)
			(end -2.286 7.366)
			(stroke
				(width 0.1)
				(type default)
			)
			(layer "B.Fab")
		)
		(fp_line
			(start 2.286 7.366)
			(end 2.286 -0.254)
			(stroke
				(width 0.1)
				(type default)
			)
			(layer "B.Fab")
		)
		(fp_line
			(start -2.286 7.366)
			(end 2.286 7.366)
			(stroke
				(width 0.1)
				(type default)
			)
			(layer "B.Fab")
		)
		(pad "1" smd rect
			(at 0 0 270)
			(size 2.54 3.048)
			(layers "B.Cu" "B.Mask" "B.Paste")
			(net "PVCCMCP_CPU1")
		)
		(pad "2" smd rect
			(at 0 7.112 270)
			(size 2.54 3.048)
			(layers "B.Cu" "B.Mask" "B.Paste")
			(net "GND")
		)
	)
	(footprint ""
		(layer "B.Cu")
		(at 489.445046 -46.665388 90)
		(property "Reference" "R25W131"
			(at 0.8382 -0.67818 90)
			(unlocked yes)
			(layer "B.SilkS")
			(effects
				(font
					(size 0.4064 0.254)
					(thickness 0.1524)
				)
				(justify left mirror)
			)
		)
		(property "Value" ""
			(at 0 0 90)
			(layer "B.Fab")
			(effects
				(font
					(size 1.27 1.27)
				)
				(justify mirror)
			)
		)
		(duplicate_pad_numbers_are_jumpers no)
		(fp_poly
			(pts
				(xy 0.2794 -0.1016) (xy -0.2794 -0.1016) (xy -0.2794 0.9906) (xy 0.2794 0.9906)
			)
			(stroke
				(width 0)
				(type default)
			)
			(fill no)
			(layer "B.CrtYd")
		)
		(fp_line
			(start 0.2794 -0.1016)
			(end 0.2794 0.9906)
			(stroke
				(width 0.1)
				(type default)
			)
			(layer "B.Fab")
		)
		(fp_line
			(start -0.2794 -0.1016)
			(end 0.2794 -0.1016)
			(stroke
				(width 0.1)
				(type default)
			)
			(layer "B.Fab")
		)
		(fp_line
			(start 0.2794 0.9906)
			(end -0.2794 0.9906)
			(stroke
				(width 0.1)
				(type default)
			)
			(layer "B.Fab")
		)
		(fp_line
			(start -0.2794 0.9906)
			(end -0.2794 -0.1016)
			(stroke
				(width 0.1)
				(type default)
			)
			(layer "B.Fab")
		)
		(pad "1" smd rect
			(at 0 0 270)
			(size 0.508 0.508)
			(layers "B.Cu" "B.Mask" "B.Paste")
			(net "P3V3")
		)
		(pad "2" smd rect
			(at 0 0.889 270)
			(size 0.508 0.508)
			(layers "B.Cu" "B.Mask" "B.Paste")
			(net "Q25W1_GATE")
		)
		(zone
			(layer "B.Cu")
			(hatch none 0.5)
			(connect_pads
				(clearance 0)
			)
			(min_thickness 0.25)
			(keepout
				(tracks allowed)
				(vias not_allowed)
				(pads allowed)
				(copperpour not_allowed)
				(footprints allowed)
			)
			(placement
				(enabled no)
				(sheetname "")
			)
			(fill
				(thermal_gap 0.5)
				(thermal_bridge_width 0.5)
				(island_removal_mode 0)
			)
			(polygon
				(pts
					(xy 489.699046 -46.919388) (xy 489.699046 -46.411388) (xy 490.080046 -46.411388) (xy 490.080046 -46.919388)
				)
			)
		)
		(zone
			(layer "B.Cu")
			(hatch none 0.5)
			(connect_pads
				(clearance 0)
			)
			(min_thickness 0.25)
			(keepout
				(tracks not_allowed)
				(vias allowed)
				(pads allowed)
				(copperpour not_allowed)
				(footprints allowed)
			)
			(placement
				(enabled no)
				(sheetname "")
			)
			(fill
				(thermal_gap 0.5)
				(thermal_bridge_width 0.5)
				(island_removal_mode 0)
			)
			(polygon
				(pts
					(xy 490.080046 -46.919388) (xy 490.080046 -46.411388) (xy 489.699046 -46.411388) (xy 489.699046 -46.919388)
				)
			)
		)
	)
	(footprint ""
		(layer "B.Cu")
		(at 334.01 2.032 90)
		(property "Reference" "C3U8"
			(at -3.07467 4.318 0)
			(unlocked yes)
			(layer "B.SilkS")
			(effects
				(font
					(size 0.7874 0.5842)
					(thickness 0.1524)
				)
				(justify mirror)
			)
		)
		(property "Value" ""
			(at 0 0 90)
			(layer "B.Fab")
			(effects
				(font
					(size 1.27 1.27)
				)
				(justify mirror)
			)
		)
		(duplicate_pad_numbers_are_jumpers no)
		(fp_line
			(start 2.563114 -1.616456)
			(end 2.563114 1.633728)
			(stroke
				(width 0.1524)
				(type default)
			)
			(layer "B.SilkS")
		)
		(fp_line
			(start 1.6002 -1.616456)
			(end 2.563114 -1.616456)
			(stroke
				(width 0.1524)
				(type default)
			)
			(layer "B.SilkS")
		)
		(fp_line
			(start -1.6002 -1.616456)
			(end -2.504948 -1.616456)
			(stroke
				(width 0.1524)
				(type default)
			)
			(layer "B.SilkS")
		)
		(fp_line
			(start -2.504948 -1.616456)
			(end -2.504948 1.633728)
			(stroke
				(width 0.1524)
				(type default)
			)
			(layer "B.SilkS")
		)
		(fp_line
			(start 2.563114 1.633728)
			(end 1.6002 1.633728)
			(stroke
				(width 0.1524)
				(type default)
			)
			(layer "B.SilkS")
		)
		(fp_line
			(start -2.504948 1.633728)
			(end -1.6002 1.633728)
			(stroke
				(width 0.1524)
				(type default)
			)
			(layer "B.SilkS")
		)
		(fp_line
			(start 2.286 7.366)
			(end 2.286 1.632712)
			(stroke
				(width 0.1524)
				(type default)
			)
			(layer "B.SilkS")
		)
		(fp_line
			(start 2.286 7.366)
			(end 1.60147 7.366)
			(stroke
				(width 0.1524)
				(type default)
			)
			(layer "B.SilkS")
		)
		(fp_line
			(start -2.286 7.366)
			(end -2.286 1.63195)
			(stroke
				(width 0.1524)
				(type default)
			)
			(layer "B.SilkS")
		)
		(fp_line
			(start -2.286 7.366)
			(end -1.600708 7.366)
			(stroke
				(width 0.1524)
				(type default)
			)
			(layer "B.SilkS")
		)
		(fp_rect
			(start -2.286 -0.254)
			(end 2.286 7.366)
			(stroke
				(width 0)
				(type default)
			)
			(fill no)
			(layer "B.CrtYd")
		)
		(fp_line
			(start 2.286 -0.254)
			(end -2.286 -0.254)
			(stroke
				(width 0.1)
				(type default)
			)
			(layer "B.Fab")
		)
		(fp_line
			(start -2.286 -0.254)
			(end -2.286 7.366)
			(stroke
				(width 0.1)
				(type default)
			)
			(layer "B.Fab")
		)
		(fp_line
			(start 2.286 7.366)
			(end 2.286 -0.254)
			(stroke
				(width 0.1)
				(type default)
			)
			(layer "B.Fab")
		)
		(fp_line
			(start -2.286 7.366)
			(end 2.286 7.366)
			(stroke
				(width 0.1)
				(type default)
			)
			(layer "B.Fab")
		)
		(pad "1" smd rect
			(at 0 0 270)
			(size 2.54 3.048)
			(layers "B.Cu" "B.Mask" "B.Paste")
			(net "PVDDQ_ABC")
		)
		(pad "2" smd rect
			(at 0 7.112 270)
			(size 2.54 3.048)
			(layers "B.Cu" "B.Mask" "B.Paste")
			(net "GND")
		)
	)
	(footprint ""
		(layer "B.Cu")
		(at 166.3192 1.2192 90)
		(property "Reference" "C4G22"
			(at 0 0 90)
			(layer "B.SilkS")
			(hide yes)
			(effects
				(font
					(size 1.27 1.27)
				)
				(justify mirror)
			)
		)
		(property "Value" ""
			(at 0 0 90)
			(layer "B.Fab")
			(effects
				(font
					(size 1.27 1.27)
				)
				(justify mirror)
			)
		)
		(duplicate_pad_numbers_are_jumpers no)
		(fp_poly
			(pts
				(xy -0.3048 -0.1016) (xy -0.3048 0.9906) (xy 0.3048 0.9906) (xy 0.3048 -0.1016)
			)
			(stroke
				(width 0)
				(type default)
			)
			(fill no)
			(layer "B.CrtYd")
		)
		(fp_line
			(start 0.3048 -0.1016)
			(end 0.3048 0.9906)
			(stroke
				(width 0.1)
				(type default)
			)
			(layer "B.Fab")
		)
		(fp_line
			(start -0.3048 -0.1016)
			(end 0.3048 -0.1016)
			(stroke
				(width 0.1)
				(type default)
			)
			(layer "B.Fab")
		)
		(fp_line
			(start 0.3048 0.9906)
			(end -0.3048 0.9906)
			(stroke
				(width 0.1)
				(type default)
			)
			(layer "B.Fab")
		)
		(fp_line
			(start -0.3048 0.9906)
			(end -0.3048 -0.1016)
			(stroke
				(width 0.1)
				(type default)
			)
			(layer "B.Fab")
		)
		(pad "1" smd rect
			(at 0 0 270)
			(size 0.508 0.508)
			(layers "B.Cu" "B.Mask" "B.Paste")
			(net "PVCCIO_CPU1")
		)
		(pad "2" smd rect
			(at 0 0.889 270)
			(size 0.508 0.508)
			(layers "B.Cu" "B.Mask" "B.Paste")
			(net "GND")
		)
		(zone
			(layer "B.Cu")
			(hatch none 0.5)
			(connect_pads
				(clearance 0)
			)
			(min_thickness 0.25)
			(keepout
				(tracks allowed)
				(vias not_allowed)
				(pads allowed)
				(copperpour not_allowed)
				(footprints allowed)
			)
			(placement
				(enabled no)
				(sheetname "")
			)
			(fill
				(thermal_gap 0.5)
				(thermal_bridge_width 0.5)
				(island_removal_mode 0)
			)
			(polygon
				(pts
					(xy 166.5732 0.9652) (xy 166.5732 1.4732) (xy 166.9542 1.4732) (xy 166.9542 0.9652)
				)
			)
		)
		(zone
			(layer "B.Cu")
			(hatch none 0.5)
			(connect_pads
				(clearance 0)
			)
			(min_thickness 0.25)
			(keepout
				(tracks not_allowed)
				(vias allowed)
				(pads allowed)
				(copperpour not_allowed)
				(footprints allowed)
			)
			(placement
				(enabled no)
				(sheetname "")
			)
			(fill
				(thermal_gap 0.5)
				(thermal_bridge_width 0.5)
				(island_removal_mode 0)
			)
			(polygon
				(pts
					(xy 166.9542 0.9652) (xy 166.9542 1.4732) (xy 166.5732 1.4732) (xy 166.5732 0.9652)
				)
			)
		)
	)
	(footprint ""
		(layer "B.Cu")
		(at 491.078266 -20.00758 -90)
		(property "Reference" "U9E1"
			(at -4.7498 -1.51257 90)
			(unlocked yes)
			(layer "B.SilkS")
			(effects
				(font
					(size 0.7874 0.5842)
					(thickness 0.1524)
				)
				(justify left mirror)
			)
		)
		(property "Value" ""
			(at 0 0 90)
			(layer "B.Fab")
			(effects
				(font
					(size 1.27 1.27)
				)
				(justify mirror)
			)
		)
		(duplicate_pad_numbers_are_jumpers no)
		(fp_line
			(start -4.826 4.6355)
			(end -1.905 4.6355)
			(stroke
				(width 0.1524)
				(type default)
			)
			(layer "B.SilkS")
		)
		(fp_line
			(start -1.905 4.6355)
			(end -1.905 -0.8255)
			(stroke
				(width 0.1524)
				(type default)
			)
			(layer "B.SilkS")
		)
		(fp_line
			(start -4.0132 0.6731)
			(end -4.0132 -0.8255)
			(stroke
				(width 0.1524)
				(type default)
			)
			(layer "B.SilkS")
		)
		(fp_line
			(start -2.7432 0.6731)
			(end -4.0132 0.6731)
			(stroke
				(width 0.1524)
				(type default)
			)
			(layer "B.SilkS")
		)
		(fp_line
			(start -4.826 -0.8255)
			(end -4.826 4.6355)
			(stroke
				(width 0.1524)
				(type default)
			)
			(layer "B.SilkS")
		)
		(fp_line
			(start -2.7432 -0.8255)
			(end -2.7432 0.6731)
			(stroke
				(width 0.1524)
				(type default)
			)
			(layer "B.SilkS")
		)
		(fp_line
			(start -1.905 -0.8255)
			(end -4.826 -0.8255)
			(stroke
				(width 0.1524)
				(type default)
			)
			(layer "B.SilkS")
		)
		(fp_circle
			(center 1.016 -1.27)
			(end 1.016 -1.4605)
			(stroke
				(width 0.381)
				(type default)
			)
			(fill no)
			(layer "B.SilkS")
		)
		(fp_poly
			(pts
				(xy -6.0833 -0.8255) (xy -6.0833 4.6355) (xy -0.6731 4.6355) (xy -0.6731 -0.8255)
			)
			(stroke
				(width 0)
				(type default)
			)
			(fill no)
			(layer "B.CrtYd")
		)
		(fp_line
			(start -4.0132 0.6731)
			(end -4.0132 -0.8255)
			(stroke
				(width 0.1)
				(type default)
			)
			(layer "B.Fab")
		)
		(fp_line
			(start -2.7432 0.6731)
			(end -4.0132 0.6731)
			(stroke
				(width 0.1)
				(type default)
			)
			(layer "B.Fab")
		)
		(fp_line
			(start -2.7432 -0.8255)
			(end -2.7432 0.6731)
			(stroke
				(width 0.1)
				(type default)
			)
			(layer "B.Fab")
		)
		(fp_rect
			(start -0.6731 4.6355)
			(end -6.0833 -0.8255)
			(stroke
				(width 0)
				(type default)
			)
			(fill no)
			(layer "B.Fab")
		)
		(fp_circle
			(center 1.016 -1.27)
			(end 1.016 -1.4605)
			(stroke
				(width 0.381)
				(type default)
			)
			(fill no)
			(layer "B.Fab")
		)
		(pad "1" smd rect
			(at 0 0 90)
			(size 1.9304 0.635)
			(layers "B.Cu" "B.Mask" "B.Paste")
			(net "SPI_NIC_CS_N")
		)
		(pad "2" smd rect
			(at 0 1.27 90)
			(size 1.9304 0.635)
			(layers "B.Cu" "B.Mask" "B.Paste")
			(net "SPI_NIC_MISO_R")
		)
		(pad "3" smd rect
			(at 0 2.54 90)
			(size 1.9304 0.635)
			(layers "B.Cu" "B.Mask" "B.Paste")
			(net "PU_NV_WP_N")
		)
		(pad "4" smd rect
			(at 0 3.81 90)
			(size 1.9304 0.635)
			(layers "B.Cu" "B.Mask" "B.Paste")
			(net "GND")
		)
		(pad "5" smd rect
			(at -6.7564 3.81 90)
			(size 1.9304 0.635)
			(layers "B.Cu" "B.Mask" "B.Paste")
			(net "SPI_NIC_MOSI")
		)
		(pad "6" smd rect
			(at -6.7564 2.54 90)
			(size 1.9304 0.635)
			(layers "B.Cu" "B.Mask" "B.Paste")
			(net "SPI_NIC_SCLK")
		)
		(pad "7" smd rect
			(at -6.7564 1.27 90)
			(size 1.9304 0.635)
			(layers "B.Cu" "B.Mask" "B.Paste")
			(net "PU_NV_HOLD_N")
		)
		(pad "8" smd rect
			(at -6.7564 0 90)
			(size 1.9304 0.635)
			(layers "B.Cu" "B.Mask" "B.Paste")
			(net "P3V3_STBY")
		)
	)
	(footprint ""
		(layer "B.Cu")
		(at 2.62382 -134.38632 90)
		(property "Reference" "C1A2"
			(at 0 0 90)
			(layer "B.SilkS")
			(hide yes)
			(effects
				(font
					(size 1.27 1.27)
				)
				(justify mirror)
			)
		)
		(property "Value" "*"
			(at -1.1811 -2.8194 90)
			(unlocked yes)
			(layer "B.Fab")
			(hide yes)
			(effects
				(font
					(size 1.27 1.016)
					(thickness 0.1524)
				)
				(justify mirror)
			)
		)
		(property "Device Type" "SC1U10V2KX-4-GP_SMD-BCG6-SC1U1A"
			(at -1.1811 -4.3434 90)
			(unlocked yes)
			(layer "B.Fab")
			(hide yes)
			(effects
				(font
					(size 1.27 1.016)
					(thickness 0.1524)
				)
				(justify mirror)
			)
		)
		(duplicate_pad_numbers_are_jumpers no)
		(fp_rect
			(start 0.4318 0.9525)
			(end -0.4318 -0.9525)
			(stroke
				(width 0)
				(type default)
			)
			(fill no)
			(layer "B.CrtYd")
		)
		(fp_rect
			(start 0.4318 0.9525)
			(end -0.4318 -0.9525)
			(stroke
				(width 0)
				(type default)
			)
			(fill no)
			(layer "B.Fab")
		)
		(pad "1" smd custom
			(at 0 -0.4445 270)
			(size 0.1524 0.1524)
			(layers "B.Cu" "B.Mask" "B.Paste")
			(net "P5V_STBY")
			(options
				(clearance outline)
				(anchor circle)
			)
			(primitives
				(gr_poly
					(pts
						(arc
							(start 0.3048 0.2032)
							(mid 0.275042 0.275042)
							(end 0.2032 0.3048)
						)
						(arc
							(start -0.2032 0.3048)
							(mid -0.275042 0.275042)
							(end -0.3048 0.2032)
						)
						(arc
							(start -0.3048 -0.2032)
							(mid -0.275042 -0.275042)
							(end -0.2032 -0.3048)
						)
						(arc
							(start 0.2032 -0.3048)
							(mid 0.275042 -0.275042)
							(end 0.3048 -0.2032)
						)
					)
					(width 0)
					(fill yes)
				)
			)
		)
		(pad "2" smd custom
			(at 0 0.4445 270)
			(size 0.1524 0.1524)
			(layers "B.Cu" "B.Mask" "B.Paste")
			(net "GND")
			(options
				(clearance outline)
				(anchor circle)
			)
			(primitives
				(gr_poly
					(pts
						(arc
							(start 0.3048 0.2032)
							(mid 0.275042 0.275042)
							(end 0.2032 0.3048)
						)
						(arc
							(start -0.2032 0.3048)
							(mid -0.275042 0.275042)
							(end -0.3048 0.2032)
						)
						(arc
							(start -0.3048 -0.2032)
							(mid -0.275042 -0.275042)
							(end -0.2032 -0.3048)
						)
						(arc
							(start 0.2032 -0.3048)
							(mid 0.275042 -0.275042)
							(end 0.3048 -0.2032)
						)
					)
					(width 0)
					(fill yes)
				)
			)
		)
	)
	(footprint ""
		(layer "B.Cu")
		(at 443.46368 -58.01614 -90)
		(property "Reference" "R1W41"
			(at 0.8382 -0.67818 270)
			(unlocked yes)
			(layer "B.SilkS")
			(effects
				(font
					(size 0.4064 0.254)
					(thickness 0.1524)
				)
				(justify left mirror)
			)
		)
		(property "Value" ""
			(at 0 0 90)
			(layer "B.Fab")
			(effects
				(font
					(size 1.27 1.27)
				)
				(justify mirror)
			)
		)
		(duplicate_pad_numbers_are_jumpers no)
		(fp_poly
			(pts
				(xy 0.2794 -0.1016) (xy -0.2794 -0.1016) (xy -0.2794 0.9906) (xy 0.2794 0.9906)
			)
			(stroke
				(width 0)
				(type default)
			)
			(fill no)
			(layer "B.CrtYd")
		)
		(fp_line
			(start -0.2794 0.9906)
			(end -0.2794 -0.1016)
			(stroke
				(width 0.1)
				(type default)
			)
			(layer "B.Fab")
		)
		(fp_line
			(start 0.2794 0.9906)
			(end -0.2794 0.9906)
			(stroke
				(width 0.1)
				(type default)
			)
			(layer "B.Fab")
		)
		(fp_line
			(start -0.2794 -0.1016)
			(end 0.2794 -0.1016)
			(stroke
				(width 0.1)
				(type default)
			)
			(layer "B.Fab")
		)
		(fp_line
			(start 0.2794 -0.1016)
			(end 0.2794 0.9906)
			(stroke
				(width 0.1)
				(type default)
			)
			(layer "B.Fab")
		)
		(pad "1" smd rect
			(at 0 0 90)
			(size 0.508 0.508)
			(layers "B.Cu" "B.Mask" "B.Paste")
			(net "GND")
		)
		(pad "2" smd rect
			(at 0 0.889 90)
			(size 0.508 0.508)
			(layers "B.Cu" "B.Mask" "B.Paste")
			(net "EXT_MDIO_I2C_SEL")
		)
		(zone
			(layer "B.Cu")
			(hatch none 0.5)
			(connect_pads
				(clearance 0)
			)
			(min_thickness 0.25)
			(keepout
				(tracks not_allowed)
				(vias allowed)
				(pads allowed)
				(copperpour not_allowed)
				(footprints allowed)
			)
			(placement
				(enabled no)
				(sheetname "")
			)
			(fill
				(thermal_gap 0.5)
				(thermal_bridge_width 0.5)
				(island_removal_mode 0)
			)
			(polygon
				(pts
					(xy 442.82868 -57.76214) (xy 442.82868 -58.27014) (xy 443.20968 -58.27014) (xy 443.20968 -57.76214)
				)
			)
		)
		(zone
			(layer "B.Cu")
			(hatch none 0.5)
			(connect_pads
				(clearance 0)
			)
			(min_thickness 0.25)
			(keepout
				(tracks allowed)
				(vias not_allowed)
				(pads allowed)
				(copperpour not_allowed)
				(footprints allowed)
			)
			(placement
				(enabled no)
				(sheetname "")
			)
			(fill
				(thermal_gap 0.5)
				(thermal_bridge_width 0.5)
				(island_removal_mode 0)
			)
			(polygon
				(pts
					(xy 443.20968 -57.76214) (xy 443.20968 -58.27014) (xy 442.82868 -58.27014) (xy 442.82868 -57.76214)
				)
			)
		)
	)
	(footprint ""
		(layer "B.Cu")
		(at 427.4185 -21.082 90)
		(property "Reference" "R1U10"
			(at 0 0 90)
			(layer "B.SilkS")
			(hide yes)
			(effects
				(font
					(size 1.27 1.27)
				)
				(justify mirror)
			)
		)
		(property "Value" ""
			(at 0 0 90)
			(layer "B.Fab")
			(effects
				(font
					(size 1.27 1.27)
				)
				(justify mirror)
			)
		)
		(duplicate_pad_numbers_are_jumpers no)
		(fp_poly
			(pts
				(xy 0.2794 -0.1016) (xy -0.2794 -0.1016) (xy -0.2794 0.9906) (xy 0.2794 0.9906)
			)
			(stroke
				(width 0)
				(type default)
			)
			(fill no)
			(layer "B.CrtYd")
		)
		(fp_line
			(start 0.2794 -0.1016)
			(end 0.2794 0.9906)
			(stroke
				(width 0.1)
				(type default)
			)
			(layer "B.Fab")
		)
		(fp_line
			(start -0.2794 -0.1016)
			(end 0.2794 -0.1016)
			(stroke
				(width 0.1)
				(type default)
			)
			(layer "B.Fab")
		)
		(fp_line
			(start 0.2794 0.9906)
			(end -0.2794 0.9906)
			(stroke
				(width 0.1)
				(type default)
			)
			(layer "B.Fab")
		)
		(fp_line
			(start -0.2794 0.9906)
			(end -0.2794 -0.1016)
			(stroke
				(width 0.1)
				(type default)
			)
			(layer "B.Fab")
		)
		(pad "1" smd rect
			(at 0 0 270)
			(size 0.508 0.508)
			(layers "B.Cu" "B.Mask" "B.Paste")
			(net "SMB_SMLINK0_STBY_LVC3_SDA_R")
		)
		(pad "2" smd rect
			(at 0 0.889 270)
			(size 0.508 0.508)
			(layers "B.Cu" "B.Mask" "B.Paste")
			(net "SMB_SMLINK0_STBY_LVC3_SDA")
		)
		(zone
			(layer "B.Cu")
			(hatch none 0.5)
			(connect_pads
				(clearance 0)
			)
			(min_thickness 0.25)
			(keepout
				(tracks allowed)
				(vias not_allowed)
				(pads allowed)
				(copperpour not_allowed)
				(footprints allowed)
			)
			(placement
				(enabled no)
				(sheetname "")
			)
			(fill
				(thermal_gap 0.5)
				(thermal_bridge_width 0.5)
				(island_removal_mode 0)
			)
			(polygon
				(pts
					(xy 427.6725 -21.336) (xy 427.6725 -20.828) (xy 428.0535 -20.828) (xy 428.0535 -21.336)
				)
			)
		)
		(zone
			(layer "B.Cu")
			(hatch none 0.5)
			(connect_pads
				(clearance 0)
			)
			(min_thickness 0.25)
			(keepout
				(tracks not_allowed)
				(vias allowed)
				(pads allowed)
				(copperpour not_allowed)
				(footprints allowed)
			)
			(placement
				(enabled no)
				(sheetname "")
			)
			(fill
				(thermal_gap 0.5)
				(thermal_bridge_width 0.5)
				(island_removal_mode 0)
			)
			(polygon
				(pts
					(xy 428.0535 -21.336) (xy 428.0535 -20.828) (xy 427.6725 -20.828) (xy 427.6725 -21.336)
				)
			)
		)
	)
	(footprint ""
		(layer "B.Cu")
		(at 30.452568 1.524 90)
		(property "Reference" "C9U10"
			(at 0 0 90)
			(layer "B.SilkS")
			(hide yes)
			(effects
				(font
					(size 1.27 1.27)
				)
				(justify mirror)
			)
		)
		(property "Value" ""
			(at 0 0 90)
			(layer "B.Fab")
			(effects
				(font
					(size 1.27 1.27)
				)
				(justify mirror)
			)
		)
		(duplicate_pad_numbers_are_jumpers no)
		(fp_poly
			(pts
				(xy -0.3048 -0.1016) (xy -0.3048 0.9906) (xy 0.3048 0.9906) (xy 0.3048 -0.1016)
			)
			(stroke
				(width 0)
				(type default)
			)
			(fill no)
			(layer "B.CrtYd")
		)
		(fp_line
			(start 0.3048 -0.1016)
			(end 0.3048 0.9906)
			(stroke
				(width 0.1)
				(type default)
			)
			(layer "B.Fab")
		)
		(fp_line
			(start -0.3048 -0.1016)
			(end 0.3048 -0.1016)
			(stroke
				(width 0.1)
				(type default)
			)
			(layer "B.Fab")
		)
		(fp_line
			(start 0.3048 0.9906)
			(end -0.3048 0.9906)
			(stroke
				(width 0.1)
				(type default)
			)
			(layer "B.Fab")
		)
		(fp_line
			(start -0.3048 0.9906)
			(end -0.3048 -0.1016)
			(stroke
				(width 0.1)
				(type default)
			)
			(layer "B.Fab")
		)
		(pad "1" smd rect
			(at 0 0 270)
			(size 0.508 0.508)
			(layers "B.Cu" "B.Mask" "B.Paste")
			(net "M_J_VREF")
		)
		(pad "2" smd rect
			(at 0 0.889 270)
			(size 0.508 0.508)
			(layers "B.Cu" "B.Mask" "B.Paste")
			(net "GND")
		)
		(zone
			(layer "B.Cu")
			(hatch none 0.5)
			(connect_pads
				(clearance 0)
			)
			(min_thickness 0.25)
			(keepout
				(tracks allowed)
				(vias not_allowed)
				(pads allowed)
				(copperpour not_allowed)
				(footprints allowed)
			)
			(placement
				(enabled no)
				(sheetname "")
			)
			(fill
				(thermal_gap 0.5)
				(thermal_bridge_width 0.5)
				(island_removal_mode 0)
			)
			(polygon
				(pts
					(xy 30.706568 1.27) (xy 30.706568 1.778) (xy 31.087568 1.778) (xy 31.087568 1.27)
				)
			)
		)
		(zone
			(layer "B.Cu")
			(hatch none 0.5)
			(connect_pads
				(clearance 0)
			)
			(min_thickness 0.25)
			(keepout
				(tracks not_allowed)
				(vias allowed)
				(pads allowed)
				(copperpour not_allowed)
				(footprints allowed)
			)
			(placement
				(enabled no)
				(sheetname "")
			)
			(fill
				(thermal_gap 0.5)
				(thermal_bridge_width 0.5)
				(island_removal_mode 0)
			)
			(polygon
				(pts
					(xy 31.087568 1.27) (xy 31.087568 1.778) (xy 30.706568 1.778) (xy 30.706568 1.27)
				)
			)
		)
	)
	(footprint ""
		(layer "B.Cu")
		(at 390.135364 -84.713572 180)
		(property "Reference" "R2L6"
			(at 0 0 0)
			(layer "B.SilkS")
			(hide yes)
			(effects
				(font
					(size 1.27 1.27)
				)
				(justify mirror)
			)
		)
		(property "Value" ""
			(at 0 0 0)
			(layer "B.Fab")
			(effects
				(font
					(size 1.27 1.27)
				)
				(justify mirror)
			)
		)
		(duplicate_pad_numbers_are_jumpers no)
		(fp_poly
			(pts
				(xy 0.2794 -0.1016) (xy -0.2794 -0.1016) (xy -0.2794 0.9906) (xy 0.2794 0.9906)
			)
			(stroke
				(width 0)
				(type default)
			)
			(fill no)
			(layer "B.CrtYd")
		)
		(fp_line
			(start 0.2794 0.9906)
			(end -0.2794 0.9906)
			(stroke
				(width 0.1)
				(type default)
			)
			(layer "B.Fab")
		)
		(fp_line
			(start 0.2794 -0.1016)
			(end 0.2794 0.9906)
			(stroke
				(width 0.1)
				(type default)
			)
			(layer "B.Fab")
		)
		(fp_line
			(start -0.2794 0.9906)
			(end -0.2794 -0.1016)
			(stroke
				(width 0.1)
				(type default)
			)
			(layer "B.Fab")
		)
		(fp_line
			(start -0.2794 -0.1016)
			(end 0.2794 -0.1016)
			(stroke
				(width 0.1)
				(type default)
			)
			(layer "B.Fab")
		)
		(pad "1" smd rect
			(at 0 0)
			(size 0.508 0.508)
			(layers "B.Cu" "B.Mask" "B.Paste")
			(net "P3V3_STBY")
		)
		(pad "2" smd rect
			(at 0 0.889)
			(size 0.508 0.508)
			(layers "B.Cu" "B.Mask" "B.Paste")
			(net "SGPIO_PCH_SSATA_CLOCK_R")
		)
		(zone
			(layer "B.Cu")
			(hatch none 0.5)
			(connect_pads
				(clearance 0)
			)
			(min_thickness 0.25)
			(keepout
				(tracks not_allowed)
				(vias allowed)
				(pads allowed)
				(copperpour not_allowed)
				(footprints allowed)
			)
			(placement
				(enabled no)
				(sheetname "")
			)
			(fill
				(thermal_gap 0.5)
				(thermal_bridge_width 0.5)
				(island_removal_mode 0)
			)
			(polygon
				(pts
					(xy 389.881364 -85.348572) (xy 390.389364 -85.348572) (xy 390.389364 -84.967572) (xy 389.881364 -84.967572)
				)
			)
		)
		(zone
			(layer "B.Cu")
			(hatch none 0.5)
			(connect_pads
				(clearance 0)
			)
			(min_thickness 0.25)
			(keepout
				(tracks allowed)
				(vias not_allowed)
				(pads allowed)
				(copperpour not_allowed)
				(footprints allowed)
			)
			(placement
				(enabled no)
				(sheetname "")
			)
			(fill
				(thermal_gap 0.5)
				(thermal_bridge_width 0.5)
				(island_removal_mode 0)
			)
			(polygon
				(pts
					(xy 389.881364 -84.967572) (xy 390.389364 -84.967572) (xy 390.389364 -85.348572) (xy 389.881364 -85.348572)
				)
			)
		)
	)
	(footprint ""
		(layer "B.Cu")
		(at 33.673796 -61.298582 90)
		(property "Reference" "C1E23"
			(at 0 0 90)
			(layer "B.SilkS")
			(hide yes)
			(effects
				(font
					(size 1.27 1.27)
				)
				(justify mirror)
			)
		)
		(property "Value" "*"
			(at -1.1811 -2.8194 90)
			(unlocked yes)
			(layer "B.Fab")
			(hide yes)
			(effects
				(font
					(size 1.27 1.016)
					(thickness 0.1524)
				)
				(justify mirror)
			)
		)
		(property "Device Type" "SC1U10V2KX-4-GP_SMD-BCG6-SC1U1A"
			(at -1.1811 -4.3434 90)
			(unlocked yes)
			(layer "B.Fab")
			(hide yes)
			(effects
				(font
					(size 1.27 1.016)
					(thickness 0.1524)
				)
				(justify mirror)
			)
		)
		(duplicate_pad_numbers_are_jumpers no)
		(fp_rect
			(start 0.4318 0.9525)
			(end -0.4318 -0.9525)
			(stroke
				(width 0)
				(type default)
			)
			(fill no)
			(layer "B.CrtYd")
		)
		(fp_rect
			(start 0.4318 0.9525)
			(end -0.4318 -0.9525)
			(stroke
				(width 0)
				(type default)
			)
			(fill no)
			(layer "B.Fab")
		)
		(pad "1" smd custom
			(at 0 -0.4445 270)
			(size 0.1524 0.1524)
			(layers "B.Cu" "B.Mask" "B.Paste")
			(net "P5V_STBY")
			(options
				(clearance outline)
				(anchor circle)
			)
			(primitives
				(gr_poly
					(pts
						(arc
							(start 0.3048 0.2032)
							(mid 0.275042 0.275042)
							(end 0.2032 0.3048)
						)
						(arc
							(start -0.2032 0.3048)
							(mid -0.275042 0.275042)
							(end -0.3048 0.2032)
						)
						(arc
							(start -0.3048 -0.2032)
							(mid -0.275042 -0.275042)
							(end -0.2032 -0.3048)
						)
						(arc
							(start 0.2032 -0.3048)
							(mid 0.275042 -0.275042)
							(end 0.3048 -0.2032)
						)
					)
					(width 0)
					(fill yes)
				)
			)
		)
		(pad "2" smd custom
			(at 0 0.4445 270)
			(size 0.1524 0.1524)
			(layers "B.Cu" "B.Mask" "B.Paste")
			(net "GND")
			(options
				(clearance outline)
				(anchor circle)
			)
			(primitives
				(gr_poly
					(pts
						(arc
							(start 0.3048 0.2032)
							(mid 0.275042 0.275042)
							(end 0.2032 0.3048)
						)
						(arc
							(start -0.2032 0.3048)
							(mid -0.275042 0.275042)
							(end -0.3048 0.2032)
						)
						(arc
							(start -0.3048 -0.2032)
							(mid -0.275042 -0.275042)
							(end -0.2032 -0.3048)
						)
						(arc
							(start 0.2032 -0.3048)
							(mid 0.275042 -0.275042)
							(end 0.3048 -0.2032)
						)
					)
					(width 0)
					(fill yes)
				)
			)
		)
	)
	(footprint ""
		(layer "B.Cu")
		(at 454.5838 -145.9738 -90)
		(property "Reference" "R9A14"
			(at 0 0 90)
			(layer "B.SilkS")
			(hide yes)
			(effects
				(font
					(size 1.27 1.27)
				)
				(justify mirror)
			)
		)
		(property "Value" ""
			(at 0 0 90)
			(layer "B.Fab")
			(effects
				(font
					(size 1.27 1.27)
				)
				(justify mirror)
			)
		)
		(duplicate_pad_numbers_are_jumpers no)
		(fp_poly
			(pts
				(xy 0.2794 -0.1016) (xy -0.2794 -0.1016) (xy -0.2794 0.9906) (xy 0.2794 0.9906)
			)
			(stroke
				(width 0)
				(type default)
			)
			(fill no)
			(layer "B.CrtYd")
		)
		(fp_line
			(start -0.2794 0.9906)
			(end -0.2794 -0.1016)
			(stroke
				(width 0.1)
				(type default)
			)
			(layer "B.Fab")
		)
		(fp_line
			(start 0.2794 0.9906)
			(end -0.2794 0.9906)
			(stroke
				(width 0.1)
				(type default)
			)
			(layer "B.Fab")
		)
		(fp_line
			(start -0.2794 -0.1016)
			(end 0.2794 -0.1016)
			(stroke
				(width 0.1)
				(type default)
			)
			(layer "B.Fab")
		)
		(fp_line
			(start 0.2794 -0.1016)
			(end 0.2794 0.9906)
			(stroke
				(width 0.1)
				(type default)
			)
			(layer "B.Fab")
		)
		(pad "1" smd rect
			(at 0 0 90)
			(size 0.508 0.508)
			(layers "B.Cu" "B.Mask" "B.Paste")
			(net "XDP_RST_CO_N")
		)
		(pad "2" smd rect
			(at 0 0.889 90)
			(size 0.508 0.508)
			(layers "B.Cu" "B.Mask" "B.Paste")
			(net "P3V3_STBY")
		)
		(zone
			(layer "B.Cu")
			(hatch none 0.5)
			(connect_pads
				(clearance 0)
			)
			(min_thickness 0.25)
			(keepout
				(tracks not_allowed)
				(vias allowed)
				(pads allowed)
				(copperpour not_allowed)
				(footprints allowed)
			)
			(placement
				(enabled no)
				(sheetname "")
			)
			(fill
				(thermal_gap 0.5)
				(thermal_bridge_width 0.5)
				(island_removal_mode 0)
			)
			(polygon
				(pts
					(xy 453.9488 -145.7198) (xy 453.9488 -146.2278) (xy 454.3298 -146.2278) (xy 454.3298 -145.7198)
				)
			)
		)
		(zone
			(layer "B.Cu")
			(hatch none 0.5)
			(connect_pads
				(clearance 0)
			)
			(min_thickness 0.25)
			(keepout
				(tracks allowed)
				(vias not_allowed)
				(pads allowed)
				(copperpour not_allowed)
				(footprints allowed)
			)
			(placement
				(enabled no)
				(sheetname "")
			)
			(fill
				(thermal_gap 0.5)
				(thermal_bridge_width 0.5)
				(island_removal_mode 0)
			)
			(polygon
				(pts
					(xy 454.3298 -145.7198) (xy 454.3298 -146.2278) (xy 453.9488 -146.2278) (xy 453.9488 -145.7198)
				)
			)
		)
	)
	(footprint ""
		(layer "B.Cu")
		(at 194.6402 -102.6668 180)
		(property "Reference" "R6N13"
			(at 0 0 0)
			(layer "B.SilkS")
			(hide yes)
			(effects
				(font
					(size 1.27 1.27)
				)
				(justify mirror)
			)
		)
		(property "Value" ""
			(at 0 0 0)
			(layer "B.Fab")
			(effects
				(font
					(size 1.27 1.27)
				)
				(justify mirror)
			)
		)
		(duplicate_pad_numbers_are_jumpers no)
		(fp_poly
			(pts
				(xy 0.2794 -0.1016) (xy -0.2794 -0.1016) (xy -0.2794 0.9906) (xy 0.2794 0.9906)
			)
			(stroke
				(width 0)
				(type default)
			)
			(fill no)
			(layer "B.CrtYd")
		)
		(fp_line
			(start 0.2794 0.9906)
			(end -0.2794 0.9906)
			(stroke
				(width 0.1)
				(type default)
			)
			(layer "B.Fab")
		)
		(fp_line
			(start 0.2794 -0.1016)
			(end 0.2794 0.9906)
			(stroke
				(width 0.1)
				(type default)
			)
			(layer "B.Fab")
		)
		(fp_line
			(start -0.2794 0.9906)
			(end -0.2794 -0.1016)
			(stroke
				(width 0.1)
				(type default)
			)
			(layer "B.Fab")
		)
		(fp_line
			(start -0.2794 -0.1016)
			(end 0.2794 -0.1016)
			(stroke
				(width 0.1)
				(type default)
			)
			(layer "B.Fab")
		)
		(pad "1" smd rect
			(at 0 0)
			(size 0.508 0.508)
			(layers "B.Cu" "B.Mask" "B.Paste")
			(net "GND")
		)
		(pad "2" smd rect
			(at 0 0.889)
			(size 0.508 0.508)
			(layers "B.Cu" "B.Mask" "B.Paste")
			(net "PD_PIROM_CPU0_ADDR1")
		)
		(zone
			(layer "B.Cu")
			(hatch none 0.5)
			(connect_pads
				(clearance 0)
			)
			(min_thickness 0.25)
			(keepout
				(tracks not_allowed)
				(vias allowed)
				(pads allowed)
				(copperpour not_allowed)
				(footprints allowed)
			)
			(placement
				(enabled no)
				(sheetname "")
			)
			(fill
				(thermal_gap 0.5)
				(thermal_bridge_width 0.5)
				(island_removal_mode 0)
			)
			(polygon
				(pts
					(xy 194.3862 -103.3018) (xy 194.8942 -103.3018) (xy 194.8942 -102.9208) (xy 194.3862 -102.9208)
				)
			)
		)
		(zone
			(layer "B.Cu")
			(hatch none 0.5)
			(connect_pads
				(clearance 0)
			)
			(min_thickness 0.25)
			(keepout
				(tracks allowed)
				(vias not_allowed)
				(pads allowed)
				(copperpour not_allowed)
				(footprints allowed)
			)
			(placement
				(enabled no)
				(sheetname "")
			)
			(fill
				(thermal_gap 0.5)
				(thermal_bridge_width 0.5)
				(island_removal_mode 0)
			)
			(polygon
				(pts
					(xy 194.3862 -102.9208) (xy 194.8942 -102.9208) (xy 194.8942 -103.3018) (xy 194.3862 -103.3018)
				)
			)
		)
	)
	(footprint ""
		(layer "B.Cu")
		(at 333.346806 -61.257434)
		(property "Reference" "C2U3"
			(at 0 0 0)
			(layer "B.SilkS")
			(hide yes)
			(effects
				(font
					(size 1.27 1.27)
				)
				(justify mirror)
			)
		)
		(property "Value" ""
			(at 0 0 0)
			(layer "B.Fab")
			(effects
				(font
					(size 1.27 1.27)
				)
				(justify mirror)
			)
		)
		(duplicate_pad_numbers_are_jumpers no)
		(fp_poly
			(pts
				(xy -0.3048 -0.1016) (xy -0.3048 0.9906) (xy 0.3048 0.9906) (xy 0.3048 -0.1016)
			)
			(stroke
				(width 0)
				(type default)
			)
			(fill no)
			(layer "B.CrtYd")
		)
		(fp_line
			(start -0.3048 -0.1016)
			(end 0.3048 -0.1016)
			(stroke
				(width 0.1)
				(type default)
			)
			(layer "B.Fab")
		)
		(fp_line
			(start -0.3048 0.9906)
			(end -0.3048 -0.1016)
			(stroke
				(width 0.1)
				(type default)
			)
			(layer "B.Fab")
		)
		(fp_line
			(start 0.3048 -0.1016)
			(end 0.3048 0.9906)
			(stroke
				(width 0.1)
				(type default)
			)
			(layer "B.Fab")
		)
		(fp_line
			(start 0.3048 0.9906)
			(end -0.3048 0.9906)
			(stroke
				(width 0.1)
				(type default)
			)
			(layer "B.Fab")
		)
		(pad "1" smd rect
			(at 0 0 180)
			(size 0.508 0.508)
			(layers "B.Cu" "B.Mask" "B.Paste")
			(net "P3E_CPU0_PE1_PCH_RXP<0>")
		)
		(pad "2" smd rect
			(at 0 0.889 180)
			(size 0.508 0.508)
			(layers "B.Cu" "B.Mask" "B.Paste")
			(net "P3E_CPU0_PE1_SS_RXP<0>")
		)
		(zone
			(layer "B.Cu")
			(hatch none 0.5)
			(connect_pads
				(clearance 0)
			)
			(min_thickness 0.25)
			(keepout
				(tracks allowed)
				(vias not_allowed)
				(pads allowed)
				(copperpour not_allowed)
				(footprints allowed)
			)
			(placement
				(enabled no)
				(sheetname "")
			)
			(fill
				(thermal_gap 0.5)
				(thermal_bridge_width 0.5)
				(island_removal_mode 0)
			)
			(polygon
				(pts
					(xy 333.600806 -61.003434) (xy 333.092806 -61.003434) (xy 333.092806 -60.622434) (xy 333.600806 -60.622434)
				)
			)
		)
		(zone
			(layer "B.Cu")
			(hatch none 0.5)
			(connect_pads
				(clearance 0)
			)
			(min_thickness 0.25)
			(keepout
				(tracks not_allowed)
				(vias allowed)
				(pads allowed)
				(copperpour not_allowed)
				(footprints allowed)
			)
			(placement
				(enabled no)
				(sheetname "")
			)
			(fill
				(thermal_gap 0.5)
				(thermal_bridge_width 0.5)
				(island_removal_mode 0)
			)
			(polygon
				(pts
					(xy 333.600806 -60.622434) (xy 333.092806 -60.622434) (xy 333.092806 -61.003434) (xy 333.600806 -61.003434)
				)
			)
		)
	)
	(footprint ""
		(layer "B.Cu")
		(at 410.679646 -25.790652 180)
		(property "Reference" "FB2T1"
			(at 0 0 0)
			(layer "B.SilkS")
			(hide yes)
			(effects
				(font
					(size 1.27 1.27)
				)
				(justify mirror)
			)
		)
		(property "Value" "*"
			(at -0.0254 -2.8829 180)
			(unlocked yes)
			(layer "B.Fab")
			(hide yes)
			(effects
				(font
					(size 1.27 1.016)
					(thickness 0.1524)
				)
				(justify mirror)
			)
		)
		(property "Device Type" "HCB1608KF-800T30-GP_DISCRET-G9A"
			(at -0.0254 -4.4069 180)
			(unlocked yes)
			(layer "B.Fab")
			(hide yes)
			(effects
				(font
					(size 1.27 1.016)
					(thickness 0.1524)
				)
				(justify mirror)
			)
		)
		(duplicate_pad_numbers_are_jumpers no)
		(fp_line
			(start -0.254 0)
			(end 0.254 0)
			(stroke
				(width 0.2032)
				(type default)
			)
			(layer "B.SilkS")
		)
		(fp_rect
			(start 0.5842 1.3335)
			(end -0.5842 -1.3335)
			(stroke
				(width 0)
				(type default)
			)
			(fill no)
			(layer "B.CrtYd")
		)
		(fp_rect
			(start 0.5842 1.3335)
			(end -0.5842 -1.3335)
			(stroke
				(width 0)
				(type default)
			)
			(fill no)
			(layer "B.Fab")
		)
		(pad "1" smd custom
			(at 0 -0.762)
			(size 0.2159 0.2159)
			(layers "B.Cu" "B.Mask" "B.Paste")
			(net "P3V3_STBY")
			(options
				(clearance outline)
				(anchor circle)
			)
			(primitives
				(gr_poly
					(pts
						(arc
							(start -0.3302 0.4318)
							(mid -0.402042 0.402042)
							(end -0.4318 0.3302)
						)
						(arc
							(start -0.4318 -0.3302)
							(mid -0.402042 -0.402042)
							(end -0.3302 -0.4318)
						)
						(arc
							(start 0.3302 -0.4318)
							(mid 0.402042 -0.402042)
							(end 0.4318 -0.3302)
						)
						(arc
							(start 0.4318 0.3302)
							(mid 0.402042 0.402042)
							(end 0.3302 0.4318)
						)
					)
					(width 0)
					(fill yes)
				)
			)
		)
		(pad "2" smd custom
			(at 0 0.762)
			(size 0.2159 0.2159)
			(layers "B.Cu" "B.Mask" "B.Paste")
			(net "VCC_VA_3V3")
			(options
				(clearance outline)
				(anchor circle)
			)
			(primitives
				(gr_poly
					(pts
						(arc
							(start -0.3302 0.4318)
							(mid -0.402042 0.402042)
							(end -0.4318 0.3302)
						)
						(arc
							(start -0.4318 -0.3302)
							(mid -0.402042 -0.402042)
							(end -0.3302 -0.4318)
						)
						(arc
							(start 0.3302 -0.4318)
							(mid 0.402042 -0.402042)
							(end 0.4318 -0.3302)
						)
						(arc
							(start 0.4318 0.3302)
							(mid 0.402042 0.402042)
							(end 0.3302 0.4318)
						)
					)
					(width 0)
					(fill yes)
				)
			)
		)
	)
	(footprint ""
		(layer "B.Cu")
		(at 355.349048 -86.312248 -90)
		(property "Reference" "C3P1"
			(at 0 0 90)
			(layer "B.SilkS")
			(hide yes)
			(effects
				(font
					(size 1.27 1.27)
				)
				(justify mirror)
			)
		)
		(property "Value" ""
			(at 0 0 90)
			(layer "B.Fab")
			(effects
				(font
					(size 1.27 1.27)
				)
				(justify mirror)
			)
		)
		(duplicate_pad_numbers_are_jumpers no)
		(fp_poly
			(pts
				(xy -0.3048 -0.1016) (xy -0.3048 0.9906) (xy 0.3048 0.9906) (xy 0.3048 -0.1016)
			)
			(stroke
				(width 0)
				(type default)
			)
			(fill no)
			(layer "B.CrtYd")
		)
		(fp_line
			(start -0.3048 0.9906)
			(end -0.3048 -0.1016)
			(stroke
				(width 0.1)
				(type default)
			)
			(layer "B.Fab")
		)
		(fp_line
			(start 0.3048 0.9906)
			(end -0.3048 0.9906)
			(stroke
				(width 0.1)
				(type default)
			)
			(layer "B.Fab")
		)
		(fp_line
			(start -0.3048 -0.1016)
			(end 0.3048 -0.1016)
			(stroke
				(width 0.1)
				(type default)
			)
			(layer "B.Fab")
		)
		(fp_line
			(start 0.3048 -0.1016)
			(end 0.3048 0.9906)
			(stroke
				(width 0.1)
				(type default)
			)
			(layer "B.Fab")
		)
		(pad "1" smd rect
			(at 0 0 90)
			(size 0.508 0.508)
			(layers "B.Cu" "B.Mask" "B.Paste")
			(net "VSENSE_PVCCIO_CPU0_SKT_VSEN")
		)
		(pad "2" smd rect
			(at 0 0.889 90)
			(size 0.508 0.508)
			(layers "B.Cu" "B.Mask" "B.Paste")
			(net "VSENSE_PVCCIO_CPU0_SKT_VRTN")
		)
		(zone
			(layer "B.Cu")
			(hatch none 0.5)
			(connect_pads
				(clearance 0)
			)
			(min_thickness 0.25)
			(keepout
				(tracks not_allowed)
				(vias allowed)
				(pads allowed)
				(copperpour not_allowed)
				(footprints allowed)
			)
			(placement
				(enabled no)
				(sheetname "")
			)
			(fill
				(thermal_gap 0.5)
				(thermal_bridge_width 0.5)
				(island_removal_mode 0)
			)
			(polygon
				(pts
					(xy 354.714048 -86.058248) (xy 354.714048 -86.566248) (xy 355.095048 -86.566248) (xy 355.095048 -86.058248)
				)
			)
		)
		(zone
			(layer "B.Cu")
			(hatch none 0.5)
			(connect_pads
				(clearance 0)
			)
			(min_thickness 0.25)
			(keepout
				(tracks allowed)
				(vias not_allowed)
				(pads allowed)
				(copperpour not_allowed)
				(footprints allowed)
			)
			(placement
				(enabled no)
				(sheetname "")
			)
			(fill
				(thermal_gap 0.5)
				(thermal_bridge_width 0.5)
				(island_removal_mode 0)
			)
			(polygon
				(pts
					(xy 355.095048 -86.058248) (xy 355.095048 -86.566248) (xy 354.714048 -86.566248) (xy 354.714048 -86.058248)
				)
			)
		)
	)
	(footprint ""
		(layer "B.Cu")
		(at 411.5308 -36.5506 90)
		(property "Reference" "C25W45"
			(at 0.8382 -0.67818 90)
			(unlocked yes)
			(layer "B.SilkS")
			(effects
				(font
					(size 0.4064 0.254)
					(thickness 0.1524)
				)
				(justify left mirror)
			)
		)
		(property "Value" ""
			(at 0 0 90)
			(layer "B.Fab")
			(effects
				(font
					(size 1.27 1.27)
				)
				(justify mirror)
			)
		)
		(duplicate_pad_numbers_are_jumpers no)
		(fp_poly
			(pts
				(xy -0.3048 -0.1016) (xy -0.3048 0.9906) (xy 0.3048 0.9906) (xy 0.3048 -0.1016)
			)
			(stroke
				(width 0)
				(type default)
			)
			(fill no)
			(layer "B.CrtYd")
		)
		(fp_line
			(start 0.3048 -0.1016)
			(end 0.3048 0.9906)
			(stroke
				(width 0.1)
				(type default)
			)
			(layer "B.Fab")
		)
		(fp_line
			(start -0.3048 -0.1016)
			(end 0.3048 -0.1016)
			(stroke
				(width 0.1)
				(type default)
			)
			(layer "B.Fab")
		)
		(fp_line
			(start 0.3048 0.9906)
			(end -0.3048 0.9906)
			(stroke
				(width 0.1)
				(type default)
			)
			(layer "B.Fab")
		)
		(fp_line
			(start -0.3048 0.9906)
			(end -0.3048 -0.1016)
			(stroke
				(width 0.1)
				(type default)
			)
			(layer "B.Fab")
		)
		(pad "1" smd rect
			(at 0 0 270)
			(size 0.508 0.508)
			(layers "B.Cu" "B.Mask" "B.Paste")
			(net "VCC_D_3V3")
		)
		(pad "2" smd rect
			(at 0 0.889 270)
			(size 0.508 0.508)
			(layers "B.Cu" "B.Mask" "B.Paste")
			(net "GND")
		)
		(zone
			(layer "B.Cu")
			(hatch none 0.5)
			(connect_pads
				(clearance 0)
			)
			(min_thickness 0.25)
			(keepout
				(tracks allowed)
				(vias not_allowed)
				(pads allowed)
				(copperpour not_allowed)
				(footprints allowed)
			)
			(placement
				(enabled no)
				(sheetname "")
			)
			(fill
				(thermal_gap 0.5)
				(thermal_bridge_width 0.5)
				(island_removal_mode 0)
			)
			(polygon
				(pts
					(xy 411.7848 -36.8046) (xy 411.7848 -36.2966) (xy 412.1658 -36.2966) (xy 412.1658 -36.8046)
				)
			)
		)
		(zone
			(layer "B.Cu")
			(hatch none 0.5)
			(connect_pads
				(clearance 0)
			)
			(min_thickness 0.25)
			(keepout
				(tracks not_allowed)
				(vias allowed)
				(pads allowed)
				(copperpour not_allowed)
				(footprints allowed)
			)
			(placement
				(enabled no)
				(sheetname "")
			)
			(fill
				(thermal_gap 0.5)
				(thermal_bridge_width 0.5)
				(island_removal_mode 0)
			)
			(polygon
				(pts
					(xy 412.1658 -36.8046) (xy 412.1658 -36.2966) (xy 411.7848 -36.2966) (xy 411.7848 -36.8046)
				)
			)
		)
	)
	(footprint ""
		(layer "B.Cu")
		(at 490.15396 -150.18004 -90)
		(property "Reference" "R1L22"
			(at 0 0 90)
			(layer "B.SilkS")
			(hide yes)
			(effects
				(font
					(size 1.27 1.27)
				)
				(justify mirror)
			)
		)
		(property "Value" ""
			(at 0 0 90)
			(layer "B.Fab")
			(effects
				(font
					(size 1.27 1.27)
				)
				(justify mirror)
			)
		)
		(duplicate_pad_numbers_are_jumpers no)
		(fp_poly
			(pts
				(xy 0.2794 -0.1016) (xy -0.2794 -0.1016) (xy -0.2794 0.9906) (xy 0.2794 0.9906)
			)
			(stroke
				(width 0)
				(type default)
			)
			(fill no)
			(layer "B.CrtYd")
		)
		(fp_line
			(start -0.2794 0.9906)
			(end -0.2794 -0.1016)
			(stroke
				(width 0.1)
				(type default)
			)
			(layer "B.Fab")
		)
		(fp_line
			(start 0.2794 0.9906)
			(end -0.2794 0.9906)
			(stroke
				(width 0.1)
				(type default)
			)
			(layer "B.Fab")
		)
		(fp_line
			(start -0.2794 -0.1016)
			(end 0.2794 -0.1016)
			(stroke
				(width 0.1)
				(type default)
			)
			(layer "B.Fab")
		)
		(fp_line
			(start 0.2794 -0.1016)
			(end 0.2794 0.9906)
			(stroke
				(width 0.1)
				(type default)
			)
			(layer "B.Fab")
		)
		(pad "1" smd rect
			(at 0 0 90)
			(size 0.508 0.508)
			(layers "B.Cu" "B.Mask" "B.Paste")
			(net "FM_DEBUG_RST_BTN_N")
		)
		(pad "2" smd rect
			(at 0 0.889 90)
			(size 0.508 0.508)
			(layers "B.Cu" "B.Mask" "B.Paste")
			(net "FP_RST_BTN_R_N")
		)
		(zone
			(layer "B.Cu")
			(hatch none 0.5)
			(connect_pads
				(clearance 0)
			)
			(min_thickness 0.25)
			(keepout
				(tracks not_allowed)
				(vias allowed)
				(pads allowed)
				(copperpour not_allowed)
				(footprints allowed)
			)
			(placement
				(enabled no)
				(sheetname "")
			)
			(fill
				(thermal_gap 0.5)
				(thermal_bridge_width 0.5)
				(island_removal_mode 0)
			)
			(polygon
				(pts
					(xy 489.51896 -149.92604) (xy 489.51896 -150.43404) (xy 489.89996 -150.43404) (xy 489.89996 -149.92604)
				)
			)
		)
		(zone
			(layer "B.Cu")
			(hatch none 0.5)
			(connect_pads
				(clearance 0)
			)
			(min_thickness 0.25)
			(keepout
				(tracks allowed)
				(vias not_allowed)
				(pads allowed)
				(copperpour not_allowed)
				(footprints allowed)
			)
			(placement
				(enabled no)
				(sheetname "")
			)
			(fill
				(thermal_gap 0.5)
				(thermal_bridge_width 0.5)
				(island_removal_mode 0)
			)
			(polygon
				(pts
					(xy 489.89996 -149.92604) (xy 489.89996 -150.43404) (xy 489.51896 -150.43404) (xy 489.51896 -149.92604)
				)
			)
		)
	)
	(footprint ""
		(layer "B.Cu")
		(at 195.2244 -96.5708 90)
		(property "Reference" "CT58"
			(at 0.8382 -0.84963 90)
			(unlocked yes)
			(layer "B.SilkS")
			(effects
				(font
					(size 0.7874 0.5842)
					(thickness 0.1524)
				)
				(justify left mirror)
			)
		)
		(property "Value" ""
			(at 0 0 90)
			(layer "B.Fab")
			(effects
				(font
					(size 1.27 1.27)
				)
				(justify mirror)
			)
		)
		(duplicate_pad_numbers_are_jumpers no)
		(fp_poly
			(pts
				(xy -0.3048 -0.1016) (xy -0.3048 0.9906) (xy 0.3048 0.9906) (xy 0.3048 -0.1016)
			)
			(stroke
				(width 0)
				(type default)
			)
			(fill no)
			(layer "B.CrtYd")
		)
		(fp_line
			(start 0.3048 -0.1016)
			(end 0.3048 0.9906)
			(stroke
				(width 0.1)
				(type default)
			)
			(layer "B.Fab")
		)
		(fp_line
			(start -0.3048 -0.1016)
			(end 0.3048 -0.1016)
			(stroke
				(width 0.1)
				(type default)
			)
			(layer "B.Fab")
		)
		(fp_line
			(start 0.3048 0.9906)
			(end -0.3048 0.9906)
			(stroke
				(width 0.1)
				(type default)
			)
			(layer "B.Fab")
		)
		(fp_line
			(start -0.3048 0.9906)
			(end -0.3048 -0.1016)
			(stroke
				(width 0.1)
				(type default)
			)
			(layer "B.Fab")
		)
		(pad "1" smd rect
			(at 0 0 270)
			(size 0.508 0.508)
			(layers "B.Cu" "B.Mask" "B.Paste")
			(net "A_TSENSE_PVSA_CPU0")
		)
		(pad "2" smd rect
			(at 0 0.889 270)
			(size 0.508 0.508)
			(layers "B.Cu" "B.Mask" "B.Paste")
			(net "GND")
		)
		(zone
			(layer "B.Cu")
			(hatch none 0.5)
			(connect_pads
				(clearance 0)
			)
			(min_thickness 0.25)
			(keepout
				(tracks allowed)
				(vias not_allowed)
				(pads allowed)
				(copperpour not_allowed)
				(footprints allowed)
			)
			(placement
				(enabled no)
				(sheetname "")
			)
			(fill
				(thermal_gap 0.5)
				(thermal_bridge_width 0.5)
				(island_removal_mode 0)
			)
			(polygon
				(pts
					(xy 195.4784 -96.8248) (xy 195.4784 -96.3168) (xy 195.8594 -96.3168) (xy 195.8594 -96.8248)
				)
			)
		)
		(zone
			(layer "B.Cu")
			(hatch none 0.5)
			(connect_pads
				(clearance 0)
			)
			(min_thickness 0.25)
			(keepout
				(tracks not_allowed)
				(vias allowed)
				(pads allowed)
				(copperpour not_allowed)
				(footprints allowed)
			)
			(placement
				(enabled no)
				(sheetname "")
			)
			(fill
				(thermal_gap 0.5)
				(thermal_bridge_width 0.5)
				(island_removal_mode 0)
			)
			(polygon
				(pts
					(xy 195.8594 -96.8248) (xy 195.8594 -96.3168) (xy 195.4784 -96.3168) (xy 195.4784 -96.8248)
				)
			)
		)
	)
	(footprint ""
		(layer "B.Cu")
		(at 259.6642 -8.122412 90)
		(property "Reference" "C5U10"
			(at 0 0 90)
			(layer "B.SilkS")
			(hide yes)
			(effects
				(font
					(size 1.27 1.27)
				)
				(justify mirror)
			)
		)
		(property "Value" ""
			(at 0 0 90)
			(layer "B.Fab")
			(effects
				(font
					(size 1.27 1.27)
				)
				(justify mirror)
			)
		)
		(duplicate_pad_numbers_are_jumpers no)
		(fp_rect
			(start -0.7239 -0.2159)
			(end 0.7239 1.9939)
			(stroke
				(width 0)
				(type default)
			)
			(fill no)
			(layer "B.CrtYd")
		)
		(fp_line
			(start 0.7239 -0.2159)
			(end 0.7239 1.9939)
			(stroke
				(width 0.1)
				(type default)
			)
			(layer "B.Fab")
		)
		(fp_line
			(start -0.7239 -0.2159)
			(end 0.7239 -0.2159)
			(stroke
				(width 0.1)
				(type default)
			)
			(layer "B.Fab")
		)
		(fp_line
			(start 0.7239 1.9939)
			(end -0.7239 1.9939)
			(stroke
				(width 0.1)
				(type default)
			)
			(layer "B.Fab")
		)
		(fp_line
			(start -0.7239 1.9939)
			(end -0.7239 -0.2159)
			(stroke
				(width 0.1)
				(type default)
			)
			(layer "B.Fab")
		)
		(pad "1" smd rect
			(at 0 0 270)
			(size 1.27 1.016)
			(layers "B.Cu" "B.Mask" "B.Paste")
			(net "PVDDQ_ABC")
		)
		(pad "2" smd rect
			(at 0 1.778 270)
			(size 1.27 1.016)
			(layers "B.Cu" "B.Mask" "B.Paste")
			(net "GND")
		)
		(zone
			(layer "B.Cu")
			(hatch none 0.5)
			(connect_pads
				(clearance 0)
			)
			(min_thickness 0.25)
			(keepout
				(tracks not_allowed)
				(vias allowed)
				(pads allowed)
				(copperpour not_allowed)
				(footprints allowed)
			)
			(placement
				(enabled no)
				(sheetname "")
			)
			(fill
				(thermal_gap 0.5)
				(thermal_bridge_width 0.5)
				(island_removal_mode 0)
			)
			(polygon
				(pts
					(xy 260.1722 -7.487412) (xy 260.9342 -7.487412) (xy 260.9342 -8.757412) (xy 260.1722 -8.757412)
				)
			)
		)
	)
	(footprint ""
		(layer "B.Cu")
		(at 116.332 -76.454 90)
		(property "Reference" "R7P13"
			(at 0 0 90)
			(layer "B.SilkS")
			(hide yes)
			(effects
				(font
					(size 1.27 1.27)
				)
				(justify mirror)
			)
		)
		(property "Value" ""
			(at 0 0 90)
			(layer "B.Fab")
			(effects
				(font
					(size 1.27 1.27)
				)
				(justify mirror)
			)
		)
		(duplicate_pad_numbers_are_jumpers no)
		(fp_poly
			(pts
				(xy 0.2794 -0.1016) (xy -0.2794 -0.1016) (xy -0.2794 0.9906) (xy 0.2794 0.9906)
			)
			(stroke
				(width 0)
				(type default)
			)
			(fill no)
			(layer "B.CrtYd")
		)
		(fp_line
			(start 0.2794 -0.1016)
			(end 0.2794 0.9906)
			(stroke
				(width 0.1)
				(type default)
			)
			(layer "B.Fab")
		)
		(fp_line
			(start -0.2794 -0.1016)
			(end 0.2794 -0.1016)
			(stroke
				(width 0.1)
				(type default)
			)
			(layer "B.Fab")
		)
		(fp_line
			(start 0.2794 0.9906)
			(end -0.2794 0.9906)
			(stroke
				(width 0.1)
				(type default)
			)
			(layer "B.Fab")
		)
		(fp_line
			(start -0.2794 0.9906)
			(end -0.2794 -0.1016)
			(stroke
				(width 0.1)
				(type default)
			)
			(layer "B.Fab")
		)
		(pad "1" smd rect
			(at 0 0 270)
			(size 0.508 0.508)
			(layers "B.Cu" "B.Mask" "B.Paste")
			(net "GND")
		)
		(pad "2" smd rect
			(at 0 0.889 270)
			(size 0.508 0.508)
			(layers "B.Cu" "B.Mask" "B.Paste")
			(net "PD_CPU1_MCP01_DMON")
		)
		(zone
			(layer "B.Cu")
			(hatch none 0.5)
			(connect_pads
				(clearance 0)
			)
			(min_thickness 0.25)
			(keepout
				(tracks allowed)
				(vias not_allowed)
				(pads allowed)
				(copperpour not_allowed)
				(footprints allowed)
			)
			(placement
				(enabled no)
				(sheetname "")
			)
			(fill
				(thermal_gap 0.5)
				(thermal_bridge_width 0.5)
				(island_removal_mode 0)
			)
			(polygon
				(pts
					(xy 116.586 -76.708) (xy 116.586 -76.2) (xy 116.967 -76.2) (xy 116.967 -76.708)
				)
			)
		)
		(zone
			(layer "B.Cu")
			(hatch none 0.5)
			(connect_pads
				(clearance 0)
			)
			(min_thickness 0.25)
			(keepout
				(tracks not_allowed)
				(vias allowed)
				(pads allowed)
				(copperpour not_allowed)
				(footprints allowed)
			)
			(placement
				(enabled no)
				(sheetname "")
			)
			(fill
				(thermal_gap 0.5)
				(thermal_bridge_width 0.5)
				(island_removal_mode 0)
			)
			(polygon
				(pts
					(xy 116.967 -76.708) (xy 116.967 -76.2) (xy 116.586 -76.2) (xy 116.586 -76.708)
				)
			)
		)
	)
	(footprint ""
		(layer "B.Cu")
		(at 101.3968 -140.208 90)
		(property "Reference" "C5G106"
			(at -1.14681 0.76708 180)
			(unlocked yes)
			(layer "B.SilkS")
			(effects
				(font
					(size 0.7874 0.5842)
					(thickness 0.1524)
				)
				(justify mirror)
			)
		)
		(property "Value" ""
			(at 0 0 90)
			(layer "B.Fab")
			(effects
				(font
					(size 1.27 1.27)
				)
				(justify mirror)
			)
		)
		(duplicate_pad_numbers_are_jumpers no)
		(fp_rect
			(start -0.4953 -0.2032)
			(end 0.4953 1.6002)
			(stroke
				(width 0)
				(type default)
			)
			(fill no)
			(layer "B.CrtYd")
		)
		(fp_line
			(start 0.4953 -0.2032)
			(end -0.4953 -0.2032)
			(stroke
				(width 0.1)
				(type default)
			)
			(layer "B.Fab")
		)
		(fp_line
			(start -0.4953 -0.2032)
			(end -0.4953 1.6002)
			(stroke
				(width 0.1)
				(type default)
			)
			(layer "B.Fab")
		)
		(fp_line
			(start 0.4953 1.6002)
			(end 0.4953 -0.2032)
			(stroke
				(width 0.1)
				(type default)
			)
			(layer "B.Fab")
		)
		(fp_line
			(start -0.4953 1.6002)
			(end 0.4953 1.6002)
			(stroke
				(width 0.1)
				(type default)
			)
			(layer "B.Fab")
		)
		(pad "1" smd rect
			(at 0 0 270)
			(size 0.762 0.889)
			(layers "B.Cu" "B.Mask" "B.Paste")
			(net "PVDDQ_KLM")
		)
		(pad "2" smd rect
			(at 0 1.397 270)
			(size 0.762 0.889)
			(layers "B.Cu" "B.Mask" "B.Paste")
			(net "GND")
		)
		(zone
			(layer "B.Cu")
			(hatch none 0.5)
			(connect_pads
				(clearance 0)
			)
			(min_thickness 0.25)
			(keepout
				(tracks not_allowed)
				(vias allowed)
				(pads allowed)
				(copperpour not_allowed)
				(footprints allowed)
			)
			(placement
				(enabled no)
				(sheetname "")
			)
			(fill
				(thermal_gap 0.5)
				(thermal_bridge_width 0.5)
				(island_removal_mode 0)
			)
			(polygon
				(pts
					(xy 101.8413 -139.827) (xy 102.3493 -139.827) (xy 102.3493 -140.589) (xy 101.8413 -140.589)
				)
			)
		)
	)
	(footprint ""
		(layer "B.Cu")
		(at 268.073886 -79.60614 180)
		(property "Reference" "C5P14"
			(at 0 0 0)
			(layer "B.SilkS")
			(hide yes)
			(effects
				(font
					(size 1.27 1.27)
				)
				(justify mirror)
			)
		)
		(property "Value" ""
			(at 0 0 0)
			(layer "B.Fab")
			(effects
				(font
					(size 1.27 1.27)
				)
				(justify mirror)
			)
		)
		(duplicate_pad_numbers_are_jumpers no)
		(fp_poly
			(pts
				(xy 0.7239 -0.2159) (xy -0.7239 -0.2159) (xy -0.7239 1.9939) (xy 0.7239 1.9939)
			)
			(stroke
				(width 0)
				(type default)
			)
			(fill no)
			(layer "B.CrtYd")
		)
		(fp_line
			(start 0.7239 1.9939)
			(end -0.7239 1.9939)
			(stroke
				(width 0.1)
				(type default)
			)
			(layer "B.Fab")
		)
		(fp_line
			(start 0.7239 -0.2159)
			(end 0.7239 1.9939)
			(stroke
				(width 0.1)
				(type default)
			)
			(layer "B.Fab")
		)
		(fp_line
			(start -0.7239 1.9939)
			(end -0.7239 -0.2159)
			(stroke
				(width 0.1)
				(type default)
			)
			(layer "B.Fab")
		)
		(fp_line
			(start -0.7239 -0.2159)
			(end 0.7239 -0.2159)
			(stroke
				(width 0.1)
				(type default)
			)
			(layer "B.Fab")
		)
		(pad "1" smd rect
			(at 0 0)
			(size 1.27 1.016)
			(layers "B.Cu" "B.Mask" "B.Paste")
			(net "PVCCIN_CPU0")
		)
		(pad "2" smd rect
			(at 0 1.778)
			(size 1.27 1.016)
			(layers "B.Cu" "B.Mask" "B.Paste")
			(net "GND")
		)
		(zone
			(layer "B.Cu")
			(hatch none 0.5)
			(connect_pads
				(clearance 0)
			)
			(min_thickness 0.25)
			(keepout
				(tracks not_allowed)
				(vias allowed)
				(pads allowed)
				(copperpour not_allowed)
				(footprints allowed)
			)
			(placement
				(enabled no)
				(sheetname "")
			)
			(fill
				(thermal_gap 0.5)
				(thermal_bridge_width 0.5)
				(island_removal_mode 0)
			)
			(polygon
				(pts
					(xy 267.438886 -80.11414) (xy 268.708886 -80.11414) (xy 268.708886 -80.87614) (xy 267.438886 -80.87614)
				)
			)
		)
	)
	(footprint ""
		(layer "B.Cu")
		(at 165.1127 4.5212 180)
		(property "Reference" "C4G25"
			(at 0 0 0)
			(layer "B.SilkS")
			(hide yes)
			(effects
				(font
					(size 1.27 1.27)
				)
				(justify mirror)
			)
		)
		(property "Value" ""
			(at 0 0 0)
			(layer "B.Fab")
			(effects
				(font
					(size 1.27 1.27)
				)
				(justify mirror)
			)
		)
		(duplicate_pad_numbers_are_jumpers no)
		(fp_poly
			(pts
				(xy -0.3048 -0.1016) (xy -0.3048 0.9906) (xy 0.3048 0.9906) (xy 0.3048 -0.1016)
			)
			(stroke
				(width 0)
				(type default)
			)
			(fill no)
			(layer "B.CrtYd")
		)
		(fp_line
			(start 0.3048 0.9906)
			(end -0.3048 0.9906)
			(stroke
				(width 0.1)
				(type default)
			)
			(layer "B.Fab")
		)
		(fp_line
			(start 0.3048 -0.1016)
			(end 0.3048 0.9906)
			(stroke
				(width 0.1)
				(type default)
			)
			(layer "B.Fab")
		)
		(fp_line
			(start -0.3048 0.9906)
			(end -0.3048 -0.1016)
			(stroke
				(width 0.1)
				(type default)
			)
			(layer "B.Fab")
		)
		(fp_line
			(start -0.3048 -0.1016)
			(end 0.3048 -0.1016)
			(stroke
				(width 0.1)
				(type default)
			)
			(layer "B.Fab")
		)
		(pad "1" smd rect
			(at 0 0)
			(size 0.508 0.508)
			(layers "B.Cu" "B.Mask" "B.Paste")
			(net "PVPP_GHJ")
		)
		(pad "2" smd rect
			(at 0 0.889)
			(size 0.508 0.508)
			(layers "B.Cu" "B.Mask" "B.Paste")
			(net "GND")
		)
		(zone
			(layer "B.Cu")
			(hatch none 0.5)
			(connect_pads
				(clearance 0)
			)
			(min_thickness 0.25)
			(keepout
				(tracks not_allowed)
				(vias allowed)
				(pads allowed)
				(copperpour not_allowed)
				(footprints allowed)
			)
			(placement
				(enabled no)
				(sheetname "")
			)
			(fill
				(thermal_gap 0.5)
				(thermal_bridge_width 0.5)
				(island_removal_mode 0)
			)
			(polygon
				(pts
					(xy 164.8587 3.8862) (xy 165.3667 3.8862) (xy 165.3667 4.2672) (xy 164.8587 4.2672)
				)
			)
		)
		(zone
			(layer "B.Cu")
			(hatch none 0.5)
			(connect_pads
				(clearance 0)
			)
			(min_thickness 0.25)
			(keepout
				(tracks allowed)
				(vias not_allowed)
				(pads allowed)
				(copperpour not_allowed)
				(footprints allowed)
			)
			(placement
				(enabled no)
				(sheetname "")
			)
			(fill
				(thermal_gap 0.5)
				(thermal_bridge_width 0.5)
				(island_removal_mode 0)
			)
			(polygon
				(pts
					(xy 164.8587 4.2672) (xy 165.3667 4.2672) (xy 165.3667 3.8862) (xy 164.8587 3.8862)
				)
			)
		)
	)
	(footprint ""
		(layer "B.Cu")
		(at 265.8872 -124.6886 -90)
		(property "Reference" "R4L2"
			(at 0 0 90)
			(layer "B.SilkS")
			(hide yes)
			(effects
				(font
					(size 1.27 1.27)
				)
				(justify mirror)
			)
		)
		(property "Value" ""
			(at 0 0 90)
			(layer "B.Fab")
			(effects
				(font
					(size 1.27 1.27)
				)
				(justify mirror)
			)
		)
		(duplicate_pad_numbers_are_jumpers no)
		(fp_rect
			(start 0.2794 -0.1016)
			(end -0.2794 0.9906)
			(stroke
				(width 0)
				(type default)
			)
			(fill no)
			(layer "B.CrtYd")
		)
		(fp_line
			(start -0.2794 0.9906)
			(end -0.2794 -0.1016)
			(stroke
				(width 0.1)
				(type default)
			)
			(layer "B.Fab")
		)
		(fp_line
			(start 0.2794 0.9906)
			(end -0.2794 0.9906)
			(stroke
				(width 0.1)
				(type default)
			)
			(layer "B.Fab")
		)
		(fp_line
			(start -0.2794 -0.1016)
			(end 0.2794 -0.1016)
			(stroke
				(width 0.1)
				(type default)
			)
			(layer "B.Fab")
		)
		(fp_line
			(start 0.2794 -0.1016)
			(end 0.2794 0.9906)
			(stroke
				(width 0.1)
				(type default)
			)
			(layer "B.Fab")
		)
		(pad "1" smd rect
			(at 0 0 90)
			(size 0.508 0.508)
			(layers "B.Cu" "B.Mask" "B.Paste")
			(net "VSENSE_PVDDQ_DEF_P")
		)
		(pad "2" smd rect
			(at 0 0.889 90)
			(size 0.508 0.508)
			(layers "B.Cu" "B.Mask" "B.Paste")
			(net "VSENSE_PVDDQ_DEF_N")
		)
		(zone
			(layer "B.Cu")
			(hatch none 0.5)
			(connect_pads
				(clearance 0)
			)
			(min_thickness 0.25)
			(keepout
				(tracks allowed)
				(vias not_allowed)
				(pads allowed)
				(copperpour not_allowed)
				(footprints allowed)
			)
			(placement
				(enabled no)
				(sheetname "")
			)
			(fill
				(thermal_gap 0.5)
				(thermal_bridge_width 0.5)
				(island_removal_mode 0)
			)
			(polygon
				(pts
					(xy 265.6332 -124.4346) (xy 265.6332 -124.9426) (xy 265.2522 -124.9426) (xy 265.2522 -124.4346)
				)
			)
		)
	)
	(footprint ""
		(layer "B.Cu")
		(at 403.4282 -122.936 180)
		(property "Reference" "C2M7"
			(at 0 0 0)
			(layer "B.SilkS")
			(hide yes)
			(effects
				(font
					(size 1.27 1.27)
				)
				(justify mirror)
			)
		)
		(property "Value" ""
			(at 0 0 0)
			(layer "B.Fab")
			(effects
				(font
					(size 1.27 1.27)
				)
				(justify mirror)
			)
		)
		(duplicate_pad_numbers_are_jumpers no)
		(fp_poly
			(pts
				(xy -0.3048 -0.1016) (xy -0.3048 0.9906) (xy 0.3048 0.9906) (xy 0.3048 -0.1016)
			)
			(stroke
				(width 0)
				(type default)
			)
			(fill no)
			(layer "B.CrtYd")
		)
		(fp_line
			(start 0.3048 0.9906)
			(end -0.3048 0.9906)
			(stroke
				(width 0.1)
				(type default)
			)
			(layer "B.Fab")
		)
		(fp_line
			(start 0.3048 -0.1016)
			(end 0.3048 0.9906)
			(stroke
				(width 0.1)
				(type default)
			)
			(layer "B.Fab")
		)
		(fp_line
			(start -0.3048 0.9906)
			(end -0.3048 -0.1016)
			(stroke
				(width 0.1)
				(type default)
			)
			(layer "B.Fab")
		)
		(fp_line
			(start -0.3048 -0.1016)
			(end 0.3048 -0.1016)
			(stroke
				(width 0.1)
				(type default)
			)
			(layer "B.Fab")
		)
		(pad "1" smd rect
			(at 0 0)
			(size 0.508 0.508)
			(layers "B.Cu" "B.Mask" "B.Paste")
			(net "P1V05_PCH_STBY_WM20_PLL")
		)
		(pad "2" smd rect
			(at 0 0.889)
			(size 0.508 0.508)
			(layers "B.Cu" "B.Mask" "B.Paste")
			(net "GND")
		)
		(zone
			(layer "B.Cu")
			(hatch none 0.5)
			(connect_pads
				(clearance 0)
			)
			(min_thickness 0.25)
			(keepout
				(tracks not_allowed)
				(vias allowed)
				(pads allowed)
				(copperpour not_allowed)
				(footprints allowed)
			)
			(placement
				(enabled no)
				(sheetname "")
			)
			(fill
				(thermal_gap 0.5)
				(thermal_bridge_width 0.5)
				(island_removal_mode 0)
			)
			(polygon
				(pts
					(xy 403.1742 -123.571) (xy 403.6822 -123.571) (xy 403.6822 -123.19) (xy 403.1742 -123.19)
				)
			)
		)
		(zone
			(layer "B.Cu")
			(hatch none 0.5)
			(connect_pads
				(clearance 0)
			)
			(min_thickness 0.25)
			(keepout
				(tracks allowed)
				(vias not_allowed)
				(pads allowed)
				(copperpour not_allowed)
				(footprints allowed)
			)
			(placement
				(enabled no)
				(sheetname "")
			)
			(fill
				(thermal_gap 0.5)
				(thermal_bridge_width 0.5)
				(island_removal_mode 0)
			)
			(polygon
				(pts
					(xy 403.1742 -123.19) (xy 403.6822 -123.19) (xy 403.6822 -123.571) (xy 403.1742 -123.571)
				)
			)
		)
	)
	(footprint ""
		(layer "B.Cu")
		(at 83.856068 -3.3528 -90)
		(property "Reference" "C5G88"
			(at -1.14681 0.76708 0)
			(unlocked yes)
			(layer "B.SilkS")
			(effects
				(font
					(size 0.7874 0.5842)
					(thickness 0.1524)
				)
				(justify mirror)
			)
		)
		(property "Value" ""
			(at 0 0 90)
			(layer "B.Fab")
			(effects
				(font
					(size 1.27 1.27)
				)
				(justify mirror)
			)
		)
		(duplicate_pad_numbers_are_jumpers no)
		(fp_rect
			(start 0.4953 1.6002)
			(end -0.4953 -0.2032)
			(stroke
				(width 0)
				(type default)
			)
			(fill no)
			(layer "B.CrtYd")
		)
		(fp_line
			(start -0.4953 1.6002)
			(end 0.4953 1.6002)
			(stroke
				(width 0.1)
				(type default)
			)
			(layer "B.Fab")
		)
		(fp_line
			(start 0.4953 1.6002)
			(end 0.4953 -0.2032)
			(stroke
				(width 0.1)
				(type default)
			)
			(layer "B.Fab")
		)
		(fp_line
			(start -0.4953 -0.2032)
			(end -0.4953 1.6002)
			(stroke
				(width 0.1)
				(type default)
			)
			(layer "B.Fab")
		)
		(fp_line
			(start 0.4953 -0.2032)
			(end -0.4953 -0.2032)
			(stroke
				(width 0.1)
				(type default)
			)
			(layer "B.Fab")
		)
		(pad "1" smd rect
			(at 0 0 90)
			(size 0.762 0.889)
			(layers "B.Cu" "B.Mask" "B.Paste")
			(net "PVDDQ_GHJ")
		)
		(pad "2" smd rect
			(at 0 1.397 90)
			(size 0.762 0.889)
			(layers "B.Cu" "B.Mask" "B.Paste")
			(net "GND")
		)
		(zone
			(layer "B.Cu")
			(hatch none 0.5)
			(connect_pads
				(clearance 0)
			)
			(min_thickness 0.25)
			(keepout
				(tracks not_allowed)
				(vias allowed)
				(pads allowed)
				(copperpour not_allowed)
				(footprints allowed)
			)
			(placement
				(enabled no)
				(sheetname "")
			)
			(fill
				(thermal_gap 0.5)
				(thermal_bridge_width 0.5)
				(island_removal_mode 0)
			)
			(polygon
				(pts
					(xy 82.903568 -2.9718) (xy 83.411568 -2.9718) (xy 83.411568 -3.7338) (xy 82.903568 -3.7338)
				)
			)
		)
	)
	(footprint ""
		(layer "B.Cu")
		(at 93.241368 -17.6276 -90)
		(property "Reference" "C8T11"
			(at 0 0 90)
			(layer "B.SilkS")
			(hide yes)
			(effects
				(font
					(size 1.27 1.27)
				)
				(justify mirror)
			)
		)
		(property "Value" ""
			(at 0 0 90)
			(layer "B.Fab")
			(effects
				(font
					(size 1.27 1.27)
				)
				(justify mirror)
			)
		)
		(duplicate_pad_numbers_are_jumpers no)
		(fp_rect
			(start 0.500126 1.598422)
			(end -0.500126 -0.201422)
			(stroke
				(width 0)
				(type default)
			)
			(fill no)
			(layer "B.CrtYd")
		)
		(fp_line
			(start -0.500126 1.598422)
			(end 0.500126 1.598422)
			(stroke
				(width 0.1)
				(type default)
			)
			(layer "B.Fab")
		)
		(fp_line
			(start 0.500126 1.598422)
			(end 0.500126 -0.201422)
			(stroke
				(width 0.1)
				(type default)
			)
			(layer "B.Fab")
		)
		(fp_line
			(start -0.500126 -0.201422)
			(end -0.500126 1.598422)
			(stroke
				(width 0.1)
				(type default)
			)
			(layer "B.Fab")
		)
		(fp_line
			(start 0.500126 -0.201422)
			(end -0.500126 -0.201422)
			(stroke
				(width 0.1)
				(type default)
			)
			(layer "B.Fab")
		)
		(pad "1" smd rect
			(at 0 0 180)
			(size 0.889 0.9906)
			(layers "B.Cu" "B.Mask" "B.Paste")
			(net "PVDDQ_GHJ")
		)
		(pad "2" smd rect
			(at 0 1.397 180)
			(size 0.889 0.9906)
			(layers "B.Cu" "B.Mask" "B.Paste")
			(net "GND")
		)
		(zone
			(layer "B.Cu")
			(hatch none 0.5)
			(connect_pads
				(clearance 0)
			)
			(min_thickness 0.25)
			(keepout
				(tracks allowed)
				(vias not_allowed)
				(pads allowed)
				(copperpour not_allowed)
				(footprints allowed)
			)
			(placement
				(enabled no)
				(sheetname "")
			)
			(fill
				(thermal_gap 0.5)
				(thermal_bridge_width 0.5)
				(island_removal_mode 0)
			)
			(polygon
				(pts
					(xy 92.288868 -17.1323) (xy 92.796868 -17.1323) (xy 92.796868 -18.1229) (xy 92.288868 -18.1229)
				)
			)
		)
		(zone
			(layer "B.Cu")
			(hatch none 0.5)
			(connect_pads
				(clearance 0)
			)
			(min_thickness 0.25)
			(keepout
				(tracks not_allowed)
				(vias allowed)
				(pads allowed)
				(copperpour not_allowed)
				(footprints allowed)
			)
			(placement
				(enabled no)
				(sheetname "")
			)
			(fill
				(thermal_gap 0.5)
				(thermal_bridge_width 0.5)
				(island_removal_mode 0)
			)
			(polygon
				(pts
					(xy 92.288868 -17.1323) (xy 92.796868 -17.1323) (xy 92.796868 -18.1229) (xy 92.288868 -18.1229)
				)
			)
		)
	)
	(footprint ""
		(layer "B.Cu")
		(at 489.65739 -146.177 90)
		(property "Reference" "R1L18"
			(at 0 0 90)
			(layer "B.SilkS")
			(hide yes)
			(effects
				(font
					(size 1.27 1.27)
				)
				(justify mirror)
			)
		)
		(property "Value" ""
			(at 0 0 90)
			(layer "B.Fab")
			(effects
				(font
					(size 1.27 1.27)
				)
				(justify mirror)
			)
		)
		(duplicate_pad_numbers_are_jumpers no)
		(fp_poly
			(pts
				(xy 0.2794 -0.1016) (xy -0.2794 -0.1016) (xy -0.2794 0.9906) (xy 0.2794 0.9906)
			)
			(stroke
				(width 0)
				(type default)
			)
			(fill no)
			(layer "B.CrtYd")
		)
		(fp_line
			(start 0.2794 -0.1016)
			(end 0.2794 0.9906)
			(stroke
				(width 0.1)
				(type default)
			)
			(layer "B.Fab")
		)
		(fp_line
			(start -0.2794 -0.1016)
			(end 0.2794 -0.1016)
			(stroke
				(width 0.1)
				(type default)
			)
			(layer "B.Fab")
		)
		(fp_line
			(start 0.2794 0.9906)
			(end -0.2794 0.9906)
			(stroke
				(width 0.1)
				(type default)
			)
			(layer "B.Fab")
		)
		(fp_line
			(start -0.2794 0.9906)
			(end -0.2794 -0.1016)
			(stroke
				(width 0.1)
				(type default)
			)
			(layer "B.Fab")
		)
		(pad "1" smd rect
			(at 0 0 270)
			(size 0.508 0.508)
			(layers "B.Cu" "B.Mask" "B.Paste")
			(net "LED_POSTCODE_5")
		)
		(pad "2" smd rect
			(at 0 0.889 270)
			(size 0.508 0.508)
			(layers "B.Cu" "B.Mask" "B.Paste")
			(net "LED_POSTCODE_5_R")
		)
		(zone
			(layer "B.Cu")
			(hatch none 0.5)
			(connect_pads
				(clearance 0)
			)
			(min_thickness 0.25)
			(keepout
				(tracks allowed)
				(vias not_allowed)
				(pads allowed)
				(copperpour not_allowed)
				(footprints allowed)
			)
			(placement
				(enabled no)
				(sheetname "")
			)
			(fill
				(thermal_gap 0.5)
				(thermal_bridge_width 0.5)
				(island_removal_mode 0)
			)
			(polygon
				(pts
					(xy 489.91139 -146.431) (xy 489.91139 -145.923) (xy 490.29239 -145.923) (xy 490.29239 -146.431)
				)
			)
		)
		(zone
			(layer "B.Cu")
			(hatch none 0.5)
			(connect_pads
				(clearance 0)
			)
			(min_thickness 0.25)
			(keepout
				(tracks not_allowed)
				(vias allowed)
				(pads allowed)
				(copperpour not_allowed)
				(footprints allowed)
			)
			(placement
				(enabled no)
				(sheetname "")
			)
			(fill
				(thermal_gap 0.5)
				(thermal_bridge_width 0.5)
				(island_removal_mode 0)
			)
			(polygon
				(pts
					(xy 490.29239 -146.431) (xy 490.29239 -145.923) (xy 489.91139 -145.923) (xy 489.91139 -146.431)
				)
			)
		)
	)
	(footprint ""
		(layer "B.Cu")
		(at 381.7239 -84.6836 180)
		(property "Reference" "R3N30"
			(at 0.8382 -0.67818 180)
			(unlocked yes)
			(layer "B.SilkS")
			(effects
				(font
					(size 0.4064 0.254)
					(thickness 0.1524)
				)
				(justify left mirror)
			)
		)
		(property "Value" ""
			(at 0 0 0)
			(layer "B.Fab")
			(effects
				(font
					(size 1.27 1.27)
				)
				(justify mirror)
			)
		)
		(duplicate_pad_numbers_are_jumpers no)
		(fp_poly
			(pts
				(xy 0.2794 -0.1016) (xy -0.2794 -0.1016) (xy -0.2794 0.9906) (xy 0.2794 0.9906)
			)
			(stroke
				(width 0)
				(type default)
			)
			(fill no)
			(layer "B.CrtYd")
		)
		(fp_line
			(start 0.2794 0.9906)
			(end -0.2794 0.9906)
			(stroke
				(width 0.1)
				(type default)
			)
			(layer "B.Fab")
		)
		(fp_line
			(start 0.2794 -0.1016)
			(end 0.2794 0.9906)
			(stroke
				(width 0.1)
				(type default)
			)
			(layer "B.Fab")
		)
		(fp_line
			(start -0.2794 0.9906)
			(end -0.2794 -0.1016)
			(stroke
				(width 0.1)
				(type default)
			)
			(layer "B.Fab")
		)
		(fp_line
			(start -0.2794 -0.1016)
			(end 0.2794 -0.1016)
			(stroke
				(width 0.1)
				(type default)
			)
			(layer "B.Fab")
		)
		(pad "1" smd rect
			(at 0 0)
			(size 0.508 0.508)
			(layers "B.Cu" "B.Mask" "B.Paste")
			(net "H_CPU0_MEMABC_MEMHOT_LVT3_N")
		)
		(pad "2" smd rect
			(at 0 0.889)
			(size 0.508 0.508)
			(layers "B.Cu" "B.Mask" "B.Paste")
			(net "H_CPU0_MEMABC_MEMHOT_PCH_N")
		)
		(zone
			(layer "B.Cu")
			(hatch none 0.5)
			(connect_pads
				(clearance 0)
			)
			(min_thickness 0.25)
			(keepout
				(tracks not_allowed)
				(vias allowed)
				(pads allowed)
				(copperpour not_allowed)
				(footprints allowed)
			)
			(placement
				(enabled no)
				(sheetname "")
			)
			(fill
				(thermal_gap 0.5)
				(thermal_bridge_width 0.5)
				(island_removal_mode 0)
			)
			(polygon
				(pts
					(xy 381.4699 -85.3186) (xy 381.9779 -85.3186) (xy 381.9779 -84.9376) (xy 381.4699 -84.9376)
				)
			)
		)
		(zone
			(layer "B.Cu")
			(hatch none 0.5)
			(connect_pads
				(clearance 0)
			)
			(min_thickness 0.25)
			(keepout
				(tracks allowed)
				(vias not_allowed)
				(pads allowed)
				(copperpour not_allowed)
				(footprints allowed)
			)
			(placement
				(enabled no)
				(sheetname "")
			)
			(fill
				(thermal_gap 0.5)
				(thermal_bridge_width 0.5)
				(island_removal_mode 0)
			)
			(polygon
				(pts
					(xy 381.4699 -84.9376) (xy 381.9779 -84.9376) (xy 381.9779 -85.3186) (xy 381.4699 -85.3186)
				)
			)
		)
	)
	(footprint ""
		(layer "B.Cu")
		(at 403.391624 -32.801052)
		(property "Reference" "C25W35"
			(at 0.8382 -0.67818 0)
			(unlocked yes)
			(layer "B.SilkS")
			(effects
				(font
					(size 0.4064 0.254)
					(thickness 0.1524)
				)
				(justify left mirror)
			)
		)
		(property "Value" ""
			(at 0 0 0)
			(layer "B.Fab")
			(effects
				(font
					(size 1.27 1.27)
				)
				(justify mirror)
			)
		)
		(duplicate_pad_numbers_are_jumpers no)
		(fp_poly
			(pts
				(xy -0.3048 -0.1016) (xy -0.3048 0.9906) (xy 0.3048 0.9906) (xy 0.3048 -0.1016)
			)
			(stroke
				(width 0)
				(type default)
			)
			(fill no)
			(layer "B.CrtYd")
		)
		(fp_line
			(start -0.3048 -0.1016)
			(end 0.3048 -0.1016)
			(stroke
				(width 0.1)
				(type default)
			)
			(layer "B.Fab")
		)
		(fp_line
			(start -0.3048 0.9906)
			(end -0.3048 -0.1016)
			(stroke
				(width 0.1)
				(type default)
			)
			(layer "B.Fab")
		)
		(fp_line
			(start 0.3048 -0.1016)
			(end 0.3048 0.9906)
			(stroke
				(width 0.1)
				(type default)
			)
			(layer "B.Fab")
		)
		(fp_line
			(start 0.3048 0.9906)
			(end -0.3048 0.9906)
			(stroke
				(width 0.1)
				(type default)
			)
			(layer "B.Fab")
		)
		(pad "1" smd rect
			(at 0 0 180)
			(size 0.508 0.508)
			(layers "B.Cu" "B.Mask" "B.Paste")
			(net "VCC_DACAV3V3")
		)
		(pad "2" smd rect
			(at 0 0.889 180)
			(size 0.508 0.508)
			(layers "B.Cu" "B.Mask" "B.Paste")
			(net "GND")
		)
		(zone
			(layer "B.Cu")
			(hatch none 0.5)
			(connect_pads
				(clearance 0)
			)
			(min_thickness 0.25)
			(keepout
				(tracks allowed)
				(vias not_allowed)
				(pads allowed)
				(copperpour not_allowed)
				(footprints allowed)
			)
			(placement
				(enabled no)
				(sheetname "")
			)
			(fill
				(thermal_gap 0.5)
				(thermal_bridge_width 0.5)
				(island_removal_mode 0)
			)
			(polygon
				(pts
					(xy 403.645624 -32.547052) (xy 403.137624 -32.547052) (xy 403.137624 -32.166052) (xy 403.645624 -32.166052)
				)
			)
		)
		(zone
			(layer "B.Cu")
			(hatch none 0.5)
			(connect_pads
				(clearance 0)
			)
			(min_thickness 0.25)
			(keepout
				(tracks not_allowed)
				(vias allowed)
				(pads allowed)
				(copperpour not_allowed)
				(footprints allowed)
			)
			(placement
				(enabled no)
				(sheetname "")
			)
			(fill
				(thermal_gap 0.5)
				(thermal_bridge_width 0.5)
				(island_removal_mode 0)
			)
			(polygon
				(pts
					(xy 403.645624 -32.166052) (xy 403.137624 -32.166052) (xy 403.137624 -32.547052) (xy 403.645624 -32.547052)
				)
			)
		)
	)
	(footprint ""
		(layer "B.Cu")
		(at 280.735024 -80.096614 180)
		(property "Reference" "C4P1"
			(at 0 0 0)
			(layer "B.SilkS")
			(hide yes)
			(effects
				(font
					(size 1.27 1.27)
				)
				(justify mirror)
			)
		)
		(property "Value" ""
			(at 0 0 0)
			(layer "B.Fab")
			(effects
				(font
					(size 1.27 1.27)
				)
				(justify mirror)
			)
		)
		(duplicate_pad_numbers_are_jumpers no)
		(fp_poly
			(pts
				(xy 0.7239 -0.2159) (xy -0.7239 -0.2159) (xy -0.7239 1.9939) (xy 0.7239 1.9939)
			)
			(stroke
				(width 0)
				(type default)
			)
			(fill no)
			(layer "B.CrtYd")
		)
		(fp_line
			(start 0.7239 1.9939)
			(end -0.7239 1.9939)
			(stroke
				(width 0.1)
				(type default)
			)
			(layer "B.Fab")
		)
		(fp_line
			(start 0.7239 -0.2159)
			(end 0.7239 1.9939)
			(stroke
				(width 0.1)
				(type default)
			)
			(layer "B.Fab")
		)
		(fp_line
			(start -0.7239 1.9939)
			(end -0.7239 -0.2159)
			(stroke
				(width 0.1)
				(type default)
			)
			(layer "B.Fab")
		)
		(fp_line
			(start -0.7239 -0.2159)
			(end 0.7239 -0.2159)
			(stroke
				(width 0.1)
				(type default)
			)
			(layer "B.Fab")
		)
		(pad "1" smd rect
			(at 0 0)
			(size 1.27 1.016)
			(layers "B.Cu" "B.Mask" "B.Paste")
			(net "PVCCIO_CPU0")
		)
		(pad "2" smd rect
			(at 0 1.778)
			(size 1.27 1.016)
			(layers "B.Cu" "B.Mask" "B.Paste")
			(net "GND")
		)
		(zone
			(layer "B.Cu")
			(hatch none 0.5)
			(connect_pads
				(clearance 0)
			)
			(min_thickness 0.25)
			(keepout
				(tracks not_allowed)
				(vias allowed)
				(pads allowed)
				(copperpour not_allowed)
				(footprints allowed)
			)
			(placement
				(enabled no)
				(sheetname "")
			)
			(fill
				(thermal_gap 0.5)
				(thermal_bridge_width 0.5)
				(island_removal_mode 0)
			)
			(polygon
				(pts
					(xy 280.100024 -80.604614) (xy 281.370024 -80.604614) (xy 281.370024 -81.366614) (xy 280.100024 -81.366614)
				)
			)
		)
	)
	(footprint ""
		(layer "B.Cu")
		(at 456.7555 -135.0772 180)
		(property "Reference" "C1L19"
			(at 0 0 0)
			(layer "B.SilkS")
			(hide yes)
			(effects
				(font
					(size 1.27 1.27)
				)
				(justify mirror)
			)
		)
		(property "Value" ""
			(at 0 0 0)
			(layer "B.Fab")
			(effects
				(font
					(size 1.27 1.27)
				)
				(justify mirror)
			)
		)
		(duplicate_pad_numbers_are_jumpers no)
		(fp_poly
			(pts
				(xy -0.3048 -0.1016) (xy -0.3048 0.9906) (xy 0.3048 0.9906) (xy 0.3048 -0.1016)
			)
			(stroke
				(width 0)
				(type default)
			)
			(fill no)
			(layer "B.CrtYd")
		)
		(fp_line
			(start 0.3048 0.9906)
			(end -0.3048 0.9906)
			(stroke
				(width 0.1)
				(type default)
			)
			(layer "B.Fab")
		)
		(fp_line
			(start 0.3048 -0.1016)
			(end 0.3048 0.9906)
			(stroke
				(width 0.1)
				(type default)
			)
			(layer "B.Fab")
		)
		(fp_line
			(start -0.3048 0.9906)
			(end -0.3048 -0.1016)
			(stroke
				(width 0.1)
				(type default)
			)
			(layer "B.Fab")
		)
		(fp_line
			(start -0.3048 -0.1016)
			(end 0.3048 -0.1016)
			(stroke
				(width 0.1)
				(type default)
			)
			(layer "B.Fab")
		)
		(pad "1" smd rect
			(at 0 0)
			(size 0.508 0.508)
			(layers "B.Cu" "B.Mask" "B.Paste")
			(net "P3V3_STBY")
		)
		(pad "2" smd rect
			(at 0 0.889)
			(size 0.508 0.508)
			(layers "B.Cu" "B.Mask" "B.Paste")
			(net "GND")
		)
		(zone
			(layer "B.Cu")
			(hatch none 0.5)
			(connect_pads
				(clearance 0)
			)
			(min_thickness 0.25)
			(keepout
				(tracks not_allowed)
				(vias allowed)
				(pads allowed)
				(copperpour not_allowed)
				(footprints allowed)
			)
			(placement
				(enabled no)
				(sheetname "")
			)
			(fill
				(thermal_gap 0.5)
				(thermal_bridge_width 0.5)
				(island_removal_mode 0)
			)
			(polygon
				(pts
					(xy 456.5015 -135.7122) (xy 457.0095 -135.7122) (xy 457.0095 -135.3312) (xy 456.5015 -135.3312)
				)
			)
		)
		(zone
			(layer "B.Cu")
			(hatch none 0.5)
			(connect_pads
				(clearance 0)
			)
			(min_thickness 0.25)
			(keepout
				(tracks allowed)
				(vias not_allowed)
				(pads allowed)
				(copperpour not_allowed)
				(footprints allowed)
			)
			(placement
				(enabled no)
				(sheetname "")
			)
			(fill
				(thermal_gap 0.5)
				(thermal_bridge_width 0.5)
				(island_removal_mode 0)
			)
			(polygon
				(pts
					(xy 456.5015 -135.3312) (xy 457.0095 -135.3312) (xy 457.0095 -135.7122) (xy 456.5015 -135.7122)
				)
			)
		)
	)
	(footprint ""
		(layer "B.Cu")
		(at 330.581 -5.969)
		(property "Reference" "R4U4"
			(at 0 0 0)
			(layer "B.SilkS")
			(hide yes)
			(effects
				(font
					(size 1.27 1.27)
				)
				(justify mirror)
			)
		)
		(property "Value" ""
			(at 0 0 0)
			(layer "B.Fab")
			(effects
				(font
					(size 1.27 1.27)
				)
				(justify mirror)
			)
		)
		(duplicate_pad_numbers_are_jumpers no)
		(fp_poly
			(pts
				(xy 0.2794 -0.1016) (xy -0.2794 -0.1016) (xy -0.2794 0.9906) (xy 0.2794 0.9906)
			)
			(stroke
				(width 0)
				(type default)
			)
			(fill no)
			(layer "B.CrtYd")
		)
		(fp_line
			(start -0.2794 -0.1016)
			(end 0.2794 -0.1016)
			(stroke
				(width 0.1)
				(type default)
			)
			(layer "B.Fab")
		)
		(fp_line
			(start -0.2794 0.9906)
			(end -0.2794 -0.1016)
			(stroke
				(width 0.1)
				(type default)
			)
			(layer "B.Fab")
		)
		(fp_line
			(start 0.2794 -0.1016)
			(end 0.2794 0.9906)
			(stroke
				(width 0.1)
				(type default)
			)
			(layer "B.Fab")
		)
		(fp_line
			(start 0.2794 0.9906)
			(end -0.2794 0.9906)
			(stroke
				(width 0.1)
				(type default)
			)
			(layer "B.Fab")
		)
		(pad "1" smd rect
			(at 0 0 180)
			(size 0.508 0.508)
			(layers "B.Cu" "B.Mask" "B.Paste")
			(net "FM_DIMM_EVENT_FET")
		)
		(pad "2" smd rect
			(at 0 0.889 180)
			(size 0.508 0.508)
			(layers "B.Cu" "B.Mask" "B.Paste")
			(net "GND")
		)
		(zone
			(layer "B.Cu")
			(hatch none 0.5)
			(connect_pads
				(clearance 0)
			)
			(min_thickness 0.25)
			(keepout
				(tracks allowed)
				(vias not_allowed)
				(pads allowed)
				(copperpour not_allowed)
				(footprints allowed)
			)
			(placement
				(enabled no)
				(sheetname "")
			)
			(fill
				(thermal_gap 0.5)
				(thermal_bridge_width 0.5)
				(island_removal_mode 0)
			)
			(polygon
				(pts
					(xy 330.835 -5.715) (xy 330.327 -5.715) (xy 330.327 -5.334) (xy 330.835 -5.334)
				)
			)
		)
		(zone
			(layer "B.Cu")
			(hatch none 0.5)
			(connect_pads
				(clearance 0)
			)
			(min_thickness 0.25)
			(keepout
				(tracks not_allowed)
				(vias allowed)
				(pads allowed)
				(copperpour not_allowed)
				(footprints allowed)
			)
			(placement
				(enabled no)
				(sheetname "")
			)
			(fill
				(thermal_gap 0.5)
				(thermal_bridge_width 0.5)
				(island_removal_mode 0)
			)
			(polygon
				(pts
					(xy 330.835 -5.334) (xy 330.327 -5.334) (xy 330.327 -5.715) (xy 330.835 -5.715)
				)
			)
		)
	)
	(footprint ""
		(layer "B.Cu")
		(at 183.795416 -59.238896 180)
		(property "Reference" "C22W14"
			(at 0 0 0)
			(layer "B.SilkS")
			(hide yes)
			(effects
				(font
					(size 1.27 1.27)
				)
				(justify mirror)
			)
		)
		(property "Value" "*"
			(at 0.0762 -6.2357 180)
			(unlocked yes)
			(layer "B.Fab")
			(hide yes)
			(effects
				(font
					(size 1.27 1.016)
					(thickness 0.1524)
				)
				(justify mirror)
			)
		)
		(property "Device Type" "SC22U16V5MX-4-GP_SMD-BCG5-SC22A"
			(at 0.0762 -8.2677 180)
			(unlocked yes)
			(layer "B.Fab")
			(hide yes)
			(effects
				(font
					(size 1.27 1.016)
					(thickness 0.1524)
				)
				(justify mirror)
			)
		)
		(duplicate_pad_numbers_are_jumpers no)
		(fp_line
			(start -0.635 0)
			(end 0.635 0)
			(stroke
				(width 0.508)
				(type default)
			)
			(layer "B.SilkS")
		)
		(fp_rect
			(start 0.9652 1.778)
			(end -0.9652 -1.778)
			(stroke
				(width 0)
				(type default)
			)
			(fill no)
			(layer "B.CrtYd")
		)
		(fp_poly
			(pts
				(xy 0.9652 -1.778) (xy -0.9652 -1.778) (xy -0.9652 1.778) (xy 0.9652 1.778)
			)
			(stroke
				(width 0)
				(type default)
			)
			(fill no)
			(layer "B.Fab")
		)
		(pad "1" smd rect
			(at 0 -0.9652)
			(size 1.397 1.143)
			(layers "B.Cu" "B.Mask" "B.Paste")
			(net "VR_FET_SW_P12V_STBY_PVCCIN_CPU0")
		)
		(pad "2" smd rect
			(at 0 0.9652)
			(size 1.397 1.143)
			(layers "B.Cu" "B.Mask" "B.Paste")
			(net "GND")
		)
	)
	(footprint ""
		(layer "B.Cu")
		(at 18.0594 -154.5844 -90)
		(property "Reference" "C9L2"
			(at -2.99593 5.1054 0)
			(unlocked yes)
			(layer "B.SilkS")
			(effects
				(font
					(size 0.7874 0.5842)
					(thickness 0.1524)
				)
				(justify mirror)
			)
		)
		(property "Value" ""
			(at 0 0 90)
			(layer "B.Fab")
			(effects
				(font
					(size 1.27 1.27)
				)
				(justify mirror)
			)
		)
		(duplicate_pad_numbers_are_jumpers no)
		(fp_line
			(start -2.286 7.366)
			(end -1.600708 7.366)
			(stroke
				(width 0.1524)
				(type default)
			)
			(layer "B.SilkS")
		)
		(fp_line
			(start -2.286 7.366)
			(end -2.286 1.63195)
			(stroke
				(width 0.1524)
				(type default)
			)
			(layer "B.SilkS")
		)
		(fp_line
			(start 2.286 7.366)
			(end 1.60147 7.366)
			(stroke
				(width 0.1524)
				(type default)
			)
			(layer "B.SilkS")
		)
		(fp_line
			(start 2.286 7.366)
			(end 2.286 1.632712)
			(stroke
				(width 0.1524)
				(type default)
			)
			(layer "B.SilkS")
		)
		(fp_line
			(start -2.504948 1.633728)
			(end -1.6002 1.633728)
			(stroke
				(width 0.1524)
				(type default)
			)
			(layer "B.SilkS")
		)
		(fp_line
			(start 2.563114 1.633728)
			(end 1.6002 1.633728)
			(stroke
				(width 0.1524)
				(type default)
			)
			(layer "B.SilkS")
		)
		(fp_line
			(start -2.504948 -1.616456)
			(end -2.504948 1.633728)
			(stroke
				(width 0.1524)
				(type default)
			)
			(layer "B.SilkS")
		)
		(fp_line
			(start -1.6002 -1.616456)
			(end -2.504948 -1.616456)
			(stroke
				(width 0.1524)
				(type default)
			)
			(layer "B.SilkS")
		)
		(fp_line
			(start 1.6002 -1.616456)
			(end 2.563114 -1.616456)
			(stroke
				(width 0.1524)
				(type default)
			)
			(layer "B.SilkS")
		)
		(fp_line
			(start 2.563114 -1.616456)
			(end 2.563114 1.633728)
			(stroke
				(width 0.1524)
				(type default)
			)
			(layer "B.SilkS")
		)
		(fp_rect
			(start 2.286 -0.254)
			(end -2.286 7.366)
			(stroke
				(width 0)
				(type default)
			)
			(fill no)
			(layer "B.CrtYd")
		)
		(fp_line
			(start -2.286 7.366)
			(end 2.286 7.366)
			(stroke
				(width 0.1)
				(type default)
			)
			(layer "B.Fab")
		)
		(fp_line
			(start 2.286 7.366)
			(end 2.286 -0.254)
			(stroke
				(width 0.1)
				(type default)
			)
			(layer "B.Fab")
		)
		(fp_line
			(start -2.286 -0.254)
			(end -2.286 7.366)
			(stroke
				(width 0.1)
				(type default)
			)
			(layer "B.Fab")
		)
		(fp_line
			(start 2.286 -0.254)
			(end -2.286 -0.254)
			(stroke
				(width 0.1)
				(type default)
			)
			(layer "B.Fab")
		)
		(pad "1" smd rect
			(at 0 0 90)
			(size 2.54 3.048)
			(layers "B.Cu" "B.Mask" "B.Paste")
			(net "PVDDQ_KLM")
		)
		(pad "2" smd rect
			(at 0 7.112 90)
			(size 2.54 3.048)
			(layers "B.Cu" "B.Mask" "B.Paste")
			(net "GND")
		)
	)
	(footprint ""
		(layer "B.Cu")
		(at 394.35405 -157.226 -90)
		(property "Reference" "C2L2"
			(at 0 0 90)
			(layer "B.SilkS")
			(hide yes)
			(effects
				(font
					(size 1.27 1.27)
				)
				(justify mirror)
			)
		)
		(property "Value" ""
			(at 0 0 90)
			(layer "B.Fab")
			(effects
				(font
					(size 1.27 1.27)
				)
				(justify mirror)
			)
		)
		(duplicate_pad_numbers_are_jumpers no)
		(fp_poly
			(pts
				(xy -0.3048 -0.1016) (xy -0.3048 0.9906) (xy 0.3048 0.9906) (xy 0.3048 -0.1016)
			)
			(stroke
				(width 0)
				(type default)
			)
			(fill no)
			(layer "B.CrtYd")
		)
		(fp_line
			(start -0.3048 0.9906)
			(end -0.3048 -0.1016)
			(stroke
				(width 0.1)
				(type default)
			)
			(layer "B.Fab")
		)
		(fp_line
			(start 0.3048 0.9906)
			(end -0.3048 0.9906)
			(stroke
				(width 0.1)
				(type default)
			)
			(layer "B.Fab")
		)
		(fp_line
			(start -0.3048 -0.1016)
			(end 0.3048 -0.1016)
			(stroke
				(width 0.1)
				(type default)
			)
			(layer "B.Fab")
		)
		(fp_line
			(start 0.3048 -0.1016)
			(end 0.3048 0.9906)
			(stroke
				(width 0.1)
				(type default)
			)
			(layer "B.Fab")
		)
		(pad "1" smd rect
			(at 0 0 90)
			(size 0.508 0.508)
			(layers "B.Cu" "B.Mask" "B.Paste")
			(net "VR_P1V05_PCH_STBY_AVSP")
		)
		(pad "2" smd rect
			(at 0 0.889 90)
			(size 0.508 0.508)
			(layers "B.Cu" "B.Mask" "B.Paste")
			(net "VSENSE_P1V05_PCH_STBY_AVSN")
		)
		(zone
			(layer "B.Cu")
			(hatch none 0.5)
			(connect_pads
				(clearance 0)
			)
			(min_thickness 0.25)
			(keepout
				(tracks not_allowed)
				(vias allowed)
				(pads allowed)
				(copperpour not_allowed)
				(footprints allowed)
			)
			(placement
				(enabled no)
				(sheetname "")
			)
			(fill
				(thermal_gap 0.5)
				(thermal_bridge_width 0.5)
				(island_removal_mode 0)
			)
			(polygon
				(pts
					(xy 393.71905 -156.972) (xy 393.71905 -157.48) (xy 394.10005 -157.48) (xy 394.10005 -156.972)
				)
			)
		)
		(zone
			(layer "B.Cu")
			(hatch none 0.5)
			(connect_pads
				(clearance 0)
			)
			(min_thickness 0.25)
			(keepout
				(tracks allowed)
				(vias not_allowed)
				(pads allowed)
				(copperpour not_allowed)
				(footprints allowed)
			)
			(placement
				(enabled no)
				(sheetname "")
			)
			(fill
				(thermal_gap 0.5)
				(thermal_bridge_width 0.5)
				(island_removal_mode 0)
			)
			(polygon
				(pts
					(xy 394.10005 -156.972) (xy 394.10005 -157.48) (xy 393.71905 -157.48) (xy 393.71905 -156.972)
				)
			)
		)
	)
	(footprint ""
		(layer "B.Cu")
		(at 423.672 -21.59 90)
		(property "Reference" "R25W58"
			(at 0 0 90)
			(layer "B.SilkS")
			(hide yes)
			(effects
				(font
					(size 1.27 1.27)
				)
				(justify mirror)
			)
		)
		(property "Value" "*"
			(at -0.064008 -4.108196 90)
			(unlocked yes)
			(layer "B.Fab")
			(hide yes)
			(effects
				(font
					(size 1.27 1.016)
					(thickness 0.1524)
				)
				(justify mirror)
			)
		)
		(property "Device Type" "18KR2F-GP_RCL_GP-18KR2F-GP,64.A"
			(at -0.064008 -5.632196 90)
			(unlocked yes)
			(layer "B.Fab")
			(hide yes)
			(effects
				(font
					(size 1.27 1.016)
					(thickness 0.1524)
				)
				(justify mirror)
			)
		)
		(duplicate_pad_numbers_are_jumpers no)
		(fp_line
			(start 0.508 -0.9398)
			(end 0.508 0.9398)
			(stroke
				(width 0.1524)
				(type default)
			)
			(layer "B.SilkS")
		)
		(fp_line
			(start -0.508 -0.9398)
			(end 0.508 -0.9398)
			(stroke
				(width 0.1524)
				(type default)
			)
			(layer "B.SilkS")
		)
		(fp_rect
			(start 0.508 0.9398)
			(end -0.508 -0.9398)
			(stroke
				(width 0)
				(type default)
			)
			(fill no)
			(layer "B.CrtYd")
		)
		(fp_rect
			(start 0.508 0.9398)
			(end -0.508 -0.9398)
			(stroke
				(width 0)
				(type default)
			)
			(fill no)
			(layer "B.Fab")
		)
		(pad "1" smd custom
			(at 0 -0.4445 270)
			(size 0.1397 0.1397)
			(layers "B.Cu" "B.Mask" "B.Paste")
			(net "A_DACRSET")
			(options
				(clearance outline)
				(anchor circle)
			)
			(primitives
				(gr_poly
					(pts
						(arc
							(start -0.1778 0.2794)
							(mid -0.249642 0.249642)
							(end -0.2794 0.1778)
						)
						(arc
							(start -0.2794 -0.1778)
							(mid -0.249642 -0.249642)
							(end -0.1778 -0.2794)
						)
						(arc
							(start 0.1778 -0.2794)
							(mid 0.249642 -0.249642)
							(end 0.2794 -0.1778)
						)
						(arc
							(start 0.2794 0.1778)
							(mid 0.249642 0.249642)
							(end 0.1778 0.2794)
						)
					)
					(width 0)
					(fill yes)
				)
			)
		)
		(pad "2" smd custom
			(at 0 0.4445 270)
			(size 0.1397 0.1397)
			(layers "B.Cu" "B.Mask" "B.Paste")
			(net "GND")
			(options
				(clearance outline)
				(anchor circle)
			)
			(primitives
				(gr_poly
					(pts
						(arc
							(start -0.1778 0.2794)
							(mid -0.249642 0.249642)
							(end -0.2794 0.1778)
						)
						(arc
							(start -0.2794 -0.1778)
							(mid -0.249642 -0.249642)
							(end -0.1778 -0.2794)
						)
						(arc
							(start 0.1778 -0.2794)
							(mid 0.249642 -0.249642)
							(end 0.2794 -0.1778)
						)
						(arc
							(start 0.2794 0.1778)
							(mid 0.249642 0.249642)
							(end 0.1778 0.2794)
						)
					)
					(width 0)
					(fill yes)
				)
			)
		)
	)
	(footprint ""
		(layer "B.Cu")
		(at 107.8611 -140.208 90)
		(property "Reference" "C5G108"
			(at -1.14681 0.76708 180)
			(unlocked yes)
			(layer "B.SilkS")
			(effects
				(font
					(size 0.7874 0.5842)
					(thickness 0.1524)
				)
				(justify mirror)
			)
		)
		(property "Value" ""
			(at 0 0 90)
			(layer "B.Fab")
			(effects
				(font
					(size 1.27 1.27)
				)
				(justify mirror)
			)
		)
		(duplicate_pad_numbers_are_jumpers no)
		(fp_rect
			(start -0.4953 -0.2032)
			(end 0.4953 1.6002)
			(stroke
				(width 0)
				(type default)
			)
			(fill no)
			(layer "B.CrtYd")
		)
		(fp_line
			(start 0.4953 -0.2032)
			(end -0.4953 -0.2032)
			(stroke
				(width 0.1)
				(type default)
			)
			(layer "B.Fab")
		)
		(fp_line
			(start -0.4953 -0.2032)
			(end -0.4953 1.6002)
			(stroke
				(width 0.1)
				(type default)
			)
			(layer "B.Fab")
		)
		(fp_line
			(start 0.4953 1.6002)
			(end 0.4953 -0.2032)
			(stroke
				(width 0.1)
				(type default)
			)
			(layer "B.Fab")
		)
		(fp_line
			(start -0.4953 1.6002)
			(end 0.4953 1.6002)
			(stroke
				(width 0.1)
				(type default)
			)
			(layer "B.Fab")
		)
		(pad "1" smd rect
			(at 0 0 270)
			(size 0.762 0.889)
			(layers "B.Cu" "B.Mask" "B.Paste")
			(net "PVDDQ_KLM")
		)
		(pad "2" smd rect
			(at 0 1.397 270)
			(size 0.762 0.889)
			(layers "B.Cu" "B.Mask" "B.Paste")
			(net "GND")
		)
		(zone
			(layer "B.Cu")
			(hatch none 0.5)
			(connect_pads
				(clearance 0)
			)
			(min_thickness 0.25)
			(keepout
				(tracks not_allowed)
				(vias allowed)
				(pads allowed)
				(copperpour not_allowed)
				(footprints allowed)
			)
			(placement
				(enabled no)
				(sheetname "")
			)
			(fill
				(thermal_gap 0.5)
				(thermal_bridge_width 0.5)
				(island_removal_mode 0)
			)
			(polygon
				(pts
					(xy 108.3056 -139.827) (xy 108.8136 -139.827) (xy 108.8136 -140.589) (xy 108.3056 -140.589)
				)
			)
		)
	)
	(footprint ""
		(layer "B.Cu")
		(at 484.0732 -48.5267)
		(property "Reference" "C1R14"
			(at 0 0 0)
			(layer "B.SilkS")
			(hide yes)
			(effects
				(font
					(size 1.27 1.27)
				)
				(justify mirror)
			)
		)
		(property "Value" ""
			(at 0 0 0)
			(layer "B.Fab")
			(effects
				(font
					(size 1.27 1.27)
				)
				(justify mirror)
			)
		)
		(duplicate_pad_numbers_are_jumpers no)
		(fp_poly
			(pts
				(xy -0.3048 -0.1016) (xy -0.3048 0.9906) (xy 0.3048 0.9906) (xy 0.3048 -0.1016)
			)
			(stroke
				(width 0)
				(type default)
			)
			(fill no)
			(layer "B.CrtYd")
		)
		(fp_line
			(start -0.3048 -0.1016)
			(end 0.3048 -0.1016)
			(stroke
				(width 0.1)
				(type default)
			)
			(layer "B.Fab")
		)
		(fp_line
			(start -0.3048 0.9906)
			(end -0.3048 -0.1016)
			(stroke
				(width 0.1)
				(type default)
			)
			(layer "B.Fab")
		)
		(fp_line
			(start 0.3048 -0.1016)
			(end 0.3048 0.9906)
			(stroke
				(width 0.1)
				(type default)
			)
			(layer "B.Fab")
		)
		(fp_line
			(start 0.3048 0.9906)
			(end -0.3048 0.9906)
			(stroke
				(width 0.1)
				(type default)
			)
			(layer "B.Fab")
		)
		(pad "1" smd rect
			(at 0 0 180)
			(size 0.508 0.508)
			(layers "B.Cu" "B.Mask" "B.Paste")
			(net "P3V3_STBY")
		)
		(pad "2" smd rect
			(at 0 0.889 180)
			(size 0.508 0.508)
			(layers "B.Cu" "B.Mask" "B.Paste")
			(net "GND")
		)
		(zone
			(layer "B.Cu")
			(hatch none 0.5)
			(connect_pads
				(clearance 0)
			)
			(min_thickness 0.25)
			(keepout
				(tracks allowed)
				(vias not_allowed)
				(pads allowed)
				(copperpour not_allowed)
				(footprints allowed)
			)
			(placement
				(enabled no)
				(sheetname "")
			)
			(fill
				(thermal_gap 0.5)
				(thermal_bridge_width 0.5)
				(island_removal_mode 0)
			)
			(polygon
				(pts
					(xy 484.3272 -48.2727) (xy 483.8192 -48.2727) (xy 483.8192 -47.8917) (xy 484.3272 -47.8917)
				)
			)
		)
		(zone
			(layer "B.Cu")
			(hatch none 0.5)
			(connect_pads
				(clearance 0)
			)
			(min_thickness 0.25)
			(keepout
				(tracks not_allowed)
				(vias allowed)
				(pads allowed)
				(copperpour not_allowed)
				(footprints allowed)
			)
			(placement
				(enabled no)
				(sheetname "")
			)
			(fill
				(thermal_gap 0.5)
				(thermal_bridge_width 0.5)
				(island_removal_mode 0)
			)
			(polygon
				(pts
					(xy 484.3272 -47.8917) (xy 483.8192 -47.8917) (xy 483.8192 -48.2727) (xy 484.3272 -48.2727)
				)
			)
		)
	)
	(footprint ""
		(layer "B.Cu")
		(at 18.161 -45.72)
		(property "Reference" "C9R14"
			(at 0 0 0)
			(layer "B.SilkS")
			(hide yes)
			(effects
				(font
					(size 1.27 1.27)
				)
				(justify mirror)
			)
		)
		(property "Value" ""
			(at 0 0 0)
			(layer "B.Fab")
			(effects
				(font
					(size 1.27 1.27)
				)
				(justify mirror)
			)
		)
		(duplicate_pad_numbers_are_jumpers no)
		(fp_poly
			(pts
				(xy -0.3048 -0.1016) (xy -0.3048 0.9906) (xy 0.3048 0.9906) (xy 0.3048 -0.1016)
			)
			(stroke
				(width 0)
				(type default)
			)
			(fill no)
			(layer "B.CrtYd")
		)
		(fp_line
			(start -0.3048 -0.1016)
			(end 0.3048 -0.1016)
			(stroke
				(width 0.1)
				(type default)
			)
			(layer "B.Fab")
		)
		(fp_line
			(start -0.3048 0.9906)
			(end -0.3048 -0.1016)
			(stroke
				(width 0.1)
				(type default)
			)
			(layer "B.Fab")
		)
		(fp_line
			(start 0.3048 -0.1016)
			(end 0.3048 0.9906)
			(stroke
				(width 0.1)
				(type default)
			)
			(layer "B.Fab")
		)
		(fp_line
			(start 0.3048 0.9906)
			(end -0.3048 0.9906)
			(stroke
				(width 0.1)
				(type default)
			)
			(layer "B.Fab")
		)
		(pad "1" smd rect
			(at 0 0 180)
			(size 0.508 0.508)
			(layers "B.Cu" "B.Mask" "B.Paste")
			(net "P3V3_STBY")
		)
		(pad "2" smd rect
			(at 0 0.889 180)
			(size 0.508 0.508)
			(layers "B.Cu" "B.Mask" "B.Paste")
			(net "GND")
		)
		(zone
			(layer "B.Cu")
			(hatch none 0.5)
			(connect_pads
				(clearance 0)
			)
			(min_thickness 0.25)
			(keepout
				(tracks allowed)
				(vias not_allowed)
				(pads allowed)
				(copperpour not_allowed)
				(footprints allowed)
			)
			(placement
				(enabled no)
				(sheetname "")
			)
			(fill
				(thermal_gap 0.5)
				(thermal_bridge_width 0.5)
				(island_removal_mode 0)
			)
			(polygon
				(pts
					(xy 18.415 -45.466) (xy 17.907 -45.466) (xy 17.907 -45.085) (xy 18.415 -45.085)
				)
			)
		)
		(zone
			(layer "B.Cu")
			(hatch none 0.5)
			(connect_pads
				(clearance 0)
			)
			(min_thickness 0.25)
			(keepout
				(tracks not_allowed)
				(vias allowed)
				(pads allowed)
				(copperpour not_allowed)
				(footprints allowed)
			)
			(placement
				(enabled no)
				(sheetname "")
			)
			(fill
				(thermal_gap 0.5)
				(thermal_bridge_width 0.5)
				(island_removal_mode 0)
			)
			(polygon
				(pts
					(xy 18.415 -45.085) (xy 17.907 -45.085) (xy 17.907 -45.466) (xy 18.415 -45.466)
				)
			)
		)
	)
	(footprint ""
		(layer "B.Cu")
		(at 269.559532 -140.208 90)
		(property "Reference" "C5G74"
			(at -1.14681 0.76708 180)
			(unlocked yes)
			(layer "B.SilkS")
			(effects
				(font
					(size 0.7874 0.5842)
					(thickness 0.1524)
				)
				(justify mirror)
			)
		)
		(property "Value" ""
			(at 0 0 90)
			(layer "B.Fab")
			(effects
				(font
					(size 1.27 1.27)
				)
				(justify mirror)
			)
		)
		(duplicate_pad_numbers_are_jumpers no)
		(fp_rect
			(start -0.4953 -0.2032)
			(end 0.4953 1.6002)
			(stroke
				(width 0)
				(type default)
			)
			(fill no)
			(layer "B.CrtYd")
		)
		(fp_line
			(start 0.4953 -0.2032)
			(end -0.4953 -0.2032)
			(stroke
				(width 0.1)
				(type default)
			)
			(layer "B.Fab")
		)
		(fp_line
			(start -0.4953 -0.2032)
			(end -0.4953 1.6002)
			(stroke
				(width 0.1)
				(type default)
			)
			(layer "B.Fab")
		)
		(fp_line
			(start 0.4953 1.6002)
			(end 0.4953 -0.2032)
			(stroke
				(width 0.1)
				(type default)
			)
			(layer "B.Fab")
		)
		(fp_line
			(start -0.4953 1.6002)
			(end 0.4953 1.6002)
			(stroke
				(width 0.1)
				(type default)
			)
			(layer "B.Fab")
		)
		(pad "1" smd rect
			(at 0 0 270)
			(size 0.762 0.889)
			(layers "B.Cu" "B.Mask" "B.Paste")
			(net "PVDDQ_DEF")
		)
		(pad "2" smd rect
			(at 0 1.397 270)
			(size 0.762 0.889)
			(layers "B.Cu" "B.Mask" "B.Paste")
			(net "GND")
		)
		(zone
			(layer "B.Cu")
			(hatch none 0.5)
			(connect_pads
				(clearance 0)
			)
			(min_thickness 0.25)
			(keepout
				(tracks not_allowed)
				(vias allowed)
				(pads allowed)
				(copperpour not_allowed)
				(footprints allowed)
			)
			(placement
				(enabled no)
				(sheetname "")
			)
			(fill
				(thermal_gap 0.5)
				(thermal_bridge_width 0.5)
				(island_removal_mode 0)
			)
			(polygon
				(pts
					(xy 270.004032 -139.827) (xy 270.512032 -139.827) (xy 270.512032 -140.589) (xy 270.004032 -140.589)
				)
			)
		)
	)
	(footprint ""
		(layer "B.Cu")
		(at 276.000464 -3.3528 90)
		(property "Reference" "C5G56"
			(at -1.14681 0.76708 180)
			(unlocked yes)
			(layer "B.SilkS")
			(effects
				(font
					(size 0.7874 0.5842)
					(thickness 0.1524)
				)
				(justify mirror)
			)
		)
		(property "Value" ""
			(at 0 0 90)
			(layer "B.Fab")
			(effects
				(font
					(size 1.27 1.27)
				)
				(justify mirror)
			)
		)
		(duplicate_pad_numbers_are_jumpers no)
		(fp_rect
			(start -0.4953 -0.2032)
			(end 0.4953 1.6002)
			(stroke
				(width 0)
				(type default)
			)
			(fill no)
			(layer "B.CrtYd")
		)
		(fp_line
			(start 0.4953 -0.2032)
			(end -0.4953 -0.2032)
			(stroke
				(width 0.1)
				(type default)
			)
			(layer "B.Fab")
		)
		(fp_line
			(start -0.4953 -0.2032)
			(end -0.4953 1.6002)
			(stroke
				(width 0.1)
				(type default)
			)
			(layer "B.Fab")
		)
		(fp_line
			(start 0.4953 1.6002)
			(end 0.4953 -0.2032)
			(stroke
				(width 0.1)
				(type default)
			)
			(layer "B.Fab")
		)
		(fp_line
			(start -0.4953 1.6002)
			(end 0.4953 1.6002)
			(stroke
				(width 0.1)
				(type default)
			)
			(layer "B.Fab")
		)
		(pad "1" smd rect
			(at 0 0 270)
			(size 0.762 0.889)
			(layers "B.Cu" "B.Mask" "B.Paste")
			(net "PVDDQ_ABC")
		)
		(pad "2" smd rect
			(at 0 1.397 270)
			(size 0.762 0.889)
			(layers "B.Cu" "B.Mask" "B.Paste")
			(net "GND")
		)
		(zone
			(layer "B.Cu")
			(hatch none 0.5)
			(connect_pads
				(clearance 0)
			)
			(min_thickness 0.25)
			(keepout
				(tracks not_allowed)
				(vias allowed)
				(pads allowed)
				(copperpour not_allowed)
				(footprints allowed)
			)
			(placement
				(enabled no)
				(sheetname "")
			)
			(fill
				(thermal_gap 0.5)
				(thermal_bridge_width 0.5)
				(island_removal_mode 0)
			)
			(polygon
				(pts
					(xy 276.444964 -2.9718) (xy 276.952964 -2.9718) (xy 276.952964 -3.7338) (xy 276.444964 -3.7338)
				)
			)
		)
	)
	(footprint ""
		(layer "B.Cu")
		(at 13.921232 4.537456 90)
		(property "Reference" "R9U10"
			(at 0 0 90)
			(layer "B.SilkS")
			(hide yes)
			(effects
				(font
					(size 1.27 1.27)
				)
				(justify mirror)
			)
		)
		(property "Value" ""
			(at 0 0 90)
			(layer "B.Fab")
			(effects
				(font
					(size 1.27 1.27)
				)
				(justify mirror)
			)
		)
		(duplicate_pad_numbers_are_jumpers no)
		(fp_rect
			(start -0.2794 0.9906)
			(end 0.2794 -0.1016)
			(stroke
				(width 0)
				(type default)
			)
			(fill no)
			(layer "B.CrtYd")
		)
		(fp_line
			(start 0.2794 -0.1016)
			(end 0.2794 0.9906)
			(stroke
				(width 0.1)
				(type default)
			)
			(layer "B.Fab")
		)
		(fp_line
			(start -0.2794 -0.1016)
			(end 0.2794 -0.1016)
			(stroke
				(width 0.1)
				(type default)
			)
			(layer "B.Fab")
		)
		(fp_line
			(start 0.2794 0.9906)
			(end -0.2794 0.9906)
			(stroke
				(width 0.1)
				(type default)
			)
			(layer "B.Fab")
		)
		(fp_line
			(start -0.2794 0.9906)
			(end -0.2794 -0.1016)
			(stroke
				(width 0.1)
				(type default)
			)
			(layer "B.Fab")
		)
		(pad "1" smd rect
			(at 0 0 270)
			(size 0.508 0.508)
			(layers "B.Cu" "B.Mask" "B.Paste")
			(net "P3V3_STBY")
		)
		(pad "2" smd rect
			(at 0 0.889 270)
			(size 0.508 0.508)
			(layers "B.Cu" "B.Mask" "B.Paste")
			(net "VR_PVDDQ_GHJ_VDD")
		)
		(zone
			(layer "B.Cu")
			(hatch none 0.5)
			(connect_pads
				(clearance 0)
			)
			(min_thickness 0.25)
			(keepout
				(tracks allowed)
				(vias not_allowed)
				(pads allowed)
				(copperpour not_allowed)
				(footprints allowed)
			)
			(placement
				(enabled no)
				(sheetname "")
			)
			(fill
				(thermal_gap 0.5)
				(thermal_bridge_width 0.5)
				(island_removal_mode 0)
			)
			(polygon
				(pts
					(xy 14.556232 4.791456) (xy 14.556232 4.283456) (xy 14.175232 4.283456) (xy 14.175232 4.791456)
				)
			)
		)
		(zone
			(layer "B.Cu")
			(hatch none 0.5)
			(connect_pads
				(clearance 0)
			)
			(min_thickness 0.25)
			(keepout
				(tracks not_allowed)
				(vias allowed)
				(pads allowed)
				(copperpour not_allowed)
				(footprints allowed)
			)
			(placement
				(enabled no)
				(sheetname "")
			)
			(fill
				(thermal_gap 0.5)
				(thermal_bridge_width 0.5)
				(island_removal_mode 0)
			)
			(polygon
				(pts
					(xy 14.556232 4.791456) (xy 14.556232 4.283456) (xy 14.175232 4.283456) (xy 14.175232 4.791456)
				)
			)
		)
	)
	(footprint ""
		(layer "B.Cu")
		(at 445.2366 -128.7272 180)
		(property "Reference" "U2M1"
			(at -3.48742 -1.08331 0)
			(unlocked yes)
			(layer "B.SilkS")
			(effects
				(font
					(size 0.7874 0.5842)
					(thickness 0.1524)
				)
				(justify left mirror)
			)
		)
		(property "Value" ""
			(at 0 0 0)
			(layer "B.Fab")
			(effects
				(font
					(size 1.27 1.27)
				)
				(justify mirror)
			)
		)
		(duplicate_pad_numbers_are_jumpers no)
		(fp_circle
			(center 0.848614 -0.6477)
			(end 0.721614 -0.6477)
			(stroke
				(width 0.254)
				(type default)
			)
			(fill no)
			(layer "B.SilkS")
		)
		(fp_poly
			(pts
				(xy -0.21463 -0.450088) (xy -1.56337 -0.450088) (xy -1.56337 1.75006) (xy -0.21463 1.75006)
			)
			(stroke
				(width 0)
				(type default)
			)
			(fill no)
			(layer "B.CrtYd")
		)
		(fp_line
			(start -0.21463 1.75006)
			(end -0.21463 -0.450088)
			(stroke
				(width 0.1)
				(type default)
			)
			(layer "B.Fab")
		)
		(fp_line
			(start -0.21463 -0.450088)
			(end -1.56337 -0.450088)
			(stroke
				(width 0.1)
				(type default)
			)
			(layer "B.Fab")
		)
		(fp_line
			(start -1.56337 1.75006)
			(end -0.21463 1.75006)
			(stroke
				(width 0.1)
				(type default)
			)
			(layer "B.Fab")
		)
		(fp_line
			(start -1.56337 -0.450088)
			(end -1.56337 1.75006)
			(stroke
				(width 0.1)
				(type default)
			)
			(layer "B.Fab")
		)
		(fp_circle
			(center 0.848614 -0.6477)
			(end 0.721614 -0.6477)
			(stroke
				(width 0.254)
				(type default)
			)
			(fill no)
			(layer "B.Fab")
		)
		(pad "1" smd rect
			(at 0 0)
			(size 1.016 0.381)
			(layers "B.Cu" "B.Mask" "B.Paste")
			(net "JTAG_MCP_CPU0_TDI")
		)
		(pad "2" smd rect
			(at 0 0.649986)
			(size 1.016 0.381)
			(layers "B.Cu" "B.Mask" "B.Paste")
			(net "GND")
		)
		(pad "3" smd rect
			(at 0 1.299972)
			(size 1.016 0.381)
			(layers "B.Cu" "B.Mask" "B.Paste")
			(net "JTAG_MCP_CPU1_TDI")
		)
		(pad "4" smd rect
			(at -1.778 1.299972)
			(size 1.016 0.381)
			(layers "B.Cu" "B.Mask" "B.Paste")
			(net "JTAG_MCP_MUX_TDI")
		)
		(pad "5" smd rect
			(at -1.778 0.649986)
			(size 1.016 0.381)
			(layers "B.Cu" "B.Mask" "B.Paste")
			(net "P3V3_STBY")
		)
		(pad "6" smd rect
			(at -1.778 0)
			(size 1.016 0.381)
			(layers "B.Cu" "B.Mask" "B.Paste")
			(net "FM_CPU0_CD_PRES")
		)
	)
	(footprint ""
		(layer "B.Cu")
		(at 271.223486 -85.06714)
		(property "Reference" "C5P5"
			(at 0 0 0)
			(layer "B.SilkS")
			(hide yes)
			(effects
				(font
					(size 1.27 1.27)
				)
				(justify mirror)
			)
		)
		(property "Value" ""
			(at 0 0 0)
			(layer "B.Fab")
			(effects
				(font
					(size 1.27 1.27)
				)
				(justify mirror)
			)
		)
		(duplicate_pad_numbers_are_jumpers no)
		(fp_poly
			(pts
				(xy 0.7239 -0.2159) (xy -0.7239 -0.2159) (xy -0.7239 1.9939) (xy 0.7239 1.9939)
			)
			(stroke
				(width 0)
				(type default)
			)
			(fill no)
			(layer "B.CrtYd")
		)
		(fp_line
			(start -0.7239 -0.2159)
			(end 0.7239 -0.2159)
			(stroke
				(width 0.1)
				(type default)
			)
			(layer "B.Fab")
		)
		(fp_line
			(start -0.7239 1.9939)
			(end -0.7239 -0.2159)
			(stroke
				(width 0.1)
				(type default)
			)
			(layer "B.Fab")
		)
		(fp_line
			(start 0.7239 -0.2159)
			(end 0.7239 1.9939)
			(stroke
				(width 0.1)
				(type default)
			)
			(layer "B.Fab")
		)
		(fp_line
			(start 0.7239 1.9939)
			(end -0.7239 1.9939)
			(stroke
				(width 0.1)
				(type default)
			)
			(layer "B.Fab")
		)
		(pad "1" smd rect
			(at 0 0 180)
			(size 1.27 1.016)
			(layers "B.Cu" "B.Mask" "B.Paste")
			(net "PVDDQ_DEF")
		)
		(pad "2" smd rect
			(at 0 1.778 180)
			(size 1.27 1.016)
			(layers "B.Cu" "B.Mask" "B.Paste")
			(net "GND")
		)
		(zone
			(layer "B.Cu")
			(hatch none 0.5)
			(connect_pads
				(clearance 0)
			)
			(min_thickness 0.25)
			(keepout
				(tracks not_allowed)
				(vias allowed)
				(pads allowed)
				(copperpour not_allowed)
				(footprints allowed)
			)
			(placement
				(enabled no)
				(sheetname "")
			)
			(fill
				(thermal_gap 0.5)
				(thermal_bridge_width 0.5)
				(island_removal_mode 0)
			)
			(polygon
				(pts
					(xy 271.858486 -84.55914) (xy 270.588486 -84.55914) (xy 270.588486 -83.79714) (xy 271.858486 -83.79714)
				)
			)
		)
	)
	(footprint ""
		(layer "B.Cu")
		(at 392.6586 -104.6226 135)
		(property "Reference" "C2N19"
			(at 0 0 135)
			(layer "B.SilkS")
			(hide yes)
			(effects
				(font
					(size 1.27 1.27)
				)
				(justify mirror)
			)
		)
		(property "Value" ""
			(at 0 0 135)
			(layer "B.Fab")
			(effects
				(font
					(size 1.27 1.27)
				)
				(justify mirror)
			)
		)
		(duplicate_pad_numbers_are_jumpers no)
		(fp_poly
			(pts
				(xy -0.279514 0.91437) (xy -0.279514 -0.11433) (xy 0.279286 -0.114331) (xy 0.279286 0.91437)
			)
			(stroke
				(width 0)
				(type default)
			)
			(fill no)
			(layer "B.CrtYd")
		)
		(fp_line
			(start 0.279466 -0.114229)
			(end -0.279466 -0.114229)
			(stroke
				(width 0.1)
				(type default)
			)
			(layer "B.Fab")
		)
		(fp_line
			(start -0.279466 -0.114229)
			(end -0.279286 0.91437)
			(stroke
				(width 0.1)
				(type default)
			)
			(layer "B.Fab")
		)
		(fp_line
			(start 0.279286 0.91437)
			(end 0.279466 -0.114229)
			(stroke
				(width 0.1)
				(type default)
			)
			(layer "B.Fab")
		)
		(fp_line
			(start -0.279286 0.91437)
			(end 0.279286 0.91437)
			(stroke
				(width 0.1)
				(type default)
			)
			(layer "B.Fab")
		)
		(pad "1" smd custom
			(at 0 0 45)
			(size 0.10414 0.10414)
			(layers "B.Cu" "B.Mask" "B.Paste")
			(net "P3V3_STBY")
			(options
				(clearance outline)
				(anchor circle)
			)
			(primitives
				(gr_poly
					(pts
						(xy -0.20828 -0.08636) (xy -0.20828 0.08636) (xy -0.08636 0.20828) (xy 0.086614 0.20828) (xy 0.20828 0.086614)
						(xy 0.20828 -0.08636) (xy 0.08636 -0.20828) (xy -0.08636 -0.20828)
					)
					(width 0)
					(fill yes)
				)
			)
		)
		(pad "2" smd custom
			(at 0 0.8001 45)
			(size 0.10414 0.10414)
			(layers "B.Cu" "B.Mask" "B.Paste")
			(net "GND")
			(options
				(clearance outline)
				(anchor circle)
			)
			(primitives
				(gr_poly
					(pts
						(xy -0.20828 -0.08636) (xy -0.20828 0.08636) (xy -0.08636 0.20828) (xy 0.086614 0.20828) (xy 0.20828 0.086614)
						(xy 0.20828 -0.08636) (xy 0.08636 -0.20828) (xy -0.08636 -0.20828)
					)
					(width 0)
					(fill yes)
				)
			)
		)
		(zone
			(layer "B.Cu")
			(hatch none 0.5)
			(connect_pads
				(clearance 0)
			)
			(min_thickness 0.25)
			(keepout
				(tracks allowed)
				(vias not_allowed)
				(pads allowed)
				(copperpour not_allowed)
				(footprints allowed)
			)
			(placement
				(enabled no)
				(sheetname "")
			)
			(fill
				(thermal_gap 0.5)
				(thermal_bridge_width 0.5)
				(island_removal_mode 0)
			)
			(polygon
				(pts
					(xy 392.744706 -104.832658) (xy 393.0142 -105.102152) (xy 393.138152 -104.9782) (xy 392.868912 -104.708706)
				)
			)
		)
		(zone
			(layer "B.Cu")
			(hatch none 0.5)
			(connect_pads
				(clearance 0)
			)
			(min_thickness 0.25)
			(keepout
				(tracks not_allowed)
				(vias allowed)
				(pads allowed)
				(copperpour not_allowed)
				(footprints allowed)
			)
			(placement
				(enabled no)
				(sheetname "")
			)
			(fill
				(thermal_gap 0.5)
				(thermal_bridge_width 0.5)
				(island_removal_mode 0)
			)
			(polygon
				(pts
					(xy 392.744706 -104.832658) (xy 393.0142 -105.102152) (xy 393.138152 -104.9782) (xy 392.868912 -104.708706)
				)
			)
		)
	)
	(footprint ""
		(layer "B.Cu")
		(at 167.005 -15.24 90)
		(property "Reference" "C6U2"
			(at 0 0 90)
			(layer "B.SilkS")
			(hide yes)
			(effects
				(font
					(size 1.27 1.27)
				)
				(justify mirror)
			)
		)
		(property "Value" ""
			(at 0 0 90)
			(layer "B.Fab")
			(effects
				(font
					(size 1.27 1.27)
				)
				(justify mirror)
			)
		)
		(duplicate_pad_numbers_are_jumpers no)
		(fp_rect
			(start -0.7239 -0.2159)
			(end 0.7239 1.9939)
			(stroke
				(width 0)
				(type default)
			)
			(fill no)
			(layer "B.CrtYd")
		)
		(fp_line
			(start 0.7239 -0.2159)
			(end 0.7239 1.9939)
			(stroke
				(width 0.1)
				(type default)
			)
			(layer "B.Fab")
		)
		(fp_line
			(start -0.7239 -0.2159)
			(end 0.7239 -0.2159)
			(stroke
				(width 0.1)
				(type default)
			)
			(layer "B.Fab")
		)
		(fp_line
			(start 0.7239 1.9939)
			(end -0.7239 1.9939)
			(stroke
				(width 0.1)
				(type default)
			)
			(layer "B.Fab")
		)
		(fp_line
			(start -0.7239 1.9939)
			(end -0.7239 -0.2159)
			(stroke
				(width 0.1)
				(type default)
			)
			(layer "B.Fab")
		)
		(pad "1" smd rect
			(at 0 0 270)
			(size 1.27 1.016)
			(layers "B.Cu" "B.Mask" "B.Paste")
			(net "PVPP_GHJ")
		)
		(pad "2" smd rect
			(at 0 1.778 270)
			(size 1.27 1.016)
			(layers "B.Cu" "B.Mask" "B.Paste")
			(net "GND")
		)
		(zone
			(layer "B.Cu")
			(hatch none 0.5)
			(connect_pads
				(clearance 0)
			)
			(min_thickness 0.25)
			(keepout
				(tracks not_allowed)
				(vias allowed)
				(pads allowed)
				(copperpour not_allowed)
				(footprints allowed)
			)
			(placement
				(enabled no)
				(sheetname "")
			)
			(fill
				(thermal_gap 0.5)
				(thermal_bridge_width 0.5)
				(island_removal_mode 0)
			)
			(polygon
				(pts
					(xy 167.513 -14.605) (xy 168.275 -14.605) (xy 168.275 -15.875) (xy 167.513 -15.875)
				)
			)
		)
	)
	(footprint ""
		(layer "B.Cu")
		(at 245.7577 -17.7546 -90)
		(property "Reference" "C5T12"
			(at -1.848866 0.752348 270)
			(unlocked yes)
			(layer "B.SilkS")
			(effects
				(font
					(size 1.27 0.9652)
					(thickness 0.1524)
				)
				(justify mirror)
			)
		)
		(property "Value" ""
			(at 0 0 90)
			(layer "B.Fab")
			(effects
				(font
					(size 1.27 1.27)
				)
				(justify mirror)
			)
		)
		(duplicate_pad_numbers_are_jumpers no)
		(fp_rect
			(start 0.500126 1.598422)
			(end -0.500126 -0.201422)
			(stroke
				(width 0)
				(type default)
			)
			(fill no)
			(layer "B.CrtYd")
		)
		(fp_line
			(start -0.500126 1.598422)
			(end 0.500126 1.598422)
			(stroke
				(width 0.1)
				(type default)
			)
			(layer "B.Fab")
		)
		(fp_line
			(start 0.500126 1.598422)
			(end 0.500126 -0.201422)
			(stroke
				(width 0.1)
				(type default)
			)
			(layer "B.Fab")
		)
		(fp_line
			(start -0.500126 -0.201422)
			(end -0.500126 1.598422)
			(stroke
				(width 0.1)
				(type default)
			)
			(layer "B.Fab")
		)
		(fp_line
			(start 0.500126 -0.201422)
			(end -0.500126 -0.201422)
			(stroke
				(width 0.1)
				(type default)
			)
			(layer "B.Fab")
		)
		(pad "1" smd rect
			(at 0 0 180)
			(size 0.889 0.9906)
			(layers "B.Cu" "B.Mask" "B.Paste")
			(net "PVDDQ_ABC")
		)
		(pad "2" smd rect
			(at 0 1.397 180)
			(size 0.889 0.9906)
			(layers "B.Cu" "B.Mask" "B.Paste")
			(net "GND")
		)
		(zone
			(layer "B.Cu")
			(hatch none 0.5)
			(connect_pads
				(clearance 0)
			)
			(min_thickness 0.25)
			(keepout
				(tracks not_allowed)
				(vias allowed)
				(pads allowed)
				(copperpour not_allowed)
				(footprints allowed)
			)
			(placement
				(enabled no)
				(sheetname "")
			)
			(fill
				(thermal_gap 0.5)
				(thermal_bridge_width 0.5)
				(island_removal_mode 0)
			)
			(polygon
				(pts
					(xy 244.8052 -17.2593) (xy 245.3132 -17.2593) (xy 245.3132 -18.2499) (xy 244.8052 -18.2499)
				)
			)
		)
		(zone
			(layer "B.Cu")
			(hatch none 0.5)
			(connect_pads
				(clearance 0)
			)
			(min_thickness 0.25)
			(keepout
				(tracks allowed)
				(vias not_allowed)
				(pads allowed)
				(copperpour not_allowed)
				(footprints allowed)
			)
			(placement
				(enabled no)
				(sheetname "")
			)
			(fill
				(thermal_gap 0.5)
				(thermal_bridge_width 0.5)
				(island_removal_mode 0)
			)
			(polygon
				(pts
					(xy 244.8052 -17.2593) (xy 245.3132 -17.2593) (xy 245.3132 -18.2499) (xy 244.8052 -18.2499)
				)
			)
		)
	)
	(footprint ""
		(layer "B.Cu")
		(at 253.392432 -8.1534 90)
		(property "Reference" "C5U6"
			(at -1.848866 0.752348 90)
			(unlocked yes)
			(layer "B.SilkS")
			(effects
				(font
					(size 1.27 0.9652)
					(thickness 0.1524)
				)
				(justify mirror)
			)
		)
		(property "Value" ""
			(at 0 0 90)
			(layer "B.Fab")
			(effects
				(font
					(size 1.27 1.27)
				)
				(justify mirror)
			)
		)
		(duplicate_pad_numbers_are_jumpers no)
		(fp_rect
			(start 0.500126 1.598422)
			(end -0.500126 -0.201422)
			(stroke
				(width 0)
				(type default)
			)
			(fill no)
			(layer "B.CrtYd")
		)
		(fp_line
			(start 0.500126 -0.201422)
			(end -0.500126 -0.201422)
			(stroke
				(width 0.1)
				(type default)
			)
			(layer "B.Fab")
		)
		(fp_line
			(start -0.500126 -0.201422)
			(end -0.500126 1.598422)
			(stroke
				(width 0.1)
				(type default)
			)
			(layer "B.Fab")
		)
		(fp_line
			(start 0.500126 1.598422)
			(end 0.500126 -0.201422)
			(stroke
				(width 0.1)
				(type default)
			)
			(layer "B.Fab")
		)
		(fp_line
			(start -0.500126 1.598422)
			(end 0.500126 1.598422)
			(stroke
				(width 0.1)
				(type default)
			)
			(layer "B.Fab")
		)
		(pad "1" smd rect
			(at 0 0)
			(size 0.889 0.9906)
			(layers "B.Cu" "B.Mask" "B.Paste")
			(net "PVDDQ_ABC")
		)
		(pad "2" smd rect
			(at 0 1.397)
			(size 0.889 0.9906)
			(layers "B.Cu" "B.Mask" "B.Paste")
			(net "GND")
		)
		(zone
			(layer "B.Cu")
			(hatch none 0.5)
			(connect_pads
				(clearance 0)
			)
			(min_thickness 0.25)
			(keepout
				(tracks not_allowed)
				(vias allowed)
				(pads allowed)
				(copperpour not_allowed)
				(footprints allowed)
			)
			(placement
				(enabled no)
				(sheetname "")
			)
			(fill
				(thermal_gap 0.5)
				(thermal_bridge_width 0.5)
				(island_removal_mode 0)
			)
			(polygon
				(pts
					(xy 254.344932 -8.6487) (xy 253.836932 -8.6487) (xy 253.836932 -7.6581) (xy 254.344932 -7.6581)
				)
			)
		)
		(zone
			(layer "B.Cu")
			(hatch none 0.5)
			(connect_pads
				(clearance 0)
			)
			(min_thickness 0.25)
			(keepout
				(tracks allowed)
				(vias not_allowed)
				(pads allowed)
				(copperpour not_allowed)
				(footprints allowed)
			)
			(placement
				(enabled no)
				(sheetname "")
			)
			(fill
				(thermal_gap 0.5)
				(thermal_bridge_width 0.5)
				(island_removal_mode 0)
			)
			(polygon
				(pts
					(xy 254.344932 -8.6487) (xy 253.836932 -8.6487) (xy 253.836932 -7.6581) (xy 254.344932 -7.6581)
				)
			)
		)
	)
	(footprint ""
		(layer "B.Cu")
		(at 194.700398 -132.876036 90)
		(property "Reference" "J6M1"
			(at 2.352548 37.96411 0)
			(unlocked yes)
			(layer "B.SilkS")
			(effects
				(font
					(size 0.7874 0.5842)
					(thickness 0.1524)
				)
				(justify left mirror)
			)
		)
		(property "Value" ""
			(at 0 0 90)
			(layer "B.Fab")
			(effects
				(font
					(size 1.27 1.27)
				)
				(justify mirror)
			)
		)
		(duplicate_pad_numbers_are_jumpers no)
		(fp_line
			(start 0.94996 -7.675118)
			(end -5.5499 -7.675118)
			(stroke
				(width 0.1524)
				(type default)
			)
			(layer "B.SilkS")
		)
		(fp_line
			(start -5.5499 -7.675118)
			(end -5.5499 -1.480058)
			(stroke
				(width 0.1524)
				(type default)
			)
			(layer "B.SilkS")
		)
		(fp_line
			(start 0.94996 -1.480058)
			(end 0.94996 -7.675118)
			(stroke
				(width 0.1524)
				(type default)
			)
			(layer "B.SilkS")
		)
		(fp_line
			(start -5.5499 128.130046)
			(end -5.5499 134.325106)
			(stroke
				(width 0.1524)
				(type default)
			)
			(layer "B.SilkS")
		)
		(fp_line
			(start 0.94996 134.325106)
			(end 0.94996 128.130046)
			(stroke
				(width 0.1524)
				(type default)
			)
			(layer "B.SilkS")
		)
		(fp_line
			(start -5.5499 134.325106)
			(end 0.94996 134.325106)
			(stroke
				(width 0.1524)
				(type default)
			)
			(layer "B.SilkS")
		)
		(fp_poly
			(pts
				(xy 3.134868 -4.125214) (xy 3.134868 -3.109214) (xy 1.864868 -3.617214)
			)
			(stroke
				(width 0)
				(type default)
			)
			(fill yes)
			(layer "B.SilkS")
		)
		(fp_poly
			(pts
				(xy 0.94996 -7.675118) (xy 0.94996 134.325106) (xy -5.5499 134.325106) (xy -5.5499 -7.675118)
			)
			(stroke
				(width 0)
				(type default)
			)
			(fill no)
			(layer "B.CrtYd")
		)
		(fp_line
			(start 0.94996 -7.675118)
			(end -5.5499 -7.675118)
			(stroke
				(width 0.1)
				(type default)
			)
			(layer "B.Fab")
		)
		(fp_line
			(start -5.5499 -7.675118)
			(end -5.5499 134.325106)
			(stroke
				(width 0.1)
				(type default)
			)
			(layer "B.Fab")
		)
		(fp_line
			(start 0.94996 134.325106)
			(end 0.94996 -7.675118)
			(stroke
				(width 0.1)
				(type default)
			)
			(layer "B.Fab")
		)
		(fp_line
			(start -5.5499 134.325106)
			(end 0.94996 134.325106)
			(stroke
				(width 0.1)
				(type default)
			)
			(layer "B.Fab")
		)
		(fp_poly
			(pts
				(xy 2.984246 -0.461264) (xy 2.984246 0.554736) (xy 1.714246 0.046736)
			)
			(stroke
				(width 0)
				(type default)
			)
			(fill yes)
			(layer "B.Fab")
		)
		(fp_text user "145"
			(at -6.156452 1.13411 0)
			(unlocked yes)
			(layer "B.SilkS")
			(effects
				(font
					(size 0.7874 0.5842)
					(thickness 0.1524)
				)
				(justify left mirror)
			)
		)
		(fp_text user "77"
			(at 1.082548 66.66611 0)
			(unlocked yes)
			(layer "B.SilkS")
			(effects
				(font
					(size 0.7874 0.5842)
					(thickness 0.1524)
				)
				(justify left mirror)
			)
		)
		(fp_text user "222"
			(at -2.482088 66.983102 0)
			(unlocked yes)
			(layer "B.SilkS")
			(effects
				(font
					(size 0.7874 0.5842)
					(thickness 0.1524)
				)
				(justify left mirror)
			)
		)
		(fp_text user "221"
			(at -6.368288 68.126102 0)
			(unlocked yes)
			(layer "B.SilkS")
			(effects
				(font
					(size 0.7874 0.5842)
					(thickness 0.1524)
				)
				(justify left mirror)
			)
		)
		(fp_text user "78"
			(at 1.463548 71.11111 0)
			(unlocked yes)
			(layer "B.SilkS")
			(effects
				(font
					(size 0.7874 0.5842)
					(thickness 0.1524)
				)
				(justify left mirror)
			)
		)
		(fp_text user "144"
			(at 1.590548 129.91211 0)
			(unlocked yes)
			(layer "B.SilkS")
			(effects
				(font
					(size 0.7874 0.5842)
					(thickness 0.1524)
				)
				(justify left mirror)
			)
		)
		(fp_text user "288"
			(at -6.156452 130.67411 0)
			(unlocked yes)
			(layer "B.SilkS")
			(effects
				(font
					(size 0.7874 0.5842)
					(thickness 0.1524)
				)
				(justify left mirror)
			)
		)
		(fp_text user "145"
			(at -2.700782 -1.37922 90)
			(unlocked yes)
			(layer "B.Fab")
			(effects
				(font
					(size 0.7874 0.5842)
					(thickness 0.1524)
				)
				(justify left mirror)
			)
		)
		(fp_text user "77"
			(at 0.474218 65.93078 90)
			(unlocked yes)
			(layer "B.Fab")
			(effects
				(font
					(size 0.7874 0.5842)
					(thickness 0.1524)
				)
				(justify left mirror)
			)
		)
		(fp_text user "221"
			(at -3.335782 65.93078 90)
			(unlocked yes)
			(layer "B.Fab")
			(effects
				(font
					(size 0.7874 0.5842)
					(thickness 0.1524)
				)
				(justify left mirror)
			)
		)
		(fp_text user "222"
			(at -3.970782 69.10578 90)
			(unlocked yes)
			(layer "B.Fab")
			(effects
				(font
					(size 0.7874 0.5842)
					(thickness 0.1524)
				)
				(justify left mirror)
			)
		)
		(fp_text user "78"
			(at 0.474218 69.74078 90)
			(unlocked yes)
			(layer "B.Fab")
			(effects
				(font
					(size 0.7874 0.5842)
					(thickness 0.1524)
				)
				(justify left mirror)
			)
		)
		(fp_text user "144"
			(at 0.474218 128.16078 90)
			(unlocked yes)
			(layer "B.Fab")
			(effects
				(font
					(size 0.7874 0.5842)
					(thickness 0.1524)
				)
				(justify left mirror)
			)
		)
		(fp_text user "288"
			(at -3.335782 128.16078 90)
			(unlocked yes)
			(layer "B.Fab")
			(effects
				(font
					(size 0.7874 0.5842)
					(thickness 0.1524)
				)
				(justify left mirror)
			)
		)
		(pad "" thru_hole circle
			(at -2.29997 -5.649976 270)
			(size 2.8194 2.8194)
			(drill 2.4384)
			(layers "*.Cu" "*.Mask")
			(remove_unused_layers no)
			(clearance 0.127)
			(thermal_gap 0.127)
		)
		(pad "" thru_hole oval
			(at -2.29997 68.90004 270)
			(size 2.8194 1.5748)
			(drill oval 2.4384 1.1938)
			(layers "*.Cu" "*.Mask")
			(remove_unused_layers no)
			(clearance 0.127)
			(thermal_gap 0.127)
		)
		(pad "" thru_hole circle
			(at -2.29997 132.299964 270)
			(size 2.8194 2.8194)
			(drill 2.4384)
			(layers "*.Cu" "*.Mask")
			(remove_unused_layers no)
			(clearance 0.127)
			(thermal_gap 0.127)
		)
		(pad "1" smd rect
			(at 0 0 270)
			(size 1.8034 0.508)
			(layers "B.Cu" "B.Mask" "B.Paste")
			(net "P12V_NVDIMM_DEF")
		)
		(pad "2" smd rect
			(at 0 0.849884 270)
			(size 1.8034 0.508)
			(layers "B.Cu" "B.Mask" "B.Paste")
			(net "GND")
		)
		(pad "3" smd rect
			(at 0 1.700022 270)
			(size 1.8034 0.508)
			(layers "B.Cu" "B.Mask" "B.Paste")
			(net "M_D_DQ<4>")
		)
		(pad "4" smd rect
			(at 0 2.549906 270)
			(size 1.8034 0.508)
			(layers "B.Cu" "B.Mask" "B.Paste")
			(net "GND")
		)
		(pad "5" smd rect
			(at 0 3.400044 270)
			(size 1.8034 0.508)
			(layers "B.Cu" "B.Mask" "B.Paste")
			(net "M_D_DQ<0>")
		)
		(pad "6" smd rect
			(at 0 4.249928 270)
			(size 1.8034 0.508)
			(layers "B.Cu" "B.Mask" "B.Paste")
			(net "GND")
		)
		(pad "7" smd rect
			(at 0 5.100066 270)
			(size 1.8034 0.508)
			(layers "B.Cu" "B.Mask" "B.Paste")
			(net "M_D_DQS_DP<9>")
		)
		(pad "8" smd rect
			(at 0 5.94995 270)
			(size 1.8034 0.508)
			(layers "B.Cu" "B.Mask" "B.Paste")
			(net "M_D_DQS_DN<9>")
		)
		(pad "9" smd rect
			(at 0 6.800088 270)
			(size 1.8034 0.508)
			(layers "B.Cu" "B.Mask" "B.Paste")
			(net "GND")
		)
		(pad "10" smd rect
			(at 0 7.649972 270)
			(size 1.8034 0.508)
			(layers "B.Cu" "B.Mask" "B.Paste")
			(net "M_D_DQ<6>")
		)
		(pad "11" smd rect
			(at 0 8.50011 270)
			(size 1.8034 0.508)
			(layers "B.Cu" "B.Mask" "B.Paste")
			(net "GND")
		)
		(pad "12" smd rect
			(at 0 9.349994 270)
			(size 1.8034 0.508)
			(layers "B.Cu" "B.Mask" "B.Paste")
			(net "M_D_DQ<2>")
		)
		(pad "13" smd rect
			(at 0 10.199878 270)
			(size 1.8034 0.508)
			(layers "B.Cu" "B.Mask" "B.Paste")
			(net "GND")
		)
		(pad "14" smd rect
			(at 0 11.050016 270)
			(size 1.8034 0.508)
			(layers "B.Cu" "B.Mask" "B.Paste")
			(net "M_D_DQ<12>")
		)
		(pad "15" smd rect
			(at 0 11.8999 270)
			(size 1.8034 0.508)
			(layers "B.Cu" "B.Mask" "B.Paste")
			(net "GND")
		)
		(pad "16" smd rect
			(at 0 12.750038 270)
			(size 1.8034 0.508)
			(layers "B.Cu" "B.Mask" "B.Paste")
			(net "M_D_DQ<8>")
		)
		(pad "17" smd rect
			(at 0 13.599922 270)
			(size 1.8034 0.508)
			(layers "B.Cu" "B.Mask" "B.Paste")
			(net "GND")
		)
		(pad "18" smd rect
			(at 0 14.45006 270)
			(size 1.8034 0.508)
			(layers "B.Cu" "B.Mask" "B.Paste")
			(net "M_D_DQS_DP<10>")
		)
		(pad "19" smd rect
			(at 0 15.299944 270)
			(size 1.8034 0.508)
			(layers "B.Cu" "B.Mask" "B.Paste")
			(net "M_D_DQS_DN<10>")
		)
		(pad "20" smd rect
			(at 0 16.150082 270)
			(size 1.8034 0.508)
			(layers "B.Cu" "B.Mask" "B.Paste")
			(net "GND")
		)
		(pad "21" smd rect
			(at 0 16.999966 270)
			(size 1.8034 0.508)
			(layers "B.Cu" "B.Mask" "B.Paste")
			(net "M_D_DQ<14>")
		)
		(pad "22" smd rect
			(at 0 17.850104 270)
			(size 1.8034 0.508)
			(layers "B.Cu" "B.Mask" "B.Paste")
			(net "GND")
		)
		(pad "23" smd rect
			(at 0 18.699988 270)
			(size 1.8034 0.508)
			(layers "B.Cu" "B.Mask" "B.Paste")
			(net "M_D_DQ<10>")
		)
		(pad "24" smd rect
			(at 0 19.550126 270)
			(size 1.8034 0.508)
			(layers "B.Cu" "B.Mask" "B.Paste")
			(net "GND")
		)
		(pad "25" smd rect
			(at 0 20.40001 270)
			(size 1.8034 0.508)
			(layers "B.Cu" "B.Mask" "B.Paste")
			(net "M_D_DQ<20>")
		)
		(pad "26" smd rect
			(at 0 21.249894 270)
			(size 1.8034 0.508)
			(layers "B.Cu" "B.Mask" "B.Paste")
			(net "GND")
		)
		(pad "27" smd rect
			(at 0 22.100032 270)
			(size 1.8034 0.508)
			(layers "B.Cu" "B.Mask" "B.Paste")
			(net "M_D_DQ<16>")
		)
		(pad "28" smd rect
			(at 0 22.949916 270)
			(size 1.8034 0.508)
			(layers "B.Cu" "B.Mask" "B.Paste")
			(net "GND")
		)
		(pad "29" smd rect
			(at 0 23.800054 270)
			(size 1.8034 0.508)
			(layers "B.Cu" "B.Mask" "B.Paste")
			(net "M_D_DQS_DP<11>")
		)
		(pad "30" smd rect
			(at 0 24.649938 270)
			(size 1.8034 0.508)
			(layers "B.Cu" "B.Mask" "B.Paste")
			(net "M_D_DQS_DN<11>")
		)
		(pad "31" smd rect
			(at 0 25.500076 270)
			(size 1.8034 0.508)
			(layers "B.Cu" "B.Mask" "B.Paste")
			(net "GND")
		)
		(pad "32" smd rect
			(at 0 26.34996 270)
			(size 1.8034 0.508)
			(layers "B.Cu" "B.Mask" "B.Paste")
			(net "M_D_DQ<22>")
		)
		(pad "33" smd rect
			(at 0 27.200098 270)
			(size 1.8034 0.508)
			(layers "B.Cu" "B.Mask" "B.Paste")
			(net "GND")
		)
		(pad "34" smd rect
			(at 0 28.049982 270)
			(size 1.8034 0.508)
			(layers "B.Cu" "B.Mask" "B.Paste")
			(net "M_D_DQ<18>")
		)
		(pad "35" smd rect
			(at 0 28.90012 270)
			(size 1.8034 0.508)
			(layers "B.Cu" "B.Mask" "B.Paste")
			(net "GND")
		)
		(pad "36" smd rect
			(at 0 29.750004 270)
			(size 1.8034 0.508)
			(layers "B.Cu" "B.Mask" "B.Paste")
			(net "M_D_DQ<28>")
		)
		(pad "37" smd rect
			(at 0 30.599888 270)
			(size 1.8034 0.508)
			(layers "B.Cu" "B.Mask" "B.Paste")
			(net "GND")
		)
		(pad "38" smd rect
			(at 0 31.450026 270)
			(size 1.8034 0.508)
			(layers "B.Cu" "B.Mask" "B.Paste")
			(net "M_D_DQ<24>")
		)
		(pad "39" smd rect
			(at 0 32.29991 270)
			(size 1.8034 0.508)
			(layers "B.Cu" "B.Mask" "B.Paste")
			(net "GND")
		)
		(pad "40" smd rect
			(at 0 33.150048 270)
			(size 1.8034 0.508)
			(layers "B.Cu" "B.Mask" "B.Paste")
			(net "M_D_DQS_DP<12>")
		)
		(pad "41" smd rect
			(at 0 33.999932 270)
			(size 1.8034 0.508)
			(layers "B.Cu" "B.Mask" "B.Paste")
			(net "M_D_DQS_DN<12>")
		)
		(pad "42" smd rect
			(at 0 34.85007 270)
			(size 1.8034 0.508)
			(layers "B.Cu" "B.Mask" "B.Paste")
			(net "GND")
		)
		(pad "43" smd rect
			(at 0 35.699954 270)
			(size 1.8034 0.508)
			(layers "B.Cu" "B.Mask" "B.Paste")
			(net "M_D_DQ<30>")
		)
		(pad "44" smd rect
			(at 0 36.550092 270)
			(size 1.8034 0.508)
			(layers "B.Cu" "B.Mask" "B.Paste")
			(net "GND")
		)
		(pad "45" smd rect
			(at 0 37.399976 270)
			(size 1.8034 0.508)
			(layers "B.Cu" "B.Mask" "B.Paste")
			(net "M_D_DQ<26>")
		)
		(pad "46" smd rect
			(at 0 38.250114 270)
			(size 1.8034 0.508)
			(layers "B.Cu" "B.Mask" "B.Paste")
			(net "GND")
		)
		(pad "47" smd rect
			(at 0 39.099998 270)
			(size 1.8034 0.508)
			(layers "B.Cu" "B.Mask" "B.Paste")
			(net "M_D_ECC<4>")
		)
		(pad "48" smd rect
			(at 0 39.949882 270)
			(size 1.8034 0.508)
			(layers "B.Cu" "B.Mask" "B.Paste")
			(net "GND")
		)
		(pad "49" smd rect
			(at 0 40.80002 270)
			(size 1.8034 0.508)
			(layers "B.Cu" "B.Mask" "B.Paste")
			(net "M_D_ECC<0>")
		)
		(pad "50" smd rect
			(at 0 41.649904 270)
			(size 1.8034 0.508)
			(layers "B.Cu" "B.Mask" "B.Paste")
			(net "GND")
		)
		(pad "51" smd rect
			(at 0 42.500042 270)
			(size 1.8034 0.508)
			(layers "B.Cu" "B.Mask" "B.Paste")
			(net "M_D_DQS_DP<17>")
		)
		(pad "52" smd rect
			(at 0 43.349926 270)
			(size 1.8034 0.508)
			(layers "B.Cu" "B.Mask" "B.Paste")
			(net "M_D_DQS_DN<17>")
		)
		(pad "53" smd rect
			(at 0 44.200064 270)
			(size 1.8034 0.508)
			(layers "B.Cu" "B.Mask" "B.Paste")
			(net "GND")
		)
		(pad "54" smd rect
			(at 0 45.049948 270)
			(size 1.8034 0.508)
			(layers "B.Cu" "B.Mask" "B.Paste")
			(net "M_D_ECC<6>")
		)
		(pad "55" smd rect
			(at 0 45.900086 270)
			(size 1.8034 0.508)
			(layers "B.Cu" "B.Mask" "B.Paste")
			(net "GND")
		)
		(pad "56" smd rect
			(at 0 46.74997 270)
			(size 1.8034 0.508)
			(layers "B.Cu" "B.Mask" "B.Paste")
			(net "M_D_ECC<2>")
		)
		(pad "57" smd rect
			(at 0 47.600108 270)
			(size 1.8034 0.508)
			(layers "B.Cu" "B.Mask" "B.Paste")
			(net "GND")
		)
		(pad "58" smd rect
			(at 0 48.449992 270)
			(size 1.8034 0.508)
			(layers "B.Cu" "B.Mask" "B.Paste")
			(net "M_DEF_RST_N")
		)
		(pad "59" smd rect
			(at 0 49.299876 270)
			(size 1.8034 0.508)
			(layers "B.Cu" "B.Mask" "B.Paste")
			(net "PVDDQ_DEF")
		)
		(pad "60" smd rect
			(at 0 50.150014 270)
			(size 1.8034 0.508)
			(layers "B.Cu" "B.Mask" "B.Paste")
			(net "M_D_CKE<2>")
		)
		(pad "61" smd rect
			(at 0 50.999898 270)
			(size 1.8034 0.508)
			(layers "B.Cu" "B.Mask" "B.Paste")
			(net "PVDDQ_DEF")
		)
		(pad "62" smd rect
			(at 0 51.850036 270)
			(size 1.8034 0.508)
			(layers "B.Cu" "B.Mask" "B.Paste")
			(net "M_D_ACT_N")
		)
		(pad "63" smd rect
			(at 0 52.69992 270)
			(size 1.8034 0.508)
			(layers "B.Cu" "B.Mask" "B.Paste")
			(net "M_D_BG<0>")
		)
		(pad "64" smd rect
			(at 0 53.550058 270)
			(size 1.8034 0.508)
			(layers "B.Cu" "B.Mask" "B.Paste")
			(net "PVDDQ_DEF")
		)
		(pad "65" smd rect
			(at 0 54.399942 270)
			(size 1.8034 0.508)
			(layers "B.Cu" "B.Mask" "B.Paste")
			(net "M_D_MA<12>")
		)
		(pad "66" smd rect
			(at 0 55.25008 270)
			(size 1.8034 0.508)
			(layers "B.Cu" "B.Mask" "B.Paste")
			(net "M_D_MA<9>")
		)
		(pad "67" smd rect
			(at 0 56.099964 270)
			(size 1.8034 0.508)
			(layers "B.Cu" "B.Mask" "B.Paste")
			(net "PVDDQ_DEF")
		)
		(pad "68" smd rect
			(at 0 56.950102 270)
			(size 1.8034 0.508)
			(layers "B.Cu" "B.Mask" "B.Paste")
			(net "M_D_MA<8>")
		)
		(pad "69" smd rect
			(at 0 57.799986 270)
			(size 1.8034 0.508)
			(layers "B.Cu" "B.Mask" "B.Paste")
			(net "M_D_MA<6>")
		)
		(pad "70" smd rect
			(at 0 58.650124 270)
			(size 1.8034 0.508)
			(layers "B.Cu" "B.Mask" "B.Paste")
			(net "PVDDQ_DEF")
		)
		(pad "71" smd rect
			(at 0 59.500008 270)
			(size 1.8034 0.508)
			(layers "B.Cu" "B.Mask" "B.Paste")
			(net "M_D_MA<3>")
		)
		(pad "72" smd rect
			(at 0 60.349892 270)
			(size 1.8034 0.508)
			(layers "B.Cu" "B.Mask" "B.Paste")
			(net "M_D_MA<1>")
		)
		(pad "73" smd rect
			(at 0 61.20003 270)
			(size 1.8034 0.508)
			(layers "B.Cu" "B.Mask" "B.Paste")
			(net "PVDDQ_DEF")
		)
		(pad "74" smd rect
			(at 0 62.049914 270)
			(size 1.8034 0.508)
			(layers "B.Cu" "B.Mask" "B.Paste")
			(net "M_D_CLK_DP<2>")
		)
		(pad "75" smd rect
			(at 0 62.900052 270)
			(size 1.8034 0.508)
			(layers "B.Cu" "B.Mask" "B.Paste")
			(net "M_D_CLK_DN<2>")
		)
		(pad "76" smd rect
			(at 0 63.749936 270)
			(size 1.8034 0.508)
			(layers "B.Cu" "B.Mask" "B.Paste")
			(net "PVDDQ_DEF")
		)
		(pad "77" smd rect
			(at 0 64.600074 270)
			(size 1.8034 0.508)
			(layers "B.Cu" "B.Mask" "B.Paste")
			(net "PVTT_DEF")
		)
		(pad "78" smd rect
			(at 0 70.550024 270)
			(size 1.8034 0.508)
			(layers "B.Cu" "B.Mask" "B.Paste")
			(net "FM_DIMM_EVENT_COD_N")
		)
		(pad "79" smd rect
			(at 0 71.399908 270)
			(size 1.8034 0.508)
			(layers "B.Cu" "B.Mask" "B.Paste")
			(net "M_D_MA<0>")
		)
		(pad "80" smd rect
			(at 0 72.250046 270)
			(size 1.8034 0.508)
			(layers "B.Cu" "B.Mask" "B.Paste")
			(net "PVDDQ_DEF")
		)
		(pad "81" smd rect
			(at 0 73.09993 270)
			(size 1.8034 0.508)
			(layers "B.Cu" "B.Mask" "B.Paste")
			(net "M_D_BA<0>")
		)
		(pad "82" smd rect
			(at 0 73.950068 270)
			(size 1.8034 0.508)
			(layers "B.Cu" "B.Mask" "B.Paste")
			(net "M_D_MA<16>")
		)
		(pad "83" smd rect
			(at 0 74.799952 270)
			(size 1.8034 0.508)
			(layers "B.Cu" "B.Mask" "B.Paste")
			(net "PVDDQ_DEF")
		)
		(pad "84" smd rect
			(at 0 75.65009 270)
			(size 1.8034 0.508)
			(layers "B.Cu" "B.Mask" "B.Paste")
			(net "M_D_CS_N<4>")
		)
		(pad "85" smd rect
			(at 0 76.499974 270)
			(size 1.8034 0.508)
			(layers "B.Cu" "B.Mask" "B.Paste")
			(net "PVDDQ_DEF")
		)
		(pad "86" smd rect
			(at 0 77.350112 270)
			(size 1.8034 0.508)
			(layers "B.Cu" "B.Mask" "B.Paste")
			(net "M_D_MA<15>")
		)
		(pad "87" smd rect
			(at 0 78.199996 270)
			(size 1.8034 0.508)
			(layers "B.Cu" "B.Mask" "B.Paste")
			(net "M_D_ODT<2>")
		)
		(pad "88" smd rect
			(at 0 79.04988 270)
			(size 1.8034 0.508)
			(layers "B.Cu" "B.Mask" "B.Paste")
			(net "PVDDQ_DEF")
		)
		(pad "89" smd rect
			(at 0 79.900018 270)
			(size 1.8034 0.508)
			(layers "B.Cu" "B.Mask" "B.Paste")
			(net "M_D_CS_N<5>")
		)
		(pad "90" smd rect
			(at 0 80.749902 270)
			(size 1.8034 0.508)
			(layers "B.Cu" "B.Mask" "B.Paste")
			(net "PVDDQ_DEF")
		)
		(pad "91" smd rect
			(at 0 81.60004 270)
			(size 1.8034 0.508)
			(layers "B.Cu" "B.Mask" "B.Paste")
			(net "M_D_ODT<3>")
		)
		(pad "92" smd rect
			(at 0 82.449924 270)
			(size 1.8034 0.508)
			(layers "B.Cu" "B.Mask" "B.Paste")
			(net "PVDDQ_DEF")
		)
		(pad "93" smd rect
			(at 0 83.300062 270)
			(size 1.8034 0.508)
			(layers "B.Cu" "B.Mask" "B.Paste")
			(net "M_D_CS_N<6>")
		)
		(pad "94" smd rect
			(at 0 84.149946 270)
			(size 1.8034 0.508)
			(layers "B.Cu" "B.Mask" "B.Paste")
			(net "GND")
		)
		(pad "95" smd rect
			(at 0 85.000084 270)
			(size 1.8034 0.508)
			(layers "B.Cu" "B.Mask" "B.Paste")
			(net "M_D_DQ<36>")
		)
		(pad "96" smd rect
			(at 0 85.849968 270)
			(size 1.8034 0.508)
			(layers "B.Cu" "B.Mask" "B.Paste")
			(net "GND")
		)
		(pad "97" smd rect
			(at 0 86.700106 270)
			(size 1.8034 0.508)
			(layers "B.Cu" "B.Mask" "B.Paste")
			(net "M_D_DQ<32>")
		)
		(pad "98" smd rect
			(at 0 87.54999 270)
			(size 1.8034 0.508)
			(layers "B.Cu" "B.Mask" "B.Paste")
			(net "GND")
		)
		(pad "99" smd rect
			(at 0 88.399874 270)
			(size 1.8034 0.508)
			(layers "B.Cu" "B.Mask" "B.Paste")
			(net "M_D_DQS_DP<13>")
		)
		(pad "100" smd rect
			(at 0 89.250012 270)
			(size 1.8034 0.508)
			(layers "B.Cu" "B.Mask" "B.Paste")
			(net "M_D_DQS_DN<13>")
		)
		(pad "101" smd rect
			(at 0 90.099896 270)
			(size 1.8034 0.508)
			(layers "B.Cu" "B.Mask" "B.Paste")
			(net "GND")
		)
		(pad "102" smd rect
			(at 0 90.950034 270)
			(size 1.8034 0.508)
			(layers "B.Cu" "B.Mask" "B.Paste")
			(net "M_D_DQ<38>")
		)
		(pad "103" smd rect
			(at 0 91.799918 270)
			(size 1.8034 0.508)
			(layers "B.Cu" "B.Mask" "B.Paste")
			(net "GND")
		)
		(pad "104" smd rect
			(at 0 92.650056 270)
			(size 1.8034 0.508)
			(layers "B.Cu" "B.Mask" "B.Paste")
			(net "M_D_DQ<34>")
		)
		(pad "105" smd rect
			(at 0 93.49994 270)
			(size 1.8034 0.508)
			(layers "B.Cu" "B.Mask" "B.Paste")
			(net "GND")
		)
		(pad "106" smd rect
			(at 0 94.350078 270)
			(size 1.8034 0.508)
			(layers "B.Cu" "B.Mask" "B.Paste")
			(net "M_D_DQ<44>")
		)
		(pad "107" smd rect
			(at 0 95.199962 270)
			(size 1.8034 0.508)
			(layers "B.Cu" "B.Mask" "B.Paste")
			(net "GND")
		)
		(pad "108" smd rect
			(at 0 96.0501 270)
			(size 1.8034 0.508)
			(layers "B.Cu" "B.Mask" "B.Paste")
			(net "M_D_DQ<40>")
		)
		(pad "109" smd rect
			(at 0 96.899984 270)
			(size 1.8034 0.508)
			(layers "B.Cu" "B.Mask" "B.Paste")
			(net "GND")
		)
		(pad "110" smd rect
			(at 0 97.750122 270)
			(size 1.8034 0.508)
			(layers "B.Cu" "B.Mask" "B.Paste")
			(net "M_D_DQS_DP<14>")
		)
		(pad "111" smd rect
			(at 0 98.600006 270)
			(size 1.8034 0.508)
			(layers "B.Cu" "B.Mask" "B.Paste")
			(net "M_D_DQS_DN<14>")
		)
		(pad "112" smd rect
			(at 0 99.44989 270)
			(size 1.8034 0.508)
			(layers "B.Cu" "B.Mask" "B.Paste")
			(net "GND")
		)
		(pad "113" smd rect
			(at 0 100.300028 270)
			(size 1.8034 0.508)
			(layers "B.Cu" "B.Mask" "B.Paste")
			(net "M_D_DQ<46>")
		)
		(pad "114" smd rect
			(at 0 101.149912 270)
			(size 1.8034 0.508)
			(layers "B.Cu" "B.Mask" "B.Paste")
			(net "GND")
		)
		(pad "115" smd rect
			(at 0 102.00005 270)
			(size 1.8034 0.508)
			(layers "B.Cu" "B.Mask" "B.Paste")
			(net "M_D_DQ<42>")
		)
		(pad "116" smd rect
			(at 0 102.849934 270)
			(size 1.8034 0.508)
			(layers "B.Cu" "B.Mask" "B.Paste")
			(net "GND")
		)
		(pad "117" smd rect
			(at 0 103.700072 270)
			(size 1.8034 0.508)
			(layers "B.Cu" "B.Mask" "B.Paste")
			(net "M_D_DQ<52>")
		)
		(pad "118" smd rect
			(at 0 104.549956 270)
			(size 1.8034 0.508)
			(layers "B.Cu" "B.Mask" "B.Paste")
			(net "GND")
		)
		(pad "119" smd rect
			(at 0 105.400094 270)
			(size 1.8034 0.508)
			(layers "B.Cu" "B.Mask" "B.Paste")
			(net "M_D_DQ<48>")
		)
		(pad "120" smd rect
			(at 0 106.249978 270)
			(size 1.8034 0.508)
			(layers "B.Cu" "B.Mask" "B.Paste")
			(net "GND")
		)
		(pad "121" smd rect
			(at 0 107.100116 270)
			(size 1.8034 0.508)
			(layers "B.Cu" "B.Mask" "B.Paste")
			(net "M_D_DQS_DP<15>")
		)
		(pad "122" smd rect
			(at 0 107.95 270)
			(size 1.8034 0.508)
			(layers "B.Cu" "B.Mask" "B.Paste")
			(net "M_D_DQS_DN<15>")
		)
		(pad "123" smd rect
			(at 0 108.799884 270)
			(size 1.8034 0.508)
			(layers "B.Cu" "B.Mask" "B.Paste")
			(net "GND")
		)
		(pad "124" smd rect
			(at 0 109.650022 270)
			(size 1.8034 0.508)
			(layers "B.Cu" "B.Mask" "B.Paste")
			(net "M_D_DQ<54>")
		)
		(pad "125" smd rect
			(at 0 110.499906 270)
			(size 1.8034 0.508)
			(layers "B.Cu" "B.Mask" "B.Paste")
			(net "GND")
		)
		(pad "126" smd rect
			(at 0 111.350044 270)
			(size 1.8034 0.508)
			(layers "B.Cu" "B.Mask" "B.Paste")
			(net "M_D_DQ<50>")
		)
		(pad "127" smd rect
			(at 0 112.199928 270)
			(size 1.8034 0.508)
			(layers "B.Cu" "B.Mask" "B.Paste")
			(net "GND")
		)
		(pad "128" smd rect
			(at 0 113.050066 270)
			(size 1.8034 0.508)
			(layers "B.Cu" "B.Mask" "B.Paste")
			(net "M_D_DQ<60>")
		)
		(pad "129" smd rect
			(at 0 113.89995 270)
			(size 1.8034 0.508)
			(layers "B.Cu" "B.Mask" "B.Paste")
			(net "GND")
		)
		(pad "130" smd rect
			(at 0 114.750088 270)
			(size 1.8034 0.508)
			(layers "B.Cu" "B.Mask" "B.Paste")
			(net "M_D_DQ<56>")
		)
		(pad "131" smd rect
			(at 0 115.599972 270)
			(size 1.8034 0.508)
			(layers "B.Cu" "B.Mask" "B.Paste")
			(net "GND")
		)
		(pad "132" smd rect
			(at 0 116.45011 270)
			(size 1.8034 0.508)
			(layers "B.Cu" "B.Mask" "B.Paste")
			(net "M_D_DQS_DP<16>")
		)
		(pad "133" smd rect
			(at 0 117.299994 270)
			(size 1.8034 0.508)
			(layers "B.Cu" "B.Mask" "B.Paste")
			(net "M_D_DQS_DN<16>")
		)
		(pad "134" smd rect
			(at 0 118.149878 270)
			(size 1.8034 0.508)
			(layers "B.Cu" "B.Mask" "B.Paste")
			(net "GND")
		)
		(pad "135" smd rect
			(at 0 119.000016 270)
			(size 1.8034 0.508)
			(layers "B.Cu" "B.Mask" "B.Paste")
			(net "M_D_DQ<62>")
		)
		(pad "136" smd rect
			(at 0 119.8499 270)
			(size 1.8034 0.508)
			(layers "B.Cu" "B.Mask" "B.Paste")
			(net "GND")
		)
		(pad "137" smd rect
			(at 0 120.700038 270)
			(size 1.8034 0.508)
			(layers "B.Cu" "B.Mask" "B.Paste")
			(net "M_D_DQ<58>")
		)
		(pad "138" smd rect
			(at 0 121.549922 270)
			(size 1.8034 0.508)
			(layers "B.Cu" "B.Mask" "B.Paste")
			(net "GND")
		)
		(pad "139" smd rect
			(at 0 122.40006 270)
			(size 1.8034 0.508)
			(layers "B.Cu" "B.Mask" "B.Paste")
			(net "PVPP_DEF")
		)
		(pad "140" smd rect
			(at 0 123.249944 270)
			(size 1.8034 0.508)
			(layers "B.Cu" "B.Mask" "B.Paste")
			(net "GND")
		)
		(pad "141" smd rect
			(at 0 124.100082 270)
			(size 1.8034 0.508)
			(layers "B.Cu" "B.Mask" "B.Paste")
			(net "SMB_DDR_DEF_VPP_SCL")
		)
		(pad "142" smd rect
			(at 0 124.949966 270)
			(size 1.8034 0.508)
			(layers "B.Cu" "B.Mask" "B.Paste")
			(net "PVPP_DEF")
		)
		(pad "143" smd rect
			(at 0 125.800104 270)
			(size 1.8034 0.508)
			(layers "B.Cu" "B.Mask" "B.Paste")
			(net "PVPP_DEF")
		)
		(pad "144" smd rect
			(at 0 126.649988 270)
			(size 1.8034 0.508)
			(layers "B.Cu" "B.Mask" "B.Paste")
			(net "TP_CH_D_DIMM_D1_RFU_2")
		)
		(pad "145" smd rect
			(at -4.59994 0 270)
			(size 1.8034 0.508)
			(layers "B.Cu" "B.Mask" "B.Paste")
			(net "P12V_NVDIMM_DEF")
		)
		(pad "146" smd rect
			(at -4.59994 0.849884 270)
			(size 1.8034 0.508)
			(layers "B.Cu" "B.Mask" "B.Paste")
			(net "M_D_VREF")
		)
		(pad "147" smd rect
			(at -4.59994 1.700022 270)
			(size 1.8034 0.508)
			(layers "B.Cu" "B.Mask" "B.Paste")
			(net "GND")
		)
		(pad "148" smd rect
			(at -4.59994 2.549906 270)
			(size 1.8034 0.508)
			(layers "B.Cu" "B.Mask" "B.Paste")
			(net "M_D_DQ<5>")
		)
		(pad "149" smd rect
			(at -4.59994 3.400044 270)
			(size 1.8034 0.508)
			(layers "B.Cu" "B.Mask" "B.Paste")
			(net "GND")
		)
		(pad "150" smd rect
			(at -4.59994 4.249928 270)
			(size 1.8034 0.508)
			(layers "B.Cu" "B.Mask" "B.Paste")
			(net "M_D_DQ<1>")
		)
		(pad "151" smd rect
			(at -4.59994 5.100066 270)
			(size 1.8034 0.508)
			(layers "B.Cu" "B.Mask" "B.Paste")
			(net "GND")
		)
		(pad "152" smd rect
			(at -4.59994 5.94995 270)
			(size 1.8034 0.508)
			(layers "B.Cu" "B.Mask" "B.Paste")
			(net "M_D_DQS_DN<0>")
		)
		(pad "153" smd rect
			(at -4.59994 6.800088 270)
			(size 1.8034 0.508)
			(layers "B.Cu" "B.Mask" "B.Paste")
			(net "M_D_DQS_DP<0>")
		)
		(pad "154" smd rect
			(at -4.59994 7.649972 270)
			(size 1.8034 0.508)
			(layers "B.Cu" "B.Mask" "B.Paste")
			(net "GND")
		)
		(pad "155" smd rect
			(at -4.59994 8.50011 270)
			(size 1.8034 0.508)
			(layers "B.Cu" "B.Mask" "B.Paste")
			(net "M_D_DQ<7>")
		)
		(pad "156" smd rect
			(at -4.59994 9.349994 270)
			(size 1.8034 0.508)
			(layers "B.Cu" "B.Mask" "B.Paste")
			(net "GND")
		)
		(pad "157" smd rect
			(at -4.59994 10.199878 270)
			(size 1.8034 0.508)
			(layers "B.Cu" "B.Mask" "B.Paste")
			(net "M_D_DQ<3>")
		)
		(pad "158" smd rect
			(at -4.59994 11.050016 270)
			(size 1.8034 0.508)
			(layers "B.Cu" "B.Mask" "B.Paste")
			(net "GND")
		)
		(pad "159" smd rect
			(at -4.59994 11.8999 270)
			(size 1.8034 0.508)
			(layers "B.Cu" "B.Mask" "B.Paste")
			(net "M_D_DQ<13>")
		)
		(pad "160" smd rect
			(at -4.59994 12.750038 270)
			(size 1.8034 0.508)
			(layers "B.Cu" "B.Mask" "B.Paste")
			(net "GND")
		)
		(pad "161" smd rect
			(at -4.59994 13.599922 270)
			(size 1.8034 0.508)
			(layers "B.Cu" "B.Mask" "B.Paste")
			(net "M_D_DQ<9>")
		)
		(pad "162" smd rect
			(at -4.59994 14.45006 270)
			(size 1.8034 0.508)
			(layers "B.Cu" "B.Mask" "B.Paste")
			(net "GND")
		)
		(pad "163" smd rect
			(at -4.59994 15.299944 270)
			(size 1.8034 0.508)
			(layers "B.Cu" "B.Mask" "B.Paste")
			(net "M_D_DQS_DN<1>")
		)
		(pad "164" smd rect
			(at -4.59994 16.150082 270)
			(size 1.8034 0.508)
			(layers "B.Cu" "B.Mask" "B.Paste")
			(net "M_D_DQS_DP<1>")
		)
		(pad "165" smd rect
			(at -4.59994 16.999966 270)
			(size 1.8034 0.508)
			(layers "B.Cu" "B.Mask" "B.Paste")
			(net "GND")
		)
		(pad "166" smd rect
			(at -4.59994 17.850104 270)
			(size 1.8034 0.508)
			(layers "B.Cu" "B.Mask" "B.Paste")
			(net "M_D_DQ<15>")
		)
		(pad "167" smd rect
			(at -4.59994 18.699988 270)
			(size 1.8034 0.508)
			(layers "B.Cu" "B.Mask" "B.Paste")
			(net "GND")
		)
		(pad "168" smd rect
			(at -4.59994 19.550126 270)
			(size 1.8034 0.508)
			(layers "B.Cu" "B.Mask" "B.Paste")
			(net "M_D_DQ<11>")
		)
		(pad "169" smd rect
			(at -4.59994 20.40001 270)
			(size 1.8034 0.508)
			(layers "B.Cu" "B.Mask" "B.Paste")
			(net "GND")
		)
		(pad "170" smd rect
			(at -4.59994 21.249894 270)
			(size 1.8034 0.508)
			(layers "B.Cu" "B.Mask" "B.Paste")
			(net "M_D_DQ<21>")
		)
		(pad "171" smd rect
			(at -4.59994 22.100032 270)
			(size 1.8034 0.508)
			(layers "B.Cu" "B.Mask" "B.Paste")
			(net "GND")
		)
		(pad "172" smd rect
			(at -4.59994 22.949916 270)
			(size 1.8034 0.508)
			(layers "B.Cu" "B.Mask" "B.Paste")
			(net "M_D_DQ<17>")
		)
		(pad "173" smd rect
			(at -4.59994 23.800054 270)
			(size 1.8034 0.508)
			(layers "B.Cu" "B.Mask" "B.Paste")
			(net "GND")
		)
		(pad "174" smd rect
			(at -4.59994 24.649938 270)
			(size 1.8034 0.508)
			(layers "B.Cu" "B.Mask" "B.Paste")
			(net "M_D_DQS_DN<2>")
		)
		(pad "175" smd rect
			(at -4.59994 25.500076 270)
			(size 1.8034 0.508)
			(layers "B.Cu" "B.Mask" "B.Paste")
			(net "M_D_DQS_DP<2>")
		)
		(pad "176" smd rect
			(at -4.59994 26.34996 270)
			(size 1.8034 0.508)
			(layers "B.Cu" "B.Mask" "B.Paste")
			(net "GND")
		)
		(pad "177" smd rect
			(at -4.59994 27.200098 270)
			(size 1.8034 0.508)
			(layers "B.Cu" "B.Mask" "B.Paste")
			(net "M_D_DQ<23>")
		)
		(pad "178" smd rect
			(at -4.59994 28.049982 270)
			(size 1.8034 0.508)
			(layers "B.Cu" "B.Mask" "B.Paste")
			(net "GND")
		)
		(pad "179" smd rect
			(at -4.59994 28.90012 270)
			(size 1.8034 0.508)
			(layers "B.Cu" "B.Mask" "B.Paste")
			(net "M_D_DQ<19>")
		)
		(pad "180" smd rect
			(at -4.59994 29.750004 270)
			(size 1.8034 0.508)
			(layers "B.Cu" "B.Mask" "B.Paste")
			(net "GND")
		)
		(pad "181" smd rect
			(at -4.59994 30.599888 270)
			(size 1.8034 0.508)
			(layers "B.Cu" "B.Mask" "B.Paste")
			(net "M_D_DQ<29>")
		)
		(pad "182" smd rect
			(at -4.59994 31.450026 270)
			(size 1.8034 0.508)
			(layers "B.Cu" "B.Mask" "B.Paste")
			(net "GND")
		)
		(pad "183" smd rect
			(at -4.59994 32.29991 270)
			(size 1.8034 0.508)
			(layers "B.Cu" "B.Mask" "B.Paste")
			(net "M_D_DQ<25>")
		)
		(pad "184" smd rect
			(at -4.59994 33.150048 270)
			(size 1.8034 0.508)
			(layers "B.Cu" "B.Mask" "B.Paste")
			(net "GND")
		)
		(pad "185" smd rect
			(at -4.59994 33.999932 270)
			(size 1.8034 0.508)
			(layers "B.Cu" "B.Mask" "B.Paste")
			(net "M_D_DQS_DN<3>")
		)
		(pad "186" smd rect
			(at -4.59994 34.85007 270)
			(size 1.8034 0.508)
			(layers "B.Cu" "B.Mask" "B.Paste")
			(net "M_D_DQS_DP<3>")
		)
		(pad "187" smd rect
			(at -4.59994 35.699954 270)
			(size 1.8034 0.508)
			(layers "B.Cu" "B.Mask" "B.Paste")
			(net "GND")
		)
		(pad "188" smd rect
			(at -4.59994 36.550092 270)
			(size 1.8034 0.508)
			(layers "B.Cu" "B.Mask" "B.Paste")
			(net "M_D_DQ<31>")
		)
		(pad "189" smd rect
			(at -4.59994 37.399976 270)
			(size 1.8034 0.508)
			(layers "B.Cu" "B.Mask" "B.Paste")
			(net "GND")
		)
		(pad "190" smd rect
			(at -4.59994 38.250114 270)
			(size 1.8034 0.508)
			(layers "B.Cu" "B.Mask" "B.Paste")
			(net "M_D_DQ<27>")
		)
		(pad "191" smd rect
			(at -4.59994 39.099998 270)
			(size 1.8034 0.508)
			(layers "B.Cu" "B.Mask" "B.Paste")
			(net "GND")
		)
		(pad "192" smd rect
			(at -4.59994 39.949882 270)
			(size 1.8034 0.508)
			(layers "B.Cu" "B.Mask" "B.Paste")
			(net "M_D_ECC<5>")
		)
		(pad "193" smd rect
			(at -4.59994 40.80002 270)
			(size 1.8034 0.508)
			(layers "B.Cu" "B.Mask" "B.Paste")
			(net "GND")
		)
		(pad "194" smd rect
			(at -4.59994 41.649904 270)
			(size 1.8034 0.508)
			(layers "B.Cu" "B.Mask" "B.Paste")
			(net "M_D_ECC<1>")
		)
		(pad "195" smd rect
			(at -4.59994 42.500042 270)
			(size 1.8034 0.508)
			(layers "B.Cu" "B.Mask" "B.Paste")
			(net "GND")
		)
		(pad "196" smd rect
			(at -4.59994 43.349926 270)
			(size 1.8034 0.508)
			(layers "B.Cu" "B.Mask" "B.Paste")
			(net "M_D_DQS_DN<8>")
		)
		(pad "197" smd rect
			(at -4.59994 44.200064 270)
			(size 1.8034 0.508)
			(layers "B.Cu" "B.Mask" "B.Paste")
			(net "M_D_DQS_DP<8>")
		)
		(pad "198" smd rect
			(at -4.59994 45.049948 270)
			(size 1.8034 0.508)
			(layers "B.Cu" "B.Mask" "B.Paste")
			(net "GND")
		)
		(pad "199" smd rect
			(at -4.59994 45.900086 270)
			(size 1.8034 0.508)
			(layers "B.Cu" "B.Mask" "B.Paste")
			(net "M_D_ECC<7>")
		)
		(pad "200" smd rect
			(at -4.59994 46.74997 270)
			(size 1.8034 0.508)
			(layers "B.Cu" "B.Mask" "B.Paste")
			(net "GND")
		)
		(pad "201" smd rect
			(at -4.59994 47.600108 270)
			(size 1.8034 0.508)
			(layers "B.Cu" "B.Mask" "B.Paste")
			(net "M_D_ECC<3>")
		)
		(pad "202" smd rect
			(at -4.59994 48.449992 270)
			(size 1.8034 0.508)
			(layers "B.Cu" "B.Mask" "B.Paste")
			(net "GND")
		)
		(pad "203" smd rect
			(at -4.59994 49.299876 270)
			(size 1.8034 0.508)
			(layers "B.Cu" "B.Mask" "B.Paste")
			(net "M_D_CKE<3>")
		)
		(pad "204" smd rect
			(at -4.59994 50.150014 270)
			(size 1.8034 0.508)
			(layers "B.Cu" "B.Mask" "B.Paste")
			(net "PVDDQ_DEF")
		)
		(pad "205" smd rect
			(at -4.59994 50.999898 270)
			(size 1.8034 0.508)
			(layers "B.Cu" "B.Mask" "B.Paste")
			(net "TP_CH_D_DIMM_D1_RFU_0")
		)
		(pad "206" smd rect
			(at -4.59994 51.850036 270)
			(size 1.8034 0.508)
			(layers "B.Cu" "B.Mask" "B.Paste")
			(net "PVDDQ_DEF")
		)
		(pad "207" smd rect
			(at -4.59994 52.69992 270)
			(size 1.8034 0.508)
			(layers "B.Cu" "B.Mask" "B.Paste")
			(net "M_D_BG<1>")
		)
		(pad "208" smd rect
			(at -4.59994 53.550058 270)
			(size 1.8034 0.508)
			(layers "B.Cu" "B.Mask" "B.Paste")
			(net "M_D_ALERT_N")
		)
		(pad "209" smd rect
			(at -4.59994 54.399942 270)
			(size 1.8034 0.508)
			(layers "B.Cu" "B.Mask" "B.Paste")
			(net "PVDDQ_DEF")
		)
		(pad "210" smd rect
			(at -4.59994 55.25008 270)
			(size 1.8034 0.508)
			(layers "B.Cu" "B.Mask" "B.Paste")
			(net "M_D_MA<11>")
		)
		(pad "211" smd rect
			(at -4.59994 56.099964 270)
			(size 1.8034 0.508)
			(layers "B.Cu" "B.Mask" "B.Paste")
			(net "M_D_MA<7>")
		)
		(pad "212" smd rect
			(at -4.59994 56.950102 270)
			(size 1.8034 0.508)
			(layers "B.Cu" "B.Mask" "B.Paste")
			(net "PVDDQ_DEF")
		)
		(pad "213" smd rect
			(at -4.59994 57.799986 270)
			(size 1.8034 0.508)
			(layers "B.Cu" "B.Mask" "B.Paste")
			(net "M_D_MA<5>")
		)
		(pad "214" smd rect
			(at -4.59994 58.650124 270)
			(size 1.8034 0.508)
			(layers "B.Cu" "B.Mask" "B.Paste")
			(net "M_D_MA<4>")
		)
		(pad "215" smd rect
			(at -4.59994 59.500008 270)
			(size 1.8034 0.508)
			(layers "B.Cu" "B.Mask" "B.Paste")
			(net "PVDDQ_DEF")
		)
		(pad "216" smd rect
			(at -4.59994 60.349892 270)
			(size 1.8034 0.508)
			(layers "B.Cu" "B.Mask" "B.Paste")
			(net "M_D_MA<2>")
		)
		(pad "217" smd rect
			(at -4.59994 61.20003 270)
			(size 1.8034 0.508)
			(layers "B.Cu" "B.Mask" "B.Paste")
			(net "PVDDQ_DEF")
		)
		(pad "218" smd rect
			(at -4.59994 62.049914 270)
			(size 1.8034 0.508)
			(layers "B.Cu" "B.Mask" "B.Paste")
			(net "M_D_CLK_DP<3>")
		)
		(pad "219" smd rect
			(at -4.59994 62.900052 270)
			(size 1.8034 0.508)
			(layers "B.Cu" "B.Mask" "B.Paste")
			(net "M_D_CLK_DN<3>")
		)
		(pad "220" smd rect
			(at -4.59994 63.749936 270)
			(size 1.8034 0.508)
			(layers "B.Cu" "B.Mask" "B.Paste")
			(net "PVDDQ_DEF")
		)
		(pad "221" smd rect
			(at -4.59994 64.600074 270)
			(size 1.8034 0.508)
			(layers "B.Cu" "B.Mask" "B.Paste")
			(net "PVTT_DEF")
		)
		(pad "222" smd rect
			(at -4.59994 70.550024 270)
			(size 1.8034 0.508)
			(layers "B.Cu" "B.Mask" "B.Paste")
			(net "M_D_PAR")
		)
		(pad "223" smd rect
			(at -4.59994 71.399908 270)
			(size 1.8034 0.508)
			(layers "B.Cu" "B.Mask" "B.Paste")
			(net "PVDDQ_DEF")
		)
		(pad "224" smd rect
			(at -4.59994 72.250046 270)
			(size 1.8034 0.508)
			(layers "B.Cu" "B.Mask" "B.Paste")
			(net "M_D_BA<1>")
		)
		(pad "225" smd rect
			(at -4.59994 73.09993 270)
			(size 1.8034 0.508)
			(layers "B.Cu" "B.Mask" "B.Paste")
			(net "M_D_MA<10>")
		)
		(pad "226" smd rect
			(at -4.59994 73.950068 270)
			(size 1.8034 0.508)
			(layers "B.Cu" "B.Mask" "B.Paste")
			(net "PVDDQ_DEF")
		)
		(pad "227" smd rect
			(at -4.59994 74.799952 270)
			(size 1.8034 0.508)
			(layers "B.Cu" "B.Mask" "B.Paste")
			(net "TP_CH_D_DIMM_D1_RFU_1")
		)
		(pad "228" smd rect
			(at -4.59994 75.65009 270)
			(size 1.8034 0.508)
			(layers "B.Cu" "B.Mask" "B.Paste")
			(net "M_D_MA<14>")
		)
		(pad "229" smd rect
			(at -4.59994 76.499974 270)
			(size 1.8034 0.508)
			(layers "B.Cu" "B.Mask" "B.Paste")
			(net "PVDDQ_DEF")
		)
		(pad "230" smd rect
			(at -4.59994 77.350112 270)
			(size 1.8034 0.508)
			(layers "B.Cu" "B.Mask" "B.Paste")
			(net "FM_ADR_COMPLETE_DEF_N")
		)
		(pad "231" smd rect
			(at -4.59994 78.199996 270)
			(size 1.8034 0.508)
			(layers "B.Cu" "B.Mask" "B.Paste")
			(net "PVDDQ_DEF")
		)
		(pad "232" smd rect
			(at -4.59994 79.04988 270)
			(size 1.8034 0.508)
			(layers "B.Cu" "B.Mask" "B.Paste")
			(net "M_D_MA<13>")
		)
		(pad "233" smd rect
			(at -4.59994 79.900018 270)
			(size 1.8034 0.508)
			(layers "B.Cu" "B.Mask" "B.Paste")
			(net "PVDDQ_DEF")
		)
		(pad "234" smd rect
			(at -4.59994 80.749902 270)
			(size 1.8034 0.508)
			(layers "B.Cu" "B.Mask" "B.Paste")
			(net "M_D_MA<17>")
		)
		(pad "235" smd rect
			(at -4.59994 81.60004 270)
			(size 1.8034 0.508)
			(layers "B.Cu" "B.Mask" "B.Paste")
			(net "M_D_C<2>")
		)
		(pad "236" smd rect
			(at -4.59994 82.449924 270)
			(size 1.8034 0.508)
			(layers "B.Cu" "B.Mask" "B.Paste")
			(net "PVDDQ_DEF")
		)
		(pad "237" smd rect
			(at -4.59994 83.300062 270)
			(size 1.8034 0.508)
			(layers "B.Cu" "B.Mask" "B.Paste")
			(net "M_D_CS_N<7>")
		)
		(pad "238" smd rect
			(at -4.59994 84.149946 270)
			(size 1.8034 0.508)
			(layers "B.Cu" "B.Mask" "B.Paste")
			(net "GND")
		)
		(pad "239" smd rect
			(at -4.59994 85.000084 270)
			(size 1.8034 0.508)
			(layers "B.Cu" "B.Mask" "B.Paste")
			(net "GND")
		)
		(pad "240" smd rect
			(at -4.59994 85.849968 270)
			(size 1.8034 0.508)
			(layers "B.Cu" "B.Mask" "B.Paste")
			(net "M_D_DQ<37>")
		)
		(pad "241" smd rect
			(at -4.59994 86.700106 270)
			(size 1.8034 0.508)
			(layers "B.Cu" "B.Mask" "B.Paste")
			(net "GND")
		)
		(pad "242" smd rect
			(at -4.59994 87.54999 270)
			(size 1.8034 0.508)
			(layers "B.Cu" "B.Mask" "B.Paste")
			(net "M_D_DQ<33>")
		)
		(pad "243" smd rect
			(at -4.59994 88.399874 270)
			(size 1.8034 0.508)
			(layers "B.Cu" "B.Mask" "B.Paste")
			(net "GND")
		)
		(pad "244" smd rect
			(at -4.59994 89.250012 270)
			(size 1.8034 0.508)
			(layers "B.Cu" "B.Mask" "B.Paste")
			(net "M_D_DQS_DN<4>")
		)
		(pad "245" smd rect
			(at -4.59994 90.099896 270)
			(size 1.8034 0.508)
			(layers "B.Cu" "B.Mask" "B.Paste")
			(net "M_D_DQS_DP<4>")
		)
		(pad "246" smd rect
			(at -4.59994 90.950034 270)
			(size 1.8034 0.508)
			(layers "B.Cu" "B.Mask" "B.Paste")
			(net "GND")
		)
		(pad "247" smd rect
			(at -4.59994 91.799918 270)
			(size 1.8034 0.508)
			(layers "B.Cu" "B.Mask" "B.Paste")
			(net "M_D_DQ<39>")
		)
		(pad "248" smd rect
			(at -4.59994 92.650056 270)
			(size 1.8034 0.508)
			(layers "B.Cu" "B.Mask" "B.Paste")
			(net "GND")
		)
		(pad "249" smd rect
			(at -4.59994 93.49994 270)
			(size 1.8034 0.508)
			(layers "B.Cu" "B.Mask" "B.Paste")
			(net "M_D_DQ<35>")
		)
		(pad "250" smd rect
			(at -4.59994 94.350078 270)
			(size 1.8034 0.508)
			(layers "B.Cu" "B.Mask" "B.Paste")
			(net "GND")
		)
		(pad "251" smd rect
			(at -4.59994 95.199962 270)
			(size 1.8034 0.508)
			(layers "B.Cu" "B.Mask" "B.Paste")
			(net "M_D_DQ<45>")
		)
		(pad "252" smd rect
			(at -4.59994 96.0501 270)
			(size 1.8034 0.508)
			(layers "B.Cu" "B.Mask" "B.Paste")
			(net "GND")
		)
		(pad "253" smd rect
			(at -4.59994 96.899984 270)
			(size 1.8034 0.508)
			(layers "B.Cu" "B.Mask" "B.Paste")
			(net "M_D_DQ<41>")
		)
		(pad "254" smd rect
			(at -4.59994 97.750122 270)
			(size 1.8034 0.508)
			(layers "B.Cu" "B.Mask" "B.Paste")
			(net "GND")
		)
		(pad "255" smd rect
			(at -4.59994 98.600006 270)
			(size 1.8034 0.508)
			(layers "B.Cu" "B.Mask" "B.Paste")
			(net "M_D_DQS_DN<5>")
		)
		(pad "256" smd rect
			(at -4.59994 99.44989 270)
			(size 1.8034 0.508)
			(layers "B.Cu" "B.Mask" "B.Paste")
			(net "M_D_DQS_DP<5>")
		)
		(pad "257" smd rect
			(at -4.59994 100.300028 270)
			(size 1.8034 0.508)
			(layers "B.Cu" "B.Mask" "B.Paste")
			(net "GND")
		)
		(pad "258" smd rect
			(at -4.59994 101.149912 270)
			(size 1.8034 0.508)
			(layers "B.Cu" "B.Mask" "B.Paste")
			(net "M_D_DQ<47>")
		)
		(pad "259" smd rect
			(at -4.59994 102.00005 270)
			(size 1.8034 0.508)
			(layers "B.Cu" "B.Mask" "B.Paste")
			(net "GND")
		)
		(pad "260" smd rect
			(at -4.59994 102.849934 270)
			(size 1.8034 0.508)
			(layers "B.Cu" "B.Mask" "B.Paste")
			(net "M_D_DQ<43>")
		)
		(pad "261" smd rect
			(at -4.59994 103.700072 270)
			(size 1.8034 0.508)
			(layers "B.Cu" "B.Mask" "B.Paste")
			(net "GND")
		)
		(pad "262" smd rect
			(at -4.59994 104.549956 270)
			(size 1.8034 0.508)
			(layers "B.Cu" "B.Mask" "B.Paste")
			(net "M_D_DQ<53>")
		)
		(pad "263" smd rect
			(at -4.59994 105.400094 270)
			(size 1.8034 0.508)
			(layers "B.Cu" "B.Mask" "B.Paste")
			(net "GND")
		)
		(pad "264" smd rect
			(at -4.59994 106.249978 270)
			(size 1.8034 0.508)
			(layers "B.Cu" "B.Mask" "B.Paste")
			(net "M_D_DQ<49>")
		)
		(pad "265" smd rect
			(at -4.59994 107.100116 270)
			(size 1.8034 0.508)
			(layers "B.Cu" "B.Mask" "B.Paste")
			(net "GND")
		)
		(pad "266" smd rect
			(at -4.59994 107.95 270)
			(size 1.8034 0.508)
			(layers "B.Cu" "B.Mask" "B.Paste")
			(net "M_D_DQS_DN<6>")
		)
		(pad "267" smd rect
			(at -4.59994 108.799884 270)
			(size 1.8034 0.508)
			(layers "B.Cu" "B.Mask" "B.Paste")
			(net "M_D_DQS_DP<6>")
		)
		(pad "268" smd rect
			(at -4.59994 109.650022 270)
			(size 1.8034 0.508)
			(layers "B.Cu" "B.Mask" "B.Paste")
			(net "GND")
		)
		(pad "269" smd rect
			(at -4.59994 110.499906 270)
			(size 1.8034 0.508)
			(layers "B.Cu" "B.Mask" "B.Paste")
			(net "M_D_DQ<55>")
		)
		(pad "270" smd rect
			(at -4.59994 111.350044 270)
			(size 1.8034 0.508)
			(layers "B.Cu" "B.Mask" "B.Paste")
			(net "GND")
		)
		(pad "271" smd rect
			(at -4.59994 112.199928 270)
			(size 1.8034 0.508)
			(layers "B.Cu" "B.Mask" "B.Paste")
			(net "M_D_DQ<51>")
		)
		(pad "272" smd rect
			(at -4.59994 113.050066 270)
			(size 1.8034 0.508)
			(layers "B.Cu" "B.Mask" "B.Paste")
			(net "GND")
		)
		(pad "273" smd rect
			(at -4.59994 113.89995 270)
			(size 1.8034 0.508)
			(layers "B.Cu" "B.Mask" "B.Paste")
			(net "M_D_DQ<61>")
		)
		(pad "274" smd rect
			(at -4.59994 114.750088 270)
			(size 1.8034 0.508)
			(layers "B.Cu" "B.Mask" "B.Paste")
			(net "GND")
		)
		(pad "275" smd rect
			(at -4.59994 115.599972 270)
			(size 1.8034 0.508)
			(layers "B.Cu" "B.Mask" "B.Paste")
			(net "M_D_DQ<57>")
		)
		(pad "276" smd rect
			(at -4.59994 116.45011 270)
			(size 1.8034 0.508)
			(layers "B.Cu" "B.Mask" "B.Paste")
			(net "GND")
		)
		(pad "277" smd rect
			(at -4.59994 117.299994 270)
			(size 1.8034 0.508)
			(layers "B.Cu" "B.Mask" "B.Paste")
			(net "M_D_DQS_DN<7>")
		)
		(pad "278" smd rect
			(at -4.59994 118.149878 270)
			(size 1.8034 0.508)
			(layers "B.Cu" "B.Mask" "B.Paste")
			(net "M_D_DQS_DP<7>")
		)
		(pad "279" smd rect
			(at -4.59994 119.000016 270)
			(size 1.8034 0.508)
			(layers "B.Cu" "B.Mask" "B.Paste")
			(net "GND")
		)
		(pad "280" smd rect
			(at -4.59994 119.8499 270)
			(size 1.8034 0.508)
			(layers "B.Cu" "B.Mask" "B.Paste")
			(net "M_D_DQ<63>")
		)
		(pad "281" smd rect
			(at -4.59994 120.700038 270)
			(size 1.8034 0.508)
			(layers "B.Cu" "B.Mask" "B.Paste")
			(net "GND")
		)
		(pad "282" smd rect
			(at -4.59994 121.549922 270)
			(size 1.8034 0.508)
			(layers "B.Cu" "B.Mask" "B.Paste")
			(net "M_D_DQ<59>")
		)
		(pad "283" smd rect
			(at -4.59994 122.40006 270)
			(size 1.8034 0.508)
			(layers "B.Cu" "B.Mask" "B.Paste")
			(net "GND")
		)
		(pad "284" smd rect
			(at -4.59994 123.249944 270)
			(size 1.8034 0.508)
			(layers "B.Cu" "B.Mask" "B.Paste")
			(net "PVPP_DEF")
		)
		(pad "285" smd rect
			(at -4.59994 124.100082 270)
			(size 1.8034 0.508)
			(layers "B.Cu" "B.Mask" "B.Paste")
			(net "SMB_DDR_DEF_VPP_SDA")
		)
		(pad "286" smd rect
			(at -4.59994 124.949966 270)
			(size 1.8034 0.508)
			(layers "B.Cu" "B.Mask" "B.Paste")
			(net "PVPP_DEF")
		)
		(pad "287" smd rect
			(at -4.59994 125.800104 270)
			(size 1.8034 0.508)
			(layers "B.Cu" "B.Mask" "B.Paste")
			(net "PVPP_DEF")
		)
		(pad "288" smd rect
			(at -4.59994 126.649988 270)
			(size 1.8034 0.508)
			(layers "B.Cu" "B.Mask" "B.Paste")
			(net "PVPP_DEF")
		)
	)
	(footprint ""
		(layer "B.Cu")
		(at 373.6975 -56.769 -90)
		(property "Reference" "R3P59"
			(at 0 0 90)
			(layer "B.SilkS")
			(hide yes)
			(effects
				(font
					(size 1.27 1.27)
				)
				(justify mirror)
			)
		)
		(property "Value" ""
			(at 0 0 90)
			(layer "B.Fab")
			(effects
				(font
					(size 1.27 1.27)
				)
				(justify mirror)
			)
		)
		(duplicate_pad_numbers_are_jumpers no)
		(fp_poly
			(pts
				(xy 0.2794 -0.1016) (xy -0.2794 -0.1016) (xy -0.2794 0.9906) (xy 0.2794 0.9906)
			)
			(stroke
				(width 0)
				(type default)
			)
			(fill no)
			(layer "B.CrtYd")
		)
		(fp_line
			(start -0.2794 0.9906)
			(end -0.2794 -0.1016)
			(stroke
				(width 0.1)
				(type default)
			)
			(layer "B.Fab")
		)
		(fp_line
			(start 0.2794 0.9906)
			(end -0.2794 0.9906)
			(stroke
				(width 0.1)
				(type default)
			)
			(layer "B.Fab")
		)
		(fp_line
			(start -0.2794 -0.1016)
			(end 0.2794 -0.1016)
			(stroke
				(width 0.1)
				(type default)
			)
			(layer "B.Fab")
		)
		(fp_line
			(start 0.2794 -0.1016)
			(end 0.2794 0.9906)
			(stroke
				(width 0.1)
				(type default)
			)
			(layer "B.Fab")
		)
		(pad "1" smd rect
			(at 0 0 90)
			(size 0.508 0.508)
			(layers "B.Cu" "B.Mask" "B.Paste")
			(net "H_CPU0_CATERR_G_N")
		)
		(pad "2" smd rect
			(at 0 0.889 90)
			(size 0.508 0.508)
			(layers "B.Cu" "B.Mask" "B.Paste")
			(net "H_CPU_CATERR_G_N")
		)
		(zone
			(layer "B.Cu")
			(hatch none 0.5)
			(connect_pads
				(clearance 0)
			)
			(min_thickness 0.25)
			(keepout
				(tracks not_allowed)
				(vias allowed)
				(pads allowed)
				(copperpour not_allowed)
				(footprints allowed)
			)
			(placement
				(enabled no)
				(sheetname "")
			)
			(fill
				(thermal_gap 0.5)
				(thermal_bridge_width 0.5)
				(island_removal_mode 0)
			)
			(polygon
				(pts
					(xy 373.0625 -56.515) (xy 373.0625 -57.023) (xy 373.4435 -57.023) (xy 373.4435 -56.515)
				)
			)
		)
		(zone
			(layer "B.Cu")
			(hatch none 0.5)
			(connect_pads
				(clearance 0)
			)
			(min_thickness 0.25)
			(keepout
				(tracks allowed)
				(vias not_allowed)
				(pads allowed)
				(copperpour not_allowed)
				(footprints allowed)
			)
			(placement
				(enabled no)
				(sheetname "")
			)
			(fill
				(thermal_gap 0.5)
				(thermal_bridge_width 0.5)
				(island_removal_mode 0)
			)
			(polygon
				(pts
					(xy 373.4435 -56.515) (xy 373.4435 -57.023) (xy 373.0625 -57.023) (xy 373.0625 -56.515)
				)
			)
		)
	)
	(footprint ""
		(layer "B.Cu")
		(at 441.3504 -52.2986)
		(property "Reference" "C2R9"
			(at 0 0 0)
			(layer "B.SilkS")
			(hide yes)
			(effects
				(font
					(size 1.27 1.27)
				)
				(justify mirror)
			)
		)
		(property "Value" ""
			(at 0 0 0)
			(layer "B.Fab")
			(effects
				(font
					(size 1.27 1.27)
				)
				(justify mirror)
			)
		)
		(duplicate_pad_numbers_are_jumpers no)
		(fp_poly
			(pts
				(xy -0.3048 -0.1016) (xy -0.3048 0.9906) (xy 0.3048 0.9906) (xy 0.3048 -0.1016)
			)
			(stroke
				(width 0)
				(type default)
			)
			(fill no)
			(layer "B.CrtYd")
		)
		(fp_line
			(start -0.3048 -0.1016)
			(end 0.3048 -0.1016)
			(stroke
				(width 0.1)
				(type default)
			)
			(layer "B.Fab")
		)
		(fp_line
			(start -0.3048 0.9906)
			(end -0.3048 -0.1016)
			(stroke
				(width 0.1)
				(type default)
			)
			(layer "B.Fab")
		)
		(fp_line
			(start 0.3048 -0.1016)
			(end 0.3048 0.9906)
			(stroke
				(width 0.1)
				(type default)
			)
			(layer "B.Fab")
		)
		(fp_line
			(start 0.3048 0.9906)
			(end -0.3048 0.9906)
			(stroke
				(width 0.1)
				(type default)
			)
			(layer "B.Fab")
		)
		(pad "1" smd rect
			(at 0 0 180)
			(size 0.508 0.508)
			(layers "B.Cu" "B.Mask" "B.Paste")
			(net "P3E_CPU0_PE3_OCP_TXN<7>")
		)
		(pad "2" smd rect
			(at 0 0.889 180)
			(size 0.508 0.508)
			(layers "B.Cu" "B.Mask" "B.Paste")
			(net "P3E_OCP_CPU0_PE3_C_TXN<7>")
		)
		(zone
			(layer "B.Cu")
			(hatch none 0.5)
			(connect_pads
				(clearance 0)
			)
			(min_thickness 0.25)
			(keepout
				(tracks allowed)
				(vias not_allowed)
				(pads allowed)
				(copperpour not_allowed)
				(footprints allowed)
			)
			(placement
				(enabled no)
				(sheetname "")
			)
			(fill
				(thermal_gap 0.5)
				(thermal_bridge_width 0.5)
				(island_removal_mode 0)
			)
			(polygon
				(pts
					(xy 441.6044 -52.0446) (xy 441.0964 -52.0446) (xy 441.0964 -51.6636) (xy 441.6044 -51.6636)
				)
			)
		)
		(zone
			(layer "B.Cu")
			(hatch none 0.5)
			(connect_pads
				(clearance 0)
			)
			(min_thickness 0.25)
			(keepout
				(tracks not_allowed)
				(vias allowed)
				(pads allowed)
				(copperpour not_allowed)
				(footprints allowed)
			)
			(placement
				(enabled no)
				(sheetname "")
			)
			(fill
				(thermal_gap 0.5)
				(thermal_bridge_width 0.5)
				(island_removal_mode 0)
			)
			(polygon
				(pts
					(xy 441.6044 -51.6636) (xy 441.0964 -51.6636) (xy 441.0964 -52.0446) (xy 441.6044 -52.0446)
				)
			)
		)
	)
	(footprint ""
		(layer "B.Cu")
		(at 472.059 -112.141 -90)
		(property "Reference" "R1M18"
			(at 0 0 90)
			(layer "B.SilkS")
			(hide yes)
			(effects
				(font
					(size 1.27 1.27)
				)
				(justify mirror)
			)
		)
		(property "Value" ""
			(at 0 0 90)
			(layer "B.Fab")
			(effects
				(font
					(size 1.27 1.27)
				)
				(justify mirror)
			)
		)
		(duplicate_pad_numbers_are_jumpers no)
		(fp_poly
			(pts
				(xy 0.2794 -0.1016) (xy -0.2794 -0.1016) (xy -0.2794 0.9906) (xy 0.2794 0.9906)
			)
			(stroke
				(width 0)
				(type default)
			)
			(fill no)
			(layer "B.CrtYd")
		)
		(fp_line
			(start -0.2794 0.9906)
			(end -0.2794 -0.1016)
			(stroke
				(width 0.1)
				(type default)
			)
			(layer "B.Fab")
		)
		(fp_line
			(start 0.2794 0.9906)
			(end -0.2794 0.9906)
			(stroke
				(width 0.1)
				(type default)
			)
			(layer "B.Fab")
		)
		(fp_line
			(start -0.2794 -0.1016)
			(end 0.2794 -0.1016)
			(stroke
				(width 0.1)
				(type default)
			)
			(layer "B.Fab")
		)
		(fp_line
			(start 0.2794 -0.1016)
			(end 0.2794 0.9906)
			(stroke
				(width 0.1)
				(type default)
			)
			(layer "B.Fab")
		)
		(pad "1" smd rect
			(at 0 0 90)
			(size 0.508 0.508)
			(layers "B.Cu" "B.Mask" "B.Paste")
			(net "RMII_BMC_OCP_RXER_R")
		)
		(pad "2" smd rect
			(at 0 0.889 90)
			(size 0.508 0.508)
			(layers "B.Cu" "B.Mask" "B.Paste")
			(net "RMII_BMC_OCP_RXER")
		)
		(zone
			(layer "B.Cu")
			(hatch none 0.5)
			(connect_pads
				(clearance 0)
			)
			(min_thickness 0.25)
			(keepout
				(tracks not_allowed)
				(vias allowed)
				(pads allowed)
				(copperpour not_allowed)
				(footprints allowed)
			)
			(placement
				(enabled no)
				(sheetname "")
			)
			(fill
				(thermal_gap 0.5)
				(thermal_bridge_width 0.5)
				(island_removal_mode 0)
			)
			(polygon
				(pts
					(xy 471.424 -111.887) (xy 471.424 -112.395) (xy 471.805 -112.395) (xy 471.805 -111.887)
				)
			)
		)
		(zone
			(layer "B.Cu")
			(hatch none 0.5)
			(connect_pads
				(clearance 0)
			)
			(min_thickness 0.25)
			(keepout
				(tracks allowed)
				(vias not_allowed)
				(pads allowed)
				(copperpour not_allowed)
				(footprints allowed)
			)
			(placement
				(enabled no)
				(sheetname "")
			)
			(fill
				(thermal_gap 0.5)
				(thermal_bridge_width 0.5)
				(island_removal_mode 0)
			)
			(polygon
				(pts
					(xy 471.805 -111.887) (xy 471.805 -112.395) (xy 471.424 -112.395) (xy 471.424 -111.887)
				)
			)
		)
	)
	(footprint ""
		(layer "B.Cu")
		(at 405.726646 -26.489152)
		(property "Reference" "R1U38"
			(at 0 0 0)
			(layer "B.SilkS")
			(hide yes)
			(effects
				(font
					(size 1.27 1.27)
				)
				(justify mirror)
			)
		)
		(property "Value" ""
			(at 0 0 0)
			(layer "B.Fab")
			(effects
				(font
					(size 1.27 1.27)
				)
				(justify mirror)
			)
		)
		(duplicate_pad_numbers_are_jumpers no)
		(fp_poly
			(pts
				(xy 0.2794 -0.1016) (xy -0.2794 -0.1016) (xy -0.2794 0.9906) (xy 0.2794 0.9906)
			)
			(stroke
				(width 0)
				(type default)
			)
			(fill no)
			(layer "B.CrtYd")
		)
		(fp_line
			(start -0.2794 -0.1016)
			(end 0.2794 -0.1016)
			(stroke
				(width 0.1)
				(type default)
			)
			(layer "B.Fab")
		)
		(fp_line
			(start -0.2794 0.9906)
			(end -0.2794 -0.1016)
			(stroke
				(width 0.1)
				(type default)
			)
			(layer "B.Fab")
		)
		(fp_line
			(start 0.2794 -0.1016)
			(end 0.2794 0.9906)
			(stroke
				(width 0.1)
				(type default)
			)
			(layer "B.Fab")
		)
		(fp_line
			(start 0.2794 0.9906)
			(end -0.2794 0.9906)
			(stroke
				(width 0.1)
				(type default)
			)
			(layer "B.Fab")
		)
		(pad "1" smd rect
			(at 0 0 180)
			(size 0.508 0.508)
			(layers "B.Cu" "B.Mask" "B.Paste")
			(net "A_P3V3_STBY_SCALED")
		)
		(pad "2" smd rect
			(at 0 0.889 180)
			(size 0.508 0.508)
			(layers "B.Cu" "B.Mask" "B.Paste")
			(net "GND")
		)
		(zone
			(layer "B.Cu")
			(hatch none 0.5)
			(connect_pads
				(clearance 0)
			)
			(min_thickness 0.25)
			(keepout
				(tracks allowed)
				(vias not_allowed)
				(pads allowed)
				(copperpour not_allowed)
				(footprints allowed)
			)
			(placement
				(enabled no)
				(sheetname "")
			)
			(fill
				(thermal_gap 0.5)
				(thermal_bridge_width 0.5)
				(island_removal_mode 0)
			)
			(polygon
				(pts
					(xy 405.980646 -26.235152) (xy 405.472646 -26.235152) (xy 405.472646 -25.854152) (xy 405.980646 -25.854152)
				)
			)
		)
		(zone
			(layer "B.Cu")
			(hatch none 0.5)
			(connect_pads
				(clearance 0)
			)
			(min_thickness 0.25)
			(keepout
				(tracks not_allowed)
				(vias allowed)
				(pads allowed)
				(copperpour not_allowed)
				(footprints allowed)
			)
			(placement
				(enabled no)
				(sheetname "")
			)
			(fill
				(thermal_gap 0.5)
				(thermal_bridge_width 0.5)
				(island_removal_mode 0)
			)
			(polygon
				(pts
					(xy 405.980646 -25.854152) (xy 405.472646 -25.854152) (xy 405.472646 -26.235152) (xy 405.980646 -26.235152)
				)
			)
		)
	)
	(footprint ""
		(layer "B.Cu")
		(at 192.786 -154.559 180)
		(property "Reference" "R6L3"
			(at 0 0 0)
			(layer "B.SilkS")
			(hide yes)
			(effects
				(font
					(size 1.27 1.27)
				)
				(justify mirror)
			)
		)
		(property "Value" ""
			(at 0 0 0)
			(layer "B.Fab")
			(effects
				(font
					(size 1.27 1.27)
				)
				(justify mirror)
			)
		)
		(duplicate_pad_numbers_are_jumpers no)
		(fp_poly
			(pts
				(xy 0.2794 -0.1016) (xy -0.2794 -0.1016) (xy -0.2794 0.9906) (xy 0.2794 0.9906)
			)
			(stroke
				(width 0)
				(type default)
			)
			(fill no)
			(layer "B.CrtYd")
		)
		(fp_line
			(start 0.2794 0.9906)
			(end -0.2794 0.9906)
			(stroke
				(width 0.1)
				(type default)
			)
			(layer "B.Fab")
		)
		(fp_line
			(start 0.2794 -0.1016)
			(end 0.2794 0.9906)
			(stroke
				(width 0.1)
				(type default)
			)
			(layer "B.Fab")
		)
		(fp_line
			(start -0.2794 0.9906)
			(end -0.2794 -0.1016)
			(stroke
				(width 0.1)
				(type default)
			)
			(layer "B.Fab")
		)
		(fp_line
			(start -0.2794 -0.1016)
			(end 0.2794 -0.1016)
			(stroke
				(width 0.1)
				(type default)
			)
			(layer "B.Fab")
		)
		(pad "1" smd rect
			(at 0 0)
			(size 0.508 0.508)
			(layers "B.Cu" "B.Mask" "B.Paste")
			(net "M_F_CPU_VREF")
		)
		(pad "2" smd rect
			(at 0 0.889)
			(size 0.508 0.508)
			(layers "B.Cu" "B.Mask" "B.Paste")
			(net "M_F_VREF")
		)
		(zone
			(layer "B.Cu")
			(hatch none 0.5)
			(connect_pads
				(clearance 0)
			)
			(min_thickness 0.25)
			(keepout
				(tracks not_allowed)
				(vias allowed)
				(pads allowed)
				(copperpour not_allowed)
				(footprints allowed)
			)
			(placement
				(enabled no)
				(sheetname "")
			)
			(fill
				(thermal_gap 0.5)
				(thermal_bridge_width 0.5)
				(island_removal_mode 0)
			)
			(polygon
				(pts
					(xy 192.532 -155.194) (xy 193.04 -155.194) (xy 193.04 -154.813) (xy 192.532 -154.813)
				)
			)
		)
		(zone
			(layer "B.Cu")
			(hatch none 0.5)
			(connect_pads
				(clearance 0)
			)
			(min_thickness 0.25)
			(keepout
				(tracks allowed)
				(vias not_allowed)
				(pads allowed)
				(copperpour not_allowed)
				(footprints allowed)
			)
			(placement
				(enabled no)
				(sheetname "")
			)
			(fill
				(thermal_gap 0.5)
				(thermal_bridge_width 0.5)
				(island_removal_mode 0)
			)
			(polygon
				(pts
					(xy 192.532 -154.813) (xy 193.04 -154.813) (xy 193.04 -155.194) (xy 192.532 -155.194)
				)
			)
		)
	)
	(footprint ""
		(layer "B.Cu")
		(at 444.45174 -20.85848 180)
		(property "Reference" "C8W2"
			(at 0.8382 -0.67818 180)
			(unlocked yes)
			(layer "B.SilkS")
			(effects
				(font
					(size 0.4064 0.254)
					(thickness 0.1524)
				)
				(justify left mirror)
			)
		)
		(property "Value" ""
			(at 0 0 0)
			(layer "B.Fab")
			(effects
				(font
					(size 1.27 1.27)
				)
				(justify mirror)
			)
		)
		(duplicate_pad_numbers_are_jumpers no)
		(fp_poly
			(pts
				(xy -0.3048 -0.1016) (xy -0.3048 0.9906) (xy 0.3048 0.9906) (xy 0.3048 -0.1016)
			)
			(stroke
				(width 0)
				(type default)
			)
			(fill no)
			(layer "B.CrtYd")
		)
		(fp_line
			(start 0.3048 0.9906)
			(end -0.3048 0.9906)
			(stroke
				(width 0.1)
				(type default)
			)
			(layer "B.Fab")
		)
		(fp_line
			(start 0.3048 -0.1016)
			(end 0.3048 0.9906)
			(stroke
				(width 0.1)
				(type default)
			)
			(layer "B.Fab")
		)
		(fp_line
			(start -0.3048 0.9906)
			(end -0.3048 -0.1016)
			(stroke
				(width 0.1)
				(type default)
			)
			(layer "B.Fab")
		)
		(fp_line
			(start -0.3048 -0.1016)
			(end 0.3048 -0.1016)
			(stroke
				(width 0.1)
				(type default)
			)
			(layer "B.Fab")
		)
		(pad "1" smd rect
			(at 0 0)
			(size 0.508 0.508)
			(layers "B.Cu" "B.Mask" "B.Paste")
			(net "P5V_STBY")
		)
		(pad "2" smd rect
			(at 0 0.889)
			(size 0.508 0.508)
			(layers "B.Cu" "B.Mask" "B.Paste")
			(net "GND")
		)
		(zone
			(layer "B.Cu")
			(hatch none 0.5)
			(connect_pads
				(clearance 0)
			)
			(min_thickness 0.25)
			(keepout
				(tracks not_allowed)
				(vias allowed)
				(pads allowed)
				(copperpour not_allowed)
				(footprints allowed)
			)
			(placement
				(enabled no)
				(sheetname "")
			)
			(fill
				(thermal_gap 0.5)
				(thermal_bridge_width 0.5)
				(island_removal_mode 0)
			)
			(polygon
				(pts
					(xy 444.19774 -21.49348) (xy 444.70574 -21.49348) (xy 444.70574 -21.11248) (xy 444.19774 -21.11248)
				)
			)
		)
		(zone
			(layer "B.Cu")
			(hatch none 0.5)
			(connect_pads
				(clearance 0)
			)
			(min_thickness 0.25)
			(keepout
				(tracks allowed)
				(vias not_allowed)
				(pads allowed)
				(copperpour not_allowed)
				(footprints allowed)
			)
			(placement
				(enabled no)
				(sheetname "")
			)
			(fill
				(thermal_gap 0.5)
				(thermal_bridge_width 0.5)
				(island_removal_mode 0)
			)
			(polygon
				(pts
					(xy 444.19774 -21.11248) (xy 444.70574 -21.11248) (xy 444.70574 -21.49348) (xy 444.19774 -21.49348)
				)
			)
		)
	)
	(footprint ""
		(layer "B.Cu")
		(at 447.136266 -22.269196 -90)
		(property "Reference" "R8W4"
			(at 0.8382 -0.67818 270)
			(unlocked yes)
			(layer "B.SilkS")
			(effects
				(font
					(size 0.4064 0.254)
					(thickness 0.1524)
				)
				(justify left mirror)
			)
		)
		(property "Value" ""
			(at 0 0 90)
			(layer "B.Fab")
			(effects
				(font
					(size 1.27 1.27)
				)
				(justify mirror)
			)
		)
		(duplicate_pad_numbers_are_jumpers no)
		(fp_poly
			(pts
				(xy 0.2794 -0.1016) (xy -0.2794 -0.1016) (xy -0.2794 0.9906) (xy 0.2794 0.9906)
			)
			(stroke
				(width 0)
				(type default)
			)
			(fill no)
			(layer "B.CrtYd")
		)
		(fp_line
			(start -0.2794 0.9906)
			(end -0.2794 -0.1016)
			(stroke
				(width 0.1)
				(type default)
			)
			(layer "B.Fab")
		)
		(fp_line
			(start 0.2794 0.9906)
			(end -0.2794 0.9906)
			(stroke
				(width 0.1)
				(type default)
			)
			(layer "B.Fab")
		)
		(fp_line
			(start -0.2794 -0.1016)
			(end 0.2794 -0.1016)
			(stroke
				(width 0.1)
				(type default)
			)
			(layer "B.Fab")
		)
		(fp_line
			(start 0.2794 -0.1016)
			(end 0.2794 0.9906)
			(stroke
				(width 0.1)
				(type default)
			)
			(layer "B.Fab")
		)
		(pad "1" smd rect
			(at 0 0 90)
			(size 0.508 0.508)
			(layers "B.Cu" "B.Mask" "B.Paste")
			(net "SMB_HOST_STBY_LVC3_SDA")
		)
		(pad "2" smd rect
			(at 0 0.889 90)
			(size 0.508 0.508)
			(layers "B.Cu" "B.Mask" "B.Paste")
			(net "SMB_HOST_STBY_LVC3_SDA_R5")
		)
		(zone
			(layer "B.Cu")
			(hatch none 0.5)
			(connect_pads
				(clearance 0)
			)
			(min_thickness 0.25)
			(keepout
				(tracks not_allowed)
				(vias allowed)
				(pads allowed)
				(copperpour not_allowed)
				(footprints allowed)
			)
			(placement
				(enabled no)
				(sheetname "")
			)
			(fill
				(thermal_gap 0.5)
				(thermal_bridge_width 0.5)
				(island_removal_mode 0)
			)
			(polygon
				(pts
					(xy 446.501266 -22.015196) (xy 446.501266 -22.523196) (xy 446.882266 -22.523196) (xy 446.882266 -22.015196)
				)
			)
		)
		(zone
			(layer "B.Cu")
			(hatch none 0.5)
			(connect_pads
				(clearance 0)
			)
			(min_thickness 0.25)
			(keepout
				(tracks allowed)
				(vias not_allowed)
				(pads allowed)
				(copperpour not_allowed)
				(footprints allowed)
			)
			(placement
				(enabled no)
				(sheetname "")
			)
			(fill
				(thermal_gap 0.5)
				(thermal_bridge_width 0.5)
				(island_removal_mode 0)
			)
			(polygon
				(pts
					(xy 446.882266 -22.015196) (xy 446.882266 -22.523196) (xy 446.501266 -22.523196) (xy 446.501266 -22.015196)
				)
			)
		)
	)
	(footprint ""
		(layer "B.Cu")
		(at 404.5585 -98.679 -90)
		(property "Reference" "R8C25"
			(at 0 0 90)
			(layer "B.SilkS")
			(hide yes)
			(effects
				(font
					(size 1.27 1.27)
				)
				(justify mirror)
			)
		)
		(property "Value" ""
			(at 0 0 90)
			(layer "B.Fab")
			(effects
				(font
					(size 1.27 1.27)
				)
				(justify mirror)
			)
		)
		(duplicate_pad_numbers_are_jumpers no)
		(fp_poly
			(pts
				(xy 0.2794 -0.1016) (xy -0.2794 -0.1016) (xy -0.2794 0.9906) (xy 0.2794 0.9906)
			)
			(stroke
				(width 0)
				(type default)
			)
			(fill no)
			(layer "B.CrtYd")
		)
		(fp_line
			(start -0.2794 0.9906)
			(end -0.2794 -0.1016)
			(stroke
				(width 0.1)
				(type default)
			)
			(layer "B.Fab")
		)
		(fp_line
			(start 0.2794 0.9906)
			(end -0.2794 0.9906)
			(stroke
				(width 0.1)
				(type default)
			)
			(layer "B.Fab")
		)
		(fp_line
			(start -0.2794 -0.1016)
			(end 0.2794 -0.1016)
			(stroke
				(width 0.1)
				(type default)
			)
			(layer "B.Fab")
		)
		(fp_line
			(start 0.2794 -0.1016)
			(end 0.2794 0.9906)
			(stroke
				(width 0.1)
				(type default)
			)
			(layer "B.Fab")
		)
		(pad "1" smd rect
			(at 0 0 90)
			(size 0.508 0.508)
			(layers "B.Cu" "B.Mask" "B.Paste")
			(net "P3V3_STBY")
		)
		(pad "2" smd rect
			(at 0 0.889 90)
			(size 0.508 0.508)
			(layers "B.Cu" "B.Mask" "B.Paste")
			(net "IRQ_PCH_NIC_ALERT_N")
		)
		(zone
			(layer "B.Cu")
			(hatch none 0.5)
			(connect_pads
				(clearance 0)
			)
			(min_thickness 0.25)
			(keepout
				(tracks not_allowed)
				(vias allowed)
				(pads allowed)
				(copperpour not_allowed)
				(footprints allowed)
			)
			(placement
				(enabled no)
				(sheetname "")
			)
			(fill
				(thermal_gap 0.5)
				(thermal_bridge_width 0.5)
				(island_removal_mode 0)
			)
			(polygon
				(pts
					(xy 403.9235 -98.425) (xy 403.9235 -98.933) (xy 404.3045 -98.933) (xy 404.3045 -98.425)
				)
			)
		)
		(zone
			(layer "B.Cu")
			(hatch none 0.5)
			(connect_pads
				(clearance 0)
			)
			(min_thickness 0.25)
			(keepout
				(tracks allowed)
				(vias not_allowed)
				(pads allowed)
				(copperpour not_allowed)
				(footprints allowed)
			)
			(placement
				(enabled no)
				(sheetname "")
			)
			(fill
				(thermal_gap 0.5)
				(thermal_bridge_width 0.5)
				(island_removal_mode 0)
			)
			(polygon
				(pts
					(xy 404.3045 -98.425) (xy 404.3045 -98.933) (xy 403.9235 -98.933) (xy 403.9235 -98.425)
				)
			)
		)
	)
	(footprint ""
		(layer "B.Cu")
		(at 100.863654 -73.51014)
		(property "Reference" "C8P25"
			(at 0 0 0)
			(layer "B.SilkS")
			(hide yes)
			(effects
				(font
					(size 1.27 1.27)
				)
				(justify mirror)
			)
		)
		(property "Value" ""
			(at 0 0 0)
			(layer "B.Fab")
			(effects
				(font
					(size 1.27 1.27)
				)
				(justify mirror)
			)
		)
		(duplicate_pad_numbers_are_jumpers no)
		(fp_poly
			(pts
				(xy 0.7239 -0.2159) (xy -0.7239 -0.2159) (xy -0.7239 1.9939) (xy 0.7239 1.9939)
			)
			(stroke
				(width 0)
				(type default)
			)
			(fill no)
			(layer "B.CrtYd")
		)
		(fp_line
			(start -0.7239 -0.2159)
			(end 0.7239 -0.2159)
			(stroke
				(width 0.1)
				(type default)
			)
			(layer "B.Fab")
		)
		(fp_line
			(start -0.7239 1.9939)
			(end -0.7239 -0.2159)
			(stroke
				(width 0.1)
				(type default)
			)
			(layer "B.Fab")
		)
		(fp_line
			(start 0.7239 -0.2159)
			(end 0.7239 1.9939)
			(stroke
				(width 0.1)
				(type default)
			)
			(layer "B.Fab")
		)
		(fp_line
			(start 0.7239 1.9939)
			(end -0.7239 1.9939)
			(stroke
				(width 0.1)
				(type default)
			)
			(layer "B.Fab")
		)
		(pad "1" smd rect
			(at 0 0 180)
			(size 1.27 1.016)
			(layers "B.Cu" "B.Mask" "B.Paste")
			(net "PVCCIN_CPU1")
		)
		(pad "2" smd rect
			(at 0 1.778 180)
			(size 1.27 1.016)
			(layers "B.Cu" "B.Mask" "B.Paste")
			(net "GND")
		)
		(zone
			(layer "B.Cu")
			(hatch none 0.5)
			(connect_pads
				(clearance 0)
			)
			(min_thickness 0.25)
			(keepout
				(tracks not_allowed)
				(vias allowed)
				(pads allowed)
				(copperpour not_allowed)
				(footprints allowed)
			)
			(placement
				(enabled no)
				(sheetname "")
			)
			(fill
				(thermal_gap 0.5)
				(thermal_bridge_width 0.5)
				(island_removal_mode 0)
			)
			(polygon
				(pts
					(xy 101.498654 -73.00214) (xy 100.228654 -73.00214) (xy 100.228654 -72.24014) (xy 101.498654 -72.24014)
				)
			)
		)
	)
	(footprint ""
		(layer "B.Cu")
		(at 374.325642 -39.874952 -90)
		(property "Reference" "R2T19"
			(at 0 0 90)
			(layer "B.SilkS")
			(hide yes)
			(effects
				(font
					(size 1.27 1.27)
				)
				(justify mirror)
			)
		)
		(property "Value" ""
			(at 0 0 90)
			(layer "B.Fab")
			(effects
				(font
					(size 1.27 1.27)
				)
				(justify mirror)
			)
		)
		(duplicate_pad_numbers_are_jumpers no)
		(fp_poly
			(pts
				(xy 0.2794 -0.1016) (xy -0.2794 -0.1016) (xy -0.2794 0.9906) (xy 0.2794 0.9906)
			)
			(stroke
				(width 0)
				(type default)
			)
			(fill no)
			(layer "B.CrtYd")
		)
		(fp_line
			(start -0.2794 0.9906)
			(end -0.2794 -0.1016)
			(stroke
				(width 0.1)
				(type default)
			)
			(layer "B.Fab")
		)
		(fp_line
			(start 0.2794 0.9906)
			(end -0.2794 0.9906)
			(stroke
				(width 0.1)
				(type default)
			)
			(layer "B.Fab")
		)
		(fp_line
			(start -0.2794 -0.1016)
			(end 0.2794 -0.1016)
			(stroke
				(width 0.1)
				(type default)
			)
			(layer "B.Fab")
		)
		(fp_line
			(start 0.2794 -0.1016)
			(end 0.2794 0.9906)
			(stroke
				(width 0.1)
				(type default)
			)
			(layer "B.Fab")
		)
		(pad "1" smd rect
			(at 0 0 90)
			(size 0.508 0.508)
			(layers "B.Cu" "B.Mask" "B.Paste")
			(net "PVCCIO_CPU0")
		)
		(pad "2" smd rect
			(at 0 0.889 90)
			(size 0.508 0.508)
			(layers "B.Cu" "B.Mask" "B.Paste")
			(net "H_CPU_ERR0_GTL_R_N")
		)
		(zone
			(layer "B.Cu")
			(hatch none 0.5)
			(connect_pads
				(clearance 0)
			)
			(min_thickness 0.25)
			(keepout
				(tracks not_allowed)
				(vias allowed)
				(pads allowed)
				(copperpour not_allowed)
				(footprints allowed)
			)
			(placement
				(enabled no)
				(sheetname "")
			)
			(fill
				(thermal_gap 0.5)
				(thermal_bridge_width 0.5)
				(island_removal_mode 0)
			)
			(polygon
				(pts
					(xy 373.690642 -39.620952) (xy 373.690642 -40.128952) (xy 374.071642 -40.128952) (xy 374.071642 -39.620952)
				)
			)
		)
		(zone
			(layer "B.Cu")
			(hatch none 0.5)
			(connect_pads
				(clearance 0)
			)
			(min_thickness 0.25)
			(keepout
				(tracks allowed)
				(vias not_allowed)
				(pads allowed)
				(copperpour not_allowed)
				(footprints allowed)
			)
			(placement
				(enabled no)
				(sheetname "")
			)
			(fill
				(thermal_gap 0.5)
				(thermal_bridge_width 0.5)
				(island_removal_mode 0)
			)
			(polygon
				(pts
					(xy 374.071642 -39.620952) (xy 374.071642 -40.128952) (xy 373.690642 -40.128952) (xy 373.690642 -39.620952)
				)
			)
		)
	)
	(footprint ""
		(layer "B.Cu")
		(at 352.8949 -72.0344 -90)
		(property "Reference" "R7D39"
			(at 0 0 90)
			(layer "B.SilkS")
			(hide yes)
			(effects
				(font
					(size 1.27 1.27)
				)
				(justify mirror)
			)
		)
		(property "Value" ""
			(at 0 0 90)
			(layer "B.Fab")
			(effects
				(font
					(size 1.27 1.27)
				)
				(justify mirror)
			)
		)
		(duplicate_pad_numbers_are_jumpers no)
		(fp_poly
			(pts
				(xy 0.2794 -0.1016) (xy -0.2794 -0.1016) (xy -0.2794 0.9906) (xy 0.2794 0.9906)
			)
			(stroke
				(width 0)
				(type default)
			)
			(fill no)
			(layer "B.CrtYd")
		)
		(fp_line
			(start -0.2794 0.9906)
			(end -0.2794 -0.1016)
			(stroke
				(width 0.1)
				(type default)
			)
			(layer "B.Fab")
		)
		(fp_line
			(start 0.2794 0.9906)
			(end -0.2794 0.9906)
			(stroke
				(width 0.1)
				(type default)
			)
			(layer "B.Fab")
		)
		(fp_line
			(start -0.2794 -0.1016)
			(end 0.2794 -0.1016)
			(stroke
				(width 0.1)
				(type default)
			)
			(layer "B.Fab")
		)
		(fp_line
			(start 0.2794 -0.1016)
			(end 0.2794 0.9906)
			(stroke
				(width 0.1)
				(type default)
			)
			(layer "B.Fab")
		)
		(pad "1" smd rect
			(at 0 0 90)
			(size 0.508 0.508)
			(layers "B.Cu" "B.Mask" "B.Paste")
			(net "FM_CPU0_VRM_OSC_EN")
		)
		(pad "2" smd rect
			(at 0 0.889 90)
			(size 0.508 0.508)
			(layers "B.Cu" "B.Mask" "B.Paste")
			(net "FM_CPU0_VRM_322M_156M_OSC_EN")
		)
		(zone
			(layer "B.Cu")
			(hatch none 0.5)
			(connect_pads
				(clearance 0)
			)
			(min_thickness 0.25)
			(keepout
				(tracks not_allowed)
				(vias allowed)
				(pads allowed)
				(copperpour not_allowed)
				(footprints allowed)
			)
			(placement
				(enabled no)
				(sheetname "")
			)
			(fill
				(thermal_gap 0.5)
				(thermal_bridge_width 0.5)
				(island_removal_mode 0)
			)
			(polygon
				(pts
					(xy 352.2599 -71.7804) (xy 352.2599 -72.2884) (xy 352.6409 -72.2884) (xy 352.6409 -71.7804)
				)
			)
		)
		(zone
			(layer "B.Cu")
			(hatch none 0.5)
			(connect_pads
				(clearance 0)
			)
			(min_thickness 0.25)
			(keepout
				(tracks allowed)
				(vias not_allowed)
				(pads allowed)
				(copperpour not_allowed)
				(footprints allowed)
			)
			(placement
				(enabled no)
				(sheetname "")
			)
			(fill
				(thermal_gap 0.5)
				(thermal_bridge_width 0.5)
				(island_removal_mode 0)
			)
			(polygon
				(pts
					(xy 352.6409 -71.7804) (xy 352.6409 -72.2884) (xy 352.2599 -72.2884) (xy 352.2599 -71.7804)
				)
			)
		)
	)
	(footprint ""
		(layer "B.Cu")
		(at 113.575592 -69.809614 -90)
		(property "Reference" "C7P18"
			(at 0 0 90)
			(layer "B.SilkS")
			(hide yes)
			(effects
				(font
					(size 1.27 1.27)
				)
				(justify mirror)
			)
		)
		(property "Value" ""
			(at 0 0 90)
			(layer "B.Fab")
			(effects
				(font
					(size 1.27 1.27)
				)
				(justify mirror)
			)
		)
		(duplicate_pad_numbers_are_jumpers no)
		(fp_poly
			(pts
				(xy 0.7239 -0.2159) (xy -0.7239 -0.2159) (xy -0.7239 1.9939) (xy 0.7239 1.9939)
			)
			(stroke
				(width 0)
				(type default)
			)
			(fill no)
			(layer "B.CrtYd")
		)
		(fp_line
			(start -0.7239 1.9939)
			(end -0.7239 -0.2159)
			(stroke
				(width 0.1)
				(type default)
			)
			(layer "B.Fab")
		)
		(fp_line
			(start 0.7239 1.9939)
			(end -0.7239 1.9939)
			(stroke
				(width 0.1)
				(type default)
			)
			(layer "B.Fab")
		)
		(fp_line
			(start -0.7239 -0.2159)
			(end 0.7239 -0.2159)
			(stroke
				(width 0.1)
				(type default)
			)
			(layer "B.Fab")
		)
		(fp_line
			(start 0.7239 -0.2159)
			(end 0.7239 1.9939)
			(stroke
				(width 0.1)
				(type default)
			)
			(layer "B.Fab")
		)
		(pad "1" smd rect
			(at 0 0 90)
			(size 1.27 1.016)
			(layers "B.Cu" "B.Mask" "B.Paste")
			(net "PVCCIO_CPU1")
		)
		(pad "2" smd rect
			(at 0 1.778 90)
			(size 1.27 1.016)
			(layers "B.Cu" "B.Mask" "B.Paste")
			(net "GND")
		)
		(zone
			(layer "B.Cu")
			(hatch none 0.5)
			(connect_pads
				(clearance 0)
			)
			(min_thickness 0.25)
			(keepout
				(tracks not_allowed)
				(vias allowed)
				(pads allowed)
				(copperpour not_allowed)
				(footprints allowed)
			)
			(placement
				(enabled no)
				(sheetname "")
			)
			(fill
				(thermal_gap 0.5)
				(thermal_bridge_width 0.5)
				(island_removal_mode 0)
			)
			(polygon
				(pts
					(xy 113.067592 -69.174614) (xy 113.067592 -70.444614) (xy 112.305592 -70.444614) (xy 112.305592 -69.174614)
				)
			)
		)
	)
	(footprint ""
		(layer "B.Cu")
		(at 400.31416 -54.25186)
		(property "Reference" "R3T3"
			(at 0 0 0)
			(layer "B.SilkS")
			(hide yes)
			(effects
				(font
					(size 1.27 1.27)
				)
				(justify mirror)
			)
		)
		(property "Value" ""
			(at 0 0 0)
			(layer "B.Fab")
			(effects
				(font
					(size 1.27 1.27)
				)
				(justify mirror)
			)
		)
		(duplicate_pad_numbers_are_jumpers no)
		(fp_poly
			(pts
				(xy 0.2794 -0.1016) (xy -0.2794 -0.1016) (xy -0.2794 0.9906) (xy 0.2794 0.9906)
			)
			(stroke
				(width 0)
				(type default)
			)
			(fill no)
			(layer "B.CrtYd")
		)
		(fp_line
			(start -0.2794 -0.1016)
			(end 0.2794 -0.1016)
			(stroke
				(width 0.1)
				(type default)
			)
			(layer "B.Fab")
		)
		(fp_line
			(start -0.2794 0.9906)
			(end -0.2794 -0.1016)
			(stroke
				(width 0.1)
				(type default)
			)
			(layer "B.Fab")
		)
		(fp_line
			(start 0.2794 -0.1016)
			(end 0.2794 0.9906)
			(stroke
				(width 0.1)
				(type default)
			)
			(layer "B.Fab")
		)
		(fp_line
			(start 0.2794 0.9906)
			(end -0.2794 0.9906)
			(stroke
				(width 0.1)
				(type default)
			)
			(layer "B.Fab")
		)
		(pad "1" smd rect
			(at 0 0 180)
			(size 0.508 0.508)
			(layers "B.Cu" "B.Mask" "B.Paste")
			(net "P3V3_STBY")
		)
		(pad "2" smd rect
			(at 0 0.889 180)
			(size 0.508 0.508)
			(layers "B.Cu" "B.Mask" "B.Paste")
			(net "PU_SPI1_RST")
		)
		(zone
			(layer "B.Cu")
			(hatch none 0.5)
			(connect_pads
				(clearance 0)
			)
			(min_thickness 0.25)
			(keepout
				(tracks allowed)
				(vias not_allowed)
				(pads allowed)
				(copperpour not_allowed)
				(footprints allowed)
			)
			(placement
				(enabled no)
				(sheetname "")
			)
			(fill
				(thermal_gap 0.5)
				(thermal_bridge_width 0.5)
				(island_removal_mode 0)
			)
			(polygon
				(pts
					(xy 400.56816 -53.99786) (xy 400.06016 -53.99786) (xy 400.06016 -53.61686) (xy 400.56816 -53.61686)
				)
			)
		)
		(zone
			(layer "B.Cu")
			(hatch none 0.5)
			(connect_pads
				(clearance 0)
			)
			(min_thickness 0.25)
			(keepout
				(tracks not_allowed)
				(vias allowed)
				(pads allowed)
				(copperpour not_allowed)
				(footprints allowed)
			)
			(placement
				(enabled no)
				(sheetname "")
			)
			(fill
				(thermal_gap 0.5)
				(thermal_bridge_width 0.5)
				(island_removal_mode 0)
			)
			(polygon
				(pts
					(xy 400.56816 -53.61686) (xy 400.06016 -53.61686) (xy 400.06016 -53.99786) (xy 400.56816 -53.99786)
				)
			)
		)
	)
	(footprint ""
		(layer "B.Cu")
		(at 192.659 -144.4752 180)
		(property "Reference" "R6L14"
			(at 0 0 0)
			(layer "B.SilkS")
			(hide yes)
			(effects
				(font
					(size 1.27 1.27)
				)
				(justify mirror)
			)
		)
		(property "Value" ""
			(at 0 0 0)
			(layer "B.Fab")
			(effects
				(font
					(size 1.27 1.27)
				)
				(justify mirror)
			)
		)
		(duplicate_pad_numbers_are_jumpers no)
		(fp_poly
			(pts
				(xy 0.2794 -0.1016) (xy -0.2794 -0.1016) (xy -0.2794 0.9906) (xy 0.2794 0.9906)
			)
			(stroke
				(width 0)
				(type default)
			)
			(fill no)
			(layer "B.CrtYd")
		)
		(fp_line
			(start 0.2794 0.9906)
			(end -0.2794 0.9906)
			(stroke
				(width 0.1)
				(type default)
			)
			(layer "B.Fab")
		)
		(fp_line
			(start 0.2794 -0.1016)
			(end 0.2794 0.9906)
			(stroke
				(width 0.1)
				(type default)
			)
			(layer "B.Fab")
		)
		(fp_line
			(start -0.2794 0.9906)
			(end -0.2794 -0.1016)
			(stroke
				(width 0.1)
				(type default)
			)
			(layer "B.Fab")
		)
		(fp_line
			(start -0.2794 -0.1016)
			(end 0.2794 -0.1016)
			(stroke
				(width 0.1)
				(type default)
			)
			(layer "B.Fab")
		)
		(pad "1" smd rect
			(at 0 0)
			(size 0.508 0.508)
			(layers "B.Cu" "B.Mask" "B.Paste")
			(net "M_E_CPU_VREF")
		)
		(pad "2" smd rect
			(at 0 0.889)
			(size 0.508 0.508)
			(layers "B.Cu" "B.Mask" "B.Paste")
			(net "M_E_VREF")
		)
		(zone
			(layer "B.Cu")
			(hatch none 0.5)
			(connect_pads
				(clearance 0)
			)
			(min_thickness 0.25)
			(keepout
				(tracks not_allowed)
				(vias allowed)
				(pads allowed)
				(copperpour not_allowed)
				(footprints allowed)
			)
			(placement
				(enabled no)
				(sheetname "")
			)
			(fill
				(thermal_gap 0.5)
				(thermal_bridge_width 0.5)
				(island_removal_mode 0)
			)
			(polygon
				(pts
					(xy 192.405 -145.1102) (xy 192.913 -145.1102) (xy 192.913 -144.7292) (xy 192.405 -144.7292)
				)
			)
		)
		(zone
			(layer "B.Cu")
			(hatch none 0.5)
			(connect_pads
				(clearance 0)
			)
			(min_thickness 0.25)
			(keepout
				(tracks allowed)
				(vias not_allowed)
				(pads allowed)
				(copperpour not_allowed)
				(footprints allowed)
			)
			(placement
				(enabled no)
				(sheetname "")
			)
			(fill
				(thermal_gap 0.5)
				(thermal_bridge_width 0.5)
				(island_removal_mode 0)
			)
			(polygon
				(pts
					(xy 192.405 -144.7292) (xy 192.913 -144.7292) (xy 192.913 -145.1102) (xy 192.405 -145.1102)
				)
			)
		)
	)
	(footprint ""
		(layer "B.Cu")
		(at 442.669168 -146.875754 90)
		(property "Reference" "R25W180"
			(at 0.8382 -0.67818 90)
			(unlocked yes)
			(layer "B.SilkS")
			(effects
				(font
					(size 0.4064 0.254)
					(thickness 0.1524)
				)
				(justify left mirror)
			)
		)
		(property "Value" ""
			(at 0 0 90)
			(layer "B.Fab")
			(effects
				(font
					(size 1.27 1.27)
				)
				(justify mirror)
			)
		)
		(duplicate_pad_numbers_are_jumpers no)
		(fp_poly
			(pts
				(xy 0.2794 -0.1016) (xy -0.2794 -0.1016) (xy -0.2794 0.9906) (xy 0.2794 0.9906)
			)
			(stroke
				(width 0)
				(type default)
			)
			(fill no)
			(layer "B.CrtYd")
		)
		(fp_line
			(start 0.2794 -0.1016)
			(end 0.2794 0.9906)
			(stroke
				(width 0.1)
				(type default)
			)
			(layer "B.Fab")
		)
		(fp_line
			(start -0.2794 -0.1016)
			(end 0.2794 -0.1016)
			(stroke
				(width 0.1)
				(type default)
			)
			(layer "B.Fab")
		)
		(fp_line
			(start 0.2794 0.9906)
			(end -0.2794 0.9906)
			(stroke
				(width 0.1)
				(type default)
			)
			(layer "B.Fab")
		)
		(fp_line
			(start -0.2794 0.9906)
			(end -0.2794 -0.1016)
			(stroke
				(width 0.1)
				(type default)
			)
			(layer "B.Fab")
		)
		(pad "1" smd rect
			(at 0 0 270)
			(size 0.508 0.508)
			(layers "B.Cu" "B.Mask" "B.Paste")
			(net "P3V3_STBY")
		)
		(pad "2" smd rect
			(at 0 0.889 270)
			(size 0.508 0.508)
			(layers "B.Cu" "B.Mask" "B.Paste")
			(net "BMC_DEBUG_EN_N")
		)
		(zone
			(layer "B.Cu")
			(hatch none 0.5)
			(connect_pads
				(clearance 0)
			)
			(min_thickness 0.25)
			(keepout
				(tracks allowed)
				(vias not_allowed)
				(pads allowed)
				(copperpour not_allowed)
				(footprints allowed)
			)
			(placement
				(enabled no)
				(sheetname "")
			)
			(fill
				(thermal_gap 0.5)
				(thermal_bridge_width 0.5)
				(island_removal_mode 0)
			)
			(polygon
				(pts
					(xy 442.923168 -147.129754) (xy 442.923168 -146.621754) (xy 443.304168 -146.621754) (xy 443.304168 -147.129754)
				)
			)
		)
		(zone
			(layer "B.Cu")
			(hatch none 0.5)
			(connect_pads
				(clearance 0)
			)
			(min_thickness 0.25)
			(keepout
				(tracks not_allowed)
				(vias allowed)
				(pads allowed)
				(copperpour not_allowed)
				(footprints allowed)
			)
			(placement
				(enabled no)
				(sheetname "")
			)
			(fill
				(thermal_gap 0.5)
				(thermal_bridge_width 0.5)
				(island_removal_mode 0)
			)
			(polygon
				(pts
					(xy 443.304168 -147.129754) (xy 443.304168 -146.621754) (xy 442.923168 -146.621754) (xy 442.923168 -147.129754)
				)
			)
		)
	)
	(footprint ""
		(layer "B.Cu")
		(at 414.75152 -45.576744 -90)
		(property "Reference" "C25W40"
			(at 0.8382 -0.67818 270)
			(unlocked yes)
			(layer "B.SilkS")
			(effects
				(font
					(size 0.4064 0.254)
					(thickness 0.1524)
				)
				(justify left mirror)
			)
		)
		(property "Value" ""
			(at 0 0 90)
			(layer "B.Fab")
			(effects
				(font
					(size 1.27 1.27)
				)
				(justify mirror)
			)
		)
		(duplicate_pad_numbers_are_jumpers no)
		(fp_poly
			(pts
				(xy -0.3048 -0.1016) (xy -0.3048 0.9906) (xy 0.3048 0.9906) (xy 0.3048 -0.1016)
			)
			(stroke
				(width 0)
				(type default)
			)
			(fill no)
			(layer "B.CrtYd")
		)
		(fp_line
			(start -0.3048 0.9906)
			(end -0.3048 -0.1016)
			(stroke
				(width 0.1)
				(type default)
			)
			(layer "B.Fab")
		)
		(fp_line
			(start 0.3048 0.9906)
			(end -0.3048 0.9906)
			(stroke
				(width 0.1)
				(type default)
			)
			(layer "B.Fab")
		)
		(fp_line
			(start -0.3048 -0.1016)
			(end 0.3048 -0.1016)
			(stroke
				(width 0.1)
				(type default)
			)
			(layer "B.Fab")
		)
		(fp_line
			(start 0.3048 -0.1016)
			(end 0.3048 0.9906)
			(stroke
				(width 0.1)
				(type default)
			)
			(layer "B.Fab")
		)
		(pad "1" smd rect
			(at 0 0 90)
			(size 0.508 0.508)
			(layers "B.Cu" "B.Mask" "B.Paste")
			(net "VCC_D_3V3")
		)
		(pad "2" smd rect
			(at 0 0.889 90)
			(size 0.508 0.508)
			(layers "B.Cu" "B.Mask" "B.Paste")
			(net "GND")
		)
		(zone
			(layer "B.Cu")
			(hatch none 0.5)
			(connect_pads
				(clearance 0)
			)
			(min_thickness 0.25)
			(keepout
				(tracks not_allowed)
				(vias allowed)
				(pads allowed)
				(copperpour not_allowed)
				(footprints allowed)
			)
			(placement
				(enabled no)
				(sheetname "")
			)
			(fill
				(thermal_gap 0.5)
				(thermal_bridge_width 0.5)
				(island_removal_mode 0)
			)
			(polygon
				(pts
					(xy 414.11652 -45.322744) (xy 414.11652 -45.830744) (xy 414.49752 -45.830744) (xy 414.49752 -45.322744)
				)
			)
		)
		(zone
			(layer "B.Cu")
			(hatch none 0.5)
			(connect_pads
				(clearance 0)
			)
			(min_thickness 0.25)
			(keepout
				(tracks allowed)
				(vias not_allowed)
				(pads allowed)
				(copperpour not_allowed)
				(footprints allowed)
			)
			(placement
				(enabled no)
				(sheetname "")
			)
			(fill
				(thermal_gap 0.5)
				(thermal_bridge_width 0.5)
				(island_removal_mode 0)
			)
			(polygon
				(pts
					(xy 414.49752 -45.322744) (xy 414.49752 -45.830744) (xy 414.11652 -45.830744) (xy 414.11652 -45.322744)
				)
			)
		)
	)
	(footprint ""
		(layer "B.Cu")
		(at 351.2312 -85.9536 90)
		(property "Reference" "C3P2"
			(at 0 0 90)
			(layer "B.SilkS")
			(hide yes)
			(effects
				(font
					(size 1.27 1.27)
				)
				(justify mirror)
			)
		)
		(property "Value" ""
			(at 0 0 90)
			(layer "B.Fab")
			(effects
				(font
					(size 1.27 1.27)
				)
				(justify mirror)
			)
		)
		(duplicate_pad_numbers_are_jumpers no)
		(fp_poly
			(pts
				(xy -0.3048 -0.1016) (xy -0.3048 0.9906) (xy 0.3048 0.9906) (xy 0.3048 -0.1016)
			)
			(stroke
				(width 0)
				(type default)
			)
			(fill no)
			(layer "B.CrtYd")
		)
		(fp_line
			(start 0.3048 -0.1016)
			(end 0.3048 0.9906)
			(stroke
				(width 0.1)
				(type default)
			)
			(layer "B.Fab")
		)
		(fp_line
			(start -0.3048 -0.1016)
			(end 0.3048 -0.1016)
			(stroke
				(width 0.1)
				(type default)
			)
			(layer "B.Fab")
		)
		(fp_line
			(start 0.3048 0.9906)
			(end -0.3048 0.9906)
			(stroke
				(width 0.1)
				(type default)
			)
			(layer "B.Fab")
		)
		(fp_line
			(start -0.3048 0.9906)
			(end -0.3048 -0.1016)
			(stroke
				(width 0.1)
				(type default)
			)
			(layer "B.Fab")
		)
		(pad "1" smd rect
			(at 0 0 270)
			(size 0.508 0.508)
			(layers "B.Cu" "B.Mask" "B.Paste")
			(net "VR_PVCCIO_CPU0_VINSEN")
		)
		(pad "2" smd rect
			(at 0 0.889 270)
			(size 0.508 0.508)
			(layers "B.Cu" "B.Mask" "B.Paste")
			(net "GND")
		)
		(zone
			(layer "B.Cu")
			(hatch none 0.5)
			(connect_pads
				(clearance 0)
			)
			(min_thickness 0.25)
			(keepout
				(tracks allowed)
				(vias not_allowed)
				(pads allowed)
				(copperpour not_allowed)
				(footprints allowed)
			)
			(placement
				(enabled no)
				(sheetname "")
			)
			(fill
				(thermal_gap 0.5)
				(thermal_bridge_width 0.5)
				(island_removal_mode 0)
			)
			(polygon
				(pts
					(xy 351.4852 -86.2076) (xy 351.4852 -85.6996) (xy 351.8662 -85.6996) (xy 351.8662 -86.2076)
				)
			)
		)
		(zone
			(layer "B.Cu")
			(hatch none 0.5)
			(connect_pads
				(clearance 0)
			)
			(min_thickness 0.25)
			(keepout
				(tracks not_allowed)
				(vias allowed)
				(pads allowed)
				(copperpour not_allowed)
				(footprints allowed)
			)
			(placement
				(enabled no)
				(sheetname "")
			)
			(fill
				(thermal_gap 0.5)
				(thermal_bridge_width 0.5)
				(island_removal_mode 0)
			)
			(polygon
				(pts
					(xy 351.8662 -86.2076) (xy 351.8662 -85.6996) (xy 351.4852 -85.6996) (xy 351.4852 -86.2076)
				)
			)
		)
	)
	(footprint ""
		(layer "B.Cu")
		(at 49.5808 -98.1202)
		(property "Reference" "R9N4"
			(at 0 0 0)
			(layer "B.SilkS")
			(hide yes)
			(effects
				(font
					(size 1.27 1.27)
				)
				(justify mirror)
			)
		)
		(property "Value" ""
			(at 0 0 0)
			(layer "B.Fab")
			(effects
				(font
					(size 1.27 1.27)
				)
				(justify mirror)
			)
		)
		(duplicate_pad_numbers_are_jumpers no)
		(fp_poly
			(pts
				(xy 0.2794 -0.1016) (xy -0.2794 -0.1016) (xy -0.2794 0.9906) (xy 0.2794 0.9906)
			)
			(stroke
				(width 0)
				(type default)
			)
			(fill no)
			(layer "B.CrtYd")
		)
		(fp_line
			(start -0.2794 -0.1016)
			(end 0.2794 -0.1016)
			(stroke
				(width 0.1)
				(type default)
			)
			(layer "B.Fab")
		)
		(fp_line
			(start -0.2794 0.9906)
			(end -0.2794 -0.1016)
			(stroke
				(width 0.1)
				(type default)
			)
			(layer "B.Fab")
		)
		(fp_line
			(start 0.2794 -0.1016)
			(end 0.2794 0.9906)
			(stroke
				(width 0.1)
				(type default)
			)
			(layer "B.Fab")
		)
		(fp_line
			(start 0.2794 0.9906)
			(end -0.2794 0.9906)
			(stroke
				(width 0.1)
				(type default)
			)
			(layer "B.Fab")
		)
		(pad "1" smd rect
			(at 0 0 180)
			(size 0.508 0.508)
			(layers "B.Cu" "B.Mask" "B.Paste")
			(net "PVSA_CPU1")
		)
		(pad "2" smd rect
			(at 0 0.889 180)
			(size 0.508 0.508)
			(layers "B.Cu" "B.Mask" "B.Paste")
			(net "GND")
		)
		(zone
			(layer "B.Cu")
			(hatch none 0.5)
			(connect_pads
				(clearance 0)
			)
			(min_thickness 0.25)
			(keepout
				(tracks allowed)
				(vias not_allowed)
				(pads allowed)
				(copperpour not_allowed)
				(footprints allowed)
			)
			(placement
				(enabled no)
				(sheetname "")
			)
			(fill
				(thermal_gap 0.5)
				(thermal_bridge_width 0.5)
				(island_removal_mode 0)
			)
			(polygon
				(pts
					(xy 49.8348 -97.8662) (xy 49.3268 -97.8662) (xy 49.3268 -97.4852) (xy 49.8348 -97.4852)
				)
			)
		)
		(zone
			(layer "B.Cu")
			(hatch none 0.5)
			(connect_pads
				(clearance 0)
			)
			(min_thickness 0.25)
			(keepout
				(tracks not_allowed)
				(vias allowed)
				(pads allowed)
				(copperpour not_allowed)
				(footprints allowed)
			)
			(placement
				(enabled no)
				(sheetname "")
			)
			(fill
				(thermal_gap 0.5)
				(thermal_bridge_width 0.5)
				(island_removal_mode 0)
			)
			(polygon
				(pts
					(xy 49.8348 -97.4852) (xy 49.3268 -97.4852) (xy 49.3268 -97.8662) (xy 49.8348 -97.8662)
				)
			)
		)
	)
	(footprint ""
		(layer "B.Cu")
		(at 167.005 -13.208 90)
		(property "Reference" "C6U3"
			(at 0 0 90)
			(layer "B.SilkS")
			(hide yes)
			(effects
				(font
					(size 1.27 1.27)
				)
				(justify mirror)
			)
		)
		(property "Value" ""
			(at 0 0 90)
			(layer "B.Fab")
			(effects
				(font
					(size 1.27 1.27)
				)
				(justify mirror)
			)
		)
		(duplicate_pad_numbers_are_jumpers no)
		(fp_rect
			(start -0.7239 -0.2159)
			(end 0.7239 1.9939)
			(stroke
				(width 0)
				(type default)
			)
			(fill no)
			(layer "B.CrtYd")
		)
		(fp_line
			(start 0.7239 -0.2159)
			(end 0.7239 1.9939)
			(stroke
				(width 0.1)
				(type default)
			)
			(layer "B.Fab")
		)
		(fp_line
			(start -0.7239 -0.2159)
			(end 0.7239 -0.2159)
			(stroke
				(width 0.1)
				(type default)
			)
			(layer "B.Fab")
		)
		(fp_line
			(start 0.7239 1.9939)
			(end -0.7239 1.9939)
			(stroke
				(width 0.1)
				(type default)
			)
			(layer "B.Fab")
		)
		(fp_line
			(start -0.7239 1.9939)
			(end -0.7239 -0.2159)
			(stroke
				(width 0.1)
				(type default)
			)
			(layer "B.Fab")
		)
		(pad "1" smd rect
			(at 0 0 270)
			(size 1.27 1.016)
			(layers "B.Cu" "B.Mask" "B.Paste")
			(net "PVPP_GHJ")
		)
		(pad "2" smd rect
			(at 0 1.778 270)
			(size 1.27 1.016)
			(layers "B.Cu" "B.Mask" "B.Paste")
			(net "GND")
		)
		(zone
			(layer "B.Cu")
			(hatch none 0.5)
			(connect_pads
				(clearance 0)
			)
			(min_thickness 0.25)
			(keepout
				(tracks not_allowed)
				(vias allowed)
				(pads allowed)
				(copperpour not_allowed)
				(footprints allowed)
			)
			(placement
				(enabled no)
				(sheetname "")
			)
			(fill
				(thermal_gap 0.5)
				(thermal_bridge_width 0.5)
				(island_removal_mode 0)
			)
			(polygon
				(pts
					(xy 167.513 -12.573) (xy 168.275 -12.573) (xy 168.275 -13.843) (xy 167.513 -13.843)
				)
			)
		)
	)
	(footprint ""
		(layer "B.Cu")
		(at 339.3186 -131.6482)
		(property "Reference" "C3M10"
			(at 0 0 0)
			(layer "B.SilkS")
			(hide yes)
			(effects
				(font
					(size 1.27 1.27)
				)
				(justify mirror)
			)
		)
		(property "Value" ""
			(at 0 0 0)
			(layer "B.Fab")
			(effects
				(font
					(size 1.27 1.27)
				)
				(justify mirror)
			)
		)
		(duplicate_pad_numbers_are_jumpers no)
		(fp_poly
			(pts
				(xy 0.4953 -0.2032) (xy -0.4953 -0.2032) (xy -0.4953 1.6002) (xy 0.4953 1.6002)
			)
			(stroke
				(width 0)
				(type default)
			)
			(fill no)
			(layer "B.CrtYd")
		)
		(fp_line
			(start -0.4953 -0.2032)
			(end -0.4953 1.6002)
			(stroke
				(width 0.1)
				(type default)
			)
			(layer "B.Fab")
		)
		(fp_line
			(start -0.4953 1.6002)
			(end 0.4953 1.6002)
			(stroke
				(width 0.1)
				(type default)
			)
			(layer "B.Fab")
		)
		(fp_line
			(start 0.4953 -0.2032)
			(end -0.4953 -0.2032)
			(stroke
				(width 0.1)
				(type default)
			)
			(layer "B.Fab")
		)
		(fp_line
			(start 0.4953 1.6002)
			(end 0.4953 -0.2032)
			(stroke
				(width 0.1)
				(type default)
			)
			(layer "B.Fab")
		)
		(pad "1" smd rect
			(at 0 0 180)
			(size 0.762 0.889)
			(layers "B.Cu" "B.Mask" "B.Paste")
			(net "VR_VB_PVPP_DEF")
		)
		(pad "2" smd rect
			(at 0 1.397 180)
			(size 0.762 0.889)
			(layers "B.Cu" "B.Mask" "B.Paste")
			(net "AGND_PVPP_DEF")
		)
		(zone
			(layer "B.Cu")
			(hatch none 0.5)
			(connect_pads
				(clearance 0)
			)
			(min_thickness 0.25)
			(keepout
				(tracks not_allowed)
				(vias allowed)
				(pads allowed)
				(copperpour not_allowed)
				(footprints allowed)
			)
			(placement
				(enabled no)
				(sheetname "")
			)
			(fill
				(thermal_gap 0.5)
				(thermal_bridge_width 0.5)
				(island_removal_mode 0)
			)
			(polygon
				(pts
					(xy 339.6996 -131.2037) (xy 338.9376 -131.2037) (xy 338.9376 -130.6957) (xy 339.6996 -130.6957)
				)
			)
		)
	)
	(footprint ""
		(layer "B.Cu")
		(at 390.7155 -37.73551 -90)
		(property "Reference" "C2T5"
			(at 0 0 90)
			(layer "B.SilkS")
			(hide yes)
			(effects
				(font
					(size 1.27 1.27)
				)
				(justify mirror)
			)
		)
		(property "Value" ""
			(at 0 0 90)
			(layer "B.Fab")
			(effects
				(font
					(size 1.27 1.27)
				)
				(justify mirror)
			)
		)
		(duplicate_pad_numbers_are_jumpers no)
		(fp_poly
			(pts
				(xy -0.3048 -0.1016) (xy -0.3048 0.9906) (xy 0.3048 0.9906) (xy 0.3048 -0.1016)
			)
			(stroke
				(width 0)
				(type default)
			)
			(fill no)
			(layer "B.CrtYd")
		)
		(fp_line
			(start -0.3048 0.9906)
			(end -0.3048 -0.1016)
			(stroke
				(width 0.1)
				(type default)
			)
			(layer "B.Fab")
		)
		(fp_line
			(start 0.3048 0.9906)
			(end -0.3048 0.9906)
			(stroke
				(width 0.1)
				(type default)
			)
			(layer "B.Fab")
		)
		(fp_line
			(start -0.3048 -0.1016)
			(end 0.3048 -0.1016)
			(stroke
				(width 0.1)
				(type default)
			)
			(layer "B.Fab")
		)
		(fp_line
			(start 0.3048 -0.1016)
			(end 0.3048 0.9906)
			(stroke
				(width 0.1)
				(type default)
			)
			(layer "B.Fab")
		)
		(pad "1" smd rect
			(at 0 0 90)
			(size 0.508 0.508)
			(layers "B.Cu" "B.Mask" "B.Paste")
			(net "P3V3")
		)
		(pad "2" smd rect
			(at 0 0.889 90)
			(size 0.508 0.508)
			(layers "B.Cu" "B.Mask" "B.Paste")
			(net "GND")
		)
		(zone
			(layer "B.Cu")
			(hatch none 0.5)
			(connect_pads
				(clearance 0)
			)
			(min_thickness 0.25)
			(keepout
				(tracks not_allowed)
				(vias allowed)
				(pads allowed)
				(copperpour not_allowed)
				(footprints allowed)
			)
			(placement
				(enabled no)
				(sheetname "")
			)
			(fill
				(thermal_gap 0.5)
				(thermal_bridge_width 0.5)
				(island_removal_mode 0)
			)
			(polygon
				(pts
					(xy 390.0805 -37.48151) (xy 390.0805 -37.98951) (xy 390.4615 -37.98951) (xy 390.4615 -37.48151)
				)
			)
		)
		(zone
			(layer "B.Cu")
			(hatch none 0.5)
			(connect_pads
				(clearance 0)
			)
			(min_thickness 0.25)
			(keepout
				(tracks allowed)
				(vias not_allowed)
				(pads allowed)
				(copperpour not_allowed)
				(footprints allowed)
			)
			(placement
				(enabled no)
				(sheetname "")
			)
			(fill
				(thermal_gap 0.5)
				(thermal_bridge_width 0.5)
				(island_removal_mode 0)
			)
			(polygon
				(pts
					(xy 390.4615 -37.48151) (xy 390.4615 -37.98951) (xy 390.0805 -37.98951) (xy 390.0805 -37.48151)
				)
			)
		)
	)
	(footprint ""
		(layer "B.Cu")
		(at 182.169562 -150.876508)
		(property "Reference" "C6L3"
			(at 0 0 0)
			(layer "B.SilkS")
			(hide yes)
			(effects
				(font
					(size 1.27 1.27)
				)
				(justify mirror)
			)
		)
		(property "Value" ""
			(at 0 0 0)
			(layer "B.Fab")
			(effects
				(font
					(size 1.27 1.27)
				)
				(justify mirror)
			)
		)
		(duplicate_pad_numbers_are_jumpers no)
		(fp_rect
			(start 0.4953 -0.2032)
			(end -0.4953 1.6002)
			(stroke
				(width 0)
				(type default)
			)
			(fill no)
			(layer "B.CrtYd")
		)
		(fp_line
			(start -0.4953 -0.2032)
			(end -0.4953 1.6002)
			(stroke
				(width 0.1)
				(type default)
			)
			(layer "B.Fab")
		)
		(fp_line
			(start -0.4953 1.6002)
			(end 0.4953 1.6002)
			(stroke
				(width 0.1)
				(type default)
			)
			(layer "B.Fab")
		)
		(fp_line
			(start 0.4953 -0.2032)
			(end -0.4953 -0.2032)
			(stroke
				(width 0.1)
				(type default)
			)
			(layer "B.Fab")
		)
		(fp_line
			(start 0.4953 1.6002)
			(end 0.4953 -0.2032)
			(stroke
				(width 0.1)
				(type default)
			)
			(layer "B.Fab")
		)
		(pad "1" smd rect
			(at 0 0 180)
			(size 0.762 0.889)
			(layers "B.Cu" "B.Mask" "B.Paste")
			(net "PVDDQ_DEF")
		)
		(pad "2" smd rect
			(at 0 1.397 180)
			(size 0.762 0.889)
			(layers "B.Cu" "B.Mask" "B.Paste")
			(net "GND")
		)
		(zone
			(layer "B.Cu")
			(hatch none 0.5)
			(connect_pads
				(clearance 0)
			)
			(min_thickness 0.25)
			(keepout
				(tracks not_allowed)
				(vias allowed)
				(pads allowed)
				(copperpour not_allowed)
				(footprints allowed)
			)
			(placement
				(enabled no)
				(sheetname "")
			)
			(fill
				(thermal_gap 0.5)
				(thermal_bridge_width 0.5)
				(island_removal_mode 0)
			)
			(polygon
				(pts
					(xy 182.550562 -150.432008) (xy 181.788562 -150.432008) (xy 181.788562 -149.924008) (xy 182.550562 -149.924008)
				)
			)
		)
	)
	(footprint ""
		(layer "B.Cu")
		(at 420.624 -25.654)
		(property "Reference" "C25W77"
			(at 0.8382 -0.67818 0)
			(unlocked yes)
			(layer "B.SilkS")
			(effects
				(font
					(size 0.4064 0.254)
					(thickness 0.1524)
				)
				(justify left mirror)
			)
		)
		(property "Value" ""
			(at 0 0 0)
			(layer "B.Fab")
			(effects
				(font
					(size 1.27 1.27)
				)
				(justify mirror)
			)
		)
		(duplicate_pad_numbers_are_jumpers no)
		(fp_poly
			(pts
				(xy -0.3048 -0.1016) (xy -0.3048 0.9906) (xy 0.3048 0.9906) (xy 0.3048 -0.1016)
			)
			(stroke
				(width 0)
				(type default)
			)
			(fill no)
			(layer "B.CrtYd")
		)
		(fp_line
			(start -0.3048 -0.1016)
			(end 0.3048 -0.1016)
			(stroke
				(width 0.1)
				(type default)
			)
			(layer "B.Fab")
		)
		(fp_line
			(start -0.3048 0.9906)
			(end -0.3048 -0.1016)
			(stroke
				(width 0.1)
				(type default)
			)
			(layer "B.Fab")
		)
		(fp_line
			(start 0.3048 -0.1016)
			(end 0.3048 0.9906)
			(stroke
				(width 0.1)
				(type default)
			)
			(layer "B.Fab")
		)
		(fp_line
			(start 0.3048 0.9906)
			(end -0.3048 0.9906)
			(stroke
				(width 0.1)
				(type default)
			)
			(layer "B.Fab")
		)
		(pad "1" smd rect
			(at 0 0 180)
			(size 0.508 0.508)
			(layers "B.Cu" "B.Mask" "B.Paste")
			(net "V_IO_R_J")
		)
		(pad "2" smd rect
			(at 0 0.889 180)
			(size 0.508 0.508)
			(layers "B.Cu" "B.Mask" "B.Paste")
			(net "GND")
		)
		(zone
			(layer "B.Cu")
			(hatch none 0.5)
			(connect_pads
				(clearance 0)
			)
			(min_thickness 0.25)
			(keepout
				(tracks allowed)
				(vias not_allowed)
				(pads allowed)
				(copperpour not_allowed)
				(footprints allowed)
			)
			(placement
				(enabled no)
				(sheetname "")
			)
			(fill
				(thermal_gap 0.5)
				(thermal_bridge_width 0.5)
				(island_removal_mode 0)
			)
			(polygon
				(pts
					(xy 420.878 -25.4) (xy 420.37 -25.4) (xy 420.37 -25.019) (xy 420.878 -25.019)
				)
			)
		)
		(zone
			(layer "B.Cu")
			(hatch none 0.5)
			(connect_pads
				(clearance 0)
			)
			(min_thickness 0.25)
			(keepout
				(tracks not_allowed)
				(vias allowed)
				(pads allowed)
				(copperpour not_allowed)
				(footprints allowed)
			)
			(placement
				(enabled no)
				(sheetname "")
			)
			(fill
				(thermal_gap 0.5)
				(thermal_bridge_width 0.5)
				(island_removal_mode 0)
			)
			(polygon
				(pts
					(xy 420.878 -25.019) (xy 420.37 -25.019) (xy 420.37 -25.4) (xy 420.878 -25.4)
				)
			)
		)
	)
	(footprint ""
		(layer "B.Cu")
		(at 271.350486 -77.82814)
		(property "Reference" "C5P20"
			(at 0 0 0)
			(layer "B.SilkS")
			(hide yes)
			(effects
				(font
					(size 1.27 1.27)
				)
				(justify mirror)
			)
		)
		(property "Value" ""
			(at 0 0 0)
			(layer "B.Fab")
			(effects
				(font
					(size 1.27 1.27)
				)
				(justify mirror)
			)
		)
		(duplicate_pad_numbers_are_jumpers no)
		(fp_poly
			(pts
				(xy 0.7239 -0.2159) (xy -0.7239 -0.2159) (xy -0.7239 1.9939) (xy 0.7239 1.9939)
			)
			(stroke
				(width 0)
				(type default)
			)
			(fill no)
			(layer "B.CrtYd")
		)
		(fp_line
			(start -0.7239 -0.2159)
			(end 0.7239 -0.2159)
			(stroke
				(width 0.1)
				(type default)
			)
			(layer "B.Fab")
		)
		(fp_line
			(start -0.7239 1.9939)
			(end -0.7239 -0.2159)
			(stroke
				(width 0.1)
				(type default)
			)
			(layer "B.Fab")
		)
		(fp_line
			(start 0.7239 -0.2159)
			(end 0.7239 1.9939)
			(stroke
				(width 0.1)
				(type default)
			)
			(layer "B.Fab")
		)
		(fp_line
			(start 0.7239 1.9939)
			(end -0.7239 1.9939)
			(stroke
				(width 0.1)
				(type default)
			)
			(layer "B.Fab")
		)
		(pad "1" smd rect
			(at 0 0 180)
			(size 1.27 1.016)
			(layers "B.Cu" "B.Mask" "B.Paste")
			(net "PVCCMCP_CPU0")
		)
		(pad "2" smd rect
			(at 0 1.778 180)
			(size 1.27 1.016)
			(layers "B.Cu" "B.Mask" "B.Paste")
			(net "GND")
		)
		(zone
			(layer "B.Cu")
			(hatch none 0.5)
			(connect_pads
				(clearance 0)
			)
			(min_thickness 0.25)
			(keepout
				(tracks not_allowed)
				(vias allowed)
				(pads allowed)
				(copperpour not_allowed)
				(footprints allowed)
			)
			(placement
				(enabled no)
				(sheetname "")
			)
			(fill
				(thermal_gap 0.5)
				(thermal_bridge_width 0.5)
				(island_removal_mode 0)
			)
			(polygon
				(pts
					(xy 271.985486 -77.32014) (xy 270.715486 -77.32014) (xy 270.715486 -76.55814) (xy 271.985486 -76.55814)
				)
			)
		)
	)
	(footprint ""
		(layer "B.Cu")
		(at 351.13468 -89.067132 90)
		(property "Reference" "C4W1"
			(at 0.8382 -0.67818 90)
			(unlocked yes)
			(layer "B.SilkS")
			(effects
				(font
					(size 0.4064 0.254)
					(thickness 0.1524)
				)
				(justify left mirror)
			)
		)
		(property "Value" ""
			(at 0 0 90)
			(layer "B.Fab")
			(effects
				(font
					(size 1.27 1.27)
				)
				(justify mirror)
			)
		)
		(duplicate_pad_numbers_are_jumpers no)
		(fp_poly
			(pts
				(xy -0.3048 -0.1016) (xy -0.3048 0.9906) (xy 0.3048 0.9906) (xy 0.3048 -0.1016)
			)
			(stroke
				(width 0)
				(type default)
			)
			(fill no)
			(layer "B.CrtYd")
		)
		(fp_line
			(start 0.3048 -0.1016)
			(end 0.3048 0.9906)
			(stroke
				(width 0.1)
				(type default)
			)
			(layer "B.Fab")
		)
		(fp_line
			(start -0.3048 -0.1016)
			(end 0.3048 -0.1016)
			(stroke
				(width 0.1)
				(type default)
			)
			(layer "B.Fab")
		)
		(fp_line
			(start 0.3048 0.9906)
			(end -0.3048 0.9906)
			(stroke
				(width 0.1)
				(type default)
			)
			(layer "B.Fab")
		)
		(fp_line
			(start -0.3048 0.9906)
			(end -0.3048 -0.1016)
			(stroke
				(width 0.1)
				(type default)
			)
			(layer "B.Fab")
		)
		(pad "1" smd rect
			(at 0 0 270)
			(size 0.508 0.508)
			(layers "B.Cu" "B.Mask" "B.Paste")
			(net "A_TSENSE_PVCCIO_CPU0")
		)
		(pad "2" smd rect
			(at 0 0.889 270)
			(size 0.508 0.508)
			(layers "B.Cu" "B.Mask" "B.Paste")
			(net "GND")
		)
		(zone
			(layer "B.Cu")
			(hatch none 0.5)
			(connect_pads
				(clearance 0)
			)
			(min_thickness 0.25)
			(keepout
				(tracks allowed)
				(vias not_allowed)
				(pads allowed)
				(copperpour not_allowed)
				(footprints allowed)
			)
			(placement
				(enabled no)
				(sheetname "")
			)
			(fill
				(thermal_gap 0.5)
				(thermal_bridge_width 0.5)
				(island_removal_mode 0)
			)
			(polygon
				(pts
					(xy 351.38868 -89.321132) (xy 351.38868 -88.813132) (xy 351.76968 -88.813132) (xy 351.76968 -89.321132)
				)
			)
		)
		(zone
			(layer "B.Cu")
			(hatch none 0.5)
			(connect_pads
				(clearance 0)
			)
			(min_thickness 0.25)
			(keepout
				(tracks not_allowed)
				(vias allowed)
				(pads allowed)
				(copperpour not_allowed)
				(footprints allowed)
			)
			(placement
				(enabled no)
				(sheetname "")
			)
			(fill
				(thermal_gap 0.5)
				(thermal_bridge_width 0.5)
				(island_removal_mode 0)
			)
			(polygon
				(pts
					(xy 351.76968 -89.321132) (xy 351.76968 -88.813132) (xy 351.38868 -88.813132) (xy 351.38868 -89.321132)
				)
			)
		)
	)
	(footprint ""
		(layer "B.Cu")
		(at 385.34594 -30.571694 90)
		(property "Reference" "C2T10"
			(at 0 0 90)
			(layer "B.SilkS")
			(hide yes)
			(effects
				(font
					(size 1.27 1.27)
				)
				(justify mirror)
			)
		)
		(property "Value" ""
			(at 0 0 90)
			(layer "B.Fab")
			(effects
				(font
					(size 1.27 1.27)
				)
				(justify mirror)
			)
		)
		(duplicate_pad_numbers_are_jumpers no)
		(fp_poly
			(pts
				(xy -0.3048 -0.1016) (xy -0.3048 0.9906) (xy 0.3048 0.9906) (xy 0.3048 -0.1016)
			)
			(stroke
				(width 0)
				(type default)
			)
			(fill no)
			(layer "B.CrtYd")
		)
		(fp_line
			(start 0.3048 -0.1016)
			(end 0.3048 0.9906)
			(stroke
				(width 0.1)
				(type default)
			)
			(layer "B.Fab")
		)
		(fp_line
			(start -0.3048 -0.1016)
			(end 0.3048 -0.1016)
			(stroke
				(width 0.1)
				(type default)
			)
			(layer "B.Fab")
		)
		(fp_line
			(start 0.3048 0.9906)
			(end -0.3048 0.9906)
			(stroke
				(width 0.1)
				(type default)
			)
			(layer "B.Fab")
		)
		(fp_line
			(start -0.3048 0.9906)
			(end -0.3048 -0.1016)
			(stroke
				(width 0.1)
				(type default)
			)
			(layer "B.Fab")
		)
		(pad "1" smd rect
			(at 0 0 270)
			(size 0.508 0.508)
			(layers "B.Cu" "B.Mask" "B.Paste")
			(net "P3E_PCH_M2_TX_C_DP<1>")
		)
		(pad "2" smd rect
			(at 0 0.889 270)
			(size 0.508 0.508)
			(layers "B.Cu" "B.Mask" "B.Paste")
			(net "P3E_PCH_M2_TX_DP<1>")
		)
		(zone
			(layer "B.Cu")
			(hatch none 0.5)
			(connect_pads
				(clearance 0)
			)
			(min_thickness 0.25)
			(keepout
				(tracks allowed)
				(vias not_allowed)
				(pads allowed)
				(copperpour not_allowed)
				(footprints allowed)
			)
			(placement
				(enabled no)
				(sheetname "")
			)
			(fill
				(thermal_gap 0.5)
				(thermal_bridge_width 0.5)
				(island_removal_mode 0)
			)
			(polygon
				(pts
					(xy 385.59994 -30.825694) (xy 385.59994 -30.317694) (xy 385.98094 -30.317694) (xy 385.98094 -30.825694)
				)
			)
		)
		(zone
			(layer "B.Cu")
			(hatch none 0.5)
			(connect_pads
				(clearance 0)
			)
			(min_thickness 0.25)
			(keepout
				(tracks not_allowed)
				(vias allowed)
				(pads allowed)
				(copperpour not_allowed)
				(footprints allowed)
			)
			(placement
				(enabled no)
				(sheetname "")
			)
			(fill
				(thermal_gap 0.5)
				(thermal_bridge_width 0.5)
				(island_removal_mode 0)
			)
			(polygon
				(pts
					(xy 385.98094 -30.825694) (xy 385.98094 -30.317694) (xy 385.59994 -30.317694) (xy 385.59994 -30.825694)
				)
			)
		)
	)
	(footprint ""
		(layer "B.Cu")
		(at 347.316806 -60.368434)
		(property "Reference" "R2U24"
			(at 0 0 0)
			(layer "B.SilkS")
			(hide yes)
			(effects
				(font
					(size 1.27 1.27)
				)
				(justify mirror)
			)
		)
		(property "Value" ""
			(at 0 0 0)
			(layer "B.Fab")
			(effects
				(font
					(size 1.27 1.27)
				)
				(justify mirror)
			)
		)
		(duplicate_pad_numbers_are_jumpers no)
		(fp_poly
			(pts
				(xy 0.2794 -0.1016) (xy -0.2794 -0.1016) (xy -0.2794 0.9906) (xy 0.2794 0.9906)
			)
			(stroke
				(width 0)
				(type default)
			)
			(fill no)
			(layer "B.CrtYd")
		)
		(fp_line
			(start -0.2794 -0.1016)
			(end 0.2794 -0.1016)
			(stroke
				(width 0.1)
				(type default)
			)
			(layer "B.Fab")
		)
		(fp_line
			(start -0.2794 0.9906)
			(end -0.2794 -0.1016)
			(stroke
				(width 0.1)
				(type default)
			)
			(layer "B.Fab")
		)
		(fp_line
			(start 0.2794 -0.1016)
			(end 0.2794 0.9906)
			(stroke
				(width 0.1)
				(type default)
			)
			(layer "B.Fab")
		)
		(fp_line
			(start 0.2794 0.9906)
			(end -0.2794 0.9906)
			(stroke
				(width 0.1)
				(type default)
			)
			(layer "B.Fab")
		)
		(pad "1" smd rect
			(at 0 0 180)
			(size 0.508 0.508)
			(layers "B.Cu" "B.Mask" "B.Paste")
			(net "P3E_CPU0_PE1_SS_RXP<5>")
		)
		(pad "2" smd rect
			(at 0 0.889 180)
			(size 0.508 0.508)
			(layers "B.Cu" "B.Mask" "B.Paste")
			(net "P3E_CPU0_PE1_SS_R_RXP<5>")
		)
		(zone
			(layer "B.Cu")
			(hatch none 0.5)
			(connect_pads
				(clearance 0)
			)
			(min_thickness 0.25)
			(keepout
				(tracks allowed)
				(vias not_allowed)
				(pads allowed)
				(copperpour not_allowed)
				(footprints allowed)
			)
			(placement
				(enabled no)
				(sheetname "")
			)
			(fill
				(thermal_gap 0.5)
				(thermal_bridge_width 0.5)
				(island_removal_mode 0)
			)
			(polygon
				(pts
					(xy 347.570806 -60.114434) (xy 347.062806 -60.114434) (xy 347.062806 -59.733434) (xy 347.570806 -59.733434)
				)
			)
		)
	)
	(footprint ""
		(layer "B.Cu")
		(at 153.794968 -154.782012 -90)
		(property "Reference" "C7L3"
			(at 0 0 90)
			(layer "B.SilkS")
			(hide yes)
			(effects
				(font
					(size 1.27 1.27)
				)
				(justify mirror)
			)
		)
		(property "Value" ""
			(at 0 0 90)
			(layer "B.Fab")
			(effects
				(font
					(size 1.27 1.27)
				)
				(justify mirror)
			)
		)
		(duplicate_pad_numbers_are_jumpers no)
		(fp_rect
			(start 0.4953 1.6002)
			(end -0.4953 -0.2032)
			(stroke
				(width 0)
				(type default)
			)
			(fill no)
			(layer "B.CrtYd")
		)
		(fp_line
			(start -0.4953 1.6002)
			(end 0.4953 1.6002)
			(stroke
				(width 0.1)
				(type default)
			)
			(layer "B.Fab")
		)
		(fp_line
			(start 0.4953 1.6002)
			(end 0.4953 -0.2032)
			(stroke
				(width 0.1)
				(type default)
			)
			(layer "B.Fab")
		)
		(fp_line
			(start -0.4953 -0.2032)
			(end -0.4953 1.6002)
			(stroke
				(width 0.1)
				(type default)
			)
			(layer "B.Fab")
		)
		(fp_line
			(start 0.4953 -0.2032)
			(end -0.4953 -0.2032)
			(stroke
				(width 0.1)
				(type default)
			)
			(layer "B.Fab")
		)
		(pad "1" smd rect
			(at 0 0 90)
			(size 0.762 0.889)
			(layers "B.Cu" "B.Mask" "B.Paste")
			(net "PVPP_KLM")
		)
		(pad "2" smd rect
			(at 0 1.397 90)
			(size 0.762 0.889)
			(layers "B.Cu" "B.Mask" "B.Paste")
			(net "GND")
		)
		(zone
			(layer "B.Cu")
			(hatch none 0.5)
			(connect_pads
				(clearance 0)
			)
			(min_thickness 0.25)
			(keepout
				(tracks not_allowed)
				(vias allowed)
				(pads allowed)
				(copperpour not_allowed)
				(footprints allowed)
			)
			(placement
				(enabled no)
				(sheetname "")
			)
			(fill
				(thermal_gap 0.5)
				(thermal_bridge_width 0.5)
				(island_removal_mode 0)
			)
			(polygon
				(pts
					(xy 152.842468 -154.401012) (xy 153.350468 -154.401012) (xy 153.350468 -155.163012) (xy 152.842468 -155.163012)
				)
			)
		)
	)
	(footprint ""
		(layer "B.Cu")
		(at 194.700398 -24.824182 90)
		(property "Reference" "J6T1"
			(at 2.200148 39.23411 0)
			(unlocked yes)
			(layer "B.SilkS")
			(effects
				(font
					(size 0.7874 0.5842)
					(thickness 0.1524)
				)
				(justify left mirror)
			)
		)
		(property "Value" ""
			(at 0 0 90)
			(layer "B.Fab")
			(effects
				(font
					(size 1.27 1.27)
				)
				(justify mirror)
			)
		)
		(duplicate_pad_numbers_are_jumpers no)
		(fp_line
			(start 0.94996 -7.675118)
			(end -5.5499 -7.675118)
			(stroke
				(width 0.1524)
				(type default)
			)
			(layer "B.SilkS")
		)
		(fp_line
			(start -5.5499 -7.675118)
			(end -5.5499 -1.480058)
			(stroke
				(width 0.1524)
				(type default)
			)
			(layer "B.SilkS")
		)
		(fp_line
			(start 0.94996 -1.480058)
			(end 0.94996 -7.675118)
			(stroke
				(width 0.1524)
				(type default)
			)
			(layer "B.SilkS")
		)
		(fp_line
			(start -5.5499 128.130046)
			(end -5.5499 134.325106)
			(stroke
				(width 0.1524)
				(type default)
			)
			(layer "B.SilkS")
		)
		(fp_line
			(start 0.94996 134.325106)
			(end 0.94996 128.130046)
			(stroke
				(width 0.1524)
				(type default)
			)
			(layer "B.SilkS")
		)
		(fp_line
			(start -5.5499 134.325106)
			(end 0.94996 134.325106)
			(stroke
				(width 0.1524)
				(type default)
			)
			(layer "B.SilkS")
		)
		(fp_poly
			(pts
				(xy 2.984246 -0.461264) (xy 2.984246 0.554736) (xy 1.714246 0.046736)
			)
			(stroke
				(width 0)
				(type default)
			)
			(fill yes)
			(layer "B.SilkS")
		)
		(fp_poly
			(pts
				(xy 0.94996 -7.675118) (xy 0.94996 134.325106) (xy -5.5499 134.325106) (xy -5.5499 -7.675118)
			)
			(stroke
				(width 0)
				(type default)
			)
			(fill no)
			(layer "B.CrtYd")
		)
		(fp_line
			(start 0.94996 -7.675118)
			(end -5.5499 -7.675118)
			(stroke
				(width 0.1)
				(type default)
			)
			(layer "B.Fab")
		)
		(fp_line
			(start -5.5499 -7.675118)
			(end -5.5499 134.325106)
			(stroke
				(width 0.1)
				(type default)
			)
			(layer "B.Fab")
		)
		(fp_line
			(start 0.94996 134.325106)
			(end 0.94996 -7.675118)
			(stroke
				(width 0.1)
				(type default)
			)
			(layer "B.Fab")
		)
		(fp_line
			(start -5.5499 134.325106)
			(end 0.94996 134.325106)
			(stroke
				(width 0.1)
				(type default)
			)
			(layer "B.Fab")
		)
		(fp_poly
			(pts
				(xy 2.984246 -0.461264) (xy 2.984246 0.554736) (xy 1.714246 0.046736)
			)
			(stroke
				(width 0)
				(type default)
			)
			(fill yes)
			(layer "B.Fab")
		)
		(fp_text user "145"
			(at -6.181852 1.26111 0)
			(unlocked yes)
			(layer "B.SilkS")
			(effects
				(font
					(size 0.7874 0.5842)
					(thickness 0.1524)
				)
				(justify left mirror)
			)
		)
		(fp_text user "77"
			(at 1.585722 64.042798 0)
			(unlocked yes)
			(layer "B.SilkS")
			(effects
				(font
					(size 0.7874 0.5842)
					(thickness 0.1524)
				)
				(justify left mirror)
			)
		)
		(fp_text user "221"
			(at -5.546852 67.68211 0)
			(unlocked yes)
			(layer "B.SilkS")
			(effects
				(font
					(size 0.7874 0.5842)
					(thickness 0.1524)
				)
				(justify left mirror)
			)
		)
		(fp_text user "78"
			(at 1.704086 71.326502 0)
			(unlocked yes)
			(layer "B.SilkS")
			(effects
				(font
					(size 0.7874 0.5842)
					(thickness 0.1524)
				)
				(justify left mirror)
			)
		)
		(fp_text user "222"
			(at -6.054852 71.87311 0)
			(unlocked yes)
			(layer "B.SilkS")
			(effects
				(font
					(size 0.7874 0.5842)
					(thickness 0.1524)
				)
				(justify left mirror)
			)
		)
		(fp_text user "288"
			(at -7.959852 129.65811 0)
			(unlocked yes)
			(layer "B.SilkS")
			(effects
				(font
					(size 0.7874 0.5842)
					(thickness 0.1524)
				)
				(justify left mirror)
			)
		)
		(fp_text user "144"
			(at 1.641348 131.326382 0)
			(unlocked yes)
			(layer "B.SilkS")
			(effects
				(font
					(size 0.7874 0.5842)
					(thickness 0.1524)
				)
				(justify left mirror)
			)
		)
		(fp_text user "145"
			(at -2.599182 -1.37922 90)
			(unlocked yes)
			(layer "B.Fab")
			(effects
				(font
					(size 0.7874 0.5842)
					(thickness 0.1524)
				)
				(justify left mirror)
			)
		)
		(fp_text user "77"
			(at 0.575818 65.93078 90)
			(unlocked yes)
			(layer "B.Fab")
			(effects
				(font
					(size 0.7874 0.5842)
					(thickness 0.1524)
				)
				(justify left mirror)
			)
		)
		(fp_text user "221"
			(at -3.234182 65.93078 90)
			(unlocked yes)
			(layer "B.Fab")
			(effects
				(font
					(size 0.7874 0.5842)
					(thickness 0.1524)
				)
				(justify left mirror)
			)
		)
		(fp_text user "78"
			(at 0.575818 69.10578 90)
			(unlocked yes)
			(layer "B.Fab")
			(effects
				(font
					(size 0.7874 0.5842)
					(thickness 0.1524)
				)
				(justify left mirror)
			)
		)
		(fp_text user "222"
			(at -3.234182 69.10578 90)
			(unlocked yes)
			(layer "B.Fab")
			(effects
				(font
					(size 0.7874 0.5842)
					(thickness 0.1524)
				)
				(justify left mirror)
			)
		)
		(fp_text user "144"
			(at 0.575818 128.16078 90)
			(unlocked yes)
			(layer "B.Fab")
			(effects
				(font
					(size 0.7874 0.5842)
					(thickness 0.1524)
				)
				(justify left mirror)
			)
		)
		(fp_text user "288"
			(at -3.234182 128.16078 90)
			(unlocked yes)
			(layer "B.Fab")
			(effects
				(font
					(size 0.7874 0.5842)
					(thickness 0.1524)
				)
				(justify left mirror)
			)
		)
		(pad "" thru_hole circle
			(at -2.29997 -5.649976 270)
			(size 2.8194 2.8194)
			(drill 2.4384)
			(layers "*.Cu" "*.Mask")
			(remove_unused_layers no)
			(clearance 0.127)
			(thermal_gap 0.127)
		)
		(pad "" thru_hole oval
			(at -2.29997 68.90004 270)
			(size 2.8194 1.5748)
			(drill oval 2.4384 1.1938)
			(layers "*.Cu" "*.Mask")
			(remove_unused_layers no)
			(clearance 0.127)
			(thermal_gap 0.127)
		)
		(pad "" thru_hole circle
			(at -2.29997 132.299964 270)
			(size 2.8194 2.8194)
			(drill 2.4384)
			(layers "*.Cu" "*.Mask")
			(remove_unused_layers no)
			(clearance 0.127)
			(thermal_gap 0.127)
		)
		(pad "1" smd rect
			(at 0 0 270)
			(size 1.8034 0.508)
			(layers "B.Cu" "B.Mask" "B.Paste")
			(net "P12V_NVDIMM_ABC")
		)
		(pad "2" smd rect
			(at 0 0.849884 270)
			(size 1.8034 0.508)
			(layers "B.Cu" "B.Mask" "B.Paste")
			(net "GND")
		)
		(pad "3" smd rect
			(at 0 1.700022 270)
			(size 1.8034 0.508)
			(layers "B.Cu" "B.Mask" "B.Paste")
			(net "M_A_DQ<4>")
		)
		(pad "4" smd rect
			(at 0 2.549906 270)
			(size 1.8034 0.508)
			(layers "B.Cu" "B.Mask" "B.Paste")
			(net "GND")
		)
		(pad "5" smd rect
			(at 0 3.400044 270)
			(size 1.8034 0.508)
			(layers "B.Cu" "B.Mask" "B.Paste")
			(net "M_A_DQ<0>")
		)
		(pad "6" smd rect
			(at 0 4.249928 270)
			(size 1.8034 0.508)
			(layers "B.Cu" "B.Mask" "B.Paste")
			(net "GND")
		)
		(pad "7" smd rect
			(at 0 5.100066 270)
			(size 1.8034 0.508)
			(layers "B.Cu" "B.Mask" "B.Paste")
			(net "M_A_DQS_DP<9>")
		)
		(pad "8" smd rect
			(at 0 5.94995 270)
			(size 1.8034 0.508)
			(layers "B.Cu" "B.Mask" "B.Paste")
			(net "M_A_DQS_DN<9>")
		)
		(pad "9" smd rect
			(at 0 6.800088 270)
			(size 1.8034 0.508)
			(layers "B.Cu" "B.Mask" "B.Paste")
			(net "GND")
		)
		(pad "10" smd rect
			(at 0 7.649972 270)
			(size 1.8034 0.508)
			(layers "B.Cu" "B.Mask" "B.Paste")
			(net "M_A_DQ<6>")
		)
		(pad "11" smd rect
			(at 0 8.50011 270)
			(size 1.8034 0.508)
			(layers "B.Cu" "B.Mask" "B.Paste")
			(net "GND")
		)
		(pad "12" smd rect
			(at 0 9.349994 270)
			(size 1.8034 0.508)
			(layers "B.Cu" "B.Mask" "B.Paste")
			(net "M_A_DQ<2>")
		)
		(pad "13" smd rect
			(at 0 10.199878 270)
			(size 1.8034 0.508)
			(layers "B.Cu" "B.Mask" "B.Paste")
			(net "GND")
		)
		(pad "14" smd rect
			(at 0 11.050016 270)
			(size 1.8034 0.508)
			(layers "B.Cu" "B.Mask" "B.Paste")
			(net "M_A_DQ<12>")
		)
		(pad "15" smd rect
			(at 0 11.8999 270)
			(size 1.8034 0.508)
			(layers "B.Cu" "B.Mask" "B.Paste")
			(net "GND")
		)
		(pad "16" smd rect
			(at 0 12.750038 270)
			(size 1.8034 0.508)
			(layers "B.Cu" "B.Mask" "B.Paste")
			(net "M_A_DQ<8>")
		)
		(pad "17" smd rect
			(at 0 13.599922 270)
			(size 1.8034 0.508)
			(layers "B.Cu" "B.Mask" "B.Paste")
			(net "GND")
		)
		(pad "18" smd rect
			(at 0 14.45006 270)
			(size 1.8034 0.508)
			(layers "B.Cu" "B.Mask" "B.Paste")
			(net "M_A_DQS_DP<10>")
		)
		(pad "19" smd rect
			(at 0 15.299944 270)
			(size 1.8034 0.508)
			(layers "B.Cu" "B.Mask" "B.Paste")
			(net "M_A_DQS_DN<10>")
		)
		(pad "20" smd rect
			(at 0 16.150082 270)
			(size 1.8034 0.508)
			(layers "B.Cu" "B.Mask" "B.Paste")
			(net "GND")
		)
		(pad "21" smd rect
			(at 0 16.999966 270)
			(size 1.8034 0.508)
			(layers "B.Cu" "B.Mask" "B.Paste")
			(net "M_A_DQ<14>")
		)
		(pad "22" smd rect
			(at 0 17.850104 270)
			(size 1.8034 0.508)
			(layers "B.Cu" "B.Mask" "B.Paste")
			(net "GND")
		)
		(pad "23" smd rect
			(at 0 18.699988 270)
			(size 1.8034 0.508)
			(layers "B.Cu" "B.Mask" "B.Paste")
			(net "M_A_DQ<10>")
		)
		(pad "24" smd rect
			(at 0 19.550126 270)
			(size 1.8034 0.508)
			(layers "B.Cu" "B.Mask" "B.Paste")
			(net "GND")
		)
		(pad "25" smd rect
			(at 0 20.40001 270)
			(size 1.8034 0.508)
			(layers "B.Cu" "B.Mask" "B.Paste")
			(net "M_A_DQ<20>")
		)
		(pad "26" smd rect
			(at 0 21.249894 270)
			(size 1.8034 0.508)
			(layers "B.Cu" "B.Mask" "B.Paste")
			(net "GND")
		)
		(pad "27" smd rect
			(at 0 22.100032 270)
			(size 1.8034 0.508)
			(layers "B.Cu" "B.Mask" "B.Paste")
			(net "M_A_DQ<16>")
		)
		(pad "28" smd rect
			(at 0 22.949916 270)
			(size 1.8034 0.508)
			(layers "B.Cu" "B.Mask" "B.Paste")
			(net "GND")
		)
		(pad "29" smd rect
			(at 0 23.800054 270)
			(size 1.8034 0.508)
			(layers "B.Cu" "B.Mask" "B.Paste")
			(net "M_A_DQS_DP<11>")
		)
		(pad "30" smd rect
			(at 0 24.649938 270)
			(size 1.8034 0.508)
			(layers "B.Cu" "B.Mask" "B.Paste")
			(net "M_A_DQS_DN<11>")
		)
		(pad "31" smd rect
			(at 0 25.500076 270)
			(size 1.8034 0.508)
			(layers "B.Cu" "B.Mask" "B.Paste")
			(net "GND")
		)
		(pad "32" smd rect
			(at 0 26.34996 270)
			(size 1.8034 0.508)
			(layers "B.Cu" "B.Mask" "B.Paste")
			(net "M_A_DQ<22>")
		)
		(pad "33" smd rect
			(at 0 27.200098 270)
			(size 1.8034 0.508)
			(layers "B.Cu" "B.Mask" "B.Paste")
			(net "GND")
		)
		(pad "34" smd rect
			(at 0 28.049982 270)
			(size 1.8034 0.508)
			(layers "B.Cu" "B.Mask" "B.Paste")
			(net "M_A_DQ<18>")
		)
		(pad "35" smd rect
			(at 0 28.90012 270)
			(size 1.8034 0.508)
			(layers "B.Cu" "B.Mask" "B.Paste")
			(net "GND")
		)
		(pad "36" smd rect
			(at 0 29.750004 270)
			(size 1.8034 0.508)
			(layers "B.Cu" "B.Mask" "B.Paste")
			(net "M_A_DQ<28>")
		)
		(pad "37" smd rect
			(at 0 30.599888 270)
			(size 1.8034 0.508)
			(layers "B.Cu" "B.Mask" "B.Paste")
			(net "GND")
		)
		(pad "38" smd rect
			(at 0 31.450026 270)
			(size 1.8034 0.508)
			(layers "B.Cu" "B.Mask" "B.Paste")
			(net "M_A_DQ<24>")
		)
		(pad "39" smd rect
			(at 0 32.29991 270)
			(size 1.8034 0.508)
			(layers "B.Cu" "B.Mask" "B.Paste")
			(net "GND")
		)
		(pad "40" smd rect
			(at 0 33.150048 270)
			(size 1.8034 0.508)
			(layers "B.Cu" "B.Mask" "B.Paste")
			(net "M_A_DQS_DP<12>")
		)
		(pad "41" smd rect
			(at 0 33.999932 270)
			(size 1.8034 0.508)
			(layers "B.Cu" "B.Mask" "B.Paste")
			(net "M_A_DQS_DN<12>")
		)
		(pad "42" smd rect
			(at 0 34.85007 270)
			(size 1.8034 0.508)
			(layers "B.Cu" "B.Mask" "B.Paste")
			(net "GND")
		)
		(pad "43" smd rect
			(at 0 35.699954 270)
			(size 1.8034 0.508)
			(layers "B.Cu" "B.Mask" "B.Paste")
			(net "M_A_DQ<30>")
		)
		(pad "44" smd rect
			(at 0 36.550092 270)
			(size 1.8034 0.508)
			(layers "B.Cu" "B.Mask" "B.Paste")
			(net "GND")
		)
		(pad "45" smd rect
			(at 0 37.399976 270)
			(size 1.8034 0.508)
			(layers "B.Cu" "B.Mask" "B.Paste")
			(net "M_A_DQ<26>")
		)
		(pad "46" smd rect
			(at 0 38.250114 270)
			(size 1.8034 0.508)
			(layers "B.Cu" "B.Mask" "B.Paste")
			(net "GND")
		)
		(pad "47" smd rect
			(at 0 39.099998 270)
			(size 1.8034 0.508)
			(layers "B.Cu" "B.Mask" "B.Paste")
			(net "M_A_ECC<4>")
		)
		(pad "48" smd rect
			(at 0 39.949882 270)
			(size 1.8034 0.508)
			(layers "B.Cu" "B.Mask" "B.Paste")
			(net "GND")
		)
		(pad "49" smd rect
			(at 0 40.80002 270)
			(size 1.8034 0.508)
			(layers "B.Cu" "B.Mask" "B.Paste")
			(net "M_A_ECC<0>")
		)
		(pad "50" smd rect
			(at 0 41.649904 270)
			(size 1.8034 0.508)
			(layers "B.Cu" "B.Mask" "B.Paste")
			(net "GND")
		)
		(pad "51" smd rect
			(at 0 42.500042 270)
			(size 1.8034 0.508)
			(layers "B.Cu" "B.Mask" "B.Paste")
			(net "M_A_DQS_DP<17>")
		)
		(pad "52" smd rect
			(at 0 43.349926 270)
			(size 1.8034 0.508)
			(layers "B.Cu" "B.Mask" "B.Paste")
			(net "M_A_DQS_DN<17>")
		)
		(pad "53" smd rect
			(at 0 44.200064 270)
			(size 1.8034 0.508)
			(layers "B.Cu" "B.Mask" "B.Paste")
			(net "GND")
		)
		(pad "54" smd rect
			(at 0 45.049948 270)
			(size 1.8034 0.508)
			(layers "B.Cu" "B.Mask" "B.Paste")
			(net "M_A_ECC<6>")
		)
		(pad "55" smd rect
			(at 0 45.900086 270)
			(size 1.8034 0.508)
			(layers "B.Cu" "B.Mask" "B.Paste")
			(net "GND")
		)
		(pad "56" smd rect
			(at 0 46.74997 270)
			(size 1.8034 0.508)
			(layers "B.Cu" "B.Mask" "B.Paste")
			(net "M_A_ECC<2>")
		)
		(pad "57" smd rect
			(at 0 47.600108 270)
			(size 1.8034 0.508)
			(layers "B.Cu" "B.Mask" "B.Paste")
			(net "GND")
		)
		(pad "58" smd rect
			(at 0 48.449992 270)
			(size 1.8034 0.508)
			(layers "B.Cu" "B.Mask" "B.Paste")
			(net "M_ABC_RST_N")
		)
		(pad "59" smd rect
			(at 0 49.299876 270)
			(size 1.8034 0.508)
			(layers "B.Cu" "B.Mask" "B.Paste")
			(net "PVDDQ_ABC")
		)
		(pad "60" smd rect
			(at 0 50.150014 270)
			(size 1.8034 0.508)
			(layers "B.Cu" "B.Mask" "B.Paste")
			(net "M_A_CKE<2>")
		)
		(pad "61" smd rect
			(at 0 50.999898 270)
			(size 1.8034 0.508)
			(layers "B.Cu" "B.Mask" "B.Paste")
			(net "PVDDQ_ABC")
		)
		(pad "62" smd rect
			(at 0 51.850036 270)
			(size 1.8034 0.508)
			(layers "B.Cu" "B.Mask" "B.Paste")
			(net "M_A_ACT_N")
		)
		(pad "63" smd rect
			(at 0 52.69992 270)
			(size 1.8034 0.508)
			(layers "B.Cu" "B.Mask" "B.Paste")
			(net "M_A_BG<0>")
		)
		(pad "64" smd rect
			(at 0 53.550058 270)
			(size 1.8034 0.508)
			(layers "B.Cu" "B.Mask" "B.Paste")
			(net "PVDDQ_ABC")
		)
		(pad "65" smd rect
			(at 0 54.399942 270)
			(size 1.8034 0.508)
			(layers "B.Cu" "B.Mask" "B.Paste")
			(net "M_A_MA<12>")
		)
		(pad "66" smd rect
			(at 0 55.25008 270)
			(size 1.8034 0.508)
			(layers "B.Cu" "B.Mask" "B.Paste")
			(net "M_A_MA<9>")
		)
		(pad "67" smd rect
			(at 0 56.099964 270)
			(size 1.8034 0.508)
			(layers "B.Cu" "B.Mask" "B.Paste")
			(net "PVDDQ_ABC")
		)
		(pad "68" smd rect
			(at 0 56.950102 270)
			(size 1.8034 0.508)
			(layers "B.Cu" "B.Mask" "B.Paste")
			(net "M_A_MA<8>")
		)
		(pad "69" smd rect
			(at 0 57.799986 270)
			(size 1.8034 0.508)
			(layers "B.Cu" "B.Mask" "B.Paste")
			(net "M_A_MA<6>")
		)
		(pad "70" smd rect
			(at 0 58.650124 270)
			(size 1.8034 0.508)
			(layers "B.Cu" "B.Mask" "B.Paste")
			(net "PVDDQ_ABC")
		)
		(pad "71" smd rect
			(at 0 59.500008 270)
			(size 1.8034 0.508)
			(layers "B.Cu" "B.Mask" "B.Paste")
			(net "M_A_MA<3>")
		)
		(pad "72" smd rect
			(at 0 60.349892 270)
			(size 1.8034 0.508)
			(layers "B.Cu" "B.Mask" "B.Paste")
			(net "M_A_MA<1>")
		)
		(pad "73" smd rect
			(at 0 61.20003 270)
			(size 1.8034 0.508)
			(layers "B.Cu" "B.Mask" "B.Paste")
			(net "PVDDQ_ABC")
		)
		(pad "74" smd rect
			(at 0 62.049914 270)
			(size 1.8034 0.508)
			(layers "B.Cu" "B.Mask" "B.Paste")
			(net "M_A_CLK_DP<2>")
		)
		(pad "75" smd rect
			(at 0 62.900052 270)
			(size 1.8034 0.508)
			(layers "B.Cu" "B.Mask" "B.Paste")
			(net "M_A_CLK_DN<2>")
		)
		(pad "76" smd rect
			(at 0 63.749936 270)
			(size 1.8034 0.508)
			(layers "B.Cu" "B.Mask" "B.Paste")
			(net "PVDDQ_ABC")
		)
		(pad "77" smd rect
			(at 0 64.600074 270)
			(size 1.8034 0.508)
			(layers "B.Cu" "B.Mask" "B.Paste")
			(net "PVTT_ABC")
		)
		(pad "78" smd rect
			(at 0 70.550024 270)
			(size 1.8034 0.508)
			(layers "B.Cu" "B.Mask" "B.Paste")
			(net "FM_DIMM_EVENT_COD_N")
		)
		(pad "79" smd rect
			(at 0 71.399908 270)
			(size 1.8034 0.508)
			(layers "B.Cu" "B.Mask" "B.Paste")
			(net "M_A_MA<0>")
		)
		(pad "80" smd rect
			(at 0 72.250046 270)
			(size 1.8034 0.508)
			(layers "B.Cu" "B.Mask" "B.Paste")
			(net "PVDDQ_ABC")
		)
		(pad "81" smd rect
			(at 0 73.09993 270)
			(size 1.8034 0.508)
			(layers "B.Cu" "B.Mask" "B.Paste")
			(net "M_A_BA<0>")
		)
		(pad "82" smd rect
			(at 0 73.950068 270)
			(size 1.8034 0.508)
			(layers "B.Cu" "B.Mask" "B.Paste")
			(net "M_A_MA<16>")
		)
		(pad "83" smd rect
			(at 0 74.799952 270)
			(size 1.8034 0.508)
			(layers "B.Cu" "B.Mask" "B.Paste")
			(net "PVDDQ_ABC")
		)
		(pad "84" smd rect
			(at 0 75.65009 270)
			(size 1.8034 0.508)
			(layers "B.Cu" "B.Mask" "B.Paste")
			(net "M_A_CS_N<4>")
		)
		(pad "85" smd rect
			(at 0 76.499974 270)
			(size 1.8034 0.508)
			(layers "B.Cu" "B.Mask" "B.Paste")
			(net "PVDDQ_ABC")
		)
		(pad "86" smd rect
			(at 0 77.350112 270)
			(size 1.8034 0.508)
			(layers "B.Cu" "B.Mask" "B.Paste")
			(net "M_A_MA<15>")
		)
		(pad "87" smd rect
			(at 0 78.199996 270)
			(size 1.8034 0.508)
			(layers "B.Cu" "B.Mask" "B.Paste")
			(net "M_A_ODT<2>")
		)
		(pad "88" smd rect
			(at 0 79.04988 270)
			(size 1.8034 0.508)
			(layers "B.Cu" "B.Mask" "B.Paste")
			(net "PVDDQ_ABC")
		)
		(pad "89" smd rect
			(at 0 79.900018 270)
			(size 1.8034 0.508)
			(layers "B.Cu" "B.Mask" "B.Paste")
			(net "M_A_CS_N<5>")
		)
		(pad "90" smd rect
			(at 0 80.749902 270)
			(size 1.8034 0.508)
			(layers "B.Cu" "B.Mask" "B.Paste")
			(net "PVDDQ_ABC")
		)
		(pad "91" smd rect
			(at 0 81.60004 270)
			(size 1.8034 0.508)
			(layers "B.Cu" "B.Mask" "B.Paste")
			(net "M_A_ODT<3>")
		)
		(pad "92" smd rect
			(at 0 82.449924 270)
			(size 1.8034 0.508)
			(layers "B.Cu" "B.Mask" "B.Paste")
			(net "PVDDQ_ABC")
		)
		(pad "93" smd rect
			(at 0 83.300062 270)
			(size 1.8034 0.508)
			(layers "B.Cu" "B.Mask" "B.Paste")
			(net "M_A_CS_N<6>")
		)
		(pad "94" smd rect
			(at 0 84.149946 270)
			(size 1.8034 0.508)
			(layers "B.Cu" "B.Mask" "B.Paste")
			(net "GND")
		)
		(pad "95" smd rect
			(at 0 85.000084 270)
			(size 1.8034 0.508)
			(layers "B.Cu" "B.Mask" "B.Paste")
			(net "M_A_DQ<36>")
		)
		(pad "96" smd rect
			(at 0 85.849968 270)
			(size 1.8034 0.508)
			(layers "B.Cu" "B.Mask" "B.Paste")
			(net "GND")
		)
		(pad "97" smd rect
			(at 0 86.700106 270)
			(size 1.8034 0.508)
			(layers "B.Cu" "B.Mask" "B.Paste")
			(net "M_A_DQ<32>")
		)
		(pad "98" smd rect
			(at 0 87.54999 270)
			(size 1.8034 0.508)
			(layers "B.Cu" "B.Mask" "B.Paste")
			(net "GND")
		)
		(pad "99" smd rect
			(at 0 88.399874 270)
			(size 1.8034 0.508)
			(layers "B.Cu" "B.Mask" "B.Paste")
			(net "M_A_DQS_DP<13>")
		)
		(pad "100" smd rect
			(at 0 89.250012 270)
			(size 1.8034 0.508)
			(layers "B.Cu" "B.Mask" "B.Paste")
			(net "M_A_DQS_DN<13>")
		)
		(pad "101" smd rect
			(at 0 90.099896 270)
			(size 1.8034 0.508)
			(layers "B.Cu" "B.Mask" "B.Paste")
			(net "GND")
		)
		(pad "102" smd rect
			(at 0 90.950034 270)
			(size 1.8034 0.508)
			(layers "B.Cu" "B.Mask" "B.Paste")
			(net "M_A_DQ<38>")
		)
		(pad "103" smd rect
			(at 0 91.799918 270)
			(size 1.8034 0.508)
			(layers "B.Cu" "B.Mask" "B.Paste")
			(net "GND")
		)
		(pad "104" smd rect
			(at 0 92.650056 270)
			(size 1.8034 0.508)
			(layers "B.Cu" "B.Mask" "B.Paste")
			(net "M_A_DQ<34>")
		)
		(pad "105" smd rect
			(at 0 93.49994 270)
			(size 1.8034 0.508)
			(layers "B.Cu" "B.Mask" "B.Paste")
			(net "GND")
		)
		(pad "106" smd rect
			(at 0 94.350078 270)
			(size 1.8034 0.508)
			(layers "B.Cu" "B.Mask" "B.Paste")
			(net "M_A_DQ<44>")
		)
		(pad "107" smd rect
			(at 0 95.199962 270)
			(size 1.8034 0.508)
			(layers "B.Cu" "B.Mask" "B.Paste")
			(net "GND")
		)
		(pad "108" smd rect
			(at 0 96.0501 270)
			(size 1.8034 0.508)
			(layers "B.Cu" "B.Mask" "B.Paste")
			(net "M_A_DQ<40>")
		)
		(pad "109" smd rect
			(at 0 96.899984 270)
			(size 1.8034 0.508)
			(layers "B.Cu" "B.Mask" "B.Paste")
			(net "GND")
		)
		(pad "110" smd rect
			(at 0 97.750122 270)
			(size 1.8034 0.508)
			(layers "B.Cu" "B.Mask" "B.Paste")
			(net "M_A_DQS_DP<14>")
		)
		(pad "111" smd rect
			(at 0 98.600006 270)
			(size 1.8034 0.508)
			(layers "B.Cu" "B.Mask" "B.Paste")
			(net "M_A_DQS_DN<14>")
		)
		(pad "112" smd rect
			(at 0 99.44989 270)
			(size 1.8034 0.508)
			(layers "B.Cu" "B.Mask" "B.Paste")
			(net "GND")
		)
		(pad "113" smd rect
			(at 0 100.300028 270)
			(size 1.8034 0.508)
			(layers "B.Cu" "B.Mask" "B.Paste")
			(net "M_A_DQ<46>")
		)
		(pad "114" smd rect
			(at 0 101.149912 270)
			(size 1.8034 0.508)
			(layers "B.Cu" "B.Mask" "B.Paste")
			(net "GND")
		)
		(pad "115" smd rect
			(at 0 102.00005 270)
			(size 1.8034 0.508)
			(layers "B.Cu" "B.Mask" "B.Paste")
			(net "M_A_DQ<42>")
		)
		(pad "116" smd rect
			(at 0 102.849934 270)
			(size 1.8034 0.508)
			(layers "B.Cu" "B.Mask" "B.Paste")
			(net "GND")
		)
		(pad "117" smd rect
			(at 0 103.700072 270)
			(size 1.8034 0.508)
			(layers "B.Cu" "B.Mask" "B.Paste")
			(net "M_A_DQ<52>")
		)
		(pad "118" smd rect
			(at 0 104.549956 270)
			(size 1.8034 0.508)
			(layers "B.Cu" "B.Mask" "B.Paste")
			(net "GND")
		)
		(pad "119" smd rect
			(at 0 105.400094 270)
			(size 1.8034 0.508)
			(layers "B.Cu" "B.Mask" "B.Paste")
			(net "M_A_DQ<48>")
		)
		(pad "120" smd rect
			(at 0 106.249978 270)
			(size 1.8034 0.508)
			(layers "B.Cu" "B.Mask" "B.Paste")
			(net "GND")
		)
		(pad "121" smd rect
			(at 0 107.100116 270)
			(size 1.8034 0.508)
			(layers "B.Cu" "B.Mask" "B.Paste")
			(net "M_A_DQS_DP<15>")
		)
		(pad "122" smd rect
			(at 0 107.95 270)
			(size 1.8034 0.508)
			(layers "B.Cu" "B.Mask" "B.Paste")
			(net "M_A_DQS_DN<15>")
		)
		(pad "123" smd rect
			(at 0 108.799884 270)
			(size 1.8034 0.508)
			(layers "B.Cu" "B.Mask" "B.Paste")
			(net "GND")
		)
		(pad "124" smd rect
			(at 0 109.650022 270)
			(size 1.8034 0.508)
			(layers "B.Cu" "B.Mask" "B.Paste")
			(net "M_A_DQ<54>")
		)
		(pad "125" smd rect
			(at 0 110.499906 270)
			(size 1.8034 0.508)
			(layers "B.Cu" "B.Mask" "B.Paste")
			(net "GND")
		)
		(pad "126" smd rect
			(at 0 111.350044 270)
			(size 1.8034 0.508)
			(layers "B.Cu" "B.Mask" "B.Paste")
			(net "M_A_DQ<50>")
		)
		(pad "127" smd rect
			(at 0 112.199928 270)
			(size 1.8034 0.508)
			(layers "B.Cu" "B.Mask" "B.Paste")
			(net "GND")
		)
		(pad "128" smd rect
			(at 0 113.050066 270)
			(size 1.8034 0.508)
			(layers "B.Cu" "B.Mask" "B.Paste")
			(net "M_A_DQ<60>")
		)
		(pad "129" smd rect
			(at 0 113.89995 270)
			(size 1.8034 0.508)
			(layers "B.Cu" "B.Mask" "B.Paste")
			(net "GND")
		)
		(pad "130" smd rect
			(at 0 114.750088 270)
			(size 1.8034 0.508)
			(layers "B.Cu" "B.Mask" "B.Paste")
			(net "M_A_DQ<56>")
		)
		(pad "131" smd rect
			(at 0 115.599972 270)
			(size 1.8034 0.508)
			(layers "B.Cu" "B.Mask" "B.Paste")
			(net "GND")
		)
		(pad "132" smd rect
			(at 0 116.45011 270)
			(size 1.8034 0.508)
			(layers "B.Cu" "B.Mask" "B.Paste")
			(net "M_A_DQS_DP<16>")
		)
		(pad "133" smd rect
			(at 0 117.299994 270)
			(size 1.8034 0.508)
			(layers "B.Cu" "B.Mask" "B.Paste")
			(net "M_A_DQS_DN<16>")
		)
		(pad "134" smd rect
			(at 0 118.149878 270)
			(size 1.8034 0.508)
			(layers "B.Cu" "B.Mask" "B.Paste")
			(net "GND")
		)
		(pad "135" smd rect
			(at 0 119.000016 270)
			(size 1.8034 0.508)
			(layers "B.Cu" "B.Mask" "B.Paste")
			(net "M_A_DQ<62>")
		)
		(pad "136" smd rect
			(at 0 119.8499 270)
			(size 1.8034 0.508)
			(layers "B.Cu" "B.Mask" "B.Paste")
			(net "GND")
		)
		(pad "137" smd rect
			(at 0 120.700038 270)
			(size 1.8034 0.508)
			(layers "B.Cu" "B.Mask" "B.Paste")
			(net "M_A_DQ<58>")
		)
		(pad "138" smd rect
			(at 0 121.549922 270)
			(size 1.8034 0.508)
			(layers "B.Cu" "B.Mask" "B.Paste")
			(net "GND")
		)
		(pad "139" smd rect
			(at 0 122.40006 270)
			(size 1.8034 0.508)
			(layers "B.Cu" "B.Mask" "B.Paste")
			(net "PVPP_ABC")
		)
		(pad "140" smd rect
			(at 0 123.249944 270)
			(size 1.8034 0.508)
			(layers "B.Cu" "B.Mask" "B.Paste")
			(net "GND")
		)
		(pad "141" smd rect
			(at 0 124.100082 270)
			(size 1.8034 0.508)
			(layers "B.Cu" "B.Mask" "B.Paste")
			(net "SMB_DDR_ABC_VPP_SCL")
		)
		(pad "142" smd rect
			(at 0 124.949966 270)
			(size 1.8034 0.508)
			(layers "B.Cu" "B.Mask" "B.Paste")
			(net "PVPP_ABC")
		)
		(pad "143" smd rect
			(at 0 125.800104 270)
			(size 1.8034 0.508)
			(layers "B.Cu" "B.Mask" "B.Paste")
			(net "PVPP_ABC")
		)
		(pad "144" smd rect
			(at 0 126.649988 270)
			(size 1.8034 0.508)
			(layers "B.Cu" "B.Mask" "B.Paste")
			(net "TP_CH_A_DIMM_A1_RFU_2")
		)
		(pad "145" smd rect
			(at -4.59994 0 270)
			(size 1.8034 0.508)
			(layers "B.Cu" "B.Mask" "B.Paste")
			(net "P12V_NVDIMM_ABC")
		)
		(pad "146" smd rect
			(at -4.59994 0.849884 270)
			(size 1.8034 0.508)
			(layers "B.Cu" "B.Mask" "B.Paste")
			(net "M_A_VREF")
		)
		(pad "147" smd rect
			(at -4.59994 1.700022 270)
			(size 1.8034 0.508)
			(layers "B.Cu" "B.Mask" "B.Paste")
			(net "GND")
		)
		(pad "148" smd rect
			(at -4.59994 2.549906 270)
			(size 1.8034 0.508)
			(layers "B.Cu" "B.Mask" "B.Paste")
			(net "M_A_DQ<5>")
		)
		(pad "149" smd rect
			(at -4.59994 3.400044 270)
			(size 1.8034 0.508)
			(layers "B.Cu" "B.Mask" "B.Paste")
			(net "GND")
		)
		(pad "150" smd rect
			(at -4.59994 4.249928 270)
			(size 1.8034 0.508)
			(layers "B.Cu" "B.Mask" "B.Paste")
			(net "M_A_DQ<1>")
		)
		(pad "151" smd rect
			(at -4.59994 5.100066 270)
			(size 1.8034 0.508)
			(layers "B.Cu" "B.Mask" "B.Paste")
			(net "GND")
		)
		(pad "152" smd rect
			(at -4.59994 5.94995 270)
			(size 1.8034 0.508)
			(layers "B.Cu" "B.Mask" "B.Paste")
			(net "M_A_DQS_DN<0>")
		)
		(pad "153" smd rect
			(at -4.59994 6.800088 270)
			(size 1.8034 0.508)
			(layers "B.Cu" "B.Mask" "B.Paste")
			(net "M_A_DQS_DP<0>")
		)
		(pad "154" smd rect
			(at -4.59994 7.649972 270)
			(size 1.8034 0.508)
			(layers "B.Cu" "B.Mask" "B.Paste")
			(net "GND")
		)
		(pad "155" smd rect
			(at -4.59994 8.50011 270)
			(size 1.8034 0.508)
			(layers "B.Cu" "B.Mask" "B.Paste")
			(net "M_A_DQ<7>")
		)
		(pad "156" smd rect
			(at -4.59994 9.349994 270)
			(size 1.8034 0.508)
			(layers "B.Cu" "B.Mask" "B.Paste")
			(net "GND")
		)
		(pad "157" smd rect
			(at -4.59994 10.199878 270)
			(size 1.8034 0.508)
			(layers "B.Cu" "B.Mask" "B.Paste")
			(net "M_A_DQ<3>")
		)
		(pad "158" smd rect
			(at -4.59994 11.050016 270)
			(size 1.8034 0.508)
			(layers "B.Cu" "B.Mask" "B.Paste")
			(net "GND")
		)
		(pad "159" smd rect
			(at -4.59994 11.8999 270)
			(size 1.8034 0.508)
			(layers "B.Cu" "B.Mask" "B.Paste")
			(net "M_A_DQ<13>")
		)
		(pad "160" smd rect
			(at -4.59994 12.750038 270)
			(size 1.8034 0.508)
			(layers "B.Cu" "B.Mask" "B.Paste")
			(net "GND")
		)
		(pad "161" smd rect
			(at -4.59994 13.599922 270)
			(size 1.8034 0.508)
			(layers "B.Cu" "B.Mask" "B.Paste")
			(net "M_A_DQ<9>")
		)
		(pad "162" smd rect
			(at -4.59994 14.45006 270)
			(size 1.8034 0.508)
			(layers "B.Cu" "B.Mask" "B.Paste")
			(net "GND")
		)
		(pad "163" smd rect
			(at -4.59994 15.299944 270)
			(size 1.8034 0.508)
			(layers "B.Cu" "B.Mask" "B.Paste")
			(net "M_A_DQS_DN<1>")
		)
		(pad "164" smd rect
			(at -4.59994 16.150082 270)
			(size 1.8034 0.508)
			(layers "B.Cu" "B.Mask" "B.Paste")
			(net "M_A_DQS_DP<1>")
		)
		(pad "165" smd rect
			(at -4.59994 16.999966 270)
			(size 1.8034 0.508)
			(layers "B.Cu" "B.Mask" "B.Paste")
			(net "GND")
		)
		(pad "166" smd rect
			(at -4.59994 17.850104 270)
			(size 1.8034 0.508)
			(layers "B.Cu" "B.Mask" "B.Paste")
			(net "M_A_DQ<15>")
		)
		(pad "167" smd rect
			(at -4.59994 18.699988 270)
			(size 1.8034 0.508)
			(layers "B.Cu" "B.Mask" "B.Paste")
			(net "GND")
		)
		(pad "168" smd rect
			(at -4.59994 19.550126 270)
			(size 1.8034 0.508)
			(layers "B.Cu" "B.Mask" "B.Paste")
			(net "M_A_DQ<11>")
		)
		(pad "169" smd rect
			(at -4.59994 20.40001 270)
			(size 1.8034 0.508)
			(layers "B.Cu" "B.Mask" "B.Paste")
			(net "GND")
		)
		(pad "170" smd rect
			(at -4.59994 21.249894 270)
			(size 1.8034 0.508)
			(layers "B.Cu" "B.Mask" "B.Paste")
			(net "M_A_DQ<21>")
		)
		(pad "171" smd rect
			(at -4.59994 22.100032 270)
			(size 1.8034 0.508)
			(layers "B.Cu" "B.Mask" "B.Paste")
			(net "GND")
		)
		(pad "172" smd rect
			(at -4.59994 22.949916 270)
			(size 1.8034 0.508)
			(layers "B.Cu" "B.Mask" "B.Paste")
			(net "M_A_DQ<17>")
		)
		(pad "173" smd rect
			(at -4.59994 23.800054 270)
			(size 1.8034 0.508)
			(layers "B.Cu" "B.Mask" "B.Paste")
			(net "GND")
		)
		(pad "174" smd rect
			(at -4.59994 24.649938 270)
			(size 1.8034 0.508)
			(layers "B.Cu" "B.Mask" "B.Paste")
			(net "M_A_DQS_DN<2>")
		)
		(pad "175" smd rect
			(at -4.59994 25.500076 270)
			(size 1.8034 0.508)
			(layers "B.Cu" "B.Mask" "B.Paste")
			(net "M_A_DQS_DP<2>")
		)
		(pad "176" smd rect
			(at -4.59994 26.34996 270)
			(size 1.8034 0.508)
			(layers "B.Cu" "B.Mask" "B.Paste")
			(net "GND")
		)
		(pad "177" smd rect
			(at -4.59994 27.200098 270)
			(size 1.8034 0.508)
			(layers "B.Cu" "B.Mask" "B.Paste")
			(net "M_A_DQ<23>")
		)
		(pad "178" smd rect
			(at -4.59994 28.049982 270)
			(size 1.8034 0.508)
			(layers "B.Cu" "B.Mask" "B.Paste")
			(net "GND")
		)
		(pad "179" smd rect
			(at -4.59994 28.90012 270)
			(size 1.8034 0.508)
			(layers "B.Cu" "B.Mask" "B.Paste")
			(net "M_A_DQ<19>")
		)
		(pad "180" smd rect
			(at -4.59994 29.750004 270)
			(size 1.8034 0.508)
			(layers "B.Cu" "B.Mask" "B.Paste")
			(net "GND")
		)
		(pad "181" smd rect
			(at -4.59994 30.599888 270)
			(size 1.8034 0.508)
			(layers "B.Cu" "B.Mask" "B.Paste")
			(net "M_A_DQ<29>")
		)
		(pad "182" smd rect
			(at -4.59994 31.450026 270)
			(size 1.8034 0.508)
			(layers "B.Cu" "B.Mask" "B.Paste")
			(net "GND")
		)
		(pad "183" smd rect
			(at -4.59994 32.29991 270)
			(size 1.8034 0.508)
			(layers "B.Cu" "B.Mask" "B.Paste")
			(net "M_A_DQ<25>")
		)
		(pad "184" smd rect
			(at -4.59994 33.150048 270)
			(size 1.8034 0.508)
			(layers "B.Cu" "B.Mask" "B.Paste")
			(net "GND")
		)
		(pad "185" smd rect
			(at -4.59994 33.999932 270)
			(size 1.8034 0.508)
			(layers "B.Cu" "B.Mask" "B.Paste")
			(net "M_A_DQS_DN<3>")
		)
		(pad "186" smd rect
			(at -4.59994 34.85007 270)
			(size 1.8034 0.508)
			(layers "B.Cu" "B.Mask" "B.Paste")
			(net "M_A_DQS_DP<3>")
		)
		(pad "187" smd rect
			(at -4.59994 35.699954 270)
			(size 1.8034 0.508)
			(layers "B.Cu" "B.Mask" "B.Paste")
			(net "GND")
		)
		(pad "188" smd rect
			(at -4.59994 36.550092 270)
			(size 1.8034 0.508)
			(layers "B.Cu" "B.Mask" "B.Paste")
			(net "M_A_DQ<31>")
		)
		(pad "189" smd rect
			(at -4.59994 37.399976 270)
			(size 1.8034 0.508)
			(layers "B.Cu" "B.Mask" "B.Paste")
			(net "GND")
		)
		(pad "190" smd rect
			(at -4.59994 38.250114 270)
			(size 1.8034 0.508)
			(layers "B.Cu" "B.Mask" "B.Paste")
			(net "M_A_DQ<27>")
		)
		(pad "191" smd rect
			(at -4.59994 39.099998 270)
			(size 1.8034 0.508)
			(layers "B.Cu" "B.Mask" "B.Paste")
			(net "GND")
		)
		(pad "192" smd rect
			(at -4.59994 39.949882 270)
			(size 1.8034 0.508)
			(layers "B.Cu" "B.Mask" "B.Paste")
			(net "M_A_ECC<5>")
		)
		(pad "193" smd rect
			(at -4.59994 40.80002 270)
			(size 1.8034 0.508)
			(layers "B.Cu" "B.Mask" "B.Paste")
			(net "GND")
		)
		(pad "194" smd rect
			(at -4.59994 41.649904 270)
			(size 1.8034 0.508)
			(layers "B.Cu" "B.Mask" "B.Paste")
			(net "M_A_ECC<1>")
		)
		(pad "195" smd rect
			(at -4.59994 42.500042 270)
			(size 1.8034 0.508)
			(layers "B.Cu" "B.Mask" "B.Paste")
			(net "GND")
		)
		(pad "196" smd rect
			(at -4.59994 43.349926 270)
			(size 1.8034 0.508)
			(layers "B.Cu" "B.Mask" "B.Paste")
			(net "M_A_DQS_DN<8>")
		)
		(pad "197" smd rect
			(at -4.59994 44.200064 270)
			(size 1.8034 0.508)
			(layers "B.Cu" "B.Mask" "B.Paste")
			(net "M_A_DQS_DP<8>")
		)
		(pad "198" smd rect
			(at -4.59994 45.049948 270)
			(size 1.8034 0.508)
			(layers "B.Cu" "B.Mask" "B.Paste")
			(net "GND")
		)
		(pad "199" smd rect
			(at -4.59994 45.900086 270)
			(size 1.8034 0.508)
			(layers "B.Cu" "B.Mask" "B.Paste")
			(net "M_A_ECC<7>")
		)
		(pad "200" smd rect
			(at -4.59994 46.74997 270)
			(size 1.8034 0.508)
			(layers "B.Cu" "B.Mask" "B.Paste")
			(net "GND")
		)
		(pad "201" smd rect
			(at -4.59994 47.600108 270)
			(size 1.8034 0.508)
			(layers "B.Cu" "B.Mask" "B.Paste")
			(net "M_A_ECC<3>")
		)
		(pad "202" smd rect
			(at -4.59994 48.449992 270)
			(size 1.8034 0.508)
			(layers "B.Cu" "B.Mask" "B.Paste")
			(net "GND")
		)
		(pad "203" smd rect
			(at -4.59994 49.299876 270)
			(size 1.8034 0.508)
			(layers "B.Cu" "B.Mask" "B.Paste")
			(net "M_A_CKE<3>")
		)
		(pad "204" smd rect
			(at -4.59994 50.150014 270)
			(size 1.8034 0.508)
			(layers "B.Cu" "B.Mask" "B.Paste")
			(net "PVDDQ_ABC")
		)
		(pad "205" smd rect
			(at -4.59994 50.999898 270)
			(size 1.8034 0.508)
			(layers "B.Cu" "B.Mask" "B.Paste")
			(net "TP_CH_A_DIMM_A1_RFU_0")
		)
		(pad "206" smd rect
			(at -4.59994 51.850036 270)
			(size 1.8034 0.508)
			(layers "B.Cu" "B.Mask" "B.Paste")
			(net "PVDDQ_ABC")
		)
		(pad "207" smd rect
			(at -4.59994 52.69992 270)
			(size 1.8034 0.508)
			(layers "B.Cu" "B.Mask" "B.Paste")
			(net "M_A_BG<1>")
		)
		(pad "208" smd rect
			(at -4.59994 53.550058 270)
			(size 1.8034 0.508)
			(layers "B.Cu" "B.Mask" "B.Paste")
			(net "M_A_ALERT_N")
		)
		(pad "209" smd rect
			(at -4.59994 54.399942 270)
			(size 1.8034 0.508)
			(layers "B.Cu" "B.Mask" "B.Paste")
			(net "PVDDQ_ABC")
		)
		(pad "210" smd rect
			(at -4.59994 55.25008 270)
			(size 1.8034 0.508)
			(layers "B.Cu" "B.Mask" "B.Paste")
			(net "M_A_MA<11>")
		)
		(pad "211" smd rect
			(at -4.59994 56.099964 270)
			(size 1.8034 0.508)
			(layers "B.Cu" "B.Mask" "B.Paste")
			(net "M_A_MA<7>")
		)
		(pad "212" smd rect
			(at -4.59994 56.950102 270)
			(size 1.8034 0.508)
			(layers "B.Cu" "B.Mask" "B.Paste")
			(net "PVDDQ_ABC")
		)
		(pad "213" smd rect
			(at -4.59994 57.799986 270)
			(size 1.8034 0.508)
			(layers "B.Cu" "B.Mask" "B.Paste")
			(net "M_A_MA<5>")
		)
		(pad "214" smd rect
			(at -4.59994 58.650124 270)
			(size 1.8034 0.508)
			(layers "B.Cu" "B.Mask" "B.Paste")
			(net "M_A_MA<4>")
		)
		(pad "215" smd rect
			(at -4.59994 59.500008 270)
			(size 1.8034 0.508)
			(layers "B.Cu" "B.Mask" "B.Paste")
			(net "PVDDQ_ABC")
		)
		(pad "216" smd rect
			(at -4.59994 60.349892 270)
			(size 1.8034 0.508)
			(layers "B.Cu" "B.Mask" "B.Paste")
			(net "M_A_MA<2>")
		)
		(pad "217" smd rect
			(at -4.59994 61.20003 270)
			(size 1.8034 0.508)
			(layers "B.Cu" "B.Mask" "B.Paste")
			(net "PVDDQ_ABC")
		)
		(pad "218" smd rect
			(at -4.59994 62.049914 270)
			(size 1.8034 0.508)
			(layers "B.Cu" "B.Mask" "B.Paste")
			(net "M_A_CLK_DP<3>")
		)
		(pad "219" smd rect
			(at -4.59994 62.900052 270)
			(size 1.8034 0.508)
			(layers "B.Cu" "B.Mask" "B.Paste")
			(net "M_A_CLK_DN<3>")
		)
		(pad "220" smd rect
			(at -4.59994 63.749936 270)
			(size 1.8034 0.508)
			(layers "B.Cu" "B.Mask" "B.Paste")
			(net "PVDDQ_ABC")
		)
		(pad "221" smd rect
			(at -4.59994 64.600074 270)
			(size 1.8034 0.508)
			(layers "B.Cu" "B.Mask" "B.Paste")
			(net "PVTT_ABC")
		)
		(pad "222" smd rect
			(at -4.59994 70.550024 270)
			(size 1.8034 0.508)
			(layers "B.Cu" "B.Mask" "B.Paste")
			(net "M_A_PAR")
		)
		(pad "223" smd rect
			(at -4.59994 71.399908 270)
			(size 1.8034 0.508)
			(layers "B.Cu" "B.Mask" "B.Paste")
			(net "PVDDQ_ABC")
		)
		(pad "224" smd rect
			(at -4.59994 72.250046 270)
			(size 1.8034 0.508)
			(layers "B.Cu" "B.Mask" "B.Paste")
			(net "M_A_BA<1>")
		)
		(pad "225" smd rect
			(at -4.59994 73.09993 270)
			(size 1.8034 0.508)
			(layers "B.Cu" "B.Mask" "B.Paste")
			(net "M_A_MA<10>")
		)
		(pad "226" smd rect
			(at -4.59994 73.950068 270)
			(size 1.8034 0.508)
			(layers "B.Cu" "B.Mask" "B.Paste")
			(net "PVDDQ_ABC")
		)
		(pad "227" smd rect
			(at -4.59994 74.799952 270)
			(size 1.8034 0.508)
			(layers "B.Cu" "B.Mask" "B.Paste")
			(net "TP_CH_A_DIMM_A1_RFU_1")
		)
		(pad "228" smd rect
			(at -4.59994 75.65009 270)
			(size 1.8034 0.508)
			(layers "B.Cu" "B.Mask" "B.Paste")
			(net "M_A_MA<14>")
		)
		(pad "229" smd rect
			(at -4.59994 76.499974 270)
			(size 1.8034 0.508)
			(layers "B.Cu" "B.Mask" "B.Paste")
			(net "PVDDQ_ABC")
		)
		(pad "230" smd rect
			(at -4.59994 77.350112 270)
			(size 1.8034 0.508)
			(layers "B.Cu" "B.Mask" "B.Paste")
			(net "FM_ADR_COMPLETE_ABC_N")
		)
		(pad "231" smd rect
			(at -4.59994 78.199996 270)
			(size 1.8034 0.508)
			(layers "B.Cu" "B.Mask" "B.Paste")
			(net "PVDDQ_ABC")
		)
		(pad "232" smd rect
			(at -4.59994 79.04988 270)
			(size 1.8034 0.508)
			(layers "B.Cu" "B.Mask" "B.Paste")
			(net "M_A_MA<13>")
		)
		(pad "233" smd rect
			(at -4.59994 79.900018 270)
			(size 1.8034 0.508)
			(layers "B.Cu" "B.Mask" "B.Paste")
			(net "PVDDQ_ABC")
		)
		(pad "234" smd rect
			(at -4.59994 80.749902 270)
			(size 1.8034 0.508)
			(layers "B.Cu" "B.Mask" "B.Paste")
			(net "M_A_MA<17>")
		)
		(pad "235" smd rect
			(at -4.59994 81.60004 270)
			(size 1.8034 0.508)
			(layers "B.Cu" "B.Mask" "B.Paste")
			(net "M_A_C<2>")
		)
		(pad "236" smd rect
			(at -4.59994 82.449924 270)
			(size 1.8034 0.508)
			(layers "B.Cu" "B.Mask" "B.Paste")
			(net "PVDDQ_ABC")
		)
		(pad "237" smd rect
			(at -4.59994 83.300062 270)
			(size 1.8034 0.508)
			(layers "B.Cu" "B.Mask" "B.Paste")
			(net "M_A_CS_N<7>")
		)
		(pad "238" smd rect
			(at -4.59994 84.149946 270)
			(size 1.8034 0.508)
			(layers "B.Cu" "B.Mask" "B.Paste")
			(net "GND")
		)
		(pad "239" smd rect
			(at -4.59994 85.000084 270)
			(size 1.8034 0.508)
			(layers "B.Cu" "B.Mask" "B.Paste")
			(net "GND")
		)
		(pad "240" smd rect
			(at -4.59994 85.849968 270)
			(size 1.8034 0.508)
			(layers "B.Cu" "B.Mask" "B.Paste")
			(net "M_A_DQ<37>")
		)
		(pad "241" smd rect
			(at -4.59994 86.700106 270)
			(size 1.8034 0.508)
			(layers "B.Cu" "B.Mask" "B.Paste")
			(net "GND")
		)
		(pad "242" smd rect
			(at -4.59994 87.54999 270)
			(size 1.8034 0.508)
			(layers "B.Cu" "B.Mask" "B.Paste")
			(net "M_A_DQ<33>")
		)
		(pad "243" smd rect
			(at -4.59994 88.399874 270)
			(size 1.8034 0.508)
			(layers "B.Cu" "B.Mask" "B.Paste")
			(net "GND")
		)
		(pad "244" smd rect
			(at -4.59994 89.250012 270)
			(size 1.8034 0.508)
			(layers "B.Cu" "B.Mask" "B.Paste")
			(net "M_A_DQS_DN<4>")
		)
		(pad "245" smd rect
			(at -4.59994 90.099896 270)
			(size 1.8034 0.508)
			(layers "B.Cu" "B.Mask" "B.Paste")
			(net "M_A_DQS_DP<4>")
		)
		(pad "246" smd rect
			(at -4.59994 90.950034 270)
			(size 1.8034 0.508)
			(layers "B.Cu" "B.Mask" "B.Paste")
			(net "GND")
		)
		(pad "247" smd rect
			(at -4.59994 91.799918 270)
			(size 1.8034 0.508)
			(layers "B.Cu" "B.Mask" "B.Paste")
			(net "M_A_DQ<39>")
		)
		(pad "248" smd rect
			(at -4.59994 92.650056 270)
			(size 1.8034 0.508)
			(layers "B.Cu" "B.Mask" "B.Paste")
			(net "GND")
		)
		(pad "249" smd rect
			(at -4.59994 93.49994 270)
			(size 1.8034 0.508)
			(layers "B.Cu" "B.Mask" "B.Paste")
			(net "M_A_DQ<35>")
		)
		(pad "250" smd rect
			(at -4.59994 94.350078 270)
			(size 1.8034 0.508)
			(layers "B.Cu" "B.Mask" "B.Paste")
			(net "GND")
		)
		(pad "251" smd rect
			(at -4.59994 95.199962 270)
			(size 1.8034 0.508)
			(layers "B.Cu" "B.Mask" "B.Paste")
			(net "M_A_DQ<45>")
		)
		(pad "252" smd rect
			(at -4.59994 96.0501 270)
			(size 1.8034 0.508)
			(layers "B.Cu" "B.Mask" "B.Paste")
			(net "GND")
		)
		(pad "253" smd rect
			(at -4.59994 96.899984 270)
			(size 1.8034 0.508)
			(layers "B.Cu" "B.Mask" "B.Paste")
			(net "M_A_DQ<41>")
		)
		(pad "254" smd rect
			(at -4.59994 97.750122 270)
			(size 1.8034 0.508)
			(layers "B.Cu" "B.Mask" "B.Paste")
			(net "GND")
		)
		(pad "255" smd rect
			(at -4.59994 98.600006 270)
			(size 1.8034 0.508)
			(layers "B.Cu" "B.Mask" "B.Paste")
			(net "M_A_DQS_DN<5>")
		)
		(pad "256" smd rect
			(at -4.59994 99.44989 270)
			(size 1.8034 0.508)
			(layers "B.Cu" "B.Mask" "B.Paste")
			(net "M_A_DQS_DP<5>")
		)
		(pad "257" smd rect
			(at -4.59994 100.300028 270)
			(size 1.8034 0.508)
			(layers "B.Cu" "B.Mask" "B.Paste")
			(net "GND")
		)
		(pad "258" smd rect
			(at -4.59994 101.149912 270)
			(size 1.8034 0.508)
			(layers "B.Cu" "B.Mask" "B.Paste")
			(net "M_A_DQ<47>")
		)
		(pad "259" smd rect
			(at -4.59994 102.00005 270)
			(size 1.8034 0.508)
			(layers "B.Cu" "B.Mask" "B.Paste")
			(net "GND")
		)
		(pad "260" smd rect
			(at -4.59994 102.849934 270)
			(size 1.8034 0.508)
			(layers "B.Cu" "B.Mask" "B.Paste")
			(net "M_A_DQ<43>")
		)
		(pad "261" smd rect
			(at -4.59994 103.700072 270)
			(size 1.8034 0.508)
			(layers "B.Cu" "B.Mask" "B.Paste")
			(net "GND")
		)
		(pad "262" smd rect
			(at -4.59994 104.549956 270)
			(size 1.8034 0.508)
			(layers "B.Cu" "B.Mask" "B.Paste")
			(net "M_A_DQ<53>")
		)
		(pad "263" smd rect
			(at -4.59994 105.400094 270)
			(size 1.8034 0.508)
			(layers "B.Cu" "B.Mask" "B.Paste")
			(net "GND")
		)
		(pad "264" smd rect
			(at -4.59994 106.249978 270)
			(size 1.8034 0.508)
			(layers "B.Cu" "B.Mask" "B.Paste")
			(net "M_A_DQ<49>")
		)
		(pad "265" smd rect
			(at -4.59994 107.100116 270)
			(size 1.8034 0.508)
			(layers "B.Cu" "B.Mask" "B.Paste")
			(net "GND")
		)
		(pad "266" smd rect
			(at -4.59994 107.95 270)
			(size 1.8034 0.508)
			(layers "B.Cu" "B.Mask" "B.Paste")
			(net "M_A_DQS_DN<6>")
		)
		(pad "267" smd rect
			(at -4.59994 108.799884 270)
			(size 1.8034 0.508)
			(layers "B.Cu" "B.Mask" "B.Paste")
			(net "M_A_DQS_DP<6>")
		)
		(pad "268" smd rect
			(at -4.59994 109.650022 270)
			(size 1.8034 0.508)
			(layers "B.Cu" "B.Mask" "B.Paste")
			(net "GND")
		)
		(pad "269" smd rect
			(at -4.59994 110.499906 270)
			(size 1.8034 0.508)
			(layers "B.Cu" "B.Mask" "B.Paste")
			(net "M_A_DQ<55>")
		)
		(pad "270" smd rect
			(at -4.59994 111.350044 270)
			(size 1.8034 0.508)
			(layers "B.Cu" "B.Mask" "B.Paste")
			(net "GND")
		)
		(pad "271" smd rect
			(at -4.59994 112.199928 270)
			(size 1.8034 0.508)
			(layers "B.Cu" "B.Mask" "B.Paste")
			(net "M_A_DQ<51>")
		)
		(pad "272" smd rect
			(at -4.59994 113.050066 270)
			(size 1.8034 0.508)
			(layers "B.Cu" "B.Mask" "B.Paste")
			(net "GND")
		)
		(pad "273" smd rect
			(at -4.59994 113.89995 270)
			(size 1.8034 0.508)
			(layers "B.Cu" "B.Mask" "B.Paste")
			(net "M_A_DQ<61>")
		)
		(pad "274" smd rect
			(at -4.59994 114.750088 270)
			(size 1.8034 0.508)
			(layers "B.Cu" "B.Mask" "B.Paste")
			(net "GND")
		)
		(pad "275" smd rect
			(at -4.59994 115.599972 270)
			(size 1.8034 0.508)
			(layers "B.Cu" "B.Mask" "B.Paste")
			(net "M_A_DQ<57>")
		)
		(pad "276" smd rect
			(at -4.59994 116.45011 270)
			(size 1.8034 0.508)
			(layers "B.Cu" "B.Mask" "B.Paste")
			(net "GND")
		)
		(pad "277" smd rect
			(at -4.59994 117.299994 270)
			(size 1.8034 0.508)
			(layers "B.Cu" "B.Mask" "B.Paste")
			(net "M_A_DQS_DN<7>")
		)
		(pad "278" smd rect
			(at -4.59994 118.149878 270)
			(size 1.8034 0.508)
			(layers "B.Cu" "B.Mask" "B.Paste")
			(net "M_A_DQS_DP<7>")
		)
		(pad "279" smd rect
			(at -4.59994 119.000016 270)
			(size 1.8034 0.508)
			(layers "B.Cu" "B.Mask" "B.Paste")
			(net "GND")
		)
		(pad "280" smd rect
			(at -4.59994 119.8499 270)
			(size 1.8034 0.508)
			(layers "B.Cu" "B.Mask" "B.Paste")
			(net "M_A_DQ<63>")
		)
		(pad "281" smd rect
			(at -4.59994 120.700038 270)
			(size 1.8034 0.508)
			(layers "B.Cu" "B.Mask" "B.Paste")
			(net "GND")
		)
		(pad "282" smd rect
			(at -4.59994 121.549922 270)
			(size 1.8034 0.508)
			(layers "B.Cu" "B.Mask" "B.Paste")
			(net "M_A_DQ<59>")
		)
		(pad "283" smd rect
			(at -4.59994 122.40006 270)
			(size 1.8034 0.508)
			(layers "B.Cu" "B.Mask" "B.Paste")
			(net "GND")
		)
		(pad "284" smd rect
			(at -4.59994 123.249944 270)
			(size 1.8034 0.508)
			(layers "B.Cu" "B.Mask" "B.Paste")
			(net "PVPP_ABC")
		)
		(pad "285" smd rect
			(at -4.59994 124.100082 270)
			(size 1.8034 0.508)
			(layers "B.Cu" "B.Mask" "B.Paste")
			(net "SMB_DDR_ABC_VPP_SDA")
		)
		(pad "286" smd rect
			(at -4.59994 124.949966 270)
			(size 1.8034 0.508)
			(layers "B.Cu" "B.Mask" "B.Paste")
			(net "PVPP_ABC")
		)
		(pad "287" smd rect
			(at -4.59994 125.800104 270)
			(size 1.8034 0.508)
			(layers "B.Cu" "B.Mask" "B.Paste")
			(net "PVPP_ABC")
		)
		(pad "288" smd rect
			(at -4.59994 126.649988 270)
			(size 1.8034 0.508)
			(layers "B.Cu" "B.Mask" "B.Paste")
			(net "PVPP_ABC")
		)
	)
	(footprint ""
		(layer "B.Cu")
		(at 374.4214 -59.9694)
		(property "Reference" "R3P45"
			(at 0 0 0)
			(layer "B.SilkS")
			(hide yes)
			(effects
				(font
					(size 1.27 1.27)
				)
				(justify mirror)
			)
		)
		(property "Value" "*"
			(at -0.064008 -4.108196 0)
			(unlocked yes)
			(layer "B.Fab")
			(hide yes)
			(effects
				(font
					(size 1.27 1.016)
					(thickness 0.1524)
				)
				(justify mirror)
			)
		)
		(property "Device Type" "374R2F-1-GP_SMD-RG-374R2F-1-GPA"
			(at -0.064008 -5.632196 0)
			(unlocked yes)
			(layer "B.Fab")
			(hide yes)
			(effects
				(font
					(size 1.27 1.016)
					(thickness 0.1524)
				)
				(justify mirror)
			)
		)
		(duplicate_pad_numbers_are_jumpers no)
		(fp_line
			(start -0.508 -0.9398)
			(end 0.508 -0.9398)
			(stroke
				(width 0.1524)
				(type default)
			)
			(layer "B.SilkS")
		)
		(fp_line
			(start 0.508 -0.9398)
			(end 0.508 0.9398)
			(stroke
				(width 0.1524)
				(type default)
			)
			(layer "B.SilkS")
		)
		(fp_rect
			(start 0.508 0.9398)
			(end -0.508 -0.9398)
			(stroke
				(width 0)
				(type default)
			)
			(fill no)
			(layer "B.CrtYd")
		)
		(fp_rect
			(start 0.508 0.9398)
			(end -0.508 -0.9398)
			(stroke
				(width 0)
				(type default)
			)
			(fill no)
			(layer "B.Fab")
		)
		(pad "1" smd custom
			(at 0 -0.4445 180)
			(size 0.1397 0.1397)
			(layers "B.Cu" "B.Mask" "B.Paste")
			(net "P3V3")
			(options
				(clearance outline)
				(anchor circle)
			)
			(primitives
				(gr_poly
					(pts
						(arc
							(start -0.1778 0.2794)
							(mid -0.249642 0.249642)
							(end -0.2794 0.1778)
						)
						(arc
							(start -0.2794 -0.1778)
							(mid -0.249642 -0.249642)
							(end -0.1778 -0.2794)
						)
						(arc
							(start 0.1778 -0.2794)
							(mid 0.249642 -0.249642)
							(end 0.2794 -0.1778)
						)
						(arc
							(start 0.2794 0.1778)
							(mid 0.249642 0.249642)
							(end 0.1778 0.2794)
						)
					)
					(width 0)
					(fill yes)
				)
			)
		)
		(pad "2" smd custom
			(at 0 0.4445 180)
			(size 0.1397 0.1397)
			(layers "B.Cu" "B.Mask" "B.Paste")
			(net "P0V7_GTL2104_VREF_1")
			(options
				(clearance outline)
				(anchor circle)
			)
			(primitives
				(gr_poly
					(pts
						(arc
							(start -0.1778 0.2794)
							(mid -0.249642 0.249642)
							(end -0.2794 0.1778)
						)
						(arc
							(start -0.2794 -0.1778)
							(mid -0.249642 -0.249642)
							(end -0.1778 -0.2794)
						)
						(arc
							(start 0.1778 -0.2794)
							(mid 0.249642 -0.249642)
							(end 0.2794 -0.1778)
						)
						(arc
							(start 0.2794 0.1778)
							(mid 0.249642 0.249642)
							(end 0.1778 0.2794)
						)
					)
					(width 0)
					(fill yes)
				)
			)
		)
	)
	(footprint ""
		(layer "B.Cu")
		(at 373.8372 -46.8376 -90)
		(property "Reference" "R2T73"
			(at 0 0 90)
			(layer "B.SilkS")
			(hide yes)
			(effects
				(font
					(size 1.27 1.27)
				)
				(justify mirror)
			)
		)
		(property "Value" ""
			(at 0 0 90)
			(layer "B.Fab")
			(effects
				(font
					(size 1.27 1.27)
				)
				(justify mirror)
			)
		)
		(duplicate_pad_numbers_are_jumpers no)
		(fp_poly
			(pts
				(xy 0.2794 -0.1016) (xy -0.2794 -0.1016) (xy -0.2794 0.9906) (xy 0.2794 0.9906)
			)
			(stroke
				(width 0)
				(type default)
			)
			(fill no)
			(layer "B.CrtYd")
		)
		(fp_line
			(start -0.2794 0.9906)
			(end -0.2794 -0.1016)
			(stroke
				(width 0.1)
				(type default)
			)
			(layer "B.Fab")
		)
		(fp_line
			(start 0.2794 0.9906)
			(end -0.2794 0.9906)
			(stroke
				(width 0.1)
				(type default)
			)
			(layer "B.Fab")
		)
		(fp_line
			(start -0.2794 -0.1016)
			(end 0.2794 -0.1016)
			(stroke
				(width 0.1)
				(type default)
			)
			(layer "B.Fab")
		)
		(fp_line
			(start 0.2794 -0.1016)
			(end 0.2794 0.9906)
			(stroke
				(width 0.1)
				(type default)
			)
			(layer "B.Fab")
		)
		(pad "1" smd rect
			(at 0 0 90)
			(size 0.508 0.508)
			(layers "B.Cu" "B.Mask" "B.Paste")
			(net "PVCCIO_CPU1")
		)
		(pad "2" smd rect
			(at 0 0.889 90)
			(size 0.508 0.508)
			(layers "B.Cu" "B.Mask" "B.Paste")
			(net "H_CPU1_PROCHOT_G_N")
		)
		(zone
			(layer "B.Cu")
			(hatch none 0.5)
			(connect_pads
				(clearance 0)
			)
			(min_thickness 0.25)
			(keepout
				(tracks not_allowed)
				(vias allowed)
				(pads allowed)
				(copperpour not_allowed)
				(footprints allowed)
			)
			(placement
				(enabled no)
				(sheetname "")
			)
			(fill
				(thermal_gap 0.5)
				(thermal_bridge_width 0.5)
				(island_removal_mode 0)
			)
			(polygon
				(pts
					(xy 373.2022 -46.5836) (xy 373.2022 -47.0916) (xy 373.5832 -47.0916) (xy 373.5832 -46.5836)
				)
			)
		)
		(zone
			(layer "B.Cu")
			(hatch none 0.5)
			(connect_pads
				(clearance 0)
			)
			(min_thickness 0.25)
			(keepout
				(tracks allowed)
				(vias not_allowed)
				(pads allowed)
				(copperpour not_allowed)
				(footprints allowed)
			)
			(placement
				(enabled no)
				(sheetname "")
			)
			(fill
				(thermal_gap 0.5)
				(thermal_bridge_width 0.5)
				(island_removal_mode 0)
			)
			(polygon
				(pts
					(xy 373.5832 -46.5836) (xy 373.5832 -47.0916) (xy 373.2022 -47.0916) (xy 373.2022 -46.5836)
				)
			)
		)
	)
	(footprint ""
		(layer "B.Cu")
		(at 365.506 -113.792 -90)
		(property "Reference" "C3M41"
			(at 0 0 90)
			(layer "B.SilkS")
			(hide yes)
			(effects
				(font
					(size 1.27 1.27)
				)
				(justify mirror)
			)
		)
		(property "Value" ""
			(at 0 0 90)
			(layer "B.Fab")
			(effects
				(font
					(size 1.27 1.27)
				)
				(justify mirror)
			)
		)
		(duplicate_pad_numbers_are_jumpers no)
		(fp_poly
			(pts
				(xy -0.3048 -0.1016) (xy -0.3048 0.9906) (xy 0.3048 0.9906) (xy 0.3048 -0.1016)
			)
			(stroke
				(width 0)
				(type default)
			)
			(fill no)
			(layer "B.CrtYd")
		)
		(fp_line
			(start -0.3048 0.9906)
			(end -0.3048 -0.1016)
			(stroke
				(width 0.1)
				(type default)
			)
			(layer "B.Fab")
		)
		(fp_line
			(start 0.3048 0.9906)
			(end -0.3048 0.9906)
			(stroke
				(width 0.1)
				(type default)
			)
			(layer "B.Fab")
		)
		(fp_line
			(start -0.3048 -0.1016)
			(end 0.3048 -0.1016)
			(stroke
				(width 0.1)
				(type default)
			)
			(layer "B.Fab")
		)
		(fp_line
			(start 0.3048 -0.1016)
			(end 0.3048 0.9906)
			(stroke
				(width 0.1)
				(type default)
			)
			(layer "B.Fab")
		)
		(pad "1" smd rect
			(at 0 0 90)
			(size 0.508 0.508)
			(layers "B.Cu" "B.Mask" "B.Paste")
			(net "DMI_CPU0_PCH_RX_DN<1>")
		)
		(pad "2" smd rect
			(at 0 0.889 90)
			(size 0.508 0.508)
			(layers "B.Cu" "B.Mask" "B.Paste")
			(net "DMI_CPU0_PCH_RX_C_DN<1>")
		)
		(zone
			(layer "B.Cu")
			(hatch none 0.5)
			(connect_pads
				(clearance 0)
			)
			(min_thickness 0.25)
			(keepout
				(tracks not_allowed)
				(vias allowed)
				(pads allowed)
				(copperpour not_allowed)
				(footprints allowed)
			)
			(placement
				(enabled no)
				(sheetname "")
			)
			(fill
				(thermal_gap 0.5)
				(thermal_bridge_width 0.5)
				(island_removal_mode 0)
			)
			(polygon
				(pts
					(xy 364.871 -113.538) (xy 364.871 -114.046) (xy 365.252 -114.046) (xy 365.252 -113.538)
				)
			)
		)
		(zone
			(layer "B.Cu")
			(hatch none 0.5)
			(connect_pads
				(clearance 0)
			)
			(min_thickness 0.25)
			(keepout
				(tracks allowed)
				(vias not_allowed)
				(pads allowed)
				(copperpour not_allowed)
				(footprints allowed)
			)
			(placement
				(enabled no)
				(sheetname "")
			)
			(fill
				(thermal_gap 0.5)
				(thermal_bridge_width 0.5)
				(island_removal_mode 0)
			)
			(polygon
				(pts
					(xy 365.252 -113.538) (xy 365.252 -114.046) (xy 364.871 -114.046) (xy 364.871 -113.538)
				)
			)
		)
	)
	(footprint ""
		(layer "B.Cu")
		(at 456.692 -116.49202)
		(property "Reference" "C1M12"
			(at 0 0 0)
			(layer "B.SilkS")
			(hide yes)
			(effects
				(font
					(size 1.27 1.27)
				)
				(justify mirror)
			)
		)
		(property "Value" ""
			(at 0 0 0)
			(layer "B.Fab")
			(effects
				(font
					(size 1.27 1.27)
				)
				(justify mirror)
			)
		)
		(duplicate_pad_numbers_are_jumpers no)
		(fp_rect
			(start -0.3048 0.9906)
			(end 0.3048 -0.1016)
			(stroke
				(width 0)
				(type default)
			)
			(fill no)
			(layer "B.CrtYd")
		)
		(fp_line
			(start -0.3048 -0.1016)
			(end 0.3048 -0.1016)
			(stroke
				(width 0.1)
				(type default)
			)
			(layer "B.Fab")
		)
		(fp_line
			(start -0.3048 0.9906)
			(end -0.3048 -0.1016)
			(stroke
				(width 0.1)
				(type default)
			)
			(layer "B.Fab")
		)
		(fp_line
			(start 0.3048 -0.1016)
			(end 0.3048 0.9906)
			(stroke
				(width 0.1)
				(type default)
			)
			(layer "B.Fab")
		)
		(fp_line
			(start 0.3048 0.9906)
			(end -0.3048 0.9906)
			(stroke
				(width 0.1)
				(type default)
			)
			(layer "B.Fab")
		)
		(pad "1" smd rect
			(at 0 0 180)
			(size 0.508 0.508)
			(layers "B.Cu" "B.Mask" "B.Paste")
			(net "P3E_CPU0_PE3_OCP_TXP<12>")
		)
		(pad "2" smd rect
			(at 0 0.889 180)
			(size 0.508 0.508)
			(layers "B.Cu" "B.Mask" "B.Paste")
			(net "P3E_OCP_CPU0_PE3_C_TXP<12>")
		)
		(zone
			(layer "B.Cu")
			(hatch none 0.5)
			(connect_pads
				(clearance 0)
			)
			(min_thickness 0.25)
			(keepout
				(tracks not_allowed)
				(vias allowed)
				(pads allowed)
				(copperpour not_allowed)
				(footprints allowed)
			)
			(placement
				(enabled no)
				(sheetname "")
			)
			(fill
				(thermal_gap 0.5)
				(thermal_bridge_width 0.5)
				(island_removal_mode 0)
			)
			(polygon
				(pts
					(xy 456.438 -115.85702) (xy 456.946 -115.85702) (xy 456.946 -116.23802) (xy 456.438 -116.23802)
				)
			)
		)
		(zone
			(layer "B.Cu")
			(hatch none 0.5)
			(connect_pads
				(clearance 0)
			)
			(min_thickness 0.25)
			(keepout
				(tracks allowed)
				(vias not_allowed)
				(pads allowed)
				(copperpour not_allowed)
				(footprints allowed)
			)
			(placement
				(enabled no)
				(sheetname "")
			)
			(fill
				(thermal_gap 0.5)
				(thermal_bridge_width 0.5)
				(island_removal_mode 0)
			)
			(polygon
				(pts
					(xy 456.438 -115.85702) (xy 456.946 -115.85702) (xy 456.946 -116.23802) (xy 456.438 -116.23802)
				)
			)
		)
	)
	(footprint ""
		(layer "B.Cu")
		(at 176.25568 -81.407 -90)
		(property "Reference" "R6P13"
			(at 0 0 90)
			(layer "B.SilkS")
			(hide yes)
			(effects
				(font
					(size 1.27 1.27)
				)
				(justify mirror)
			)
		)
		(property "Value" ""
			(at 0 0 90)
			(layer "B.Fab")
			(effects
				(font
					(size 1.27 1.27)
				)
				(justify mirror)
			)
		)
		(duplicate_pad_numbers_are_jumpers no)
		(fp_poly
			(pts
				(xy 0.2794 -0.1016) (xy -0.2794 -0.1016) (xy -0.2794 0.9906) (xy 0.2794 0.9906)
			)
			(stroke
				(width 0)
				(type default)
			)
			(fill no)
			(layer "B.CrtYd")
		)
		(fp_line
			(start -0.2794 0.9906)
			(end -0.2794 -0.1016)
			(stroke
				(width 0.1)
				(type default)
			)
			(layer "B.Fab")
		)
		(fp_line
			(start 0.2794 0.9906)
			(end -0.2794 0.9906)
			(stroke
				(width 0.1)
				(type default)
			)
			(layer "B.Fab")
		)
		(fp_line
			(start -0.2794 -0.1016)
			(end 0.2794 -0.1016)
			(stroke
				(width 0.1)
				(type default)
			)
			(layer "B.Fab")
		)
		(fp_line
			(start 0.2794 -0.1016)
			(end 0.2794 0.9906)
			(stroke
				(width 0.1)
				(type default)
			)
			(layer "B.Fab")
		)
		(pad "1" smd rect
			(at 0 0 90)
			(size 0.508 0.508)
			(layers "B.Cu" "B.Mask" "B.Paste")
			(net "CLK_100M_CPU0_BCLK2_DP")
		)
		(pad "2" smd rect
			(at 0 0.889 90)
			(size 0.508 0.508)
			(layers "B.Cu" "B.Mask" "B.Paste")
			(net "GND")
		)
		(zone
			(layer "B.Cu")
			(hatch none 0.5)
			(connect_pads
				(clearance 0)
			)
			(min_thickness 0.25)
			(keepout
				(tracks not_allowed)
				(vias allowed)
				(pads allowed)
				(copperpour not_allowed)
				(footprints allowed)
			)
			(placement
				(enabled no)
				(sheetname "")
			)
			(fill
				(thermal_gap 0.5)
				(thermal_bridge_width 0.5)
				(island_removal_mode 0)
			)
			(polygon
				(pts
					(xy 175.62068 -81.153) (xy 175.62068 -81.661) (xy 176.00168 -81.661) (xy 176.00168 -81.153)
				)
			)
		)
		(zone
			(layer "B.Cu")
			(hatch none 0.5)
			(connect_pads
				(clearance 0)
			)
			(min_thickness 0.25)
			(keepout
				(tracks allowed)
				(vias not_allowed)
				(pads allowed)
				(copperpour not_allowed)
				(footprints allowed)
			)
			(placement
				(enabled no)
				(sheetname "")
			)
			(fill
				(thermal_gap 0.5)
				(thermal_bridge_width 0.5)
				(island_removal_mode 0)
			)
			(polygon
				(pts
					(xy 176.00168 -81.153) (xy 176.00168 -81.661) (xy 175.62068 -81.661) (xy 175.62068 -81.153)
				)
			)
		)
	)
	(footprint ""
		(layer "B.Cu")
		(at 184.658 -153.416)
		(property "Reference" "R6L4"
			(at 0 0 0)
			(layer "B.SilkS")
			(hide yes)
			(effects
				(font
					(size 1.27 1.27)
				)
				(justify mirror)
			)
		)
		(property "Value" ""
			(at 0 0 0)
			(layer "B.Fab")
			(effects
				(font
					(size 1.27 1.27)
				)
				(justify mirror)
			)
		)
		(duplicate_pad_numbers_are_jumpers no)
		(fp_rect
			(start 0.2794 -0.1016)
			(end -0.2794 0.9906)
			(stroke
				(width 0)
				(type default)
			)
			(fill no)
			(layer "B.CrtYd")
		)
		(fp_line
			(start -0.2794 -0.1016)
			(end 0.2794 -0.1016)
			(stroke
				(width 0.1)
				(type default)
			)
			(layer "B.Fab")
		)
		(fp_line
			(start -0.2794 0.9906)
			(end -0.2794 -0.1016)
			(stroke
				(width 0.1)
				(type default)
			)
			(layer "B.Fab")
		)
		(fp_line
			(start 0.2794 -0.1016)
			(end 0.2794 0.9906)
			(stroke
				(width 0.1)
				(type default)
			)
			(layer "B.Fab")
		)
		(fp_line
			(start 0.2794 0.9906)
			(end -0.2794 0.9906)
			(stroke
				(width 0.1)
				(type default)
			)
			(layer "B.Fab")
		)
		(pad "1" smd rect
			(at 0 0 180)
			(size 0.508 0.508)
			(layers "B.Cu" "B.Mask" "B.Paste")
			(net "P3V3")
		)
		(pad "2" smd rect
			(at 0 0.889 180)
			(size 0.508 0.508)
			(layers "B.Cu" "B.Mask" "B.Paste")
			(net "FM_PVTT_DEF_EN_R")
		)
		(zone
			(layer "B.Cu")
			(hatch none 0.5)
			(connect_pads
				(clearance 0)
			)
			(min_thickness 0.25)
			(keepout
				(tracks allowed)
				(vias not_allowed)
				(pads allowed)
				(copperpour not_allowed)
				(footprints allowed)
			)
			(placement
				(enabled no)
				(sheetname "")
			)
			(fill
				(thermal_gap 0.5)
				(thermal_bridge_width 0.5)
				(island_removal_mode 0)
			)
			(polygon
				(pts
					(xy 184.912 -153.162) (xy 184.404 -153.162) (xy 184.404 -152.781) (xy 184.912 -152.781)
				)
			)
		)
		(zone
			(layer "B.Cu")
			(hatch none 0.5)
			(connect_pads
				(clearance 0)
			)
			(min_thickness 0.25)
			(keepout
				(tracks not_allowed)
				(vias allowed)
				(pads allowed)
				(copperpour not_allowed)
				(footprints allowed)
			)
			(placement
				(enabled no)
				(sheetname "")
			)
			(fill
				(thermal_gap 0.5)
				(thermal_bridge_width 0.5)
				(island_removal_mode 0)
			)
			(polygon
				(pts
					(xy 184.912 -153.162) (xy 184.404 -153.162) (xy 184.404 -152.781) (xy 184.912 -152.781)
				)
			)
		)
	)
	(footprint ""
		(layer "B.Cu")
		(at 371.983 -6.1595)
		(property "Reference" "R7G26"
			(at 0 0 0)
			(layer "B.SilkS")
			(hide yes)
			(effects
				(font
					(size 1.27 1.27)
				)
				(justify mirror)
			)
		)
		(property "Value" ""
			(at 0 0 0)
			(layer "B.Fab")
			(effects
				(font
					(size 1.27 1.27)
				)
				(justify mirror)
			)
		)
		(duplicate_pad_numbers_are_jumpers no)
		(fp_poly
			(pts
				(xy 0.2794 -0.1016) (xy -0.2794 -0.1016) (xy -0.2794 0.9906) (xy 0.2794 0.9906)
			)
			(stroke
				(width 0)
				(type default)
			)
			(fill no)
			(layer "B.CrtYd")
		)
		(fp_line
			(start -0.2794 -0.1016)
			(end 0.2794 -0.1016)
			(stroke
				(width 0.1)
				(type default)
			)
			(layer "B.Fab")
		)
		(fp_line
			(start -0.2794 0.9906)
			(end -0.2794 -0.1016)
			(stroke
				(width 0.1)
				(type default)
			)
			(layer "B.Fab")
		)
		(fp_line
			(start 0.2794 -0.1016)
			(end 0.2794 0.9906)
			(stroke
				(width 0.1)
				(type default)
			)
			(layer "B.Fab")
		)
		(fp_line
			(start 0.2794 0.9906)
			(end -0.2794 0.9906)
			(stroke
				(width 0.1)
				(type default)
			)
			(layer "B.Fab")
		)
		(pad "1" smd rect
			(at 0 0 180)
			(size 0.508 0.508)
			(layers "B.Cu" "B.Mask" "B.Paste")
			(net "P3V3_STBY")
		)
		(pad "2" smd rect
			(at 0 0.889 180)
			(size 0.508 0.508)
			(layers "B.Cu" "B.Mask" "B.Paste")
			(net "FM_ME_RECOVER_N")
		)
		(zone
			(layer "B.Cu")
			(hatch none 0.5)
			(connect_pads
				(clearance 0)
			)
			(min_thickness 0.25)
			(keepout
				(tracks allowed)
				(vias not_allowed)
				(pads allowed)
				(copperpour not_allowed)
				(footprints allowed)
			)
			(placement
				(enabled no)
				(sheetname "")
			)
			(fill
				(thermal_gap 0.5)
				(thermal_bridge_width 0.5)
				(island_removal_mode 0)
			)
			(polygon
				(pts
					(xy 372.237 -5.9055) (xy 371.729 -5.9055) (xy 371.729 -5.5245) (xy 372.237 -5.5245)
				)
			)
		)
		(zone
			(layer "B.Cu")
			(hatch none 0.5)
			(connect_pads
				(clearance 0)
			)
			(min_thickness 0.25)
			(keepout
				(tracks not_allowed)
				(vias allowed)
				(pads allowed)
				(copperpour not_allowed)
				(footprints allowed)
			)
			(placement
				(enabled no)
				(sheetname "")
			)
			(fill
				(thermal_gap 0.5)
				(thermal_bridge_width 0.5)
				(island_removal_mode 0)
			)
			(polygon
				(pts
					(xy 372.237 -5.5245) (xy 371.729 -5.5245) (xy 371.729 -5.9055) (xy 372.237 -5.9055)
				)
			)
		)
	)
	(footprint ""
		(layer "B.Cu")
		(at 393.286234 -151.84374 90)
		(property "Reference" "C2L11"
			(at 0 0 90)
			(layer "B.SilkS")
			(hide yes)
			(effects
				(font
					(size 1.27 1.27)
				)
				(justify mirror)
			)
		)
		(property "Value" ""
			(at 0 0 90)
			(layer "B.Fab")
			(effects
				(font
					(size 1.27 1.27)
				)
				(justify mirror)
			)
		)
		(duplicate_pad_numbers_are_jumpers no)
		(fp_poly
			(pts
				(xy -0.3048 -0.1016) (xy -0.3048 0.9906) (xy 0.3048 0.9906) (xy 0.3048 -0.1016)
			)
			(stroke
				(width 0)
				(type default)
			)
			(fill no)
			(layer "B.CrtYd")
		)
		(fp_line
			(start 0.3048 -0.1016)
			(end 0.3048 0.9906)
			(stroke
				(width 0.1)
				(type default)
			)
			(layer "B.Fab")
		)
		(fp_line
			(start -0.3048 -0.1016)
			(end 0.3048 -0.1016)
			(stroke
				(width 0.1)
				(type default)
			)
			(layer "B.Fab")
		)
		(fp_line
			(start 0.3048 0.9906)
			(end -0.3048 0.9906)
			(stroke
				(width 0.1)
				(type default)
			)
			(layer "B.Fab")
		)
		(fp_line
			(start -0.3048 0.9906)
			(end -0.3048 -0.1016)
			(stroke
				(width 0.1)
				(type default)
			)
			(layer "B.Fab")
		)
		(pad "1" smd rect
			(at 0 0 270)
			(size 0.508 0.508)
			(layers "B.Cu" "B.Mask" "B.Paste")
			(net "VR_PVNN_PCH_VDD")
		)
		(pad "2" smd rect
			(at 0 0.889 270)
			(size 0.508 0.508)
			(layers "B.Cu" "B.Mask" "B.Paste")
			(net "GND")
		)
		(zone
			(layer "B.Cu")
			(hatch none 0.5)
			(connect_pads
				(clearance 0)
			)
			(min_thickness 0.25)
			(keepout
				(tracks allowed)
				(vias not_allowed)
				(pads allowed)
				(copperpour not_allowed)
				(footprints allowed)
			)
			(placement
				(enabled no)
				(sheetname "")
			)
			(fill
				(thermal_gap 0.5)
				(thermal_bridge_width 0.5)
				(island_removal_mode 0)
			)
			(polygon
				(pts
					(xy 393.540234 -152.09774) (xy 393.540234 -151.58974) (xy 393.921234 -151.58974) (xy 393.921234 -152.09774)
				)
			)
		)
		(zone
			(layer "B.Cu")
			(hatch none 0.5)
			(connect_pads
				(clearance 0)
			)
			(min_thickness 0.25)
			(keepout
				(tracks not_allowed)
				(vias allowed)
				(pads allowed)
				(copperpour not_allowed)
				(footprints allowed)
			)
			(placement
				(enabled no)
				(sheetname "")
			)
			(fill
				(thermal_gap 0.5)
				(thermal_bridge_width 0.5)
				(island_removal_mode 0)
			)
			(polygon
				(pts
					(xy 393.921234 -152.09774) (xy 393.921234 -151.58974) (xy 393.540234 -151.58974) (xy 393.540234 -152.09774)
				)
			)
		)
	)
	(footprint ""
		(layer "B.Cu")
		(at 378.0028 -137.8458 -90)
		(property "Reference" "C3M17"
			(at 0 0 90)
			(layer "B.SilkS")
			(hide yes)
			(effects
				(font
					(size 1.27 1.27)
				)
				(justify mirror)
			)
		)
		(property "Value" ""
			(at 0 0 90)
			(layer "B.Fab")
			(effects
				(font
					(size 1.27 1.27)
				)
				(justify mirror)
			)
		)
		(duplicate_pad_numbers_are_jumpers no)
		(fp_poly
			(pts
				(xy 0.4953 -0.2032) (xy -0.4953 -0.2032) (xy -0.4953 1.6002) (xy 0.4953 1.6002)
			)
			(stroke
				(width 0)
				(type default)
			)
			(fill no)
			(layer "B.CrtYd")
		)
		(fp_line
			(start -0.4953 1.6002)
			(end 0.4953 1.6002)
			(stroke
				(width 0.1)
				(type default)
			)
			(layer "B.Fab")
		)
		(fp_line
			(start 0.4953 1.6002)
			(end 0.4953 -0.2032)
			(stroke
				(width 0.1)
				(type default)
			)
			(layer "B.Fab")
		)
		(fp_line
			(start -0.4953 -0.2032)
			(end -0.4953 1.6002)
			(stroke
				(width 0.1)
				(type default)
			)
			(layer "B.Fab")
		)
		(fp_line
			(start 0.4953 -0.2032)
			(end -0.4953 -0.2032)
			(stroke
				(width 0.1)
				(type default)
			)
			(layer "B.Fab")
		)
		(pad "1" smd rect
			(at 0 0 90)
			(size 0.762 0.889)
			(layers "B.Cu" "B.Mask" "B.Paste")
			(net "P1V05_PCH_STBY_VCCA_PLL1")
		)
		(pad "2" smd rect
			(at 0 1.397 90)
			(size 0.762 0.889)
			(layers "B.Cu" "B.Mask" "B.Paste")
			(net "GND")
		)
		(zone
			(layer "B.Cu")
			(hatch none 0.5)
			(connect_pads
				(clearance 0)
			)
			(min_thickness 0.25)
			(keepout
				(tracks not_allowed)
				(vias allowed)
				(pads allowed)
				(copperpour not_allowed)
				(footprints allowed)
			)
			(placement
				(enabled no)
				(sheetname "")
			)
			(fill
				(thermal_gap 0.5)
				(thermal_bridge_width 0.5)
				(island_removal_mode 0)
			)
			(polygon
				(pts
					(xy 377.5583 -137.4648) (xy 377.5583 -138.2268) (xy 377.0503 -138.2268) (xy 377.0503 -137.4648)
				)
			)
		)
	)
	(footprint ""
		(layer "B.Cu")
		(at 375.0564 -131.9784 180)
		(property "Reference" "C3M29"
			(at 0 0 0)
			(layer "B.SilkS")
			(hide yes)
			(effects
				(font
					(size 1.27 1.27)
				)
				(justify mirror)
			)
		)
		(property "Value" ""
			(at 0 0 0)
			(layer "B.Fab")
			(effects
				(font
					(size 1.27 1.27)
				)
				(justify mirror)
			)
		)
		(duplicate_pad_numbers_are_jumpers no)
		(fp_poly
			(pts
				(xy -0.3048 -0.1016) (xy -0.3048 0.9906) (xy 0.3048 0.9906) (xy 0.3048 -0.1016)
			)
			(stroke
				(width 0)
				(type default)
			)
			(fill no)
			(layer "B.CrtYd")
		)
		(fp_line
			(start 0.3048 0.9906)
			(end -0.3048 0.9906)
			(stroke
				(width 0.1)
				(type default)
			)
			(layer "B.Fab")
		)
		(fp_line
			(start 0.3048 -0.1016)
			(end 0.3048 0.9906)
			(stroke
				(width 0.1)
				(type default)
			)
			(layer "B.Fab")
		)
		(fp_line
			(start -0.3048 0.9906)
			(end -0.3048 -0.1016)
			(stroke
				(width 0.1)
				(type default)
			)
			(layer "B.Fab")
		)
		(fp_line
			(start -0.3048 -0.1016)
			(end 0.3048 -0.1016)
			(stroke
				(width 0.1)
				(type default)
			)
			(layer "B.Fab")
		)
		(pad "1" smd rect
			(at 0 0)
			(size 0.508 0.508)
			(layers "B.Cu" "B.Mask" "B.Paste")
			(net "P1V05_PCH_STBY_ISCLK_PLL")
		)
		(pad "2" smd rect
			(at 0 0.889)
			(size 0.508 0.508)
			(layers "B.Cu" "B.Mask" "B.Paste")
			(net "GND")
		)
		(zone
			(layer "B.Cu")
			(hatch none 0.5)
			(connect_pads
				(clearance 0)
			)
			(min_thickness 0.25)
			(keepout
				(tracks not_allowed)
				(vias allowed)
				(pads allowed)
				(copperpour not_allowed)
				(footprints allowed)
			)
			(placement
				(enabled no)
				(sheetname "")
			)
			(fill
				(thermal_gap 0.5)
				(thermal_bridge_width 0.5)
				(island_removal_mode 0)
			)
			(polygon
				(pts
					(xy 374.8024 -132.6134) (xy 375.3104 -132.6134) (xy 375.3104 -132.2324) (xy 374.8024 -132.2324)
				)
			)
		)
		(zone
			(layer "B.Cu")
			(hatch none 0.5)
			(connect_pads
				(clearance 0)
			)
			(min_thickness 0.25)
			(keepout
				(tracks allowed)
				(vias not_allowed)
				(pads allowed)
				(copperpour not_allowed)
				(footprints allowed)
			)
			(placement
				(enabled no)
				(sheetname "")
			)
			(fill
				(thermal_gap 0.5)
				(thermal_bridge_width 0.5)
				(island_removal_mode 0)
			)
			(polygon
				(pts
					(xy 374.8024 -132.2324) (xy 375.3104 -132.2324) (xy 375.3104 -132.6134) (xy 374.8024 -132.6134)
				)
			)
		)
	)
	(footprint ""
		(layer "B.Cu")
		(at 405.44496 -50.9397 90)
		(property "Reference" "R25W144"
			(at 0.8382 -0.67818 90)
			(unlocked yes)
			(layer "B.SilkS")
			(effects
				(font
					(size 0.4064 0.254)
					(thickness 0.1524)
				)
				(justify left mirror)
			)
		)
		(property "Value" ""
			(at 0 0 90)
			(layer "B.Fab")
			(effects
				(font
					(size 1.27 1.27)
				)
				(justify mirror)
			)
		)
		(duplicate_pad_numbers_are_jumpers no)
		(fp_poly
			(pts
				(xy 0.2794 -0.1016) (xy -0.2794 -0.1016) (xy -0.2794 0.9906) (xy 0.2794 0.9906)
			)
			(stroke
				(width 0)
				(type default)
			)
			(fill no)
			(layer "B.CrtYd")
		)
		(fp_line
			(start 0.2794 -0.1016)
			(end 0.2794 0.9906)
			(stroke
				(width 0.1)
				(type default)
			)
			(layer "B.Fab")
		)
		(fp_line
			(start -0.2794 -0.1016)
			(end 0.2794 -0.1016)
			(stroke
				(width 0.1)
				(type default)
			)
			(layer "B.Fab")
		)
		(fp_line
			(start 0.2794 0.9906)
			(end -0.2794 0.9906)
			(stroke
				(width 0.1)
				(type default)
			)
			(layer "B.Fab")
		)
		(fp_line
			(start -0.2794 0.9906)
			(end -0.2794 -0.1016)
			(stroke
				(width 0.1)
				(type default)
			)
			(layer "B.Fab")
		)
		(pad "1" smd rect
			(at 0 0 270)
			(size 0.508 0.508)
			(layers "B.Cu" "B.Mask" "B.Paste")
			(net "FM_PWR_BTN_R1_N")
		)
		(pad "2" smd rect
			(at 0 0.889 270)
			(size 0.508 0.508)
			(layers "B.Cu" "B.Mask" "B.Paste")
			(net "FM_PWR_BTN_N")
		)
		(zone
			(layer "B.Cu")
			(hatch none 0.5)
			(connect_pads
				(clearance 0)
			)
			(min_thickness 0.25)
			(keepout
				(tracks allowed)
				(vias not_allowed)
				(pads allowed)
				(copperpour not_allowed)
				(footprints allowed)
			)
			(placement
				(enabled no)
				(sheetname "")
			)
			(fill
				(thermal_gap 0.5)
				(thermal_bridge_width 0.5)
				(island_removal_mode 0)
			)
			(polygon
				(pts
					(xy 405.69896 -51.1937) (xy 405.69896 -50.6857) (xy 406.07996 -50.6857) (xy 406.07996 -51.1937)
				)
			)
		)
		(zone
			(layer "B.Cu")
			(hatch none 0.5)
			(connect_pads
				(clearance 0)
			)
			(min_thickness 0.25)
			(keepout
				(tracks not_allowed)
				(vias allowed)
				(pads allowed)
				(copperpour not_allowed)
				(footprints allowed)
			)
			(placement
				(enabled no)
				(sheetname "")
			)
			(fill
				(thermal_gap 0.5)
				(thermal_bridge_width 0.5)
				(island_removal_mode 0)
			)
			(polygon
				(pts
					(xy 406.07996 -51.1937) (xy 406.07996 -50.6857) (xy 405.69896 -50.6857) (xy 405.69896 -51.1937)
				)
			)
		)
	)
	(footprint ""
		(layer "B.Cu")
		(at 442.9506 -22.3393 90)
		(property "Reference" "R3W4"
			(at 0 0 90)
			(layer "B.SilkS")
			(hide yes)
			(effects
				(font
					(size 1.27 1.27)
				)
				(justify mirror)
			)
		)
		(property "Value" "*"
			(at -0.064008 -4.108196 90)
			(unlocked yes)
			(layer "B.Fab")
			(hide yes)
			(effects
				(font
					(size 1.27 1.016)
					(thickness 0.1524)
				)
				(justify mirror)
			)
		)
		(property "Device Type" "47KR2F-GP_RCL_GP-47KR2F-GP,64.A"
			(at -0.064008 -5.632196 90)
			(unlocked yes)
			(layer "B.Fab")
			(hide yes)
			(effects
				(font
					(size 1.27 1.016)
					(thickness 0.1524)
				)
				(justify mirror)
			)
		)
		(duplicate_pad_numbers_are_jumpers no)
		(fp_line
			(start 0.508 -0.9398)
			(end 0.508 0.9398)
			(stroke
				(width 0.1524)
				(type default)
			)
			(layer "B.SilkS")
		)
		(fp_line
			(start -0.508 -0.9398)
			(end 0.508 -0.9398)
			(stroke
				(width 0.1524)
				(type default)
			)
			(layer "B.SilkS")
		)
		(fp_rect
			(start 0.508 0.9398)
			(end -0.508 -0.9398)
			(stroke
				(width 0)
				(type default)
			)
			(fill no)
			(layer "B.CrtYd")
		)
		(fp_rect
			(start 0.508 0.9398)
			(end -0.508 -0.9398)
			(stroke
				(width 0)
				(type default)
			)
			(fill no)
			(layer "B.Fab")
		)
		(pad "1" smd custom
			(at 0 -0.4445 270)
			(size 0.1397 0.1397)
			(layers "B.Cu" "B.Mask" "B.Paste")
			(net "FM_TPM_PRES_RST_N")
			(options
				(clearance outline)
				(anchor circle)
			)
			(primitives
				(gr_poly
					(pts
						(arc
							(start -0.1778 0.2794)
							(mid -0.249642 0.249642)
							(end -0.2794 0.1778)
						)
						(arc
							(start -0.2794 -0.1778)
							(mid -0.249642 -0.249642)
							(end -0.1778 -0.2794)
						)
						(arc
							(start 0.1778 -0.2794)
							(mid 0.249642 -0.249642)
							(end 0.2794 -0.1778)
						)
						(arc
							(start 0.2794 0.1778)
							(mid 0.249642 0.249642)
							(end 0.1778 0.2794)
						)
					)
					(width 0)
					(fill yes)
				)
			)
		)
		(pad "2" smd custom
			(at 0 0.4445 270)
			(size 0.1397 0.1397)
			(layers "B.Cu" "B.Mask" "B.Paste")
			(net "FM_TPM_PRES_RST_N_R")
			(options
				(clearance outline)
				(anchor circle)
			)
			(primitives
				(gr_poly
					(pts
						(arc
							(start -0.1778 0.2794)
							(mid -0.249642 0.249642)
							(end -0.2794 0.1778)
						)
						(arc
							(start -0.2794 -0.1778)
							(mid -0.249642 -0.249642)
							(end -0.1778 -0.2794)
						)
						(arc
							(start 0.1778 -0.2794)
							(mid 0.249642 -0.249642)
							(end 0.2794 -0.1778)
						)
						(arc
							(start 0.2794 0.1778)
							(mid 0.249642 0.249642)
							(end 0.1778 0.2794)
						)
					)
					(width 0)
					(fill yes)
				)
			)
		)
	)
	(footprint ""
		(layer "B.Cu")
		(at 401.701 -34.798 90)
		(property "Reference" "R25W106"
			(at 0.8382 -0.67818 90)
			(unlocked yes)
			(layer "B.SilkS")
			(effects
				(font
					(size 0.4064 0.254)
					(thickness 0.1524)
				)
				(justify left mirror)
			)
		)
		(property "Value" ""
			(at 0 0 90)
			(layer "B.Fab")
			(effects
				(font
					(size 1.27 1.27)
				)
				(justify mirror)
			)
		)
		(duplicate_pad_numbers_are_jumpers no)
		(fp_poly
			(pts
				(xy 0.2794 -0.1016) (xy -0.2794 -0.1016) (xy -0.2794 0.9906) (xy 0.2794 0.9906)
			)
			(stroke
				(width 0)
				(type default)
			)
			(fill no)
			(layer "B.CrtYd")
		)
		(fp_line
			(start 0.2794 -0.1016)
			(end 0.2794 0.9906)
			(stroke
				(width 0.1)
				(type default)
			)
			(layer "B.Fab")
		)
		(fp_line
			(start -0.2794 -0.1016)
			(end 0.2794 -0.1016)
			(stroke
				(width 0.1)
				(type default)
			)
			(layer "B.Fab")
		)
		(fp_line
			(start 0.2794 0.9906)
			(end -0.2794 0.9906)
			(stroke
				(width 0.1)
				(type default)
			)
			(layer "B.Fab")
		)
		(fp_line
			(start -0.2794 0.9906)
			(end -0.2794 -0.1016)
			(stroke
				(width 0.1)
				(type default)
			)
			(layer "B.Fab")
		)
		(pad "1" smd rect
			(at 0 0 270)
			(size 0.508 0.508)
			(layers "B.Cu" "B.Mask" "B.Paste")
			(net "P3V3_STBY")
		)
		(pad "2" smd rect
			(at 0 0.889 270)
			(size 0.508 0.508)
			(layers "B.Cu" "B.Mask" "B.Paste")
			(net "RMII_BMC_OCP_TXEN")
		)
		(zone
			(layer "B.Cu")
			(hatch none 0.5)
			(connect_pads
				(clearance 0)
			)
			(min_thickness 0.25)
			(keepout
				(tracks allowed)
				(vias not_allowed)
				(pads allowed)
				(copperpour not_allowed)
				(footprints allowed)
			)
			(placement
				(enabled no)
				(sheetname "")
			)
			(fill
				(thermal_gap 0.5)
				(thermal_bridge_width 0.5)
				(island_removal_mode 0)
			)
			(polygon
				(pts
					(xy 401.955 -35.052) (xy 401.955 -34.544) (xy 402.336 -34.544) (xy 402.336 -35.052)
				)
			)
		)
		(zone
			(layer "B.Cu")
			(hatch none 0.5)
			(connect_pads
				(clearance 0)
			)
			(min_thickness 0.25)
			(keepout
				(tracks not_allowed)
				(vias allowed)
				(pads allowed)
				(copperpour not_allowed)
				(footprints allowed)
			)
			(placement
				(enabled no)
				(sheetname "")
			)
			(fill
				(thermal_gap 0.5)
				(thermal_bridge_width 0.5)
				(island_removal_mode 0)
			)
			(polygon
				(pts
					(xy 402.336 -35.052) (xy 402.336 -34.544) (xy 401.955 -34.544) (xy 401.955 -35.052)
				)
			)
		)
	)
	(footprint ""
		(layer "B.Cu")
		(at 278.576024 -69.809614 -90)
		(property "Reference" "C4P10"
			(at 0 0 90)
			(layer "B.SilkS")
			(hide yes)
			(effects
				(font
					(size 1.27 1.27)
				)
				(justify mirror)
			)
		)
		(property "Value" ""
			(at 0 0 90)
			(layer "B.Fab")
			(effects
				(font
					(size 1.27 1.27)
				)
				(justify mirror)
			)
		)
		(duplicate_pad_numbers_are_jumpers no)
		(fp_poly
			(pts
				(xy 0.7239 -0.2159) (xy -0.7239 -0.2159) (xy -0.7239 1.9939) (xy 0.7239 1.9939)
			)
			(stroke
				(width 0)
				(type default)
			)
			(fill no)
			(layer "B.CrtYd")
		)
		(fp_line
			(start -0.7239 1.9939)
			(end -0.7239 -0.2159)
			(stroke
				(width 0.1)
				(type default)
			)
			(layer "B.Fab")
		)
		(fp_line
			(start 0.7239 1.9939)
			(end -0.7239 1.9939)
			(stroke
				(width 0.1)
				(type default)
			)
			(layer "B.Fab")
		)
		(fp_line
			(start -0.7239 -0.2159)
			(end 0.7239 -0.2159)
			(stroke
				(width 0.1)
				(type default)
			)
			(layer "B.Fab")
		)
		(fp_line
			(start 0.7239 -0.2159)
			(end 0.7239 1.9939)
			(stroke
				(width 0.1)
				(type default)
			)
			(layer "B.Fab")
		)
		(pad "1" smd rect
			(at 0 0 90)
			(size 1.27 1.016)
			(layers "B.Cu" "B.Mask" "B.Paste")
			(net "PVCCIO_CPU0")
		)
		(pad "2" smd rect
			(at 0 1.778 90)
			(size 1.27 1.016)
			(layers "B.Cu" "B.Mask" "B.Paste")
			(net "GND")
		)
		(zone
			(layer "B.Cu")
			(hatch none 0.5)
			(connect_pads
				(clearance 0)
			)
			(min_thickness 0.25)
			(keepout
				(tracks not_allowed)
				(vias allowed)
				(pads allowed)
				(copperpour not_allowed)
				(footprints allowed)
			)
			(placement
				(enabled no)
				(sheetname "")
			)
			(fill
				(thermal_gap 0.5)
				(thermal_bridge_width 0.5)
				(island_removal_mode 0)
			)
			(polygon
				(pts
					(xy 278.068024 -69.174614) (xy 278.068024 -70.444614) (xy 277.306024 -70.444614) (xy 277.306024 -69.174614)
				)
			)
		)
	)
	(footprint ""
		(layer "B.Cu")
		(at 411.503368 -39.63797 -90)
		(property "Reference" "C25W42"
			(at 0.8382 -0.67818 270)
			(unlocked yes)
			(layer "B.SilkS")
			(effects
				(font
					(size 0.4064 0.254)
					(thickness 0.1524)
				)
				(justify left mirror)
			)
		)
		(property "Value" ""
			(at 0 0 90)
			(layer "B.Fab")
			(effects
				(font
					(size 1.27 1.27)
				)
				(justify mirror)
			)
		)
		(duplicate_pad_numbers_are_jumpers no)
		(fp_poly
			(pts
				(xy -0.3048 -0.1016) (xy -0.3048 0.9906) (xy 0.3048 0.9906) (xy 0.3048 -0.1016)
			)
			(stroke
				(width 0)
				(type default)
			)
			(fill no)
			(layer "B.CrtYd")
		)
		(fp_line
			(start -0.3048 0.9906)
			(end -0.3048 -0.1016)
			(stroke
				(width 0.1)
				(type default)
			)
			(layer "B.Fab")
		)
		(fp_line
			(start 0.3048 0.9906)
			(end -0.3048 0.9906)
			(stroke
				(width 0.1)
				(type default)
			)
			(layer "B.Fab")
		)
		(fp_line
			(start -0.3048 -0.1016)
			(end 0.3048 -0.1016)
			(stroke
				(width 0.1)
				(type default)
			)
			(layer "B.Fab")
		)
		(fp_line
			(start 0.3048 -0.1016)
			(end 0.3048 0.9906)
			(stroke
				(width 0.1)
				(type default)
			)
			(layer "B.Fab")
		)
		(pad "1" smd rect
			(at 0 0 90)
			(size 0.508 0.508)
			(layers "B.Cu" "B.Mask" "B.Paste")
			(net "VCC_D_3V3")
		)
		(pad "2" smd rect
			(at 0 0.889 90)
			(size 0.508 0.508)
			(layers "B.Cu" "B.Mask" "B.Paste")
			(net "GND")
		)
		(zone
			(layer "B.Cu")
			(hatch none 0.5)
			(connect_pads
				(clearance 0)
			)
			(min_thickness 0.25)
			(keepout
				(tracks not_allowed)
				(vias allowed)
				(pads allowed)
				(copperpour not_allowed)
				(footprints allowed)
			)
			(placement
				(enabled no)
				(sheetname "")
			)
			(fill
				(thermal_gap 0.5)
				(thermal_bridge_width 0.5)
				(island_removal_mode 0)
			)
			(polygon
				(pts
					(xy 410.868368 -39.38397) (xy 410.868368 -39.89197) (xy 411.249368 -39.89197) (xy 411.249368 -39.38397)
				)
			)
		)
		(zone
			(layer "B.Cu")
			(hatch none 0.5)
			(connect_pads
				(clearance 0)
			)
			(min_thickness 0.25)
			(keepout
				(tracks allowed)
				(vias not_allowed)
				(pads allowed)
				(copperpour not_allowed)
				(footprints allowed)
			)
			(placement
				(enabled no)
				(sheetname "")
			)
			(fill
				(thermal_gap 0.5)
				(thermal_bridge_width 0.5)
				(island_removal_mode 0)
			)
			(polygon
				(pts
					(xy 411.249368 -39.38397) (xy 411.249368 -39.89197) (xy 410.868368 -39.89197) (xy 410.868368 -39.38397)
				)
			)
		)
	)
	(footprint ""
		(layer "B.Cu")
		(at 245.7577 -145.0086 -90)
		(property "Reference" "C5L13"
			(at -1.848866 0.752348 270)
			(unlocked yes)
			(layer "B.SilkS")
			(effects
				(font
					(size 1.27 0.9652)
					(thickness 0.1524)
				)
				(justify mirror)
			)
		)
		(property "Value" ""
			(at 0 0 90)
			(layer "B.Fab")
			(effects
				(font
					(size 1.27 1.27)
				)
				(justify mirror)
			)
		)
		(duplicate_pad_numbers_are_jumpers no)
		(fp_rect
			(start 0.500126 1.598422)
			(end -0.500126 -0.201422)
			(stroke
				(width 0)
				(type default)
			)
			(fill no)
			(layer "B.CrtYd")
		)
		(fp_line
			(start -0.500126 1.598422)
			(end 0.500126 1.598422)
			(stroke
				(width 0.1)
				(type default)
			)
			(layer "B.Fab")
		)
		(fp_line
			(start 0.500126 1.598422)
			(end 0.500126 -0.201422)
			(stroke
				(width 0.1)
				(type default)
			)
			(layer "B.Fab")
		)
		(fp_line
			(start -0.500126 -0.201422)
			(end -0.500126 1.598422)
			(stroke
				(width 0.1)
				(type default)
			)
			(layer "B.Fab")
		)
		(fp_line
			(start 0.500126 -0.201422)
			(end -0.500126 -0.201422)
			(stroke
				(width 0.1)
				(type default)
			)
			(layer "B.Fab")
		)
		(pad "1" smd rect
			(at 0 0 180)
			(size 0.889 0.9906)
			(layers "B.Cu" "B.Mask" "B.Paste")
			(net "PVDDQ_DEF")
		)
		(pad "2" smd rect
			(at 0 1.397 180)
			(size 0.889 0.9906)
			(layers "B.Cu" "B.Mask" "B.Paste")
			(net "GND")
		)
		(zone
			(layer "B.Cu")
			(hatch none 0.5)
			(connect_pads
				(clearance 0)
			)
			(min_thickness 0.25)
			(keepout
				(tracks allowed)
				(vias not_allowed)
				(pads allowed)
				(copperpour not_allowed)
				(footprints allowed)
			)
			(placement
				(enabled no)
				(sheetname "")
			)
			(fill
				(thermal_gap 0.5)
				(thermal_bridge_width 0.5)
				(island_removal_mode 0)
			)
			(polygon
				(pts
					(xy 244.8052 -144.5133) (xy 245.3132 -144.5133) (xy 245.3132 -145.5039) (xy 244.8052 -145.5039)
				)
			)
		)
		(zone
			(layer "B.Cu")
			(hatch none 0.5)
			(connect_pads
				(clearance 0)
			)
			(min_thickness 0.25)
			(keepout
				(tracks not_allowed)
				(vias allowed)
				(pads allowed)
				(copperpour not_allowed)
				(footprints allowed)
			)
			(placement
				(enabled no)
				(sheetname "")
			)
			(fill
				(thermal_gap 0.5)
				(thermal_bridge_width 0.5)
				(island_removal_mode 0)
			)
			(polygon
				(pts
					(xy 244.8052 -144.5133) (xy 245.3132 -144.5133) (xy 245.3132 -145.5039) (xy 244.8052 -145.5039)
				)
			)
		)
	)
	(footprint ""
		(layer "B.Cu")
		(at 363.4486 -62.6999 180)
		(property "Reference" "C3P50"
			(at 0 0 0)
			(layer "B.SilkS")
			(hide yes)
			(effects
				(font
					(size 1.27 1.27)
				)
				(justify mirror)
			)
		)
		(property "Value" ""
			(at 0 0 0)
			(layer "B.Fab")
			(effects
				(font
					(size 1.27 1.27)
				)
				(justify mirror)
			)
		)
		(duplicate_pad_numbers_are_jumpers no)
		(fp_poly
			(pts
				(xy -0.3048 -0.1016) (xy -0.3048 0.9906) (xy 0.3048 0.9906) (xy 0.3048 -0.1016)
			)
			(stroke
				(width 0)
				(type default)
			)
			(fill no)
			(layer "B.CrtYd")
		)
		(fp_line
			(start 0.3048 0.9906)
			(end -0.3048 0.9906)
			(stroke
				(width 0.1)
				(type default)
			)
			(layer "B.Fab")
		)
		(fp_line
			(start 0.3048 -0.1016)
			(end 0.3048 0.9906)
			(stroke
				(width 0.1)
				(type default)
			)
			(layer "B.Fab")
		)
		(fp_line
			(start -0.3048 0.9906)
			(end -0.3048 -0.1016)
			(stroke
				(width 0.1)
				(type default)
			)
			(layer "B.Fab")
		)
		(fp_line
			(start -0.3048 -0.1016)
			(end 0.3048 -0.1016)
			(stroke
				(width 0.1)
				(type default)
			)
			(layer "B.Fab")
		)
		(pad "1" smd rect
			(at 0 0)
			(size 0.508 0.508)
			(layers "B.Cu" "B.Mask" "B.Paste")
			(net "P3V3")
		)
		(pad "2" smd rect
			(at 0 0.889)
			(size 0.508 0.508)
			(layers "B.Cu" "B.Mask" "B.Paste")
			(net "GND")
		)
		(zone
			(layer "B.Cu")
			(hatch none 0.5)
			(connect_pads
				(clearance 0)
			)
			(min_thickness 0.25)
			(keepout
				(tracks not_allowed)
				(vias allowed)
				(pads allowed)
				(copperpour not_allowed)
				(footprints allowed)
			)
			(placement
				(enabled no)
				(sheetname "")
			)
			(fill
				(thermal_gap 0.5)
				(thermal_bridge_width 0.5)
				(island_removal_mode 0)
			)
			(polygon
				(pts
					(xy 363.1946 -63.3349) (xy 363.7026 -63.3349) (xy 363.7026 -62.9539) (xy 363.1946 -62.9539)
				)
			)
		)
		(zone
			(layer "B.Cu")
			(hatch none 0.5)
			(connect_pads
				(clearance 0)
			)
			(min_thickness 0.25)
			(keepout
				(tracks allowed)
				(vias not_allowed)
				(pads allowed)
				(copperpour not_allowed)
				(footprints allowed)
			)
			(placement
				(enabled no)
				(sheetname "")
			)
			(fill
				(thermal_gap 0.5)
				(thermal_bridge_width 0.5)
				(island_removal_mode 0)
			)
			(polygon
				(pts
					(xy 363.1946 -62.9539) (xy 363.7026 -62.9539) (xy 363.7026 -63.3349) (xy 363.1946 -63.3349)
				)
			)
		)
	)
	(footprint ""
		(layer "B.Cu")
		(at 409.1305 -19.812 90)
		(property "Reference" "R1U29"
			(at 0 0 90)
			(layer "B.SilkS")
			(hide yes)
			(effects
				(font
					(size 1.27 1.27)
				)
				(justify mirror)
			)
		)
		(property "Value" ""
			(at 0 0 90)
			(layer "B.Fab")
			(effects
				(font
					(size 1.27 1.27)
				)
				(justify mirror)
			)
		)
		(duplicate_pad_numbers_are_jumpers no)
		(fp_poly
			(pts
				(xy 0.2794 -0.1016) (xy -0.2794 -0.1016) (xy -0.2794 0.9906) (xy 0.2794 0.9906)
			)
			(stroke
				(width 0)
				(type default)
			)
			(fill no)
			(layer "B.CrtYd")
		)
		(fp_line
			(start 0.2794 -0.1016)
			(end 0.2794 0.9906)
			(stroke
				(width 0.1)
				(type default)
			)
			(layer "B.Fab")
		)
		(fp_line
			(start -0.2794 -0.1016)
			(end 0.2794 -0.1016)
			(stroke
				(width 0.1)
				(type default)
			)
			(layer "B.Fab")
		)
		(fp_line
			(start 0.2794 0.9906)
			(end -0.2794 0.9906)
			(stroke
				(width 0.1)
				(type default)
			)
			(layer "B.Fab")
		)
		(fp_line
			(start -0.2794 0.9906)
			(end -0.2794 -0.1016)
			(stroke
				(width 0.1)
				(type default)
			)
			(layer "B.Fab")
		)
		(pad "1" smd rect
			(at 0 0 270)
			(size 0.508 0.508)
			(layers "B.Cu" "B.Mask" "B.Paste")
			(net "P5V")
		)
		(pad "2" smd rect
			(at 0 0.889 270)
			(size 0.508 0.508)
			(layers "B.Cu" "B.Mask" "B.Paste")
			(net "A_P5V_SCALED")
		)
		(zone
			(layer "B.Cu")
			(hatch none 0.5)
			(connect_pads
				(clearance 0)
			)
			(min_thickness 0.25)
			(keepout
				(tracks allowed)
				(vias not_allowed)
				(pads allowed)
				(copperpour not_allowed)
				(footprints allowed)
			)
			(placement
				(enabled no)
				(sheetname "")
			)
			(fill
				(thermal_gap 0.5)
				(thermal_bridge_width 0.5)
				(island_removal_mode 0)
			)
			(polygon
				(pts
					(xy 409.3845 -20.066) (xy 409.3845 -19.558) (xy 409.7655 -19.558) (xy 409.7655 -20.066)
				)
			)
		)
		(zone
			(layer "B.Cu")
			(hatch none 0.5)
			(connect_pads
				(clearance 0)
			)
			(min_thickness 0.25)
			(keepout
				(tracks not_allowed)
				(vias allowed)
				(pads allowed)
				(copperpour not_allowed)
				(footprints allowed)
			)
			(placement
				(enabled no)
				(sheetname "")
			)
			(fill
				(thermal_gap 0.5)
				(thermal_bridge_width 0.5)
				(island_removal_mode 0)
			)
			(polygon
				(pts
					(xy 409.7655 -20.066) (xy 409.7655 -19.558) (xy 409.3845 -19.558) (xy 409.3845 -20.066)
				)
			)
		)
	)
	(footprint ""
		(layer "B.Cu")
		(at 442.6712 -15.5702 -90)
		(property "Reference" "R1U43"
			(at 0 0 90)
			(layer "B.SilkS")
			(hide yes)
			(effects
				(font
					(size 1.27 1.27)
				)
				(justify mirror)
			)
		)
		(property "Value" "*"
			(at -0.064008 -4.108196 270)
			(unlocked yes)
			(layer "B.Fab")
			(hide yes)
			(effects
				(font
					(size 1.27 1.016)
					(thickness 0.1524)
				)
				(justify mirror)
			)
		)
		(property "Device Type" "374R2F-1-GP_SMD-RG-374R2F-1-GPA"
			(at -0.064008 -5.632196 270)
			(unlocked yes)
			(layer "B.Fab")
			(hide yes)
			(effects
				(font
					(size 1.27 1.016)
					(thickness 0.1524)
				)
				(justify mirror)
			)
		)
		(duplicate_pad_numbers_are_jumpers no)
		(fp_line
			(start -0.508 -0.9398)
			(end 0.508 -0.9398)
			(stroke
				(width 0.1524)
				(type default)
			)
			(layer "B.SilkS")
		)
		(fp_line
			(start 0.508 -0.9398)
			(end 0.508 0.9398)
			(stroke
				(width 0.1524)
				(type default)
			)
			(layer "B.SilkS")
		)
		(fp_rect
			(start 0.508 0.9398)
			(end -0.508 -0.9398)
			(stroke
				(width 0)
				(type default)
			)
			(fill no)
			(layer "B.CrtYd")
		)
		(fp_rect
			(start 0.508 0.9398)
			(end -0.508 -0.9398)
			(stroke
				(width 0)
				(type default)
			)
			(fill no)
			(layer "B.Fab")
		)
		(pad "1" smd custom
			(at 0 -0.4445 90)
			(size 0.1397 0.1397)
			(layers "B.Cu" "B.Mask" "B.Paste")
			(net "P3V3")
			(options
				(clearance outline)
				(anchor circle)
			)
			(primitives
				(gr_poly
					(pts
						(arc
							(start -0.1778 0.2794)
							(mid -0.249642 0.249642)
							(end -0.2794 0.1778)
						)
						(arc
							(start -0.2794 -0.1778)
							(mid -0.249642 -0.249642)
							(end -0.1778 -0.2794)
						)
						(arc
							(start 0.1778 -0.2794)
							(mid 0.249642 -0.249642)
							(end 0.2794 -0.1778)
						)
						(arc
							(start 0.2794 0.1778)
							(mid 0.249642 0.249642)
							(end 0.1778 0.2794)
						)
					)
					(width 0)
					(fill yes)
				)
			)
		)
		(pad "2" smd custom
			(at 0 0.4445 90)
			(size 0.1397 0.1397)
			(layers "B.Cu" "B.Mask" "B.Paste")
			(net "P0V7_GTL2014_2")
			(options
				(clearance outline)
				(anchor circle)
			)
			(primitives
				(gr_poly
					(pts
						(arc
							(start -0.1778 0.2794)
							(mid -0.249642 0.249642)
							(end -0.2794 0.1778)
						)
						(arc
							(start -0.2794 -0.1778)
							(mid -0.249642 -0.249642)
							(end -0.1778 -0.2794)
						)
						(arc
							(start 0.1778 -0.2794)
							(mid 0.249642 -0.249642)
							(end 0.2794 -0.1778)
						)
						(arc
							(start 0.2794 0.1778)
							(mid 0.249642 0.249642)
							(end 0.1778 0.2794)
						)
					)
					(width 0)
					(fill yes)
				)
			)
		)
	)
	(footprint ""
		(layer "B.Cu")
		(at 24.257 -85.9028 -90)
		(property "Reference" "R9P6"
			(at 0 0 90)
			(layer "B.SilkS")
			(hide yes)
			(effects
				(font
					(size 1.27 1.27)
				)
				(justify mirror)
			)
		)
		(property "Value" ""
			(at 0 0 90)
			(layer "B.Fab")
			(effects
				(font
					(size 1.27 1.27)
				)
				(justify mirror)
			)
		)
		(duplicate_pad_numbers_are_jumpers no)
		(fp_poly
			(pts
				(xy 0.2794 -0.1016) (xy -0.2794 -0.1016) (xy -0.2794 0.9906) (xy 0.2794 0.9906)
			)
			(stroke
				(width 0)
				(type default)
			)
			(fill no)
			(layer "B.CrtYd")
		)
		(fp_line
			(start -0.2794 0.9906)
			(end -0.2794 -0.1016)
			(stroke
				(width 0.1)
				(type default)
			)
			(layer "B.Fab")
		)
		(fp_line
			(start 0.2794 0.9906)
			(end -0.2794 0.9906)
			(stroke
				(width 0.1)
				(type default)
			)
			(layer "B.Fab")
		)
		(fp_line
			(start -0.2794 -0.1016)
			(end 0.2794 -0.1016)
			(stroke
				(width 0.1)
				(type default)
			)
			(layer "B.Fab")
		)
		(fp_line
			(start 0.2794 -0.1016)
			(end 0.2794 0.9906)
			(stroke
				(width 0.1)
				(type default)
			)
			(layer "B.Fab")
		)
		(pad "1" smd rect
			(at 0 0 90)
			(size 0.508 0.508)
			(layers "B.Cu" "B.Mask" "B.Paste")
			(net "P3V3_STBY")
		)
		(pad "2" smd rect
			(at 0 0.889 90)
			(size 0.508 0.508)
			(layers "B.Cu" "B.Mask" "B.Paste")
			(net "FM_UV_ADR_TRIGGER_N")
		)
		(zone
			(layer "B.Cu")
			(hatch none 0.5)
			(connect_pads
				(clearance 0)
			)
			(min_thickness 0.25)
			(keepout
				(tracks not_allowed)
				(vias allowed)
				(pads allowed)
				(copperpour not_allowed)
				(footprints allowed)
			)
			(placement
				(enabled no)
				(sheetname "")
			)
			(fill
				(thermal_gap 0.5)
				(thermal_bridge_width 0.5)
				(island_removal_mode 0)
			)
			(polygon
				(pts
					(xy 23.622 -85.6488) (xy 23.622 -86.1568) (xy 24.003 -86.1568) (xy 24.003 -85.6488)
				)
			)
		)
		(zone
			(layer "B.Cu")
			(hatch none 0.5)
			(connect_pads
				(clearance 0)
			)
			(min_thickness 0.25)
			(keepout
				(tracks allowed)
				(vias not_allowed)
				(pads allowed)
				(copperpour not_allowed)
				(footprints allowed)
			)
			(placement
				(enabled no)
				(sheetname "")
			)
			(fill
				(thermal_gap 0.5)
				(thermal_bridge_width 0.5)
				(island_removal_mode 0)
			)
			(polygon
				(pts
					(xy 24.003 -85.6488) (xy 24.003 -86.1568) (xy 23.622 -86.1568) (xy 23.622 -85.6488)
				)
			)
		)
	)
	(footprint ""
		(layer "B.Cu")
		(at 368.935 -103.632 -90)
		(property "Reference" "C3N28"
			(at 0 0 90)
			(layer "B.SilkS")
			(hide yes)
			(effects
				(font
					(size 1.27 1.27)
				)
				(justify mirror)
			)
		)
		(property "Value" ""
			(at 0 0 90)
			(layer "B.Fab")
			(effects
				(font
					(size 1.27 1.27)
				)
				(justify mirror)
			)
		)
		(duplicate_pad_numbers_are_jumpers no)
		(fp_poly
			(pts
				(xy 0.4953 -0.2032) (xy -0.4953 -0.2032) (xy -0.4953 1.6002) (xy 0.4953 1.6002)
			)
			(stroke
				(width 0)
				(type default)
			)
			(fill no)
			(layer "B.CrtYd")
		)
		(fp_line
			(start -0.4953 1.6002)
			(end 0.4953 1.6002)
			(stroke
				(width 0.1)
				(type default)
			)
			(layer "B.Fab")
		)
		(fp_line
			(start 0.4953 1.6002)
			(end 0.4953 -0.2032)
			(stroke
				(width 0.1)
				(type default)
			)
			(layer "B.Fab")
		)
		(fp_line
			(start -0.4953 -0.2032)
			(end -0.4953 1.6002)
			(stroke
				(width 0.1)
				(type default)
			)
			(layer "B.Fab")
		)
		(fp_line
			(start 0.4953 -0.2032)
			(end -0.4953 -0.2032)
			(stroke
				(width 0.1)
				(type default)
			)
			(layer "B.Fab")
		)
		(pad "1" smd rect
			(at 0 0 90)
			(size 0.762 0.889)
			(layers "B.Cu" "B.Mask" "B.Paste")
			(net "PVNN_PCH_STBY")
		)
		(pad "2" smd rect
			(at 0 1.397 90)
			(size 0.762 0.889)
			(layers "B.Cu" "B.Mask" "B.Paste")
			(net "GND")
		)
		(zone
			(layer "B.Cu")
			(hatch none 0.5)
			(connect_pads
				(clearance 0)
			)
			(min_thickness 0.25)
			(keepout
				(tracks not_allowed)
				(vias allowed)
				(pads allowed)
				(copperpour not_allowed)
				(footprints allowed)
			)
			(placement
				(enabled no)
				(sheetname "")
			)
			(fill
				(thermal_gap 0.5)
				(thermal_bridge_width 0.5)
				(island_removal_mode 0)
			)
			(polygon
				(pts
					(xy 368.4905 -103.251) (xy 368.4905 -104.013) (xy 367.9825 -104.013) (xy 367.9825 -103.251)
				)
			)
		)
	)
	(footprint ""
		(layer "B.Cu")
		(at 473.973906 -19.948398 -90)
		(property "Reference" "R8F3"
			(at 0 0 90)
			(layer "B.SilkS")
			(hide yes)
			(effects
				(font
					(size 1.27 1.27)
				)
				(justify mirror)
			)
		)
		(property "Value" ""
			(at 0 0 90)
			(layer "B.Fab")
			(effects
				(font
					(size 1.27 1.27)
				)
				(justify mirror)
			)
		)
		(duplicate_pad_numbers_are_jumpers no)
		(fp_rect
			(start -0.2794 -0.1016)
			(end 0.2794 0.9906)
			(stroke
				(width 0)
				(type default)
			)
			(fill no)
			(layer "B.CrtYd")
		)
		(fp_line
			(start -0.2794 0.9906)
			(end -0.2794 -0.1016)
			(stroke
				(width 0.1)
				(type default)
			)
			(layer "B.Fab")
		)
		(fp_line
			(start 0.2794 0.9906)
			(end -0.2794 0.9906)
			(stroke
				(width 0.1)
				(type default)
			)
			(layer "B.Fab")
		)
		(fp_line
			(start -0.2794 -0.1016)
			(end 0.2794 -0.1016)
			(stroke
				(width 0.1)
				(type default)
			)
			(layer "B.Fab")
		)
		(fp_line
			(start 0.2794 -0.1016)
			(end 0.2794 0.9906)
			(stroke
				(width 0.1)
				(type default)
			)
			(layer "B.Fab")
		)
		(pad "1" smd rect
			(at 0 0 90)
			(size 0.508 0.508)
			(layers "B.Cu" "B.Mask" "B.Paste")
			(net "VR_P3V3_STBY_SNUB")
		)
		(pad "2" smd rect
			(at 0 0.889 90)
			(size 0.508 0.508)
			(layers "B.Cu" "B.Mask" "B.Paste")
			(net "GND")
		)
		(zone
			(layer "B.Cu")
			(hatch none 0.5)
			(connect_pads
				(clearance 0)
			)
			(min_thickness 0.25)
			(keepout
				(tracks allowed)
				(vias not_allowed)
				(pads allowed)
				(copperpour not_allowed)
				(footprints allowed)
			)
			(placement
				(enabled no)
				(sheetname "")
			)
			(fill
				(thermal_gap 0.5)
				(thermal_bridge_width 0.5)
				(island_removal_mode 0)
			)
			(polygon
				(pts
					(xy 473.719906 -20.202398) (xy 473.338906 -20.202398) (xy 473.338906 -19.694398) (xy 473.719906 -19.694398)
				)
			)
		)
		(zone
			(layer "B.Cu")
			(hatch none 0.5)
			(connect_pads
				(clearance 0)
			)
			(min_thickness 0.25)
			(keepout
				(tracks not_allowed)
				(vias allowed)
				(pads allowed)
				(copperpour not_allowed)
				(footprints allowed)
			)
			(placement
				(enabled no)
				(sheetname "")
			)
			(fill
				(thermal_gap 0.5)
				(thermal_bridge_width 0.5)
				(island_removal_mode 0)
			)
			(polygon
				(pts
					(xy 473.719906 -20.202398) (xy 473.338906 -20.202398) (xy 473.338906 -19.694398) (xy 473.719906 -19.694398)
				)
			)
		)
	)
	(footprint ""
		(layer "B.Cu")
		(at 385.778248 -58.809128 -90)
		(property "Reference" "R2T2"
			(at 0 0 90)
			(layer "B.SilkS")
			(hide yes)
			(effects
				(font
					(size 1.27 1.27)
				)
				(justify mirror)
			)
		)
		(property "Value" ""
			(at 0 0 90)
			(layer "B.Fab")
			(effects
				(font
					(size 1.27 1.27)
				)
				(justify mirror)
			)
		)
		(duplicate_pad_numbers_are_jumpers no)
		(fp_poly
			(pts
				(xy 0.2794 -0.1016) (xy -0.2794 -0.1016) (xy -0.2794 0.9906) (xy 0.2794 0.9906)
			)
			(stroke
				(width 0)
				(type default)
			)
			(fill no)
			(layer "B.CrtYd")
		)
		(fp_line
			(start -0.2794 0.9906)
			(end -0.2794 -0.1016)
			(stroke
				(width 0.1)
				(type default)
			)
			(layer "B.Fab")
		)
		(fp_line
			(start 0.2794 0.9906)
			(end -0.2794 0.9906)
			(stroke
				(width 0.1)
				(type default)
			)
			(layer "B.Fab")
		)
		(fp_line
			(start -0.2794 -0.1016)
			(end 0.2794 -0.1016)
			(stroke
				(width 0.1)
				(type default)
			)
			(layer "B.Fab")
		)
		(fp_line
			(start 0.2794 -0.1016)
			(end 0.2794 0.9906)
			(stroke
				(width 0.1)
				(type default)
			)
			(layer "B.Fab")
		)
		(pad "1" smd rect
			(at 0 0 90)
			(size 0.508 0.508)
			(layers "B.Cu" "B.Mask" "B.Paste")
			(net "SPI_PCH_IO3")
		)
		(pad "2" smd rect
			(at 0 0.889 90)
			(size 0.508 0.508)
			(layers "B.Cu" "B.Mask" "B.Paste")
			(net "SPI_PCH_IO3_R1")
		)
		(zone
			(layer "B.Cu")
			(hatch none 0.5)
			(connect_pads
				(clearance 0)
			)
			(min_thickness 0.25)
			(keepout
				(tracks not_allowed)
				(vias allowed)
				(pads allowed)
				(copperpour not_allowed)
				(footprints allowed)
			)
			(placement
				(enabled no)
				(sheetname "")
			)
			(fill
				(thermal_gap 0.5)
				(thermal_bridge_width 0.5)
				(island_removal_mode 0)
			)
			(polygon
				(pts
					(xy 385.143248 -58.555128) (xy 385.143248 -59.063128) (xy 385.524248 -59.063128) (xy 385.524248 -58.555128)
				)
			)
		)
		(zone
			(layer "B.Cu")
			(hatch none 0.5)
			(connect_pads
				(clearance 0)
			)
			(min_thickness 0.25)
			(keepout
				(tracks allowed)
				(vias not_allowed)
				(pads allowed)
				(copperpour not_allowed)
				(footprints allowed)
			)
			(placement
				(enabled no)
				(sheetname "")
			)
			(fill
				(thermal_gap 0.5)
				(thermal_bridge_width 0.5)
				(island_removal_mode 0)
			)
			(polygon
				(pts
					(xy 385.524248 -58.555128) (xy 385.524248 -59.063128) (xy 385.143248 -59.063128) (xy 385.143248 -58.555128)
				)
			)
		)
	)
	(footprint ""
		(layer "B.Cu")
		(at 378.587 -86.233)
		(property "Reference" "R7C17"
			(at 0.8382 -0.67818 0)
			(unlocked yes)
			(layer "B.SilkS")
			(effects
				(font
					(size 0.4064 0.254)
					(thickness 0.1524)
				)
				(justify left mirror)
			)
		)
		(property "Value" ""
			(at 0 0 0)
			(layer "B.Fab")
			(effects
				(font
					(size 1.27 1.27)
				)
				(justify mirror)
			)
		)
		(duplicate_pad_numbers_are_jumpers no)
		(fp_poly
			(pts
				(xy 0.2794 -0.1016) (xy -0.2794 -0.1016) (xy -0.2794 0.9906) (xy 0.2794 0.9906)
			)
			(stroke
				(width 0)
				(type default)
			)
			(fill no)
			(layer "B.CrtYd")
		)
		(fp_line
			(start -0.2794 -0.1016)
			(end 0.2794 -0.1016)
			(stroke
				(width 0.1)
				(type default)
			)
			(layer "B.Fab")
		)
		(fp_line
			(start -0.2794 0.9906)
			(end -0.2794 -0.1016)
			(stroke
				(width 0.1)
				(type default)
			)
			(layer "B.Fab")
		)
		(fp_line
			(start 0.2794 -0.1016)
			(end 0.2794 0.9906)
			(stroke
				(width 0.1)
				(type default)
			)
			(layer "B.Fab")
		)
		(fp_line
			(start 0.2794 0.9906)
			(end -0.2794 0.9906)
			(stroke
				(width 0.1)
				(type default)
			)
			(layer "B.Fab")
		)
		(pad "1" smd rect
			(at 0 0 180)
			(size 0.508 0.508)
			(layers "B.Cu" "B.Mask" "B.Paste")
			(net "PVCCIO_CPU0")
		)
		(pad "2" smd rect
			(at 0 0.889 180)
			(size 0.508 0.508)
			(layers "B.Cu" "B.Mask" "B.Paste")
			(net "PECI_BMC")
		)
		(zone
			(layer "B.Cu")
			(hatch none 0.5)
			(connect_pads
				(clearance 0)
			)
			(min_thickness 0.25)
			(keepout
				(tracks allowed)
				(vias not_allowed)
				(pads allowed)
				(copperpour not_allowed)
				(footprints allowed)
			)
			(placement
				(enabled no)
				(sheetname "")
			)
			(fill
				(thermal_gap 0.5)
				(thermal_bridge_width 0.5)
				(island_removal_mode 0)
			)
			(polygon
				(pts
					(xy 378.841 -85.979) (xy 378.333 -85.979) (xy 378.333 -85.598) (xy 378.841 -85.598)
				)
			)
		)
		(zone
			(layer "B.Cu")
			(hatch none 0.5)
			(connect_pads
				(clearance 0)
			)
			(min_thickness 0.25)
			(keepout
				(tracks not_allowed)
				(vias allowed)
				(pads allowed)
				(copperpour not_allowed)
				(footprints allowed)
			)
			(placement
				(enabled no)
				(sheetname "")
			)
			(fill
				(thermal_gap 0.5)
				(thermal_bridge_width 0.5)
				(island_removal_mode 0)
			)
			(polygon
				(pts
					(xy 378.841 -85.598) (xy 378.333 -85.598) (xy 378.333 -85.979) (xy 378.841 -85.979)
				)
			)
		)
	)
	(footprint ""
		(layer "B.Cu")
		(at 266.3952 -126.0348 -90)
		(property "Reference" "C5M12"
			(at 0 0 90)
			(layer "B.SilkS")
			(hide yes)
			(effects
				(font
					(size 1.27 1.27)
				)
				(justify mirror)
			)
		)
		(property "Value" ""
			(at 0 0 90)
			(layer "B.Fab")
			(effects
				(font
					(size 1.27 1.27)
				)
				(justify mirror)
			)
		)
		(duplicate_pad_numbers_are_jumpers no)
		(fp_rect
			(start 0.7239 1.9939)
			(end -0.7239 -0.2159)
			(stroke
				(width 0)
				(type default)
			)
			(fill no)
			(layer "B.CrtYd")
		)
		(fp_line
			(start -0.7239 1.9939)
			(end -0.7239 -0.2159)
			(stroke
				(width 0.1)
				(type default)
			)
			(layer "B.Fab")
		)
		(fp_line
			(start 0.7239 1.9939)
			(end -0.7239 1.9939)
			(stroke
				(width 0.1)
				(type default)
			)
			(layer "B.Fab")
		)
		(fp_line
			(start -0.7239 -0.2159)
			(end 0.7239 -0.2159)
			(stroke
				(width 0.1)
				(type default)
			)
			(layer "B.Fab")
		)
		(fp_line
			(start 0.7239 -0.2159)
			(end 0.7239 1.9939)
			(stroke
				(width 0.1)
				(type default)
			)
			(layer "B.Fab")
		)
		(pad "1" smd rect
			(at 0 0 90)
			(size 1.27 1.016)
			(layers "B.Cu" "B.Mask" "B.Paste")
			(net "PVDDQ_DEF")
		)
		(pad "2" smd rect
			(at 0 1.778 90)
			(size 1.27 1.016)
			(layers "B.Cu" "B.Mask" "B.Paste")
			(net "GND")
		)
		(zone
			(layer "B.Cu")
			(hatch none 0.5)
			(connect_pads
				(clearance 0)
			)
			(min_thickness 0.25)
			(keepout
				(tracks not_allowed)
				(vias allowed)
				(pads allowed)
				(copperpour not_allowed)
				(footprints allowed)
			)
			(placement
				(enabled no)
				(sheetname "")
			)
			(fill
				(thermal_gap 0.5)
				(thermal_bridge_width 0.5)
				(island_removal_mode 0)
			)
			(polygon
				(pts
					(xy 265.1252 -125.3998) (xy 265.8872 -125.3998) (xy 265.8872 -126.6698) (xy 265.1252 -126.6698)
				)
			)
		)
	)
	(footprint ""
		(layer "B.Cu")
		(at 494.712244 -49.154588 180)
		(property "Reference" "C25W78"
			(at 0.8382 -0.67818 180)
			(unlocked yes)
			(layer "B.SilkS")
			(effects
				(font
					(size 0.4064 0.254)
					(thickness 0.1524)
				)
				(justify left mirror)
			)
		)
		(property "Value" ""
			(at 0 0 0)
			(layer "B.Fab")
			(effects
				(font
					(size 1.27 1.27)
				)
				(justify mirror)
			)
		)
		(duplicate_pad_numbers_are_jumpers no)
		(fp_poly
			(pts
				(xy -0.3048 -0.1016) (xy -0.3048 0.9906) (xy 0.3048 0.9906) (xy 0.3048 -0.1016)
			)
			(stroke
				(width 0)
				(type default)
			)
			(fill no)
			(layer "B.CrtYd")
		)
		(fp_line
			(start 0.3048 0.9906)
			(end -0.3048 0.9906)
			(stroke
				(width 0.1)
				(type default)
			)
			(layer "B.Fab")
		)
		(fp_line
			(start 0.3048 -0.1016)
			(end 0.3048 0.9906)
			(stroke
				(width 0.1)
				(type default)
			)
			(layer "B.Fab")
		)
		(fp_line
			(start -0.3048 0.9906)
			(end -0.3048 -0.1016)
			(stroke
				(width 0.1)
				(type default)
			)
			(layer "B.Fab")
		)
		(fp_line
			(start -0.3048 -0.1016)
			(end 0.3048 -0.1016)
			(stroke
				(width 0.1)
				(type default)
			)
			(layer "B.Fab")
		)
		(pad "1" smd rect
			(at 0 0)
			(size 0.508 0.508)
			(layers "B.Cu" "B.Mask" "B.Paste")
			(net "V_IBMC_5V_DDC_SCL_J")
		)
		(pad "2" smd rect
			(at 0 0.889)
			(size 0.508 0.508)
			(layers "B.Cu" "B.Mask" "B.Paste")
			(net "GND")
		)
		(zone
			(layer "B.Cu")
			(hatch none 0.5)
			(connect_pads
				(clearance 0)
			)
			(min_thickness 0.25)
			(keepout
				(tracks not_allowed)
				(vias allowed)
				(pads allowed)
				(copperpour not_allowed)
				(footprints allowed)
			)
			(placement
				(enabled no)
				(sheetname "")
			)
			(fill
				(thermal_gap 0.5)
				(thermal_bridge_width 0.5)
				(island_removal_mode 0)
			)
			(polygon
				(pts
					(xy 494.458244 -49.789588) (xy 494.966244 -49.789588) (xy 494.966244 -49.408588) (xy 494.458244 -49.408588)
				)
			)
		)
		(zone
			(layer "B.Cu")
			(hatch none 0.5)
			(connect_pads
				(clearance 0)
			)
			(min_thickness 0.25)
			(keepout
				(tracks allowed)
				(vias not_allowed)
				(pads allowed)
				(copperpour not_allowed)
				(footprints allowed)
			)
			(placement
				(enabled no)
				(sheetname "")
			)
			(fill
				(thermal_gap 0.5)
				(thermal_bridge_width 0.5)
				(island_removal_mode 0)
			)
			(polygon
				(pts
					(xy 494.458244 -49.408588) (xy 494.966244 -49.408588) (xy 494.966244 -49.789588) (xy 494.458244 -49.789588)
				)
			)
		)
	)
	(footprint ""
		(layer "B.Cu")
		(at 395.0843 -20.6248 90)
		(property "Reference" "R32W3"
			(at 0.8382 -0.67818 90)
			(unlocked yes)
			(layer "B.SilkS")
			(effects
				(font
					(size 0.4064 0.254)
					(thickness 0.1524)
				)
				(justify left mirror)
			)
		)
		(property "Value" ""
			(at 0 0 90)
			(layer "B.Fab")
			(effects
				(font
					(size 1.27 1.27)
				)
				(justify mirror)
			)
		)
		(duplicate_pad_numbers_are_jumpers no)
		(fp_poly
			(pts
				(xy 0.2794 -0.1016) (xy -0.2794 -0.1016) (xy -0.2794 0.9906) (xy 0.2794 0.9906)
			)
			(stroke
				(width 0)
				(type default)
			)
			(fill no)
			(layer "B.CrtYd")
		)
		(fp_line
			(start 0.2794 -0.1016)
			(end 0.2794 0.9906)
			(stroke
				(width 0.1)
				(type default)
			)
			(layer "B.Fab")
		)
		(fp_line
			(start -0.2794 -0.1016)
			(end 0.2794 -0.1016)
			(stroke
				(width 0.1)
				(type default)
			)
			(layer "B.Fab")
		)
		(fp_line
			(start 0.2794 0.9906)
			(end -0.2794 0.9906)
			(stroke
				(width 0.1)
				(type default)
			)
			(layer "B.Fab")
		)
		(fp_line
			(start -0.2794 0.9906)
			(end -0.2794 -0.1016)
			(stroke
				(width 0.1)
				(type default)
			)
			(layer "B.Fab")
		)
		(pad "1" smd rect
			(at 0 0 270)
			(size 0.508 0.508)
			(layers "B.Cu" "B.Mask" "B.Paste")
			(net "VREF_LMV431_1V42")
		)
		(pad "2" smd rect
			(at 0 0.889 270)
			(size 0.508 0.508)
			(layers "B.Cu" "B.Mask" "B.Paste")
			(net "GND")
		)
		(zone
			(layer "B.Cu")
			(hatch none 0.5)
			(connect_pads
				(clearance 0)
			)
			(min_thickness 0.25)
			(keepout
				(tracks allowed)
				(vias not_allowed)
				(pads allowed)
				(copperpour not_allowed)
				(footprints allowed)
			)
			(placement
				(enabled no)
				(sheetname "")
			)
			(fill
				(thermal_gap 0.5)
				(thermal_bridge_width 0.5)
				(island_removal_mode 0)
			)
			(polygon
				(pts
					(xy 395.3383 -20.8788) (xy 395.3383 -20.3708) (xy 395.7193 -20.3708) (xy 395.7193 -20.8788)
				)
			)
		)
		(zone
			(layer "B.Cu")
			(hatch none 0.5)
			(connect_pads
				(clearance 0)
			)
			(min_thickness 0.25)
			(keepout
				(tracks not_allowed)
				(vias allowed)
				(pads allowed)
				(copperpour not_allowed)
				(footprints allowed)
			)
			(placement
				(enabled no)
				(sheetname "")
			)
			(fill
				(thermal_gap 0.5)
				(thermal_bridge_width 0.5)
				(island_removal_mode 0)
			)
			(polygon
				(pts
					(xy 395.7193 -20.8788) (xy 395.7193 -20.3708) (xy 395.3383 -20.3708) (xy 395.3383 -20.8788)
				)
			)
		)
	)
	(footprint ""
		(layer "B.Cu")
		(at 394.337032 -66.273172 90)
		(property "Reference" "R2T13"
			(at 0 0 90)
			(layer "B.SilkS")
			(hide yes)
			(effects
				(font
					(size 1.27 1.27)
				)
				(justify mirror)
			)
		)
		(property "Value" ""
			(at 0 0 90)
			(layer "B.Fab")
			(effects
				(font
					(size 1.27 1.27)
				)
				(justify mirror)
			)
		)
		(duplicate_pad_numbers_are_jumpers no)
		(fp_poly
			(pts
				(xy 0.2794 -0.1016) (xy -0.2794 -0.1016) (xy -0.2794 0.9906) (xy 0.2794 0.9906)
			)
			(stroke
				(width 0)
				(type default)
			)
			(fill no)
			(layer "B.CrtYd")
		)
		(fp_line
			(start 0.2794 -0.1016)
			(end 0.2794 0.9906)
			(stroke
				(width 0.1)
				(type default)
			)
			(layer "B.Fab")
		)
		(fp_line
			(start -0.2794 -0.1016)
			(end 0.2794 -0.1016)
			(stroke
				(width 0.1)
				(type default)
			)
			(layer "B.Fab")
		)
		(fp_line
			(start 0.2794 0.9906)
			(end -0.2794 0.9906)
			(stroke
				(width 0.1)
				(type default)
			)
			(layer "B.Fab")
		)
		(fp_line
			(start -0.2794 0.9906)
			(end -0.2794 -0.1016)
			(stroke
				(width 0.1)
				(type default)
			)
			(layer "B.Fab")
		)
		(pad "1" smd rect
			(at 0 0 270)
			(size 0.508 0.508)
			(layers "B.Cu" "B.Mask" "B.Paste")
			(net "SPI_CS0_PRIMARY_N")
		)
		(pad "2" smd rect
			(at 0 0.889 270)
			(size 0.508 0.508)
			(layers "B.Cu" "B.Mask" "B.Paste")
			(net "SPI_CS0_PRIMARY_R_N")
		)
		(zone
			(layer "B.Cu")
			(hatch none 0.5)
			(connect_pads
				(clearance 0)
			)
			(min_thickness 0.25)
			(keepout
				(tracks allowed)
				(vias not_allowed)
				(pads allowed)
				(copperpour not_allowed)
				(footprints allowed)
			)
			(placement
				(enabled no)
				(sheetname "")
			)
			(fill
				(thermal_gap 0.5)
				(thermal_bridge_width 0.5)
				(island_removal_mode 0)
			)
			(polygon
				(pts
					(xy 394.591032 -66.527172) (xy 394.591032 -66.019172) (xy 394.972032 -66.019172) (xy 394.972032 -66.527172)
				)
			)
		)
		(zone
			(layer "B.Cu")
			(hatch none 0.5)
			(connect_pads
				(clearance 0)
			)
			(min_thickness 0.25)
			(keepout
				(tracks not_allowed)
				(vias allowed)
				(pads allowed)
				(copperpour not_allowed)
				(footprints allowed)
			)
			(placement
				(enabled no)
				(sheetname "")
			)
			(fill
				(thermal_gap 0.5)
				(thermal_bridge_width 0.5)
				(island_removal_mode 0)
			)
			(polygon
				(pts
					(xy 394.972032 -66.527172) (xy 394.972032 -66.019172) (xy 394.591032 -66.019172) (xy 394.591032 -66.527172)
				)
			)
		)
	)
	(footprint ""
		(layer "B.Cu")
		(at 169.545 -73.4822 180)
		(property "Reference" "R6P25"
			(at 0 0 0)
			(layer "B.SilkS")
			(hide yes)
			(effects
				(font
					(size 1.27 1.27)
				)
				(justify mirror)
			)
		)
		(property "Value" ""
			(at 0 0 0)
			(layer "B.Fab")
			(effects
				(font
					(size 1.27 1.27)
				)
				(justify mirror)
			)
		)
		(duplicate_pad_numbers_are_jumpers no)
		(fp_poly
			(pts
				(xy 0.4953 -0.2032) (xy -0.4953 -0.2032) (xy -0.4953 1.6002) (xy 0.4953 1.6002)
			)
			(stroke
				(width 0)
				(type default)
			)
			(fill no)
			(layer "B.CrtYd")
		)
		(fp_line
			(start 0.4953 1.6002)
			(end 0.4953 -0.2032)
			(stroke
				(width 0.1)
				(type default)
			)
			(layer "B.Fab")
		)
		(fp_line
			(start 0.4953 -0.2032)
			(end -0.4953 -0.2032)
			(stroke
				(width 0.1)
				(type default)
			)
			(layer "B.Fab")
		)
		(fp_line
			(start -0.4953 1.6002)
			(end 0.4953 1.6002)
			(stroke
				(width 0.1)
				(type default)
			)
			(layer "B.Fab")
		)
		(fp_line
			(start -0.4953 -0.2032)
			(end -0.4953 1.6002)
			(stroke
				(width 0.1)
				(type default)
			)
			(layer "B.Fab")
		)
		(pad "1" smd rect
			(at 0 0)
			(size 0.762 0.889)
			(layers "B.Cu" "B.Mask" "B.Paste")
			(net "P3V3_DB1200")
		)
		(pad "2" smd rect
			(at 0 1.397)
			(size 0.762 0.889)
			(layers "B.Cu" "B.Mask" "B.Paste")
			(net "P3V3_DB1200_R")
		)
		(zone
			(layer "B.Cu")
			(hatch none 0.5)
			(connect_pads
				(clearance 0)
			)
			(min_thickness 0.25)
			(keepout
				(tracks not_allowed)
				(vias allowed)
				(pads allowed)
				(copperpour not_allowed)
				(footprints allowed)
			)
			(placement
				(enabled no)
				(sheetname "")
			)
			(fill
				(thermal_gap 0.5)
				(thermal_bridge_width 0.5)
				(island_removal_mode 0)
			)
			(polygon
				(pts
					(xy 169.164 -74.4347) (xy 169.164 -73.9267) (xy 169.926 -73.9267) (xy 169.926 -74.4347)
				)
			)
		)
		(zone
			(layer "B.Cu")
			(hatch none 0.5)
			(connect_pads
				(clearance 0)
			)
			(min_thickness 0.25)
			(keepout
				(tracks allowed)
				(vias not_allowed)
				(pads allowed)
				(copperpour not_allowed)
				(footprints allowed)
			)
			(placement
				(enabled no)
				(sheetname "")
			)
			(fill
				(thermal_gap 0.5)
				(thermal_bridge_width 0.5)
				(island_removal_mode 0)
			)
			(polygon
				(pts
					(xy 169.926 -74.4347) (xy 169.926 -73.9267) (xy 169.164 -73.9267) (xy 169.164 -74.4347)
				)
			)
		)
	)
	(footprint ""
		(layer "B.Cu")
		(at 1.3462 -139.446 90)
		(property "Reference" "C9L6"
			(at 0 0 90)
			(layer "B.SilkS")
			(hide yes)
			(effects
				(font
					(size 1.27 1.27)
				)
				(justify mirror)
			)
		)
		(property "Value" ""
			(at 0 0 90)
			(layer "B.Fab")
			(effects
				(font
					(size 1.27 1.27)
				)
				(justify mirror)
			)
		)
		(duplicate_pad_numbers_are_jumpers no)
		(fp_rect
			(start -0.7239 -0.2159)
			(end 0.7239 1.9939)
			(stroke
				(width 0)
				(type default)
			)
			(fill no)
			(layer "B.CrtYd")
		)
		(fp_line
			(start 0.7239 -0.2159)
			(end 0.7239 1.9939)
			(stroke
				(width 0.1)
				(type default)
			)
			(layer "B.Fab")
		)
		(fp_line
			(start -0.7239 -0.2159)
			(end 0.7239 -0.2159)
			(stroke
				(width 0.1)
				(type default)
			)
			(layer "B.Fab")
		)
		(fp_line
			(start 0.7239 1.9939)
			(end -0.7239 1.9939)
			(stroke
				(width 0.1)
				(type default)
			)
			(layer "B.Fab")
		)
		(fp_line
			(start -0.7239 1.9939)
			(end -0.7239 -0.2159)
			(stroke
				(width 0.1)
				(type default)
			)
			(layer "B.Fab")
		)
		(pad "1" smd rect
			(at 0 0 270)
			(size 1.27 1.016)
			(layers "B.Cu" "B.Mask" "B.Paste")
			(net "VR_FET_SW_P12V_STBY_PVDDQ_KLM")
		)
		(pad "2" smd rect
			(at 0 1.778 270)
			(size 1.27 1.016)
			(layers "B.Cu" "B.Mask" "B.Paste")
			(net "GND")
		)
		(zone
			(layer "B.Cu")
			(hatch none 0.5)
			(connect_pads
				(clearance 0)
			)
			(min_thickness 0.25)
			(keepout
				(tracks not_allowed)
				(vias allowed)
				(pads allowed)
				(copperpour not_allowed)
				(footprints allowed)
			)
			(placement
				(enabled no)
				(sheetname "")
			)
			(fill
				(thermal_gap 0.5)
				(thermal_bridge_width 0.5)
				(island_removal_mode 0)
			)
			(polygon
				(pts
					(xy 1.8542 -138.811) (xy 2.6162 -138.811) (xy 2.6162 -140.081) (xy 1.8542 -140.081)
				)
			)
		)
	)
	(footprint ""
		(layer "B.Cu")
		(at 188.22797 -60.461144 180)
		(property "Reference" "C22W21"
			(at 0 0 0)
			(layer "B.SilkS")
			(hide yes)
			(effects
				(font
					(size 1.27 1.27)
				)
				(justify mirror)
			)
		)
		(property "Value" "*"
			(at 0.0762 -6.2357 180)
			(unlocked yes)
			(layer "B.Fab")
			(hide yes)
			(effects
				(font
					(size 1.27 1.016)
					(thickness 0.1524)
				)
				(justify mirror)
			)
		)
		(property "Device Type" "SC22U16V5MX-4-GP_SMD-BCG5-SC22A"
			(at 0.0762 -8.2677 180)
			(unlocked yes)
			(layer "B.Fab")
			(hide yes)
			(effects
				(font
					(size 1.27 1.016)
					(thickness 0.1524)
				)
				(justify mirror)
			)
		)
		(duplicate_pad_numbers_are_jumpers no)
		(fp_line
			(start -0.635 0)
			(end 0.635 0)
			(stroke
				(width 0.508)
				(type default)
			)
			(layer "B.SilkS")
		)
		(fp_rect
			(start 0.9652 1.778)
			(end -0.9652 -1.778)
			(stroke
				(width 0)
				(type default)
			)
			(fill no)
			(layer "B.CrtYd")
		)
		(fp_poly
			(pts
				(xy 0.9652 -1.778) (xy -0.9652 -1.778) (xy -0.9652 1.778) (xy 0.9652 1.778)
			)
			(stroke
				(width 0)
				(type default)
			)
			(fill no)
			(layer "B.Fab")
		)
		(pad "1" smd rect
			(at 0 -0.9652)
			(size 1.397 1.143)
			(layers "B.Cu" "B.Mask" "B.Paste")
			(net "VR_FET_SW_P12V_STBY_PVCCIN_CPU0")
		)
		(pad "2" smd rect
			(at 0 0.9652)
			(size 1.397 1.143)
			(layers "B.Cu" "B.Mask" "B.Paste")
			(net "GND")
		)
	)
	(footprint ""
		(layer "B.Cu")
		(at 386.309616 -13.04417)
		(property "Reference" "R32W12"
			(at 0.8382 -0.67818 0)
			(unlocked yes)
			(layer "B.SilkS")
			(effects
				(font
					(size 0.4064 0.254)
					(thickness 0.1524)
				)
				(justify left mirror)
			)
		)
		(property "Value" ""
			(at 0 0 0)
			(layer "B.Fab")
			(effects
				(font
					(size 1.27 1.27)
				)
				(justify mirror)
			)
		)
		(duplicate_pad_numbers_are_jumpers no)
		(fp_poly
			(pts
				(xy 0.2794 -0.1016) (xy -0.2794 -0.1016) (xy -0.2794 0.9906) (xy 0.2794 0.9906)
			)
			(stroke
				(width 0)
				(type default)
			)
			(fill no)
			(layer "B.CrtYd")
		)
		(fp_line
			(start -0.2794 -0.1016)
			(end 0.2794 -0.1016)
			(stroke
				(width 0.1)
				(type default)
			)
			(layer "B.Fab")
		)
		(fp_line
			(start -0.2794 0.9906)
			(end -0.2794 -0.1016)
			(stroke
				(width 0.1)
				(type default)
			)
			(layer "B.Fab")
		)
		(fp_line
			(start 0.2794 -0.1016)
			(end 0.2794 0.9906)
			(stroke
				(width 0.1)
				(type default)
			)
			(layer "B.Fab")
		)
		(fp_line
			(start 0.2794 0.9906)
			(end -0.2794 0.9906)
			(stroke
				(width 0.1)
				(type default)
			)
			(layer "B.Fab")
		)
		(pad "1" smd rect
			(at 0 0 180)
			(size 0.508 0.508)
			(layers "B.Cu" "B.Mask" "B.Paste")
			(net "SMB_M2_ALT_N")
		)
		(pad "2" smd rect
			(at 0 0.889 180)
			(size 0.508 0.508)
			(layers "B.Cu" "B.Mask" "B.Paste")
			(net "SMB_M2_ALT_R_N")
		)
		(zone
			(layer "B.Cu")
			(hatch none 0.5)
			(connect_pads
				(clearance 0)
			)
			(min_thickness 0.25)
			(keepout
				(tracks allowed)
				(vias not_allowed)
				(pads allowed)
				(copperpour not_allowed)
				(footprints allowed)
			)
			(placement
				(enabled no)
				(sheetname "")
			)
			(fill
				(thermal_gap 0.5)
				(thermal_bridge_width 0.5)
				(island_removal_mode 0)
			)
			(polygon
				(pts
					(xy 386.563616 -12.79017) (xy 386.055616 -12.79017) (xy 386.055616 -12.40917) (xy 386.563616 -12.40917)
				)
			)
		)
		(zone
			(layer "B.Cu")
			(hatch none 0.5)
			(connect_pads
				(clearance 0)
			)
			(min_thickness 0.25)
			(keepout
				(tracks not_allowed)
				(vias allowed)
				(pads allowed)
				(copperpour not_allowed)
				(footprints allowed)
			)
			(placement
				(enabled no)
				(sheetname "")
			)
			(fill
				(thermal_gap 0.5)
				(thermal_bridge_width 0.5)
				(island_removal_mode 0)
			)
			(polygon
				(pts
					(xy 386.563616 -12.40917) (xy 386.055616 -12.40917) (xy 386.055616 -12.79017) (xy 386.563616 -12.79017)
				)
			)
		)
	)
	(footprint ""
		(layer "B.Cu")
		(at 393.9667 -10.01903 180)
		(property "Reference" "R32W10"
			(at 0.8382 -0.67818 180)
			(unlocked yes)
			(layer "B.SilkS")
			(effects
				(font
					(size 0.4064 0.254)
					(thickness 0.1524)
				)
				(justify left mirror)
			)
		)
		(property "Value" ""
			(at 0 0 0)
			(layer "B.Fab")
			(effects
				(font
					(size 1.27 1.27)
				)
				(justify mirror)
			)
		)
		(duplicate_pad_numbers_are_jumpers no)
		(fp_poly
			(pts
				(xy 0.2794 -0.1016) (xy -0.2794 -0.1016) (xy -0.2794 0.9906) (xy 0.2794 0.9906)
			)
			(stroke
				(width 0)
				(type default)
			)
			(fill no)
			(layer "B.CrtYd")
		)
		(fp_line
			(start 0.2794 0.9906)
			(end -0.2794 0.9906)
			(stroke
				(width 0.1)
				(type default)
			)
			(layer "B.Fab")
		)
		(fp_line
			(start 0.2794 -0.1016)
			(end 0.2794 0.9906)
			(stroke
				(width 0.1)
				(type default)
			)
			(layer "B.Fab")
		)
		(fp_line
			(start -0.2794 0.9906)
			(end -0.2794 -0.1016)
			(stroke
				(width 0.1)
				(type default)
			)
			(layer "B.Fab")
		)
		(fp_line
			(start -0.2794 -0.1016)
			(end 0.2794 -0.1016)
			(stroke
				(width 0.1)
				(type default)
			)
			(layer "B.Fab")
		)
		(pad "1" smd rect
			(at 0 0)
			(size 0.508 0.508)
			(layers "B.Cu" "B.Mask" "B.Paste")
			(net "SMB_M2_SCL")
		)
		(pad "2" smd rect
			(at 0 0.889)
			(size 0.508 0.508)
			(layers "B.Cu" "B.Mask" "B.Paste")
			(net "SMB_M2_SCL_R")
		)
		(zone
			(layer "B.Cu")
			(hatch none 0.5)
			(connect_pads
				(clearance 0)
			)
			(min_thickness 0.25)
			(keepout
				(tracks not_allowed)
				(vias allowed)
				(pads allowed)
				(copperpour not_allowed)
				(footprints allowed)
			)
			(placement
				(enabled no)
				(sheetname "")
			)
			(fill
				(thermal_gap 0.5)
				(thermal_bridge_width 0.5)
				(island_removal_mode 0)
			)
			(polygon
				(pts
					(xy 393.7127 -10.65403) (xy 394.2207 -10.65403) (xy 394.2207 -10.27303) (xy 393.7127 -10.27303)
				)
			)
		)
		(zone
			(layer "B.Cu")
			(hatch none 0.5)
			(connect_pads
				(clearance 0)
			)
			(min_thickness 0.25)
			(keepout
				(tracks allowed)
				(vias not_allowed)
				(pads allowed)
				(copperpour not_allowed)
				(footprints allowed)
			)
			(placement
				(enabled no)
				(sheetname "")
			)
			(fill
				(thermal_gap 0.5)
				(thermal_bridge_width 0.5)
				(island_removal_mode 0)
			)
			(polygon
				(pts
					(xy 393.7127 -10.27303) (xy 394.2207 -10.27303) (xy 394.2207 -10.65403) (xy 393.7127 -10.65403)
				)
			)
		)
	)
	(footprint ""
		(layer "B.Cu")
		(at 347.17736 -77.788516 180)
		(property "Reference" "C3P23"
			(at 0 0 0)
			(layer "B.SilkS")
			(hide yes)
			(effects
				(font
					(size 1.27 1.27)
				)
				(justify mirror)
			)
		)
		(property "Value" ""
			(at 0 0 0)
			(layer "B.Fab")
			(effects
				(font
					(size 1.27 1.27)
				)
				(justify mirror)
			)
		)
		(duplicate_pad_numbers_are_jumpers no)
		(fp_poly
			(pts
				(xy -0.3048 -0.1016) (xy -0.3048 0.9906) (xy 0.3048 0.9906) (xy 0.3048 -0.1016)
			)
			(stroke
				(width 0)
				(type default)
			)
			(fill no)
			(layer "B.CrtYd")
		)
		(fp_line
			(start 0.3048 0.9906)
			(end -0.3048 0.9906)
			(stroke
				(width 0.1)
				(type default)
			)
			(layer "B.Fab")
		)
		(fp_line
			(start 0.3048 -0.1016)
			(end 0.3048 0.9906)
			(stroke
				(width 0.1)
				(type default)
			)
			(layer "B.Fab")
		)
		(fp_line
			(start -0.3048 0.9906)
			(end -0.3048 -0.1016)
			(stroke
				(width 0.1)
				(type default)
			)
			(layer "B.Fab")
		)
		(fp_line
			(start -0.3048 -0.1016)
			(end 0.3048 -0.1016)
			(stroke
				(width 0.1)
				(type default)
			)
			(layer "B.Fab")
		)
		(pad "1" smd rect
			(at 0 0)
			(size 0.508 0.508)
			(layers "B.Cu" "B.Mask" "B.Paste")
			(net "P3E_CPU0_PE1_SS_TXP<3>")
		)
		(pad "2" smd rect
			(at 0 0.889)
			(size 0.508 0.508)
			(layers "B.Cu" "B.Mask" "B.Paste")
			(net "P3E_CPU0_PE1_PCH_TXP<3>")
		)
		(zone
			(layer "B.Cu")
			(hatch none 0.5)
			(connect_pads
				(clearance 0)
			)
			(min_thickness 0.25)
			(keepout
				(tracks not_allowed)
				(vias allowed)
				(pads allowed)
				(copperpour not_allowed)
				(footprints allowed)
			)
			(placement
				(enabled no)
				(sheetname "")
			)
			(fill
				(thermal_gap 0.5)
				(thermal_bridge_width 0.5)
				(island_removal_mode 0)
			)
			(polygon
				(pts
					(xy 346.92336 -78.423516) (xy 347.43136 -78.423516) (xy 347.43136 -78.042516) (xy 346.92336 -78.042516)
				)
			)
		)
		(zone
			(layer "B.Cu")
			(hatch none 0.5)
			(connect_pads
				(clearance 0)
			)
			(min_thickness 0.25)
			(keepout
				(tracks allowed)
				(vias not_allowed)
				(pads allowed)
				(copperpour not_allowed)
				(footprints allowed)
			)
			(placement
				(enabled no)
				(sheetname "")
			)
			(fill
				(thermal_gap 0.5)
				(thermal_bridge_width 0.5)
				(island_removal_mode 0)
			)
			(polygon
				(pts
					(xy 346.92336 -78.042516) (xy 347.43136 -78.042516) (xy 347.43136 -78.423516) (xy 346.92336 -78.423516)
				)
			)
		)
	)
	(footprint ""
		(layer "B.Cu")
		(at 374.1928 -53.8099 -90)
		(property "Reference" "R3P36"
			(at 0 0 90)
			(layer "B.SilkS")
			(hide yes)
			(effects
				(font
					(size 1.27 1.27)
				)
				(justify mirror)
			)
		)
		(property "Value" ""
			(at 0 0 90)
			(layer "B.Fab")
			(effects
				(font
					(size 1.27 1.27)
				)
				(justify mirror)
			)
		)
		(duplicate_pad_numbers_are_jumpers no)
		(fp_poly
			(pts
				(xy 0.2794 -0.1016) (xy -0.2794 -0.1016) (xy -0.2794 0.9906) (xy 0.2794 0.9906)
			)
			(stroke
				(width 0)
				(type default)
			)
			(fill no)
			(layer "B.CrtYd")
		)
		(fp_line
			(start -0.2794 0.9906)
			(end -0.2794 -0.1016)
			(stroke
				(width 0.1)
				(type default)
			)
			(layer "B.Fab")
		)
		(fp_line
			(start 0.2794 0.9906)
			(end -0.2794 0.9906)
			(stroke
				(width 0.1)
				(type default)
			)
			(layer "B.Fab")
		)
		(fp_line
			(start -0.2794 -0.1016)
			(end 0.2794 -0.1016)
			(stroke
				(width 0.1)
				(type default)
			)
			(layer "B.Fab")
		)
		(fp_line
			(start 0.2794 -0.1016)
			(end 0.2794 0.9906)
			(stroke
				(width 0.1)
				(type default)
			)
			(layer "B.Fab")
		)
		(pad "1" smd rect
			(at 0 0 90)
			(size 0.508 0.508)
			(layers "B.Cu" "B.Mask" "B.Paste")
			(net "P3V3_STBY")
		)
		(pad "2" smd rect
			(at 0 0.889 90)
			(size 0.508 0.508)
			(layers "B.Cu" "B.Mask" "B.Paste")
			(net "PU_GTL2014_1_DIR")
		)
		(zone
			(layer "B.Cu")
			(hatch none 0.5)
			(connect_pads
				(clearance 0)
			)
			(min_thickness 0.25)
			(keepout
				(tracks not_allowed)
				(vias allowed)
				(pads allowed)
				(copperpour not_allowed)
				(footprints allowed)
			)
			(placement
				(enabled no)
				(sheetname "")
			)
			(fill
				(thermal_gap 0.5)
				(thermal_bridge_width 0.5)
				(island_removal_mode 0)
			)
			(polygon
				(pts
					(xy 373.5578 -53.5559) (xy 373.5578 -54.0639) (xy 373.9388 -54.0639) (xy 373.9388 -53.5559)
				)
			)
		)
		(zone
			(layer "B.Cu")
			(hatch none 0.5)
			(connect_pads
				(clearance 0)
			)
			(min_thickness 0.25)
			(keepout
				(tracks allowed)
				(vias not_allowed)
				(pads allowed)
				(copperpour not_allowed)
				(footprints allowed)
			)
			(placement
				(enabled no)
				(sheetname "")
			)
			(fill
				(thermal_gap 0.5)
				(thermal_bridge_width 0.5)
				(island_removal_mode 0)
			)
			(polygon
				(pts
					(xy 373.9388 -53.5559) (xy 373.9388 -54.0639) (xy 373.5578 -54.0639) (xy 373.5578 -53.5559)
				)
			)
		)
	)
	(footprint ""
		(layer "B.Cu")
		(at 194.700398 -142.477236 90)
		(property "Reference" "J6L2"
			(at 2.276348 38.21811 0)
			(unlocked yes)
			(layer "B.SilkS")
			(effects
				(font
					(size 0.7874 0.5842)
					(thickness 0.1524)
				)
				(justify left mirror)
			)
		)
		(property "Value" ""
			(at 0 0 90)
			(layer "B.Fab")
			(effects
				(font
					(size 1.27 1.27)
				)
				(justify mirror)
			)
		)
		(duplicate_pad_numbers_are_jumpers no)
		(fp_line
			(start 0.94996 -7.675118)
			(end -5.5499 -7.675118)
			(stroke
				(width 0.1524)
				(type default)
			)
			(layer "B.SilkS")
		)
		(fp_line
			(start -5.5499 -7.675118)
			(end -5.5499 -1.480058)
			(stroke
				(width 0.1524)
				(type default)
			)
			(layer "B.SilkS")
		)
		(fp_line
			(start 0.94996 -1.480058)
			(end 0.94996 -7.675118)
			(stroke
				(width 0.1524)
				(type default)
			)
			(layer "B.SilkS")
		)
		(fp_line
			(start -5.5499 128.130046)
			(end -5.5499 134.325106)
			(stroke
				(width 0.1524)
				(type default)
			)
			(layer "B.SilkS")
		)
		(fp_line
			(start 0.94996 134.325106)
			(end 0.94996 128.130046)
			(stroke
				(width 0.1524)
				(type default)
			)
			(layer "B.SilkS")
		)
		(fp_line
			(start -5.5499 134.325106)
			(end 0.94996 134.325106)
			(stroke
				(width 0.1524)
				(type default)
			)
			(layer "B.SilkS")
		)
		(fp_poly
			(pts
				(xy 3.149854 -4.283202) (xy 3.149854 -3.267202) (xy 1.879854 -3.775202)
			)
			(stroke
				(width 0)
				(type default)
			)
			(fill yes)
			(layer "B.SilkS")
		)
		(fp_poly
			(pts
				(xy 0.94996 -7.675118) (xy 0.94996 134.325106) (xy -5.5499 134.325106) (xy -5.5499 -7.675118)
			)
			(stroke
				(width 0)
				(type default)
			)
			(fill no)
			(layer "B.CrtYd")
		)
		(fp_line
			(start 0.94996 -7.675118)
			(end -5.5499 -7.675118)
			(stroke
				(width 0.1)
				(type default)
			)
			(layer "B.Fab")
		)
		(fp_line
			(start -5.5499 -7.675118)
			(end -5.5499 134.325106)
			(stroke
				(width 0.1)
				(type default)
			)
			(layer "B.Fab")
		)
		(fp_line
			(start 0.94996 134.325106)
			(end 0.94996 -7.675118)
			(stroke
				(width 0.1)
				(type default)
			)
			(layer "B.Fab")
		)
		(fp_line
			(start -5.5499 134.325106)
			(end 0.94996 134.325106)
			(stroke
				(width 0.1)
				(type default)
			)
			(layer "B.Fab")
		)
		(fp_poly
			(pts
				(xy 2.984246 -0.461264) (xy 2.984246 0.554736) (xy 1.714246 0.046736)
			)
			(stroke
				(width 0)
				(type default)
			)
			(fill yes)
			(layer "B.Fab")
		)
		(fp_text user "145"
			(at -6.105652 2.65811 0)
			(unlocked yes)
			(layer "B.SilkS")
			(effects
				(font
					(size 0.7874 0.5842)
					(thickness 0.1524)
				)
				(justify left mirror)
			)
		)
		(fp_text user "77"
			(at 0.752348 66.66611 0)
			(unlocked yes)
			(layer "B.SilkS")
			(effects
				(font
					(size 0.7874 0.5842)
					(thickness 0.1524)
				)
				(justify left mirror)
			)
		)
		(fp_text user "221"
			(at -5.851652 67.17411 0)
			(unlocked yes)
			(layer "B.SilkS")
			(effects
				(font
					(size 0.7874 0.5842)
					(thickness 0.1524)
				)
				(justify left mirror)
			)
		)
		(fp_text user "78"
			(at 1.514348 71.23811 0)
			(unlocked yes)
			(layer "B.SilkS")
			(effects
				(font
					(size 0.7874 0.5842)
					(thickness 0.1524)
				)
				(justify left mirror)
			)
		)
		(fp_text user "222"
			(at -6.105652 72.00011 0)
			(unlocked yes)
			(layer "B.SilkS")
			(effects
				(font
					(size 0.7874 0.5842)
					(thickness 0.1524)
				)
				(justify left mirror)
			)
		)
		(fp_text user "144"
			(at 1.514348 129.78511 0)
			(unlocked yes)
			(layer "B.SilkS")
			(effects
				(font
					(size 0.7874 0.5842)
					(thickness 0.1524)
				)
				(justify left mirror)
			)
		)
		(fp_text user "288"
			(at -6.359652 129.78511 0)
			(unlocked yes)
			(layer "B.SilkS")
			(effects
				(font
					(size 0.7874 0.5842)
					(thickness 0.1524)
				)
				(justify left mirror)
			)
		)
		(fp_text user "145"
			(at -3.411982 -1.37922 90)
			(unlocked yes)
			(layer "B.Fab")
			(effects
				(font
					(size 0.7874 0.5842)
					(thickness 0.1524)
				)
				(justify left mirror)
			)
		)
		(fp_text user "77"
			(at 0.398018 65.93078 90)
			(unlocked yes)
			(layer "B.Fab")
			(effects
				(font
					(size 0.7874 0.5842)
					(thickness 0.1524)
				)
				(justify left mirror)
			)
		)
		(fp_text user "221"
			(at -3.411982 65.93078 90)
			(unlocked yes)
			(layer "B.Fab")
			(effects
				(font
					(size 0.7874 0.5842)
					(thickness 0.1524)
				)
				(justify left mirror)
			)
		)
		(fp_text user "78"
			(at 0.398018 69.10578 90)
			(unlocked yes)
			(layer "B.Fab")
			(effects
				(font
					(size 0.7874 0.5842)
					(thickness 0.1524)
				)
				(justify left mirror)
			)
		)
		(fp_text user "222"
			(at -3.411982 69.10578 90)
			(unlocked yes)
			(layer "B.Fab")
			(effects
				(font
					(size 0.7874 0.5842)
					(thickness 0.1524)
				)
				(justify left mirror)
			)
		)
		(fp_text user "144"
			(at 0.398018 128.16078 90)
			(unlocked yes)
			(layer "B.Fab")
			(effects
				(font
					(size 0.7874 0.5842)
					(thickness 0.1524)
				)
				(justify left mirror)
			)
		)
		(fp_text user "288"
			(at -3.411982 128.16078 90)
			(unlocked yes)
			(layer "B.Fab")
			(effects
				(font
					(size 0.7874 0.5842)
					(thickness 0.1524)
				)
				(justify left mirror)
			)
		)
		(pad "" thru_hole circle
			(at -2.29997 -5.649976 270)
			(size 2.8194 2.8194)
			(drill 2.4384)
			(layers "*.Cu" "*.Mask")
			(remove_unused_layers no)
			(clearance 0.127)
			(thermal_gap 0.127)
		)
		(pad "" thru_hole oval
			(at -2.29997 68.90004 270)
			(size 2.8194 1.5748)
			(drill oval 2.4384 1.1938)
			(layers "*.Cu" "*.Mask")
			(remove_unused_layers no)
			(clearance 0.127)
			(thermal_gap 0.127)
		)
		(pad "" thru_hole circle
			(at -2.29997 132.299964 270)
			(size 2.8194 2.8194)
			(drill 2.4384)
			(layers "*.Cu" "*.Mask")
			(remove_unused_layers no)
			(clearance 0.127)
			(thermal_gap 0.127)
		)
		(pad "1" smd rect
			(at 0 0 270)
			(size 1.8034 0.508)
			(layers "B.Cu" "B.Mask" "B.Paste")
			(net "P12V_NVDIMM_DEF")
		)
		(pad "2" smd rect
			(at 0 0.849884 270)
			(size 1.8034 0.508)
			(layers "B.Cu" "B.Mask" "B.Paste")
			(net "GND")
		)
		(pad "3" smd rect
			(at 0 1.700022 270)
			(size 1.8034 0.508)
			(layers "B.Cu" "B.Mask" "B.Paste")
			(net "M_E_DQ<4>")
		)
		(pad "4" smd rect
			(at 0 2.549906 270)
			(size 1.8034 0.508)
			(layers "B.Cu" "B.Mask" "B.Paste")
			(net "GND")
		)
		(pad "5" smd rect
			(at 0 3.400044 270)
			(size 1.8034 0.508)
			(layers "B.Cu" "B.Mask" "B.Paste")
			(net "M_E_DQ<0>")
		)
		(pad "6" smd rect
			(at 0 4.249928 270)
			(size 1.8034 0.508)
			(layers "B.Cu" "B.Mask" "B.Paste")
			(net "GND")
		)
		(pad "7" smd rect
			(at 0 5.100066 270)
			(size 1.8034 0.508)
			(layers "B.Cu" "B.Mask" "B.Paste")
			(net "M_E_DQS_DP<9>")
		)
		(pad "8" smd rect
			(at 0 5.94995 270)
			(size 1.8034 0.508)
			(layers "B.Cu" "B.Mask" "B.Paste")
			(net "M_E_DQS_DN<9>")
		)
		(pad "9" smd rect
			(at 0 6.800088 270)
			(size 1.8034 0.508)
			(layers "B.Cu" "B.Mask" "B.Paste")
			(net "GND")
		)
		(pad "10" smd rect
			(at 0 7.649972 270)
			(size 1.8034 0.508)
			(layers "B.Cu" "B.Mask" "B.Paste")
			(net "M_E_DQ<6>")
		)
		(pad "11" smd rect
			(at 0 8.50011 270)
			(size 1.8034 0.508)
			(layers "B.Cu" "B.Mask" "B.Paste")
			(net "GND")
		)
		(pad "12" smd rect
			(at 0 9.349994 270)
			(size 1.8034 0.508)
			(layers "B.Cu" "B.Mask" "B.Paste")
			(net "M_E_DQ<2>")
		)
		(pad "13" smd rect
			(at 0 10.199878 270)
			(size 1.8034 0.508)
			(layers "B.Cu" "B.Mask" "B.Paste")
			(net "GND")
		)
		(pad "14" smd rect
			(at 0 11.050016 270)
			(size 1.8034 0.508)
			(layers "B.Cu" "B.Mask" "B.Paste")
			(net "M_E_DQ<12>")
		)
		(pad "15" smd rect
			(at 0 11.8999 270)
			(size 1.8034 0.508)
			(layers "B.Cu" "B.Mask" "B.Paste")
			(net "GND")
		)
		(pad "16" smd rect
			(at 0 12.750038 270)
			(size 1.8034 0.508)
			(layers "B.Cu" "B.Mask" "B.Paste")
			(net "M_E_DQ<8>")
		)
		(pad "17" smd rect
			(at 0 13.599922 270)
			(size 1.8034 0.508)
			(layers "B.Cu" "B.Mask" "B.Paste")
			(net "GND")
		)
		(pad "18" smd rect
			(at 0 14.45006 270)
			(size 1.8034 0.508)
			(layers "B.Cu" "B.Mask" "B.Paste")
			(net "M_E_DQS_DP<10>")
		)
		(pad "19" smd rect
			(at 0 15.299944 270)
			(size 1.8034 0.508)
			(layers "B.Cu" "B.Mask" "B.Paste")
			(net "M_E_DQS_DN<10>")
		)
		(pad "20" smd rect
			(at 0 16.150082 270)
			(size 1.8034 0.508)
			(layers "B.Cu" "B.Mask" "B.Paste")
			(net "GND")
		)
		(pad "21" smd rect
			(at 0 16.999966 270)
			(size 1.8034 0.508)
			(layers "B.Cu" "B.Mask" "B.Paste")
			(net "M_E_DQ<14>")
		)
		(pad "22" smd rect
			(at 0 17.850104 270)
			(size 1.8034 0.508)
			(layers "B.Cu" "B.Mask" "B.Paste")
			(net "GND")
		)
		(pad "23" smd rect
			(at 0 18.699988 270)
			(size 1.8034 0.508)
			(layers "B.Cu" "B.Mask" "B.Paste")
			(net "M_E_DQ<10>")
		)
		(pad "24" smd rect
			(at 0 19.550126 270)
			(size 1.8034 0.508)
			(layers "B.Cu" "B.Mask" "B.Paste")
			(net "GND")
		)
		(pad "25" smd rect
			(at 0 20.40001 270)
			(size 1.8034 0.508)
			(layers "B.Cu" "B.Mask" "B.Paste")
			(net "M_E_DQ<20>")
		)
		(pad "26" smd rect
			(at 0 21.249894 270)
			(size 1.8034 0.508)
			(layers "B.Cu" "B.Mask" "B.Paste")
			(net "GND")
		)
		(pad "27" smd rect
			(at 0 22.100032 270)
			(size 1.8034 0.508)
			(layers "B.Cu" "B.Mask" "B.Paste")
			(net "M_E_DQ<16>")
		)
		(pad "28" smd rect
			(at 0 22.949916 270)
			(size 1.8034 0.508)
			(layers "B.Cu" "B.Mask" "B.Paste")
			(net "GND")
		)
		(pad "29" smd rect
			(at 0 23.800054 270)
			(size 1.8034 0.508)
			(layers "B.Cu" "B.Mask" "B.Paste")
			(net "M_E_DQS_DP<11>")
		)
		(pad "30" smd rect
			(at 0 24.649938 270)
			(size 1.8034 0.508)
			(layers "B.Cu" "B.Mask" "B.Paste")
			(net "M_E_DQS_DN<11>")
		)
		(pad "31" smd rect
			(at 0 25.500076 270)
			(size 1.8034 0.508)
			(layers "B.Cu" "B.Mask" "B.Paste")
			(net "GND")
		)
		(pad "32" smd rect
			(at 0 26.34996 270)
			(size 1.8034 0.508)
			(layers "B.Cu" "B.Mask" "B.Paste")
			(net "M_E_DQ<22>")
		)
		(pad "33" smd rect
			(at 0 27.200098 270)
			(size 1.8034 0.508)
			(layers "B.Cu" "B.Mask" "B.Paste")
			(net "GND")
		)
		(pad "34" smd rect
			(at 0 28.049982 270)
			(size 1.8034 0.508)
			(layers "B.Cu" "B.Mask" "B.Paste")
			(net "M_E_DQ<18>")
		)
		(pad "35" smd rect
			(at 0 28.90012 270)
			(size 1.8034 0.508)
			(layers "B.Cu" "B.Mask" "B.Paste")
			(net "GND")
		)
		(pad "36" smd rect
			(at 0 29.750004 270)
			(size 1.8034 0.508)
			(layers "B.Cu" "B.Mask" "B.Paste")
			(net "M_E_DQ<28>")
		)
		(pad "37" smd rect
			(at 0 30.599888 270)
			(size 1.8034 0.508)
			(layers "B.Cu" "B.Mask" "B.Paste")
			(net "GND")
		)
		(pad "38" smd rect
			(at 0 31.450026 270)
			(size 1.8034 0.508)
			(layers "B.Cu" "B.Mask" "B.Paste")
			(net "M_E_DQ<24>")
		)
		(pad "39" smd rect
			(at 0 32.29991 270)
			(size 1.8034 0.508)
			(layers "B.Cu" "B.Mask" "B.Paste")
			(net "GND")
		)
		(pad "40" smd rect
			(at 0 33.150048 270)
			(size 1.8034 0.508)
			(layers "B.Cu" "B.Mask" "B.Paste")
			(net "M_E_DQS_DP<12>")
		)
		(pad "41" smd rect
			(at 0 33.999932 270)
			(size 1.8034 0.508)
			(layers "B.Cu" "B.Mask" "B.Paste")
			(net "M_E_DQS_DN<12>")
		)
		(pad "42" smd rect
			(at 0 34.85007 270)
			(size 1.8034 0.508)
			(layers "B.Cu" "B.Mask" "B.Paste")
			(net "GND")
		)
		(pad "43" smd rect
			(at 0 35.699954 270)
			(size 1.8034 0.508)
			(layers "B.Cu" "B.Mask" "B.Paste")
			(net "M_E_DQ<30>")
		)
		(pad "44" smd rect
			(at 0 36.550092 270)
			(size 1.8034 0.508)
			(layers "B.Cu" "B.Mask" "B.Paste")
			(net "GND")
		)
		(pad "45" smd rect
			(at 0 37.399976 270)
			(size 1.8034 0.508)
			(layers "B.Cu" "B.Mask" "B.Paste")
			(net "M_E_DQ<26>")
		)
		(pad "46" smd rect
			(at 0 38.250114 270)
			(size 1.8034 0.508)
			(layers "B.Cu" "B.Mask" "B.Paste")
			(net "GND")
		)
		(pad "47" smd rect
			(at 0 39.099998 270)
			(size 1.8034 0.508)
			(layers "B.Cu" "B.Mask" "B.Paste")
			(net "M_E_ECC<4>")
		)
		(pad "48" smd rect
			(at 0 39.949882 270)
			(size 1.8034 0.508)
			(layers "B.Cu" "B.Mask" "B.Paste")
			(net "GND")
		)
		(pad "49" smd rect
			(at 0 40.80002 270)
			(size 1.8034 0.508)
			(layers "B.Cu" "B.Mask" "B.Paste")
			(net "M_E_ECC<0>")
		)
		(pad "50" smd rect
			(at 0 41.649904 270)
			(size 1.8034 0.508)
			(layers "B.Cu" "B.Mask" "B.Paste")
			(net "GND")
		)
		(pad "51" smd rect
			(at 0 42.500042 270)
			(size 1.8034 0.508)
			(layers "B.Cu" "B.Mask" "B.Paste")
			(net "M_E_DQS_DP<17>")
		)
		(pad "52" smd rect
			(at 0 43.349926 270)
			(size 1.8034 0.508)
			(layers "B.Cu" "B.Mask" "B.Paste")
			(net "M_E_DQS_DN<17>")
		)
		(pad "53" smd rect
			(at 0 44.200064 270)
			(size 1.8034 0.508)
			(layers "B.Cu" "B.Mask" "B.Paste")
			(net "GND")
		)
		(pad "54" smd rect
			(at 0 45.049948 270)
			(size 1.8034 0.508)
			(layers "B.Cu" "B.Mask" "B.Paste")
			(net "M_E_ECC<6>")
		)
		(pad "55" smd rect
			(at 0 45.900086 270)
			(size 1.8034 0.508)
			(layers "B.Cu" "B.Mask" "B.Paste")
			(net "GND")
		)
		(pad "56" smd rect
			(at 0 46.74997 270)
			(size 1.8034 0.508)
			(layers "B.Cu" "B.Mask" "B.Paste")
			(net "M_E_ECC<2>")
		)
		(pad "57" smd rect
			(at 0 47.600108 270)
			(size 1.8034 0.508)
			(layers "B.Cu" "B.Mask" "B.Paste")
			(net "GND")
		)
		(pad "58" smd rect
			(at 0 48.449992 270)
			(size 1.8034 0.508)
			(layers "B.Cu" "B.Mask" "B.Paste")
			(net "M_DEF_RST_N")
		)
		(pad "59" smd rect
			(at 0 49.299876 270)
			(size 1.8034 0.508)
			(layers "B.Cu" "B.Mask" "B.Paste")
			(net "PVDDQ_DEF")
		)
		(pad "60" smd rect
			(at 0 50.150014 270)
			(size 1.8034 0.508)
			(layers "B.Cu" "B.Mask" "B.Paste")
			(net "M_E_CKE<2>")
		)
		(pad "61" smd rect
			(at 0 50.999898 270)
			(size 1.8034 0.508)
			(layers "B.Cu" "B.Mask" "B.Paste")
			(net "PVDDQ_DEF")
		)
		(pad "62" smd rect
			(at 0 51.850036 270)
			(size 1.8034 0.508)
			(layers "B.Cu" "B.Mask" "B.Paste")
			(net "M_E_ACT_N")
		)
		(pad "63" smd rect
			(at 0 52.69992 270)
			(size 1.8034 0.508)
			(layers "B.Cu" "B.Mask" "B.Paste")
			(net "M_E_BG<0>")
		)
		(pad "64" smd rect
			(at 0 53.550058 270)
			(size 1.8034 0.508)
			(layers "B.Cu" "B.Mask" "B.Paste")
			(net "PVDDQ_DEF")
		)
		(pad "65" smd rect
			(at 0 54.399942 270)
			(size 1.8034 0.508)
			(layers "B.Cu" "B.Mask" "B.Paste")
			(net "M_E_MA<12>")
		)
		(pad "66" smd rect
			(at 0 55.25008 270)
			(size 1.8034 0.508)
			(layers "B.Cu" "B.Mask" "B.Paste")
			(net "M_E_MA<9>")
		)
		(pad "67" smd rect
			(at 0 56.099964 270)
			(size 1.8034 0.508)
			(layers "B.Cu" "B.Mask" "B.Paste")
			(net "PVDDQ_DEF")
		)
		(pad "68" smd rect
			(at 0 56.950102 270)
			(size 1.8034 0.508)
			(layers "B.Cu" "B.Mask" "B.Paste")
			(net "M_E_MA<8>")
		)
		(pad "69" smd rect
			(at 0 57.799986 270)
			(size 1.8034 0.508)
			(layers "B.Cu" "B.Mask" "B.Paste")
			(net "M_E_MA<6>")
		)
		(pad "70" smd rect
			(at 0 58.650124 270)
			(size 1.8034 0.508)
			(layers "B.Cu" "B.Mask" "B.Paste")
			(net "PVDDQ_DEF")
		)
		(pad "71" smd rect
			(at 0 59.500008 270)
			(size 1.8034 0.508)
			(layers "B.Cu" "B.Mask" "B.Paste")
			(net "M_E_MA<3>")
		)
		(pad "72" smd rect
			(at 0 60.349892 270)
			(size 1.8034 0.508)
			(layers "B.Cu" "B.Mask" "B.Paste")
			(net "M_E_MA<1>")
		)
		(pad "73" smd rect
			(at 0 61.20003 270)
			(size 1.8034 0.508)
			(layers "B.Cu" "B.Mask" "B.Paste")
			(net "PVDDQ_DEF")
		)
		(pad "74" smd rect
			(at 0 62.049914 270)
			(size 1.8034 0.508)
			(layers "B.Cu" "B.Mask" "B.Paste")
			(net "M_E_CLK_DP<2>")
		)
		(pad "75" smd rect
			(at 0 62.900052 270)
			(size 1.8034 0.508)
			(layers "B.Cu" "B.Mask" "B.Paste")
			(net "M_E_CLK_DN<2>")
		)
		(pad "76" smd rect
			(at 0 63.749936 270)
			(size 1.8034 0.508)
			(layers "B.Cu" "B.Mask" "B.Paste")
			(net "PVDDQ_DEF")
		)
		(pad "77" smd rect
			(at 0 64.600074 270)
			(size 1.8034 0.508)
			(layers "B.Cu" "B.Mask" "B.Paste")
			(net "PVTT_DEF")
		)
		(pad "78" smd rect
			(at 0 70.550024 270)
			(size 1.8034 0.508)
			(layers "B.Cu" "B.Mask" "B.Paste")
			(net "FM_DIMM_EVENT_COD_N")
		)
		(pad "79" smd rect
			(at 0 71.399908 270)
			(size 1.8034 0.508)
			(layers "B.Cu" "B.Mask" "B.Paste")
			(net "M_E_MA<0>")
		)
		(pad "80" smd rect
			(at 0 72.250046 270)
			(size 1.8034 0.508)
			(layers "B.Cu" "B.Mask" "B.Paste")
			(net "PVDDQ_DEF")
		)
		(pad "81" smd rect
			(at 0 73.09993 270)
			(size 1.8034 0.508)
			(layers "B.Cu" "B.Mask" "B.Paste")
			(net "M_E_BA<0>")
		)
		(pad "82" smd rect
			(at 0 73.950068 270)
			(size 1.8034 0.508)
			(layers "B.Cu" "B.Mask" "B.Paste")
			(net "M_E_MA<16>")
		)
		(pad "83" smd rect
			(at 0 74.799952 270)
			(size 1.8034 0.508)
			(layers "B.Cu" "B.Mask" "B.Paste")
			(net "PVDDQ_DEF")
		)
		(pad "84" smd rect
			(at 0 75.65009 270)
			(size 1.8034 0.508)
			(layers "B.Cu" "B.Mask" "B.Paste")
			(net "M_E_CS_N<4>")
		)
		(pad "85" smd rect
			(at 0 76.499974 270)
			(size 1.8034 0.508)
			(layers "B.Cu" "B.Mask" "B.Paste")
			(net "PVDDQ_DEF")
		)
		(pad "86" smd rect
			(at 0 77.350112 270)
			(size 1.8034 0.508)
			(layers "B.Cu" "B.Mask" "B.Paste")
			(net "M_E_MA<15>")
		)
		(pad "87" smd rect
			(at 0 78.199996 270)
			(size 1.8034 0.508)
			(layers "B.Cu" "B.Mask" "B.Paste")
			(net "M_E_ODT<2>")
		)
		(pad "88" smd rect
			(at 0 79.04988 270)
			(size 1.8034 0.508)
			(layers "B.Cu" "B.Mask" "B.Paste")
			(net "PVDDQ_DEF")
		)
		(pad "89" smd rect
			(at 0 79.900018 270)
			(size 1.8034 0.508)
			(layers "B.Cu" "B.Mask" "B.Paste")
			(net "M_E_CS_N<5>")
		)
		(pad "90" smd rect
			(at 0 80.749902 270)
			(size 1.8034 0.508)
			(layers "B.Cu" "B.Mask" "B.Paste")
			(net "PVDDQ_DEF")
		)
		(pad "91" smd rect
			(at 0 81.60004 270)
			(size 1.8034 0.508)
			(layers "B.Cu" "B.Mask" "B.Paste")
			(net "M_E_ODT<3>")
		)
		(pad "92" smd rect
			(at 0 82.449924 270)
			(size 1.8034 0.508)
			(layers "B.Cu" "B.Mask" "B.Paste")
			(net "PVDDQ_DEF")
		)
		(pad "93" smd rect
			(at 0 83.300062 270)
			(size 1.8034 0.508)
			(layers "B.Cu" "B.Mask" "B.Paste")
			(net "M_E_CS_N<6>")
		)
		(pad "94" smd rect
			(at 0 84.149946 270)
			(size 1.8034 0.508)
			(layers "B.Cu" "B.Mask" "B.Paste")
			(net "GND")
		)
		(pad "95" smd rect
			(at 0 85.000084 270)
			(size 1.8034 0.508)
			(layers "B.Cu" "B.Mask" "B.Paste")
			(net "M_E_DQ<36>")
		)
		(pad "96" smd rect
			(at 0 85.849968 270)
			(size 1.8034 0.508)
			(layers "B.Cu" "B.Mask" "B.Paste")
			(net "GND")
		)
		(pad "97" smd rect
			(at 0 86.700106 270)
			(size 1.8034 0.508)
			(layers "B.Cu" "B.Mask" "B.Paste")
			(net "M_E_DQ<32>")
		)
		(pad "98" smd rect
			(at 0 87.54999 270)
			(size 1.8034 0.508)
			(layers "B.Cu" "B.Mask" "B.Paste")
			(net "GND")
		)
		(pad "99" smd rect
			(at 0 88.399874 270)
			(size 1.8034 0.508)
			(layers "B.Cu" "B.Mask" "B.Paste")
			(net "M_E_DQS_DP<13>")
		)
		(pad "100" smd rect
			(at 0 89.250012 270)
			(size 1.8034 0.508)
			(layers "B.Cu" "B.Mask" "B.Paste")
			(net "M_E_DQS_DN<13>")
		)
		(pad "101" smd rect
			(at 0 90.099896 270)
			(size 1.8034 0.508)
			(layers "B.Cu" "B.Mask" "B.Paste")
			(net "GND")
		)
		(pad "102" smd rect
			(at 0 90.950034 270)
			(size 1.8034 0.508)
			(layers "B.Cu" "B.Mask" "B.Paste")
			(net "M_E_DQ<38>")
		)
		(pad "103" smd rect
			(at 0 91.799918 270)
			(size 1.8034 0.508)
			(layers "B.Cu" "B.Mask" "B.Paste")
			(net "GND")
		)
		(pad "104" smd rect
			(at 0 92.650056 270)
			(size 1.8034 0.508)
			(layers "B.Cu" "B.Mask" "B.Paste")
			(net "M_E_DQ<34>")
		)
		(pad "105" smd rect
			(at 0 93.49994 270)
			(size 1.8034 0.508)
			(layers "B.Cu" "B.Mask" "B.Paste")
			(net "GND")
		)
		(pad "106" smd rect
			(at 0 94.350078 270)
			(size 1.8034 0.508)
			(layers "B.Cu" "B.Mask" "B.Paste")
			(net "M_E_DQ<44>")
		)
		(pad "107" smd rect
			(at 0 95.199962 270)
			(size 1.8034 0.508)
			(layers "B.Cu" "B.Mask" "B.Paste")
			(net "GND")
		)
		(pad "108" smd rect
			(at 0 96.0501 270)
			(size 1.8034 0.508)
			(layers "B.Cu" "B.Mask" "B.Paste")
			(net "M_E_DQ<40>")
		)
		(pad "109" smd rect
			(at 0 96.899984 270)
			(size 1.8034 0.508)
			(layers "B.Cu" "B.Mask" "B.Paste")
			(net "GND")
		)
		(pad "110" smd rect
			(at 0 97.750122 270)
			(size 1.8034 0.508)
			(layers "B.Cu" "B.Mask" "B.Paste")
			(net "M_E_DQS_DP<14>")
		)
		(pad "111" smd rect
			(at 0 98.600006 270)
			(size 1.8034 0.508)
			(layers "B.Cu" "B.Mask" "B.Paste")
			(net "M_E_DQS_DN<14>")
		)
		(pad "112" smd rect
			(at 0 99.44989 270)
			(size 1.8034 0.508)
			(layers "B.Cu" "B.Mask" "B.Paste")
			(net "GND")
		)
		(pad "113" smd rect
			(at 0 100.300028 270)
			(size 1.8034 0.508)
			(layers "B.Cu" "B.Mask" "B.Paste")
			(net "M_E_DQ<46>")
		)
		(pad "114" smd rect
			(at 0 101.149912 270)
			(size 1.8034 0.508)
			(layers "B.Cu" "B.Mask" "B.Paste")
			(net "GND")
		)
		(pad "115" smd rect
			(at 0 102.00005 270)
			(size 1.8034 0.508)
			(layers "B.Cu" "B.Mask" "B.Paste")
			(net "M_E_DQ<42>")
		)
		(pad "116" smd rect
			(at 0 102.849934 270)
			(size 1.8034 0.508)
			(layers "B.Cu" "B.Mask" "B.Paste")
			(net "GND")
		)
		(pad "117" smd rect
			(at 0 103.700072 270)
			(size 1.8034 0.508)
			(layers "B.Cu" "B.Mask" "B.Paste")
			(net "M_E_DQ<52>")
		)
		(pad "118" smd rect
			(at 0 104.549956 270)
			(size 1.8034 0.508)
			(layers "B.Cu" "B.Mask" "B.Paste")
			(net "GND")
		)
		(pad "119" smd rect
			(at 0 105.400094 270)
			(size 1.8034 0.508)
			(layers "B.Cu" "B.Mask" "B.Paste")
			(net "M_E_DQ<48>")
		)
		(pad "120" smd rect
			(at 0 106.249978 270)
			(size 1.8034 0.508)
			(layers "B.Cu" "B.Mask" "B.Paste")
			(net "GND")
		)
		(pad "121" smd rect
			(at 0 107.100116 270)
			(size 1.8034 0.508)
			(layers "B.Cu" "B.Mask" "B.Paste")
			(net "M_E_DQS_DP<15>")
		)
		(pad "122" smd rect
			(at 0 107.95 270)
			(size 1.8034 0.508)
			(layers "B.Cu" "B.Mask" "B.Paste")
			(net "M_E_DQS_DN<15>")
		)
		(pad "123" smd rect
			(at 0 108.799884 270)
			(size 1.8034 0.508)
			(layers "B.Cu" "B.Mask" "B.Paste")
			(net "GND")
		)
		(pad "124" smd rect
			(at 0 109.650022 270)
			(size 1.8034 0.508)
			(layers "B.Cu" "B.Mask" "B.Paste")
			(net "M_E_DQ<54>")
		)
		(pad "125" smd rect
			(at 0 110.499906 270)
			(size 1.8034 0.508)
			(layers "B.Cu" "B.Mask" "B.Paste")
			(net "GND")
		)
		(pad "126" smd rect
			(at 0 111.350044 270)
			(size 1.8034 0.508)
			(layers "B.Cu" "B.Mask" "B.Paste")
			(net "M_E_DQ<50>")
		)
		(pad "127" smd rect
			(at 0 112.199928 270)
			(size 1.8034 0.508)
			(layers "B.Cu" "B.Mask" "B.Paste")
			(net "GND")
		)
		(pad "128" smd rect
			(at 0 113.050066 270)
			(size 1.8034 0.508)
			(layers "B.Cu" "B.Mask" "B.Paste")
			(net "M_E_DQ<60>")
		)
		(pad "129" smd rect
			(at 0 113.89995 270)
			(size 1.8034 0.508)
			(layers "B.Cu" "B.Mask" "B.Paste")
			(net "GND")
		)
		(pad "130" smd rect
			(at 0 114.750088 270)
			(size 1.8034 0.508)
			(layers "B.Cu" "B.Mask" "B.Paste")
			(net "M_E_DQ<56>")
		)
		(pad "131" smd rect
			(at 0 115.599972 270)
			(size 1.8034 0.508)
			(layers "B.Cu" "B.Mask" "B.Paste")
			(net "GND")
		)
		(pad "132" smd rect
			(at 0 116.45011 270)
			(size 1.8034 0.508)
			(layers "B.Cu" "B.Mask" "B.Paste")
			(net "M_E_DQS_DP<16>")
		)
		(pad "133" smd rect
			(at 0 117.299994 270)
			(size 1.8034 0.508)
			(layers "B.Cu" "B.Mask" "B.Paste")
			(net "M_E_DQS_DN<16>")
		)
		(pad "134" smd rect
			(at 0 118.149878 270)
			(size 1.8034 0.508)
			(layers "B.Cu" "B.Mask" "B.Paste")
			(net "GND")
		)
		(pad "135" smd rect
			(at 0 119.000016 270)
			(size 1.8034 0.508)
			(layers "B.Cu" "B.Mask" "B.Paste")
			(net "M_E_DQ<62>")
		)
		(pad "136" smd rect
			(at 0 119.8499 270)
			(size 1.8034 0.508)
			(layers "B.Cu" "B.Mask" "B.Paste")
			(net "GND")
		)
		(pad "137" smd rect
			(at 0 120.700038 270)
			(size 1.8034 0.508)
			(layers "B.Cu" "B.Mask" "B.Paste")
			(net "M_E_DQ<58>")
		)
		(pad "138" smd rect
			(at 0 121.549922 270)
			(size 1.8034 0.508)
			(layers "B.Cu" "B.Mask" "B.Paste")
			(net "GND")
		)
		(pad "139" smd rect
			(at 0 122.40006 270)
			(size 1.8034 0.508)
			(layers "B.Cu" "B.Mask" "B.Paste")
			(net "PVPP_DEF")
		)
		(pad "140" smd rect
			(at 0 123.249944 270)
			(size 1.8034 0.508)
			(layers "B.Cu" "B.Mask" "B.Paste")
			(net "PVPP_DEF")
		)
		(pad "141" smd rect
			(at 0 124.100082 270)
			(size 1.8034 0.508)
			(layers "B.Cu" "B.Mask" "B.Paste")
			(net "SMB_DDR_DEF_VPP_SCL")
		)
		(pad "142" smd rect
			(at 0 124.949966 270)
			(size 1.8034 0.508)
			(layers "B.Cu" "B.Mask" "B.Paste")
			(net "PVPP_DEF")
		)
		(pad "143" smd rect
			(at 0 125.800104 270)
			(size 1.8034 0.508)
			(layers "B.Cu" "B.Mask" "B.Paste")
			(net "PVPP_DEF")
		)
		(pad "144" smd rect
			(at 0 126.649988 270)
			(size 1.8034 0.508)
			(layers "B.Cu" "B.Mask" "B.Paste")
			(net "TP_CH_E_DIMM_E1_RFU_2")
		)
		(pad "145" smd rect
			(at -4.59994 0 270)
			(size 1.8034 0.508)
			(layers "B.Cu" "B.Mask" "B.Paste")
			(net "P12V_NVDIMM_DEF")
		)
		(pad "146" smd rect
			(at -4.59994 0.849884 270)
			(size 1.8034 0.508)
			(layers "B.Cu" "B.Mask" "B.Paste")
			(net "M_E_VREF")
		)
		(pad "147" smd rect
			(at -4.59994 1.700022 270)
			(size 1.8034 0.508)
			(layers "B.Cu" "B.Mask" "B.Paste")
			(net "GND")
		)
		(pad "148" smd rect
			(at -4.59994 2.549906 270)
			(size 1.8034 0.508)
			(layers "B.Cu" "B.Mask" "B.Paste")
			(net "M_E_DQ<5>")
		)
		(pad "149" smd rect
			(at -4.59994 3.400044 270)
			(size 1.8034 0.508)
			(layers "B.Cu" "B.Mask" "B.Paste")
			(net "GND")
		)
		(pad "150" smd rect
			(at -4.59994 4.249928 270)
			(size 1.8034 0.508)
			(layers "B.Cu" "B.Mask" "B.Paste")
			(net "M_E_DQ<1>")
		)
		(pad "151" smd rect
			(at -4.59994 5.100066 270)
			(size 1.8034 0.508)
			(layers "B.Cu" "B.Mask" "B.Paste")
			(net "GND")
		)
		(pad "152" smd rect
			(at -4.59994 5.94995 270)
			(size 1.8034 0.508)
			(layers "B.Cu" "B.Mask" "B.Paste")
			(net "M_E_DQS_DN<0>")
		)
		(pad "153" smd rect
			(at -4.59994 6.800088 270)
			(size 1.8034 0.508)
			(layers "B.Cu" "B.Mask" "B.Paste")
			(net "M_E_DQS_DP<0>")
		)
		(pad "154" smd rect
			(at -4.59994 7.649972 270)
			(size 1.8034 0.508)
			(layers "B.Cu" "B.Mask" "B.Paste")
			(net "GND")
		)
		(pad "155" smd rect
			(at -4.59994 8.50011 270)
			(size 1.8034 0.508)
			(layers "B.Cu" "B.Mask" "B.Paste")
			(net "M_E_DQ<7>")
		)
		(pad "156" smd rect
			(at -4.59994 9.349994 270)
			(size 1.8034 0.508)
			(layers "B.Cu" "B.Mask" "B.Paste")
			(net "GND")
		)
		(pad "157" smd rect
			(at -4.59994 10.199878 270)
			(size 1.8034 0.508)
			(layers "B.Cu" "B.Mask" "B.Paste")
			(net "M_E_DQ<3>")
		)
		(pad "158" smd rect
			(at -4.59994 11.050016 270)
			(size 1.8034 0.508)
			(layers "B.Cu" "B.Mask" "B.Paste")
			(net "GND")
		)
		(pad "159" smd rect
			(at -4.59994 11.8999 270)
			(size 1.8034 0.508)
			(layers "B.Cu" "B.Mask" "B.Paste")
			(net "M_E_DQ<13>")
		)
		(pad "160" smd rect
			(at -4.59994 12.750038 270)
			(size 1.8034 0.508)
			(layers "B.Cu" "B.Mask" "B.Paste")
			(net "GND")
		)
		(pad "161" smd rect
			(at -4.59994 13.599922 270)
			(size 1.8034 0.508)
			(layers "B.Cu" "B.Mask" "B.Paste")
			(net "M_E_DQ<9>")
		)
		(pad "162" smd rect
			(at -4.59994 14.45006 270)
			(size 1.8034 0.508)
			(layers "B.Cu" "B.Mask" "B.Paste")
			(net "GND")
		)
		(pad "163" smd rect
			(at -4.59994 15.299944 270)
			(size 1.8034 0.508)
			(layers "B.Cu" "B.Mask" "B.Paste")
			(net "M_E_DQS_DN<1>")
		)
		(pad "164" smd rect
			(at -4.59994 16.150082 270)
			(size 1.8034 0.508)
			(layers "B.Cu" "B.Mask" "B.Paste")
			(net "M_E_DQS_DP<1>")
		)
		(pad "165" smd rect
			(at -4.59994 16.999966 270)
			(size 1.8034 0.508)
			(layers "B.Cu" "B.Mask" "B.Paste")
			(net "GND")
		)
		(pad "166" smd rect
			(at -4.59994 17.850104 270)
			(size 1.8034 0.508)
			(layers "B.Cu" "B.Mask" "B.Paste")
			(net "M_E_DQ<15>")
		)
		(pad "167" smd rect
			(at -4.59994 18.699988 270)
			(size 1.8034 0.508)
			(layers "B.Cu" "B.Mask" "B.Paste")
			(net "GND")
		)
		(pad "168" smd rect
			(at -4.59994 19.550126 270)
			(size 1.8034 0.508)
			(layers "B.Cu" "B.Mask" "B.Paste")
			(net "M_E_DQ<11>")
		)
		(pad "169" smd rect
			(at -4.59994 20.40001 270)
			(size 1.8034 0.508)
			(layers "B.Cu" "B.Mask" "B.Paste")
			(net "GND")
		)
		(pad "170" smd rect
			(at -4.59994 21.249894 270)
			(size 1.8034 0.508)
			(layers "B.Cu" "B.Mask" "B.Paste")
			(net "M_E_DQ<21>")
		)
		(pad "171" smd rect
			(at -4.59994 22.100032 270)
			(size 1.8034 0.508)
			(layers "B.Cu" "B.Mask" "B.Paste")
			(net "GND")
		)
		(pad "172" smd rect
			(at -4.59994 22.949916 270)
			(size 1.8034 0.508)
			(layers "B.Cu" "B.Mask" "B.Paste")
			(net "M_E_DQ<17>")
		)
		(pad "173" smd rect
			(at -4.59994 23.800054 270)
			(size 1.8034 0.508)
			(layers "B.Cu" "B.Mask" "B.Paste")
			(net "GND")
		)
		(pad "174" smd rect
			(at -4.59994 24.649938 270)
			(size 1.8034 0.508)
			(layers "B.Cu" "B.Mask" "B.Paste")
			(net "M_E_DQS_DN<2>")
		)
		(pad "175" smd rect
			(at -4.59994 25.500076 270)
			(size 1.8034 0.508)
			(layers "B.Cu" "B.Mask" "B.Paste")
			(net "M_E_DQS_DP<2>")
		)
		(pad "176" smd rect
			(at -4.59994 26.34996 270)
			(size 1.8034 0.508)
			(layers "B.Cu" "B.Mask" "B.Paste")
			(net "GND")
		)
		(pad "177" smd rect
			(at -4.59994 27.200098 270)
			(size 1.8034 0.508)
			(layers "B.Cu" "B.Mask" "B.Paste")
			(net "M_E_DQ<23>")
		)
		(pad "178" smd rect
			(at -4.59994 28.049982 270)
			(size 1.8034 0.508)
			(layers "B.Cu" "B.Mask" "B.Paste")
			(net "GND")
		)
		(pad "179" smd rect
			(at -4.59994 28.90012 270)
			(size 1.8034 0.508)
			(layers "B.Cu" "B.Mask" "B.Paste")
			(net "M_E_DQ<19>")
		)
		(pad "180" smd rect
			(at -4.59994 29.750004 270)
			(size 1.8034 0.508)
			(layers "B.Cu" "B.Mask" "B.Paste")
			(net "GND")
		)
		(pad "181" smd rect
			(at -4.59994 30.599888 270)
			(size 1.8034 0.508)
			(layers "B.Cu" "B.Mask" "B.Paste")
			(net "M_E_DQ<29>")
		)
		(pad "182" smd rect
			(at -4.59994 31.450026 270)
			(size 1.8034 0.508)
			(layers "B.Cu" "B.Mask" "B.Paste")
			(net "GND")
		)
		(pad "183" smd rect
			(at -4.59994 32.29991 270)
			(size 1.8034 0.508)
			(layers "B.Cu" "B.Mask" "B.Paste")
			(net "M_E_DQ<25>")
		)
		(pad "184" smd rect
			(at -4.59994 33.150048 270)
			(size 1.8034 0.508)
			(layers "B.Cu" "B.Mask" "B.Paste")
			(net "GND")
		)
		(pad "185" smd rect
			(at -4.59994 33.999932 270)
			(size 1.8034 0.508)
			(layers "B.Cu" "B.Mask" "B.Paste")
			(net "M_E_DQS_DN<3>")
		)
		(pad "186" smd rect
			(at -4.59994 34.85007 270)
			(size 1.8034 0.508)
			(layers "B.Cu" "B.Mask" "B.Paste")
			(net "M_E_DQS_DP<3>")
		)
		(pad "187" smd rect
			(at -4.59994 35.699954 270)
			(size 1.8034 0.508)
			(layers "B.Cu" "B.Mask" "B.Paste")
			(net "GND")
		)
		(pad "188" smd rect
			(at -4.59994 36.550092 270)
			(size 1.8034 0.508)
			(layers "B.Cu" "B.Mask" "B.Paste")
			(net "M_E_DQ<31>")
		)
		(pad "189" smd rect
			(at -4.59994 37.399976 270)
			(size 1.8034 0.508)
			(layers "B.Cu" "B.Mask" "B.Paste")
			(net "GND")
		)
		(pad "190" smd rect
			(at -4.59994 38.250114 270)
			(size 1.8034 0.508)
			(layers "B.Cu" "B.Mask" "B.Paste")
			(net "M_E_DQ<27>")
		)
		(pad "191" smd rect
			(at -4.59994 39.099998 270)
			(size 1.8034 0.508)
			(layers "B.Cu" "B.Mask" "B.Paste")
			(net "GND")
		)
		(pad "192" smd rect
			(at -4.59994 39.949882 270)
			(size 1.8034 0.508)
			(layers "B.Cu" "B.Mask" "B.Paste")
			(net "M_E_ECC<5>")
		)
		(pad "193" smd rect
			(at -4.59994 40.80002 270)
			(size 1.8034 0.508)
			(layers "B.Cu" "B.Mask" "B.Paste")
			(net "GND")
		)
		(pad "194" smd rect
			(at -4.59994 41.649904 270)
			(size 1.8034 0.508)
			(layers "B.Cu" "B.Mask" "B.Paste")
			(net "M_E_ECC<1>")
		)
		(pad "195" smd rect
			(at -4.59994 42.500042 270)
			(size 1.8034 0.508)
			(layers "B.Cu" "B.Mask" "B.Paste")
			(net "GND")
		)
		(pad "196" smd rect
			(at -4.59994 43.349926 270)
			(size 1.8034 0.508)
			(layers "B.Cu" "B.Mask" "B.Paste")
			(net "M_E_DQS_DN<8>")
		)
		(pad "197" smd rect
			(at -4.59994 44.200064 270)
			(size 1.8034 0.508)
			(layers "B.Cu" "B.Mask" "B.Paste")
			(net "M_E_DQS_DP<8>")
		)
		(pad "198" smd rect
			(at -4.59994 45.049948 270)
			(size 1.8034 0.508)
			(layers "B.Cu" "B.Mask" "B.Paste")
			(net "GND")
		)
		(pad "199" smd rect
			(at -4.59994 45.900086 270)
			(size 1.8034 0.508)
			(layers "B.Cu" "B.Mask" "B.Paste")
			(net "M_E_ECC<7>")
		)
		(pad "200" smd rect
			(at -4.59994 46.74997 270)
			(size 1.8034 0.508)
			(layers "B.Cu" "B.Mask" "B.Paste")
			(net "GND")
		)
		(pad "201" smd rect
			(at -4.59994 47.600108 270)
			(size 1.8034 0.508)
			(layers "B.Cu" "B.Mask" "B.Paste")
			(net "M_E_ECC<3>")
		)
		(pad "202" smd rect
			(at -4.59994 48.449992 270)
			(size 1.8034 0.508)
			(layers "B.Cu" "B.Mask" "B.Paste")
			(net "GND")
		)
		(pad "203" smd rect
			(at -4.59994 49.299876 270)
			(size 1.8034 0.508)
			(layers "B.Cu" "B.Mask" "B.Paste")
			(net "M_E_CKE<3>")
		)
		(pad "204" smd rect
			(at -4.59994 50.150014 270)
			(size 1.8034 0.508)
			(layers "B.Cu" "B.Mask" "B.Paste")
			(net "PVDDQ_DEF")
		)
		(pad "205" smd rect
			(at -4.59994 50.999898 270)
			(size 1.8034 0.508)
			(layers "B.Cu" "B.Mask" "B.Paste")
			(net "TP_CH_E_DIMM_E1_RFU_0")
		)
		(pad "206" smd rect
			(at -4.59994 51.850036 270)
			(size 1.8034 0.508)
			(layers "B.Cu" "B.Mask" "B.Paste")
			(net "PVDDQ_DEF")
		)
		(pad "207" smd rect
			(at -4.59994 52.69992 270)
			(size 1.8034 0.508)
			(layers "B.Cu" "B.Mask" "B.Paste")
			(net "M_E_BG<1>")
		)
		(pad "208" smd rect
			(at -4.59994 53.550058 270)
			(size 1.8034 0.508)
			(layers "B.Cu" "B.Mask" "B.Paste")
			(net "M_E_ALERT_N")
		)
		(pad "209" smd rect
			(at -4.59994 54.399942 270)
			(size 1.8034 0.508)
			(layers "B.Cu" "B.Mask" "B.Paste")
			(net "PVDDQ_DEF")
		)
		(pad "210" smd rect
			(at -4.59994 55.25008 270)
			(size 1.8034 0.508)
			(layers "B.Cu" "B.Mask" "B.Paste")
			(net "M_E_MA<11>")
		)
		(pad "211" smd rect
			(at -4.59994 56.099964 270)
			(size 1.8034 0.508)
			(layers "B.Cu" "B.Mask" "B.Paste")
			(net "M_E_MA<7>")
		)
		(pad "212" smd rect
			(at -4.59994 56.950102 270)
			(size 1.8034 0.508)
			(layers "B.Cu" "B.Mask" "B.Paste")
			(net "PVDDQ_DEF")
		)
		(pad "213" smd rect
			(at -4.59994 57.799986 270)
			(size 1.8034 0.508)
			(layers "B.Cu" "B.Mask" "B.Paste")
			(net "M_E_MA<5>")
		)
		(pad "214" smd rect
			(at -4.59994 58.650124 270)
			(size 1.8034 0.508)
			(layers "B.Cu" "B.Mask" "B.Paste")
			(net "M_E_MA<4>")
		)
		(pad "215" smd rect
			(at -4.59994 59.500008 270)
			(size 1.8034 0.508)
			(layers "B.Cu" "B.Mask" "B.Paste")
			(net "PVDDQ_DEF")
		)
		(pad "216" smd rect
			(at -4.59994 60.349892 270)
			(size 1.8034 0.508)
			(layers "B.Cu" "B.Mask" "B.Paste")
			(net "M_E_MA<2>")
		)
		(pad "217" smd rect
			(at -4.59994 61.20003 270)
			(size 1.8034 0.508)
			(layers "B.Cu" "B.Mask" "B.Paste")
			(net "PVDDQ_DEF")
		)
		(pad "218" smd rect
			(at -4.59994 62.049914 270)
			(size 1.8034 0.508)
			(layers "B.Cu" "B.Mask" "B.Paste")
			(net "M_E_CLK_DP<3>")
		)
		(pad "219" smd rect
			(at -4.59994 62.900052 270)
			(size 1.8034 0.508)
			(layers "B.Cu" "B.Mask" "B.Paste")
			(net "M_E_CLK_DN<3>")
		)
		(pad "220" smd rect
			(at -4.59994 63.749936 270)
			(size 1.8034 0.508)
			(layers "B.Cu" "B.Mask" "B.Paste")
			(net "PVDDQ_DEF")
		)
		(pad "221" smd rect
			(at -4.59994 64.600074 270)
			(size 1.8034 0.508)
			(layers "B.Cu" "B.Mask" "B.Paste")
			(net "PVTT_DEF")
		)
		(pad "222" smd rect
			(at -4.59994 70.550024 270)
			(size 1.8034 0.508)
			(layers "B.Cu" "B.Mask" "B.Paste")
			(net "M_E_PAR")
		)
		(pad "223" smd rect
			(at -4.59994 71.399908 270)
			(size 1.8034 0.508)
			(layers "B.Cu" "B.Mask" "B.Paste")
			(net "PVDDQ_DEF")
		)
		(pad "224" smd rect
			(at -4.59994 72.250046 270)
			(size 1.8034 0.508)
			(layers "B.Cu" "B.Mask" "B.Paste")
			(net "M_E_BA<1>")
		)
		(pad "225" smd rect
			(at -4.59994 73.09993 270)
			(size 1.8034 0.508)
			(layers "B.Cu" "B.Mask" "B.Paste")
			(net "M_E_MA<10>")
		)
		(pad "226" smd rect
			(at -4.59994 73.950068 270)
			(size 1.8034 0.508)
			(layers "B.Cu" "B.Mask" "B.Paste")
			(net "PVDDQ_DEF")
		)
		(pad "227" smd rect
			(at -4.59994 74.799952 270)
			(size 1.8034 0.508)
			(layers "B.Cu" "B.Mask" "B.Paste")
			(net "TP_CH_E_DIMM_E1_RFU_1")
		)
		(pad "228" smd rect
			(at -4.59994 75.65009 270)
			(size 1.8034 0.508)
			(layers "B.Cu" "B.Mask" "B.Paste")
			(net "M_E_MA<14>")
		)
		(pad "229" smd rect
			(at -4.59994 76.499974 270)
			(size 1.8034 0.508)
			(layers "B.Cu" "B.Mask" "B.Paste")
			(net "PVDDQ_DEF")
		)
		(pad "230" smd rect
			(at -4.59994 77.350112 270)
			(size 1.8034 0.508)
			(layers "B.Cu" "B.Mask" "B.Paste")
			(net "FM_ADR_COMPLETE_DEF_N")
		)
		(pad "231" smd rect
			(at -4.59994 78.199996 270)
			(size 1.8034 0.508)
			(layers "B.Cu" "B.Mask" "B.Paste")
			(net "PVDDQ_DEF")
		)
		(pad "232" smd rect
			(at -4.59994 79.04988 270)
			(size 1.8034 0.508)
			(layers "B.Cu" "B.Mask" "B.Paste")
			(net "M_E_MA<13>")
		)
		(pad "233" smd rect
			(at -4.59994 79.900018 270)
			(size 1.8034 0.508)
			(layers "B.Cu" "B.Mask" "B.Paste")
			(net "PVDDQ_DEF")
		)
		(pad "234" smd rect
			(at -4.59994 80.749902 270)
			(size 1.8034 0.508)
			(layers "B.Cu" "B.Mask" "B.Paste")
			(net "M_E_MA<17>")
		)
		(pad "235" smd rect
			(at -4.59994 81.60004 270)
			(size 1.8034 0.508)
			(layers "B.Cu" "B.Mask" "B.Paste")
			(net "M_E_C<2>")
		)
		(pad "236" smd rect
			(at -4.59994 82.449924 270)
			(size 1.8034 0.508)
			(layers "B.Cu" "B.Mask" "B.Paste")
			(net "PVDDQ_DEF")
		)
		(pad "237" smd rect
			(at -4.59994 83.300062 270)
			(size 1.8034 0.508)
			(layers "B.Cu" "B.Mask" "B.Paste")
			(net "M_E_CS_N<7>")
		)
		(pad "238" smd rect
			(at -4.59994 84.149946 270)
			(size 1.8034 0.508)
			(layers "B.Cu" "B.Mask" "B.Paste")
			(net "GND")
		)
		(pad "239" smd rect
			(at -4.59994 85.000084 270)
			(size 1.8034 0.508)
			(layers "B.Cu" "B.Mask" "B.Paste")
			(net "GND")
		)
		(pad "240" smd rect
			(at -4.59994 85.849968 270)
			(size 1.8034 0.508)
			(layers "B.Cu" "B.Mask" "B.Paste")
			(net "M_E_DQ<37>")
		)
		(pad "241" smd rect
			(at -4.59994 86.700106 270)
			(size 1.8034 0.508)
			(layers "B.Cu" "B.Mask" "B.Paste")
			(net "GND")
		)
		(pad "242" smd rect
			(at -4.59994 87.54999 270)
			(size 1.8034 0.508)
			(layers "B.Cu" "B.Mask" "B.Paste")
			(net "M_E_DQ<33>")
		)
		(pad "243" smd rect
			(at -4.59994 88.399874 270)
			(size 1.8034 0.508)
			(layers "B.Cu" "B.Mask" "B.Paste")
			(net "GND")
		)
		(pad "244" smd rect
			(at -4.59994 89.250012 270)
			(size 1.8034 0.508)
			(layers "B.Cu" "B.Mask" "B.Paste")
			(net "M_E_DQS_DN<4>")
		)
		(pad "245" smd rect
			(at -4.59994 90.099896 270)
			(size 1.8034 0.508)
			(layers "B.Cu" "B.Mask" "B.Paste")
			(net "M_E_DQS_DP<4>")
		)
		(pad "246" smd rect
			(at -4.59994 90.950034 270)
			(size 1.8034 0.508)
			(layers "B.Cu" "B.Mask" "B.Paste")
			(net "GND")
		)
		(pad "247" smd rect
			(at -4.59994 91.799918 270)
			(size 1.8034 0.508)
			(layers "B.Cu" "B.Mask" "B.Paste")
			(net "M_E_DQ<39>")
		)
		(pad "248" smd rect
			(at -4.59994 92.650056 270)
			(size 1.8034 0.508)
			(layers "B.Cu" "B.Mask" "B.Paste")
			(net "GND")
		)
		(pad "249" smd rect
			(at -4.59994 93.49994 270)
			(size 1.8034 0.508)
			(layers "B.Cu" "B.Mask" "B.Paste")
			(net "M_E_DQ<35>")
		)
		(pad "250" smd rect
			(at -4.59994 94.350078 270)
			(size 1.8034 0.508)
			(layers "B.Cu" "B.Mask" "B.Paste")
			(net "GND")
		)
		(pad "251" smd rect
			(at -4.59994 95.199962 270)
			(size 1.8034 0.508)
			(layers "B.Cu" "B.Mask" "B.Paste")
			(net "M_E_DQ<45>")
		)
		(pad "252" smd rect
			(at -4.59994 96.0501 270)
			(size 1.8034 0.508)
			(layers "B.Cu" "B.Mask" "B.Paste")
			(net "GND")
		)
		(pad "253" smd rect
			(at -4.59994 96.899984 270)
			(size 1.8034 0.508)
			(layers "B.Cu" "B.Mask" "B.Paste")
			(net "M_E_DQ<41>")
		)
		(pad "254" smd rect
			(at -4.59994 97.750122 270)
			(size 1.8034 0.508)
			(layers "B.Cu" "B.Mask" "B.Paste")
			(net "GND")
		)
		(pad "255" smd rect
			(at -4.59994 98.600006 270)
			(size 1.8034 0.508)
			(layers "B.Cu" "B.Mask" "B.Paste")
			(net "M_E_DQS_DN<5>")
		)
		(pad "256" smd rect
			(at -4.59994 99.44989 270)
			(size 1.8034 0.508)
			(layers "B.Cu" "B.Mask" "B.Paste")
			(net "M_E_DQS_DP<5>")
		)
		(pad "257" smd rect
			(at -4.59994 100.300028 270)
			(size 1.8034 0.508)
			(layers "B.Cu" "B.Mask" "B.Paste")
			(net "GND")
		)
		(pad "258" smd rect
			(at -4.59994 101.149912 270)
			(size 1.8034 0.508)
			(layers "B.Cu" "B.Mask" "B.Paste")
			(net "M_E_DQ<47>")
		)
		(pad "259" smd rect
			(at -4.59994 102.00005 270)
			(size 1.8034 0.508)
			(layers "B.Cu" "B.Mask" "B.Paste")
			(net "GND")
		)
		(pad "260" smd rect
			(at -4.59994 102.849934 270)
			(size 1.8034 0.508)
			(layers "B.Cu" "B.Mask" "B.Paste")
			(net "M_E_DQ<43>")
		)
		(pad "261" smd rect
			(at -4.59994 103.700072 270)
			(size 1.8034 0.508)
			(layers "B.Cu" "B.Mask" "B.Paste")
			(net "GND")
		)
		(pad "262" smd rect
			(at -4.59994 104.549956 270)
			(size 1.8034 0.508)
			(layers "B.Cu" "B.Mask" "B.Paste")
			(net "M_E_DQ<53>")
		)
		(pad "263" smd rect
			(at -4.59994 105.400094 270)
			(size 1.8034 0.508)
			(layers "B.Cu" "B.Mask" "B.Paste")
			(net "GND")
		)
		(pad "264" smd rect
			(at -4.59994 106.249978 270)
			(size 1.8034 0.508)
			(layers "B.Cu" "B.Mask" "B.Paste")
			(net "M_E_DQ<49>")
		)
		(pad "265" smd rect
			(at -4.59994 107.100116 270)
			(size 1.8034 0.508)
			(layers "B.Cu" "B.Mask" "B.Paste")
			(net "GND")
		)
		(pad "266" smd rect
			(at -4.59994 107.95 270)
			(size 1.8034 0.508)
			(layers "B.Cu" "B.Mask" "B.Paste")
			(net "M_E_DQS_DN<6>")
		)
		(pad "267" smd rect
			(at -4.59994 108.799884 270)
			(size 1.8034 0.508)
			(layers "B.Cu" "B.Mask" "B.Paste")
			(net "M_E_DQS_DP<6>")
		)
		(pad "268" smd rect
			(at -4.59994 109.650022 270)
			(size 1.8034 0.508)
			(layers "B.Cu" "B.Mask" "B.Paste")
			(net "GND")
		)
		(pad "269" smd rect
			(at -4.59994 110.499906 270)
			(size 1.8034 0.508)
			(layers "B.Cu" "B.Mask" "B.Paste")
			(net "M_E_DQ<55>")
		)
		(pad "270" smd rect
			(at -4.59994 111.350044 270)
			(size 1.8034 0.508)
			(layers "B.Cu" "B.Mask" "B.Paste")
			(net "GND")
		)
		(pad "271" smd rect
			(at -4.59994 112.199928 270)
			(size 1.8034 0.508)
			(layers "B.Cu" "B.Mask" "B.Paste")
			(net "M_E_DQ<51>")
		)
		(pad "272" smd rect
			(at -4.59994 113.050066 270)
			(size 1.8034 0.508)
			(layers "B.Cu" "B.Mask" "B.Paste")
			(net "GND")
		)
		(pad "273" smd rect
			(at -4.59994 113.89995 270)
			(size 1.8034 0.508)
			(layers "B.Cu" "B.Mask" "B.Paste")
			(net "M_E_DQ<61>")
		)
		(pad "274" smd rect
			(at -4.59994 114.750088 270)
			(size 1.8034 0.508)
			(layers "B.Cu" "B.Mask" "B.Paste")
			(net "GND")
		)
		(pad "275" smd rect
			(at -4.59994 115.599972 270)
			(size 1.8034 0.508)
			(layers "B.Cu" "B.Mask" "B.Paste")
			(net "M_E_DQ<57>")
		)
		(pad "276" smd rect
			(at -4.59994 116.45011 270)
			(size 1.8034 0.508)
			(layers "B.Cu" "B.Mask" "B.Paste")
			(net "GND")
		)
		(pad "277" smd rect
			(at -4.59994 117.299994 270)
			(size 1.8034 0.508)
			(layers "B.Cu" "B.Mask" "B.Paste")
			(net "M_E_DQS_DN<7>")
		)
		(pad "278" smd rect
			(at -4.59994 118.149878 270)
			(size 1.8034 0.508)
			(layers "B.Cu" "B.Mask" "B.Paste")
			(net "M_E_DQS_DP<7>")
		)
		(pad "279" smd rect
			(at -4.59994 119.000016 270)
			(size 1.8034 0.508)
			(layers "B.Cu" "B.Mask" "B.Paste")
			(net "GND")
		)
		(pad "280" smd rect
			(at -4.59994 119.8499 270)
			(size 1.8034 0.508)
			(layers "B.Cu" "B.Mask" "B.Paste")
			(net "M_E_DQ<63>")
		)
		(pad "281" smd rect
			(at -4.59994 120.700038 270)
			(size 1.8034 0.508)
			(layers "B.Cu" "B.Mask" "B.Paste")
			(net "GND")
		)
		(pad "282" smd rect
			(at -4.59994 121.549922 270)
			(size 1.8034 0.508)
			(layers "B.Cu" "B.Mask" "B.Paste")
			(net "M_E_DQ<59>")
		)
		(pad "283" smd rect
			(at -4.59994 122.40006 270)
			(size 1.8034 0.508)
			(layers "B.Cu" "B.Mask" "B.Paste")
			(net "GND")
		)
		(pad "284" smd rect
			(at -4.59994 123.249944 270)
			(size 1.8034 0.508)
			(layers "B.Cu" "B.Mask" "B.Paste")
			(net "PVPP_DEF")
		)
		(pad "285" smd rect
			(at -4.59994 124.100082 270)
			(size 1.8034 0.508)
			(layers "B.Cu" "B.Mask" "B.Paste")
			(net "SMB_DDR_DEF_VPP_SDA")
		)
		(pad "286" smd rect
			(at -4.59994 124.949966 270)
			(size 1.8034 0.508)
			(layers "B.Cu" "B.Mask" "B.Paste")
			(net "PVPP_DEF")
		)
		(pad "287" smd rect
			(at -4.59994 125.800104 270)
			(size 1.8034 0.508)
			(layers "B.Cu" "B.Mask" "B.Paste")
			(net "PVPP_DEF")
		)
		(pad "288" smd rect
			(at -4.59994 126.649988 270)
			(size 1.8034 0.508)
			(layers "B.Cu" "B.Mask" "B.Paste")
			(net "PVPP_DEF")
		)
	)
	(footprint ""
		(layer "B.Cu")
		(at 39.334694 -106.922316 -90)
		(property "Reference" "R1C2"
			(at 0 0 90)
			(layer "B.SilkS")
			(hide yes)
			(effects
				(font
					(size 1.27 1.27)
				)
				(justify mirror)
			)
		)
		(property "Value" ""
			(at 0 0 90)
			(layer "B.Fab")
			(effects
				(font
					(size 1.27 1.27)
				)
				(justify mirror)
			)
		)
		(duplicate_pad_numbers_are_jumpers no)
		(fp_poly
			(pts
				(xy 0.2794 -0.1016) (xy -0.2794 -0.1016) (xy -0.2794 0.9906) (xy 0.2794 0.9906)
			)
			(stroke
				(width 0)
				(type default)
			)
			(fill no)
			(layer "B.CrtYd")
		)
		(fp_line
			(start -0.2794 0.9906)
			(end -0.2794 -0.1016)
			(stroke
				(width 0.1)
				(type default)
			)
			(layer "B.Fab")
		)
		(fp_line
			(start 0.2794 0.9906)
			(end -0.2794 0.9906)
			(stroke
				(width 0.1)
				(type default)
			)
			(layer "B.Fab")
		)
		(fp_line
			(start -0.2794 -0.1016)
			(end 0.2794 -0.1016)
			(stroke
				(width 0.1)
				(type default)
			)
			(layer "B.Fab")
		)
		(fp_line
			(start 0.2794 -0.1016)
			(end 0.2794 0.9906)
			(stroke
				(width 0.1)
				(type default)
			)
			(layer "B.Fab")
		)
		(pad "1" smd rect
			(at 0 0 90)
			(size 0.508 0.508)
			(layers "B.Cu" "B.Mask" "B.Paste")
			(net "SVID_DIO1_CPU1")
		)
		(pad "2" smd rect
			(at 0 0.889 90)
			(size 0.508 0.508)
			(layers "B.Cu" "B.Mask" "B.Paste")
			(net "SVID_DIO1_CPU1_R")
		)
		(zone
			(layer "B.Cu")
			(hatch none 0.5)
			(connect_pads
				(clearance 0)
			)
			(min_thickness 0.25)
			(keepout
				(tracks not_allowed)
				(vias allowed)
				(pads allowed)
				(copperpour not_allowed)
				(footprints allowed)
			)
			(placement
				(enabled no)
				(sheetname "")
			)
			(fill
				(thermal_gap 0.5)
				(thermal_bridge_width 0.5)
				(island_removal_mode 0)
			)
			(polygon
				(pts
					(xy 38.699694 -106.668316) (xy 38.699694 -107.176316) (xy 39.080694 -107.176316) (xy 39.080694 -106.668316)
				)
			)
		)
		(zone
			(layer "B.Cu")
			(hatch none 0.5)
			(connect_pads
				(clearance 0)
			)
			(min_thickness 0.25)
			(keepout
				(tracks allowed)
				(vias not_allowed)
				(pads allowed)
				(copperpour not_allowed)
				(footprints allowed)
			)
			(placement
				(enabled no)
				(sheetname "")
			)
			(fill
				(thermal_gap 0.5)
				(thermal_bridge_width 0.5)
				(island_removal_mode 0)
			)
			(polygon
				(pts
					(xy 39.080694 -106.668316) (xy 39.080694 -107.176316) (xy 38.699694 -107.176316) (xy 38.699694 -106.668316)
				)
			)
		)
	)
	(footprint ""
		(layer "B.Cu")
		(at 370.1669 -103.6066 90)
		(property "Reference" "C3N30"
			(at 0 0 90)
			(layer "B.SilkS")
			(hide yes)
			(effects
				(font
					(size 1.27 1.27)
				)
				(justify mirror)
			)
		)
		(property "Value" ""
			(at 0 0 90)
			(layer "B.Fab")
			(effects
				(font
					(size 1.27 1.27)
				)
				(justify mirror)
			)
		)
		(duplicate_pad_numbers_are_jumpers no)
		(fp_poly
			(pts
				(xy 0.4953 -0.2032) (xy -0.4953 -0.2032) (xy -0.4953 1.6002) (xy 0.4953 1.6002)
			)
			(stroke
				(width 0)
				(type default)
			)
			(fill no)
			(layer "B.CrtYd")
		)
		(fp_line
			(start 0.4953 -0.2032)
			(end -0.4953 -0.2032)
			(stroke
				(width 0.1)
				(type default)
			)
			(layer "B.Fab")
		)
		(fp_line
			(start -0.4953 -0.2032)
			(end -0.4953 1.6002)
			(stroke
				(width 0.1)
				(type default)
			)
			(layer "B.Fab")
		)
		(fp_line
			(start 0.4953 1.6002)
			(end 0.4953 -0.2032)
			(stroke
				(width 0.1)
				(type default)
			)
			(layer "B.Fab")
		)
		(fp_line
			(start -0.4953 1.6002)
			(end 0.4953 1.6002)
			(stroke
				(width 0.1)
				(type default)
			)
			(layer "B.Fab")
		)
		(pad "1" smd rect
			(at 0 0 270)
			(size 0.762 0.889)
			(layers "B.Cu" "B.Mask" "B.Paste")
			(net "PVNN_PCH_STBY")
		)
		(pad "2" smd rect
			(at 0 1.397 270)
			(size 0.762 0.889)
			(layers "B.Cu" "B.Mask" "B.Paste")
			(net "GND")
		)
		(zone
			(layer "B.Cu")
			(hatch none 0.5)
			(connect_pads
				(clearance 0)
			)
			(min_thickness 0.25)
			(keepout
				(tracks not_allowed)
				(vias allowed)
				(pads allowed)
				(copperpour not_allowed)
				(footprints allowed)
			)
			(placement
				(enabled no)
				(sheetname "")
			)
			(fill
				(thermal_gap 0.5)
				(thermal_bridge_width 0.5)
				(island_removal_mode 0)
			)
			(polygon
				(pts
					(xy 370.6114 -103.9876) (xy 370.6114 -103.2256) (xy 371.1194 -103.2256) (xy 371.1194 -103.9876)
				)
			)
		)
	)
	(footprint ""
		(layer "B.Cu")
		(at 404.3045 -30.099 90)
		(property "Reference" "R25W114"
			(at 0.8382 -0.67818 90)
			(unlocked yes)
			(layer "B.SilkS")
			(effects
				(font
					(size 0.4064 0.254)
					(thickness 0.1524)
				)
				(justify left mirror)
			)
		)
		(property "Value" ""
			(at 0 0 90)
			(layer "B.Fab")
			(effects
				(font
					(size 1.27 1.27)
				)
				(justify mirror)
			)
		)
		(duplicate_pad_numbers_are_jumpers no)
		(fp_poly
			(pts
				(xy 0.2794 -0.1016) (xy -0.2794 -0.1016) (xy -0.2794 0.9906) (xy 0.2794 0.9906)
			)
			(stroke
				(width 0)
				(type default)
			)
			(fill no)
			(layer "B.CrtYd")
		)
		(fp_line
			(start 0.2794 -0.1016)
			(end 0.2794 0.9906)
			(stroke
				(width 0.1)
				(type default)
			)
			(layer "B.Fab")
		)
		(fp_line
			(start -0.2794 -0.1016)
			(end 0.2794 -0.1016)
			(stroke
				(width 0.1)
				(type default)
			)
			(layer "B.Fab")
		)
		(fp_line
			(start 0.2794 0.9906)
			(end -0.2794 0.9906)
			(stroke
				(width 0.1)
				(type default)
			)
			(layer "B.Fab")
		)
		(fp_line
			(start -0.2794 0.9906)
			(end -0.2794 -0.1016)
			(stroke
				(width 0.1)
				(type default)
			)
			(layer "B.Fab")
		)
		(pad "1" smd rect
			(at 0 0 270)
			(size 0.508 0.508)
			(layers "B.Cu" "B.Mask" "B.Paste")
			(net "P3V3_STBY")
		)
		(pad "2" smd rect
			(at 0 0.889 270)
			(size 0.508 0.508)
			(layers "B.Cu" "B.Mask" "B.Paste")
			(net "TP_RGMII1TXD2_GPIOT4")
		)
		(zone
			(layer "B.Cu")
			(hatch none 0.5)
			(connect_pads
				(clearance 0)
			)
			(min_thickness 0.25)
			(keepout
				(tracks allowed)
				(vias not_allowed)
				(pads allowed)
				(copperpour not_allowed)
				(footprints allowed)
			)
			(placement
				(enabled no)
				(sheetname "")
			)
			(fill
				(thermal_gap 0.5)
				(thermal_bridge_width 0.5)
				(island_removal_mode 0)
			)
			(polygon
				(pts
					(xy 404.5585 -30.353) (xy 404.5585 -29.845) (xy 404.9395 -29.845) (xy 404.9395 -30.353)
				)
			)
		)
		(zone
			(layer "B.Cu")
			(hatch none 0.5)
			(connect_pads
				(clearance 0)
			)
			(min_thickness 0.25)
			(keepout
				(tracks not_allowed)
				(vias allowed)
				(pads allowed)
				(copperpour not_allowed)
				(footprints allowed)
			)
			(placement
				(enabled no)
				(sheetname "")
			)
			(fill
				(thermal_gap 0.5)
				(thermal_bridge_width 0.5)
				(island_removal_mode 0)
			)
			(polygon
				(pts
					(xy 404.9395 -30.353) (xy 404.9395 -29.845) (xy 404.5585 -29.845) (xy 404.5585 -30.353)
				)
			)
		)
	)
	(footprint ""
		(layer "B.Cu")
		(at 411.099 -141.0208 -90)
		(property "Reference" "C2L48"
			(at 0 0 90)
			(layer "B.SilkS")
			(hide yes)
			(effects
				(font
					(size 1.27 1.27)
				)
				(justify mirror)
			)
		)
		(property "Value" ""
			(at 0 0 90)
			(layer "B.Fab")
			(effects
				(font
					(size 1.27 1.27)
				)
				(justify mirror)
			)
		)
		(duplicate_pad_numbers_are_jumpers no)
		(fp_poly
			(pts
				(xy -0.3048 -0.1016) (xy -0.3048 0.9906) (xy 0.3048 0.9906) (xy 0.3048 -0.1016)
			)
			(stroke
				(width 0)
				(type default)
			)
			(fill no)
			(layer "B.CrtYd")
		)
		(fp_line
			(start -0.3048 0.9906)
			(end -0.3048 -0.1016)
			(stroke
				(width 0.1)
				(type default)
			)
			(layer "B.Fab")
		)
		(fp_line
			(start 0.3048 0.9906)
			(end -0.3048 0.9906)
			(stroke
				(width 0.1)
				(type default)
			)
			(layer "B.Fab")
		)
		(fp_line
			(start -0.3048 -0.1016)
			(end 0.3048 -0.1016)
			(stroke
				(width 0.1)
				(type default)
			)
			(layer "B.Fab")
		)
		(fp_line
			(start 0.3048 -0.1016)
			(end 0.3048 0.9906)
			(stroke
				(width 0.1)
				(type default)
			)
			(layer "B.Fab")
		)
		(pad "1" smd rect
			(at 0 0 90)
			(size 0.508 0.508)
			(layers "B.Cu" "B.Mask" "B.Paste")
			(net "SATA6G_P6_TX_C_DP")
		)
		(pad "2" smd rect
			(at 0 0.889 90)
			(size 0.508 0.508)
			(layers "B.Cu" "B.Mask" "B.Paste")
			(net "SATA6G_PCH_PCIE_UP_SATA_TXP<6>")
		)
		(zone
			(layer "B.Cu")
			(hatch none 0.5)
			(connect_pads
				(clearance 0)
			)
			(min_thickness 0.25)
			(keepout
				(tracks not_allowed)
				(vias allowed)
				(pads allowed)
				(copperpour not_allowed)
				(footprints allowed)
			)
			(placement
				(enabled no)
				(sheetname "")
			)
			(fill
				(thermal_gap 0.5)
				(thermal_bridge_width 0.5)
				(island_removal_mode 0)
			)
			(polygon
				(pts
					(xy 410.464 -140.7668) (xy 410.464 -141.2748) (xy 410.845 -141.2748) (xy 410.845 -140.7668)
				)
			)
		)
		(zone
			(layer "B.Cu")
			(hatch none 0.5)
			(connect_pads
				(clearance 0)
			)
			(min_thickness 0.25)
			(keepout
				(tracks allowed)
				(vias not_allowed)
				(pads allowed)
				(copperpour not_allowed)
				(footprints allowed)
			)
			(placement
				(enabled no)
				(sheetname "")
			)
			(fill
				(thermal_gap 0.5)
				(thermal_bridge_width 0.5)
				(island_removal_mode 0)
			)
			(polygon
				(pts
					(xy 410.845 -140.7668) (xy 410.845 -141.2748) (xy 410.464 -141.2748) (xy 410.464 -140.7668)
				)
			)
		)
	)
	(footprint ""
		(layer "B.Cu")
		(at 276.5806 -84.5312)
		(property "Reference" "C8W3"
			(at -1.47828 0.78994 90)
			(unlocked yes)
			(layer "B.SilkS")
			(effects
				(font
					(size 0.4064 0.254)
					(thickness 0.1524)
				)
				(justify mirror)
			)
		)
		(property "Value" ""
			(at 0 0 0)
			(layer "B.Fab")
			(effects
				(font
					(size 1.27 1.27)
				)
				(justify mirror)
			)
		)
		(duplicate_pad_numbers_are_jumpers no)
		(fp_poly
			(pts
				(xy 0.7239 -0.2159) (xy -0.7239 -0.2159) (xy -0.7239 1.9939) (xy 0.7239 1.9939)
			)
			(stroke
				(width 0)
				(type default)
			)
			(fill no)
			(layer "B.CrtYd")
		)
		(fp_line
			(start -0.7239 -0.2159)
			(end 0.7239 -0.2159)
			(stroke
				(width 0.1)
				(type default)
			)
			(layer "B.Fab")
		)
		(fp_line
			(start -0.7239 1.9939)
			(end -0.7239 -0.2159)
			(stroke
				(width 0.1)
				(type default)
			)
			(layer "B.Fab")
		)
		(fp_line
			(start 0.7239 -0.2159)
			(end 0.7239 1.9939)
			(stroke
				(width 0.1)
				(type default)
			)
			(layer "B.Fab")
		)
		(fp_line
			(start 0.7239 1.9939)
			(end -0.7239 1.9939)
			(stroke
				(width 0.1)
				(type default)
			)
			(layer "B.Fab")
		)
		(pad "1" smd rect
			(at 0 0 180)
			(size 1.27 1.016)
			(layers "B.Cu" "B.Mask" "B.Paste")
			(net "PVCCIN_CPU0")
		)
		(pad "2" smd rect
			(at 0 1.778 180)
			(size 1.27 1.016)
			(layers "B.Cu" "B.Mask" "B.Paste")
			(net "GND")
		)
		(zone
			(layer "B.Cu")
			(hatch none 0.5)
			(connect_pads
				(clearance 0)
			)
			(min_thickness 0.25)
			(keepout
				(tracks not_allowed)
				(vias allowed)
				(pads allowed)
				(copperpour not_allowed)
				(footprints allowed)
			)
			(placement
				(enabled no)
				(sheetname "")
			)
			(fill
				(thermal_gap 0.5)
				(thermal_bridge_width 0.5)
				(island_removal_mode 0)
			)
			(polygon
				(pts
					(xy 277.2156 -84.0232) (xy 275.9456 -84.0232) (xy 275.9456 -83.2612) (xy 277.2156 -83.2612)
				)
			)
		)
	)
	(footprint ""
		(layer "B.Cu")
		(at 361.444794 -47.258986 -90)
		(property "Reference" "R7D24"
			(at 0 0 90)
			(layer "B.SilkS")
			(hide yes)
			(effects
				(font
					(size 1.27 1.27)
				)
				(justify mirror)
			)
		)
		(property "Value" ""
			(at 0 0 90)
			(layer "B.Fab")
			(effects
				(font
					(size 1.27 1.27)
				)
				(justify mirror)
			)
		)
		(duplicate_pad_numbers_are_jumpers no)
		(fp_poly
			(pts
				(xy 0.2794 -0.1016) (xy -0.2794 -0.1016) (xy -0.2794 0.9906) (xy 0.2794 0.9906)
			)
			(stroke
				(width 0)
				(type default)
			)
			(fill no)
			(layer "B.CrtYd")
		)
		(fp_line
			(start -0.2794 0.9906)
			(end -0.2794 -0.1016)
			(stroke
				(width 0.1)
				(type default)
			)
			(layer "B.Fab")
		)
		(fp_line
			(start 0.2794 0.9906)
			(end -0.2794 0.9906)
			(stroke
				(width 0.1)
				(type default)
			)
			(layer "B.Fab")
		)
		(fp_line
			(start -0.2794 -0.1016)
			(end 0.2794 -0.1016)
			(stroke
				(width 0.1)
				(type default)
			)
			(layer "B.Fab")
		)
		(fp_line
			(start 0.2794 -0.1016)
			(end 0.2794 0.9906)
			(stroke
				(width 0.1)
				(type default)
			)
			(layer "B.Fab")
		)
		(pad "1" smd rect
			(at 0 0 90)
			(size 0.508 0.508)
			(layers "B.Cu" "B.Mask" "B.Paste")
			(net "FM_CPU1_PROCHOT_LVT3_K_N")
		)
		(pad "2" smd rect
			(at 0 0.889 90)
			(size 0.508 0.508)
			(layers "B.Cu" "B.Mask" "B.Paste")
			(net "FM_CPU1_PROCHOT_LVT3_N")
		)
		(zone
			(layer "B.Cu")
			(hatch none 0.5)
			(connect_pads
				(clearance 0)
			)
			(min_thickness 0.25)
			(keepout
				(tracks not_allowed)
				(vias allowed)
				(pads allowed)
				(copperpour not_allowed)
				(footprints allowed)
			)
			(placement
				(enabled no)
				(sheetname "")
			)
			(fill
				(thermal_gap 0.5)
				(thermal_bridge_width 0.5)
				(island_removal_mode 0)
			)
			(polygon
				(pts
					(xy 360.809794 -47.004986) (xy 360.809794 -47.512986) (xy 361.190794 -47.512986) (xy 361.190794 -47.004986)
				)
			)
		)
		(zone
			(layer "B.Cu")
			(hatch none 0.5)
			(connect_pads
				(clearance 0)
			)
			(min_thickness 0.25)
			(keepout
				(tracks allowed)
				(vias not_allowed)
				(pads allowed)
				(copperpour not_allowed)
				(footprints allowed)
			)
			(placement
				(enabled no)
				(sheetname "")
			)
			(fill
				(thermal_gap 0.5)
				(thermal_bridge_width 0.5)
				(island_removal_mode 0)
			)
			(polygon
				(pts
					(xy 361.190794 -47.004986) (xy 361.190794 -47.512986) (xy 360.809794 -47.512986) (xy 360.809794 -47.004986)
				)
			)
		)
	)
	(footprint ""
		(layer "B.Cu")
		(at 401.828 -73.406 180)
		(property "Reference" "R2T53"
			(at 0 0 0)
			(layer "B.SilkS")
			(hide yes)
			(effects
				(font
					(size 1.27 1.27)
				)
				(justify mirror)
			)
		)
		(property "Value" ""
			(at 0 0 0)
			(layer "B.Fab")
			(effects
				(font
					(size 1.27 1.27)
				)
				(justify mirror)
			)
		)
		(duplicate_pad_numbers_are_jumpers no)
		(fp_poly
			(pts
				(xy 0.2794 -0.1016) (xy -0.2794 -0.1016) (xy -0.2794 0.9906) (xy 0.2794 0.9906)
			)
			(stroke
				(width 0)
				(type default)
			)
			(fill no)
			(layer "B.CrtYd")
		)
		(fp_line
			(start 0.2794 0.9906)
			(end -0.2794 0.9906)
			(stroke
				(width 0.1)
				(type default)
			)
			(layer "B.Fab")
		)
		(fp_line
			(start 0.2794 -0.1016)
			(end 0.2794 0.9906)
			(stroke
				(width 0.1)
				(type default)
			)
			(layer "B.Fab")
		)
		(fp_line
			(start -0.2794 0.9906)
			(end -0.2794 -0.1016)
			(stroke
				(width 0.1)
				(type default)
			)
			(layer "B.Fab")
		)
		(fp_line
			(start -0.2794 -0.1016)
			(end 0.2794 -0.1016)
			(stroke
				(width 0.1)
				(type default)
			)
			(layer "B.Fab")
		)
		(pad "1" smd rect
			(at 0 0)
			(size 0.508 0.508)
			(layers "B.Cu" "B.Mask" "B.Paste")
			(net "P3V3_STBY")
		)
		(pad "2" smd rect
			(at 0 0.889)
			(size 0.508 0.508)
			(layers "B.Cu" "B.Mask" "B.Paste")
			(net "SMB_BMC_PMBUS_STBY_LVC3_SDA")
		)
		(zone
			(layer "B.Cu")
			(hatch none 0.5)
			(connect_pads
				(clearance 0)
			)
			(min_thickness 0.25)
			(keepout
				(tracks not_allowed)
				(vias allowed)
				(pads allowed)
				(copperpour not_allowed)
				(footprints allowed)
			)
			(placement
				(enabled no)
				(sheetname "")
			)
			(fill
				(thermal_gap 0.5)
				(thermal_bridge_width 0.5)
				(island_removal_mode 0)
			)
			(polygon
				(pts
					(xy 401.574 -74.041) (xy 402.082 -74.041) (xy 402.082 -73.66) (xy 401.574 -73.66)
				)
			)
		)
		(zone
			(layer "B.Cu")
			(hatch none 0.5)
			(connect_pads
				(clearance 0)
			)
			(min_thickness 0.25)
			(keepout
				(tracks allowed)
				(vias not_allowed)
				(pads allowed)
				(copperpour not_allowed)
				(footprints allowed)
			)
			(placement
				(enabled no)
				(sheetname "")
			)
			(fill
				(thermal_gap 0.5)
				(thermal_bridge_width 0.5)
				(island_removal_mode 0)
			)
			(polygon
				(pts
					(xy 401.574 -73.66) (xy 402.082 -73.66) (xy 402.082 -74.041) (xy 401.574 -74.041)
				)
			)
		)
	)
	(footprint ""
		(layer "B.Cu")
		(at 479.6917 -38.6334 90)
		(property "Reference" "C1R31"
			(at 0 0 90)
			(layer "B.SilkS")
			(hide yes)
			(effects
				(font
					(size 1.27 1.27)
				)
				(justify mirror)
			)
		)
		(property "Value" ""
			(at 0 0 90)
			(layer "B.Fab")
			(effects
				(font
					(size 1.27 1.27)
				)
				(justify mirror)
			)
		)
		(duplicate_pad_numbers_are_jumpers no)
		(fp_poly
			(pts
				(xy -0.3048 -0.1016) (xy -0.3048 0.9906) (xy 0.3048 0.9906) (xy 0.3048 -0.1016)
			)
			(stroke
				(width 0)
				(type default)
			)
			(fill no)
			(layer "B.CrtYd")
		)
		(fp_line
			(start 0.3048 -0.1016)
			(end 0.3048 0.9906)
			(stroke
				(width 0.1)
				(type default)
			)
			(layer "B.Fab")
		)
		(fp_line
			(start -0.3048 -0.1016)
			(end 0.3048 -0.1016)
			(stroke
				(width 0.1)
				(type default)
			)
			(layer "B.Fab")
		)
		(fp_line
			(start 0.3048 0.9906)
			(end -0.3048 0.9906)
			(stroke
				(width 0.1)
				(type default)
			)
			(layer "B.Fab")
		)
		(fp_line
			(start -0.3048 0.9906)
			(end -0.3048 -0.1016)
			(stroke
				(width 0.1)
				(type default)
			)
			(layer "B.Fab")
		)
		(pad "1" smd rect
			(at 0 0 270)
			(size 0.508 0.508)
			(layers "B.Cu" "B.Mask" "B.Paste")
			(net "P1V5_LAN")
		)
		(pad "2" smd rect
			(at 0 0.889 270)
			(size 0.508 0.508)
			(layers "B.Cu" "B.Mask" "B.Paste")
			(net "GND")
		)
		(zone
			(layer "B.Cu")
			(hatch none 0.5)
			(connect_pads
				(clearance 0)
			)
			(min_thickness 0.25)
			(keepout
				(tracks allowed)
				(vias not_allowed)
				(pads allowed)
				(copperpour not_allowed)
				(footprints allowed)
			)
			(placement
				(enabled no)
				(sheetname "")
			)
			(fill
				(thermal_gap 0.5)
				(thermal_bridge_width 0.5)
				(island_removal_mode 0)
			)
			(polygon
				(pts
					(xy 479.9457 -38.8874) (xy 479.9457 -38.3794) (xy 480.3267 -38.3794) (xy 480.3267 -38.8874)
				)
			)
		)
		(zone
			(layer "B.Cu")
			(hatch none 0.5)
			(connect_pads
				(clearance 0)
			)
			(min_thickness 0.25)
			(keepout
				(tracks not_allowed)
				(vias allowed)
				(pads allowed)
				(copperpour not_allowed)
				(footprints allowed)
			)
			(placement
				(enabled no)
				(sheetname "")
			)
			(fill
				(thermal_gap 0.5)
				(thermal_bridge_width 0.5)
				(island_removal_mode 0)
			)
			(polygon
				(pts
					(xy 480.3267 -38.8874) (xy 480.3267 -38.3794) (xy 479.9457 -38.3794) (xy 479.9457 -38.8874)
				)
			)
		)
	)
	(footprint ""
		(layer "B.Cu")
		(at 162.687 -81.788 90)
		(property "Reference" "R7P4"
			(at 0 0 90)
			(layer "B.SilkS")
			(hide yes)
			(effects
				(font
					(size 1.27 1.27)
				)
				(justify mirror)
			)
		)
		(property "Value" ""
			(at 0 0 90)
			(layer "B.Fab")
			(effects
				(font
					(size 1.27 1.27)
				)
				(justify mirror)
			)
		)
		(duplicate_pad_numbers_are_jumpers no)
		(fp_poly
			(pts
				(xy 0.2794 -0.1016) (xy -0.2794 -0.1016) (xy -0.2794 0.9906) (xy 0.2794 0.9906)
			)
			(stroke
				(width 0)
				(type default)
			)
			(fill no)
			(layer "B.CrtYd")
		)
		(fp_line
			(start 0.2794 -0.1016)
			(end 0.2794 0.9906)
			(stroke
				(width 0.1)
				(type default)
			)
			(layer "B.Fab")
		)
		(fp_line
			(start -0.2794 -0.1016)
			(end 0.2794 -0.1016)
			(stroke
				(width 0.1)
				(type default)
			)
			(layer "B.Fab")
		)
		(fp_line
			(start 0.2794 0.9906)
			(end -0.2794 0.9906)
			(stroke
				(width 0.1)
				(type default)
			)
			(layer "B.Fab")
		)
		(fp_line
			(start -0.2794 0.9906)
			(end -0.2794 -0.1016)
			(stroke
				(width 0.1)
				(type default)
			)
			(layer "B.Fab")
		)
		(pad "1" smd rect
			(at 0 0 270)
			(size 0.508 0.508)
			(layers "B.Cu" "B.Mask" "B.Paste")
			(net "CLK_100M_CPU1_PE_REFCLK_DN")
		)
		(pad "2" smd rect
			(at 0 0.889 270)
			(size 0.508 0.508)
			(layers "B.Cu" "B.Mask" "B.Paste")
			(net "GND")
		)
		(zone
			(layer "B.Cu")
			(hatch none 0.5)
			(connect_pads
				(clearance 0)
			)
			(min_thickness 0.25)
			(keepout
				(tracks allowed)
				(vias not_allowed)
				(pads allowed)
				(copperpour not_allowed)
				(footprints allowed)
			)
			(placement
				(enabled no)
				(sheetname "")
			)
			(fill
				(thermal_gap 0.5)
				(thermal_bridge_width 0.5)
				(island_removal_mode 0)
			)
			(polygon
				(pts
					(xy 162.941 -82.042) (xy 162.941 -81.534) (xy 163.322 -81.534) (xy 163.322 -82.042)
				)
			)
		)
		(zone
			(layer "B.Cu")
			(hatch none 0.5)
			(connect_pads
				(clearance 0)
			)
			(min_thickness 0.25)
			(keepout
				(tracks not_allowed)
				(vias allowed)
				(pads allowed)
				(copperpour not_allowed)
				(footprints allowed)
			)
			(placement
				(enabled no)
				(sheetname "")
			)
			(fill
				(thermal_gap 0.5)
				(thermal_bridge_width 0.5)
				(island_removal_mode 0)
			)
			(polygon
				(pts
					(xy 163.322 -82.042) (xy 163.322 -81.534) (xy 162.941 -81.534) (xy 162.941 -82.042)
				)
			)
		)
	)
	(footprint ""
		(layer "B.Cu")
		(at 108.9025 -164.973 -90)
		(property "Reference" "T1D5"
			(at 0 0 90)
			(layer "B.SilkS")
			(hide yes)
			(effects
				(font
					(size 1.27 1.27)
				)
				(justify mirror)
			)
		)
		(property "Value" "*"
			(at 3.4036 -4.46405 270)
			(unlocked yes)
			(layer "B.Fab")
			(hide yes)
			(effects
				(font
					(size 0.889 0.889)
					(thickness 0.1524)
				)
				(justify mirror)
			)
		)
		(property "Device Type" "TEST-PAD-12P-1-GP-U_DISCRET-GBA"
			(at 3.4036 -5.98805 270)
			(unlocked yes)
			(layer "B.Fab")
			(hide yes)
			(effects
				(font
					(size 0.889 0.889)
					(thickness 0.1524)
				)
				(justify mirror)
			)
		)
		(duplicate_pad_numbers_are_jumpers no)
		(fp_line
			(start -2.3622 3.4798)
			(end 2.3876 3.4798)
			(stroke
				(width 0.1524)
				(type default)
			)
			(layer "B.SilkS")
		)
		(fp_line
			(start 2.3876 3.4798)
			(end 2.3876 -4.826)
			(stroke
				(width 0.1524)
				(type default)
			)
			(layer "B.SilkS")
		)
		(fp_line
			(start -2.3622 -4.826)
			(end -2.3622 3.4798)
			(stroke
				(width 0.1524)
				(type default)
			)
			(layer "B.SilkS")
		)
		(fp_line
			(start 2.3876 -4.826)
			(end -2.3622 -4.826)
			(stroke
				(width 0.1524)
				(type default)
			)
			(layer "B.SilkS")
		)
		(fp_rect
			(start 2.6416 3.7338)
			(end -2.6162 -5.08)
			(stroke
				(width 0)
				(type default)
			)
			(fill no)
			(layer "B.CrtYd")
		)
		(fp_rect
			(start 2.6416 3.7338)
			(end -2.6162 -5.08)
			(stroke
				(width 0)
				(type default)
			)
			(fill no)
			(layer "B.Fab")
		)
		(pad "1" smd circle
			(at -0.496824 -1.301496 90)
			(size 0.6604 0.6604)
			(layers "B.Cu" "B.Mask" "B.Paste")
			(net "L5_85OHM_5INCH_DP")
		)
		(pad "2" smd circle
			(at 0.503936 -1.301496 90)
			(size 0.6604 0.6604)
			(layers "B.Cu" "B.Mask" "B.Paste")
			(net "L5_85OHM_5INCH_DN")
		)
		(pad "3" smd custom
			(at 0.00889 0.370078 90)
			(size 0.74295 0.74295)
			(layers "B.Cu" "B.Mask" "B.Paste")
			(net "GND")
			(options
				(clearance outline)
				(anchor circle)
			)
			(primitives
				(gr_poly
					(pts
						(xy -2.1209 -1.4859) (xy 2.1209 -1.4859) (xy 2.1209 1.4859) (xy 1.08585 1.4859) (xy 1.08585 0.4699)
						(xy -1.08585 0.4699) (xy -1.08585 1.4859) (xy -2.1209 1.4859)
					)
					(width 0)
					(fill yes)
				)
			)
		)
		(pad "4" thru_hole circle
			(at -1.266444 -3.851656 90)
			(size 1.4478 1.4478)
			(drill 1.0414)
			(layers "*.Cu" "*.Mask")
			(remove_unused_layers no)
			(net "GND")
			(clearance 0.1524)
			(thermal_gap 0.1524)
		)
		(pad "5" thru_hole circle
			(at 1.273556 -3.851656 90)
			(size 1.4478 1.4478)
			(drill 1.0414)
			(layers "*.Cu" "*.Mask")
			(remove_unused_layers no)
			(net "GND")
			(clearance 0.1524)
			(thermal_gap 0.1524)
		)
		(pad "6" thru_hole circle
			(at -1.266444 2.498344 90)
			(size 1.4478 1.4478)
			(drill 1.0414)
			(layers "*.Cu" "*.Mask")
			(remove_unused_layers no)
			(net "GND")
			(clearance 0.1524)
			(thermal_gap 0.1524)
		)
		(pad "7" thru_hole circle
			(at 1.273556 2.498344 90)
			(size 1.4478 1.4478)
			(drill 1.0414)
			(layers "*.Cu" "*.Mask")
			(remove_unused_layers no)
			(net "GND")
			(clearance 0.1524)
			(thermal_gap 0.1524)
		)
		(pad "8" thru_hole circle
			(at -1.27 -0.4572 90)
			(size 0.7112 0.7112)
			(drill 0.4064)
			(layers "*.Cu" "*.Mask")
			(remove_unused_layers no)
			(net "GND")
			(clearance 0.1016)
			(thermal_gap 0.1016)
		)
		(pad "9" thru_hole circle
			(at -1.27 0.762 90)
			(size 0.7112 0.7112)
			(drill 0.4064)
			(layers "*.Cu" "*.Mask")
			(remove_unused_layers no)
			(net "GND")
			(clearance 0.1016)
			(thermal_gap 0.1016)
		)
		(pad "10" thru_hole circle
			(at 0.0254 0.762 90)
			(size 0.7112 0.7112)
			(drill 0.4064)
			(layers "*.Cu" "*.Mask")
			(remove_unused_layers no)
			(net "GND")
			(clearance 0.1016)
			(thermal_gap 0.1016)
		)
		(pad "11" thru_hole circle
			(at 1.27 0.762 90)
			(size 0.7112 0.7112)
			(drill 0.4064)
			(layers "*.Cu" "*.Mask")
			(remove_unused_layers no)
			(net "GND")
			(clearance 0.1016)
			(thermal_gap 0.1016)
		)
		(pad "12" thru_hole circle
			(at 1.27 -0.4572 90)
			(size 0.7112 0.7112)
			(drill 0.4064)
			(layers "*.Cu" "*.Mask")
			(remove_unused_layers no)
			(net "GND")
			(clearance 0.1016)
			(thermal_gap 0.1016)
		)
	)
	(footprint ""
		(layer "B.Cu")
		(at 88.392 -12.954 90)
		(property "Reference" "C5G82"
			(at -1.14681 0.76708 180)
			(unlocked yes)
			(layer "B.SilkS")
			(effects
				(font
					(size 0.7874 0.5842)
					(thickness 0.1524)
				)
				(justify mirror)
			)
		)
		(property "Value" ""
			(at 0 0 90)
			(layer "B.Fab")
			(effects
				(font
					(size 1.27 1.27)
				)
				(justify mirror)
			)
		)
		(duplicate_pad_numbers_are_jumpers no)
		(fp_rect
			(start -0.4953 -0.2032)
			(end 0.4953 1.6002)
			(stroke
				(width 0)
				(type default)
			)
			(fill no)
			(layer "B.CrtYd")
		)
		(fp_line
			(start 0.4953 -0.2032)
			(end -0.4953 -0.2032)
			(stroke
				(width 0.1)
				(type default)
			)
			(layer "B.Fab")
		)
		(fp_line
			(start -0.4953 -0.2032)
			(end -0.4953 1.6002)
			(stroke
				(width 0.1)
				(type default)
			)
			(layer "B.Fab")
		)
		(fp_line
			(start 0.4953 1.6002)
			(end 0.4953 -0.2032)
			(stroke
				(width 0.1)
				(type default)
			)
			(layer "B.Fab")
		)
		(fp_line
			(start -0.4953 1.6002)
			(end 0.4953 1.6002)
			(stroke
				(width 0.1)
				(type default)
			)
			(layer "B.Fab")
		)
		(pad "1" smd rect
			(at 0 0 270)
			(size 0.762 0.889)
			(layers "B.Cu" "B.Mask" "B.Paste")
			(net "PVDDQ_GHJ")
		)
		(pad "2" smd rect
			(at 0 1.397 270)
			(size 0.762 0.889)
			(layers "B.Cu" "B.Mask" "B.Paste")
			(net "GND")
		)
		(zone
			(layer "B.Cu")
			(hatch none 0.5)
			(connect_pads
				(clearance 0)
			)
			(min_thickness 0.25)
			(keepout
				(tracks not_allowed)
				(vias allowed)
				(pads allowed)
				(copperpour not_allowed)
				(footprints allowed)
			)
			(placement
				(enabled no)
				(sheetname "")
			)
			(fill
				(thermal_gap 0.5)
				(thermal_bridge_width 0.5)
				(island_removal_mode 0)
			)
			(polygon
				(pts
					(xy 88.8365 -12.573) (xy 89.3445 -12.573) (xy 89.3445 -13.335) (xy 88.8365 -13.335)
				)
			)
		)
	)
	(footprint ""
		(layer "B.Cu")
		(at 32.832802 -68.101464 90)
		(property "Reference" "C9P22"
			(at 0 0 90)
			(layer "B.SilkS")
			(hide yes)
			(effects
				(font
					(size 1.27 1.27)
				)
				(justify mirror)
			)
		)
		(property "Value" ""
			(at 0 0 90)
			(layer "B.Fab")
			(effects
				(font
					(size 1.27 1.27)
				)
				(justify mirror)
			)
		)
		(duplicate_pad_numbers_are_jumpers no)
		(fp_poly
			(pts
				(xy 0.7239 -0.2159) (xy -0.7239 -0.2159) (xy -0.7239 1.9939) (xy 0.7239 1.9939)
			)
			(stroke
				(width 0)
				(type default)
			)
			(fill no)
			(layer "B.CrtYd")
		)
		(fp_line
			(start 0.7239 -0.2159)
			(end 0.7239 1.9939)
			(stroke
				(width 0.1)
				(type default)
			)
			(layer "B.Fab")
		)
		(fp_line
			(start -0.7239 -0.2159)
			(end 0.7239 -0.2159)
			(stroke
				(width 0.1)
				(type default)
			)
			(layer "B.Fab")
		)
		(fp_line
			(start 0.7239 1.9939)
			(end -0.7239 1.9939)
			(stroke
				(width 0.1)
				(type default)
			)
			(layer "B.Fab")
		)
		(fp_line
			(start -0.7239 1.9939)
			(end -0.7239 -0.2159)
			(stroke
				(width 0.1)
				(type default)
			)
			(layer "B.Fab")
		)
		(pad "1" smd rect
			(at 0 0 270)
			(size 1.27 1.016)
			(layers "B.Cu" "B.Mask" "B.Paste")
			(net "VR_FET_SW_P12V_STBY_PVCCIN_CPU1")
		)
		(pad "2" smd rect
			(at 0 1.778 270)
			(size 1.27 1.016)
			(layers "B.Cu" "B.Mask" "B.Paste")
			(net "GND")
		)
		(zone
			(layer "B.Cu")
			(hatch none 0.5)
			(connect_pads
				(clearance 0)
			)
			(min_thickness 0.25)
			(keepout
				(tracks not_allowed)
				(vias allowed)
				(pads allowed)
				(copperpour not_allowed)
				(footprints allowed)
			)
			(placement
				(enabled no)
				(sheetname "")
			)
			(fill
				(thermal_gap 0.5)
				(thermal_bridge_width 0.5)
				(island_removal_mode 0)
			)
			(polygon
				(pts
					(xy 33.340802 -68.736464) (xy 33.340802 -67.466464) (xy 34.102802 -67.466464) (xy 34.102802 -68.736464)
				)
			)
		)
	)
	(footprint ""
		(layer "B.Cu")
		(at 400.756628 -115.579144)
		(property "Reference" "R24W2"
			(at 0.8382 -0.67818 0)
			(unlocked yes)
			(layer "B.SilkS")
			(effects
				(font
					(size 0.4064 0.254)
					(thickness 0.1524)
				)
				(justify left mirror)
			)
		)
		(property "Value" ""
			(at 0 0 0)
			(layer "B.Fab")
			(effects
				(font
					(size 1.27 1.27)
				)
				(justify mirror)
			)
		)
		(duplicate_pad_numbers_are_jumpers no)
		(fp_poly
			(pts
				(xy 0.2794 -0.1016) (xy -0.2794 -0.1016) (xy -0.2794 0.9906) (xy 0.2794 0.9906)
			)
			(stroke
				(width 0)
				(type default)
			)
			(fill no)
			(layer "B.CrtYd")
		)
		(fp_line
			(start -0.2794 -0.1016)
			(end 0.2794 -0.1016)
			(stroke
				(width 0.1)
				(type default)
			)
			(layer "B.Fab")
		)
		(fp_line
			(start -0.2794 0.9906)
			(end -0.2794 -0.1016)
			(stroke
				(width 0.1)
				(type default)
			)
			(layer "B.Fab")
		)
		(fp_line
			(start 0.2794 -0.1016)
			(end 0.2794 0.9906)
			(stroke
				(width 0.1)
				(type default)
			)
			(layer "B.Fab")
		)
		(fp_line
			(start 0.2794 0.9906)
			(end -0.2794 0.9906)
			(stroke
				(width 0.1)
				(type default)
			)
			(layer "B.Fab")
		)
		(pad "1" smd rect
			(at 0 0 180)
			(size 0.508 0.508)
			(layers "B.Cu" "B.Mask" "B.Paste")
			(net "P3V3_STBY")
		)
		(pad "2" smd rect
			(at 0 0.889 180)
			(size 0.508 0.508)
			(layers "B.Cu" "B.Mask" "B.Paste")
			(net "SMB_SLOTX24_PCH_STBY_LVC3_SCL")
		)
		(zone
			(layer "B.Cu")
			(hatch none 0.5)
			(connect_pads
				(clearance 0)
			)
			(min_thickness 0.25)
			(keepout
				(tracks allowed)
				(vias not_allowed)
				(pads allowed)
				(copperpour not_allowed)
				(footprints allowed)
			)
			(placement
				(enabled no)
				(sheetname "")
			)
			(fill
				(thermal_gap 0.5)
				(thermal_bridge_width 0.5)
				(island_removal_mode 0)
			)
			(polygon
				(pts
					(xy 401.010628 -115.325144) (xy 400.502628 -115.325144) (xy 400.502628 -114.944144) (xy 401.010628 -114.944144)
				)
			)
		)
		(zone
			(layer "B.Cu")
			(hatch none 0.5)
			(connect_pads
				(clearance 0)
			)
			(min_thickness 0.25)
			(keepout
				(tracks not_allowed)
				(vias allowed)
				(pads allowed)
				(copperpour not_allowed)
				(footprints allowed)
			)
			(placement
				(enabled no)
				(sheetname "")
			)
			(fill
				(thermal_gap 0.5)
				(thermal_bridge_width 0.5)
				(island_removal_mode 0)
			)
			(polygon
				(pts
					(xy 401.010628 -114.944144) (xy 400.502628 -114.944144) (xy 400.502628 -115.325144) (xy 401.010628 -115.325144)
				)
			)
		)
	)
	(footprint ""
		(layer "B.Cu")
		(at 334.743806 -61.257434)
		(property "Reference" "C2U4"
			(at 0 0 0)
			(layer "B.SilkS")
			(hide yes)
			(effects
				(font
					(size 1.27 1.27)
				)
				(justify mirror)
			)
		)
		(property "Value" ""
			(at 0 0 0)
			(layer "B.Fab")
			(effects
				(font
					(size 1.27 1.27)
				)
				(justify mirror)
			)
		)
		(duplicate_pad_numbers_are_jumpers no)
		(fp_poly
			(pts
				(xy -0.3048 -0.1016) (xy -0.3048 0.9906) (xy 0.3048 0.9906) (xy 0.3048 -0.1016)
			)
			(stroke
				(width 0)
				(type default)
			)
			(fill no)
			(layer "B.CrtYd")
		)
		(fp_line
			(start -0.3048 -0.1016)
			(end 0.3048 -0.1016)
			(stroke
				(width 0.1)
				(type default)
			)
			(layer "B.Fab")
		)
		(fp_line
			(start -0.3048 0.9906)
			(end -0.3048 -0.1016)
			(stroke
				(width 0.1)
				(type default)
			)
			(layer "B.Fab")
		)
		(fp_line
			(start 0.3048 -0.1016)
			(end 0.3048 0.9906)
			(stroke
				(width 0.1)
				(type default)
			)
			(layer "B.Fab")
		)
		(fp_line
			(start 0.3048 0.9906)
			(end -0.3048 0.9906)
			(stroke
				(width 0.1)
				(type default)
			)
			(layer "B.Fab")
		)
		(pad "1" smd rect
			(at 0 0 180)
			(size 0.508 0.508)
			(layers "B.Cu" "B.Mask" "B.Paste")
			(net "P3E_CPU0_PE1_PCH_RXN<0>")
		)
		(pad "2" smd rect
			(at 0 0.889 180)
			(size 0.508 0.508)
			(layers "B.Cu" "B.Mask" "B.Paste")
			(net "P3E_CPU0_PE1_SS_RXN<0>")
		)
		(zone
			(layer "B.Cu")
			(hatch none 0.5)
			(connect_pads
				(clearance 0)
			)
			(min_thickness 0.25)
			(keepout
				(tracks allowed)
				(vias not_allowed)
				(pads allowed)
				(copperpour not_allowed)
				(footprints allowed)
			)
			(placement
				(enabled no)
				(sheetname "")
			)
			(fill
				(thermal_gap 0.5)
				(thermal_bridge_width 0.5)
				(island_removal_mode 0)
			)
			(polygon
				(pts
					(xy 334.997806 -61.003434) (xy 334.489806 -61.003434) (xy 334.489806 -60.622434) (xy 334.997806 -60.622434)
				)
			)
		)
		(zone
			(layer "B.Cu")
			(hatch none 0.5)
			(connect_pads
				(clearance 0)
			)
			(min_thickness 0.25)
			(keepout
				(tracks not_allowed)
				(vias allowed)
				(pads allowed)
				(copperpour not_allowed)
				(footprints allowed)
			)
			(placement
				(enabled no)
				(sheetname "")
			)
			(fill
				(thermal_gap 0.5)
				(thermal_bridge_width 0.5)
				(island_removal_mode 0)
			)
			(polygon
				(pts
					(xy 334.997806 -60.622434) (xy 334.489806 -60.622434) (xy 334.489806 -61.003434) (xy 334.997806 -61.003434)
				)
			)
		)
	)
	(footprint ""
		(layer "B.Cu")
		(at 443.865 -116.49202)
		(property "Reference" "C2M14"
			(at 0 0 0)
			(layer "B.SilkS")
			(hide yes)
			(effects
				(font
					(size 1.27 1.27)
				)
				(justify mirror)
			)
		)
		(property "Value" ""
			(at 0 0 0)
			(layer "B.Fab")
			(effects
				(font
					(size 1.27 1.27)
				)
				(justify mirror)
			)
		)
		(duplicate_pad_numbers_are_jumpers no)
		(fp_rect
			(start -0.3048 0.9906)
			(end 0.3048 -0.1016)
			(stroke
				(width 0)
				(type default)
			)
			(fill no)
			(layer "B.CrtYd")
		)
		(fp_line
			(start -0.3048 -0.1016)
			(end 0.3048 -0.1016)
			(stroke
				(width 0.1)
				(type default)
			)
			(layer "B.Fab")
		)
		(fp_line
			(start -0.3048 0.9906)
			(end -0.3048 -0.1016)
			(stroke
				(width 0.1)
				(type default)
			)
			(layer "B.Fab")
		)
		(fp_line
			(start 0.3048 -0.1016)
			(end 0.3048 0.9906)
			(stroke
				(width 0.1)
				(type default)
			)
			(layer "B.Fab")
		)
		(fp_line
			(start 0.3048 0.9906)
			(end -0.3048 0.9906)
			(stroke
				(width 0.1)
				(type default)
			)
			(layer "B.Fab")
		)
		(pad "1" smd rect
			(at 0 0 180)
			(size 0.508 0.508)
			(layers "B.Cu" "B.Mask" "B.Paste")
			(net "P3E_CPU0_PE3_OCP_TXP<8>")
		)
		(pad "2" smd rect
			(at 0 0.889 180)
			(size 0.508 0.508)
			(layers "B.Cu" "B.Mask" "B.Paste")
			(net "P3E_OCP_CPU0_PE3_C_TXP<8>")
		)
		(zone
			(layer "B.Cu")
			(hatch none 0.5)
			(connect_pads
				(clearance 0)
			)
			(min_thickness 0.25)
			(keepout
				(tracks not_allowed)
				(vias allowed)
				(pads allowed)
				(copperpour not_allowed)
				(footprints allowed)
			)
			(placement
				(enabled no)
				(sheetname "")
			)
			(fill
				(thermal_gap 0.5)
				(thermal_bridge_width 0.5)
				(island_removal_mode 0)
			)
			(polygon
				(pts
					(xy 443.611 -115.85702) (xy 444.119 -115.85702) (xy 444.119 -116.23802) (xy 443.611 -116.23802)
				)
			)
		)
		(zone
			(layer "B.Cu")
			(hatch none 0.5)
			(connect_pads
				(clearance 0)
			)
			(min_thickness 0.25)
			(keepout
				(tracks allowed)
				(vias not_allowed)
				(pads allowed)
				(copperpour not_allowed)
				(footprints allowed)
			)
			(placement
				(enabled no)
				(sheetname "")
			)
			(fill
				(thermal_gap 0.5)
				(thermal_bridge_width 0.5)
				(island_removal_mode 0)
			)
			(polygon
				(pts
					(xy 443.611 -115.85702) (xy 444.119 -115.85702) (xy 444.119 -116.23802) (xy 443.611 -116.23802)
				)
			)
		)
	)
	(footprint ""
		(layer "B.Cu")
		(at 318.483996 -154.801824 -90)
		(property "Reference" "C4L2"
			(at 0 0 90)
			(layer "B.SilkS")
			(hide yes)
			(effects
				(font
					(size 1.27 1.27)
				)
				(justify mirror)
			)
		)
		(property "Value" ""
			(at 0 0 90)
			(layer "B.Fab")
			(effects
				(font
					(size 1.27 1.27)
				)
				(justify mirror)
			)
		)
		(duplicate_pad_numbers_are_jumpers no)
		(fp_poly
			(pts
				(xy 0.4953 -0.2032) (xy -0.4953 -0.2032) (xy -0.4953 1.6002) (xy 0.4953 1.6002)
			)
			(stroke
				(width 0)
				(type default)
			)
			(fill no)
			(layer "B.CrtYd")
		)
		(fp_line
			(start -0.4953 1.6002)
			(end 0.4953 1.6002)
			(stroke
				(width 0.1)
				(type default)
			)
			(layer "B.Fab")
		)
		(fp_line
			(start 0.4953 1.6002)
			(end 0.4953 -0.2032)
			(stroke
				(width 0.1)
				(type default)
			)
			(layer "B.Fab")
		)
		(fp_line
			(start -0.4953 -0.2032)
			(end -0.4953 1.6002)
			(stroke
				(width 0.1)
				(type default)
			)
			(layer "B.Fab")
		)
		(fp_line
			(start 0.4953 -0.2032)
			(end -0.4953 -0.2032)
			(stroke
				(width 0.1)
				(type default)
			)
			(layer "B.Fab")
		)
		(pad "1" smd rect
			(at 0 0 90)
			(size 0.762 0.889)
			(layers "B.Cu" "B.Mask" "B.Paste")
			(net "PVPP_DEF")
		)
		(pad "2" smd rect
			(at 0 1.397 90)
			(size 0.762 0.889)
			(layers "B.Cu" "B.Mask" "B.Paste")
			(net "GND")
		)
		(zone
			(layer "B.Cu")
			(hatch none 0.5)
			(connect_pads
				(clearance 0)
			)
			(min_thickness 0.25)
			(keepout
				(tracks not_allowed)
				(vias allowed)
				(pads allowed)
				(copperpour not_allowed)
				(footprints allowed)
			)
			(placement
				(enabled no)
				(sheetname "")
			)
			(fill
				(thermal_gap 0.5)
				(thermal_bridge_width 0.5)
				(island_removal_mode 0)
			)
			(polygon
				(pts
					(xy 318.039496 -154.420824) (xy 318.039496 -155.182824) (xy 317.531496 -155.182824) (xy 317.531496 -154.420824)
				)
			)
		)
	)
	(footprint ""
		(layer "B.Cu")
		(at 358.44988 -77.923136 180)
		(property "Reference" "C3P40"
			(at 0 0 0)
			(layer "B.SilkS")
			(hide yes)
			(effects
				(font
					(size 1.27 1.27)
				)
				(justify mirror)
			)
		)
		(property "Value" ""
			(at 0 0 0)
			(layer "B.Fab")
			(effects
				(font
					(size 1.27 1.27)
				)
				(justify mirror)
			)
		)
		(duplicate_pad_numbers_are_jumpers no)
		(fp_poly
			(pts
				(xy -0.3048 -0.1016) (xy -0.3048 0.9906) (xy 0.3048 0.9906) (xy 0.3048 -0.1016)
			)
			(stroke
				(width 0)
				(type default)
			)
			(fill no)
			(layer "B.CrtYd")
		)
		(fp_line
			(start 0.3048 0.9906)
			(end -0.3048 0.9906)
			(stroke
				(width 0.1)
				(type default)
			)
			(layer "B.Fab")
		)
		(fp_line
			(start 0.3048 -0.1016)
			(end 0.3048 0.9906)
			(stroke
				(width 0.1)
				(type default)
			)
			(layer "B.Fab")
		)
		(fp_line
			(start -0.3048 0.9906)
			(end -0.3048 -0.1016)
			(stroke
				(width 0.1)
				(type default)
			)
			(layer "B.Fab")
		)
		(fp_line
			(start -0.3048 -0.1016)
			(end 0.3048 -0.1016)
			(stroke
				(width 0.1)
				(type default)
			)
			(layer "B.Fab")
		)
		(pad "1" smd rect
			(at 0 0)
			(size 0.508 0.508)
			(layers "B.Cu" "B.Mask" "B.Paste")
			(net "P3E_CPU0_PE1_SS_TXN<7>")
		)
		(pad "2" smd rect
			(at 0 0.889)
			(size 0.508 0.508)
			(layers "B.Cu" "B.Mask" "B.Paste")
			(net "P3E_CPU0_PE1_PCH_TXN<7>")
		)
		(zone
			(layer "B.Cu")
			(hatch none 0.5)
			(connect_pads
				(clearance 0)
			)
			(min_thickness 0.25)
			(keepout
				(tracks not_allowed)
				(vias allowed)
				(pads allowed)
				(copperpour not_allowed)
				(footprints allowed)
			)
			(placement
				(enabled no)
				(sheetname "")
			)
			(fill
				(thermal_gap 0.5)
				(thermal_bridge_width 0.5)
				(island_removal_mode 0)
			)
			(polygon
				(pts
					(xy 358.19588 -78.558136) (xy 358.70388 -78.558136) (xy 358.70388 -78.177136) (xy 358.19588 -78.177136)
				)
			)
		)
		(zone
			(layer "B.Cu")
			(hatch none 0.5)
			(connect_pads
				(clearance 0)
			)
			(min_thickness 0.25)
			(keepout
				(tracks allowed)
				(vias not_allowed)
				(pads allowed)
				(copperpour not_allowed)
				(footprints allowed)
			)
			(placement
				(enabled no)
				(sheetname "")
			)
			(fill
				(thermal_gap 0.5)
				(thermal_bridge_width 0.5)
				(island_removal_mode 0)
			)
			(polygon
				(pts
					(xy 358.19588 -78.177136) (xy 358.70388 -78.177136) (xy 358.70388 -78.558136) (xy 358.19588 -78.558136)
				)
			)
		)
	)
	(footprint ""
		(layer "B.Cu")
		(at 176.25568 -82.677 -90)
		(property "Reference" "R6P12"
			(at 0 0 90)
			(layer "B.SilkS")
			(hide yes)
			(effects
				(font
					(size 1.27 1.27)
				)
				(justify mirror)
			)
		)
		(property "Value" ""
			(at 0 0 90)
			(layer "B.Fab")
			(effects
				(font
					(size 1.27 1.27)
				)
				(justify mirror)
			)
		)
		(duplicate_pad_numbers_are_jumpers no)
		(fp_poly
			(pts
				(xy 0.2794 -0.1016) (xy -0.2794 -0.1016) (xy -0.2794 0.9906) (xy 0.2794 0.9906)
			)
			(stroke
				(width 0)
				(type default)
			)
			(fill no)
			(layer "B.CrtYd")
		)
		(fp_line
			(start -0.2794 0.9906)
			(end -0.2794 -0.1016)
			(stroke
				(width 0.1)
				(type default)
			)
			(layer "B.Fab")
		)
		(fp_line
			(start 0.2794 0.9906)
			(end -0.2794 0.9906)
			(stroke
				(width 0.1)
				(type default)
			)
			(layer "B.Fab")
		)
		(fp_line
			(start -0.2794 -0.1016)
			(end 0.2794 -0.1016)
			(stroke
				(width 0.1)
				(type default)
			)
			(layer "B.Fab")
		)
		(fp_line
			(start 0.2794 -0.1016)
			(end 0.2794 0.9906)
			(stroke
				(width 0.1)
				(type default)
			)
			(layer "B.Fab")
		)
		(pad "1" smd rect
			(at 0 0 90)
			(size 0.508 0.508)
			(layers "B.Cu" "B.Mask" "B.Paste")
			(net "CLK_100M_CPU0_BCLK2_DN")
		)
		(pad "2" smd rect
			(at 0 0.889 90)
			(size 0.508 0.508)
			(layers "B.Cu" "B.Mask" "B.Paste")
			(net "GND")
		)
		(zone
			(layer "B.Cu")
			(hatch none 0.5)
			(connect_pads
				(clearance 0)
			)
			(min_thickness 0.25)
			(keepout
				(tracks not_allowed)
				(vias allowed)
				(pads allowed)
				(copperpour not_allowed)
				(footprints allowed)
			)
			(placement
				(enabled no)
				(sheetname "")
			)
			(fill
				(thermal_gap 0.5)
				(thermal_bridge_width 0.5)
				(island_removal_mode 0)
			)
			(polygon
				(pts
					(xy 175.62068 -82.423) (xy 175.62068 -82.931) (xy 176.00168 -82.931) (xy 176.00168 -82.423)
				)
			)
		)
		(zone
			(layer "B.Cu")
			(hatch none 0.5)
			(connect_pads
				(clearance 0)
			)
			(min_thickness 0.25)
			(keepout
				(tracks allowed)
				(vias not_allowed)
				(pads allowed)
				(copperpour not_allowed)
				(footprints allowed)
			)
			(placement
				(enabled no)
				(sheetname "")
			)
			(fill
				(thermal_gap 0.5)
				(thermal_bridge_width 0.5)
				(island_removal_mode 0)
			)
			(polygon
				(pts
					(xy 176.00168 -82.423) (xy 176.00168 -82.931) (xy 175.62068 -82.931) (xy 175.62068 -82.423)
				)
			)
		)
	)
	(footprint ""
		(layer "B.Cu")
		(at 169.799 -85.344)
		(property "Reference" "C6P4"
			(at 0 0 0)
			(layer "B.SilkS")
			(hide yes)
			(effects
				(font
					(size 1.27 1.27)
				)
				(justify mirror)
			)
		)
		(property "Value" ""
			(at 0 0 0)
			(layer "B.Fab")
			(effects
				(font
					(size 1.27 1.27)
				)
				(justify mirror)
			)
		)
		(duplicate_pad_numbers_are_jumpers no)
		(fp_poly
			(pts
				(xy -0.3048 -0.1016) (xy -0.3048 0.9906) (xy 0.3048 0.9906) (xy 0.3048 -0.1016)
			)
			(stroke
				(width 0)
				(type default)
			)
			(fill no)
			(layer "B.CrtYd")
		)
		(fp_line
			(start -0.3048 -0.1016)
			(end 0.3048 -0.1016)
			(stroke
				(width 0.1)
				(type default)
			)
			(layer "B.Fab")
		)
		(fp_line
			(start -0.3048 0.9906)
			(end -0.3048 -0.1016)
			(stroke
				(width 0.1)
				(type default)
			)
			(layer "B.Fab")
		)
		(fp_line
			(start 0.3048 -0.1016)
			(end 0.3048 0.9906)
			(stroke
				(width 0.1)
				(type default)
			)
			(layer "B.Fab")
		)
		(fp_line
			(start 0.3048 0.9906)
			(end -0.3048 0.9906)
			(stroke
				(width 0.1)
				(type default)
			)
			(layer "B.Fab")
		)
		(pad "1" smd rect
			(at 0 0 180)
			(size 0.508 0.508)
			(layers "B.Cu" "B.Mask" "B.Paste")
			(net "P3V3_DB1200")
		)
		(pad "2" smd rect
			(at 0 0.889 180)
			(size 0.508 0.508)
			(layers "B.Cu" "B.Mask" "B.Paste")
			(net "GND")
		)
		(zone
			(layer "B.Cu")
			(hatch none 0.5)
			(connect_pads
				(clearance 0)
			)
			(min_thickness 0.25)
			(keepout
				(tracks allowed)
				(vias not_allowed)
				(pads allowed)
				(copperpour not_allowed)
				(footprints allowed)
			)
			(placement
				(enabled no)
				(sheetname "")
			)
			(fill
				(thermal_gap 0.5)
				(thermal_bridge_width 0.5)
				(island_removal_mode 0)
			)
			(polygon
				(pts
					(xy 170.053 -85.09) (xy 169.545 -85.09) (xy 169.545 -84.709) (xy 170.053 -84.709)
				)
			)
		)
		(zone
			(layer "B.Cu")
			(hatch none 0.5)
			(connect_pads
				(clearance 0)
			)
			(min_thickness 0.25)
			(keepout
				(tracks not_allowed)
				(vias allowed)
				(pads allowed)
				(copperpour not_allowed)
				(footprints allowed)
			)
			(placement
				(enabled no)
				(sheetname "")
			)
			(fill
				(thermal_gap 0.5)
				(thermal_bridge_width 0.5)
				(island_removal_mode 0)
			)
			(polygon
				(pts
					(xy 170.053 -84.709) (xy 169.545 -84.709) (xy 169.545 -85.09) (xy 170.053 -85.09)
				)
			)
		)
	)
	(footprint ""
		(layer "B.Cu")
		(at 409.2702 -126.2888 90)
		(property "Reference" "FB2M1"
			(at 0 0 90)
			(layer "B.SilkS")
			(hide yes)
			(effects
				(font
					(size 1.27 1.27)
				)
				(justify mirror)
			)
		)
		(property "Value" ""
			(at 0 0 90)
			(layer "B.Fab")
			(effects
				(font
					(size 1.27 1.27)
				)
				(justify mirror)
			)
		)
		(duplicate_pad_numbers_are_jumpers no)
		(fp_poly
			(pts
				(xy 0.15113 -0.47498) (xy -1.59893 -0.47498) (xy -1.59893 0.47498) (xy 0.15113 0.47498)
			)
			(stroke
				(width 0)
				(type default)
			)
			(fill no)
			(layer "B.CrtYd")
		)
		(fp_line
			(start 0.15113 -0.47498)
			(end -1.59893 -0.47498)
			(stroke
				(width 0.1)
				(type default)
			)
			(layer "B.Fab")
		)
		(fp_line
			(start -1.59893 -0.47498)
			(end -1.59893 0.47498)
			(stroke
				(width 0.1)
				(type default)
			)
			(layer "B.Fab")
		)
		(fp_line
			(start 0.15113 0.47498)
			(end 0.15113 -0.47498)
			(stroke
				(width 0.1)
				(type default)
			)
			(layer "B.Fab")
		)
		(fp_line
			(start -1.59893 0.47498)
			(end 0.15113 0.47498)
			(stroke
				(width 0.1)
				(type default)
			)
			(layer "B.Fab")
		)
		(pad "1" smd rect
			(at 0 0 270)
			(size 0.9398 0.9398)
			(layers "B.Cu" "B.Mask" "B.Paste")
			(net "P1V05_PCH_STBY")
		)
		(pad "2" smd rect
			(at -1.4478 0 270)
			(size 0.9398 0.9398)
			(layers "B.Cu" "B.Mask" "B.Paste")
			(net "P1V05_PCH_STBY_WM20_PLL")
		)
		(zone
			(layer "B.Cu")
			(hatch none 0.5)
			(connect_pads
				(clearance 0)
			)
			(min_thickness 0.25)
			(keepout
				(tracks not_allowed)
				(vias allowed)
				(pads allowed)
				(copperpour not_allowed)
				(footprints allowed)
			)
			(placement
				(enabled no)
				(sheetname "")
			)
			(fill
				(thermal_gap 0.5)
				(thermal_bridge_width 0.5)
				(island_removal_mode 0)
			)
			(polygon
				(pts
					(xy 409.7401 -125.8189) (xy 408.8003 -125.8189) (xy 408.8003 -125.3109) (xy 409.7401 -125.3109)
				)
			)
		)
		(zone
			(layer "B.Cu")
			(hatch none 0.5)
			(connect_pads
				(clearance 0)
			)
			(min_thickness 0.25)
			(keepout
				(tracks allowed)
				(vias not_allowed)
				(pads allowed)
				(copperpour not_allowed)
				(footprints allowed)
			)
			(placement
				(enabled no)
				(sheetname "")
			)
			(fill
				(thermal_gap 0.5)
				(thermal_bridge_width 0.5)
				(island_removal_mode 0)
			)
			(polygon
				(pts
					(xy 409.7401 -125.8189) (xy 408.8003 -125.8189) (xy 408.8003 -125.3109) (xy 409.7401 -125.3109)
				)
			)
		)
	)
	(footprint ""
		(layer "B.Cu")
		(at 28.801568 -134.874 180)
		(property "Reference" "R9M1"
			(at 0 0 0)
			(layer "B.SilkS")
			(hide yes)
			(effects
				(font
					(size 1.27 1.27)
				)
				(justify mirror)
			)
		)
		(property "Value" ""
			(at 0 0 0)
			(layer "B.Fab")
			(effects
				(font
					(size 1.27 1.27)
				)
				(justify mirror)
			)
		)
		(duplicate_pad_numbers_are_jumpers no)
		(fp_poly
			(pts
				(xy 0.2794 -0.1016) (xy -0.2794 -0.1016) (xy -0.2794 0.9906) (xy 0.2794 0.9906)
			)
			(stroke
				(width 0)
				(type default)
			)
			(fill no)
			(layer "B.CrtYd")
		)
		(fp_line
			(start 0.2794 0.9906)
			(end -0.2794 0.9906)
			(stroke
				(width 0.1)
				(type default)
			)
			(layer "B.Fab")
		)
		(fp_line
			(start 0.2794 -0.1016)
			(end 0.2794 0.9906)
			(stroke
				(width 0.1)
				(type default)
			)
			(layer "B.Fab")
		)
		(fp_line
			(start -0.2794 0.9906)
			(end -0.2794 -0.1016)
			(stroke
				(width 0.1)
				(type default)
			)
			(layer "B.Fab")
		)
		(fp_line
			(start -0.2794 -0.1016)
			(end 0.2794 -0.1016)
			(stroke
				(width 0.1)
				(type default)
			)
			(layer "B.Fab")
		)
		(pad "1" smd rect
			(at 0 0)
			(size 0.508 0.508)
			(layers "B.Cu" "B.Mask" "B.Paste")
			(net "PVDDQ_KLM")
		)
		(pad "2" smd rect
			(at 0 0.889)
			(size 0.508 0.508)
			(layers "B.Cu" "B.Mask" "B.Paste")
			(net "M_K_VREF")
		)
		(zone
			(layer "B.Cu")
			(hatch none 0.5)
			(connect_pads
				(clearance 0)
			)
			(min_thickness 0.25)
			(keepout
				(tracks not_allowed)
				(vias allowed)
				(pads allowed)
				(copperpour not_allowed)
				(footprints allowed)
			)
			(placement
				(enabled no)
				(sheetname "")
			)
			(fill
				(thermal_gap 0.5)
				(thermal_bridge_width 0.5)
				(island_removal_mode 0)
			)
			(polygon
				(pts
					(xy 28.547568 -135.509) (xy 29.055568 -135.509) (xy 29.055568 -135.128) (xy 28.547568 -135.128)
				)
			)
		)
		(zone
			(layer "B.Cu")
			(hatch none 0.5)
			(connect_pads
				(clearance 0)
			)
			(min_thickness 0.25)
			(keepout
				(tracks allowed)
				(vias not_allowed)
				(pads allowed)
				(copperpour not_allowed)
				(footprints allowed)
			)
			(placement
				(enabled no)
				(sheetname "")
			)
			(fill
				(thermal_gap 0.5)
				(thermal_bridge_width 0.5)
				(island_removal_mode 0)
			)
			(polygon
				(pts
					(xy 28.547568 -135.128) (xy 29.055568 -135.128) (xy 29.055568 -135.509) (xy 28.547568 -135.509)
				)
			)
		)
	)
	(footprint ""
		(layer "B.Cu")
		(at 18.0594 -149.5044 -90)
		(property "Reference" "C9L4"
			(at -1.97993 9.0424 0)
			(unlocked yes)
			(layer "B.SilkS")
			(effects
				(font
					(size 0.7874 0.5842)
					(thickness 0.1524)
				)
				(justify mirror)
			)
		)
		(property "Value" ""
			(at 0 0 90)
			(layer "B.Fab")
			(effects
				(font
					(size 1.27 1.27)
				)
				(justify mirror)
			)
		)
		(duplicate_pad_numbers_are_jumpers no)
		(fp_line
			(start -2.286 7.366)
			(end -1.600708 7.366)
			(stroke
				(width 0.1524)
				(type default)
			)
			(layer "B.SilkS")
		)
		(fp_line
			(start -2.286 7.366)
			(end -2.286 1.63195)
			(stroke
				(width 0.1524)
				(type default)
			)
			(layer "B.SilkS")
		)
		(fp_line
			(start 2.286 7.366)
			(end 1.60147 7.366)
			(stroke
				(width 0.1524)
				(type default)
			)
			(layer "B.SilkS")
		)
		(fp_line
			(start 2.286 7.366)
			(end 2.286 1.632712)
			(stroke
				(width 0.1524)
				(type default)
			)
			(layer "B.SilkS")
		)
		(fp_line
			(start -2.504948 1.633728)
			(end -1.6002 1.633728)
			(stroke
				(width 0.1524)
				(type default)
			)
			(layer "B.SilkS")
		)
		(fp_line
			(start 2.563114 1.633728)
			(end 1.6002 1.633728)
			(stroke
				(width 0.1524)
				(type default)
			)
			(layer "B.SilkS")
		)
		(fp_line
			(start -2.504948 -1.616456)
			(end -2.504948 1.633728)
			(stroke
				(width 0.1524)
				(type default)
			)
			(layer "B.SilkS")
		)
		(fp_line
			(start -1.6002 -1.616456)
			(end -2.504948 -1.616456)
			(stroke
				(width 0.1524)
				(type default)
			)
			(layer "B.SilkS")
		)
		(fp_line
			(start 1.6002 -1.616456)
			(end 2.563114 -1.616456)
			(stroke
				(width 0.1524)
				(type default)
			)
			(layer "B.SilkS")
		)
		(fp_line
			(start 2.563114 -1.616456)
			(end 2.563114 1.633728)
			(stroke
				(width 0.1524)
				(type default)
			)
			(layer "B.SilkS")
		)
		(fp_rect
			(start 2.286 -0.254)
			(end -2.286 7.366)
			(stroke
				(width 0)
				(type default)
			)
			(fill no)
			(layer "B.CrtYd")
		)
		(fp_line
			(start -2.286 7.366)
			(end 2.286 7.366)
			(stroke
				(width 0.1)
				(type default)
			)
			(layer "B.Fab")
		)
		(fp_line
			(start 2.286 7.366)
			(end 2.286 -0.254)
			(stroke
				(width 0.1)
				(type default)
			)
			(layer "B.Fab")
		)
		(fp_line
			(start -2.286 -0.254)
			(end -2.286 7.366)
			(stroke
				(width 0.1)
				(type default)
			)
			(layer "B.Fab")
		)
		(fp_line
			(start 2.286 -0.254)
			(end -2.286 -0.254)
			(stroke
				(width 0.1)
				(type default)
			)
			(layer "B.Fab")
		)
		(pad "1" smd rect
			(at 0 0 90)
			(size 2.54 3.048)
			(layers "B.Cu" "B.Mask" "B.Paste")
			(net "PVDDQ_KLM")
		)
		(pad "2" smd rect
			(at 0 7.112 90)
			(size 2.54 3.048)
			(layers "B.Cu" "B.Mask" "B.Paste")
			(net "GND")
		)
	)
	(footprint ""
		(layer "B.Cu")
		(at 13.84046 -106.59618 90)
		(property "Reference" "C9N4"
			(at 0 0 90)
			(layer "B.SilkS")
			(hide yes)
			(effects
				(font
					(size 1.27 1.27)
				)
				(justify mirror)
			)
		)
		(property "Value" ""
			(at 0 0 90)
			(layer "B.Fab")
			(effects
				(font
					(size 1.27 1.27)
				)
				(justify mirror)
			)
		)
		(duplicate_pad_numbers_are_jumpers no)
		(fp_poly
			(pts
				(xy -0.3048 -0.1016) (xy -0.3048 0.9906) (xy 0.3048 0.9906) (xy 0.3048 -0.1016)
			)
			(stroke
				(width 0)
				(type default)
			)
			(fill no)
			(layer "B.CrtYd")
		)
		(fp_line
			(start 0.3048 -0.1016)
			(end 0.3048 0.9906)
			(stroke
				(width 0.1)
				(type default)
			)
			(layer "B.Fab")
		)
		(fp_line
			(start -0.3048 -0.1016)
			(end 0.3048 -0.1016)
			(stroke
				(width 0.1)
				(type default)
			)
			(layer "B.Fab")
		)
		(fp_line
			(start 0.3048 0.9906)
			(end -0.3048 0.9906)
			(stroke
				(width 0.1)
				(type default)
			)
			(layer "B.Fab")
		)
		(fp_line
			(start -0.3048 0.9906)
			(end -0.3048 -0.1016)
			(stroke
				(width 0.1)
				(type default)
			)
			(layer "B.Fab")
		)
		(pad "1" smd rect
			(at 0 0 270)
			(size 0.508 0.508)
			(layers "B.Cu" "B.Mask" "B.Paste")
			(net "P3E_CPU1_PE3_MP_C_TXP<11>")
		)
		(pad "2" smd rect
			(at 0 0.889 270)
			(size 0.508 0.508)
			(layers "B.Cu" "B.Mask" "B.Paste")
			(net "P3E_CPU1_PE3_MP_TXP<11>")
		)
		(zone
			(layer "B.Cu")
			(hatch none 0.5)
			(connect_pads
				(clearance 0)
			)
			(min_thickness 0.25)
			(keepout
				(tracks allowed)
				(vias not_allowed)
				(pads allowed)
				(copperpour not_allowed)
				(footprints allowed)
			)
			(placement
				(enabled no)
				(sheetname "")
			)
			(fill
				(thermal_gap 0.5)
				(thermal_bridge_width 0.5)
				(island_removal_mode 0)
			)
			(polygon
				(pts
					(xy 14.09446 -106.85018) (xy 14.09446 -106.34218) (xy 14.47546 -106.34218) (xy 14.47546 -106.85018)
				)
			)
		)
		(zone
			(layer "B.Cu")
			(hatch none 0.5)
			(connect_pads
				(clearance 0)
			)
			(min_thickness 0.25)
			(keepout
				(tracks not_allowed)
				(vias allowed)
				(pads allowed)
				(copperpour not_allowed)
				(footprints allowed)
			)
			(placement
				(enabled no)
				(sheetname "")
			)
			(fill
				(thermal_gap 0.5)
				(thermal_bridge_width 0.5)
				(island_removal_mode 0)
			)
			(polygon
				(pts
					(xy 14.47546 -106.85018) (xy 14.47546 -106.34218) (xy 14.09446 -106.34218) (xy 14.09446 -106.85018)
				)
			)
		)
	)
	(footprint ""
		(layer "B.Cu")
		(at 458.0001 -41.51376 -90)
		(property "Reference" "C9W16"
			(at -0.97536 0.76708 0)
			(unlocked yes)
			(layer "B.SilkS")
			(effects
				(font
					(size 0.4064 0.254)
					(thickness 0.1524)
				)
				(justify mirror)
			)
		)
		(property "Value" ""
			(at 0 0 90)
			(layer "B.Fab")
			(effects
				(font
					(size 1.27 1.27)
				)
				(justify mirror)
			)
		)
		(duplicate_pad_numbers_are_jumpers no)
		(fp_poly
			(pts
				(xy 0.4953 -0.2032) (xy -0.4953 -0.2032) (xy -0.4953 1.6002) (xy 0.4953 1.6002)
			)
			(stroke
				(width 0)
				(type default)
			)
			(fill no)
			(layer "B.CrtYd")
		)
		(fp_line
			(start -0.4953 1.6002)
			(end 0.4953 1.6002)
			(stroke
				(width 0.1)
				(type default)
			)
			(layer "B.Fab")
		)
		(fp_line
			(start 0.4953 1.6002)
			(end 0.4953 -0.2032)
			(stroke
				(width 0.1)
				(type default)
			)
			(layer "B.Fab")
		)
		(fp_line
			(start -0.4953 -0.2032)
			(end -0.4953 1.6002)
			(stroke
				(width 0.1)
				(type default)
			)
			(layer "B.Fab")
		)
		(fp_line
			(start 0.4953 -0.2032)
			(end -0.4953 -0.2032)
			(stroke
				(width 0.1)
				(type default)
			)
			(layer "B.Fab")
		)
		(pad "1" smd rect
			(at 0 0 90)
			(size 0.762 0.889)
			(layers "B.Cu" "B.Mask" "B.Paste")
			(net "P1V15_AUX_BMC")
		)
		(pad "2" smd rect
			(at 0 1.397 90)
			(size 0.762 0.889)
			(layers "B.Cu" "B.Mask" "B.Paste")
			(net "GND")
		)
		(zone
			(layer "B.Cu")
			(hatch none 0.5)
			(connect_pads
				(clearance 0)
			)
			(min_thickness 0.25)
			(keepout
				(tracks not_allowed)
				(vias allowed)
				(pads allowed)
				(copperpour not_allowed)
				(footprints allowed)
			)
			(placement
				(enabled no)
				(sheetname "")
			)
			(fill
				(thermal_gap 0.5)
				(thermal_bridge_width 0.5)
				(island_removal_mode 0)
			)
			(polygon
				(pts
					(xy 457.5556 -41.13276) (xy 457.5556 -41.89476) (xy 457.0476 -41.89476) (xy 457.0476 -41.13276)
				)
			)
		)
	)
	(footprint ""
		(layer "B.Cu")
		(at 154.023568 -135.376412 -90)
		(property "Reference" "C7M4"
			(at 0 0 90)
			(layer "B.SilkS")
			(hide yes)
			(effects
				(font
					(size 1.27 1.27)
				)
				(justify mirror)
			)
		)
		(property "Value" ""
			(at 0 0 90)
			(layer "B.Fab")
			(effects
				(font
					(size 1.27 1.27)
				)
				(justify mirror)
			)
		)
		(duplicate_pad_numbers_are_jumpers no)
		(fp_rect
			(start 0.4953 1.6002)
			(end -0.4953 -0.2032)
			(stroke
				(width 0)
				(type default)
			)
			(fill no)
			(layer "B.CrtYd")
		)
		(fp_line
			(start -0.4953 1.6002)
			(end 0.4953 1.6002)
			(stroke
				(width 0.1)
				(type default)
			)
			(layer "B.Fab")
		)
		(fp_line
			(start 0.4953 1.6002)
			(end 0.4953 -0.2032)
			(stroke
				(width 0.1)
				(type default)
			)
			(layer "B.Fab")
		)
		(fp_line
			(start -0.4953 -0.2032)
			(end -0.4953 1.6002)
			(stroke
				(width 0.1)
				(type default)
			)
			(layer "B.Fab")
		)
		(fp_line
			(start 0.4953 -0.2032)
			(end -0.4953 -0.2032)
			(stroke
				(width 0.1)
				(type default)
			)
			(layer "B.Fab")
		)
		(pad "1" smd rect
			(at 0 0 90)
			(size 0.762 0.889)
			(layers "B.Cu" "B.Mask" "B.Paste")
			(net "PVPP_KLM")
		)
		(pad "2" smd rect
			(at 0 1.397 90)
			(size 0.762 0.889)
			(layers "B.Cu" "B.Mask" "B.Paste")
			(net "GND")
		)
		(zone
			(layer "B.Cu")
			(hatch none 0.5)
			(connect_pads
				(clearance 0)
			)
			(min_thickness 0.25)
			(keepout
				(tracks not_allowed)
				(vias allowed)
				(pads allowed)
				(copperpour not_allowed)
				(footprints allowed)
			)
			(placement
				(enabled no)
				(sheetname "")
			)
			(fill
				(thermal_gap 0.5)
				(thermal_bridge_width 0.5)
				(island_removal_mode 0)
			)
			(polygon
				(pts
					(xy 153.071068 -134.995412) (xy 153.579068 -134.995412) (xy 153.579068 -135.757412) (xy 153.071068 -135.757412)
				)
			)
		)
	)
	(footprint ""
		(layer "B.Cu")
		(at 100.6856 3.8862 -90)
		(property "Reference" "C8U13"
			(at 0 0 90)
			(layer "B.SilkS")
			(hide yes)
			(effects
				(font
					(size 1.27 1.27)
				)
				(justify mirror)
			)
		)
		(property "Value" ""
			(at 0 0 90)
			(layer "B.Fab")
			(effects
				(font
					(size 1.27 1.27)
				)
				(justify mirror)
			)
		)
		(duplicate_pad_numbers_are_jumpers no)
		(fp_rect
			(start 0.500126 1.598422)
			(end -0.500126 -0.201422)
			(stroke
				(width 0)
				(type default)
			)
			(fill no)
			(layer "B.CrtYd")
		)
		(fp_line
			(start -0.500126 1.598422)
			(end 0.500126 1.598422)
			(stroke
				(width 0.1)
				(type default)
			)
			(layer "B.Fab")
		)
		(fp_line
			(start 0.500126 1.598422)
			(end 0.500126 -0.201422)
			(stroke
				(width 0.1)
				(type default)
			)
			(layer "B.Fab")
		)
		(fp_line
			(start -0.500126 -0.201422)
			(end -0.500126 1.598422)
			(stroke
				(width 0.1)
				(type default)
			)
			(layer "B.Fab")
		)
		(fp_line
			(start 0.500126 -0.201422)
			(end -0.500126 -0.201422)
			(stroke
				(width 0.1)
				(type default)
			)
			(layer "B.Fab")
		)
		(pad "1" smd rect
			(at 0 0 180)
			(size 0.889 0.9906)
			(layers "B.Cu" "B.Mask" "B.Paste")
			(net "PVDDQ_GHJ")
		)
		(pad "2" smd rect
			(at 0 1.397 180)
			(size 0.889 0.9906)
			(layers "B.Cu" "B.Mask" "B.Paste")
			(net "GND")
		)
		(zone
			(layer "B.Cu")
			(hatch none 0.5)
			(connect_pads
				(clearance 0)
			)
			(min_thickness 0.25)
			(keepout
				(tracks allowed)
				(vias not_allowed)
				(pads allowed)
				(copperpour not_allowed)
				(footprints allowed)
			)
			(placement
				(enabled no)
				(sheetname "")
			)
			(fill
				(thermal_gap 0.5)
				(thermal_bridge_width 0.5)
				(island_removal_mode 0)
			)
			(polygon
				(pts
					(xy 99.7331 4.3815) (xy 100.2411 4.3815) (xy 100.2411 3.3909) (xy 99.7331 3.3909)
				)
			)
		)
		(zone
			(layer "B.Cu")
			(hatch none 0.5)
			(connect_pads
				(clearance 0)
			)
			(min_thickness 0.25)
			(keepout
				(tracks not_allowed)
				(vias allowed)
				(pads allowed)
				(copperpour not_allowed)
				(footprints allowed)
			)
			(placement
				(enabled no)
				(sheetname "")
			)
			(fill
				(thermal_gap 0.5)
				(thermal_bridge_width 0.5)
				(island_removal_mode 0)
			)
			(polygon
				(pts
					(xy 99.7331 4.3815) (xy 100.2411 4.3815) (xy 100.2411 3.3909) (xy 99.7331 3.3909)
				)
			)
		)
	)
	(footprint ""
		(layer "B.Cu")
		(at 391.668 -87.4395)
		(property "Reference" "R8D19"
			(at 0.8382 -0.67818 0)
			(unlocked yes)
			(layer "B.SilkS")
			(effects
				(font
					(size 0.4064 0.254)
					(thickness 0.1524)
				)
				(justify left mirror)
			)
		)
		(property "Value" ""
			(at 0 0 0)
			(layer "B.Fab")
			(effects
				(font
					(size 1.27 1.27)
				)
				(justify mirror)
			)
		)
		(duplicate_pad_numbers_are_jumpers no)
		(fp_poly
			(pts
				(xy 0.2794 -0.1016) (xy -0.2794 -0.1016) (xy -0.2794 0.9906) (xy 0.2794 0.9906)
			)
			(stroke
				(width 0)
				(type default)
			)
			(fill no)
			(layer "B.CrtYd")
		)
		(fp_line
			(start -0.2794 -0.1016)
			(end 0.2794 -0.1016)
			(stroke
				(width 0.1)
				(type default)
			)
			(layer "B.Fab")
		)
		(fp_line
			(start -0.2794 0.9906)
			(end -0.2794 -0.1016)
			(stroke
				(width 0.1)
				(type default)
			)
			(layer "B.Fab")
		)
		(fp_line
			(start 0.2794 -0.1016)
			(end 0.2794 0.9906)
			(stroke
				(width 0.1)
				(type default)
			)
			(layer "B.Fab")
		)
		(fp_line
			(start 0.2794 0.9906)
			(end -0.2794 0.9906)
			(stroke
				(width 0.1)
				(type default)
			)
			(layer "B.Fab")
		)
		(pad "1" smd rect
			(at 0 0 180)
			(size 0.508 0.508)
			(layers "B.Cu" "B.Mask" "B.Paste")
			(net "SGPIO_PCH_SATA_DOUT0")
		)
		(pad "2" smd rect
			(at 0 0.889 180)
			(size 0.508 0.508)
			(layers "B.Cu" "B.Mask" "B.Paste")
			(net "SGPIO_PCH_SATA_DOUT0_R")
		)
		(zone
			(layer "B.Cu")
			(hatch none 0.5)
			(connect_pads
				(clearance 0)
			)
			(min_thickness 0.25)
			(keepout
				(tracks allowed)
				(vias not_allowed)
				(pads allowed)
				(copperpour not_allowed)
				(footprints allowed)
			)
			(placement
				(enabled no)
				(sheetname "")
			)
			(fill
				(thermal_gap 0.5)
				(thermal_bridge_width 0.5)
				(island_removal_mode 0)
			)
			(polygon
				(pts
					(xy 391.922 -87.1855) (xy 391.414 -87.1855) (xy 391.414 -86.8045) (xy 391.922 -86.8045)
				)
			)
		)
		(zone
			(layer "B.Cu")
			(hatch none 0.5)
			(connect_pads
				(clearance 0)
			)
			(min_thickness 0.25)
			(keepout
				(tracks not_allowed)
				(vias allowed)
				(pads allowed)
				(copperpour not_allowed)
				(footprints allowed)
			)
			(placement
				(enabled no)
				(sheetname "")
			)
			(fill
				(thermal_gap 0.5)
				(thermal_bridge_width 0.5)
				(island_removal_mode 0)
			)
			(polygon
				(pts
					(xy 391.922 -86.8045) (xy 391.414 -86.8045) (xy 391.414 -87.1855) (xy 391.922 -87.1855)
				)
			)
		)
	)
	(footprint ""
		(layer "B.Cu")
		(at 104.775254 -68.17614 180)
		(property "Reference" "C8P33"
			(at 0 0 0)
			(layer "B.SilkS")
			(hide yes)
			(effects
				(font
					(size 1.27 1.27)
				)
				(justify mirror)
			)
		)
		(property "Value" ""
			(at 0 0 0)
			(layer "B.Fab")
			(effects
				(font
					(size 1.27 1.27)
				)
				(justify mirror)
			)
		)
		(duplicate_pad_numbers_are_jumpers no)
		(fp_poly
			(pts
				(xy 0.7239 -0.2159) (xy -0.7239 -0.2159) (xy -0.7239 1.9939) (xy 0.7239 1.9939)
			)
			(stroke
				(width 0)
				(type default)
			)
			(fill no)
			(layer "B.CrtYd")
		)
		(fp_line
			(start 0.7239 1.9939)
			(end -0.7239 1.9939)
			(stroke
				(width 0.1)
				(type default)
			)
			(layer "B.Fab")
		)
		(fp_line
			(start 0.7239 -0.2159)
			(end 0.7239 1.9939)
			(stroke
				(width 0.1)
				(type default)
			)
			(layer "B.Fab")
		)
		(fp_line
			(start -0.7239 1.9939)
			(end -0.7239 -0.2159)
			(stroke
				(width 0.1)
				(type default)
			)
			(layer "B.Fab")
		)
		(fp_line
			(start -0.7239 -0.2159)
			(end 0.7239 -0.2159)
			(stroke
				(width 0.1)
				(type default)
			)
			(layer "B.Fab")
		)
		(pad "1" smd rect
			(at 0 0)
			(size 1.27 1.016)
			(layers "B.Cu" "B.Mask" "B.Paste")
			(net "PVDDQ_GHJ")
		)
		(pad "2" smd rect
			(at 0 1.778)
			(size 1.27 1.016)
			(layers "B.Cu" "B.Mask" "B.Paste")
			(net "GND")
		)
		(zone
			(layer "B.Cu")
			(hatch none 0.5)
			(connect_pads
				(clearance 0)
			)
			(min_thickness 0.25)
			(keepout
				(tracks not_allowed)
				(vias allowed)
				(pads allowed)
				(copperpour not_allowed)
				(footprints allowed)
			)
			(placement
				(enabled no)
				(sheetname "")
			)
			(fill
				(thermal_gap 0.5)
				(thermal_bridge_width 0.5)
				(island_removal_mode 0)
			)
			(polygon
				(pts
					(xy 104.140254 -68.68414) (xy 105.410254 -68.68414) (xy 105.410254 -69.44614) (xy 104.140254 -69.44614)
				)
			)
		)
	)
	(footprint ""
		(layer "B.Cu")
		(at 382.07696 -105.005124 180)
		(property "Reference" "C3N23"
			(at 0 0 0)
			(layer "B.SilkS")
			(hide yes)
			(effects
				(font
					(size 1.27 1.27)
				)
				(justify mirror)
			)
		)
		(property "Value" ""
			(at 0 0 0)
			(layer "B.Fab")
			(effects
				(font
					(size 1.27 1.27)
				)
				(justify mirror)
			)
		)
		(duplicate_pad_numbers_are_jumpers no)
		(fp_rect
			(start 0.2794 0.9144)
			(end -0.2794 -0.1143)
			(stroke
				(width 0)
				(type default)
			)
			(fill no)
			(layer "B.CrtYd")
		)
		(fp_line
			(start 0.2794 0.9144)
			(end 0.2794 -0.1143)
			(stroke
				(width 0.1)
				(type default)
			)
			(layer "B.Fab")
		)
		(fp_line
			(start 0.2794 -0.1143)
			(end -0.2794 -0.1143)
			(stroke
				(width 0.1)
				(type default)
			)
			(layer "B.Fab")
		)
		(fp_line
			(start -0.2794 0.9144)
			(end 0.2794 0.9144)
			(stroke
				(width 0.1)
				(type default)
			)
			(layer "B.Fab")
		)
		(fp_line
			(start -0.2794 -0.1143)
			(end -0.2794 0.9144)
			(stroke
				(width 0.1)
				(type default)
			)
			(layer "B.Fab")
		)
		(pad "1" smd custom
			(at 0 0 90)
			(size 0.10414 0.10414)
			(layers "B.Cu" "B.Mask" "B.Paste")
			(net "P3V3_STBY")
			(options
				(clearance outline)
				(anchor circle)
			)
			(primitives
				(gr_poly
					(pts
						(xy -0.20828 -0.08636) (xy -0.20828 0.08636) (xy -0.08636 0.20828) (xy 0.086614 0.20828) (xy 0.20828 0.086614)
						(xy 0.20828 -0.08636) (xy 0.08636 -0.20828) (xy -0.08636 -0.20828)
					)
					(width 0)
					(fill yes)
				)
			)
		)
		(pad "2" smd custom
			(at 0 0.8001 90)
			(size 0.10414 0.10414)
			(layers "B.Cu" "B.Mask" "B.Paste")
			(net "GND")
			(options
				(clearance outline)
				(anchor circle)
			)
			(primitives
				(gr_poly
					(pts
						(xy -0.20828 -0.08636) (xy -0.20828 0.08636) (xy -0.08636 0.20828) (xy 0.086614 0.20828) (xy 0.20828 0.086614)
						(xy 0.20828 -0.08636) (xy 0.08636 -0.20828) (xy -0.08636 -0.20828)
					)
					(width 0)
					(fill yes)
				)
			)
		)
		(zone
			(layer "B.Cu")
			(hatch none 0.5)
			(connect_pads
				(clearance 0)
			)
			(min_thickness 0.25)
			(keepout
				(tracks not_allowed)
				(vias allowed)
				(pads allowed)
				(copperpour not_allowed)
				(footprints allowed)
			)
			(placement
				(enabled no)
				(sheetname "")
			)
			(fill
				(thermal_gap 0.5)
				(thermal_bridge_width 0.5)
				(island_removal_mode 0)
			)
			(polygon
				(pts
					(xy 381.98933 -105.214674) (xy 381.98933 -105.595674) (xy 382.16459 -105.595674) (xy 382.164844 -105.214674)
				)
			)
		)
		(zone
			(layer "B.Cu")
			(hatch none 0.5)
			(connect_pads
				(clearance 0)
			)
			(min_thickness 0.25)
			(keepout
				(tracks allowed)
				(vias not_allowed)
				(pads allowed)
				(copperpour not_allowed)
				(footprints allowed)
			)
			(placement
				(enabled no)
				(sheetname "")
			)
			(fill
				(thermal_gap 0.5)
				(thermal_bridge_width 0.5)
				(island_removal_mode 0)
			)
			(polygon
				(pts
					(xy 381.98933 -105.214674) (xy 381.98933 -105.595674) (xy 382.16459 -105.595674) (xy 382.164844 -105.214674)
				)
			)
		)
	)
	(footprint ""
		(layer "B.Cu")
		(at 368.935 -104.902 -90)
		(property "Reference" "C3N24"
			(at 0 0 90)
			(layer "B.SilkS")
			(hide yes)
			(effects
				(font
					(size 1.27 1.27)
				)
				(justify mirror)
			)
		)
		(property "Value" ""
			(at 0 0 90)
			(layer "B.Fab")
			(effects
				(font
					(size 1.27 1.27)
				)
				(justify mirror)
			)
		)
		(duplicate_pad_numbers_are_jumpers no)
		(fp_poly
			(pts
				(xy 0.4953 -0.2032) (xy -0.4953 -0.2032) (xy -0.4953 1.6002) (xy 0.4953 1.6002)
			)
			(stroke
				(width 0)
				(type default)
			)
			(fill no)
			(layer "B.CrtYd")
		)
		(fp_line
			(start -0.4953 1.6002)
			(end 0.4953 1.6002)
			(stroke
				(width 0.1)
				(type default)
			)
			(layer "B.Fab")
		)
		(fp_line
			(start 0.4953 1.6002)
			(end 0.4953 -0.2032)
			(stroke
				(width 0.1)
				(type default)
			)
			(layer "B.Fab")
		)
		(fp_line
			(start -0.4953 -0.2032)
			(end -0.4953 1.6002)
			(stroke
				(width 0.1)
				(type default)
			)
			(layer "B.Fab")
		)
		(fp_line
			(start 0.4953 -0.2032)
			(end -0.4953 -0.2032)
			(stroke
				(width 0.1)
				(type default)
			)
			(layer "B.Fab")
		)
		(pad "1" smd rect
			(at 0 0 90)
			(size 0.762 0.889)
			(layers "B.Cu" "B.Mask" "B.Paste")
			(net "PVNN_PCH_STBY")
		)
		(pad "2" smd rect
			(at 0 1.397 90)
			(size 0.762 0.889)
			(layers "B.Cu" "B.Mask" "B.Paste")
			(net "GND")
		)
		(zone
			(layer "B.Cu")
			(hatch none 0.5)
			(connect_pads
				(clearance 0)
			)
			(min_thickness 0.25)
			(keepout
				(tracks not_allowed)
				(vias allowed)
				(pads allowed)
				(copperpour not_allowed)
				(footprints allowed)
			)
			(placement
				(enabled no)
				(sheetname "")
			)
			(fill
				(thermal_gap 0.5)
				(thermal_bridge_width 0.5)
				(island_removal_mode 0)
			)
			(polygon
				(pts
					(xy 368.4905 -104.521) (xy 368.4905 -105.283) (xy 367.9825 -105.283) (xy 367.9825 -104.521)
				)
			)
		)
	)
	(footprint ""
		(layer "B.Cu")
		(at -4.36626 -120.60936)
		(property "Reference" "C9M7"
			(at 0 0 0)
			(layer "B.SilkS")
			(hide yes)
			(effects
				(font
					(size 1.27 1.27)
				)
				(justify mirror)
			)
		)
		(property "Value" ""
			(at 0 0 0)
			(layer "B.Fab")
			(effects
				(font
					(size 1.27 1.27)
				)
				(justify mirror)
			)
		)
		(duplicate_pad_numbers_are_jumpers no)
		(fp_rect
			(start -0.3048 0.9906)
			(end 0.3048 -0.1016)
			(stroke
				(width 0)
				(type default)
			)
			(fill no)
			(layer "B.CrtYd")
		)
		(fp_line
			(start -0.3048 -0.1016)
			(end 0.3048 -0.1016)
			(stroke
				(width 0.1)
				(type default)
			)
			(layer "B.Fab")
		)
		(fp_line
			(start -0.3048 0.9906)
			(end -0.3048 -0.1016)
			(stroke
				(width 0.1)
				(type default)
			)
			(layer "B.Fab")
		)
		(fp_line
			(start 0.3048 -0.1016)
			(end 0.3048 0.9906)
			(stroke
				(width 0.1)
				(type default)
			)
			(layer "B.Fab")
		)
		(fp_line
			(start 0.3048 0.9906)
			(end -0.3048 0.9906)
			(stroke
				(width 0.1)
				(type default)
			)
			(layer "B.Fab")
		)
		(pad "1" smd rect
			(at 0 0 180)
			(size 0.508 0.508)
			(layers "B.Cu" "B.Mask" "B.Paste")
			(net "P3V3_STBY")
		)
		(pad "2" smd rect
			(at 0 0.889 180)
			(size 0.508 0.508)
			(layers "B.Cu" "B.Mask" "B.Paste")
			(net "GND")
		)
		(zone
			(layer "B.Cu")
			(hatch none 0.5)
			(connect_pads
				(clearance 0)
			)
			(min_thickness 0.25)
			(keepout
				(tracks allowed)
				(vias not_allowed)
				(pads allowed)
				(copperpour not_allowed)
				(footprints allowed)
			)
			(placement
				(enabled no)
				(sheetname "")
			)
			(fill
				(thermal_gap 0.5)
				(thermal_bridge_width 0.5)
				(island_removal_mode 0)
			)
			(polygon
				(pts
					(xy -4.62026 -119.97436) (xy -4.11226 -119.97436) (xy -4.11226 -120.35536) (xy -4.62026 -120.35536)
				)
			)
		)
		(zone
			(layer "B.Cu")
			(hatch none 0.5)
			(connect_pads
				(clearance 0)
			)
			(min_thickness 0.25)
			(keepout
				(tracks not_allowed)
				(vias allowed)
				(pads allowed)
				(copperpour not_allowed)
				(footprints allowed)
			)
			(placement
				(enabled no)
				(sheetname "")
			)
			(fill
				(thermal_gap 0.5)
				(thermal_bridge_width 0.5)
				(island_removal_mode 0)
			)
			(polygon
				(pts
					(xy -4.62026 -119.97436) (xy -4.11226 -119.97436) (xy -4.11226 -120.35536) (xy -4.62026 -120.35536)
				)
			)
		)
	)
	(footprint ""
		(layer "B.Cu")
		(at 17.653 -42.291 -90)
		(property "Reference" "R9R12"
			(at 0 0 90)
			(layer "B.SilkS")
			(hide yes)
			(effects
				(font
					(size 1.27 1.27)
				)
				(justify mirror)
			)
		)
		(property "Value" ""
			(at 0 0 90)
			(layer "B.Fab")
			(effects
				(font
					(size 1.27 1.27)
				)
				(justify mirror)
			)
		)
		(duplicate_pad_numbers_are_jumpers no)
		(fp_poly
			(pts
				(xy 0.2794 -0.1016) (xy -0.2794 -0.1016) (xy -0.2794 0.9906) (xy 0.2794 0.9906)
			)
			(stroke
				(width 0)
				(type default)
			)
			(fill no)
			(layer "B.CrtYd")
		)
		(fp_line
			(start -0.2794 0.9906)
			(end -0.2794 -0.1016)
			(stroke
				(width 0.1)
				(type default)
			)
			(layer "B.Fab")
		)
		(fp_line
			(start 0.2794 0.9906)
			(end -0.2794 0.9906)
			(stroke
				(width 0.1)
				(type default)
			)
			(layer "B.Fab")
		)
		(fp_line
			(start -0.2794 -0.1016)
			(end 0.2794 -0.1016)
			(stroke
				(width 0.1)
				(type default)
			)
			(layer "B.Fab")
		)
		(fp_line
			(start 0.2794 -0.1016)
			(end 0.2794 0.9906)
			(stroke
				(width 0.1)
				(type default)
			)
			(layer "B.Fab")
		)
		(pad "1" smd rect
			(at 0 0 90)
			(size 0.508 0.508)
			(layers "B.Cu" "B.Mask" "B.Paste")
			(net "FAN_TACH2")
		)
		(pad "2" smd rect
			(at 0 0.889 90)
			(size 0.508 0.508)
			(layers "B.Cu" "B.Mask" "B.Paste")
			(net "FAN_TACH2_R")
		)
		(zone
			(layer "B.Cu")
			(hatch none 0.5)
			(connect_pads
				(clearance 0)
			)
			(min_thickness 0.25)
			(keepout
				(tracks not_allowed)
				(vias allowed)
				(pads allowed)
				(copperpour not_allowed)
				(footprints allowed)
			)
			(placement
				(enabled no)
				(sheetname "")
			)
			(fill
				(thermal_gap 0.5)
				(thermal_bridge_width 0.5)
				(island_removal_mode 0)
			)
			(polygon
				(pts
					(xy 17.018 -42.037) (xy 17.018 -42.545) (xy 17.399 -42.545) (xy 17.399 -42.037)
				)
			)
		)
		(zone
			(layer "B.Cu")
			(hatch none 0.5)
			(connect_pads
				(clearance 0)
			)
			(min_thickness 0.25)
			(keepout
				(tracks allowed)
				(vias not_allowed)
				(pads allowed)
				(copperpour not_allowed)
				(footprints allowed)
			)
			(placement
				(enabled no)
				(sheetname "")
			)
			(fill
				(thermal_gap 0.5)
				(thermal_bridge_width 0.5)
				(island_removal_mode 0)
			)
			(polygon
				(pts
					(xy 17.399 -42.037) (xy 17.399 -42.545) (xy 17.018 -42.545) (xy 17.018 -42.037)
				)
			)
		)
	)
	(footprint ""
		(layer "B.Cu")
		(at 271.731486 -79.60614 180)
		(property "Reference" "C5P12"
			(at 0 0 0)
			(layer "B.SilkS")
			(hide yes)
			(effects
				(font
					(size 1.27 1.27)
				)
				(justify mirror)
			)
		)
		(property "Value" ""
			(at 0 0 0)
			(layer "B.Fab")
			(effects
				(font
					(size 1.27 1.27)
				)
				(justify mirror)
			)
		)
		(duplicate_pad_numbers_are_jumpers no)
		(fp_poly
			(pts
				(xy 0.7239 -0.2159) (xy -0.7239 -0.2159) (xy -0.7239 1.9939) (xy 0.7239 1.9939)
			)
			(stroke
				(width 0)
				(type default)
			)
			(fill no)
			(layer "B.CrtYd")
		)
		(fp_line
			(start 0.7239 1.9939)
			(end -0.7239 1.9939)
			(stroke
				(width 0.1)
				(type default)
			)
			(layer "B.Fab")
		)
		(fp_line
			(start 0.7239 -0.2159)
			(end 0.7239 1.9939)
			(stroke
				(width 0.1)
				(type default)
			)
			(layer "B.Fab")
		)
		(fp_line
			(start -0.7239 1.9939)
			(end -0.7239 -0.2159)
			(stroke
				(width 0.1)
				(type default)
			)
			(layer "B.Fab")
		)
		(fp_line
			(start -0.7239 -0.2159)
			(end 0.7239 -0.2159)
			(stroke
				(width 0.1)
				(type default)
			)
			(layer "B.Fab")
		)
		(pad "1" smd rect
			(at 0 0)
			(size 1.27 1.016)
			(layers "B.Cu" "B.Mask" "B.Paste")
			(net "PVCCMCP_CPU0")
		)
		(pad "2" smd rect
			(at 0 1.778)
			(size 1.27 1.016)
			(layers "B.Cu" "B.Mask" "B.Paste")
			(net "GND")
		)
		(zone
			(layer "B.Cu")
			(hatch none 0.5)
			(connect_pads
				(clearance 0)
			)
			(min_thickness 0.25)
			(keepout
				(tracks not_allowed)
				(vias allowed)
				(pads allowed)
				(copperpour not_allowed)
				(footprints allowed)
			)
			(placement
				(enabled no)
				(sheetname "")
			)
			(fill
				(thermal_gap 0.5)
				(thermal_bridge_width 0.5)
				(island_removal_mode 0)
			)
			(polygon
				(pts
					(xy 271.096486 -80.11414) (xy 272.366486 -80.11414) (xy 272.366486 -80.87614) (xy 271.096486 -80.87614)
				)
			)
		)
	)
	(footprint ""
		(layer "B.Cu")
		(at 32.3342 -54.5084 90)
		(property "Reference" "R9R2"
			(at 0 0 90)
			(layer "B.SilkS")
			(hide yes)
			(effects
				(font
					(size 1.27 1.27)
				)
				(justify mirror)
			)
		)
		(property "Value" ""
			(at 0 0 90)
			(layer "B.Fab")
			(effects
				(font
					(size 1.27 1.27)
				)
				(justify mirror)
			)
		)
		(duplicate_pad_numbers_are_jumpers no)
		(fp_poly
			(pts
				(xy 0.2794 -0.1016) (xy -0.2794 -0.1016) (xy -0.2794 0.9906) (xy 0.2794 0.9906)
			)
			(stroke
				(width 0)
				(type default)
			)
			(fill no)
			(layer "B.CrtYd")
		)
		(fp_line
			(start 0.2794 -0.1016)
			(end 0.2794 0.9906)
			(stroke
				(width 0.1)
				(type default)
			)
			(layer "B.Fab")
		)
		(fp_line
			(start -0.2794 -0.1016)
			(end 0.2794 -0.1016)
			(stroke
				(width 0.1)
				(type default)
			)
			(layer "B.Fab")
		)
		(fp_line
			(start 0.2794 0.9906)
			(end -0.2794 0.9906)
			(stroke
				(width 0.1)
				(type default)
			)
			(layer "B.Fab")
		)
		(fp_line
			(start -0.2794 0.9906)
			(end -0.2794 -0.1016)
			(stroke
				(width 0.1)
				(type default)
			)
			(layer "B.Fab")
		)
		(pad "1" smd rect
			(at 0 0 270)
			(size 0.508 0.508)
			(layers "B.Cu" "B.Mask" "B.Paste")
			(net "VR_PVCCIN_CPU1_PH1_VCIN")
		)
		(pad "2" smd rect
			(at 0 0.889 270)
			(size 0.508 0.508)
			(layers "B.Cu" "B.Mask" "B.Paste")
			(net "P5V_STBY")
		)
		(zone
			(layer "B.Cu")
			(hatch none 0.5)
			(connect_pads
				(clearance 0)
			)
			(min_thickness 0.25)
			(keepout
				(tracks allowed)
				(vias not_allowed)
				(pads allowed)
				(copperpour not_allowed)
				(footprints allowed)
			)
			(placement
				(enabled no)
				(sheetname "")
			)
			(fill
				(thermal_gap 0.5)
				(thermal_bridge_width 0.5)
				(island_removal_mode 0)
			)
			(polygon
				(pts
					(xy 32.5882 -54.7624) (xy 32.5882 -54.2544) (xy 32.9692 -54.2544) (xy 32.9692 -54.7624)
				)
			)
		)
		(zone
			(layer "B.Cu")
			(hatch none 0.5)
			(connect_pads
				(clearance 0)
			)
			(min_thickness 0.25)
			(keepout
				(tracks not_allowed)
				(vias allowed)
				(pads allowed)
				(copperpour not_allowed)
				(footprints allowed)
			)
			(placement
				(enabled no)
				(sheetname "")
			)
			(fill
				(thermal_gap 0.5)
				(thermal_bridge_width 0.5)
				(island_removal_mode 0)
			)
			(polygon
				(pts
					(xy 32.9692 -54.7624) (xy 32.9692 -54.2544) (xy 32.5882 -54.2544) (xy 32.5882 -54.7624)
				)
			)
		)
	)
	(footprint ""
		(layer "B.Cu")
		(at 179.2986 -95.4532)
		(property "Reference" "C6N5"
			(at 3.17373 4.6482 270)
			(unlocked yes)
			(layer "B.SilkS")
			(effects
				(font
					(size 0.7874 0.5842)
					(thickness 0.1524)
				)
				(justify mirror)
			)
		)
		(property "Value" ""
			(at 0 0 0)
			(layer "B.Fab")
			(effects
				(font
					(size 1.27 1.27)
				)
				(justify mirror)
			)
		)
		(duplicate_pad_numbers_are_jumpers no)
		(fp_line
			(start -2.504948 -1.616456)
			(end -2.504948 1.633728)
			(stroke
				(width 0.1524)
				(type default)
			)
			(layer "B.SilkS")
		)
		(fp_line
			(start -2.504948 1.633728)
			(end -1.6002 1.633728)
			(stroke
				(width 0.1524)
				(type default)
			)
			(layer "B.SilkS")
		)
		(fp_line
			(start -2.286 7.366)
			(end -2.286 1.63195)
			(stroke
				(width 0.1524)
				(type default)
			)
			(layer "B.SilkS")
		)
		(fp_line
			(start -2.286 7.366)
			(end -1.600708 7.366)
			(stroke
				(width 0.1524)
				(type default)
			)
			(layer "B.SilkS")
		)
		(fp_line
			(start -1.6002 -1.616456)
			(end -2.504948 -1.616456)
			(stroke
				(width 0.1524)
				(type default)
			)
			(layer "B.SilkS")
		)
		(fp_line
			(start 1.6002 -1.616456)
			(end 2.563114 -1.616456)
			(stroke
				(width 0.1524)
				(type default)
			)
			(layer "B.SilkS")
		)
		(fp_line
			(start 2.286 7.366)
			(end 1.60147 7.366)
			(stroke
				(width 0.1524)
				(type default)
			)
			(layer "B.SilkS")
		)
		(fp_line
			(start 2.286 7.366)
			(end 2.286 1.632712)
			(stroke
				(width 0.1524)
				(type default)
			)
			(layer "B.SilkS")
		)
		(fp_line
			(start 2.563114 -1.616456)
			(end 2.563114 1.633728)
			(stroke
				(width 0.1524)
				(type default)
			)
			(layer "B.SilkS")
		)
		(fp_line
			(start 2.563114 1.633728)
			(end 1.6002 1.633728)
			(stroke
				(width 0.1524)
				(type default)
			)
			(layer "B.SilkS")
		)
		(fp_rect
			(start 2.286 7.366)
			(end -2.286 -0.254)
			(stroke
				(width 0)
				(type default)
			)
			(fill no)
			(layer "B.CrtYd")
		)
		(fp_line
			(start -2.286 -0.254)
			(end -2.286 7.366)
			(stroke
				(width 0.1)
				(type default)
			)
			(layer "B.Fab")
		)
		(fp_line
			(start -2.286 7.366)
			(end 2.286 7.366)
			(stroke
				(width 0.1)
				(type default)
			)
			(layer "B.Fab")
		)
		(fp_line
			(start 2.286 -0.254)
			(end -2.286 -0.254)
			(stroke
				(width 0.1)
				(type default)
			)
			(layer "B.Fab")
		)
		(fp_line
			(start 2.286 7.366)
			(end 2.286 -0.254)
			(stroke
				(width 0.1)
				(type default)
			)
			(layer "B.Fab")
		)
		(pad "1" smd rect
			(at 0 0 180)
			(size 2.54 3.048)
			(layers "B.Cu" "B.Mask" "B.Paste")
			(net "P12V_STBY")
		)
		(pad "2" smd rect
			(at 0 7.112 180)
			(size 2.54 3.048)
			(layers "B.Cu" "B.Mask" "B.Paste")
			(net "GND")
		)
	)
	(footprint ""
		(layer "B.Cu")
		(at 380.746 -46.0883 180)
		(property "Reference" "Q7E6"
			(at 1.17475 1.7907 90)
			(unlocked yes)
			(layer "B.SilkS")
			(effects
				(font
					(size 0.7874 0.5842)
					(thickness 0.1524)
				)
				(justify left mirror)
			)
		)
		(property "Value" ""
			(at 0 0 0)
			(layer "B.Fab")
			(effects
				(font
					(size 1.27 1.27)
				)
				(justify mirror)
			)
		)
		(duplicate_pad_numbers_are_jumpers no)
		(fp_circle
			(center 0.508 -0.7874)
			(end 0.381 -0.7874)
			(stroke
				(width 0.254)
				(type default)
			)
			(fill no)
			(layer "B.SilkS")
		)
		(fp_poly
			(pts
				(xy -0.2159 1.7526) (xy -1.5621 1.7526) (xy -1.5621 -0.4572) (xy -0.2159 -0.4572)
			)
			(stroke
				(width 0)
				(type default)
			)
			(fill no)
			(layer "B.CrtYd")
		)
		(fp_line
			(start -0.2159 1.75514)
			(end -1.5621 1.75514)
			(stroke
				(width 0.1)
				(type default)
			)
			(layer "B.Fab")
		)
		(fp_line
			(start -0.2159 -0.45466)
			(end -0.2159 1.75514)
			(stroke
				(width 0.1)
				(type default)
			)
			(layer "B.Fab")
		)
		(fp_line
			(start -1.5621 1.75514)
			(end -1.5621 -0.45466)
			(stroke
				(width 0.1)
				(type default)
			)
			(layer "B.Fab")
		)
		(fp_line
			(start -1.5621 -0.45466)
			(end -0.2159 -0.45466)
			(stroke
				(width 0.1)
				(type default)
			)
			(layer "B.Fab")
		)
		(fp_circle
			(center 0.508 -0.7874)
			(end 0.381 -0.7874)
			(stroke
				(width 0.254)
				(type default)
			)
			(fill no)
			(layer "B.Fab")
		)
		(pad "1" smd rect
			(at 0 0)
			(size 1.016 0.381)
			(layers "B.Cu" "B.Mask" "B.Paste")
			(net "GND")
		)
		(pad "2" smd rect
			(at 0 0.65024)
			(size 1.016 0.381)
			(layers "B.Cu" "B.Mask" "B.Paste")
			(net "IRQ_CPU1_PROCHOT_G_N")
		)
		(pad "3" smd rect
			(at 0 1.30048)
			(size 1.016 0.381)
			(layers "B.Cu" "B.Mask" "B.Paste")
			(net "H_CPU1_PROCHOT_G_N")
		)
		(pad "4" smd rect
			(at -1.778 1.30048)
			(size 1.016 0.381)
			(layers "B.Cu" "B.Mask" "B.Paste")
			(net "GND")
		)
		(pad "5" smd rect
			(at -1.778 0.65024)
			(size 1.016 0.381)
			(layers "B.Cu" "B.Mask" "B.Paste")
			(net "IRQ_CPU1_VRHOT")
		)
		(pad "6" smd rect
			(at -1.778 0)
			(size 1.016 0.381)
			(layers "B.Cu" "B.Mask" "B.Paste")
			(net "IRQ_CPU1_VRHOT")
		)
		(zone
			(layer "B.Cu")
			(hatch none 0.5)
			(connect_pads
				(clearance 0)
			)
			(min_thickness 0.25)
			(keepout
				(tracks allowed)
				(vias not_allowed)
				(pads allowed)
				(copperpour not_allowed)
				(footprints allowed)
			)
			(placement
				(enabled no)
				(sheetname "")
			)
			(fill
				(thermal_gap 0.5)
				(thermal_bridge_width 0.5)
				(island_removal_mode 0)
			)
			(polygon
				(pts
					(xy 380.238 -45.8978) (xy 381.254 -45.8978) (xy 381.254 -47.5869) (xy 380.238 -47.5869)
				)
			)
		)
		(zone
			(layer "B.Cu")
			(hatch none 0.5)
			(connect_pads
				(clearance 0)
			)
			(min_thickness 0.25)
			(keepout
				(tracks allowed)
				(vias not_allowed)
				(pads allowed)
				(copperpour not_allowed)
				(footprints allowed)
			)
			(placement
				(enabled no)
				(sheetname "")
			)
			(fill
				(thermal_gap 0.5)
				(thermal_bridge_width 0.5)
				(island_removal_mode 0)
			)
			(polygon
				(pts
					(xy 382.016 -45.8978) (xy 383.032 -45.8978) (xy 383.032 -47.5869) (xy 382.016 -47.5869)
				)
			)
		)
	)
	(footprint ""
		(layer "B.Cu")
		(at 490.3851 -121.5136 90)
		(property "Reference" "R9G12"
			(at 0 0 90)
			(layer "B.SilkS")
			(hide yes)
			(effects
				(font
					(size 1.27 1.27)
				)
				(justify mirror)
			)
		)
		(property "Value" ""
			(at 0 0 90)
			(layer "B.Fab")
			(effects
				(font
					(size 1.27 1.27)
				)
				(justify mirror)
			)
		)
		(duplicate_pad_numbers_are_jumpers no)
		(fp_poly
			(pts
				(xy 0.2794 -0.1016) (xy -0.2794 -0.1016) (xy -0.2794 0.9906) (xy 0.2794 0.9906)
			)
			(stroke
				(width 0)
				(type default)
			)
			(fill no)
			(layer "B.CrtYd")
		)
		(fp_line
			(start 0.2794 -0.1016)
			(end 0.2794 0.9906)
			(stroke
				(width 0.1)
				(type default)
			)
			(layer "B.Fab")
		)
		(fp_line
			(start -0.2794 -0.1016)
			(end 0.2794 -0.1016)
			(stroke
				(width 0.1)
				(type default)
			)
			(layer "B.Fab")
		)
		(fp_line
			(start 0.2794 0.9906)
			(end -0.2794 0.9906)
			(stroke
				(width 0.1)
				(type default)
			)
			(layer "B.Fab")
		)
		(fp_line
			(start -0.2794 0.9906)
			(end -0.2794 -0.1016)
			(stroke
				(width 0.1)
				(type default)
			)
			(layer "B.Fab")
		)
		(pad "1" smd rect
			(at 0 0 270)
			(size 0.508 0.508)
			(layers "B.Cu" "B.Mask" "B.Paste")
			(net "SMB_OCP_LAN_STBY_LVC3_SDA")
		)
		(pad "2" smd rect
			(at 0 0.889 270)
			(size 0.508 0.508)
			(layers "B.Cu" "B.Mask" "B.Paste")
			(net "SMB_SPRINGVILLE_STBY_LVC3_SDA")
		)
		(zone
			(layer "B.Cu")
			(hatch none 0.5)
			(connect_pads
				(clearance 0)
			)
			(min_thickness 0.25)
			(keepout
				(tracks allowed)
				(vias not_allowed)
				(pads allowed)
				(copperpour not_allowed)
				(footprints allowed)
			)
			(placement
				(enabled no)
				(sheetname "")
			)
			(fill
				(thermal_gap 0.5)
				(thermal_bridge_width 0.5)
				(island_removal_mode 0)
			)
			(polygon
				(pts
					(xy 490.6391 -121.7676) (xy 490.6391 -121.2596) (xy 491.0201 -121.2596) (xy 491.0201 -121.7676)
				)
			)
		)
		(zone
			(layer "B.Cu")
			(hatch none 0.5)
			(connect_pads
				(clearance 0)
			)
			(min_thickness 0.25)
			(keepout
				(tracks not_allowed)
				(vias allowed)
				(pads allowed)
				(copperpour not_allowed)
				(footprints allowed)
			)
			(placement
				(enabled no)
				(sheetname "")
			)
			(fill
				(thermal_gap 0.5)
				(thermal_bridge_width 0.5)
				(island_removal_mode 0)
			)
			(polygon
				(pts
					(xy 491.0201 -121.7676) (xy 491.0201 -121.2596) (xy 490.6391 -121.2596) (xy 490.6391 -121.7676)
				)
			)
		)
	)
	(footprint ""
		(layer "B.Cu")
		(at 349.2246 -147.715224 -90)
		(property "Reference" "R3L8"
			(at 0 0 90)
			(layer "B.SilkS")
			(hide yes)
			(effects
				(font
					(size 1.27 1.27)
				)
				(justify mirror)
			)
		)
		(property "Value" ""
			(at 0 0 90)
			(layer "B.Fab")
			(effects
				(font
					(size 1.27 1.27)
				)
				(justify mirror)
			)
		)
		(duplicate_pad_numbers_are_jumpers no)
		(fp_poly
			(pts
				(xy 0.2794 -0.1016) (xy -0.2794 -0.1016) (xy -0.2794 0.9906) (xy 0.2794 0.9906)
			)
			(stroke
				(width 0)
				(type default)
			)
			(fill no)
			(layer "B.CrtYd")
		)
		(fp_line
			(start -0.2794 0.9906)
			(end -0.2794 -0.1016)
			(stroke
				(width 0.1)
				(type default)
			)
			(layer "B.Fab")
		)
		(fp_line
			(start 0.2794 0.9906)
			(end -0.2794 0.9906)
			(stroke
				(width 0.1)
				(type default)
			)
			(layer "B.Fab")
		)
		(fp_line
			(start -0.2794 -0.1016)
			(end 0.2794 -0.1016)
			(stroke
				(width 0.1)
				(type default)
			)
			(layer "B.Fab")
		)
		(fp_line
			(start 0.2794 -0.1016)
			(end 0.2794 0.9906)
			(stroke
				(width 0.1)
				(type default)
			)
			(layer "B.Fab")
		)
		(pad "1" smd rect
			(at 0 0 90)
			(size 0.508 0.508)
			(layers "B.Cu" "B.Mask" "B.Paste")
			(net "VR_PVDDQ_DEF_PH2_VCIN")
		)
		(pad "2" smd rect
			(at 0 0.889 90)
			(size 0.508 0.508)
			(layers "B.Cu" "B.Mask" "B.Paste")
			(net "P5V_STBY")
		)
		(zone
			(layer "B.Cu")
			(hatch none 0.5)
			(connect_pads
				(clearance 0)
			)
			(min_thickness 0.25)
			(keepout
				(tracks not_allowed)
				(vias allowed)
				(pads allowed)
				(copperpour not_allowed)
				(footprints allowed)
			)
			(placement
				(enabled no)
				(sheetname "")
			)
			(fill
				(thermal_gap 0.5)
				(thermal_bridge_width 0.5)
				(island_removal_mode 0)
			)
			(polygon
				(pts
					(xy 348.5896 -147.461224) (xy 348.5896 -147.969224) (xy 348.9706 -147.969224) (xy 348.9706 -147.461224)
				)
			)
		)
		(zone
			(layer "B.Cu")
			(hatch none 0.5)
			(connect_pads
				(clearance 0)
			)
			(min_thickness 0.25)
			(keepout
				(tracks allowed)
				(vias not_allowed)
				(pads allowed)
				(copperpour not_allowed)
				(footprints allowed)
			)
			(placement
				(enabled no)
				(sheetname "")
			)
			(fill
				(thermal_gap 0.5)
				(thermal_bridge_width 0.5)
				(island_removal_mode 0)
			)
			(polygon
				(pts
					(xy 348.9706 -147.461224) (xy 348.9706 -147.969224) (xy 348.5896 -147.969224) (xy 348.5896 -147.461224)
				)
			)
		)
	)
	(footprint ""
		(layer "B.Cu")
		(at 487.357674 -52.946046 -90)
		(property "Reference" "F25W1"
			(at 0 0 90)
			(layer "B.SilkS")
			(hide yes)
			(effects
				(font
					(size 1.27 1.27)
				)
				(justify mirror)
			)
		)
		(property "Value" "*"
			(at 0 -5.312918 270)
			(unlocked yes)
			(layer "B.Fab")
			(hide yes)
			(effects
				(font
					(size 1.27 1.016)
					(thickness 0.1524)
				)
				(justify mirror)
			)
		)
		(property "Device Type" "POLYSW-D5A6V-2-GP-U_DISCRET-GAA"
			(at 0 -7.344918 270)
			(unlocked yes)
			(layer "B.Fab")
			(hide yes)
			(effects
				(font
					(size 1.27 1.016)
					(thickness 0.1524)
				)
				(justify mirror)
			)
		)
		(duplicate_pad_numbers_are_jumpers no)
		(fp_line
			(start -1.0287 1.6637)
			(end -1.0287 -1.6637)
			(stroke
				(width 0.1524)
				(type default)
			)
			(layer "B.SilkS")
		)
		(fp_line
			(start 1.0287 1.6637)
			(end -1.0287 1.6637)
			(stroke
				(width 0.1524)
				(type default)
			)
			(layer "B.SilkS")
		)
		(fp_line
			(start -1.0287 -1.6637)
			(end 1.0287 -1.6637)
			(stroke
				(width 0.1524)
				(type default)
			)
			(layer "B.SilkS")
		)
		(fp_line
			(start 1.0287 -1.6637)
			(end 1.0287 1.6637)
			(stroke
				(width 0.1524)
				(type default)
			)
			(layer "B.SilkS")
		)
		(fp_rect
			(start 1.1049 1.7399)
			(end -1.1049 -1.7399)
			(stroke
				(width 0)
				(type default)
			)
			(fill no)
			(layer "B.CrtYd")
		)
		(fp_poly
			(pts
				(xy 1.1049 -1.7399) (xy -1.1049 -1.7399) (xy -1.1049 1.7399) (xy 1.1049 1.7399)
			)
			(stroke
				(width 0)
				(type default)
			)
			(fill no)
			(layer "B.Fab")
		)
		(pad "1" smd rect
			(at 0 -0.9398 90)
			(size 1.6002 0.9652)
			(layers "B.Cu" "B.Mask" "B.Paste")
			(net "P5V_VGA")
		)
		(pad "2" smd rect
			(at 0 0.9398 90)
			(size 1.6002 0.9652)
			(layers "B.Cu" "B.Mask" "B.Paste")
			(net "P5V_VGA_D")
		)
	)
	(footprint ""
		(layer "B.Cu")
		(at 102.080568 3.81 90)
		(property "Reference" "C8U12"
			(at 0 0 90)
			(layer "B.SilkS")
			(hide yes)
			(effects
				(font
					(size 1.27 1.27)
				)
				(justify mirror)
			)
		)
		(property "Value" ""
			(at 0 0 90)
			(layer "B.Fab")
			(effects
				(font
					(size 1.27 1.27)
				)
				(justify mirror)
			)
		)
		(duplicate_pad_numbers_are_jumpers no)
		(fp_poly
			(pts
				(xy 0.7239 -0.2159) (xy -0.7239 -0.2159) (xy -0.7239 1.9939) (xy 0.7239 1.9939)
			)
			(stroke
				(width 0)
				(type default)
			)
			(fill no)
			(layer "B.CrtYd")
		)
		(fp_line
			(start 0.7239 -0.2159)
			(end 0.7239 1.9939)
			(stroke
				(width 0.1)
				(type default)
			)
			(layer "B.Fab")
		)
		(fp_line
			(start -0.7239 -0.2159)
			(end 0.7239 -0.2159)
			(stroke
				(width 0.1)
				(type default)
			)
			(layer "B.Fab")
		)
		(fp_line
			(start 0.7239 1.9939)
			(end -0.7239 1.9939)
			(stroke
				(width 0.1)
				(type default)
			)
			(layer "B.Fab")
		)
		(fp_line
			(start -0.7239 1.9939)
			(end -0.7239 -0.2159)
			(stroke
				(width 0.1)
				(type default)
			)
			(layer "B.Fab")
		)
		(pad "1" smd rect
			(at 0 0 270)
			(size 1.27 1.016)
			(layers "B.Cu" "B.Mask" "B.Paste")
			(net "PVDDQ_GHJ")
		)
		(pad "2" smd rect
			(at 0 1.778 270)
			(size 1.27 1.016)
			(layers "B.Cu" "B.Mask" "B.Paste")
			(net "GND")
		)
		(zone
			(layer "B.Cu")
			(hatch none 0.5)
			(connect_pads
				(clearance 0)
			)
			(min_thickness 0.25)
			(keepout
				(tracks not_allowed)
				(vias allowed)
				(pads allowed)
				(copperpour not_allowed)
				(footprints allowed)
			)
			(placement
				(enabled no)
				(sheetname "")
			)
			(fill
				(thermal_gap 0.5)
				(thermal_bridge_width 0.5)
				(island_removal_mode 0)
			)
			(polygon
				(pts
					(xy 102.588568 3.175) (xy 102.588568 4.445) (xy 103.350568 4.445) (xy 103.350568 3.175)
				)
			)
		)
	)
	(footprint ""
		(layer "B.Cu")
		(at 485.267 -30.226)
		(property "Reference" "FB2T2"
			(at -1.34747 0.197104 270)
			(unlocked yes)
			(layer "B.SilkS")
			(effects
				(font
					(size 0.7874 0.5842)
					(thickness 0.1524)
				)
				(justify mirror)
			)
		)
		(property "Value" ""
			(at 0 0 0)
			(layer "B.Fab")
			(effects
				(font
					(size 1.27 1.27)
				)
				(justify mirror)
			)
		)
		(duplicate_pad_numbers_are_jumpers no)
		(fp_poly
			(pts
				(xy 0.7239 -0.26035) (xy -0.7239 -0.26035) (xy -0.7239 2.03835) (xy 0.7239 2.03835)
			)
			(stroke
				(width 0)
				(type default)
			)
			(fill no)
			(layer "B.CrtYd")
		)
		(fp_line
			(start -0.7239 -0.26035)
			(end -0.7239 2.03835)
			(stroke
				(width 0.1)
				(type default)
			)
			(layer "B.Fab")
		)
		(fp_line
			(start -0.7239 2.03835)
			(end 0.7239 2.03835)
			(stroke
				(width 0.1)
				(type default)
			)
			(layer "B.Fab")
		)
		(fp_line
			(start 0.7239 -0.26035)
			(end -0.7239 -0.26035)
			(stroke
				(width 0.1)
				(type default)
			)
			(layer "B.Fab")
		)
		(fp_line
			(start 0.7239 2.03835)
			(end 0.7239 -0.26035)
			(stroke
				(width 0.1)
				(type default)
			)
			(layer "B.Fab")
		)
		(pad "1" smd rect
			(at 0 0 180)
			(size 1.27 1.016)
			(layers "B.Cu" "B.Mask" "B.Paste")
			(net "P3V3_STBY")
		)
		(pad "2" smd rect
			(at 0 1.778 180)
			(size 1.27 1.016)
			(layers "B.Cu" "B.Mask" "B.Paste")
			(net "P3V3_STBY_MNG")
		)
		(zone
			(layer "B.Cu")
			(hatch none 0.5)
			(connect_pads
				(clearance 0)
			)
			(min_thickness 0.25)
			(keepout
				(tracks not_allowed)
				(vias allowed)
				(pads allowed)
				(copperpour not_allowed)
				(footprints allowed)
			)
			(placement
				(enabled no)
				(sheetname "")
			)
			(fill
				(thermal_gap 0.5)
				(thermal_bridge_width 0.5)
				(island_removal_mode 0)
			)
			(polygon
				(pts
					(xy 484.632 -29.718) (xy 484.632 -28.956) (xy 484.7209 -28.956) (xy 485.902 -28.956) (xy 485.902 -29.718)
				)
			)
		)
	)
	(footprint ""
		(layer "B.Cu")
		(at 384.53695 -111.85525 180)
		(property "Reference" "C3N2"
			(at 0 0 0)
			(layer "B.SilkS")
			(hide yes)
			(effects
				(font
					(size 1.27 1.27)
				)
				(justify mirror)
			)
		)
		(property "Value" ""
			(at 0 0 0)
			(layer "B.Fab")
			(effects
				(font
					(size 1.27 1.27)
				)
				(justify mirror)
			)
		)
		(duplicate_pad_numbers_are_jumpers no)
		(fp_rect
			(start 0.2794 0.9144)
			(end -0.2794 -0.1143)
			(stroke
				(width 0)
				(type default)
			)
			(fill no)
			(layer "B.CrtYd")
		)
		(fp_line
			(start 0.2794 0.9144)
			(end 0.2794 -0.1143)
			(stroke
				(width 0.1)
				(type default)
			)
			(layer "B.Fab")
		)
		(fp_line
			(start 0.2794 -0.1143)
			(end -0.2794 -0.1143)
			(stroke
				(width 0.1)
				(type default)
			)
			(layer "B.Fab")
		)
		(fp_line
			(start -0.2794 0.9144)
			(end 0.2794 0.9144)
			(stroke
				(width 0.1)
				(type default)
			)
			(layer "B.Fab")
		)
		(fp_line
			(start -0.2794 -0.1143)
			(end -0.2794 0.9144)
			(stroke
				(width 0.1)
				(type default)
			)
			(layer "B.Fab")
		)
		(pad "1" smd custom
			(at 0 0 90)
			(size 0.10414 0.10414)
			(layers "B.Cu" "B.Mask" "B.Paste")
			(net "PVNN_PCH_STBY")
			(options
				(clearance outline)
				(anchor circle)
			)
			(primitives
				(gr_poly
					(pts
						(xy -0.20828 -0.08636) (xy -0.20828 0.08636) (xy -0.08636 0.20828) (xy 0.086614 0.20828) (xy 0.20828 0.086614)
						(xy 0.20828 -0.08636) (xy 0.08636 -0.20828) (xy -0.08636 -0.20828)
					)
					(width 0)
					(fill yes)
				)
			)
		)
		(pad "2" smd custom
			(at 0 0.8001 90)
			(size 0.10414 0.10414)
			(layers "B.Cu" "B.Mask" "B.Paste")
			(net "GND")
			(options
				(clearance outline)
				(anchor circle)
			)
			(primitives
				(gr_poly
					(pts
						(xy -0.20828 -0.08636) (xy -0.20828 0.08636) (xy -0.08636 0.20828) (xy 0.086614 0.20828) (xy 0.20828 0.086614)
						(xy 0.20828 -0.08636) (xy 0.08636 -0.20828) (xy -0.08636 -0.20828)
					)
					(width 0)
					(fill yes)
				)
			)
		)
		(zone
			(layer "B.Cu")
			(hatch none 0.5)
			(connect_pads
				(clearance 0)
			)
			(min_thickness 0.25)
			(keepout
				(tracks not_allowed)
				(vias allowed)
				(pads allowed)
				(copperpour not_allowed)
				(footprints allowed)
			)
			(placement
				(enabled no)
				(sheetname "")
			)
			(fill
				(thermal_gap 0.5)
				(thermal_bridge_width 0.5)
				(island_removal_mode 0)
			)
			(polygon
				(pts
					(xy 384.44932 -112.0648) (xy 384.44932 -112.4458) (xy 384.62458 -112.4458) (xy 384.624834 -112.0648)
				)
			)
		)
		(zone
			(layer "B.Cu")
			(hatch none 0.5)
			(connect_pads
				(clearance 0)
			)
			(min_thickness 0.25)
			(keepout
				(tracks allowed)
				(vias not_allowed)
				(pads allowed)
				(copperpour not_allowed)
				(footprints allowed)
			)
			(placement
				(enabled no)
				(sheetname "")
			)
			(fill
				(thermal_gap 0.5)
				(thermal_bridge_width 0.5)
				(island_removal_mode 0)
			)
			(polygon
				(pts
					(xy 384.44932 -112.0648) (xy 384.44932 -112.4458) (xy 384.62458 -112.4458) (xy 384.624834 -112.0648)
				)
			)
		)
	)
	(footprint ""
		(layer "B.Cu")
		(at 397.637 -37.846 180)
		(property "Reference" "R8G2"
			(at 0 0 0)
			(layer "B.SilkS")
			(hide yes)
			(effects
				(font
					(size 1.27 1.27)
				)
				(justify mirror)
			)
		)
		(property "Value" ""
			(at 0 0 0)
			(layer "B.Fab")
			(effects
				(font
					(size 1.27 1.27)
				)
				(justify mirror)
			)
		)
		(duplicate_pad_numbers_are_jumpers no)
		(fp_poly
			(pts
				(xy 0.2794 -0.1016) (xy -0.2794 -0.1016) (xy -0.2794 0.9906) (xy 0.2794 0.9906)
			)
			(stroke
				(width 0)
				(type default)
			)
			(fill no)
			(layer "B.CrtYd")
		)
		(fp_line
			(start 0.2794 0.9906)
			(end -0.2794 0.9906)
			(stroke
				(width 0.1)
				(type default)
			)
			(layer "B.Fab")
		)
		(fp_line
			(start 0.2794 -0.1016)
			(end 0.2794 0.9906)
			(stroke
				(width 0.1)
				(type default)
			)
			(layer "B.Fab")
		)
		(fp_line
			(start -0.2794 0.9906)
			(end -0.2794 -0.1016)
			(stroke
				(width 0.1)
				(type default)
			)
			(layer "B.Fab")
		)
		(fp_line
			(start -0.2794 -0.1016)
			(end 0.2794 -0.1016)
			(stroke
				(width 0.1)
				(type default)
			)
			(layer "B.Fab")
		)
		(pad "1" smd rect
			(at 0 0)
			(size 0.508 0.508)
			(layers "B.Cu" "B.Mask" "B.Paste")
			(net "P3V3_STBY")
		)
		(pad "2" smd rect
			(at 0 0.889)
			(size 0.508 0.508)
			(layers "B.Cu" "B.Mask" "B.Paste")
			(net "FM_PCH_PWRBTN_OUT_N")
		)
		(zone
			(layer "B.Cu")
			(hatch none 0.5)
			(connect_pads
				(clearance 0)
			)
			(min_thickness 0.25)
			(keepout
				(tracks not_allowed)
				(vias allowed)
				(pads allowed)
				(copperpour not_allowed)
				(footprints allowed)
			)
			(placement
				(enabled no)
				(sheetname "")
			)
			(fill
				(thermal_gap 0.5)
				(thermal_bridge_width 0.5)
				(island_removal_mode 0)
			)
			(polygon
				(pts
					(xy 397.383 -38.481) (xy 397.891 -38.481) (xy 397.891 -38.1) (xy 397.383 -38.1)
				)
			)
		)
		(zone
			(layer "B.Cu")
			(hatch none 0.5)
			(connect_pads
				(clearance 0)
			)
			(min_thickness 0.25)
			(keepout
				(tracks allowed)
				(vias not_allowed)
				(pads allowed)
				(copperpour not_allowed)
				(footprints allowed)
			)
			(placement
				(enabled no)
				(sheetname "")
			)
			(fill
				(thermal_gap 0.5)
				(thermal_bridge_width 0.5)
				(island_removal_mode 0)
			)
			(polygon
				(pts
					(xy 397.383 -38.1) (xy 397.891 -38.1) (xy 397.891 -38.481) (xy 397.383 -38.481)
				)
			)
		)
	)
	(footprint ""
		(layer "B.Cu")
		(at 347.469206 2.694178 -90)
		(property "Reference" "C3U7"
			(at 0 0 90)
			(layer "B.SilkS")
			(hide yes)
			(effects
				(font
					(size 1.27 1.27)
				)
				(justify mirror)
			)
		)
		(property "Value" ""
			(at 0 0 90)
			(layer "B.Fab")
			(effects
				(font
					(size 1.27 1.27)
				)
				(justify mirror)
			)
		)
		(duplicate_pad_numbers_are_jumpers no)
		(fp_rect
			(start 0.7239 1.9939)
			(end -0.7239 -0.2159)
			(stroke
				(width 0)
				(type default)
			)
			(fill no)
			(layer "B.CrtYd")
		)
		(fp_line
			(start -0.7239 1.9939)
			(end -0.7239 -0.2159)
			(stroke
				(width 0.1)
				(type default)
			)
			(layer "B.Fab")
		)
		(fp_line
			(start 0.7239 1.9939)
			(end -0.7239 1.9939)
			(stroke
				(width 0.1)
				(type default)
			)
			(layer "B.Fab")
		)
		(fp_line
			(start -0.7239 -0.2159)
			(end 0.7239 -0.2159)
			(stroke
				(width 0.1)
				(type default)
			)
			(layer "B.Fab")
		)
		(fp_line
			(start 0.7239 -0.2159)
			(end 0.7239 1.9939)
			(stroke
				(width 0.1)
				(type default)
			)
			(layer "B.Fab")
		)
		(pad "1" smd rect
			(at 0 0 90)
			(size 1.27 1.016)
			(layers "B.Cu" "B.Mask" "B.Paste")
			(net "VR_FET_SW_P12V_STBY_PVDDQ_ABC")
		)
		(pad "2" smd rect
			(at 0 1.778 90)
			(size 1.27 1.016)
			(layers "B.Cu" "B.Mask" "B.Paste")
			(net "GND")
		)
		(zone
			(layer "B.Cu")
			(hatch none 0.5)
			(connect_pads
				(clearance 0)
			)
			(min_thickness 0.25)
			(keepout
				(tracks not_allowed)
				(vias allowed)
				(pads allowed)
				(copperpour not_allowed)
				(footprints allowed)
			)
			(placement
				(enabled no)
				(sheetname "")
			)
			(fill
				(thermal_gap 0.5)
				(thermal_bridge_width 0.5)
				(island_removal_mode 0)
			)
			(polygon
				(pts
					(xy 346.199206 3.329178) (xy 346.961206 3.329178) (xy 346.961206 2.059178) (xy 346.199206 2.059178)
				)
			)
		)
	)
	(footprint ""
		(layer "B.Cu")
		(at 205.74 -105.537 -90)
		(property "Reference" "R6N11"
			(at 0 0 90)
			(layer "B.SilkS")
			(hide yes)
			(effects
				(font
					(size 1.27 1.27)
				)
				(justify mirror)
			)
		)
		(property "Value" ""
			(at 0 0 90)
			(layer "B.Fab")
			(effects
				(font
					(size 1.27 1.27)
				)
				(justify mirror)
			)
		)
		(duplicate_pad_numbers_are_jumpers no)
		(fp_poly
			(pts
				(xy 0.2794 -0.1016) (xy -0.2794 -0.1016) (xy -0.2794 0.9906) (xy 0.2794 0.9906)
			)
			(stroke
				(width 0)
				(type default)
			)
			(fill no)
			(layer "B.CrtYd")
		)
		(fp_line
			(start -0.2794 0.9906)
			(end -0.2794 -0.1016)
			(stroke
				(width 0.1)
				(type default)
			)
			(layer "B.Fab")
		)
		(fp_line
			(start 0.2794 0.9906)
			(end -0.2794 0.9906)
			(stroke
				(width 0.1)
				(type default)
			)
			(layer "B.Fab")
		)
		(fp_line
			(start -0.2794 -0.1016)
			(end 0.2794 -0.1016)
			(stroke
				(width 0.1)
				(type default)
			)
			(layer "B.Fab")
		)
		(fp_line
			(start 0.2794 -0.1016)
			(end 0.2794 0.9906)
			(stroke
				(width 0.1)
				(type default)
			)
			(layer "B.Fab")
		)
		(pad "1" smd rect
			(at 0 0 90)
			(size 0.508 0.508)
			(layers "B.Cu" "B.Mask" "B.Paste")
			(net "SVID_DIO0_CPU0")
		)
		(pad "2" smd rect
			(at 0 0.889 90)
			(size 0.508 0.508)
			(layers "B.Cu" "B.Mask" "B.Paste")
			(net "SVID_DIO0_CPU0_R")
		)
		(zone
			(layer "B.Cu")
			(hatch none 0.5)
			(connect_pads
				(clearance 0)
			)
			(min_thickness 0.25)
			(keepout
				(tracks not_allowed)
				(vias allowed)
				(pads allowed)
				(copperpour not_allowed)
				(footprints allowed)
			)
			(placement
				(enabled no)
				(sheetname "")
			)
			(fill
				(thermal_gap 0.5)
				(thermal_bridge_width 0.5)
				(island_removal_mode 0)
			)
			(polygon
				(pts
					(xy 205.105 -105.283) (xy 205.105 -105.791) (xy 205.486 -105.791) (xy 205.486 -105.283)
				)
			)
		)
		(zone
			(layer "B.Cu")
			(hatch none 0.5)
			(connect_pads
				(clearance 0)
			)
			(min_thickness 0.25)
			(keepout
				(tracks allowed)
				(vias not_allowed)
				(pads allowed)
				(copperpour not_allowed)
				(footprints allowed)
			)
			(placement
				(enabled no)
				(sheetname "")
			)
			(fill
				(thermal_gap 0.5)
				(thermal_bridge_width 0.5)
				(island_removal_mode 0)
			)
			(polygon
				(pts
					(xy 205.486 -105.283) (xy 205.486 -105.791) (xy 205.105 -105.791) (xy 205.105 -105.283)
				)
			)
		)
	)
	(footprint ""
		(layer "B.Cu")
		(at 333.659226 -39.539418 90)
		(property "Reference" "C3T1"
			(at 0 0 90)
			(layer "B.SilkS")
			(hide yes)
			(effects
				(font
					(size 1.27 1.27)
				)
				(justify mirror)
			)
		)
		(property "Value" ""
			(at 0 0 90)
			(layer "B.Fab")
			(effects
				(font
					(size 1.27 1.27)
				)
				(justify mirror)
			)
		)
		(duplicate_pad_numbers_are_jumpers no)
		(fp_rect
			(start 0.500126 1.598422)
			(end -0.500126 -0.201422)
			(stroke
				(width 0)
				(type default)
			)
			(fill no)
			(layer "B.CrtYd")
		)
		(fp_line
			(start 0.500126 -0.201422)
			(end -0.500126 -0.201422)
			(stroke
				(width 0.1)
				(type default)
			)
			(layer "B.Fab")
		)
		(fp_line
			(start -0.500126 -0.201422)
			(end -0.500126 1.598422)
			(stroke
				(width 0.1)
				(type default)
			)
			(layer "B.Fab")
		)
		(fp_line
			(start 0.500126 1.598422)
			(end 0.500126 -0.201422)
			(stroke
				(width 0.1)
				(type default)
			)
			(layer "B.Fab")
		)
		(fp_line
			(start -0.500126 1.598422)
			(end 0.500126 1.598422)
			(stroke
				(width 0.1)
				(type default)
			)
			(layer "B.Fab")
		)
		(pad "1" smd rect
			(at 0 0)
			(size 0.889 0.9906)
			(layers "B.Cu" "B.Mask" "B.Paste")
			(net "P1V8_MCP_CPU0")
		)
		(pad "2" smd rect
			(at 0 1.397)
			(size 0.889 0.9906)
			(layers "B.Cu" "B.Mask" "B.Paste")
			(net "GND")
		)
		(zone
			(layer "B.Cu")
			(hatch none 0.5)
			(connect_pads
				(clearance 0)
			)
			(min_thickness 0.25)
			(keepout
				(tracks not_allowed)
				(vias allowed)
				(pads allowed)
				(copperpour not_allowed)
				(footprints allowed)
			)
			(placement
				(enabled no)
				(sheetname "")
			)
			(fill
				(thermal_gap 0.5)
				(thermal_bridge_width 0.5)
				(island_removal_mode 0)
			)
			(polygon
				(pts
					(xy 334.611726 -40.034718) (xy 334.103726 -40.034718) (xy 334.103726 -39.044118) (xy 334.611726 -39.044118)
				)
			)
		)
		(zone
			(layer "B.Cu")
			(hatch none 0.5)
			(connect_pads
				(clearance 0)
			)
			(min_thickness 0.25)
			(keepout
				(tracks allowed)
				(vias not_allowed)
				(pads allowed)
				(copperpour not_allowed)
				(footprints allowed)
			)
			(placement
				(enabled no)
				(sheetname "")
			)
			(fill
				(thermal_gap 0.5)
				(thermal_bridge_width 0.5)
				(island_removal_mode 0)
			)
			(polygon
				(pts
					(xy 334.611726 -40.034718) (xy 334.103726 -40.034718) (xy 334.103726 -39.044118) (xy 334.611726 -39.044118)
				)
			)
		)
	)
	(footprint ""
		(layer "B.Cu")
		(at 166.66718 -145.97126 180)
		(property "Reference" "C6W13"
			(at -1.47828 0.78994 270)
			(unlocked yes)
			(layer "B.SilkS")
			(effects
				(font
					(size 0.4064 0.254)
					(thickness 0.1524)
				)
				(justify mirror)
			)
		)
		(property "Value" ""
			(at 0 0 0)
			(layer "B.Fab")
			(effects
				(font
					(size 1.27 1.27)
				)
				(justify mirror)
			)
		)
		(duplicate_pad_numbers_are_jumpers no)
		(fp_poly
			(pts
				(xy 0.7239 -0.2159) (xy -0.7239 -0.2159) (xy -0.7239 1.9939) (xy 0.7239 1.9939)
			)
			(stroke
				(width 0)
				(type default)
			)
			(fill no)
			(layer "B.CrtYd")
		)
		(fp_line
			(start 0.7239 1.9939)
			(end -0.7239 1.9939)
			(stroke
				(width 0.1)
				(type default)
			)
			(layer "B.Fab")
		)
		(fp_line
			(start 0.7239 -0.2159)
			(end 0.7239 1.9939)
			(stroke
				(width 0.1)
				(type default)
			)
			(layer "B.Fab")
		)
		(fp_line
			(start -0.7239 1.9939)
			(end -0.7239 -0.2159)
			(stroke
				(width 0.1)
				(type default)
			)
			(layer "B.Fab")
		)
		(fp_line
			(start -0.7239 -0.2159)
			(end 0.7239 -0.2159)
			(stroke
				(width 0.1)
				(type default)
			)
			(layer "B.Fab")
		)
		(pad "1" smd rect
			(at 0 0)
			(size 1.27 1.016)
			(layers "B.Cu" "B.Mask" "B.Paste")
			(net "PVTT_KLM")
		)
		(pad "2" smd rect
			(at 0 1.778)
			(size 1.27 1.016)
			(layers "B.Cu" "B.Mask" "B.Paste")
			(net "GND")
		)
		(zone
			(layer "B.Cu")
			(hatch none 0.5)
			(connect_pads
				(clearance 0)
			)
			(min_thickness 0.25)
			(keepout
				(tracks not_allowed)
				(vias allowed)
				(pads allowed)
				(copperpour not_allowed)
				(footprints allowed)
			)
			(placement
				(enabled no)
				(sheetname "")
			)
			(fill
				(thermal_gap 0.5)
				(thermal_bridge_width 0.5)
				(island_removal_mode 0)
			)
			(polygon
				(pts
					(xy 166.03218 -146.47926) (xy 167.30218 -146.47926) (xy 167.30218 -147.24126) (xy 166.03218 -147.24126)
				)
			)
		)
	)
	(footprint ""
		(layer "B.Cu")
		(at 396.113 -87.3125 180)
		(property "Reference" "R2N32"
			(at 0.8382 -0.67818 180)
			(unlocked yes)
			(layer "B.SilkS")
			(effects
				(font
					(size 0.4064 0.254)
					(thickness 0.1524)
				)
				(justify left mirror)
			)
		)
		(property "Value" ""
			(at 0 0 0)
			(layer "B.Fab")
			(effects
				(font
					(size 1.27 1.27)
				)
				(justify mirror)
			)
		)
		(duplicate_pad_numbers_are_jumpers no)
		(fp_poly
			(pts
				(xy 0.2794 -0.1016) (xy -0.2794 -0.1016) (xy -0.2794 0.9906) (xy 0.2794 0.9906)
			)
			(stroke
				(width 0)
				(type default)
			)
			(fill no)
			(layer "B.CrtYd")
		)
		(fp_line
			(start 0.2794 0.9906)
			(end -0.2794 0.9906)
			(stroke
				(width 0.1)
				(type default)
			)
			(layer "B.Fab")
		)
		(fp_line
			(start 0.2794 -0.1016)
			(end 0.2794 0.9906)
			(stroke
				(width 0.1)
				(type default)
			)
			(layer "B.Fab")
		)
		(fp_line
			(start -0.2794 0.9906)
			(end -0.2794 -0.1016)
			(stroke
				(width 0.1)
				(type default)
			)
			(layer "B.Fab")
		)
		(fp_line
			(start -0.2794 -0.1016)
			(end 0.2794 -0.1016)
			(stroke
				(width 0.1)
				(type default)
			)
			(layer "B.Fab")
		)
		(pad "1" smd rect
			(at 0 0)
			(size 0.508 0.508)
			(layers "B.Cu" "B.Mask" "B.Paste")
			(net "P3V3_STBY")
		)
		(pad "2" smd rect
			(at 0 0.889)
			(size 0.508 0.508)
			(layers "B.Cu" "B.Mask" "B.Paste")
			(net "FM_BIOS_SMI_ACTIVE_N")
		)
		(zone
			(layer "B.Cu")
			(hatch none 0.5)
			(connect_pads
				(clearance 0)
			)
			(min_thickness 0.25)
			(keepout
				(tracks not_allowed)
				(vias allowed)
				(pads allowed)
				(copperpour not_allowed)
				(footprints allowed)
			)
			(placement
				(enabled no)
				(sheetname "")
			)
			(fill
				(thermal_gap 0.5)
				(thermal_bridge_width 0.5)
				(island_removal_mode 0)
			)
			(polygon
				(pts
					(xy 395.859 -87.9475) (xy 396.367 -87.9475) (xy 396.367 -87.5665) (xy 395.859 -87.5665)
				)
			)
		)
		(zone
			(layer "B.Cu")
			(hatch none 0.5)
			(connect_pads
				(clearance 0)
			)
			(min_thickness 0.25)
			(keepout
				(tracks allowed)
				(vias not_allowed)
				(pads allowed)
				(copperpour not_allowed)
				(footprints allowed)
			)
			(placement
				(enabled no)
				(sheetname "")
			)
			(fill
				(thermal_gap 0.5)
				(thermal_bridge_width 0.5)
				(island_removal_mode 0)
			)
			(polygon
				(pts
					(xy 395.859 -87.5665) (xy 396.367 -87.5665) (xy 396.367 -87.9475) (xy 395.859 -87.9475)
				)
			)
		)
	)
	(footprint ""
		(layer "B.Cu")
		(at 104.5591 -145.0086 90)
		(property "Reference" "C8L5"
			(at -1.848866 0.752348 90)
			(unlocked yes)
			(layer "B.SilkS")
			(effects
				(font
					(size 1.27 0.9652)
					(thickness 0.1524)
				)
				(justify mirror)
			)
		)
		(property "Value" ""
			(at 0 0 90)
			(layer "B.Fab")
			(effects
				(font
					(size 1.27 1.27)
				)
				(justify mirror)
			)
		)
		(duplicate_pad_numbers_are_jumpers no)
		(fp_rect
			(start 0.500126 1.598422)
			(end -0.500126 -0.201422)
			(stroke
				(width 0)
				(type default)
			)
			(fill no)
			(layer "B.CrtYd")
		)
		(fp_line
			(start 0.500126 -0.201422)
			(end -0.500126 -0.201422)
			(stroke
				(width 0.1)
				(type default)
			)
			(layer "B.Fab")
		)
		(fp_line
			(start -0.500126 -0.201422)
			(end -0.500126 1.598422)
			(stroke
				(width 0.1)
				(type default)
			)
			(layer "B.Fab")
		)
		(fp_line
			(start 0.500126 1.598422)
			(end 0.500126 -0.201422)
			(stroke
				(width 0.1)
				(type default)
			)
			(layer "B.Fab")
		)
		(fp_line
			(start -0.500126 1.598422)
			(end 0.500126 1.598422)
			(stroke
				(width 0.1)
				(type default)
			)
			(layer "B.Fab")
		)
		(pad "1" smd rect
			(at 0 0)
			(size 0.889 0.9906)
			(layers "B.Cu" "B.Mask" "B.Paste")
			(net "PVDDQ_KLM")
		)
		(pad "2" smd rect
			(at 0 1.397)
			(size 0.889 0.9906)
			(layers "B.Cu" "B.Mask" "B.Paste")
			(net "GND")
		)
		(zone
			(layer "B.Cu")
			(hatch none 0.5)
			(connect_pads
				(clearance 0)
			)
			(min_thickness 0.25)
			(keepout
				(tracks allowed)
				(vias not_allowed)
				(pads allowed)
				(copperpour not_allowed)
				(footprints allowed)
			)
			(placement
				(enabled no)
				(sheetname "")
			)
			(fill
				(thermal_gap 0.5)
				(thermal_bridge_width 0.5)
				(island_removal_mode 0)
			)
			(polygon
				(pts
					(xy 105.5116 -145.5039) (xy 105.0036 -145.5039) (xy 105.0036 -144.5133) (xy 105.5116 -144.5133)
				)
			)
		)
		(zone
			(layer "B.Cu")
			(hatch none 0.5)
			(connect_pads
				(clearance 0)
			)
			(min_thickness 0.25)
			(keepout
				(tracks not_allowed)
				(vias allowed)
				(pads allowed)
				(copperpour not_allowed)
				(footprints allowed)
			)
			(placement
				(enabled no)
				(sheetname "")
			)
			(fill
				(thermal_gap 0.5)
				(thermal_bridge_width 0.5)
				(island_removal_mode 0)
			)
			(polygon
				(pts
					(xy 105.5116 -145.5039) (xy 105.0036 -145.5039) (xy 105.0036 -144.5133) (xy 105.5116 -144.5133)
				)
			)
		)
	)
	(footprint ""
		(layer "B.Cu")
		(at 1.9304 -8.4582)
		(property "Reference" "CT28"
			(at 0.8382 -0.84963 0)
			(unlocked yes)
			(layer "B.SilkS")
			(effects
				(font
					(size 0.7874 0.5842)
					(thickness 0.1524)
				)
				(justify left mirror)
			)
		)
		(property "Value" ""
			(at 0 0 0)
			(layer "B.Fab")
			(effects
				(font
					(size 1.27 1.27)
				)
				(justify mirror)
			)
		)
		(duplicate_pad_numbers_are_jumpers no)
		(fp_poly
			(pts
				(xy -0.3048 -0.1016) (xy -0.3048 0.9906) (xy 0.3048 0.9906) (xy 0.3048 -0.1016)
			)
			(stroke
				(width 0)
				(type default)
			)
			(fill no)
			(layer "B.CrtYd")
		)
		(fp_line
			(start -0.3048 -0.1016)
			(end 0.3048 -0.1016)
			(stroke
				(width 0.1)
				(type default)
			)
			(layer "B.Fab")
		)
		(fp_line
			(start -0.3048 0.9906)
			(end -0.3048 -0.1016)
			(stroke
				(width 0.1)
				(type default)
			)
			(layer "B.Fab")
		)
		(fp_line
			(start 0.3048 -0.1016)
			(end 0.3048 0.9906)
			(stroke
				(width 0.1)
				(type default)
			)
			(layer "B.Fab")
		)
		(fp_line
			(start 0.3048 0.9906)
			(end -0.3048 0.9906)
			(stroke
				(width 0.1)
				(type default)
			)
			(layer "B.Fab")
		)
		(pad "1" smd rect
			(at 0 0 180)
			(size 0.508 0.508)
			(layers "B.Cu" "B.Mask" "B.Paste")
			(net "A_TSENSE_PVDDQ_GHJ")
		)
		(pad "2" smd rect
			(at 0 0.889 180)
			(size 0.508 0.508)
			(layers "B.Cu" "B.Mask" "B.Paste")
			(net "GND")
		)
		(zone
			(layer "B.Cu")
			(hatch none 0.5)
			(connect_pads
				(clearance 0)
			)
			(min_thickness 0.25)
			(keepout
				(tracks allowed)
				(vias not_allowed)
				(pads allowed)
				(copperpour not_allowed)
				(footprints allowed)
			)
			(placement
				(enabled no)
				(sheetname "")
			)
			(fill
				(thermal_gap 0.5)
				(thermal_bridge_width 0.5)
				(island_removal_mode 0)
			)
			(polygon
				(pts
					(xy 2.1844 -8.2042) (xy 1.6764 -8.2042) (xy 1.6764 -7.8232) (xy 2.1844 -7.8232)
				)
			)
		)
		(zone
			(layer "B.Cu")
			(hatch none 0.5)
			(connect_pads
				(clearance 0)
			)
			(min_thickness 0.25)
			(keepout
				(tracks not_allowed)
				(vias allowed)
				(pads allowed)
				(copperpour not_allowed)
				(footprints allowed)
			)
			(placement
				(enabled no)
				(sheetname "")
			)
			(fill
				(thermal_gap 0.5)
				(thermal_bridge_width 0.5)
				(island_removal_mode 0)
			)
			(polygon
				(pts
					(xy 2.1844 -7.8232) (xy 1.6764 -7.8232) (xy 1.6764 -8.2042) (xy 2.1844 -8.2042)
				)
			)
		)
	)
	(footprint ""
		(layer "B.Cu")
		(at 402.463 -148.1074 180)
		(property "Reference" "R2L19"
			(at 0 0 0)
			(layer "B.SilkS")
			(hide yes)
			(effects
				(font
					(size 1.27 1.27)
				)
				(justify mirror)
			)
		)
		(property "Value" ""
			(at 0 0 0)
			(layer "B.Fab")
			(effects
				(font
					(size 1.27 1.27)
				)
				(justify mirror)
			)
		)
		(duplicate_pad_numbers_are_jumpers no)
		(fp_poly
			(pts
				(xy 0.2794 -0.1016) (xy -0.2794 -0.1016) (xy -0.2794 0.9906) (xy 0.2794 0.9906)
			)
			(stroke
				(width 0)
				(type default)
			)
			(fill no)
			(layer "B.CrtYd")
		)
		(fp_line
			(start 0.2794 0.9906)
			(end -0.2794 0.9906)
			(stroke
				(width 0.1)
				(type default)
			)
			(layer "B.Fab")
		)
		(fp_line
			(start 0.2794 -0.1016)
			(end 0.2794 0.9906)
			(stroke
				(width 0.1)
				(type default)
			)
			(layer "B.Fab")
		)
		(fp_line
			(start -0.2794 0.9906)
			(end -0.2794 -0.1016)
			(stroke
				(width 0.1)
				(type default)
			)
			(layer "B.Fab")
		)
		(fp_line
			(start -0.2794 -0.1016)
			(end 0.2794 -0.1016)
			(stroke
				(width 0.1)
				(type default)
			)
			(layer "B.Fab")
		)
		(pad "1" smd rect
			(at 0 0)
			(size 0.508 0.508)
			(layers "B.Cu" "B.Mask" "B.Paste")
			(net "VR_P1V8_PCH_STBY_FB")
		)
		(pad "2" smd rect
			(at 0 0.889)
			(size 0.508 0.508)
			(layers "B.Cu" "B.Mask" "B.Paste")
			(net "GND")
		)
		(zone
			(layer "B.Cu")
			(hatch none 0.5)
			(connect_pads
				(clearance 0)
			)
			(min_thickness 0.25)
			(keepout
				(tracks not_allowed)
				(vias allowed)
				(pads allowed)
				(copperpour not_allowed)
				(footprints allowed)
			)
			(placement
				(enabled no)
				(sheetname "")
			)
			(fill
				(thermal_gap 0.5)
				(thermal_bridge_width 0.5)
				(island_removal_mode 0)
			)
			(polygon
				(pts
					(xy 402.209 -148.7424) (xy 402.717 -148.7424) (xy 402.717 -148.3614) (xy 402.209 -148.3614)
				)
			)
		)
		(zone
			(layer "B.Cu")
			(hatch none 0.5)
			(connect_pads
				(clearance 0)
			)
			(min_thickness 0.25)
			(keepout
				(tracks allowed)
				(vias not_allowed)
				(pads allowed)
				(copperpour not_allowed)
				(footprints allowed)
			)
			(placement
				(enabled no)
				(sheetname "")
			)
			(fill
				(thermal_gap 0.5)
				(thermal_bridge_width 0.5)
				(island_removal_mode 0)
			)
			(polygon
				(pts
					(xy 402.209 -148.3614) (xy 402.717 -148.3614) (xy 402.717 -148.7424) (xy 402.209 -148.7424)
				)
			)
		)
	)
	(footprint ""
		(layer "B.Cu")
		(at 374.777 -90.2335 180)
		(property "Reference" "R7C10"
			(at 0 0 0)
			(layer "B.SilkS")
			(hide yes)
			(effects
				(font
					(size 1.27 1.27)
				)
				(justify mirror)
			)
		)
		(property "Value" ""
			(at 0 0 0)
			(layer "B.Fab")
			(effects
				(font
					(size 1.27 1.27)
				)
				(justify mirror)
			)
		)
		(duplicate_pad_numbers_are_jumpers no)
		(fp_poly
			(pts
				(xy 0.2794 -0.1016) (xy -0.2794 -0.1016) (xy -0.2794 0.9906) (xy 0.2794 0.9906)
			)
			(stroke
				(width 0)
				(type default)
			)
			(fill no)
			(layer "B.CrtYd")
		)
		(fp_line
			(start 0.2794 0.9906)
			(end -0.2794 0.9906)
			(stroke
				(width 0.1)
				(type default)
			)
			(layer "B.Fab")
		)
		(fp_line
			(start 0.2794 -0.1016)
			(end 0.2794 0.9906)
			(stroke
				(width 0.1)
				(type default)
			)
			(layer "B.Fab")
		)
		(fp_line
			(start -0.2794 0.9906)
			(end -0.2794 -0.1016)
			(stroke
				(width 0.1)
				(type default)
			)
			(layer "B.Fab")
		)
		(fp_line
			(start -0.2794 -0.1016)
			(end 0.2794 -0.1016)
			(stroke
				(width 0.1)
				(type default)
			)
			(layer "B.Fab")
		)
		(pad "1" smd rect
			(at 0 0)
			(size 0.508 0.508)
			(layers "B.Cu" "B.Mask" "B.Paste")
			(net "P3V3_RTC_STBY")
		)
		(pad "2" smd rect
			(at 0 0.889)
			(size 0.508 0.508)
			(layers "B.Cu" "B.Mask" "B.Paste")
			(net "RST_RTCRST_N")
		)
		(zone
			(layer "B.Cu")
			(hatch none 0.5)
			(connect_pads
				(clearance 0)
			)
			(min_thickness 0.25)
			(keepout
				(tracks not_allowed)
				(vias allowed)
				(pads allowed)
				(copperpour not_allowed)
				(footprints allowed)
			)
			(placement
				(enabled no)
				(sheetname "")
			)
			(fill
				(thermal_gap 0.5)
				(thermal_bridge_width 0.5)
				(island_removal_mode 0)
			)
			(polygon
				(pts
					(xy 374.523 -90.8685) (xy 375.031 -90.8685) (xy 375.031 -90.4875) (xy 374.523 -90.4875)
				)
			)
		)
		(zone
			(layer "B.Cu")
			(hatch none 0.5)
			(connect_pads
				(clearance 0)
			)
			(min_thickness 0.25)
			(keepout
				(tracks allowed)
				(vias not_allowed)
				(pads allowed)
				(copperpour not_allowed)
				(footprints allowed)
			)
			(placement
				(enabled no)
				(sheetname "")
			)
			(fill
				(thermal_gap 0.5)
				(thermal_bridge_width 0.5)
				(island_removal_mode 0)
			)
			(polygon
				(pts
					(xy 374.523 -90.4875) (xy 375.031 -90.4875) (xy 375.031 -90.8685) (xy 374.523 -90.8685)
				)
			)
		)
	)
	(footprint ""
		(layer "B.Cu")
		(at 111.000032 -17.7546 90)
		(property "Reference" "C7T4"
			(at -1.848866 0.752348 90)
			(unlocked yes)
			(layer "B.SilkS")
			(effects
				(font
					(size 1.27 0.9652)
					(thickness 0.1524)
				)
				(justify mirror)
			)
		)
		(property "Value" ""
			(at 0 0 90)
			(layer "B.Fab")
			(effects
				(font
					(size 1.27 1.27)
				)
				(justify mirror)
			)
		)
		(duplicate_pad_numbers_are_jumpers no)
		(fp_rect
			(start 0.500126 1.598422)
			(end -0.500126 -0.201422)
			(stroke
				(width 0)
				(type default)
			)
			(fill no)
			(layer "B.CrtYd")
		)
		(fp_line
			(start 0.500126 -0.201422)
			(end -0.500126 -0.201422)
			(stroke
				(width 0.1)
				(type default)
			)
			(layer "B.Fab")
		)
		(fp_line
			(start -0.500126 -0.201422)
			(end -0.500126 1.598422)
			(stroke
				(width 0.1)
				(type default)
			)
			(layer "B.Fab")
		)
		(fp_line
			(start 0.500126 1.598422)
			(end 0.500126 -0.201422)
			(stroke
				(width 0.1)
				(type default)
			)
			(layer "B.Fab")
		)
		(fp_line
			(start -0.500126 1.598422)
			(end 0.500126 1.598422)
			(stroke
				(width 0.1)
				(type default)
			)
			(layer "B.Fab")
		)
		(pad "1" smd rect
			(at 0 0)
			(size 0.889 0.9906)
			(layers "B.Cu" "B.Mask" "B.Paste")
			(net "PVDDQ_GHJ")
		)
		(pad "2" smd rect
			(at 0 1.397)
			(size 0.889 0.9906)
			(layers "B.Cu" "B.Mask" "B.Paste")
			(net "GND")
		)
		(zone
			(layer "B.Cu")
			(hatch none 0.5)
			(connect_pads
				(clearance 0)
			)
			(min_thickness 0.25)
			(keepout
				(tracks allowed)
				(vias not_allowed)
				(pads allowed)
				(copperpour not_allowed)
				(footprints allowed)
			)
			(placement
				(enabled no)
				(sheetname "")
			)
			(fill
				(thermal_gap 0.5)
				(thermal_bridge_width 0.5)
				(island_removal_mode 0)
			)
			(polygon
				(pts
					(xy 111.952532 -18.2499) (xy 111.444532 -18.2499) (xy 111.444532 -17.2593) (xy 111.952532 -17.2593)
				)
			)
		)
		(zone
			(layer "B.Cu")
			(hatch none 0.5)
			(connect_pads
				(clearance 0)
			)
			(min_thickness 0.25)
			(keepout
				(tracks not_allowed)
				(vias allowed)
				(pads allowed)
				(copperpour not_allowed)
				(footprints allowed)
			)
			(placement
				(enabled no)
				(sheetname "")
			)
			(fill
				(thermal_gap 0.5)
				(thermal_bridge_width 0.5)
				(island_removal_mode 0)
			)
			(polygon
				(pts
					(xy 111.952532 -18.2499) (xy 111.444532 -18.2499) (xy 111.444532 -17.2593) (xy 111.952532 -17.2593)
				)
			)
		)
	)
	(footprint ""
		(layer "B.Cu")
		(at 87.158068 -3.3528 -90)
		(property "Reference" "C5G86"
			(at -1.14681 0.76708 0)
			(unlocked yes)
			(layer "B.SilkS")
			(effects
				(font
					(size 0.7874 0.5842)
					(thickness 0.1524)
				)
				(justify mirror)
			)
		)
		(property "Value" ""
			(at 0 0 90)
			(layer "B.Fab")
			(effects
				(font
					(size 1.27 1.27)
				)
				(justify mirror)
			)
		)
		(duplicate_pad_numbers_are_jumpers no)
		(fp_rect
			(start 0.4953 1.6002)
			(end -0.4953 -0.2032)
			(stroke
				(width 0)
				(type default)
			)
			(fill no)
			(layer "B.CrtYd")
		)
		(fp_line
			(start -0.4953 1.6002)
			(end 0.4953 1.6002)
			(stroke
				(width 0.1)
				(type default)
			)
			(layer "B.Fab")
		)
		(fp_line
			(start 0.4953 1.6002)
			(end 0.4953 -0.2032)
			(stroke
				(width 0.1)
				(type default)
			)
			(layer "B.Fab")
		)
		(fp_line
			(start -0.4953 -0.2032)
			(end -0.4953 1.6002)
			(stroke
				(width 0.1)
				(type default)
			)
			(layer "B.Fab")
		)
		(fp_line
			(start 0.4953 -0.2032)
			(end -0.4953 -0.2032)
			(stroke
				(width 0.1)
				(type default)
			)
			(layer "B.Fab")
		)
		(pad "1" smd rect
			(at 0 0 90)
			(size 0.762 0.889)
			(layers "B.Cu" "B.Mask" "B.Paste")
			(net "PVDDQ_GHJ")
		)
		(pad "2" smd rect
			(at 0 1.397 90)
			(size 0.762 0.889)
			(layers "B.Cu" "B.Mask" "B.Paste")
			(net "GND")
		)
		(zone
			(layer "B.Cu")
			(hatch none 0.5)
			(connect_pads
				(clearance 0)
			)
			(min_thickness 0.25)
			(keepout
				(tracks not_allowed)
				(vias allowed)
				(pads allowed)
				(copperpour not_allowed)
				(footprints allowed)
			)
			(placement
				(enabled no)
				(sheetname "")
			)
			(fill
				(thermal_gap 0.5)
				(thermal_bridge_width 0.5)
				(island_removal_mode 0)
			)
			(polygon
				(pts
					(xy 86.205568 -2.9718) (xy 86.713568 -2.9718) (xy 86.713568 -3.7338) (xy 86.205568 -3.7338)
				)
			)
		)
	)
	(footprint ""
		(layer "B.Cu")
		(at 394.589 -88.2015)
		(property "Reference" "R2N20"
			(at 0 0 0)
			(layer "B.SilkS")
			(hide yes)
			(effects
				(font
					(size 1.27 1.27)
				)
				(justify mirror)
			)
		)
		(property "Value" ""
			(at 0 0 0)
			(layer "B.Fab")
			(effects
				(font
					(size 1.27 1.27)
				)
				(justify mirror)
			)
		)
		(duplicate_pad_numbers_are_jumpers no)
		(fp_poly
			(pts
				(xy 0.2794 -0.1016) (xy -0.2794 -0.1016) (xy -0.2794 0.9906) (xy 0.2794 0.9906)
			)
			(stroke
				(width 0)
				(type default)
			)
			(fill no)
			(layer "B.CrtYd")
		)
		(fp_line
			(start -0.2794 -0.1016)
			(end 0.2794 -0.1016)
			(stroke
				(width 0.1)
				(type default)
			)
			(layer "B.Fab")
		)
		(fp_line
			(start -0.2794 0.9906)
			(end -0.2794 -0.1016)
			(stroke
				(width 0.1)
				(type default)
			)
			(layer "B.Fab")
		)
		(fp_line
			(start 0.2794 -0.1016)
			(end 0.2794 0.9906)
			(stroke
				(width 0.1)
				(type default)
			)
			(layer "B.Fab")
		)
		(fp_line
			(start 0.2794 0.9906)
			(end -0.2794 0.9906)
			(stroke
				(width 0.1)
				(type default)
			)
			(layer "B.Fab")
		)
		(pad "1" smd rect
			(at 0 0 180)
			(size 0.508 0.508)
			(layers "B.Cu" "B.Mask" "B.Paste")
			(net "SMB_LAN_STBY_LVC3_SDA_R2")
		)
		(pad "2" smd rect
			(at 0 0.889 180)
			(size 0.508 0.508)
			(layers "B.Cu" "B.Mask" "B.Paste")
			(net "SMB_LAN_STBY_LVC3_SDA")
		)
		(zone
			(layer "B.Cu")
			(hatch none 0.5)
			(connect_pads
				(clearance 0)
			)
			(min_thickness 0.25)
			(keepout
				(tracks allowed)
				(vias not_allowed)
				(pads allowed)
				(copperpour not_allowed)
				(footprints allowed)
			)
			(placement
				(enabled no)
				(sheetname "")
			)
			(fill
				(thermal_gap 0.5)
				(thermal_bridge_width 0.5)
				(island_removal_mode 0)
			)
			(polygon
				(pts
					(xy 394.843 -87.9475) (xy 394.335 -87.9475) (xy 394.335 -87.5665) (xy 394.843 -87.5665)
				)
			)
		)
		(zone
			(layer "B.Cu")
			(hatch none 0.5)
			(connect_pads
				(clearance 0)
			)
			(min_thickness 0.25)
			(keepout
				(tracks not_allowed)
				(vias allowed)
				(pads allowed)
				(copperpour not_allowed)
				(footprints allowed)
			)
			(placement
				(enabled no)
				(sheetname "")
			)
			(fill
				(thermal_gap 0.5)
				(thermal_bridge_width 0.5)
				(island_removal_mode 0)
			)
			(polygon
				(pts
					(xy 394.843 -87.5665) (xy 394.335 -87.5665) (xy 394.335 -87.9475) (xy 394.843 -87.9475)
				)
			)
		)
	)
	(footprint ""
		(layer "B.Cu")
		(at 413.5755 -17.526 -90)
		(property "Reference" "R2U45"
			(at 0 0 90)
			(layer "B.SilkS")
			(hide yes)
			(effects
				(font
					(size 1.27 1.27)
				)
				(justify mirror)
			)
		)
		(property "Value" ""
			(at 0 0 90)
			(layer "B.Fab")
			(effects
				(font
					(size 1.27 1.27)
				)
				(justify mirror)
			)
		)
		(duplicate_pad_numbers_are_jumpers no)
		(fp_poly
			(pts
				(xy 0.2794 -0.1016) (xy -0.2794 -0.1016) (xy -0.2794 0.9906) (xy 0.2794 0.9906)
			)
			(stroke
				(width 0)
				(type default)
			)
			(fill no)
			(layer "B.CrtYd")
		)
		(fp_line
			(start -0.2794 0.9906)
			(end -0.2794 -0.1016)
			(stroke
				(width 0.1)
				(type default)
			)
			(layer "B.Fab")
		)
		(fp_line
			(start 0.2794 0.9906)
			(end -0.2794 0.9906)
			(stroke
				(width 0.1)
				(type default)
			)
			(layer "B.Fab")
		)
		(fp_line
			(start -0.2794 -0.1016)
			(end 0.2794 -0.1016)
			(stroke
				(width 0.1)
				(type default)
			)
			(layer "B.Fab")
		)
		(fp_line
			(start 0.2794 -0.1016)
			(end 0.2794 0.9906)
			(stroke
				(width 0.1)
				(type default)
			)
			(layer "B.Fab")
		)
		(pad "1" smd rect
			(at 0 0 90)
			(size 0.508 0.508)
			(layers "B.Cu" "B.Mask" "B.Paste")
			(net "H_CPU1_MEMKLM_MEMHOT_LVT3_N")
		)
		(pad "2" smd rect
			(at 0 0.889 90)
			(size 0.508 0.508)
			(layers "B.Cu" "B.Mask" "B.Paste")
			(net "H_CPU1_MEMKLM_MEMHOT_PCH_N")
		)
		(zone
			(layer "B.Cu")
			(hatch none 0.5)
			(connect_pads
				(clearance 0)
			)
			(min_thickness 0.25)
			(keepout
				(tracks not_allowed)
				(vias allowed)
				(pads allowed)
				(copperpour not_allowed)
				(footprints allowed)
			)
			(placement
				(enabled no)
				(sheetname "")
			)
			(fill
				(thermal_gap 0.5)
				(thermal_bridge_width 0.5)
				(island_removal_mode 0)
			)
			(polygon
				(pts
					(xy 412.9405 -17.272) (xy 412.9405 -17.78) (xy 413.3215 -17.78) (xy 413.3215 -17.272)
				)
			)
		)
		(zone
			(layer "B.Cu")
			(hatch none 0.5)
			(connect_pads
				(clearance 0)
			)
			(min_thickness 0.25)
			(keepout
				(tracks allowed)
				(vias not_allowed)
				(pads allowed)
				(copperpour not_allowed)
				(footprints allowed)
			)
			(placement
				(enabled no)
				(sheetname "")
			)
			(fill
				(thermal_gap 0.5)
				(thermal_bridge_width 0.5)
				(island_removal_mode 0)
			)
			(polygon
				(pts
					(xy 413.3215 -17.272) (xy 413.3215 -17.78) (xy 412.9405 -17.78) (xy 412.9405 -17.272)
				)
			)
		)
	)
	(footprint ""
		(layer "B.Cu")
		(at 45.212 -62.611 -90)
		(property "Reference" "C9R3"
			(at -1.75133 -3.429 0)
			(unlocked yes)
			(layer "B.SilkS")
			(effects
				(font
					(size 0.7874 0.5842)
					(thickness 0.1524)
				)
				(justify mirror)
			)
		)
		(property "Value" ""
			(at 0 0 90)
			(layer "B.Fab")
			(effects
				(font
					(size 1.27 1.27)
				)
				(justify mirror)
			)
		)
		(duplicate_pad_numbers_are_jumpers no)
		(fp_line
			(start -2.286 7.366)
			(end -1.600708 7.366)
			(stroke
				(width 0.1524)
				(type default)
			)
			(layer "B.SilkS")
		)
		(fp_line
			(start -2.286 7.366)
			(end -2.286 1.63195)
			(stroke
				(width 0.1524)
				(type default)
			)
			(layer "B.SilkS")
		)
		(fp_line
			(start 2.286 7.366)
			(end 1.60147 7.366)
			(stroke
				(width 0.1524)
				(type default)
			)
			(layer "B.SilkS")
		)
		(fp_line
			(start 2.286 7.366)
			(end 2.286 1.632712)
			(stroke
				(width 0.1524)
				(type default)
			)
			(layer "B.SilkS")
		)
		(fp_line
			(start -2.504948 1.633728)
			(end -1.6002 1.633728)
			(stroke
				(width 0.1524)
				(type default)
			)
			(layer "B.SilkS")
		)
		(fp_line
			(start 2.563114 1.633728)
			(end 1.6002 1.633728)
			(stroke
				(width 0.1524)
				(type default)
			)
			(layer "B.SilkS")
		)
		(fp_line
			(start -2.504948 -1.616456)
			(end -2.504948 1.633728)
			(stroke
				(width 0.1524)
				(type default)
			)
			(layer "B.SilkS")
		)
		(fp_line
			(start -1.6002 -1.616456)
			(end -2.504948 -1.616456)
			(stroke
				(width 0.1524)
				(type default)
			)
			(layer "B.SilkS")
		)
		(fp_line
			(start 1.6002 -1.616456)
			(end 2.563114 -1.616456)
			(stroke
				(width 0.1524)
				(type default)
			)
			(layer "B.SilkS")
		)
		(fp_line
			(start 2.563114 -1.616456)
			(end 2.563114 1.633728)
			(stroke
				(width 0.1524)
				(type default)
			)
			(layer "B.SilkS")
		)
		(fp_rect
			(start 2.286 7.366)
			(end -2.286 -0.254)
			(stroke
				(width 0)
				(type default)
			)
			(fill no)
			(layer "B.CrtYd")
		)
		(fp_line
			(start -2.286 7.366)
			(end 2.286 7.366)
			(stroke
				(width 0.1)
				(type default)
			)
			(layer "B.Fab")
		)
		(fp_line
			(start 2.286 7.366)
			(end 2.286 -0.254)
			(stroke
				(width 0.1)
				(type default)
			)
			(layer "B.Fab")
		)
		(fp_line
			(start -2.286 -0.254)
			(end -2.286 7.366)
			(stroke
				(width 0.1)
				(type default)
			)
			(layer "B.Fab")
		)
		(fp_line
			(start 2.286 -0.254)
			(end -2.286 -0.254)
			(stroke
				(width 0.1)
				(type default)
			)
			(layer "B.Fab")
		)
		(pad "1" smd rect
			(at 0 0 90)
			(size 2.54 3.048)
			(layers "B.Cu" "B.Mask" "B.Paste")
			(net "PVCCIN_CPU1")
		)
		(pad "2" smd rect
			(at 0 7.112 90)
			(size 2.54 3.048)
			(layers "B.Cu" "B.Mask" "B.Paste")
			(net "GND")
		)
	)
	(footprint ""
		(layer "B.Cu")
		(at 487.160062 -28.4226 180)
		(property "Reference" "R1R6"
			(at 0.8382 -0.67818 180)
			(unlocked yes)
			(layer "B.SilkS")
			(effects
				(font
					(size 0.4064 0.254)
					(thickness 0.1524)
				)
				(justify left mirror)
			)
		)
		(property "Value" ""
			(at 0 0 0)
			(layer "B.Fab")
			(effects
				(font
					(size 1.27 1.27)
				)
				(justify mirror)
			)
		)
		(duplicate_pad_numbers_are_jumpers no)
		(fp_poly
			(pts
				(xy 0.2794 -0.1016) (xy -0.2794 -0.1016) (xy -0.2794 0.9906) (xy 0.2794 0.9906)
			)
			(stroke
				(width 0)
				(type default)
			)
			(fill no)
			(layer "B.CrtYd")
		)
		(fp_line
			(start 0.2794 0.9906)
			(end -0.2794 0.9906)
			(stroke
				(width 0.1)
				(type default)
			)
			(layer "B.Fab")
		)
		(fp_line
			(start 0.2794 -0.1016)
			(end 0.2794 0.9906)
			(stroke
				(width 0.1)
				(type default)
			)
			(layer "B.Fab")
		)
		(fp_line
			(start -0.2794 0.9906)
			(end -0.2794 -0.1016)
			(stroke
				(width 0.1)
				(type default)
			)
			(layer "B.Fab")
		)
		(fp_line
			(start -0.2794 -0.1016)
			(end 0.2794 -0.1016)
			(stroke
				(width 0.1)
				(type default)
			)
			(layer "B.Fab")
		)
		(pad "1" smd rect
			(at 0 0)
			(size 0.508 0.508)
			(layers "B.Cu" "B.Mask" "B.Paste")
			(net "SPI_NIC_MOSI")
		)
		(pad "2" smd rect
			(at 0 0.889)
			(size 0.508 0.508)
			(layers "B.Cu" "B.Mask" "B.Paste")
			(net "GND")
		)
		(zone
			(layer "B.Cu")
			(hatch none 0.5)
			(connect_pads
				(clearance 0)
			)
			(min_thickness 0.25)
			(keepout
				(tracks not_allowed)
				(vias allowed)
				(pads allowed)
				(copperpour not_allowed)
				(footprints allowed)
			)
			(placement
				(enabled no)
				(sheetname "")
			)
			(fill
				(thermal_gap 0.5)
				(thermal_bridge_width 0.5)
				(island_removal_mode 0)
			)
			(polygon
				(pts
					(xy 486.906062 -29.0576) (xy 487.414062 -29.0576) (xy 487.414062 -28.6766) (xy 486.906062 -28.6766)
				)
			)
		)
		(zone
			(layer "B.Cu")
			(hatch none 0.5)
			(connect_pads
				(clearance 0)
			)
			(min_thickness 0.25)
			(keepout
				(tracks allowed)
				(vias not_allowed)
				(pads allowed)
				(copperpour not_allowed)
				(footprints allowed)
			)
			(placement
				(enabled no)
				(sheetname "")
			)
			(fill
				(thermal_gap 0.5)
				(thermal_bridge_width 0.5)
				(island_removal_mode 0)
			)
			(polygon
				(pts
					(xy 486.906062 -28.6766) (xy 487.414062 -28.6766) (xy 487.414062 -29.0576) (xy 486.906062 -29.0576)
				)
			)
		)
	)
	(footprint ""
		(layer "B.Cu")
		(at 45.212 -73.279 -90)
		(property "Reference" "C9P18"
			(at -0.98933 -3.81 0)
			(unlocked yes)
			(layer "B.SilkS")
			(effects
				(font
					(size 0.7874 0.5842)
					(thickness 0.1524)
				)
				(justify mirror)
			)
		)
		(property "Value" ""
			(at 0 0 90)
			(layer "B.Fab")
			(effects
				(font
					(size 1.27 1.27)
				)
				(justify mirror)
			)
		)
		(duplicate_pad_numbers_are_jumpers no)
		(fp_line
			(start -2.286 7.366)
			(end -1.600708 7.366)
			(stroke
				(width 0.1524)
				(type default)
			)
			(layer "B.SilkS")
		)
		(fp_line
			(start -2.286 7.366)
			(end -2.286 1.63195)
			(stroke
				(width 0.1524)
				(type default)
			)
			(layer "B.SilkS")
		)
		(fp_line
			(start 2.286 7.366)
			(end 1.60147 7.366)
			(stroke
				(width 0.1524)
				(type default)
			)
			(layer "B.SilkS")
		)
		(fp_line
			(start 2.286 7.366)
			(end 2.286 1.632712)
			(stroke
				(width 0.1524)
				(type default)
			)
			(layer "B.SilkS")
		)
		(fp_line
			(start -2.504948 1.633728)
			(end -1.6002 1.633728)
			(stroke
				(width 0.1524)
				(type default)
			)
			(layer "B.SilkS")
		)
		(fp_line
			(start 2.563114 1.633728)
			(end 1.6002 1.633728)
			(stroke
				(width 0.1524)
				(type default)
			)
			(layer "B.SilkS")
		)
		(fp_line
			(start -2.504948 -1.616456)
			(end -2.504948 1.633728)
			(stroke
				(width 0.1524)
				(type default)
			)
			(layer "B.SilkS")
		)
		(fp_line
			(start -1.6002 -1.616456)
			(end -2.504948 -1.616456)
			(stroke
				(width 0.1524)
				(type default)
			)
			(layer "B.SilkS")
		)
		(fp_line
			(start 1.6002 -1.616456)
			(end 2.563114 -1.616456)
			(stroke
				(width 0.1524)
				(type default)
			)
			(layer "B.SilkS")
		)
		(fp_line
			(start 2.563114 -1.616456)
			(end 2.563114 1.633728)
			(stroke
				(width 0.1524)
				(type default)
			)
			(layer "B.SilkS")
		)
		(fp_rect
			(start 2.286 7.366)
			(end -2.286 -0.254)
			(stroke
				(width 0)
				(type default)
			)
			(fill no)
			(layer "B.CrtYd")
		)
		(fp_line
			(start -2.286 7.366)
			(end 2.286 7.366)
			(stroke
				(width 0.1)
				(type default)
			)
			(layer "B.Fab")
		)
		(fp_line
			(start 2.286 7.366)
			(end 2.286 -0.254)
			(stroke
				(width 0.1)
				(type default)
			)
			(layer "B.Fab")
		)
		(fp_line
			(start -2.286 -0.254)
			(end -2.286 7.366)
			(stroke
				(width 0.1)
				(type default)
			)
			(layer "B.Fab")
		)
		(fp_line
			(start 2.286 -0.254)
			(end -2.286 -0.254)
			(stroke
				(width 0.1)
				(type default)
			)
			(layer "B.Fab")
		)
		(pad "1" smd rect
			(at 0 0 90)
			(size 2.54 3.048)
			(layers "B.Cu" "B.Mask" "B.Paste")
			(net "PVCCIN_CPU1")
		)
		(pad "2" smd rect
			(at 0 7.112 90)
			(size 2.54 3.048)
			(layers "B.Cu" "B.Mask" "B.Paste")
			(net "GND")
		)
	)
	(footprint ""
		(layer "B.Cu")
		(at 104.5591 -135.4074 90)
		(property "Reference" "C8M1"
			(at -1.848866 0.752348 90)
			(unlocked yes)
			(layer "B.SilkS")
			(effects
				(font
					(size 1.27 0.9652)
					(thickness 0.1524)
				)
				(justify mirror)
			)
		)
		(property "Value" ""
			(at 0 0 90)
			(layer "B.Fab")
			(effects
				(font
					(size 1.27 1.27)
				)
				(justify mirror)
			)
		)
		(duplicate_pad_numbers_are_jumpers no)
		(fp_rect
			(start 0.500126 1.598422)
			(end -0.500126 -0.201422)
			(stroke
				(width 0)
				(type default)
			)
			(fill no)
			(layer "B.CrtYd")
		)
		(fp_line
			(start 0.500126 -0.201422)
			(end -0.500126 -0.201422)
			(stroke
				(width 0.1)
				(type default)
			)
			(layer "B.Fab")
		)
		(fp_line
			(start -0.500126 -0.201422)
			(end -0.500126 1.598422)
			(stroke
				(width 0.1)
				(type default)
			)
			(layer "B.Fab")
		)
		(fp_line
			(start 0.500126 1.598422)
			(end 0.500126 -0.201422)
			(stroke
				(width 0.1)
				(type default)
			)
			(layer "B.Fab")
		)
		(fp_line
			(start -0.500126 1.598422)
			(end 0.500126 1.598422)
			(stroke
				(width 0.1)
				(type default)
			)
			(layer "B.Fab")
		)
		(pad "1" smd rect
			(at 0 0)
			(size 0.889 0.9906)
			(layers "B.Cu" "B.Mask" "B.Paste")
			(net "PVDDQ_KLM")
		)
		(pad "2" smd rect
			(at 0 1.397)
			(size 0.889 0.9906)
			(layers "B.Cu" "B.Mask" "B.Paste")
			(net "GND")
		)
		(zone
			(layer "B.Cu")
			(hatch none 0.5)
			(connect_pads
				(clearance 0)
			)
			(min_thickness 0.25)
			(keepout
				(tracks not_allowed)
				(vias allowed)
				(pads allowed)
				(copperpour not_allowed)
				(footprints allowed)
			)
			(placement
				(enabled no)
				(sheetname "")
			)
			(fill
				(thermal_gap 0.5)
				(thermal_bridge_width 0.5)
				(island_removal_mode 0)
			)
			(polygon
				(pts
					(xy 105.5116 -135.9027) (xy 105.0036 -135.9027) (xy 105.0036 -134.9121) (xy 105.5116 -134.9121)
				)
			)
		)
		(zone
			(layer "B.Cu")
			(hatch none 0.5)
			(connect_pads
				(clearance 0)
			)
			(min_thickness 0.25)
			(keepout
				(tracks allowed)
				(vias not_allowed)
				(pads allowed)
				(copperpour not_allowed)
				(footprints allowed)
			)
			(placement
				(enabled no)
				(sheetname "")
			)
			(fill
				(thermal_gap 0.5)
				(thermal_bridge_width 0.5)
				(island_removal_mode 0)
			)
			(polygon
				(pts
					(xy 105.5116 -135.9027) (xy 105.0036 -135.9027) (xy 105.0036 -134.9121) (xy 105.5116 -134.9121)
				)
			)
		)
	)
	(footprint ""
		(layer "B.Cu")
		(at 32.258 -95.1484 90)
		(property "Reference" "R9N3"
			(at 0 0 90)
			(layer "B.SilkS")
			(hide yes)
			(effects
				(font
					(size 1.27 1.27)
				)
				(justify mirror)
			)
		)
		(property "Value" ""
			(at 0 0 90)
			(layer "B.Fab")
			(effects
				(font
					(size 1.27 1.27)
				)
				(justify mirror)
			)
		)
		(duplicate_pad_numbers_are_jumpers no)
		(fp_poly
			(pts
				(xy 0.2794 -0.1016) (xy -0.2794 -0.1016) (xy -0.2794 0.9906) (xy 0.2794 0.9906)
			)
			(stroke
				(width 0)
				(type default)
			)
			(fill no)
			(layer "B.CrtYd")
		)
		(fp_line
			(start 0.2794 -0.1016)
			(end 0.2794 0.9906)
			(stroke
				(width 0.1)
				(type default)
			)
			(layer "B.Fab")
		)
		(fp_line
			(start -0.2794 -0.1016)
			(end 0.2794 -0.1016)
			(stroke
				(width 0.1)
				(type default)
			)
			(layer "B.Fab")
		)
		(fp_line
			(start 0.2794 0.9906)
			(end -0.2794 0.9906)
			(stroke
				(width 0.1)
				(type default)
			)
			(layer "B.Fab")
		)
		(fp_line
			(start -0.2794 0.9906)
			(end -0.2794 -0.1016)
			(stroke
				(width 0.1)
				(type default)
			)
			(layer "B.Fab")
		)
		(pad "1" smd rect
			(at 0 0 270)
			(size 0.508 0.508)
			(layers "B.Cu" "B.Mask" "B.Paste")
			(net "VR_PVSA_CPU1_VCIN")
		)
		(pad "2" smd rect
			(at 0 0.889 270)
			(size 0.508 0.508)
			(layers "B.Cu" "B.Mask" "B.Paste")
			(net "P5V_STBY")
		)
		(zone
			(layer "B.Cu")
			(hatch none 0.5)
			(connect_pads
				(clearance 0)
			)
			(min_thickness 0.25)
			(keepout
				(tracks allowed)
				(vias not_allowed)
				(pads allowed)
				(copperpour not_allowed)
				(footprints allowed)
			)
			(placement
				(enabled no)
				(sheetname "")
			)
			(fill
				(thermal_gap 0.5)
				(thermal_bridge_width 0.5)
				(island_removal_mode 0)
			)
			(polygon
				(pts
					(xy 32.512 -95.4024) (xy 32.512 -94.8944) (xy 32.893 -94.8944) (xy 32.893 -95.4024)
				)
			)
		)
		(zone
			(layer "B.Cu")
			(hatch none 0.5)
			(connect_pads
				(clearance 0)
			)
			(min_thickness 0.25)
			(keepout
				(tracks not_allowed)
				(vias allowed)
				(pads allowed)
				(copperpour not_allowed)
				(footprints allowed)
			)
			(placement
				(enabled no)
				(sheetname "")
			)
			(fill
				(thermal_gap 0.5)
				(thermal_bridge_width 0.5)
				(island_removal_mode 0)
			)
			(polygon
				(pts
					(xy 32.893 -95.4024) (xy 32.893 -94.8944) (xy 32.512 -94.8944) (xy 32.512 -95.4024)
				)
			)
		)
	)
	(footprint ""
		(layer "B.Cu")
		(at 465.328 -116.49202)
		(property "Reference" "C1M7"
			(at 0 0 0)
			(layer "B.SilkS")
			(hide yes)
			(effects
				(font
					(size 1.27 1.27)
				)
				(justify mirror)
			)
		)
		(property "Value" ""
			(at 0 0 0)
			(layer "B.Fab")
			(effects
				(font
					(size 1.27 1.27)
				)
				(justify mirror)
			)
		)
		(duplicate_pad_numbers_are_jumpers no)
		(fp_rect
			(start -0.3048 0.9906)
			(end 0.3048 -0.1016)
			(stroke
				(width 0)
				(type default)
			)
			(fill no)
			(layer "B.CrtYd")
		)
		(fp_line
			(start -0.3048 -0.1016)
			(end 0.3048 -0.1016)
			(stroke
				(width 0.1)
				(type default)
			)
			(layer "B.Fab")
		)
		(fp_line
			(start -0.3048 0.9906)
			(end -0.3048 -0.1016)
			(stroke
				(width 0.1)
				(type default)
			)
			(layer "B.Fab")
		)
		(fp_line
			(start 0.3048 -0.1016)
			(end 0.3048 0.9906)
			(stroke
				(width 0.1)
				(type default)
			)
			(layer "B.Fab")
		)
		(fp_line
			(start 0.3048 0.9906)
			(end -0.3048 0.9906)
			(stroke
				(width 0.1)
				(type default)
			)
			(layer "B.Fab")
		)
		(pad "1" smd rect
			(at 0 0 180)
			(size 0.508 0.508)
			(layers "B.Cu" "B.Mask" "B.Paste")
			(net "P3E_CPU0_PE3_OCP_TXN<15>")
		)
		(pad "2" smd rect
			(at 0 0.889 180)
			(size 0.508 0.508)
			(layers "B.Cu" "B.Mask" "B.Paste")
			(net "P3E_OCP_CPU0_PE3_C_TXN<15>")
		)
		(zone
			(layer "B.Cu")
			(hatch none 0.5)
			(connect_pads
				(clearance 0)
			)
			(min_thickness 0.25)
			(keepout
				(tracks allowed)
				(vias not_allowed)
				(pads allowed)
				(copperpour not_allowed)
				(footprints allowed)
			)
			(placement
				(enabled no)
				(sheetname "")
			)
			(fill
				(thermal_gap 0.5)
				(thermal_bridge_width 0.5)
				(island_removal_mode 0)
			)
			(polygon
				(pts
					(xy 465.074 -115.85702) (xy 465.582 -115.85702) (xy 465.582 -116.23802) (xy 465.074 -116.23802)
				)
			)
		)
		(zone
			(layer "B.Cu")
			(hatch none 0.5)
			(connect_pads
				(clearance 0)
			)
			(min_thickness 0.25)
			(keepout
				(tracks not_allowed)
				(vias allowed)
				(pads allowed)
				(copperpour not_allowed)
				(footprints allowed)
			)
			(placement
				(enabled no)
				(sheetname "")
			)
			(fill
				(thermal_gap 0.5)
				(thermal_bridge_width 0.5)
				(island_removal_mode 0)
			)
			(polygon
				(pts
					(xy 465.074 -115.85702) (xy 465.582 -115.85702) (xy 465.582 -116.23802) (xy 465.074 -116.23802)
				)
			)
		)
	)
	(footprint ""
		(layer "B.Cu")
		(at 450.2277 -148.59 -90)
		(property "Reference" "C25W93"
			(at 0.8382 -0.67818 270)
			(unlocked yes)
			(layer "B.SilkS")
			(effects
				(font
					(size 0.4064 0.254)
					(thickness 0.1524)
				)
				(justify left mirror)
			)
		)
		(property "Value" ""
			(at 0 0 90)
			(layer "B.Fab")
			(effects
				(font
					(size 1.27 1.27)
				)
				(justify mirror)
			)
		)
		(duplicate_pad_numbers_are_jumpers no)
		(fp_poly
			(pts
				(xy -0.3048 -0.1016) (xy -0.3048 0.9906) (xy 0.3048 0.9906) (xy 0.3048 -0.1016)
			)
			(stroke
				(width 0)
				(type default)
			)
			(fill no)
			(layer "B.CrtYd")
		)
		(fp_line
			(start -0.3048 0.9906)
			(end -0.3048 -0.1016)
			(stroke
				(width 0.1)
				(type default)
			)
			(layer "B.Fab")
		)
		(fp_line
			(start 0.3048 0.9906)
			(end -0.3048 0.9906)
			(stroke
				(width 0.1)
				(type default)
			)
			(layer "B.Fab")
		)
		(fp_line
			(start -0.3048 -0.1016)
			(end 0.3048 -0.1016)
			(stroke
				(width 0.1)
				(type default)
			)
			(layer "B.Fab")
		)
		(fp_line
			(start 0.3048 -0.1016)
			(end 0.3048 0.9906)
			(stroke
				(width 0.1)
				(type default)
			)
			(layer "B.Fab")
		)
		(pad "1" smd rect
			(at 0 0 90)
			(size 0.508 0.508)
			(layers "B.Cu" "B.Mask" "B.Paste")
			(net "P0V7_GTL2014_VREF_6")
		)
		(pad "2" smd rect
			(at 0 0.889 90)
			(size 0.508 0.508)
			(layers "B.Cu" "B.Mask" "B.Paste")
			(net "GND")
		)
		(zone
			(layer "B.Cu")
			(hatch none 0.5)
			(connect_pads
				(clearance 0)
			)
			(min_thickness 0.25)
			(keepout
				(tracks not_allowed)
				(vias allowed)
				(pads allowed)
				(copperpour not_allowed)
				(footprints allowed)
			)
			(placement
				(enabled no)
				(sheetname "")
			)
			(fill
				(thermal_gap 0.5)
				(thermal_bridge_width 0.5)
				(island_removal_mode 0)
			)
			(polygon
				(pts
					(xy 449.5927 -148.336) (xy 449.5927 -148.844) (xy 449.9737 -148.844) (xy 449.9737 -148.336)
				)
			)
		)
		(zone
			(layer "B.Cu")
			(hatch none 0.5)
			(connect_pads
				(clearance 0)
			)
			(min_thickness 0.25)
			(keepout
				(tracks allowed)
				(vias not_allowed)
				(pads allowed)
				(copperpour not_allowed)
				(footprints allowed)
			)
			(placement
				(enabled no)
				(sheetname "")
			)
			(fill
				(thermal_gap 0.5)
				(thermal_bridge_width 0.5)
				(island_removal_mode 0)
			)
			(polygon
				(pts
					(xy 449.9737 -148.336) (xy 449.9737 -148.844) (xy 449.5927 -148.844) (xy 449.5927 -148.336)
				)
			)
		)
	)
	(footprint ""
		(layer "B.Cu")
		(at 330.08316 -67.26936 90)
		(property "Reference" "R4P15"
			(at 0 0 90)
			(layer "B.SilkS")
			(hide yes)
			(effects
				(font
					(size 1.27 1.27)
				)
				(justify mirror)
			)
		)
		(property "Value" ""
			(at 0 0 90)
			(layer "B.Fab")
			(effects
				(font
					(size 1.27 1.27)
				)
				(justify mirror)
			)
		)
		(duplicate_pad_numbers_are_jumpers no)
		(fp_poly
			(pts
				(xy 0.2794 -0.1016) (xy -0.2794 -0.1016) (xy -0.2794 0.9906) (xy 0.2794 0.9906)
			)
			(stroke
				(width 0)
				(type default)
			)
			(fill no)
			(layer "B.CrtYd")
		)
		(fp_line
			(start 0.2794 -0.1016)
			(end 0.2794 0.9906)
			(stroke
				(width 0.1)
				(type default)
			)
			(layer "B.Fab")
		)
		(fp_line
			(start -0.2794 -0.1016)
			(end 0.2794 -0.1016)
			(stroke
				(width 0.1)
				(type default)
			)
			(layer "B.Fab")
		)
		(fp_line
			(start 0.2794 0.9906)
			(end -0.2794 0.9906)
			(stroke
				(width 0.1)
				(type default)
			)
			(layer "B.Fab")
		)
		(fp_line
			(start -0.2794 0.9906)
			(end -0.2794 -0.1016)
			(stroke
				(width 0.1)
				(type default)
			)
			(layer "B.Fab")
		)
		(pad "1" smd rect
			(at 0 0 270)
			(size 0.508 0.508)
			(layers "B.Cu" "B.Mask" "B.Paste")
			(net "PVCCIO_CPU0")
		)
		(pad "2" smd rect
			(at 0 0.889 270)
			(size 0.508 0.508)
			(layers "B.Cu" "B.Mask" "B.Paste")
			(net "XDP_CPU_MBP1_N")
		)
		(zone
			(layer "B.Cu")
			(hatch none 0.5)
			(connect_pads
				(clearance 0)
			)
			(min_thickness 0.25)
			(keepout
				(tracks allowed)
				(vias not_allowed)
				(pads allowed)
				(copperpour not_allowed)
				(footprints allowed)
			)
			(placement
				(enabled no)
				(sheetname "")
			)
			(fill
				(thermal_gap 0.5)
				(thermal_bridge_width 0.5)
				(island_removal_mode 0)
			)
			(polygon
				(pts
					(xy 330.33716 -67.52336) (xy 330.33716 -67.01536) (xy 330.71816 -67.01536) (xy 330.71816 -67.52336)
				)
			)
		)
		(zone
			(layer "B.Cu")
			(hatch none 0.5)
			(connect_pads
				(clearance 0)
			)
			(min_thickness 0.25)
			(keepout
				(tracks not_allowed)
				(vias allowed)
				(pads allowed)
				(copperpour not_allowed)
				(footprints allowed)
			)
			(placement
				(enabled no)
				(sheetname "")
			)
			(fill
				(thermal_gap 0.5)
				(thermal_bridge_width 0.5)
				(island_removal_mode 0)
			)
			(polygon
				(pts
					(xy 330.71816 -67.52336) (xy 330.71816 -67.01536) (xy 330.33716 -67.01536) (xy 330.33716 -67.52336)
				)
			)
		)
	)
	(footprint ""
		(layer "B.Cu")
		(at 339.717126 -90.049604 90)
		(property "Reference" "R3N19"
			(at 0 0 90)
			(layer "B.SilkS")
			(hide yes)
			(effects
				(font
					(size 1.27 1.27)
				)
				(justify mirror)
			)
		)
		(property "Value" ""
			(at 0 0 90)
			(layer "B.Fab")
			(effects
				(font
					(size 1.27 1.27)
				)
				(justify mirror)
			)
		)
		(duplicate_pad_numbers_are_jumpers no)
		(fp_poly
			(pts
				(xy 0.2794 -0.1016) (xy -0.2794 -0.1016) (xy -0.2794 0.9906) (xy 0.2794 0.9906)
			)
			(stroke
				(width 0)
				(type default)
			)
			(fill no)
			(layer "B.CrtYd")
		)
		(fp_line
			(start 0.2794 -0.1016)
			(end 0.2794 0.9906)
			(stroke
				(width 0.1)
				(type default)
			)
			(layer "B.Fab")
		)
		(fp_line
			(start -0.2794 -0.1016)
			(end 0.2794 -0.1016)
			(stroke
				(width 0.1)
				(type default)
			)
			(layer "B.Fab")
		)
		(fp_line
			(start 0.2794 0.9906)
			(end -0.2794 0.9906)
			(stroke
				(width 0.1)
				(type default)
			)
			(layer "B.Fab")
		)
		(fp_line
			(start -0.2794 0.9906)
			(end -0.2794 -0.1016)
			(stroke
				(width 0.1)
				(type default)
			)
			(layer "B.Fab")
		)
		(pad "1" smd rect
			(at 0 0 270)
			(size 0.508 0.508)
			(layers "B.Cu" "B.Mask" "B.Paste")
			(net "VSENSE_PVCCIO_CPU0_AVSP")
		)
		(pad "2" smd rect
			(at 0 0.889 270)
			(size 0.508 0.508)
			(layers "B.Cu" "B.Mask" "B.Paste")
			(net "VR_PVCCIO_CPU0_AVSP")
		)
		(zone
			(layer "B.Cu")
			(hatch none 0.5)
			(connect_pads
				(clearance 0)
			)
			(min_thickness 0.25)
			(keepout
				(tracks allowed)
				(vias not_allowed)
				(pads allowed)
				(copperpour not_allowed)
				(footprints allowed)
			)
			(placement
				(enabled no)
				(sheetname "")
			)
			(fill
				(thermal_gap 0.5)
				(thermal_bridge_width 0.5)
				(island_removal_mode 0)
			)
			(polygon
				(pts
					(xy 339.971126 -90.303604) (xy 339.971126 -89.795604) (xy 340.352126 -89.795604) (xy 340.352126 -90.303604)
				)
			)
		)
		(zone
			(layer "B.Cu")
			(hatch none 0.5)
			(connect_pads
				(clearance 0)
			)
			(min_thickness 0.25)
			(keepout
				(tracks not_allowed)
				(vias allowed)
				(pads allowed)
				(copperpour not_allowed)
				(footprints allowed)
			)
			(placement
				(enabled no)
				(sheetname "")
			)
			(fill
				(thermal_gap 0.5)
				(thermal_bridge_width 0.5)
				(island_removal_mode 0)
			)
			(polygon
				(pts
					(xy 340.352126 -90.303604) (xy 340.352126 -89.795604) (xy 339.971126 -89.795604) (xy 339.971126 -90.303604)
				)
			)
		)
	)
	(footprint ""
		(layer "B.Cu")
		(at 13.11402 -100.46208 90)
		(property "Reference" "C9N14"
			(at 0 0 90)
			(layer "B.SilkS")
			(hide yes)
			(effects
				(font
					(size 1.27 1.27)
				)
				(justify mirror)
			)
		)
		(property "Value" ""
			(at 0 0 90)
			(layer "B.Fab")
			(effects
				(font
					(size 1.27 1.27)
				)
				(justify mirror)
			)
		)
		(duplicate_pad_numbers_are_jumpers no)
		(fp_poly
			(pts
				(xy -0.3048 -0.1016) (xy -0.3048 0.9906) (xy 0.3048 0.9906) (xy 0.3048 -0.1016)
			)
			(stroke
				(width 0)
				(type default)
			)
			(fill no)
			(layer "B.CrtYd")
		)
		(fp_line
			(start 0.3048 -0.1016)
			(end 0.3048 0.9906)
			(stroke
				(width 0.1)
				(type default)
			)
			(layer "B.Fab")
		)
		(fp_line
			(start -0.3048 -0.1016)
			(end 0.3048 -0.1016)
			(stroke
				(width 0.1)
				(type default)
			)
			(layer "B.Fab")
		)
		(fp_line
			(start 0.3048 0.9906)
			(end -0.3048 0.9906)
			(stroke
				(width 0.1)
				(type default)
			)
			(layer "B.Fab")
		)
		(fp_line
			(start -0.3048 0.9906)
			(end -0.3048 -0.1016)
			(stroke
				(width 0.1)
				(type default)
			)
			(layer "B.Fab")
		)
		(pad "1" smd rect
			(at 0 0 270)
			(size 0.508 0.508)
			(layers "B.Cu" "B.Mask" "B.Paste")
			(net "P3E_CPU1_PE3_MP_C_TXP<12>")
		)
		(pad "2" smd rect
			(at 0 0.889 270)
			(size 0.508 0.508)
			(layers "B.Cu" "B.Mask" "B.Paste")
			(net "P3E_CPU1_PE3_MP_TXP<12>")
		)
		(zone
			(layer "B.Cu")
			(hatch none 0.5)
			(connect_pads
				(clearance 0)
			)
			(min_thickness 0.25)
			(keepout
				(tracks allowed)
				(vias not_allowed)
				(pads allowed)
				(copperpour not_allowed)
				(footprints allowed)
			)
			(placement
				(enabled no)
				(sheetname "")
			)
			(fill
				(thermal_gap 0.5)
				(thermal_bridge_width 0.5)
				(island_removal_mode 0)
			)
			(polygon
				(pts
					(xy 13.36802 -100.71608) (xy 13.36802 -100.20808) (xy 13.74902 -100.20808) (xy 13.74902 -100.71608)
				)
			)
		)
		(zone
			(layer "B.Cu")
			(hatch none 0.5)
			(connect_pads
				(clearance 0)
			)
			(min_thickness 0.25)
			(keepout
				(tracks not_allowed)
				(vias allowed)
				(pads allowed)
				(copperpour not_allowed)
				(footprints allowed)
			)
			(placement
				(enabled no)
				(sheetname "")
			)
			(fill
				(thermal_gap 0.5)
				(thermal_bridge_width 0.5)
				(island_removal_mode 0)
			)
			(polygon
				(pts
					(xy 13.74902 -100.71608) (xy 13.74902 -100.20808) (xy 13.36802 -100.20808) (xy 13.36802 -100.71608)
				)
			)
		)
	)
	(footprint ""
		(layer "B.Cu")
		(at 409.6004 -146.939 -90)
		(property "Reference" "C2L24"
			(at 0 0 90)
			(layer "B.SilkS")
			(hide yes)
			(effects
				(font
					(size 1.27 1.27)
				)
				(justify mirror)
			)
		)
		(property "Value" ""
			(at 0 0 90)
			(layer "B.Fab")
			(effects
				(font
					(size 1.27 1.27)
				)
				(justify mirror)
			)
		)
		(duplicate_pad_numbers_are_jumpers no)
		(fp_poly
			(pts
				(xy -0.3048 -0.1016) (xy -0.3048 0.9906) (xy 0.3048 0.9906) (xy 0.3048 -0.1016)
			)
			(stroke
				(width 0)
				(type default)
			)
			(fill no)
			(layer "B.CrtYd")
		)
		(fp_line
			(start -0.3048 0.9906)
			(end -0.3048 -0.1016)
			(stroke
				(width 0.1)
				(type default)
			)
			(layer "B.Fab")
		)
		(fp_line
			(start 0.3048 0.9906)
			(end -0.3048 0.9906)
			(stroke
				(width 0.1)
				(type default)
			)
			(layer "B.Fab")
		)
		(fp_line
			(start -0.3048 -0.1016)
			(end 0.3048 -0.1016)
			(stroke
				(width 0.1)
				(type default)
			)
			(layer "B.Fab")
		)
		(fp_line
			(start 0.3048 -0.1016)
			(end 0.3048 0.9906)
			(stroke
				(width 0.1)
				(type default)
			)
			(layer "B.Fab")
		)
		(pad "1" smd rect
			(at 0 0 90)
			(size 0.508 0.508)
			(layers "B.Cu" "B.Mask" "B.Paste")
			(net "SATA6G_P7_TX_C_DP")
		)
		(pad "2" smd rect
			(at 0 0.889 90)
			(size 0.508 0.508)
			(layers "B.Cu" "B.Mask" "B.Paste")
			(net "SATA6G_PCH_PCIE_UP_SATA_TXP<7>")
		)
		(zone
			(layer "B.Cu")
			(hatch none 0.5)
			(connect_pads
				(clearance 0)
			)
			(min_thickness 0.25)
			(keepout
				(tracks not_allowed)
				(vias allowed)
				(pads allowed)
				(copperpour not_allowed)
				(footprints allowed)
			)
			(placement
				(enabled no)
				(sheetname "")
			)
			(fill
				(thermal_gap 0.5)
				(thermal_bridge_width 0.5)
				(island_removal_mode 0)
			)
			(polygon
				(pts
					(xy 408.9654 -146.685) (xy 408.9654 -147.193) (xy 409.3464 -147.193) (xy 409.3464 -146.685)
				)
			)
		)
		(zone
			(layer "B.Cu")
			(hatch none 0.5)
			(connect_pads
				(clearance 0)
			)
			(min_thickness 0.25)
			(keepout
				(tracks allowed)
				(vias not_allowed)
				(pads allowed)
				(copperpour not_allowed)
				(footprints allowed)
			)
			(placement
				(enabled no)
				(sheetname "")
			)
			(fill
				(thermal_gap 0.5)
				(thermal_bridge_width 0.5)
				(island_removal_mode 0)
			)
			(polygon
				(pts
					(xy 409.3464 -146.685) (xy 409.3464 -147.193) (xy 408.9654 -147.193) (xy 408.9654 -146.685)
				)
			)
		)
	)
	(footprint ""
		(layer "B.Cu")
		(at 462.026 -116.49202)
		(property "Reference" "C1M9"
			(at 0 0 0)
			(layer "B.SilkS")
			(hide yes)
			(effects
				(font
					(size 1.27 1.27)
				)
				(justify mirror)
			)
		)
		(property "Value" ""
			(at 0 0 0)
			(layer "B.Fab")
			(effects
				(font
					(size 1.27 1.27)
				)
				(justify mirror)
			)
		)
		(duplicate_pad_numbers_are_jumpers no)
		(fp_rect
			(start -0.3048 0.9906)
			(end 0.3048 -0.1016)
			(stroke
				(width 0)
				(type default)
			)
			(fill no)
			(layer "B.CrtYd")
		)
		(fp_line
			(start -0.3048 -0.1016)
			(end 0.3048 -0.1016)
			(stroke
				(width 0.1)
				(type default)
			)
			(layer "B.Fab")
		)
		(fp_line
			(start -0.3048 0.9906)
			(end -0.3048 -0.1016)
			(stroke
				(width 0.1)
				(type default)
			)
			(layer "B.Fab")
		)
		(fp_line
			(start 0.3048 -0.1016)
			(end 0.3048 0.9906)
			(stroke
				(width 0.1)
				(type default)
			)
			(layer "B.Fab")
		)
		(fp_line
			(start 0.3048 0.9906)
			(end -0.3048 0.9906)
			(stroke
				(width 0.1)
				(type default)
			)
			(layer "B.Fab")
		)
		(pad "1" smd rect
			(at 0 0 180)
			(size 0.508 0.508)
			(layers "B.Cu" "B.Mask" "B.Paste")
			(net "P3E_CPU0_PE3_OCP_TXN<14>")
		)
		(pad "2" smd rect
			(at 0 0.889 180)
			(size 0.508 0.508)
			(layers "B.Cu" "B.Mask" "B.Paste")
			(net "P3E_OCP_CPU0_PE3_C_TXN<14>")
		)
		(zone
			(layer "B.Cu")
			(hatch none 0.5)
			(connect_pads
				(clearance 0)
			)
			(min_thickness 0.25)
			(keepout
				(tracks allowed)
				(vias not_allowed)
				(pads allowed)
				(copperpour not_allowed)
				(footprints allowed)
			)
			(placement
				(enabled no)
				(sheetname "")
			)
			(fill
				(thermal_gap 0.5)
				(thermal_bridge_width 0.5)
				(island_removal_mode 0)
			)
			(polygon
				(pts
					(xy 461.772 -115.85702) (xy 462.28 -115.85702) (xy 462.28 -116.23802) (xy 461.772 -116.23802)
				)
			)
		)
	)
	(footprint ""
		(layer "B.Cu")
		(at 399.764758 -115.605814)
		(property "Reference" "R24W1"
			(at 0.8382 -0.67818 0)
			(unlocked yes)
			(layer "B.SilkS")
			(effects
				(font
					(size 0.4064 0.254)
					(thickness 0.1524)
				)
				(justify left mirror)
			)
		)
		(property "Value" ""
			(at 0 0 0)
			(layer "B.Fab")
			(effects
				(font
					(size 1.27 1.27)
				)
				(justify mirror)
			)
		)
		(duplicate_pad_numbers_are_jumpers no)
		(fp_poly
			(pts
				(xy 0.2794 -0.1016) (xy -0.2794 -0.1016) (xy -0.2794 0.9906) (xy 0.2794 0.9906)
			)
			(stroke
				(width 0)
				(type default)
			)
			(fill no)
			(layer "B.CrtYd")
		)
		(fp_line
			(start -0.2794 -0.1016)
			(end 0.2794 -0.1016)
			(stroke
				(width 0.1)
				(type default)
			)
			(layer "B.Fab")
		)
		(fp_line
			(start -0.2794 0.9906)
			(end -0.2794 -0.1016)
			(stroke
				(width 0.1)
				(type default)
			)
			(layer "B.Fab")
		)
		(fp_line
			(start 0.2794 -0.1016)
			(end 0.2794 0.9906)
			(stroke
				(width 0.1)
				(type default)
			)
			(layer "B.Fab")
		)
		(fp_line
			(start 0.2794 0.9906)
			(end -0.2794 0.9906)
			(stroke
				(width 0.1)
				(type default)
			)
			(layer "B.Fab")
		)
		(pad "1" smd rect
			(at 0 0 180)
			(size 0.508 0.508)
			(layers "B.Cu" "B.Mask" "B.Paste")
			(net "P3V3_STBY")
		)
		(pad "2" smd rect
			(at 0 0.889 180)
			(size 0.508 0.508)
			(layers "B.Cu" "B.Mask" "B.Paste")
			(net "SMB_SLOTX24_PCH_STBY_LVC3_SDA")
		)
		(zone
			(layer "B.Cu")
			(hatch none 0.5)
			(connect_pads
				(clearance 0)
			)
			(min_thickness 0.25)
			(keepout
				(tracks allowed)
				(vias not_allowed)
				(pads allowed)
				(copperpour not_allowed)
				(footprints allowed)
			)
			(placement
				(enabled no)
				(sheetname "")
			)
			(fill
				(thermal_gap 0.5)
				(thermal_bridge_width 0.5)
				(island_removal_mode 0)
			)
			(polygon
				(pts
					(xy 400.018758 -115.351814) (xy 399.510758 -115.351814) (xy 399.510758 -114.970814) (xy 400.018758 -114.970814)
				)
			)
		)
		(zone
			(layer "B.Cu")
			(hatch none 0.5)
			(connect_pads
				(clearance 0)
			)
			(min_thickness 0.25)
			(keepout
				(tracks not_allowed)
				(vias allowed)
				(pads allowed)
				(copperpour not_allowed)
				(footprints allowed)
			)
			(placement
				(enabled no)
				(sheetname "")
			)
			(fill
				(thermal_gap 0.5)
				(thermal_bridge_width 0.5)
				(island_removal_mode 0)
			)
			(polygon
				(pts
					(xy 400.018758 -114.970814) (xy 399.510758 -114.970814) (xy 399.510758 -115.351814) (xy 400.018758 -115.351814)
				)
			)
		)
	)
	(footprint ""
		(layer "B.Cu")
		(at 413.059118 -92.428314)
		(property "Reference" "R3R4"
			(at 0 0 0)
			(layer "B.SilkS")
			(hide yes)
			(effects
				(font
					(size 1.27 1.27)
				)
				(justify mirror)
			)
		)
		(property "Value" ""
			(at 0 0 0)
			(layer "B.Fab")
			(effects
				(font
					(size 1.27 1.27)
				)
				(justify mirror)
			)
		)
		(duplicate_pad_numbers_are_jumpers no)
		(fp_poly
			(pts
				(xy 0.2794 -0.1016) (xy -0.2794 -0.1016) (xy -0.2794 0.9906) (xy 0.2794 0.9906)
			)
			(stroke
				(width 0)
				(type default)
			)
			(fill no)
			(layer "B.CrtYd")
		)
		(fp_line
			(start -0.2794 -0.1016)
			(end 0.2794 -0.1016)
			(stroke
				(width 0.1)
				(type default)
			)
			(layer "B.Fab")
		)
		(fp_line
			(start -0.2794 0.9906)
			(end -0.2794 -0.1016)
			(stroke
				(width 0.1)
				(type default)
			)
			(layer "B.Fab")
		)
		(fp_line
			(start 0.2794 -0.1016)
			(end 0.2794 0.9906)
			(stroke
				(width 0.1)
				(type default)
			)
			(layer "B.Fab")
		)
		(fp_line
			(start 0.2794 0.9906)
			(end -0.2794 0.9906)
			(stroke
				(width 0.1)
				(type default)
			)
			(layer "B.Fab")
		)
		(pad "1" smd rect
			(at 0 0 180)
			(size 0.508 0.508)
			(layers "B.Cu" "B.Mask" "B.Paste")
			(net "P3V3")
		)
		(pad "2" smd rect
			(at 0 0.889 180)
			(size 0.508 0.508)
			(layers "B.Cu" "B.Mask" "B.Paste")
			(net "H_CPU0_MEMDEF_MEMHOT")
		)
		(zone
			(layer "B.Cu")
			(hatch none 0.5)
			(connect_pads
				(clearance 0)
			)
			(min_thickness 0.25)
			(keepout
				(tracks allowed)
				(vias not_allowed)
				(pads allowed)
				(copperpour not_allowed)
				(footprints allowed)
			)
			(placement
				(enabled no)
				(sheetname "")
			)
			(fill
				(thermal_gap 0.5)
				(thermal_bridge_width 0.5)
				(island_removal_mode 0)
			)
			(polygon
				(pts
					(xy 413.313118 -92.174314) (xy 412.805118 -92.174314) (xy 412.805118 -91.793314) (xy 413.313118 -91.793314)
				)
			)
		)
		(zone
			(layer "B.Cu")
			(hatch none 0.5)
			(connect_pads
				(clearance 0)
			)
			(min_thickness 0.25)
			(keepout
				(tracks not_allowed)
				(vias allowed)
				(pads allowed)
				(copperpour not_allowed)
				(footprints allowed)
			)
			(placement
				(enabled no)
				(sheetname "")
			)
			(fill
				(thermal_gap 0.5)
				(thermal_bridge_width 0.5)
				(island_removal_mode 0)
			)
			(polygon
				(pts
					(xy 413.313118 -91.793314) (xy 412.805118 -91.793314) (xy 412.805118 -92.174314) (xy 413.313118 -92.174314)
				)
			)
		)
	)
	(footprint ""
		(layer "B.Cu")
		(at 386.80898 -126.9238 180)
		(property "Reference" "R3M10"
			(at 0 0 0)
			(layer "B.SilkS")
			(hide yes)
			(effects
				(font
					(size 1.27 1.27)
				)
				(justify mirror)
			)
		)
		(property "Value" ""
			(at 0 0 0)
			(layer "B.Fab")
			(effects
				(font
					(size 1.27 1.27)
				)
				(justify mirror)
			)
		)
		(duplicate_pad_numbers_are_jumpers no)
		(fp_poly
			(pts
				(xy 0.2794 -0.1016) (xy -0.2794 -0.1016) (xy -0.2794 0.9906) (xy 0.2794 0.9906)
			)
			(stroke
				(width 0)
				(type default)
			)
			(fill no)
			(layer "B.CrtYd")
		)
		(fp_line
			(start 0.2794 0.9906)
			(end -0.2794 0.9906)
			(stroke
				(width 0.1)
				(type default)
			)
			(layer "B.Fab")
		)
		(fp_line
			(start 0.2794 -0.1016)
			(end 0.2794 0.9906)
			(stroke
				(width 0.1)
				(type default)
			)
			(layer "B.Fab")
		)
		(fp_line
			(start -0.2794 0.9906)
			(end -0.2794 -0.1016)
			(stroke
				(width 0.1)
				(type default)
			)
			(layer "B.Fab")
		)
		(fp_line
			(start -0.2794 -0.1016)
			(end 0.2794 -0.1016)
			(stroke
				(width 0.1)
				(type default)
			)
			(layer "B.Fab")
		)
		(pad "1" smd rect
			(at 0 0)
			(size 0.508 0.508)
			(layers "B.Cu" "B.Mask" "B.Paste")
			(net "XDP_PCH_CPU_TCK0")
		)
		(pad "2" smd rect
			(at 0 0.889)
			(size 0.508 0.508)
			(layers "B.Cu" "B.Mask" "B.Paste")
			(net "GND")
		)
		(zone
			(layer "B.Cu")
			(hatch none 0.5)
			(connect_pads
				(clearance 0)
			)
			(min_thickness 0.25)
			(keepout
				(tracks not_allowed)
				(vias allowed)
				(pads allowed)
				(copperpour not_allowed)
				(footprints allowed)
			)
			(placement
				(enabled no)
				(sheetname "")
			)
			(fill
				(thermal_gap 0.5)
				(thermal_bridge_width 0.5)
				(island_removal_mode 0)
			)
			(polygon
				(pts
					(xy 386.55498 -127.5588) (xy 387.06298 -127.5588) (xy 387.06298 -127.1778) (xy 386.55498 -127.1778)
				)
			)
		)
		(zone
			(layer "B.Cu")
			(hatch none 0.5)
			(connect_pads
				(clearance 0)
			)
			(min_thickness 0.25)
			(keepout
				(tracks allowed)
				(vias not_allowed)
				(pads allowed)
				(copperpour not_allowed)
				(footprints allowed)
			)
			(placement
				(enabled no)
				(sheetname "")
			)
			(fill
				(thermal_gap 0.5)
				(thermal_bridge_width 0.5)
				(island_removal_mode 0)
			)
			(polygon
				(pts
					(xy 386.55498 -127.1778) (xy 387.06298 -127.1778) (xy 387.06298 -127.5588) (xy 386.55498 -127.5588)
				)
			)
		)
	)
	(footprint ""
		(layer "B.Cu")
		(at 162.179 -69.596)
		(property "Reference" "R7P20"
			(at 0 0 0)
			(layer "B.SilkS")
			(hide yes)
			(effects
				(font
					(size 1.27 1.27)
				)
				(justify mirror)
			)
		)
		(property "Value" ""
			(at 0 0 0)
			(layer "B.Fab")
			(effects
				(font
					(size 1.27 1.27)
				)
				(justify mirror)
			)
		)
		(duplicate_pad_numbers_are_jumpers no)
		(fp_poly
			(pts
				(xy 0.2794 -0.1016) (xy -0.2794 -0.1016) (xy -0.2794 0.9906) (xy 0.2794 0.9906)
			)
			(stroke
				(width 0)
				(type default)
			)
			(fill no)
			(layer "B.CrtYd")
		)
		(fp_line
			(start -0.2794 -0.1016)
			(end 0.2794 -0.1016)
			(stroke
				(width 0.1)
				(type default)
			)
			(layer "B.Fab")
		)
		(fp_line
			(start -0.2794 0.9906)
			(end -0.2794 -0.1016)
			(stroke
				(width 0.1)
				(type default)
			)
			(layer "B.Fab")
		)
		(fp_line
			(start 0.2794 -0.1016)
			(end 0.2794 0.9906)
			(stroke
				(width 0.1)
				(type default)
			)
			(layer "B.Fab")
		)
		(fp_line
			(start 0.2794 0.9906)
			(end -0.2794 0.9906)
			(stroke
				(width 0.1)
				(type default)
			)
			(layer "B.Fab")
		)
		(pad "1" smd rect
			(at 0 0 180)
			(size 0.508 0.508)
			(layers "B.Cu" "B.Mask" "B.Paste")
			(net "PVCCIO_CPU0")
		)
		(pad "2" smd rect
			(at 0 0.889 180)
			(size 0.508 0.508)
			(layers "B.Cu" "B.Mask" "B.Paste")
			(net "H_CPU1_FAST_WAKE_N")
		)
		(zone
			(layer "B.Cu")
			(hatch none 0.5)
			(connect_pads
				(clearance 0)
			)
			(min_thickness 0.25)
			(keepout
				(tracks allowed)
				(vias not_allowed)
				(pads allowed)
				(copperpour not_allowed)
				(footprints allowed)
			)
			(placement
				(enabled no)
				(sheetname "")
			)
			(fill
				(thermal_gap 0.5)
				(thermal_bridge_width 0.5)
				(island_removal_mode 0)
			)
			(polygon
				(pts
					(xy 162.433 -69.342) (xy 161.925 -69.342) (xy 161.925 -68.961) (xy 162.433 -68.961)
				)
			)
		)
		(zone
			(layer "B.Cu")
			(hatch none 0.5)
			(connect_pads
				(clearance 0)
			)
			(min_thickness 0.25)
			(keepout
				(tracks not_allowed)
				(vias allowed)
				(pads allowed)
				(copperpour not_allowed)
				(footprints allowed)
			)
			(placement
				(enabled no)
				(sheetname "")
			)
			(fill
				(thermal_gap 0.5)
				(thermal_bridge_width 0.5)
				(island_removal_mode 0)
			)
			(polygon
				(pts
					(xy 162.433 -68.961) (xy 161.925 -68.961) (xy 161.925 -69.342) (xy 162.433 -69.342)
				)
			)
		)
	)
	(footprint ""
		(layer "B.Cu")
		(at 438.5945 -15.92072)
		(property "Reference" "U9G1"
			(at -5.64388 -0.89027 0)
			(unlocked yes)
			(layer "B.SilkS")
			(effects
				(font
					(size 0.7874 0.5842)
					(thickness 0.1524)
				)
				(justify left mirror)
			)
		)
		(property "Value" ""
			(at 0 0 0)
			(layer "B.Fab")
			(effects
				(font
					(size 1.27 1.27)
				)
				(justify mirror)
			)
		)
		(duplicate_pad_numbers_are_jumpers no)
		(fp_line
			(start -4.4323 -0.64008)
			(end -4.4323 4.52628)
			(stroke
				(width 0.1524)
				(type default)
			)
			(layer "B.SilkS")
		)
		(fp_line
			(start -4.4323 4.52628)
			(end -1.5367 4.52628)
			(stroke
				(width 0.1524)
				(type default)
			)
			(layer "B.SilkS")
		)
		(fp_line
			(start -3.302 0.49022)
			(end -3.302 -0.64008)
			(stroke
				(width 0.1524)
				(type default)
			)
			(layer "B.SilkS")
		)
		(fp_line
			(start -2.667 -0.64008)
			(end -2.667 0.49022)
			(stroke
				(width 0.1524)
				(type default)
			)
			(layer "B.SilkS")
		)
		(fp_line
			(start -2.667 0.49022)
			(end -3.302 0.49022)
			(stroke
				(width 0.1524)
				(type default)
			)
			(layer "B.SilkS")
		)
		(fp_line
			(start -1.5367 -0.64008)
			(end -4.4323 -0.64008)
			(stroke
				(width 0.1524)
				(type default)
			)
			(layer "B.SilkS")
		)
		(fp_line
			(start -1.5367 4.52628)
			(end -1.5367 -0.64008)
			(stroke
				(width 0.1524)
				(type default)
			)
			(layer "B.SilkS")
		)
		(fp_circle
			(center 1.296162 -0.6731)
			(end 1.423162 -0.6731)
			(stroke
				(width 0.254)
				(type default)
			)
			(fill no)
			(layer "B.SilkS")
		)
		(fp_poly
			(pts
				(xy -0.7366 4.54152) (xy -0.7366 -0.64008) (xy -4.7244 -0.64008) (xy -5.2324 -0.64008) (xy -5.2324 4.54152)
				(xy -4.7244 4.54152)
			)
			(stroke
				(width 0)
				(type default)
			)
			(fill no)
			(layer "B.CrtYd")
		)
		(fp_line
			(start -5.2324 -0.64008)
			(end -5.2324 4.54152)
			(stroke
				(width 0.1)
				(type default)
			)
			(layer "B.Fab")
		)
		(fp_line
			(start -5.2324 4.54152)
			(end -0.7366 4.54152)
			(stroke
				(width 0.1)
				(type default)
			)
			(layer "B.Fab")
		)
		(fp_line
			(start -3.302 0.49022)
			(end -3.302 -0.64008)
			(stroke
				(width 0.1)
				(type default)
			)
			(layer "B.Fab")
		)
		(fp_line
			(start -2.667 -0.64008)
			(end -2.667 0.49022)
			(stroke
				(width 0.1)
				(type default)
			)
			(layer "B.Fab")
		)
		(fp_line
			(start -2.667 0.49022)
			(end -3.302 0.49022)
			(stroke
				(width 0.1)
				(type default)
			)
			(layer "B.Fab")
		)
		(fp_line
			(start -0.7366 -0.64008)
			(end -5.2324 -0.64008)
			(stroke
				(width 0.1)
				(type default)
			)
			(layer "B.Fab")
		)
		(fp_line
			(start -0.7366 4.54152)
			(end -0.7366 -0.64008)
			(stroke
				(width 0.1)
				(type default)
			)
			(layer "B.Fab")
		)
		(fp_circle
			(center 1.612138 -0.684784)
			(end 1.739138 -0.684784)
			(stroke
				(width 0.254)
				(type default)
			)
			(fill no)
			(layer "B.Fab")
		)
		(pad "1" smd rect
			(at 0 0 180)
			(size 2.159 0.381)
			(layers "B.Cu" "B.Mask" "B.Paste")
			(net "PD_DIR_2")
		)
		(pad "2" smd rect
			(at 0 0.65024 180)
			(size 2.159 0.381)
			(layers "B.Cu" "B.Mask" "B.Paste")
			(net "H_CPU1_MEMKLM_MEMHOT_G_R_N")
		)
		(pad "3" smd rect
			(at 0 1.30048 180)
			(size 2.159 0.381)
			(layers "B.Cu" "B.Mask" "B.Paste")
			(net "H_CPU1_MEMGHJ_MEMHOT_G_R_N")
		)
		(pad "4" smd rect
			(at 0 1.95072 180)
			(size 2.159 0.381)
			(layers "B.Cu" "B.Mask" "B.Paste")
			(net "P0V7_GTL2014_2")
		)
		(pad "5" smd rect
			(at 0 2.60096 180)
			(size 2.159 0.381)
			(layers "B.Cu" "B.Mask" "B.Paste")
			(net "H_CPU0_MEMDEF_MEMHOT_G_R_N")
		)
		(pad "6" smd rect
			(at 0 3.2512 180)
			(size 2.159 0.381)
			(layers "B.Cu" "B.Mask" "B.Paste")
			(net "H_CPU0_MEMABC_MEMHOT_G_R_N")
		)
		(pad "7" smd rect
			(at 0 3.90144 180)
			(size 2.159 0.381)
			(layers "B.Cu" "B.Mask" "B.Paste")
			(net "GND")
		)
		(pad "8" smd rect
			(at -5.969 3.90144 180)
			(size 2.159 0.381)
			(layers "B.Cu" "B.Mask" "B.Paste")
			(net "GND")
		)
		(pad "9" smd rect
			(at -5.969 3.2512 180)
			(size 2.159 0.381)
			(layers "B.Cu" "B.Mask" "B.Paste")
			(net "H_CPU0_ABC_MEMHOT_LVT3_R_N")
		)
		(pad "10" smd rect
			(at -5.969 2.60096 180)
			(size 2.159 0.381)
			(layers "B.Cu" "B.Mask" "B.Paste")
			(net "H_CPU0_DEF_MEMHOT_LVT3_R_N")
		)
		(pad "11" smd rect
			(at -5.969 1.95072 180)
			(size 2.159 0.381)
			(layers "B.Cu" "B.Mask" "B.Paste")
			(net "GND")
		)
		(pad "12" smd rect
			(at -5.969 1.30048 180)
			(size 2.159 0.381)
			(layers "B.Cu" "B.Mask" "B.Paste")
			(net "H_CPU1_GHJ_MEMHOT_LVT3_R_N")
		)
		(pad "13" smd rect
			(at -5.969 0.65024 180)
			(size 2.159 0.381)
			(layers "B.Cu" "B.Mask" "B.Paste")
			(net "H_CPU1_KLM_MEMHOT_LVT3_R_N")
		)
		(pad "14" smd rect
			(at -5.969 0 180)
			(size 2.159 0.381)
			(layers "B.Cu" "B.Mask" "B.Paste")
			(net "P3V3")
		)
	)
	(footprint ""
		(layer "B.Cu")
		(at 428.3075 -21.844 -90)
		(property "Reference" "R25W129"
			(at 0.8382 -0.67818 270)
			(unlocked yes)
			(layer "B.SilkS")
			(effects
				(font
					(size 0.4064 0.254)
					(thickness 0.1524)
				)
				(justify left mirror)
			)
		)
		(property "Value" ""
			(at 0 0 90)
			(layer "B.Fab")
			(effects
				(font
					(size 1.27 1.27)
				)
				(justify mirror)
			)
		)
		(duplicate_pad_numbers_are_jumpers no)
		(fp_poly
			(pts
				(xy 0.2794 -0.1016) (xy -0.2794 -0.1016) (xy -0.2794 0.9906) (xy 0.2794 0.9906)
			)
			(stroke
				(width 0)
				(type default)
			)
			(fill no)
			(layer "B.CrtYd")
		)
		(fp_line
			(start -0.2794 0.9906)
			(end -0.2794 -0.1016)
			(stroke
				(width 0.1)
				(type default)
			)
			(layer "B.Fab")
		)
		(fp_line
			(start 0.2794 0.9906)
			(end -0.2794 0.9906)
			(stroke
				(width 0.1)
				(type default)
			)
			(layer "B.Fab")
		)
		(fp_line
			(start -0.2794 -0.1016)
			(end 0.2794 -0.1016)
			(stroke
				(width 0.1)
				(type default)
			)
			(layer "B.Fab")
		)
		(fp_line
			(start 0.2794 -0.1016)
			(end 0.2794 0.9906)
			(stroke
				(width 0.1)
				(type default)
			)
			(layer "B.Fab")
		)
		(pad "1" smd rect
			(at 0 0 90)
			(size 0.508 0.508)
			(layers "B.Cu" "B.Mask" "B.Paste")
			(net "P3V3")
		)
		(pad "2" smd rect
			(at 0 0.889 90)
			(size 0.508 0.508)
			(layers "B.Cu" "B.Mask" "B.Paste")
			(net "I2C_BMC_VGA_DDC_SCL")
		)
		(zone
			(layer "B.Cu")
			(hatch none 0.5)
			(connect_pads
				(clearance 0)
			)
			(min_thickness 0.25)
			(keepout
				(tracks not_allowed)
				(vias allowed)
				(pads allowed)
				(copperpour not_allowed)
				(footprints allowed)
			)
			(placement
				(enabled no)
				(sheetname "")
			)
			(fill
				(thermal_gap 0.5)
				(thermal_bridge_width 0.5)
				(island_removal_mode 0)
			)
			(polygon
				(pts
					(xy 427.6725 -21.59) (xy 427.6725 -22.098) (xy 428.0535 -22.098) (xy 428.0535 -21.59)
				)
			)
		)
		(zone
			(layer "B.Cu")
			(hatch none 0.5)
			(connect_pads
				(clearance 0)
			)
			(min_thickness 0.25)
			(keepout
				(tracks allowed)
				(vias not_allowed)
				(pads allowed)
				(copperpour not_allowed)
				(footprints allowed)
			)
			(placement
				(enabled no)
				(sheetname "")
			)
			(fill
				(thermal_gap 0.5)
				(thermal_bridge_width 0.5)
				(island_removal_mode 0)
			)
			(polygon
				(pts
					(xy 428.0535 -21.59) (xy 428.0535 -22.098) (xy 427.6725 -22.098) (xy 427.6725 -21.59)
				)
			)
		)
	)
	(footprint ""
		(layer "B.Cu")
		(at 490.203998 -35.445192 180)
		(property "Reference" "U9F1"
			(at -3.03276 3.60553 180)
			(unlocked yes)
			(layer "B.SilkS")
			(effects
				(font
					(size 0.7874 0.5842)
					(thickness 0.1524)
				)
				(justify mirror)
			)
		)
		(property "Value" ""
			(at 0 0 0)
			(layer "B.Fab")
			(effects
				(font
					(size 1.27 1.27)
				)
				(justify mirror)
			)
		)
		(duplicate_pad_numbers_are_jumpers no)
		(fp_line
			(start -1.269238 1.8034)
			(end -1.77673 1.8034)
			(stroke
				(width 0.1524)
				(type default)
			)
			(layer "B.SilkS")
		)
		(fp_line
			(start -1.269238 -0.3048)
			(end -1.77673 -0.3048)
			(stroke
				(width 0.1524)
				(type default)
			)
			(layer "B.SilkS")
		)
		(fp_circle
			(center -0.149606 -0.7366)
			(end -0.276606 -0.7366)
			(stroke
				(width 0.635)
				(type default)
			)
			(fill no)
			(layer "B.SilkS")
		)
		(fp_rect
			(start -0.3302 1.8034)
			(end -2.7432 -0.3048)
			(stroke
				(width 0)
				(type default)
			)
			(fill no)
			(layer "B.CrtYd")
		)
		(fp_line
			(start -0.3302 1.8034)
			(end -0.3302 -0.3048)
			(stroke
				(width 0.1)
				(type default)
			)
			(layer "B.Fab")
		)
		(fp_line
			(start -0.3302 -0.3048)
			(end -2.7432 -0.3048)
			(stroke
				(width 0.1)
				(type default)
			)
			(layer "B.Fab")
		)
		(fp_line
			(start -2.7432 1.8034)
			(end -0.3302 1.8034)
			(stroke
				(width 0.1)
				(type default)
			)
			(layer "B.Fab")
		)
		(fp_line
			(start -2.7432 -0.3048)
			(end -2.7432 1.8034)
			(stroke
				(width 0.1)
				(type default)
			)
			(layer "B.Fab")
		)
		(fp_circle
			(center -0.149606 -0.7366)
			(end -0.276606 -0.7366)
			(stroke
				(width 0.254)
				(type default)
			)
			(fill no)
			(layer "B.Fab")
		)
		(pad "1" smd rect
			(at 0 0)
			(size 1.524 0.254)
			(layers "B.Cu" "B.Mask" "B.Paste")
			(net "SP2_BMC_CM_UART_RX_R")
		)
		(pad "2" smd rect
			(at 0 0.499872)
			(size 1.524 0.254)
			(layers "B.Cu" "B.Mask" "B.Paste")
			(net "UART_BMC_RXD5")
		)
		(pad "3" smd rect
			(at 0 0.999744)
			(size 1.524 0.254)
			(layers "B.Cu" "B.Mask" "B.Paste")
			(net "SP1_BMC_HOST_UART_RX")
		)
		(pad "4" smd rect
			(at 0 1.499616)
			(size 1.524 0.254)
			(layers "B.Cu" "B.Mask" "B.Paste")
			(net "GND")
		)
		(pad "5" smd rect
			(at -3.048 1.499616)
			(size 1.524 0.254)
			(layers "B.Cu" "B.Mask" "B.Paste")
			(net "FM_UARTSW_MSB_N")
		)
		(pad "6" smd rect
			(at -3.048 0.999744)
			(size 1.524 0.254)
			(layers "B.Cu" "B.Mask" "B.Paste")
			(net "FM_UARTSW_LSB_N")
		)
		(pad "7" smd rect
			(at -3.048 0.499872)
			(size 1.524 0.254)
			(layers "B.Cu" "B.Mask" "B.Paste")
			(net "UART_MUX_IN_R")
		)
		(pad "8" smd rect
			(at -3.048 0)
			(size 1.524 0.254)
			(layers "B.Cu" "B.Mask" "B.Paste")
			(net "P3V3_STBY")
		)
	)
	(footprint ""
		(layer "B.Cu")
		(at 422.3004 -13.335)
		(property "Reference" "R2T5"
			(at 0 0 0)
			(layer "B.SilkS")
			(hide yes)
			(effects
				(font
					(size 1.27 1.27)
				)
				(justify mirror)
			)
		)
		(property "Value" ""
			(at 0 0 0)
			(layer "B.Fab")
			(effects
				(font
					(size 1.27 1.27)
				)
				(justify mirror)
			)
		)
		(duplicate_pad_numbers_are_jumpers no)
		(fp_poly
			(pts
				(xy 0.2794 -0.1016) (xy -0.2794 -0.1016) (xy -0.2794 0.9906) (xy 0.2794 0.9906)
			)
			(stroke
				(width 0)
				(type default)
			)
			(fill no)
			(layer "B.CrtYd")
		)
		(fp_line
			(start -0.2794 -0.1016)
			(end 0.2794 -0.1016)
			(stroke
				(width 0.1)
				(type default)
			)
			(layer "B.Fab")
		)
		(fp_line
			(start -0.2794 0.9906)
			(end -0.2794 -0.1016)
			(stroke
				(width 0.1)
				(type default)
			)
			(layer "B.Fab")
		)
		(fp_line
			(start 0.2794 -0.1016)
			(end 0.2794 0.9906)
			(stroke
				(width 0.1)
				(type default)
			)
			(layer "B.Fab")
		)
		(fp_line
			(start 0.2794 0.9906)
			(end -0.2794 0.9906)
			(stroke
				(width 0.1)
				(type default)
			)
			(layer "B.Fab")
		)
		(pad "1" smd rect
			(at 0 0 180)
			(size 0.508 0.508)
			(layers "B.Cu" "B.Mask" "B.Paste")
			(net "P3V3_STBY")
		)
		(pad "2" smd rect
			(at 0 0.889 180)
			(size 0.508 0.508)
			(layers "B.Cu" "B.Mask" "B.Paste")
			(net "H_CPU0_FAST_WAKE")
		)
		(zone
			(layer "B.Cu")
			(hatch none 0.5)
			(connect_pads
				(clearance 0)
			)
			(min_thickness 0.25)
			(keepout
				(tracks allowed)
				(vias not_allowed)
				(pads allowed)
				(copperpour not_allowed)
				(footprints allowed)
			)
			(placement
				(enabled no)
				(sheetname "")
			)
			(fill
				(thermal_gap 0.5)
				(thermal_bridge_width 0.5)
				(island_removal_mode 0)
			)
			(polygon
				(pts
					(xy 422.5544 -13.081) (xy 422.0464 -13.081) (xy 422.0464 -12.7) (xy 422.5544 -12.7)
				)
			)
		)
		(zone
			(layer "B.Cu")
			(hatch none 0.5)
			(connect_pads
				(clearance 0)
			)
			(min_thickness 0.25)
			(keepout
				(tracks not_allowed)
				(vias allowed)
				(pads allowed)
				(copperpour not_allowed)
				(footprints allowed)
			)
			(placement
				(enabled no)
				(sheetname "")
			)
			(fill
				(thermal_gap 0.5)
				(thermal_bridge_width 0.5)
				(island_removal_mode 0)
			)
			(polygon
				(pts
					(xy 422.5544 -12.7) (xy 422.0464 -12.7) (xy 422.0464 -13.081) (xy 422.5544 -13.081)
				)
			)
		)
	)
	(footprint ""
		(layer "B.Cu")
		(at 411.5435 -33.401 -90)
		(property "Reference" "C25W48"
			(at 0.8382 -0.67818 270)
			(unlocked yes)
			(layer "B.SilkS")
			(effects
				(font
					(size 0.4064 0.254)
					(thickness 0.1524)
				)
				(justify left mirror)
			)
		)
		(property "Value" ""
			(at 0 0 90)
			(layer "B.Fab")
			(effects
				(font
					(size 1.27 1.27)
				)
				(justify mirror)
			)
		)
		(duplicate_pad_numbers_are_jumpers no)
		(fp_poly
			(pts
				(xy -0.3048 -0.1016) (xy -0.3048 0.9906) (xy 0.3048 0.9906) (xy 0.3048 -0.1016)
			)
			(stroke
				(width 0)
				(type default)
			)
			(fill no)
			(layer "B.CrtYd")
		)
		(fp_line
			(start -0.3048 0.9906)
			(end -0.3048 -0.1016)
			(stroke
				(width 0.1)
				(type default)
			)
			(layer "B.Fab")
		)
		(fp_line
			(start 0.3048 0.9906)
			(end -0.3048 0.9906)
			(stroke
				(width 0.1)
				(type default)
			)
			(layer "B.Fab")
		)
		(fp_line
			(start -0.3048 -0.1016)
			(end 0.3048 -0.1016)
			(stroke
				(width 0.1)
				(type default)
			)
			(layer "B.Fab")
		)
		(fp_line
			(start 0.3048 -0.1016)
			(end 0.3048 0.9906)
			(stroke
				(width 0.1)
				(type default)
			)
			(layer "B.Fab")
		)
		(pad "1" smd rect
			(at 0 0 90)
			(size 0.508 0.508)
			(layers "B.Cu" "B.Mask" "B.Paste")
			(net "P3V3_STBY")
		)
		(pad "2" smd rect
			(at 0 0.889 90)
			(size 0.508 0.508)
			(layers "B.Cu" "B.Mask" "B.Paste")
			(net "GND")
		)
		(zone
			(layer "B.Cu")
			(hatch none 0.5)
			(connect_pads
				(clearance 0)
			)
			(min_thickness 0.25)
			(keepout
				(tracks not_allowed)
				(vias allowed)
				(pads allowed)
				(copperpour not_allowed)
				(footprints allowed)
			)
			(placement
				(enabled no)
				(sheetname "")
			)
			(fill
				(thermal_gap 0.5)
				(thermal_bridge_width 0.5)
				(island_removal_mode 0)
			)
			(polygon
				(pts
					(xy 410.9085 -33.147) (xy 410.9085 -33.655) (xy 411.2895 -33.655) (xy 411.2895 -33.147)
				)
			)
		)
		(zone
			(layer "B.Cu")
			(hatch none 0.5)
			(connect_pads
				(clearance 0)
			)
			(min_thickness 0.25)
			(keepout
				(tracks allowed)
				(vias not_allowed)
				(pads allowed)
				(copperpour not_allowed)
				(footprints allowed)
			)
			(placement
				(enabled no)
				(sheetname "")
			)
			(fill
				(thermal_gap 0.5)
				(thermal_bridge_width 0.5)
				(island_removal_mode 0)
			)
			(polygon
				(pts
					(xy 411.2895 -33.147) (xy 411.2895 -33.655) (xy 410.9085 -33.655) (xy 410.9085 -33.147)
				)
			)
		)
	)
	(footprint ""
		(layer "B.Cu")
		(at 482.512116 -142.485872 -90)
		(property "Reference" "R6W4"
			(at 0.8382 -0.67818 270)
			(unlocked yes)
			(layer "B.SilkS")
			(effects
				(font
					(size 0.4064 0.254)
					(thickness 0.1524)
				)
				(justify left mirror)
			)
		)
		(property "Value" ""
			(at 0 0 90)
			(layer "B.Fab")
			(effects
				(font
					(size 1.27 1.27)
				)
				(justify mirror)
			)
		)
		(duplicate_pad_numbers_are_jumpers no)
		(fp_poly
			(pts
				(xy 0.2794 -0.1016) (xy -0.2794 -0.1016) (xy -0.2794 0.9906) (xy 0.2794 0.9906)
			)
			(stroke
				(width 0)
				(type default)
			)
			(fill no)
			(layer "B.CrtYd")
		)
		(fp_line
			(start -0.2794 0.9906)
			(end -0.2794 -0.1016)
			(stroke
				(width 0.1)
				(type default)
			)
			(layer "B.Fab")
		)
		(fp_line
			(start 0.2794 0.9906)
			(end -0.2794 0.9906)
			(stroke
				(width 0.1)
				(type default)
			)
			(layer "B.Fab")
		)
		(fp_line
			(start -0.2794 -0.1016)
			(end 0.2794 -0.1016)
			(stroke
				(width 0.1)
				(type default)
			)
			(layer "B.Fab")
		)
		(fp_line
			(start 0.2794 -0.1016)
			(end 0.2794 0.9906)
			(stroke
				(width 0.1)
				(type default)
			)
			(layer "B.Fab")
		)
		(pad "1" smd rect
			(at 0 0 90)
			(size 0.508 0.508)
			(layers "B.Cu" "B.Mask" "B.Paste")
			(net "P3V3_STBY")
		)
		(pad "2" smd rect
			(at 0 0.889 90)
			(size 0.508 0.508)
			(layers "B.Cu" "B.Mask" "B.Paste")
			(net "PCA9555_A2")
		)
		(zone
			(layer "B.Cu")
			(hatch none 0.5)
			(connect_pads
				(clearance 0)
			)
			(min_thickness 0.25)
			(keepout
				(tracks not_allowed)
				(vias allowed)
				(pads allowed)
				(copperpour not_allowed)
				(footprints allowed)
			)
			(placement
				(enabled no)
				(sheetname "")
			)
			(fill
				(thermal_gap 0.5)
				(thermal_bridge_width 0.5)
				(island_removal_mode 0)
			)
			(polygon
				(pts
					(xy 481.877116 -142.231872) (xy 481.877116 -142.739872) (xy 482.258116 -142.739872) (xy 482.258116 -142.231872)
				)
			)
		)
		(zone
			(layer "B.Cu")
			(hatch none 0.5)
			(connect_pads
				(clearance 0)
			)
			(min_thickness 0.25)
			(keepout
				(tracks allowed)
				(vias not_allowed)
				(pads allowed)
				(copperpour not_allowed)
				(footprints allowed)
			)
			(placement
				(enabled no)
				(sheetname "")
			)
			(fill
				(thermal_gap 0.5)
				(thermal_bridge_width 0.5)
				(island_removal_mode 0)
			)
			(polygon
				(pts
					(xy 482.258116 -142.231872) (xy 482.258116 -142.739872) (xy 481.877116 -142.739872) (xy 481.877116 -142.231872)
				)
			)
		)
	)
	(footprint ""
		(layer "B.Cu")
		(at 418.719 -31.8135 180)
		(property "Reference" "C25W54"
			(at 0.8382 -0.67818 180)
			(unlocked yes)
			(layer "B.SilkS")
			(effects
				(font
					(size 0.4064 0.254)
					(thickness 0.1524)
				)
				(justify left mirror)
			)
		)
		(property "Value" ""
			(at 0 0 0)
			(layer "B.Fab")
			(effects
				(font
					(size 1.27 1.27)
				)
				(justify mirror)
			)
		)
		(duplicate_pad_numbers_are_jumpers no)
		(fp_poly
			(pts
				(xy -0.3048 -0.1016) (xy -0.3048 0.9906) (xy 0.3048 0.9906) (xy 0.3048 -0.1016)
			)
			(stroke
				(width 0)
				(type default)
			)
			(fill no)
			(layer "B.CrtYd")
		)
		(fp_line
			(start 0.3048 0.9906)
			(end -0.3048 0.9906)
			(stroke
				(width 0.1)
				(type default)
			)
			(layer "B.Fab")
		)
		(fp_line
			(start 0.3048 -0.1016)
			(end 0.3048 0.9906)
			(stroke
				(width 0.1)
				(type default)
			)
			(layer "B.Fab")
		)
		(fp_line
			(start -0.3048 0.9906)
			(end -0.3048 -0.1016)
			(stroke
				(width 0.1)
				(type default)
			)
			(layer "B.Fab")
		)
		(fp_line
			(start -0.3048 -0.1016)
			(end 0.3048 -0.1016)
			(stroke
				(width 0.1)
				(type default)
			)
			(layer "B.Fab")
		)
		(pad "1" smd rect
			(at 0 0)
			(size 0.508 0.508)
			(layers "B.Cu" "B.Mask" "B.Paste")
			(net "P1V2_AUX_BMC")
		)
		(pad "2" smd rect
			(at 0 0.889)
			(size 0.508 0.508)
			(layers "B.Cu" "B.Mask" "B.Paste")
			(net "GND")
		)
		(zone
			(layer "B.Cu")
			(hatch none 0.5)
			(connect_pads
				(clearance 0)
			)
			(min_thickness 0.25)
			(keepout
				(tracks not_allowed)
				(vias allowed)
				(pads allowed)
				(copperpour not_allowed)
				(footprints allowed)
			)
			(placement
				(enabled no)
				(sheetname "")
			)
			(fill
				(thermal_gap 0.5)
				(thermal_bridge_width 0.5)
				(island_removal_mode 0)
			)
			(polygon
				(pts
					(xy 418.465 -32.4485) (xy 418.973 -32.4485) (xy 418.973 -32.0675) (xy 418.465 -32.0675)
				)
			)
		)
		(zone
			(layer "B.Cu")
			(hatch none 0.5)
			(connect_pads
				(clearance 0)
			)
			(min_thickness 0.25)
			(keepout
				(tracks allowed)
				(vias not_allowed)
				(pads allowed)
				(copperpour not_allowed)
				(footprints allowed)
			)
			(placement
				(enabled no)
				(sheetname "")
			)
			(fill
				(thermal_gap 0.5)
				(thermal_bridge_width 0.5)
				(island_removal_mode 0)
			)
			(polygon
				(pts
					(xy 418.465 -32.0675) (xy 418.973 -32.0675) (xy 418.973 -32.4485) (xy 418.465 -32.4485)
				)
			)
		)
	)
	(footprint ""
		(layer "B.Cu")
		(at 394.208 -63.627 90)
		(property "Reference" "C2T8"
			(at 0 0 90)
			(layer "B.SilkS")
			(hide yes)
			(effects
				(font
					(size 1.27 1.27)
				)
				(justify mirror)
			)
		)
		(property "Value" ""
			(at 0 0 90)
			(layer "B.Fab")
			(effects
				(font
					(size 1.27 1.27)
				)
				(justify mirror)
			)
		)
		(duplicate_pad_numbers_are_jumpers no)
		(fp_poly
			(pts
				(xy -0.3048 -0.1016) (xy -0.3048 0.9906) (xy 0.3048 0.9906) (xy 0.3048 -0.1016)
			)
			(stroke
				(width 0)
				(type default)
			)
			(fill no)
			(layer "B.CrtYd")
		)
		(fp_line
			(start 0.3048 -0.1016)
			(end 0.3048 0.9906)
			(stroke
				(width 0.1)
				(type default)
			)
			(layer "B.Fab")
		)
		(fp_line
			(start -0.3048 -0.1016)
			(end 0.3048 -0.1016)
			(stroke
				(width 0.1)
				(type default)
			)
			(layer "B.Fab")
		)
		(fp_line
			(start 0.3048 0.9906)
			(end -0.3048 0.9906)
			(stroke
				(width 0.1)
				(type default)
			)
			(layer "B.Fab")
		)
		(fp_line
			(start -0.3048 0.9906)
			(end -0.3048 -0.1016)
			(stroke
				(width 0.1)
				(type default)
			)
			(layer "B.Fab")
		)
		(pad "1" smd rect
			(at 0 0 270)
			(size 0.508 0.508)
			(layers "B.Cu" "B.Mask" "B.Paste")
			(net "P3V3_STBY")
		)
		(pad "2" smd rect
			(at 0 0.889 270)
			(size 0.508 0.508)
			(layers "B.Cu" "B.Mask" "B.Paste")
			(net "GND")
		)
		(zone
			(layer "B.Cu")
			(hatch none 0.5)
			(connect_pads
				(clearance 0)
			)
			(min_thickness 0.25)
			(keepout
				(tracks allowed)
				(vias not_allowed)
				(pads allowed)
				(copperpour not_allowed)
				(footprints allowed)
			)
			(placement
				(enabled no)
				(sheetname "")
			)
			(fill
				(thermal_gap 0.5)
				(thermal_bridge_width 0.5)
				(island_removal_mode 0)
			)
			(polygon
				(pts
					(xy 394.462 -63.881) (xy 394.462 -63.373) (xy 394.843 -63.373) (xy 394.843 -63.881)
				)
			)
		)
		(zone
			(layer "B.Cu")
			(hatch none 0.5)
			(connect_pads
				(clearance 0)
			)
			(min_thickness 0.25)
			(keepout
				(tracks not_allowed)
				(vias allowed)
				(pads allowed)
				(copperpour not_allowed)
				(footprints allowed)
			)
			(placement
				(enabled no)
				(sheetname "")
			)
			(fill
				(thermal_gap 0.5)
				(thermal_bridge_width 0.5)
				(island_removal_mode 0)
			)
			(polygon
				(pts
					(xy 394.843 -63.881) (xy 394.843 -63.373) (xy 394.462 -63.373) (xy 394.462 -63.881)
				)
			)
		)
	)
	(footprint ""
		(layer "B.Cu")
		(at 348.1578 -94.869 -90)
		(property "Reference" "C3N36"
			(at 0 0 90)
			(layer "B.SilkS")
			(hide yes)
			(effects
				(font
					(size 1.27 1.27)
				)
				(justify mirror)
			)
		)
		(property "Value" ""
			(at 0 0 90)
			(layer "B.Fab")
			(effects
				(font
					(size 1.27 1.27)
				)
				(justify mirror)
			)
		)
		(duplicate_pad_numbers_are_jumpers no)
		(fp_poly
			(pts
				(xy 0.7239 -0.2159) (xy -0.7239 -0.2159) (xy -0.7239 1.9939) (xy 0.7239 1.9939)
			)
			(stroke
				(width 0)
				(type default)
			)
			(fill no)
			(layer "B.CrtYd")
		)
		(fp_line
			(start -0.7239 1.9939)
			(end -0.7239 -0.2159)
			(stroke
				(width 0.1)
				(type default)
			)
			(layer "B.Fab")
		)
		(fp_line
			(start 0.7239 1.9939)
			(end -0.7239 1.9939)
			(stroke
				(width 0.1)
				(type default)
			)
			(layer "B.Fab")
		)
		(fp_line
			(start -0.7239 -0.2159)
			(end 0.7239 -0.2159)
			(stroke
				(width 0.1)
				(type default)
			)
			(layer "B.Fab")
		)
		(fp_line
			(start 0.7239 -0.2159)
			(end 0.7239 1.9939)
			(stroke
				(width 0.1)
				(type default)
			)
			(layer "B.Fab")
		)
		(pad "1" smd rect
			(at 0 0 90)
			(size 1.27 1.016)
			(layers "B.Cu" "B.Mask" "B.Paste")
			(net "VR_FET_SW_P12V_STBY_PVCCIO_CPU0")
		)
		(pad "2" smd rect
			(at 0 1.778 90)
			(size 1.27 1.016)
			(layers "B.Cu" "B.Mask" "B.Paste")
			(net "GND")
		)
		(zone
			(layer "B.Cu")
			(hatch none 0.5)
			(connect_pads
				(clearance 0)
			)
			(min_thickness 0.25)
			(keepout
				(tracks not_allowed)
				(vias allowed)
				(pads allowed)
				(copperpour not_allowed)
				(footprints allowed)
			)
			(placement
				(enabled no)
				(sheetname "")
			)
			(fill
				(thermal_gap 0.5)
				(thermal_bridge_width 0.5)
				(island_removal_mode 0)
			)
			(polygon
				(pts
					(xy 347.6498 -94.234) (xy 347.6498 -95.504) (xy 346.8878 -95.504) (xy 346.8878 -94.234)
				)
			)
		)
	)
	(footprint ""
		(layer "B.Cu")
		(at 396.240508 -29.845 90)
		(property "Reference" "R8F26"
			(at 0 0 90)
			(layer "B.SilkS")
			(hide yes)
			(effects
				(font
					(size 1.27 1.27)
				)
				(justify mirror)
			)
		)
		(property "Value" ""
			(at 0 0 90)
			(layer "B.Fab")
			(effects
				(font
					(size 1.27 1.27)
				)
				(justify mirror)
			)
		)
		(duplicate_pad_numbers_are_jumpers no)
		(fp_poly
			(pts
				(xy 0.2794 -0.101854) (xy -0.2794 -0.101854) (xy -0.2794 0.990346) (xy 0.2794 0.990346)
			)
			(stroke
				(width 0)
				(type default)
			)
			(fill no)
			(layer "B.CrtYd")
		)
		(fp_line
			(start 0.2794 -0.101854)
			(end 0.2794 0.990346)
			(stroke
				(width 0.1)
				(type default)
			)
			(layer "B.Fab")
		)
		(fp_line
			(start -0.2794 -0.101854)
			(end 0.2794 -0.101854)
			(stroke
				(width 0.1)
				(type default)
			)
			(layer "B.Fab")
		)
		(fp_line
			(start 0.2794 0.990346)
			(end -0.2794 0.990346)
			(stroke
				(width 0.1)
				(type default)
			)
			(layer "B.Fab")
		)
		(fp_line
			(start -0.2794 0.990346)
			(end -0.2794 -0.101854)
			(stroke
				(width 0.1)
				(type default)
			)
			(layer "B.Fab")
		)
		(pad "1" smd rect
			(at 0 0 270)
			(size 0.508 0.508)
			(layers "B.Cu" "B.Mask" "B.Paste")
			(net "P3V3_STBY")
		)
		(pad "2" smd rect
			(at 0 0.889 270)
			(size 0.508 0.508)
			(layers "B.Cu" "B.Mask" "B.Paste")
			(net "FM_PCH_PWRBTN_R_N")
		)
	)
	(footprint ""
		(layer "B.Cu")
		(at 376.9614 -45.1358)
		(property "Reference" "R2W2"
			(at 0.8382 -0.67818 0)
			(unlocked yes)
			(layer "B.SilkS")
			(effects
				(font
					(size 0.4064 0.254)
					(thickness 0.1524)
				)
				(justify left mirror)
			)
		)
		(property "Value" ""
			(at 0 0 0)
			(layer "B.Fab")
			(effects
				(font
					(size 1.27 1.27)
				)
				(justify mirror)
			)
		)
		(duplicate_pad_numbers_are_jumpers no)
		(fp_poly
			(pts
				(xy 0.2794 -0.1016) (xy -0.2794 -0.1016) (xy -0.2794 0.9906) (xy 0.2794 0.9906)
			)
			(stroke
				(width 0)
				(type default)
			)
			(fill no)
			(layer "B.CrtYd")
		)
		(fp_line
			(start -0.2794 -0.1016)
			(end 0.2794 -0.1016)
			(stroke
				(width 0.1)
				(type default)
			)
			(layer "B.Fab")
		)
		(fp_line
			(start -0.2794 0.9906)
			(end -0.2794 -0.1016)
			(stroke
				(width 0.1)
				(type default)
			)
			(layer "B.Fab")
		)
		(fp_line
			(start 0.2794 -0.1016)
			(end 0.2794 0.9906)
			(stroke
				(width 0.1)
				(type default)
			)
			(layer "B.Fab")
		)
		(fp_line
			(start 0.2794 0.9906)
			(end -0.2794 0.9906)
			(stroke
				(width 0.1)
				(type default)
			)
			(layer "B.Fab")
		)
		(pad "1" smd rect
			(at 0 0 180)
			(size 0.508 0.508)
			(layers "B.Cu" "B.Mask" "B.Paste")
			(net "PVCCIO_CPU0")
		)
		(pad "2" smd rect
			(at 0 0.889 180)
			(size 0.508 0.508)
			(layers "B.Cu" "B.Mask" "B.Paste")
			(net "P0V7_GTL2104_5_VREF")
		)
		(zone
			(layer "B.Cu")
			(hatch none 0.5)
			(connect_pads
				(clearance 0)
			)
			(min_thickness 0.25)
			(keepout
				(tracks allowed)
				(vias not_allowed)
				(pads allowed)
				(copperpour not_allowed)
				(footprints allowed)
			)
			(placement
				(enabled no)
				(sheetname "")
			)
			(fill
				(thermal_gap 0.5)
				(thermal_bridge_width 0.5)
				(island_removal_mode 0)
			)
			(polygon
				(pts
					(xy 377.2154 -44.8818) (xy 376.7074 -44.8818) (xy 376.7074 -44.5008) (xy 377.2154 -44.5008)
				)
			)
		)
		(zone
			(layer "B.Cu")
			(hatch none 0.5)
			(connect_pads
				(clearance 0)
			)
			(min_thickness 0.25)
			(keepout
				(tracks not_allowed)
				(vias allowed)
				(pads allowed)
				(copperpour not_allowed)
				(footprints allowed)
			)
			(placement
				(enabled no)
				(sheetname "")
			)
			(fill
				(thermal_gap 0.5)
				(thermal_bridge_width 0.5)
				(island_removal_mode 0)
			)
			(polygon
				(pts
					(xy 377.2154 -44.5008) (xy 376.7074 -44.5008) (xy 376.7074 -44.8818) (xy 377.2154 -44.8818)
				)
			)
		)
	)
	(footprint ""
		(layer "B.Cu")
		(at 395.351 -22.86 -90)
		(property "Reference" "VR32W1"
			(at 0 0 90)
			(layer "B.SilkS")
			(hide yes)
			(effects
				(font
					(size 1.27 1.27)
				)
				(justify mirror)
			)
		)
		(property "Value" "*"
			(at 0 -4.33705 270)
			(unlocked yes)
			(layer "B.Fab")
			(hide yes)
			(effects
				(font
					(size 0.889 0.889)
					(thickness 0.1524)
				)
				(justify mirror)
			)
		)
		(property "Device Type" "LMV431AIMFX-GP_DISCRET-G5-LMV4A"
			(at 0 -5.73405 270)
			(unlocked yes)
			(layer "B.Fab")
			(hide yes)
			(effects
				(font
					(size 0.889 0.889)
					(thickness 0.1524)
				)
				(justify mirror)
			)
		)
		(duplicate_pad_numbers_are_jumpers no)
		(fp_line
			(start -1.7018 0.254)
			(end -1.7018 -0.254)
			(stroke
				(width 0.1524)
				(type default)
			)
			(layer "B.SilkS")
		)
		(fp_line
			(start 1.7018 0.254)
			(end -1.7018 0.254)
			(stroke
				(width 0.1524)
				(type default)
			)
			(layer "B.SilkS")
		)
		(fp_line
			(start -1.7018 -0.254)
			(end 1.7018 -0.254)
			(stroke
				(width 0.1524)
				(type default)
			)
			(layer "B.SilkS")
		)
		(fp_line
			(start 1.7018 -0.254)
			(end 1.7018 0.254)
			(stroke
				(width 0.1524)
				(type default)
			)
			(layer "B.SilkS")
		)
		(fp_rect
			(start 1.778 1.9812)
			(end -1.778 -1.9812)
			(stroke
				(width 0)
				(type default)
			)
			(fill no)
			(layer "B.CrtYd")
		)
		(fp_rect
			(start 1.778 1.9812)
			(end -1.778 -1.9812)
			(stroke
				(width 0)
				(type default)
			)
			(fill no)
			(layer "B.Fab")
		)
		(pad "1" smd custom
			(at 1.016 1.1176 90)
			(size 0.254 0.254)
			(layers "B.Cu" "B.Mask" "B.Paste")
			(net "VREF_LMV431_1V42")
			(options
				(clearance outline)
				(anchor circle)
			)
			(primitives
				(gr_poly
					(pts
						(arc
							(start -0.508 0.4064)
							(mid -0.448484 0.550084)
							(end -0.3048 0.6096)
						)
						(arc
							(start 0.3048 0.6096)
							(mid 0.448484 0.550084)
							(end 0.508 0.4064)
						)
						(arc
							(start 0.508 -0.4064)
							(mid 0.448484 -0.550084)
							(end 0.3048 -0.6096)
						)
						(arc
							(start -0.3048 -0.6096)
							(mid -0.448484 -0.550084)
							(end -0.508 -0.4064)
						)
					)
					(width 0)
					(fill yes)
				)
			)
		)
		(pad "2" smd custom
			(at -1.016 1.1176 90)
			(size 0.254 0.254)
			(layers "B.Cu" "B.Mask" "B.Paste")
			(net "P1V8_M2")
			(options
				(clearance outline)
				(anchor circle)
			)
			(primitives
				(gr_poly
					(pts
						(arc
							(start -0.508 0.4064)
							(mid -0.448484 0.550084)
							(end -0.3048 0.6096)
						)
						(arc
							(start 0.3048 0.6096)
							(mid 0.448484 0.550084)
							(end 0.508 0.4064)
						)
						(arc
							(start 0.508 -0.4064)
							(mid 0.448484 -0.550084)
							(end 0.3048 -0.6096)
						)
						(arc
							(start -0.3048 -0.6096)
							(mid -0.448484 -0.550084)
							(end -0.508 -0.4064)
						)
					)
					(width 0)
					(fill yes)
				)
			)
		)
		(pad "3" smd custom
			(at 0 -1.1176 90)
			(size 0.254 0.254)
			(layers "B.Cu" "B.Mask" "B.Paste")
			(net "GND")
			(options
				(clearance outline)
				(anchor circle)
			)
			(primitives
				(gr_poly
					(pts
						(arc
							(start -0.508 0.4064)
							(mid -0.448484 0.550084)
							(end -0.3048 0.6096)
						)
						(arc
							(start 0.3048 0.6096)
							(mid 0.448484 0.550084)
							(end 0.508 0.4064)
						)
						(arc
							(start 0.508 -0.4064)
							(mid 0.448484 -0.550084)
							(end 0.3048 -0.6096)
						)
						(arc
							(start -0.3048 -0.6096)
							(mid -0.448484 -0.550084)
							(end -0.508 -0.4064)
						)
					)
					(width 0)
					(fill yes)
				)
			)
		)
	)
	(footprint ""
		(layer "B.Cu")
		(at 18.0594 -144.2974 -90)
		(property "Reference" "C9L9"
			(at -1.97993 9.1694 0)
			(unlocked yes)
			(layer "B.SilkS")
			(effects
				(font
					(size 0.7874 0.5842)
					(thickness 0.1524)
				)
				(justify mirror)
			)
		)
		(property "Value" ""
			(at 0 0 90)
			(layer "B.Fab")
			(effects
				(font
					(size 1.27 1.27)
				)
				(justify mirror)
			)
		)
		(duplicate_pad_numbers_are_jumpers no)
		(fp_line
			(start -2.286 7.366)
			(end -1.600708 7.366)
			(stroke
				(width 0.1524)
				(type default)
			)
			(layer "B.SilkS")
		)
		(fp_line
			(start -2.286 7.366)
			(end -2.286 1.63195)
			(stroke
				(width 0.1524)
				(type default)
			)
			(layer "B.SilkS")
		)
		(fp_line
			(start 2.286 7.366)
			(end 1.60147 7.366)
			(stroke
				(width 0.1524)
				(type default)
			)
			(layer "B.SilkS")
		)
		(fp_line
			(start 2.286 7.366)
			(end 2.286 1.632712)
			(stroke
				(width 0.1524)
				(type default)
			)
			(layer "B.SilkS")
		)
		(fp_line
			(start -2.504948 1.633728)
			(end -1.6002 1.633728)
			(stroke
				(width 0.1524)
				(type default)
			)
			(layer "B.SilkS")
		)
		(fp_line
			(start 2.563114 1.633728)
			(end 1.6002 1.633728)
			(stroke
				(width 0.1524)
				(type default)
			)
			(layer "B.SilkS")
		)
		(fp_line
			(start -2.504948 -1.616456)
			(end -2.504948 1.633728)
			(stroke
				(width 0.1524)
				(type default)
			)
			(layer "B.SilkS")
		)
		(fp_line
			(start -1.6002 -1.616456)
			(end -2.504948 -1.616456)
			(stroke
				(width 0.1524)
				(type default)
			)
			(layer "B.SilkS")
		)
		(fp_line
			(start 1.6002 -1.616456)
			(end 2.563114 -1.616456)
			(stroke
				(width 0.1524)
				(type default)
			)
			(layer "B.SilkS")
		)
		(fp_line
			(start 2.563114 -1.616456)
			(end 2.563114 1.633728)
			(stroke
				(width 0.1524)
				(type default)
			)
			(layer "B.SilkS")
		)
		(fp_rect
			(start 2.286 -0.254)
			(end -2.286 7.366)
			(stroke
				(width 0)
				(type default)
			)
			(fill no)
			(layer "B.CrtYd")
		)
		(fp_line
			(start -2.286 7.366)
			(end 2.286 7.366)
			(stroke
				(width 0.1)
				(type default)
			)
			(layer "B.Fab")
		)
		(fp_line
			(start 2.286 7.366)
			(end 2.286 -0.254)
			(stroke
				(width 0.1)
				(type default)
			)
			(layer "B.Fab")
		)
		(fp_line
			(start -2.286 -0.254)
			(end -2.286 7.366)
			(stroke
				(width 0.1)
				(type default)
			)
			(layer "B.Fab")
		)
		(fp_line
			(start 2.286 -0.254)
			(end -2.286 -0.254)
			(stroke
				(width 0.1)
				(type default)
			)
			(layer "B.Fab")
		)
		(pad "1" smd rect
			(at 0 0 90)
			(size 2.54 3.048)
			(layers "B.Cu" "B.Mask" "B.Paste")
			(net "PVDDQ_KLM")
		)
		(pad "2" smd rect
			(at 0 7.112 90)
			(size 2.54 3.048)
			(layers "B.Cu" "B.Mask" "B.Paste")
			(net "GND")
		)
	)
	(footprint ""
		(layer "B.Cu")
		(at 450.215 -150.1394 -90)
		(property "Reference" "R25W176"
			(at 0.8382 -0.67818 270)
			(unlocked yes)
			(layer "B.SilkS")
			(effects
				(font
					(size 0.4064 0.254)
					(thickness 0.1524)
				)
				(justify left mirror)
			)
		)
		(property "Value" ""
			(at 0 0 90)
			(layer "B.Fab")
			(effects
				(font
					(size 1.27 1.27)
				)
				(justify mirror)
			)
		)
		(duplicate_pad_numbers_are_jumpers no)
		(fp_poly
			(pts
				(xy 0.2794 -0.1016) (xy -0.2794 -0.1016) (xy -0.2794 0.9906) (xy 0.2794 0.9906)
			)
			(stroke
				(width 0)
				(type default)
			)
			(fill no)
			(layer "B.CrtYd")
		)
		(fp_line
			(start -0.2794 0.9906)
			(end -0.2794 -0.1016)
			(stroke
				(width 0.1)
				(type default)
			)
			(layer "B.Fab")
		)
		(fp_line
			(start 0.2794 0.9906)
			(end -0.2794 0.9906)
			(stroke
				(width 0.1)
				(type default)
			)
			(layer "B.Fab")
		)
		(fp_line
			(start -0.2794 -0.1016)
			(end 0.2794 -0.1016)
			(stroke
				(width 0.1)
				(type default)
			)
			(layer "B.Fab")
		)
		(fp_line
			(start 0.2794 -0.1016)
			(end 0.2794 0.9906)
			(stroke
				(width 0.1)
				(type default)
			)
			(layer "B.Fab")
		)
		(pad "1" smd rect
			(at 0 0 90)
			(size 0.508 0.508)
			(layers "B.Cu" "B.Mask" "B.Paste")
			(net "PD_GTL2014_6_B2")
		)
		(pad "2" smd rect
			(at 0 0.889 90)
			(size 0.508 0.508)
			(layers "B.Cu" "B.Mask" "B.Paste")
			(net "GND")
		)
		(zone
			(layer "B.Cu")
			(hatch none 0.5)
			(connect_pads
				(clearance 0)
			)
			(min_thickness 0.25)
			(keepout
				(tracks not_allowed)
				(vias allowed)
				(pads allowed)
				(copperpour not_allowed)
				(footprints allowed)
			)
			(placement
				(enabled no)
				(sheetname "")
			)
			(fill
				(thermal_gap 0.5)
				(thermal_bridge_width 0.5)
				(island_removal_mode 0)
			)
			(polygon
				(pts
					(xy 449.58 -149.8854) (xy 449.58 -150.3934) (xy 449.961 -150.3934) (xy 449.961 -149.8854)
				)
			)
		)
		(zone
			(layer "B.Cu")
			(hatch none 0.5)
			(connect_pads
				(clearance 0)
			)
			(min_thickness 0.25)
			(keepout
				(tracks allowed)
				(vias not_allowed)
				(pads allowed)
				(copperpour not_allowed)
				(footprints allowed)
			)
			(placement
				(enabled no)
				(sheetname "")
			)
			(fill
				(thermal_gap 0.5)
				(thermal_bridge_width 0.5)
				(island_removal_mode 0)
			)
			(polygon
				(pts
					(xy 449.961 -149.8854) (xy 449.961 -150.3934) (xy 449.58 -150.3934) (xy 449.58 -149.8854)
				)
			)
		)
	)
	(footprint ""
		(layer "B.Cu")
		(at 492.3536 -133.223 90)
		(property "Reference" "U6W4"
			(at 0.14986 2.621788 90)
			(unlocked yes)
			(layer "B.SilkS")
			(effects
				(font
					(size 1.27 0.964946)
					(thickness 0.000001)
				)
				(justify left mirror)
			)
		)
		(property "Value" ""
			(at 0 0 90)
			(layer "B.Fab")
			(effects
				(font
					(size 1.27 1.27)
				)
				(justify mirror)
			)
		)
		(duplicate_pad_numbers_are_jumpers no)
		(fp_circle
			(center 0.4699 -0.8382)
			(end 0.4699 -0.7112)
			(stroke
				(width 0.254)
				(type default)
			)
			(fill no)
			(layer "B.SilkS")
		)
		(fp_poly
			(pts
				(xy -0.21463 -0.450088) (xy -1.56337 -0.450088) (xy -1.56337 1.75006) (xy -0.21463 1.75006)
			)
			(stroke
				(width 0)
				(type default)
			)
			(fill no)
			(layer "B.CrtYd")
		)
		(fp_line
			(start -0.21463 -0.450088)
			(end -1.56337 -0.450088)
			(stroke
				(width 0.1)
				(type default)
			)
			(layer "B.Fab")
		)
		(fp_line
			(start -1.56337 -0.450088)
			(end -1.56337 1.75006)
			(stroke
				(width 0.1)
				(type default)
			)
			(layer "B.Fab")
		)
		(fp_line
			(start -0.21463 1.75006)
			(end -0.21463 -0.450088)
			(stroke
				(width 0.1)
				(type default)
			)
			(layer "B.Fab")
		)
		(fp_line
			(start -1.56337 1.75006)
			(end -0.21463 1.75006)
			(stroke
				(width 0.1)
				(type default)
			)
			(layer "B.Fab")
		)
		(fp_circle
			(center 0.4699 -0.8382)
			(end 0.4699 -0.7112)
			(stroke
				(width 0.254)
				(type default)
			)
			(fill no)
			(layer "B.Fab")
		)
		(pad "1" smd rect
			(at 0 0 270)
			(size 1.016 0.381)
			(layers "B.Cu" "B.Mask" "B.Paste")
			(net "DEBUG_CARD2_PRSNT")
		)
		(pad "2" smd rect
			(at 0 0.649986 270)
			(size 1.016 0.381)
			(layers "B.Cu" "B.Mask" "B.Paste")
			(net "SPA_MID_DBG2_RX")
		)
		(pad "3" smd rect
			(at 0 1.299972 270)
			(size 1.016 0.381)
			(layers "B.Cu" "B.Mask" "B.Paste")
			(net "GND")
		)
		(pad "4" smd rect
			(at -1.778 1.299972 270)
			(size 1.016 0.381)
			(layers "B.Cu" "B.Mask" "B.Paste")
			(net "SPA_MID_DBG2_RX_BUF")
		)
		(pad "5" smd rect
			(at -1.778 0 270)
			(size 1.016 0.381)
			(layers "B.Cu" "B.Mask" "B.Paste")
			(net "P3V3_STBY")
		)
	)
	(footprint ""
		(layer "B.Cu")
		(at 350.9772 -88.269572 90)
		(property "Reference" "R3N31"
			(at 0 0 90)
			(layer "B.SilkS")
			(hide yes)
			(effects
				(font
					(size 1.27 1.27)
				)
				(justify mirror)
			)
		)
		(property "Value" ""
			(at 0 0 90)
			(layer "B.Fab")
			(effects
				(font
					(size 1.27 1.27)
				)
				(justify mirror)
			)
		)
		(duplicate_pad_numbers_are_jumpers no)
		(fp_poly
			(pts
				(xy 0.2794 -0.1016) (xy -0.2794 -0.1016) (xy -0.2794 0.9906) (xy 0.2794 0.9906)
			)
			(stroke
				(width 0)
				(type default)
			)
			(fill no)
			(layer "B.CrtYd")
		)
		(fp_line
			(start 0.2794 -0.1016)
			(end 0.2794 0.9906)
			(stroke
				(width 0.1)
				(type default)
			)
			(layer "B.Fab")
		)
		(fp_line
			(start -0.2794 -0.1016)
			(end 0.2794 -0.1016)
			(stroke
				(width 0.1)
				(type default)
			)
			(layer "B.Fab")
		)
		(fp_line
			(start 0.2794 0.9906)
			(end -0.2794 0.9906)
			(stroke
				(width 0.1)
				(type default)
			)
			(layer "B.Fab")
		)
		(fp_line
			(start -0.2794 0.9906)
			(end -0.2794 -0.1016)
			(stroke
				(width 0.1)
				(type default)
			)
			(layer "B.Fab")
		)
		(pad "1" smd rect
			(at 0 0 270)
			(size 0.508 0.508)
			(layers "B.Cu" "B.Mask" "B.Paste")
			(net "VR_PVCCIO_CPU0_XADDR1")
		)
		(pad "2" smd rect
			(at 0 0.889 270)
			(size 0.508 0.508)
			(layers "B.Cu" "B.Mask" "B.Paste")
			(net "GND")
		)
		(zone
			(layer "B.Cu")
			(hatch none 0.5)
			(connect_pads
				(clearance 0)
			)
			(min_thickness 0.25)
			(keepout
				(tracks allowed)
				(vias not_allowed)
				(pads allowed)
				(copperpour not_allowed)
				(footprints allowed)
			)
			(placement
				(enabled no)
				(sheetname "")
			)
			(fill
				(thermal_gap 0.5)
				(thermal_bridge_width 0.5)
				(island_removal_mode 0)
			)
			(polygon
				(pts
					(xy 351.2312 -88.523572) (xy 351.2312 -88.015572) (xy 351.6122 -88.015572) (xy 351.6122 -88.523572)
				)
			)
		)
		(zone
			(layer "B.Cu")
			(hatch none 0.5)
			(connect_pads
				(clearance 0)
			)
			(min_thickness 0.25)
			(keepout
				(tracks not_allowed)
				(vias allowed)
				(pads allowed)
				(copperpour not_allowed)
				(footprints allowed)
			)
			(placement
				(enabled no)
				(sheetname "")
			)
			(fill
				(thermal_gap 0.5)
				(thermal_bridge_width 0.5)
				(island_removal_mode 0)
			)
			(polygon
				(pts
					(xy 351.6122 -88.523572) (xy 351.6122 -88.015572) (xy 351.2312 -88.015572) (xy 351.2312 -88.523572)
				)
			)
		)
	)
	(footprint ""
		(layer "B.Cu")
		(at 411.861 -7.4295 180)
		(property "Reference" "R8D41"
			(at 0 0 0)
			(layer "B.SilkS")
			(hide yes)
			(effects
				(font
					(size 1.27 1.27)
				)
				(justify mirror)
			)
		)
		(property "Value" ""
			(at 0 0 0)
			(layer "B.Fab")
			(effects
				(font
					(size 1.27 1.27)
				)
				(justify mirror)
			)
		)
		(duplicate_pad_numbers_are_jumpers no)
		(fp_poly
			(pts
				(xy 0.2794 -0.1016) (xy -0.2794 -0.1016) (xy -0.2794 0.9906) (xy 0.2794 0.9906)
			)
			(stroke
				(width 0)
				(type default)
			)
			(fill no)
			(layer "B.CrtYd")
		)
		(fp_line
			(start 0.2794 0.9906)
			(end -0.2794 0.9906)
			(stroke
				(width 0.1)
				(type default)
			)
			(layer "B.Fab")
		)
		(fp_line
			(start 0.2794 -0.1016)
			(end 0.2794 0.9906)
			(stroke
				(width 0.1)
				(type default)
			)
			(layer "B.Fab")
		)
		(fp_line
			(start -0.2794 0.9906)
			(end -0.2794 -0.1016)
			(stroke
				(width 0.1)
				(type default)
			)
			(layer "B.Fab")
		)
		(fp_line
			(start -0.2794 -0.1016)
			(end 0.2794 -0.1016)
			(stroke
				(width 0.1)
				(type default)
			)
			(layer "B.Fab")
		)
		(pad "1" smd rect
			(at 0 0)
			(size 0.508 0.508)
			(layers "B.Cu" "B.Mask" "B.Paste")
			(net "P3V3_STBY")
		)
		(pad "2" smd rect
			(at 0 0.889)
			(size 0.508 0.508)
			(layers "B.Cu" "B.Mask" "B.Paste")
			(net "PWRGD_P12V_MAIN_R")
		)
		(zone
			(layer "B.Cu")
			(hatch none 0.5)
			(connect_pads
				(clearance 0)
			)
			(min_thickness 0.25)
			(keepout
				(tracks not_allowed)
				(vias allowed)
				(pads allowed)
				(copperpour not_allowed)
				(footprints allowed)
			)
			(placement
				(enabled no)
				(sheetname "")
			)
			(fill
				(thermal_gap 0.5)
				(thermal_bridge_width 0.5)
				(island_removal_mode 0)
			)
			(polygon
				(pts
					(xy 411.607 -8.0645) (xy 412.115 -8.0645) (xy 412.115 -7.6835) (xy 411.607 -7.6835)
				)
			)
		)
		(zone
			(layer "B.Cu")
			(hatch none 0.5)
			(connect_pads
				(clearance 0)
			)
			(min_thickness 0.25)
			(keepout
				(tracks allowed)
				(vias not_allowed)
				(pads allowed)
				(copperpour not_allowed)
				(footprints allowed)
			)
			(placement
				(enabled no)
				(sheetname "")
			)
			(fill
				(thermal_gap 0.5)
				(thermal_bridge_width 0.5)
				(island_removal_mode 0)
			)
			(polygon
				(pts
					(xy 411.607 -7.6835) (xy 412.115 -7.6835) (xy 412.115 -8.0645) (xy 411.607 -8.0645)
				)
			)
		)
	)
	(footprint ""
		(layer "B.Cu")
		(at 413.9438 -89.4207 -90)
		(property "Reference" "R3R10"
			(at 0 0 90)
			(layer "B.SilkS")
			(hide yes)
			(effects
				(font
					(size 1.27 1.27)
				)
				(justify mirror)
			)
		)
		(property "Value" ""
			(at 0 0 90)
			(layer "B.Fab")
			(effects
				(font
					(size 1.27 1.27)
				)
				(justify mirror)
			)
		)
		(duplicate_pad_numbers_are_jumpers no)
		(fp_poly
			(pts
				(xy 0.2794 -0.1016) (xy -0.2794 -0.1016) (xy -0.2794 0.9906) (xy 0.2794 0.9906)
			)
			(stroke
				(width 0)
				(type default)
			)
			(fill no)
			(layer "B.CrtYd")
		)
		(fp_line
			(start -0.2794 0.9906)
			(end -0.2794 -0.1016)
			(stroke
				(width 0.1)
				(type default)
			)
			(layer "B.Fab")
		)
		(fp_line
			(start 0.2794 0.9906)
			(end -0.2794 0.9906)
			(stroke
				(width 0.1)
				(type default)
			)
			(layer "B.Fab")
		)
		(fp_line
			(start -0.2794 -0.1016)
			(end 0.2794 -0.1016)
			(stroke
				(width 0.1)
				(type default)
			)
			(layer "B.Fab")
		)
		(fp_line
			(start 0.2794 -0.1016)
			(end 0.2794 0.9906)
			(stroke
				(width 0.1)
				(type default)
			)
			(layer "B.Fab")
		)
		(pad "1" smd rect
			(at 0 0 90)
			(size 0.508 0.508)
			(layers "B.Cu" "B.Mask" "B.Paste")
			(net "P3V3")
		)
		(pad "2" smd rect
			(at 0 0.889 90)
			(size 0.508 0.508)
			(layers "B.Cu" "B.Mask" "B.Paste")
			(net "H_CPU1_MEMGHJ_MEMHOT")
		)
		(zone
			(layer "B.Cu")
			(hatch none 0.5)
			(connect_pads
				(clearance 0)
			)
			(min_thickness 0.25)
			(keepout
				(tracks not_allowed)
				(vias allowed)
				(pads allowed)
				(copperpour not_allowed)
				(footprints allowed)
			)
			(placement
				(enabled no)
				(sheetname "")
			)
			(fill
				(thermal_gap 0.5)
				(thermal_bridge_width 0.5)
				(island_removal_mode 0)
			)
			(polygon
				(pts
					(xy 413.3088 -89.1667) (xy 413.3088 -89.6747) (xy 413.6898 -89.6747) (xy 413.6898 -89.1667)
				)
			)
		)
		(zone
			(layer "B.Cu")
			(hatch none 0.5)
			(connect_pads
				(clearance 0)
			)
			(min_thickness 0.25)
			(keepout
				(tracks allowed)
				(vias not_allowed)
				(pads allowed)
				(copperpour not_allowed)
				(footprints allowed)
			)
			(placement
				(enabled no)
				(sheetname "")
			)
			(fill
				(thermal_gap 0.5)
				(thermal_bridge_width 0.5)
				(island_removal_mode 0)
			)
			(polygon
				(pts
					(xy 413.6898 -89.1667) (xy 413.6898 -89.6747) (xy 413.3088 -89.6747) (xy 413.3088 -89.1667)
				)
			)
		)
	)
	(footprint ""
		(layer "B.Cu")
		(at 30.452568 -154.6352 90)
		(property "Reference" "C9L1"
			(at 0 0 90)
			(layer "B.SilkS")
			(hide yes)
			(effects
				(font
					(size 1.27 1.27)
				)
				(justify mirror)
			)
		)
		(property "Value" ""
			(at 0 0 90)
			(layer "B.Fab")
			(effects
				(font
					(size 1.27 1.27)
				)
				(justify mirror)
			)
		)
		(duplicate_pad_numbers_are_jumpers no)
		(fp_poly
			(pts
				(xy -0.3048 -0.1016) (xy -0.3048 0.9906) (xy 0.3048 0.9906) (xy 0.3048 -0.1016)
			)
			(stroke
				(width 0)
				(type default)
			)
			(fill no)
			(layer "B.CrtYd")
		)
		(fp_line
			(start 0.3048 -0.1016)
			(end 0.3048 0.9906)
			(stroke
				(width 0.1)
				(type default)
			)
			(layer "B.Fab")
		)
		(fp_line
			(start -0.3048 -0.1016)
			(end 0.3048 -0.1016)
			(stroke
				(width 0.1)
				(type default)
			)
			(layer "B.Fab")
		)
		(fp_line
			(start 0.3048 0.9906)
			(end -0.3048 0.9906)
			(stroke
				(width 0.1)
				(type default)
			)
			(layer "B.Fab")
		)
		(fp_line
			(start -0.3048 0.9906)
			(end -0.3048 -0.1016)
			(stroke
				(width 0.1)
				(type default)
			)
			(layer "B.Fab")
		)
		(pad "1" smd rect
			(at 0 0 270)
			(size 0.508 0.508)
			(layers "B.Cu" "B.Mask" "B.Paste")
			(net "M_M_VREF")
		)
		(pad "2" smd rect
			(at 0 0.889 270)
			(size 0.508 0.508)
			(layers "B.Cu" "B.Mask" "B.Paste")
			(net "GND")
		)
		(zone
			(layer "B.Cu")
			(hatch none 0.5)
			(connect_pads
				(clearance 0)
			)
			(min_thickness 0.25)
			(keepout
				(tracks allowed)
				(vias not_allowed)
				(pads allowed)
				(copperpour not_allowed)
				(footprints allowed)
			)
			(placement
				(enabled no)
				(sheetname "")
			)
			(fill
				(thermal_gap 0.5)
				(thermal_bridge_width 0.5)
				(island_removal_mode 0)
			)
			(polygon
				(pts
					(xy 30.706568 -154.8892) (xy 30.706568 -154.3812) (xy 31.087568 -154.3812) (xy 31.087568 -154.8892)
				)
			)
		)
		(zone
			(layer "B.Cu")
			(hatch none 0.5)
			(connect_pads
				(clearance 0)
			)
			(min_thickness 0.25)
			(keepout
				(tracks not_allowed)
				(vias allowed)
				(pads allowed)
				(copperpour not_allowed)
				(footprints allowed)
			)
			(placement
				(enabled no)
				(sheetname "")
			)
			(fill
				(thermal_gap 0.5)
				(thermal_bridge_width 0.5)
				(island_removal_mode 0)
			)
			(polygon
				(pts
					(xy 31.087568 -154.8892) (xy 31.087568 -154.3812) (xy 30.706568 -154.3812) (xy 30.706568 -154.8892)
				)
			)
		)
	)
	(footprint ""
		(layer "B.Cu")
		(at 330.116434 -62.456822 90)
		(property "Reference" "R3R7"
			(at 0 0 90)
			(layer "B.SilkS")
			(hide yes)
			(effects
				(font
					(size 1.27 1.27)
				)
				(justify mirror)
			)
		)
		(property "Value" ""
			(at 0 0 90)
			(layer "B.Fab")
			(effects
				(font
					(size 1.27 1.27)
				)
				(justify mirror)
			)
		)
		(duplicate_pad_numbers_are_jumpers no)
		(fp_poly
			(pts
				(xy 0.2794 -0.1016) (xy -0.2794 -0.1016) (xy -0.2794 0.9906) (xy 0.2794 0.9906)
			)
			(stroke
				(width 0)
				(type default)
			)
			(fill no)
			(layer "B.CrtYd")
		)
		(fp_line
			(start 0.2794 -0.1016)
			(end 0.2794 0.9906)
			(stroke
				(width 0.1)
				(type default)
			)
			(layer "B.Fab")
		)
		(fp_line
			(start -0.2794 -0.1016)
			(end 0.2794 -0.1016)
			(stroke
				(width 0.1)
				(type default)
			)
			(layer "B.Fab")
		)
		(fp_line
			(start 0.2794 0.9906)
			(end -0.2794 0.9906)
			(stroke
				(width 0.1)
				(type default)
			)
			(layer "B.Fab")
		)
		(fp_line
			(start -0.2794 0.9906)
			(end -0.2794 -0.1016)
			(stroke
				(width 0.1)
				(type default)
			)
			(layer "B.Fab")
		)
		(pad "1" smd rect
			(at 0 0 270)
			(size 0.508 0.508)
			(layers "B.Cu" "B.Mask" "B.Paste")
			(net "SMB_DDR_DEF_SCL_G_R")
		)
		(pad "2" smd rect
			(at 0 0.889 270)
			(size 0.508 0.508)
			(layers "B.Cu" "B.Mask" "B.Paste")
			(net "SMB_DDR_DEF_SCL_G")
		)
		(zone
			(layer "B.Cu")
			(hatch none 0.5)
			(connect_pads
				(clearance 0)
			)
			(min_thickness 0.25)
			(keepout
				(tracks allowed)
				(vias not_allowed)
				(pads allowed)
				(copperpour not_allowed)
				(footprints allowed)
			)
			(placement
				(enabled no)
				(sheetname "")
			)
			(fill
				(thermal_gap 0.5)
				(thermal_bridge_width 0.5)
				(island_removal_mode 0)
			)
			(polygon
				(pts
					(xy 330.370434 -62.710822) (xy 330.370434 -62.202822) (xy 330.751434 -62.202822) (xy 330.751434 -62.710822)
				)
			)
		)
		(zone
			(layer "B.Cu")
			(hatch none 0.5)
			(connect_pads
				(clearance 0)
			)
			(min_thickness 0.25)
			(keepout
				(tracks not_allowed)
				(vias allowed)
				(pads allowed)
				(copperpour not_allowed)
				(footprints allowed)
			)
			(placement
				(enabled no)
				(sheetname "")
			)
			(fill
				(thermal_gap 0.5)
				(thermal_bridge_width 0.5)
				(island_removal_mode 0)
			)
			(polygon
				(pts
					(xy 330.751434 -62.710822) (xy 330.751434 -62.202822) (xy 330.370434 -62.202822) (xy 330.370434 -62.710822)
				)
			)
		)
	)
	(footprint ""
		(layer "B.Cu")
		(at 462.801208 -136.525254 90)
		(property "Reference" "R1L41"
			(at 0 0 90)
			(layer "B.SilkS")
			(hide yes)
			(effects
				(font
					(size 1.27 1.27)
				)
				(justify mirror)
			)
		)
		(property "Value" ""
			(at 0 0 90)
			(layer "B.Fab")
			(effects
				(font
					(size 1.27 1.27)
				)
				(justify mirror)
			)
		)
		(duplicate_pad_numbers_are_jumpers no)
		(fp_poly
			(pts
				(xy 0.2794 -0.1016) (xy -0.2794 -0.1016) (xy -0.2794 0.9906) (xy 0.2794 0.9906)
			)
			(stroke
				(width 0)
				(type default)
			)
			(fill no)
			(layer "B.CrtYd")
		)
		(fp_line
			(start 0.2794 -0.1016)
			(end 0.2794 0.9906)
			(stroke
				(width 0.1)
				(type default)
			)
			(layer "B.Fab")
		)
		(fp_line
			(start -0.2794 -0.1016)
			(end 0.2794 -0.1016)
			(stroke
				(width 0.1)
				(type default)
			)
			(layer "B.Fab")
		)
		(fp_line
			(start 0.2794 0.9906)
			(end -0.2794 0.9906)
			(stroke
				(width 0.1)
				(type default)
			)
			(layer "B.Fab")
		)
		(fp_line
			(start -0.2794 0.9906)
			(end -0.2794 -0.1016)
			(stroke
				(width 0.1)
				(type default)
			)
			(layer "B.Fab")
		)
		(pad "1" smd rect
			(at 0 0 270)
			(size 0.508 0.508)
			(layers "B.Cu" "B.Mask" "B.Paste")
			(net "P1V05_PCH_STBY")
		)
		(pad "2" smd rect
			(at 0 0.889 270)
			(size 0.508 0.508)
			(layers "B.Cu" "B.Mask" "B.Paste")
			(net "XDP_PREQ_N")
		)
		(zone
			(layer "B.Cu")
			(hatch none 0.5)
			(connect_pads
				(clearance 0)
			)
			(min_thickness 0.25)
			(keepout
				(tracks allowed)
				(vias not_allowed)
				(pads allowed)
				(copperpour not_allowed)
				(footprints allowed)
			)
			(placement
				(enabled no)
				(sheetname "")
			)
			(fill
				(thermal_gap 0.5)
				(thermal_bridge_width 0.5)
				(island_removal_mode 0)
			)
			(polygon
				(pts
					(xy 463.055208 -136.779254) (xy 463.055208 -136.271254) (xy 463.436208 -136.271254) (xy 463.436208 -136.779254)
				)
			)
		)
		(zone
			(layer "B.Cu")
			(hatch none 0.5)
			(connect_pads
				(clearance 0)
			)
			(min_thickness 0.25)
			(keepout
				(tracks not_allowed)
				(vias allowed)
				(pads allowed)
				(copperpour not_allowed)
				(footprints allowed)
			)
			(placement
				(enabled no)
				(sheetname "")
			)
			(fill
				(thermal_gap 0.5)
				(thermal_bridge_width 0.5)
				(island_removal_mode 0)
			)
			(polygon
				(pts
					(xy 463.436208 -136.779254) (xy 463.436208 -136.271254) (xy 463.055208 -136.271254) (xy 463.055208 -136.779254)
				)
			)
		)
	)
	(footprint ""
		(layer "B.Cu")
		(at 447.6242 -12.2174 180)
		(property "Reference" "C2U26"
			(at 0 0 0)
			(layer "B.SilkS")
			(hide yes)
			(effects
				(font
					(size 1.27 1.27)
				)
				(justify mirror)
			)
		)
		(property "Value" ""
			(at 0 0 0)
			(layer "B.Fab")
			(effects
				(font
					(size 1.27 1.27)
				)
				(justify mirror)
			)
		)
		(duplicate_pad_numbers_are_jumpers no)
		(fp_poly
			(pts
				(xy -0.3048 -0.1016) (xy -0.3048 0.9906) (xy 0.3048 0.9906) (xy 0.3048 -0.1016)
			)
			(stroke
				(width 0)
				(type default)
			)
			(fill no)
			(layer "B.CrtYd")
		)
		(fp_line
			(start 0.3048 0.9906)
			(end -0.3048 0.9906)
			(stroke
				(width 0.1)
				(type default)
			)
			(layer "B.Fab")
		)
		(fp_line
			(start 0.3048 -0.1016)
			(end 0.3048 0.9906)
			(stroke
				(width 0.1)
				(type default)
			)
			(layer "B.Fab")
		)
		(fp_line
			(start -0.3048 0.9906)
			(end -0.3048 -0.1016)
			(stroke
				(width 0.1)
				(type default)
			)
			(layer "B.Fab")
		)
		(fp_line
			(start -0.3048 -0.1016)
			(end 0.3048 -0.1016)
			(stroke
				(width 0.1)
				(type default)
			)
			(layer "B.Fab")
		)
		(pad "1" smd rect
			(at 0 0)
			(size 0.508 0.508)
			(layers "B.Cu" "B.Mask" "B.Paste")
			(net "P3V3_RTC_STBY")
		)
		(pad "2" smd rect
			(at 0 0.889)
			(size 0.508 0.508)
			(layers "B.Cu" "B.Mask" "B.Paste")
			(net "GND")
		)
		(zone
			(layer "B.Cu")
			(hatch none 0.5)
			(connect_pads
				(clearance 0)
			)
			(min_thickness 0.25)
			(keepout
				(tracks not_allowed)
				(vias allowed)
				(pads allowed)
				(copperpour not_allowed)
				(footprints allowed)
			)
			(placement
				(enabled no)
				(sheetname "")
			)
			(fill
				(thermal_gap 0.5)
				(thermal_bridge_width 0.5)
				(island_removal_mode 0)
			)
			(polygon
				(pts
					(xy 447.3702 -12.8524) (xy 447.8782 -12.8524) (xy 447.8782 -12.4714) (xy 447.3702 -12.4714)
				)
			)
		)
		(zone
			(layer "B.Cu")
			(hatch none 0.5)
			(connect_pads
				(clearance 0)
			)
			(min_thickness 0.25)
			(keepout
				(tracks allowed)
				(vias not_allowed)
				(pads allowed)
				(copperpour not_allowed)
				(footprints allowed)
			)
			(placement
				(enabled no)
				(sheetname "")
			)
			(fill
				(thermal_gap 0.5)
				(thermal_bridge_width 0.5)
				(island_removal_mode 0)
			)
			(polygon
				(pts
					(xy 447.3702 -12.4714) (xy 447.8782 -12.4714) (xy 447.8782 -12.8524) (xy 447.3702 -12.8524)
				)
			)
		)
	)
	(footprint ""
		(layer "B.Cu")
		(at 481.965 -32.512 180)
		(property "Reference" "R2T47"
			(at 0 0 0)
			(layer "B.SilkS")
			(hide yes)
			(effects
				(font
					(size 1.27 1.27)
				)
				(justify mirror)
			)
		)
		(property "Value" ""
			(at 0 0 0)
			(layer "B.Fab")
			(effects
				(font
					(size 1.27 1.27)
				)
				(justify mirror)
			)
		)
		(duplicate_pad_numbers_are_jumpers no)
		(fp_poly
			(pts
				(xy 0.2794 -0.1016) (xy -0.2794 -0.1016) (xy -0.2794 0.9906) (xy 0.2794 0.9906)
			)
			(stroke
				(width 0)
				(type default)
			)
			(fill no)
			(layer "B.CrtYd")
		)
		(fp_line
			(start 0.2794 0.9906)
			(end -0.2794 0.9906)
			(stroke
				(width 0.1)
				(type default)
			)
			(layer "B.Fab")
		)
		(fp_line
			(start 0.2794 -0.1016)
			(end 0.2794 0.9906)
			(stroke
				(width 0.1)
				(type default)
			)
			(layer "B.Fab")
		)
		(fp_line
			(start -0.2794 0.9906)
			(end -0.2794 -0.1016)
			(stroke
				(width 0.1)
				(type default)
			)
			(layer "B.Fab")
		)
		(fp_line
			(start -0.2794 -0.1016)
			(end 0.2794 -0.1016)
			(stroke
				(width 0.1)
				(type default)
			)
			(layer "B.Fab")
		)
		(pad "1" smd rect
			(at 0 0)
			(size 0.508 0.508)
			(layers "B.Cu" "B.Mask" "B.Paste")
			(net "CLK_25M_CPLD_R")
		)
		(pad "2" smd rect
			(at 0 0.889)
			(size 0.508 0.508)
			(layers "B.Cu" "B.Mask" "B.Paste")
			(net "CLK_25M_CPLD")
		)
		(zone
			(layer "B.Cu")
			(hatch none 0.5)
			(connect_pads
				(clearance 0)
			)
			(min_thickness 0.25)
			(keepout
				(tracks not_allowed)
				(vias allowed)
				(pads allowed)
				(copperpour not_allowed)
				(footprints allowed)
			)
			(placement
				(enabled no)
				(sheetname "")
			)
			(fill
				(thermal_gap 0.5)
				(thermal_bridge_width 0.5)
				(island_removal_mode 0)
			)
			(polygon
				(pts
					(xy 481.711 -33.147) (xy 482.219 -33.147) (xy 482.219 -32.766) (xy 481.711 -32.766)
				)
			)
		)
		(zone
			(layer "B.Cu")
			(hatch none 0.5)
			(connect_pads
				(clearance 0)
			)
			(min_thickness 0.25)
			(keepout
				(tracks allowed)
				(vias not_allowed)
				(pads allowed)
				(copperpour not_allowed)
				(footprints allowed)
			)
			(placement
				(enabled no)
				(sheetname "")
			)
			(fill
				(thermal_gap 0.5)
				(thermal_bridge_width 0.5)
				(island_removal_mode 0)
			)
			(polygon
				(pts
					(xy 481.711 -32.766) (xy 482.219 -32.766) (xy 482.219 -33.147) (xy 481.711 -33.147)
				)
			)
		)
	)
	(footprint ""
		(layer "B.Cu")
		(at 385.34594 -29.555694 90)
		(property "Reference" "C2T11"
			(at 0 0 90)
			(layer "B.SilkS")
			(hide yes)
			(effects
				(font
					(size 1.27 1.27)
				)
				(justify mirror)
			)
		)
		(property "Value" ""
			(at 0 0 90)
			(layer "B.Fab")
			(effects
				(font
					(size 1.27 1.27)
				)
				(justify mirror)
			)
		)
		(duplicate_pad_numbers_are_jumpers no)
		(fp_poly
			(pts
				(xy -0.3048 -0.1016) (xy -0.3048 0.9906) (xy 0.3048 0.9906) (xy 0.3048 -0.1016)
			)
			(stroke
				(width 0)
				(type default)
			)
			(fill no)
			(layer "B.CrtYd")
		)
		(fp_line
			(start 0.3048 -0.1016)
			(end 0.3048 0.9906)
			(stroke
				(width 0.1)
				(type default)
			)
			(layer "B.Fab")
		)
		(fp_line
			(start -0.3048 -0.1016)
			(end 0.3048 -0.1016)
			(stroke
				(width 0.1)
				(type default)
			)
			(layer "B.Fab")
		)
		(fp_line
			(start 0.3048 0.9906)
			(end -0.3048 0.9906)
			(stroke
				(width 0.1)
				(type default)
			)
			(layer "B.Fab")
		)
		(fp_line
			(start -0.3048 0.9906)
			(end -0.3048 -0.1016)
			(stroke
				(width 0.1)
				(type default)
			)
			(layer "B.Fab")
		)
		(pad "1" smd rect
			(at 0 0 270)
			(size 0.508 0.508)
			(layers "B.Cu" "B.Mask" "B.Paste")
			(net "P3E_PCH_M2_TX_C_DN<1>")
		)
		(pad "2" smd rect
			(at 0 0.889 270)
			(size 0.508 0.508)
			(layers "B.Cu" "B.Mask" "B.Paste")
			(net "P3E_PCH_M2_TX_DN<1>")
		)
		(zone
			(layer "B.Cu")
			(hatch none 0.5)
			(connect_pads
				(clearance 0)
			)
			(min_thickness 0.25)
			(keepout
				(tracks allowed)
				(vias not_allowed)
				(pads allowed)
				(copperpour not_allowed)
				(footprints allowed)
			)
			(placement
				(enabled no)
				(sheetname "")
			)
			(fill
				(thermal_gap 0.5)
				(thermal_bridge_width 0.5)
				(island_removal_mode 0)
			)
			(polygon
				(pts
					(xy 385.59994 -29.809694) (xy 385.59994 -29.301694) (xy 385.98094 -29.301694) (xy 385.98094 -29.809694)
				)
			)
		)
		(zone
			(layer "B.Cu")
			(hatch none 0.5)
			(connect_pads
				(clearance 0)
			)
			(min_thickness 0.25)
			(keepout
				(tracks not_allowed)
				(vias allowed)
				(pads allowed)
				(copperpour not_allowed)
				(footprints allowed)
			)
			(placement
				(enabled no)
				(sheetname "")
			)
			(fill
				(thermal_gap 0.5)
				(thermal_bridge_width 0.5)
				(island_removal_mode 0)
			)
			(polygon
				(pts
					(xy 385.98094 -29.809694) (xy 385.98094 -29.301694) (xy 385.59994 -29.301694) (xy 385.59994 -29.809694)
				)
			)
		)
	)
	(footprint ""
		(layer "B.Cu")
		(at 414.528 -20.3962 -90)
		(property "Reference" "R1U7"
			(at 0 0 90)
			(layer "B.SilkS")
			(hide yes)
			(effects
				(font
					(size 1.27 1.27)
				)
				(justify mirror)
			)
		)
		(property "Value" ""
			(at 0 0 90)
			(layer "B.Fab")
			(effects
				(font
					(size 1.27 1.27)
				)
				(justify mirror)
			)
		)
		(duplicate_pad_numbers_are_jumpers no)
		(fp_poly
			(pts
				(xy 0.2794 -0.1016) (xy -0.2794 -0.1016) (xy -0.2794 0.9906) (xy 0.2794 0.9906)
			)
			(stroke
				(width 0)
				(type default)
			)
			(fill no)
			(layer "B.CrtYd")
		)
		(fp_line
			(start -0.2794 0.9906)
			(end -0.2794 -0.1016)
			(stroke
				(width 0.1)
				(type default)
			)
			(layer "B.Fab")
		)
		(fp_line
			(start 0.2794 0.9906)
			(end -0.2794 0.9906)
			(stroke
				(width 0.1)
				(type default)
			)
			(layer "B.Fab")
		)
		(fp_line
			(start -0.2794 -0.1016)
			(end 0.2794 -0.1016)
			(stroke
				(width 0.1)
				(type default)
			)
			(layer "B.Fab")
		)
		(fp_line
			(start 0.2794 -0.1016)
			(end 0.2794 0.9906)
			(stroke
				(width 0.1)
				(type default)
			)
			(layer "B.Fab")
		)
		(pad "1" smd rect
			(at 0 0 90)
			(size 0.508 0.508)
			(layers "B.Cu" "B.Mask" "B.Paste")
			(net "GND")
		)
		(pad "2" smd rect
			(at 0 0.889 90)
			(size 0.508 0.508)
			(layers "B.Cu" "B.Mask" "B.Paste")
			(net "PD_SP_ENTEST")
		)
		(zone
			(layer "B.Cu")
			(hatch none 0.5)
			(connect_pads
				(clearance 0)
			)
			(min_thickness 0.25)
			(keepout
				(tracks not_allowed)
				(vias allowed)
				(pads allowed)
				(copperpour not_allowed)
				(footprints allowed)
			)
			(placement
				(enabled no)
				(sheetname "")
			)
			(fill
				(thermal_gap 0.5)
				(thermal_bridge_width 0.5)
				(island_removal_mode 0)
			)
			(polygon
				(pts
					(xy 413.893 -20.1422) (xy 413.893 -20.6502) (xy 414.274 -20.6502) (xy 414.274 -20.1422)
				)
			)
		)
		(zone
			(layer "B.Cu")
			(hatch none 0.5)
			(connect_pads
				(clearance 0)
			)
			(min_thickness 0.25)
			(keepout
				(tracks allowed)
				(vias not_allowed)
				(pads allowed)
				(copperpour not_allowed)
				(footprints allowed)
			)
			(placement
				(enabled no)
				(sheetname "")
			)
			(fill
				(thermal_gap 0.5)
				(thermal_bridge_width 0.5)
				(island_removal_mode 0)
			)
			(polygon
				(pts
					(xy 414.274 -20.1422) (xy 414.274 -20.6502) (xy 413.893 -20.6502) (xy 413.893 -20.1422)
				)
			)
		)
	)
	(footprint ""
		(layer "B.Cu")
		(at 379.476 -19.304 90)
		(property "Reference" "CN8F2"
			(at 0.8382 -0.67818 90)
			(unlocked yes)
			(layer "B.SilkS")
			(effects
				(font
					(size 0.4064 0.254)
					(thickness 0.1524)
				)
				(justify left mirror)
			)
		)
		(property "Value" ""
			(at 0 0 90)
			(layer "B.Fab")
			(effects
				(font
					(size 1.27 1.27)
				)
				(justify mirror)
			)
		)
		(duplicate_pad_numbers_are_jumpers no)
		(fp_poly
			(pts
				(xy -0.3048 -0.1016) (xy -0.3048 0.9906) (xy 0.3048 0.9906) (xy 0.3048 -0.1016)
			)
			(stroke
				(width 0)
				(type default)
			)
			(fill no)
			(layer "B.CrtYd")
		)
		(fp_line
			(start 0.3048 -0.1016)
			(end 0.3048 0.9906)
			(stroke
				(width 0.1)
				(type default)
			)
			(layer "B.Fab")
		)
		(fp_line
			(start -0.3048 -0.1016)
			(end 0.3048 -0.1016)
			(stroke
				(width 0.1)
				(type default)
			)
			(layer "B.Fab")
		)
		(fp_line
			(start 0.3048 0.9906)
			(end -0.3048 0.9906)
			(stroke
				(width 0.1)
				(type default)
			)
			(layer "B.Fab")
		)
		(fp_line
			(start -0.3048 0.9906)
			(end -0.3048 -0.1016)
			(stroke
				(width 0.1)
				(type default)
			)
			(layer "B.Fab")
		)
		(pad "1" smd rect
			(at 0 0 270)
			(size 0.508 0.508)
			(layers "B.Cu" "B.Mask" "B.Paste")
			(net "P3V3_STBY")
		)
		(pad "2" smd rect
			(at 0 0.889 270)
			(size 0.508 0.508)
			(layers "B.Cu" "B.Mask" "B.Paste")
			(net "GND")
		)
		(zone
			(layer "B.Cu")
			(hatch none 0.5)
			(connect_pads
				(clearance 0)
			)
			(min_thickness 0.25)
			(keepout
				(tracks allowed)
				(vias not_allowed)
				(pads allowed)
				(copperpour not_allowed)
				(footprints allowed)
			)
			(placement
				(enabled no)
				(sheetname "")
			)
			(fill
				(thermal_gap 0.5)
				(thermal_bridge_width 0.5)
				(island_removal_mode 0)
			)
			(polygon
				(pts
					(xy 379.73 -19.558) (xy 379.73 -19.05) (xy 380.111 -19.05) (xy 380.111 -19.558)
				)
			)
		)
		(zone
			(layer "B.Cu")
			(hatch none 0.5)
			(connect_pads
				(clearance 0)
			)
			(min_thickness 0.25)
			(keepout
				(tracks not_allowed)
				(vias allowed)
				(pads allowed)
				(copperpour not_allowed)
				(footprints allowed)
			)
			(placement
				(enabled no)
				(sheetname "")
			)
			(fill
				(thermal_gap 0.5)
				(thermal_bridge_width 0.5)
				(island_removal_mode 0)
			)
			(polygon
				(pts
					(xy 380.111 -19.558) (xy 380.111 -19.05) (xy 379.73 -19.05) (xy 379.73 -19.558)
				)
			)
		)
	)
	(footprint ""
		(layer "B.Cu")
		(at 493.5474 -124.05868 180)
		(property "Reference" "R1M13"
			(at 0 0 0)
			(layer "B.SilkS")
			(hide yes)
			(effects
				(font
					(size 1.27 1.27)
				)
				(justify mirror)
			)
		)
		(property "Value" ""
			(at 0 0 0)
			(layer "B.Fab")
			(effects
				(font
					(size 1.27 1.27)
				)
				(justify mirror)
			)
		)
		(duplicate_pad_numbers_are_jumpers no)
		(fp_poly
			(pts
				(xy 0.2794 -0.1016) (xy -0.2794 -0.1016) (xy -0.2794 0.9906) (xy 0.2794 0.9906)
			)
			(stroke
				(width 0)
				(type default)
			)
			(fill no)
			(layer "B.CrtYd")
		)
		(fp_line
			(start 0.2794 0.9906)
			(end -0.2794 0.9906)
			(stroke
				(width 0.1)
				(type default)
			)
			(layer "B.Fab")
		)
		(fp_line
			(start 0.2794 -0.1016)
			(end 0.2794 0.9906)
			(stroke
				(width 0.1)
				(type default)
			)
			(layer "B.Fab")
		)
		(fp_line
			(start -0.2794 0.9906)
			(end -0.2794 -0.1016)
			(stroke
				(width 0.1)
				(type default)
			)
			(layer "B.Fab")
		)
		(fp_line
			(start -0.2794 -0.1016)
			(end 0.2794 -0.1016)
			(stroke
				(width 0.1)
				(type default)
			)
			(layer "B.Fab")
		)
		(pad "1" smd rect
			(at 0 0)
			(size 0.508 0.508)
			(layers "B.Cu" "B.Mask" "B.Paste")
			(net "LED_PCH_SSATA_HDD_N")
		)
		(pad "2" smd rect
			(at 0 0.889)
			(size 0.508 0.508)
			(layers "B.Cu" "B.Mask" "B.Paste")
			(net "LED_SAS_ACT_R_N")
		)
		(zone
			(layer "B.Cu")
			(hatch none 0.5)
			(connect_pads
				(clearance 0)
			)
			(min_thickness 0.25)
			(keepout
				(tracks not_allowed)
				(vias allowed)
				(pads allowed)
				(copperpour not_allowed)
				(footprints allowed)
			)
			(placement
				(enabled no)
				(sheetname "")
			)
			(fill
				(thermal_gap 0.5)
				(thermal_bridge_width 0.5)
				(island_removal_mode 0)
			)
			(polygon
				(pts
					(xy 493.2934 -124.69368) (xy 493.8014 -124.69368) (xy 493.8014 -124.31268) (xy 493.2934 -124.31268)
				)
			)
		)
		(zone
			(layer "B.Cu")
			(hatch none 0.5)
			(connect_pads
				(clearance 0)
			)
			(min_thickness 0.25)
			(keepout
				(tracks allowed)
				(vias not_allowed)
				(pads allowed)
				(copperpour not_allowed)
				(footprints allowed)
			)
			(placement
				(enabled no)
				(sheetname "")
			)
			(fill
				(thermal_gap 0.5)
				(thermal_bridge_width 0.5)
				(island_removal_mode 0)
			)
			(polygon
				(pts
					(xy 493.2934 -124.31268) (xy 493.8014 -124.31268) (xy 493.8014 -124.69368) (xy 493.2934 -124.69368)
				)
			)
		)
	)
	(footprint ""
		(layer "B.Cu")
		(at 269.559532 -12.954 90)
		(property "Reference" "C5G47"
			(at -1.14681 0.76708 180)
			(unlocked yes)
			(layer "B.SilkS")
			(effects
				(font
					(size 0.7874 0.5842)
					(thickness 0.1524)
				)
				(justify mirror)
			)
		)
		(property "Value" ""
			(at 0 0 90)
			(layer "B.Fab")
			(effects
				(font
					(size 1.27 1.27)
				)
				(justify mirror)
			)
		)
		(duplicate_pad_numbers_are_jumpers no)
		(fp_rect
			(start -0.4953 -0.2032)
			(end 0.4953 1.6002)
			(stroke
				(width 0)
				(type default)
			)
			(fill no)
			(layer "B.CrtYd")
		)
		(fp_line
			(start 0.4953 -0.2032)
			(end -0.4953 -0.2032)
			(stroke
				(width 0.1)
				(type default)
			)
			(layer "B.Fab")
		)
		(fp_line
			(start -0.4953 -0.2032)
			(end -0.4953 1.6002)
			(stroke
				(width 0.1)
				(type default)
			)
			(layer "B.Fab")
		)
		(fp_line
			(start 0.4953 1.6002)
			(end 0.4953 -0.2032)
			(stroke
				(width 0.1)
				(type default)
			)
			(layer "B.Fab")
		)
		(fp_line
			(start -0.4953 1.6002)
			(end 0.4953 1.6002)
			(stroke
				(width 0.1)
				(type default)
			)
			(layer "B.Fab")
		)
		(pad "1" smd rect
			(at 0 0 270)
			(size 0.762 0.889)
			(layers "B.Cu" "B.Mask" "B.Paste")
			(net "PVDDQ_ABC")
		)
		(pad "2" smd rect
			(at 0 1.397 270)
			(size 0.762 0.889)
			(layers "B.Cu" "B.Mask" "B.Paste")
			(net "GND")
		)
		(zone
			(layer "B.Cu")
			(hatch none 0.5)
			(connect_pads
				(clearance 0)
			)
			(min_thickness 0.25)
			(keepout
				(tracks not_allowed)
				(vias allowed)
				(pads allowed)
				(copperpour not_allowed)
				(footprints allowed)
			)
			(placement
				(enabled no)
				(sheetname "")
			)
			(fill
				(thermal_gap 0.5)
				(thermal_bridge_width 0.5)
				(island_removal_mode 0)
			)
			(polygon
				(pts
					(xy 270.004032 -12.573) (xy 270.512032 -12.573) (xy 270.512032 -13.335) (xy 270.004032 -13.335)
				)
			)
		)
	)
	(footprint ""
		(layer "B.Cu")
		(at 267.081 3.81 90)
		(property "Reference" "C5U15"
			(at 0 0 90)
			(layer "B.SilkS")
			(hide yes)
			(effects
				(font
					(size 1.27 1.27)
				)
				(justify mirror)
			)
		)
		(property "Value" ""
			(at 0 0 90)
			(layer "B.Fab")
			(effects
				(font
					(size 1.27 1.27)
				)
				(justify mirror)
			)
		)
		(duplicate_pad_numbers_are_jumpers no)
		(fp_rect
			(start -0.7239 -0.2159)
			(end 0.7239 1.9939)
			(stroke
				(width 0)
				(type default)
			)
			(fill no)
			(layer "B.CrtYd")
		)
		(fp_line
			(start 0.7239 -0.2159)
			(end 0.7239 1.9939)
			(stroke
				(width 0.1)
				(type default)
			)
			(layer "B.Fab")
		)
		(fp_line
			(start -0.7239 -0.2159)
			(end 0.7239 -0.2159)
			(stroke
				(width 0.1)
				(type default)
			)
			(layer "B.Fab")
		)
		(fp_line
			(start 0.7239 1.9939)
			(end -0.7239 1.9939)
			(stroke
				(width 0.1)
				(type default)
			)
			(layer "B.Fab")
		)
		(fp_line
			(start -0.7239 1.9939)
			(end -0.7239 -0.2159)
			(stroke
				(width 0.1)
				(type default)
			)
			(layer "B.Fab")
		)
		(pad "1" smd rect
			(at 0 0 270)
			(size 1.27 1.016)
			(layers "B.Cu" "B.Mask" "B.Paste")
			(net "PVDDQ_ABC")
		)
		(pad "2" smd rect
			(at 0 1.778 270)
			(size 1.27 1.016)
			(layers "B.Cu" "B.Mask" "B.Paste")
			(net "GND")
		)
		(zone
			(layer "B.Cu")
			(hatch none 0.5)
			(connect_pads
				(clearance 0)
			)
			(min_thickness 0.25)
			(keepout
				(tracks not_allowed)
				(vias allowed)
				(pads allowed)
				(copperpour not_allowed)
				(footprints allowed)
			)
			(placement
				(enabled no)
				(sheetname "")
			)
			(fill
				(thermal_gap 0.5)
				(thermal_bridge_width 0.5)
				(island_removal_mode 0)
			)
			(polygon
				(pts
					(xy 267.589 4.445) (xy 268.351 4.445) (xy 268.351 3.175) (xy 267.589 3.175)
				)
			)
		)
	)
	(footprint ""
		(layer "B.Cu")
		(at 461.1116 -143.0274)
		(property "Reference" "U1L4"
			(at 1.28143 2.50952 270)
			(unlocked yes)
			(layer "B.SilkS")
			(effects
				(font
					(size 0.7874 0.5842)
					(thickness 0.1524)
				)
				(justify left mirror)
			)
		)
		(property "Value" ""
			(at 0 0 0)
			(layer "B.Fab")
			(effects
				(font
					(size 1.27 1.27)
				)
				(justify mirror)
			)
		)
		(duplicate_pad_numbers_are_jumpers no)
		(fp_circle
			(center 0.4699 -0.8382)
			(end 0.5969 -0.8382)
			(stroke
				(width 0.254)
				(type default)
			)
			(fill no)
			(layer "B.SilkS")
		)
		(fp_poly
			(pts
				(xy -0.21463 -0.450088) (xy -1.56337 -0.450088) (xy -1.56337 1.75006) (xy -0.21463 1.75006)
			)
			(stroke
				(width 0)
				(type default)
			)
			(fill no)
			(layer "B.CrtYd")
		)
		(fp_line
			(start -1.56337 -0.450088)
			(end -1.56337 1.75006)
			(stroke
				(width 0.1)
				(type default)
			)
			(layer "B.Fab")
		)
		(fp_line
			(start -1.56337 1.75006)
			(end -0.21463 1.75006)
			(stroke
				(width 0.1)
				(type default)
			)
			(layer "B.Fab")
		)
		(fp_line
			(start -0.21463 -0.450088)
			(end -1.56337 -0.450088)
			(stroke
				(width 0.1)
				(type default)
			)
			(layer "B.Fab")
		)
		(fp_line
			(start -0.21463 1.75006)
			(end -0.21463 -0.450088)
			(stroke
				(width 0.1)
				(type default)
			)
			(layer "B.Fab")
		)
		(fp_circle
			(center 0.4699 -0.8382)
			(end 0.5969 -0.8382)
			(stroke
				(width 0.254)
				(type default)
			)
			(fill no)
			(layer "B.Fab")
		)
		(pad "1" smd rect
			(at 0 0 180)
			(size 1.016 0.381)
			(layers "B.Cu" "B.Mask" "B.Paste")
			(net "Net_6475")
		)
		(pad "2" smd rect
			(at 0 0.649986 180)
			(size 1.016 0.381)
			(layers "B.Cu" "B.Mask" "B.Paste")
			(net "XDP_RST_CO_N")
		)
		(pad "3" smd rect
			(at 0 1.299972 180)
			(size 1.016 0.381)
			(layers "B.Cu" "B.Mask" "B.Paste")
			(net "GND")
		)
		(pad "4" smd rect
			(at -1.778 1.299972 180)
			(size 1.016 0.381)
			(layers "B.Cu" "B.Mask" "B.Paste")
			(net "FM_DEBUG_RST_BTN_R1_N")
		)
		(pad "5" smd rect
			(at -1.778 0 180)
			(size 1.016 0.381)
			(layers "B.Cu" "B.Mask" "B.Paste")
			(net "P3V3_STBY")
		)
	)
	(footprint ""
		(layer "B.Cu")
		(at 333.014574 -120.260364 90)
		(property "Reference" "C4M7"
			(at -0.15367 10.5918 0)
			(unlocked yes)
			(layer "B.SilkS")
			(effects
				(font
					(size 0.7874 0.5842)
					(thickness 0.1524)
				)
				(justify mirror)
			)
		)
		(property "Value" ""
			(at 0 0 90)
			(layer "B.Fab")
			(effects
				(font
					(size 1.27 1.27)
				)
				(justify mirror)
			)
		)
		(duplicate_pad_numbers_are_jumpers no)
		(fp_line
			(start 2.563114 -1.616456)
			(end 2.563114 1.633728)
			(stroke
				(width 0.1524)
				(type default)
			)
			(layer "B.SilkS")
		)
		(fp_line
			(start 1.6002 -1.616456)
			(end 2.563114 -1.616456)
			(stroke
				(width 0.1524)
				(type default)
			)
			(layer "B.SilkS")
		)
		(fp_line
			(start -1.6002 -1.616456)
			(end -2.504948 -1.616456)
			(stroke
				(width 0.1524)
				(type default)
			)
			(layer "B.SilkS")
		)
		(fp_line
			(start -2.504948 -1.616456)
			(end -2.504948 1.633728)
			(stroke
				(width 0.1524)
				(type default)
			)
			(layer "B.SilkS")
		)
		(fp_line
			(start 2.563114 1.633728)
			(end 1.6002 1.633728)
			(stroke
				(width 0.1524)
				(type default)
			)
			(layer "B.SilkS")
		)
		(fp_line
			(start -2.504948 1.633728)
			(end -1.6002 1.633728)
			(stroke
				(width 0.1524)
				(type default)
			)
			(layer "B.SilkS")
		)
		(fp_line
			(start 2.286 7.366)
			(end 2.286 1.632712)
			(stroke
				(width 0.1524)
				(type default)
			)
			(layer "B.SilkS")
		)
		(fp_line
			(start 2.286 7.366)
			(end 1.60147 7.366)
			(stroke
				(width 0.1524)
				(type default)
			)
			(layer "B.SilkS")
		)
		(fp_line
			(start -2.286 7.366)
			(end -2.286 1.63195)
			(stroke
				(width 0.1524)
				(type default)
			)
			(layer "B.SilkS")
		)
		(fp_line
			(start -2.286 7.366)
			(end -1.600708 7.366)
			(stroke
				(width 0.1524)
				(type default)
			)
			(layer "B.SilkS")
		)
		(fp_rect
			(start 2.286 7.366)
			(end -2.286 -0.254)
			(stroke
				(width 0)
				(type default)
			)
			(fill no)
			(layer "B.CrtYd")
		)
		(fp_line
			(start 2.286 -0.254)
			(end -2.286 -0.254)
			(stroke
				(width 0.1)
				(type default)
			)
			(layer "B.Fab")
		)
		(fp_line
			(start -2.286 -0.254)
			(end -2.286 7.366)
			(stroke
				(width 0.1)
				(type default)
			)
			(layer "B.Fab")
		)
		(fp_line
			(start 2.286 7.366)
			(end 2.286 -0.254)
			(stroke
				(width 0.1)
				(type default)
			)
			(layer "B.Fab")
		)
		(fp_line
			(start -2.286 7.366)
			(end 2.286 7.366)
			(stroke
				(width 0.1)
				(type default)
			)
			(layer "B.Fab")
		)
		(pad "1" smd rect
			(at 0 0 270)
			(size 2.54 3.048)
			(layers "B.Cu" "B.Mask" "B.Paste")
			(net "P12V_STBY")
		)
		(pad "2" smd rect
			(at 0 7.112 270)
			(size 2.54 3.048)
			(layers "B.Cu" "B.Mask" "B.Paste")
			(net "GND")
		)
	)
	(footprint ""
		(layer "B.Cu")
		(at 403.8854 2.4384 -90)
		(property "Reference" "C2U28"
			(at 0 0 90)
			(layer "B.SilkS")
			(hide yes)
			(effects
				(font
					(size 1.27 1.27)
				)
				(justify mirror)
			)
		)
		(property "Value" ""
			(at 0 0 90)
			(layer "B.Fab")
			(effects
				(font
					(size 1.27 1.27)
				)
				(justify mirror)
			)
		)
		(duplicate_pad_numbers_are_jumpers no)
		(fp_poly
			(pts
				(xy -0.3048 -0.1016) (xy -0.3048 0.9906) (xy 0.3048 0.9906) (xy 0.3048 -0.1016)
			)
			(stroke
				(width 0)
				(type default)
			)
			(fill no)
			(layer "B.CrtYd")
		)
		(fp_line
			(start -0.3048 0.9906)
			(end -0.3048 -0.1016)
			(stroke
				(width 0.1)
				(type default)
			)
			(layer "B.Fab")
		)
		(fp_line
			(start 0.3048 0.9906)
			(end -0.3048 0.9906)
			(stroke
				(width 0.1)
				(type default)
			)
			(layer "B.Fab")
		)
		(fp_line
			(start -0.3048 -0.1016)
			(end 0.3048 -0.1016)
			(stroke
				(width 0.1)
				(type default)
			)
			(layer "B.Fab")
		)
		(fp_line
			(start 0.3048 -0.1016)
			(end 0.3048 0.9906)
			(stroke
				(width 0.1)
				(type default)
			)
			(layer "B.Fab")
		)
		(pad "1" smd rect
			(at 0 0 90)
			(size 0.508 0.508)
			(layers "B.Cu" "B.Mask" "B.Paste")
			(net "P3V3_STBY")
		)
		(pad "2" smd rect
			(at 0 0.889 90)
			(size 0.508 0.508)
			(layers "B.Cu" "B.Mask" "B.Paste")
			(net "GND")
		)
		(zone
			(layer "B.Cu")
			(hatch none 0.5)
			(connect_pads
				(clearance 0)
			)
			(min_thickness 0.25)
			(keepout
				(tracks not_allowed)
				(vias allowed)
				(pads allowed)
				(copperpour not_allowed)
				(footprints allowed)
			)
			(placement
				(enabled no)
				(sheetname "")
			)
			(fill
				(thermal_gap 0.5)
				(thermal_bridge_width 0.5)
				(island_removal_mode 0)
			)
			(polygon
				(pts
					(xy 403.2504 2.6924) (xy 403.2504 2.1844) (xy 403.6314 2.1844) (xy 403.6314 2.6924)
				)
			)
		)
		(zone
			(layer "B.Cu")
			(hatch none 0.5)
			(connect_pads
				(clearance 0)
			)
			(min_thickness 0.25)
			(keepout
				(tracks allowed)
				(vias not_allowed)
				(pads allowed)
				(copperpour not_allowed)
				(footprints allowed)
			)
			(placement
				(enabled no)
				(sheetname "")
			)
			(fill
				(thermal_gap 0.5)
				(thermal_bridge_width 0.5)
				(island_removal_mode 0)
			)
			(polygon
				(pts
					(xy 403.6314 2.6924) (xy 403.6314 2.1844) (xy 403.2504 2.1844) (xy 403.2504 2.6924)
				)
			)
		)
	)
	(footprint ""
		(layer "B.Cu")
		(at 381.887984 -71.296276 90)
		(property "Reference" "R7E20"
			(at 0 0 90)
			(layer "B.SilkS")
			(hide yes)
			(effects
				(font
					(size 1.27 1.27)
				)
				(justify mirror)
			)
		)
		(property "Value" ""
			(at 0 0 90)
			(layer "B.Fab")
			(effects
				(font
					(size 1.27 1.27)
				)
				(justify mirror)
			)
		)
		(duplicate_pad_numbers_are_jumpers no)
		(fp_poly
			(pts
				(xy 0.2794 -0.1016) (xy -0.2794 -0.1016) (xy -0.2794 0.9906) (xy 0.2794 0.9906)
			)
			(stroke
				(width 0)
				(type default)
			)
			(fill no)
			(layer "B.CrtYd")
		)
		(fp_line
			(start 0.2794 -0.1016)
			(end 0.2794 0.9906)
			(stroke
				(width 0.1)
				(type default)
			)
			(layer "B.Fab")
		)
		(fp_line
			(start -0.2794 -0.1016)
			(end 0.2794 -0.1016)
			(stroke
				(width 0.1)
				(type default)
			)
			(layer "B.Fab")
		)
		(fp_line
			(start 0.2794 0.9906)
			(end -0.2794 0.9906)
			(stroke
				(width 0.1)
				(type default)
			)
			(layer "B.Fab")
		)
		(fp_line
			(start -0.2794 0.9906)
			(end -0.2794 -0.1016)
			(stroke
				(width 0.1)
				(type default)
			)
			(layer "B.Fab")
		)
		(pad "1" smd rect
			(at 0 0 270)
			(size 0.508 0.508)
			(layers "B.Cu" "B.Mask" "B.Paste")
			(net "FM_MEM_EVENT_FUNC")
		)
		(pad "2" smd rect
			(at 0 0.889 270)
			(size 0.508 0.508)
			(layers "B.Cu" "B.Mask" "B.Paste")
			(net "GND")
		)
		(zone
			(layer "B.Cu")
			(hatch none 0.5)
			(connect_pads
				(clearance 0)
			)
			(min_thickness 0.25)
			(keepout
				(tracks allowed)
				(vias not_allowed)
				(pads allowed)
				(copperpour not_allowed)
				(footprints allowed)
			)
			(placement
				(enabled no)
				(sheetname "")
			)
			(fill
				(thermal_gap 0.5)
				(thermal_bridge_width 0.5)
				(island_removal_mode 0)
			)
			(polygon
				(pts
					(xy 382.141984 -71.550276) (xy 382.141984 -71.042276) (xy 382.522984 -71.042276) (xy 382.522984 -71.550276)
				)
			)
		)
		(zone
			(layer "B.Cu")
			(hatch none 0.5)
			(connect_pads
				(clearance 0)
			)
			(min_thickness 0.25)
			(keepout
				(tracks not_allowed)
				(vias allowed)
				(pads allowed)
				(copperpour not_allowed)
				(footprints allowed)
			)
			(placement
				(enabled no)
				(sheetname "")
			)
			(fill
				(thermal_gap 0.5)
				(thermal_bridge_width 0.5)
				(island_removal_mode 0)
			)
			(polygon
				(pts
					(xy 382.522984 -71.550276) (xy 382.522984 -71.042276) (xy 382.141984 -71.042276) (xy 382.141984 -71.550276)
				)
			)
		)
	)
	(footprint ""
		(layer "B.Cu")
		(at 443.865 -64.7446 180)
		(property "Reference" "C2P15"
			(at 0 0 0)
			(layer "B.SilkS")
			(hide yes)
			(effects
				(font
					(size 1.27 1.27)
				)
				(justify mirror)
			)
		)
		(property "Value" ""
			(at 0 0 0)
			(layer "B.Fab")
			(effects
				(font
					(size 1.27 1.27)
				)
				(justify mirror)
			)
		)
		(duplicate_pad_numbers_are_jumpers no)
		(fp_poly
			(pts
				(xy -0.3048 -0.1016) (xy -0.3048 0.9906) (xy 0.3048 0.9906) (xy 0.3048 -0.1016)
			)
			(stroke
				(width 0)
				(type default)
			)
			(fill no)
			(layer "B.CrtYd")
		)
		(fp_line
			(start 0.3048 0.9906)
			(end -0.3048 0.9906)
			(stroke
				(width 0.1)
				(type default)
			)
			(layer "B.Fab")
		)
		(fp_line
			(start 0.3048 -0.1016)
			(end 0.3048 0.9906)
			(stroke
				(width 0.1)
				(type default)
			)
			(layer "B.Fab")
		)
		(fp_line
			(start -0.3048 0.9906)
			(end -0.3048 -0.1016)
			(stroke
				(width 0.1)
				(type default)
			)
			(layer "B.Fab")
		)
		(fp_line
			(start -0.3048 -0.1016)
			(end 0.3048 -0.1016)
			(stroke
				(width 0.1)
				(type default)
			)
			(layer "B.Fab")
		)
		(pad "1" smd rect
			(at 0 0)
			(size 0.508 0.508)
			(layers "B.Cu" "B.Mask" "B.Paste")
			(net "P12V_STBY")
		)
		(pad "2" smd rect
			(at 0 0.889)
			(size 0.508 0.508)
			(layers "B.Cu" "B.Mask" "B.Paste")
			(net "GND")
		)
		(zone
			(layer "B.Cu")
			(hatch none 0.5)
			(connect_pads
				(clearance 0)
			)
			(min_thickness 0.25)
			(keepout
				(tracks not_allowed)
				(vias allowed)
				(pads allowed)
				(copperpour not_allowed)
				(footprints allowed)
			)
			(placement
				(enabled no)
				(sheetname "")
			)
			(fill
				(thermal_gap 0.5)
				(thermal_bridge_width 0.5)
				(island_removal_mode 0)
			)
			(polygon
				(pts
					(xy 443.611 -65.3796) (xy 444.119 -65.3796) (xy 444.119 -64.9986) (xy 443.611 -64.9986)
				)
			)
		)
		(zone
			(layer "B.Cu")
			(hatch none 0.5)
			(connect_pads
				(clearance 0)
			)
			(min_thickness 0.25)
			(keepout
				(tracks allowed)
				(vias not_allowed)
				(pads allowed)
				(copperpour not_allowed)
				(footprints allowed)
			)
			(placement
				(enabled no)
				(sheetname "")
			)
			(fill
				(thermal_gap 0.5)
				(thermal_bridge_width 0.5)
				(island_removal_mode 0)
			)
			(polygon
				(pts
					(xy 443.611 -64.9986) (xy 444.119 -64.9986) (xy 444.119 -65.3796) (xy 443.611 -65.3796)
				)
			)
		)
	)
	(footprint ""
		(layer "B.Cu")
		(at 172.466 -87.757)
		(property "Reference" "R6P2"
			(at 0 0 0)
			(layer "B.SilkS")
			(hide yes)
			(effects
				(font
					(size 1.27 1.27)
				)
				(justify mirror)
			)
		)
		(property "Value" ""
			(at 0 0 0)
			(layer "B.Fab")
			(effects
				(font
					(size 1.27 1.27)
				)
				(justify mirror)
			)
		)
		(duplicate_pad_numbers_are_jumpers no)
		(fp_poly
			(pts
				(xy 0.2794 -0.1016) (xy -0.2794 -0.1016) (xy -0.2794 0.9906) (xy 0.2794 0.9906)
			)
			(stroke
				(width 0)
				(type default)
			)
			(fill no)
			(layer "B.CrtYd")
		)
		(fp_line
			(start -0.2794 -0.1016)
			(end 0.2794 -0.1016)
			(stroke
				(width 0.1)
				(type default)
			)
			(layer "B.Fab")
		)
		(fp_line
			(start -0.2794 0.9906)
			(end -0.2794 -0.1016)
			(stroke
				(width 0.1)
				(type default)
			)
			(layer "B.Fab")
		)
		(fp_line
			(start 0.2794 -0.1016)
			(end 0.2794 0.9906)
			(stroke
				(width 0.1)
				(type default)
			)
			(layer "B.Fab")
		)
		(fp_line
			(start 0.2794 0.9906)
			(end -0.2794 0.9906)
			(stroke
				(width 0.1)
				(type default)
			)
			(layer "B.Fab")
		)
		(pad "1" smd rect
			(at 0 0 180)
			(size 0.508 0.508)
			(layers "B.Cu" "B.Mask" "B.Paste")
			(net "CLK_100M_CPU0_RC_REFCLK0_DN")
		)
		(pad "2" smd rect
			(at 0 0.889 180)
			(size 0.508 0.508)
			(layers "B.Cu" "B.Mask" "B.Paste")
			(net "GND")
		)
		(zone
			(layer "B.Cu")
			(hatch none 0.5)
			(connect_pads
				(clearance 0)
			)
			(min_thickness 0.25)
			(keepout
				(tracks allowed)
				(vias not_allowed)
				(pads allowed)
				(copperpour not_allowed)
				(footprints allowed)
			)
			(placement
				(enabled no)
				(sheetname "")
			)
			(fill
				(thermal_gap 0.5)
				(thermal_bridge_width 0.5)
				(island_removal_mode 0)
			)
			(polygon
				(pts
					(xy 172.72 -87.503) (xy 172.212 -87.503) (xy 172.212 -87.122) (xy 172.72 -87.122)
				)
			)
		)
		(zone
			(layer "B.Cu")
			(hatch none 0.5)
			(connect_pads
				(clearance 0)
			)
			(min_thickness 0.25)
			(keepout
				(tracks not_allowed)
				(vias allowed)
				(pads allowed)
				(copperpour not_allowed)
				(footprints allowed)
			)
			(placement
				(enabled no)
				(sheetname "")
			)
			(fill
				(thermal_gap 0.5)
				(thermal_bridge_width 0.5)
				(island_removal_mode 0)
			)
			(polygon
				(pts
					(xy 172.72 -87.122) (xy 172.212 -87.122) (xy 172.212 -87.503) (xy 172.72 -87.503)
				)
			)
		)
	)
	(footprint ""
		(layer "B.Cu")
		(at 330.984606 -65.303908 -90)
		(property "Reference" "R4P20"
			(at 0 0 90)
			(layer "B.SilkS")
			(hide yes)
			(effects
				(font
					(size 1.27 1.27)
				)
				(justify mirror)
			)
		)
		(property "Value" ""
			(at 0 0 90)
			(layer "B.Fab")
			(effects
				(font
					(size 1.27 1.27)
				)
				(justify mirror)
			)
		)
		(duplicate_pad_numbers_are_jumpers no)
		(fp_poly
			(pts
				(xy 0.2794 -0.1016) (xy -0.2794 -0.1016) (xy -0.2794 0.9906) (xy 0.2794 0.9906)
			)
			(stroke
				(width 0)
				(type default)
			)
			(fill no)
			(layer "B.CrtYd")
		)
		(fp_line
			(start -0.2794 0.9906)
			(end -0.2794 -0.1016)
			(stroke
				(width 0.1)
				(type default)
			)
			(layer "B.Fab")
		)
		(fp_line
			(start 0.2794 0.9906)
			(end -0.2794 0.9906)
			(stroke
				(width 0.1)
				(type default)
			)
			(layer "B.Fab")
		)
		(fp_line
			(start -0.2794 -0.1016)
			(end 0.2794 -0.1016)
			(stroke
				(width 0.1)
				(type default)
			)
			(layer "B.Fab")
		)
		(fp_line
			(start 0.2794 -0.1016)
			(end 0.2794 0.9906)
			(stroke
				(width 0.1)
				(type default)
			)
			(layer "B.Fab")
		)
		(pad "1" smd rect
			(at 0 0 90)
			(size 0.508 0.508)
			(layers "B.Cu" "B.Mask" "B.Paste")
			(net "H_CPU0_MEMDEF_MEMHOT_G_N")
		)
		(pad "2" smd rect
			(at 0 0.889 90)
			(size 0.508 0.508)
			(layers "B.Cu" "B.Mask" "B.Paste")
			(net "PVCCIO_CPU0")
		)
		(zone
			(layer "B.Cu")
			(hatch none 0.5)
			(connect_pads
				(clearance 0)
			)
			(min_thickness 0.25)
			(keepout
				(tracks not_allowed)
				(vias allowed)
				(pads allowed)
				(copperpour not_allowed)
				(footprints allowed)
			)
			(placement
				(enabled no)
				(sheetname "")
			)
			(fill
				(thermal_gap 0.5)
				(thermal_bridge_width 0.5)
				(island_removal_mode 0)
			)
			(polygon
				(pts
					(xy 330.349606 -65.049908) (xy 330.349606 -65.557908) (xy 330.730606 -65.557908) (xy 330.730606 -65.049908)
				)
			)
		)
		(zone
			(layer "B.Cu")
			(hatch none 0.5)
			(connect_pads
				(clearance 0)
			)
			(min_thickness 0.25)
			(keepout
				(tracks allowed)
				(vias not_allowed)
				(pads allowed)
				(copperpour not_allowed)
				(footprints allowed)
			)
			(placement
				(enabled no)
				(sheetname "")
			)
			(fill
				(thermal_gap 0.5)
				(thermal_bridge_width 0.5)
				(island_removal_mode 0)
			)
			(polygon
				(pts
					(xy 330.730606 -65.049908) (xy 330.730606 -65.557908) (xy 330.349606 -65.557908) (xy 330.349606 -65.049908)
				)
			)
		)
	)
	(footprint ""
		(layer "B.Cu")
		(at 162.91306 -85.598 90)
		(property "Reference" "R7P1"
			(at 0 0 90)
			(layer "B.SilkS")
			(hide yes)
			(effects
				(font
					(size 1.27 1.27)
				)
				(justify mirror)
			)
		)
		(property "Value" ""
			(at 0 0 90)
			(layer "B.Fab")
			(effects
				(font
					(size 1.27 1.27)
				)
				(justify mirror)
			)
		)
		(duplicate_pad_numbers_are_jumpers no)
		(fp_poly
			(pts
				(xy 0.2794 -0.1016) (xy -0.2794 -0.1016) (xy -0.2794 0.9906) (xy 0.2794 0.9906)
			)
			(stroke
				(width 0)
				(type default)
			)
			(fill no)
			(layer "B.CrtYd")
		)
		(fp_line
			(start 0.2794 -0.1016)
			(end 0.2794 0.9906)
			(stroke
				(width 0.1)
				(type default)
			)
			(layer "B.Fab")
		)
		(fp_line
			(start -0.2794 -0.1016)
			(end 0.2794 -0.1016)
			(stroke
				(width 0.1)
				(type default)
			)
			(layer "B.Fab")
		)
		(fp_line
			(start 0.2794 0.9906)
			(end -0.2794 0.9906)
			(stroke
				(width 0.1)
				(type default)
			)
			(layer "B.Fab")
		)
		(fp_line
			(start -0.2794 0.9906)
			(end -0.2794 -0.1016)
			(stroke
				(width 0.1)
				(type default)
			)
			(layer "B.Fab")
		)
		(pad "1" smd rect
			(at 0 0 270)
			(size 0.508 0.508)
			(layers "B.Cu" "B.Mask" "B.Paste")
			(net "CLK_100M_CPU1_BCLK2_DP")
		)
		(pad "2" smd rect
			(at 0 0.889 270)
			(size 0.508 0.508)
			(layers "B.Cu" "B.Mask" "B.Paste")
			(net "GND")
		)
		(zone
			(layer "B.Cu")
			(hatch none 0.5)
			(connect_pads
				(clearance 0)
			)
			(min_thickness 0.25)
			(keepout
				(tracks allowed)
				(vias not_allowed)
				(pads allowed)
				(copperpour not_allowed)
				(footprints allowed)
			)
			(placement
				(enabled no)
				(sheetname "")
			)
			(fill
				(thermal_gap 0.5)
				(thermal_bridge_width 0.5)
				(island_removal_mode 0)
			)
			(polygon
				(pts
					(xy 163.16706 -85.852) (xy 163.16706 -85.344) (xy 163.54806 -85.344) (xy 163.54806 -85.852)
				)
			)
		)
		(zone
			(layer "B.Cu")
			(hatch none 0.5)
			(connect_pads
				(clearance 0)
			)
			(min_thickness 0.25)
			(keepout
				(tracks not_allowed)
				(vias allowed)
				(pads allowed)
				(copperpour not_allowed)
				(footprints allowed)
			)
			(placement
				(enabled no)
				(sheetname "")
			)
			(fill
				(thermal_gap 0.5)
				(thermal_bridge_width 0.5)
				(island_removal_mode 0)
			)
			(polygon
				(pts
					(xy 163.54806 -85.852) (xy 163.54806 -85.344) (xy 163.16706 -85.344) (xy 163.16706 -85.852)
				)
			)
		)
	)
	(footprint ""
		(layer "B.Cu")
		(at 404.0251 -29.337 90)
		(property "Reference" "R25W110"
			(at 0.8382 -0.67818 90)
			(unlocked yes)
			(layer "B.SilkS")
			(effects
				(font
					(size 0.4064 0.254)
					(thickness 0.1524)
				)
				(justify left mirror)
			)
		)
		(property "Value" ""
			(at 0 0 90)
			(layer "B.Fab")
			(effects
				(font
					(size 1.27 1.27)
				)
				(justify mirror)
			)
		)
		(duplicate_pad_numbers_are_jumpers no)
		(fp_poly
			(pts
				(xy 0.2794 -0.1016) (xy -0.2794 -0.1016) (xy -0.2794 0.9906) (xy 0.2794 0.9906)
			)
			(stroke
				(width 0)
				(type default)
			)
			(fill no)
			(layer "B.CrtYd")
		)
		(fp_line
			(start 0.2794 -0.1016)
			(end 0.2794 0.9906)
			(stroke
				(width 0.1)
				(type default)
			)
			(layer "B.Fab")
		)
		(fp_line
			(start -0.2794 -0.1016)
			(end 0.2794 -0.1016)
			(stroke
				(width 0.1)
				(type default)
			)
			(layer "B.Fab")
		)
		(fp_line
			(start 0.2794 0.9906)
			(end -0.2794 0.9906)
			(stroke
				(width 0.1)
				(type default)
			)
			(layer "B.Fab")
		)
		(fp_line
			(start -0.2794 0.9906)
			(end -0.2794 -0.1016)
			(stroke
				(width 0.1)
				(type default)
			)
			(layer "B.Fab")
		)
		(pad "1" smd rect
			(at 0 0 270)
			(size 0.508 0.508)
			(layers "B.Cu" "B.Mask" "B.Paste")
			(net "P3V3_STBY")
		)
		(pad "2" smd rect
			(at 0 0.889 270)
			(size 0.508 0.508)
			(layers "B.Cu" "B.Mask" "B.Paste")
			(net "TP_RGMII2TXD2_GPIOU2")
		)
		(zone
			(layer "B.Cu")
			(hatch none 0.5)
			(connect_pads
				(clearance 0)
			)
			(min_thickness 0.25)
			(keepout
				(tracks allowed)
				(vias not_allowed)
				(pads allowed)
				(copperpour not_allowed)
				(footprints allowed)
			)
			(placement
				(enabled no)
				(sheetname "")
			)
			(fill
				(thermal_gap 0.5)
				(thermal_bridge_width 0.5)
				(island_removal_mode 0)
			)
			(polygon
				(pts
					(xy 404.2791 -29.591) (xy 404.2791 -29.083) (xy 404.6601 -29.083) (xy 404.6601 -29.591)
				)
			)
		)
		(zone
			(layer "B.Cu")
			(hatch none 0.5)
			(connect_pads
				(clearance 0)
			)
			(min_thickness 0.25)
			(keepout
				(tracks not_allowed)
				(vias allowed)
				(pads allowed)
				(copperpour not_allowed)
				(footprints allowed)
			)
			(placement
				(enabled no)
				(sheetname "")
			)
			(fill
				(thermal_gap 0.5)
				(thermal_bridge_width 0.5)
				(island_removal_mode 0)
			)
			(polygon
				(pts
					(xy 404.6601 -29.591) (xy 404.6601 -29.083) (xy 404.2791 -29.083) (xy 404.2791 -29.591)
				)
			)
		)
	)
	(footprint ""
		(layer "B.Cu")
		(at 276.381464 -135.4074 90)
		(property "Reference" "C4M2"
			(at -1.848866 0.752348 90)
			(unlocked yes)
			(layer "B.SilkS")
			(effects
				(font
					(size 1.27 0.9652)
					(thickness 0.1524)
				)
				(justify mirror)
			)
		)
		(property "Value" ""
			(at 0 0 90)
			(layer "B.Fab")
			(effects
				(font
					(size 1.27 1.27)
				)
				(justify mirror)
			)
		)
		(duplicate_pad_numbers_are_jumpers no)
		(fp_rect
			(start 0.500126 1.598422)
			(end -0.500126 -0.201422)
			(stroke
				(width 0)
				(type default)
			)
			(fill no)
			(layer "B.CrtYd")
		)
		(fp_line
			(start 0.500126 -0.201422)
			(end -0.500126 -0.201422)
			(stroke
				(width 0.1)
				(type default)
			)
			(layer "B.Fab")
		)
		(fp_line
			(start -0.500126 -0.201422)
			(end -0.500126 1.598422)
			(stroke
				(width 0.1)
				(type default)
			)
			(layer "B.Fab")
		)
		(fp_line
			(start 0.500126 1.598422)
			(end 0.500126 -0.201422)
			(stroke
				(width 0.1)
				(type default)
			)
			(layer "B.Fab")
		)
		(fp_line
			(start -0.500126 1.598422)
			(end 0.500126 1.598422)
			(stroke
				(width 0.1)
				(type default)
			)
			(layer "B.Fab")
		)
		(pad "1" smd rect
			(at 0 0)
			(size 0.889 0.9906)
			(layers "B.Cu" "B.Mask" "B.Paste")
			(net "PVDDQ_DEF")
		)
		(pad "2" smd rect
			(at 0 1.397)
			(size 0.889 0.9906)
			(layers "B.Cu" "B.Mask" "B.Paste")
			(net "GND")
		)
		(zone
			(layer "B.Cu")
			(hatch none 0.5)
			(connect_pads
				(clearance 0)
			)
			(min_thickness 0.25)
			(keepout
				(tracks allowed)
				(vias not_allowed)
				(pads allowed)
				(copperpour not_allowed)
				(footprints allowed)
			)
			(placement
				(enabled no)
				(sheetname "")
			)
			(fill
				(thermal_gap 0.5)
				(thermal_bridge_width 0.5)
				(island_removal_mode 0)
			)
			(polygon
				(pts
					(xy 277.333964 -135.9027) (xy 276.825964 -135.9027) (xy 276.825964 -134.9121) (xy 277.333964 -134.9121)
				)
			)
		)
		(zone
			(layer "B.Cu")
			(hatch none 0.5)
			(connect_pads
				(clearance 0)
			)
			(min_thickness 0.25)
			(keepout
				(tracks not_allowed)
				(vias allowed)
				(pads allowed)
				(copperpour not_allowed)
				(footprints allowed)
			)
			(placement
				(enabled no)
				(sheetname "")
			)
			(fill
				(thermal_gap 0.5)
				(thermal_bridge_width 0.5)
				(island_removal_mode 0)
			)
			(polygon
				(pts
					(xy 277.333964 -135.9027) (xy 276.825964 -135.9027) (xy 276.825964 -134.9121) (xy 277.333964 -134.9121)
				)
			)
		)
	)
	(footprint ""
		(layer "B.Cu")
		(at 350.9772 -84.328 90)
		(property "Reference" "C3P3"
			(at 0 0 90)
			(layer "B.SilkS")
			(hide yes)
			(effects
				(font
					(size 1.27 1.27)
				)
				(justify mirror)
			)
		)
		(property "Value" ""
			(at 0 0 90)
			(layer "B.Fab")
			(effects
				(font
					(size 1.27 1.27)
				)
				(justify mirror)
			)
		)
		(duplicate_pad_numbers_are_jumpers no)
		(fp_poly
			(pts
				(xy -0.3048 -0.1016) (xy -0.3048 0.9906) (xy 0.3048 0.9906) (xy 0.3048 -0.1016)
			)
			(stroke
				(width 0)
				(type default)
			)
			(fill no)
			(layer "B.CrtYd")
		)
		(fp_line
			(start 0.3048 -0.1016)
			(end 0.3048 0.9906)
			(stroke
				(width 0.1)
				(type default)
			)
			(layer "B.Fab")
		)
		(fp_line
			(start -0.3048 -0.1016)
			(end 0.3048 -0.1016)
			(stroke
				(width 0.1)
				(type default)
			)
			(layer "B.Fab")
		)
		(fp_line
			(start 0.3048 0.9906)
			(end -0.3048 0.9906)
			(stroke
				(width 0.1)
				(type default)
			)
			(layer "B.Fab")
		)
		(fp_line
			(start -0.3048 0.9906)
			(end -0.3048 -0.1016)
			(stroke
				(width 0.1)
				(type default)
			)
			(layer "B.Fab")
		)
		(pad "1" smd rect
			(at 0 0 270)
			(size 0.508 0.508)
			(layers "B.Cu" "B.Mask" "B.Paste")
			(net "VR_PVCCIO_CPU0_VDD")
		)
		(pad "2" smd rect
			(at 0 0.889 270)
			(size 0.508 0.508)
			(layers "B.Cu" "B.Mask" "B.Paste")
			(net "GND")
		)
		(zone
			(layer "B.Cu")
			(hatch none 0.5)
			(connect_pads
				(clearance 0)
			)
			(min_thickness 0.25)
			(keepout
				(tracks allowed)
				(vias not_allowed)
				(pads allowed)
				(copperpour not_allowed)
				(footprints allowed)
			)
			(placement
				(enabled no)
				(sheetname "")
			)
			(fill
				(thermal_gap 0.5)
				(thermal_bridge_width 0.5)
				(island_removal_mode 0)
			)
			(polygon
				(pts
					(xy 351.2312 -84.582) (xy 351.2312 -84.074) (xy 351.6122 -84.074) (xy 351.6122 -84.582)
				)
			)
		)
		(zone
			(layer "B.Cu")
			(hatch none 0.5)
			(connect_pads
				(clearance 0)
			)
			(min_thickness 0.25)
			(keepout
				(tracks not_allowed)
				(vias allowed)
				(pads allowed)
				(copperpour not_allowed)
				(footprints allowed)
			)
			(placement
				(enabled no)
				(sheetname "")
			)
			(fill
				(thermal_gap 0.5)
				(thermal_bridge_width 0.5)
				(island_removal_mode 0)
			)
			(polygon
				(pts
					(xy 351.6122 -84.582) (xy 351.6122 -84.074) (xy 351.2312 -84.074) (xy 351.2312 -84.582)
				)
			)
		)
	)
	(footprint ""
		(layer "B.Cu")
		(at 415.442146 -39.735252 90)
		(property "Reference" "C25W47"
			(at -0.97536 0.76708 180)
			(unlocked yes)
			(layer "B.SilkS")
			(effects
				(font
					(size 0.4064 0.254)
					(thickness 0.1524)
				)
				(justify mirror)
			)
		)
		(property "Value" ""
			(at 0 0 90)
			(layer "B.Fab")
			(effects
				(font
					(size 1.27 1.27)
				)
				(justify mirror)
			)
		)
		(duplicate_pad_numbers_are_jumpers no)
		(fp_poly
			(pts
				(xy 0.4953 -0.2032) (xy -0.4953 -0.2032) (xy -0.4953 1.6002) (xy 0.4953 1.6002)
			)
			(stroke
				(width 0)
				(type default)
			)
			(fill no)
			(layer "B.CrtYd")
		)
		(fp_line
			(start 0.4953 -0.2032)
			(end -0.4953 -0.2032)
			(stroke
				(width 0.1)
				(type default)
			)
			(layer "B.Fab")
		)
		(fp_line
			(start -0.4953 -0.2032)
			(end -0.4953 1.6002)
			(stroke
				(width 0.1)
				(type default)
			)
			(layer "B.Fab")
		)
		(fp_line
			(start 0.4953 1.6002)
			(end 0.4953 -0.2032)
			(stroke
				(width 0.1)
				(type default)
			)
			(layer "B.Fab")
		)
		(fp_line
			(start -0.4953 1.6002)
			(end 0.4953 1.6002)
			(stroke
				(width 0.1)
				(type default)
			)
			(layer "B.Fab")
		)
		(pad "1" smd rect
			(at 0 0 270)
			(size 0.762 0.889)
			(layers "B.Cu" "B.Mask" "B.Paste")
			(net "VCC_D_3V3")
		)
		(pad "2" smd rect
			(at 0 1.397 270)
			(size 0.762 0.889)
			(layers "B.Cu" "B.Mask" "B.Paste")
			(net "GND")
		)
		(zone
			(layer "B.Cu")
			(hatch none 0.5)
			(connect_pads
				(clearance 0)
			)
			(min_thickness 0.25)
			(keepout
				(tracks not_allowed)
				(vias allowed)
				(pads allowed)
				(copperpour not_allowed)
				(footprints allowed)
			)
			(placement
				(enabled no)
				(sheetname "")
			)
			(fill
				(thermal_gap 0.5)
				(thermal_bridge_width 0.5)
				(island_removal_mode 0)
			)
			(polygon
				(pts
					(xy 415.886646 -40.116252) (xy 415.886646 -39.354252) (xy 416.394646 -39.354252) (xy 416.394646 -40.116252)
				)
			)
		)
	)
	(footprint ""
		(layer "B.Cu")
		(at 210.847432 -62.611 -90)
		(property "Reference" "C6R3"
			(at -2.64033 -3.528568 0)
			(unlocked yes)
			(layer "B.SilkS")
			(effects
				(font
					(size 0.7874 0.5842)
					(thickness 0.1524)
				)
				(justify mirror)
			)
		)
		(property "Value" ""
			(at 0 0 90)
			(layer "B.Fab")
			(effects
				(font
					(size 1.27 1.27)
				)
				(justify mirror)
			)
		)
		(duplicate_pad_numbers_are_jumpers no)
		(fp_line
			(start -2.286 7.366)
			(end -1.600708 7.366)
			(stroke
				(width 0.1524)
				(type default)
			)
			(layer "B.SilkS")
		)
		(fp_line
			(start -2.286 7.366)
			(end -2.286 1.63195)
			(stroke
				(width 0.1524)
				(type default)
			)
			(layer "B.SilkS")
		)
		(fp_line
			(start 2.286 7.366)
			(end 1.60147 7.366)
			(stroke
				(width 0.1524)
				(type default)
			)
			(layer "B.SilkS")
		)
		(fp_line
			(start 2.286 7.366)
			(end 2.286 1.632712)
			(stroke
				(width 0.1524)
				(type default)
			)
			(layer "B.SilkS")
		)
		(fp_line
			(start -2.504948 1.633728)
			(end -1.6002 1.633728)
			(stroke
				(width 0.1524)
				(type default)
			)
			(layer "B.SilkS")
		)
		(fp_line
			(start 2.563114 1.633728)
			(end 1.6002 1.633728)
			(stroke
				(width 0.1524)
				(type default)
			)
			(layer "B.SilkS")
		)
		(fp_line
			(start -2.504948 -1.616456)
			(end -2.504948 1.633728)
			(stroke
				(width 0.1524)
				(type default)
			)
			(layer "B.SilkS")
		)
		(fp_line
			(start -1.6002 -1.616456)
			(end -2.504948 -1.616456)
			(stroke
				(width 0.1524)
				(type default)
			)
			(layer "B.SilkS")
		)
		(fp_line
			(start 1.6002 -1.616456)
			(end 2.563114 -1.616456)
			(stroke
				(width 0.1524)
				(type default)
			)
			(layer "B.SilkS")
		)
		(fp_line
			(start 2.563114 -1.616456)
			(end 2.563114 1.633728)
			(stroke
				(width 0.1524)
				(type default)
			)
			(layer "B.SilkS")
		)
		(fp_rect
			(start 2.286 7.366)
			(end -2.286 -0.254)
			(stroke
				(width 0)
				(type default)
			)
			(fill no)
			(layer "B.CrtYd")
		)
		(fp_line
			(start -2.286 7.366)
			(end 2.286 7.366)
			(stroke
				(width 0.1)
				(type default)
			)
			(layer "B.Fab")
		)
		(fp_line
			(start 2.286 7.366)
			(end 2.286 -0.254)
			(stroke
				(width 0.1)
				(type default)
			)
			(layer "B.Fab")
		)
		(fp_line
			(start -2.286 -0.254)
			(end -2.286 7.366)
			(stroke
				(width 0.1)
				(type default)
			)
			(layer "B.Fab")
		)
		(fp_line
			(start 2.286 -0.254)
			(end -2.286 -0.254)
			(stroke
				(width 0.1)
				(type default)
			)
			(layer "B.Fab")
		)
		(pad "1" smd rect
			(at 0 0 90)
			(size 2.54 3.048)
			(layers "B.Cu" "B.Mask" "B.Paste")
			(net "PVCCIN_CPU0")
		)
		(pad "2" smd rect
			(at 0 7.112 90)
			(size 2.54 3.048)
			(layers "B.Cu" "B.Mask" "B.Paste")
			(net "GND")
		)
	)
	(footprint ""
		(layer "B.Cu")
		(at -3.09626 -118.78056 180)
		(property "Reference" "C9M8"
			(at 0 0 0)
			(layer "B.SilkS")
			(hide yes)
			(effects
				(font
					(size 1.27 1.27)
				)
				(justify mirror)
			)
		)
		(property "Value" ""
			(at 0 0 0)
			(layer "B.Fab")
			(effects
				(font
					(size 1.27 1.27)
				)
				(justify mirror)
			)
		)
		(duplicate_pad_numbers_are_jumpers no)
		(fp_rect
			(start 0.3048 -0.1016)
			(end -0.3048 0.9906)
			(stroke
				(width 0)
				(type default)
			)
			(fill no)
			(layer "B.CrtYd")
		)
		(fp_line
			(start 0.3048 0.9906)
			(end -0.3048 0.9906)
			(stroke
				(width 0.1)
				(type default)
			)
			(layer "B.Fab")
		)
		(fp_line
			(start 0.3048 -0.1016)
			(end 0.3048 0.9906)
			(stroke
				(width 0.1)
				(type default)
			)
			(layer "B.Fab")
		)
		(fp_line
			(start -0.3048 0.9906)
			(end -0.3048 -0.1016)
			(stroke
				(width 0.1)
				(type default)
			)
			(layer "B.Fab")
		)
		(fp_line
			(start -0.3048 -0.1016)
			(end 0.3048 -0.1016)
			(stroke
				(width 0.1)
				(type default)
			)
			(layer "B.Fab")
		)
		(pad "1" smd rect
			(at 0 0)
			(size 0.508 0.508)
			(layers "B.Cu" "B.Mask" "B.Paste")
			(net "PVCCIO_CPU1")
		)
		(pad "2" smd rect
			(at 0 0.889)
			(size 0.508 0.508)
			(layers "B.Cu" "B.Mask" "B.Paste")
			(net "GND")
		)
		(zone
			(layer "B.Cu")
			(hatch none 0.5)
			(connect_pads
				(clearance 0)
			)
			(min_thickness 0.25)
			(keepout
				(tracks allowed)
				(vias not_allowed)
				(pads allowed)
				(copperpour not_allowed)
				(footprints allowed)
			)
			(placement
				(enabled no)
				(sheetname "")
			)
			(fill
				(thermal_gap 0.5)
				(thermal_bridge_width 0.5)
				(island_removal_mode 0)
			)
			(polygon
				(pts
					(xy -3.35026 -119.03456) (xy -2.84226 -119.03456) (xy -2.84226 -119.41556) (xy -3.35026 -119.41556)
				)
			)
		)
		(zone
			(layer "B.Cu")
			(hatch none 0.5)
			(connect_pads
				(clearance 0)
			)
			(min_thickness 0.25)
			(keepout
				(tracks not_allowed)
				(vias allowed)
				(pads allowed)
				(copperpour not_allowed)
				(footprints allowed)
			)
			(placement
				(enabled no)
				(sheetname "")
			)
			(fill
				(thermal_gap 0.5)
				(thermal_bridge_width 0.5)
				(island_removal_mode 0)
			)
			(polygon
				(pts
					(xy -3.35026 -119.03456) (xy -2.84226 -119.03456) (xy -2.84226 -119.41556) (xy -3.35026 -119.41556)
				)
			)
		)
	)
	(footprint ""
		(layer "B.Cu")
		(at 385.2545 -54.61 90)
		(property "Reference" "R1U6"
			(at 0 0 90)
			(layer "B.SilkS")
			(hide yes)
			(effects
				(font
					(size 1.27 1.27)
				)
				(justify mirror)
			)
		)
		(property "Value" ""
			(at 0 0 90)
			(layer "B.Fab")
			(effects
				(font
					(size 1.27 1.27)
				)
				(justify mirror)
			)
		)
		(duplicate_pad_numbers_are_jumpers no)
		(fp_poly
			(pts
				(xy 0.2794 -0.1016) (xy -0.2794 -0.1016) (xy -0.2794 0.9906) (xy 0.2794 0.9906)
			)
			(stroke
				(width 0)
				(type default)
			)
			(fill no)
			(layer "B.CrtYd")
		)
		(fp_line
			(start 0.2794 -0.1016)
			(end 0.2794 0.9906)
			(stroke
				(width 0.1)
				(type default)
			)
			(layer "B.Fab")
		)
		(fp_line
			(start -0.2794 -0.1016)
			(end 0.2794 -0.1016)
			(stroke
				(width 0.1)
				(type default)
			)
			(layer "B.Fab")
		)
		(fp_line
			(start 0.2794 0.9906)
			(end -0.2794 0.9906)
			(stroke
				(width 0.1)
				(type default)
			)
			(layer "B.Fab")
		)
		(fp_line
			(start -0.2794 0.9906)
			(end -0.2794 -0.1016)
			(stroke
				(width 0.1)
				(type default)
			)
			(layer "B.Fab")
		)
		(pad "1" smd rect
			(at 0 0 270)
			(size 0.508 0.508)
			(layers "B.Cu" "B.Mask" "B.Paste")
			(net "FM_BIOS_SPI_BMC_CTRL")
		)
		(pad "2" smd rect
			(at 0 0.889 270)
			(size 0.508 0.508)
			(layers "B.Cu" "B.Mask" "B.Paste")
			(net "GND")
		)
		(zone
			(layer "B.Cu")
			(hatch none 0.5)
			(connect_pads
				(clearance 0)
			)
			(min_thickness 0.25)
			(keepout
				(tracks allowed)
				(vias not_allowed)
				(pads allowed)
				(copperpour not_allowed)
				(footprints allowed)
			)
			(placement
				(enabled no)
				(sheetname "")
			)
			(fill
				(thermal_gap 0.5)
				(thermal_bridge_width 0.5)
				(island_removal_mode 0)
			)
			(polygon
				(pts
					(xy 385.5085 -54.864) (xy 385.5085 -54.356) (xy 385.8895 -54.356) (xy 385.8895 -54.864)
				)
			)
		)
		(zone
			(layer "B.Cu")
			(hatch none 0.5)
			(connect_pads
				(clearance 0)
			)
			(min_thickness 0.25)
			(keepout
				(tracks not_allowed)
				(vias allowed)
				(pads allowed)
				(copperpour not_allowed)
				(footprints allowed)
			)
			(placement
				(enabled no)
				(sheetname "")
			)
			(fill
				(thermal_gap 0.5)
				(thermal_bridge_width 0.5)
				(island_removal_mode 0)
			)
			(polygon
				(pts
					(xy 385.8895 -54.864) (xy 385.8895 -54.356) (xy 385.5085 -54.356) (xy 385.5085 -54.864)
				)
			)
		)
	)
	(footprint ""
		(layer "B.Cu")
		(at 197.848728 -89.187782 90)
		(property "Reference" "C6N11"
			(at 0 0 90)
			(layer "B.SilkS")
			(hide yes)
			(effects
				(font
					(size 1.27 1.27)
				)
				(justify mirror)
			)
		)
		(property "Value" ""
			(at 0 0 90)
			(layer "B.Fab")
			(effects
				(font
					(size 1.27 1.27)
				)
				(justify mirror)
			)
		)
		(duplicate_pad_numbers_are_jumpers no)
		(fp_rect
			(start -0.7239 -0.2159)
			(end 0.7239 1.9939)
			(stroke
				(width 0)
				(type default)
			)
			(fill no)
			(layer "B.CrtYd")
		)
		(fp_line
			(start 0.7239 -0.2159)
			(end 0.7239 1.9939)
			(stroke
				(width 0.1)
				(type default)
			)
			(layer "B.Fab")
		)
		(fp_line
			(start -0.7239 -0.2159)
			(end 0.7239 -0.2159)
			(stroke
				(width 0.1)
				(type default)
			)
			(layer "B.Fab")
		)
		(fp_line
			(start 0.7239 1.9939)
			(end -0.7239 1.9939)
			(stroke
				(width 0.1)
				(type default)
			)
			(layer "B.Fab")
		)
		(fp_line
			(start -0.7239 1.9939)
			(end -0.7239 -0.2159)
			(stroke
				(width 0.1)
				(type default)
			)
			(layer "B.Fab")
		)
		(pad "1" smd rect
			(at 0 0 270)
			(size 1.27 1.016)
			(layers "B.Cu" "B.Mask" "B.Paste")
			(net "VR_FET_SW_P12V_STBY_PVCCIN_CPU0")
		)
		(pad "2" smd rect
			(at 0 1.778 270)
			(size 1.27 1.016)
			(layers "B.Cu" "B.Mask" "B.Paste")
			(net "GND")
		)
		(zone
			(layer "B.Cu")
			(hatch none 0.5)
			(connect_pads
				(clearance 0)
			)
			(min_thickness 0.25)
			(keepout
				(tracks not_allowed)
				(vias allowed)
				(pads allowed)
				(copperpour not_allowed)
				(footprints allowed)
			)
			(placement
				(enabled no)
				(sheetname "")
			)
			(fill
				(thermal_gap 0.5)
				(thermal_bridge_width 0.5)
				(island_removal_mode 0)
			)
			(polygon
				(pts
					(xy 198.356728 -88.552782) (xy 199.118728 -88.552782) (xy 199.118728 -89.822782) (xy 198.356728 -89.822782)
				)
			)
		)
	)
	(footprint ""
		(layer "B.Cu")
		(at 179.197 -56.769 -90)
		(property "Reference" "R6R5"
			(at 0 0 90)
			(layer "B.SilkS")
			(hide yes)
			(effects
				(font
					(size 1.27 1.27)
				)
				(justify mirror)
			)
		)
		(property "Value" ""
			(at 0 0 90)
			(layer "B.Fab")
			(effects
				(font
					(size 1.27 1.27)
				)
				(justify mirror)
			)
		)
		(duplicate_pad_numbers_are_jumpers no)
		(fp_poly
			(pts
				(xy 0.2794 -0.1016) (xy -0.2794 -0.1016) (xy -0.2794 0.9906) (xy 0.2794 0.9906)
			)
			(stroke
				(width 0)
				(type default)
			)
			(fill no)
			(layer "B.CrtYd")
		)
		(fp_line
			(start -0.2794 0.9906)
			(end -0.2794 -0.1016)
			(stroke
				(width 0.1)
				(type default)
			)
			(layer "B.Fab")
		)
		(fp_line
			(start 0.2794 0.9906)
			(end -0.2794 0.9906)
			(stroke
				(width 0.1)
				(type default)
			)
			(layer "B.Fab")
		)
		(fp_line
			(start -0.2794 -0.1016)
			(end 0.2794 -0.1016)
			(stroke
				(width 0.1)
				(type default)
			)
			(layer "B.Fab")
		)
		(fp_line
			(start 0.2794 -0.1016)
			(end 0.2794 0.9906)
			(stroke
				(width 0.1)
				(type default)
			)
			(layer "B.Fab")
		)
		(pad "1" smd rect
			(at 0 0 90)
			(size 0.508 0.508)
			(layers "B.Cu" "B.Mask" "B.Paste")
			(net "VR_PVCCIO_CPU1_PH1_VCIN")
		)
		(pad "2" smd rect
			(at 0 0.889 90)
			(size 0.508 0.508)
			(layers "B.Cu" "B.Mask" "B.Paste")
			(net "P5V_STBY")
		)
		(zone
			(layer "B.Cu")
			(hatch none 0.5)
			(connect_pads
				(clearance 0)
			)
			(min_thickness 0.25)
			(keepout
				(tracks not_allowed)
				(vias allowed)
				(pads allowed)
				(copperpour not_allowed)
				(footprints allowed)
			)
			(placement
				(enabled no)
				(sheetname "")
			)
			(fill
				(thermal_gap 0.5)
				(thermal_bridge_width 0.5)
				(island_removal_mode 0)
			)
			(polygon
				(pts
					(xy 178.562 -56.515) (xy 178.562 -57.023) (xy 178.943 -57.023) (xy 178.943 -56.515)
				)
			)
		)
		(zone
			(layer "B.Cu")
			(hatch none 0.5)
			(connect_pads
				(clearance 0)
			)
			(min_thickness 0.25)
			(keepout
				(tracks allowed)
				(vias not_allowed)
				(pads allowed)
				(copperpour not_allowed)
				(footprints allowed)
			)
			(placement
				(enabled no)
				(sheetname "")
			)
			(fill
				(thermal_gap 0.5)
				(thermal_bridge_width 0.5)
				(island_removal_mode 0)
			)
			(polygon
				(pts
					(xy 178.943 -56.515) (xy 178.943 -57.023) (xy 178.562 -57.023) (xy 178.562 -56.515)
				)
			)
		)
	)
	(footprint ""
		(layer "B.Cu")
		(at 160.4264 -122.1994)
		(property "Reference" "R7M5"
			(at 0 0 0)
			(layer "B.SilkS")
			(hide yes)
			(effects
				(font
					(size 1.27 1.27)
				)
				(justify mirror)
			)
		)
		(property "Value" ""
			(at 0 0 0)
			(layer "B.Fab")
			(effects
				(font
					(size 1.27 1.27)
				)
				(justify mirror)
			)
		)
		(duplicate_pad_numbers_are_jumpers no)
		(fp_poly
			(pts
				(xy 0.2794 -0.1016) (xy -0.2794 -0.1016) (xy -0.2794 0.9906) (xy 0.2794 0.9906)
			)
			(stroke
				(width 0)
				(type default)
			)
			(fill no)
			(layer "B.CrtYd")
		)
		(fp_line
			(start -0.2794 -0.1016)
			(end 0.2794 -0.1016)
			(stroke
				(width 0.1)
				(type default)
			)
			(layer "B.Fab")
		)
		(fp_line
			(start -0.2794 0.9906)
			(end -0.2794 -0.1016)
			(stroke
				(width 0.1)
				(type default)
			)
			(layer "B.Fab")
		)
		(fp_line
			(start 0.2794 -0.1016)
			(end 0.2794 0.9906)
			(stroke
				(width 0.1)
				(type default)
			)
			(layer "B.Fab")
		)
		(fp_line
			(start 0.2794 0.9906)
			(end -0.2794 0.9906)
			(stroke
				(width 0.1)
				(type default)
			)
			(layer "B.Fab")
		)
		(pad "1" smd rect
			(at 0 0 180)
			(size 0.508 0.508)
			(layers "B.Cu" "B.Mask" "B.Paste")
			(net "SMB_DDR_KLM_VPP_SDA_R")
		)
		(pad "2" smd rect
			(at 0 0.889 180)
			(size 0.508 0.508)
			(layers "B.Cu" "B.Mask" "B.Paste")
			(net "SMB_DDR_KLM_VPP_SDA")
		)
		(zone
			(layer "B.Cu")
			(hatch none 0.5)
			(connect_pads
				(clearance 0)
			)
			(min_thickness 0.25)
			(keepout
				(tracks allowed)
				(vias not_allowed)
				(pads allowed)
				(copperpour not_allowed)
				(footprints allowed)
			)
			(placement
				(enabled no)
				(sheetname "")
			)
			(fill
				(thermal_gap 0.5)
				(thermal_bridge_width 0.5)
				(island_removal_mode 0)
			)
			(polygon
				(pts
					(xy 160.6804 -121.9454) (xy 160.1724 -121.9454) (xy 160.1724 -121.5644) (xy 160.6804 -121.5644)
				)
			)
		)
		(zone
			(layer "B.Cu")
			(hatch none 0.5)
			(connect_pads
				(clearance 0)
			)
			(min_thickness 0.25)
			(keepout
				(tracks not_allowed)
				(vias allowed)
				(pads allowed)
				(copperpour not_allowed)
				(footprints allowed)
			)
			(placement
				(enabled no)
				(sheetname "")
			)
			(fill
				(thermal_gap 0.5)
				(thermal_bridge_width 0.5)
				(island_removal_mode 0)
			)
			(polygon
				(pts
					(xy 160.6804 -121.5644) (xy 160.1724 -121.5644) (xy 160.1724 -121.9454) (xy 160.6804 -121.9454)
				)
			)
		)
	)
	(footprint ""
		(layer "B.Cu")
		(at 248.8565 -145.0086 -90)
		(property "Reference" "C5L12"
			(at -1.848866 0.752348 270)
			(unlocked yes)
			(layer "B.SilkS")
			(effects
				(font
					(size 1.27 0.9652)
					(thickness 0.1524)
				)
				(justify mirror)
			)
		)
		(property "Value" ""
			(at 0 0 90)
			(layer "B.Fab")
			(effects
				(font
					(size 1.27 1.27)
				)
				(justify mirror)
			)
		)
		(duplicate_pad_numbers_are_jumpers no)
		(fp_rect
			(start 0.500126 1.598422)
			(end -0.500126 -0.201422)
			(stroke
				(width 0)
				(type default)
			)
			(fill no)
			(layer "B.CrtYd")
		)
		(fp_line
			(start -0.500126 1.598422)
			(end 0.500126 1.598422)
			(stroke
				(width 0.1)
				(type default)
			)
			(layer "B.Fab")
		)
		(fp_line
			(start 0.500126 1.598422)
			(end 0.500126 -0.201422)
			(stroke
				(width 0.1)
				(type default)
			)
			(layer "B.Fab")
		)
		(fp_line
			(start -0.500126 -0.201422)
			(end -0.500126 1.598422)
			(stroke
				(width 0.1)
				(type default)
			)
			(layer "B.Fab")
		)
		(fp_line
			(start 0.500126 -0.201422)
			(end -0.500126 -0.201422)
			(stroke
				(width 0.1)
				(type default)
			)
			(layer "B.Fab")
		)
		(pad "1" smd rect
			(at 0 0 180)
			(size 0.889 0.9906)
			(layers "B.Cu" "B.Mask" "B.Paste")
			(net "PVDDQ_DEF")
		)
		(pad "2" smd rect
			(at 0 1.397 180)
			(size 0.889 0.9906)
			(layers "B.Cu" "B.Mask" "B.Paste")
			(net "GND")
		)
		(zone
			(layer "B.Cu")
			(hatch none 0.5)
			(connect_pads
				(clearance 0)
			)
			(min_thickness 0.25)
			(keepout
				(tracks not_allowed)
				(vias allowed)
				(pads allowed)
				(copperpour not_allowed)
				(footprints allowed)
			)
			(placement
				(enabled no)
				(sheetname "")
			)
			(fill
				(thermal_gap 0.5)
				(thermal_bridge_width 0.5)
				(island_removal_mode 0)
			)
			(polygon
				(pts
					(xy 247.904 -144.5133) (xy 248.412 -144.5133) (xy 248.412 -145.5039) (xy 247.904 -145.5039)
				)
			)
		)
		(zone
			(layer "B.Cu")
			(hatch none 0.5)
			(connect_pads
				(clearance 0)
			)
			(min_thickness 0.25)
			(keepout
				(tracks allowed)
				(vias not_allowed)
				(pads allowed)
				(copperpour not_allowed)
				(footprints allowed)
			)
			(placement
				(enabled no)
				(sheetname "")
			)
			(fill
				(thermal_gap 0.5)
				(thermal_bridge_width 0.5)
				(island_removal_mode 0)
			)
			(polygon
				(pts
					(xy 247.904 -144.5133) (xy 248.412 -144.5133) (xy 248.412 -145.5039) (xy 247.904 -145.5039)
				)
			)
		)
	)
	(footprint ""
		(layer "B.Cu")
		(at 359.8672 -4.2418 180)
		(property "Reference" "R8W10"
			(at 0.8382 -0.67818 180)
			(unlocked yes)
			(layer "B.SilkS")
			(effects
				(font
					(size 0.4064 0.254)
					(thickness 0.1524)
				)
				(justify left mirror)
			)
		)
		(property "Value" ""
			(at 0 0 0)
			(layer "B.Fab")
			(effects
				(font
					(size 1.27 1.27)
				)
				(justify mirror)
			)
		)
		(duplicate_pad_numbers_are_jumpers no)
		(fp_poly
			(pts
				(xy 0.2794 -0.1016) (xy -0.2794 -0.1016) (xy -0.2794 0.9906) (xy 0.2794 0.9906)
			)
			(stroke
				(width 0)
				(type default)
			)
			(fill no)
			(layer "B.CrtYd")
		)
		(fp_line
			(start 0.2794 0.9906)
			(end -0.2794 0.9906)
			(stroke
				(width 0.1)
				(type default)
			)
			(layer "B.Fab")
		)
		(fp_line
			(start 0.2794 -0.1016)
			(end 0.2794 0.9906)
			(stroke
				(width 0.1)
				(type default)
			)
			(layer "B.Fab")
		)
		(fp_line
			(start -0.2794 0.9906)
			(end -0.2794 -0.1016)
			(stroke
				(width 0.1)
				(type default)
			)
			(layer "B.Fab")
		)
		(fp_line
			(start -0.2794 -0.1016)
			(end 0.2794 -0.1016)
			(stroke
				(width 0.1)
				(type default)
			)
			(layer "B.Fab")
		)
		(pad "1" smd rect
			(at 0 0)
			(size 0.508 0.508)
			(layers "B.Cu" "B.Mask" "B.Paste")
			(net "JTAG_RISER_TMS")
		)
		(pad "2" smd rect
			(at 0 0.889)
			(size 0.508 0.508)
			(layers "B.Cu" "B.Mask" "B.Paste")
			(net "JTAG_PLD_TMS_MUX")
		)
		(zone
			(layer "B.Cu")
			(hatch none 0.5)
			(connect_pads
				(clearance 0)
			)
			(min_thickness 0.25)
			(keepout
				(tracks not_allowed)
				(vias allowed)
				(pads allowed)
				(copperpour not_allowed)
				(footprints allowed)
			)
			(placement
				(enabled no)
				(sheetname "")
			)
			(fill
				(thermal_gap 0.5)
				(thermal_bridge_width 0.5)
				(island_removal_mode 0)
			)
			(polygon
				(pts
					(xy 359.6132 -4.8768) (xy 360.1212 -4.8768) (xy 360.1212 -4.4958) (xy 359.6132 -4.4958)
				)
			)
		)
		(zone
			(layer "B.Cu")
			(hatch none 0.5)
			(connect_pads
				(clearance 0)
			)
			(min_thickness 0.25)
			(keepout
				(tracks allowed)
				(vias not_allowed)
				(pads allowed)
				(copperpour not_allowed)
				(footprints allowed)
			)
			(placement
				(enabled no)
				(sheetname "")
			)
			(fill
				(thermal_gap 0.5)
				(thermal_bridge_width 0.5)
				(island_removal_mode 0)
			)
			(polygon
				(pts
					(xy 359.6132 -4.4958) (xy 360.1212 -4.4958) (xy 360.1212 -4.8768) (xy 359.6132 -4.8768)
				)
			)
		)
	)
	(footprint ""
		(layer "B.Cu")
		(at 214.581232 -98.1202)
		(property "Reference" "R6N4"
			(at 0 0 0)
			(layer "B.SilkS")
			(hide yes)
			(effects
				(font
					(size 1.27 1.27)
				)
				(justify mirror)
			)
		)
		(property "Value" ""
			(at 0 0 0)
			(layer "B.Fab")
			(effects
				(font
					(size 1.27 1.27)
				)
				(justify mirror)
			)
		)
		(duplicate_pad_numbers_are_jumpers no)
		(fp_poly
			(pts
				(xy 0.2794 -0.1016) (xy -0.2794 -0.1016) (xy -0.2794 0.9906) (xy 0.2794 0.9906)
			)
			(stroke
				(width 0)
				(type default)
			)
			(fill no)
			(layer "B.CrtYd")
		)
		(fp_line
			(start -0.2794 -0.1016)
			(end 0.2794 -0.1016)
			(stroke
				(width 0.1)
				(type default)
			)
			(layer "B.Fab")
		)
		(fp_line
			(start -0.2794 0.9906)
			(end -0.2794 -0.1016)
			(stroke
				(width 0.1)
				(type default)
			)
			(layer "B.Fab")
		)
		(fp_line
			(start 0.2794 -0.1016)
			(end 0.2794 0.9906)
			(stroke
				(width 0.1)
				(type default)
			)
			(layer "B.Fab")
		)
		(fp_line
			(start 0.2794 0.9906)
			(end -0.2794 0.9906)
			(stroke
				(width 0.1)
				(type default)
			)
			(layer "B.Fab")
		)
		(pad "1" smd rect
			(at 0 0 180)
			(size 0.508 0.508)
			(layers "B.Cu" "B.Mask" "B.Paste")
			(net "PVSA_CPU0")
		)
		(pad "2" smd rect
			(at 0 0.889 180)
			(size 0.508 0.508)
			(layers "B.Cu" "B.Mask" "B.Paste")
			(net "GND")
		)
		(zone
			(layer "B.Cu")
			(hatch none 0.5)
			(connect_pads
				(clearance 0)
			)
			(min_thickness 0.25)
			(keepout
				(tracks allowed)
				(vias not_allowed)
				(pads allowed)
				(copperpour not_allowed)
				(footprints allowed)
			)
			(placement
				(enabled no)
				(sheetname "")
			)
			(fill
				(thermal_gap 0.5)
				(thermal_bridge_width 0.5)
				(island_removal_mode 0)
			)
			(polygon
				(pts
					(xy 214.835232 -97.8662) (xy 214.327232 -97.8662) (xy 214.327232 -97.4852) (xy 214.835232 -97.4852)
				)
			)
		)
		(zone
			(layer "B.Cu")
			(hatch none 0.5)
			(connect_pads
				(clearance 0)
			)
			(min_thickness 0.25)
			(keepout
				(tracks not_allowed)
				(vias allowed)
				(pads allowed)
				(copperpour not_allowed)
				(footprints allowed)
			)
			(placement
				(enabled no)
				(sheetname "")
			)
			(fill
				(thermal_gap 0.5)
				(thermal_bridge_width 0.5)
				(island_removal_mode 0)
			)
			(polygon
				(pts
					(xy 214.835232 -97.4852) (xy 214.327232 -97.4852) (xy 214.327232 -97.8662) (xy 214.835232 -97.8662)
				)
			)
		)
	)
	(footprint ""
		(layer "B.Cu")
		(at 317.72606 -125.42774 180)
		(property "Reference" "R3R8"
			(at 0 0 0)
			(layer "B.SilkS")
			(hide yes)
			(effects
				(font
					(size 1.27 1.27)
				)
				(justify mirror)
			)
		)
		(property "Value" ""
			(at 0 0 0)
			(layer "B.Fab")
			(effects
				(font
					(size 1.27 1.27)
				)
				(justify mirror)
			)
		)
		(duplicate_pad_numbers_are_jumpers no)
		(fp_poly
			(pts
				(xy 0.2794 -0.1016) (xy -0.2794 -0.1016) (xy -0.2794 0.9906) (xy 0.2794 0.9906)
			)
			(stroke
				(width 0)
				(type default)
			)
			(fill no)
			(layer "B.CrtYd")
		)
		(fp_line
			(start 0.2794 0.9906)
			(end -0.2794 0.9906)
			(stroke
				(width 0.1)
				(type default)
			)
			(layer "B.Fab")
		)
		(fp_line
			(start 0.2794 -0.1016)
			(end 0.2794 0.9906)
			(stroke
				(width 0.1)
				(type default)
			)
			(layer "B.Fab")
		)
		(fp_line
			(start -0.2794 0.9906)
			(end -0.2794 -0.1016)
			(stroke
				(width 0.1)
				(type default)
			)
			(layer "B.Fab")
		)
		(fp_line
			(start -0.2794 -0.1016)
			(end 0.2794 -0.1016)
			(stroke
				(width 0.1)
				(type default)
			)
			(layer "B.Fab")
		)
		(pad "1" smd rect
			(at 0 0)
			(size 0.508 0.508)
			(layers "B.Cu" "B.Mask" "B.Paste")
			(net "SMB_DDR_DEF_VPP_SCL_R")
		)
		(pad "2" smd rect
			(at 0 0.889)
			(size 0.508 0.508)
			(layers "B.Cu" "B.Mask" "B.Paste")
			(net "SMB_DDR_DEF_VPP_SCL")
		)
		(zone
			(layer "B.Cu")
			(hatch none 0.5)
			(connect_pads
				(clearance 0)
			)
			(min_thickness 0.25)
			(keepout
				(tracks not_allowed)
				(vias allowed)
				(pads allowed)
				(copperpour not_allowed)
				(footprints allowed)
			)
			(placement
				(enabled no)
				(sheetname "")
			)
			(fill
				(thermal_gap 0.5)
				(thermal_bridge_width 0.5)
				(island_removal_mode 0)
			)
			(polygon
				(pts
					(xy 317.47206 -126.06274) (xy 317.98006 -126.06274) (xy 317.98006 -125.68174) (xy 317.47206 -125.68174)
				)
			)
		)
		(zone
			(layer "B.Cu")
			(hatch none 0.5)
			(connect_pads
				(clearance 0)
			)
			(min_thickness 0.25)
			(keepout
				(tracks allowed)
				(vias not_allowed)
				(pads allowed)
				(copperpour not_allowed)
				(footprints allowed)
			)
			(placement
				(enabled no)
				(sheetname "")
			)
			(fill
				(thermal_gap 0.5)
				(thermal_bridge_width 0.5)
				(island_removal_mode 0)
			)
			(polygon
				(pts
					(xy 317.47206 -125.68174) (xy 317.98006 -125.68174) (xy 317.98006 -126.06274) (xy 317.47206 -126.06274)
				)
			)
		)
	)
	(footprint ""
		(layer "B.Cu")
		(at 382.782826 -72.058276 -90)
		(property "Reference" "R7E19"
			(at 0 0 90)
			(layer "B.SilkS")
			(hide yes)
			(effects
				(font
					(size 1.27 1.27)
				)
				(justify mirror)
			)
		)
		(property "Value" ""
			(at 0 0 90)
			(layer "B.Fab")
			(effects
				(font
					(size 1.27 1.27)
				)
				(justify mirror)
			)
		)
		(duplicate_pad_numbers_are_jumpers no)
		(fp_poly
			(pts
				(xy 0.2794 -0.1016) (xy -0.2794 -0.1016) (xy -0.2794 0.9906) (xy 0.2794 0.9906)
			)
			(stroke
				(width 0)
				(type default)
			)
			(fill no)
			(layer "B.CrtYd")
		)
		(fp_line
			(start -0.2794 0.9906)
			(end -0.2794 -0.1016)
			(stroke
				(width 0.1)
				(type default)
			)
			(layer "B.Fab")
		)
		(fp_line
			(start 0.2794 0.9906)
			(end -0.2794 0.9906)
			(stroke
				(width 0.1)
				(type default)
			)
			(layer "B.Fab")
		)
		(fp_line
			(start -0.2794 -0.1016)
			(end 0.2794 -0.1016)
			(stroke
				(width 0.1)
				(type default)
			)
			(layer "B.Fab")
		)
		(fp_line
			(start 0.2794 -0.1016)
			(end 0.2794 0.9906)
			(stroke
				(width 0.1)
				(type default)
			)
			(layer "B.Fab")
		)
		(pad "1" smd rect
			(at 0 0 90)
			(size 0.508 0.508)
			(layers "B.Cu" "B.Mask" "B.Paste")
			(net "P3V3_STBY")
		)
		(pad "2" smd rect
			(at 0 0.889 90)
			(size 0.508 0.508)
			(layers "B.Cu" "B.Mask" "B.Paste")
			(net "FM_MEM_EVENT_FUNC")
		)
		(zone
			(layer "B.Cu")
			(hatch none 0.5)
			(connect_pads
				(clearance 0)
			)
			(min_thickness 0.25)
			(keepout
				(tracks not_allowed)
				(vias allowed)
				(pads allowed)
				(copperpour not_allowed)
				(footprints allowed)
			)
			(placement
				(enabled no)
				(sheetname "")
			)
			(fill
				(thermal_gap 0.5)
				(thermal_bridge_width 0.5)
				(island_removal_mode 0)
			)
			(polygon
				(pts
					(xy 382.147826 -71.804276) (xy 382.147826 -72.312276) (xy 382.528826 -72.312276) (xy 382.528826 -71.804276)
				)
			)
		)
		(zone
			(layer "B.Cu")
			(hatch none 0.5)
			(connect_pads
				(clearance 0)
			)
			(min_thickness 0.25)
			(keepout
				(tracks allowed)
				(vias not_allowed)
				(pads allowed)
				(copperpour not_allowed)
				(footprints allowed)
			)
			(placement
				(enabled no)
				(sheetname "")
			)
			(fill
				(thermal_gap 0.5)
				(thermal_bridge_width 0.5)
				(island_removal_mode 0)
			)
			(polygon
				(pts
					(xy 382.528826 -71.804276) (xy 382.528826 -72.312276) (xy 382.147826 -72.312276) (xy 382.147826 -71.804276)
				)
			)
		)
	)
	(footprint ""
		(layer "B.Cu")
		(at 173.863 -80.645 -90)
		(property "Reference" "C6P11"
			(at 0 0 90)
			(layer "B.SilkS")
			(hide yes)
			(effects
				(font
					(size 1.27 1.27)
				)
				(justify mirror)
			)
		)
		(property "Value" ""
			(at 0 0 90)
			(layer "B.Fab")
			(effects
				(font
					(size 1.27 1.27)
				)
				(justify mirror)
			)
		)
		(duplicate_pad_numbers_are_jumpers no)
		(fp_poly
			(pts
				(xy -0.3048 -0.1016) (xy -0.3048 0.9906) (xy 0.3048 0.9906) (xy 0.3048 -0.1016)
			)
			(stroke
				(width 0)
				(type default)
			)
			(fill no)
			(layer "B.CrtYd")
		)
		(fp_line
			(start -0.3048 0.9906)
			(end -0.3048 -0.1016)
			(stroke
				(width 0.1)
				(type default)
			)
			(layer "B.Fab")
		)
		(fp_line
			(start 0.3048 0.9906)
			(end -0.3048 0.9906)
			(stroke
				(width 0.1)
				(type default)
			)
			(layer "B.Fab")
		)
		(fp_line
			(start -0.3048 -0.1016)
			(end 0.3048 -0.1016)
			(stroke
				(width 0.1)
				(type default)
			)
			(layer "B.Fab")
		)
		(fp_line
			(start 0.3048 -0.1016)
			(end 0.3048 0.9906)
			(stroke
				(width 0.1)
				(type default)
			)
			(layer "B.Fab")
		)
		(pad "1" smd rect
			(at 0 0 90)
			(size 0.508 0.508)
			(layers "B.Cu" "B.Mask" "B.Paste")
			(net "P3V3_DB1200")
		)
		(pad "2" smd rect
			(at 0 0.889 90)
			(size 0.508 0.508)
			(layers "B.Cu" "B.Mask" "B.Paste")
			(net "GND")
		)
		(zone
			(layer "B.Cu")
			(hatch none 0.5)
			(connect_pads
				(clearance 0)
			)
			(min_thickness 0.25)
			(keepout
				(tracks not_allowed)
				(vias allowed)
				(pads allowed)
				(copperpour not_allowed)
				(footprints allowed)
			)
			(placement
				(enabled no)
				(sheetname "")
			)
			(fill
				(thermal_gap 0.5)
				(thermal_bridge_width 0.5)
				(island_removal_mode 0)
			)
			(polygon
				(pts
					(xy 173.228 -80.391) (xy 173.228 -80.899) (xy 173.609 -80.899) (xy 173.609 -80.391)
				)
			)
		)
		(zone
			(layer "B.Cu")
			(hatch none 0.5)
			(connect_pads
				(clearance 0)
			)
			(min_thickness 0.25)
			(keepout
				(tracks allowed)
				(vias not_allowed)
				(pads allowed)
				(copperpour not_allowed)
				(footprints allowed)
			)
			(placement
				(enabled no)
				(sheetname "")
			)
			(fill
				(thermal_gap 0.5)
				(thermal_bridge_width 0.5)
				(island_removal_mode 0)
			)
			(polygon
				(pts
					(xy 173.609 -80.391) (xy 173.609 -80.899) (xy 173.228 -80.899) (xy 173.228 -80.391)
				)
			)
		)
	)
	(footprint ""
		(layer "B.Cu")
		(at 489.65739 -147.193 90)
		(property "Reference" "R1L14"
			(at 0 0 90)
			(layer "B.SilkS")
			(hide yes)
			(effects
				(font
					(size 1.27 1.27)
				)
				(justify mirror)
			)
		)
		(property "Value" ""
			(at 0 0 90)
			(layer "B.Fab")
			(effects
				(font
					(size 1.27 1.27)
				)
				(justify mirror)
			)
		)
		(duplicate_pad_numbers_are_jumpers no)
		(fp_poly
			(pts
				(xy 0.2794 -0.1016) (xy -0.2794 -0.1016) (xy -0.2794 0.9906) (xy 0.2794 0.9906)
			)
			(stroke
				(width 0)
				(type default)
			)
			(fill no)
			(layer "B.CrtYd")
		)
		(fp_line
			(start 0.2794 -0.1016)
			(end 0.2794 0.9906)
			(stroke
				(width 0.1)
				(type default)
			)
			(layer "B.Fab")
		)
		(fp_line
			(start -0.2794 -0.1016)
			(end 0.2794 -0.1016)
			(stroke
				(width 0.1)
				(type default)
			)
			(layer "B.Fab")
		)
		(fp_line
			(start 0.2794 0.9906)
			(end -0.2794 0.9906)
			(stroke
				(width 0.1)
				(type default)
			)
			(layer "B.Fab")
		)
		(fp_line
			(start -0.2794 0.9906)
			(end -0.2794 -0.1016)
			(stroke
				(width 0.1)
				(type default)
			)
			(layer "B.Fab")
		)
		(pad "1" smd rect
			(at 0 0 270)
			(size 0.508 0.508)
			(layers "B.Cu" "B.Mask" "B.Paste")
			(net "LED_POSTCODE_6")
		)
		(pad "2" smd rect
			(at 0 0.889 270)
			(size 0.508 0.508)
			(layers "B.Cu" "B.Mask" "B.Paste")
			(net "LED_POSTCODE_6_R")
		)
		(zone
			(layer "B.Cu")
			(hatch none 0.5)
			(connect_pads
				(clearance 0)
			)
			(min_thickness 0.25)
			(keepout
				(tracks allowed)
				(vias not_allowed)
				(pads allowed)
				(copperpour not_allowed)
				(footprints allowed)
			)
			(placement
				(enabled no)
				(sheetname "")
			)
			(fill
				(thermal_gap 0.5)
				(thermal_bridge_width 0.5)
				(island_removal_mode 0)
			)
			(polygon
				(pts
					(xy 489.91139 -147.447) (xy 489.91139 -146.939) (xy 490.29239 -146.939) (xy 490.29239 -147.447)
				)
			)
		)
		(zone
			(layer "B.Cu")
			(hatch none 0.5)
			(connect_pads
				(clearance 0)
			)
			(min_thickness 0.25)
			(keepout
				(tracks not_allowed)
				(vias allowed)
				(pads allowed)
				(copperpour not_allowed)
				(footprints allowed)
			)
			(placement
				(enabled no)
				(sheetname "")
			)
			(fill
				(thermal_gap 0.5)
				(thermal_bridge_width 0.5)
				(island_removal_mode 0)
			)
			(polygon
				(pts
					(xy 490.29239 -147.447) (xy 490.29239 -146.939) (xy 489.91139 -146.939) (xy 489.91139 -147.447)
				)
			)
		)
	)
	(footprint ""
		(layer "B.Cu")
		(at 400.43608 -141.224 180)
		(property "Reference" "C7B16"
			(at 0 0 0)
			(layer "B.SilkS")
			(hide yes)
			(effects
				(font
					(size 1.27 1.27)
				)
				(justify mirror)
			)
		)
		(property "Value" ""
			(at 0 0 0)
			(layer "B.Fab")
			(effects
				(font
					(size 1.27 1.27)
				)
				(justify mirror)
			)
		)
		(duplicate_pad_numbers_are_jumpers no)
		(fp_rect
			(start 0.4953 1.6002)
			(end -0.4953 -0.2032)
			(stroke
				(width 0)
				(type default)
			)
			(fill no)
			(layer "B.CrtYd")
		)
		(fp_line
			(start 0.4953 1.6002)
			(end 0.4953 -0.2032)
			(stroke
				(width 0.1)
				(type default)
			)
			(layer "B.Fab")
		)
		(fp_line
			(start 0.4953 -0.2032)
			(end -0.4953 -0.2032)
			(stroke
				(width 0.1)
				(type default)
			)
			(layer "B.Fab")
		)
		(fp_line
			(start -0.4953 1.6002)
			(end 0.4953 1.6002)
			(stroke
				(width 0.1)
				(type default)
			)
			(layer "B.Fab")
		)
		(fp_line
			(start -0.4953 -0.2032)
			(end -0.4953 1.6002)
			(stroke
				(width 0.1)
				(type default)
			)
			(layer "B.Fab")
		)
		(pad "1" smd rect
			(at 0 0)
			(size 0.762 0.889)
			(layers "B.Cu" "B.Mask" "B.Paste")
			(net "P1V05_PCH_STBY")
		)
		(pad "2" smd rect
			(at 0 1.397)
			(size 0.762 0.889)
			(layers "B.Cu" "B.Mask" "B.Paste")
			(net "GND")
		)
		(zone
			(layer "B.Cu")
			(hatch none 0.5)
			(connect_pads
				(clearance 0)
			)
			(min_thickness 0.25)
			(keepout
				(tracks not_allowed)
				(vias allowed)
				(pads allowed)
				(copperpour not_allowed)
				(footprints allowed)
			)
			(placement
				(enabled no)
				(sheetname "")
			)
			(fill
				(thermal_gap 0.5)
				(thermal_bridge_width 0.5)
				(island_removal_mode 0)
			)
			(polygon
				(pts
					(xy 400.05508 -142.1765) (xy 400.05508 -141.6685) (xy 400.81708 -141.6685) (xy 400.81708 -142.1765)
				)
			)
		)
	)
	(footprint ""
		(layer "B.Cu")
		(at 117.221 -77.978 -90)
		(property "Reference" "R7P10"
			(at 0 0 90)
			(layer "B.SilkS")
			(hide yes)
			(effects
				(font
					(size 1.27 1.27)
				)
				(justify mirror)
			)
		)
		(property "Value" ""
			(at 0 0 90)
			(layer "B.Fab")
			(effects
				(font
					(size 1.27 1.27)
				)
				(justify mirror)
			)
		)
		(duplicate_pad_numbers_are_jumpers no)
		(fp_poly
			(pts
				(xy 0.2794 -0.1016) (xy -0.2794 -0.1016) (xy -0.2794 0.9906) (xy 0.2794 0.9906)
			)
			(stroke
				(width 0)
				(type default)
			)
			(fill no)
			(layer "B.CrtYd")
		)
		(fp_line
			(start -0.2794 0.9906)
			(end -0.2794 -0.1016)
			(stroke
				(width 0.1)
				(type default)
			)
			(layer "B.Fab")
		)
		(fp_line
			(start 0.2794 0.9906)
			(end -0.2794 0.9906)
			(stroke
				(width 0.1)
				(type default)
			)
			(layer "B.Fab")
		)
		(fp_line
			(start -0.2794 -0.1016)
			(end 0.2794 -0.1016)
			(stroke
				(width 0.1)
				(type default)
			)
			(layer "B.Fab")
		)
		(fp_line
			(start 0.2794 -0.1016)
			(end 0.2794 0.9906)
			(stroke
				(width 0.1)
				(type default)
			)
			(layer "B.Fab")
		)
		(pad "1" smd rect
			(at 0 0 90)
			(size 0.508 0.508)
			(layers "B.Cu" "B.Mask" "B.Paste")
			(net "A_CPU1_PE012_RBIAS")
		)
		(pad "2" smd rect
			(at 0 0.889 90)
			(size 0.508 0.508)
			(layers "B.Cu" "B.Mask" "B.Paste")
			(net "GND")
		)
		(zone
			(layer "B.Cu")
			(hatch none 0.5)
			(connect_pads
				(clearance 0)
			)
			(min_thickness 0.25)
			(keepout
				(tracks not_allowed)
				(vias allowed)
				(pads allowed)
				(copperpour not_allowed)
				(footprints allowed)
			)
			(placement
				(enabled no)
				(sheetname "")
			)
			(fill
				(thermal_gap 0.5)
				(thermal_bridge_width 0.5)
				(island_removal_mode 0)
			)
			(polygon
				(pts
					(xy 116.586 -77.724) (xy 116.586 -78.232) (xy 116.967 -78.232) (xy 116.967 -77.724)
				)
			)
		)
		(zone
			(layer "B.Cu")
			(hatch none 0.5)
			(connect_pads
				(clearance 0)
			)
			(min_thickness 0.25)
			(keepout
				(tracks allowed)
				(vias not_allowed)
				(pads allowed)
				(copperpour not_allowed)
				(footprints allowed)
			)
			(placement
				(enabled no)
				(sheetname "")
			)
			(fill
				(thermal_gap 0.5)
				(thermal_bridge_width 0.5)
				(island_removal_mode 0)
			)
			(polygon
				(pts
					(xy 116.967 -77.724) (xy 116.967 -78.232) (xy 116.586 -78.232) (xy 116.586 -77.724)
				)
			)
		)
	)
	(footprint ""
		(layer "B.Cu")
		(at 348.600014 -122.459242 -90)
		(property "Reference" "R771"
			(at 0.8382 -0.67818 270)
			(unlocked yes)
			(layer "B.SilkS")
			(effects
				(font
					(size 0.4064 0.254)
					(thickness 0.1524)
				)
				(justify left mirror)
			)
		)
		(property "Value" ""
			(at 0 0 90)
			(layer "B.Fab")
			(effects
				(font
					(size 1.27 1.27)
				)
				(justify mirror)
			)
		)
		(duplicate_pad_numbers_are_jumpers no)
		(fp_poly
			(pts
				(xy 0.2794 -0.1016) (xy -0.2794 -0.1016) (xy -0.2794 0.9906) (xy 0.2794 0.9906)
			)
			(stroke
				(width 0)
				(type default)
			)
			(fill no)
			(layer "B.CrtYd")
		)
		(fp_line
			(start -0.2794 0.9906)
			(end -0.2794 -0.1016)
			(stroke
				(width 0.1)
				(type default)
			)
			(layer "B.Fab")
		)
		(fp_line
			(start 0.2794 0.9906)
			(end -0.2794 0.9906)
			(stroke
				(width 0.1)
				(type default)
			)
			(layer "B.Fab")
		)
		(fp_line
			(start -0.2794 -0.1016)
			(end 0.2794 -0.1016)
			(stroke
				(width 0.1)
				(type default)
			)
			(layer "B.Fab")
		)
		(fp_line
			(start 0.2794 -0.1016)
			(end 0.2794 0.9906)
			(stroke
				(width 0.1)
				(type default)
			)
			(layer "B.Fab")
		)
		(pad "1" smd rect
			(at 0 0 90)
			(size 0.508 0.508)
			(layers "B.Cu" "B.Mask" "B.Paste")
			(net "P3E_CPU0_PE1_PCH_RXN<13>")
		)
		(pad "2" smd rect
			(at 0 0.889 90)
			(size 0.508 0.508)
			(layers "B.Cu" "B.Mask" "B.Paste")
			(net "P3E_CPU0_PE1_PCH_CON_RXN<13>")
		)
		(zone
			(layer "B.Cu")
			(hatch none 0.5)
			(connect_pads
				(clearance 0)
			)
			(min_thickness 0.25)
			(keepout
				(tracks not_allowed)
				(vias allowed)
				(pads allowed)
				(copperpour not_allowed)
				(footprints allowed)
			)
			(placement
				(enabled no)
				(sheetname "")
			)
			(fill
				(thermal_gap 0.5)
				(thermal_bridge_width 0.5)
				(island_removal_mode 0)
			)
			(polygon
				(pts
					(xy 347.965014 -122.205242) (xy 347.965014 -122.713242) (xy 348.346014 -122.713242) (xy 348.346014 -122.205242)
				)
			)
		)
		(zone
			(layer "B.Cu")
			(hatch none 0.5)
			(connect_pads
				(clearance 0)
			)
			(min_thickness 0.25)
			(keepout
				(tracks allowed)
				(vias not_allowed)
				(pads allowed)
				(copperpour not_allowed)
				(footprints allowed)
			)
			(placement
				(enabled no)
				(sheetname "")
			)
			(fill
				(thermal_gap 0.5)
				(thermal_bridge_width 0.5)
				(island_removal_mode 0)
			)
			(polygon
				(pts
					(xy 348.346014 -122.205242) (xy 348.346014 -122.713242) (xy 347.965014 -122.713242) (xy 347.965014 -122.205242)
				)
			)
		)
	)
	(footprint ""
		(layer "B.Cu")
		(at 3.04292 -5.41782 90)
		(property "Reference" "R9U1"
			(at 0 0 90)
			(layer "B.SilkS")
			(hide yes)
			(effects
				(font
					(size 1.27 1.27)
				)
				(justify mirror)
			)
		)
		(property "Value" ""
			(at 0 0 90)
			(layer "B.Fab")
			(effects
				(font
					(size 1.27 1.27)
				)
				(justify mirror)
			)
		)
		(duplicate_pad_numbers_are_jumpers no)
		(fp_rect
			(start -0.2794 -0.1016)
			(end 0.2794 0.9906)
			(stroke
				(width 0)
				(type default)
			)
			(fill no)
			(layer "B.CrtYd")
		)
		(fp_line
			(start 0.2794 -0.1016)
			(end 0.2794 0.9906)
			(stroke
				(width 0.1)
				(type default)
			)
			(layer "B.Fab")
		)
		(fp_line
			(start -0.2794 -0.1016)
			(end 0.2794 -0.1016)
			(stroke
				(width 0.1)
				(type default)
			)
			(layer "B.Fab")
		)
		(fp_line
			(start 0.2794 0.9906)
			(end -0.2794 0.9906)
			(stroke
				(width 0.1)
				(type default)
			)
			(layer "B.Fab")
		)
		(fp_line
			(start -0.2794 0.9906)
			(end -0.2794 -0.1016)
			(stroke
				(width 0.1)
				(type default)
			)
			(layer "B.Fab")
		)
		(pad "1" smd rect
			(at 0 0 270)
			(size 0.508 0.508)
			(layers "B.Cu" "B.Mask" "B.Paste")
			(net "VR_PVDDQ_GHJ_PH1_VCIN")
		)
		(pad "2" smd rect
			(at 0 0.889 270)
			(size 0.508 0.508)
			(layers "B.Cu" "B.Mask" "B.Paste")
			(net "P5V_STBY")
		)
		(zone
			(layer "B.Cu")
			(hatch none 0.5)
			(connect_pads
				(clearance 0)
			)
			(min_thickness 0.25)
			(keepout
				(tracks allowed)
				(vias not_allowed)
				(pads allowed)
				(copperpour not_allowed)
				(footprints allowed)
			)
			(placement
				(enabled no)
				(sheetname "")
			)
			(fill
				(thermal_gap 0.5)
				(thermal_bridge_width 0.5)
				(island_removal_mode 0)
			)
			(polygon
				(pts
					(xy 3.29692 -5.16382) (xy 3.67792 -5.16382) (xy 3.67792 -5.67182) (xy 3.29692 -5.67182)
				)
			)
		)
		(zone
			(layer "B.Cu")
			(hatch none 0.5)
			(connect_pads
				(clearance 0)
			)
			(min_thickness 0.25)
			(keepout
				(tracks not_allowed)
				(vias allowed)
				(pads allowed)
				(copperpour not_allowed)
				(footprints allowed)
			)
			(placement
				(enabled no)
				(sheetname "")
			)
			(fill
				(thermal_gap 0.5)
				(thermal_bridge_width 0.5)
				(island_removal_mode 0)
			)
			(polygon
				(pts
					(xy 3.29692 -5.16382) (xy 3.67792 -5.16382) (xy 3.67792 -5.67182) (xy 3.29692 -5.67182)
				)
			)
		)
	)
	(footprint ""
		(layer "B.Cu")
		(at 487.1085 -151.6126 90)
		(property "Reference" "R1L6"
			(at 0 0 90)
			(layer "B.SilkS")
			(hide yes)
			(effects
				(font
					(size 1.27 1.27)
				)
				(justify mirror)
			)
		)
		(property "Value" ""
			(at 0 0 90)
			(layer "B.Fab")
			(effects
				(font
					(size 1.27 1.27)
				)
				(justify mirror)
			)
		)
		(duplicate_pad_numbers_are_jumpers no)
		(fp_poly
			(pts
				(xy 0.2794 -0.1016) (xy -0.2794 -0.1016) (xy -0.2794 0.9906) (xy 0.2794 0.9906)
			)
			(stroke
				(width 0)
				(type default)
			)
			(fill no)
			(layer "B.CrtYd")
		)
		(fp_line
			(start 0.2794 -0.1016)
			(end 0.2794 0.9906)
			(stroke
				(width 0.1)
				(type default)
			)
			(layer "B.Fab")
		)
		(fp_line
			(start -0.2794 -0.1016)
			(end 0.2794 -0.1016)
			(stroke
				(width 0.1)
				(type default)
			)
			(layer "B.Fab")
		)
		(fp_line
			(start 0.2794 0.9906)
			(end -0.2794 0.9906)
			(stroke
				(width 0.1)
				(type default)
			)
			(layer "B.Fab")
		)
		(fp_line
			(start -0.2794 0.9906)
			(end -0.2794 -0.1016)
			(stroke
				(width 0.1)
				(type default)
			)
			(layer "B.Fab")
		)
		(pad "1" smd rect
			(at 0 0 270)
			(size 0.508 0.508)
			(layers "B.Cu" "B.Mask" "B.Paste")
			(net "FM_UART_SWITCH_N")
		)
		(pad "2" smd rect
			(at 0 0.889 270)
			(size 0.508 0.508)
			(layers "B.Cu" "B.Mask" "B.Paste")
			(net "FM_DB_UART_SEL0_N")
		)
		(zone
			(layer "B.Cu")
			(hatch none 0.5)
			(connect_pads
				(clearance 0)
			)
			(min_thickness 0.25)
			(keepout
				(tracks allowed)
				(vias not_allowed)
				(pads allowed)
				(copperpour not_allowed)
				(footprints allowed)
			)
			(placement
				(enabled no)
				(sheetname "")
			)
			(fill
				(thermal_gap 0.5)
				(thermal_bridge_width 0.5)
				(island_removal_mode 0)
			)
			(polygon
				(pts
					(xy 487.3625 -151.8666) (xy 487.3625 -151.3586) (xy 487.7435 -151.3586) (xy 487.7435 -151.8666)
				)
			)
		)
		(zone
			(layer "B.Cu")
			(hatch none 0.5)
			(connect_pads
				(clearance 0)
			)
			(min_thickness 0.25)
			(keepout
				(tracks not_allowed)
				(vias allowed)
				(pads allowed)
				(copperpour not_allowed)
				(footprints allowed)
			)
			(placement
				(enabled no)
				(sheetname "")
			)
			(fill
				(thermal_gap 0.5)
				(thermal_bridge_width 0.5)
				(island_removal_mode 0)
			)
			(polygon
				(pts
					(xy 487.7435 -151.8666) (xy 487.7435 -151.3586) (xy 487.3625 -151.3586) (xy 487.3625 -151.8666)
				)
			)
		)
	)
	(footprint ""
		(layer "B.Cu")
		(at 380.746 -87.3125 180)
		(property "Reference" "R7C13"
			(at 0 0 0)
			(layer "B.SilkS")
			(hide yes)
			(effects
				(font
					(size 1.27 1.27)
				)
				(justify mirror)
			)
		)
		(property "Value" ""
			(at 0 0 0)
			(layer "B.Fab")
			(effects
				(font
					(size 1.27 1.27)
				)
				(justify mirror)
			)
		)
		(duplicate_pad_numbers_are_jumpers no)
		(fp_poly
			(pts
				(xy 0.2794 -0.1016) (xy -0.2794 -0.1016) (xy -0.2794 0.9906) (xy 0.2794 0.9906)
			)
			(stroke
				(width 0)
				(type default)
			)
			(fill no)
			(layer "B.CrtYd")
		)
		(fp_line
			(start 0.2794 0.9906)
			(end -0.2794 0.9906)
			(stroke
				(width 0.1)
				(type default)
			)
			(layer "B.Fab")
		)
		(fp_line
			(start 0.2794 -0.1016)
			(end 0.2794 0.9906)
			(stroke
				(width 0.1)
				(type default)
			)
			(layer "B.Fab")
		)
		(fp_line
			(start -0.2794 0.9906)
			(end -0.2794 -0.1016)
			(stroke
				(width 0.1)
				(type default)
			)
			(layer "B.Fab")
		)
		(fp_line
			(start -0.2794 -0.1016)
			(end 0.2794 -0.1016)
			(stroke
				(width 0.1)
				(type default)
			)
			(layer "B.Fab")
		)
		(pad "1" smd rect
			(at 0 0)
			(size 0.508 0.508)
			(layers "B.Cu" "B.Mask" "B.Paste")
			(net "P3V3_STBY")
		)
		(pad "2" smd rect
			(at 0 0.889)
			(size 0.508 0.508)
			(layers "B.Cu" "B.Mask" "B.Paste")
			(net "FM_UART_PRES_N")
		)
		(zone
			(layer "B.Cu")
			(hatch none 0.5)
			(connect_pads
				(clearance 0)
			)
			(min_thickness 0.25)
			(keepout
				(tracks not_allowed)
				(vias allowed)
				(pads allowed)
				(copperpour not_allowed)
				(footprints allowed)
			)
			(placement
				(enabled no)
				(sheetname "")
			)
			(fill
				(thermal_gap 0.5)
				(thermal_bridge_width 0.5)
				(island_removal_mode 0)
			)
			(polygon
				(pts
					(xy 380.492 -87.9475) (xy 381 -87.9475) (xy 381 -87.5665) (xy 380.492 -87.5665)
				)
			)
		)
		(zone
			(layer "B.Cu")
			(hatch none 0.5)
			(connect_pads
				(clearance 0)
			)
			(min_thickness 0.25)
			(keepout
				(tracks allowed)
				(vias not_allowed)
				(pads allowed)
				(copperpour not_allowed)
				(footprints allowed)
			)
			(placement
				(enabled no)
				(sheetname "")
			)
			(fill
				(thermal_gap 0.5)
				(thermal_bridge_width 0.5)
				(island_removal_mode 0)
			)
			(polygon
				(pts
					(xy 380.492 -87.5665) (xy 381 -87.5665) (xy 381 -87.9475) (xy 380.492 -87.9475)
				)
			)
		)
	)
	(footprint ""
		(layer "B.Cu")
		(at 1.3462 -137.795 90)
		(property "Reference" "C9L10"
			(at 0 0 90)
			(layer "B.SilkS")
			(hide yes)
			(effects
				(font
					(size 1.27 1.27)
				)
				(justify mirror)
			)
		)
		(property "Value" ""
			(at 0 0 90)
			(layer "B.Fab")
			(effects
				(font
					(size 1.27 1.27)
				)
				(justify mirror)
			)
		)
		(duplicate_pad_numbers_are_jumpers no)
		(fp_rect
			(start -0.7239 -0.2159)
			(end 0.7239 1.9939)
			(stroke
				(width 0)
				(type default)
			)
			(fill no)
			(layer "B.CrtYd")
		)
		(fp_line
			(start 0.7239 -0.2159)
			(end 0.7239 1.9939)
			(stroke
				(width 0.1)
				(type default)
			)
			(layer "B.Fab")
		)
		(fp_line
			(start -0.7239 -0.2159)
			(end 0.7239 -0.2159)
			(stroke
				(width 0.1)
				(type default)
			)
			(layer "B.Fab")
		)
		(fp_line
			(start 0.7239 1.9939)
			(end -0.7239 1.9939)
			(stroke
				(width 0.1)
				(type default)
			)
			(layer "B.Fab")
		)
		(fp_line
			(start -0.7239 1.9939)
			(end -0.7239 -0.2159)
			(stroke
				(width 0.1)
				(type default)
			)
			(layer "B.Fab")
		)
		(pad "1" smd rect
			(at 0 0 270)
			(size 1.27 1.016)
			(layers "B.Cu" "B.Mask" "B.Paste")
			(net "VR_FET_SW_P12V_STBY_PVDDQ_KLM")
		)
		(pad "2" smd rect
			(at 0 1.778 270)
			(size 1.27 1.016)
			(layers "B.Cu" "B.Mask" "B.Paste")
			(net "GND")
		)
		(zone
			(layer "B.Cu")
			(hatch none 0.5)
			(connect_pads
				(clearance 0)
			)
			(min_thickness 0.25)
			(keepout
				(tracks not_allowed)
				(vias allowed)
				(pads allowed)
				(copperpour not_allowed)
				(footprints allowed)
			)
			(placement
				(enabled no)
				(sheetname "")
			)
			(fill
				(thermal_gap 0.5)
				(thermal_bridge_width 0.5)
				(island_removal_mode 0)
			)
			(polygon
				(pts
					(xy 1.8542 -137.16) (xy 2.6162 -137.16) (xy 2.6162 -138.43) (xy 1.8542 -138.43)
				)
			)
		)
	)
	(footprint ""
		(layer "B.Cu")
		(at 401.04568 -48.49368 -90)
		(property "Reference" "R3T5"
			(at 0.8382 -0.67818 270)
			(unlocked yes)
			(layer "B.SilkS")
			(effects
				(font
					(size 0.4064 0.254)
					(thickness 0.1524)
				)
				(justify left mirror)
			)
		)
		(property "Value" ""
			(at 0 0 90)
			(layer "B.Fab")
			(effects
				(font
					(size 1.27 1.27)
				)
				(justify mirror)
			)
		)
		(duplicate_pad_numbers_are_jumpers no)
		(fp_poly
			(pts
				(xy 0.2794 -0.1016) (xy -0.2794 -0.1016) (xy -0.2794 0.9906) (xy 0.2794 0.9906)
			)
			(stroke
				(width 0)
				(type default)
			)
			(fill no)
			(layer "B.CrtYd")
		)
		(fp_line
			(start -0.2794 0.9906)
			(end -0.2794 -0.1016)
			(stroke
				(width 0.1)
				(type default)
			)
			(layer "B.Fab")
		)
		(fp_line
			(start 0.2794 0.9906)
			(end -0.2794 0.9906)
			(stroke
				(width 0.1)
				(type default)
			)
			(layer "B.Fab")
		)
		(fp_line
			(start -0.2794 -0.1016)
			(end 0.2794 -0.1016)
			(stroke
				(width 0.1)
				(type default)
			)
			(layer "B.Fab")
		)
		(fp_line
			(start 0.2794 -0.1016)
			(end 0.2794 0.9906)
			(stroke
				(width 0.1)
				(type default)
			)
			(layer "B.Fab")
		)
		(pad "1" smd rect
			(at 0 0 90)
			(size 0.508 0.508)
			(layers "B.Cu" "B.Mask" "B.Paste")
			(net "P3V3_STBY")
		)
		(pad "2" smd rect
			(at 0 0.889 90)
			(size 0.508 0.508)
			(layers "B.Cu" "B.Mask" "B.Paste")
			(net "SPI_CS0_SECONDARY_R_N")
		)
		(zone
			(layer "B.Cu")
			(hatch none 0.5)
			(connect_pads
				(clearance 0)
			)
			(min_thickness 0.25)
			(keepout
				(tracks not_allowed)
				(vias allowed)
				(pads allowed)
				(copperpour not_allowed)
				(footprints allowed)
			)
			(placement
				(enabled no)
				(sheetname "")
			)
			(fill
				(thermal_gap 0.5)
				(thermal_bridge_width 0.5)
				(island_removal_mode 0)
			)
			(polygon
				(pts
					(xy 400.41068 -48.23968) (xy 400.41068 -48.74768) (xy 400.79168 -48.74768) (xy 400.79168 -48.23968)
				)
			)
		)
		(zone
			(layer "B.Cu")
			(hatch none 0.5)
			(connect_pads
				(clearance 0)
			)
			(min_thickness 0.25)
			(keepout
				(tracks allowed)
				(vias not_allowed)
				(pads allowed)
				(copperpour not_allowed)
				(footprints allowed)
			)
			(placement
				(enabled no)
				(sheetname "")
			)
			(fill
				(thermal_gap 0.5)
				(thermal_bridge_width 0.5)
				(island_removal_mode 0)
			)
			(polygon
				(pts
					(xy 400.79168 -48.23968) (xy 400.79168 -48.74768) (xy 400.41068 -48.74768) (xy 400.41068 -48.23968)
				)
			)
		)
	)
	(footprint ""
		(layer "B.Cu")
		(at 374.646952 -43.224958)
		(property "Reference" "R2T27"
			(at 0 0 0)
			(layer "B.SilkS")
			(hide yes)
			(effects
				(font
					(size 1.27 1.27)
				)
				(justify mirror)
			)
		)
		(property "Value" ""
			(at 0 0 0)
			(layer "B.Fab")
			(effects
				(font
					(size 1.27 1.27)
				)
				(justify mirror)
			)
		)
		(duplicate_pad_numbers_are_jumpers no)
		(fp_poly
			(pts
				(xy 0.2794 -0.1016) (xy -0.2794 -0.1016) (xy -0.2794 0.9906) (xy 0.2794 0.9906)
			)
			(stroke
				(width 0)
				(type default)
			)
			(fill no)
			(layer "B.CrtYd")
		)
		(fp_line
			(start -0.2794 -0.1016)
			(end 0.2794 -0.1016)
			(stroke
				(width 0.1)
				(type default)
			)
			(layer "B.Fab")
		)
		(fp_line
			(start -0.2794 0.9906)
			(end -0.2794 -0.1016)
			(stroke
				(width 0.1)
				(type default)
			)
			(layer "B.Fab")
		)
		(fp_line
			(start 0.2794 -0.1016)
			(end 0.2794 0.9906)
			(stroke
				(width 0.1)
				(type default)
			)
			(layer "B.Fab")
		)
		(fp_line
			(start 0.2794 0.9906)
			(end -0.2794 0.9906)
			(stroke
				(width 0.1)
				(type default)
			)
			(layer "B.Fab")
		)
		(pad "1" smd rect
			(at 0 0 180)
			(size 0.508 0.508)
			(layers "B.Cu" "B.Mask" "B.Paste")
			(net "H_CPU1_ERR1_G_N")
		)
		(pad "2" smd rect
			(at 0 0.889 180)
			(size 0.508 0.508)
			(layers "B.Cu" "B.Mask" "B.Paste")
			(net "H_CPU_ERR1_GTL_R_N")
		)
		(zone
			(layer "B.Cu")
			(hatch none 0.5)
			(connect_pads
				(clearance 0)
			)
			(min_thickness 0.25)
			(keepout
				(tracks allowed)
				(vias not_allowed)
				(pads allowed)
				(copperpour not_allowed)
				(footprints allowed)
			)
			(placement
				(enabled no)
				(sheetname "")
			)
			(fill
				(thermal_gap 0.5)
				(thermal_bridge_width 0.5)
				(island_removal_mode 0)
			)
			(polygon
				(pts
					(xy 374.900952 -42.970958) (xy 374.392952 -42.970958) (xy 374.392952 -42.589958) (xy 374.900952 -42.589958)
				)
			)
		)
		(zone
			(layer "B.Cu")
			(hatch none 0.5)
			(connect_pads
				(clearance 0)
			)
			(min_thickness 0.25)
			(keepout
				(tracks not_allowed)
				(vias allowed)
				(pads allowed)
				(copperpour not_allowed)
				(footprints allowed)
			)
			(placement
				(enabled no)
				(sheetname "")
			)
			(fill
				(thermal_gap 0.5)
				(thermal_bridge_width 0.5)
				(island_removal_mode 0)
			)
			(polygon
				(pts
					(xy 374.900952 -42.589958) (xy 374.392952 -42.589958) (xy 374.392952 -42.970958) (xy 374.900952 -42.970958)
				)
			)
		)
	)
	(footprint ""
		(layer "B.Cu")
		(at 174.443136 -74.018648 90)
		(property "Reference" "R4W2"
			(at 0.8382 -0.67818 90)
			(unlocked yes)
			(layer "B.SilkS")
			(effects
				(font
					(size 0.4064 0.254)
					(thickness 0.1524)
				)
				(justify left mirror)
			)
		)
		(property "Value" ""
			(at 0 0 90)
			(layer "B.Fab")
			(effects
				(font
					(size 1.27 1.27)
				)
				(justify mirror)
			)
		)
		(duplicate_pad_numbers_are_jumpers no)
		(fp_poly
			(pts
				(xy 0.2794 -0.1016) (xy -0.2794 -0.1016) (xy -0.2794 0.9906) (xy 0.2794 0.9906)
			)
			(stroke
				(width 0)
				(type default)
			)
			(fill no)
			(layer "B.CrtYd")
		)
		(fp_line
			(start 0.2794 -0.1016)
			(end 0.2794 0.9906)
			(stroke
				(width 0.1)
				(type default)
			)
			(layer "B.Fab")
		)
		(fp_line
			(start -0.2794 -0.1016)
			(end 0.2794 -0.1016)
			(stroke
				(width 0.1)
				(type default)
			)
			(layer "B.Fab")
		)
		(fp_line
			(start 0.2794 0.9906)
			(end -0.2794 0.9906)
			(stroke
				(width 0.1)
				(type default)
			)
			(layer "B.Fab")
		)
		(fp_line
			(start -0.2794 0.9906)
			(end -0.2794 -0.1016)
			(stroke
				(width 0.1)
				(type default)
			)
			(layer "B.Fab")
		)
		(pad "1" smd rect
			(at 0 0 270)
			(size 0.508 0.508)
			(layers "B.Cu" "B.Mask" "B.Paste")
			(net "P3V3_DB1200")
		)
		(pad "2" smd rect
			(at 0 0.889 270)
			(size 0.508 0.508)
			(layers "B.Cu" "B.Mask" "B.Paste")
			(net "P3V3_DB1200_R1")
		)
		(zone
			(layer "B.Cu")
			(hatch none 0.5)
			(connect_pads
				(clearance 0)
			)
			(min_thickness 0.25)
			(keepout
				(tracks allowed)
				(vias not_allowed)
				(pads allowed)
				(copperpour not_allowed)
				(footprints allowed)
			)
			(placement
				(enabled no)
				(sheetname "")
			)
			(fill
				(thermal_gap 0.5)
				(thermal_bridge_width 0.5)
				(island_removal_mode 0)
			)
			(polygon
				(pts
					(xy 174.697136 -74.272648) (xy 174.697136 -73.764648) (xy 175.078136 -73.764648) (xy 175.078136 -74.272648)
				)
			)
		)
		(zone
			(layer "B.Cu")
			(hatch none 0.5)
			(connect_pads
				(clearance 0)
			)
			(min_thickness 0.25)
			(keepout
				(tracks not_allowed)
				(vias allowed)
				(pads allowed)
				(copperpour not_allowed)
				(footprints allowed)
			)
			(placement
				(enabled no)
				(sheetname "")
			)
			(fill
				(thermal_gap 0.5)
				(thermal_bridge_width 0.5)
				(island_removal_mode 0)
			)
			(polygon
				(pts
					(xy 175.078136 -74.272648) (xy 175.078136 -73.764648) (xy 174.697136 -73.764648) (xy 174.697136 -74.272648)
				)
			)
		)
	)
	(footprint ""
		(layer "B.Cu")
		(at 367.157 -39.8272)
		(property "Reference" "R8F16"
			(at 0 0 0)
			(layer "B.SilkS")
			(hide yes)
			(effects
				(font
					(size 1.27 1.27)
				)
				(justify mirror)
			)
		)
		(property "Value" ""
			(at 0 0 0)
			(layer "B.Fab")
			(effects
				(font
					(size 1.27 1.27)
				)
				(justify mirror)
			)
		)
		(duplicate_pad_numbers_are_jumpers no)
		(fp_poly
			(pts
				(xy 0.2794 -0.1016) (xy -0.2794 -0.1016) (xy -0.2794 0.9906) (xy 0.2794 0.9906)
			)
			(stroke
				(width 0)
				(type default)
			)
			(fill no)
			(layer "B.CrtYd")
		)
		(fp_line
			(start -0.2794 -0.1016)
			(end 0.2794 -0.1016)
			(stroke
				(width 0.1)
				(type default)
			)
			(layer "B.Fab")
		)
		(fp_line
			(start -0.2794 0.9906)
			(end -0.2794 -0.1016)
			(stroke
				(width 0.1)
				(type default)
			)
			(layer "B.Fab")
		)
		(fp_line
			(start 0.2794 -0.1016)
			(end 0.2794 0.9906)
			(stroke
				(width 0.1)
				(type default)
			)
			(layer "B.Fab")
		)
		(fp_line
			(start 0.2794 0.9906)
			(end -0.2794 0.9906)
			(stroke
				(width 0.1)
				(type default)
			)
			(layer "B.Fab")
		)
		(pad "1" smd rect
			(at 0 0 180)
			(size 0.508 0.508)
			(layers "B.Cu" "B.Mask" "B.Paste")
			(net "P3V3_STBY")
		)
		(pad "2" smd rect
			(at 0 0.889 180)
			(size 0.508 0.508)
			(layers "B.Cu" "B.Mask" "B.Paste")
			(net "PU_SPI_FLASH_RESET_2_N")
		)
		(zone
			(layer "B.Cu")
			(hatch none 0.5)
			(connect_pads
				(clearance 0)
			)
			(min_thickness 0.25)
			(keepout
				(tracks allowed)
				(vias not_allowed)
				(pads allowed)
				(copperpour not_allowed)
				(footprints allowed)
			)
			(placement
				(enabled no)
				(sheetname "")
			)
			(fill
				(thermal_gap 0.5)
				(thermal_bridge_width 0.5)
				(island_removal_mode 0)
			)
			(polygon
				(pts
					(xy 367.411 -39.5732) (xy 366.903 -39.5732) (xy 366.903 -39.1922) (xy 367.411 -39.1922)
				)
			)
		)
		(zone
			(layer "B.Cu")
			(hatch none 0.5)
			(connect_pads
				(clearance 0)
			)
			(min_thickness 0.25)
			(keepout
				(tracks not_allowed)
				(vias allowed)
				(pads allowed)
				(copperpour not_allowed)
				(footprints allowed)
			)
			(placement
				(enabled no)
				(sheetname "")
			)
			(fill
				(thermal_gap 0.5)
				(thermal_bridge_width 0.5)
				(island_removal_mode 0)
			)
			(polygon
				(pts
					(xy 367.411 -39.1922) (xy 366.903 -39.1922) (xy 366.903 -39.5732) (xy 367.411 -39.5732)
				)
			)
		)
	)
	(footprint ""
		(layer "B.Cu")
		(at 476.4151 -36.2712 90)
		(property "Reference" "R1T34"
			(at 0 0 90)
			(layer "B.SilkS")
			(hide yes)
			(effects
				(font
					(size 1.27 1.27)
				)
				(justify mirror)
			)
		)
		(property "Value" ""
			(at 0 0 90)
			(layer "B.Fab")
			(effects
				(font
					(size 1.27 1.27)
				)
				(justify mirror)
			)
		)
		(duplicate_pad_numbers_are_jumpers no)
		(fp_poly
			(pts
				(xy 0.4953 -0.2032) (xy -0.4953 -0.2032) (xy -0.4953 1.6002) (xy 0.4953 1.6002)
			)
			(stroke
				(width 0)
				(type default)
			)
			(fill no)
			(layer "B.CrtYd")
		)
		(fp_line
			(start 0.4953 -0.2032)
			(end -0.4953 -0.2032)
			(stroke
				(width 0.1)
				(type default)
			)
			(layer "B.Fab")
		)
		(fp_line
			(start -0.4953 -0.2032)
			(end -0.4953 1.6002)
			(stroke
				(width 0.1)
				(type default)
			)
			(layer "B.Fab")
		)
		(fp_line
			(start 0.4953 1.6002)
			(end 0.4953 -0.2032)
			(stroke
				(width 0.1)
				(type default)
			)
			(layer "B.Fab")
		)
		(fp_line
			(start -0.4953 1.6002)
			(end 0.4953 1.6002)
			(stroke
				(width 0.1)
				(type default)
			)
			(layer "B.Fab")
		)
		(pad "1" smd rect
			(at 0 0 270)
			(size 0.762 0.889)
			(layers "B.Cu" "B.Mask" "B.Paste")
			(net "P3V3_STBY")
		)
		(pad "2" smd rect
			(at 0 1.397 270)
			(size 0.762 0.889)
			(layers "B.Cu" "B.Mask" "B.Paste")
			(net "P3V3_STBY_P1V5_LAN_I210")
		)
		(zone
			(layer "B.Cu")
			(hatch none 0.5)
			(connect_pads
				(clearance 0)
			)
			(min_thickness 0.25)
			(keepout
				(tracks not_allowed)
				(vias allowed)
				(pads allowed)
				(copperpour not_allowed)
				(footprints allowed)
			)
			(placement
				(enabled no)
				(sheetname "")
			)
			(fill
				(thermal_gap 0.5)
				(thermal_bridge_width 0.5)
				(island_removal_mode 0)
			)
			(polygon
				(pts
					(xy 477.3676 -36.6522) (xy 476.8596 -36.6522) (xy 476.8596 -35.8902) (xy 477.3676 -35.8902)
				)
			)
		)
		(zone
			(layer "B.Cu")
			(hatch none 0.5)
			(connect_pads
				(clearance 0)
			)
			(min_thickness 0.25)
			(keepout
				(tracks allowed)
				(vias not_allowed)
				(pads allowed)
				(copperpour not_allowed)
				(footprints allowed)
			)
			(placement
				(enabled no)
				(sheetname "")
			)
			(fill
				(thermal_gap 0.5)
				(thermal_bridge_width 0.5)
				(island_removal_mode 0)
			)
			(polygon
				(pts
					(xy 477.3676 -35.8902) (xy 476.8596 -35.8902) (xy 476.8596 -36.6522) (xy 477.3676 -36.6522)
				)
			)
		)
	)
	(footprint ""
		(layer "B.Cu")
		(at 498.6528 -151.9174)
		(property "Reference" "R1L8"
			(at 0 0 0)
			(layer "B.SilkS")
			(hide yes)
			(effects
				(font
					(size 1.27 1.27)
				)
				(justify mirror)
			)
		)
		(property "Value" ""
			(at 0 0 0)
			(layer "B.Fab")
			(effects
				(font
					(size 1.27 1.27)
				)
				(justify mirror)
			)
		)
		(duplicate_pad_numbers_are_jumpers no)
		(fp_poly
			(pts
				(xy 0.2794 -0.1016) (xy -0.2794 -0.1016) (xy -0.2794 0.9906) (xy 0.2794 0.9906)
			)
			(stroke
				(width 0)
				(type default)
			)
			(fill no)
			(layer "B.CrtYd")
		)
		(fp_line
			(start -0.2794 -0.1016)
			(end 0.2794 -0.1016)
			(stroke
				(width 0.1)
				(type default)
			)
			(layer "B.Fab")
		)
		(fp_line
			(start -0.2794 0.9906)
			(end -0.2794 -0.1016)
			(stroke
				(width 0.1)
				(type default)
			)
			(layer "B.Fab")
		)
		(fp_line
			(start 0.2794 -0.1016)
			(end 0.2794 0.9906)
			(stroke
				(width 0.1)
				(type default)
			)
			(layer "B.Fab")
		)
		(fp_line
			(start 0.2794 0.9906)
			(end -0.2794 0.9906)
			(stroke
				(width 0.1)
				(type default)
			)
			(layer "B.Fab")
		)
		(pad "1" smd rect
			(at 0 0 180)
			(size 0.508 0.508)
			(layers "B.Cu" "B.Mask" "B.Paste")
			(net "P5V_STBY")
		)
		(pad "2" smd rect
			(at 0 0.889 180)
			(size 0.508 0.508)
			(layers "B.Cu" "B.Mask" "B.Paste")
			(net "FP_ID_LED_XOR_R")
		)
		(zone
			(layer "B.Cu")
			(hatch none 0.5)
			(connect_pads
				(clearance 0)
			)
			(min_thickness 0.25)
			(keepout
				(tracks allowed)
				(vias not_allowed)
				(pads allowed)
				(copperpour not_allowed)
				(footprints allowed)
			)
			(placement
				(enabled no)
				(sheetname "")
			)
			(fill
				(thermal_gap 0.5)
				(thermal_bridge_width 0.5)
				(island_removal_mode 0)
			)
			(polygon
				(pts
					(xy 498.9068 -151.6634) (xy 498.3988 -151.6634) (xy 498.3988 -151.2824) (xy 498.9068 -151.2824)
				)
			)
		)
		(zone
			(layer "B.Cu")
			(hatch none 0.5)
			(connect_pads
				(clearance 0)
			)
			(min_thickness 0.25)
			(keepout
				(tracks not_allowed)
				(vias allowed)
				(pads allowed)
				(copperpour not_allowed)
				(footprints allowed)
			)
			(placement
				(enabled no)
				(sheetname "")
			)
			(fill
				(thermal_gap 0.5)
				(thermal_bridge_width 0.5)
				(island_removal_mode 0)
			)
			(polygon
				(pts
					(xy 498.9068 -151.2824) (xy 498.3988 -151.2824) (xy 498.3988 -151.6634) (xy 498.9068 -151.6634)
				)
			)
		)
	)
	(footprint ""
		(layer "B.Cu")
		(at 491.925864 -55.880762 -90)
		(property "Reference" "CR30W1"
			(at 1.495806 -1.067816 270)
			(unlocked yes)
			(layer "B.SilkS")
			(effects
				(font
					(size 0.4064 0.254)
					(thickness 0.1524)
				)
				(justify left mirror)
			)
		)
		(property "Value" ""
			(at 0 0 90)
			(layer "B.Fab")
			(effects
				(font
					(size 1.27 1.27)
				)
				(justify mirror)
			)
		)
		(duplicate_pad_numbers_are_jumpers no)
		(fp_circle
			(center 0.589026 -0.5334)
			(end 0.589026 -0.6604)
			(stroke
				(width 0.254)
				(type default)
			)
			(fill no)
			(layer "B.SilkS")
		)
		(fp_rect
			(start 0.225552 2.167382)
			(end -0.809498 -0.167386)
			(stroke
				(width 0)
				(type default)
			)
			(fill no)
			(layer "B.CrtYd")
		)
		(fp_line
			(start -0.809498 2.167382)
			(end 0.225552 2.167382)
			(stroke
				(width 0.1)
				(type default)
			)
			(layer "B.Fab")
		)
		(fp_line
			(start 0.225552 2.167382)
			(end 0.225552 -0.167386)
			(stroke
				(width 0.1)
				(type default)
			)
			(layer "B.Fab")
		)
		(fp_line
			(start -0.809498 -0.167386)
			(end -0.809498 2.167382)
			(stroke
				(width 0.1)
				(type default)
			)
			(layer "B.Fab")
		)
		(fp_line
			(start 0.225552 -0.167386)
			(end -0.809498 -0.167386)
			(stroke
				(width 0.1)
				(type default)
			)
			(layer "B.Fab")
		)
		(fp_circle
			(center 0.589026 -0.5334)
			(end 0.589026 -0.6604)
			(stroke
				(width 0.254)
				(type default)
			)
			(fill no)
			(layer "B.Fab")
		)
		(pad "1" smd rect
			(at 0 0 90)
			(size 0.3556 0.2032)
			(layers "B.Cu" "B.Mask" "B.Paste")
			(net "USB3_P01_FB_TXN")
		)
		(pad "2" smd rect
			(at 0 0.500126 90)
			(size 0.3556 0.2032)
			(layers "B.Cu" "B.Mask" "B.Paste")
			(net "USB3_P01_FB_TXP")
		)
		(pad "3" smd rect
			(at -0.2921 0.999998 90)
			(size 0.9398 0.4064)
			(layers "B.Cu" "B.Mask" "B.Paste")
			(net "GND")
		)
		(pad "4" smd rect
			(at 0 1.500124 90)
			(size 0.3556 0.2032)
			(layers "B.Cu" "B.Mask" "B.Paste")
			(net "USB3_P01_FB_RXN")
		)
		(pad "5" smd rect
			(at 0 1.999996 90)
			(size 0.3556 0.2032)
			(layers "B.Cu" "B.Mask" "B.Paste")
			(net "USB3_P01_FB_RXP")
		)
		(pad "6" smd rect
			(at -0.583946 1.999996 90)
			(size 0.3556 0.2032)
			(layers "B.Cu" "B.Mask" "B.Paste")
			(net "USB3_P01_FB_RXP")
		)
		(pad "7" smd rect
			(at -0.583946 1.500124 90)
			(size 0.3556 0.2032)
			(layers "B.Cu" "B.Mask" "B.Paste")
			(net "USB3_P01_FB_RXN")
		)
		(pad "8" smd rect
			(at -0.583946 0.500126 90)
			(size 0.3556 0.2032)
			(layers "B.Cu" "B.Mask" "B.Paste")
			(net "USB3_P01_FB_TXP")
		)
		(pad "9" smd rect
			(at -0.583946 0 90)
			(size 0.3556 0.2032)
			(layers "B.Cu" "B.Mask" "B.Paste")
			(net "USB3_P01_FB_TXN")
		)
	)
	(footprint ""
		(layer "B.Cu")
		(at 402.59 -73.406 180)
		(property "Reference" "R2T54"
			(at 0 0 0)
			(layer "B.SilkS")
			(hide yes)
			(effects
				(font
					(size 1.27 1.27)
				)
				(justify mirror)
			)
		)
		(property "Value" ""
			(at 0 0 0)
			(layer "B.Fab")
			(effects
				(font
					(size 1.27 1.27)
				)
				(justify mirror)
			)
		)
		(duplicate_pad_numbers_are_jumpers no)
		(fp_poly
			(pts
				(xy 0.2794 -0.1016) (xy -0.2794 -0.1016) (xy -0.2794 0.9906) (xy 0.2794 0.9906)
			)
			(stroke
				(width 0)
				(type default)
			)
			(fill no)
			(layer "B.CrtYd")
		)
		(fp_line
			(start 0.2794 0.9906)
			(end -0.2794 0.9906)
			(stroke
				(width 0.1)
				(type default)
			)
			(layer "B.Fab")
		)
		(fp_line
			(start 0.2794 -0.1016)
			(end 0.2794 0.9906)
			(stroke
				(width 0.1)
				(type default)
			)
			(layer "B.Fab")
		)
		(fp_line
			(start -0.2794 0.9906)
			(end -0.2794 -0.1016)
			(stroke
				(width 0.1)
				(type default)
			)
			(layer "B.Fab")
		)
		(fp_line
			(start -0.2794 -0.1016)
			(end 0.2794 -0.1016)
			(stroke
				(width 0.1)
				(type default)
			)
			(layer "B.Fab")
		)
		(pad "1" smd rect
			(at 0 0)
			(size 0.508 0.508)
			(layers "B.Cu" "B.Mask" "B.Paste")
			(net "P3V3_STBY")
		)
		(pad "2" smd rect
			(at 0 0.889)
			(size 0.508 0.508)
			(layers "B.Cu" "B.Mask" "B.Paste")
			(net "SMB_BMC_PMBUS_STBY_LVC3_SCL")
		)
		(zone
			(layer "B.Cu")
			(hatch none 0.5)
			(connect_pads
				(clearance 0)
			)
			(min_thickness 0.25)
			(keepout
				(tracks not_allowed)
				(vias allowed)
				(pads allowed)
				(copperpour not_allowed)
				(footprints allowed)
			)
			(placement
				(enabled no)
				(sheetname "")
			)
			(fill
				(thermal_gap 0.5)
				(thermal_bridge_width 0.5)
				(island_removal_mode 0)
			)
			(polygon
				(pts
					(xy 402.336 -74.041) (xy 402.844 -74.041) (xy 402.844 -73.66) (xy 402.336 -73.66)
				)
			)
		)
		(zone
			(layer "B.Cu")
			(hatch none 0.5)
			(connect_pads
				(clearance 0)
			)
			(min_thickness 0.25)
			(keepout
				(tracks allowed)
				(vias not_allowed)
				(pads allowed)
				(copperpour not_allowed)
				(footprints allowed)
			)
			(placement
				(enabled no)
				(sheetname "")
			)
			(fill
				(thermal_gap 0.5)
				(thermal_bridge_width 0.5)
				(island_removal_mode 0)
			)
			(polygon
				(pts
					(xy 402.336 -73.66) (xy 402.844 -73.66) (xy 402.844 -74.041) (xy 402.336 -74.041)
				)
			)
		)
	)
	(footprint ""
		(layer "B.Cu")
		(at 418.7063 -48.1584 -90)
		(property "Reference" "R1T2"
			(at 0 0 90)
			(layer "B.SilkS")
			(hide yes)
			(effects
				(font
					(size 1.27 1.27)
				)
				(justify mirror)
			)
		)
		(property "Value" ""
			(at 0 0 90)
			(layer "B.Fab")
			(effects
				(font
					(size 1.27 1.27)
				)
				(justify mirror)
			)
		)
		(duplicate_pad_numbers_are_jumpers no)
		(fp_poly
			(pts
				(xy 0.2794 -0.1016) (xy -0.2794 -0.1016) (xy -0.2794 0.9906) (xy 0.2794 0.9906)
			)
			(stroke
				(width 0)
				(type default)
			)
			(fill no)
			(layer "B.CrtYd")
		)
		(fp_line
			(start -0.2794 0.9906)
			(end -0.2794 -0.1016)
			(stroke
				(width 0.1)
				(type default)
			)
			(layer "B.Fab")
		)
		(fp_line
			(start 0.2794 0.9906)
			(end -0.2794 0.9906)
			(stroke
				(width 0.1)
				(type default)
			)
			(layer "B.Fab")
		)
		(fp_line
			(start -0.2794 -0.1016)
			(end 0.2794 -0.1016)
			(stroke
				(width 0.1)
				(type default)
			)
			(layer "B.Fab")
		)
		(fp_line
			(start 0.2794 -0.1016)
			(end 0.2794 0.9906)
			(stroke
				(width 0.1)
				(type default)
			)
			(layer "B.Fab")
		)
		(pad "1" smd rect
			(at 0 0 90)
			(size 0.508 0.508)
			(layers "B.Cu" "B.Mask" "B.Paste")
			(net "P3V3_STBY")
		)
		(pad "2" smd rect
			(at 0 0.889 90)
			(size 0.508 0.508)
			(layers "B.Cu" "B.Mask" "B.Paste")
			(net "SMB_SLOTX24_STBY_LVC3_SCL_R")
		)
		(zone
			(layer "B.Cu")
			(hatch none 0.5)
			(connect_pads
				(clearance 0)
			)
			(min_thickness 0.25)
			(keepout
				(tracks not_allowed)
				(vias allowed)
				(pads allowed)
				(copperpour not_allowed)
				(footprints allowed)
			)
			(placement
				(enabled no)
				(sheetname "")
			)
			(fill
				(thermal_gap 0.5)
				(thermal_bridge_width 0.5)
				(island_removal_mode 0)
			)
			(polygon
				(pts
					(xy 418.0713 -47.9044) (xy 418.0713 -48.4124) (xy 418.4523 -48.4124) (xy 418.4523 -47.9044)
				)
			)
		)
		(zone
			(layer "B.Cu")
			(hatch none 0.5)
			(connect_pads
				(clearance 0)
			)
			(min_thickness 0.25)
			(keepout
				(tracks allowed)
				(vias not_allowed)
				(pads allowed)
				(copperpour not_allowed)
				(footprints allowed)
			)
			(placement
				(enabled no)
				(sheetname "")
			)
			(fill
				(thermal_gap 0.5)
				(thermal_bridge_width 0.5)
				(island_removal_mode 0)
			)
			(polygon
				(pts
					(xy 418.4523 -47.9044) (xy 418.4523 -48.4124) (xy 418.0713 -48.4124) (xy 418.0713 -47.9044)
				)
			)
		)
	)
	(footprint ""
		(layer "B.Cu")
		(at 454.311258 -31.999174 90)
		(property "Reference" "R8D25"
			(at 0 0 90)
			(layer "B.SilkS")
			(hide yes)
			(effects
				(font
					(size 1.27 1.27)
				)
				(justify mirror)
			)
		)
		(property "Value" ""
			(at 0 0 90)
			(layer "B.Fab")
			(effects
				(font
					(size 1.27 1.27)
				)
				(justify mirror)
			)
		)
		(duplicate_pad_numbers_are_jumpers no)
		(fp_poly
			(pts
				(xy 0.2794 -0.1016) (xy -0.2794 -0.1016) (xy -0.2794 0.9906) (xy 0.2794 0.9906)
			)
			(stroke
				(width 0)
				(type default)
			)
			(fill no)
			(layer "B.CrtYd")
		)
		(fp_line
			(start 0.2794 -0.1016)
			(end 0.2794 0.9906)
			(stroke
				(width 0.1)
				(type default)
			)
			(layer "B.Fab")
		)
		(fp_line
			(start -0.2794 -0.1016)
			(end 0.2794 -0.1016)
			(stroke
				(width 0.1)
				(type default)
			)
			(layer "B.Fab")
		)
		(fp_line
			(start 0.2794 0.9906)
			(end -0.2794 0.9906)
			(stroke
				(width 0.1)
				(type default)
			)
			(layer "B.Fab")
		)
		(fp_line
			(start -0.2794 0.9906)
			(end -0.2794 -0.1016)
			(stroke
				(width 0.1)
				(type default)
			)
			(layer "B.Fab")
		)
		(pad "1" smd rect
			(at 0 0 270)
			(size 0.508 0.508)
			(layers "B.Cu" "B.Mask" "B.Paste")
			(net "P3V3_STBY")
		)
		(pad "2" smd rect
			(at 0 0.889 270)
			(size 0.508 0.508)
			(layers "B.Cu" "B.Mask" "B.Paste")
			(net "RST_BMC_SRST_R2_N")
		)
		(zone
			(layer "B.Cu")
			(hatch none 0.5)
			(connect_pads
				(clearance 0)
			)
			(min_thickness 0.25)
			(keepout
				(tracks allowed)
				(vias not_allowed)
				(pads allowed)
				(copperpour not_allowed)
				(footprints allowed)
			)
			(placement
				(enabled no)
				(sheetname "")
			)
			(fill
				(thermal_gap 0.5)
				(thermal_bridge_width 0.5)
				(island_removal_mode 0)
			)
			(polygon
				(pts
					(xy 454.565258 -32.253174) (xy 454.565258 -31.745174) (xy 454.946258 -31.745174) (xy 454.946258 -32.253174)
				)
			)
		)
		(zone
			(layer "B.Cu")
			(hatch none 0.5)
			(connect_pads
				(clearance 0)
			)
			(min_thickness 0.25)
			(keepout
				(tracks not_allowed)
				(vias allowed)
				(pads allowed)
				(copperpour not_allowed)
				(footprints allowed)
			)
			(placement
				(enabled no)
				(sheetname "")
			)
			(fill
				(thermal_gap 0.5)
				(thermal_bridge_width 0.5)
				(island_removal_mode 0)
			)
			(polygon
				(pts
					(xy 454.946258 -32.253174) (xy 454.946258 -31.745174) (xy 454.565258 -31.745174) (xy 454.565258 -32.253174)
				)
			)
		)
	)
	(footprint ""
		(layer "B.Cu")
		(at 349.377 -16.51 180)
		(property "Reference" "R3T13"
			(at 0 0 0)
			(layer "B.SilkS")
			(hide yes)
			(effects
				(font
					(size 1.27 1.27)
				)
				(justify mirror)
			)
		)
		(property "Value" ""
			(at 0 0 0)
			(layer "B.Fab")
			(effects
				(font
					(size 1.27 1.27)
				)
				(justify mirror)
			)
		)
		(duplicate_pad_numbers_are_jumpers no)
		(fp_rect
			(start -0.2794 0.9906)
			(end 0.2794 -0.1016)
			(stroke
				(width 0)
				(type default)
			)
			(fill no)
			(layer "B.CrtYd")
		)
		(fp_line
			(start 0.2794 0.9906)
			(end -0.2794 0.9906)
			(stroke
				(width 0.1)
				(type default)
			)
			(layer "B.Fab")
		)
		(fp_line
			(start 0.2794 -0.1016)
			(end 0.2794 0.9906)
			(stroke
				(width 0.1)
				(type default)
			)
			(layer "B.Fab")
		)
		(fp_line
			(start -0.2794 0.9906)
			(end -0.2794 -0.1016)
			(stroke
				(width 0.1)
				(type default)
			)
			(layer "B.Fab")
		)
		(fp_line
			(start -0.2794 -0.1016)
			(end 0.2794 -0.1016)
			(stroke
				(width 0.1)
				(type default)
			)
			(layer "B.Fab")
		)
		(pad "1" smd rect
			(at 0 0)
			(size 0.508 0.508)
			(layers "B.Cu" "B.Mask" "B.Paste")
			(net "P3V3_STBY")
		)
		(pad "2" smd rect
			(at 0 0.889)
			(size 0.508 0.508)
			(layers "B.Cu" "B.Mask" "B.Paste")
			(net "VR_PVDDQ_ABC_VDD")
		)
		(zone
			(layer "B.Cu")
			(hatch none 0.5)
			(connect_pads
				(clearance 0)
			)
			(min_thickness 0.25)
			(keepout
				(tracks allowed)
				(vias not_allowed)
				(pads allowed)
				(copperpour not_allowed)
				(footprints allowed)
			)
			(placement
				(enabled no)
				(sheetname "")
			)
			(fill
				(thermal_gap 0.5)
				(thermal_bridge_width 0.5)
				(island_removal_mode 0)
			)
			(polygon
				(pts
					(xy 349.631 -17.145) (xy 349.123 -17.145) (xy 349.123 -16.764) (xy 349.631 -16.764)
				)
			)
		)
		(zone
			(layer "B.Cu")
			(hatch none 0.5)
			(connect_pads
				(clearance 0)
			)
			(min_thickness 0.25)
			(keepout
				(tracks not_allowed)
				(vias allowed)
				(pads allowed)
				(copperpour not_allowed)
				(footprints allowed)
			)
			(placement
				(enabled no)
				(sheetname "")
			)
			(fill
				(thermal_gap 0.5)
				(thermal_bridge_width 0.5)
				(island_removal_mode 0)
			)
			(polygon
				(pts
					(xy 349.631 -17.145) (xy 349.123 -17.145) (xy 349.123 -16.764) (xy 349.631 -16.764)
				)
			)
		)
	)
	(footprint ""
		(layer "B.Cu")
		(at 470.027 -57.912 -90)
		(property "Reference" "R1R20"
			(at 0 0 90)
			(layer "B.SilkS")
			(hide yes)
			(effects
				(font
					(size 1.27 1.27)
				)
				(justify mirror)
			)
		)
		(property "Value" ""
			(at 0 0 90)
			(layer "B.Fab")
			(effects
				(font
					(size 1.27 1.27)
				)
				(justify mirror)
			)
		)
		(duplicate_pad_numbers_are_jumpers no)
		(fp_poly
			(pts
				(xy 0.2794 -0.1016) (xy -0.2794 -0.1016) (xy -0.2794 0.9906) (xy 0.2794 0.9906)
			)
			(stroke
				(width 0)
				(type default)
			)
			(fill no)
			(layer "B.CrtYd")
		)
		(fp_line
			(start -0.2794 0.9906)
			(end -0.2794 -0.1016)
			(stroke
				(width 0.1)
				(type default)
			)
			(layer "B.Fab")
		)
		(fp_line
			(start 0.2794 0.9906)
			(end -0.2794 0.9906)
			(stroke
				(width 0.1)
				(type default)
			)
			(layer "B.Fab")
		)
		(fp_line
			(start -0.2794 -0.1016)
			(end 0.2794 -0.1016)
			(stroke
				(width 0.1)
				(type default)
			)
			(layer "B.Fab")
		)
		(fp_line
			(start 0.2794 -0.1016)
			(end 0.2794 0.9906)
			(stroke
				(width 0.1)
				(type default)
			)
			(layer "B.Fab")
		)
		(pad "1" smd rect
			(at 0 0 90)
			(size 0.508 0.508)
			(layers "B.Cu" "B.Mask" "B.Paste")
			(net "P3V3_STBY")
		)
		(pad "2" smd rect
			(at 0 0.889 90)
			(size 0.508 0.508)
			(layers "B.Cu" "B.Mask" "B.Paste")
			(net "SMB_PCH_MEZZ_LOM1_SCL")
		)
		(zone
			(layer "B.Cu")
			(hatch none 0.5)
			(connect_pads
				(clearance 0)
			)
			(min_thickness 0.25)
			(keepout
				(tracks not_allowed)
				(vias allowed)
				(pads allowed)
				(copperpour not_allowed)
				(footprints allowed)
			)
			(placement
				(enabled no)
				(sheetname "")
			)
			(fill
				(thermal_gap 0.5)
				(thermal_bridge_width 0.5)
				(island_removal_mode 0)
			)
			(polygon
				(pts
					(xy 469.392 -57.658) (xy 469.392 -58.166) (xy 469.773 -58.166) (xy 469.773 -57.658)
				)
			)
		)
		(zone
			(layer "B.Cu")
			(hatch none 0.5)
			(connect_pads
				(clearance 0)
			)
			(min_thickness 0.25)
			(keepout
				(tracks allowed)
				(vias not_allowed)
				(pads allowed)
				(copperpour not_allowed)
				(footprints allowed)
			)
			(placement
				(enabled no)
				(sheetname "")
			)
			(fill
				(thermal_gap 0.5)
				(thermal_bridge_width 0.5)
				(island_removal_mode 0)
			)
			(polygon
				(pts
					(xy 469.773 -57.658) (xy 469.773 -58.166) (xy 469.392 -58.166) (xy 469.392 -57.658)
				)
			)
		)
	)
	(footprint ""
		(layer "B.Cu")
		(at 111.000032 -145.0086 90)
		(property "Reference" "C7L4"
			(at -1.848866 0.752348 90)
			(unlocked yes)
			(layer "B.SilkS")
			(effects
				(font
					(size 1.27 0.9652)
					(thickness 0.1524)
				)
				(justify mirror)
			)
		)
		(property "Value" ""
			(at 0 0 90)
			(layer "B.Fab")
			(effects
				(font
					(size 1.27 1.27)
				)
				(justify mirror)
			)
		)
		(duplicate_pad_numbers_are_jumpers no)
		(fp_rect
			(start 0.500126 1.598422)
			(end -0.500126 -0.201422)
			(stroke
				(width 0)
				(type default)
			)
			(fill no)
			(layer "B.CrtYd")
		)
		(fp_line
			(start 0.500126 -0.201422)
			(end -0.500126 -0.201422)
			(stroke
				(width 0.1)
				(type default)
			)
			(layer "B.Fab")
		)
		(fp_line
			(start -0.500126 -0.201422)
			(end -0.500126 1.598422)
			(stroke
				(width 0.1)
				(type default)
			)
			(layer "B.Fab")
		)
		(fp_line
			(start 0.500126 1.598422)
			(end 0.500126 -0.201422)
			(stroke
				(width 0.1)
				(type default)
			)
			(layer "B.Fab")
		)
		(fp_line
			(start -0.500126 1.598422)
			(end 0.500126 1.598422)
			(stroke
				(width 0.1)
				(type default)
			)
			(layer "B.Fab")
		)
		(pad "1" smd rect
			(at 0 0)
			(size 0.889 0.9906)
			(layers "B.Cu" "B.Mask" "B.Paste")
			(net "PVDDQ_KLM")
		)
		(pad "2" smd rect
			(at 0 1.397)
			(size 0.889 0.9906)
			(layers "B.Cu" "B.Mask" "B.Paste")
			(net "GND")
		)
		(zone
			(layer "B.Cu")
			(hatch none 0.5)
			(connect_pads
				(clearance 0)
			)
			(min_thickness 0.25)
			(keepout
				(tracks allowed)
				(vias not_allowed)
				(pads allowed)
				(copperpour not_allowed)
				(footprints allowed)
			)
			(placement
				(enabled no)
				(sheetname "")
			)
			(fill
				(thermal_gap 0.5)
				(thermal_bridge_width 0.5)
				(island_removal_mode 0)
			)
			(polygon
				(pts
					(xy 111.952532 -145.5039) (xy 111.444532 -145.5039) (xy 111.444532 -144.5133) (xy 111.952532 -144.5133)
				)
			)
		)
		(zone
			(layer "B.Cu")
			(hatch none 0.5)
			(connect_pads
				(clearance 0)
			)
			(min_thickness 0.25)
			(keepout
				(tracks not_allowed)
				(vias allowed)
				(pads allowed)
				(copperpour not_allowed)
				(footprints allowed)
			)
			(placement
				(enabled no)
				(sheetname "")
			)
			(fill
				(thermal_gap 0.5)
				(thermal_bridge_width 0.5)
				(island_removal_mode 0)
			)
			(polygon
				(pts
					(xy 111.952532 -145.5039) (xy 111.444532 -145.5039) (xy 111.444532 -144.5133) (xy 111.952532 -144.5133)
				)
			)
		)
	)
	(footprint ""
		(layer "B.Cu")
		(at 397.886174 -33.262316)
		(property "Reference" "R2T35"
			(at 0 0 0)
			(layer "B.SilkS")
			(hide yes)
			(effects
				(font
					(size 1.27 1.27)
				)
				(justify mirror)
			)
		)
		(property "Value" ""
			(at 0 0 0)
			(layer "B.Fab")
			(effects
				(font
					(size 1.27 1.27)
				)
				(justify mirror)
			)
		)
		(duplicate_pad_numbers_are_jumpers no)
		(fp_poly
			(pts
				(xy 0.2794 -0.1016) (xy -0.2794 -0.1016) (xy -0.2794 0.9906) (xy 0.2794 0.9906)
			)
			(stroke
				(width 0)
				(type default)
			)
			(fill no)
			(layer "B.CrtYd")
		)
		(fp_line
			(start -0.2794 -0.1016)
			(end 0.2794 -0.1016)
			(stroke
				(width 0.1)
				(type default)
			)
			(layer "B.Fab")
		)
		(fp_line
			(start -0.2794 0.9906)
			(end -0.2794 -0.1016)
			(stroke
				(width 0.1)
				(type default)
			)
			(layer "B.Fab")
		)
		(fp_line
			(start 0.2794 -0.1016)
			(end 0.2794 0.9906)
			(stroke
				(width 0.1)
				(type default)
			)
			(layer "B.Fab")
		)
		(fp_line
			(start 0.2794 0.9906)
			(end -0.2794 0.9906)
			(stroke
				(width 0.1)
				(type default)
			)
			(layer "B.Fab")
		)
		(pad "1" smd rect
			(at 0 0 180)
			(size 0.508 0.508)
			(layers "B.Cu" "B.Mask" "B.Paste")
			(net "P3V3_STBY")
		)
		(pad "2" smd rect
			(at 0 0.889 180)
			(size 0.508 0.508)
			(layers "B.Cu" "B.Mask" "B.Paste")
			(net "RST_BMC_SYSRST_BTN_OUT_N")
		)
		(zone
			(layer "B.Cu")
			(hatch none 0.5)
			(connect_pads
				(clearance 0)
			)
			(min_thickness 0.25)
			(keepout
				(tracks allowed)
				(vias not_allowed)
				(pads allowed)
				(copperpour not_allowed)
				(footprints allowed)
			)
			(placement
				(enabled no)
				(sheetname "")
			)
			(fill
				(thermal_gap 0.5)
				(thermal_bridge_width 0.5)
				(island_removal_mode 0)
			)
			(polygon
				(pts
					(xy 398.140174 -33.008316) (xy 397.632174 -33.008316) (xy 397.632174 -32.627316) (xy 398.140174 -32.627316)
				)
			)
		)
		(zone
			(layer "B.Cu")
			(hatch none 0.5)
			(connect_pads
				(clearance 0)
			)
			(min_thickness 0.25)
			(keepout
				(tracks not_allowed)
				(vias allowed)
				(pads allowed)
				(copperpour not_allowed)
				(footprints allowed)
			)
			(placement
				(enabled no)
				(sheetname "")
			)
			(fill
				(thermal_gap 0.5)
				(thermal_bridge_width 0.5)
				(island_removal_mode 0)
			)
			(polygon
				(pts
					(xy 398.140174 -32.627316) (xy 397.632174 -32.627316) (xy 397.632174 -33.008316) (xy 398.140174 -33.008316)
				)
			)
		)
	)
	(footprint ""
		(layer "B.Cu")
		(at 470.4715 -138.557 90)
		(property "Reference" "R1L27"
			(at 0 0 90)
			(layer "B.SilkS")
			(hide yes)
			(effects
				(font
					(size 1.27 1.27)
				)
				(justify mirror)
			)
		)
		(property "Value" ""
			(at 0 0 90)
			(layer "B.Fab")
			(effects
				(font
					(size 1.27 1.27)
				)
				(justify mirror)
			)
		)
		(duplicate_pad_numbers_are_jumpers no)
		(fp_poly
			(pts
				(xy 0.2794 -0.1016) (xy -0.2794 -0.1016) (xy -0.2794 0.9906) (xy 0.2794 0.9906)
			)
			(stroke
				(width 0)
				(type default)
			)
			(fill no)
			(layer "B.CrtYd")
		)
		(fp_line
			(start 0.2794 -0.1016)
			(end 0.2794 0.9906)
			(stroke
				(width 0.1)
				(type default)
			)
			(layer "B.Fab")
		)
		(fp_line
			(start -0.2794 -0.1016)
			(end 0.2794 -0.1016)
			(stroke
				(width 0.1)
				(type default)
			)
			(layer "B.Fab")
		)
		(fp_line
			(start 0.2794 0.9906)
			(end -0.2794 0.9906)
			(stroke
				(width 0.1)
				(type default)
			)
			(layer "B.Fab")
		)
		(fp_line
			(start -0.2794 0.9906)
			(end -0.2794 -0.1016)
			(stroke
				(width 0.1)
				(type default)
			)
			(layer "B.Fab")
		)
		(pad "1" smd rect
			(at 0 0 270)
			(size 0.508 0.508)
			(layers "B.Cu" "B.Mask" "B.Paste")
			(net "P3V3_STBY")
		)
		(pad "2" smd rect
			(at 0 0.889 270)
			(size 0.508 0.508)
			(layers "B.Cu" "B.Mask" "B.Paste")
			(net "FP_PWR_BTN_R_N")
		)
		(zone
			(layer "B.Cu")
			(hatch none 0.5)
			(connect_pads
				(clearance 0)
			)
			(min_thickness 0.25)
			(keepout
				(tracks allowed)
				(vias not_allowed)
				(pads allowed)
				(copperpour not_allowed)
				(footprints allowed)
			)
			(placement
				(enabled no)
				(sheetname "")
			)
			(fill
				(thermal_gap 0.5)
				(thermal_bridge_width 0.5)
				(island_removal_mode 0)
			)
			(polygon
				(pts
					(xy 470.7255 -138.811) (xy 470.7255 -138.303) (xy 471.1065 -138.303) (xy 471.1065 -138.811)
				)
			)
		)
		(zone
			(layer "B.Cu")
			(hatch none 0.5)
			(connect_pads
				(clearance 0)
			)
			(min_thickness 0.25)
			(keepout
				(tracks not_allowed)
				(vias allowed)
				(pads allowed)
				(copperpour not_allowed)
				(footprints allowed)
			)
			(placement
				(enabled no)
				(sheetname "")
			)
			(fill
				(thermal_gap 0.5)
				(thermal_bridge_width 0.5)
				(island_removal_mode 0)
			)
			(polygon
				(pts
					(xy 471.1065 -138.811) (xy 471.1065 -138.303) (xy 470.7255 -138.303) (xy 470.7255 -138.811)
				)
			)
		)
	)
	(footprint ""
		(layer "B.Cu")
		(at 476.885 -34.0995)
		(property "Reference" "C2T38"
			(at 0 0 0)
			(layer "B.SilkS")
			(hide yes)
			(effects
				(font
					(size 1.27 1.27)
				)
				(justify mirror)
			)
		)
		(property "Value" ""
			(at 0 0 0)
			(layer "B.Fab")
			(effects
				(font
					(size 1.27 1.27)
				)
				(justify mirror)
			)
		)
		(duplicate_pad_numbers_are_jumpers no)
		(fp_poly
			(pts
				(xy -0.3048 -0.1016) (xy -0.3048 0.9906) (xy 0.3048 0.9906) (xy 0.3048 -0.1016)
			)
			(stroke
				(width 0)
				(type default)
			)
			(fill no)
			(layer "B.CrtYd")
		)
		(fp_line
			(start -0.3048 -0.1016)
			(end 0.3048 -0.1016)
			(stroke
				(width 0.1)
				(type default)
			)
			(layer "B.Fab")
		)
		(fp_line
			(start -0.3048 0.9906)
			(end -0.3048 -0.1016)
			(stroke
				(width 0.1)
				(type default)
			)
			(layer "B.Fab")
		)
		(fp_line
			(start 0.3048 -0.1016)
			(end 0.3048 0.9906)
			(stroke
				(width 0.1)
				(type default)
			)
			(layer "B.Fab")
		)
		(fp_line
			(start 0.3048 0.9906)
			(end -0.3048 0.9906)
			(stroke
				(width 0.1)
				(type default)
			)
			(layer "B.Fab")
		)
		(pad "1" smd rect
			(at 0 0 180)
			(size 0.508 0.508)
			(layers "B.Cu" "B.Mask" "B.Paste")
			(net "P3V3_STBY_MNG_RMII")
		)
		(pad "2" smd rect
			(at 0 0.889 180)
			(size 0.508 0.508)
			(layers "B.Cu" "B.Mask" "B.Paste")
			(net "GND")
		)
		(zone
			(layer "B.Cu")
			(hatch none 0.5)
			(connect_pads
				(clearance 0)
			)
			(min_thickness 0.25)
			(keepout
				(tracks allowed)
				(vias not_allowed)
				(pads allowed)
				(copperpour not_allowed)
				(footprints allowed)
			)
			(placement
				(enabled no)
				(sheetname "")
			)
			(fill
				(thermal_gap 0.5)
				(thermal_bridge_width 0.5)
				(island_removal_mode 0)
			)
			(polygon
				(pts
					(xy 477.139 -33.8455) (xy 476.631 -33.8455) (xy 476.631 -33.4645) (xy 477.139 -33.4645)
				)
			)
		)
		(zone
			(layer "B.Cu")
			(hatch none 0.5)
			(connect_pads
				(clearance 0)
			)
			(min_thickness 0.25)
			(keepout
				(tracks not_allowed)
				(vias allowed)
				(pads allowed)
				(copperpour not_allowed)
				(footprints allowed)
			)
			(placement
				(enabled no)
				(sheetname "")
			)
			(fill
				(thermal_gap 0.5)
				(thermal_bridge_width 0.5)
				(island_removal_mode 0)
			)
			(polygon
				(pts
					(xy 477.139 -33.4645) (xy 476.631 -33.4645) (xy 476.631 -33.8455) (xy 477.139 -33.8455)
				)
			)
		)
	)
	(footprint ""
		(layer "B.Cu")
		(at 228.1174 -86.614 90)
		(property "Reference" "R4C5"
			(at 0.8382 -0.67818 90)
			(unlocked yes)
			(layer "B.SilkS")
			(effects
				(font
					(size 0.4064 0.254)
					(thickness 0.1524)
				)
				(justify left mirror)
			)
		)
		(property "Value" ""
			(at 0 0 90)
			(layer "B.Fab")
			(effects
				(font
					(size 1.27 1.27)
				)
				(justify mirror)
			)
		)
		(duplicate_pad_numbers_are_jumpers no)
		(fp_poly
			(pts
				(xy 0.2794 -0.1016) (xy -0.2794 -0.1016) (xy -0.2794 0.9906) (xy 0.2794 0.9906)
			)
			(stroke
				(width 0)
				(type default)
			)
			(fill no)
			(layer "B.CrtYd")
		)
		(fp_line
			(start 0.2794 -0.1016)
			(end 0.2794 0.9906)
			(stroke
				(width 0.1)
				(type default)
			)
			(layer "B.Fab")
		)
		(fp_line
			(start -0.2794 -0.1016)
			(end 0.2794 -0.1016)
			(stroke
				(width 0.1)
				(type default)
			)
			(layer "B.Fab")
		)
		(fp_line
			(start 0.2794 0.9906)
			(end -0.2794 0.9906)
			(stroke
				(width 0.1)
				(type default)
			)
			(layer "B.Fab")
		)
		(fp_line
			(start -0.2794 0.9906)
			(end -0.2794 -0.1016)
			(stroke
				(width 0.1)
				(type default)
			)
			(layer "B.Fab")
		)
		(pad "1" smd rect
			(at 0 0 270)
			(size 0.508 0.508)
			(layers "B.Cu" "B.Mask" "B.Paste")
			(net "VSENSE_PVSA_CPU0_P")
		)
		(pad "2" smd rect
			(at 0 0.889 270)
			(size 0.508 0.508)
			(layers "B.Cu" "B.Mask" "B.Paste")
			(net "PVSA_CPU0")
		)
		(zone
			(layer "B.Cu")
			(hatch none 0.5)
			(connect_pads
				(clearance 0)
			)
			(min_thickness 0.25)
			(keepout
				(tracks allowed)
				(vias not_allowed)
				(pads allowed)
				(copperpour not_allowed)
				(footprints allowed)
			)
			(placement
				(enabled no)
				(sheetname "")
			)
			(fill
				(thermal_gap 0.5)
				(thermal_bridge_width 0.5)
				(island_removal_mode 0)
			)
			(polygon
				(pts
					(xy 228.3714 -86.868) (xy 228.3714 -86.36) (xy 228.7524 -86.36) (xy 228.7524 -86.868)
				)
			)
		)
		(zone
			(layer "B.Cu")
			(hatch none 0.5)
			(connect_pads
				(clearance 0)
			)
			(min_thickness 0.25)
			(keepout
				(tracks not_allowed)
				(vias allowed)
				(pads allowed)
				(copperpour not_allowed)
				(footprints allowed)
			)
			(placement
				(enabled no)
				(sheetname "")
			)
			(fill
				(thermal_gap 0.5)
				(thermal_bridge_width 0.5)
				(island_removal_mode 0)
			)
			(polygon
				(pts
					(xy 228.7524 -86.868) (xy 228.7524 -86.36) (xy 228.3714 -86.36) (xy 228.3714 -86.868)
				)
			)
		)
	)
	(footprint ""
		(layer "B.Cu")
		(at 436.626 -52.3875)
		(property "Reference" "C2R18"
			(at 0 0 0)
			(layer "B.SilkS")
			(hide yes)
			(effects
				(font
					(size 1.27 1.27)
				)
				(justify mirror)
			)
		)
		(property "Value" ""
			(at 0 0 0)
			(layer "B.Fab")
			(effects
				(font
					(size 1.27 1.27)
				)
				(justify mirror)
			)
		)
		(duplicate_pad_numbers_are_jumpers no)
		(fp_poly
			(pts
				(xy -0.3048 -0.1016) (xy -0.3048 0.9906) (xy 0.3048 0.9906) (xy 0.3048 -0.1016)
			)
			(stroke
				(width 0)
				(type default)
			)
			(fill no)
			(layer "B.CrtYd")
		)
		(fp_line
			(start -0.3048 -0.1016)
			(end 0.3048 -0.1016)
			(stroke
				(width 0.1)
				(type default)
			)
			(layer "B.Fab")
		)
		(fp_line
			(start -0.3048 0.9906)
			(end -0.3048 -0.1016)
			(stroke
				(width 0.1)
				(type default)
			)
			(layer "B.Fab")
		)
		(fp_line
			(start 0.3048 -0.1016)
			(end 0.3048 0.9906)
			(stroke
				(width 0.1)
				(type default)
			)
			(layer "B.Fab")
		)
		(fp_line
			(start 0.3048 0.9906)
			(end -0.3048 0.9906)
			(stroke
				(width 0.1)
				(type default)
			)
			(layer "B.Fab")
		)
		(pad "1" smd rect
			(at 0 0 180)
			(size 0.508 0.508)
			(layers "B.Cu" "B.Mask" "B.Paste")
			(net "P12V_STBY")
		)
		(pad "2" smd rect
			(at 0 0.889 180)
			(size 0.508 0.508)
			(layers "B.Cu" "B.Mask" "B.Paste")
			(net "GND")
		)
		(zone
			(layer "B.Cu")
			(hatch none 0.5)
			(connect_pads
				(clearance 0)
			)
			(min_thickness 0.25)
			(keepout
				(tracks allowed)
				(vias not_allowed)
				(pads allowed)
				(copperpour not_allowed)
				(footprints allowed)
			)
			(placement
				(enabled no)
				(sheetname "")
			)
			(fill
				(thermal_gap 0.5)
				(thermal_bridge_width 0.5)
				(island_removal_mode 0)
			)
			(polygon
				(pts
					(xy 436.88 -52.1335) (xy 436.372 -52.1335) (xy 436.372 -51.7525) (xy 436.88 -51.7525)
				)
			)
		)
		(zone
			(layer "B.Cu")
			(hatch none 0.5)
			(connect_pads
				(clearance 0)
			)
			(min_thickness 0.25)
			(keepout
				(tracks not_allowed)
				(vias allowed)
				(pads allowed)
				(copperpour not_allowed)
				(footprints allowed)
			)
			(placement
				(enabled no)
				(sheetname "")
			)
			(fill
				(thermal_gap 0.5)
				(thermal_bridge_width 0.5)
				(island_removal_mode 0)
			)
			(polygon
				(pts
					(xy 436.88 -51.7525) (xy 436.372 -51.7525) (xy 436.372 -52.1335) (xy 436.88 -52.1335)
				)
			)
		)
	)
	(footprint ""
		(layer "B.Cu")
		(at 155.194 -17.78 90)
		(property "Reference" "C7T2"
			(at 0 0 90)
			(layer "B.SilkS")
			(hide yes)
			(effects
				(font
					(size 1.27 1.27)
				)
				(justify mirror)
			)
		)
		(property "Value" ""
			(at 0 0 90)
			(layer "B.Fab")
			(effects
				(font
					(size 1.27 1.27)
				)
				(justify mirror)
			)
		)
		(duplicate_pad_numbers_are_jumpers no)
		(fp_poly
			(pts
				(xy 0.4953 -0.2032) (xy -0.4953 -0.2032) (xy -0.4953 1.6002) (xy 0.4953 1.6002)
			)
			(stroke
				(width 0)
				(type default)
			)
			(fill no)
			(layer "B.CrtYd")
		)
		(fp_line
			(start 0.4953 -0.2032)
			(end -0.4953 -0.2032)
			(stroke
				(width 0.1)
				(type default)
			)
			(layer "B.Fab")
		)
		(fp_line
			(start -0.4953 -0.2032)
			(end -0.4953 1.6002)
			(stroke
				(width 0.1)
				(type default)
			)
			(layer "B.Fab")
		)
		(fp_line
			(start 0.4953 1.6002)
			(end 0.4953 -0.2032)
			(stroke
				(width 0.1)
				(type default)
			)
			(layer "B.Fab")
		)
		(fp_line
			(start -0.4953 1.6002)
			(end 0.4953 1.6002)
			(stroke
				(width 0.1)
				(type default)
			)
			(layer "B.Fab")
		)
		(pad "1" smd rect
			(at 0 0 270)
			(size 0.762 0.889)
			(layers "B.Cu" "B.Mask" "B.Paste")
			(net "PVPP_GHJ")
		)
		(pad "2" smd rect
			(at 0 1.397 270)
			(size 0.762 0.889)
			(layers "B.Cu" "B.Mask" "B.Paste")
			(net "GND")
		)
		(zone
			(layer "B.Cu")
			(hatch none 0.5)
			(connect_pads
				(clearance 0)
			)
			(min_thickness 0.25)
			(keepout
				(tracks not_allowed)
				(vias allowed)
				(pads allowed)
				(copperpour not_allowed)
				(footprints allowed)
			)
			(placement
				(enabled no)
				(sheetname "")
			)
			(fill
				(thermal_gap 0.5)
				(thermal_bridge_width 0.5)
				(island_removal_mode 0)
			)
			(polygon
				(pts
					(xy 155.6385 -18.161) (xy 155.6385 -17.399) (xy 156.1465 -17.399) (xy 156.1465 -18.161)
				)
			)
		)
	)
	(footprint ""
		(layer "B.Cu")
		(at 347.469206 4.370578 -90)
		(property "Reference" "C3U9"
			(at 0 0 90)
			(layer "B.SilkS")
			(hide yes)
			(effects
				(font
					(size 1.27 1.27)
				)
				(justify mirror)
			)
		)
		(property "Value" ""
			(at 0 0 90)
			(layer "B.Fab")
			(effects
				(font
					(size 1.27 1.27)
				)
				(justify mirror)
			)
		)
		(duplicate_pad_numbers_are_jumpers no)
		(fp_rect
			(start 0.7239 1.9939)
			(end -0.7239 -0.2159)
			(stroke
				(width 0)
				(type default)
			)
			(fill no)
			(layer "B.CrtYd")
		)
		(fp_line
			(start -0.7239 1.9939)
			(end -0.7239 -0.2159)
			(stroke
				(width 0.1)
				(type default)
			)
			(layer "B.Fab")
		)
		(fp_line
			(start 0.7239 1.9939)
			(end -0.7239 1.9939)
			(stroke
				(width 0.1)
				(type default)
			)
			(layer "B.Fab")
		)
		(fp_line
			(start -0.7239 -0.2159)
			(end 0.7239 -0.2159)
			(stroke
				(width 0.1)
				(type default)
			)
			(layer "B.Fab")
		)
		(fp_line
			(start 0.7239 -0.2159)
			(end 0.7239 1.9939)
			(stroke
				(width 0.1)
				(type default)
			)
			(layer "B.Fab")
		)
		(pad "1" smd rect
			(at 0 0 90)
			(size 1.27 1.016)
			(layers "B.Cu" "B.Mask" "B.Paste")
			(net "VR_FET_SW_P12V_STBY_PVDDQ_ABC")
		)
		(pad "2" smd rect
			(at 0 1.778 90)
			(size 1.27 1.016)
			(layers "B.Cu" "B.Mask" "B.Paste")
			(net "GND")
		)
		(zone
			(layer "B.Cu")
			(hatch none 0.5)
			(connect_pads
				(clearance 0)
			)
			(min_thickness 0.25)
			(keepout
				(tracks not_allowed)
				(vias allowed)
				(pads allowed)
				(copperpour not_allowed)
				(footprints allowed)
			)
			(placement
				(enabled no)
				(sheetname "")
			)
			(fill
				(thermal_gap 0.5)
				(thermal_bridge_width 0.5)
				(island_removal_mode 0)
			)
			(polygon
				(pts
					(xy 346.199206 5.005578) (xy 346.961206 5.005578) (xy 346.961206 3.735578) (xy 346.199206 3.735578)
				)
			)
		)
	)
	(footprint ""
		(layer "B.Cu")
		(at 176.212754 -83.947 -90)
		(property "Reference" "R6P11"
			(at 0 0 90)
			(layer "B.SilkS")
			(hide yes)
			(effects
				(font
					(size 1.27 1.27)
				)
				(justify mirror)
			)
		)
		(property "Value" ""
			(at 0 0 90)
			(layer "B.Fab")
			(effects
				(font
					(size 1.27 1.27)
				)
				(justify mirror)
			)
		)
		(duplicate_pad_numbers_are_jumpers no)
		(fp_poly
			(pts
				(xy 0.2794 -0.1016) (xy -0.2794 -0.1016) (xy -0.2794 0.9906) (xy 0.2794 0.9906)
			)
			(stroke
				(width 0)
				(type default)
			)
			(fill no)
			(layer "B.CrtYd")
		)
		(fp_line
			(start -0.2794 0.9906)
			(end -0.2794 -0.1016)
			(stroke
				(width 0.1)
				(type default)
			)
			(layer "B.Fab")
		)
		(fp_line
			(start 0.2794 0.9906)
			(end -0.2794 0.9906)
			(stroke
				(width 0.1)
				(type default)
			)
			(layer "B.Fab")
		)
		(fp_line
			(start -0.2794 -0.1016)
			(end 0.2794 -0.1016)
			(stroke
				(width 0.1)
				(type default)
			)
			(layer "B.Fab")
		)
		(fp_line
			(start 0.2794 -0.1016)
			(end 0.2794 0.9906)
			(stroke
				(width 0.1)
				(type default)
			)
			(layer "B.Fab")
		)
		(pad "1" smd rect
			(at 0 0 90)
			(size 0.508 0.508)
			(layers "B.Cu" "B.Mask" "B.Paste")
			(net "CLK_100M_CPU0_PE_REFCLK_DP")
		)
		(pad "2" smd rect
			(at 0 0.889 90)
			(size 0.508 0.508)
			(layers "B.Cu" "B.Mask" "B.Paste")
			(net "GND")
		)
		(zone
			(layer "B.Cu")
			(hatch none 0.5)
			(connect_pads
				(clearance 0)
			)
			(min_thickness 0.25)
			(keepout
				(tracks not_allowed)
				(vias allowed)
				(pads allowed)
				(copperpour not_allowed)
				(footprints allowed)
			)
			(placement
				(enabled no)
				(sheetname "")
			)
			(fill
				(thermal_gap 0.5)
				(thermal_bridge_width 0.5)
				(island_removal_mode 0)
			)
			(polygon
				(pts
					(xy 175.577754 -83.693) (xy 175.577754 -84.201) (xy 175.958754 -84.201) (xy 175.958754 -83.693)
				)
			)
		)
		(zone
			(layer "B.Cu")
			(hatch none 0.5)
			(connect_pads
				(clearance 0)
			)
			(min_thickness 0.25)
			(keepout
				(tracks allowed)
				(vias not_allowed)
				(pads allowed)
				(copperpour not_allowed)
				(footprints allowed)
			)
			(placement
				(enabled no)
				(sheetname "")
			)
			(fill
				(thermal_gap 0.5)
				(thermal_bridge_width 0.5)
				(island_removal_mode 0)
			)
			(polygon
				(pts
					(xy 175.958754 -83.693) (xy 175.958754 -84.201) (xy 175.577754 -84.201) (xy 175.577754 -83.693)
				)
			)
		)
	)
	(footprint ""
		(layer "B.Cu")
		(at 181.864 -145.796 180)
		(property "Reference" "R6L11"
			(at 0 0 0)
			(layer "B.SilkS")
			(hide yes)
			(effects
				(font
					(size 1.27 1.27)
				)
				(justify mirror)
			)
		)
		(property "Value" ""
			(at 0 0 0)
			(layer "B.Fab")
			(effects
				(font
					(size 1.27 1.27)
				)
				(justify mirror)
			)
		)
		(duplicate_pad_numbers_are_jumpers no)
		(fp_rect
			(start -0.2794 0.9906)
			(end 0.2794 -0.1016)
			(stroke
				(width 0)
				(type default)
			)
			(fill no)
			(layer "B.CrtYd")
		)
		(fp_line
			(start 0.2794 0.9906)
			(end -0.2794 0.9906)
			(stroke
				(width 0.1)
				(type default)
			)
			(layer "B.Fab")
		)
		(fp_line
			(start 0.2794 -0.1016)
			(end 0.2794 0.9906)
			(stroke
				(width 0.1)
				(type default)
			)
			(layer "B.Fab")
		)
		(fp_line
			(start -0.2794 0.9906)
			(end -0.2794 -0.1016)
			(stroke
				(width 0.1)
				(type default)
			)
			(layer "B.Fab")
		)
		(fp_line
			(start -0.2794 -0.1016)
			(end 0.2794 -0.1016)
			(stroke
				(width 0.1)
				(type default)
			)
			(layer "B.Fab")
		)
		(pad "1" smd rect
			(at 0 0)
			(size 0.508 0.508)
			(layers "B.Cu" "B.Mask" "B.Paste")
			(net "P3V3")
		)
		(pad "2" smd rect
			(at 0 0.889)
			(size 0.508 0.508)
			(layers "B.Cu" "B.Mask" "B.Paste")
			(net "VR_PVTT_DEF_BIAS")
		)
		(zone
			(layer "B.Cu")
			(hatch none 0.5)
			(connect_pads
				(clearance 0)
			)
			(min_thickness 0.25)
			(keepout
				(tracks not_allowed)
				(vias allowed)
				(pads allowed)
				(copperpour not_allowed)
				(footprints allowed)
			)
			(placement
				(enabled no)
				(sheetname "")
			)
			(fill
				(thermal_gap 0.5)
				(thermal_bridge_width 0.5)
				(island_removal_mode 0)
			)
			(polygon
				(pts
					(xy 182.118 -146.431) (xy 181.61 -146.431) (xy 181.61 -146.05) (xy 182.118 -146.05)
				)
			)
		)
		(zone
			(layer "B.Cu")
			(hatch none 0.5)
			(connect_pads
				(clearance 0)
			)
			(min_thickness 0.25)
			(keepout
				(tracks allowed)
				(vias not_allowed)
				(pads allowed)
				(copperpour not_allowed)
				(footprints allowed)
			)
			(placement
				(enabled no)
				(sheetname "")
			)
			(fill
				(thermal_gap 0.5)
				(thermal_bridge_width 0.5)
				(island_removal_mode 0)
			)
			(polygon
				(pts
					(xy 182.118 -146.431) (xy 181.61 -146.431) (xy 181.61 -146.05) (xy 182.118 -146.05)
				)
			)
		)
	)
	(footprint ""
		(layer "B.Cu")
		(at 2.54 -59.944 -90)
		(property "Reference" "C9R6"
			(at 0 0 90)
			(layer "B.SilkS")
			(hide yes)
			(effects
				(font
					(size 1.27 1.27)
				)
				(justify mirror)
			)
		)
		(property "Value" ""
			(at 0 0 90)
			(layer "B.Fab")
			(effects
				(font
					(size 1.27 1.27)
				)
				(justify mirror)
			)
		)
		(duplicate_pad_numbers_are_jumpers no)
		(fp_rect
			(start 0.3048 -0.1016)
			(end -0.3048 0.9906)
			(stroke
				(width 0)
				(type default)
			)
			(fill no)
			(layer "B.CrtYd")
		)
		(fp_line
			(start -0.3048 0.9906)
			(end -0.3048 -0.1016)
			(stroke
				(width 0.1)
				(type default)
			)
			(layer "B.Fab")
		)
		(fp_line
			(start 0.3048 0.9906)
			(end -0.3048 0.9906)
			(stroke
				(width 0.1)
				(type default)
			)
			(layer "B.Fab")
		)
		(fp_line
			(start -0.3048 -0.1016)
			(end 0.3048 -0.1016)
			(stroke
				(width 0.1)
				(type default)
			)
			(layer "B.Fab")
		)
		(fp_line
			(start 0.3048 -0.1016)
			(end 0.3048 0.9906)
			(stroke
				(width 0.1)
				(type default)
			)
			(layer "B.Fab")
		)
		(pad "1" smd rect
			(at 0 0 90)
			(size 0.508 0.508)
			(layers "B.Cu" "B.Mask" "B.Paste")
			(net "P12V_PSU")
		)
		(pad "2" smd rect
			(at 0 0.889 90)
			(size 0.508 0.508)
			(layers "B.Cu" "B.Mask" "B.Paste")
			(net "GND")
		)
		(zone
			(layer "B.Cu")
			(hatch none 0.5)
			(connect_pads
				(clearance 0)
			)
			(min_thickness 0.25)
			(keepout
				(tracks allowed)
				(vias not_allowed)
				(pads allowed)
				(copperpour not_allowed)
				(footprints allowed)
			)
			(placement
				(enabled no)
				(sheetname "")
			)
			(fill
				(thermal_gap 0.5)
				(thermal_bridge_width 0.5)
				(island_removal_mode 0)
			)
			(polygon
				(pts
					(xy 2.286 -59.69) (xy 2.286 -60.198) (xy 1.905 -60.198) (xy 1.905 -59.69)
				)
			)
		)
		(zone
			(layer "B.Cu")
			(hatch none 0.5)
			(connect_pads
				(clearance 0)
			)
			(min_thickness 0.25)
			(keepout
				(tracks not_allowed)
				(vias allowed)
				(pads allowed)
				(copperpour not_allowed)
				(footprints allowed)
			)
			(placement
				(enabled no)
				(sheetname "")
			)
			(fill
				(thermal_gap 0.5)
				(thermal_bridge_width 0.5)
				(island_removal_mode 0)
			)
			(polygon
				(pts
					(xy 2.286 -59.69) (xy 2.286 -60.198) (xy 1.905 -60.198) (xy 1.905 -59.69)
				)
			)
		)
	)
	(footprint ""
		(layer "B.Cu")
		(at 99.415854 -79.60614 180)
		(property "Reference" "C8P12"
			(at 0 0 0)
			(layer "B.SilkS")
			(hide yes)
			(effects
				(font
					(size 1.27 1.27)
				)
				(justify mirror)
			)
		)
		(property "Value" ""
			(at 0 0 0)
			(layer "B.Fab")
			(effects
				(font
					(size 1.27 1.27)
				)
				(justify mirror)
			)
		)
		(duplicate_pad_numbers_are_jumpers no)
		(fp_poly
			(pts
				(xy 0.7239 -0.2159) (xy -0.7239 -0.2159) (xy -0.7239 1.9939) (xy 0.7239 1.9939)
			)
			(stroke
				(width 0)
				(type default)
			)
			(fill no)
			(layer "B.CrtYd")
		)
		(fp_line
			(start 0.7239 1.9939)
			(end -0.7239 1.9939)
			(stroke
				(width 0.1)
				(type default)
			)
			(layer "B.Fab")
		)
		(fp_line
			(start 0.7239 -0.2159)
			(end 0.7239 1.9939)
			(stroke
				(width 0.1)
				(type default)
			)
			(layer "B.Fab")
		)
		(fp_line
			(start -0.7239 1.9939)
			(end -0.7239 -0.2159)
			(stroke
				(width 0.1)
				(type default)
			)
			(layer "B.Fab")
		)
		(fp_line
			(start -0.7239 -0.2159)
			(end 0.7239 -0.2159)
			(stroke
				(width 0.1)
				(type default)
			)
			(layer "B.Fab")
		)
		(pad "1" smd rect
			(at 0 0)
			(size 1.27 1.016)
			(layers "B.Cu" "B.Mask" "B.Paste")
			(net "PVCCIN_CPU1")
		)
		(pad "2" smd rect
			(at 0 1.778)
			(size 1.27 1.016)
			(layers "B.Cu" "B.Mask" "B.Paste")
			(net "GND")
		)
		(zone
			(layer "B.Cu")
			(hatch none 0.5)
			(connect_pads
				(clearance 0)
			)
			(min_thickness 0.25)
			(keepout
				(tracks not_allowed)
				(vias allowed)
				(pads allowed)
				(copperpour not_allowed)
				(footprints allowed)
			)
			(placement
				(enabled no)
				(sheetname "")
			)
			(fill
				(thermal_gap 0.5)
				(thermal_bridge_width 0.5)
				(island_removal_mode 0)
			)
			(polygon
				(pts
					(xy 98.780854 -80.11414) (xy 100.050854 -80.11414) (xy 100.050854 -80.87614) (xy 98.780854 -80.87614)
				)
			)
		)
	)
	(footprint ""
		(layer "B.Cu")
		(at 367.157 -40.5892 180)
		(property "Reference" "R8F14"
			(at 0 0 0)
			(layer "B.SilkS")
			(hide yes)
			(effects
				(font
					(size 1.27 1.27)
				)
				(justify mirror)
			)
		)
		(property "Value" ""
			(at 0 0 0)
			(layer "B.Fab")
			(effects
				(font
					(size 1.27 1.27)
				)
				(justify mirror)
			)
		)
		(duplicate_pad_numbers_are_jumpers no)
		(fp_poly
			(pts
				(xy 0.2794 -0.1016) (xy -0.2794 -0.1016) (xy -0.2794 0.9906) (xy 0.2794 0.9906)
			)
			(stroke
				(width 0)
				(type default)
			)
			(fill no)
			(layer "B.CrtYd")
		)
		(fp_line
			(start 0.2794 0.9906)
			(end -0.2794 0.9906)
			(stroke
				(width 0.1)
				(type default)
			)
			(layer "B.Fab")
		)
		(fp_line
			(start 0.2794 -0.1016)
			(end 0.2794 0.9906)
			(stroke
				(width 0.1)
				(type default)
			)
			(layer "B.Fab")
		)
		(fp_line
			(start -0.2794 0.9906)
			(end -0.2794 -0.1016)
			(stroke
				(width 0.1)
				(type default)
			)
			(layer "B.Fab")
		)
		(fp_line
			(start -0.2794 -0.1016)
			(end 0.2794 -0.1016)
			(stroke
				(width 0.1)
				(type default)
			)
			(layer "B.Fab")
		)
		(pad "1" smd rect
			(at 0 0)
			(size 0.508 0.508)
			(layers "B.Cu" "B.Mask" "B.Paste")
			(net "P3V3_STBY")
		)
		(pad "2" smd rect
			(at 0 0.889)
			(size 0.508 0.508)
			(layers "B.Cu" "B.Mask" "B.Paste")
			(net "PU_SPI_BMC_BT_HOLD_N")
		)
		(zone
			(layer "B.Cu")
			(hatch none 0.5)
			(connect_pads
				(clearance 0)
			)
			(min_thickness 0.25)
			(keepout
				(tracks not_allowed)
				(vias allowed)
				(pads allowed)
				(copperpour not_allowed)
				(footprints allowed)
			)
			(placement
				(enabled no)
				(sheetname "")
			)
			(fill
				(thermal_gap 0.5)
				(thermal_bridge_width 0.5)
				(island_removal_mode 0)
			)
			(polygon
				(pts
					(xy 366.903 -41.2242) (xy 367.411 -41.2242) (xy 367.411 -40.8432) (xy 366.903 -40.8432)
				)
			)
		)
		(zone
			(layer "B.Cu")
			(hatch none 0.5)
			(connect_pads
				(clearance 0)
			)
			(min_thickness 0.25)
			(keepout
				(tracks allowed)
				(vias not_allowed)
				(pads allowed)
				(copperpour not_allowed)
				(footprints allowed)
			)
			(placement
				(enabled no)
				(sheetname "")
			)
			(fill
				(thermal_gap 0.5)
				(thermal_bridge_width 0.5)
				(island_removal_mode 0)
			)
			(polygon
				(pts
					(xy 366.903 -40.8432) (xy 367.411 -40.8432) (xy 367.411 -41.2242) (xy 366.903 -41.2242)
				)
			)
		)
	)
	(footprint ""
		(layer "B.Cu")
		(at 463.492088 -11.993372 -90)
		(property "Reference" "C2U1"
			(at 0 0 90)
			(layer "B.SilkS")
			(hide yes)
			(effects
				(font
					(size 1.27 1.27)
				)
				(justify mirror)
			)
		)
		(property "Value" ""
			(at 0 0 90)
			(layer "B.Fab")
			(effects
				(font
					(size 1.27 1.27)
				)
				(justify mirror)
			)
		)
		(duplicate_pad_numbers_are_jumpers no)
		(fp_rect
			(start -0.7239 1.9939)
			(end 0.7239 -0.2159)
			(stroke
				(width 0)
				(type default)
			)
			(fill no)
			(layer "B.CrtYd")
		)
		(fp_line
			(start -0.7239 1.9939)
			(end -0.7239 -0.2159)
			(stroke
				(width 0.1)
				(type default)
			)
			(layer "B.Fab")
		)
		(fp_line
			(start 0.7239 1.9939)
			(end -0.7239 1.9939)
			(stroke
				(width 0.1)
				(type default)
			)
			(layer "B.Fab")
		)
		(fp_line
			(start -0.7239 -0.2159)
			(end 0.7239 -0.2159)
			(stroke
				(width 0.1)
				(type default)
			)
			(layer "B.Fab")
		)
		(fp_line
			(start 0.7239 -0.2159)
			(end 0.7239 1.9939)
			(stroke
				(width 0.1)
				(type default)
			)
			(layer "B.Fab")
		)
		(pad "1" smd rect
			(at 0 0 90)
			(size 1.27 1.016)
			(layers "B.Cu" "B.Mask" "B.Paste")
			(net "P3V3_STBY")
		)
		(pad "2" smd rect
			(at 0 1.778 90)
			(size 1.27 1.016)
			(layers "B.Cu" "B.Mask" "B.Paste")
			(net "GND")
		)
		(zone
			(layer "B.Cu")
			(hatch none 0.5)
			(connect_pads
				(clearance 0)
			)
			(min_thickness 0.25)
			(keepout
				(tracks not_allowed)
				(vias allowed)
				(pads allowed)
				(copperpour not_allowed)
				(footprints allowed)
			)
			(placement
				(enabled no)
				(sheetname "")
			)
			(fill
				(thermal_gap 0.5)
				(thermal_bridge_width 0.5)
				(island_removal_mode 0)
			)
			(polygon
				(pts
					(xy 462.222088 -12.628372) (xy 462.222088 -11.358372) (xy 462.984088 -11.358372) (xy 462.984088 -12.628372)
				)
			)
		)
	)
	(footprint ""
		(layer "B.Cu")
		(at 485.049322 4.971288 90)
		(property "Reference" "R9G4"
			(at 0 0 90)
			(layer "B.SilkS")
			(hide yes)
			(effects
				(font
					(size 1.27 1.27)
				)
				(justify mirror)
			)
		)
		(property "Value" ""
			(at 0 0 90)
			(layer "B.Fab")
			(effects
				(font
					(size 1.27 1.27)
				)
				(justify mirror)
			)
		)
		(duplicate_pad_numbers_are_jumpers no)
		(fp_poly
			(pts
				(xy 0.2794 -0.1016) (xy -0.2794 -0.1016) (xy -0.2794 0.9906) (xy 0.2794 0.9906)
			)
			(stroke
				(width 0)
				(type default)
			)
			(fill no)
			(layer "B.CrtYd")
		)
		(fp_line
			(start 0.2794 -0.1016)
			(end 0.2794 0.9906)
			(stroke
				(width 0.1)
				(type default)
			)
			(layer "B.Fab")
		)
		(fp_line
			(start -0.2794 -0.1016)
			(end 0.2794 -0.1016)
			(stroke
				(width 0.1)
				(type default)
			)
			(layer "B.Fab")
		)
		(fp_line
			(start 0.2794 0.9906)
			(end -0.2794 0.9906)
			(stroke
				(width 0.1)
				(type default)
			)
			(layer "B.Fab")
		)
		(fp_line
			(start -0.2794 0.9906)
			(end -0.2794 -0.1016)
			(stroke
				(width 0.1)
				(type default)
			)
			(layer "B.Fab")
		)
		(pad "1" smd rect
			(at 0 0 270)
			(size 0.508 0.508)
			(layers "B.Cu" "B.Mask" "B.Paste")
			(net "NIC_LED_ACT_ANODE_R")
		)
		(pad "2" smd rect
			(at 0 0.889 270)
			(size 0.508 0.508)
			(layers "B.Cu" "B.Mask" "B.Paste")
			(net "P3V3_STBY")
		)
		(zone
			(layer "B.Cu")
			(hatch none 0.5)
			(connect_pads
				(clearance 0)
			)
			(min_thickness 0.25)
			(keepout
				(tracks allowed)
				(vias not_allowed)
				(pads allowed)
				(copperpour not_allowed)
				(footprints allowed)
			)
			(placement
				(enabled no)
				(sheetname "")
			)
			(fill
				(thermal_gap 0.5)
				(thermal_bridge_width 0.5)
				(island_removal_mode 0)
			)
			(polygon
				(pts
					(xy 485.303322 4.717288) (xy 485.303322 5.225288) (xy 485.684322 5.225288) (xy 485.684322 4.717288)
				)
			)
		)
		(zone
			(layer "B.Cu")
			(hatch none 0.5)
			(connect_pads
				(clearance 0)
			)
			(min_thickness 0.25)
			(keepout
				(tracks not_allowed)
				(vias allowed)
				(pads allowed)
				(copperpour not_allowed)
				(footprints allowed)
			)
			(placement
				(enabled no)
				(sheetname "")
			)
			(fill
				(thermal_gap 0.5)
				(thermal_bridge_width 0.5)
				(island_removal_mode 0)
			)
			(polygon
				(pts
					(xy 485.684322 4.717288) (xy 485.684322 5.225288) (xy 485.303322 5.225288) (xy 485.303322 4.717288)
				)
			)
		)
	)
	(footprint ""
		(layer "B.Cu")
		(at 439.976006 -43.54195 180)
		(property "Reference" "R25W41"
			(at 0 0 0)
			(layer "B.SilkS")
			(hide yes)
			(effects
				(font
					(size 1.27 1.27)
				)
				(justify mirror)
			)
		)
		(property "Value" "*"
			(at -0.064008 -4.108196 180)
			(unlocked yes)
			(layer "B.Fab")
			(hide yes)
			(effects
				(font
					(size 1.27 1.016)
					(thickness 0.1524)
				)
				(justify mirror)
			)
		)
		(property "Device Type" "120R2F-GP_RCL_GP-120R2F-GP,64.A"
			(at -0.064008 -5.632196 180)
			(unlocked yes)
			(layer "B.Fab")
			(hide yes)
			(effects
				(font
					(size 1.27 1.016)
					(thickness 0.1524)
				)
				(justify mirror)
			)
		)
		(duplicate_pad_numbers_are_jumpers no)
		(fp_line
			(start 0.508 -0.9398)
			(end 0.508 0.9398)
			(stroke
				(width 0.1524)
				(type default)
			)
			(layer "B.SilkS")
		)
		(fp_line
			(start -0.508 -0.9398)
			(end 0.508 -0.9398)
			(stroke
				(width 0.1524)
				(type default)
			)
			(layer "B.SilkS")
		)
		(fp_rect
			(start 0.508 0.9398)
			(end -0.508 -0.9398)
			(stroke
				(width 0)
				(type default)
			)
			(fill no)
			(layer "B.CrtYd")
		)
		(fp_rect
			(start 0.508 0.9398)
			(end -0.508 -0.9398)
			(stroke
				(width 0)
				(type default)
			)
			(fill no)
			(layer "B.Fab")
		)
		(pad "1" smd custom
			(at 0 -0.4445)
			(size 0.1397 0.1397)
			(layers "B.Cu" "B.Mask" "B.Paste")
			(net "BMC_M_A3")
			(options
				(clearance outline)
				(anchor circle)
			)
			(primitives
				(gr_poly
					(pts
						(arc
							(start -0.1778 0.2794)
							(mid -0.249642 0.249642)
							(end -0.2794 0.1778)
						)
						(arc
							(start -0.2794 -0.1778)
							(mid -0.249642 -0.249642)
							(end -0.1778 -0.2794)
						)
						(arc
							(start 0.1778 -0.2794)
							(mid 0.249642 -0.249642)
							(end 0.2794 -0.1778)
						)
						(arc
							(start 0.2794 0.1778)
							(mid 0.249642 0.249642)
							(end 0.1778 0.2794)
						)
					)
					(width 0)
					(fill yes)
				)
			)
		)
		(pad "2" smd custom
			(at 0 0.4445)
			(size 0.1397 0.1397)
			(layers "B.Cu" "B.Mask" "B.Paste")
			(net "P1V2_AUX_BMC")
			(options
				(clearance outline)
				(anchor circle)
			)
			(primitives
				(gr_poly
					(pts
						(arc
							(start -0.1778 0.2794)
							(mid -0.249642 0.249642)
							(end -0.2794 0.1778)
						)
						(arc
							(start -0.2794 -0.1778)
							(mid -0.249642 -0.249642)
							(end -0.1778 -0.2794)
						)
						(arc
							(start 0.1778 -0.2794)
							(mid 0.249642 -0.249642)
							(end 0.2794 -0.1778)
						)
						(arc
							(start 0.2794 0.1778)
							(mid 0.249642 0.249642)
							(end 0.1778 0.2794)
						)
					)
					(width 0)
					(fill yes)
				)
			)
		)
	)
	(footprint ""
		(layer "B.Cu")
		(at 168.656 -125.603 -90)
		(property "Reference" "C6M6"
			(at 0.8382 -0.84963 270)
			(unlocked yes)
			(layer "B.SilkS")
			(effects
				(font
					(size 0.7874 0.5842)
					(thickness 0.1524)
				)
				(justify left mirror)
			)
		)
		(property "Value" ""
			(at 0 0 90)
			(layer "B.Fab")
			(effects
				(font
					(size 1.27 1.27)
				)
				(justify mirror)
			)
		)
		(duplicate_pad_numbers_are_jumpers no)
		(fp_poly
			(pts
				(xy -0.3048 -0.1016) (xy -0.3048 0.9906) (xy 0.3048 0.9906) (xy 0.3048 -0.1016)
			)
			(stroke
				(width 0)
				(type default)
			)
			(fill no)
			(layer "B.CrtYd")
		)
		(fp_line
			(start -0.3048 0.9906)
			(end -0.3048 -0.1016)
			(stroke
				(width 0.1)
				(type default)
			)
			(layer "B.Fab")
		)
		(fp_line
			(start 0.3048 0.9906)
			(end -0.3048 0.9906)
			(stroke
				(width 0.1)
				(type default)
			)
			(layer "B.Fab")
		)
		(fp_line
			(start -0.3048 -0.1016)
			(end 0.3048 -0.1016)
			(stroke
				(width 0.1)
				(type default)
			)
			(layer "B.Fab")
		)
		(fp_line
			(start 0.3048 -0.1016)
			(end 0.3048 0.9906)
			(stroke
				(width 0.1)
				(type default)
			)
			(layer "B.Fab")
		)
		(pad "1" smd rect
			(at 0 0 90)
			(size 0.508 0.508)
			(layers "B.Cu" "B.Mask" "B.Paste")
			(net "JTAG_MCP_CPU1_TDI_R")
		)
		(pad "2" smd rect
			(at 0 0.889 90)
			(size 0.508 0.508)
			(layers "B.Cu" "B.Mask" "B.Paste")
			(net "GND")
		)
		(zone
			(layer "B.Cu")
			(hatch none 0.5)
			(connect_pads
				(clearance 0)
			)
			(min_thickness 0.25)
			(keepout
				(tracks not_allowed)
				(vias allowed)
				(pads allowed)
				(copperpour not_allowed)
				(footprints allowed)
			)
			(placement
				(enabled no)
				(sheetname "")
			)
			(fill
				(thermal_gap 0.5)
				(thermal_bridge_width 0.5)
				(island_removal_mode 0)
			)
			(polygon
				(pts
					(xy 168.021 -125.349) (xy 168.021 -125.857) (xy 168.402 -125.857) (xy 168.402 -125.349)
				)
			)
		)
		(zone
			(layer "B.Cu")
			(hatch none 0.5)
			(connect_pads
				(clearance 0)
			)
			(min_thickness 0.25)
			(keepout
				(tracks allowed)
				(vias not_allowed)
				(pads allowed)
				(copperpour not_allowed)
				(footprints allowed)
			)
			(placement
				(enabled no)
				(sheetname "")
			)
			(fill
				(thermal_gap 0.5)
				(thermal_bridge_width 0.5)
				(island_removal_mode 0)
			)
			(polygon
				(pts
					(xy 168.402 -125.349) (xy 168.402 -125.857) (xy 168.021 -125.857) (xy 168.021 -125.349)
				)
			)
		)
	)
	(footprint ""
		(layer "B.Cu")
		(at 197.866 -56.7182 90)
		(property "Reference" "C6R13"
			(at 0 0 90)
			(layer "B.SilkS")
			(hide yes)
			(effects
				(font
					(size 1.27 1.27)
				)
				(justify mirror)
			)
		)
		(property "Value" ""
			(at 0 0 90)
			(layer "B.Fab")
			(effects
				(font
					(size 1.27 1.27)
				)
				(justify mirror)
			)
		)
		(duplicate_pad_numbers_are_jumpers no)
		(fp_rect
			(start -0.7239 -0.2159)
			(end 0.7239 1.9939)
			(stroke
				(width 0)
				(type default)
			)
			(fill no)
			(layer "B.CrtYd")
		)
		(fp_line
			(start 0.7239 -0.2159)
			(end 0.7239 1.9939)
			(stroke
				(width 0.1)
				(type default)
			)
			(layer "B.Fab")
		)
		(fp_line
			(start -0.7239 -0.2159)
			(end 0.7239 -0.2159)
			(stroke
				(width 0.1)
				(type default)
			)
			(layer "B.Fab")
		)
		(fp_line
			(start 0.7239 1.9939)
			(end -0.7239 1.9939)
			(stroke
				(width 0.1)
				(type default)
			)
			(layer "B.Fab")
		)
		(fp_line
			(start -0.7239 1.9939)
			(end -0.7239 -0.2159)
			(stroke
				(width 0.1)
				(type default)
			)
			(layer "B.Fab")
		)
		(pad "1" smd rect
			(at 0 0 270)
			(size 1.27 1.016)
			(layers "B.Cu" "B.Mask" "B.Paste")
			(net "VR_FET_SW_P12V_STBY_PVCCIN_CPU0")
		)
		(pad "2" smd rect
			(at 0 1.778 270)
			(size 1.27 1.016)
			(layers "B.Cu" "B.Mask" "B.Paste")
			(net "GND")
		)
		(zone
			(layer "B.Cu")
			(hatch none 0.5)
			(connect_pads
				(clearance 0)
			)
			(min_thickness 0.25)
			(keepout
				(tracks not_allowed)
				(vias allowed)
				(pads allowed)
				(copperpour not_allowed)
				(footprints allowed)
			)
			(placement
				(enabled no)
				(sheetname "")
			)
			(fill
				(thermal_gap 0.5)
				(thermal_bridge_width 0.5)
				(island_removal_mode 0)
			)
			(polygon
				(pts
					(xy 198.374 -56.0832) (xy 199.136 -56.0832) (xy 199.136 -57.3532) (xy 198.374 -57.3532)
				)
			)
		)
	)
	(footprint ""
		(layer "B.Cu")
		(at 367.9444 -5.3467 180)
		(property "Reference" "R7G29"
			(at 0 0 0)
			(layer "B.SilkS")
			(hide yes)
			(effects
				(font
					(size 1.27 1.27)
				)
				(justify mirror)
			)
		)
		(property "Value" ""
			(at 0 0 0)
			(layer "B.Fab")
			(effects
				(font
					(size 1.27 1.27)
				)
				(justify mirror)
			)
		)
		(duplicate_pad_numbers_are_jumpers no)
		(fp_poly
			(pts
				(xy 0.2794 -0.1016) (xy -0.2794 -0.1016) (xy -0.2794 0.9906) (xy 0.2794 0.9906)
			)
			(stroke
				(width 0)
				(type default)
			)
			(fill no)
			(layer "B.CrtYd")
		)
		(fp_line
			(start 0.2794 0.9906)
			(end -0.2794 0.9906)
			(stroke
				(width 0.1)
				(type default)
			)
			(layer "B.Fab")
		)
		(fp_line
			(start 0.2794 -0.1016)
			(end 0.2794 0.9906)
			(stroke
				(width 0.1)
				(type default)
			)
			(layer "B.Fab")
		)
		(fp_line
			(start -0.2794 0.9906)
			(end -0.2794 -0.1016)
			(stroke
				(width 0.1)
				(type default)
			)
			(layer "B.Fab")
		)
		(fp_line
			(start -0.2794 -0.1016)
			(end 0.2794 -0.1016)
			(stroke
				(width 0.1)
				(type default)
			)
			(layer "B.Fab")
		)
		(pad "1" smd rect
			(at 0 0)
			(size 0.508 0.508)
			(layers "B.Cu" "B.Mask" "B.Paste")
			(net "PD_PASSWORD_CLEAR")
		)
		(pad "2" smd rect
			(at 0 0.889)
			(size 0.508 0.508)
			(layers "B.Cu" "B.Mask" "B.Paste")
			(net "GND")
		)
		(zone
			(layer "B.Cu")
			(hatch none 0.5)
			(connect_pads
				(clearance 0)
			)
			(min_thickness 0.25)
			(keepout
				(tracks not_allowed)
				(vias allowed)
				(pads allowed)
				(copperpour not_allowed)
				(footprints allowed)
			)
			(placement
				(enabled no)
				(sheetname "")
			)
			(fill
				(thermal_gap 0.5)
				(thermal_bridge_width 0.5)
				(island_removal_mode 0)
			)
			(polygon
				(pts
					(xy 367.6904 -5.9817) (xy 368.1984 -5.9817) (xy 368.1984 -5.6007) (xy 367.6904 -5.6007)
				)
			)
		)
		(zone
			(layer "B.Cu")
			(hatch none 0.5)
			(connect_pads
				(clearance 0)
			)
			(min_thickness 0.25)
			(keepout
				(tracks allowed)
				(vias not_allowed)
				(pads allowed)
				(copperpour not_allowed)
				(footprints allowed)
			)
			(placement
				(enabled no)
				(sheetname "")
			)
			(fill
				(thermal_gap 0.5)
				(thermal_bridge_width 0.5)
				(island_removal_mode 0)
			)
			(polygon
				(pts
					(xy 367.6904 -5.6007) (xy 368.1984 -5.6007) (xy 368.1984 -5.9817) (xy 367.6904 -5.9817)
				)
			)
		)
	)
	(footprint ""
		(layer "B.Cu")
		(at 462.8896 -7.1628)
		(property "Reference" "R2U37"
			(at 0 0 0)
			(layer "B.SilkS")
			(hide yes)
			(effects
				(font
					(size 1.27 1.27)
				)
				(justify mirror)
			)
		)
		(property "Value" ""
			(at 0 0 0)
			(layer "B.Fab")
			(effects
				(font
					(size 1.27 1.27)
				)
				(justify mirror)
			)
		)
		(duplicate_pad_numbers_are_jumpers no)
		(fp_poly
			(pts
				(xy 0.2794 -0.1016) (xy -0.2794 -0.1016) (xy -0.2794 0.9906) (xy 0.2794 0.9906)
			)
			(stroke
				(width 0)
				(type default)
			)
			(fill no)
			(layer "B.CrtYd")
		)
		(fp_line
			(start -0.2794 -0.1016)
			(end 0.2794 -0.1016)
			(stroke
				(width 0.1)
				(type default)
			)
			(layer "B.Fab")
		)
		(fp_line
			(start -0.2794 0.9906)
			(end -0.2794 -0.1016)
			(stroke
				(width 0.1)
				(type default)
			)
			(layer "B.Fab")
		)
		(fp_line
			(start 0.2794 -0.1016)
			(end 0.2794 0.9906)
			(stroke
				(width 0.1)
				(type default)
			)
			(layer "B.Fab")
		)
		(fp_line
			(start 0.2794 0.9906)
			(end -0.2794 0.9906)
			(stroke
				(width 0.1)
				(type default)
			)
			(layer "B.Fab")
		)
		(pad "1" smd rect
			(at 0 0 180)
			(size 0.508 0.508)
			(layers "B.Cu" "B.Mask" "B.Paste")
			(net "RST_PCIE_RISER1_PERST_N")
		)
		(pad "2" smd rect
			(at 0 0.889 180)
			(size 0.508 0.508)
			(layers "B.Cu" "B.Mask" "B.Paste")
			(net "RST_PCIE_RISER1_PERST_R_N")
		)
		(zone
			(layer "B.Cu")
			(hatch none 0.5)
			(connect_pads
				(clearance 0)
			)
			(min_thickness 0.25)
			(keepout
				(tracks allowed)
				(vias not_allowed)
				(pads allowed)
				(copperpour not_allowed)
				(footprints allowed)
			)
			(placement
				(enabled no)
				(sheetname "")
			)
			(fill
				(thermal_gap 0.5)
				(thermal_bridge_width 0.5)
				(island_removal_mode 0)
			)
			(polygon
				(pts
					(xy 463.1436 -6.9088) (xy 462.6356 -6.9088) (xy 462.6356 -6.5278) (xy 463.1436 -6.5278)
				)
			)
		)
		(zone
			(layer "B.Cu")
			(hatch none 0.5)
			(connect_pads
				(clearance 0)
			)
			(min_thickness 0.25)
			(keepout
				(tracks not_allowed)
				(vias allowed)
				(pads allowed)
				(copperpour not_allowed)
				(footprints allowed)
			)
			(placement
				(enabled no)
				(sheetname "")
			)
			(fill
				(thermal_gap 0.5)
				(thermal_bridge_width 0.5)
				(island_removal_mode 0)
			)
			(polygon
				(pts
					(xy 463.1436 -6.5278) (xy 462.6356 -6.5278) (xy 462.6356 -6.9088) (xy 463.1436 -6.9088)
				)
			)
		)
	)
	(footprint ""
		(layer "B.Cu")
		(at 282.259024 -73.492614 -90)
		(property "Reference" "R4P8"
			(at 0 0 90)
			(layer "B.SilkS")
			(hide yes)
			(effects
				(font
					(size 1.27 1.27)
				)
				(justify mirror)
			)
		)
		(property "Value" ""
			(at 0 0 90)
			(layer "B.Fab")
			(effects
				(font
					(size 1.27 1.27)
				)
				(justify mirror)
			)
		)
		(duplicate_pad_numbers_are_jumpers no)
		(fp_rect
			(start 0.2794 0.9906)
			(end -0.2794 -0.1016)
			(stroke
				(width 0)
				(type default)
			)
			(fill no)
			(layer "B.CrtYd")
		)
		(fp_line
			(start -0.2794 0.9906)
			(end -0.2794 -0.1016)
			(stroke
				(width 0.1)
				(type default)
			)
			(layer "B.Fab")
		)
		(fp_line
			(start 0.2794 0.9906)
			(end -0.2794 0.9906)
			(stroke
				(width 0.1)
				(type default)
			)
			(layer "B.Fab")
		)
		(fp_line
			(start -0.2794 -0.1016)
			(end 0.2794 -0.1016)
			(stroke
				(width 0.1)
				(type default)
			)
			(layer "B.Fab")
		)
		(fp_line
			(start 0.2794 -0.1016)
			(end 0.2794 0.9906)
			(stroke
				(width 0.1)
				(type default)
			)
			(layer "B.Fab")
		)
		(pad "1" smd rect
			(at 0 0 90)
			(size 0.508 0.508)
			(layers "B.Cu" "B.Mask" "B.Paste")
			(net "A_CPU0_ABC_RCOMP0")
		)
		(pad "2" smd rect
			(at 0 0.889 90)
			(size 0.508 0.508)
			(layers "B.Cu" "B.Mask" "B.Paste")
			(net "GND")
		)
		(zone
			(layer "B.Cu")
			(hatch none 0.5)
			(connect_pads
				(clearance 0)
			)
			(min_thickness 0.25)
			(keepout
				(tracks allowed)
				(vias not_allowed)
				(pads allowed)
				(copperpour not_allowed)
				(footprints allowed)
			)
			(placement
				(enabled no)
				(sheetname "")
			)
			(fill
				(thermal_gap 0.5)
				(thermal_bridge_width 0.5)
				(island_removal_mode 0)
			)
			(polygon
				(pts
					(xy 281.624024 -73.238614) (xy 282.005024 -73.238614) (xy 282.005024 -73.746614) (xy 281.624024 -73.746614)
				)
			)
		)
		(zone
			(layer "B.Cu")
			(hatch none 0.5)
			(connect_pads
				(clearance 0)
			)
			(min_thickness 0.25)
			(keepout
				(tracks not_allowed)
				(vias allowed)
				(pads allowed)
				(copperpour not_allowed)
				(footprints allowed)
			)
			(placement
				(enabled no)
				(sheetname "")
			)
			(fill
				(thermal_gap 0.5)
				(thermal_bridge_width 0.5)
				(island_removal_mode 0)
			)
			(polygon
				(pts
					(xy 281.624024 -73.238614) (xy 282.005024 -73.238614) (xy 282.005024 -73.746614) (xy 281.624024 -73.746614)
				)
			)
		)
	)
	(footprint ""
		(layer "B.Cu")
		(at 175.006 -88.646 180)
		(property "Reference" "R6N8"
			(at 0 0 0)
			(layer "B.SilkS")
			(hide yes)
			(effects
				(font
					(size 1.27 1.27)
				)
				(justify mirror)
			)
		)
		(property "Value" ""
			(at 0 0 0)
			(layer "B.Fab")
			(effects
				(font
					(size 1.27 1.27)
				)
				(justify mirror)
			)
		)
		(duplicate_pad_numbers_are_jumpers no)
		(fp_poly
			(pts
				(xy 0.2794 -0.1016) (xy -0.2794 -0.1016) (xy -0.2794 0.9906) (xy 0.2794 0.9906)
			)
			(stroke
				(width 0)
				(type default)
			)
			(fill no)
			(layer "B.CrtYd")
		)
		(fp_line
			(start 0.2794 0.9906)
			(end -0.2794 0.9906)
			(stroke
				(width 0.1)
				(type default)
			)
			(layer "B.Fab")
		)
		(fp_line
			(start 0.2794 -0.1016)
			(end 0.2794 0.9906)
			(stroke
				(width 0.1)
				(type default)
			)
			(layer "B.Fab")
		)
		(fp_line
			(start -0.2794 0.9906)
			(end -0.2794 -0.1016)
			(stroke
				(width 0.1)
				(type default)
			)
			(layer "B.Fab")
		)
		(fp_line
			(start -0.2794 -0.1016)
			(end 0.2794 -0.1016)
			(stroke
				(width 0.1)
				(type default)
			)
			(layer "B.Fab")
		)
		(pad "1" smd rect
			(at 0 0)
			(size 0.508 0.508)
			(layers "B.Cu" "B.Mask" "B.Paste")
			(net "SMB_CPU1_PE_HP_GTL_SCL")
		)
		(pad "2" smd rect
			(at 0 0.889)
			(size 0.508 0.508)
			(layers "B.Cu" "B.Mask" "B.Paste")
			(net "SMB_CPU1_PE_HP_GTL_R_SCL")
		)
		(zone
			(layer "B.Cu")
			(hatch none 0.5)
			(connect_pads
				(clearance 0)
			)
			(min_thickness 0.25)
			(keepout
				(tracks not_allowed)
				(vias allowed)
				(pads allowed)
				(copperpour not_allowed)
				(footprints allowed)
			)
			(placement
				(enabled no)
				(sheetname "")
			)
			(fill
				(thermal_gap 0.5)
				(thermal_bridge_width 0.5)
				(island_removal_mode 0)
			)
			(polygon
				(pts
					(xy 174.752 -89.281) (xy 175.26 -89.281) (xy 175.26 -88.9) (xy 174.752 -88.9)
				)
			)
		)
		(zone
			(layer "B.Cu")
			(hatch none 0.5)
			(connect_pads
				(clearance 0)
			)
			(min_thickness 0.25)
			(keepout
				(tracks allowed)
				(vias not_allowed)
				(pads allowed)
				(copperpour not_allowed)
				(footprints allowed)
			)
			(placement
				(enabled no)
				(sheetname "")
			)
			(fill
				(thermal_gap 0.5)
				(thermal_bridge_width 0.5)
				(island_removal_mode 0)
			)
			(polygon
				(pts
					(xy 174.752 -88.9) (xy 175.26 -88.9) (xy 175.26 -89.281) (xy 174.752 -89.281)
				)
			)
		)
	)
	(footprint ""
		(layer "B.Cu")
		(at 113.702592 -71.714614 180)
		(property "Reference" "C7P17"
			(at 0 0 0)
			(layer "B.SilkS")
			(hide yes)
			(effects
				(font
					(size 1.27 1.27)
				)
				(justify mirror)
			)
		)
		(property "Value" ""
			(at 0 0 0)
			(layer "B.Fab")
			(effects
				(font
					(size 1.27 1.27)
				)
				(justify mirror)
			)
		)
		(duplicate_pad_numbers_are_jumpers no)
		(fp_poly
			(pts
				(xy 0.7239 -0.2159) (xy -0.7239 -0.2159) (xy -0.7239 1.9939) (xy 0.7239 1.9939)
			)
			(stroke
				(width 0)
				(type default)
			)
			(fill no)
			(layer "B.CrtYd")
		)
		(fp_line
			(start 0.7239 1.9939)
			(end -0.7239 1.9939)
			(stroke
				(width 0.1)
				(type default)
			)
			(layer "B.Fab")
		)
		(fp_line
			(start 0.7239 -0.2159)
			(end 0.7239 1.9939)
			(stroke
				(width 0.1)
				(type default)
			)
			(layer "B.Fab")
		)
		(fp_line
			(start -0.7239 1.9939)
			(end -0.7239 -0.2159)
			(stroke
				(width 0.1)
				(type default)
			)
			(layer "B.Fab")
		)
		(fp_line
			(start -0.7239 -0.2159)
			(end 0.7239 -0.2159)
			(stroke
				(width 0.1)
				(type default)
			)
			(layer "B.Fab")
		)
		(pad "1" smd rect
			(at 0 0)
			(size 1.27 1.016)
			(layers "B.Cu" "B.Mask" "B.Paste")
			(net "PVCCIO_CPU1")
		)
		(pad "2" smd rect
			(at 0 1.778)
			(size 1.27 1.016)
			(layers "B.Cu" "B.Mask" "B.Paste")
			(net "GND")
		)
		(zone
			(layer "B.Cu")
			(hatch none 0.5)
			(connect_pads
				(clearance 0)
			)
			(min_thickness 0.25)
			(keepout
				(tracks not_allowed)
				(vias allowed)
				(pads allowed)
				(copperpour not_allowed)
				(footprints allowed)
			)
			(placement
				(enabled no)
				(sheetname "")
			)
			(fill
				(thermal_gap 0.5)
				(thermal_bridge_width 0.5)
				(island_removal_mode 0)
			)
			(polygon
				(pts
					(xy 113.067592 -72.222614) (xy 114.337592 -72.222614) (xy 114.337592 -72.984614) (xy 113.067592 -72.984614)
				)
			)
		)
	)
	(footprint ""
		(layer "B.Cu")
		(at 477.645222 -3.3782 -90)
		(property "Reference" "C9G9"
			(at 0 0 90)
			(layer "B.SilkS")
			(hide yes)
			(effects
				(font
					(size 1.27 1.27)
				)
				(justify mirror)
			)
		)
		(property "Value" ""
			(at 0 0 90)
			(layer "B.Fab")
			(effects
				(font
					(size 1.27 1.27)
				)
				(justify mirror)
			)
		)
		(duplicate_pad_numbers_are_jumpers no)
		(fp_poly
			(pts
				(xy -0.3048 -0.1016) (xy -0.3048 0.9906) (xy 0.3048 0.9906) (xy 0.3048 -0.1016)
			)
			(stroke
				(width 0)
				(type default)
			)
			(fill no)
			(layer "B.CrtYd")
		)
		(fp_line
			(start -0.3048 0.9906)
			(end -0.3048 -0.1016)
			(stroke
				(width 0.1)
				(type default)
			)
			(layer "B.Fab")
		)
		(fp_line
			(start 0.3048 0.9906)
			(end -0.3048 0.9906)
			(stroke
				(width 0.1)
				(type default)
			)
			(layer "B.Fab")
		)
		(fp_line
			(start -0.3048 -0.1016)
			(end 0.3048 -0.1016)
			(stroke
				(width 0.1)
				(type default)
			)
			(layer "B.Fab")
		)
		(fp_line
			(start 0.3048 -0.1016)
			(end 0.3048 0.9906)
			(stroke
				(width 0.1)
				(type default)
			)
			(layer "B.Fab")
		)
		(pad "1" smd rect
			(at 0 0 90)
			(size 0.508 0.508)
			(layers "B.Cu" "B.Mask" "B.Paste")
			(net "NIC_SER_P_MDI_3_DP")
		)
		(pad "2" smd rect
			(at 0 0.889 90)
			(size 0.508 0.508)
			(layers "B.Cu" "B.Mask" "B.Paste")
			(net "NIC_MDI_MNG_RX_DP")
		)
		(zone
			(layer "B.Cu")
			(hatch none 0.5)
			(connect_pads
				(clearance 0)
			)
			(min_thickness 0.25)
			(keepout
				(tracks not_allowed)
				(vias allowed)
				(pads allowed)
				(copperpour not_allowed)
				(footprints allowed)
			)
			(placement
				(enabled no)
				(sheetname "")
			)
			(fill
				(thermal_gap 0.5)
				(thermal_bridge_width 0.5)
				(island_removal_mode 0)
			)
			(polygon
				(pts
					(xy 477.010222 -3.1242) (xy 477.010222 -3.6322) (xy 477.391222 -3.6322) (xy 477.391222 -3.1242)
				)
			)
		)
		(zone
			(layer "B.Cu")
			(hatch none 0.5)
			(connect_pads
				(clearance 0)
			)
			(min_thickness 0.25)
			(keepout
				(tracks allowed)
				(vias not_allowed)
				(pads allowed)
				(copperpour not_allowed)
				(footprints allowed)
			)
			(placement
				(enabled no)
				(sheetname "")
			)
			(fill
				(thermal_gap 0.5)
				(thermal_bridge_width 0.5)
				(island_removal_mode 0)
			)
			(polygon
				(pts
					(xy 477.391222 -3.1242) (xy 477.391222 -3.6322) (xy 477.010222 -3.6322) (xy 477.010222 -3.1242)
				)
			)
		)
	)
	(footprint ""
		(layer "B.Cu")
		(at 494.712244 -47.503588 180)
		(property "Reference" "R25W133"
			(at 0.8382 -0.67818 180)
			(unlocked yes)
			(layer "B.SilkS")
			(effects
				(font
					(size 0.4064 0.254)
					(thickness 0.1524)
				)
				(justify left mirror)
			)
		)
		(property "Value" ""
			(at 0 0 0)
			(layer "B.Fab")
			(effects
				(font
					(size 1.27 1.27)
				)
				(justify mirror)
			)
		)
		(duplicate_pad_numbers_are_jumpers no)
		(fp_poly
			(pts
				(xy 0.2794 -0.1016) (xy -0.2794 -0.1016) (xy -0.2794 0.9906) (xy 0.2794 0.9906)
			)
			(stroke
				(width 0)
				(type default)
			)
			(fill no)
			(layer "B.CrtYd")
		)
		(fp_line
			(start 0.2794 0.9906)
			(end -0.2794 0.9906)
			(stroke
				(width 0.1)
				(type default)
			)
			(layer "B.Fab")
		)
		(fp_line
			(start 0.2794 -0.1016)
			(end 0.2794 0.9906)
			(stroke
				(width 0.1)
				(type default)
			)
			(layer "B.Fab")
		)
		(fp_line
			(start -0.2794 0.9906)
			(end -0.2794 -0.1016)
			(stroke
				(width 0.1)
				(type default)
			)
			(layer "B.Fab")
		)
		(fp_line
			(start -0.2794 -0.1016)
			(end 0.2794 -0.1016)
			(stroke
				(width 0.1)
				(type default)
			)
			(layer "B.Fab")
		)
		(pad "1" smd rect
			(at 0 0)
			(size 0.508 0.508)
			(layers "B.Cu" "B.Mask" "B.Paste")
			(net "I2C_BMC_VGA_DDC_SCL_G")
		)
		(pad "2" smd rect
			(at 0 0.889)
			(size 0.508 0.508)
			(layers "B.Cu" "B.Mask" "B.Paste")
			(net "V_IBMC_5V_DDC_SCL_J")
		)
		(zone
			(layer "B.Cu")
			(hatch none 0.5)
			(connect_pads
				(clearance 0)
			)
			(min_thickness 0.25)
			(keepout
				(tracks not_allowed)
				(vias allowed)
				(pads allowed)
				(copperpour not_allowed)
				(footprints allowed)
			)
			(placement
				(enabled no)
				(sheetname "")
			)
			(fill
				(thermal_gap 0.5)
				(thermal_bridge_width 0.5)
				(island_removal_mode 0)
			)
			(polygon
				(pts
					(xy 494.458244 -48.138588) (xy 494.966244 -48.138588) (xy 494.966244 -47.757588) (xy 494.458244 -47.757588)
				)
			)
		)
		(zone
			(layer "B.Cu")
			(hatch none 0.5)
			(connect_pads
				(clearance 0)
			)
			(min_thickness 0.25)
			(keepout
				(tracks allowed)
				(vias not_allowed)
				(pads allowed)
				(copperpour not_allowed)
				(footprints allowed)
			)
			(placement
				(enabled no)
				(sheetname "")
			)
			(fill
				(thermal_gap 0.5)
				(thermal_bridge_width 0.5)
				(island_removal_mode 0)
			)
			(polygon
				(pts
					(xy 494.458244 -47.757588) (xy 494.966244 -47.757588) (xy 494.966244 -48.138588) (xy 494.458244 -48.138588)
				)
			)
		)
	)
	(footprint ""
		(layer "B.Cu")
		(at 404.101046 -25.600152 180)
		(property "Reference" "R1U39"
			(at 0 0 0)
			(layer "B.SilkS")
			(hide yes)
			(effects
				(font
					(size 1.27 1.27)
				)
				(justify mirror)
			)
		)
		(property "Value" ""
			(at 0 0 0)
			(layer "B.Fab")
			(effects
				(font
					(size 1.27 1.27)
				)
				(justify mirror)
			)
		)
		(duplicate_pad_numbers_are_jumpers no)
		(fp_poly
			(pts
				(xy 0.2794 -0.1016) (xy -0.2794 -0.1016) (xy -0.2794 0.9906) (xy 0.2794 0.9906)
			)
			(stroke
				(width 0)
				(type default)
			)
			(fill no)
			(layer "B.CrtYd")
		)
		(fp_line
			(start 0.2794 0.9906)
			(end -0.2794 0.9906)
			(stroke
				(width 0.1)
				(type default)
			)
			(layer "B.Fab")
		)
		(fp_line
			(start 0.2794 -0.1016)
			(end 0.2794 0.9906)
			(stroke
				(width 0.1)
				(type default)
			)
			(layer "B.Fab")
		)
		(fp_line
			(start -0.2794 0.9906)
			(end -0.2794 -0.1016)
			(stroke
				(width 0.1)
				(type default)
			)
			(layer "B.Fab")
		)
		(fp_line
			(start -0.2794 -0.1016)
			(end 0.2794 -0.1016)
			(stroke
				(width 0.1)
				(type default)
			)
			(layer "B.Fab")
		)
		(pad "1" smd rect
			(at 0 0)
			(size 0.508 0.508)
			(layers "B.Cu" "B.Mask" "B.Paste")
			(net "P3V3_STBY")
		)
		(pad "2" smd rect
			(at 0 0.889)
			(size 0.508 0.508)
			(layers "B.Cu" "B.Mask" "B.Paste")
			(net "A_P3V3_STBY_SCALED")
		)
		(zone
			(layer "B.Cu")
			(hatch none 0.5)
			(connect_pads
				(clearance 0)
			)
			(min_thickness 0.25)
			(keepout
				(tracks not_allowed)
				(vias allowed)
				(pads allowed)
				(copperpour not_allowed)
				(footprints allowed)
			)
			(placement
				(enabled no)
				(sheetname "")
			)
			(fill
				(thermal_gap 0.5)
				(thermal_bridge_width 0.5)
				(island_removal_mode 0)
			)
			(polygon
				(pts
					(xy 403.847046 -26.235152) (xy 404.355046 -26.235152) (xy 404.355046 -25.854152) (xy 403.847046 -25.854152)
				)
			)
		)
		(zone
			(layer "B.Cu")
			(hatch none 0.5)
			(connect_pads
				(clearance 0)
			)
			(min_thickness 0.25)
			(keepout
				(tracks allowed)
				(vias not_allowed)
				(pads allowed)
				(copperpour not_allowed)
				(footprints allowed)
			)
			(placement
				(enabled no)
				(sheetname "")
			)
			(fill
				(thermal_gap 0.5)
				(thermal_bridge_width 0.5)
				(island_removal_mode 0)
			)
			(polygon
				(pts
					(xy 403.847046 -25.854152) (xy 404.355046 -25.854152) (xy 404.355046 -26.235152) (xy 403.847046 -26.235152)
				)
			)
		)
	)
	(footprint ""
		(layer "B.Cu")
		(at 409.1432 -123.6218 90)
		(property "Reference" "C2M5"
			(at 0 0 90)
			(layer "B.SilkS")
			(hide yes)
			(effects
				(font
					(size 1.27 1.27)
				)
				(justify mirror)
			)
		)
		(property "Value" ""
			(at 0 0 90)
			(layer "B.Fab")
			(effects
				(font
					(size 1.27 1.27)
				)
				(justify mirror)
			)
		)
		(duplicate_pad_numbers_are_jumpers no)
		(fp_poly
			(pts
				(xy 0.4953 -0.2032) (xy -0.4953 -0.2032) (xy -0.4953 1.6002) (xy 0.4953 1.6002)
			)
			(stroke
				(width 0)
				(type default)
			)
			(fill no)
			(layer "B.CrtYd")
		)
		(fp_line
			(start 0.4953 -0.2032)
			(end -0.4953 -0.2032)
			(stroke
				(width 0.1)
				(type default)
			)
			(layer "B.Fab")
		)
		(fp_line
			(start -0.4953 -0.2032)
			(end -0.4953 1.6002)
			(stroke
				(width 0.1)
				(type default)
			)
			(layer "B.Fab")
		)
		(fp_line
			(start 0.4953 1.6002)
			(end 0.4953 -0.2032)
			(stroke
				(width 0.1)
				(type default)
			)
			(layer "B.Fab")
		)
		(fp_line
			(start -0.4953 1.6002)
			(end 0.4953 1.6002)
			(stroke
				(width 0.1)
				(type default)
			)
			(layer "B.Fab")
		)
		(pad "1" smd rect
			(at 0 0 270)
			(size 0.762 0.889)
			(layers "B.Cu" "B.Mask" "B.Paste")
			(net "P1V05_PCH_STBY_WM20_PLL")
		)
		(pad "2" smd rect
			(at 0 1.397 270)
			(size 0.762 0.889)
			(layers "B.Cu" "B.Mask" "B.Paste")
			(net "GND")
		)
		(zone
			(layer "B.Cu")
			(hatch none 0.5)
			(connect_pads
				(clearance 0)
			)
			(min_thickness 0.25)
			(keepout
				(tracks not_allowed)
				(vias allowed)
				(pads allowed)
				(copperpour not_allowed)
				(footprints allowed)
			)
			(placement
				(enabled no)
				(sheetname "")
			)
			(fill
				(thermal_gap 0.5)
				(thermal_bridge_width 0.5)
				(island_removal_mode 0)
			)
			(polygon
				(pts
					(xy 409.5877 -124.0028) (xy 409.5877 -123.2408) (xy 410.0957 -123.2408) (xy 410.0957 -124.0028)
				)
			)
		)
	)
	(footprint ""
		(layer "B.Cu")
		(at 405.369522 -113.7412)
		(property "Reference" "L2M1"
			(at 0 0 0)
			(layer "B.SilkS")
			(hide yes)
			(effects
				(font
					(size 1.27 1.27)
				)
				(justify mirror)
			)
		)
		(property "Value" ""
			(at 0 0 0)
			(layer "B.Fab")
			(effects
				(font
					(size 1.27 1.27)
				)
				(justify mirror)
			)
		)
		(duplicate_pad_numbers_are_jumpers no)
		(fp_rect
			(start 0.7239 1.93802)
			(end -0.7239 -0.26162)
			(stroke
				(width 0)
				(type default)
			)
			(fill no)
			(layer "B.CrtYd")
		)
		(fp_line
			(start -0.7239 -0.26162)
			(end 0.7239 -0.26162)
			(stroke
				(width 0.1)
				(type default)
			)
			(layer "B.Fab")
		)
		(fp_line
			(start -0.7239 1.93802)
			(end -0.7239 -0.26162)
			(stroke
				(width 0.1)
				(type default)
			)
			(layer "B.Fab")
		)
		(fp_line
			(start 0.7239 -0.26162)
			(end 0.7239 1.93802)
			(stroke
				(width 0.1)
				(type default)
			)
			(layer "B.Fab")
		)
		(fp_line
			(start 0.7239 1.93802)
			(end -0.7239 1.93802)
			(stroke
				(width 0.1)
				(type default)
			)
			(layer "B.Fab")
		)
		(pad "1" smd rect
			(at 0 0 180)
			(size 1.4986 0.9144)
			(layers "B.Cu" "B.Mask" "B.Paste")
			(net "P1V05_PCH_STBY")
		)
		(pad "2" smd rect
			(at 0 1.6764 180)
			(size 1.4986 0.9144)
			(layers "B.Cu" "B.Mask" "B.Paste")
			(net "P1V05_PCH_STBY_KR_PLL")
		)
		(zone
			(layer "B.Cu")
			(hatch none 0.5)
			(connect_pads
				(clearance 0)
			)
			(min_thickness 0.25)
			(keepout
				(tracks allowed)
				(vias not_allowed)
				(pads allowed)
				(copperpour not_allowed)
				(footprints allowed)
			)
			(placement
				(enabled no)
				(sheetname "")
			)
			(fill
				(thermal_gap 0.5)
				(thermal_bridge_width 0.5)
				(island_removal_mode 0)
			)
			(polygon
				(pts
					(xy 406.118822 -113.284) (xy 406.118822 -112.522) (xy 404.620222 -112.522) (xy 404.620222 -113.284)
				)
			)
		)
		(zone
			(layer "B.Cu")
			(hatch none 0.5)
			(connect_pads
				(clearance 0)
			)
			(min_thickness 0.25)
			(keepout
				(tracks not_allowed)
				(vias allowed)
				(pads allowed)
				(copperpour not_allowed)
				(footprints allowed)
			)
			(placement
				(enabled no)
				(sheetname "")
			)
			(fill
				(thermal_gap 0.5)
				(thermal_bridge_width 0.5)
				(island_removal_mode 0)
			)
			(polygon
				(pts
					(xy 406.118822 -112.522) (xy 406.118822 -113.284) (xy 404.620222 -113.284) (xy 404.620222 -112.522)
				)
			)
		)
	)
	(footprint ""
		(layer "B.Cu")
		(at 355.178614 -125.532642 -90)
		(property "Reference" "C3M1"
			(at 0 0 90)
			(layer "B.SilkS")
			(hide yes)
			(effects
				(font
					(size 1.27 1.27)
				)
				(justify mirror)
			)
		)
		(property "Value" ""
			(at 0 0 90)
			(layer "B.Fab")
			(effects
				(font
					(size 1.27 1.27)
				)
				(justify mirror)
			)
		)
		(duplicate_pad_numbers_are_jumpers no)
		(fp_poly
			(pts
				(xy -0.3048 -0.1016) (xy -0.3048 0.9906) (xy 0.3048 0.9906) (xy 0.3048 -0.1016)
			)
			(stroke
				(width 0)
				(type default)
			)
			(fill no)
			(layer "B.CrtYd")
		)
		(fp_line
			(start -0.3048 0.9906)
			(end -0.3048 -0.1016)
			(stroke
				(width 0.1)
				(type default)
			)
			(layer "B.Fab")
		)
		(fp_line
			(start 0.3048 0.9906)
			(end -0.3048 0.9906)
			(stroke
				(width 0.1)
				(type default)
			)
			(layer "B.Fab")
		)
		(fp_line
			(start -0.3048 -0.1016)
			(end 0.3048 -0.1016)
			(stroke
				(width 0.1)
				(type default)
			)
			(layer "B.Fab")
		)
		(fp_line
			(start 0.3048 -0.1016)
			(end 0.3048 0.9906)
			(stroke
				(width 0.1)
				(type default)
			)
			(layer "B.Fab")
		)
		(pad "1" smd rect
			(at 0 0 90)
			(size 0.508 0.508)
			(layers "B.Cu" "B.Mask" "B.Paste")
			(net "P3E_CPU0_PE1_PCH_R_RXN<15>")
		)
		(pad "2" smd rect
			(at 0 0.889 90)
			(size 0.508 0.508)
			(layers "B.Cu" "B.Mask" "B.Paste")
			(net "P3E_CPU0_PE1_PCH_RXN<15>")
		)
		(zone
			(layer "B.Cu")
			(hatch none 0.5)
			(connect_pads
				(clearance 0)
			)
			(min_thickness 0.25)
			(keepout
				(tracks not_allowed)
				(vias allowed)
				(pads allowed)
				(copperpour not_allowed)
				(footprints allowed)
			)
			(placement
				(enabled no)
				(sheetname "")
			)
			(fill
				(thermal_gap 0.5)
				(thermal_bridge_width 0.5)
				(island_removal_mode 0)
			)
			(polygon
				(pts
					(xy 354.543614 -125.278642) (xy 354.543614 -125.786642) (xy 354.924614 -125.786642) (xy 354.924614 -125.278642)
				)
			)
		)
		(zone
			(layer "B.Cu")
			(hatch none 0.5)
			(connect_pads
				(clearance 0)
			)
			(min_thickness 0.25)
			(keepout
				(tracks allowed)
				(vias not_allowed)
				(pads allowed)
				(copperpour not_allowed)
				(footprints allowed)
			)
			(placement
				(enabled no)
				(sheetname "")
			)
			(fill
				(thermal_gap 0.5)
				(thermal_bridge_width 0.5)
				(island_removal_mode 0)
			)
			(polygon
				(pts
					(xy 354.924614 -125.278642) (xy 354.924614 -125.786642) (xy 354.543614 -125.786642) (xy 354.543614 -125.278642)
				)
			)
		)
	)
	(footprint ""
		(layer "B.Cu")
		(at 374.65 -66.04 180)
		(property "Reference" "R2R3"
			(at 0 0 0)
			(layer "B.SilkS")
			(hide yes)
			(effects
				(font
					(size 1.27 1.27)
				)
				(justify mirror)
			)
		)
		(property "Value" ""
			(at 0 0 0)
			(layer "B.Fab")
			(effects
				(font
					(size 1.27 1.27)
				)
				(justify mirror)
			)
		)
		(duplicate_pad_numbers_are_jumpers no)
		(fp_poly
			(pts
				(xy 0.2794 -0.1016) (xy -0.2794 -0.1016) (xy -0.2794 0.9906) (xy 0.2794 0.9906)
			)
			(stroke
				(width 0)
				(type default)
			)
			(fill no)
			(layer "B.CrtYd")
		)
		(fp_line
			(start 0.2794 0.9906)
			(end -0.2794 0.9906)
			(stroke
				(width 0.1)
				(type default)
			)
			(layer "B.Fab")
		)
		(fp_line
			(start 0.2794 -0.1016)
			(end 0.2794 0.9906)
			(stroke
				(width 0.1)
				(type default)
			)
			(layer "B.Fab")
		)
		(fp_line
			(start -0.2794 0.9906)
			(end -0.2794 -0.1016)
			(stroke
				(width 0.1)
				(type default)
			)
			(layer "B.Fab")
		)
		(fp_line
			(start -0.2794 -0.1016)
			(end 0.2794 -0.1016)
			(stroke
				(width 0.1)
				(type default)
			)
			(layer "B.Fab")
		)
		(pad "1" smd rect
			(at 0 0)
			(size 0.508 0.508)
			(layers "B.Cu" "B.Mask" "B.Paste")
			(net "P3V3_STBY")
		)
		(pad "2" smd rect
			(at 0 0.889)
			(size 0.508 0.508)
			(layers "B.Cu" "B.Mask" "B.Paste")
			(net "FM_PLD_DEBUG_MODE_N")
		)
		(zone
			(layer "B.Cu")
			(hatch none 0.5)
			(connect_pads
				(clearance 0)
			)
			(min_thickness 0.25)
			(keepout
				(tracks not_allowed)
				(vias allowed)
				(pads allowed)
				(copperpour not_allowed)
				(footprints allowed)
			)
			(placement
				(enabled no)
				(sheetname "")
			)
			(fill
				(thermal_gap 0.5)
				(thermal_bridge_width 0.5)
				(island_removal_mode 0)
			)
			(polygon
				(pts
					(xy 374.396 -66.675) (xy 374.904 -66.675) (xy 374.904 -66.294) (xy 374.396 -66.294)
				)
			)
		)
		(zone
			(layer "B.Cu")
			(hatch none 0.5)
			(connect_pads
				(clearance 0)
			)
			(min_thickness 0.25)
			(keepout
				(tracks allowed)
				(vias not_allowed)
				(pads allowed)
				(copperpour not_allowed)
				(footprints allowed)
			)
			(placement
				(enabled no)
				(sheetname "")
			)
			(fill
				(thermal_gap 0.5)
				(thermal_bridge_width 0.5)
				(island_removal_mode 0)
			)
			(polygon
				(pts
					(xy 374.396 -66.294) (xy 374.904 -66.294) (xy 374.904 -66.675) (xy 374.396 -66.675)
				)
			)
		)
	)
	(footprint ""
		(layer "B.Cu")
		(at 457.7842 -26.543)
		(property "Reference" "U6W3"
			(at -1.778 -1.46558 0)
			(unlocked yes)
			(layer "B.SilkS")
			(effects
				(font
					(size 0.4064 0.254)
					(thickness 0.1524)
				)
				(justify left mirror)
			)
		)
		(property "Value" ""
			(at 0 0 0)
			(layer "B.Fab")
			(effects
				(font
					(size 1.27 1.27)
				)
				(justify mirror)
			)
		)
		(duplicate_pad_numbers_are_jumpers no)
		(fp_line
			(start -4.191 -0.5969)
			(end -4.191 4.4069)
			(stroke
				(width 0.1524)
				(type default)
			)
			(layer "B.SilkS")
		)
		(fp_line
			(start -4.191 4.4069)
			(end -1.2954 4.4069)
			(stroke
				(width 0.1524)
				(type default)
			)
			(layer "B.SilkS")
		)
		(fp_line
			(start -3.3782 0.6731)
			(end -3.3782 -0.5842)
			(stroke
				(width 0.1524)
				(type default)
			)
			(layer "B.SilkS")
		)
		(fp_line
			(start -2.1082 -0.5842)
			(end -2.1082 0.6731)
			(stroke
				(width 0.1524)
				(type default)
			)
			(layer "B.SilkS")
		)
		(fp_line
			(start -2.1082 0.6731)
			(end -3.3782 0.6731)
			(stroke
				(width 0.1524)
				(type default)
			)
			(layer "B.SilkS")
		)
		(fp_line
			(start -1.2954 -0.5969)
			(end -4.191 -0.5969)
			(stroke
				(width 0.1524)
				(type default)
			)
			(layer "B.SilkS")
		)
		(fp_line
			(start -1.2954 4.4069)
			(end -1.2954 -0.5969)
			(stroke
				(width 0.1524)
				(type default)
			)
			(layer "B.SilkS")
		)
		(fp_circle
			(center 1.382014 -0.7112)
			(end 1.509014 -0.7112)
			(stroke
				(width 0.254)
				(type default)
			)
			(fill no)
			(layer "B.SilkS")
		)
		(fp_poly
			(pts
				(xy -0.7493 -0.5969) (xy -4.7371 -0.5969) (xy -4.7371 4.4069) (xy -0.7493 4.4069)
			)
			(stroke
				(width 0)
				(type default)
			)
			(fill no)
			(layer "B.CrtYd")
		)
		(fp_line
			(start -4.7371 -0.5969)
			(end -4.7371 4.4069)
			(stroke
				(width 0.1)
				(type default)
			)
			(layer "B.Fab")
		)
		(fp_line
			(start -4.7371 4.4069)
			(end -0.7493 4.4069)
			(stroke
				(width 0.1)
				(type default)
			)
			(layer "B.Fab")
		)
		(fp_line
			(start -3.3782 0.6731)
			(end -3.3782 -0.5842)
			(stroke
				(width 0.1)
				(type default)
			)
			(layer "B.Fab")
		)
		(fp_line
			(start -2.1082 -0.5842)
			(end -2.1082 0.6731)
			(stroke
				(width 0.1)
				(type default)
			)
			(layer "B.Fab")
		)
		(fp_line
			(start -2.1082 0.6731)
			(end -3.3782 0.6731)
			(stroke
				(width 0.1)
				(type default)
			)
			(layer "B.Fab")
		)
		(fp_line
			(start -0.7493 -0.5969)
			(end -4.7371 -0.5969)
			(stroke
				(width 0.1)
				(type default)
			)
			(layer "B.Fab")
		)
		(fp_line
			(start -0.7493 4.4069)
			(end -0.7493 -0.5969)
			(stroke
				(width 0.1)
				(type default)
			)
			(layer "B.Fab")
		)
		(fp_circle
			(center 1.382014 -0.7112)
			(end 1.509014 -0.7112)
			(stroke
				(width 0.254)
				(type default)
			)
			(fill no)
			(layer "B.Fab")
		)
		(pad "1" smd rect
			(at 0 0 180)
			(size 1.9304 0.635)
			(layers "B.Cu" "B.Mask" "B.Paste")
			(net "PU_ID_EEPROM_A0")
		)
		(pad "2" smd rect
			(at 0 1.27 180)
			(size 1.9304 0.635)
			(layers "B.Cu" "B.Mask" "B.Paste")
			(net "GND")
		)
		(pad "3" smd rect
			(at 0 2.54 180)
			(size 1.9304 0.635)
			(layers "B.Cu" "B.Mask" "B.Paste")
			(net "GND")
		)
		(pad "4" smd rect
			(at 0 3.81 180)
			(size 1.9304 0.635)
			(layers "B.Cu" "B.Mask" "B.Paste")
			(net "GND")
		)
		(pad "5" smd rect
			(at -5.4864 3.81 180)
			(size 1.9304 0.635)
			(layers "B.Cu" "B.Mask" "B.Paste")
			(net "SMB_HOST_STBY_LVC3_SDA_R3")
		)
		(pad "6" smd rect
			(at -5.4864 2.54 180)
			(size 1.9304 0.635)
			(layers "B.Cu" "B.Mask" "B.Paste")
			(net "SMB_HOST_STBY_LVC3_SCL_R3")
		)
		(pad "7" smd rect
			(at -5.4864 1.27 180)
			(size 1.9304 0.635)
			(layers "B.Cu" "B.Mask" "B.Paste")
			(net "PD_ID_EEPROM_WP")
		)
		(pad "8" smd rect
			(at -5.4864 0 180)
			(size 1.9304 0.635)
			(layers "B.Cu" "B.Mask" "B.Paste")
			(net "P3V3_STBY")
		)
	)
	(footprint ""
		(layer "B.Cu")
		(at 355.178614 -126.624842 -90)
		(property "Reference" "C3M2"
			(at 0 0 90)
			(layer "B.SilkS")
			(hide yes)
			(effects
				(font
					(size 1.27 1.27)
				)
				(justify mirror)
			)
		)
		(property "Value" ""
			(at 0 0 90)
			(layer "B.Fab")
			(effects
				(font
					(size 1.27 1.27)
				)
				(justify mirror)
			)
		)
		(duplicate_pad_numbers_are_jumpers no)
		(fp_poly
			(pts
				(xy -0.3048 -0.1016) (xy -0.3048 0.9906) (xy 0.3048 0.9906) (xy 0.3048 -0.1016)
			)
			(stroke
				(width 0)
				(type default)
			)
			(fill no)
			(layer "B.CrtYd")
		)
		(fp_line
			(start -0.3048 0.9906)
			(end -0.3048 -0.1016)
			(stroke
				(width 0.1)
				(type default)
			)
			(layer "B.Fab")
		)
		(fp_line
			(start 0.3048 0.9906)
			(end -0.3048 0.9906)
			(stroke
				(width 0.1)
				(type default)
			)
			(layer "B.Fab")
		)
		(fp_line
			(start -0.3048 -0.1016)
			(end 0.3048 -0.1016)
			(stroke
				(width 0.1)
				(type default)
			)
			(layer "B.Fab")
		)
		(fp_line
			(start 0.3048 -0.1016)
			(end 0.3048 0.9906)
			(stroke
				(width 0.1)
				(type default)
			)
			(layer "B.Fab")
		)
		(pad "1" smd rect
			(at 0 0 90)
			(size 0.508 0.508)
			(layers "B.Cu" "B.Mask" "B.Paste")
			(net "P3E_CPU0_PE1_PCH_R_RXP<15>")
		)
		(pad "2" smd rect
			(at 0 0.889 90)
			(size 0.508 0.508)
			(layers "B.Cu" "B.Mask" "B.Paste")
			(net "P3E_CPU0_PE1_PCH_RXP<15>")
		)
		(zone
			(layer "B.Cu")
			(hatch none 0.5)
			(connect_pads
				(clearance 0)
			)
			(min_thickness 0.25)
			(keepout
				(tracks not_allowed)
				(vias allowed)
				(pads allowed)
				(copperpour not_allowed)
				(footprints allowed)
			)
			(placement
				(enabled no)
				(sheetname "")
			)
			(fill
				(thermal_gap 0.5)
				(thermal_bridge_width 0.5)
				(island_removal_mode 0)
			)
			(polygon
				(pts
					(xy 354.543614 -126.370842) (xy 354.543614 -126.878842) (xy 354.924614 -126.878842) (xy 354.924614 -126.370842)
				)
			)
		)
		(zone
			(layer "B.Cu")
			(hatch none 0.5)
			(connect_pads
				(clearance 0)
			)
			(min_thickness 0.25)
			(keepout
				(tracks allowed)
				(vias not_allowed)
				(pads allowed)
				(copperpour not_allowed)
				(footprints allowed)
			)
			(placement
				(enabled no)
				(sheetname "")
			)
			(fill
				(thermal_gap 0.5)
				(thermal_bridge_width 0.5)
				(island_removal_mode 0)
			)
			(polygon
				(pts
					(xy 354.924614 -126.370842) (xy 354.924614 -126.878842) (xy 354.543614 -126.878842) (xy 354.543614 -126.370842)
				)
			)
		)
	)
	(footprint ""
		(layer "B.Cu")
		(at 195.453 -17.723612 90)
		(property "Reference" "C6T1"
			(at 0 0 90)
			(layer "B.SilkS")
			(hide yes)
			(effects
				(font
					(size 1.27 1.27)
				)
				(justify mirror)
			)
		)
		(property "Value" ""
			(at 0 0 90)
			(layer "B.Fab")
			(effects
				(font
					(size 1.27 1.27)
				)
				(justify mirror)
			)
		)
		(duplicate_pad_numbers_are_jumpers no)
		(fp_poly
			(pts
				(xy -0.3048 -0.1016) (xy -0.3048 0.9906) (xy 0.3048 0.9906) (xy 0.3048 -0.1016)
			)
			(stroke
				(width 0)
				(type default)
			)
			(fill no)
			(layer "B.CrtYd")
		)
		(fp_line
			(start 0.3048 -0.1016)
			(end 0.3048 0.9906)
			(stroke
				(width 0.1)
				(type default)
			)
			(layer "B.Fab")
		)
		(fp_line
			(start -0.3048 -0.1016)
			(end 0.3048 -0.1016)
			(stroke
				(width 0.1)
				(type default)
			)
			(layer "B.Fab")
		)
		(fp_line
			(start 0.3048 0.9906)
			(end -0.3048 0.9906)
			(stroke
				(width 0.1)
				(type default)
			)
			(layer "B.Fab")
		)
		(fp_line
			(start -0.3048 0.9906)
			(end -0.3048 -0.1016)
			(stroke
				(width 0.1)
				(type default)
			)
			(layer "B.Fab")
		)
		(pad "1" smd rect
			(at 0 0 270)
			(size 0.508 0.508)
			(layers "B.Cu" "B.Mask" "B.Paste")
			(net "M_A_VREF")
		)
		(pad "2" smd rect
			(at 0 0.889 270)
			(size 0.508 0.508)
			(layers "B.Cu" "B.Mask" "B.Paste")
			(net "GND")
		)
		(zone
			(layer "B.Cu")
			(hatch none 0.5)
			(connect_pads
				(clearance 0)
			)
			(min_thickness 0.25)
			(keepout
				(tracks allowed)
				(vias not_allowed)
				(pads allowed)
				(copperpour not_allowed)
				(footprints allowed)
			)
			(placement
				(enabled no)
				(sheetname "")
			)
			(fill
				(thermal_gap 0.5)
				(thermal_bridge_width 0.5)
				(island_removal_mode 0)
			)
			(polygon
				(pts
					(xy 195.707 -17.977612) (xy 195.707 -17.469612) (xy 196.088 -17.469612) (xy 196.088 -17.977612)
				)
			)
		)
		(zone
			(layer "B.Cu")
			(hatch none 0.5)
			(connect_pads
				(clearance 0)
			)
			(min_thickness 0.25)
			(keepout
				(tracks not_allowed)
				(vias allowed)
				(pads allowed)
				(copperpour not_allowed)
				(footprints allowed)
			)
			(placement
				(enabled no)
				(sheetname "")
			)
			(fill
				(thermal_gap 0.5)
				(thermal_bridge_width 0.5)
				(island_removal_mode 0)
			)
			(polygon
				(pts
					(xy 196.088 -17.977612) (xy 196.088 -17.469612) (xy 195.707 -17.469612) (xy 195.707 -17.977612)
				)
			)
		)
	)
	(footprint ""
		(layer "B.Cu")
		(at 418.8206 -11.587734 180)
		(property "Reference" "Q2T1"
			(at 1.22047 3.2004 90)
			(unlocked yes)
			(layer "B.SilkS")
			(effects
				(font
					(size 0.7874 0.5842)
					(thickness 0.1524)
				)
				(justify left mirror)
			)
		)
		(property "Value" ""
			(at 0 0 0)
			(layer "B.Fab")
			(effects
				(font
					(size 1.27 1.27)
				)
				(justify mirror)
			)
		)
		(duplicate_pad_numbers_are_jumpers no)
		(fp_line
			(start -0.381 0.635)
			(end -0.381 1.27)
			(stroke
				(width 0.1524)
				(type default)
			)
			(layer "B.SilkS")
		)
		(fp_line
			(start -0.9525 2.4765)
			(end -1.778 2.4765)
			(stroke
				(width 0.1524)
				(type default)
			)
			(layer "B.SilkS")
		)
		(fp_line
			(start -0.9525 -0.5715)
			(end -1.778 -0.5715)
			(stroke
				(width 0.1524)
				(type default)
			)
			(layer "B.SilkS")
		)
		(fp_line
			(start -1.778 2.4765)
			(end -1.778 1.5875)
			(stroke
				(width 0.1524)
				(type default)
			)
			(layer "B.SilkS")
		)
		(fp_line
			(start -1.778 -0.5715)
			(end -1.778 0.3175)
			(stroke
				(width 0.1524)
				(type default)
			)
			(layer "B.SilkS")
		)
		(fp_circle
			(center 0.9525 -0.9271)
			(end 0.8255 -0.9271)
			(stroke
				(width 0.254)
				(type default)
			)
			(fill no)
			(layer "B.SilkS")
		)
		(fp_poly
			(pts
				(xy -1.778 2.4765) (xy -0.381 2.4765) (xy -0.381 -0.5715) (xy -1.778 -0.5715)
			)
			(stroke
				(width 0)
				(type default)
			)
			(fill no)
			(layer "B.CrtYd")
		)
		(fp_line
			(start -0.381 2.4765)
			(end -1.778 2.4765)
			(stroke
				(width 0.1)
				(type default)
			)
			(layer "B.Fab")
		)
		(fp_line
			(start -0.381 -0.5715)
			(end -0.381 2.4765)
			(stroke
				(width 0.1)
				(type default)
			)
			(layer "B.Fab")
		)
		(fp_line
			(start -1.778 2.4765)
			(end -1.778 -0.5715)
			(stroke
				(width 0.1)
				(type default)
			)
			(layer "B.Fab")
		)
		(fp_line
			(start -1.778 -0.5715)
			(end -0.381 -0.5715)
			(stroke
				(width 0.1)
				(type default)
			)
			(layer "B.Fab")
		)
		(fp_circle
			(center 0.9525 -0.9271)
			(end 0.8255 -0.9271)
			(stroke
				(width 0.254)
				(type default)
			)
			(fill no)
			(layer "B.Fab")
		)
		(pad "1" smd rect
			(at 0 0)
			(size 1.143 0.508)
			(layers "B.Cu" "B.Mask" "B.Paste")
			(net "H_CPU0_FAST_WAKE_B_N")
		)
		(pad "2" smd rect
			(at 0 1.905)
			(size 1.143 0.508)
			(layers "B.Cu" "B.Mask" "B.Paste")
			(net "GND")
		)
		(pad "3" smd rect
			(at -2.159 0.9525)
			(size 1.143 0.508)
			(layers "B.Cu" "B.Mask" "B.Paste")
			(net "H_CPU0_FAST_WAKE")
		)
	)
	(footprint ""
		(layer "B.Cu")
		(at 18.415 -73.406 180)
		(property "Reference" "C9P16"
			(at 0 0 0)
			(layer "B.SilkS")
			(hide yes)
			(effects
				(font
					(size 1.27 1.27)
				)
				(justify mirror)
			)
		)
		(property "Value" ""
			(at 0 0 0)
			(layer "B.Fab")
			(effects
				(font
					(size 1.27 1.27)
				)
				(justify mirror)
			)
		)
		(duplicate_pad_numbers_are_jumpers no)
		(fp_rect
			(start -0.3048 0.9906)
			(end 0.3048 -0.1016)
			(stroke
				(width 0)
				(type default)
			)
			(fill no)
			(layer "B.CrtYd")
		)
		(fp_line
			(start 0.3048 0.9906)
			(end -0.3048 0.9906)
			(stroke
				(width 0.1)
				(type default)
			)
			(layer "B.Fab")
		)
		(fp_line
			(start 0.3048 -0.1016)
			(end 0.3048 0.9906)
			(stroke
				(width 0.1)
				(type default)
			)
			(layer "B.Fab")
		)
		(fp_line
			(start -0.3048 0.9906)
			(end -0.3048 -0.1016)
			(stroke
				(width 0.1)
				(type default)
			)
			(layer "B.Fab")
		)
		(fp_line
			(start -0.3048 -0.1016)
			(end 0.3048 -0.1016)
			(stroke
				(width 0.1)
				(type default)
			)
			(layer "B.Fab")
		)
		(pad "1" smd rect
			(at 0 0)
			(size 0.508 0.508)
			(layers "B.Cu" "B.Mask" "B.Paste")
			(net "A_HSC_MOP")
		)
		(pad "2" smd rect
			(at 0 0.889)
			(size 0.508 0.508)
			(layers "B.Cu" "B.Mask" "B.Paste")
			(net "AGND_HSC")
		)
		(zone
			(layer "B.Cu")
			(hatch none 0.5)
			(connect_pads
				(clearance 0)
			)
			(min_thickness 0.25)
			(keepout
				(tracks not_allowed)
				(vias allowed)
				(pads allowed)
				(copperpour not_allowed)
				(footprints allowed)
			)
			(placement
				(enabled no)
				(sheetname "")
			)
			(fill
				(thermal_gap 0.5)
				(thermal_bridge_width 0.5)
				(island_removal_mode 0)
			)
			(polygon
				(pts
					(xy 18.669 -74.041) (xy 18.161 -74.041) (xy 18.161 -73.66) (xy 18.669 -73.66)
				)
			)
		)
		(zone
			(layer "B.Cu")
			(hatch none 0.5)
			(connect_pads
				(clearance 0)
			)
			(min_thickness 0.25)
			(keepout
				(tracks allowed)
				(vias not_allowed)
				(pads allowed)
				(copperpour not_allowed)
				(footprints allowed)
			)
			(placement
				(enabled no)
				(sheetname "")
			)
			(fill
				(thermal_gap 0.5)
				(thermal_bridge_width 0.5)
				(island_removal_mode 0)
			)
			(polygon
				(pts
					(xy 18.669 -74.041) (xy 18.161 -74.041) (xy 18.161 -73.66) (xy 18.669 -73.66)
				)
			)
		)
	)
	(footprint ""
		(layer "B.Cu")
		(at 171.196 -87.757)
		(property "Reference" "R6P3"
			(at 0 0 0)
			(layer "B.SilkS")
			(hide yes)
			(effects
				(font
					(size 1.27 1.27)
				)
				(justify mirror)
			)
		)
		(property "Value" ""
			(at 0 0 0)
			(layer "B.Fab")
			(effects
				(font
					(size 1.27 1.27)
				)
				(justify mirror)
			)
		)
		(duplicate_pad_numbers_are_jumpers no)
		(fp_poly
			(pts
				(xy 0.2794 -0.1016) (xy -0.2794 -0.1016) (xy -0.2794 0.9906) (xy 0.2794 0.9906)
			)
			(stroke
				(width 0)
				(type default)
			)
			(fill no)
			(layer "B.CrtYd")
		)
		(fp_line
			(start -0.2794 -0.1016)
			(end 0.2794 -0.1016)
			(stroke
				(width 0.1)
				(type default)
			)
			(layer "B.Fab")
		)
		(fp_line
			(start -0.2794 0.9906)
			(end -0.2794 -0.1016)
			(stroke
				(width 0.1)
				(type default)
			)
			(layer "B.Fab")
		)
		(fp_line
			(start 0.2794 -0.1016)
			(end 0.2794 0.9906)
			(stroke
				(width 0.1)
				(type default)
			)
			(layer "B.Fab")
		)
		(fp_line
			(start 0.2794 0.9906)
			(end -0.2794 0.9906)
			(stroke
				(width 0.1)
				(type default)
			)
			(layer "B.Fab")
		)
		(pad "1" smd rect
			(at 0 0 180)
			(size 0.508 0.508)
			(layers "B.Cu" "B.Mask" "B.Paste")
			(net "CLK_100M_CPU0_RC_REFCLK1_DP")
		)
		(pad "2" smd rect
			(at 0 0.889 180)
			(size 0.508 0.508)
			(layers "B.Cu" "B.Mask" "B.Paste")
			(net "GND")
		)
		(zone
			(layer "B.Cu")
			(hatch none 0.5)
			(connect_pads
				(clearance 0)
			)
			(min_thickness 0.25)
			(keepout
				(tracks allowed)
				(vias not_allowed)
				(pads allowed)
				(copperpour not_allowed)
				(footprints allowed)
			)
			(placement
				(enabled no)
				(sheetname "")
			)
			(fill
				(thermal_gap 0.5)
				(thermal_bridge_width 0.5)
				(island_removal_mode 0)
			)
			(polygon
				(pts
					(xy 171.45 -87.503) (xy 170.942 -87.503) (xy 170.942 -87.122) (xy 171.45 -87.122)
				)
			)
		)
		(zone
			(layer "B.Cu")
			(hatch none 0.5)
			(connect_pads
				(clearance 0)
			)
			(min_thickness 0.25)
			(keepout
				(tracks not_allowed)
				(vias allowed)
				(pads allowed)
				(copperpour not_allowed)
				(footprints allowed)
			)
			(placement
				(enabled no)
				(sheetname "")
			)
			(fill
				(thermal_gap 0.5)
				(thermal_bridge_width 0.5)
				(island_removal_mode 0)
			)
			(polygon
				(pts
					(xy 171.45 -87.122) (xy 170.942 -87.122) (xy 170.942 -87.503) (xy 171.45 -87.503)
				)
			)
		)
	)
	(footprint ""
		(layer "B.Cu")
		(at 420.624 -150.876 90)
		(property "Reference" "C2L15"
			(at 0 0 90)
			(layer "B.SilkS")
			(hide yes)
			(effects
				(font
					(size 1.27 1.27)
				)
				(justify mirror)
			)
		)
		(property "Value" ""
			(at 0 0 90)
			(layer "B.Fab")
			(effects
				(font
					(size 1.27 1.27)
				)
				(justify mirror)
			)
		)
		(duplicate_pad_numbers_are_jumpers no)
		(fp_poly
			(pts
				(xy -0.3048 -0.1016) (xy -0.3048 0.9906) (xy 0.3048 0.9906) (xy 0.3048 -0.1016)
			)
			(stroke
				(width 0)
				(type default)
			)
			(fill no)
			(layer "B.CrtYd")
		)
		(fp_line
			(start 0.3048 -0.1016)
			(end 0.3048 0.9906)
			(stroke
				(width 0.1)
				(type default)
			)
			(layer "B.Fab")
		)
		(fp_line
			(start -0.3048 -0.1016)
			(end 0.3048 -0.1016)
			(stroke
				(width 0.1)
				(type default)
			)
			(layer "B.Fab")
		)
		(fp_line
			(start 0.3048 0.9906)
			(end -0.3048 0.9906)
			(stroke
				(width 0.1)
				(type default)
			)
			(layer "B.Fab")
		)
		(fp_line
			(start -0.3048 0.9906)
			(end -0.3048 -0.1016)
			(stroke
				(width 0.1)
				(type default)
			)
			(layer "B.Fab")
		)
		(pad "1" smd rect
			(at 0 0 270)
			(size 0.508 0.508)
			(layers "B.Cu" "B.Mask" "B.Paste")
			(net "SATA6G_PCH_PCIE_UP_SATA_RXP<2>")
		)
		(pad "2" smd rect
			(at 0 0.889 270)
			(size 0.508 0.508)
			(layers "B.Cu" "B.Mask" "B.Paste")
			(net "SATA6G_P2_RX_C_DP")
		)
		(zone
			(layer "B.Cu")
			(hatch none 0.5)
			(connect_pads
				(clearance 0)
			)
			(min_thickness 0.25)
			(keepout
				(tracks allowed)
				(vias not_allowed)
				(pads allowed)
				(copperpour not_allowed)
				(footprints allowed)
			)
			(placement
				(enabled no)
				(sheetname "")
			)
			(fill
				(thermal_gap 0.5)
				(thermal_bridge_width 0.5)
				(island_removal_mode 0)
			)
			(polygon
				(pts
					(xy 420.878 -151.13) (xy 420.878 -150.622) (xy 421.259 -150.622) (xy 421.259 -151.13)
				)
			)
		)
		(zone
			(layer "B.Cu")
			(hatch none 0.5)
			(connect_pads
				(clearance 0)
			)
			(min_thickness 0.25)
			(keepout
				(tracks not_allowed)
				(vias allowed)
				(pads allowed)
				(copperpour not_allowed)
				(footprints allowed)
			)
			(placement
				(enabled no)
				(sheetname "")
			)
			(fill
				(thermal_gap 0.5)
				(thermal_bridge_width 0.5)
				(island_removal_mode 0)
			)
			(polygon
				(pts
					(xy 421.259 -151.13) (xy 421.259 -150.622) (xy 420.878 -150.622) (xy 420.878 -151.13)
				)
			)
		)
	)
	(footprint ""
		(layer "B.Cu")
		(at 101.3968 -3.3528 90)
		(property "Reference" "C5G89"
			(at -1.14681 0.76708 180)
			(unlocked yes)
			(layer "B.SilkS")
			(effects
				(font
					(size 0.7874 0.5842)
					(thickness 0.1524)
				)
				(justify mirror)
			)
		)
		(property "Value" ""
			(at 0 0 90)
			(layer "B.Fab")
			(effects
				(font
					(size 1.27 1.27)
				)
				(justify mirror)
			)
		)
		(duplicate_pad_numbers_are_jumpers no)
		(fp_rect
			(start -0.4953 -0.2032)
			(end 0.4953 1.6002)
			(stroke
				(width 0)
				(type default)
			)
			(fill no)
			(layer "B.CrtYd")
		)
		(fp_line
			(start 0.4953 -0.2032)
			(end -0.4953 -0.2032)
			(stroke
				(width 0.1)
				(type default)
			)
			(layer "B.Fab")
		)
		(fp_line
			(start -0.4953 -0.2032)
			(end -0.4953 1.6002)
			(stroke
				(width 0.1)
				(type default)
			)
			(layer "B.Fab")
		)
		(fp_line
			(start 0.4953 1.6002)
			(end 0.4953 -0.2032)
			(stroke
				(width 0.1)
				(type default)
			)
			(layer "B.Fab")
		)
		(fp_line
			(start -0.4953 1.6002)
			(end 0.4953 1.6002)
			(stroke
				(width 0.1)
				(type default)
			)
			(layer "B.Fab")
		)
		(pad "1" smd rect
			(at 0 0 270)
			(size 0.762 0.889)
			(layers "B.Cu" "B.Mask" "B.Paste")
			(net "PVDDQ_GHJ")
		)
		(pad "2" smd rect
			(at 0 1.397 270)
			(size 0.762 0.889)
			(layers "B.Cu" "B.Mask" "B.Paste")
			(net "GND")
		)
		(zone
			(layer "B.Cu")
			(hatch none 0.5)
			(connect_pads
				(clearance 0)
			)
			(min_thickness 0.25)
			(keepout
				(tracks not_allowed)
				(vias allowed)
				(pads allowed)
				(copperpour not_allowed)
				(footprints allowed)
			)
			(placement
				(enabled no)
				(sheetname "")
			)
			(fill
				(thermal_gap 0.5)
				(thermal_bridge_width 0.5)
				(island_removal_mode 0)
			)
			(polygon
				(pts
					(xy 101.8413 -2.9718) (xy 102.3493 -2.9718) (xy 102.3493 -3.7338) (xy 101.8413 -3.7338)
				)
			)
		)
	)
	(footprint ""
		(layer "B.Cu")
		(at 446.381632 -32.4485 90)
		(property "Reference" "R25W1"
			(at 0 0 90)
			(layer "B.SilkS")
			(hide yes)
			(effects
				(font
					(size 1.27 1.27)
				)
				(justify mirror)
			)
		)
		(property "Value" "*"
			(at -0.064008 -4.108196 90)
			(unlocked yes)
			(layer "B.Fab")
			(hide yes)
			(effects
				(font
					(size 1.27 1.016)
					(thickness 0.1524)
				)
				(justify mirror)
			)
		)
		(property "Device Type" "120R2F-GP_RCL_GP-120R2F-GP,64.A"
			(at -0.064008 -5.632196 90)
			(unlocked yes)
			(layer "B.Fab")
			(hide yes)
			(effects
				(font
					(size 1.27 1.016)
					(thickness 0.1524)
				)
				(justify mirror)
			)
		)
		(duplicate_pad_numbers_are_jumpers no)
		(fp_line
			(start 0.508 -0.9398)
			(end 0.508 0.9398)
			(stroke
				(width 0.1524)
				(type default)
			)
			(layer "B.SilkS")
		)
		(fp_line
			(start -0.508 -0.9398)
			(end 0.508 -0.9398)
			(stroke
				(width 0.1524)
				(type default)
			)
			(layer "B.SilkS")
		)
		(fp_rect
			(start 0.508 0.9398)
			(end -0.508 -0.9398)
			(stroke
				(width 0)
				(type default)
			)
			(fill no)
			(layer "B.CrtYd")
		)
		(fp_rect
			(start 0.508 0.9398)
			(end -0.508 -0.9398)
			(stroke
				(width 0)
				(type default)
			)
			(fill no)
			(layer "B.Fab")
		)
		(pad "1" smd custom
			(at 0 -0.4445 270)
			(size 0.1397 0.1397)
			(layers "B.Cu" "B.Mask" "B.Paste")
			(net "GND")
			(options
				(clearance outline)
				(anchor circle)
			)
			(primitives
				(gr_poly
					(pts
						(arc
							(start -0.1778 0.2794)
							(mid -0.249642 0.249642)
							(end -0.2794 0.1778)
						)
						(arc
							(start -0.2794 -0.1778)
							(mid -0.249642 -0.249642)
							(end -0.1778 -0.2794)
						)
						(arc
							(start 0.1778 -0.2794)
							(mid 0.249642 -0.249642)
							(end 0.2794 -0.1778)
						)
						(arc
							(start 0.2794 0.1778)
							(mid 0.249642 0.249642)
							(end 0.1778 0.2794)
						)
					)
					(width 0)
					(fill yes)
				)
			)
		)
		(pad "2" smd custom
			(at 0 0.4445 270)
			(size 0.1397 0.1397)
			(layers "B.Cu" "B.Mask" "B.Paste")
			(net "BMC_M_CKE")
			(options
				(clearance outline)
				(anchor circle)
			)
			(primitives
				(gr_poly
					(pts
						(arc
							(start -0.1778 0.2794)
							(mid -0.249642 0.249642)
							(end -0.2794 0.1778)
						)
						(arc
							(start -0.2794 -0.1778)
							(mid -0.249642 -0.249642)
							(end -0.1778 -0.2794)
						)
						(arc
							(start 0.1778 -0.2794)
							(mid 0.249642 -0.249642)
							(end 0.2794 -0.1778)
						)
						(arc
							(start 0.2794 0.1778)
							(mid 0.249642 0.249642)
							(end 0.1778 0.2794)
						)
					)
					(width 0)
					(fill yes)
				)
			)
		)
	)
	(footprint ""
		(layer "B.Cu")
		(at 3.893312 -20.237196 90)
		(property "Reference" "C9T4"
			(at 0 0 90)
			(layer "B.SilkS")
			(hide yes)
			(effects
				(font
					(size 1.27 1.27)
				)
				(justify mirror)
			)
		)
		(property "Value" ""
			(at 0 0 90)
			(layer "B.Fab")
			(effects
				(font
					(size 1.27 1.27)
				)
				(justify mirror)
			)
		)
		(duplicate_pad_numbers_are_jumpers no)
		(fp_rect
			(start -0.7239 -0.2159)
			(end 0.7239 1.9939)
			(stroke
				(width 0)
				(type default)
			)
			(fill no)
			(layer "B.CrtYd")
		)
		(fp_line
			(start 0.7239 -0.2159)
			(end 0.7239 1.9939)
			(stroke
				(width 0.1)
				(type default)
			)
			(layer "B.Fab")
		)
		(fp_line
			(start -0.7239 -0.2159)
			(end 0.7239 -0.2159)
			(stroke
				(width 0.1)
				(type default)
			)
			(layer "B.Fab")
		)
		(fp_line
			(start 0.7239 1.9939)
			(end -0.7239 1.9939)
			(stroke
				(width 0.1)
				(type default)
			)
			(layer "B.Fab")
		)
		(fp_line
			(start -0.7239 1.9939)
			(end -0.7239 -0.2159)
			(stroke
				(width 0.1)
				(type default)
			)
			(layer "B.Fab")
		)
		(pad "1" smd rect
			(at 0 0 270)
			(size 1.27 1.016)
			(layers "B.Cu" "B.Mask" "B.Paste")
			(net "VR_FET_SW_P12V_STBY_PVDDQ_GHJ")
		)
		(pad "2" smd rect
			(at 0 1.778 270)
			(size 1.27 1.016)
			(layers "B.Cu" "B.Mask" "B.Paste")
			(net "GND")
		)
		(zone
			(layer "B.Cu")
			(hatch none 0.5)
			(connect_pads
				(clearance 0)
			)
			(min_thickness 0.25)
			(keepout
				(tracks not_allowed)
				(vias allowed)
				(pads allowed)
				(copperpour not_allowed)
				(footprints allowed)
			)
			(placement
				(enabled no)
				(sheetname "")
			)
			(fill
				(thermal_gap 0.5)
				(thermal_bridge_width 0.5)
				(island_removal_mode 0)
			)
			(polygon
				(pts
					(xy 4.401312 -19.602196) (xy 5.163312 -19.602196) (xy 5.163312 -20.872196) (xy 4.401312 -20.872196)
				)
			)
		)
	)
	(footprint ""
		(layer "B.Cu")
		(at 398.860518 -61.894974 -90)
		(property "Reference" "R1W29"
			(at 0.8382 -0.67818 270)
			(unlocked yes)
			(layer "B.SilkS")
			(effects
				(font
					(size 0.4064 0.254)
					(thickness 0.1524)
				)
				(justify left mirror)
			)
		)
		(property "Value" ""
			(at 0 0 90)
			(layer "B.Fab")
			(effects
				(font
					(size 1.27 1.27)
				)
				(justify mirror)
			)
		)
		(duplicate_pad_numbers_are_jumpers no)
		(fp_poly
			(pts
				(xy 0.2794 -0.1016) (xy -0.2794 -0.1016) (xy -0.2794 0.9906) (xy 0.2794 0.9906)
			)
			(stroke
				(width 0)
				(type default)
			)
			(fill no)
			(layer "B.CrtYd")
		)
		(fp_line
			(start -0.2794 0.9906)
			(end -0.2794 -0.1016)
			(stroke
				(width 0.1)
				(type default)
			)
			(layer "B.Fab")
		)
		(fp_line
			(start 0.2794 0.9906)
			(end -0.2794 0.9906)
			(stroke
				(width 0.1)
				(type default)
			)
			(layer "B.Fab")
		)
		(fp_line
			(start -0.2794 -0.1016)
			(end 0.2794 -0.1016)
			(stroke
				(width 0.1)
				(type default)
			)
			(layer "B.Fab")
		)
		(fp_line
			(start 0.2794 -0.1016)
			(end 0.2794 0.9906)
			(stroke
				(width 0.1)
				(type default)
			)
			(layer "B.Fab")
		)
		(pad "1" smd rect
			(at 0 0 90)
			(size 0.508 0.508)
			(layers "B.Cu" "B.Mask" "B.Paste")
			(net "RST_BMC_SYSRST_BTN_OUT_B_N")
		)
		(pad "2" smd rect
			(at 0 0.889 90)
			(size 0.508 0.508)
			(layers "B.Cu" "B.Mask" "B.Paste")
			(net "RST_BMC_SYSRST_BTN_OUT_B_R1_N")
		)
		(zone
			(layer "B.Cu")
			(hatch none 0.5)
			(connect_pads
				(clearance 0)
			)
			(min_thickness 0.25)
			(keepout
				(tracks not_allowed)
				(vias allowed)
				(pads allowed)
				(copperpour not_allowed)
				(footprints allowed)
			)
			(placement
				(enabled no)
				(sheetname "")
			)
			(fill
				(thermal_gap 0.5)
				(thermal_bridge_width 0.5)
				(island_removal_mode 0)
			)
			(polygon
				(pts
					(xy 398.225518 -61.640974) (xy 398.225518 -62.148974) (xy 398.606518 -62.148974) (xy 398.606518 -61.640974)
				)
			)
		)
		(zone
			(layer "B.Cu")
			(hatch none 0.5)
			(connect_pads
				(clearance 0)
			)
			(min_thickness 0.25)
			(keepout
				(tracks allowed)
				(vias not_allowed)
				(pads allowed)
				(copperpour not_allowed)
				(footprints allowed)
			)
			(placement
				(enabled no)
				(sheetname "")
			)
			(fill
				(thermal_gap 0.5)
				(thermal_bridge_width 0.5)
				(island_removal_mode 0)
			)
			(polygon
				(pts
					(xy 398.606518 -61.640974) (xy 398.606518 -62.148974) (xy 398.225518 -62.148974) (xy 398.225518 -61.640974)
				)
			)
		)
	)
	(footprint ""
		(layer "B.Cu")
		(at 259.4102 -144.977612 90)
		(property "Reference" "C5L14"
			(at 0 0 90)
			(layer "B.SilkS")
			(hide yes)
			(effects
				(font
					(size 1.27 1.27)
				)
				(justify mirror)
			)
		)
		(property "Value" ""
			(at 0 0 90)
			(layer "B.Fab")
			(effects
				(font
					(size 1.27 1.27)
				)
				(justify mirror)
			)
		)
		(duplicate_pad_numbers_are_jumpers no)
		(fp_rect
			(start -0.7239 -0.2159)
			(end 0.7239 1.9939)
			(stroke
				(width 0)
				(type default)
			)
			(fill no)
			(layer "B.CrtYd")
		)
		(fp_line
			(start 0.7239 -0.2159)
			(end 0.7239 1.9939)
			(stroke
				(width 0.1)
				(type default)
			)
			(layer "B.Fab")
		)
		(fp_line
			(start -0.7239 -0.2159)
			(end 0.7239 -0.2159)
			(stroke
				(width 0.1)
				(type default)
			)
			(layer "B.Fab")
		)
		(fp_line
			(start 0.7239 1.9939)
			(end -0.7239 1.9939)
			(stroke
				(width 0.1)
				(type default)
			)
			(layer "B.Fab")
		)
		(fp_line
			(start -0.7239 1.9939)
			(end -0.7239 -0.2159)
			(stroke
				(width 0.1)
				(type default)
			)
			(layer "B.Fab")
		)
		(pad "1" smd rect
			(at 0 0 270)
			(size 1.27 1.016)
			(layers "B.Cu" "B.Mask" "B.Paste")
			(net "PVDDQ_DEF")
		)
		(pad "2" smd rect
			(at 0 1.778 270)
			(size 1.27 1.016)
			(layers "B.Cu" "B.Mask" "B.Paste")
			(net "GND")
		)
		(zone
			(layer "B.Cu")
			(hatch none 0.5)
			(connect_pads
				(clearance 0)
			)
			(min_thickness 0.25)
			(keepout
				(tracks not_allowed)
				(vias allowed)
				(pads allowed)
				(copperpour not_allowed)
				(footprints allowed)
			)
			(placement
				(enabled no)
				(sheetname "")
			)
			(fill
				(thermal_gap 0.5)
				(thermal_bridge_width 0.5)
				(island_removal_mode 0)
			)
			(polygon
				(pts
					(xy 259.9182 -144.342612) (xy 260.6802 -144.342612) (xy 260.6802 -145.612612) (xy 259.9182 -145.612612)
				)
			)
		)
	)
	(footprint ""
		(layer "B.Cu")
		(at 343.248234 -130.120898 90)
		(property "Reference" "R7B20"
			(at 0 0 90)
			(layer "B.SilkS")
			(hide yes)
			(effects
				(font
					(size 1.27 1.27)
				)
				(justify mirror)
			)
		)
		(property "Value" ""
			(at 0 0 90)
			(layer "B.Fab")
			(effects
				(font
					(size 1.27 1.27)
				)
				(justify mirror)
			)
		)
		(duplicate_pad_numbers_are_jumpers no)
		(fp_poly
			(pts
				(xy 0.2794 -0.1016) (xy -0.2794 -0.1016) (xy -0.2794 0.9906) (xy 0.2794 0.9906)
			)
			(stroke
				(width 0)
				(type default)
			)
			(fill no)
			(layer "B.CrtYd")
		)
		(fp_line
			(start 0.2794 -0.1016)
			(end 0.2794 0.9906)
			(stroke
				(width 0.1)
				(type default)
			)
			(layer "B.Fab")
		)
		(fp_line
			(start -0.2794 -0.1016)
			(end 0.2794 -0.1016)
			(stroke
				(width 0.1)
				(type default)
			)
			(layer "B.Fab")
		)
		(fp_line
			(start 0.2794 0.9906)
			(end -0.2794 0.9906)
			(stroke
				(width 0.1)
				(type default)
			)
			(layer "B.Fab")
		)
		(fp_line
			(start -0.2794 0.9906)
			(end -0.2794 -0.1016)
			(stroke
				(width 0.1)
				(type default)
			)
			(layer "B.Fab")
		)
		(pad "1" smd rect
			(at 0 0 270)
			(size 0.508 0.508)
			(layers "B.Cu" "B.Mask" "B.Paste")
			(net "GND")
		)
		(pad "2" smd rect
			(at 0 0.889 270)
			(size 0.508 0.508)
			(layers "B.Cu" "B.Mask" "B.Paste")
			(net "AGND_PVPP_DEF")
		)
		(zone
			(layer "B.Cu")
			(hatch none 0.5)
			(connect_pads
				(clearance 0)
			)
			(min_thickness 0.25)
			(keepout
				(tracks allowed)
				(vias not_allowed)
				(pads allowed)
				(copperpour not_allowed)
				(footprints allowed)
			)
			(placement
				(enabled no)
				(sheetname "")
			)
			(fill
				(thermal_gap 0.5)
				(thermal_bridge_width 0.5)
				(island_removal_mode 0)
			)
			(polygon
				(pts
					(xy 343.502234 -130.374898) (xy 343.502234 -129.866898) (xy 343.883234 -129.866898) (xy 343.883234 -130.374898)
				)
			)
		)
		(zone
			(layer "B.Cu")
			(hatch none 0.5)
			(connect_pads
				(clearance 0)
			)
			(min_thickness 0.25)
			(keepout
				(tracks not_allowed)
				(vias allowed)
				(pads allowed)
				(copperpour not_allowed)
				(footprints allowed)
			)
			(placement
				(enabled no)
				(sheetname "")
			)
			(fill
				(thermal_gap 0.5)
				(thermal_bridge_width 0.5)
				(island_removal_mode 0)
			)
			(polygon
				(pts
					(xy 343.883234 -130.374898) (xy 343.883234 -129.866898) (xy 343.502234 -129.866898) (xy 343.502234 -130.374898)
				)
			)
		)
	)
	(footprint ""
		(layer "B.Cu")
		(at 405.219408 -94.517718 -90)
		(property "Reference" "R2U30"
			(at 0 0 90)
			(layer "B.SilkS")
			(hide yes)
			(effects
				(font
					(size 1.27 1.27)
				)
				(justify mirror)
			)
		)
		(property "Value" ""
			(at 0 0 90)
			(layer "B.Fab")
			(effects
				(font
					(size 1.27 1.27)
				)
				(justify mirror)
			)
		)
		(duplicate_pad_numbers_are_jumpers no)
		(fp_poly
			(pts
				(xy 0.2794 -0.1016) (xy -0.2794 -0.1016) (xy -0.2794 0.9906) (xy 0.2794 0.9906)
			)
			(stroke
				(width 0)
				(type default)
			)
			(fill no)
			(layer "B.CrtYd")
		)
		(fp_line
			(start -0.2794 0.9906)
			(end -0.2794 -0.1016)
			(stroke
				(width 0.1)
				(type default)
			)
			(layer "B.Fab")
		)
		(fp_line
			(start 0.2794 0.9906)
			(end -0.2794 0.9906)
			(stroke
				(width 0.1)
				(type default)
			)
			(layer "B.Fab")
		)
		(fp_line
			(start -0.2794 -0.1016)
			(end 0.2794 -0.1016)
			(stroke
				(width 0.1)
				(type default)
			)
			(layer "B.Fab")
		)
		(fp_line
			(start 0.2794 -0.1016)
			(end 0.2794 0.9906)
			(stroke
				(width 0.1)
				(type default)
			)
			(layer "B.Fab")
		)
		(pad "1" smd rect
			(at 0 0 90)
			(size 0.508 0.508)
			(layers "B.Cu" "B.Mask" "B.Paste")
			(net "P3V3_STBY")
		)
		(pad "2" smd rect
			(at 0 0.889 90)
			(size 0.508 0.508)
			(layers "B.Cu" "B.Mask" "B.Paste")
			(net "FM_UV_ADR_TRIGGER_EN")
		)
		(zone
			(layer "B.Cu")
			(hatch none 0.5)
			(connect_pads
				(clearance 0)
			)
			(min_thickness 0.25)
			(keepout
				(tracks not_allowed)
				(vias allowed)
				(pads allowed)
				(copperpour not_allowed)
				(footprints allowed)
			)
			(placement
				(enabled no)
				(sheetname "")
			)
			(fill
				(thermal_gap 0.5)
				(thermal_bridge_width 0.5)
				(island_removal_mode 0)
			)
			(polygon
				(pts
					(xy 404.584408 -94.263718) (xy 404.584408 -94.771718) (xy 404.965408 -94.771718) (xy 404.965408 -94.263718)
				)
			)
		)
		(zone
			(layer "B.Cu")
			(hatch none 0.5)
			(connect_pads
				(clearance 0)
			)
			(min_thickness 0.25)
			(keepout
				(tracks allowed)
				(vias not_allowed)
				(pads allowed)
				(copperpour not_allowed)
				(footprints allowed)
			)
			(placement
				(enabled no)
				(sheetname "")
			)
			(fill
				(thermal_gap 0.5)
				(thermal_bridge_width 0.5)
				(island_removal_mode 0)
			)
			(polygon
				(pts
					(xy 404.965408 -94.263718) (xy 404.965408 -94.771718) (xy 404.584408 -94.771718) (xy 404.584408 -94.263718)
				)
			)
		)
	)
	(footprint ""
		(layer "B.Cu")
		(at 372.676166 -61.098938 90)
		(property "Reference" "R3R1"
			(at 0 0 90)
			(layer "B.SilkS")
			(hide yes)
			(effects
				(font
					(size 1.27 1.27)
				)
				(justify mirror)
			)
		)
		(property "Value" ""
			(at 0 0 90)
			(layer "B.Fab")
			(effects
				(font
					(size 1.27 1.27)
				)
				(justify mirror)
			)
		)
		(duplicate_pad_numbers_are_jumpers no)
		(fp_poly
			(pts
				(xy 0.2794 -0.1016) (xy -0.2794 -0.1016) (xy -0.2794 0.9906) (xy 0.2794 0.9906)
			)
			(stroke
				(width 0)
				(type default)
			)
			(fill no)
			(layer "B.CrtYd")
		)
		(fp_line
			(start 0.2794 -0.1016)
			(end 0.2794 0.9906)
			(stroke
				(width 0.1)
				(type default)
			)
			(layer "B.Fab")
		)
		(fp_line
			(start -0.2794 -0.1016)
			(end 0.2794 -0.1016)
			(stroke
				(width 0.1)
				(type default)
			)
			(layer "B.Fab")
		)
		(fp_line
			(start 0.2794 0.9906)
			(end -0.2794 0.9906)
			(stroke
				(width 0.1)
				(type default)
			)
			(layer "B.Fab")
		)
		(fp_line
			(start -0.2794 0.9906)
			(end -0.2794 -0.1016)
			(stroke
				(width 0.1)
				(type default)
			)
			(layer "B.Fab")
		)
		(pad "1" smd rect
			(at 0 0 270)
			(size 0.508 0.508)
			(layers "B.Cu" "B.Mask" "B.Paste")
			(net "PD_GTL2104_DIR_1")
		)
		(pad "2" smd rect
			(at 0 0.889 270)
			(size 0.508 0.508)
			(layers "B.Cu" "B.Mask" "B.Paste")
			(net "GND")
		)
		(zone
			(layer "B.Cu")
			(hatch none 0.5)
			(connect_pads
				(clearance 0)
			)
			(min_thickness 0.25)
			(keepout
				(tracks allowed)
				(vias not_allowed)
				(pads allowed)
				(copperpour not_allowed)
				(footprints allowed)
			)
			(placement
				(enabled no)
				(sheetname "")
			)
			(fill
				(thermal_gap 0.5)
				(thermal_bridge_width 0.5)
				(island_removal_mode 0)
			)
			(polygon
				(pts
					(xy 372.930166 -61.352938) (xy 372.930166 -60.844938) (xy 373.311166 -60.844938) (xy 373.311166 -61.352938)
				)
			)
		)
		(zone
			(layer "B.Cu")
			(hatch none 0.5)
			(connect_pads
				(clearance 0)
			)
			(min_thickness 0.25)
			(keepout
				(tracks not_allowed)
				(vias allowed)
				(pads allowed)
				(copperpour not_allowed)
				(footprints allowed)
			)
			(placement
				(enabled no)
				(sheetname "")
			)
			(fill
				(thermal_gap 0.5)
				(thermal_bridge_width 0.5)
				(island_removal_mode 0)
			)
			(polygon
				(pts
					(xy 373.311166 -61.352938) (xy 373.311166 -60.844938) (xy 372.930166 -60.844938) (xy 372.930166 -61.352938)
				)
			)
		)
	)
	(footprint ""
		(layer "B.Cu")
		(at 166.68877 2.209546 90)
		(property "Reference" "R6U13"
			(at 0 0 90)
			(layer "B.SilkS")
			(hide yes)
			(effects
				(font
					(size 1.27 1.27)
				)
				(justify mirror)
			)
		)
		(property "Value" ""
			(at 0 0 90)
			(layer "B.Fab")
			(effects
				(font
					(size 1.27 1.27)
				)
				(justify mirror)
			)
		)
		(duplicate_pad_numbers_are_jumpers no)
		(fp_poly
			(pts
				(xy 0.2794 -0.1016) (xy -0.2794 -0.1016) (xy -0.2794 0.9906) (xy 0.2794 0.9906)
			)
			(stroke
				(width 0)
				(type default)
			)
			(fill no)
			(layer "B.CrtYd")
		)
		(fp_line
			(start 0.2794 -0.1016)
			(end 0.2794 0.9906)
			(stroke
				(width 0.1)
				(type default)
			)
			(layer "B.Fab")
		)
		(fp_line
			(start -0.2794 -0.1016)
			(end 0.2794 -0.1016)
			(stroke
				(width 0.1)
				(type default)
			)
			(layer "B.Fab")
		)
		(fp_line
			(start 0.2794 0.9906)
			(end -0.2794 0.9906)
			(stroke
				(width 0.1)
				(type default)
			)
			(layer "B.Fab")
		)
		(fp_line
			(start -0.2794 0.9906)
			(end -0.2794 -0.1016)
			(stroke
				(width 0.1)
				(type default)
			)
			(layer "B.Fab")
		)
		(pad "1" smd rect
			(at 0 0 270)
			(size 0.508 0.508)
			(layers "B.Cu" "B.Mask" "B.Paste")
			(net "SMB_DDR_GHJ_VPP_SCL_R")
		)
		(pad "2" smd rect
			(at 0 0.889 270)
			(size 0.508 0.508)
			(layers "B.Cu" "B.Mask" "B.Paste")
			(net "SMB_DDR_GHJ_VPP_SCL")
		)
		(zone
			(layer "B.Cu")
			(hatch none 0.5)
			(connect_pads
				(clearance 0)
			)
			(min_thickness 0.25)
			(keepout
				(tracks allowed)
				(vias not_allowed)
				(pads allowed)
				(copperpour not_allowed)
				(footprints allowed)
			)
			(placement
				(enabled no)
				(sheetname "")
			)
			(fill
				(thermal_gap 0.5)
				(thermal_bridge_width 0.5)
				(island_removal_mode 0)
			)
			(polygon
				(pts
					(xy 166.94277 1.955546) (xy 166.94277 2.463546) (xy 167.32377 2.463546) (xy 167.32377 1.955546)
				)
			)
		)
		(zone
			(layer "B.Cu")
			(hatch none 0.5)
			(connect_pads
				(clearance 0)
			)
			(min_thickness 0.25)
			(keepout
				(tracks not_allowed)
				(vias allowed)
				(pads allowed)
				(copperpour not_allowed)
				(footprints allowed)
			)
			(placement
				(enabled no)
				(sheetname "")
			)
			(fill
				(thermal_gap 0.5)
				(thermal_bridge_width 0.5)
				(island_removal_mode 0)
			)
			(polygon
				(pts
					(xy 167.32377 1.955546) (xy 167.32377 2.463546) (xy 166.94277 2.463546) (xy 166.94277 1.955546)
				)
			)
		)
	)
	(footprint ""
		(layer "B.Cu")
		(at 499.995698 -55.370222)
		(property "Reference" "C30W5"
			(at 0 0 0)
			(layer "B.SilkS")
			(hide yes)
			(effects
				(font
					(size 1.27 1.27)
				)
				(justify mirror)
			)
		)
		(property "Value" "*"
			(at 0.0762 -6.2357 0)
			(unlocked yes)
			(layer "B.Fab")
			(hide yes)
			(effects
				(font
					(size 1.27 1.016)
					(thickness 0.1524)
				)
				(justify mirror)
			)
		)
		(property "Device Type" "SC22U16V5MX-4-GP_SMD-BCG5-SC22A"
			(at 0.0762 -8.2677 0)
			(unlocked yes)
			(layer "B.Fab")
			(hide yes)
			(effects
				(font
					(size 1.27 1.016)
					(thickness 0.1524)
				)
				(justify mirror)
			)
		)
		(duplicate_pad_numbers_are_jumpers no)
		(fp_line
			(start -0.635 0)
			(end 0.635 0)
			(stroke
				(width 0.508)
				(type default)
			)
			(layer "B.SilkS")
		)
		(fp_rect
			(start 0.9652 1.778)
			(end -0.9652 -1.778)
			(stroke
				(width 0)
				(type default)
			)
			(fill no)
			(layer "B.CrtYd")
		)
		(fp_poly
			(pts
				(xy 0.9652 -1.778) (xy -0.9652 -1.778) (xy -0.9652 1.778) (xy 0.9652 1.778)
			)
			(stroke
				(width 0)
				(type default)
			)
			(fill no)
			(layer "B.Fab")
		)
		(pad "1" smd rect
			(at 0 -0.9652 180)
			(size 1.397 1.143)
			(layers "B.Cu" "B.Mask" "B.Paste")
			(net "P5V_STBY_USBC")
		)
		(pad "2" smd rect
			(at 0 0.9652 180)
			(size 1.397 1.143)
			(layers "B.Cu" "B.Mask" "B.Paste")
			(net "GND")
		)
	)
	(footprint ""
		(layer "B.Cu")
		(at 44.97578 -30.7975)
		(property "Reference" ""
			(at 0 0 0)
			(layer "B.SilkS")
			(hide yes)
			(effects
				(font
					(size 1.27 1.27)
				)
				(justify mirror)
			)
		)
		(property "Value" ""
			(at 0 0 0)
			(layer "B.Fab")
			(effects
				(font
					(size 1.27 1.27)
				)
				(justify mirror)
			)
		)
		(duplicate_pad_numbers_are_jumpers no)
		(fp_poly
			(pts
				(arc
					(start 2.032 0)
					(mid -2.032 0)
					(end 2.032 0)
				)
			)
			(stroke
				(width 0)
				(type default)
			)
			(fill no)
			(layer "B.CrtYd")
		)
		(pad "1" smd circle
			(at 0 0 180)
			(size 1.016 1.016)
			(layers "B.Cu" "B.Mask" "B.Paste")
			(net "Net_386")
		)
		(zone
			(layer "B.Cu")
			(hatch none 0.5)
			(connect_pads
				(clearance 0)
			)
			(min_thickness 0.25)
			(keepout
				(tracks not_allowed)
				(vias allowed)
				(pads allowed)
				(copperpour not_allowed)
				(footprints allowed)
			)
			(placement
				(enabled no)
				(sheetname "")
			)
			(fill
				(thermal_gap 0.5)
				(thermal_bridge_width 0.5)
				(island_removal_mode 0)
			)
			(polygon
				(pts
					(arc
						(start 46.49978 -30.7975)
						(mid 43.45178 -30.7975)
						(end 46.49978 -30.7975)
					)
				)
			)
		)
	)
	(footprint ""
		(layer "B.Cu")
		(at 488.2515 -43.5864 -90)
		(property "Reference" "C1R20"
			(at 0 0 90)
			(layer "B.SilkS")
			(hide yes)
			(effects
				(font
					(size 1.27 1.27)
				)
				(justify mirror)
			)
		)
		(property "Value" ""
			(at 0 0 90)
			(layer "B.Fab")
			(effects
				(font
					(size 1.27 1.27)
				)
				(justify mirror)
			)
		)
		(duplicate_pad_numbers_are_jumpers no)
		(fp_poly
			(pts
				(xy -0.3048 -0.1016) (xy -0.3048 0.9906) (xy 0.3048 0.9906) (xy 0.3048 -0.1016)
			)
			(stroke
				(width 0)
				(type default)
			)
			(fill no)
			(layer "B.CrtYd")
		)
		(fp_line
			(start -0.3048 0.9906)
			(end -0.3048 -0.1016)
			(stroke
				(width 0.1)
				(type default)
			)
			(layer "B.Fab")
		)
		(fp_line
			(start 0.3048 0.9906)
			(end -0.3048 0.9906)
			(stroke
				(width 0.1)
				(type default)
			)
			(layer "B.Fab")
		)
		(fp_line
			(start -0.3048 -0.1016)
			(end 0.3048 -0.1016)
			(stroke
				(width 0.1)
				(type default)
			)
			(layer "B.Fab")
		)
		(fp_line
			(start 0.3048 -0.1016)
			(end 0.3048 0.9906)
			(stroke
				(width 0.1)
				(type default)
			)
			(layer "B.Fab")
		)
		(pad "1" smd rect
			(at 0 0 90)
			(size 0.508 0.508)
			(layers "B.Cu" "B.Mask" "B.Paste")
			(net "P3V3_STBY")
		)
		(pad "2" smd rect
			(at 0 0.889 90)
			(size 0.508 0.508)
			(layers "B.Cu" "B.Mask" "B.Paste")
			(net "GND")
		)
		(zone
			(layer "B.Cu")
			(hatch none 0.5)
			(connect_pads
				(clearance 0)
			)
			(min_thickness 0.25)
			(keepout
				(tracks not_allowed)
				(vias allowed)
				(pads allowed)
				(copperpour not_allowed)
				(footprints allowed)
			)
			(placement
				(enabled no)
				(sheetname "")
			)
			(fill
				(thermal_gap 0.5)
				(thermal_bridge_width 0.5)
				(island_removal_mode 0)
			)
			(polygon
				(pts
					(xy 487.6165 -43.3324) (xy 487.6165 -43.8404) (xy 487.9975 -43.8404) (xy 487.9975 -43.3324)
				)
			)
		)
		(zone
			(layer "B.Cu")
			(hatch none 0.5)
			(connect_pads
				(clearance 0)
			)
			(min_thickness 0.25)
			(keepout
				(tracks allowed)
				(vias not_allowed)
				(pads allowed)
				(copperpour not_allowed)
				(footprints allowed)
			)
			(placement
				(enabled no)
				(sheetname "")
			)
			(fill
				(thermal_gap 0.5)
				(thermal_bridge_width 0.5)
				(island_removal_mode 0)
			)
			(polygon
				(pts
					(xy 487.9975 -43.3324) (xy 487.9975 -43.8404) (xy 487.6165 -43.8404) (xy 487.6165 -43.3324)
				)
			)
		)
	)
	(footprint ""
		(layer "B.Cu")
		(at 2.19456 -143.256 90)
		(property "Reference" "C1A11"
			(at 0 0 90)
			(layer "B.SilkS")
			(hide yes)
			(effects
				(font
					(size 1.27 1.27)
				)
				(justify mirror)
			)
		)
		(property "Value" "*"
			(at -1.1811 -2.8194 90)
			(unlocked yes)
			(layer "B.Fab")
			(hide yes)
			(effects
				(font
					(size 1.27 1.016)
					(thickness 0.1524)
				)
				(justify mirror)
			)
		)
		(property "Device Type" "SC1U10V2KX-4-GP_SMD-BCG6-SC1U1A"
			(at -1.1811 -4.3434 90)
			(unlocked yes)
			(layer "B.Fab")
			(hide yes)
			(effects
				(font
					(size 1.27 1.016)
					(thickness 0.1524)
				)
				(justify mirror)
			)
		)
		(duplicate_pad_numbers_are_jumpers no)
		(fp_rect
			(start 0.4318 0.9525)
			(end -0.4318 -0.9525)
			(stroke
				(width 0)
				(type default)
			)
			(fill no)
			(layer "B.CrtYd")
		)
		(fp_rect
			(start 0.4318 0.9525)
			(end -0.4318 -0.9525)
			(stroke
				(width 0)
				(type default)
			)
			(fill no)
			(layer "B.Fab")
		)
		(pad "1" smd custom
			(at 0 -0.4445 270)
			(size 0.1524 0.1524)
			(layers "B.Cu" "B.Mask" "B.Paste")
			(net "P5V_STBY")
			(options
				(clearance outline)
				(anchor circle)
			)
			(primitives
				(gr_poly
					(pts
						(arc
							(start 0.3048 0.2032)
							(mid 0.275042 0.275042)
							(end 0.2032 0.3048)
						)
						(arc
							(start -0.2032 0.3048)
							(mid -0.275042 0.275042)
							(end -0.3048 0.2032)
						)
						(arc
							(start -0.3048 -0.2032)
							(mid -0.275042 -0.275042)
							(end -0.2032 -0.3048)
						)
						(arc
							(start 0.2032 -0.3048)
							(mid 0.275042 -0.275042)
							(end 0.3048 -0.2032)
						)
					)
					(width 0)
					(fill yes)
				)
			)
		)
		(pad "2" smd custom
			(at 0 0.4445 270)
			(size 0.1524 0.1524)
			(layers "B.Cu" "B.Mask" "B.Paste")
			(net "GND")
			(options
				(clearance outline)
				(anchor circle)
			)
			(primitives
				(gr_poly
					(pts
						(arc
							(start 0.3048 0.2032)
							(mid 0.275042 0.275042)
							(end 0.2032 0.3048)
						)
						(arc
							(start -0.2032 0.3048)
							(mid -0.275042 0.275042)
							(end -0.3048 0.2032)
						)
						(arc
							(start -0.3048 -0.2032)
							(mid -0.275042 -0.275042)
							(end -0.2032 -0.3048)
						)
						(arc
							(start 0.2032 -0.3048)
							(mid 0.275042 -0.275042)
							(end 0.3048 -0.2032)
						)
					)
					(width 0)
					(fill yes)
				)
			)
		)
	)
	(footprint ""
		(layer "B.Cu")
		(at 269.559532 -145.0086 90)
		(property "Reference" "C5L8"
			(at -1.848866 0.752348 90)
			(unlocked yes)
			(layer "B.SilkS")
			(effects
				(font
					(size 1.27 0.9652)
					(thickness 0.1524)
				)
				(justify mirror)
			)
		)
		(property "Value" ""
			(at 0 0 90)
			(layer "B.Fab")
			(effects
				(font
					(size 1.27 1.27)
				)
				(justify mirror)
			)
		)
		(duplicate_pad_numbers_are_jumpers no)
		(fp_rect
			(start 0.500126 1.598422)
			(end -0.500126 -0.201422)
			(stroke
				(width 0)
				(type default)
			)
			(fill no)
			(layer "B.CrtYd")
		)
		(fp_line
			(start 0.500126 -0.201422)
			(end -0.500126 -0.201422)
			(stroke
				(width 0.1)
				(type default)
			)
			(layer "B.Fab")
		)
		(fp_line
			(start -0.500126 -0.201422)
			(end -0.500126 1.598422)
			(stroke
				(width 0.1)
				(type default)
			)
			(layer "B.Fab")
		)
		(fp_line
			(start 0.500126 1.598422)
			(end 0.500126 -0.201422)
			(stroke
				(width 0.1)
				(type default)
			)
			(layer "B.Fab")
		)
		(fp_line
			(start -0.500126 1.598422)
			(end 0.500126 1.598422)
			(stroke
				(width 0.1)
				(type default)
			)
			(layer "B.Fab")
		)
		(pad "1" smd rect
			(at 0 0)
			(size 0.889 0.9906)
			(layers "B.Cu" "B.Mask" "B.Paste")
			(net "PVDDQ_DEF")
		)
		(pad "2" smd rect
			(at 0 1.397)
			(size 0.889 0.9906)
			(layers "B.Cu" "B.Mask" "B.Paste")
			(net "GND")
		)
		(zone
			(layer "B.Cu")
			(hatch none 0.5)
			(connect_pads
				(clearance 0)
			)
			(min_thickness 0.25)
			(keepout
				(tracks allowed)
				(vias not_allowed)
				(pads allowed)
				(copperpour not_allowed)
				(footprints allowed)
			)
			(placement
				(enabled no)
				(sheetname "")
			)
			(fill
				(thermal_gap 0.5)
				(thermal_bridge_width 0.5)
				(island_removal_mode 0)
			)
			(polygon
				(pts
					(xy 270.512032 -145.5039) (xy 270.004032 -145.5039) (xy 270.004032 -144.5133) (xy 270.512032 -144.5133)
				)
			)
		)
		(zone
			(layer "B.Cu")
			(hatch none 0.5)
			(connect_pads
				(clearance 0)
			)
			(min_thickness 0.25)
			(keepout
				(tracks not_allowed)
				(vias allowed)
				(pads allowed)
				(copperpour not_allowed)
				(footprints allowed)
			)
			(placement
				(enabled no)
				(sheetname "")
			)
			(fill
				(thermal_gap 0.5)
				(thermal_bridge_width 0.5)
				(island_removal_mode 0)
			)
			(polygon
				(pts
					(xy 270.512032 -145.5039) (xy 270.004032 -145.5039) (xy 270.004032 -144.5133) (xy 270.512032 -144.5133)
				)
			)
		)
	)
	(footprint ""
		(layer "B.Cu")
		(at 442.262006 -41.648126 180)
		(property "Reference" "R25W14"
			(at 0 0 0)
			(layer "B.SilkS")
			(hide yes)
			(effects
				(font
					(size 1.27 1.27)
				)
				(justify mirror)
			)
		)
		(property "Value" "*"
			(at -0.064008 -4.108196 180)
			(unlocked yes)
			(layer "B.Fab")
			(hide yes)
			(effects
				(font
					(size 1.27 1.016)
					(thickness 0.1524)
				)
				(justify mirror)
			)
		)
		(property "Device Type" "120R2F-GP_RCL_GP-120R2F-GP,64.A"
			(at -0.064008 -5.632196 180)
			(unlocked yes)
			(layer "B.Fab")
			(hide yes)
			(effects
				(font
					(size 1.27 1.016)
					(thickness 0.1524)
				)
				(justify mirror)
			)
		)
		(duplicate_pad_numbers_are_jumpers no)
		(fp_line
			(start 0.508 -0.9398)
			(end 0.508 0.9398)
			(stroke
				(width 0.1524)
				(type default)
			)
			(layer "B.SilkS")
		)
		(fp_line
			(start -0.508 -0.9398)
			(end 0.508 -0.9398)
			(stroke
				(width 0.1524)
				(type default)
			)
			(layer "B.SilkS")
		)
		(fp_rect
			(start 0.508 0.9398)
			(end -0.508 -0.9398)
			(stroke
				(width 0)
				(type default)
			)
			(fill no)
			(layer "B.CrtYd")
		)
		(fp_rect
			(start 0.508 0.9398)
			(end -0.508 -0.9398)
			(stroke
				(width 0)
				(type default)
			)
			(fill no)
			(layer "B.Fab")
		)
		(pad "1" smd custom
			(at 0 -0.4445)
			(size 0.1397 0.1397)
			(layers "B.Cu" "B.Mask" "B.Paste")
			(net "GND")
			(options
				(clearance outline)
				(anchor circle)
			)
			(primitives
				(gr_poly
					(pts
						(arc
							(start -0.1778 0.2794)
							(mid -0.249642 0.249642)
							(end -0.2794 0.1778)
						)
						(arc
							(start -0.2794 -0.1778)
							(mid -0.249642 -0.249642)
							(end -0.1778 -0.2794)
						)
						(arc
							(start 0.1778 -0.2794)
							(mid 0.249642 -0.249642)
							(end 0.2794 -0.1778)
						)
						(arc
							(start 0.2794 0.1778)
							(mid 0.249642 0.249642)
							(end 0.1778 0.2794)
						)
					)
					(width 0)
					(fill yes)
				)
			)
		)
		(pad "2" smd custom
			(at 0 0.4445)
			(size 0.1397 0.1397)
			(layers "B.Cu" "B.Mask" "B.Paste")
			(net "BMC_M_A2")
			(options
				(clearance outline)
				(anchor circle)
			)
			(primitives
				(gr_poly
					(pts
						(arc
							(start -0.1778 0.2794)
							(mid -0.249642 0.249642)
							(end -0.2794 0.1778)
						)
						(arc
							(start -0.2794 -0.1778)
							(mid -0.249642 -0.249642)
							(end -0.1778 -0.2794)
						)
						(arc
							(start 0.1778 -0.2794)
							(mid 0.249642 -0.249642)
							(end 0.2794 -0.1778)
						)
						(arc
							(start 0.2794 0.1778)
							(mid 0.249642 0.249642)
							(end 0.1778 0.2794)
						)
					)
					(width 0)
					(fill yes)
				)
			)
		)
	)
	(footprint ""
		(layer "B.Cu")
		(at 470.027 -54.991 -90)
		(property "Reference" "R1R23"
			(at 0 0 90)
			(layer "B.SilkS")
			(hide yes)
			(effects
				(font
					(size 1.27 1.27)
				)
				(justify mirror)
			)
		)
		(property "Value" ""
			(at 0 0 90)
			(layer "B.Fab")
			(effects
				(font
					(size 1.27 1.27)
				)
				(justify mirror)
			)
		)
		(duplicate_pad_numbers_are_jumpers no)
		(fp_poly
			(pts
				(xy 0.2794 -0.1016) (xy -0.2794 -0.1016) (xy -0.2794 0.9906) (xy 0.2794 0.9906)
			)
			(stroke
				(width 0)
				(type default)
			)
			(fill no)
			(layer "B.CrtYd")
		)
		(fp_line
			(start -0.2794 0.9906)
			(end -0.2794 -0.1016)
			(stroke
				(width 0.1)
				(type default)
			)
			(layer "B.Fab")
		)
		(fp_line
			(start 0.2794 0.9906)
			(end -0.2794 0.9906)
			(stroke
				(width 0.1)
				(type default)
			)
			(layer "B.Fab")
		)
		(fp_line
			(start -0.2794 -0.1016)
			(end 0.2794 -0.1016)
			(stroke
				(width 0.1)
				(type default)
			)
			(layer "B.Fab")
		)
		(fp_line
			(start 0.2794 -0.1016)
			(end 0.2794 0.9906)
			(stroke
				(width 0.1)
				(type default)
			)
			(layer "B.Fab")
		)
		(pad "1" smd rect
			(at 0 0 90)
			(size 0.508 0.508)
			(layers "B.Cu" "B.Mask" "B.Paste")
			(net "P3V3_STBY")
		)
		(pad "2" smd rect
			(at 0 0.889 90)
			(size 0.508 0.508)
			(layers "B.Cu" "B.Mask" "B.Paste")
			(net "SMB_PCH_MEZZ_LOM3_SCL")
		)
		(zone
			(layer "B.Cu")
			(hatch none 0.5)
			(connect_pads
				(clearance 0)
			)
			(min_thickness 0.25)
			(keepout
				(tracks not_allowed)
				(vias allowed)
				(pads allowed)
				(copperpour not_allowed)
				(footprints allowed)
			)
			(placement
				(enabled no)
				(sheetname "")
			)
			(fill
				(thermal_gap 0.5)
				(thermal_bridge_width 0.5)
				(island_removal_mode 0)
			)
			(polygon
				(pts
					(xy 469.392 -54.737) (xy 469.392 -55.245) (xy 469.773 -55.245) (xy 469.773 -54.737)
				)
			)
		)
		(zone
			(layer "B.Cu")
			(hatch none 0.5)
			(connect_pads
				(clearance 0)
			)
			(min_thickness 0.25)
			(keepout
				(tracks allowed)
				(vias not_allowed)
				(pads allowed)
				(copperpour not_allowed)
				(footprints allowed)
			)
			(placement
				(enabled no)
				(sheetname "")
			)
			(fill
				(thermal_gap 0.5)
				(thermal_bridge_width 0.5)
				(island_removal_mode 0)
			)
			(polygon
				(pts
					(xy 469.773 -54.737) (xy 469.773 -55.245) (xy 469.392 -55.245) (xy 469.392 -54.737)
				)
			)
		)
	)
	(footprint ""
		(layer "B.Cu")
		(at 404.5585 -96.393 -90)
		(property "Reference" "R2N14"
			(at 0 0 90)
			(layer "B.SilkS")
			(hide yes)
			(effects
				(font
					(size 1.27 1.27)
				)
				(justify mirror)
			)
		)
		(property "Value" ""
			(at 0 0 90)
			(layer "B.Fab")
			(effects
				(font
					(size 1.27 1.27)
				)
				(justify mirror)
			)
		)
		(duplicate_pad_numbers_are_jumpers no)
		(fp_poly
			(pts
				(xy 0.2794 -0.1016) (xy -0.2794 -0.1016) (xy -0.2794 0.9906) (xy 0.2794 0.9906)
			)
			(stroke
				(width 0)
				(type default)
			)
			(fill no)
			(layer "B.CrtYd")
		)
		(fp_line
			(start -0.2794 0.9906)
			(end -0.2794 -0.1016)
			(stroke
				(width 0.1)
				(type default)
			)
			(layer "B.Fab")
		)
		(fp_line
			(start 0.2794 0.9906)
			(end -0.2794 0.9906)
			(stroke
				(width 0.1)
				(type default)
			)
			(layer "B.Fab")
		)
		(fp_line
			(start -0.2794 -0.1016)
			(end 0.2794 -0.1016)
			(stroke
				(width 0.1)
				(type default)
			)
			(layer "B.Fab")
		)
		(fp_line
			(start 0.2794 -0.1016)
			(end 0.2794 0.9906)
			(stroke
				(width 0.1)
				(type default)
			)
			(layer "B.Fab")
		)
		(pad "1" smd rect
			(at 0 0 90)
			(size 0.508 0.508)
			(layers "B.Cu" "B.Mask" "B.Paste")
			(net "P3V3_STBY")
		)
		(pad "2" smd rect
			(at 0 0.889 90)
			(size 0.508 0.508)
			(layers "B.Cu" "B.Mask" "B.Paste")
			(net "FM_USB_P0_EN_BOOT_BIOS_STRAP_N")
		)
		(zone
			(layer "B.Cu")
			(hatch none 0.5)
			(connect_pads
				(clearance 0)
			)
			(min_thickness 0.25)
			(keepout
				(tracks not_allowed)
				(vias allowed)
				(pads allowed)
				(copperpour not_allowed)
				(footprints allowed)
			)
			(placement
				(enabled no)
				(sheetname "")
			)
			(fill
				(thermal_gap 0.5)
				(thermal_bridge_width 0.5)
				(island_removal_mode 0)
			)
			(polygon
				(pts
					(xy 403.9235 -96.139) (xy 403.9235 -96.647) (xy 404.3045 -96.647) (xy 404.3045 -96.139)
				)
			)
		)
		(zone
			(layer "B.Cu")
			(hatch none 0.5)
			(connect_pads
				(clearance 0)
			)
			(min_thickness 0.25)
			(keepout
				(tracks allowed)
				(vias not_allowed)
				(pads allowed)
				(copperpour not_allowed)
				(footprints allowed)
			)
			(placement
				(enabled no)
				(sheetname "")
			)
			(fill
				(thermal_gap 0.5)
				(thermal_bridge_width 0.5)
				(island_removal_mode 0)
			)
			(polygon
				(pts
					(xy 404.3045 -96.139) (xy 404.3045 -96.647) (xy 403.9235 -96.647) (xy 403.9235 -96.139)
				)
			)
		)
	)
	(footprint ""
		(layer "B.Cu")
		(at 195.1736 -72.1614 90)
		(property "Reference" "CT37"
			(at 0.8382 -0.84963 90)
			(unlocked yes)
			(layer "B.SilkS")
			(effects
				(font
					(size 0.7874 0.5842)
					(thickness 0.1524)
				)
				(justify left mirror)
			)
		)
		(property "Value" ""
			(at 0 0 90)
			(layer "B.Fab")
			(effects
				(font
					(size 1.27 1.27)
				)
				(justify mirror)
			)
		)
		(duplicate_pad_numbers_are_jumpers no)
		(fp_poly
			(pts
				(xy -0.3048 -0.1016) (xy -0.3048 0.9906) (xy 0.3048 0.9906) (xy 0.3048 -0.1016)
			)
			(stroke
				(width 0)
				(type default)
			)
			(fill no)
			(layer "B.CrtYd")
		)
		(fp_line
			(start 0.3048 -0.1016)
			(end 0.3048 0.9906)
			(stroke
				(width 0.1)
				(type default)
			)
			(layer "B.Fab")
		)
		(fp_line
			(start -0.3048 -0.1016)
			(end 0.3048 -0.1016)
			(stroke
				(width 0.1)
				(type default)
			)
			(layer "B.Fab")
		)
		(fp_line
			(start 0.3048 0.9906)
			(end -0.3048 0.9906)
			(stroke
				(width 0.1)
				(type default)
			)
			(layer "B.Fab")
		)
		(fp_line
			(start -0.3048 0.9906)
			(end -0.3048 -0.1016)
			(stroke
				(width 0.1)
				(type default)
			)
			(layer "B.Fab")
		)
		(pad "1" smd rect
			(at 0 0 270)
			(size 0.508 0.508)
			(layers "B.Cu" "B.Mask" "B.Paste")
			(net "A_TSENSE_PVCCIN_CPU0")
		)
		(pad "2" smd rect
			(at 0 0.889 270)
			(size 0.508 0.508)
			(layers "B.Cu" "B.Mask" "B.Paste")
			(net "GND")
		)
		(zone
			(layer "B.Cu")
			(hatch none 0.5)
			(connect_pads
				(clearance 0)
			)
			(min_thickness 0.25)
			(keepout
				(tracks allowed)
				(vias not_allowed)
				(pads allowed)
				(copperpour not_allowed)
				(footprints allowed)
			)
			(placement
				(enabled no)
				(sheetname "")
			)
			(fill
				(thermal_gap 0.5)
				(thermal_bridge_width 0.5)
				(island_removal_mode 0)
			)
			(polygon
				(pts
					(xy 195.4276 -72.4154) (xy 195.4276 -71.9074) (xy 195.8086 -71.9074) (xy 195.8086 -72.4154)
				)
			)
		)
		(zone
			(layer "B.Cu")
			(hatch none 0.5)
			(connect_pads
				(clearance 0)
			)
			(min_thickness 0.25)
			(keepout
				(tracks not_allowed)
				(vias allowed)
				(pads allowed)
				(copperpour not_allowed)
				(footprints allowed)
			)
			(placement
				(enabled no)
				(sheetname "")
			)
			(fill
				(thermal_gap 0.5)
				(thermal_bridge_width 0.5)
				(island_removal_mode 0)
			)
			(polygon
				(pts
					(xy 195.8086 -72.4154) (xy 195.8086 -71.9074) (xy 195.4276 -71.9074) (xy 195.4276 -72.4154)
				)
			)
		)
	)
	(footprint ""
		(layer "B.Cu")
		(at 385.463034 -27.522932 90)
		(property "Reference" "C2T13"
			(at 0 0 90)
			(layer "B.SilkS")
			(hide yes)
			(effects
				(font
					(size 1.27 1.27)
				)
				(justify mirror)
			)
		)
		(property "Value" ""
			(at 0 0 90)
			(layer "B.Fab")
			(effects
				(font
					(size 1.27 1.27)
				)
				(justify mirror)
			)
		)
		(duplicate_pad_numbers_are_jumpers no)
		(fp_poly
			(pts
				(xy -0.3048 -0.1016) (xy -0.3048 0.9906) (xy 0.3048 0.9906) (xy 0.3048 -0.1016)
			)
			(stroke
				(width 0)
				(type default)
			)
			(fill no)
			(layer "B.CrtYd")
		)
		(fp_line
			(start 0.3048 -0.1016)
			(end 0.3048 0.9906)
			(stroke
				(width 0.1)
				(type default)
			)
			(layer "B.Fab")
		)
		(fp_line
			(start -0.3048 -0.1016)
			(end 0.3048 -0.1016)
			(stroke
				(width 0.1)
				(type default)
			)
			(layer "B.Fab")
		)
		(fp_line
			(start 0.3048 0.9906)
			(end -0.3048 0.9906)
			(stroke
				(width 0.1)
				(type default)
			)
			(layer "B.Fab")
		)
		(fp_line
			(start -0.3048 0.9906)
			(end -0.3048 -0.1016)
			(stroke
				(width 0.1)
				(type default)
			)
			(layer "B.Fab")
		)
		(pad "1" smd rect
			(at 0 0 270)
			(size 0.508 0.508)
			(layers "B.Cu" "B.Mask" "B.Paste")
			(net "P3E_PCH_M2_TX_C_DP<2>")
		)
		(pad "2" smd rect
			(at 0 0.889 270)
			(size 0.508 0.508)
			(layers "B.Cu" "B.Mask" "B.Paste")
			(net "P3E_PCH_M2_TX_DP<2>")
		)
		(zone
			(layer "B.Cu")
			(hatch none 0.5)
			(connect_pads
				(clearance 0)
			)
			(min_thickness 0.25)
			(keepout
				(tracks allowed)
				(vias not_allowed)
				(pads allowed)
				(copperpour not_allowed)
				(footprints allowed)
			)
			(placement
				(enabled no)
				(sheetname "")
			)
			(fill
				(thermal_gap 0.5)
				(thermal_bridge_width 0.5)
				(island_removal_mode 0)
			)
			(polygon
				(pts
					(xy 385.717034 -27.776932) (xy 385.717034 -27.268932) (xy 386.098034 -27.268932) (xy 386.098034 -27.776932)
				)
			)
		)
		(zone
			(layer "B.Cu")
			(hatch none 0.5)
			(connect_pads
				(clearance 0)
			)
			(min_thickness 0.25)
			(keepout
				(tracks not_allowed)
				(vias allowed)
				(pads allowed)
				(copperpour not_allowed)
				(footprints allowed)
			)
			(placement
				(enabled no)
				(sheetname "")
			)
			(fill
				(thermal_gap 0.5)
				(thermal_bridge_width 0.5)
				(island_removal_mode 0)
			)
			(polygon
				(pts
					(xy 386.098034 -27.776932) (xy 386.098034 -27.268932) (xy 385.717034 -27.268932) (xy 385.717034 -27.776932)
				)
			)
		)
	)
	(footprint ""
		(layer "B.Cu")
		(at 195.4784 -102.6414 180)
		(property "Reference" "R6N15"
			(at 0 0 0)
			(layer "B.SilkS")
			(hide yes)
			(effects
				(font
					(size 1.27 1.27)
				)
				(justify mirror)
			)
		)
		(property "Value" ""
			(at 0 0 0)
			(layer "B.Fab")
			(effects
				(font
					(size 1.27 1.27)
				)
				(justify mirror)
			)
		)
		(duplicate_pad_numbers_are_jumpers no)
		(fp_poly
			(pts
				(xy 0.2794 -0.1016) (xy -0.2794 -0.1016) (xy -0.2794 0.9906) (xy 0.2794 0.9906)
			)
			(stroke
				(width 0)
				(type default)
			)
			(fill no)
			(layer "B.CrtYd")
		)
		(fp_line
			(start 0.2794 0.9906)
			(end -0.2794 0.9906)
			(stroke
				(width 0.1)
				(type default)
			)
			(layer "B.Fab")
		)
		(fp_line
			(start 0.2794 -0.1016)
			(end 0.2794 0.9906)
			(stroke
				(width 0.1)
				(type default)
			)
			(layer "B.Fab")
		)
		(fp_line
			(start -0.2794 0.9906)
			(end -0.2794 -0.1016)
			(stroke
				(width 0.1)
				(type default)
			)
			(layer "B.Fab")
		)
		(fp_line
			(start -0.2794 -0.1016)
			(end 0.2794 -0.1016)
			(stroke
				(width 0.1)
				(type default)
			)
			(layer "B.Fab")
		)
		(pad "1" smd rect
			(at 0 0)
			(size 0.508 0.508)
			(layers "B.Cu" "B.Mask" "B.Paste")
			(net "GND")
		)
		(pad "2" smd rect
			(at 0 0.889)
			(size 0.508 0.508)
			(layers "B.Cu" "B.Mask" "B.Paste")
			(net "PD_PIROM_CPU0_ADDR2")
		)
		(zone
			(layer "B.Cu")
			(hatch none 0.5)
			(connect_pads
				(clearance 0)
			)
			(min_thickness 0.25)
			(keepout
				(tracks not_allowed)
				(vias allowed)
				(pads allowed)
				(copperpour not_allowed)
				(footprints allowed)
			)
			(placement
				(enabled no)
				(sheetname "")
			)
			(fill
				(thermal_gap 0.5)
				(thermal_bridge_width 0.5)
				(island_removal_mode 0)
			)
			(polygon
				(pts
					(xy 195.2244 -103.2764) (xy 195.7324 -103.2764) (xy 195.7324 -102.8954) (xy 195.2244 -102.8954)
				)
			)
		)
		(zone
			(layer "B.Cu")
			(hatch none 0.5)
			(connect_pads
				(clearance 0)
			)
			(min_thickness 0.25)
			(keepout
				(tracks allowed)
				(vias not_allowed)
				(pads allowed)
				(copperpour not_allowed)
				(footprints allowed)
			)
			(placement
				(enabled no)
				(sheetname "")
			)
			(fill
				(thermal_gap 0.5)
				(thermal_bridge_width 0.5)
				(island_removal_mode 0)
			)
			(polygon
				(pts
					(xy 195.2244 -102.8954) (xy 195.7324 -102.8954) (xy 195.7324 -103.2764) (xy 195.2244 -103.2764)
				)
			)
		)
	)
	(footprint ""
		(layer "B.Cu")
		(at 443.633606 -52.342034)
		(property "Reference" "C2R8"
			(at 0 0 0)
			(layer "B.SilkS")
			(hide yes)
			(effects
				(font
					(size 1.27 1.27)
				)
				(justify mirror)
			)
		)
		(property "Value" ""
			(at 0 0 0)
			(layer "B.Fab")
			(effects
				(font
					(size 1.27 1.27)
				)
				(justify mirror)
			)
		)
		(duplicate_pad_numbers_are_jumpers no)
		(fp_poly
			(pts
				(xy -0.3048 -0.1016) (xy -0.3048 0.9906) (xy 0.3048 0.9906) (xy 0.3048 -0.1016)
			)
			(stroke
				(width 0)
				(type default)
			)
			(fill no)
			(layer "B.CrtYd")
		)
		(fp_line
			(start -0.3048 -0.1016)
			(end 0.3048 -0.1016)
			(stroke
				(width 0.1)
				(type default)
			)
			(layer "B.Fab")
		)
		(fp_line
			(start -0.3048 0.9906)
			(end -0.3048 -0.1016)
			(stroke
				(width 0.1)
				(type default)
			)
			(layer "B.Fab")
		)
		(fp_line
			(start 0.3048 -0.1016)
			(end 0.3048 0.9906)
			(stroke
				(width 0.1)
				(type default)
			)
			(layer "B.Fab")
		)
		(fp_line
			(start 0.3048 0.9906)
			(end -0.3048 0.9906)
			(stroke
				(width 0.1)
				(type default)
			)
			(layer "B.Fab")
		)
		(pad "1" smd rect
			(at 0 0 180)
			(size 0.508 0.508)
			(layers "B.Cu" "B.Mask" "B.Paste")
			(net "P3E_CPU0_PE3_OCP_TXP<6>")
		)
		(pad "2" smd rect
			(at 0 0.889 180)
			(size 0.508 0.508)
			(layers "B.Cu" "B.Mask" "B.Paste")
			(net "P3E_OCP_CPU0_PE3_C_TXP<6>")
		)
		(zone
			(layer "B.Cu")
			(hatch none 0.5)
			(connect_pads
				(clearance 0)
			)
			(min_thickness 0.25)
			(keepout
				(tracks allowed)
				(vias not_allowed)
				(pads allowed)
				(copperpour not_allowed)
				(footprints allowed)
			)
			(placement
				(enabled no)
				(sheetname "")
			)
			(fill
				(thermal_gap 0.5)
				(thermal_bridge_width 0.5)
				(island_removal_mode 0)
			)
			(polygon
				(pts
					(xy 443.887606 -52.088034) (xy 443.379606 -52.088034) (xy 443.379606 -51.707034) (xy 443.887606 -51.707034)
				)
			)
		)
		(zone
			(layer "B.Cu")
			(hatch none 0.5)
			(connect_pads
				(clearance 0)
			)
			(min_thickness 0.25)
			(keepout
				(tracks not_allowed)
				(vias allowed)
				(pads allowed)
				(copperpour not_allowed)
				(footprints allowed)
			)
			(placement
				(enabled no)
				(sheetname "")
			)
			(fill
				(thermal_gap 0.5)
				(thermal_bridge_width 0.5)
				(island_removal_mode 0)
			)
			(polygon
				(pts
					(xy 443.887606 -51.707034) (xy 443.379606 -51.707034) (xy 443.379606 -52.088034) (xy 443.887606 -52.088034)
				)
			)
		)
	)
	(footprint ""
		(layer "B.Cu")
		(at 260.863334 2.123694 -90)
		(property "Reference" "SH5U1"
			(at 0 0 90)
			(layer "B.SilkS")
			(hide yes)
			(effects
				(font
					(size 1.27 1.27)
				)
				(justify mirror)
			)
		)
		(property "Value" ""
			(at 0 0 90)
			(layer "B.Fab")
			(effects
				(font
					(size 1.27 1.27)
				)
				(justify mirror)
			)
		)
		(duplicate_pad_numbers_are_jumpers no)
		(fp_poly
			(pts
				(xy 0.1651 -0.0508) (xy 0.1651 0.5842) (xy -0.1651 0.5842) (xy -0.1651 -0.0508)
			)
			(stroke
				(width 0)
				(type default)
			)
			(fill no)
			(layer "B.CrtYd")
		)
		(fp_line
			(start -0.1651 0.5842)
			(end 0.1651 0.5842)
			(stroke
				(width 0.1)
				(type default)
			)
			(layer "B.Fab")
		)
		(fp_line
			(start 0.1651 0.5842)
			(end 0.1651 -0.0508)
			(stroke
				(width 0.1)
				(type default)
			)
			(layer "B.Fab")
		)
		(fp_line
			(start -0.1651 -0.0508)
			(end -0.1651 0.5842)
			(stroke
				(width 0.1)
				(type default)
			)
			(layer "B.Fab")
		)
		(fp_line
			(start 0.1651 -0.0508)
			(end -0.1651 -0.0508)
			(stroke
				(width 0.1)
				(type default)
			)
			(layer "B.Fab")
		)
		(pad "1" smd custom
			(at 0 0 270)
			(size 0.0762 0.0762)
			(layers "B.Cu" "B.Mask" "B.Paste")
			(net "VR_PVTT_ABC_SNS")
			(options
				(clearance outline)
				(anchor circle)
			)
			(primitives
				(gr_poly
					(pts
						(arc
							(start -0.1524 0.10795)
							(mid -0.098518 0.130268)
							(end -0.0762 0.18415)
						)
						(xy -0.0762 0.22225) (xy 0.0762 0.22225)
						(arc
							(start 0.0762 0.18415)
							(mid 0.098518 0.130268)
							(end 0.1524 0.10795)
						)
						(xy 0.1524 -0.22225) (xy -0.1524 -0.22225)
					)
					(width 0)
					(fill yes)
				)
			)
		)
		(pad "2" smd custom
			(at 0 0.5334 90)
			(size 0.0762 0.0762)
			(layers "B.Cu" "B.Mask" "B.Paste")
			(net "PVTT_ABC")
			(options
				(clearance outline)
				(anchor circle)
			)
			(primitives
				(gr_poly
					(pts
						(arc
							(start -0.1524 0.10795)
							(mid -0.098518 0.130268)
							(end -0.0762 0.18415)
						)
						(xy -0.0762 0.22225) (xy 0.0762 0.22225)
						(arc
							(start 0.0762 0.18415)
							(mid 0.098518 0.130268)
							(end 0.1524 0.10795)
						)
						(xy 0.1524 -0.22225) (xy -0.1524 -0.22225)
					)
					(width 0)
					(fill yes)
				)
			)
		)
	)
	(footprint ""
		(layer "B.Cu")
		(at 371.348 -64.008 -90)
		(property "Reference" "C3P42"
			(at 0 0 90)
			(layer "B.SilkS")
			(hide yes)
			(effects
				(font
					(size 1.27 1.27)
				)
				(justify mirror)
			)
		)
		(property "Value" ""
			(at 0 0 90)
			(layer "B.Fab")
			(effects
				(font
					(size 1.27 1.27)
				)
				(justify mirror)
			)
		)
		(duplicate_pad_numbers_are_jumpers no)
		(fp_poly
			(pts
				(xy -0.3048 -0.1016) (xy -0.3048 0.9906) (xy 0.3048 0.9906) (xy 0.3048 -0.1016)
			)
			(stroke
				(width 0)
				(type default)
			)
			(fill no)
			(layer "B.CrtYd")
		)
		(fp_line
			(start -0.3048 0.9906)
			(end -0.3048 -0.1016)
			(stroke
				(width 0.1)
				(type default)
			)
			(layer "B.Fab")
		)
		(fp_line
			(start 0.3048 0.9906)
			(end -0.3048 0.9906)
			(stroke
				(width 0.1)
				(type default)
			)
			(layer "B.Fab")
		)
		(fp_line
			(start -0.3048 -0.1016)
			(end 0.3048 -0.1016)
			(stroke
				(width 0.1)
				(type default)
			)
			(layer "B.Fab")
		)
		(fp_line
			(start 0.3048 -0.1016)
			(end 0.3048 0.9906)
			(stroke
				(width 0.1)
				(type default)
			)
			(layer "B.Fab")
		)
		(pad "1" smd rect
			(at 0 0 90)
			(size 0.508 0.508)
			(layers "B.Cu" "B.Mask" "B.Paste")
			(net "P3V3_STBY")
		)
		(pad "2" smd rect
			(at 0 0.889 90)
			(size 0.508 0.508)
			(layers "B.Cu" "B.Mask" "B.Paste")
			(net "GND")
		)
		(zone
			(layer "B.Cu")
			(hatch none 0.5)
			(connect_pads
				(clearance 0)
			)
			(min_thickness 0.25)
			(keepout
				(tracks not_allowed)
				(vias allowed)
				(pads allowed)
				(copperpour not_allowed)
				(footprints allowed)
			)
			(placement
				(enabled no)
				(sheetname "")
			)
			(fill
				(thermal_gap 0.5)
				(thermal_bridge_width 0.5)
				(island_removal_mode 0)
			)
			(polygon
				(pts
					(xy 370.713 -63.754) (xy 370.713 -64.262) (xy 371.094 -64.262) (xy 371.094 -63.754)
				)
			)
		)
		(zone
			(layer "B.Cu")
			(hatch none 0.5)
			(connect_pads
				(clearance 0)
			)
			(min_thickness 0.25)
			(keepout
				(tracks allowed)
				(vias not_allowed)
				(pads allowed)
				(copperpour not_allowed)
				(footprints allowed)
			)
			(placement
				(enabled no)
				(sheetname "")
			)
			(fill
				(thermal_gap 0.5)
				(thermal_bridge_width 0.5)
				(island_removal_mode 0)
			)
			(polygon
				(pts
					(xy 371.094 -63.754) (xy 371.094 -64.262) (xy 370.713 -64.262) (xy 370.713 -63.754)
				)
			)
		)
	)
	(footprint ""
		(layer "B.Cu")
		(at 153.543 -8.128 -90)
		(property "Reference" "C7U4"
			(at 0 0 90)
			(layer "B.SilkS")
			(hide yes)
			(effects
				(font
					(size 1.27 1.27)
				)
				(justify mirror)
			)
		)
		(property "Value" ""
			(at 0 0 90)
			(layer "B.Fab")
			(effects
				(font
					(size 1.27 1.27)
				)
				(justify mirror)
			)
		)
		(duplicate_pad_numbers_are_jumpers no)
		(fp_poly
			(pts
				(xy 0.4953 -0.2032) (xy -0.4953 -0.2032) (xy -0.4953 1.6002) (xy 0.4953 1.6002)
			)
			(stroke
				(width 0)
				(type default)
			)
			(fill no)
			(layer "B.CrtYd")
		)
		(fp_line
			(start -0.4953 1.6002)
			(end 0.4953 1.6002)
			(stroke
				(width 0.1)
				(type default)
			)
			(layer "B.Fab")
		)
		(fp_line
			(start 0.4953 1.6002)
			(end 0.4953 -0.2032)
			(stroke
				(width 0.1)
				(type default)
			)
			(layer "B.Fab")
		)
		(fp_line
			(start -0.4953 -0.2032)
			(end -0.4953 1.6002)
			(stroke
				(width 0.1)
				(type default)
			)
			(layer "B.Fab")
		)
		(fp_line
			(start 0.4953 -0.2032)
			(end -0.4953 -0.2032)
			(stroke
				(width 0.1)
				(type default)
			)
			(layer "B.Fab")
		)
		(pad "1" smd rect
			(at 0 0 90)
			(size 0.762 0.889)
			(layers "B.Cu" "B.Mask" "B.Paste")
			(net "PVPP_GHJ")
		)
		(pad "2" smd rect
			(at 0 1.397 90)
			(size 0.762 0.889)
			(layers "B.Cu" "B.Mask" "B.Paste")
			(net "GND")
		)
		(zone
			(layer "B.Cu")
			(hatch none 0.5)
			(connect_pads
				(clearance 0)
			)
			(min_thickness 0.25)
			(keepout
				(tracks not_allowed)
				(vias allowed)
				(pads allowed)
				(copperpour not_allowed)
				(footprints allowed)
			)
			(placement
				(enabled no)
				(sheetname "")
			)
			(fill
				(thermal_gap 0.5)
				(thermal_bridge_width 0.5)
				(island_removal_mode 0)
			)
			(polygon
				(pts
					(xy 153.0985 -7.747) (xy 153.0985 -8.509) (xy 152.5905 -8.509) (xy 152.5905 -7.747)
				)
			)
		)
	)
	(footprint ""
		(layer "B.Cu")
		(at 32.832802 -100.613464 90)
		(property "Reference" "C9N21"
			(at 0 0 90)
			(layer "B.SilkS")
			(hide yes)
			(effects
				(font
					(size 1.27 1.27)
				)
				(justify mirror)
			)
		)
		(property "Value" ""
			(at 0 0 90)
			(layer "B.Fab")
			(effects
				(font
					(size 1.27 1.27)
				)
				(justify mirror)
			)
		)
		(duplicate_pad_numbers_are_jumpers no)
		(fp_poly
			(pts
				(xy 0.7239 -0.2159) (xy -0.7239 -0.2159) (xy -0.7239 1.9939) (xy 0.7239 1.9939)
			)
			(stroke
				(width 0)
				(type default)
			)
			(fill no)
			(layer "B.CrtYd")
		)
		(fp_line
			(start 0.7239 -0.2159)
			(end 0.7239 1.9939)
			(stroke
				(width 0.1)
				(type default)
			)
			(layer "B.Fab")
		)
		(fp_line
			(start -0.7239 -0.2159)
			(end 0.7239 -0.2159)
			(stroke
				(width 0.1)
				(type default)
			)
			(layer "B.Fab")
		)
		(fp_line
			(start 0.7239 1.9939)
			(end -0.7239 1.9939)
			(stroke
				(width 0.1)
				(type default)
			)
			(layer "B.Fab")
		)
		(fp_line
			(start -0.7239 1.9939)
			(end -0.7239 -0.2159)
			(stroke
				(width 0.1)
				(type default)
			)
			(layer "B.Fab")
		)
		(pad "1" smd rect
			(at 0 0 270)
			(size 1.27 1.016)
			(layers "B.Cu" "B.Mask" "B.Paste")
			(net "VR_FET_SW_P12V_STBY_PVCCIN_CPU1")
		)
		(pad "2" smd rect
			(at 0 1.778 270)
			(size 1.27 1.016)
			(layers "B.Cu" "B.Mask" "B.Paste")
			(net "GND")
		)
		(zone
			(layer "B.Cu")
			(hatch none 0.5)
			(connect_pads
				(clearance 0)
			)
			(min_thickness 0.25)
			(keepout
				(tracks not_allowed)
				(vias allowed)
				(pads allowed)
				(copperpour not_allowed)
				(footprints allowed)
			)
			(placement
				(enabled no)
				(sheetname "")
			)
			(fill
				(thermal_gap 0.5)
				(thermal_bridge_width 0.5)
				(island_removal_mode 0)
			)
			(polygon
				(pts
					(xy 33.340802 -101.248464) (xy 33.340802 -99.978464) (xy 34.102802 -99.978464) (xy 34.102802 -101.248464)
				)
			)
		)
	)
	(footprint ""
		(layer "B.Cu")
		(at 375.062242 -41.424352 -90)
		(property "Reference" "R2T17"
			(at 0 0 90)
			(layer "B.SilkS")
			(hide yes)
			(effects
				(font
					(size 1.27 1.27)
				)
				(justify mirror)
			)
		)
		(property "Value" ""
			(at 0 0 90)
			(layer "B.Fab")
			(effects
				(font
					(size 1.27 1.27)
				)
				(justify mirror)
			)
		)
		(duplicate_pad_numbers_are_jumpers no)
		(fp_poly
			(pts
				(xy 0.2794 -0.1016) (xy -0.2794 -0.1016) (xy -0.2794 0.9906) (xy 0.2794 0.9906)
			)
			(stroke
				(width 0)
				(type default)
			)
			(fill no)
			(layer "B.CrtYd")
		)
		(fp_line
			(start -0.2794 0.9906)
			(end -0.2794 -0.1016)
			(stroke
				(width 0.1)
				(type default)
			)
			(layer "B.Fab")
		)
		(fp_line
			(start 0.2794 0.9906)
			(end -0.2794 0.9906)
			(stroke
				(width 0.1)
				(type default)
			)
			(layer "B.Fab")
		)
		(fp_line
			(start -0.2794 -0.1016)
			(end 0.2794 -0.1016)
			(stroke
				(width 0.1)
				(type default)
			)
			(layer "B.Fab")
		)
		(fp_line
			(start 0.2794 -0.1016)
			(end 0.2794 0.9906)
			(stroke
				(width 0.1)
				(type default)
			)
			(layer "B.Fab")
		)
		(pad "1" smd rect
			(at 0 0 90)
			(size 0.508 0.508)
			(layers "B.Cu" "B.Mask" "B.Paste")
			(net "H_CPU0_ERR0_G_N")
		)
		(pad "2" smd rect
			(at 0 0.889 90)
			(size 0.508 0.508)
			(layers "B.Cu" "B.Mask" "B.Paste")
			(net "H_CPU_ERR0_GTL_R_N")
		)
		(zone
			(layer "B.Cu")
			(hatch none 0.5)
			(connect_pads
				(clearance 0)
			)
			(min_thickness 0.25)
			(keepout
				(tracks not_allowed)
				(vias allowed)
				(pads allowed)
				(copperpour not_allowed)
				(footprints allowed)
			)
			(placement
				(enabled no)
				(sheetname "")
			)
			(fill
				(thermal_gap 0.5)
				(thermal_bridge_width 0.5)
				(island_removal_mode 0)
			)
			(polygon
				(pts
					(xy 374.427242 -41.170352) (xy 374.427242 -41.678352) (xy 374.808242 -41.678352) (xy 374.808242 -41.170352)
				)
			)
		)
		(zone
			(layer "B.Cu")
			(hatch none 0.5)
			(connect_pads
				(clearance 0)
			)
			(min_thickness 0.25)
			(keepout
				(tracks allowed)
				(vias not_allowed)
				(pads allowed)
				(copperpour not_allowed)
				(footprints allowed)
			)
			(placement
				(enabled no)
				(sheetname "")
			)
			(fill
				(thermal_gap 0.5)
				(thermal_bridge_width 0.5)
				(island_removal_mode 0)
			)
			(polygon
				(pts
					(xy 374.808242 -41.170352) (xy 374.808242 -41.678352) (xy 374.427242 -41.678352) (xy 374.427242 -41.170352)
				)
			)
		)
	)
	(footprint ""
		(layer "B.Cu")
		(at 488.191302 -45.584872 -90)
		(property "Reference" "C1R16"
			(at 0 0 90)
			(layer "B.SilkS")
			(hide yes)
			(effects
				(font
					(size 1.27 1.27)
				)
				(justify mirror)
			)
		)
		(property "Value" ""
			(at 0 0 90)
			(layer "B.Fab")
			(effects
				(font
					(size 1.27 1.27)
				)
				(justify mirror)
			)
		)
		(duplicate_pad_numbers_are_jumpers no)
		(fp_poly
			(pts
				(xy 0.4953 -0.2032) (xy -0.4953 -0.2032) (xy -0.4953 1.6002) (xy 0.4953 1.6002)
			)
			(stroke
				(width 0)
				(type default)
			)
			(fill no)
			(layer "B.CrtYd")
		)
		(fp_line
			(start -0.4953 1.6002)
			(end 0.4953 1.6002)
			(stroke
				(width 0.1)
				(type default)
			)
			(layer "B.Fab")
		)
		(fp_line
			(start 0.4953 1.6002)
			(end 0.4953 -0.2032)
			(stroke
				(width 0.1)
				(type default)
			)
			(layer "B.Fab")
		)
		(fp_line
			(start -0.4953 -0.2032)
			(end -0.4953 1.6002)
			(stroke
				(width 0.1)
				(type default)
			)
			(layer "B.Fab")
		)
		(fp_line
			(start 0.4953 -0.2032)
			(end -0.4953 -0.2032)
			(stroke
				(width 0.1)
				(type default)
			)
			(layer "B.Fab")
		)
		(pad "1" smd rect
			(at 0 0 90)
			(size 0.762 0.889)
			(layers "B.Cu" "B.Mask" "B.Paste")
			(net "P0V9_LAN")
		)
		(pad "2" smd rect
			(at 0 1.397 90)
			(size 0.762 0.889)
			(layers "B.Cu" "B.Mask" "B.Paste")
			(net "GND")
		)
		(zone
			(layer "B.Cu")
			(hatch none 0.5)
			(connect_pads
				(clearance 0)
			)
			(min_thickness 0.25)
			(keepout
				(tracks not_allowed)
				(vias allowed)
				(pads allowed)
				(copperpour not_allowed)
				(footprints allowed)
			)
			(placement
				(enabled no)
				(sheetname "")
			)
			(fill
				(thermal_gap 0.5)
				(thermal_bridge_width 0.5)
				(island_removal_mode 0)
			)
			(polygon
				(pts
					(xy 487.746802 -45.203872) (xy 487.746802 -45.965872) (xy 487.238802 -45.965872) (xy 487.238802 -45.203872)
				)
			)
		)
	)
	(footprint ""
		(layer "B.Cu")
		(at 361.444794 -45.607986 -90)
		(property "Reference" "R2T71"
			(at 0 0 90)
			(layer "B.SilkS")
			(hide yes)
			(effects
				(font
					(size 1.27 1.27)
				)
				(justify mirror)
			)
		)
		(property "Value" ""
			(at 0 0 90)
			(layer "B.Fab")
			(effects
				(font
					(size 1.27 1.27)
				)
				(justify mirror)
			)
		)
		(duplicate_pad_numbers_are_jumpers no)
		(fp_poly
			(pts
				(xy 0.2794 -0.1016) (xy -0.2794 -0.1016) (xy -0.2794 0.9906) (xy 0.2794 0.9906)
			)
			(stroke
				(width 0)
				(type default)
			)
			(fill no)
			(layer "B.CrtYd")
		)
		(fp_line
			(start -0.2794 0.9906)
			(end -0.2794 -0.1016)
			(stroke
				(width 0.1)
				(type default)
			)
			(layer "B.Fab")
		)
		(fp_line
			(start 0.2794 0.9906)
			(end -0.2794 0.9906)
			(stroke
				(width 0.1)
				(type default)
			)
			(layer "B.Fab")
		)
		(fp_line
			(start -0.2794 -0.1016)
			(end 0.2794 -0.1016)
			(stroke
				(width 0.1)
				(type default)
			)
			(layer "B.Fab")
		)
		(fp_line
			(start 0.2794 -0.1016)
			(end 0.2794 0.9906)
			(stroke
				(width 0.1)
				(type default)
			)
			(layer "B.Fab")
		)
		(pad "1" smd rect
			(at 0 0 90)
			(size 0.508 0.508)
			(layers "B.Cu" "B.Mask" "B.Paste")
			(net "FM_CPU0_PROCHOT_LVT3_K_N")
		)
		(pad "2" smd rect
			(at 0 0.889 90)
			(size 0.508 0.508)
			(layers "B.Cu" "B.Mask" "B.Paste")
			(net "H_CPU0_PROCHOT_G_PCH_N")
		)
		(zone
			(layer "B.Cu")
			(hatch none 0.5)
			(connect_pads
				(clearance 0)
			)
			(min_thickness 0.25)
			(keepout
				(tracks not_allowed)
				(vias allowed)
				(pads allowed)
				(copperpour not_allowed)
				(footprints allowed)
			)
			(placement
				(enabled no)
				(sheetname "")
			)
			(fill
				(thermal_gap 0.5)
				(thermal_bridge_width 0.5)
				(island_removal_mode 0)
			)
			(polygon
				(pts
					(xy 360.809794 -45.353986) (xy 360.809794 -45.861986) (xy 361.190794 -45.861986) (xy 361.190794 -45.353986)
				)
			)
		)
		(zone
			(layer "B.Cu")
			(hatch none 0.5)
			(connect_pads
				(clearance 0)
			)
			(min_thickness 0.25)
			(keepout
				(tracks allowed)
				(vias not_allowed)
				(pads allowed)
				(copperpour not_allowed)
				(footprints allowed)
			)
			(placement
				(enabled no)
				(sheetname "")
			)
			(fill
				(thermal_gap 0.5)
				(thermal_bridge_width 0.5)
				(island_removal_mode 0)
			)
			(polygon
				(pts
					(xy 361.190794 -45.353986) (xy 361.190794 -45.861986) (xy 360.809794 -45.861986) (xy 360.809794 -45.353986)
				)
			)
		)
	)
	(footprint ""
		(layer "B.Cu")
		(at 352.96729 -77.915516 180)
		(property "Reference" "C3P30"
			(at 0 0 0)
			(layer "B.SilkS")
			(hide yes)
			(effects
				(font
					(size 1.27 1.27)
				)
				(justify mirror)
			)
		)
		(property "Value" ""
			(at 0 0 0)
			(layer "B.Fab")
			(effects
				(font
					(size 1.27 1.27)
				)
				(justify mirror)
			)
		)
		(duplicate_pad_numbers_are_jumpers no)
		(fp_poly
			(pts
				(xy -0.3048 -0.1016) (xy -0.3048 0.9906) (xy 0.3048 0.9906) (xy 0.3048 -0.1016)
			)
			(stroke
				(width 0)
				(type default)
			)
			(fill no)
			(layer "B.CrtYd")
		)
		(fp_line
			(start 0.3048 0.9906)
			(end -0.3048 0.9906)
			(stroke
				(width 0.1)
				(type default)
			)
			(layer "B.Fab")
		)
		(fp_line
			(start 0.3048 -0.1016)
			(end 0.3048 0.9906)
			(stroke
				(width 0.1)
				(type default)
			)
			(layer "B.Fab")
		)
		(fp_line
			(start -0.3048 0.9906)
			(end -0.3048 -0.1016)
			(stroke
				(width 0.1)
				(type default)
			)
			(layer "B.Fab")
		)
		(fp_line
			(start -0.3048 -0.1016)
			(end 0.3048 -0.1016)
			(stroke
				(width 0.1)
				(type default)
			)
			(layer "B.Fab")
		)
		(pad "1" smd rect
			(at 0 0)
			(size 0.508 0.508)
			(layers "B.Cu" "B.Mask" "B.Paste")
			(net "P3E_CPU0_PE1_SS_TXP<5>")
		)
		(pad "2" smd rect
			(at 0 0.889)
			(size 0.508 0.508)
			(layers "B.Cu" "B.Mask" "B.Paste")
			(net "P3E_CPU0_PE1_PCH_TXP<5>")
		)
		(zone
			(layer "B.Cu")
			(hatch none 0.5)
			(connect_pads
				(clearance 0)
			)
			(min_thickness 0.25)
			(keepout
				(tracks not_allowed)
				(vias allowed)
				(pads allowed)
				(copperpour not_allowed)
				(footprints allowed)
			)
			(placement
				(enabled no)
				(sheetname "")
			)
			(fill
				(thermal_gap 0.5)
				(thermal_bridge_width 0.5)
				(island_removal_mode 0)
			)
			(polygon
				(pts
					(xy 352.71329 -78.550516) (xy 353.22129 -78.550516) (xy 353.22129 -78.169516) (xy 352.71329 -78.169516)
				)
			)
		)
		(zone
			(layer "B.Cu")
			(hatch none 0.5)
			(connect_pads
				(clearance 0)
			)
			(min_thickness 0.25)
			(keepout
				(tracks allowed)
				(vias not_allowed)
				(pads allowed)
				(copperpour not_allowed)
				(footprints allowed)
			)
			(placement
				(enabled no)
				(sheetname "")
			)
			(fill
				(thermal_gap 0.5)
				(thermal_bridge_width 0.5)
				(island_removal_mode 0)
			)
			(polygon
				(pts
					(xy 352.71329 -78.169516) (xy 353.22129 -78.169516) (xy 353.22129 -78.550516) (xy 352.71329 -78.550516)
				)
			)
		)
	)
	(footprint ""
		(layer "B.Cu")
		(at 487.7054 -36.3474 90)
		(property "Reference" "R9W34"
			(at 0.8382 -0.67818 90)
			(unlocked yes)
			(layer "B.SilkS")
			(effects
				(font
					(size 0.4064 0.254)
					(thickness 0.1524)
				)
				(justify left mirror)
			)
		)
		(property "Value" ""
			(at 0 0 90)
			(layer "B.Fab")
			(effects
				(font
					(size 1.27 1.27)
				)
				(justify mirror)
			)
		)
		(duplicate_pad_numbers_are_jumpers no)
		(fp_poly
			(pts
				(xy 0.2794 -0.1016) (xy -0.2794 -0.1016) (xy -0.2794 0.9906) (xy 0.2794 0.9906)
			)
			(stroke
				(width 0)
				(type default)
			)
			(fill no)
			(layer "B.CrtYd")
		)
		(fp_line
			(start 0.2794 -0.1016)
			(end 0.2794 0.9906)
			(stroke
				(width 0.1)
				(type default)
			)
			(layer "B.Fab")
		)
		(fp_line
			(start -0.2794 -0.1016)
			(end 0.2794 -0.1016)
			(stroke
				(width 0.1)
				(type default)
			)
			(layer "B.Fab")
		)
		(fp_line
			(start 0.2794 0.9906)
			(end -0.2794 0.9906)
			(stroke
				(width 0.1)
				(type default)
			)
			(layer "B.Fab")
		)
		(fp_line
			(start -0.2794 0.9906)
			(end -0.2794 -0.1016)
			(stroke
				(width 0.1)
				(type default)
			)
			(layer "B.Fab")
		)
		(pad "1" smd rect
			(at 0 0 270)
			(size 0.508 0.508)
			(layers "B.Cu" "B.Mask" "B.Paste")
			(net "P3V3_STBY")
		)
		(pad "2" smd rect
			(at 0 0.889 270)
			(size 0.508 0.508)
			(layers "B.Cu" "B.Mask" "B.Paste")
			(net "UART_BMC_RXD5")
		)
		(zone
			(layer "B.Cu")
			(hatch none 0.5)
			(connect_pads
				(clearance 0)
			)
			(min_thickness 0.25)
			(keepout
				(tracks allowed)
				(vias not_allowed)
				(pads allowed)
				(copperpour not_allowed)
				(footprints allowed)
			)
			(placement
				(enabled no)
				(sheetname "")
			)
			(fill
				(thermal_gap 0.5)
				(thermal_bridge_width 0.5)
				(island_removal_mode 0)
			)
			(polygon
				(pts
					(xy 487.9594 -36.6014) (xy 487.9594 -36.0934) (xy 488.3404 -36.0934) (xy 488.3404 -36.6014)
				)
			)
		)
		(zone
			(layer "B.Cu")
			(hatch none 0.5)
			(connect_pads
				(clearance 0)
			)
			(min_thickness 0.25)
			(keepout
				(tracks not_allowed)
				(vias allowed)
				(pads allowed)
				(copperpour not_allowed)
				(footprints allowed)
			)
			(placement
				(enabled no)
				(sheetname "")
			)
			(fill
				(thermal_gap 0.5)
				(thermal_bridge_width 0.5)
				(island_removal_mode 0)
			)
			(polygon
				(pts
					(xy 488.3404 -36.6014) (xy 488.3404 -36.0934) (xy 487.9594 -36.0934) (xy 487.9594 -36.6014)
				)
			)
		)
	)
	(footprint ""
		(layer "B.Cu")
		(at 355.41966 -135.1915 -90)
		(property "Reference" "R12W6"
			(at 0 0 90)
			(layer "B.SilkS")
			(hide yes)
			(effects
				(font
					(size 1.27 1.27)
				)
				(justify mirror)
			)
		)
		(property "Value" "*"
			(at 0 -8.9535 270)
			(unlocked yes)
			(layer "B.Fab")
			(hide yes)
			(effects
				(font
					(size 1.27 1.016)
					(thickness 0.1524)
				)
				(justify mirror)
			)
		)
		(property "Device Type" "665KR5B-1-GP_SMD-RG3-665KR5B-1A"
			(at 0 -10.6299 270)
			(unlocked yes)
			(layer "B.Fab")
			(hide yes)
			(effects
				(font
					(size 1.27 1.016)
					(thickness 0.1524)
				)
				(justify mirror)
			)
		)
		(duplicate_pad_numbers_are_jumpers no)
		(fp_line
			(start -0.889 1.7018)
			(end -0.889 -0.508)
			(stroke
				(width 0.1524)
				(type default)
			)
			(layer "B.SilkS")
		)
		(fp_line
			(start 0.889 1.7018)
			(end -0.889 1.7018)
			(stroke
				(width 0.1524)
				(type default)
			)
			(layer "B.SilkS")
		)
		(fp_line
			(start 0.889 0.0762)
			(end 0.889 1.7018)
			(stroke
				(width 0.1524)
				(type default)
			)
			(layer "B.SilkS")
		)
		(fp_line
			(start -0.889 -1.7018)
			(end -0.889 -0.381)
			(stroke
				(width 0.1524)
				(type default)
			)
			(layer "B.SilkS")
		)
		(fp_line
			(start -0.889 -1.7018)
			(end 0.889 -1.7018)
			(stroke
				(width 0.1524)
				(type default)
			)
			(layer "B.SilkS")
		)
		(fp_line
			(start 0.889 -1.7018)
			(end 0.889 0.2794)
			(stroke
				(width 0.1524)
				(type default)
			)
			(layer "B.SilkS")
		)
		(fp_poly
			(pts
				(xy -0.9652 -1.778) (xy -0.9652 1.778) (xy 0.9652 1.778) (xy 0.9652 -1.778)
			)
			(stroke
				(width 0)
				(type default)
			)
			(fill no)
			(layer "B.CrtYd")
		)
		(fp_rect
			(start 0.9652 1.778)
			(end -0.9652 -1.778)
			(stroke
				(width 0)
				(type default)
			)
			(fill no)
			(layer "B.Fab")
		)
		(pad "1" smd rect
			(at 0 -0.9652 90)
			(size 1.397 1.143)
			(layers "B.Cu" "B.Mask" "B.Paste")
			(net "P12V_STBY")
		)
		(pad "2" smd rect
			(at 0 0.9652 90)
			(size 1.397 1.143)
			(layers "B.Cu" "B.Mask" "B.Paste")
			(net "VR_PVDDQ_DEF_AIINSEN")
		)
	)
	(footprint ""
		(layer "B.Cu")
		(at 341.1982 -87.4522 90)
		(property "Reference" "R3P11"
			(at 0 0 90)
			(layer "B.SilkS")
			(hide yes)
			(effects
				(font
					(size 1.27 1.27)
				)
				(justify mirror)
			)
		)
		(property "Value" ""
			(at 0 0 90)
			(layer "B.Fab")
			(effects
				(font
					(size 1.27 1.27)
				)
				(justify mirror)
			)
		)
		(duplicate_pad_numbers_are_jumpers no)
		(fp_poly
			(pts
				(xy 0.2794 -0.1016) (xy -0.2794 -0.1016) (xy -0.2794 0.9906) (xy 0.2794 0.9906)
			)
			(stroke
				(width 0)
				(type default)
			)
			(fill no)
			(layer "B.CrtYd")
		)
		(fp_line
			(start 0.2794 -0.1016)
			(end 0.2794 0.9906)
			(stroke
				(width 0.1)
				(type default)
			)
			(layer "B.Fab")
		)
		(fp_line
			(start -0.2794 -0.1016)
			(end 0.2794 -0.1016)
			(stroke
				(width 0.1)
				(type default)
			)
			(layer "B.Fab")
		)
		(fp_line
			(start 0.2794 0.9906)
			(end -0.2794 0.9906)
			(stroke
				(width 0.1)
				(type default)
			)
			(layer "B.Fab")
		)
		(fp_line
			(start -0.2794 0.9906)
			(end -0.2794 -0.1016)
			(stroke
				(width 0.1)
				(type default)
			)
			(layer "B.Fab")
		)
		(pad "1" smd rect
			(at 0 0 270)
			(size 0.508 0.508)
			(layers "B.Cu" "B.Mask" "B.Paste")
			(net "SVID_DIO0_CPU0_R")
		)
		(pad "2" smd rect
			(at 0 0.889 270)
			(size 0.508 0.508)
			(layers "B.Cu" "B.Mask" "B.Paste")
			(net "SVID_VDIO_PVCCIO_CPU0")
		)
		(zone
			(layer "B.Cu")
			(hatch none 0.5)
			(connect_pads
				(clearance 0)
			)
			(min_thickness 0.25)
			(keepout
				(tracks allowed)
				(vias not_allowed)
				(pads allowed)
				(copperpour not_allowed)
				(footprints allowed)
			)
			(placement
				(enabled no)
				(sheetname "")
			)
			(fill
				(thermal_gap 0.5)
				(thermal_bridge_width 0.5)
				(island_removal_mode 0)
			)
			(polygon
				(pts
					(xy 341.4522 -87.7062) (xy 341.4522 -87.1982) (xy 341.8332 -87.1982) (xy 341.8332 -87.7062)
				)
			)
		)
		(zone
			(layer "B.Cu")
			(hatch none 0.5)
			(connect_pads
				(clearance 0)
			)
			(min_thickness 0.25)
			(keepout
				(tracks not_allowed)
				(vias allowed)
				(pads allowed)
				(copperpour not_allowed)
				(footprints allowed)
			)
			(placement
				(enabled no)
				(sheetname "")
			)
			(fill
				(thermal_gap 0.5)
				(thermal_bridge_width 0.5)
				(island_removal_mode 0)
			)
			(polygon
				(pts
					(xy 341.8332 -87.7062) (xy 341.8332 -87.1982) (xy 341.4522 -87.1982) (xy 341.4522 -87.7062)
				)
			)
		)
	)
	(footprint ""
		(layer "B.Cu")
		(at 420.624 -22.352)
		(property "Reference" "C25W75"
			(at 0.8382 -0.67818 0)
			(unlocked yes)
			(layer "B.SilkS")
			(effects
				(font
					(size 0.4064 0.254)
					(thickness 0.1524)
				)
				(justify left mirror)
			)
		)
		(property "Value" ""
			(at 0 0 0)
			(layer "B.Fab")
			(effects
				(font
					(size 1.27 1.27)
				)
				(justify mirror)
			)
		)
		(duplicate_pad_numbers_are_jumpers no)
		(fp_poly
			(pts
				(xy -0.3048 -0.1016) (xy -0.3048 0.9906) (xy 0.3048 0.9906) (xy 0.3048 -0.1016)
			)
			(stroke
				(width 0)
				(type default)
			)
			(fill no)
			(layer "B.CrtYd")
		)
		(fp_line
			(start -0.3048 -0.1016)
			(end 0.3048 -0.1016)
			(stroke
				(width 0.1)
				(type default)
			)
			(layer "B.Fab")
		)
		(fp_line
			(start -0.3048 0.9906)
			(end -0.3048 -0.1016)
			(stroke
				(width 0.1)
				(type default)
			)
			(layer "B.Fab")
		)
		(fp_line
			(start 0.3048 -0.1016)
			(end 0.3048 0.9906)
			(stroke
				(width 0.1)
				(type default)
			)
			(layer "B.Fab")
		)
		(fp_line
			(start 0.3048 0.9906)
			(end -0.3048 0.9906)
			(stroke
				(width 0.1)
				(type default)
			)
			(layer "B.Fab")
		)
		(pad "1" smd rect
			(at 0 0 180)
			(size 0.508 0.508)
			(layers "B.Cu" "B.Mask" "B.Paste")
			(net "V_IO_B_J")
		)
		(pad "2" smd rect
			(at 0 0.889 180)
			(size 0.508 0.508)
			(layers "B.Cu" "B.Mask" "B.Paste")
			(net "GND")
		)
		(zone
			(layer "B.Cu")
			(hatch none 0.5)
			(connect_pads
				(clearance 0)
			)
			(min_thickness 0.25)
			(keepout
				(tracks allowed)
				(vias not_allowed)
				(pads allowed)
				(copperpour not_allowed)
				(footprints allowed)
			)
			(placement
				(enabled no)
				(sheetname "")
			)
			(fill
				(thermal_gap 0.5)
				(thermal_bridge_width 0.5)
				(island_removal_mode 0)
			)
			(polygon
				(pts
					(xy 420.878 -22.098) (xy 420.37 -22.098) (xy 420.37 -21.717) (xy 420.878 -21.717)
				)
			)
		)
		(zone
			(layer "B.Cu")
			(hatch none 0.5)
			(connect_pads
				(clearance 0)
			)
			(min_thickness 0.25)
			(keepout
				(tracks not_allowed)
				(vias allowed)
				(pads allowed)
				(copperpour not_allowed)
				(footprints allowed)
			)
			(placement
				(enabled no)
				(sheetname "")
			)
			(fill
				(thermal_gap 0.5)
				(thermal_bridge_width 0.5)
				(island_removal_mode 0)
			)
			(polygon
				(pts
					(xy 420.878 -21.717) (xy 420.37 -21.717) (xy 420.37 -22.098) (xy 420.878 -22.098)
				)
			)
		)
	)
	(footprint ""
		(layer "B.Cu")
		(at 13.923264 2.985516 90)
		(property "Reference" "R9U7"
			(at 0 0 90)
			(layer "B.SilkS")
			(hide yes)
			(effects
				(font
					(size 1.27 1.27)
				)
				(justify mirror)
			)
		)
		(property "Value" ""
			(at 0 0 90)
			(layer "B.Fab")
			(effects
				(font
					(size 1.27 1.27)
				)
				(justify mirror)
			)
		)
		(duplicate_pad_numbers_are_jumpers no)
		(fp_poly
			(pts
				(xy 0.2794 -0.1016) (xy -0.2794 -0.1016) (xy -0.2794 0.9906) (xy 0.2794 0.9906)
			)
			(stroke
				(width 0)
				(type default)
			)
			(fill no)
			(layer "B.CrtYd")
		)
		(fp_line
			(start 0.2794 -0.1016)
			(end 0.2794 0.9906)
			(stroke
				(width 0.1)
				(type default)
			)
			(layer "B.Fab")
		)
		(fp_line
			(start -0.2794 -0.1016)
			(end 0.2794 -0.1016)
			(stroke
				(width 0.1)
				(type default)
			)
			(layer "B.Fab")
		)
		(fp_line
			(start 0.2794 0.9906)
			(end -0.2794 0.9906)
			(stroke
				(width 0.1)
				(type default)
			)
			(layer "B.Fab")
		)
		(fp_line
			(start -0.2794 0.9906)
			(end -0.2794 -0.1016)
			(stroke
				(width 0.1)
				(type default)
			)
			(layer "B.Fab")
		)
		(pad "1" smd rect
			(at 0 0 270)
			(size 0.508 0.508)
			(layers "B.Cu" "B.Mask" "B.Paste")
			(net "FM_PVDDQ_GHJ_EN")
		)
		(pad "2" smd rect
			(at 0 0.889 270)
			(size 0.508 0.508)
			(layers "B.Cu" "B.Mask" "B.Paste")
			(net "VR_PVDDQ_GHJ_VREN")
		)
		(zone
			(layer "B.Cu")
			(hatch none 0.5)
			(connect_pads
				(clearance 0)
			)
			(min_thickness 0.25)
			(keepout
				(tracks allowed)
				(vias not_allowed)
				(pads allowed)
				(copperpour not_allowed)
				(footprints allowed)
			)
			(placement
				(enabled no)
				(sheetname "")
			)
			(fill
				(thermal_gap 0.5)
				(thermal_bridge_width 0.5)
				(island_removal_mode 0)
			)
			(polygon
				(pts
					(xy 14.177264 2.731516) (xy 14.177264 3.239516) (xy 14.558264 3.239516) (xy 14.558264 2.731516)
				)
			)
		)
		(zone
			(layer "B.Cu")
			(hatch none 0.5)
			(connect_pads
				(clearance 0)
			)
			(min_thickness 0.25)
			(keepout
				(tracks not_allowed)
				(vias allowed)
				(pads allowed)
				(copperpour not_allowed)
				(footprints allowed)
			)
			(placement
				(enabled no)
				(sheetname "")
			)
			(fill
				(thermal_gap 0.5)
				(thermal_bridge_width 0.5)
				(island_removal_mode 0)
			)
			(polygon
				(pts
					(xy 14.558264 2.731516) (xy 14.558264 3.239516) (xy 14.177264 3.239516) (xy 14.177264 2.731516)
				)
			)
		)
	)
	(footprint ""
		(layer "B.Cu")
		(at 418.465 -4.191 90)
		(property "Reference" "CR7E1"
			(at 0 0 90)
			(layer "B.SilkS")
			(hide yes)
			(effects
				(font
					(size 1.27 1.27)
				)
				(justify mirror)
			)
		)
		(property "Value" ""
			(at 0 0 90)
			(layer "B.Fab")
			(effects
				(font
					(size 1.27 1.27)
				)
				(justify mirror)
			)
		)
		(duplicate_pad_numbers_are_jumpers no)
		(fp_line
			(start 1.335278 -0.291846)
			(end 1.335278 0.831596)
			(stroke
				(width 0.1524)
				(type default)
			)
			(layer "B.SilkS")
		)
		(fp_line
			(start 1.335278 0.831596)
			(end 0.854456 1.664462)
			(stroke
				(width 0.1524)
				(type default)
			)
			(layer "B.SilkS")
		)
		(fp_line
			(start 0.854456 0.831596)
			(end 1.8161 0.831596)
			(stroke
				(width 0.1524)
				(type default)
			)
			(layer "B.SilkS")
		)
		(fp_line
			(start 1.8161 1.664462)
			(end 1.335278 0.831596)
			(stroke
				(width 0.1524)
				(type default)
			)
			(layer "B.SilkS")
		)
		(fp_line
			(start 1.335278 1.664462)
			(end 1.8161 1.664462)
			(stroke
				(width 0.1524)
				(type default)
			)
			(layer "B.SilkS")
		)
		(fp_line
			(start 0.854456 1.664462)
			(end 1.335278 1.664462)
			(stroke
				(width 0.1524)
				(type default)
			)
			(layer "B.SilkS")
		)
		(fp_line
			(start 1.335278 2.576068)
			(end 1.335278 1.664462)
			(stroke
				(width 0.1524)
				(type default)
			)
			(layer "B.SilkS")
		)
		(fp_poly
			(pts
				(xy 0.67437 0.24384) (xy 0.67437 2.04216) (xy -0.67437 2.04216) (xy -0.67437 0.24384)
			)
			(stroke
				(width 0)
				(type default)
			)
			(fill no)
			(layer "B.CrtYd")
		)
		(fp_line
			(start 0.67437 0.24384)
			(end 0.67437 2.04216)
			(stroke
				(width 0.1)
				(type default)
			)
			(layer "B.Fab")
		)
		(fp_line
			(start -0.67437 0.24384)
			(end 0.67437 0.24384)
			(stroke
				(width 0.1)
				(type default)
			)
			(layer "B.Fab")
		)
		(fp_line
			(start 1.335278 0.831596)
			(end 1.335278 -0.291846)
			(stroke
				(width 0.1)
				(type default)
			)
			(layer "B.Fab")
		)
		(fp_line
			(start 1.335278 0.831596)
			(end 0.854456 1.664462)
			(stroke
				(width 0.1)
				(type default)
			)
			(layer "B.Fab")
		)
		(fp_line
			(start 0.854456 0.831596)
			(end 1.8161 0.831596)
			(stroke
				(width 0.1)
				(type default)
			)
			(layer "B.Fab")
		)
		(fp_line
			(start 1.8161 1.664462)
			(end 1.335278 0.831596)
			(stroke
				(width 0.1)
				(type default)
			)
			(layer "B.Fab")
		)
		(fp_line
			(start 1.335278 1.664462)
			(end 1.335278 2.576068)
			(stroke
				(width 0.1)
				(type default)
			)
			(layer "B.Fab")
		)
		(fp_line
			(start 0.854456 1.664462)
			(end 1.8161 1.664462)
			(stroke
				(width 0.1)
				(type default)
			)
			(layer "B.Fab")
		)
		(fp_line
			(start 0.67437 2.04216)
			(end -0.67437 2.04216)
			(stroke
				(width 0.1)
				(type default)
			)
			(layer "B.Fab")
		)
		(fp_line
			(start -0.67437 2.04216)
			(end -0.67437 0.24384)
			(stroke
				(width 0.1)
				(type default)
			)
			(layer "B.Fab")
		)
		(pad "1" smd rect
			(at 0 0 270)
			(size 0.4064 1.016)
			(layers "B.Cu" "B.Mask" "B.Paste")
			(net "PWRGD_P3V3_STBY")
		)
		(pad "2" smd rect
			(at 0 2.286 270)
			(size 0.4064 1.016)
			(layers "B.Cu" "B.Mask" "B.Paste")
			(net "PWRGD_DSW_PWROK")
		)
	)
	(footprint ""
		(layer "B.Cu")
		(at 373.888 -66.929)
		(property "Reference" "R2R6"
			(at 0 0 0)
			(layer "B.SilkS")
			(hide yes)
			(effects
				(font
					(size 1.27 1.27)
				)
				(justify mirror)
			)
		)
		(property "Value" ""
			(at 0 0 0)
			(layer "B.Fab")
			(effects
				(font
					(size 1.27 1.27)
				)
				(justify mirror)
			)
		)
		(duplicate_pad_numbers_are_jumpers no)
		(fp_poly
			(pts
				(xy 0.2794 -0.1016) (xy -0.2794 -0.1016) (xy -0.2794 0.9906) (xy 0.2794 0.9906)
			)
			(stroke
				(width 0)
				(type default)
			)
			(fill no)
			(layer "B.CrtYd")
		)
		(fp_line
			(start -0.2794 -0.1016)
			(end 0.2794 -0.1016)
			(stroke
				(width 0.1)
				(type default)
			)
			(layer "B.Fab")
		)
		(fp_line
			(start -0.2794 0.9906)
			(end -0.2794 -0.1016)
			(stroke
				(width 0.1)
				(type default)
			)
			(layer "B.Fab")
		)
		(fp_line
			(start 0.2794 -0.1016)
			(end 0.2794 0.9906)
			(stroke
				(width 0.1)
				(type default)
			)
			(layer "B.Fab")
		)
		(fp_line
			(start 0.2794 0.9906)
			(end -0.2794 0.9906)
			(stroke
				(width 0.1)
				(type default)
			)
			(layer "B.Fab")
		)
		(pad "1" smd rect
			(at 0 0 180)
			(size 0.508 0.508)
			(layers "B.Cu" "B.Mask" "B.Paste")
			(net "SGPIO_BMC_DIN_R")
		)
		(pad "2" smd rect
			(at 0 0.889 180)
			(size 0.508 0.508)
			(layers "B.Cu" "B.Mask" "B.Paste")
			(net "SGPIO_BMC_DIN")
		)
		(zone
			(layer "B.Cu")
			(hatch none 0.5)
			(connect_pads
				(clearance 0)
			)
			(min_thickness 0.25)
			(keepout
				(tracks allowed)
				(vias not_allowed)
				(pads allowed)
				(copperpour not_allowed)
				(footprints allowed)
			)
			(placement
				(enabled no)
				(sheetname "")
			)
			(fill
				(thermal_gap 0.5)
				(thermal_bridge_width 0.5)
				(island_removal_mode 0)
			)
			(polygon
				(pts
					(xy 374.142 -66.675) (xy 373.634 -66.675) (xy 373.634 -66.294) (xy 374.142 -66.294)
				)
			)
		)
		(zone
			(layer "B.Cu")
			(hatch none 0.5)
			(connect_pads
				(clearance 0)
			)
			(min_thickness 0.25)
			(keepout
				(tracks not_allowed)
				(vias allowed)
				(pads allowed)
				(copperpour not_allowed)
				(footprints allowed)
			)
			(placement
				(enabled no)
				(sheetname "")
			)
			(fill
				(thermal_gap 0.5)
				(thermal_bridge_width 0.5)
				(island_removal_mode 0)
			)
			(polygon
				(pts
					(xy 374.142 -66.294) (xy 373.634 -66.294) (xy 373.634 -66.675) (xy 374.142 -66.675)
				)
			)
		)
	)
	(footprint ""
		(layer "B.Cu")
		(at 486.3338 -34.9504 90)
		(property "Reference" "R9W35"
			(at 0.8382 -0.67818 90)
			(unlocked yes)
			(layer "B.SilkS")
			(effects
				(font
					(size 0.4064 0.254)
					(thickness 0.1524)
				)
				(justify left mirror)
			)
		)
		(property "Value" ""
			(at 0 0 90)
			(layer "B.Fab")
			(effects
				(font
					(size 1.27 1.27)
				)
				(justify mirror)
			)
		)
		(duplicate_pad_numbers_are_jumpers no)
		(fp_poly
			(pts
				(xy 0.2794 -0.1016) (xy -0.2794 -0.1016) (xy -0.2794 0.9906) (xy 0.2794 0.9906)
			)
			(stroke
				(width 0)
				(type default)
			)
			(fill no)
			(layer "B.CrtYd")
		)
		(fp_line
			(start 0.2794 -0.1016)
			(end 0.2794 0.9906)
			(stroke
				(width 0.1)
				(type default)
			)
			(layer "B.Fab")
		)
		(fp_line
			(start -0.2794 -0.1016)
			(end 0.2794 -0.1016)
			(stroke
				(width 0.1)
				(type default)
			)
			(layer "B.Fab")
		)
		(fp_line
			(start 0.2794 0.9906)
			(end -0.2794 0.9906)
			(stroke
				(width 0.1)
				(type default)
			)
			(layer "B.Fab")
		)
		(fp_line
			(start -0.2794 0.9906)
			(end -0.2794 -0.1016)
			(stroke
				(width 0.1)
				(type default)
			)
			(layer "B.Fab")
		)
		(pad "1" smd rect
			(at 0 0 270)
			(size 0.508 0.508)
			(layers "B.Cu" "B.Mask" "B.Paste")
			(net "P3V3_STBY")
		)
		(pad "2" smd rect
			(at 0 0.889 270)
			(size 0.508 0.508)
			(layers "B.Cu" "B.Mask" "B.Paste")
			(net "SP2_BMC_CM_UART_RX_R")
		)
		(zone
			(layer "B.Cu")
			(hatch none 0.5)
			(connect_pads
				(clearance 0)
			)
			(min_thickness 0.25)
			(keepout
				(tracks allowed)
				(vias not_allowed)
				(pads allowed)
				(copperpour not_allowed)
				(footprints allowed)
			)
			(placement
				(enabled no)
				(sheetname "")
			)
			(fill
				(thermal_gap 0.5)
				(thermal_bridge_width 0.5)
				(island_removal_mode 0)
			)
			(polygon
				(pts
					(xy 486.5878 -35.2044) (xy 486.5878 -34.6964) (xy 486.9688 -34.6964) (xy 486.9688 -35.2044)
				)
			)
		)
		(zone
			(layer "B.Cu")
			(hatch none 0.5)
			(connect_pads
				(clearance 0)
			)
			(min_thickness 0.25)
			(keepout
				(tracks not_allowed)
				(vias allowed)
				(pads allowed)
				(copperpour not_allowed)
				(footprints allowed)
			)
			(placement
				(enabled no)
				(sheetname "")
			)
			(fill
				(thermal_gap 0.5)
				(thermal_bridge_width 0.5)
				(island_removal_mode 0)
			)
			(polygon
				(pts
					(xy 486.9688 -35.2044) (xy 486.9688 -34.6964) (xy 486.5878 -34.6964) (xy 486.5878 -35.2044)
				)
			)
		)
	)
	(footprint ""
		(layer "B.Cu")
		(at 499.521226 -34.715704 -90)
		(property "Reference" "R9F65"
			(at 0 0 90)
			(layer "B.SilkS")
			(hide yes)
			(effects
				(font
					(size 1.27 1.27)
				)
				(justify mirror)
			)
		)
		(property "Value" ""
			(at 0 0 90)
			(layer "B.Fab")
			(effects
				(font
					(size 1.27 1.27)
				)
				(justify mirror)
			)
		)
		(duplicate_pad_numbers_are_jumpers no)
		(fp_poly
			(pts
				(xy 0.2794 -0.1016) (xy -0.2794 -0.1016) (xy -0.2794 0.9906) (xy 0.2794 0.9906)
			)
			(stroke
				(width 0)
				(type default)
			)
			(fill no)
			(layer "B.CrtYd")
		)
		(fp_line
			(start -0.2794 0.9906)
			(end -0.2794 -0.1016)
			(stroke
				(width 0.1)
				(type default)
			)
			(layer "B.Fab")
		)
		(fp_line
			(start 0.2794 0.9906)
			(end -0.2794 0.9906)
			(stroke
				(width 0.1)
				(type default)
			)
			(layer "B.Fab")
		)
		(fp_line
			(start -0.2794 -0.1016)
			(end 0.2794 -0.1016)
			(stroke
				(width 0.1)
				(type default)
			)
			(layer "B.Fab")
		)
		(fp_line
			(start 0.2794 -0.1016)
			(end 0.2794 0.9906)
			(stroke
				(width 0.1)
				(type default)
			)
			(layer "B.Fab")
		)
		(pad "1" smd rect
			(at 0 0 90)
			(size 0.508 0.508)
			(layers "B.Cu" "B.Mask" "B.Paste")
			(net "SP2_BMC_CM_UART_TX_R1")
		)
		(pad "2" smd rect
			(at 0 0.889 90)
			(size 0.508 0.508)
			(layers "B.Cu" "B.Mask" "B.Paste")
			(net "SP2_BMC_CM_UART_TX_R")
		)
		(zone
			(layer "B.Cu")
			(hatch none 0.5)
			(connect_pads
				(clearance 0)
			)
			(min_thickness 0.25)
			(keepout
				(tracks not_allowed)
				(vias allowed)
				(pads allowed)
				(copperpour not_allowed)
				(footprints allowed)
			)
			(placement
				(enabled no)
				(sheetname "")
			)
			(fill
				(thermal_gap 0.5)
				(thermal_bridge_width 0.5)
				(island_removal_mode 0)
			)
			(polygon
				(pts
					(xy 498.886226 -34.461704) (xy 498.886226 -34.969704) (xy 499.267226 -34.969704) (xy 499.267226 -34.461704)
				)
			)
		)
		(zone
			(layer "B.Cu")
			(hatch none 0.5)
			(connect_pads
				(clearance 0)
			)
			(min_thickness 0.25)
			(keepout
				(tracks allowed)
				(vias not_allowed)
				(pads allowed)
				(copperpour not_allowed)
				(footprints allowed)
			)
			(placement
				(enabled no)
				(sheetname "")
			)
			(fill
				(thermal_gap 0.5)
				(thermal_bridge_width 0.5)
				(island_removal_mode 0)
			)
			(polygon
				(pts
					(xy 499.267226 -34.461704) (xy 499.267226 -34.969704) (xy 498.886226 -34.969704) (xy 498.886226 -34.461704)
				)
			)
		)
	)
	(footprint ""
		(layer "B.Cu")
		(at 180.653182 -20.014692 180)
		(property "Reference" "R6T8"
			(at 0 0 0)
			(layer "B.SilkS")
			(hide yes)
			(effects
				(font
					(size 1.27 1.27)
				)
				(justify mirror)
			)
		)
		(property "Value" ""
			(at 0 0 0)
			(layer "B.Fab")
			(effects
				(font
					(size 1.27 1.27)
				)
				(justify mirror)
			)
		)
		(duplicate_pad_numbers_are_jumpers no)
		(fp_rect
			(start -0.2794 -0.1016)
			(end 0.2794 0.9906)
			(stroke
				(width 0)
				(type default)
			)
			(fill no)
			(layer "B.CrtYd")
		)
		(fp_line
			(start 0.2794 0.9906)
			(end -0.2794 0.9906)
			(stroke
				(width 0.1)
				(type default)
			)
			(layer "B.Fab")
		)
		(fp_line
			(start 0.2794 -0.1016)
			(end 0.2794 0.9906)
			(stroke
				(width 0.1)
				(type default)
			)
			(layer "B.Fab")
		)
		(fp_line
			(start -0.2794 0.9906)
			(end -0.2794 -0.1016)
			(stroke
				(width 0.1)
				(type default)
			)
			(layer "B.Fab")
		)
		(fp_line
			(start -0.2794 -0.1016)
			(end 0.2794 -0.1016)
			(stroke
				(width 0.1)
				(type default)
			)
			(layer "B.Fab")
		)
		(pad "1" smd rect
			(at 0 0)
			(size 0.508 0.508)
			(layers "B.Cu" "B.Mask" "B.Paste")
			(net "PVCCIO_CPU0")
		)
		(pad "2" smd rect
			(at 0 0.889)
			(size 0.508 0.508)
			(layers "B.Cu" "B.Mask" "B.Paste")
			(net "XDP_CPU_OBSFN_B0_MBP6_N")
		)
		(zone
			(layer "B.Cu")
			(hatch none 0.5)
			(connect_pads
				(clearance 0)
			)
			(min_thickness 0.25)
			(keepout
				(tracks allowed)
				(vias not_allowed)
				(pads allowed)
				(copperpour not_allowed)
				(footprints allowed)
			)
			(placement
				(enabled no)
				(sheetname "")
			)
			(fill
				(thermal_gap 0.5)
				(thermal_bridge_width 0.5)
				(island_removal_mode 0)
			)
			(polygon
				(pts
					(xy 180.907182 -20.268692) (xy 180.907182 -20.649692) (xy 180.399182 -20.649692) (xy 180.399182 -20.268692)
				)
			)
		)
		(zone
			(layer "B.Cu")
			(hatch none 0.5)
			(connect_pads
				(clearance 0)
			)
			(min_thickness 0.25)
			(keepout
				(tracks not_allowed)
				(vias allowed)
				(pads allowed)
				(copperpour not_allowed)
				(footprints allowed)
			)
			(placement
				(enabled no)
				(sheetname "")
			)
			(fill
				(thermal_gap 0.5)
				(thermal_bridge_width 0.5)
				(island_removal_mode 0)
			)
			(polygon
				(pts
					(xy 180.907182 -20.268692) (xy 180.907182 -20.649692) (xy 180.399182 -20.649692) (xy 180.399182 -20.268692)
				)
			)
		)
	)
	(footprint ""
		(layer "B.Cu")
		(at 340.3092 -87.1982 180)
		(property "Reference" "R3P13"
			(at 0 0 0)
			(layer "B.SilkS")
			(hide yes)
			(effects
				(font
					(size 1.27 1.27)
				)
				(justify mirror)
			)
		)
		(property "Value" ""
			(at 0 0 0)
			(layer "B.Fab")
			(effects
				(font
					(size 1.27 1.27)
				)
				(justify mirror)
			)
		)
		(duplicate_pad_numbers_are_jumpers no)
		(fp_poly
			(pts
				(xy 0.2794 -0.1016) (xy -0.2794 -0.1016) (xy -0.2794 0.9906) (xy 0.2794 0.9906)
			)
			(stroke
				(width 0)
				(type default)
			)
			(fill no)
			(layer "B.CrtYd")
		)
		(fp_line
			(start 0.2794 0.9906)
			(end -0.2794 0.9906)
			(stroke
				(width 0.1)
				(type default)
			)
			(layer "B.Fab")
		)
		(fp_line
			(start 0.2794 -0.1016)
			(end 0.2794 0.9906)
			(stroke
				(width 0.1)
				(type default)
			)
			(layer "B.Fab")
		)
		(fp_line
			(start -0.2794 0.9906)
			(end -0.2794 -0.1016)
			(stroke
				(width 0.1)
				(type default)
			)
			(layer "B.Fab")
		)
		(fp_line
			(start -0.2794 -0.1016)
			(end 0.2794 -0.1016)
			(stroke
				(width 0.1)
				(type default)
			)
			(layer "B.Fab")
		)
		(pad "1" smd rect
			(at 0 0)
			(size 0.508 0.508)
			(layers "B.Cu" "B.Mask" "B.Paste")
			(net "PVCCIO_CPU0")
		)
		(pad "2" smd rect
			(at 0 0.889)
			(size 0.508 0.508)
			(layers "B.Cu" "B.Mask" "B.Paste")
			(net "SVID_DIO0_CPU0_R")
		)
		(zone
			(layer "B.Cu")
			(hatch none 0.5)
			(connect_pads
				(clearance 0)
			)
			(min_thickness 0.25)
			(keepout
				(tracks not_allowed)
				(vias allowed)
				(pads allowed)
				(copperpour not_allowed)
				(footprints allowed)
			)
			(placement
				(enabled no)
				(sheetname "")
			)
			(fill
				(thermal_gap 0.5)
				(thermal_bridge_width 0.5)
				(island_removal_mode 0)
			)
			(polygon
				(pts
					(xy 340.0552 -87.8332) (xy 340.5632 -87.8332) (xy 340.5632 -87.4522) (xy 340.0552 -87.4522)
				)
			)
		)
		(zone
			(layer "B.Cu")
			(hatch none 0.5)
			(connect_pads
				(clearance 0)
			)
			(min_thickness 0.25)
			(keepout
				(tracks allowed)
				(vias not_allowed)
				(pads allowed)
				(copperpour not_allowed)
				(footprints allowed)
			)
			(placement
				(enabled no)
				(sheetname "")
			)
			(fill
				(thermal_gap 0.5)
				(thermal_bridge_width 0.5)
				(island_removal_mode 0)
			)
			(polygon
				(pts
					(xy 340.0552 -87.4522) (xy 340.5632 -87.4522) (xy 340.5632 -87.8332) (xy 340.0552 -87.8332)
				)
			)
		)
	)
	(footprint ""
		(layer "B.Cu")
		(at 23.876 -77.089 180)
		(property "Reference" "R9P21"
			(at 0 0 0)
			(layer "B.SilkS")
			(hide yes)
			(effects
				(font
					(size 1.27 1.27)
				)
				(justify mirror)
			)
		)
		(property "Value" ""
			(at 0 0 0)
			(layer "B.Fab")
			(effects
				(font
					(size 1.27 1.27)
				)
				(justify mirror)
			)
		)
		(duplicate_pad_numbers_are_jumpers no)
		(fp_poly
			(pts
				(xy 0.2794 -0.1016) (xy -0.2794 -0.1016) (xy -0.2794 0.9906) (xy 0.2794 0.9906)
			)
			(stroke
				(width 0)
				(type default)
			)
			(fill no)
			(layer "B.CrtYd")
		)
		(fp_line
			(start 0.2794 0.9906)
			(end -0.2794 0.9906)
			(stroke
				(width 0.1)
				(type default)
			)
			(layer "B.Fab")
		)
		(fp_line
			(start 0.2794 -0.1016)
			(end 0.2794 0.9906)
			(stroke
				(width 0.1)
				(type default)
			)
			(layer "B.Fab")
		)
		(fp_line
			(start -0.2794 0.9906)
			(end -0.2794 -0.1016)
			(stroke
				(width 0.1)
				(type default)
			)
			(layer "B.Fab")
		)
		(fp_line
			(start -0.2794 -0.1016)
			(end 0.2794 -0.1016)
			(stroke
				(width 0.1)
				(type default)
			)
			(layer "B.Fab")
		)
		(pad "1" smd rect
			(at 0 0)
			(size 0.508 0.508)
			(layers "B.Cu" "B.Mask" "B.Paste")
			(net "A_HSC_TIMER")
		)
		(pad "2" smd rect
			(at 0 0.889)
			(size 0.508 0.508)
			(layers "B.Cu" "B.Mask" "B.Paste")
			(net "A_HSC_TIMER_R")
		)
		(zone
			(layer "B.Cu")
			(hatch none 0.5)
			(connect_pads
				(clearance 0)
			)
			(min_thickness 0.25)
			(keepout
				(tracks not_allowed)
				(vias allowed)
				(pads allowed)
				(copperpour not_allowed)
				(footprints allowed)
			)
			(placement
				(enabled no)
				(sheetname "")
			)
			(fill
				(thermal_gap 0.5)
				(thermal_bridge_width 0.5)
				(island_removal_mode 0)
			)
			(polygon
				(pts
					(xy 23.622 -77.724) (xy 24.13 -77.724) (xy 24.13 -77.343) (xy 23.622 -77.343)
				)
			)
		)
		(zone
			(layer "B.Cu")
			(hatch none 0.5)
			(connect_pads
				(clearance 0)
			)
			(min_thickness 0.25)
			(keepout
				(tracks allowed)
				(vias not_allowed)
				(pads allowed)
				(copperpour not_allowed)
				(footprints allowed)
			)
			(placement
				(enabled no)
				(sheetname "")
			)
			(fill
				(thermal_gap 0.5)
				(thermal_bridge_width 0.5)
				(island_removal_mode 0)
			)
			(polygon
				(pts
					(xy 23.622 -77.343) (xy 24.13 -77.343) (xy 24.13 -77.724) (xy 23.622 -77.724)
				)
			)
		)
	)
	(footprint ""
		(layer "B.Cu")
		(at 102.692454 -77.82814)
		(property "Reference" "C8P16"
			(at 0 0 0)
			(layer "B.SilkS")
			(hide yes)
			(effects
				(font
					(size 1.27 1.27)
				)
				(justify mirror)
			)
		)
		(property "Value" ""
			(at 0 0 0)
			(layer "B.Fab")
			(effects
				(font
					(size 1.27 1.27)
				)
				(justify mirror)
			)
		)
		(duplicate_pad_numbers_are_jumpers no)
		(fp_poly
			(pts
				(xy 0.7239 -0.2159) (xy -0.7239 -0.2159) (xy -0.7239 1.9939) (xy 0.7239 1.9939)
			)
			(stroke
				(width 0)
				(type default)
			)
			(fill no)
			(layer "B.CrtYd")
		)
		(fp_line
			(start -0.7239 -0.2159)
			(end 0.7239 -0.2159)
			(stroke
				(width 0.1)
				(type default)
			)
			(layer "B.Fab")
		)
		(fp_line
			(start -0.7239 1.9939)
			(end -0.7239 -0.2159)
			(stroke
				(width 0.1)
				(type default)
			)
			(layer "B.Fab")
		)
		(fp_line
			(start 0.7239 -0.2159)
			(end 0.7239 1.9939)
			(stroke
				(width 0.1)
				(type default)
			)
			(layer "B.Fab")
		)
		(fp_line
			(start 0.7239 1.9939)
			(end -0.7239 1.9939)
			(stroke
				(width 0.1)
				(type default)
			)
			(layer "B.Fab")
		)
		(pad "1" smd rect
			(at 0 0 180)
			(size 1.27 1.016)
			(layers "B.Cu" "B.Mask" "B.Paste")
			(net "PVCCIN_CPU1")
		)
		(pad "2" smd rect
			(at 0 1.778 180)
			(size 1.27 1.016)
			(layers "B.Cu" "B.Mask" "B.Paste")
			(net "GND")
		)
		(zone
			(layer "B.Cu")
			(hatch none 0.5)
			(connect_pads
				(clearance 0)
			)
			(min_thickness 0.25)
			(keepout
				(tracks not_allowed)
				(vias allowed)
				(pads allowed)
				(copperpour not_allowed)
				(footprints allowed)
			)
			(placement
				(enabled no)
				(sheetname "")
			)
			(fill
				(thermal_gap 0.5)
				(thermal_bridge_width 0.5)
				(island_removal_mode 0)
			)
			(polygon
				(pts
					(xy 103.327454 -77.32014) (xy 102.057454 -77.32014) (xy 102.057454 -76.55814) (xy 103.327454 -76.55814)
				)
			)
		)
	)
	(footprint ""
		(layer "B.Cu")
		(at 447.9036 -18.1102 -90)
		(property "Reference" "R3W9"
			(at 0.8382 -0.67818 270)
			(unlocked yes)
			(layer "B.SilkS")
			(effects
				(font
					(size 0.4064 0.254)
					(thickness 0.1524)
				)
				(justify left mirror)
			)
		)
		(property "Value" ""
			(at 0 0 90)
			(layer "B.Fab")
			(effects
				(font
					(size 1.27 1.27)
				)
				(justify mirror)
			)
		)
		(duplicate_pad_numbers_are_jumpers no)
		(fp_poly
			(pts
				(xy 0.2794 -0.1016) (xy -0.2794 -0.1016) (xy -0.2794 0.9906) (xy 0.2794 0.9906)
			)
			(stroke
				(width 0)
				(type default)
			)
			(fill no)
			(layer "B.CrtYd")
		)
		(fp_line
			(start -0.2794 0.9906)
			(end -0.2794 -0.1016)
			(stroke
				(width 0.1)
				(type default)
			)
			(layer "B.Fab")
		)
		(fp_line
			(start 0.2794 0.9906)
			(end -0.2794 0.9906)
			(stroke
				(width 0.1)
				(type default)
			)
			(layer "B.Fab")
		)
		(fp_line
			(start -0.2794 -0.1016)
			(end 0.2794 -0.1016)
			(stroke
				(width 0.1)
				(type default)
			)
			(layer "B.Fab")
		)
		(fp_line
			(start 0.2794 -0.1016)
			(end 0.2794 0.9906)
			(stroke
				(width 0.1)
				(type default)
			)
			(layer "B.Fab")
		)
		(pad "1" smd rect
			(at 0 0 90)
			(size 0.508 0.508)
			(layers "B.Cu" "B.Mask" "B.Paste")
			(net "VREF_2V2")
		)
		(pad "2" smd rect
			(at 0 0.889 90)
			(size 0.508 0.508)
			(layers "B.Cu" "B.Mask" "B.Paste")
			(net "GND")
		)
		(zone
			(layer "B.Cu")
			(hatch none 0.5)
			(connect_pads
				(clearance 0)
			)
			(min_thickness 0.25)
			(keepout
				(tracks not_allowed)
				(vias allowed)
				(pads allowed)
				(copperpour not_allowed)
				(footprints allowed)
			)
			(placement
				(enabled no)
				(sheetname "")
			)
			(fill
				(thermal_gap 0.5)
				(thermal_bridge_width 0.5)
				(island_removal_mode 0)
			)
			(polygon
				(pts
					(xy 447.2686 -17.8562) (xy 447.2686 -18.3642) (xy 447.6496 -18.3642) (xy 447.6496 -17.8562)
				)
			)
		)
		(zone
			(layer "B.Cu")
			(hatch none 0.5)
			(connect_pads
				(clearance 0)
			)
			(min_thickness 0.25)
			(keepout
				(tracks allowed)
				(vias not_allowed)
				(pads allowed)
				(copperpour not_allowed)
				(footprints allowed)
			)
			(placement
				(enabled no)
				(sheetname "")
			)
			(fill
				(thermal_gap 0.5)
				(thermal_bridge_width 0.5)
				(island_removal_mode 0)
			)
			(polygon
				(pts
					(xy 447.6496 -17.8562) (xy 447.6496 -18.3642) (xy 447.2686 -18.3642) (xy 447.2686 -17.8562)
				)
			)
		)
	)
	(footprint ""
		(layer "B.Cu")
		(at 266.397232 -140.208 90)
		(property "Reference" "C5G73"
			(at -1.14681 0.76708 180)
			(unlocked yes)
			(layer "B.SilkS")
			(effects
				(font
					(size 0.7874 0.5842)
					(thickness 0.1524)
				)
				(justify mirror)
			)
		)
		(property "Value" ""
			(at 0 0 90)
			(layer "B.Fab")
			(effects
				(font
					(size 1.27 1.27)
				)
				(justify mirror)
			)
		)
		(duplicate_pad_numbers_are_jumpers no)
		(fp_rect
			(start -0.4953 -0.2032)
			(end 0.4953 1.6002)
			(stroke
				(width 0)
				(type default)
			)
			(fill no)
			(layer "B.CrtYd")
		)
		(fp_line
			(start 0.4953 -0.2032)
			(end -0.4953 -0.2032)
			(stroke
				(width 0.1)
				(type default)
			)
			(layer "B.Fab")
		)
		(fp_line
			(start -0.4953 -0.2032)
			(end -0.4953 1.6002)
			(stroke
				(width 0.1)
				(type default)
			)
			(layer "B.Fab")
		)
		(fp_line
			(start 0.4953 1.6002)
			(end 0.4953 -0.2032)
			(stroke
				(width 0.1)
				(type default)
			)
			(layer "B.Fab")
		)
		(fp_line
			(start -0.4953 1.6002)
			(end 0.4953 1.6002)
			(stroke
				(width 0.1)
				(type default)
			)
			(layer "B.Fab")
		)
		(pad "1" smd rect
			(at 0 0 270)
			(size 0.762 0.889)
			(layers "B.Cu" "B.Mask" "B.Paste")
			(net "PVDDQ_DEF")
		)
		(pad "2" smd rect
			(at 0 1.397 270)
			(size 0.762 0.889)
			(layers "B.Cu" "B.Mask" "B.Paste")
			(net "GND")
		)
		(zone
			(layer "B.Cu")
			(hatch none 0.5)
			(connect_pads
				(clearance 0)
			)
			(min_thickness 0.25)
			(keepout
				(tracks not_allowed)
				(vias allowed)
				(pads allowed)
				(copperpour not_allowed)
				(footprints allowed)
			)
			(placement
				(enabled no)
				(sheetname "")
			)
			(fill
				(thermal_gap 0.5)
				(thermal_bridge_width 0.5)
				(island_removal_mode 0)
			)
			(polygon
				(pts
					(xy 266.841732 -139.827) (xy 267.349732 -139.827) (xy 267.349732 -140.589) (xy 266.841732 -140.589)
				)
			)
		)
	)
	(footprint ""
		(layer "B.Cu")
		(at 396.018766 -157.117288 -90)
		(property "Reference" "CF24"
			(at 0 0 90)
			(layer "B.SilkS")
			(hide yes)
			(effects
				(font
					(size 1.27 1.27)
				)
				(justify mirror)
			)
		)
		(property "Value" "*"
			(at -1.1811 -2.8194 270)
			(unlocked yes)
			(layer "B.Fab")
			(hide yes)
			(effects
				(font
					(size 1.27 1.016)
					(thickness 0.1524)
				)
				(justify mirror)
			)
		)
		(property "Device Type" "SC22P50V2JN-4GP_SMD-BCG-SC22P5A"
			(at -1.1811 -4.3434 270)
			(unlocked yes)
			(layer "B.Fab")
			(hide yes)
			(effects
				(font
					(size 1.27 1.016)
					(thickness 0.1524)
				)
				(justify mirror)
			)
		)
		(duplicate_pad_numbers_are_jumpers no)
		(fp_rect
			(start 0.4318 0.9525)
			(end -0.4318 -0.9525)
			(stroke
				(width 0)
				(type default)
			)
			(fill no)
			(layer "B.CrtYd")
		)
		(fp_rect
			(start 0.4318 0.9525)
			(end -0.4318 -0.9525)
			(stroke
				(width 0)
				(type default)
			)
			(fill no)
			(layer "B.Fab")
		)
		(pad "1" smd custom
			(at 0 -0.4445 90)
			(size 0.1524 0.1524)
			(layers "B.Cu" "B.Mask" "B.Paste")
			(net "VR_P1V05_PCH_BIREF1")
			(options
				(clearance outline)
				(anchor circle)
			)
			(primitives
				(gr_poly
					(pts
						(arc
							(start 0.3048 0.2032)
							(mid 0.275042 0.275042)
							(end 0.2032 0.3048)
						)
						(arc
							(start -0.2032 0.3048)
							(mid -0.275042 0.275042)
							(end -0.3048 0.2032)
						)
						(arc
							(start -0.3048 -0.2032)
							(mid -0.275042 -0.275042)
							(end -0.2032 -0.3048)
						)
						(arc
							(start 0.2032 -0.3048)
							(mid 0.275042 -0.275042)
							(end 0.3048 -0.2032)
						)
					)
					(width 0)
					(fill yes)
				)
			)
		)
		(pad "2" smd custom
			(at 0 0.4445 90)
			(size 0.1524 0.1524)
			(layers "B.Cu" "B.Mask" "B.Paste")
			(net "ISENSE_P1V05_PCH_STBY_PH1_IMON")
			(options
				(clearance outline)
				(anchor circle)
			)
			(primitives
				(gr_poly
					(pts
						(arc
							(start 0.3048 0.2032)
							(mid 0.275042 0.275042)
							(end 0.2032 0.3048)
						)
						(arc
							(start -0.2032 0.3048)
							(mid -0.275042 0.275042)
							(end -0.3048 0.2032)
						)
						(arc
							(start -0.3048 -0.2032)
							(mid -0.275042 -0.275042)
							(end -0.2032 -0.3048)
						)
						(arc
							(start 0.2032 -0.3048)
							(mid 0.275042 -0.275042)
							(end 0.3048 -0.2032)
						)
					)
					(width 0)
					(fill yes)
				)
			)
		)
	)
	(footprint ""
		(layer "B.Cu")
		(at 379.3998 -154.467306)
		(property "Reference" "C3L8"
			(at 0 0 0)
			(layer "B.SilkS")
			(hide yes)
			(effects
				(font
					(size 1.27 1.27)
				)
				(justify mirror)
			)
		)
		(property "Value" ""
			(at 0 0 0)
			(layer "B.Fab")
			(effects
				(font
					(size 1.27 1.27)
				)
				(justify mirror)
			)
		)
		(duplicate_pad_numbers_are_jumpers no)
		(fp_poly
			(pts
				(xy 0.7239 -0.2159) (xy -0.7239 -0.2159) (xy -0.7239 1.9939) (xy 0.7239 1.9939)
			)
			(stroke
				(width 0)
				(type default)
			)
			(fill no)
			(layer "B.CrtYd")
		)
		(fp_line
			(start -0.7239 -0.2159)
			(end 0.7239 -0.2159)
			(stroke
				(width 0.1)
				(type default)
			)
			(layer "B.Fab")
		)
		(fp_line
			(start -0.7239 1.9939)
			(end -0.7239 -0.2159)
			(stroke
				(width 0.1)
				(type default)
			)
			(layer "B.Fab")
		)
		(fp_line
			(start 0.7239 -0.2159)
			(end 0.7239 1.9939)
			(stroke
				(width 0.1)
				(type default)
			)
			(layer "B.Fab")
		)
		(fp_line
			(start 0.7239 1.9939)
			(end -0.7239 1.9939)
			(stroke
				(width 0.1)
				(type default)
			)
			(layer "B.Fab")
		)
		(pad "1" smd rect
			(at 0 0 180)
			(size 1.27 1.016)
			(layers "B.Cu" "B.Mask" "B.Paste")
			(net "VR_FET_SW_P12V_STBY_PVDDQ_DEF")
		)
		(pad "2" smd rect
			(at 0 1.778 180)
			(size 1.27 1.016)
			(layers "B.Cu" "B.Mask" "B.Paste")
			(net "GND")
		)
		(zone
			(layer "B.Cu")
			(hatch none 0.5)
			(connect_pads
				(clearance 0)
			)
			(min_thickness 0.25)
			(keepout
				(tracks not_allowed)
				(vias allowed)
				(pads allowed)
				(copperpour not_allowed)
				(footprints allowed)
			)
			(placement
				(enabled no)
				(sheetname "")
			)
			(fill
				(thermal_gap 0.5)
				(thermal_bridge_width 0.5)
				(island_removal_mode 0)
			)
			(polygon
				(pts
					(xy 380.0348 -153.959306) (xy 378.7648 -153.959306) (xy 378.7648 -153.197306) (xy 380.0348 -153.197306)
				)
			)
		)
	)
	(footprint ""
		(layer "B.Cu")
		(at 412.313374 -48.687482 -90)
		(property "Reference" "R8F37"
			(at 0 0 90)
			(layer "B.SilkS")
			(hide yes)
			(effects
				(font
					(size 1.27 1.27)
				)
				(justify mirror)
			)
		)
		(property "Value" ""
			(at 0 0 90)
			(layer "B.Fab")
			(effects
				(font
					(size 1.27 1.27)
				)
				(justify mirror)
			)
		)
		(duplicate_pad_numbers_are_jumpers no)
		(fp_poly
			(pts
				(xy 0.2794 -0.1016) (xy -0.2794 -0.1016) (xy -0.2794 0.9906) (xy 0.2794 0.9906)
			)
			(stroke
				(width 0)
				(type default)
			)
			(fill no)
			(layer "B.CrtYd")
		)
		(fp_line
			(start -0.2794 0.9906)
			(end -0.2794 -0.1016)
			(stroke
				(width 0.1)
				(type default)
			)
			(layer "B.Fab")
		)
		(fp_line
			(start 0.2794 0.9906)
			(end -0.2794 0.9906)
			(stroke
				(width 0.1)
				(type default)
			)
			(layer "B.Fab")
		)
		(fp_line
			(start -0.2794 -0.1016)
			(end 0.2794 -0.1016)
			(stroke
				(width 0.1)
				(type default)
			)
			(layer "B.Fab")
		)
		(fp_line
			(start 0.2794 -0.1016)
			(end 0.2794 0.9906)
			(stroke
				(width 0.1)
				(type default)
			)
			(layer "B.Fab")
		)
		(pad "1" smd rect
			(at 0 0 90)
			(size 0.508 0.508)
			(layers "B.Cu" "B.Mask" "B.Paste")
			(net "FM_CPU_ERR0_LVT3_N")
		)
		(pad "2" smd rect
			(at 0 0.889 90)
			(size 0.508 0.508)
			(layers "B.Cu" "B.Mask" "B.Paste")
			(net "FM_CPU_ERR0_PCH_N")
		)
		(zone
			(layer "B.Cu")
			(hatch none 0.5)
			(connect_pads
				(clearance 0)
			)
			(min_thickness 0.25)
			(keepout
				(tracks not_allowed)
				(vias allowed)
				(pads allowed)
				(copperpour not_allowed)
				(footprints allowed)
			)
			(placement
				(enabled no)
				(sheetname "")
			)
			(fill
				(thermal_gap 0.5)
				(thermal_bridge_width 0.5)
				(island_removal_mode 0)
			)
			(polygon
				(pts
					(xy 411.678374 -48.433482) (xy 411.678374 -48.941482) (xy 412.059374 -48.941482) (xy 412.059374 -48.433482)
				)
			)
		)
		(zone
			(layer "B.Cu")
			(hatch none 0.5)
			(connect_pads
				(clearance 0)
			)
			(min_thickness 0.25)
			(keepout
				(tracks allowed)
				(vias not_allowed)
				(pads allowed)
				(copperpour not_allowed)
				(footprints allowed)
			)
			(placement
				(enabled no)
				(sheetname "")
			)
			(fill
				(thermal_gap 0.5)
				(thermal_bridge_width 0.5)
				(island_removal_mode 0)
			)
			(polygon
				(pts
					(xy 412.059374 -48.433482) (xy 412.059374 -48.941482) (xy 411.678374 -48.941482) (xy 411.678374 -48.433482)
				)
			)
		)
	)
	(footprint ""
		(layer "B.Cu")
		(at 448.55638 -32.4485 90)
		(property "Reference" "R25W27"
			(at 0 0 90)
			(layer "B.SilkS")
			(hide yes)
			(effects
				(font
					(size 1.27 1.27)
				)
				(justify mirror)
			)
		)
		(property "Value" "*"
			(at -0.064008 -4.108196 90)
			(unlocked yes)
			(layer "B.Fab")
			(hide yes)
			(effects
				(font
					(size 1.27 1.016)
					(thickness 0.1524)
				)
				(justify mirror)
			)
		)
		(property "Device Type" "120R2F-GP_RCL_GP-120R2F-GP,64.A"
			(at -0.064008 -5.632196 90)
			(unlocked yes)
			(layer "B.Fab")
			(hide yes)
			(effects
				(font
					(size 1.27 1.016)
					(thickness 0.1524)
				)
				(justify mirror)
			)
		)
		(duplicate_pad_numbers_are_jumpers no)
		(fp_line
			(start 0.508 -0.9398)
			(end 0.508 0.9398)
			(stroke
				(width 0.1524)
				(type default)
			)
			(layer "B.SilkS")
		)
		(fp_line
			(start -0.508 -0.9398)
			(end 0.508 -0.9398)
			(stroke
				(width 0.1524)
				(type default)
			)
			(layer "B.SilkS")
		)
		(fp_rect
			(start 0.508 0.9398)
			(end -0.508 -0.9398)
			(stroke
				(width 0)
				(type default)
			)
			(fill no)
			(layer "B.CrtYd")
		)
		(fp_rect
			(start 0.508 0.9398)
			(end -0.508 -0.9398)
			(stroke
				(width 0)
				(type default)
			)
			(fill no)
			(layer "B.Fab")
		)
		(pad "1" smd custom
			(at 0 -0.4445 270)
			(size 0.1397 0.1397)
			(layers "B.Cu" "B.Mask" "B.Paste")
			(net "BMC_M_CKE")
			(options
				(clearance outline)
				(anchor circle)
			)
			(primitives
				(gr_poly
					(pts
						(arc
							(start -0.1778 0.2794)
							(mid -0.249642 0.249642)
							(end -0.2794 0.1778)
						)
						(arc
							(start -0.2794 -0.1778)
							(mid -0.249642 -0.249642)
							(end -0.1778 -0.2794)
						)
						(arc
							(start 0.1778 -0.2794)
							(mid 0.249642 -0.249642)
							(end 0.2794 -0.1778)
						)
						(arc
							(start 0.2794 0.1778)
							(mid 0.249642 0.249642)
							(end 0.1778 0.2794)
						)
					)
					(width 0)
					(fill yes)
				)
			)
		)
		(pad "2" smd custom
			(at 0 0.4445 270)
			(size 0.1397 0.1397)
			(layers "B.Cu" "B.Mask" "B.Paste")
			(net "P1V2_AUX_BMC")
			(options
				(clearance outline)
				(anchor circle)
			)
			(primitives
				(gr_poly
					(pts
						(arc
							(start -0.1778 0.2794)
							(mid -0.249642 0.249642)
							(end -0.2794 0.1778)
						)
						(arc
							(start -0.2794 -0.1778)
							(mid -0.249642 -0.249642)
							(end -0.1778 -0.2794)
						)
						(arc
							(start 0.1778 -0.2794)
							(mid 0.249642 -0.249642)
							(end 0.2794 -0.1778)
						)
						(arc
							(start 0.2794 0.1778)
							(mid 0.249642 0.249642)
							(end 0.1778 0.2794)
						)
					)
					(width 0)
					(fill yes)
				)
			)
		)
	)
	(footprint ""
		(layer "B.Cu")
		(at 272.861532 -140.208 90)
		(property "Reference" "C5G75"
			(at -1.14681 0.76708 180)
			(unlocked yes)
			(layer "B.SilkS")
			(effects
				(font
					(size 0.7874 0.5842)
					(thickness 0.1524)
				)
				(justify mirror)
			)
		)
		(property "Value" ""
			(at 0 0 90)
			(layer "B.Fab")
			(effects
				(font
					(size 1.27 1.27)
				)
				(justify mirror)
			)
		)
		(duplicate_pad_numbers_are_jumpers no)
		(fp_rect
			(start -0.4953 -0.2032)
			(end 0.4953 1.6002)
			(stroke
				(width 0)
				(type default)
			)
			(fill no)
			(layer "B.CrtYd")
		)
		(fp_line
			(start 0.4953 -0.2032)
			(end -0.4953 -0.2032)
			(stroke
				(width 0.1)
				(type default)
			)
			(layer "B.Fab")
		)
		(fp_line
			(start -0.4953 -0.2032)
			(end -0.4953 1.6002)
			(stroke
				(width 0.1)
				(type default)
			)
			(layer "B.Fab")
		)
		(fp_line
			(start 0.4953 1.6002)
			(end 0.4953 -0.2032)
			(stroke
				(width 0.1)
				(type default)
			)
			(layer "B.Fab")
		)
		(fp_line
			(start -0.4953 1.6002)
			(end 0.4953 1.6002)
			(stroke
				(width 0.1)
				(type default)
			)
			(layer "B.Fab")
		)
		(pad "1" smd rect
			(at 0 0 270)
			(size 0.762 0.889)
			(layers "B.Cu" "B.Mask" "B.Paste")
			(net "PVDDQ_DEF")
		)
		(pad "2" smd rect
			(at 0 1.397 270)
			(size 0.762 0.889)
			(layers "B.Cu" "B.Mask" "B.Paste")
			(net "GND")
		)
		(zone
			(layer "B.Cu")
			(hatch none 0.5)
			(connect_pads
				(clearance 0)
			)
			(min_thickness 0.25)
			(keepout
				(tracks not_allowed)
				(vias allowed)
				(pads allowed)
				(copperpour not_allowed)
				(footprints allowed)
			)
			(placement
				(enabled no)
				(sheetname "")
			)
			(fill
				(thermal_gap 0.5)
				(thermal_bridge_width 0.5)
				(island_removal_mode 0)
			)
			(polygon
				(pts
					(xy 273.306032 -139.827) (xy 273.814032 -139.827) (xy 273.814032 -140.589) (xy 273.306032 -140.589)
				)
			)
		)
	)
	(footprint ""
		(layer "B.Cu")
		(at 164.973 -67.2592 90)
		(property "Reference" "R6P40"
			(at 0 0 90)
			(layer "B.SilkS")
			(hide yes)
			(effects
				(font
					(size 1.27 1.27)
				)
				(justify mirror)
			)
		)
		(property "Value" ""
			(at 0 0 90)
			(layer "B.Fab")
			(effects
				(font
					(size 1.27 1.27)
				)
				(justify mirror)
			)
		)
		(duplicate_pad_numbers_are_jumpers no)
		(fp_poly
			(pts
				(xy 0.2794 -0.1016) (xy -0.2794 -0.1016) (xy -0.2794 0.9906) (xy 0.2794 0.9906)
			)
			(stroke
				(width 0)
				(type default)
			)
			(fill no)
			(layer "B.CrtYd")
		)
		(fp_line
			(start 0.2794 -0.1016)
			(end 0.2794 0.9906)
			(stroke
				(width 0.1)
				(type default)
			)
			(layer "B.Fab")
		)
		(fp_line
			(start -0.2794 -0.1016)
			(end 0.2794 -0.1016)
			(stroke
				(width 0.1)
				(type default)
			)
			(layer "B.Fab")
		)
		(fp_line
			(start 0.2794 0.9906)
			(end -0.2794 0.9906)
			(stroke
				(width 0.1)
				(type default)
			)
			(layer "B.Fab")
		)
		(fp_line
			(start -0.2794 0.9906)
			(end -0.2794 -0.1016)
			(stroke
				(width 0.1)
				(type default)
			)
			(layer "B.Fab")
		)
		(pad "1" smd rect
			(at 0 0 270)
			(size 0.508 0.508)
			(layers "B.Cu" "B.Mask" "B.Paste")
			(net "P3V3_STBY")
		)
		(pad "2" smd rect
			(at 0 0.889 270)
			(size 0.508 0.508)
			(layers "B.Cu" "B.Mask" "B.Paste")
			(net "VR_PVCCIO_CPU1_EN")
		)
		(zone
			(layer "B.Cu")
			(hatch none 0.5)
			(connect_pads
				(clearance 0)
			)
			(min_thickness 0.25)
			(keepout
				(tracks allowed)
				(vias not_allowed)
				(pads allowed)
				(copperpour not_allowed)
				(footprints allowed)
			)
			(placement
				(enabled no)
				(sheetname "")
			)
			(fill
				(thermal_gap 0.5)
				(thermal_bridge_width 0.5)
				(island_removal_mode 0)
			)
			(polygon
				(pts
					(xy 165.227 -67.5132) (xy 165.227 -67.0052) (xy 165.608 -67.0052) (xy 165.608 -67.5132)
				)
			)
		)
		(zone
			(layer "B.Cu")
			(hatch none 0.5)
			(connect_pads
				(clearance 0)
			)
			(min_thickness 0.25)
			(keepout
				(tracks not_allowed)
				(vias allowed)
				(pads allowed)
				(copperpour not_allowed)
				(footprints allowed)
			)
			(placement
				(enabled no)
				(sheetname "")
			)
			(fill
				(thermal_gap 0.5)
				(thermal_bridge_width 0.5)
				(island_removal_mode 0)
			)
			(polygon
				(pts
					(xy 165.608 -67.5132) (xy 165.608 -67.0052) (xy 165.227 -67.0052) (xy 165.227 -67.5132)
				)
			)
		)
	)
	(footprint ""
		(layer "B.Cu")
		(at 342.8238 -46.6598 90)
		(property "Reference" "C4R1"
			(at 3.07467 3.429 180)
			(unlocked yes)
			(layer "B.SilkS")
			(effects
				(font
					(size 0.7874 0.5842)
					(thickness 0.1524)
				)
				(justify mirror)
			)
		)
		(property "Value" ""
			(at 0 0 90)
			(layer "B.Fab")
			(effects
				(font
					(size 1.27 1.27)
				)
				(justify mirror)
			)
		)
		(duplicate_pad_numbers_are_jumpers no)
		(fp_line
			(start 2.563114 -1.616456)
			(end 2.563114 1.633728)
			(stroke
				(width 0.1524)
				(type default)
			)
			(layer "B.SilkS")
		)
		(fp_line
			(start 1.6002 -1.616456)
			(end 2.563114 -1.616456)
			(stroke
				(width 0.1524)
				(type default)
			)
			(layer "B.SilkS")
		)
		(fp_line
			(start -1.6002 -1.616456)
			(end -2.504948 -1.616456)
			(stroke
				(width 0.1524)
				(type default)
			)
			(layer "B.SilkS")
		)
		(fp_line
			(start -2.504948 -1.616456)
			(end -2.504948 1.633728)
			(stroke
				(width 0.1524)
				(type default)
			)
			(layer "B.SilkS")
		)
		(fp_line
			(start 2.563114 1.633728)
			(end 1.6002 1.633728)
			(stroke
				(width 0.1524)
				(type default)
			)
			(layer "B.SilkS")
		)
		(fp_line
			(start -2.504948 1.633728)
			(end -1.6002 1.633728)
			(stroke
				(width 0.1524)
				(type default)
			)
			(layer "B.SilkS")
		)
		(fp_line
			(start 2.286 7.366)
			(end 2.286 1.632712)
			(stroke
				(width 0.1524)
				(type default)
			)
			(layer "B.SilkS")
		)
		(fp_line
			(start 2.286 7.366)
			(end 1.60147 7.366)
			(stroke
				(width 0.1524)
				(type default)
			)
			(layer "B.SilkS")
		)
		(fp_line
			(start -2.286 7.366)
			(end -2.286 1.63195)
			(stroke
				(width 0.1524)
				(type default)
			)
			(layer "B.SilkS")
		)
		(fp_line
			(start -2.286 7.366)
			(end -1.600708 7.366)
			(stroke
				(width 0.1524)
				(type default)
			)
			(layer "B.SilkS")
		)
		(fp_rect
			(start 2.286 7.366)
			(end -2.286 -0.254)
			(stroke
				(width 0)
				(type default)
			)
			(fill no)
			(layer "B.CrtYd")
		)
		(fp_line
			(start 2.286 -0.254)
			(end -2.286 -0.254)
			(stroke
				(width 0.1)
				(type default)
			)
			(layer "B.Fab")
		)
		(fp_line
			(start -2.286 -0.254)
			(end -2.286 7.366)
			(stroke
				(width 0.1)
				(type default)
			)
			(layer "B.Fab")
		)
		(fp_line
			(start 2.286 7.366)
			(end 2.286 -0.254)
			(stroke
				(width 0.1)
				(type default)
			)
			(layer "B.Fab")
		)
		(fp_line
			(start -2.286 7.366)
			(end 2.286 7.366)
			(stroke
				(width 0.1)
				(type default)
			)
			(layer "B.Fab")
		)
		(pad "1" smd rect
			(at 0 0 270)
			(size 2.54 3.048)
			(layers "B.Cu" "B.Mask" "B.Paste")
			(net "PVCCMCP_CPU0")
		)
		(pad "2" smd rect
			(at 0 7.112 270)
			(size 2.54 3.048)
			(layers "B.Cu" "B.Mask" "B.Paste")
			(net "GND")
		)
	)
	(footprint ""
		(layer "B.Cu")
		(at 267.692886 -73.51014)
		(property "Reference" "C5P32"
			(at 0 0 0)
			(layer "B.SilkS")
			(hide yes)
			(effects
				(font
					(size 1.27 1.27)
				)
				(justify mirror)
			)
		)
		(property "Value" ""
			(at 0 0 0)
			(layer "B.Fab")
			(effects
				(font
					(size 1.27 1.27)
				)
				(justify mirror)
			)
		)
		(duplicate_pad_numbers_are_jumpers no)
		(fp_poly
			(pts
				(xy 0.7239 -0.2159) (xy -0.7239 -0.2159) (xy -0.7239 1.9939) (xy 0.7239 1.9939)
			)
			(stroke
				(width 0)
				(type default)
			)
			(fill no)
			(layer "B.CrtYd")
		)
		(fp_line
			(start -0.7239 -0.2159)
			(end 0.7239 -0.2159)
			(stroke
				(width 0.1)
				(type default)
			)
			(layer "B.Fab")
		)
		(fp_line
			(start -0.7239 1.9939)
			(end -0.7239 -0.2159)
			(stroke
				(width 0.1)
				(type default)
			)
			(layer "B.Fab")
		)
		(fp_line
			(start 0.7239 -0.2159)
			(end 0.7239 1.9939)
			(stroke
				(width 0.1)
				(type default)
			)
			(layer "B.Fab")
		)
		(fp_line
			(start 0.7239 1.9939)
			(end -0.7239 1.9939)
			(stroke
				(width 0.1)
				(type default)
			)
			(layer "B.Fab")
		)
		(pad "1" smd rect
			(at 0 0 180)
			(size 1.27 1.016)
			(layers "B.Cu" "B.Mask" "B.Paste")
			(net "PVCCIN_CPU0")
		)
		(pad "2" smd rect
			(at 0 1.778 180)
			(size 1.27 1.016)
			(layers "B.Cu" "B.Mask" "B.Paste")
			(net "GND")
		)
		(zone
			(layer "B.Cu")
			(hatch none 0.5)
			(connect_pads
				(clearance 0)
			)
			(min_thickness 0.25)
			(keepout
				(tracks not_allowed)
				(vias allowed)
				(pads allowed)
				(copperpour not_allowed)
				(footprints allowed)
			)
			(placement
				(enabled no)
				(sheetname "")
			)
			(fill
				(thermal_gap 0.5)
				(thermal_bridge_width 0.5)
				(island_removal_mode 0)
			)
			(polygon
				(pts
					(xy 268.327886 -73.00214) (xy 267.057886 -73.00214) (xy 267.057886 -72.24014) (xy 268.327886 -72.24014)
				)
			)
		)
	)
	(footprint ""
		(layer "B.Cu")
		(at 30.988 -64.262 180)
		(property "Reference" "CT26"
			(at 0.8382 -0.84963 180)
			(unlocked yes)
			(layer "B.SilkS")
			(effects
				(font
					(size 0.7874 0.5842)
					(thickness 0.1524)
				)
				(justify left mirror)
			)
		)
		(property "Value" ""
			(at 0 0 0)
			(layer "B.Fab")
			(effects
				(font
					(size 1.27 1.27)
				)
				(justify mirror)
			)
		)
		(duplicate_pad_numbers_are_jumpers no)
		(fp_poly
			(pts
				(xy -0.3048 -0.1016) (xy -0.3048 0.9906) (xy 0.3048 0.9906) (xy 0.3048 -0.1016)
			)
			(stroke
				(width 0)
				(type default)
			)
			(fill no)
			(layer "B.CrtYd")
		)
		(fp_line
			(start 0.3048 0.9906)
			(end -0.3048 0.9906)
			(stroke
				(width 0.1)
				(type default)
			)
			(layer "B.Fab")
		)
		(fp_line
			(start 0.3048 -0.1016)
			(end 0.3048 0.9906)
			(stroke
				(width 0.1)
				(type default)
			)
			(layer "B.Fab")
		)
		(fp_line
			(start -0.3048 0.9906)
			(end -0.3048 -0.1016)
			(stroke
				(width 0.1)
				(type default)
			)
			(layer "B.Fab")
		)
		(fp_line
			(start -0.3048 -0.1016)
			(end 0.3048 -0.1016)
			(stroke
				(width 0.1)
				(type default)
			)
			(layer "B.Fab")
		)
		(pad "1" smd rect
			(at 0 0)
			(size 0.508 0.508)
			(layers "B.Cu" "B.Mask" "B.Paste")
			(net "A_TSENSE_PVCCIN_CPU1")
		)
		(pad "2" smd rect
			(at 0 0.889)
			(size 0.508 0.508)
			(layers "B.Cu" "B.Mask" "B.Paste")
			(net "GND")
		)
		(zone
			(layer "B.Cu")
			(hatch none 0.5)
			(connect_pads
				(clearance 0)
			)
			(min_thickness 0.25)
			(keepout
				(tracks not_allowed)
				(vias allowed)
				(pads allowed)
				(copperpour not_allowed)
				(footprints allowed)
			)
			(placement
				(enabled no)
				(sheetname "")
			)
			(fill
				(thermal_gap 0.5)
				(thermal_bridge_width 0.5)
				(island_removal_mode 0)
			)
			(polygon
				(pts
					(xy 30.734 -64.897) (xy 31.242 -64.897) (xy 31.242 -64.516) (xy 30.734 -64.516)
				)
			)
		)
		(zone
			(layer "B.Cu")
			(hatch none 0.5)
			(connect_pads
				(clearance 0)
			)
			(min_thickness 0.25)
			(keepout
				(tracks allowed)
				(vias not_allowed)
				(pads allowed)
				(copperpour not_allowed)
				(footprints allowed)
			)
			(placement
				(enabled no)
				(sheetname "")
			)
			(fill
				(thermal_gap 0.5)
				(thermal_bridge_width 0.5)
				(island_removal_mode 0)
			)
			(polygon
				(pts
					(xy 30.734 -64.516) (xy 31.242 -64.516) (xy 31.242 -64.897) (xy 30.734 -64.897)
				)
			)
		)
	)
	(footprint ""
		(layer "B.Cu")
		(at 339.979 -27.178)
		(property "Reference" "C3T11"
			(at 0 0 0)
			(layer "B.SilkS")
			(hide yes)
			(effects
				(font
					(size 1.27 1.27)
				)
				(justify mirror)
			)
		)
		(property "Value" ""
			(at 0 0 0)
			(layer "B.Fab")
			(effects
				(font
					(size 1.27 1.27)
				)
				(justify mirror)
			)
		)
		(duplicate_pad_numbers_are_jumpers no)
		(fp_rect
			(start 0.4953 1.6002)
			(end -0.4953 -0.2032)
			(stroke
				(width 0)
				(type default)
			)
			(fill no)
			(layer "B.CrtYd")
		)
		(fp_line
			(start -0.4953 -0.2032)
			(end -0.4953 1.6002)
			(stroke
				(width 0.1)
				(type default)
			)
			(layer "B.Fab")
		)
		(fp_line
			(start -0.4953 1.6002)
			(end 0.4953 1.6002)
			(stroke
				(width 0.1)
				(type default)
			)
			(layer "B.Fab")
		)
		(fp_line
			(start 0.4953 -0.2032)
			(end -0.4953 -0.2032)
			(stroke
				(width 0.1)
				(type default)
			)
			(layer "B.Fab")
		)
		(fp_line
			(start 0.4953 1.6002)
			(end 0.4953 -0.2032)
			(stroke
				(width 0.1)
				(type default)
			)
			(layer "B.Fab")
		)
		(pad "1" smd rect
			(at 0 0 180)
			(size 0.762 0.889)
			(layers "B.Cu" "B.Mask" "B.Paste")
			(net "VR_VB_PVPP_ABC")
		)
		(pad "2" smd rect
			(at 0 1.397 180)
			(size 0.762 0.889)
			(layers "B.Cu" "B.Mask" "B.Paste")
			(net "AGND_PVPP_ABC")
		)
		(zone
			(layer "B.Cu")
			(hatch none 0.5)
			(connect_pads
				(clearance 0)
			)
			(min_thickness 0.25)
			(keepout
				(tracks not_allowed)
				(vias allowed)
				(pads allowed)
				(copperpour not_allowed)
				(footprints allowed)
			)
			(placement
				(enabled no)
				(sheetname "")
			)
			(fill
				(thermal_gap 0.5)
				(thermal_bridge_width 0.5)
				(island_removal_mode 0)
			)
			(polygon
				(pts
					(xy 340.36 -26.2255) (xy 340.36 -26.7335) (xy 339.598 -26.7335) (xy 339.598 -26.2255)
				)
			)
		)
	)
	(footprint ""
		(layer "B.Cu")
		(at 438.703974 -22.6314 -90)
		(property "Reference" "R3W6"
			(at 0.8382 -0.67818 270)
			(unlocked yes)
			(layer "B.SilkS")
			(effects
				(font
					(size 0.4064 0.254)
					(thickness 0.1524)
				)
				(justify left mirror)
			)
		)
		(property "Value" ""
			(at 0 0 90)
			(layer "B.Fab")
			(effects
				(font
					(size 1.27 1.27)
				)
				(justify mirror)
			)
		)
		(duplicate_pad_numbers_are_jumpers no)
		(fp_poly
			(pts
				(xy 0.2794 -0.1016) (xy -0.2794 -0.1016) (xy -0.2794 0.9906) (xy 0.2794 0.9906)
			)
			(stroke
				(width 0)
				(type default)
			)
			(fill no)
			(layer "B.CrtYd")
		)
		(fp_line
			(start -0.2794 0.9906)
			(end -0.2794 -0.1016)
			(stroke
				(width 0.1)
				(type default)
			)
			(layer "B.Fab")
		)
		(fp_line
			(start 0.2794 0.9906)
			(end -0.2794 0.9906)
			(stroke
				(width 0.1)
				(type default)
			)
			(layer "B.Fab")
		)
		(fp_line
			(start -0.2794 -0.1016)
			(end 0.2794 -0.1016)
			(stroke
				(width 0.1)
				(type default)
			)
			(layer "B.Fab")
		)
		(fp_line
			(start 0.2794 -0.1016)
			(end 0.2794 0.9906)
			(stroke
				(width 0.1)
				(type default)
			)
			(layer "B.Fab")
		)
		(pad "1" smd rect
			(at 0 0 90)
			(size 0.508 0.508)
			(layers "B.Cu" "B.Mask" "B.Paste")
			(net "P3V3_STBY")
		)
		(pad "2" smd rect
			(at 0 0.889 90)
			(size 0.508 0.508)
			(layers "B.Cu" "B.Mask" "B.Paste")
			(net "RST_BMC_EXTRST_N")
		)
		(zone
			(layer "B.Cu")
			(hatch none 0.5)
			(connect_pads
				(clearance 0)
			)
			(min_thickness 0.25)
			(keepout
				(tracks not_allowed)
				(vias allowed)
				(pads allowed)
				(copperpour not_allowed)
				(footprints allowed)
			)
			(placement
				(enabled no)
				(sheetname "")
			)
			(fill
				(thermal_gap 0.5)
				(thermal_bridge_width 0.5)
				(island_removal_mode 0)
			)
			(polygon
				(pts
					(xy 438.068974 -22.3774) (xy 438.068974 -22.8854) (xy 438.449974 -22.8854) (xy 438.449974 -22.3774)
				)
			)
		)
		(zone
			(layer "B.Cu")
			(hatch none 0.5)
			(connect_pads
				(clearance 0)
			)
			(min_thickness 0.25)
			(keepout
				(tracks allowed)
				(vias not_allowed)
				(pads allowed)
				(copperpour not_allowed)
				(footprints allowed)
			)
			(placement
				(enabled no)
				(sheetname "")
			)
			(fill
				(thermal_gap 0.5)
				(thermal_bridge_width 0.5)
				(island_removal_mode 0)
			)
			(polygon
				(pts
					(xy 438.449974 -22.3774) (xy 438.449974 -22.8854) (xy 438.068974 -22.8854) (xy 438.068974 -22.3774)
				)
			)
		)
	)
	(footprint ""
		(layer "B.Cu")
		(at 370.3955 -60.87872)
		(property "Reference" "U3P2"
			(at -4.435856 5.186172 180)
			(unlocked yes)
			(layer "B.SilkS")
			(effects
				(font
					(size 0.7874 0.5842)
					(thickness 0.1524)
				)
				(justify left mirror)
			)
		)
		(property "Value" ""
			(at 0 0 0)
			(layer "B.Fab")
			(effects
				(font
					(size 1.27 1.27)
				)
				(justify mirror)
			)
		)
		(duplicate_pad_numbers_are_jumpers no)
		(fp_line
			(start -4.4323 -0.64008)
			(end -4.4323 4.52628)
			(stroke
				(width 0.1524)
				(type default)
			)
			(layer "B.SilkS")
		)
		(fp_line
			(start -4.4323 4.52628)
			(end -1.5367 4.52628)
			(stroke
				(width 0.1524)
				(type default)
			)
			(layer "B.SilkS")
		)
		(fp_line
			(start -3.302 0.49022)
			(end -3.302 -0.64008)
			(stroke
				(width 0.1524)
				(type default)
			)
			(layer "B.SilkS")
		)
		(fp_line
			(start -2.667 -0.64008)
			(end -2.667 0.49022)
			(stroke
				(width 0.1524)
				(type default)
			)
			(layer "B.SilkS")
		)
		(fp_line
			(start -2.667 0.49022)
			(end -3.302 0.49022)
			(stroke
				(width 0.1524)
				(type default)
			)
			(layer "B.SilkS")
		)
		(fp_line
			(start -1.5367 -0.64008)
			(end -4.4323 -0.64008)
			(stroke
				(width 0.1524)
				(type default)
			)
			(layer "B.SilkS")
		)
		(fp_line
			(start -1.5367 4.52628)
			(end -1.5367 -0.64008)
			(stroke
				(width 0.1524)
				(type default)
			)
			(layer "B.SilkS")
		)
		(fp_circle
			(center 1.612138 -0.684784)
			(end 1.739138 -0.684784)
			(stroke
				(width 0.254)
				(type default)
			)
			(fill no)
			(layer "B.SilkS")
		)
		(fp_poly
			(pts
				(xy -0.7366 4.54152) (xy -0.7366 -0.64008) (xy -4.7244 -0.64008) (xy -5.2324 -0.64008) (xy -5.2324 4.54152)
				(xy -4.7244 4.54152)
			)
			(stroke
				(width 0)
				(type default)
			)
			(fill no)
			(layer "B.CrtYd")
		)
		(fp_line
			(start -5.2324 -0.64008)
			(end -5.2324 4.54152)
			(stroke
				(width 0.1)
				(type default)
			)
			(layer "B.Fab")
		)
		(fp_line
			(start -5.2324 4.54152)
			(end -0.7366 4.54152)
			(stroke
				(width 0.1)
				(type default)
			)
			(layer "B.Fab")
		)
		(fp_line
			(start -3.302 0.49022)
			(end -3.302 -0.64008)
			(stroke
				(width 0.1)
				(type default)
			)
			(layer "B.Fab")
		)
		(fp_line
			(start -2.667 -0.64008)
			(end -2.667 0.49022)
			(stroke
				(width 0.1)
				(type default)
			)
			(layer "B.Fab")
		)
		(fp_line
			(start -2.667 0.49022)
			(end -3.302 0.49022)
			(stroke
				(width 0.1)
				(type default)
			)
			(layer "B.Fab")
		)
		(fp_line
			(start -0.7366 -0.64008)
			(end -5.2324 -0.64008)
			(stroke
				(width 0.1)
				(type default)
			)
			(layer "B.Fab")
		)
		(fp_line
			(start -0.7366 4.54152)
			(end -0.7366 -0.64008)
			(stroke
				(width 0.1)
				(type default)
			)
			(layer "B.Fab")
		)
		(fp_circle
			(center 1.612138 -0.684784)
			(end 1.739138 -0.684784)
			(stroke
				(width 0.254)
				(type default)
			)
			(fill no)
			(layer "B.Fab")
		)
		(pad "1" smd rect
			(at 0 0 180)
			(size 2.159 0.381)
			(layers "B.Cu" "B.Mask" "B.Paste")
			(net "PD_GTL2104_DIR_1")
		)
		(pad "2" smd rect
			(at 0 0.65024 180)
			(size 2.159 0.381)
			(layers "B.Cu" "B.Mask" "B.Paste")
			(net "PWRGD_CPUPWRGD_GTL")
		)
		(pad "3" smd rect
			(at 0 1.30048 180)
			(size 2.159 0.381)
			(layers "B.Cu" "B.Mask" "B.Paste")
			(net "H_CPU1_FIVR_FAULT_G")
		)
		(pad "4" smd rect
			(at 0 1.95072 180)
			(size 2.159 0.381)
			(layers "B.Cu" "B.Mask" "B.Paste")
			(net "P0V7_GTL2104_VREF_1")
		)
		(pad "5" smd rect
			(at 0 2.60096 180)
			(size 2.159 0.381)
			(layers "B.Cu" "B.Mask" "B.Paste")
			(net "H_CPU_CATERR_G_N")
		)
		(pad "6" smd rect
			(at 0 3.2512 180)
			(size 2.159 0.381)
			(layers "B.Cu" "B.Mask" "B.Paste")
			(net "H_CPU1_THERMTRIP_G_N")
		)
		(pad "7" smd rect
			(at 0 3.90144 180)
			(size 2.159 0.381)
			(layers "B.Cu" "B.Mask" "B.Paste")
			(net "GND")
		)
		(pad "8" smd rect
			(at -5.969 3.90144 180)
			(size 2.159 0.381)
			(layers "B.Cu" "B.Mask" "B.Paste")
			(net "GND")
		)
		(pad "9" smd rect
			(at -5.969 3.2512 180)
			(size 2.159 0.381)
			(layers "B.Cu" "B.Mask" "B.Paste")
			(net "FM_CPU1_THERMTRIP_LVT3_R_N")
		)
		(pad "10" smd rect
			(at -5.969 2.60096 180)
			(size 2.159 0.381)
			(layers "B.Cu" "B.Mask" "B.Paste")
			(net "FM_CPU_CATERR_LVT3_R2_N")
		)
		(pad "11" smd rect
			(at -5.969 1.95072 180)
			(size 2.159 0.381)
			(layers "B.Cu" "B.Mask" "B.Paste")
			(net "GND")
		)
		(pad "12" smd rect
			(at -5.969 1.30048 180)
			(size 2.159 0.381)
			(layers "B.Cu" "B.Mask" "B.Paste")
			(net "FM_CPU1_FIVR_FAULT_R_LVT3")
		)
		(pad "13" smd rect
			(at -5.969 0.65024 180)
			(size 2.159 0.381)
			(layers "B.Cu" "B.Mask" "B.Paste")
			(net "PWRGD_CPUPWRGD_R1")
		)
		(pad "14" smd rect
			(at -5.969 0 180)
			(size 2.159 0.381)
			(layers "B.Cu" "B.Mask" "B.Paste")
			(net "P3V3")
		)
	)
	(footprint ""
		(layer "B.Cu")
		(at 416.9664 -22.987 180)
		(property "Reference" "R25W124"
			(at 0.8382 -0.67818 180)
			(unlocked yes)
			(layer "B.SilkS")
			(effects
				(font
					(size 0.4064 0.254)
					(thickness 0.1524)
				)
				(justify left mirror)
			)
		)
		(property "Value" ""
			(at 0 0 0)
			(layer "B.Fab")
			(effects
				(font
					(size 1.27 1.27)
				)
				(justify mirror)
			)
		)
		(duplicate_pad_numbers_are_jumpers no)
		(fp_poly
			(pts
				(xy 0.2794 -0.1016) (xy -0.2794 -0.1016) (xy -0.2794 0.9906) (xy 0.2794 0.9906)
			)
			(stroke
				(width 0)
				(type default)
			)
			(fill no)
			(layer "B.CrtYd")
		)
		(fp_line
			(start 0.2794 0.9906)
			(end -0.2794 0.9906)
			(stroke
				(width 0.1)
				(type default)
			)
			(layer "B.Fab")
		)
		(fp_line
			(start 0.2794 -0.1016)
			(end 0.2794 0.9906)
			(stroke
				(width 0.1)
				(type default)
			)
			(layer "B.Fab")
		)
		(fp_line
			(start -0.2794 0.9906)
			(end -0.2794 -0.1016)
			(stroke
				(width 0.1)
				(type default)
			)
			(layer "B.Fab")
		)
		(fp_line
			(start -0.2794 -0.1016)
			(end 0.2794 -0.1016)
			(stroke
				(width 0.1)
				(type default)
			)
			(layer "B.Fab")
		)
		(pad "1" smd rect
			(at 0 0)
			(size 0.508 0.508)
			(layers "B.Cu" "B.Mask" "B.Paste")
			(net "BMC_VGA_GREEN")
		)
		(pad "2" smd rect
			(at 0 0.889)
			(size 0.508 0.508)
			(layers "B.Cu" "B.Mask" "B.Paste")
			(net "GND")
		)
		(zone
			(layer "B.Cu")
			(hatch none 0.5)
			(connect_pads
				(clearance 0)
			)
			(min_thickness 0.25)
			(keepout
				(tracks not_allowed)
				(vias allowed)
				(pads allowed)
				(copperpour not_allowed)
				(footprints allowed)
			)
			(placement
				(enabled no)
				(sheetname "")
			)
			(fill
				(thermal_gap 0.5)
				(thermal_bridge_width 0.5)
				(island_removal_mode 0)
			)
			(polygon
				(pts
					(xy 416.7124 -23.622) (xy 417.2204 -23.622) (xy 417.2204 -23.241) (xy 416.7124 -23.241)
				)
			)
		)
		(zone
			(layer "B.Cu")
			(hatch none 0.5)
			(connect_pads
				(clearance 0)
			)
			(min_thickness 0.25)
			(keepout
				(tracks allowed)
				(vias not_allowed)
				(pads allowed)
				(copperpour not_allowed)
				(footprints allowed)
			)
			(placement
				(enabled no)
				(sheetname "")
			)
			(fill
				(thermal_gap 0.5)
				(thermal_bridge_width 0.5)
				(island_removal_mode 0)
			)
			(polygon
				(pts
					(xy 416.7124 -23.241) (xy 417.2204 -23.241) (xy 417.2204 -23.622) (xy 416.7124 -23.622)
				)
			)
		)
	)
	(footprint ""
		(layer "B.Cu")
		(at 417.223194 -38.2905 90)
		(property "Reference" "C25W44"
			(at 0.8382 -0.67818 90)
			(unlocked yes)
			(layer "B.SilkS")
			(effects
				(font
					(size 0.4064 0.254)
					(thickness 0.1524)
				)
				(justify left mirror)
			)
		)
		(property "Value" ""
			(at 0 0 90)
			(layer "B.Fab")
			(effects
				(font
					(size 1.27 1.27)
				)
				(justify mirror)
			)
		)
		(duplicate_pad_numbers_are_jumpers no)
		(fp_poly
			(pts
				(xy -0.3048 -0.1016) (xy -0.3048 0.9906) (xy 0.3048 0.9906) (xy 0.3048 -0.1016)
			)
			(stroke
				(width 0)
				(type default)
			)
			(fill no)
			(layer "B.CrtYd")
		)
		(fp_line
			(start 0.3048 -0.1016)
			(end 0.3048 0.9906)
			(stroke
				(width 0.1)
				(type default)
			)
			(layer "B.Fab")
		)
		(fp_line
			(start -0.3048 -0.1016)
			(end 0.3048 -0.1016)
			(stroke
				(width 0.1)
				(type default)
			)
			(layer "B.Fab")
		)
		(fp_line
			(start 0.3048 0.9906)
			(end -0.3048 0.9906)
			(stroke
				(width 0.1)
				(type default)
			)
			(layer "B.Fab")
		)
		(fp_line
			(start -0.3048 0.9906)
			(end -0.3048 -0.1016)
			(stroke
				(width 0.1)
				(type default)
			)
			(layer "B.Fab")
		)
		(pad "1" smd rect
			(at 0 0 270)
			(size 0.508 0.508)
			(layers "B.Cu" "B.Mask" "B.Paste")
			(net "VCC_D_3V3")
		)
		(pad "2" smd rect
			(at 0 0.889 270)
			(size 0.508 0.508)
			(layers "B.Cu" "B.Mask" "B.Paste")
			(net "GND")
		)
		(zone
			(layer "B.Cu")
			(hatch none 0.5)
			(connect_pads
				(clearance 0)
			)
			(min_thickness 0.25)
			(keepout
				(tracks allowed)
				(vias not_allowed)
				(pads allowed)
				(copperpour not_allowed)
				(footprints allowed)
			)
			(placement
				(enabled no)
				(sheetname "")
			)
			(fill
				(thermal_gap 0.5)
				(thermal_bridge_width 0.5)
				(island_removal_mode 0)
			)
			(polygon
				(pts
					(xy 417.477194 -38.5445) (xy 417.477194 -38.0365) (xy 417.858194 -38.0365) (xy 417.858194 -38.5445)
				)
			)
		)
		(zone
			(layer "B.Cu")
			(hatch none 0.5)
			(connect_pads
				(clearance 0)
			)
			(min_thickness 0.25)
			(keepout
				(tracks not_allowed)
				(vias allowed)
				(pads allowed)
				(copperpour not_allowed)
				(footprints allowed)
			)
			(placement
				(enabled no)
				(sheetname "")
			)
			(fill
				(thermal_gap 0.5)
				(thermal_bridge_width 0.5)
				(island_removal_mode 0)
			)
			(polygon
				(pts
					(xy 417.858194 -38.5445) (xy 417.858194 -38.0365) (xy 417.477194 -38.0365) (xy 417.477194 -38.5445)
				)
			)
		)
	)
	(footprint ""
		(layer "B.Cu")
		(at 272.861532 -8.1534 90)
		(property "Reference" "C5U3"
			(at -1.848866 0.752348 90)
			(unlocked yes)
			(layer "B.SilkS")
			(effects
				(font
					(size 1.27 0.9652)
					(thickness 0.1524)
				)
				(justify mirror)
			)
		)
		(property "Value" ""
			(at 0 0 90)
			(layer "B.Fab")
			(effects
				(font
					(size 1.27 1.27)
				)
				(justify mirror)
			)
		)
		(duplicate_pad_numbers_are_jumpers no)
		(fp_rect
			(start 0.500126 1.598422)
			(end -0.500126 -0.201422)
			(stroke
				(width 0)
				(type default)
			)
			(fill no)
			(layer "B.CrtYd")
		)
		(fp_line
			(start 0.500126 -0.201422)
			(end -0.500126 -0.201422)
			(stroke
				(width 0.1)
				(type default)
			)
			(layer "B.Fab")
		)
		(fp_line
			(start -0.500126 -0.201422)
			(end -0.500126 1.598422)
			(stroke
				(width 0.1)
				(type default)
			)
			(layer "B.Fab")
		)
		(fp_line
			(start 0.500126 1.598422)
			(end 0.500126 -0.201422)
			(stroke
				(width 0.1)
				(type default)
			)
			(layer "B.Fab")
		)
		(fp_line
			(start -0.500126 1.598422)
			(end 0.500126 1.598422)
			(stroke
				(width 0.1)
				(type default)
			)
			(layer "B.Fab")
		)
		(pad "1" smd rect
			(at 0 0)
			(size 0.889 0.9906)
			(layers "B.Cu" "B.Mask" "B.Paste")
			(net "PVDDQ_ABC")
		)
		(pad "2" smd rect
			(at 0 1.397)
			(size 0.889 0.9906)
			(layers "B.Cu" "B.Mask" "B.Paste")
			(net "GND")
		)
		(zone
			(layer "B.Cu")
			(hatch none 0.5)
			(connect_pads
				(clearance 0)
			)
			(min_thickness 0.25)
			(keepout
				(tracks not_allowed)
				(vias allowed)
				(pads allowed)
				(copperpour not_allowed)
				(footprints allowed)
			)
			(placement
				(enabled no)
				(sheetname "")
			)
			(fill
				(thermal_gap 0.5)
				(thermal_bridge_width 0.5)
				(island_removal_mode 0)
			)
			(polygon
				(pts
					(xy 273.814032 -8.6487) (xy 273.306032 -8.6487) (xy 273.306032 -7.6581) (xy 273.814032 -7.6581)
				)
			)
		)
		(zone
			(layer "B.Cu")
			(hatch none 0.5)
			(connect_pads
				(clearance 0)
			)
			(min_thickness 0.25)
			(keepout
				(tracks allowed)
				(vias not_allowed)
				(pads allowed)
				(copperpour not_allowed)
				(footprints allowed)
			)
			(placement
				(enabled no)
				(sheetname "")
			)
			(fill
				(thermal_gap 0.5)
				(thermal_bridge_width 0.5)
				(island_removal_mode 0)
			)
			(polygon
				(pts
					(xy 273.814032 -8.6487) (xy 273.306032 -8.6487) (xy 273.306032 -7.6581) (xy 273.814032 -7.6581)
				)
			)
		)
	)
	(footprint ""
		(layer "B.Cu")
		(at 32.832802 -89.158064 90)
		(property "Reference" "C9N27"
			(at 0 0 90)
			(layer "B.SilkS")
			(hide yes)
			(effects
				(font
					(size 1.27 1.27)
				)
				(justify mirror)
			)
		)
		(property "Value" ""
			(at 0 0 90)
			(layer "B.Fab")
			(effects
				(font
					(size 1.27 1.27)
				)
				(justify mirror)
			)
		)
		(duplicate_pad_numbers_are_jumpers no)
		(fp_poly
			(pts
				(xy 0.7239 -0.2159) (xy -0.7239 -0.2159) (xy -0.7239 1.9939) (xy 0.7239 1.9939)
			)
			(stroke
				(width 0)
				(type default)
			)
			(fill no)
			(layer "B.CrtYd")
		)
		(fp_line
			(start 0.7239 -0.2159)
			(end 0.7239 1.9939)
			(stroke
				(width 0.1)
				(type default)
			)
			(layer "B.Fab")
		)
		(fp_line
			(start -0.7239 -0.2159)
			(end 0.7239 -0.2159)
			(stroke
				(width 0.1)
				(type default)
			)
			(layer "B.Fab")
		)
		(fp_line
			(start 0.7239 1.9939)
			(end -0.7239 1.9939)
			(stroke
				(width 0.1)
				(type default)
			)
			(layer "B.Fab")
		)
		(fp_line
			(start -0.7239 1.9939)
			(end -0.7239 -0.2159)
			(stroke
				(width 0.1)
				(type default)
			)
			(layer "B.Fab")
		)
		(pad "1" smd rect
			(at 0 0 270)
			(size 1.27 1.016)
			(layers "B.Cu" "B.Mask" "B.Paste")
			(net "VR_FET_SW_P12V_STBY_PVCCIN_CPU1")
		)
		(pad "2" smd rect
			(at 0 1.778 270)
			(size 1.27 1.016)
			(layers "B.Cu" "B.Mask" "B.Paste")
			(net "GND")
		)
		(zone
			(layer "B.Cu")
			(hatch none 0.5)
			(connect_pads
				(clearance 0)
			)
			(min_thickness 0.25)
			(keepout
				(tracks not_allowed)
				(vias allowed)
				(pads allowed)
				(copperpour not_allowed)
				(footprints allowed)
			)
			(placement
				(enabled no)
				(sheetname "")
			)
			(fill
				(thermal_gap 0.5)
				(thermal_bridge_width 0.5)
				(island_removal_mode 0)
			)
			(polygon
				(pts
					(xy 33.340802 -89.793064) (xy 33.340802 -88.523064) (xy 34.102802 -88.523064) (xy 34.102802 -89.793064)
				)
			)
		)
	)
	(footprint ""
		(layer "B.Cu")
		(at 253.392432 -145.0086 90)
		(property "Reference" "C5L10"
			(at -1.848866 0.752348 90)
			(unlocked yes)
			(layer "B.SilkS")
			(effects
				(font
					(size 1.27 0.9652)
					(thickness 0.1524)
				)
				(justify mirror)
			)
		)
		(property "Value" ""
			(at 0 0 90)
			(layer "B.Fab")
			(effects
				(font
					(size 1.27 1.27)
				)
				(justify mirror)
			)
		)
		(duplicate_pad_numbers_are_jumpers no)
		(fp_rect
			(start 0.500126 1.598422)
			(end -0.500126 -0.201422)
			(stroke
				(width 0)
				(type default)
			)
			(fill no)
			(layer "B.CrtYd")
		)
		(fp_line
			(start 0.500126 -0.201422)
			(end -0.500126 -0.201422)
			(stroke
				(width 0.1)
				(type default)
			)
			(layer "B.Fab")
		)
		(fp_line
			(start -0.500126 -0.201422)
			(end -0.500126 1.598422)
			(stroke
				(width 0.1)
				(type default)
			)
			(layer "B.Fab")
		)
		(fp_line
			(start 0.500126 1.598422)
			(end 0.500126 -0.201422)
			(stroke
				(width 0.1)
				(type default)
			)
			(layer "B.Fab")
		)
		(fp_line
			(start -0.500126 1.598422)
			(end 0.500126 1.598422)
			(stroke
				(width 0.1)
				(type default)
			)
			(layer "B.Fab")
		)
		(pad "1" smd rect
			(at 0 0)
			(size 0.889 0.9906)
			(layers "B.Cu" "B.Mask" "B.Paste")
			(net "PVDDQ_DEF")
		)
		(pad "2" smd rect
			(at 0 1.397)
			(size 0.889 0.9906)
			(layers "B.Cu" "B.Mask" "B.Paste")
			(net "GND")
		)
		(zone
			(layer "B.Cu")
			(hatch none 0.5)
			(connect_pads
				(clearance 0)
			)
			(min_thickness 0.25)
			(keepout
				(tracks not_allowed)
				(vias allowed)
				(pads allowed)
				(copperpour not_allowed)
				(footprints allowed)
			)
			(placement
				(enabled no)
				(sheetname "")
			)
			(fill
				(thermal_gap 0.5)
				(thermal_bridge_width 0.5)
				(island_removal_mode 0)
			)
			(polygon
				(pts
					(xy 254.344932 -145.5039) (xy 253.836932 -145.5039) (xy 253.836932 -144.5133) (xy 254.344932 -144.5133)
				)
			)
		)
		(zone
			(layer "B.Cu")
			(hatch none 0.5)
			(connect_pads
				(clearance 0)
			)
			(min_thickness 0.25)
			(keepout
				(tracks allowed)
				(vias not_allowed)
				(pads allowed)
				(copperpour not_allowed)
				(footprints allowed)
			)
			(placement
				(enabled no)
				(sheetname "")
			)
			(fill
				(thermal_gap 0.5)
				(thermal_bridge_width 0.5)
				(island_removal_mode 0)
			)
			(polygon
				(pts
					(xy 254.344932 -145.5039) (xy 253.836932 -145.5039) (xy 253.836932 -144.5133) (xy 254.344932 -144.5133)
				)
			)
		)
	)
	(footprint ""
		(layer "B.Cu")
		(at 32.832802 -84.357464 90)
		(property "Reference" "C9P2"
			(at 0 0 90)
			(layer "B.SilkS")
			(hide yes)
			(effects
				(font
					(size 1.27 1.27)
				)
				(justify mirror)
			)
		)
		(property "Value" ""
			(at 0 0 90)
			(layer "B.Fab")
			(effects
				(font
					(size 1.27 1.27)
				)
				(justify mirror)
			)
		)
		(duplicate_pad_numbers_are_jumpers no)
		(fp_poly
			(pts
				(xy 0.7239 -0.2159) (xy -0.7239 -0.2159) (xy -0.7239 1.9939) (xy 0.7239 1.9939)
			)
			(stroke
				(width 0)
				(type default)
			)
			(fill no)
			(layer "B.CrtYd")
		)
		(fp_line
			(start 0.7239 -0.2159)
			(end 0.7239 1.9939)
			(stroke
				(width 0.1)
				(type default)
			)
			(layer "B.Fab")
		)
		(fp_line
			(start -0.7239 -0.2159)
			(end 0.7239 -0.2159)
			(stroke
				(width 0.1)
				(type default)
			)
			(layer "B.Fab")
		)
		(fp_line
			(start 0.7239 1.9939)
			(end -0.7239 1.9939)
			(stroke
				(width 0.1)
				(type default)
			)
			(layer "B.Fab")
		)
		(fp_line
			(start -0.7239 1.9939)
			(end -0.7239 -0.2159)
			(stroke
				(width 0.1)
				(type default)
			)
			(layer "B.Fab")
		)
		(pad "1" smd rect
			(at 0 0 270)
			(size 1.27 1.016)
			(layers "B.Cu" "B.Mask" "B.Paste")
			(net "VR_FET_SW_P12V_STBY_PVCCIN_CPU1")
		)
		(pad "2" smd rect
			(at 0 1.778 270)
			(size 1.27 1.016)
			(layers "B.Cu" "B.Mask" "B.Paste")
			(net "GND")
		)
		(zone
			(layer "B.Cu")
			(hatch none 0.5)
			(connect_pads
				(clearance 0)
			)
			(min_thickness 0.25)
			(keepout
				(tracks not_allowed)
				(vias allowed)
				(pads allowed)
				(copperpour not_allowed)
				(footprints allowed)
			)
			(placement
				(enabled no)
				(sheetname "")
			)
			(fill
				(thermal_gap 0.5)
				(thermal_bridge_width 0.5)
				(island_removal_mode 0)
			)
			(polygon
				(pts
					(xy 33.340802 -84.992464) (xy 33.340802 -83.722464) (xy 34.102802 -83.722464) (xy 34.102802 -84.992464)
				)
			)
		)
	)
	(footprint ""
		(layer "B.Cu")
		(at 446.024 -116.49202)
		(property "Reference" "C1M19"
			(at 0 0 0)
			(layer "B.SilkS")
			(hide yes)
			(effects
				(font
					(size 1.27 1.27)
				)
				(justify mirror)
			)
		)
		(property "Value" ""
			(at 0 0 0)
			(layer "B.Fab")
			(effects
				(font
					(size 1.27 1.27)
				)
				(justify mirror)
			)
		)
		(duplicate_pad_numbers_are_jumpers no)
		(fp_rect
			(start -0.3048 0.9906)
			(end 0.3048 -0.1016)
			(stroke
				(width 0)
				(type default)
			)
			(fill no)
			(layer "B.CrtYd")
		)
		(fp_line
			(start -0.3048 -0.1016)
			(end 0.3048 -0.1016)
			(stroke
				(width 0.1)
				(type default)
			)
			(layer "B.Fab")
		)
		(fp_line
			(start -0.3048 0.9906)
			(end -0.3048 -0.1016)
			(stroke
				(width 0.1)
				(type default)
			)
			(layer "B.Fab")
		)
		(fp_line
			(start 0.3048 -0.1016)
			(end 0.3048 0.9906)
			(stroke
				(width 0.1)
				(type default)
			)
			(layer "B.Fab")
		)
		(fp_line
			(start 0.3048 0.9906)
			(end -0.3048 0.9906)
			(stroke
				(width 0.1)
				(type default)
			)
			(layer "B.Fab")
		)
		(pad "1" smd rect
			(at 0 0 180)
			(size 0.508 0.508)
			(layers "B.Cu" "B.Mask" "B.Paste")
			(net "P3E_CPU0_PE3_OCP_TXN<9>")
		)
		(pad "2" smd rect
			(at 0 0.889 180)
			(size 0.508 0.508)
			(layers "B.Cu" "B.Mask" "B.Paste")
			(net "P3E_OCP_CPU0_PE3_C_TXN<9>")
		)
		(zone
			(layer "B.Cu")
			(hatch none 0.5)
			(connect_pads
				(clearance 0)
			)
			(min_thickness 0.25)
			(keepout
				(tracks allowed)
				(vias not_allowed)
				(pads allowed)
				(copperpour not_allowed)
				(footprints allowed)
			)
			(placement
				(enabled no)
				(sheetname "")
			)
			(fill
				(thermal_gap 0.5)
				(thermal_bridge_width 0.5)
				(island_removal_mode 0)
			)
			(polygon
				(pts
					(xy 445.77 -115.85702) (xy 446.278 -115.85702) (xy 446.278 -116.23802) (xy 445.77 -116.23802)
				)
			)
		)
		(zone
			(layer "B.Cu")
			(hatch none 0.5)
			(connect_pads
				(clearance 0)
			)
			(min_thickness 0.25)
			(keepout
				(tracks not_allowed)
				(vias allowed)
				(pads allowed)
				(copperpour not_allowed)
				(footprints allowed)
			)
			(placement
				(enabled no)
				(sheetname "")
			)
			(fill
				(thermal_gap 0.5)
				(thermal_bridge_width 0.5)
				(island_removal_mode 0)
			)
			(polygon
				(pts
					(xy 445.77 -115.85702) (xy 446.278 -115.85702) (xy 446.278 -116.23802) (xy 445.77 -116.23802)
				)
			)
		)
	)
	(footprint ""
		(layer "B.Cu")
		(at 245.815612 -125.55601 90)
		(property "Reference" "C5M11"
			(at 0 0 90)
			(layer "B.SilkS")
			(hide yes)
			(effects
				(font
					(size 1.27 1.27)
				)
				(justify mirror)
			)
		)
		(property "Value" ""
			(at 0 0 90)
			(layer "B.Fab")
			(effects
				(font
					(size 1.27 1.27)
				)
				(justify mirror)
			)
		)
		(duplicate_pad_numbers_are_jumpers no)
		(fp_rect
			(start 0.500126 1.598422)
			(end -0.500126 -0.201422)
			(stroke
				(width 0)
				(type default)
			)
			(fill no)
			(layer "B.CrtYd")
		)
		(fp_line
			(start 0.500126 -0.201422)
			(end -0.500126 -0.201422)
			(stroke
				(width 0.1)
				(type default)
			)
			(layer "B.Fab")
		)
		(fp_line
			(start -0.500126 -0.201422)
			(end -0.500126 1.598422)
			(stroke
				(width 0.1)
				(type default)
			)
			(layer "B.Fab")
		)
		(fp_line
			(start 0.500126 1.598422)
			(end 0.500126 -0.201422)
			(stroke
				(width 0.1)
				(type default)
			)
			(layer "B.Fab")
		)
		(fp_line
			(start -0.500126 1.598422)
			(end 0.500126 1.598422)
			(stroke
				(width 0.1)
				(type default)
			)
			(layer "B.Fab")
		)
		(pad "1" smd rect
			(at 0 0)
			(size 0.889 0.9906)
			(layers "B.Cu" "B.Mask" "B.Paste")
			(net "PVDDQ_DEF")
		)
		(pad "2" smd rect
			(at 0 1.397)
			(size 0.889 0.9906)
			(layers "B.Cu" "B.Mask" "B.Paste")
			(net "GND")
		)
		(zone
			(layer "B.Cu")
			(hatch none 0.5)
			(connect_pads
				(clearance 0)
			)
			(min_thickness 0.25)
			(keepout
				(tracks not_allowed)
				(vias allowed)
				(pads allowed)
				(copperpour not_allowed)
				(footprints allowed)
			)
			(placement
				(enabled no)
				(sheetname "")
			)
			(fill
				(thermal_gap 0.5)
				(thermal_bridge_width 0.5)
				(island_removal_mode 0)
			)
			(polygon
				(pts
					(xy 246.768112 -126.05131) (xy 246.260112 -126.05131) (xy 246.260112 -125.06071) (xy 246.768112 -125.06071)
				)
			)
		)
		(zone
			(layer "B.Cu")
			(hatch none 0.5)
			(connect_pads
				(clearance 0)
			)
			(min_thickness 0.25)
			(keepout
				(tracks allowed)
				(vias not_allowed)
				(pads allowed)
				(copperpour not_allowed)
				(footprints allowed)
			)
			(placement
				(enabled no)
				(sheetname "")
			)
			(fill
				(thermal_gap 0.5)
				(thermal_bridge_width 0.5)
				(island_removal_mode 0)
			)
			(polygon
				(pts
					(xy 246.768112 -126.05131) (xy 246.260112 -126.05131) (xy 246.260112 -125.06071) (xy 246.768112 -125.06071)
				)
			)
		)
	)
	(footprint ""
		(layer "B.Cu")
		(at 351.536 -34.798 -90)
		(property "Reference" "C3T3"
			(at 3.45567 5.207 0)
			(unlocked yes)
			(layer "B.SilkS")
			(effects
				(font
					(size 0.7874 0.5842)
					(thickness 0.1524)
				)
				(justify mirror)
			)
		)
		(property "Value" ""
			(at 0 0 90)
			(layer "B.Fab")
			(effects
				(font
					(size 1.27 1.27)
				)
				(justify mirror)
			)
		)
		(duplicate_pad_numbers_are_jumpers no)
		(fp_line
			(start -2.286 7.366)
			(end -1.600708 7.366)
			(stroke
				(width 0.1524)
				(type default)
			)
			(layer "B.SilkS")
		)
		(fp_line
			(start -2.286 7.366)
			(end -2.286 1.63195)
			(stroke
				(width 0.1524)
				(type default)
			)
			(layer "B.SilkS")
		)
		(fp_line
			(start 2.286 7.366)
			(end 1.60147 7.366)
			(stroke
				(width 0.1524)
				(type default)
			)
			(layer "B.SilkS")
		)
		(fp_line
			(start 2.286 7.366)
			(end 2.286 1.632712)
			(stroke
				(width 0.1524)
				(type default)
			)
			(layer "B.SilkS")
		)
		(fp_line
			(start -2.504948 1.633728)
			(end -1.6002 1.633728)
			(stroke
				(width 0.1524)
				(type default)
			)
			(layer "B.SilkS")
		)
		(fp_line
			(start 2.563114 1.633728)
			(end 1.6002 1.633728)
			(stroke
				(width 0.1524)
				(type default)
			)
			(layer "B.SilkS")
		)
		(fp_line
			(start -2.504948 -1.616456)
			(end -2.504948 1.633728)
			(stroke
				(width 0.1524)
				(type default)
			)
			(layer "B.SilkS")
		)
		(fp_line
			(start -1.6002 -1.616456)
			(end -2.504948 -1.616456)
			(stroke
				(width 0.1524)
				(type default)
			)
			(layer "B.SilkS")
		)
		(fp_line
			(start 1.6002 -1.616456)
			(end 2.563114 -1.616456)
			(stroke
				(width 0.1524)
				(type default)
			)
			(layer "B.SilkS")
		)
		(fp_line
			(start 2.563114 -1.616456)
			(end 2.563114 1.633728)
			(stroke
				(width 0.1524)
				(type default)
			)
			(layer "B.SilkS")
		)
		(fp_rect
			(start 2.286 7.366)
			(end -2.286 -0.254)
			(stroke
				(width 0)
				(type default)
			)
			(fill no)
			(layer "B.CrtYd")
		)
		(fp_line
			(start -2.286 7.366)
			(end 2.286 7.366)
			(stroke
				(width 0.1)
				(type default)
			)
			(layer "B.Fab")
		)
		(fp_line
			(start 2.286 7.366)
			(end 2.286 -0.254)
			(stroke
				(width 0.1)
				(type default)
			)
			(layer "B.Fab")
		)
		(fp_line
			(start -2.286 -0.254)
			(end -2.286 7.366)
			(stroke
				(width 0.1)
				(type default)
			)
			(layer "B.Fab")
		)
		(fp_line
			(start 2.286 -0.254)
			(end -2.286 -0.254)
			(stroke
				(width 0.1)
				(type default)
			)
			(layer "B.Fab")
		)
		(pad "1" smd rect
			(at 0 0 90)
			(size 2.54 3.048)
			(layers "B.Cu" "B.Mask" "B.Paste")
			(net "P12V_STBY")
		)
		(pad "2" smd rect
			(at 0 7.112 90)
			(size 2.54 3.048)
			(layers "B.Cu" "B.Mask" "B.Paste")
			(net "GND")
		)
	)
	(footprint ""
		(layer "B.Cu")
		(at 456.7936 -142.9004)
		(property "Reference" "R1L29"
			(at 0 0 0)
			(layer "B.SilkS")
			(hide yes)
			(effects
				(font
					(size 1.27 1.27)
				)
				(justify mirror)
			)
		)
		(property "Value" ""
			(at 0 0 0)
			(layer "B.Fab")
			(effects
				(font
					(size 1.27 1.27)
				)
				(justify mirror)
			)
		)
		(duplicate_pad_numbers_are_jumpers no)
		(fp_poly
			(pts
				(xy 0.2794 -0.1016) (xy -0.2794 -0.1016) (xy -0.2794 0.9906) (xy 0.2794 0.9906)
			)
			(stroke
				(width 0)
				(type default)
			)
			(fill no)
			(layer "B.CrtYd")
		)
		(fp_line
			(start -0.2794 -0.1016)
			(end 0.2794 -0.1016)
			(stroke
				(width 0.1)
				(type default)
			)
			(layer "B.Fab")
		)
		(fp_line
			(start -0.2794 0.9906)
			(end -0.2794 -0.1016)
			(stroke
				(width 0.1)
				(type default)
			)
			(layer "B.Fab")
		)
		(fp_line
			(start 0.2794 -0.1016)
			(end 0.2794 0.9906)
			(stroke
				(width 0.1)
				(type default)
			)
			(layer "B.Fab")
		)
		(fp_line
			(start 0.2794 0.9906)
			(end -0.2794 0.9906)
			(stroke
				(width 0.1)
				(type default)
			)
			(layer "B.Fab")
		)
		(pad "1" smd rect
			(at 0 0 180)
			(size 0.508 0.508)
			(layers "B.Cu" "B.Mask" "B.Paste")
			(net "FM_DEBUG_RST_BTN_R1_N")
		)
		(pad "2" smd rect
			(at 0 0.889 180)
			(size 0.508 0.508)
			(layers "B.Cu" "B.Mask" "B.Paste")
			(net "FM_DEBUG_RST_BTN_N")
		)
		(zone
			(layer "B.Cu")
			(hatch none 0.5)
			(connect_pads
				(clearance 0)
			)
			(min_thickness 0.25)
			(keepout
				(tracks allowed)
				(vias not_allowed)
				(pads allowed)
				(copperpour not_allowed)
				(footprints allowed)
			)
			(placement
				(enabled no)
				(sheetname "")
			)
			(fill
				(thermal_gap 0.5)
				(thermal_bridge_width 0.5)
				(island_removal_mode 0)
			)
			(polygon
				(pts
					(xy 457.0476 -142.6464) (xy 456.5396 -142.6464) (xy 456.5396 -142.2654) (xy 457.0476 -142.2654)
				)
			)
		)
		(zone
			(layer "B.Cu")
			(hatch none 0.5)
			(connect_pads
				(clearance 0)
			)
			(min_thickness 0.25)
			(keepout
				(tracks not_allowed)
				(vias allowed)
				(pads allowed)
				(copperpour not_allowed)
				(footprints allowed)
			)
			(placement
				(enabled no)
				(sheetname "")
			)
			(fill
				(thermal_gap 0.5)
				(thermal_bridge_width 0.5)
				(island_removal_mode 0)
			)
			(polygon
				(pts
					(xy 457.0476 -142.2654) (xy 456.5396 -142.2654) (xy 456.5396 -142.6464) (xy 457.0476 -142.6464)
				)
			)
		)
	)
	(footprint ""
		(layer "B.Cu")
		(at 252.1585 -145.0086 -90)
		(property "Reference" "C5L11"
			(at -1.848866 0.752348 270)
			(unlocked yes)
			(layer "B.SilkS")
			(effects
				(font
					(size 1.27 0.9652)
					(thickness 0.1524)
				)
				(justify mirror)
			)
		)
		(property "Value" ""
			(at 0 0 90)
			(layer "B.Fab")
			(effects
				(font
					(size 1.27 1.27)
				)
				(justify mirror)
			)
		)
		(duplicate_pad_numbers_are_jumpers no)
		(fp_rect
			(start 0.500126 1.598422)
			(end -0.500126 -0.201422)
			(stroke
				(width 0)
				(type default)
			)
			(fill no)
			(layer "B.CrtYd")
		)
		(fp_line
			(start -0.500126 1.598422)
			(end 0.500126 1.598422)
			(stroke
				(width 0.1)
				(type default)
			)
			(layer "B.Fab")
		)
		(fp_line
			(start 0.500126 1.598422)
			(end 0.500126 -0.201422)
			(stroke
				(width 0.1)
				(type default)
			)
			(layer "B.Fab")
		)
		(fp_line
			(start -0.500126 -0.201422)
			(end -0.500126 1.598422)
			(stroke
				(width 0.1)
				(type default)
			)
			(layer "B.Fab")
		)
		(fp_line
			(start 0.500126 -0.201422)
			(end -0.500126 -0.201422)
			(stroke
				(width 0.1)
				(type default)
			)
			(layer "B.Fab")
		)
		(pad "1" smd rect
			(at 0 0 180)
			(size 0.889 0.9906)
			(layers "B.Cu" "B.Mask" "B.Paste")
			(net "PVDDQ_DEF")
		)
		(pad "2" smd rect
			(at 0 1.397 180)
			(size 0.889 0.9906)
			(layers "B.Cu" "B.Mask" "B.Paste")
			(net "GND")
		)
		(zone
			(layer "B.Cu")
			(hatch none 0.5)
			(connect_pads
				(clearance 0)
			)
			(min_thickness 0.25)
			(keepout
				(tracks allowed)
				(vias not_allowed)
				(pads allowed)
				(copperpour not_allowed)
				(footprints allowed)
			)
			(placement
				(enabled no)
				(sheetname "")
			)
			(fill
				(thermal_gap 0.5)
				(thermal_bridge_width 0.5)
				(island_removal_mode 0)
			)
			(polygon
				(pts
					(xy 251.206 -144.5133) (xy 251.714 -144.5133) (xy 251.714 -145.5039) (xy 251.206 -145.5039)
				)
			)
		)
		(zone
			(layer "B.Cu")
			(hatch none 0.5)
			(connect_pads
				(clearance 0)
			)
			(min_thickness 0.25)
			(keepout
				(tracks not_allowed)
				(vias allowed)
				(pads allowed)
				(copperpour not_allowed)
				(footprints allowed)
			)
			(placement
				(enabled no)
				(sheetname "")
			)
			(fill
				(thermal_gap 0.5)
				(thermal_bridge_width 0.5)
				(island_removal_mode 0)
			)
			(polygon
				(pts
					(xy 251.206 -144.5133) (xy 251.714 -144.5133) (xy 251.714 -145.5039) (xy 251.206 -145.5039)
				)
			)
		)
	)
	(footprint ""
		(layer "B.Cu")
		(at 447.157094 -23.642574 -90)
		(property "Reference" "R8W5"
			(at 0.8382 -0.67818 270)
			(unlocked yes)
			(layer "B.SilkS")
			(effects
				(font
					(size 0.4064 0.254)
					(thickness 0.1524)
				)
				(justify left mirror)
			)
		)
		(property "Value" ""
			(at 0 0 90)
			(layer "B.Fab")
			(effects
				(font
					(size 1.27 1.27)
				)
				(justify mirror)
			)
		)
		(duplicate_pad_numbers_are_jumpers no)
		(fp_poly
			(pts
				(xy 0.2794 -0.1016) (xy -0.2794 -0.1016) (xy -0.2794 0.9906) (xy 0.2794 0.9906)
			)
			(stroke
				(width 0)
				(type default)
			)
			(fill no)
			(layer "B.CrtYd")
		)
		(fp_line
			(start -0.2794 0.9906)
			(end -0.2794 -0.1016)
			(stroke
				(width 0.1)
				(type default)
			)
			(layer "B.Fab")
		)
		(fp_line
			(start 0.2794 0.9906)
			(end -0.2794 0.9906)
			(stroke
				(width 0.1)
				(type default)
			)
			(layer "B.Fab")
		)
		(fp_line
			(start -0.2794 -0.1016)
			(end 0.2794 -0.1016)
			(stroke
				(width 0.1)
				(type default)
			)
			(layer "B.Fab")
		)
		(fp_line
			(start 0.2794 -0.1016)
			(end 0.2794 0.9906)
			(stroke
				(width 0.1)
				(type default)
			)
			(layer "B.Fab")
		)
		(pad "1" smd rect
			(at 0 0 90)
			(size 0.508 0.508)
			(layers "B.Cu" "B.Mask" "B.Paste")
			(net "SMB_HOST_STBY_LVC3_SCL")
		)
		(pad "2" smd rect
			(at 0 0.889 90)
			(size 0.508 0.508)
			(layers "B.Cu" "B.Mask" "B.Paste")
			(net "SMB_HOST_STBY_LVC3_SCL_R5")
		)
		(zone
			(layer "B.Cu")
			(hatch none 0.5)
			(connect_pads
				(clearance 0)
			)
			(min_thickness 0.25)
			(keepout
				(tracks not_allowed)
				(vias allowed)
				(pads allowed)
				(copperpour not_allowed)
				(footprints allowed)
			)
			(placement
				(enabled no)
				(sheetname "")
			)
			(fill
				(thermal_gap 0.5)
				(thermal_bridge_width 0.5)
				(island_removal_mode 0)
			)
			(polygon
				(pts
					(xy 446.522094 -23.388574) (xy 446.522094 -23.896574) (xy 446.903094 -23.896574) (xy 446.903094 -23.388574)
				)
			)
		)
		(zone
			(layer "B.Cu")
			(hatch none 0.5)
			(connect_pads
				(clearance 0)
			)
			(min_thickness 0.25)
			(keepout
				(tracks allowed)
				(vias not_allowed)
				(pads allowed)
				(copperpour not_allowed)
				(footprints allowed)
			)
			(placement
				(enabled no)
				(sheetname "")
			)
			(fill
				(thermal_gap 0.5)
				(thermal_bridge_width 0.5)
				(island_removal_mode 0)
			)
			(polygon
				(pts
					(xy 446.903094 -23.388574) (xy 446.903094 -23.896574) (xy 446.522094 -23.896574) (xy 446.522094 -23.388574)
				)
			)
		)
	)
	(footprint ""
		(layer "B.Cu")
		(at 411.0355 -130.6068 90)
		(property "Reference" "C2M1"
			(at 0 0 90)
			(layer "B.SilkS")
			(hide yes)
			(effects
				(font
					(size 1.27 1.27)
				)
				(justify mirror)
			)
		)
		(property "Value" ""
			(at 0 0 90)
			(layer "B.Fab")
			(effects
				(font
					(size 1.27 1.27)
				)
				(justify mirror)
			)
		)
		(duplicate_pad_numbers_are_jumpers no)
		(fp_poly
			(pts
				(xy 0.4953 -0.2032) (xy -0.4953 -0.2032) (xy -0.4953 1.6002) (xy 0.4953 1.6002)
			)
			(stroke
				(width 0)
				(type default)
			)
			(fill no)
			(layer "B.CrtYd")
		)
		(fp_line
			(start 0.4953 -0.2032)
			(end -0.4953 -0.2032)
			(stroke
				(width 0.1)
				(type default)
			)
			(layer "B.Fab")
		)
		(fp_line
			(start -0.4953 -0.2032)
			(end -0.4953 1.6002)
			(stroke
				(width 0.1)
				(type default)
			)
			(layer "B.Fab")
		)
		(fp_line
			(start 0.4953 1.6002)
			(end 0.4953 -0.2032)
			(stroke
				(width 0.1)
				(type default)
			)
			(layer "B.Fab")
		)
		(fp_line
			(start -0.4953 1.6002)
			(end 0.4953 1.6002)
			(stroke
				(width 0.1)
				(type default)
			)
			(layer "B.Fab")
		)
		(pad "1" smd rect
			(at 0 0 270)
			(size 0.762 0.889)
			(layers "B.Cu" "B.Mask" "B.Paste")
			(net "P1V8_PCH_STBY")
		)
		(pad "2" smd rect
			(at 0 1.397 270)
			(size 0.762 0.889)
			(layers "B.Cu" "B.Mask" "B.Paste")
			(net "GND")
		)
		(zone
			(layer "B.Cu")
			(hatch none 0.5)
			(connect_pads
				(clearance 0)
			)
			(min_thickness 0.25)
			(keepout
				(tracks not_allowed)
				(vias allowed)
				(pads allowed)
				(copperpour not_allowed)
				(footprints allowed)
			)
			(placement
				(enabled no)
				(sheetname "")
			)
			(fill
				(thermal_gap 0.5)
				(thermal_bridge_width 0.5)
				(island_removal_mode 0)
			)
			(polygon
				(pts
					(xy 411.48 -130.9878) (xy 411.48 -130.2258) (xy 411.988 -130.2258) (xy 411.988 -130.9878)
				)
			)
		)
	)
	(footprint ""
		(layer "B.Cu")
		(at 334.01 -150.368 90)
		(property "Reference" "C3L14"
			(at -2.18567 9.525 0)
			(unlocked yes)
			(layer "B.SilkS")
			(effects
				(font
					(size 0.7874 0.5842)
					(thickness 0.1524)
				)
				(justify mirror)
			)
		)
		(property "Value" ""
			(at 0 0 90)
			(layer "B.Fab")
			(effects
				(font
					(size 1.27 1.27)
				)
				(justify mirror)
			)
		)
		(duplicate_pad_numbers_are_jumpers no)
		(fp_line
			(start 2.563114 -1.616456)
			(end 2.563114 1.633728)
			(stroke
				(width 0.1524)
				(type default)
			)
			(layer "B.SilkS")
		)
		(fp_line
			(start 1.6002 -1.616456)
			(end 2.563114 -1.616456)
			(stroke
				(width 0.1524)
				(type default)
			)
			(layer "B.SilkS")
		)
		(fp_line
			(start -1.6002 -1.616456)
			(end -2.504948 -1.616456)
			(stroke
				(width 0.1524)
				(type default)
			)
			(layer "B.SilkS")
		)
		(fp_line
			(start -2.504948 -1.616456)
			(end -2.504948 1.633728)
			(stroke
				(width 0.1524)
				(type default)
			)
			(layer "B.SilkS")
		)
		(fp_line
			(start 2.563114 1.633728)
			(end 1.6002 1.633728)
			(stroke
				(width 0.1524)
				(type default)
			)
			(layer "B.SilkS")
		)
		(fp_line
			(start -2.504948 1.633728)
			(end -1.6002 1.633728)
			(stroke
				(width 0.1524)
				(type default)
			)
			(layer "B.SilkS")
		)
		(fp_line
			(start 2.286 7.366)
			(end 2.286 1.632712)
			(stroke
				(width 0.1524)
				(type default)
			)
			(layer "B.SilkS")
		)
		(fp_line
			(start 2.286 7.366)
			(end 1.60147 7.366)
			(stroke
				(width 0.1524)
				(type default)
			)
			(layer "B.SilkS")
		)
		(fp_line
			(start -2.286 7.366)
			(end -2.286 1.63195)
			(stroke
				(width 0.1524)
				(type default)
			)
			(layer "B.SilkS")
		)
		(fp_line
			(start -2.286 7.366)
			(end -1.600708 7.366)
			(stroke
				(width 0.1524)
				(type default)
			)
			(layer "B.SilkS")
		)
		(fp_rect
			(start 2.286 7.366)
			(end -2.286 -0.254)
			(stroke
				(width 0)
				(type default)
			)
			(fill no)
			(layer "B.CrtYd")
		)
		(fp_line
			(start 2.286 -0.254)
			(end -2.286 -0.254)
			(stroke
				(width 0.1)
				(type default)
			)
			(layer "B.Fab")
		)
		(fp_line
			(start -2.286 -0.254)
			(end -2.286 7.366)
			(stroke
				(width 0.1)
				(type default)
			)
			(layer "B.Fab")
		)
		(fp_line
			(start 2.286 7.366)
			(end 2.286 -0.254)
			(stroke
				(width 0.1)
				(type default)
			)
			(layer "B.Fab")
		)
		(fp_line
			(start -2.286 7.366)
			(end 2.286 7.366)
			(stroke
				(width 0.1)
				(type default)
			)
			(layer "B.Fab")
		)
		(pad "1" smd rect
			(at 0 0 270)
			(size 2.54 3.048)
			(layers "B.Cu" "B.Mask" "B.Paste")
			(net "PVDDQ_DEF")
		)
		(pad "2" smd rect
			(at 0 7.112 270)
			(size 2.54 3.048)
			(layers "B.Cu" "B.Mask" "B.Paste")
			(net "GND")
		)
	)
	(footprint ""
		(layer "B.Cu")
		(at 266.7762 -124.6886 90)
		(property "Reference" "SH4L2"
			(at 0 0 90)
			(layer "B.SilkS")
			(hide yes)
			(effects
				(font
					(size 1.27 1.27)
				)
				(justify mirror)
			)
		)
		(property "Value" ""
			(at 0 0 90)
			(layer "B.Fab")
			(effects
				(font
					(size 1.27 1.27)
				)
				(justify mirror)
			)
		)
		(duplicate_pad_numbers_are_jumpers no)
		(fp_poly
			(pts
				(xy 0.1651 -0.0508) (xy 0.1651 0.5842) (xy -0.1651 0.5842) (xy -0.1651 -0.0508)
			)
			(stroke
				(width 0)
				(type default)
			)
			(fill no)
			(layer "B.CrtYd")
		)
		(fp_line
			(start 0.1651 -0.0508)
			(end -0.1651 -0.0508)
			(stroke
				(width 0.1)
				(type default)
			)
			(layer "B.Fab")
		)
		(fp_line
			(start -0.1651 -0.0508)
			(end -0.1651 0.5842)
			(stroke
				(width 0.1)
				(type default)
			)
			(layer "B.Fab")
		)
		(fp_line
			(start 0.1651 0.5842)
			(end 0.1651 -0.0508)
			(stroke
				(width 0.1)
				(type default)
			)
			(layer "B.Fab")
		)
		(fp_line
			(start -0.1651 0.5842)
			(end 0.1651 0.5842)
			(stroke
				(width 0.1)
				(type default)
			)
			(layer "B.Fab")
		)
		(pad "1" smd custom
			(at 0 0 90)
			(size 0.0762 0.0762)
			(layers "B.Cu" "B.Mask" "B.Paste")
			(net "VSENSE_PVDDQ_DEF_P")
			(options
				(clearance outline)
				(anchor circle)
			)
			(primitives
				(gr_poly
					(pts
						(arc
							(start -0.1524 0.10795)
							(mid -0.098518 0.130268)
							(end -0.0762 0.18415)
						)
						(xy -0.0762 0.22225) (xy 0.0762 0.22225)
						(arc
							(start 0.0762 0.18415)
							(mid 0.098518 0.130268)
							(end 0.1524 0.10795)
						)
						(xy 0.1524 -0.22225) (xy -0.1524 -0.22225)
					)
					(width 0)
					(fill yes)
				)
			)
		)
		(pad "2" smd custom
			(at 0 0.5334 270)
			(size 0.0762 0.0762)
			(layers "B.Cu" "B.Mask" "B.Paste")
			(net "PVDDQ_DEF")
			(options
				(clearance outline)
				(anchor circle)
			)
			(primitives
				(gr_poly
					(pts
						(arc
							(start -0.1524 0.10795)
							(mid -0.098518 0.130268)
							(end -0.0762 0.18415)
						)
						(xy -0.0762 0.22225) (xy 0.0762 0.22225)
						(arc
							(start 0.0762 0.18415)
							(mid 0.098518 0.130268)
							(end 0.1524 0.10795)
						)
						(xy 0.1524 -0.22225) (xy -0.1524 -0.22225)
					)
					(width 0)
					(fill yes)
				)
			)
		)
	)
	(footprint ""
		(layer "B.Cu")
		(at 449.3895 -21.48078)
		(property "Reference" "R3W3"
			(at 0.8382 -0.67818 0)
			(unlocked yes)
			(layer "B.SilkS")
			(effects
				(font
					(size 0.4064 0.254)
					(thickness 0.1524)
				)
				(justify left mirror)
			)
		)
		(property "Value" ""
			(at 0 0 0)
			(layer "B.Fab")
			(effects
				(font
					(size 1.27 1.27)
				)
				(justify mirror)
			)
		)
		(duplicate_pad_numbers_are_jumpers no)
		(fp_poly
			(pts
				(xy 0.2794 -0.1016) (xy -0.2794 -0.1016) (xy -0.2794 0.9906) (xy 0.2794 0.9906)
			)
			(stroke
				(width 0)
				(type default)
			)
			(fill no)
			(layer "B.CrtYd")
		)
		(fp_line
			(start -0.2794 -0.1016)
			(end 0.2794 -0.1016)
			(stroke
				(width 0.1)
				(type default)
			)
			(layer "B.Fab")
		)
		(fp_line
			(start -0.2794 0.9906)
			(end -0.2794 -0.1016)
			(stroke
				(width 0.1)
				(type default)
			)
			(layer "B.Fab")
		)
		(fp_line
			(start 0.2794 -0.1016)
			(end 0.2794 0.9906)
			(stroke
				(width 0.1)
				(type default)
			)
			(layer "B.Fab")
		)
		(fp_line
			(start 0.2794 0.9906)
			(end -0.2794 0.9906)
			(stroke
				(width 0.1)
				(type default)
			)
			(layer "B.Fab")
		)
		(pad "1" smd rect
			(at 0 0 180)
			(size 0.508 0.508)
			(layers "B.Cu" "B.Mask" "B.Paste")
			(net "P3V3_STBY")
		)
		(pad "2" smd rect
			(at 0 0.889 180)
			(size 0.508 0.508)
			(layers "B.Cu" "B.Mask" "B.Paste")
			(net "FM_TPM_PRES_RST_N")
		)
		(zone
			(layer "B.Cu")
			(hatch none 0.5)
			(connect_pads
				(clearance 0)
			)
			(min_thickness 0.25)
			(keepout
				(tracks allowed)
				(vias not_allowed)
				(pads allowed)
				(copperpour not_allowed)
				(footprints allowed)
			)
			(placement
				(enabled no)
				(sheetname "")
			)
			(fill
				(thermal_gap 0.5)
				(thermal_bridge_width 0.5)
				(island_removal_mode 0)
			)
			(polygon
				(pts
					(xy 449.6435 -21.22678) (xy 449.1355 -21.22678) (xy 449.1355 -20.84578) (xy 449.6435 -20.84578)
				)
			)
		)
		(zone
			(layer "B.Cu")
			(hatch none 0.5)
			(connect_pads
				(clearance 0)
			)
			(min_thickness 0.25)
			(keepout
				(tracks not_allowed)
				(vias allowed)
				(pads allowed)
				(copperpour not_allowed)
				(footprints allowed)
			)
			(placement
				(enabled no)
				(sheetname "")
			)
			(fill
				(thermal_gap 0.5)
				(thermal_bridge_width 0.5)
				(island_removal_mode 0)
			)
			(polygon
				(pts
					(xy 449.6435 -20.84578) (xy 449.1355 -20.84578) (xy 449.1355 -21.22678) (xy 449.6435 -21.22678)
				)
			)
		)
	)
	(footprint ""
		(layer "B.Cu")
		(at 332.028038 -37.815266)
		(property "Reference" "C4T1"
			(at 0 0 0)
			(layer "B.SilkS")
			(hide yes)
			(effects
				(font
					(size 1.27 1.27)
				)
				(justify mirror)
			)
		)
		(property "Value" ""
			(at 0 0 0)
			(layer "B.Fab")
			(effects
				(font
					(size 1.27 1.27)
				)
				(justify mirror)
			)
		)
		(duplicate_pad_numbers_are_jumpers no)
		(fp_poly
			(pts
				(xy -0.3048 -0.1016) (xy -0.3048 0.9906) (xy 0.3048 0.9906) (xy 0.3048 -0.1016)
			)
			(stroke
				(width 0)
				(type default)
			)
			(fill no)
			(layer "B.CrtYd")
		)
		(fp_line
			(start -0.3048 -0.1016)
			(end 0.3048 -0.1016)
			(stroke
				(width 0.1)
				(type default)
			)
			(layer "B.Fab")
		)
		(fp_line
			(start -0.3048 0.9906)
			(end -0.3048 -0.1016)
			(stroke
				(width 0.1)
				(type default)
			)
			(layer "B.Fab")
		)
		(fp_line
			(start 0.3048 -0.1016)
			(end 0.3048 0.9906)
			(stroke
				(width 0.1)
				(type default)
			)
			(layer "B.Fab")
		)
		(fp_line
			(start 0.3048 0.9906)
			(end -0.3048 0.9906)
			(stroke
				(width 0.1)
				(type default)
			)
			(layer "B.Fab")
		)
		(pad "1" smd rect
			(at 0 0 180)
			(size 0.508 0.508)
			(layers "B.Cu" "B.Mask" "B.Paste")
			(net "P1V8_MCP_CPU0")
		)
		(pad "2" smd rect
			(at 0 0.889 180)
			(size 0.508 0.508)
			(layers "B.Cu" "B.Mask" "B.Paste")
			(net "GND")
		)
		(zone
			(layer "B.Cu")
			(hatch none 0.5)
			(connect_pads
				(clearance 0)
			)
			(min_thickness 0.25)
			(keepout
				(tracks allowed)
				(vias not_allowed)
				(pads allowed)
				(copperpour not_allowed)
				(footprints allowed)
			)
			(placement
				(enabled no)
				(sheetname "")
			)
			(fill
				(thermal_gap 0.5)
				(thermal_bridge_width 0.5)
				(island_removal_mode 0)
			)
			(polygon
				(pts
					(xy 332.282038 -37.561266) (xy 331.774038 -37.561266) (xy 331.774038 -37.180266) (xy 332.282038 -37.180266)
				)
			)
		)
		(zone
			(layer "B.Cu")
			(hatch none 0.5)
			(connect_pads
				(clearance 0)
			)
			(min_thickness 0.25)
			(keepout
				(tracks not_allowed)
				(vias allowed)
				(pads allowed)
				(copperpour not_allowed)
				(footprints allowed)
			)
			(placement
				(enabled no)
				(sheetname "")
			)
			(fill
				(thermal_gap 0.5)
				(thermal_bridge_width 0.5)
				(island_removal_mode 0)
			)
			(polygon
				(pts
					(xy 332.282038 -37.180266) (xy 331.774038 -37.180266) (xy 331.774038 -37.561266) (xy 332.282038 -37.561266)
				)
			)
		)
	)
	(footprint ""
		(layer "B.Cu")
		(at 393.2047 -10.01903 180)
		(property "Reference" "R32W11"
			(at 0.8382 -0.67818 180)
			(unlocked yes)
			(layer "B.SilkS")
			(effects
				(font
					(size 0.4064 0.254)
					(thickness 0.1524)
				)
				(justify left mirror)
			)
		)
		(property "Value" ""
			(at 0 0 0)
			(layer "B.Fab")
			(effects
				(font
					(size 1.27 1.27)
				)
				(justify mirror)
			)
		)
		(duplicate_pad_numbers_are_jumpers no)
		(fp_poly
			(pts
				(xy 0.2794 -0.1016) (xy -0.2794 -0.1016) (xy -0.2794 0.9906) (xy 0.2794 0.9906)
			)
			(stroke
				(width 0)
				(type default)
			)
			(fill no)
			(layer "B.CrtYd")
		)
		(fp_line
			(start 0.2794 0.9906)
			(end -0.2794 0.9906)
			(stroke
				(width 0.1)
				(type default)
			)
			(layer "B.Fab")
		)
		(fp_line
			(start 0.2794 -0.1016)
			(end 0.2794 0.9906)
			(stroke
				(width 0.1)
				(type default)
			)
			(layer "B.Fab")
		)
		(fp_line
			(start -0.2794 0.9906)
			(end -0.2794 -0.1016)
			(stroke
				(width 0.1)
				(type default)
			)
			(layer "B.Fab")
		)
		(fp_line
			(start -0.2794 -0.1016)
			(end 0.2794 -0.1016)
			(stroke
				(width 0.1)
				(type default)
			)
			(layer "B.Fab")
		)
		(pad "1" smd rect
			(at 0 0)
			(size 0.508 0.508)
			(layers "B.Cu" "B.Mask" "B.Paste")
			(net "SMB_M2_SDA")
		)
		(pad "2" smd rect
			(at 0 0.889)
			(size 0.508 0.508)
			(layers "B.Cu" "B.Mask" "B.Paste")
			(net "SMB_M2_SDA_R")
		)
		(zone
			(layer "B.Cu")
			(hatch none 0.5)
			(connect_pads
				(clearance 0)
			)
			(min_thickness 0.25)
			(keepout
				(tracks not_allowed)
				(vias allowed)
				(pads allowed)
				(copperpour not_allowed)
				(footprints allowed)
			)
			(placement
				(enabled no)
				(sheetname "")
			)
			(fill
				(thermal_gap 0.5)
				(thermal_bridge_width 0.5)
				(island_removal_mode 0)
			)
			(polygon
				(pts
					(xy 392.9507 -10.65403) (xy 393.4587 -10.65403) (xy 393.4587 -10.27303) (xy 392.9507 -10.27303)
				)
			)
		)
		(zone
			(layer "B.Cu")
			(hatch none 0.5)
			(connect_pads
				(clearance 0)
			)
			(min_thickness 0.25)
			(keepout
				(tracks allowed)
				(vias not_allowed)
				(pads allowed)
				(copperpour not_allowed)
				(footprints allowed)
			)
			(placement
				(enabled no)
				(sheetname "")
			)
			(fill
				(thermal_gap 0.5)
				(thermal_bridge_width 0.5)
				(island_removal_mode 0)
			)
			(polygon
				(pts
					(xy 392.9507 -10.27303) (xy 393.4587 -10.27303) (xy 393.4587 -10.65403) (xy 392.9507 -10.65403)
				)
			)
		)
	)
	(footprint ""
		(layer "B.Cu")
		(at 354.597208 -89.97188 180)
		(property "Reference" "R3N21"
			(at 0 0 0)
			(layer "B.SilkS")
			(hide yes)
			(effects
				(font
					(size 1.27 1.27)
				)
				(justify mirror)
			)
		)
		(property "Value" ""
			(at 0 0 0)
			(layer "B.Fab")
			(effects
				(font
					(size 1.27 1.27)
				)
				(justify mirror)
			)
		)
		(duplicate_pad_numbers_are_jumpers no)
		(fp_poly
			(pts
				(xy 0.2794 -0.1016) (xy -0.2794 -0.1016) (xy -0.2794 0.9906) (xy 0.2794 0.9906)
			)
			(stroke
				(width 0)
				(type default)
			)
			(fill no)
			(layer "B.CrtYd")
		)
		(fp_line
			(start 0.2794 0.9906)
			(end -0.2794 0.9906)
			(stroke
				(width 0.1)
				(type default)
			)
			(layer "B.Fab")
		)
		(fp_line
			(start 0.2794 -0.1016)
			(end 0.2794 0.9906)
			(stroke
				(width 0.1)
				(type default)
			)
			(layer "B.Fab")
		)
		(fp_line
			(start -0.2794 0.9906)
			(end -0.2794 -0.1016)
			(stroke
				(width 0.1)
				(type default)
			)
			(layer "B.Fab")
		)
		(fp_line
			(start -0.2794 -0.1016)
			(end 0.2794 -0.1016)
			(stroke
				(width 0.1)
				(type default)
			)
			(layer "B.Fab")
		)
		(pad "1" smd rect
			(at 0 0)
			(size 0.508 0.508)
			(layers "B.Cu" "B.Mask" "B.Paste")
			(net "VSENSE_PVCCIO_CPU0_AVSP")
		)
		(pad "2" smd rect
			(at 0 0.889)
			(size 0.508 0.508)
			(layers "B.Cu" "B.Mask" "B.Paste")
			(net "PVCCIO_CPU0")
		)
		(zone
			(layer "B.Cu")
			(hatch none 0.5)
			(connect_pads
				(clearance 0)
			)
			(min_thickness 0.25)
			(keepout
				(tracks not_allowed)
				(vias allowed)
				(pads allowed)
				(copperpour not_allowed)
				(footprints allowed)
			)
			(placement
				(enabled no)
				(sheetname "")
			)
			(fill
				(thermal_gap 0.5)
				(thermal_bridge_width 0.5)
				(island_removal_mode 0)
			)
			(polygon
				(pts
					(xy 354.343208 -90.60688) (xy 354.851208 -90.60688) (xy 354.851208 -90.22588) (xy 354.343208 -90.22588)
				)
			)
		)
		(zone
			(layer "B.Cu")
			(hatch none 0.5)
			(connect_pads
				(clearance 0)
			)
			(min_thickness 0.25)
			(keepout
				(tracks allowed)
				(vias not_allowed)
				(pads allowed)
				(copperpour not_allowed)
				(footprints allowed)
			)
			(placement
				(enabled no)
				(sheetname "")
			)
			(fill
				(thermal_gap 0.5)
				(thermal_bridge_width 0.5)
				(island_removal_mode 0)
			)
			(polygon
				(pts
					(xy 354.343208 -90.22588) (xy 354.851208 -90.22588) (xy 354.851208 -90.60688) (xy 354.343208 -90.60688)
				)
			)
		)
	)
	(footprint ""
		(layer "B.Cu")
		(at 382.7653 -61.5315)
		(property "Reference" "U2T1"
			(at -2.91592 -1.22809 0)
			(unlocked yes)
			(layer "B.SilkS")
			(effects
				(font
					(size 0.7874 0.5842)
					(thickness 0.1524)
				)
				(justify left mirror)
			)
		)
		(property "Value" ""
			(at 0 0 0)
			(layer "B.Fab")
			(effects
				(font
					(size 1.27 1.27)
				)
				(justify mirror)
			)
		)
		(duplicate_pad_numbers_are_jumpers no)
		(fp_line
			(start -3.9243 -0.2794)
			(end -3.9243 4.7244)
			(stroke
				(width 0.1524)
				(type default)
			)
			(layer "B.SilkS")
		)
		(fp_line
			(start -3.9243 4.7244)
			(end -1.5367 4.7244)
			(stroke
				(width 0.1524)
				(type default)
			)
			(layer "B.SilkS")
		)
		(fp_line
			(start -3.1242 -0.2794)
			(end -3.1242 0.7366)
			(stroke
				(width 0.1524)
				(type default)
			)
			(layer "B.SilkS")
		)
		(fp_line
			(start -3.1242 0.7366)
			(end -2.3622 0.7366)
			(stroke
				(width 0.1524)
				(type default)
			)
			(layer "B.SilkS")
		)
		(fp_line
			(start -2.3622 -0.2794)
			(end -3.1242 -0.2794)
			(stroke
				(width 0.1524)
				(type default)
			)
			(layer "B.SilkS")
		)
		(fp_line
			(start -2.3622 0.7366)
			(end -2.3622 -0.2794)
			(stroke
				(width 0.1524)
				(type default)
			)
			(layer "B.SilkS")
		)
		(fp_line
			(start -1.5367 -0.2794)
			(end -3.9243 -0.2794)
			(stroke
				(width 0.1524)
				(type default)
			)
			(layer "B.SilkS")
		)
		(fp_line
			(start -1.5367 4.7244)
			(end -1.5367 -0.2794)
			(stroke
				(width 0.1524)
				(type default)
			)
			(layer "B.SilkS")
		)
		(fp_circle
			(center 0.9144 -1.0414)
			(end 1.1049 -1.0414)
			(stroke
				(width 0.381)
				(type default)
			)
			(fill no)
			(layer "B.SilkS")
		)
		(fp_poly
			(pts
				(xy -0.7366 -0.2794) (xy -4.7244 -0.2794) (xy -4.7244 4.7244) (xy -0.7366 4.7244)
			)
			(stroke
				(width 0)
				(type default)
			)
			(fill no)
			(layer "B.CrtYd")
		)
		(fp_line
			(start -4.7244 -0.2794)
			(end -4.7244 4.7244)
			(stroke
				(width 0.1)
				(type default)
			)
			(layer "B.Fab")
		)
		(fp_line
			(start -4.7244 4.7244)
			(end -0.7366 4.7244)
			(stroke
				(width 0.1)
				(type default)
			)
			(layer "B.Fab")
		)
		(fp_line
			(start -0.7366 -0.2794)
			(end -4.7244 -0.2794)
			(stroke
				(width 0.1)
				(type default)
			)
			(layer "B.Fab")
		)
		(fp_line
			(start -0.7366 4.7244)
			(end -0.7366 -0.2794)
			(stroke
				(width 0.1)
				(type default)
			)
			(layer "B.Fab")
		)
		(fp_circle
			(center 0.9144 -1.0414)
			(end 1.1049 -1.0414)
			(stroke
				(width 0.381)
				(type default)
			)
			(fill no)
			(layer "B.Fab")
		)
		(pad "1" smd rect
			(at 0 0 180)
			(size 2.159 0.381)
			(layers "B.Cu" "B.Mask" "B.Paste")
			(net "FM_BIOS_SPI_BMC_CTRL")
		)
		(pad "2" smd rect
			(at 0 0.635 180)
			(size 2.159 0.381)
			(layers "B.Cu" "B.Mask" "B.Paste")
			(net "SPI_PCH_IO2_R1")
		)
		(pad "3" smd rect
			(at 0 1.27 180)
			(size 2.159 0.381)
			(layers "B.Cu" "B.Mask" "B.Paste")
			(net "TP_SPI_SWITCH1_3")
		)
		(pad "4" smd rect
			(at 0 1.905 180)
			(size 2.159 0.381)
			(layers "B.Cu" "B.Mask" "B.Paste")
			(net "SPI_BIOS_SOCKET_IO2")
		)
		(pad "5" smd rect
			(at 0 2.54 180)
			(size 2.159 0.381)
			(layers "B.Cu" "B.Mask" "B.Paste")
			(net "SPI_PCH_IO3_R1")
		)
		(pad "6" smd rect
			(at 0 3.175 180)
			(size 2.159 0.381)
			(layers "B.Cu" "B.Mask" "B.Paste")
			(net "TP_SPI_SWITCH1_6")
		)
		(pad "7" smd rect
			(at 0 3.81 180)
			(size 2.159 0.381)
			(layers "B.Cu" "B.Mask" "B.Paste")
			(net "SPI_BIOS_SOCKET_IO3")
		)
		(pad "8" smd rect
			(at 0 4.445 180)
			(size 2.159 0.381)
			(layers "B.Cu" "B.Mask" "B.Paste")
			(net "GND")
		)
		(pad "9" smd rect
			(at -5.461 4.445 180)
			(size 2.159 0.381)
			(layers "B.Cu" "B.Mask" "B.Paste")
			(net "TP_SPI_SWITCH1_9")
		)
		(pad "10" smd rect
			(at -5.461 3.81 180)
			(size 2.159 0.381)
			(layers "B.Cu" "B.Mask" "B.Paste")
			(net "TP_SPI_SWITCH1_10")
		)
		(pad "11" smd rect
			(at -5.461 3.175 180)
			(size 2.159 0.381)
			(layers "B.Cu" "B.Mask" "B.Paste")
			(net "TP_SPI_SWITCH1_11")
		)
		(pad "12" smd rect
			(at -5.461 2.54 180)
			(size 2.159 0.381)
			(layers "B.Cu" "B.Mask" "B.Paste")
			(net "TP_SPI_SWITCH1_12")
		)
		(pad "13" smd rect
			(at -5.461 1.905 180)
			(size 2.159 0.381)
			(layers "B.Cu" "B.Mask" "B.Paste")
			(net "TP_SPI_SWITCH1_13")
		)
		(pad "14" smd rect
			(at -5.461 1.27 180)
			(size 2.159 0.381)
			(layers "B.Cu" "B.Mask" "B.Paste")
			(net "TP_SPI_SWITCH1_14")
		)
		(pad "15" smd rect
			(at -5.461 0.635 180)
			(size 2.159 0.381)
			(layers "B.Cu" "B.Mask" "B.Paste")
			(net "GND")
		)
		(pad "16" smd rect
			(at -5.461 0 180)
			(size 2.159 0.381)
			(layers "B.Cu" "B.Mask" "B.Paste")
			(net "P3V3_STBY")
		)
	)
	(footprint ""
		(layer "B.Cu")
		(at 30.988 -55.7276 180)
		(property "Reference" "CT22"
			(at 0.8382 -0.84963 180)
			(unlocked yes)
			(layer "B.SilkS")
			(effects
				(font
					(size 0.7874 0.5842)
					(thickness 0.1524)
				)
				(justify left mirror)
			)
		)
		(property "Value" ""
			(at 0 0 0)
			(layer "B.Fab")
			(effects
				(font
					(size 1.27 1.27)
				)
				(justify mirror)
			)
		)
		(duplicate_pad_numbers_are_jumpers no)
		(fp_poly
			(pts
				(xy -0.3048 -0.1016) (xy -0.3048 0.9906) (xy 0.3048 0.9906) (xy 0.3048 -0.1016)
			)
			(stroke
				(width 0)
				(type default)
			)
			(fill no)
			(layer "B.CrtYd")
		)
		(fp_line
			(start 0.3048 0.9906)
			(end -0.3048 0.9906)
			(stroke
				(width 0.1)
				(type default)
			)
			(layer "B.Fab")
		)
		(fp_line
			(start 0.3048 -0.1016)
			(end 0.3048 0.9906)
			(stroke
				(width 0.1)
				(type default)
			)
			(layer "B.Fab")
		)
		(fp_line
			(start -0.3048 0.9906)
			(end -0.3048 -0.1016)
			(stroke
				(width 0.1)
				(type default)
			)
			(layer "B.Fab")
		)
		(fp_line
			(start -0.3048 -0.1016)
			(end 0.3048 -0.1016)
			(stroke
				(width 0.1)
				(type default)
			)
			(layer "B.Fab")
		)
		(pad "1" smd rect
			(at 0 0)
			(size 0.508 0.508)
			(layers "B.Cu" "B.Mask" "B.Paste")
			(net "A_TSENSE_PVCCIN_CPU1")
		)
		(pad "2" smd rect
			(at 0 0.889)
			(size 0.508 0.508)
			(layers "B.Cu" "B.Mask" "B.Paste")
			(net "GND")
		)
		(zone
			(layer "B.Cu")
			(hatch none 0.5)
			(connect_pads
				(clearance 0)
			)
			(min_thickness 0.25)
			(keepout
				(tracks not_allowed)
				(vias allowed)
				(pads allowed)
				(copperpour not_allowed)
				(footprints allowed)
			)
			(placement
				(enabled no)
				(sheetname "")
			)
			(fill
				(thermal_gap 0.5)
				(thermal_bridge_width 0.5)
				(island_removal_mode 0)
			)
			(polygon
				(pts
					(xy 30.734 -56.3626) (xy 31.242 -56.3626) (xy 31.242 -55.9816) (xy 30.734 -55.9816)
				)
			)
		)
		(zone
			(layer "B.Cu")
			(hatch none 0.5)
			(connect_pads
				(clearance 0)
			)
			(min_thickness 0.25)
			(keepout
				(tracks allowed)
				(vias not_allowed)
				(pads allowed)
				(copperpour not_allowed)
				(footprints allowed)
			)
			(placement
				(enabled no)
				(sheetname "")
			)
			(fill
				(thermal_gap 0.5)
				(thermal_bridge_width 0.5)
				(island_removal_mode 0)
			)
			(polygon
				(pts
					(xy 30.734 -55.9816) (xy 31.242 -55.9816) (xy 31.242 -56.3626) (xy 30.734 -56.3626)
				)
			)
		)
	)
	(footprint ""
		(layer "B.Cu")
		(at 197.239128 -62.659006 90)
		(property "Reference" "R6R6"
			(at 0 0 90)
			(layer "B.SilkS")
			(hide yes)
			(effects
				(font
					(size 1.27 1.27)
				)
				(justify mirror)
			)
		)
		(property "Value" ""
			(at 0 0 90)
			(layer "B.Fab")
			(effects
				(font
					(size 1.27 1.27)
				)
				(justify mirror)
			)
		)
		(duplicate_pad_numbers_are_jumpers no)
		(fp_rect
			(start 0.2794 -0.1016)
			(end -0.2794 0.9906)
			(stroke
				(width 0)
				(type default)
			)
			(fill no)
			(layer "B.CrtYd")
		)
		(fp_line
			(start 0.2794 -0.1016)
			(end 0.2794 0.9906)
			(stroke
				(width 0.1)
				(type default)
			)
			(layer "B.Fab")
		)
		(fp_line
			(start -0.2794 -0.1016)
			(end 0.2794 -0.1016)
			(stroke
				(width 0.1)
				(type default)
			)
			(layer "B.Fab")
		)
		(fp_line
			(start 0.2794 0.9906)
			(end -0.2794 0.9906)
			(stroke
				(width 0.1)
				(type default)
			)
			(layer "B.Fab")
		)
		(fp_line
			(start -0.2794 0.9906)
			(end -0.2794 -0.1016)
			(stroke
				(width 0.1)
				(type default)
			)
			(layer "B.Fab")
		)
		(pad "1" smd rect
			(at 0 0 270)
			(size 0.508 0.508)
			(layers "B.Cu" "B.Mask" "B.Paste")
			(net "VR_PVCCIN_CPU0_PH2_VCIN")
		)
		(pad "2" smd rect
			(at 0 0.889 270)
			(size 0.508 0.508)
			(layers "B.Cu" "B.Mask" "B.Paste")
			(net "P5V_STBY")
		)
		(zone
			(layer "B.Cu")
			(hatch none 0.5)
			(connect_pads
				(clearance 0)
			)
			(min_thickness 0.25)
			(keepout
				(tracks allowed)
				(vias not_allowed)
				(pads allowed)
				(copperpour not_allowed)
				(footprints allowed)
			)
			(placement
				(enabled no)
				(sheetname "")
			)
			(fill
				(thermal_gap 0.5)
				(thermal_bridge_width 0.5)
				(island_removal_mode 0)
			)
			(polygon
				(pts
					(xy 197.493128 -62.913006) (xy 197.493128 -62.405006) (xy 197.874128 -62.405006) (xy 197.874128 -62.913006)
				)
			)
		)
		(zone
			(layer "B.Cu")
			(hatch none 0.5)
			(connect_pads
				(clearance 0)
			)
			(min_thickness 0.25)
			(keepout
				(tracks not_allowed)
				(vias allowed)
				(pads allowed)
				(copperpour not_allowed)
				(footprints allowed)
			)
			(placement
				(enabled no)
				(sheetname "")
			)
			(fill
				(thermal_gap 0.5)
				(thermal_bridge_width 0.5)
				(island_removal_mode 0)
			)
			(polygon
				(pts
					(xy 197.493128 -62.913006) (xy 197.493128 -62.405006) (xy 197.874128 -62.405006) (xy 197.874128 -62.913006)
				)
			)
		)
	)
	(footprint ""
		(layer "B.Cu")
		(at 375.285 -138.1125)
		(property "Reference" "C3L22"
			(at 0 0 0)
			(layer "B.SilkS")
			(hide yes)
			(effects
				(font
					(size 1.27 1.27)
				)
				(justify mirror)
			)
		)
		(property "Value" ""
			(at 0 0 0)
			(layer "B.Fab")
			(effects
				(font
					(size 1.27 1.27)
				)
				(justify mirror)
			)
		)
		(duplicate_pad_numbers_are_jumpers no)
		(fp_poly
			(pts
				(xy 0.4953 -0.2032) (xy -0.4953 -0.2032) (xy -0.4953 1.6002) (xy 0.4953 1.6002)
			)
			(stroke
				(width 0)
				(type default)
			)
			(fill no)
			(layer "B.CrtYd")
		)
		(fp_line
			(start -0.4953 -0.2032)
			(end -0.4953 1.6002)
			(stroke
				(width 0.1)
				(type default)
			)
			(layer "B.Fab")
		)
		(fp_line
			(start -0.4953 1.6002)
			(end 0.4953 1.6002)
			(stroke
				(width 0.1)
				(type default)
			)
			(layer "B.Fab")
		)
		(fp_line
			(start 0.4953 -0.2032)
			(end -0.4953 -0.2032)
			(stroke
				(width 0.1)
				(type default)
			)
			(layer "B.Fab")
		)
		(fp_line
			(start 0.4953 1.6002)
			(end 0.4953 -0.2032)
			(stroke
				(width 0.1)
				(type default)
			)
			(layer "B.Fab")
		)
		(pad "1" smd rect
			(at 0 0 180)
			(size 0.762 0.889)
			(layers "B.Cu" "B.Mask" "B.Paste")
			(net "PVNN_PCH_STBY")
		)
		(pad "2" smd rect
			(at 0 1.397 180)
			(size 0.762 0.889)
			(layers "B.Cu" "B.Mask" "B.Paste")
			(net "GND")
		)
		(zone
			(layer "B.Cu")
			(hatch none 0.5)
			(connect_pads
				(clearance 0)
			)
			(min_thickness 0.25)
			(keepout
				(tracks not_allowed)
				(vias allowed)
				(pads allowed)
				(copperpour not_allowed)
				(footprints allowed)
			)
			(placement
				(enabled no)
				(sheetname "")
			)
			(fill
				(thermal_gap 0.5)
				(thermal_bridge_width 0.5)
				(island_removal_mode 0)
			)
			(polygon
				(pts
					(xy 375.666 -137.668) (xy 374.904 -137.668) (xy 374.904 -137.16) (xy 375.666 -137.16)
				)
			)
		)
	)
	(footprint ""
		(layer "B.Cu")
		(at 179.206144 -68.341494 -90)
		(property "Reference" "R6P37"
			(at 0 0 90)
			(layer "B.SilkS")
			(hide yes)
			(effects
				(font
					(size 1.27 1.27)
				)
				(justify mirror)
			)
		)
		(property "Value" ""
			(at 0 0 90)
			(layer "B.Fab")
			(effects
				(font
					(size 1.27 1.27)
				)
				(justify mirror)
			)
		)
		(duplicate_pad_numbers_are_jumpers no)
		(fp_rect
			(start -0.2794 -0.1016)
			(end 0.2794 0.9906)
			(stroke
				(width 0)
				(type default)
			)
			(fill no)
			(layer "B.CrtYd")
		)
		(fp_line
			(start -0.2794 0.9906)
			(end -0.2794 -0.1016)
			(stroke
				(width 0.1)
				(type default)
			)
			(layer "B.Fab")
		)
		(fp_line
			(start 0.2794 0.9906)
			(end -0.2794 0.9906)
			(stroke
				(width 0.1)
				(type default)
			)
			(layer "B.Fab")
		)
		(fp_line
			(start -0.2794 -0.1016)
			(end 0.2794 -0.1016)
			(stroke
				(width 0.1)
				(type default)
			)
			(layer "B.Fab")
		)
		(fp_line
			(start 0.2794 -0.1016)
			(end 0.2794 0.9906)
			(stroke
				(width 0.1)
				(type default)
			)
			(layer "B.Fab")
		)
		(pad "1" smd rect
			(at 0 0 90)
			(size 0.508 0.508)
			(layers "B.Cu" "B.Mask" "B.Paste")
			(net "P3V3_STBY")
		)
		(pad "2" smd rect
			(at 0 0.889 90)
			(size 0.508 0.508)
			(layers "B.Cu" "B.Mask" "B.Paste")
			(net "SMB_VR_STBY_LVC3_SCL")
		)
		(zone
			(layer "B.Cu")
			(hatch none 0.5)
			(connect_pads
				(clearance 0)
			)
			(min_thickness 0.25)
			(keepout
				(tracks not_allowed)
				(vias allowed)
				(pads allowed)
				(copperpour not_allowed)
				(footprints allowed)
			)
			(placement
				(enabled no)
				(sheetname "")
			)
			(fill
				(thermal_gap 0.5)
				(thermal_bridge_width 0.5)
				(island_removal_mode 0)
			)
			(polygon
				(pts
					(xy 178.952144 -68.595494) (xy 178.571144 -68.595494) (xy 178.571144 -68.087494) (xy 178.952144 -68.087494)
				)
			)
		)
		(zone
			(layer "B.Cu")
			(hatch none 0.5)
			(connect_pads
				(clearance 0)
			)
			(min_thickness 0.25)
			(keepout
				(tracks allowed)
				(vias not_allowed)
				(pads allowed)
				(copperpour not_allowed)
				(footprints allowed)
			)
			(placement
				(enabled no)
				(sheetname "")
			)
			(fill
				(thermal_gap 0.5)
				(thermal_bridge_width 0.5)
				(island_removal_mode 0)
			)
			(polygon
				(pts
					(xy 178.952144 -68.595494) (xy 178.571144 -68.595494) (xy 178.571144 -68.087494) (xy 178.952144 -68.087494)
				)
			)
		)
	)
	(footprint ""
		(layer "B.Cu")
		(at 366.522 -62.2935 180)
		(property "Reference" "R3P46"
			(at 0 0 0)
			(layer "B.SilkS")
			(hide yes)
			(effects
				(font
					(size 1.27 1.27)
				)
				(justify mirror)
			)
		)
		(property "Value" ""
			(at 0 0 0)
			(layer "B.Fab")
			(effects
				(font
					(size 1.27 1.27)
				)
				(justify mirror)
			)
		)
		(duplicate_pad_numbers_are_jumpers no)
		(fp_poly
			(pts
				(xy 0.2794 -0.1016) (xy -0.2794 -0.1016) (xy -0.2794 0.9906) (xy 0.2794 0.9906)
			)
			(stroke
				(width 0)
				(type default)
			)
			(fill no)
			(layer "B.CrtYd")
		)
		(fp_line
			(start 0.2794 0.9906)
			(end -0.2794 0.9906)
			(stroke
				(width 0.1)
				(type default)
			)
			(layer "B.Fab")
		)
		(fp_line
			(start 0.2794 -0.1016)
			(end 0.2794 0.9906)
			(stroke
				(width 0.1)
				(type default)
			)
			(layer "B.Fab")
		)
		(fp_line
			(start -0.2794 0.9906)
			(end -0.2794 -0.1016)
			(stroke
				(width 0.1)
				(type default)
			)
			(layer "B.Fab")
		)
		(fp_line
			(start -0.2794 -0.1016)
			(end 0.2794 -0.1016)
			(stroke
				(width 0.1)
				(type default)
			)
			(layer "B.Fab")
		)
		(pad "1" smd rect
			(at 0 0)
			(size 0.508 0.508)
			(layers "B.Cu" "B.Mask" "B.Paste")
			(net "FM_CPU1_FIVR_FAULT_R_LVT3")
		)
		(pad "2" smd rect
			(at 0 0.889)
			(size 0.508 0.508)
			(layers "B.Cu" "B.Mask" "B.Paste")
			(net "FM_CPU1_FIVR_FAULT_LVT3")
		)
		(zone
			(layer "B.Cu")
			(hatch none 0.5)
			(connect_pads
				(clearance 0)
			)
			(min_thickness 0.25)
			(keepout
				(tracks not_allowed)
				(vias allowed)
				(pads allowed)
				(copperpour not_allowed)
				(footprints allowed)
			)
			(placement
				(enabled no)
				(sheetname "")
			)
			(fill
				(thermal_gap 0.5)
				(thermal_bridge_width 0.5)
				(island_removal_mode 0)
			)
			(polygon
				(pts
					(xy 366.268 -62.9285) (xy 366.776 -62.9285) (xy 366.776 -62.5475) (xy 366.268 -62.5475)
				)
			)
		)
		(zone
			(layer "B.Cu")
			(hatch none 0.5)
			(connect_pads
				(clearance 0)
			)
			(min_thickness 0.25)
			(keepout
				(tracks allowed)
				(vias not_allowed)
				(pads allowed)
				(copperpour not_allowed)
				(footprints allowed)
			)
			(placement
				(enabled no)
				(sheetname "")
			)
			(fill
				(thermal_gap 0.5)
				(thermal_bridge_width 0.5)
				(island_removal_mode 0)
			)
			(polygon
				(pts
					(xy 366.268 -62.5475) (xy 366.776 -62.5475) (xy 366.776 -62.9285) (xy 366.268 -62.9285)
				)
			)
		)
	)
	(footprint ""
		(layer "B.Cu")
		(at 376.215656 -92.173298)
		(property "Reference" "R1W27"
			(at 0.8382 -0.67818 0)
			(unlocked yes)
			(layer "B.SilkS")
			(effects
				(font
					(size 0.4064 0.254)
					(thickness 0.1524)
				)
				(justify left mirror)
			)
		)
		(property "Value" ""
			(at 0 0 0)
			(layer "B.Fab")
			(effects
				(font
					(size 1.27 1.27)
				)
				(justify mirror)
			)
		)
		(duplicate_pad_numbers_are_jumpers no)
		(fp_poly
			(pts
				(xy 0.2794 -0.1016) (xy -0.2794 -0.1016) (xy -0.2794 0.9906) (xy 0.2794 0.9906)
			)
			(stroke
				(width 0)
				(type default)
			)
			(fill no)
			(layer "B.CrtYd")
		)
		(fp_line
			(start -0.2794 -0.1016)
			(end 0.2794 -0.1016)
			(stroke
				(width 0.1)
				(type default)
			)
			(layer "B.Fab")
		)
		(fp_line
			(start -0.2794 0.9906)
			(end -0.2794 -0.1016)
			(stroke
				(width 0.1)
				(type default)
			)
			(layer "B.Fab")
		)
		(fp_line
			(start 0.2794 -0.1016)
			(end 0.2794 0.9906)
			(stroke
				(width 0.1)
				(type default)
			)
			(layer "B.Fab")
		)
		(fp_line
			(start 0.2794 0.9906)
			(end -0.2794 0.9906)
			(stroke
				(width 0.1)
				(type default)
			)
			(layer "B.Fab")
		)
		(pad "1" smd rect
			(at 0 0 180)
			(size 0.508 0.508)
			(layers "B.Cu" "B.Mask" "B.Paste")
			(net "FM_PWR_BTN_N")
		)
		(pad "2" smd rect
			(at 0 0.889 180)
			(size 0.508 0.508)
			(layers "B.Cu" "B.Mask" "B.Paste")
			(net "FM_PWR_BTN_R2_N")
		)
		(zone
			(layer "B.Cu")
			(hatch none 0.5)
			(connect_pads
				(clearance 0)
			)
			(min_thickness 0.25)
			(keepout
				(tracks allowed)
				(vias not_allowed)
				(pads allowed)
				(copperpour not_allowed)
				(footprints allowed)
			)
			(placement
				(enabled no)
				(sheetname "")
			)
			(fill
				(thermal_gap 0.5)
				(thermal_bridge_width 0.5)
				(island_removal_mode 0)
			)
			(polygon
				(pts
					(xy 376.469656 -91.919298) (xy 375.961656 -91.919298) (xy 375.961656 -91.538298) (xy 376.469656 -91.538298)
				)
			)
		)
		(zone
			(layer "B.Cu")
			(hatch none 0.5)
			(connect_pads
				(clearance 0)
			)
			(min_thickness 0.25)
			(keepout
				(tracks not_allowed)
				(vias allowed)
				(pads allowed)
				(copperpour not_allowed)
				(footprints allowed)
			)
			(placement
				(enabled no)
				(sheetname "")
			)
			(fill
				(thermal_gap 0.5)
				(thermal_bridge_width 0.5)
				(island_removal_mode 0)
			)
			(polygon
				(pts
					(xy 376.469656 -91.538298) (xy 375.961656 -91.538298) (xy 375.961656 -91.919298) (xy 376.469656 -91.919298)
				)
			)
		)
	)
	(footprint ""
		(layer "B.Cu")
		(at 368.7064 -141.0462 180)
		(property "Reference" "C3L18"
			(at -3.10007 3.24612 270)
			(unlocked yes)
			(layer "B.SilkS")
			(effects
				(font
					(size 0.7874 0.5842)
					(thickness 0.1524)
				)
				(justify mirror)
			)
		)
		(property "Value" ""
			(at 0 0 0)
			(layer "B.Fab")
			(effects
				(font
					(size 1.27 1.27)
				)
				(justify mirror)
			)
		)
		(duplicate_pad_numbers_are_jumpers no)
		(fp_line
			(start 2.563114 1.633728)
			(end 1.6002 1.633728)
			(stroke
				(width 0.1524)
				(type default)
			)
			(layer "B.SilkS")
		)
		(fp_line
			(start 2.563114 -1.616456)
			(end 2.563114 1.633728)
			(stroke
				(width 0.1524)
				(type default)
			)
			(layer "B.SilkS")
		)
		(fp_line
			(start 2.286 7.366)
			(end 2.286 1.632712)
			(stroke
				(width 0.1524)
				(type default)
			)
			(layer "B.SilkS")
		)
		(fp_line
			(start 2.286 7.366)
			(end 1.60147 7.366)
			(stroke
				(width 0.1524)
				(type default)
			)
			(layer "B.SilkS")
		)
		(fp_line
			(start 1.6002 -1.616456)
			(end 2.563114 -1.616456)
			(stroke
				(width 0.1524)
				(type default)
			)
			(layer "B.SilkS")
		)
		(fp_line
			(start -1.6002 -1.616456)
			(end -2.504948 -1.616456)
			(stroke
				(width 0.1524)
				(type default)
			)
			(layer "B.SilkS")
		)
		(fp_line
			(start -2.286 7.366)
			(end -1.600708 7.366)
			(stroke
				(width 0.1524)
				(type default)
			)
			(layer "B.SilkS")
		)
		(fp_line
			(start -2.286 7.366)
			(end -2.286 1.63195)
			(stroke
				(width 0.1524)
				(type default)
			)
			(layer "B.SilkS")
		)
		(fp_line
			(start -2.504948 1.633728)
			(end -1.6002 1.633728)
			(stroke
				(width 0.1524)
				(type default)
			)
			(layer "B.SilkS")
		)
		(fp_line
			(start -2.504948 -1.616456)
			(end -2.504948 1.633728)
			(stroke
				(width 0.1524)
				(type default)
			)
			(layer "B.SilkS")
		)
		(fp_rect
			(start 2.286 7.366)
			(end -2.286 -0.254)
			(stroke
				(width 0)
				(type default)
			)
			(fill no)
			(layer "B.CrtYd")
		)
		(fp_line
			(start 2.286 7.366)
			(end 2.286 -0.254)
			(stroke
				(width 0.1)
				(type default)
			)
			(layer "B.Fab")
		)
		(fp_line
			(start 2.286 -0.254)
			(end -2.286 -0.254)
			(stroke
				(width 0.1)
				(type default)
			)
			(layer "B.Fab")
		)
		(fp_line
			(start -2.286 7.366)
			(end 2.286 7.366)
			(stroke
				(width 0.1)
				(type default)
			)
			(layer "B.Fab")
		)
		(fp_line
			(start -2.286 -0.254)
			(end -2.286 7.366)
			(stroke
				(width 0.1)
				(type default)
			)
			(layer "B.Fab")
		)
		(pad "1" smd rect
			(at 0 0)
			(size 2.54 3.048)
			(layers "B.Cu" "B.Mask" "B.Paste")
			(net "PVNN_PCH_STBY")
		)
		(pad "2" smd rect
			(at 0 7.112)
			(size 2.54 3.048)
			(layers "B.Cu" "B.Mask" "B.Paste")
			(net "GND")
		)
	)
	(footprint ""
		(layer "B.Cu")
		(at 404.43658 -143.561816 -90)
		(property "Reference" "C2L32"
			(at 0 0 90)
			(layer "B.SilkS")
			(hide yes)
			(effects
				(font
					(size 1.27 1.27)
				)
				(justify mirror)
			)
		)
		(property "Value" ""
			(at 0 0 90)
			(layer "B.Fab")
			(effects
				(font
					(size 1.27 1.27)
				)
				(justify mirror)
			)
		)
		(duplicate_pad_numbers_are_jumpers no)
		(fp_poly
			(pts
				(xy 0.7239 -0.2159) (xy -0.7239 -0.2159) (xy -0.7239 1.9939) (xy 0.7239 1.9939)
			)
			(stroke
				(width 0)
				(type default)
			)
			(fill no)
			(layer "B.CrtYd")
		)
		(fp_line
			(start -0.7239 1.9939)
			(end -0.7239 -0.2159)
			(stroke
				(width 0.1)
				(type default)
			)
			(layer "B.Fab")
		)
		(fp_line
			(start 0.7239 1.9939)
			(end -0.7239 1.9939)
			(stroke
				(width 0.1)
				(type default)
			)
			(layer "B.Fab")
		)
		(fp_line
			(start -0.7239 -0.2159)
			(end 0.7239 -0.2159)
			(stroke
				(width 0.1)
				(type default)
			)
			(layer "B.Fab")
		)
		(fp_line
			(start 0.7239 -0.2159)
			(end 0.7239 1.9939)
			(stroke
				(width 0.1)
				(type default)
			)
			(layer "B.Fab")
		)
		(pad "1" smd rect
			(at 0 0 90)
			(size 1.27 1.016)
			(layers "B.Cu" "B.Mask" "B.Paste")
			(net "P1V8_PCH_STBY")
		)
		(pad "2" smd rect
			(at 0 1.778 90)
			(size 1.27 1.016)
			(layers "B.Cu" "B.Mask" "B.Paste")
			(net "GND")
		)
		(zone
			(layer "B.Cu")
			(hatch none 0.5)
			(connect_pads
				(clearance 0)
			)
			(min_thickness 0.25)
			(keepout
				(tracks not_allowed)
				(vias allowed)
				(pads allowed)
				(copperpour not_allowed)
				(footprints allowed)
			)
			(placement
				(enabled no)
				(sheetname "")
			)
			(fill
				(thermal_gap 0.5)
				(thermal_bridge_width 0.5)
				(island_removal_mode 0)
			)
			(polygon
				(pts
					(xy 403.92858 -142.926816) (xy 403.92858 -144.196816) (xy 403.16658 -144.196816) (xy 403.16658 -142.926816)
				)
			)
		)
	)
	(footprint ""
		(layer "B.Cu")
		(at 482.132894 -17.067022 90)
		(property "Reference" "R9G3"
			(at 0 0 90)
			(layer "B.SilkS")
			(hide yes)
			(effects
				(font
					(size 1.27 1.27)
				)
				(justify mirror)
			)
		)
		(property "Value" ""
			(at 0 0 90)
			(layer "B.Fab")
			(effects
				(font
					(size 1.27 1.27)
				)
				(justify mirror)
			)
		)
		(duplicate_pad_numbers_are_jumpers no)
		(fp_poly
			(pts
				(xy 0.2794 -0.1016) (xy -0.2794 -0.1016) (xy -0.2794 0.9906) (xy 0.2794 0.9906)
			)
			(stroke
				(width 0)
				(type default)
			)
			(fill no)
			(layer "B.CrtYd")
		)
		(fp_line
			(start 0.2794 -0.1016)
			(end 0.2794 0.9906)
			(stroke
				(width 0.1)
				(type default)
			)
			(layer "B.Fab")
		)
		(fp_line
			(start -0.2794 -0.1016)
			(end 0.2794 -0.1016)
			(stroke
				(width 0.1)
				(type default)
			)
			(layer "B.Fab")
		)
		(fp_line
			(start 0.2794 0.9906)
			(end -0.2794 0.9906)
			(stroke
				(width 0.1)
				(type default)
			)
			(layer "B.Fab")
		)
		(fp_line
			(start -0.2794 0.9906)
			(end -0.2794 -0.1016)
			(stroke
				(width 0.1)
				(type default)
			)
			(layer "B.Fab")
		)
		(pad "1" smd rect
			(at 0 0 270)
			(size 0.508 0.508)
			(layers "B.Cu" "B.Mask" "B.Paste")
			(net "LED_LAN_0_R_N")
		)
		(pad "2" smd rect
			(at 0 0.889 270)
			(size 0.508 0.508)
			(layers "B.Cu" "B.Mask" "B.Paste")
			(net "LED_LAN_0_N")
		)
		(zone
			(layer "B.Cu")
			(hatch none 0.5)
			(connect_pads
				(clearance 0)
			)
			(min_thickness 0.25)
			(keepout
				(tracks allowed)
				(vias not_allowed)
				(pads allowed)
				(copperpour not_allowed)
				(footprints allowed)
			)
			(placement
				(enabled no)
				(sheetname "")
			)
			(fill
				(thermal_gap 0.5)
				(thermal_bridge_width 0.5)
				(island_removal_mode 0)
			)
			(polygon
				(pts
					(xy 482.386894 -17.321022) (xy 482.386894 -16.813022) (xy 482.767894 -16.813022) (xy 482.767894 -17.321022)
				)
			)
		)
		(zone
			(layer "B.Cu")
			(hatch none 0.5)
			(connect_pads
				(clearance 0)
			)
			(min_thickness 0.25)
			(keepout
				(tracks not_allowed)
				(vias allowed)
				(pads allowed)
				(copperpour not_allowed)
				(footprints allowed)
			)
			(placement
				(enabled no)
				(sheetname "")
			)
			(fill
				(thermal_gap 0.5)
				(thermal_bridge_width 0.5)
				(island_removal_mode 0)
			)
			(polygon
				(pts
					(xy 482.767894 -17.321022) (xy 482.767894 -16.813022) (xy 482.386894 -16.813022) (xy 482.386894 -17.321022)
				)
			)
		)
	)
	(footprint ""
		(layer "B.Cu")
		(at 105.636568 3.81 90)
		(property "Reference" "C8U11"
			(at 0 0 90)
			(layer "B.SilkS")
			(hide yes)
			(effects
				(font
					(size 1.27 1.27)
				)
				(justify mirror)
			)
		)
		(property "Value" ""
			(at 0 0 90)
			(layer "B.Fab")
			(effects
				(font
					(size 1.27 1.27)
				)
				(justify mirror)
			)
		)
		(duplicate_pad_numbers_are_jumpers no)
		(fp_poly
			(pts
				(xy 0.7239 -0.2159) (xy -0.7239 -0.2159) (xy -0.7239 1.9939) (xy 0.7239 1.9939)
			)
			(stroke
				(width 0)
				(type default)
			)
			(fill no)
			(layer "B.CrtYd")
		)
		(fp_line
			(start 0.7239 -0.2159)
			(end 0.7239 1.9939)
			(stroke
				(width 0.1)
				(type default)
			)
			(layer "B.Fab")
		)
		(fp_line
			(start -0.7239 -0.2159)
			(end 0.7239 -0.2159)
			(stroke
				(width 0.1)
				(type default)
			)
			(layer "B.Fab")
		)
		(fp_line
			(start 0.7239 1.9939)
			(end -0.7239 1.9939)
			(stroke
				(width 0.1)
				(type default)
			)
			(layer "B.Fab")
		)
		(fp_line
			(start -0.7239 1.9939)
			(end -0.7239 -0.2159)
			(stroke
				(width 0.1)
				(type default)
			)
			(layer "B.Fab")
		)
		(pad "1" smd rect
			(at 0 0 270)
			(size 1.27 1.016)
			(layers "B.Cu" "B.Mask" "B.Paste")
			(net "PVDDQ_GHJ")
		)
		(pad "2" smd rect
			(at 0 1.778 270)
			(size 1.27 1.016)
			(layers "B.Cu" "B.Mask" "B.Paste")
			(net "GND")
		)
		(zone
			(layer "B.Cu")
			(hatch none 0.5)
			(connect_pads
				(clearance 0)
			)
			(min_thickness 0.25)
			(keepout
				(tracks not_allowed)
				(vias allowed)
				(pads allowed)
				(copperpour not_allowed)
				(footprints allowed)
			)
			(placement
				(enabled no)
				(sheetname "")
			)
			(fill
				(thermal_gap 0.5)
				(thermal_bridge_width 0.5)
				(island_removal_mode 0)
			)
			(polygon
				(pts
					(xy 106.144568 3.175) (xy 106.144568 4.445) (xy 106.906568 4.445) (xy 106.906568 3.175)
				)
			)
		)
	)
	(footprint ""
		(layer "B.Cu")
		(at 413.922972 -31.805372)
		(property "Reference" "FB2T7"
			(at 0 0 0)
			(layer "B.SilkS")
			(hide yes)
			(effects
				(font
					(size 1.27 1.27)
				)
				(justify mirror)
			)
		)
		(property "Value" "*"
			(at -0.0254 -2.8829 0)
			(unlocked yes)
			(layer "B.Fab")
			(hide yes)
			(effects
				(font
					(size 1.27 1.016)
					(thickness 0.1524)
				)
				(justify mirror)
			)
		)
		(property "Device Type" "HCB1608KF-800T30-GP_DISCRET-G9A"
			(at -0.0254 -4.4069 0)
			(unlocked yes)
			(layer "B.Fab")
			(hide yes)
			(effects
				(font
					(size 1.27 1.016)
					(thickness 0.1524)
				)
				(justify mirror)
			)
		)
		(duplicate_pad_numbers_are_jumpers no)
		(fp_line
			(start -0.254 0)
			(end 0.254 0)
			(stroke
				(width 0.2032)
				(type default)
			)
			(layer "B.SilkS")
		)
		(fp_rect
			(start 0.5842 1.3335)
			(end -0.5842 -1.3335)
			(stroke
				(width 0)
				(type default)
			)
			(fill no)
			(layer "B.CrtYd")
		)
		(fp_rect
			(start 0.5842 1.3335)
			(end -0.5842 -1.3335)
			(stroke
				(width 0)
				(type default)
			)
			(fill no)
			(layer "B.Fab")
		)
		(pad "1" smd custom
			(at 0 -0.762 180)
			(size 0.2159 0.2159)
			(layers "B.Cu" "B.Mask" "B.Paste")
			(net "P1V15_AUX_BMC")
			(options
				(clearance outline)
				(anchor circle)
			)
			(primitives
				(gr_poly
					(pts
						(arc
							(start -0.3302 0.4318)
							(mid -0.402042 0.402042)
							(end -0.4318 0.3302)
						)
						(arc
							(start -0.4318 -0.3302)
							(mid -0.402042 -0.402042)
							(end -0.3302 -0.4318)
						)
						(arc
							(start 0.3302 -0.4318)
							(mid 0.402042 -0.402042)
							(end 0.4318 -0.3302)
						)
						(arc
							(start 0.4318 0.3302)
							(mid 0.402042 0.402042)
							(end 0.3302 0.4318)
						)
					)
					(width 0)
					(fill yes)
				)
			)
		)
		(pad "2" smd custom
			(at 0 0.762 180)
			(size 0.2159 0.2159)
			(layers "B.Cu" "B.Mask" "B.Paste")
			(net "VCC_A_1V1")
			(options
				(clearance outline)
				(anchor circle)
			)
			(primitives
				(gr_poly
					(pts
						(arc
							(start -0.3302 0.4318)
							(mid -0.402042 0.402042)
							(end -0.4318 0.3302)
						)
						(arc
							(start -0.4318 -0.3302)
							(mid -0.402042 -0.402042)
							(end -0.3302 -0.4318)
						)
						(arc
							(start 0.3302 -0.4318)
							(mid 0.402042 -0.402042)
							(end 0.4318 -0.3302)
						)
						(arc
							(start 0.4318 0.3302)
							(mid 0.402042 0.402042)
							(end 0.3302 0.4318)
						)
					)
					(width 0)
					(fill yes)
				)
			)
		)
	)
	(footprint ""
		(layer "B.Cu")
		(at 352.305874 -24.727916 90)
		(property "Reference" "C22W10"
			(at 0 0 90)
			(layer "B.SilkS")
			(hide yes)
			(effects
				(font
					(size 1.27 1.27)
				)
				(justify mirror)
			)
		)
		(property "Value" "*"
			(at 0.0762 -6.2357 90)
			(unlocked yes)
			(layer "B.Fab")
			(hide yes)
			(effects
				(font
					(size 1.27 1.016)
					(thickness 0.1524)
				)
				(justify mirror)
			)
		)
		(property "Device Type" "SC22U16V5MX-4-GP_SMD-BCG5-SC22A"
			(at 0.0762 -8.2677 90)
			(unlocked yes)
			(layer "B.Fab")
			(hide yes)
			(effects
				(font
					(size 1.27 1.016)
					(thickness 0.1524)
				)
				(justify mirror)
			)
		)
		(duplicate_pad_numbers_are_jumpers no)
		(fp_line
			(start -0.635 0)
			(end 0.635 0)
			(stroke
				(width 0.508)
				(type default)
			)
			(layer "B.SilkS")
		)
		(fp_rect
			(start 0.9652 1.778)
			(end -0.9652 -1.778)
			(stroke
				(width 0)
				(type default)
			)
			(fill no)
			(layer "B.CrtYd")
		)
		(fp_poly
			(pts
				(xy 0.9652 -1.778) (xy -0.9652 -1.778) (xy -0.9652 1.778) (xy 0.9652 1.778)
			)
			(stroke
				(width 0)
				(type default)
			)
			(fill no)
			(layer "B.Fab")
		)
		(pad "1" smd rect
			(at 0 -0.9652 270)
			(size 1.397 1.143)
			(layers "B.Cu" "B.Mask" "B.Paste")
			(net "VR_FET_SW_P12V_STBY_PVPP_ABC")
		)
		(pad "2" smd rect
			(at 0 0.9652 270)
			(size 1.397 1.143)
			(layers "B.Cu" "B.Mask" "B.Paste")
			(net "GND")
		)
	)
	(footprint ""
		(layer "B.Cu")
		(at 453.2122 -52.330858)
		(property "Reference" "C1R8"
			(at 0 0 0)
			(layer "B.SilkS")
			(hide yes)
			(effects
				(font
					(size 1.27 1.27)
				)
				(justify mirror)
			)
		)
		(property "Value" ""
			(at 0 0 0)
			(layer "B.Fab")
			(effects
				(font
					(size 1.27 1.27)
				)
				(justify mirror)
			)
		)
		(duplicate_pad_numbers_are_jumpers no)
		(fp_poly
			(pts
				(xy -0.3048 -0.1016) (xy -0.3048 0.9906) (xy 0.3048 0.9906) (xy 0.3048 -0.1016)
			)
			(stroke
				(width 0)
				(type default)
			)
			(fill no)
			(layer "B.CrtYd")
		)
		(fp_line
			(start -0.3048 -0.1016)
			(end 0.3048 -0.1016)
			(stroke
				(width 0.1)
				(type default)
			)
			(layer "B.Fab")
		)
		(fp_line
			(start -0.3048 0.9906)
			(end -0.3048 -0.1016)
			(stroke
				(width 0.1)
				(type default)
			)
			(layer "B.Fab")
		)
		(fp_line
			(start 0.3048 -0.1016)
			(end 0.3048 0.9906)
			(stroke
				(width 0.1)
				(type default)
			)
			(layer "B.Fab")
		)
		(fp_line
			(start 0.3048 0.9906)
			(end -0.3048 0.9906)
			(stroke
				(width 0.1)
				(type default)
			)
			(layer "B.Fab")
		)
		(pad "1" smd rect
			(at 0 0 180)
			(size 0.508 0.508)
			(layers "B.Cu" "B.Mask" "B.Paste")
			(net "P3E_CPU0_PE3_OCP_TXP<3>")
		)
		(pad "2" smd rect
			(at 0 0.889 180)
			(size 0.508 0.508)
			(layers "B.Cu" "B.Mask" "B.Paste")
			(net "P3E_OCP_CPU0_PE3_C_TXP<3>")
		)
		(zone
			(layer "B.Cu")
			(hatch none 0.5)
			(connect_pads
				(clearance 0)
			)
			(min_thickness 0.25)
			(keepout
				(tracks allowed)
				(vias not_allowed)
				(pads allowed)
				(copperpour not_allowed)
				(footprints allowed)
			)
			(placement
				(enabled no)
				(sheetname "")
			)
			(fill
				(thermal_gap 0.5)
				(thermal_bridge_width 0.5)
				(island_removal_mode 0)
			)
			(polygon
				(pts
					(xy 453.4662 -52.076858) (xy 452.9582 -52.076858) (xy 452.9582 -51.695858) (xy 453.4662 -51.695858)
				)
			)
		)
	)
	(footprint ""
		(layer "B.Cu")
		(at 168.529 -65.405)
		(property "Reference" "RF14"
			(at 0.8382 -0.67818 0)
			(unlocked yes)
			(layer "B.SilkS")
			(effects
				(font
					(size 0.4064 0.254)
					(thickness 0.1524)
				)
				(justify left mirror)
			)
		)
		(property "Value" ""
			(at 0 0 0)
			(layer "B.Fab")
			(effects
				(font
					(size 1.27 1.27)
				)
				(justify mirror)
			)
		)
		(duplicate_pad_numbers_are_jumpers no)
		(fp_poly
			(pts
				(xy 0.2794 -0.1016) (xy -0.2794 -0.1016) (xy -0.2794 0.9906) (xy 0.2794 0.9906)
			)
			(stroke
				(width 0)
				(type default)
			)
			(fill no)
			(layer "B.CrtYd")
		)
		(fp_line
			(start -0.2794 -0.1016)
			(end 0.2794 -0.1016)
			(stroke
				(width 0.1)
				(type default)
			)
			(layer "B.Fab")
		)
		(fp_line
			(start -0.2794 0.9906)
			(end -0.2794 -0.1016)
			(stroke
				(width 0.1)
				(type default)
			)
			(layer "B.Fab")
		)
		(fp_line
			(start 0.2794 -0.1016)
			(end 0.2794 0.9906)
			(stroke
				(width 0.1)
				(type default)
			)
			(layer "B.Fab")
		)
		(fp_line
			(start 0.2794 0.9906)
			(end -0.2794 0.9906)
			(stroke
				(width 0.1)
				(type default)
			)
			(layer "B.Fab")
		)
		(pad "1" smd rect
			(at 0 0 180)
			(size 0.508 0.508)
			(layers "B.Cu" "B.Mask" "B.Paste")
			(net "VR_PVCCIO_CPU1_AIREF1")
		)
		(pad "2" smd rect
			(at 0 0.889 180)
			(size 0.508 0.508)
			(layers "B.Cu" "B.Mask" "B.Paste")
			(net "ISENSE_PVCCIO_CPU1_PH1_IMON")
		)
		(zone
			(layer "B.Cu")
			(hatch none 0.5)
			(connect_pads
				(clearance 0)
			)
			(min_thickness 0.25)
			(keepout
				(tracks allowed)
				(vias not_allowed)
				(pads allowed)
				(copperpour not_allowed)
				(footprints allowed)
			)
			(placement
				(enabled no)
				(sheetname "")
			)
			(fill
				(thermal_gap 0.5)
				(thermal_bridge_width 0.5)
				(island_removal_mode 0)
			)
			(polygon
				(pts
					(xy 168.783 -65.151) (xy 168.275 -65.151) (xy 168.275 -64.77) (xy 168.783 -64.77)
				)
			)
		)
		(zone
			(layer "B.Cu")
			(hatch none 0.5)
			(connect_pads
				(clearance 0)
			)
			(min_thickness 0.25)
			(keepout
				(tracks not_allowed)
				(vias allowed)
				(pads allowed)
				(copperpour not_allowed)
				(footprints allowed)
			)
			(placement
				(enabled no)
				(sheetname "")
			)
			(fill
				(thermal_gap 0.5)
				(thermal_bridge_width 0.5)
				(island_removal_mode 0)
			)
			(polygon
				(pts
					(xy 168.783 -64.77) (xy 168.275 -64.77) (xy 168.275 -65.151) (xy 168.783 -65.151)
				)
			)
		)
	)
	(footprint ""
		(layer "B.Cu")
		(at 369.443 -113.792 -90)
		(property "Reference" "C3M40"
			(at 0 0 90)
			(layer "B.SilkS")
			(hide yes)
			(effects
				(font
					(size 1.27 1.27)
				)
				(justify mirror)
			)
		)
		(property "Value" ""
			(at 0 0 90)
			(layer "B.Fab")
			(effects
				(font
					(size 1.27 1.27)
				)
				(justify mirror)
			)
		)
		(duplicate_pad_numbers_are_jumpers no)
		(fp_poly
			(pts
				(xy -0.3048 -0.1016) (xy -0.3048 0.9906) (xy 0.3048 0.9906) (xy 0.3048 -0.1016)
			)
			(stroke
				(width 0)
				(type default)
			)
			(fill no)
			(layer "B.CrtYd")
		)
		(fp_line
			(start -0.3048 0.9906)
			(end -0.3048 -0.1016)
			(stroke
				(width 0.1)
				(type default)
			)
			(layer "B.Fab")
		)
		(fp_line
			(start 0.3048 0.9906)
			(end -0.3048 0.9906)
			(stroke
				(width 0.1)
				(type default)
			)
			(layer "B.Fab")
		)
		(fp_line
			(start -0.3048 -0.1016)
			(end 0.3048 -0.1016)
			(stroke
				(width 0.1)
				(type default)
			)
			(layer "B.Fab")
		)
		(fp_line
			(start 0.3048 -0.1016)
			(end 0.3048 0.9906)
			(stroke
				(width 0.1)
				(type default)
			)
			(layer "B.Fab")
		)
		(pad "1" smd rect
			(at 0 0 90)
			(size 0.508 0.508)
			(layers "B.Cu" "B.Mask" "B.Paste")
			(net "DMI_CPU0_PCH_RX_DP<0>")
		)
		(pad "2" smd rect
			(at 0 0.889 90)
			(size 0.508 0.508)
			(layers "B.Cu" "B.Mask" "B.Paste")
			(net "DMI_CPU0_PCH_RX_C_DP<0>")
		)
		(zone
			(layer "B.Cu")
			(hatch none 0.5)
			(connect_pads
				(clearance 0)
			)
			(min_thickness 0.25)
			(keepout
				(tracks not_allowed)
				(vias allowed)
				(pads allowed)
				(copperpour not_allowed)
				(footprints allowed)
			)
			(placement
				(enabled no)
				(sheetname "")
			)
			(fill
				(thermal_gap 0.5)
				(thermal_bridge_width 0.5)
				(island_removal_mode 0)
			)
			(polygon
				(pts
					(xy 368.808 -113.538) (xy 368.808 -114.046) (xy 369.189 -114.046) (xy 369.189 -113.538)
				)
			)
		)
		(zone
			(layer "B.Cu")
			(hatch none 0.5)
			(connect_pads
				(clearance 0)
			)
			(min_thickness 0.25)
			(keepout
				(tracks allowed)
				(vias not_allowed)
				(pads allowed)
				(copperpour not_allowed)
				(footprints allowed)
			)
			(placement
				(enabled no)
				(sheetname "")
			)
			(fill
				(thermal_gap 0.5)
				(thermal_bridge_width 0.5)
				(island_removal_mode 0)
			)
			(polygon
				(pts
					(xy 369.189 -113.538) (xy 369.189 -114.046) (xy 368.808 -114.046) (xy 368.808 -113.538)
				)
			)
		)
	)
	(footprint ""
		(layer "B.Cu")
		(at 422.8465 -4.191 -90)
		(property "Reference" "R3P44"
			(at 0 0 90)
			(layer "B.SilkS")
			(hide yes)
			(effects
				(font
					(size 1.27 1.27)
				)
				(justify mirror)
			)
		)
		(property "Value" ""
			(at 0 0 90)
			(layer "B.Fab")
			(effects
				(font
					(size 1.27 1.27)
				)
				(justify mirror)
			)
		)
		(duplicate_pad_numbers_are_jumpers no)
		(fp_rect
			(start 0.2794 -0.1016)
			(end -0.2794 0.9906)
			(stroke
				(width 0)
				(type default)
			)
			(fill no)
			(layer "B.CrtYd")
		)
		(fp_line
			(start -0.2794 0.9906)
			(end -0.2794 -0.1016)
			(stroke
				(width 0.1)
				(type default)
			)
			(layer "B.Fab")
		)
		(fp_line
			(start 0.2794 0.9906)
			(end -0.2794 0.9906)
			(stroke
				(width 0.1)
				(type default)
			)
			(layer "B.Fab")
		)
		(fp_line
			(start -0.2794 -0.1016)
			(end 0.2794 -0.1016)
			(stroke
				(width 0.1)
				(type default)
			)
			(layer "B.Fab")
		)
		(fp_line
			(start 0.2794 -0.1016)
			(end 0.2794 0.9906)
			(stroke
				(width 0.1)
				(type default)
			)
			(layer "B.Fab")
		)
		(pad "1" smd rect
			(at 0 0 90)
			(size 0.508 0.508)
			(layers "B.Cu" "B.Mask" "B.Paste")
			(net "P3V3_STBY")
		)
		(pad "2" smd rect
			(at 0 0.889 90)
			(size 0.508 0.508)
			(layers "B.Cu" "B.Mask" "B.Paste")
			(net "PWRGD_DSW_PWROK")
		)
		(zone
			(layer "B.Cu")
			(hatch none 0.5)
			(connect_pads
				(clearance 0)
			)
			(min_thickness 0.25)
			(keepout
				(tracks allowed)
				(vias not_allowed)
				(pads allowed)
				(copperpour not_allowed)
				(footprints allowed)
			)
			(placement
				(enabled no)
				(sheetname "")
			)
			(fill
				(thermal_gap 0.5)
				(thermal_bridge_width 0.5)
				(island_removal_mode 0)
			)
			(polygon
				(pts
					(xy 422.5925 -3.937) (xy 422.5925 -4.445) (xy 422.2115 -4.445) (xy 422.2115 -3.937)
				)
			)
		)
		(zone
			(layer "B.Cu")
			(hatch none 0.5)
			(connect_pads
				(clearance 0)
			)
			(min_thickness 0.25)
			(keepout
				(tracks not_allowed)
				(vias allowed)
				(pads allowed)
				(copperpour not_allowed)
				(footprints allowed)
			)
			(placement
				(enabled no)
				(sheetname "")
			)
			(fill
				(thermal_gap 0.5)
				(thermal_bridge_width 0.5)
				(island_removal_mode 0)
			)
			(polygon
				(pts
					(xy 422.5925 -3.937) (xy 422.5925 -4.445) (xy 422.2115 -4.445) (xy 422.2115 -3.937)
				)
			)
		)
	)
	(footprint ""
		(layer "B.Cu")
		(at 444.548006 -41.648126 180)
		(property "Reference" "R25W18"
			(at 0 0 0)
			(layer "B.SilkS")
			(hide yes)
			(effects
				(font
					(size 1.27 1.27)
				)
				(justify mirror)
			)
		)
		(property "Value" "*"
			(at -0.064008 -4.108196 180)
			(unlocked yes)
			(layer "B.Fab")
			(hide yes)
			(effects
				(font
					(size 1.27 1.016)
					(thickness 0.1524)
				)
				(justify mirror)
			)
		)
		(property "Device Type" "120R2F-GP_RCL_GP-120R2F-GP,64.A"
			(at -0.064008 -5.632196 180)
			(unlocked yes)
			(layer "B.Fab")
			(hide yes)
			(effects
				(font
					(size 1.27 1.016)
					(thickness 0.1524)
				)
				(justify mirror)
			)
		)
		(duplicate_pad_numbers_are_jumpers no)
		(fp_line
			(start 0.508 -0.9398)
			(end 0.508 0.9398)
			(stroke
				(width 0.1524)
				(type default)
			)
			(layer "B.SilkS")
		)
		(fp_line
			(start -0.508 -0.9398)
			(end 0.508 -0.9398)
			(stroke
				(width 0.1524)
				(type default)
			)
			(layer "B.SilkS")
		)
		(fp_rect
			(start 0.508 0.9398)
			(end -0.508 -0.9398)
			(stroke
				(width 0)
				(type default)
			)
			(fill no)
			(layer "B.CrtYd")
		)
		(fp_rect
			(start 0.508 0.9398)
			(end -0.508 -0.9398)
			(stroke
				(width 0)
				(type default)
			)
			(fill no)
			(layer "B.Fab")
		)
		(pad "1" smd custom
			(at 0 -0.4445)
			(size 0.1397 0.1397)
			(layers "B.Cu" "B.Mask" "B.Paste")
			(net "GND")
			(options
				(clearance outline)
				(anchor circle)
			)
			(primitives
				(gr_poly
					(pts
						(arc
							(start -0.1778 0.2794)
							(mid -0.249642 0.249642)
							(end -0.2794 0.1778)
						)
						(arc
							(start -0.2794 -0.1778)
							(mid -0.249642 -0.249642)
							(end -0.1778 -0.2794)
						)
						(arc
							(start 0.1778 -0.2794)
							(mid 0.249642 -0.249642)
							(end 0.2794 -0.1778)
						)
						(arc
							(start 0.2794 0.1778)
							(mid 0.249642 0.249642)
							(end 0.1778 0.2794)
						)
					)
					(width 0)
					(fill yes)
				)
			)
		)
		(pad "2" smd custom
			(at 0 0.4445)
			(size 0.1397 0.1397)
			(layers "B.Cu" "B.Mask" "B.Paste")
			(net "BMC_M_A6")
			(options
				(clearance outline)
				(anchor circle)
			)
			(primitives
				(gr_poly
					(pts
						(arc
							(start -0.1778 0.2794)
							(mid -0.249642 0.249642)
							(end -0.2794 0.1778)
						)
						(arc
							(start -0.2794 -0.1778)
							(mid -0.249642 -0.249642)
							(end -0.1778 -0.2794)
						)
						(arc
							(start 0.1778 -0.2794)
							(mid 0.249642 -0.249642)
							(end 0.2794 -0.1778)
						)
						(arc
							(start 0.2794 0.1778)
							(mid 0.249642 0.249642)
							(end 0.1778 0.2794)
						)
					)
					(width 0)
					(fill yes)
				)
			)
		)
	)
	(footprint ""
		(layer "B.Cu")
		(at 197.226428 -95.171006 90)
		(property "Reference" "R6N3"
			(at 0 0 90)
			(layer "B.SilkS")
			(hide yes)
			(effects
				(font
					(size 1.27 1.27)
				)
				(justify mirror)
			)
		)
		(property "Value" ""
			(at 0 0 90)
			(layer "B.Fab")
			(effects
				(font
					(size 1.27 1.27)
				)
				(justify mirror)
			)
		)
		(duplicate_pad_numbers_are_jumpers no)
		(fp_rect
			(start 0.2794 -0.1016)
			(end -0.2794 0.9906)
			(stroke
				(width 0)
				(type default)
			)
			(fill no)
			(layer "B.CrtYd")
		)
		(fp_line
			(start 0.2794 -0.1016)
			(end 0.2794 0.9906)
			(stroke
				(width 0.1)
				(type default)
			)
			(layer "B.Fab")
		)
		(fp_line
			(start -0.2794 -0.1016)
			(end 0.2794 -0.1016)
			(stroke
				(width 0.1)
				(type default)
			)
			(layer "B.Fab")
		)
		(fp_line
			(start 0.2794 0.9906)
			(end -0.2794 0.9906)
			(stroke
				(width 0.1)
				(type default)
			)
			(layer "B.Fab")
		)
		(fp_line
			(start -0.2794 0.9906)
			(end -0.2794 -0.1016)
			(stroke
				(width 0.1)
				(type default)
			)
			(layer "B.Fab")
		)
		(pad "1" smd rect
			(at 0 0 270)
			(size 0.508 0.508)
			(layers "B.Cu" "B.Mask" "B.Paste")
			(net "VR_PVSA_CPU0_VCIN")
		)
		(pad "2" smd rect
			(at 0 0.889 270)
			(size 0.508 0.508)
			(layers "B.Cu" "B.Mask" "B.Paste")
			(net "P5V_STBY")
		)
		(zone
			(layer "B.Cu")
			(hatch none 0.5)
			(connect_pads
				(clearance 0)
			)
			(min_thickness 0.25)
			(keepout
				(tracks not_allowed)
				(vias allowed)
				(pads allowed)
				(copperpour not_allowed)
				(footprints allowed)
			)
			(placement
				(enabled no)
				(sheetname "")
			)
			(fill
				(thermal_gap 0.5)
				(thermal_bridge_width 0.5)
				(island_removal_mode 0)
			)
			(polygon
				(pts
					(xy 197.480428 -95.425006) (xy 197.480428 -94.917006) (xy 197.861428 -94.917006) (xy 197.861428 -95.425006)
				)
			)
		)
		(zone
			(layer "B.Cu")
			(hatch none 0.5)
			(connect_pads
				(clearance 0)
			)
			(min_thickness 0.25)
			(keepout
				(tracks allowed)
				(vias not_allowed)
				(pads allowed)
				(copperpour not_allowed)
				(footprints allowed)
			)
			(placement
				(enabled no)
				(sheetname "")
			)
			(fill
				(thermal_gap 0.5)
				(thermal_bridge_width 0.5)
				(island_removal_mode 0)
			)
			(polygon
				(pts
					(xy 197.480428 -95.425006) (xy 197.480428 -94.917006) (xy 197.861428 -94.917006) (xy 197.861428 -95.425006)
				)
			)
		)
	)
	(footprint ""
		(layer "B.Cu")
		(at 40.936418 -103.482648 90)
		(property "Reference" "R1C12"
			(at 0.8382 -0.67818 90)
			(unlocked yes)
			(layer "B.SilkS")
			(effects
				(font
					(size 0.4064 0.254)
					(thickness 0.1524)
				)
				(justify left mirror)
			)
		)
		(property "Value" ""
			(at 0 0 90)
			(layer "B.Fab")
			(effects
				(font
					(size 1.27 1.27)
				)
				(justify mirror)
			)
		)
		(duplicate_pad_numbers_are_jumpers no)
		(fp_poly
			(pts
				(xy 0.2794 -0.1016) (xy -0.2794 -0.1016) (xy -0.2794 0.9906) (xy 0.2794 0.9906)
			)
			(stroke
				(width 0)
				(type default)
			)
			(fill no)
			(layer "B.CrtYd")
		)
		(fp_line
			(start 0.2794 -0.1016)
			(end 0.2794 0.9906)
			(stroke
				(width 0.1)
				(type default)
			)
			(layer "B.Fab")
		)
		(fp_line
			(start -0.2794 -0.1016)
			(end 0.2794 -0.1016)
			(stroke
				(width 0.1)
				(type default)
			)
			(layer "B.Fab")
		)
		(fp_line
			(start 0.2794 0.9906)
			(end -0.2794 0.9906)
			(stroke
				(width 0.1)
				(type default)
			)
			(layer "B.Fab")
		)
		(fp_line
			(start -0.2794 0.9906)
			(end -0.2794 -0.1016)
			(stroke
				(width 0.1)
				(type default)
			)
			(layer "B.Fab")
		)
		(pad "1" smd rect
			(at 0 0 270)
			(size 0.508 0.508)
			(layers "B.Cu" "B.Mask" "B.Paste")
			(net "VSENSE_PVSA_CPU1_P")
		)
		(pad "2" smd rect
			(at 0 0.889 270)
			(size 0.508 0.508)
			(layers "B.Cu" "B.Mask" "B.Paste")
			(net "PVSA_CPU1")
		)
		(zone
			(layer "B.Cu")
			(hatch none 0.5)
			(connect_pads
				(clearance 0)
			)
			(min_thickness 0.25)
			(keepout
				(tracks allowed)
				(vias not_allowed)
				(pads allowed)
				(copperpour not_allowed)
				(footprints allowed)
			)
			(placement
				(enabled no)
				(sheetname "")
			)
			(fill
				(thermal_gap 0.5)
				(thermal_bridge_width 0.5)
				(island_removal_mode 0)
			)
			(polygon
				(pts
					(xy 41.190418 -103.736648) (xy 41.190418 -103.228648) (xy 41.571418 -103.228648) (xy 41.571418 -103.736648)
				)
			)
		)
		(zone
			(layer "B.Cu")
			(hatch none 0.5)
			(connect_pads
				(clearance 0)
			)
			(min_thickness 0.25)
			(keepout
				(tracks not_allowed)
				(vias allowed)
				(pads allowed)
				(copperpour not_allowed)
				(footprints allowed)
			)
			(placement
				(enabled no)
				(sheetname "")
			)
			(fill
				(thermal_gap 0.5)
				(thermal_bridge_width 0.5)
				(island_removal_mode 0)
			)
			(polygon
				(pts
					(xy 41.571418 -103.736648) (xy 41.571418 -103.228648) (xy 41.190418 -103.228648) (xy 41.190418 -103.736648)
				)
			)
		)
	)
	(footprint ""
		(layer "B.Cu")
		(at 386.08 -87.3125 180)
		(property "Reference" "R3N10"
			(at 0 0 0)
			(layer "B.SilkS")
			(hide yes)
			(effects
				(font
					(size 1.27 1.27)
				)
				(justify mirror)
			)
		)
		(property "Value" ""
			(at 0 0 0)
			(layer "B.Fab")
			(effects
				(font
					(size 1.27 1.27)
				)
				(justify mirror)
			)
		)
		(duplicate_pad_numbers_are_jumpers no)
		(fp_poly
			(pts
				(xy 0.2794 -0.1016) (xy -0.2794 -0.1016) (xy -0.2794 0.9906) (xy 0.2794 0.9906)
			)
			(stroke
				(width 0)
				(type default)
			)
			(fill no)
			(layer "B.CrtYd")
		)
		(fp_line
			(start 0.2794 0.9906)
			(end -0.2794 0.9906)
			(stroke
				(width 0.1)
				(type default)
			)
			(layer "B.Fab")
		)
		(fp_line
			(start 0.2794 -0.1016)
			(end 0.2794 0.9906)
			(stroke
				(width 0.1)
				(type default)
			)
			(layer "B.Fab")
		)
		(fp_line
			(start -0.2794 0.9906)
			(end -0.2794 -0.1016)
			(stroke
				(width 0.1)
				(type default)
			)
			(layer "B.Fab")
		)
		(fp_line
			(start -0.2794 -0.1016)
			(end 0.2794 -0.1016)
			(stroke
				(width 0.1)
				(type default)
			)
			(layer "B.Fab")
		)
		(pad "1" smd rect
			(at 0 0)
			(size 0.508 0.508)
			(layers "B.Cu" "B.Mask" "B.Paste")
			(net "P3V3_STBY")
		)
		(pad "2" smd rect
			(at 0 0.889)
			(size 0.508 0.508)
			(layers "B.Cu" "B.Mask" "B.Paste")
			(net "FM_INTRUDER_HDR_PCH_N")
		)
		(zone
			(layer "B.Cu")
			(hatch none 0.5)
			(connect_pads
				(clearance 0)
			)
			(min_thickness 0.25)
			(keepout
				(tracks not_allowed)
				(vias allowed)
				(pads allowed)
				(copperpour not_allowed)
				(footprints allowed)
			)
			(placement
				(enabled no)
				(sheetname "")
			)
			(fill
				(thermal_gap 0.5)
				(thermal_bridge_width 0.5)
				(island_removal_mode 0)
			)
			(polygon
				(pts
					(xy 385.826 -87.9475) (xy 386.334 -87.9475) (xy 386.334 -87.5665) (xy 385.826 -87.5665)
				)
			)
		)
		(zone
			(layer "B.Cu")
			(hatch none 0.5)
			(connect_pads
				(clearance 0)
			)
			(min_thickness 0.25)
			(keepout
				(tracks allowed)
				(vias not_allowed)
				(pads allowed)
				(copperpour not_allowed)
				(footprints allowed)
			)
			(placement
				(enabled no)
				(sheetname "")
			)
			(fill
				(thermal_gap 0.5)
				(thermal_bridge_width 0.5)
				(island_removal_mode 0)
			)
			(polygon
				(pts
					(xy 385.826 -87.5665) (xy 386.334 -87.5665) (xy 386.334 -87.9475) (xy 385.826 -87.9475)
				)
			)
		)
	)
	(footprint ""
		(layer "B.Cu")
		(at 322.0847 -27.34818 -90)
		(property "Reference" "R4T10"
			(at 0 0 90)
			(layer "B.SilkS")
			(hide yes)
			(effects
				(font
					(size 1.27 1.27)
				)
				(justify mirror)
			)
		)
		(property "Value" ""
			(at 0 0 90)
			(layer "B.Fab")
			(effects
				(font
					(size 1.27 1.27)
				)
				(justify mirror)
			)
		)
		(duplicate_pad_numbers_are_jumpers no)
		(fp_poly
			(pts
				(xy 0.2794 -0.1016) (xy -0.2794 -0.1016) (xy -0.2794 0.9906) (xy 0.2794 0.9906)
			)
			(stroke
				(width 0)
				(type default)
			)
			(fill no)
			(layer "B.CrtYd")
		)
		(fp_line
			(start -0.2794 0.9906)
			(end -0.2794 -0.1016)
			(stroke
				(width 0.1)
				(type default)
			)
			(layer "B.Fab")
		)
		(fp_line
			(start 0.2794 0.9906)
			(end -0.2794 0.9906)
			(stroke
				(width 0.1)
				(type default)
			)
			(layer "B.Fab")
		)
		(fp_line
			(start -0.2794 -0.1016)
			(end 0.2794 -0.1016)
			(stroke
				(width 0.1)
				(type default)
			)
			(layer "B.Fab")
		)
		(fp_line
			(start 0.2794 -0.1016)
			(end 0.2794 0.9906)
			(stroke
				(width 0.1)
				(type default)
			)
			(layer "B.Fab")
		)
		(pad "1" smd rect
			(at 0 0 90)
			(size 0.508 0.508)
			(layers "B.Cu" "B.Mask" "B.Paste")
			(net "SMB_DDR_ABC_VPP_SDA_R")
		)
		(pad "2" smd rect
			(at 0 0.889 90)
			(size 0.508 0.508)
			(layers "B.Cu" "B.Mask" "B.Paste")
			(net "SMB_DDR_ABC_VPP_SDA")
		)
		(zone
			(layer "B.Cu")
			(hatch none 0.5)
			(connect_pads
				(clearance 0)
			)
			(min_thickness 0.25)
			(keepout
				(tracks not_allowed)
				(vias allowed)
				(pads allowed)
				(copperpour not_allowed)
				(footprints allowed)
			)
			(placement
				(enabled no)
				(sheetname "")
			)
			(fill
				(thermal_gap 0.5)
				(thermal_bridge_width 0.5)
				(island_removal_mode 0)
			)
			(polygon
				(pts
					(xy 321.4497 -27.09418) (xy 321.4497 -27.60218) (xy 321.8307 -27.60218) (xy 321.8307 -27.09418)
				)
			)
		)
		(zone
			(layer "B.Cu")
			(hatch none 0.5)
			(connect_pads
				(clearance 0)
			)
			(min_thickness 0.25)
			(keepout
				(tracks allowed)
				(vias not_allowed)
				(pads allowed)
				(copperpour not_allowed)
				(footprints allowed)
			)
			(placement
				(enabled no)
				(sheetname "")
			)
			(fill
				(thermal_gap 0.5)
				(thermal_bridge_width 0.5)
				(island_removal_mode 0)
			)
			(polygon
				(pts
					(xy 321.8307 -27.09418) (xy 321.8307 -27.60218) (xy 321.4497 -27.60218) (xy 321.4497 -27.09418)
				)
			)
		)
	)
	(footprint ""
		(layer "B.Cu")
		(at 1.38176 -5.35686 90)
		(property "Reference" "CT30"
			(at 0.43307 14.8844 180)
			(unlocked yes)
			(layer "B.SilkS")
			(effects
				(font
					(size 0.7874 0.5842)
					(thickness 0.1524)
				)
				(justify left mirror)
			)
		)
		(property "Value" ""
			(at 0 0 90)
			(layer "B.Fab")
			(effects
				(font
					(size 1.27 1.27)
				)
				(justify mirror)
			)
		)
		(duplicate_pad_numbers_are_jumpers no)
		(fp_rect
			(start -0.3048 -0.1016)
			(end 0.3048 0.9906)
			(stroke
				(width 0)
				(type default)
			)
			(fill no)
			(layer "B.CrtYd")
		)
		(fp_line
			(start 0.3048 -0.1016)
			(end 0.3048 0.9906)
			(stroke
				(width 0.1)
				(type default)
			)
			(layer "B.Fab")
		)
		(fp_line
			(start -0.3048 -0.1016)
			(end 0.3048 -0.1016)
			(stroke
				(width 0.1)
				(type default)
			)
			(layer "B.Fab")
		)
		(fp_line
			(start 0.3048 0.9906)
			(end -0.3048 0.9906)
			(stroke
				(width 0.1)
				(type default)
			)
			(layer "B.Fab")
		)
		(fp_line
			(start -0.3048 0.9906)
			(end -0.3048 -0.1016)
			(stroke
				(width 0.1)
				(type default)
			)
			(layer "B.Fab")
		)
		(pad "1" smd rect
			(at 0 0 270)
			(size 0.508 0.508)
			(layers "B.Cu" "B.Mask" "B.Paste")
			(net "VR_PVDDQ_GHJ_AIREF1")
		)
		(pad "2" smd rect
			(at 0 0.889 270)
			(size 0.508 0.508)
			(layers "B.Cu" "B.Mask" "B.Paste")
			(net "GND")
		)
		(zone
			(layer "B.Cu")
			(hatch none 0.5)
			(connect_pads
				(clearance 0)
			)
			(min_thickness 0.25)
			(keepout
				(tracks allowed)
				(vias not_allowed)
				(pads allowed)
				(copperpour not_allowed)
				(footprints allowed)
			)
			(placement
				(enabled no)
				(sheetname "")
			)
			(fill
				(thermal_gap 0.5)
				(thermal_bridge_width 0.5)
				(island_removal_mode 0)
			)
			(polygon
				(pts
					(xy 1.63576 -5.10286) (xy 2.01676 -5.10286) (xy 2.01676 -5.61086) (xy 1.63576 -5.61086)
				)
			)
		)
		(zone
			(layer "B.Cu")
			(hatch none 0.5)
			(connect_pads
				(clearance 0)
			)
			(min_thickness 0.25)
			(keepout
				(tracks not_allowed)
				(vias allowed)
				(pads allowed)
				(copperpour not_allowed)
				(footprints allowed)
			)
			(placement
				(enabled no)
				(sheetname "")
			)
			(fill
				(thermal_gap 0.5)
				(thermal_bridge_width 0.5)
				(island_removal_mode 0)
			)
			(polygon
				(pts
					(xy 1.63576 -5.10286) (xy 2.01676 -5.10286) (xy 2.01676 -5.61086) (xy 1.63576 -5.61086)
				)
			)
		)
	)
	(footprint ""
		(layer "B.Cu")
		(at 293.881302 -65.417192)
		(property "Reference" "R4P24"
			(at 0 0 0)
			(layer "B.SilkS")
			(hide yes)
			(effects
				(font
					(size 1.27 1.27)
				)
				(justify mirror)
			)
		)
		(property "Value" ""
			(at 0 0 0)
			(layer "B.Fab")
			(effects
				(font
					(size 1.27 1.27)
				)
				(justify mirror)
			)
		)
		(duplicate_pad_numbers_are_jumpers no)
		(fp_rect
			(start 0.2794 -0.1016)
			(end -0.2794 0.9906)
			(stroke
				(width 0)
				(type default)
			)
			(fill no)
			(layer "B.CrtYd")
		)
		(fp_line
			(start -0.2794 -0.1016)
			(end 0.2794 -0.1016)
			(stroke
				(width 0.1)
				(type default)
			)
			(layer "B.Fab")
		)
		(fp_line
			(start -0.2794 0.9906)
			(end -0.2794 -0.1016)
			(stroke
				(width 0.1)
				(type default)
			)
			(layer "B.Fab")
		)
		(fp_line
			(start 0.2794 -0.1016)
			(end 0.2794 0.9906)
			(stroke
				(width 0.1)
				(type default)
			)
			(layer "B.Fab")
		)
		(fp_line
			(start 0.2794 0.9906)
			(end -0.2794 0.9906)
			(stroke
				(width 0.1)
				(type default)
			)
			(layer "B.Fab")
		)
		(pad "1" smd rect
			(at 0 0 180)
			(size 0.508 0.508)
			(layers "B.Cu" "B.Mask" "B.Paste")
			(net "PVCCIO_CPU0")
		)
		(pad "2" smd rect
			(at 0 0.889 180)
			(size 0.508 0.508)
			(layers "B.Cu" "B.Mask" "B.Paste")
			(net "XDP_CPU_TDI")
		)
		(zone
			(layer "B.Cu")
			(hatch none 0.5)
			(connect_pads
				(clearance 0)
			)
			(min_thickness 0.25)
			(keepout
				(tracks not_allowed)
				(vias allowed)
				(pads allowed)
				(copperpour not_allowed)
				(footprints allowed)
			)
			(placement
				(enabled no)
				(sheetname "")
			)
			(fill
				(thermal_gap 0.5)
				(thermal_bridge_width 0.5)
				(island_removal_mode 0)
			)
			(polygon
				(pts
					(xy 294.135302 -65.163192) (xy 293.627302 -65.163192) (xy 293.627302 -64.782192) (xy 294.135302 -64.782192)
				)
			)
		)
		(zone
			(layer "B.Cu")
			(hatch none 0.5)
			(connect_pads
				(clearance 0)
			)
			(min_thickness 0.25)
			(keepout
				(tracks allowed)
				(vias not_allowed)
				(pads allowed)
				(copperpour not_allowed)
				(footprints allowed)
			)
			(placement
				(enabled no)
				(sheetname "")
			)
			(fill
				(thermal_gap 0.5)
				(thermal_bridge_width 0.5)
				(island_removal_mode 0)
			)
			(polygon
				(pts
					(xy 294.135302 -65.163192) (xy 293.627302 -65.163192) (xy 293.627302 -64.782192) (xy 294.135302 -64.782192)
				)
			)
		)
	)
	(footprint ""
		(layer "B.Cu")
		(at 404.0378 -116.7765 180)
		(property "Reference" "C2M13"
			(at 0 0 0)
			(layer "B.SilkS")
			(hide yes)
			(effects
				(font
					(size 1.27 1.27)
				)
				(justify mirror)
			)
		)
		(property "Value" ""
			(at 0 0 0)
			(layer "B.Fab")
			(effects
				(font
					(size 1.27 1.27)
				)
				(justify mirror)
			)
		)
		(duplicate_pad_numbers_are_jumpers no)
		(fp_poly
			(pts
				(xy 0.4953 -0.2032) (xy -0.4953 -0.2032) (xy -0.4953 1.6002) (xy 0.4953 1.6002)
			)
			(stroke
				(width 0)
				(type default)
			)
			(fill no)
			(layer "B.CrtYd")
		)
		(fp_line
			(start 0.4953 1.6002)
			(end 0.4953 -0.2032)
			(stroke
				(width 0.1)
				(type default)
			)
			(layer "B.Fab")
		)
		(fp_line
			(start 0.4953 -0.2032)
			(end -0.4953 -0.2032)
			(stroke
				(width 0.1)
				(type default)
			)
			(layer "B.Fab")
		)
		(fp_line
			(start -0.4953 1.6002)
			(end 0.4953 1.6002)
			(stroke
				(width 0.1)
				(type default)
			)
			(layer "B.Fab")
		)
		(fp_line
			(start -0.4953 -0.2032)
			(end -0.4953 1.6002)
			(stroke
				(width 0.1)
				(type default)
			)
			(layer "B.Fab")
		)
		(pad "1" smd rect
			(at 0 0)
			(size 0.762 0.889)
			(layers "B.Cu" "B.Mask" "B.Paste")
			(net "P1V05_PCH_STBY")
		)
		(pad "2" smd rect
			(at 0 1.397)
			(size 0.762 0.889)
			(layers "B.Cu" "B.Mask" "B.Paste")
			(net "GND")
		)
		(zone
			(layer "B.Cu")
			(hatch none 0.5)
			(connect_pads
				(clearance 0)
			)
			(min_thickness 0.25)
			(keepout
				(tracks not_allowed)
				(vias allowed)
				(pads allowed)
				(copperpour not_allowed)
				(footprints allowed)
			)
			(placement
				(enabled no)
				(sheetname "")
			)
			(fill
				(thermal_gap 0.5)
				(thermal_bridge_width 0.5)
				(island_removal_mode 0)
			)
			(polygon
				(pts
					(xy 403.6568 -117.221) (xy 404.4188 -117.221) (xy 404.4188 -117.729) (xy 403.6568 -117.729)
				)
			)
		)
	)
	(footprint ""
		(layer "B.Cu")
		(at 164.973 -66.3702 90)
		(property "Reference" "R6P41"
			(at 0 0 90)
			(layer "B.SilkS")
			(hide yes)
			(effects
				(font
					(size 1.27 1.27)
				)
				(justify mirror)
			)
		)
		(property "Value" ""
			(at 0 0 90)
			(layer "B.Fab")
			(effects
				(font
					(size 1.27 1.27)
				)
				(justify mirror)
			)
		)
		(duplicate_pad_numbers_are_jumpers no)
		(fp_poly
			(pts
				(xy 0.2794 -0.1016) (xy -0.2794 -0.1016) (xy -0.2794 0.9906) (xy 0.2794 0.9906)
			)
			(stroke
				(width 0)
				(type default)
			)
			(fill no)
			(layer "B.CrtYd")
		)
		(fp_line
			(start 0.2794 -0.1016)
			(end 0.2794 0.9906)
			(stroke
				(width 0.1)
				(type default)
			)
			(layer "B.Fab")
		)
		(fp_line
			(start -0.2794 -0.1016)
			(end 0.2794 -0.1016)
			(stroke
				(width 0.1)
				(type default)
			)
			(layer "B.Fab")
		)
		(fp_line
			(start 0.2794 0.9906)
			(end -0.2794 0.9906)
			(stroke
				(width 0.1)
				(type default)
			)
			(layer "B.Fab")
		)
		(fp_line
			(start -0.2794 0.9906)
			(end -0.2794 -0.1016)
			(stroke
				(width 0.1)
				(type default)
			)
			(layer "B.Fab")
		)
		(pad "1" smd rect
			(at 0 0 270)
			(size 0.508 0.508)
			(layers "B.Cu" "B.Mask" "B.Paste")
			(net "FM_PVCCIO_CPU1_EN")
		)
		(pad "2" smd rect
			(at 0 0.889 270)
			(size 0.508 0.508)
			(layers "B.Cu" "B.Mask" "B.Paste")
			(net "VR_PVCCIO_CPU1_EN")
		)
		(zone
			(layer "B.Cu")
			(hatch none 0.5)
			(connect_pads
				(clearance 0)
			)
			(min_thickness 0.25)
			(keepout
				(tracks allowed)
				(vias not_allowed)
				(pads allowed)
				(copperpour not_allowed)
				(footprints allowed)
			)
			(placement
				(enabled no)
				(sheetname "")
			)
			(fill
				(thermal_gap 0.5)
				(thermal_bridge_width 0.5)
				(island_removal_mode 0)
			)
			(polygon
				(pts
					(xy 165.227 -66.6242) (xy 165.227 -66.1162) (xy 165.608 -66.1162) (xy 165.608 -66.6242)
				)
			)
		)
		(zone
			(layer "B.Cu")
			(hatch none 0.5)
			(connect_pads
				(clearance 0)
			)
			(min_thickness 0.25)
			(keepout
				(tracks not_allowed)
				(vias allowed)
				(pads allowed)
				(copperpour not_allowed)
				(footprints allowed)
			)
			(placement
				(enabled no)
				(sheetname "")
			)
			(fill
				(thermal_gap 0.5)
				(thermal_bridge_width 0.5)
				(island_removal_mode 0)
			)
			(polygon
				(pts
					(xy 165.608 -66.6242) (xy 165.608 -66.1162) (xy 165.227 -66.1162) (xy 165.227 -66.6242)
				)
			)
		)
	)
	(footprint ""
		(layer "B.Cu")
		(at 274.066 3.81 90)
		(property "Reference" "C5U13"
			(at 0 0 90)
			(layer "B.SilkS")
			(hide yes)
			(effects
				(font
					(size 1.27 1.27)
				)
				(justify mirror)
			)
		)
		(property "Value" ""
			(at 0 0 90)
			(layer "B.Fab")
			(effects
				(font
					(size 1.27 1.27)
				)
				(justify mirror)
			)
		)
		(duplicate_pad_numbers_are_jumpers no)
		(fp_rect
			(start -0.7239 -0.2159)
			(end 0.7239 1.9939)
			(stroke
				(width 0)
				(type default)
			)
			(fill no)
			(layer "B.CrtYd")
		)
		(fp_line
			(start 0.7239 -0.2159)
			(end 0.7239 1.9939)
			(stroke
				(width 0.1)
				(type default)
			)
			(layer "B.Fab")
		)
		(fp_line
			(start -0.7239 -0.2159)
			(end 0.7239 -0.2159)
			(stroke
				(width 0.1)
				(type default)
			)
			(layer "B.Fab")
		)
		(fp_line
			(start 0.7239 1.9939)
			(end -0.7239 1.9939)
			(stroke
				(width 0.1)
				(type default)
			)
			(layer "B.Fab")
		)
		(fp_line
			(start -0.7239 1.9939)
			(end -0.7239 -0.2159)
			(stroke
				(width 0.1)
				(type default)
			)
			(layer "B.Fab")
		)
		(pad "1" smd rect
			(at 0 0 270)
			(size 1.27 1.016)
			(layers "B.Cu" "B.Mask" "B.Paste")
			(net "PVDDQ_ABC")
		)
		(pad "2" smd rect
			(at 0 1.778 270)
			(size 1.27 1.016)
			(layers "B.Cu" "B.Mask" "B.Paste")
			(net "GND")
		)
		(zone
			(layer "B.Cu")
			(hatch none 0.5)
			(connect_pads
				(clearance 0)
			)
			(min_thickness 0.25)
			(keepout
				(tracks not_allowed)
				(vias allowed)
				(pads allowed)
				(copperpour not_allowed)
				(footprints allowed)
			)
			(placement
				(enabled no)
				(sheetname "")
			)
			(fill
				(thermal_gap 0.5)
				(thermal_bridge_width 0.5)
				(island_removal_mode 0)
			)
			(polygon
				(pts
					(xy 274.574 4.445) (xy 275.336 4.445) (xy 275.336 3.175) (xy 274.574 3.175)
				)
			)
		)
	)
	(footprint ""
		(layer "B.Cu")
		(at 172.6692 -135.636)
		(property "Reference" "C6L12"
			(at 0 0 0)
			(layer "B.SilkS")
			(hide yes)
			(effects
				(font
					(size 1.27 1.27)
				)
				(justify mirror)
			)
		)
		(property "Value" ""
			(at 0 0 0)
			(layer "B.Fab")
			(effects
				(font
					(size 1.27 1.27)
				)
				(justify mirror)
			)
		)
		(duplicate_pad_numbers_are_jumpers no)
		(fp_poly
			(pts
				(xy 0.4953 -0.2032) (xy -0.4953 -0.2032) (xy -0.4953 1.6002) (xy 0.4953 1.6002)
			)
			(stroke
				(width 0)
				(type default)
			)
			(fill no)
			(layer "B.CrtYd")
		)
		(fp_line
			(start -0.4953 -0.2032)
			(end -0.4953 1.6002)
			(stroke
				(width 0.1)
				(type default)
			)
			(layer "B.Fab")
		)
		(fp_line
			(start -0.4953 1.6002)
			(end 0.4953 1.6002)
			(stroke
				(width 0.1)
				(type default)
			)
			(layer "B.Fab")
		)
		(fp_line
			(start 0.4953 -0.2032)
			(end -0.4953 -0.2032)
			(stroke
				(width 0.1)
				(type default)
			)
			(layer "B.Fab")
		)
		(fp_line
			(start 0.4953 1.6002)
			(end 0.4953 -0.2032)
			(stroke
				(width 0.1)
				(type default)
			)
			(layer "B.Fab")
		)
		(pad "1" smd rect
			(at 0 0 180)
			(size 0.762 0.889)
			(layers "B.Cu" "B.Mask" "B.Paste")
			(net "VR_VB_PVPP_KLM")
		)
		(pad "2" smd rect
			(at 0 1.397 180)
			(size 0.762 0.889)
			(layers "B.Cu" "B.Mask" "B.Paste")
			(net "AGND_PVPP_KLM")
		)
		(zone
			(layer "B.Cu")
			(hatch none 0.5)
			(connect_pads
				(clearance 0)
			)
			(min_thickness 0.25)
			(keepout
				(tracks not_allowed)
				(vias allowed)
				(pads allowed)
				(copperpour not_allowed)
				(footprints allowed)
			)
			(placement
				(enabled no)
				(sheetname "")
			)
			(fill
				(thermal_gap 0.5)
				(thermal_bridge_width 0.5)
				(island_removal_mode 0)
			)
			(polygon
				(pts
					(xy 173.0502 -135.1915) (xy 172.2882 -135.1915) (xy 172.2882 -134.6835) (xy 173.0502 -134.6835)
				)
			)
		)
	)
	(footprint ""
		(layer "B.Cu")
		(at 169.037 -4.699 90)
		(property "Reference" "C6U13"
			(at 0 0 90)
			(layer "B.SilkS")
			(hide yes)
			(effects
				(font
					(size 1.27 1.27)
				)
				(justify mirror)
			)
		)
		(property "Value" ""
			(at 0 0 90)
			(layer "B.Fab")
			(effects
				(font
					(size 1.27 1.27)
				)
				(justify mirror)
			)
		)
		(duplicate_pad_numbers_are_jumpers no)
		(fp_rect
			(start 0.4953 1.6002)
			(end -0.4953 -0.2032)
			(stroke
				(width 0)
				(type default)
			)
			(fill no)
			(layer "B.CrtYd")
		)
		(fp_line
			(start 0.4953 -0.2032)
			(end -0.4953 -0.2032)
			(stroke
				(width 0.1)
				(type default)
			)
			(layer "B.Fab")
		)
		(fp_line
			(start -0.4953 -0.2032)
			(end -0.4953 1.6002)
			(stroke
				(width 0.1)
				(type default)
			)
			(layer "B.Fab")
		)
		(fp_line
			(start 0.4953 1.6002)
			(end 0.4953 -0.2032)
			(stroke
				(width 0.1)
				(type default)
			)
			(layer "B.Fab")
		)
		(fp_line
			(start -0.4953 1.6002)
			(end 0.4953 1.6002)
			(stroke
				(width 0.1)
				(type default)
			)
			(layer "B.Fab")
		)
		(pad "1" smd rect
			(at 0 0 270)
			(size 0.762 0.889)
			(layers "B.Cu" "B.Mask" "B.Paste")
			(net "PVDDQ_GHJ")
		)
		(pad "2" smd rect
			(at 0 1.397 270)
			(size 0.762 0.889)
			(layers "B.Cu" "B.Mask" "B.Paste")
			(net "GND")
		)
		(zone
			(layer "B.Cu")
			(hatch none 0.5)
			(connect_pads
				(clearance 0)
			)
			(min_thickness 0.25)
			(keepout
				(tracks not_allowed)
				(vias allowed)
				(pads allowed)
				(copperpour not_allowed)
				(footprints allowed)
			)
			(placement
				(enabled no)
				(sheetname "")
			)
			(fill
				(thermal_gap 0.5)
				(thermal_bridge_width 0.5)
				(island_removal_mode 0)
			)
			(polygon
				(pts
					(xy 169.9895 -5.08) (xy 169.4815 -5.08) (xy 169.4815 -4.318) (xy 169.9895 -4.318)
				)
			)
		)
	)
	(footprint ""
		(layer "B.Cu")
		(at 498.487954 -47.771812)
		(property "Reference" "CR25W2"
			(at 1.495806 -1.067816 0)
			(unlocked yes)
			(layer "B.SilkS")
			(effects
				(font
					(size 0.4064 0.254)
					(thickness 0.1524)
				)
				(justify left mirror)
			)
		)
		(property "Value" ""
			(at 0 0 0)
			(layer "B.Fab")
			(effects
				(font
					(size 1.27 1.27)
				)
				(justify mirror)
			)
		)
		(duplicate_pad_numbers_are_jumpers no)
		(fp_circle
			(center 0.589026 -0.5334)
			(end 0.716026 -0.5334)
			(stroke
				(width 0.254)
				(type default)
			)
			(fill no)
			(layer "B.SilkS")
		)
		(fp_rect
			(start 0.225552 2.167382)
			(end -0.809498 -0.167386)
			(stroke
				(width 0)
				(type default)
			)
			(fill no)
			(layer "B.CrtYd")
		)
		(fp_line
			(start -0.809498 -0.167386)
			(end -0.809498 2.167382)
			(stroke
				(width 0.1)
				(type default)
			)
			(layer "B.Fab")
		)
		(fp_line
			(start -0.809498 2.167382)
			(end 0.225552 2.167382)
			(stroke
				(width 0.1)
				(type default)
			)
			(layer "B.Fab")
		)
		(fp_line
			(start 0.225552 -0.167386)
			(end -0.809498 -0.167386)
			(stroke
				(width 0.1)
				(type default)
			)
			(layer "B.Fab")
		)
		(fp_line
			(start 0.225552 2.167382)
			(end 0.225552 -0.167386)
			(stroke
				(width 0.1)
				(type default)
			)
			(layer "B.Fab")
		)
		(fp_circle
			(center 0.589026 -0.5334)
			(end 0.716026 -0.5334)
			(stroke
				(width 0.254)
				(type default)
			)
			(fill no)
			(layer "B.Fab")
		)
		(pad "1" smd rect
			(at 0 0 180)
			(size 0.3556 0.2032)
			(layers "B.Cu" "B.Mask" "B.Paste")
			(net "V_IBMC_5V_DDC_SDA_J")
		)
		(pad "2" smd rect
			(at 0 0.500126 180)
			(size 0.3556 0.2032)
			(layers "B.Cu" "B.Mask" "B.Paste")
			(net "V_IBMC_5V_DDC_SCL_J")
		)
		(pad "3" smd rect
			(at -0.2921 0.999998 180)
			(size 0.9398 0.4064)
			(layers "B.Cu" "B.Mask" "B.Paste")
			(net "GND")
		)
		(pad "4" smd rect
			(at 0 1.500124 180)
			(size 0.3556 0.2032)
			(layers "B.Cu" "B.Mask" "B.Paste")
			(net "V_IO_VSYNC_J")
		)
		(pad "5" smd rect
			(at 0 1.999996 180)
			(size 0.3556 0.2032)
			(layers "B.Cu" "B.Mask" "B.Paste")
			(net "V_IO_HSYNC_J")
		)
		(pad "6" smd rect
			(at -0.583946 1.999996 180)
			(size 0.3556 0.2032)
			(layers "B.Cu" "B.Mask" "B.Paste")
			(net "V_IO_HSYNC_J")
		)
		(pad "7" smd rect
			(at -0.583946 1.500124 180)
			(size 0.3556 0.2032)
			(layers "B.Cu" "B.Mask" "B.Paste")
			(net "V_IO_VSYNC_J")
		)
		(pad "8" smd rect
			(at -0.583946 0.500126 180)
			(size 0.3556 0.2032)
			(layers "B.Cu" "B.Mask" "B.Paste")
			(net "V_IBMC_5V_DDC_SCL_J")
		)
		(pad "9" smd rect
			(at -0.583946 0 180)
			(size 0.3556 0.2032)
			(layers "B.Cu" "B.Mask" "B.Paste")
			(net "V_IBMC_5V_DDC_SDA_J")
		)
	)
	(footprint ""
		(layer "B.Cu")
		(at 363.032294 -145.471642)
		(property "Reference" "C7W7"
			(at 0 0 0)
			(layer "B.SilkS")
			(hide yes)
			(effects
				(font
					(size 1.27 1.27)
				)
				(justify mirror)
			)
		)
		(property "Value" "*"
			(at 0.0762 -6.2357 0)
			(unlocked yes)
			(layer "B.Fab")
			(hide yes)
			(effects
				(font
					(size 1.27 1.016)
					(thickness 0.1524)
				)
				(justify mirror)
			)
		)
		(property "Device Type" "SC22U16V5MX-4-GP_SMD-BCG5-SC22A"
			(at 0.0762 -8.2677 0)
			(unlocked yes)
			(layer "B.Fab")
			(hide yes)
			(effects
				(font
					(size 1.27 1.016)
					(thickness 0.1524)
				)
				(justify mirror)
			)
		)
		(duplicate_pad_numbers_are_jumpers no)
		(fp_line
			(start -0.635 0)
			(end 0.635 0)
			(stroke
				(width 0.508)
				(type default)
			)
			(layer "B.SilkS")
		)
		(fp_rect
			(start 0.9652 1.778)
			(end -0.9652 -1.778)
			(stroke
				(width 0)
				(type default)
			)
			(fill no)
			(layer "B.CrtYd")
		)
		(fp_poly
			(pts
				(xy 0.9652 -1.778) (xy -0.9652 -1.778) (xy -0.9652 1.778) (xy 0.9652 1.778)
			)
			(stroke
				(width 0)
				(type default)
			)
			(fill no)
			(layer "B.Fab")
		)
		(pad "1" smd rect
			(at 0 -0.9652 180)
			(size 1.397 1.143)
			(layers "B.Cu" "B.Mask" "B.Paste")
			(net "VR_FET_SW_P12V_STBY_PVDDQ_DEF")
		)
		(pad "2" smd rect
			(at 0 0.9652 180)
			(size 1.397 1.143)
			(layers "B.Cu" "B.Mask" "B.Paste")
			(net "GND")
		)
	)
	(footprint ""
		(layer "B.Cu")
		(at 393.0396 -37.1348 180)
		(property "Reference" "R2T18"
			(at 0 0 0)
			(layer "B.SilkS")
			(hide yes)
			(effects
				(font
					(size 1.27 1.27)
				)
				(justify mirror)
			)
		)
		(property "Value" ""
			(at 0 0 0)
			(layer "B.Fab")
			(effects
				(font
					(size 1.27 1.27)
				)
				(justify mirror)
			)
		)
		(duplicate_pad_numbers_are_jumpers no)
		(fp_poly
			(pts
				(xy 0.2794 -0.1016) (xy -0.2794 -0.1016) (xy -0.2794 0.9906) (xy 0.2794 0.9906)
			)
			(stroke
				(width 0)
				(type default)
			)
			(fill no)
			(layer "B.CrtYd")
		)
		(fp_line
			(start 0.2794 0.9906)
			(end -0.2794 0.9906)
			(stroke
				(width 0.1)
				(type default)
			)
			(layer "B.Fab")
		)
		(fp_line
			(start 0.2794 -0.1016)
			(end 0.2794 0.9906)
			(stroke
				(width 0.1)
				(type default)
			)
			(layer "B.Fab")
		)
		(fp_line
			(start -0.2794 0.9906)
			(end -0.2794 -0.1016)
			(stroke
				(width 0.1)
				(type default)
			)
			(layer "B.Fab")
		)
		(fp_line
			(start -0.2794 -0.1016)
			(end 0.2794 -0.1016)
			(stroke
				(width 0.1)
				(type default)
			)
			(layer "B.Fab")
		)
		(pad "1" smd rect
			(at 0 0)
			(size 0.508 0.508)
			(layers "B.Cu" "B.Mask" "B.Paste")
			(net "RST_BMC_SYSRST_BTN_OUT_B_R_N")
		)
		(pad "2" smd rect
			(at 0 0.889)
			(size 0.508 0.508)
			(layers "B.Cu" "B.Mask" "B.Paste")
			(net "RST_BMC_SYSRST_BTN_OUT_B_N")
		)
		(zone
			(layer "B.Cu")
			(hatch none 0.5)
			(connect_pads
				(clearance 0)
			)
			(min_thickness 0.25)
			(keepout
				(tracks not_allowed)
				(vias allowed)
				(pads allowed)
				(copperpour not_allowed)
				(footprints allowed)
			)
			(placement
				(enabled no)
				(sheetname "")
			)
			(fill
				(thermal_gap 0.5)
				(thermal_bridge_width 0.5)
				(island_removal_mode 0)
			)
			(polygon
				(pts
					(xy 392.7856 -37.7698) (xy 393.2936 -37.7698) (xy 393.2936 -37.3888) (xy 392.7856 -37.3888)
				)
			)
		)
		(zone
			(layer "B.Cu")
			(hatch none 0.5)
			(connect_pads
				(clearance 0)
			)
			(min_thickness 0.25)
			(keepout
				(tracks allowed)
				(vias not_allowed)
				(pads allowed)
				(copperpour not_allowed)
				(footprints allowed)
			)
			(placement
				(enabled no)
				(sheetname "")
			)
			(fill
				(thermal_gap 0.5)
				(thermal_bridge_width 0.5)
				(island_removal_mode 0)
			)
			(polygon
				(pts
					(xy 392.7856 -37.3888) (xy 393.2936 -37.3888) (xy 393.2936 -37.7698) (xy 392.7856 -37.7698)
				)
			)
		)
	)
	(footprint ""
		(layer "B.Cu")
		(at 390.93775 -107.85475 90)
		(property "Reference" "C2N11"
			(at 0 0 90)
			(layer "B.SilkS")
			(hide yes)
			(effects
				(font
					(size 1.27 1.27)
				)
				(justify mirror)
			)
		)
		(property "Value" ""
			(at 0 0 90)
			(layer "B.Fab")
			(effects
				(font
					(size 1.27 1.27)
				)
				(justify mirror)
			)
		)
		(duplicate_pad_numbers_are_jumpers no)
		(fp_rect
			(start 0.2794 0.9144)
			(end -0.2794 -0.1143)
			(stroke
				(width 0)
				(type default)
			)
			(fill no)
			(layer "B.CrtYd")
		)
		(fp_line
			(start 0.2794 -0.1143)
			(end -0.2794 -0.1143)
			(stroke
				(width 0.1)
				(type default)
			)
			(layer "B.Fab")
		)
		(fp_line
			(start -0.2794 -0.1143)
			(end -0.2794 0.9144)
			(stroke
				(width 0.1)
				(type default)
			)
			(layer "B.Fab")
		)
		(fp_line
			(start 0.2794 0.9144)
			(end 0.2794 -0.1143)
			(stroke
				(width 0.1)
				(type default)
			)
			(layer "B.Fab")
		)
		(fp_line
			(start -0.2794 0.9144)
			(end 0.2794 0.9144)
			(stroke
				(width 0.1)
				(type default)
			)
			(layer "B.Fab")
		)
		(pad "1" smd custom
			(at 0 0)
			(size 0.10414 0.10414)
			(layers "B.Cu" "B.Mask" "B.Paste")
			(net "PVNN_PCH_STBY")
			(options
				(clearance outline)
				(anchor circle)
			)
			(primitives
				(gr_poly
					(pts
						(xy -0.20828 -0.08636) (xy -0.20828 0.08636) (xy -0.08636 0.20828) (xy 0.086614 0.20828) (xy 0.20828 0.086614)
						(xy 0.20828 -0.08636) (xy 0.08636 -0.20828) (xy -0.08636 -0.20828)
					)
					(width 0)
					(fill yes)
				)
			)
		)
		(pad "2" smd custom
			(at 0 0.8001)
			(size 0.10414 0.10414)
			(layers "B.Cu" "B.Mask" "B.Paste")
			(net "GND")
			(options
				(clearance outline)
				(anchor circle)
			)
			(primitives
				(gr_poly
					(pts
						(xy -0.20828 -0.08636) (xy -0.20828 0.08636) (xy -0.08636 0.20828) (xy 0.086614 0.20828) (xy 0.20828 0.086614)
						(xy 0.20828 -0.08636) (xy 0.08636 -0.20828) (xy -0.08636 -0.20828)
					)
					(width 0)
					(fill yes)
				)
			)
		)
		(zone
			(layer "B.Cu")
			(hatch none 0.5)
			(connect_pads
				(clearance 0)
			)
			(min_thickness 0.25)
			(keepout
				(tracks allowed)
				(vias not_allowed)
				(pads allowed)
				(copperpour not_allowed)
				(footprints allowed)
			)
			(placement
				(enabled no)
				(sheetname "")
			)
			(fill
				(thermal_gap 0.5)
				(thermal_bridge_width 0.5)
				(island_removal_mode 0)
			)
			(polygon
				(pts
					(xy 391.1473 -107.94238) (xy 391.5283 -107.94238) (xy 391.5283 -107.76712) (xy 391.1473 -107.766866)
				)
			)
		)
		(zone
			(layer "B.Cu")
			(hatch none 0.5)
			(connect_pads
				(clearance 0)
			)
			(min_thickness 0.25)
			(keepout
				(tracks not_allowed)
				(vias allowed)
				(pads allowed)
				(copperpour not_allowed)
				(footprints allowed)
			)
			(placement
				(enabled no)
				(sheetname "")
			)
			(fill
				(thermal_gap 0.5)
				(thermal_bridge_width 0.5)
				(island_removal_mode 0)
			)
			(polygon
				(pts
					(xy 391.1473 -107.94238) (xy 391.5283 -107.94238) (xy 391.5283 -107.76712) (xy 391.1473 -107.766866)
				)
			)
		)
	)
	(footprint ""
		(layer "B.Cu")
		(at 27.785568 -154.559 180)
		(property "Reference" "R9L3"
			(at 0 0 0)
			(layer "B.SilkS")
			(hide yes)
			(effects
				(font
					(size 1.27 1.27)
				)
				(justify mirror)
			)
		)
		(property "Value" ""
			(at 0 0 0)
			(layer "B.Fab")
			(effects
				(font
					(size 1.27 1.27)
				)
				(justify mirror)
			)
		)
		(duplicate_pad_numbers_are_jumpers no)
		(fp_poly
			(pts
				(xy 0.2794 -0.1016) (xy -0.2794 -0.1016) (xy -0.2794 0.9906) (xy 0.2794 0.9906)
			)
			(stroke
				(width 0)
				(type default)
			)
			(fill no)
			(layer "B.CrtYd")
		)
		(fp_line
			(start 0.2794 0.9906)
			(end -0.2794 0.9906)
			(stroke
				(width 0.1)
				(type default)
			)
			(layer "B.Fab")
		)
		(fp_line
			(start 0.2794 -0.1016)
			(end 0.2794 0.9906)
			(stroke
				(width 0.1)
				(type default)
			)
			(layer "B.Fab")
		)
		(fp_line
			(start -0.2794 0.9906)
			(end -0.2794 -0.1016)
			(stroke
				(width 0.1)
				(type default)
			)
			(layer "B.Fab")
		)
		(fp_line
			(start -0.2794 -0.1016)
			(end 0.2794 -0.1016)
			(stroke
				(width 0.1)
				(type default)
			)
			(layer "B.Fab")
		)
		(pad "1" smd rect
			(at 0 0)
			(size 0.508 0.508)
			(layers "B.Cu" "B.Mask" "B.Paste")
			(net "M_M_CPU_VREF")
		)
		(pad "2" smd rect
			(at 0 0.889)
			(size 0.508 0.508)
			(layers "B.Cu" "B.Mask" "B.Paste")
			(net "M_M_VREF")
		)
		(zone
			(layer "B.Cu")
			(hatch none 0.5)
			(connect_pads
				(clearance 0)
			)
			(min_thickness 0.25)
			(keepout
				(tracks not_allowed)
				(vias allowed)
				(pads allowed)
				(copperpour not_allowed)
				(footprints allowed)
			)
			(placement
				(enabled no)
				(sheetname "")
			)
			(fill
				(thermal_gap 0.5)
				(thermal_bridge_width 0.5)
				(island_removal_mode 0)
			)
			(polygon
				(pts
					(xy 27.531568 -155.194) (xy 28.039568 -155.194) (xy 28.039568 -154.813) (xy 27.531568 -154.813)
				)
			)
		)
		(zone
			(layer "B.Cu")
			(hatch none 0.5)
			(connect_pads
				(clearance 0)
			)
			(min_thickness 0.25)
			(keepout
				(tracks allowed)
				(vias not_allowed)
				(pads allowed)
				(copperpour not_allowed)
				(footprints allowed)
			)
			(placement
				(enabled no)
				(sheetname "")
			)
			(fill
				(thermal_gap 0.5)
				(thermal_bridge_width 0.5)
				(island_removal_mode 0)
			)
			(polygon
				(pts
					(xy 27.531568 -154.813) (xy 28.039568 -154.813) (xy 28.039568 -155.194) (xy 27.531568 -155.194)
				)
			)
		)
	)
	(footprint ""
		(layer "B.Cu")
		(at 495.676174 -40.573706)
		(property "Reference" "U25W7"
			(at 0 0 0)
			(layer "B.SilkS")
			(hide yes)
			(effects
				(font
					(size 1.27 1.27)
				)
				(justify mirror)
			)
		)
		(property "Value" "*"
			(at 0 -10.7315 0)
			(unlocked yes)
			(layer "B.Fab")
			(hide yes)
			(effects
				(font
					(size 1.27 1.016)
					(thickness 0.1524)
				)
				(justify mirror)
			)
		)
		(property "Device Type" "U74AHCT1G125G-AL5-R-GP-U_TTL-GA"
			(at 0 -12.2555 0)
			(unlocked yes)
			(layer "B.Fab")
			(hide yes)
			(effects
				(font
					(size 1.27 1.016)
					(thickness 0.1524)
				)
				(justify mirror)
			)
		)
		(duplicate_pad_numbers_are_jumpers no)
		(fp_line
			(start -1.24714 -1.79832)
			(end -1.24714 1.82372)
			(stroke
				(width 0.1524)
				(type default)
			)
			(layer "B.SilkS")
		)
		(fp_line
			(start -1.2446 1.81102)
			(end -1.25476 1.82118)
			(stroke
				(width 0.1524)
				(type default)
			)
			(layer "B.SilkS")
		)
		(fp_line
			(start -1.08712 -1.80848)
			(end 1.23952 -1.80848)
			(stroke
				(width 0.1524)
				(type default)
			)
			(layer "B.SilkS")
		)
		(fp_line
			(start -1.08204 -1.80848)
			(end -1.26492 -1.80848)
			(stroke
				(width 0.1524)
				(type default)
			)
			(layer "B.SilkS")
		)
		(fp_line
			(start -1.08204 1.81102)
			(end 1.4859 1.81102)
			(stroke
				(width 0.1524)
				(type default)
			)
			(layer "B.SilkS")
		)
		(fp_line
			(start -1.06934 1.81102)
			(end -1.2446 1.81102)
			(stroke
				(width 0.1524)
				(type default)
			)
			(layer "B.SilkS")
		)
		(fp_line
			(start 1.2446 1.8034)
			(end 1.2446 -1.8161)
			(stroke
				(width 0.1524)
				(type default)
			)
			(layer "B.SilkS")
		)
		(fp_line
			(start 1.3081 0.49022)
			(end 1.3081 1.7907)
			(stroke
				(width 0.508)
				(type default)
			)
			(layer "B.SilkS")
		)
		(fp_poly
			(pts
				(xy 0.82804 0.10922) (xy -0.82804 0.10922) (xy -0.82804 -0.10795) (xy 0.82804 -0.10795)
			)
			(stroke
				(width 0)
				(type default)
			)
			(fill yes)
			(layer "B.SilkS")
		)
		(fp_poly
			(pts
				(xy 1.5621 2.0447) (xy -1.5621 2.0447) (xy -1.5621 -2.0447) (xy 1.5621 -2.0447)
			)
			(stroke
				(width 0)
				(type default)
			)
			(fill no)
			(layer "B.CrtYd")
		)
		(fp_poly
			(pts
				(xy 1.5621 -2.0447) (xy -1.5621 -2.0447) (xy -1.5621 2.0447) (xy 1.5621 2.0447)
			)
			(stroke
				(width 0)
				(type default)
			)
			(fill no)
			(layer "B.Fab")
		)
		(pad "1" smd rect
			(at 0.65024 0.92202 180)
			(size 0.3556 1.2192)
			(layers "B.Cu" "B.Mask" "B.Paste")
			(net "GND")
		)
		(pad "2" smd rect
			(at 0 0.92202 180)
			(size 0.3556 1.2192)
			(layers "B.Cu" "B.Mask" "B.Paste")
			(net "BMC_VGA_HSYNC")
		)
		(pad "3" smd rect
			(at -0.65024 0.92202 180)
			(size 0.3556 1.2192)
			(layers "B.Cu" "B.Mask" "B.Paste")
			(net "GND")
		)
		(pad "4" smd rect
			(at -0.65024 -0.92075 180)
			(size 0.3556 1.2192)
			(layers "B.Cu" "B.Mask" "B.Paste")
			(net "VGA_REAR_HSYNC_S")
		)
		(pad "5" smd rect
			(at 0.65024 -0.92075 180)
			(size 0.3556 1.2192)
			(layers "B.Cu" "B.Mask" "B.Paste")
			(net "P5V_VGA_D")
		)
	)
	(footprint ""
		(layer "B.Cu")
		(at 323.8627 -31.967678 -90)
		(property "Reference" "R4T5"
			(at 0 0 90)
			(layer "B.SilkS")
			(hide yes)
			(effects
				(font
					(size 1.27 1.27)
				)
				(justify mirror)
			)
		)
		(property "Value" ""
			(at 0 0 90)
			(layer "B.Fab")
			(effects
				(font
					(size 1.27 1.27)
				)
				(justify mirror)
			)
		)
		(duplicate_pad_numbers_are_jumpers no)
		(fp_poly
			(pts
				(xy 0.2794 -0.1016) (xy -0.2794 -0.1016) (xy -0.2794 0.9906) (xy 0.2794 0.9906)
			)
			(stroke
				(width 0)
				(type default)
			)
			(fill no)
			(layer "B.CrtYd")
		)
		(fp_line
			(start -0.2794 0.9906)
			(end -0.2794 -0.1016)
			(stroke
				(width 0.1)
				(type default)
			)
			(layer "B.Fab")
		)
		(fp_line
			(start 0.2794 0.9906)
			(end -0.2794 0.9906)
			(stroke
				(width 0.1)
				(type default)
			)
			(layer "B.Fab")
		)
		(fp_line
			(start -0.2794 -0.1016)
			(end 0.2794 -0.1016)
			(stroke
				(width 0.1)
				(type default)
			)
			(layer "B.Fab")
		)
		(fp_line
			(start 0.2794 -0.1016)
			(end 0.2794 0.9906)
			(stroke
				(width 0.1)
				(type default)
			)
			(layer "B.Fab")
		)
		(pad "1" smd rect
			(at 0 0 90)
			(size 0.508 0.508)
			(layers "B.Cu" "B.Mask" "B.Paste")
			(net "PVCCIO_CPU0")
		)
		(pad "2" smd rect
			(at 0 0.889 90)
			(size 0.508 0.508)
			(layers "B.Cu" "B.Mask" "B.Paste")
			(net "SMB_DDR_ABC_SCL_G")
		)
		(zone
			(layer "B.Cu")
			(hatch none 0.5)
			(connect_pads
				(clearance 0)
			)
			(min_thickness 0.25)
			(keepout
				(tracks not_allowed)
				(vias allowed)
				(pads allowed)
				(copperpour not_allowed)
				(footprints allowed)
			)
			(placement
				(enabled no)
				(sheetname "")
			)
			(fill
				(thermal_gap 0.5)
				(thermal_bridge_width 0.5)
				(island_removal_mode 0)
			)
			(polygon
				(pts
					(xy 323.2277 -31.713678) (xy 323.2277 -32.221678) (xy 323.6087 -32.221678) (xy 323.6087 -31.713678)
				)
			)
		)
		(zone
			(layer "B.Cu")
			(hatch none 0.5)
			(connect_pads
				(clearance 0)
			)
			(min_thickness 0.25)
			(keepout
				(tracks allowed)
				(vias not_allowed)
				(pads allowed)
				(copperpour not_allowed)
				(footprints allowed)
			)
			(placement
				(enabled no)
				(sheetname "")
			)
			(fill
				(thermal_gap 0.5)
				(thermal_bridge_width 0.5)
				(island_removal_mode 0)
			)
			(polygon
				(pts
					(xy 323.6087 -31.713678) (xy 323.6087 -32.221678) (xy 323.2277 -32.221678) (xy 323.2277 -31.713678)
				)
			)
		)
	)
	(footprint ""
		(layer "B.Cu")
		(at 63.0428 -93.1672 90)
		(property "Reference" "R8N1"
			(at 0 0 90)
			(layer "B.SilkS")
			(hide yes)
			(effects
				(font
					(size 1.27 1.27)
				)
				(justify mirror)
			)
		)
		(property "Value" ""
			(at 0 0 90)
			(layer "B.Fab")
			(effects
				(font
					(size 1.27 1.27)
				)
				(justify mirror)
			)
		)
		(duplicate_pad_numbers_are_jumpers no)
		(fp_poly
			(pts
				(xy 0.2794 -0.1016) (xy -0.2794 -0.1016) (xy -0.2794 0.9906) (xy 0.2794 0.9906)
			)
			(stroke
				(width 0)
				(type default)
			)
			(fill no)
			(layer "B.CrtYd")
		)
		(fp_line
			(start 0.2794 -0.1016)
			(end 0.2794 0.9906)
			(stroke
				(width 0.1)
				(type default)
			)
			(layer "B.Fab")
		)
		(fp_line
			(start -0.2794 -0.1016)
			(end 0.2794 -0.1016)
			(stroke
				(width 0.1)
				(type default)
			)
			(layer "B.Fab")
		)
		(fp_line
			(start 0.2794 0.9906)
			(end -0.2794 0.9906)
			(stroke
				(width 0.1)
				(type default)
			)
			(layer "B.Fab")
		)
		(fp_line
			(start -0.2794 0.9906)
			(end -0.2794 -0.1016)
			(stroke
				(width 0.1)
				(type default)
			)
			(layer "B.Fab")
		)
		(pad "1" smd rect
			(at 0 0 270)
			(size 0.508 0.508)
			(layers "B.Cu" "B.Mask" "B.Paste")
			(net "P3V3_STBY")
		)
		(pad "2" smd rect
			(at 0 0.889 270)
			(size 0.508 0.508)
			(layers "B.Cu" "B.Mask" "B.Paste")
			(net "FM_CPU1_PROC_ID1")
		)
		(zone
			(layer "B.Cu")
			(hatch none 0.5)
			(connect_pads
				(clearance 0)
			)
			(min_thickness 0.25)
			(keepout
				(tracks allowed)
				(vias not_allowed)
				(pads allowed)
				(copperpour not_allowed)
				(footprints allowed)
			)
			(placement
				(enabled no)
				(sheetname "")
			)
			(fill
				(thermal_gap 0.5)
				(thermal_bridge_width 0.5)
				(island_removal_mode 0)
			)
			(polygon
				(pts
					(xy 63.2968 -93.4212) (xy 63.2968 -92.9132) (xy 63.6778 -92.9132) (xy 63.6778 -93.4212)
				)
			)
		)
		(zone
			(layer "B.Cu")
			(hatch none 0.5)
			(connect_pads
				(clearance 0)
			)
			(min_thickness 0.25)
			(keepout
				(tracks not_allowed)
				(vias allowed)
				(pads allowed)
				(copperpour not_allowed)
				(footprints allowed)
			)
			(placement
				(enabled no)
				(sheetname "")
			)
			(fill
				(thermal_gap 0.5)
				(thermal_bridge_width 0.5)
				(island_removal_mode 0)
			)
			(polygon
				(pts
					(xy 63.6778 -93.4212) (xy 63.6778 -92.9132) (xy 63.2968 -92.9132) (xy 63.2968 -93.4212)
				)
			)
		)
	)
	(footprint ""
		(layer "B.Cu")
		(at 413.734504 -48.445674 90)
		(property "Reference" "C25W46"
			(at -1.47828 0.78994 180)
			(unlocked yes)
			(layer "B.SilkS")
			(effects
				(font
					(size 0.4064 0.254)
					(thickness 0.1524)
				)
				(justify mirror)
			)
		)
		(property "Value" ""
			(at 0 0 90)
			(layer "B.Fab")
			(effects
				(font
					(size 1.27 1.27)
				)
				(justify mirror)
			)
		)
		(duplicate_pad_numbers_are_jumpers no)
		(fp_poly
			(pts
				(xy 0.7239 -0.2159) (xy -0.7239 -0.2159) (xy -0.7239 1.9939) (xy 0.7239 1.9939)
			)
			(stroke
				(width 0)
				(type default)
			)
			(fill no)
			(layer "B.CrtYd")
		)
		(fp_line
			(start 0.7239 -0.2159)
			(end 0.7239 1.9939)
			(stroke
				(width 0.1)
				(type default)
			)
			(layer "B.Fab")
		)
		(fp_line
			(start -0.7239 -0.2159)
			(end 0.7239 -0.2159)
			(stroke
				(width 0.1)
				(type default)
			)
			(layer "B.Fab")
		)
		(fp_line
			(start 0.7239 1.9939)
			(end -0.7239 1.9939)
			(stroke
				(width 0.1)
				(type default)
			)
			(layer "B.Fab")
		)
		(fp_line
			(start -0.7239 1.9939)
			(end -0.7239 -0.2159)
			(stroke
				(width 0.1)
				(type default)
			)
			(layer "B.Fab")
		)
		(pad "1" smd rect
			(at 0 0 270)
			(size 1.27 1.016)
			(layers "B.Cu" "B.Mask" "B.Paste")
			(net "VCC_D_3V3")
		)
		(pad "2" smd rect
			(at 0 1.778 270)
			(size 1.27 1.016)
			(layers "B.Cu" "B.Mask" "B.Paste")
			(net "GND")
		)
		(zone
			(layer "B.Cu")
			(hatch none 0.5)
			(connect_pads
				(clearance 0)
			)
			(min_thickness 0.25)
			(keepout
				(tracks not_allowed)
				(vias allowed)
				(pads allowed)
				(copperpour not_allowed)
				(footprints allowed)
			)
			(placement
				(enabled no)
				(sheetname "")
			)
			(fill
				(thermal_gap 0.5)
				(thermal_bridge_width 0.5)
				(island_removal_mode 0)
			)
			(polygon
				(pts
					(xy 414.242504 -49.080674) (xy 414.242504 -47.810674) (xy 415.004504 -47.810674) (xy 415.004504 -49.080674)
				)
			)
		)
	)
	(footprint ""
		(layer "B.Cu")
		(at 266.397232 -3.3528 90)
		(property "Reference" "C5G55"
			(at -1.14681 0.76708 180)
			(unlocked yes)
			(layer "B.SilkS")
			(effects
				(font
					(size 0.7874 0.5842)
					(thickness 0.1524)
				)
				(justify mirror)
			)
		)
		(property "Value" ""
			(at 0 0 90)
			(layer "B.Fab")
			(effects
				(font
					(size 1.27 1.27)
				)
				(justify mirror)
			)
		)
		(duplicate_pad_numbers_are_jumpers no)
		(fp_rect
			(start -0.4953 -0.2032)
			(end 0.4953 1.6002)
			(stroke
				(width 0)
				(type default)
			)
			(fill no)
			(layer "B.CrtYd")
		)
		(fp_line
			(start 0.4953 -0.2032)
			(end -0.4953 -0.2032)
			(stroke
				(width 0.1)
				(type default)
			)
			(layer "B.Fab")
		)
		(fp_line
			(start -0.4953 -0.2032)
			(end -0.4953 1.6002)
			(stroke
				(width 0.1)
				(type default)
			)
			(layer "B.Fab")
		)
		(fp_line
			(start 0.4953 1.6002)
			(end 0.4953 -0.2032)
			(stroke
				(width 0.1)
				(type default)
			)
			(layer "B.Fab")
		)
		(fp_line
			(start -0.4953 1.6002)
			(end 0.4953 1.6002)
			(stroke
				(width 0.1)
				(type default)
			)
			(layer "B.Fab")
		)
		(pad "1" smd rect
			(at 0 0 270)
			(size 0.762 0.889)
			(layers "B.Cu" "B.Mask" "B.Paste")
			(net "PVDDQ_ABC")
		)
		(pad "2" smd rect
			(at 0 1.397 270)
			(size 0.762 0.889)
			(layers "B.Cu" "B.Mask" "B.Paste")
			(net "GND")
		)
		(zone
			(layer "B.Cu")
			(hatch none 0.5)
			(connect_pads
				(clearance 0)
			)
			(min_thickness 0.25)
			(keepout
				(tracks not_allowed)
				(vias allowed)
				(pads allowed)
				(copperpour not_allowed)
				(footprints allowed)
			)
			(placement
				(enabled no)
				(sheetname "")
			)
			(fill
				(thermal_gap 0.5)
				(thermal_bridge_width 0.5)
				(island_removal_mode 0)
			)
			(polygon
				(pts
					(xy 266.841732 -2.9718) (xy 267.349732 -2.9718) (xy 267.349732 -3.7338) (xy 266.841732 -3.7338)
				)
			)
		)
	)
	(footprint ""
		(layer "B.Cu")
		(at 381.49022 -79.12354 -90)
		(property "Reference" "R9F55"
			(at 0 0 90)
			(layer "B.SilkS")
			(hide yes)
			(effects
				(font
					(size 1.27 1.27)
				)
				(justify mirror)
			)
		)
		(property "Value" ""
			(at 0 0 90)
			(layer "B.Fab")
			(effects
				(font
					(size 1.27 1.27)
				)
				(justify mirror)
			)
		)
		(duplicate_pad_numbers_are_jumpers no)
		(fp_poly
			(pts
				(xy 0.2794 -0.1016) (xy -0.2794 -0.1016) (xy -0.2794 0.9906) (xy 0.2794 0.9906)
			)
			(stroke
				(width 0)
				(type default)
			)
			(fill no)
			(layer "B.CrtYd")
		)
		(fp_line
			(start -0.2794 0.9906)
			(end -0.2794 -0.1016)
			(stroke
				(width 0.1)
				(type default)
			)
			(layer "B.Fab")
		)
		(fp_line
			(start 0.2794 0.9906)
			(end -0.2794 0.9906)
			(stroke
				(width 0.1)
				(type default)
			)
			(layer "B.Fab")
		)
		(fp_line
			(start -0.2794 -0.1016)
			(end 0.2794 -0.1016)
			(stroke
				(width 0.1)
				(type default)
			)
			(layer "B.Fab")
		)
		(fp_line
			(start 0.2794 -0.1016)
			(end 0.2794 0.9906)
			(stroke
				(width 0.1)
				(type default)
			)
			(layer "B.Fab")
		)
		(pad "1" smd rect
			(at 0 0 90)
			(size 0.508 0.508)
			(layers "B.Cu" "B.Mask" "B.Paste")
			(net "P3V3_STBY")
		)
		(pad "2" smd rect
			(at 0 0.889 90)
			(size 0.508 0.508)
			(layers "B.Cu" "B.Mask" "B.Paste")
			(net "FM_UART_ALERT_N")
		)
		(zone
			(layer "B.Cu")
			(hatch none 0.5)
			(connect_pads
				(clearance 0)
			)
			(min_thickness 0.25)
			(keepout
				(tracks not_allowed)
				(vias allowed)
				(pads allowed)
				(copperpour not_allowed)
				(footprints allowed)
			)
			(placement
				(enabled no)
				(sheetname "")
			)
			(fill
				(thermal_gap 0.5)
				(thermal_bridge_width 0.5)
				(island_removal_mode 0)
			)
			(polygon
				(pts
					(xy 380.85522 -78.86954) (xy 380.85522 -79.37754) (xy 381.23622 -79.37754) (xy 381.23622 -78.86954)
				)
			)
		)
		(zone
			(layer "B.Cu")
			(hatch none 0.5)
			(connect_pads
				(clearance 0)
			)
			(min_thickness 0.25)
			(keepout
				(tracks allowed)
				(vias not_allowed)
				(pads allowed)
				(copperpour not_allowed)
				(footprints allowed)
			)
			(placement
				(enabled no)
				(sheetname "")
			)
			(fill
				(thermal_gap 0.5)
				(thermal_bridge_width 0.5)
				(island_removal_mode 0)
			)
			(polygon
				(pts
					(xy 381.23622 -78.86954) (xy 381.23622 -79.37754) (xy 380.85522 -79.37754) (xy 380.85522 -78.86954)
				)
			)
		)
	)
	(footprint ""
		(layer "B.Cu")
		(at 382.3335 -44.958 90)
		(property "Reference" "R7E11"
			(at 0 0 90)
			(layer "B.SilkS")
			(hide yes)
			(effects
				(font
					(size 1.27 1.27)
				)
				(justify mirror)
			)
		)
		(property "Value" ""
			(at 0 0 90)
			(layer "B.Fab")
			(effects
				(font
					(size 1.27 1.27)
				)
				(justify mirror)
			)
		)
		(duplicate_pad_numbers_are_jumpers no)
		(fp_poly
			(pts
				(xy 0.2794 -0.1016) (xy -0.2794 -0.1016) (xy -0.2794 0.9906) (xy 0.2794 0.9906)
			)
			(stroke
				(width 0)
				(type default)
			)
			(fill no)
			(layer "B.CrtYd")
		)
		(fp_line
			(start 0.2794 -0.1016)
			(end 0.2794 0.9906)
			(stroke
				(width 0.1)
				(type default)
			)
			(layer "B.Fab")
		)
		(fp_line
			(start -0.2794 -0.1016)
			(end 0.2794 -0.1016)
			(stroke
				(width 0.1)
				(type default)
			)
			(layer "B.Fab")
		)
		(fp_line
			(start 0.2794 0.9906)
			(end -0.2794 0.9906)
			(stroke
				(width 0.1)
				(type default)
			)
			(layer "B.Fab")
		)
		(fp_line
			(start -0.2794 0.9906)
			(end -0.2794 -0.1016)
			(stroke
				(width 0.1)
				(type default)
			)
			(layer "B.Fab")
		)
		(pad "1" smd rect
			(at 0 0 270)
			(size 0.508 0.508)
			(layers "B.Cu" "B.Mask" "B.Paste")
			(net "P3V3")
		)
		(pad "2" smd rect
			(at 0 0.889 270)
			(size 0.508 0.508)
			(layers "B.Cu" "B.Mask" "B.Paste")
			(net "IRQ_CPU1_VRHOT")
		)
		(zone
			(layer "B.Cu")
			(hatch none 0.5)
			(connect_pads
				(clearance 0)
			)
			(min_thickness 0.25)
			(keepout
				(tracks allowed)
				(vias not_allowed)
				(pads allowed)
				(copperpour not_allowed)
				(footprints allowed)
			)
			(placement
				(enabled no)
				(sheetname "")
			)
			(fill
				(thermal_gap 0.5)
				(thermal_bridge_width 0.5)
				(island_removal_mode 0)
			)
			(polygon
				(pts
					(xy 382.5875 -45.212) (xy 382.5875 -44.704) (xy 382.9685 -44.704) (xy 382.9685 -45.212)
				)
			)
		)
		(zone
			(layer "B.Cu")
			(hatch none 0.5)
			(connect_pads
				(clearance 0)
			)
			(min_thickness 0.25)
			(keepout
				(tracks not_allowed)
				(vias allowed)
				(pads allowed)
				(copperpour not_allowed)
				(footprints allowed)
			)
			(placement
				(enabled no)
				(sheetname "")
			)
			(fill
				(thermal_gap 0.5)
				(thermal_bridge_width 0.5)
				(island_removal_mode 0)
			)
			(polygon
				(pts
					(xy 382.9685 -45.212) (xy 382.9685 -44.704) (xy 382.5875 -44.704) (xy 382.5875 -45.212)
				)
			)
		)
	)
	(footprint ""
		(layer "B.Cu")
		(at 3.920998 -16.934942 90)
		(property "Reference" "C9T9"
			(at 0 0 90)
			(layer "B.SilkS")
			(hide yes)
			(effects
				(font
					(size 1.27 1.27)
				)
				(justify mirror)
			)
		)
		(property "Value" ""
			(at 0 0 90)
			(layer "B.Fab")
			(effects
				(font
					(size 1.27 1.27)
				)
				(justify mirror)
			)
		)
		(duplicate_pad_numbers_are_jumpers no)
		(fp_rect
			(start -0.7239 -0.2159)
			(end 0.7239 1.9939)
			(stroke
				(width 0)
				(type default)
			)
			(fill no)
			(layer "B.CrtYd")
		)
		(fp_line
			(start 0.7239 -0.2159)
			(end 0.7239 1.9939)
			(stroke
				(width 0.1)
				(type default)
			)
			(layer "B.Fab")
		)
		(fp_line
			(start -0.7239 -0.2159)
			(end 0.7239 -0.2159)
			(stroke
				(width 0.1)
				(type default)
			)
			(layer "B.Fab")
		)
		(fp_line
			(start 0.7239 1.9939)
			(end -0.7239 1.9939)
			(stroke
				(width 0.1)
				(type default)
			)
			(layer "B.Fab")
		)
		(fp_line
			(start -0.7239 1.9939)
			(end -0.7239 -0.2159)
			(stroke
				(width 0.1)
				(type default)
			)
			(layer "B.Fab")
		)
		(pad "1" smd rect
			(at 0 0 270)
			(size 1.27 1.016)
			(layers "B.Cu" "B.Mask" "B.Paste")
			(net "VR_FET_SW_P12V_STBY_PVDDQ_GHJ")
		)
		(pad "2" smd rect
			(at 0 1.778 270)
			(size 1.27 1.016)
			(layers "B.Cu" "B.Mask" "B.Paste")
			(net "GND")
		)
		(zone
			(layer "B.Cu")
			(hatch none 0.5)
			(connect_pads
				(clearance 0)
			)
			(min_thickness 0.25)
			(keepout
				(tracks not_allowed)
				(vias allowed)
				(pads allowed)
				(copperpour not_allowed)
				(footprints allowed)
			)
			(placement
				(enabled no)
				(sheetname "")
			)
			(fill
				(thermal_gap 0.5)
				(thermal_bridge_width 0.5)
				(island_removal_mode 0)
			)
			(polygon
				(pts
					(xy 4.428998 -16.299942) (xy 5.190998 -16.299942) (xy 5.190998 -17.569942) (xy 4.428998 -17.569942)
				)
			)
		)
	)
	(footprint ""
		(layer "B.Cu")
		(at 173.863 -84.582 -90)
		(property "Reference" "C6P6"
			(at 0 0 90)
			(layer "B.SilkS")
			(hide yes)
			(effects
				(font
					(size 1.27 1.27)
				)
				(justify mirror)
			)
		)
		(property "Value" ""
			(at 0 0 90)
			(layer "B.Fab")
			(effects
				(font
					(size 1.27 1.27)
				)
				(justify mirror)
			)
		)
		(duplicate_pad_numbers_are_jumpers no)
		(fp_poly
			(pts
				(xy -0.3048 -0.1016) (xy -0.3048 0.9906) (xy 0.3048 0.9906) (xy 0.3048 -0.1016)
			)
			(stroke
				(width 0)
				(type default)
			)
			(fill no)
			(layer "B.CrtYd")
		)
		(fp_line
			(start -0.3048 0.9906)
			(end -0.3048 -0.1016)
			(stroke
				(width 0.1)
				(type default)
			)
			(layer "B.Fab")
		)
		(fp_line
			(start 0.3048 0.9906)
			(end -0.3048 0.9906)
			(stroke
				(width 0.1)
				(type default)
			)
			(layer "B.Fab")
		)
		(fp_line
			(start -0.3048 -0.1016)
			(end 0.3048 -0.1016)
			(stroke
				(width 0.1)
				(type default)
			)
			(layer "B.Fab")
		)
		(fp_line
			(start 0.3048 -0.1016)
			(end 0.3048 0.9906)
			(stroke
				(width 0.1)
				(type default)
			)
			(layer "B.Fab")
		)
		(pad "1" smd rect
			(at 0 0 90)
			(size 0.508 0.508)
			(layers "B.Cu" "B.Mask" "B.Paste")
			(net "P3V3_DB1200")
		)
		(pad "2" smd rect
			(at 0 0.889 90)
			(size 0.508 0.508)
			(layers "B.Cu" "B.Mask" "B.Paste")
			(net "GND")
		)
		(zone
			(layer "B.Cu")
			(hatch none 0.5)
			(connect_pads
				(clearance 0)
			)
			(min_thickness 0.25)
			(keepout
				(tracks not_allowed)
				(vias allowed)
				(pads allowed)
				(copperpour not_allowed)
				(footprints allowed)
			)
			(placement
				(enabled no)
				(sheetname "")
			)
			(fill
				(thermal_gap 0.5)
				(thermal_bridge_width 0.5)
				(island_removal_mode 0)
			)
			(polygon
				(pts
					(xy 173.228 -84.328) (xy 173.228 -84.836) (xy 173.609 -84.836) (xy 173.609 -84.328)
				)
			)
		)
		(zone
			(layer "B.Cu")
			(hatch none 0.5)
			(connect_pads
				(clearance 0)
			)
			(min_thickness 0.25)
			(keepout
				(tracks allowed)
				(vias not_allowed)
				(pads allowed)
				(copperpour not_allowed)
				(footprints allowed)
			)
			(placement
				(enabled no)
				(sheetname "")
			)
			(fill
				(thermal_gap 0.5)
				(thermal_bridge_width 0.5)
				(island_removal_mode 0)
			)
			(polygon
				(pts
					(xy 173.609 -84.328) (xy 173.609 -84.836) (xy 173.228 -84.836) (xy 173.228 -84.328)
				)
			)
		)
	)
	(footprint ""
		(layer "B.Cu")
		(at 388.64794 -84.75472 -90)
		(property "Reference" "R7D1"
			(at 0.8382 -0.67818 270)
			(unlocked yes)
			(layer "B.SilkS")
			(effects
				(font
					(size 0.4064 0.254)
					(thickness 0.1524)
				)
				(justify left mirror)
			)
		)
		(property "Value" ""
			(at 0 0 90)
			(layer "B.Fab")
			(effects
				(font
					(size 1.27 1.27)
				)
				(justify mirror)
			)
		)
		(duplicate_pad_numbers_are_jumpers no)
		(fp_poly
			(pts
				(xy 0.2794 -0.1016) (xy -0.2794 -0.1016) (xy -0.2794 0.9906) (xy 0.2794 0.9906)
			)
			(stroke
				(width 0)
				(type default)
			)
			(fill no)
			(layer "B.CrtYd")
		)
		(fp_line
			(start -0.2794 0.9906)
			(end -0.2794 -0.1016)
			(stroke
				(width 0.1)
				(type default)
			)
			(layer "B.Fab")
		)
		(fp_line
			(start 0.2794 0.9906)
			(end -0.2794 0.9906)
			(stroke
				(width 0.1)
				(type default)
			)
			(layer "B.Fab")
		)
		(fp_line
			(start -0.2794 -0.1016)
			(end 0.2794 -0.1016)
			(stroke
				(width 0.1)
				(type default)
			)
			(layer "B.Fab")
		)
		(fp_line
			(start 0.2794 -0.1016)
			(end 0.2794 0.9906)
			(stroke
				(width 0.1)
				(type default)
			)
			(layer "B.Fab")
		)
		(pad "1" smd rect
			(at 0 0 90)
			(size 0.508 0.508)
			(layers "B.Cu" "B.Mask" "B.Paste")
			(net "RMII_PCH_SPRNGVLLE_ARB_OUT")
		)
		(pad "2" smd rect
			(at 0 0.889 90)
			(size 0.508 0.508)
			(layers "B.Cu" "B.Mask" "B.Paste")
			(net "GND")
		)
		(zone
			(layer "B.Cu")
			(hatch none 0.5)
			(connect_pads
				(clearance 0)
			)
			(min_thickness 0.25)
			(keepout
				(tracks not_allowed)
				(vias allowed)
				(pads allowed)
				(copperpour not_allowed)
				(footprints allowed)
			)
			(placement
				(enabled no)
				(sheetname "")
			)
			(fill
				(thermal_gap 0.5)
				(thermal_bridge_width 0.5)
				(island_removal_mode 0)
			)
			(polygon
				(pts
					(xy 388.01294 -84.50072) (xy 388.01294 -85.00872) (xy 388.39394 -85.00872) (xy 388.39394 -84.50072)
				)
			)
		)
		(zone
			(layer "B.Cu")
			(hatch none 0.5)
			(connect_pads
				(clearance 0)
			)
			(min_thickness 0.25)
			(keepout
				(tracks allowed)
				(vias not_allowed)
				(pads allowed)
				(copperpour not_allowed)
				(footprints allowed)
			)
			(placement
				(enabled no)
				(sheetname "")
			)
			(fill
				(thermal_gap 0.5)
				(thermal_bridge_width 0.5)
				(island_removal_mode 0)
			)
			(polygon
				(pts
					(xy 388.39394 -84.50072) (xy 388.39394 -85.00872) (xy 388.01294 -85.00872) (xy 388.01294 -84.50072)
				)
			)
		)
	)
	(footprint ""
		(layer "B.Cu")
		(at 177.927 -79.121)
		(property "Reference" "R6P48"
			(at 0 0 0)
			(layer "B.SilkS")
			(hide yes)
			(effects
				(font
					(size 1.27 1.27)
				)
				(justify mirror)
			)
		)
		(property "Value" ""
			(at 0 0 0)
			(layer "B.Fab")
			(effects
				(font
					(size 1.27 1.27)
				)
				(justify mirror)
			)
		)
		(duplicate_pad_numbers_are_jumpers no)
		(fp_poly
			(pts
				(xy 0.2794 -0.1016) (xy -0.2794 -0.1016) (xy -0.2794 0.9906) (xy 0.2794 0.9906)
			)
			(stroke
				(width 0)
				(type default)
			)
			(fill no)
			(layer "B.CrtYd")
		)
		(fp_line
			(start -0.2794 -0.1016)
			(end 0.2794 -0.1016)
			(stroke
				(width 0.1)
				(type default)
			)
			(layer "B.Fab")
		)
		(fp_line
			(start -0.2794 0.9906)
			(end -0.2794 -0.1016)
			(stroke
				(width 0.1)
				(type default)
			)
			(layer "B.Fab")
		)
		(fp_line
			(start 0.2794 -0.1016)
			(end 0.2794 0.9906)
			(stroke
				(width 0.1)
				(type default)
			)
			(layer "B.Fab")
		)
		(fp_line
			(start 0.2794 0.9906)
			(end -0.2794 0.9906)
			(stroke
				(width 0.1)
				(type default)
			)
			(layer "B.Fab")
		)
		(pad "1" smd rect
			(at 0 0 180)
			(size 0.508 0.508)
			(layers "B.Cu" "B.Mask" "B.Paste")
			(net "P3V3")
		)
		(pad "2" smd rect
			(at 0 0.889 180)
			(size 0.508 0.508)
			(layers "B.Cu" "B.Mask" "B.Paste")
			(net "FM_DB1200ZL_BCLKS_EN_N")
		)
		(zone
			(layer "B.Cu")
			(hatch none 0.5)
			(connect_pads
				(clearance 0)
			)
			(min_thickness 0.25)
			(keepout
				(tracks allowed)
				(vias not_allowed)
				(pads allowed)
				(copperpour not_allowed)
				(footprints allowed)
			)
			(placement
				(enabled no)
				(sheetname "")
			)
			(fill
				(thermal_gap 0.5)
				(thermal_bridge_width 0.5)
				(island_removal_mode 0)
			)
			(polygon
				(pts
					(xy 178.181 -78.867) (xy 177.673 -78.867) (xy 177.673 -78.486) (xy 178.181 -78.486)
				)
			)
		)
		(zone
			(layer "B.Cu")
			(hatch none 0.5)
			(connect_pads
				(clearance 0)
			)
			(min_thickness 0.25)
			(keepout
				(tracks not_allowed)
				(vias allowed)
				(pads allowed)
				(copperpour not_allowed)
				(footprints allowed)
			)
			(placement
				(enabled no)
				(sheetname "")
			)
			(fill
				(thermal_gap 0.5)
				(thermal_bridge_width 0.5)
				(island_removal_mode 0)
			)
			(polygon
				(pts
					(xy 178.181 -78.486) (xy 177.673 -78.486) (xy 177.673 -78.867) (xy 178.181 -78.867)
				)
			)
		)
	)
	(footprint ""
		(layer "B.Cu")
		(at 417.8173 -48.9204 90)
		(property "Reference" "R1T7"
			(at 0 0 90)
			(layer "B.SilkS")
			(hide yes)
			(effects
				(font
					(size 1.27 1.27)
				)
				(justify mirror)
			)
		)
		(property "Value" ""
			(at 0 0 90)
			(layer "B.Fab")
			(effects
				(font
					(size 1.27 1.27)
				)
				(justify mirror)
			)
		)
		(duplicate_pad_numbers_are_jumpers no)
		(fp_poly
			(pts
				(xy 0.2794 -0.1016) (xy -0.2794 -0.1016) (xy -0.2794 0.9906) (xy 0.2794 0.9906)
			)
			(stroke
				(width 0)
				(type default)
			)
			(fill no)
			(layer "B.CrtYd")
		)
		(fp_line
			(start 0.2794 -0.1016)
			(end 0.2794 0.9906)
			(stroke
				(width 0.1)
				(type default)
			)
			(layer "B.Fab")
		)
		(fp_line
			(start -0.2794 -0.1016)
			(end 0.2794 -0.1016)
			(stroke
				(width 0.1)
				(type default)
			)
			(layer "B.Fab")
		)
		(fp_line
			(start 0.2794 0.9906)
			(end -0.2794 0.9906)
			(stroke
				(width 0.1)
				(type default)
			)
			(layer "B.Fab")
		)
		(fp_line
			(start -0.2794 0.9906)
			(end -0.2794 -0.1016)
			(stroke
				(width 0.1)
				(type default)
			)
			(layer "B.Fab")
		)
		(pad "1" smd rect
			(at 0 0 270)
			(size 0.508 0.508)
			(layers "B.Cu" "B.Mask" "B.Paste")
			(net "SMB_SLOTX24_STBY_LVC3_SCL_R")
		)
		(pad "2" smd rect
			(at 0 0.889 270)
			(size 0.508 0.508)
			(layers "B.Cu" "B.Mask" "B.Paste")
			(net "SMB_SLOTX24_BMC_STBY_LVC3_SCL")
		)
		(zone
			(layer "B.Cu")
			(hatch none 0.5)
			(connect_pads
				(clearance 0)
			)
			(min_thickness 0.25)
			(keepout
				(tracks allowed)
				(vias not_allowed)
				(pads allowed)
				(copperpour not_allowed)
				(footprints allowed)
			)
			(placement
				(enabled no)
				(sheetname "")
			)
			(fill
				(thermal_gap 0.5)
				(thermal_bridge_width 0.5)
				(island_removal_mode 0)
			)
			(polygon
				(pts
					(xy 418.0713 -49.1744) (xy 418.0713 -48.6664) (xy 418.4523 -48.6664) (xy 418.4523 -49.1744)
				)
			)
		)
		(zone
			(layer "B.Cu")
			(hatch none 0.5)
			(connect_pads
				(clearance 0)
			)
			(min_thickness 0.25)
			(keepout
				(tracks not_allowed)
				(vias allowed)
				(pads allowed)
				(copperpour not_allowed)
				(footprints allowed)
			)
			(placement
				(enabled no)
				(sheetname "")
			)
			(fill
				(thermal_gap 0.5)
				(thermal_bridge_width 0.5)
				(island_removal_mode 0)
			)
			(polygon
				(pts
					(xy 418.4523 -49.1744) (xy 418.4523 -48.6664) (xy 418.0713 -48.6664) (xy 418.0713 -49.1744)
				)
			)
		)
	)
	(footprint ""
		(layer "B.Cu")
		(at 24.638 -56.8452 -90)
		(property "Reference" "R9R4"
			(at 0 0 90)
			(layer "B.SilkS")
			(hide yes)
			(effects
				(font
					(size 1.27 1.27)
				)
				(justify mirror)
			)
		)
		(property "Value" ""
			(at 0 0 90)
			(layer "B.Fab")
			(effects
				(font
					(size 1.27 1.27)
				)
				(justify mirror)
			)
		)
		(duplicate_pad_numbers_are_jumpers no)
		(fp_rect
			(start 0.2794 0.9906)
			(end -0.2794 -0.1016)
			(stroke
				(width 0)
				(type default)
			)
			(fill no)
			(layer "B.CrtYd")
		)
		(fp_line
			(start -0.2794 0.9906)
			(end -0.2794 -0.1016)
			(stroke
				(width 0.1)
				(type default)
			)
			(layer "B.Fab")
		)
		(fp_line
			(start 0.2794 0.9906)
			(end -0.2794 0.9906)
			(stroke
				(width 0.1)
				(type default)
			)
			(layer "B.Fab")
		)
		(fp_line
			(start -0.2794 -0.1016)
			(end 0.2794 -0.1016)
			(stroke
				(width 0.1)
				(type default)
			)
			(layer "B.Fab")
		)
		(fp_line
			(start 0.2794 -0.1016)
			(end 0.2794 0.9906)
			(stroke
				(width 0.1)
				(type default)
			)
			(layer "B.Fab")
		)
		(pad "1" smd rect
			(at 0 0 90)
			(size 0.508 0.508)
			(layers "B.Cu" "B.Mask" "B.Paste")
			(net "A_HSC_GATE")
		)
		(pad "2" smd rect
			(at 0 0.889 90)
			(size 0.508 0.508)
			(layers "B.Cu" "B.Mask" "B.Paste")
			(net "A_HSC_GATE2_R")
		)
		(zone
			(layer "B.Cu")
			(hatch none 0.5)
			(connect_pads
				(clearance 0)
			)
			(min_thickness 0.25)
			(keepout
				(tracks not_allowed)
				(vias allowed)
				(pads allowed)
				(copperpour not_allowed)
				(footprints allowed)
			)
			(placement
				(enabled no)
				(sheetname "")
			)
			(fill
				(thermal_gap 0.5)
				(thermal_bridge_width 0.5)
				(island_removal_mode 0)
			)
			(polygon
				(pts
					(xy 24.003 -56.5912) (xy 24.384 -56.5912) (xy 24.384 -57.0992) (xy 24.003 -57.0992)
				)
			)
		)
		(zone
			(layer "B.Cu")
			(hatch none 0.5)
			(connect_pads
				(clearance 0)
			)
			(min_thickness 0.25)
			(keepout
				(tracks allowed)
				(vias not_allowed)
				(pads allowed)
				(copperpour not_allowed)
				(footprints allowed)
			)
			(placement
				(enabled no)
				(sheetname "")
			)
			(fill
				(thermal_gap 0.5)
				(thermal_bridge_width 0.5)
				(island_removal_mode 0)
			)
			(polygon
				(pts
					(xy 24.003 -56.5912) (xy 24.384 -56.5912) (xy 24.384 -57.0992) (xy 24.003 -57.0992)
				)
			)
		)
	)
	(footprint ""
		(layer "B.Cu")
		(at 355.514148 -137.904728 -90)
		(property "Reference" "R12W7"
			(at 0 0 90)
			(layer "B.SilkS")
			(hide yes)
			(effects
				(font
					(size 1.27 1.27)
				)
				(justify mirror)
			)
		)
		(property "Value" "*"
			(at 0 -8.9535 270)
			(unlocked yes)
			(layer "B.Fab")
			(hide yes)
			(effects
				(font
					(size 1.27 1.016)
					(thickness 0.1524)
				)
				(justify mirror)
			)
		)
		(property "Device Type" "665KR5B-1-GP_SMD-RG3-665KR5B-1A"
			(at 0 -10.6299 270)
			(unlocked yes)
			(layer "B.Fab")
			(hide yes)
			(effects
				(font
					(size 1.27 1.016)
					(thickness 0.1524)
				)
				(justify mirror)
			)
		)
		(duplicate_pad_numbers_are_jumpers no)
		(fp_line
			(start -0.889 1.7018)
			(end -0.889 -0.508)
			(stroke
				(width 0.1524)
				(type default)
			)
			(layer "B.SilkS")
		)
		(fp_line
			(start 0.889 1.7018)
			(end -0.889 1.7018)
			(stroke
				(width 0.1524)
				(type default)
			)
			(layer "B.SilkS")
		)
		(fp_line
			(start 0.889 0.0762)
			(end 0.889 1.7018)
			(stroke
				(width 0.1524)
				(type default)
			)
			(layer "B.SilkS")
		)
		(fp_line
			(start -0.889 -1.7018)
			(end -0.889 -0.381)
			(stroke
				(width 0.1524)
				(type default)
			)
			(layer "B.SilkS")
		)
		(fp_line
			(start -0.889 -1.7018)
			(end 0.889 -1.7018)
			(stroke
				(width 0.1524)
				(type default)
			)
			(layer "B.SilkS")
		)
		(fp_line
			(start 0.889 -1.7018)
			(end 0.889 0.2794)
			(stroke
				(width 0.1524)
				(type default)
			)
			(layer "B.SilkS")
		)
		(fp_poly
			(pts
				(xy -0.9652 -1.778) (xy -0.9652 1.778) (xy 0.9652 1.778) (xy 0.9652 -1.778)
			)
			(stroke
				(width 0)
				(type default)
			)
			(fill no)
			(layer "B.CrtYd")
		)
		(fp_rect
			(start 0.9652 1.778)
			(end -0.9652 -1.778)
			(stroke
				(width 0)
				(type default)
			)
			(fill no)
			(layer "B.Fab")
		)
		(pad "1" smd rect
			(at 0 -0.9652 90)
			(size 1.397 1.143)
			(layers "B.Cu" "B.Mask" "B.Paste")
			(net "P12V_NVDIMM_DEF_D")
		)
		(pad "2" smd rect
			(at 0 0.9652 90)
			(size 1.397 1.143)
			(layers "B.Cu" "B.Mask" "B.Paste")
			(net "VR_PVDDQ_DEF_VINSEN")
		)
	)
	(footprint ""
		(layer "B.Cu")
		(at 99.034854 -77.82814)
		(property "Reference" "C8P18"
			(at 0 0 0)
			(layer "B.SilkS")
			(hide yes)
			(effects
				(font
					(size 1.27 1.27)
				)
				(justify mirror)
			)
		)
		(property "Value" ""
			(at 0 0 0)
			(layer "B.Fab")
			(effects
				(font
					(size 1.27 1.27)
				)
				(justify mirror)
			)
		)
		(duplicate_pad_numbers_are_jumpers no)
		(fp_poly
			(pts
				(xy 0.7239 -0.2159) (xy -0.7239 -0.2159) (xy -0.7239 1.9939) (xy 0.7239 1.9939)
			)
			(stroke
				(width 0)
				(type default)
			)
			(fill no)
			(layer "B.CrtYd")
		)
		(fp_line
			(start -0.7239 -0.2159)
			(end 0.7239 -0.2159)
			(stroke
				(width 0.1)
				(type default)
			)
			(layer "B.Fab")
		)
		(fp_line
			(start -0.7239 1.9939)
			(end -0.7239 -0.2159)
			(stroke
				(width 0.1)
				(type default)
			)
			(layer "B.Fab")
		)
		(fp_line
			(start 0.7239 -0.2159)
			(end 0.7239 1.9939)
			(stroke
				(width 0.1)
				(type default)
			)
			(layer "B.Fab")
		)
		(fp_line
			(start 0.7239 1.9939)
			(end -0.7239 1.9939)
			(stroke
				(width 0.1)
				(type default)
			)
			(layer "B.Fab")
		)
		(pad "1" smd rect
			(at 0 0 180)
			(size 1.27 1.016)
			(layers "B.Cu" "B.Mask" "B.Paste")
			(net "PVCCIN_CPU1")
		)
		(pad "2" smd rect
			(at 0 1.778 180)
			(size 1.27 1.016)
			(layers "B.Cu" "B.Mask" "B.Paste")
			(net "GND")
		)
		(zone
			(layer "B.Cu")
			(hatch none 0.5)
			(connect_pads
				(clearance 0)
			)
			(min_thickness 0.25)
			(keepout
				(tracks not_allowed)
				(vias allowed)
				(pads allowed)
				(copperpour not_allowed)
				(footprints allowed)
			)
			(placement
				(enabled no)
				(sheetname "")
			)
			(fill
				(thermal_gap 0.5)
				(thermal_bridge_width 0.5)
				(island_removal_mode 0)
			)
			(polygon
				(pts
					(xy 99.669854 -77.32014) (xy 98.399854 -77.32014) (xy 98.399854 -76.55814) (xy 99.669854 -76.55814)
				)
			)
		)
	)
	(footprint ""
		(layer "B.Cu")
		(at 320.194432 1.7018 90)
		(property "Reference" "C4U3"
			(at 0 0 90)
			(layer "B.SilkS")
			(hide yes)
			(effects
				(font
					(size 1.27 1.27)
				)
				(justify mirror)
			)
		)
		(property "Value" ""
			(at 0 0 90)
			(layer "B.Fab")
			(effects
				(font
					(size 1.27 1.27)
				)
				(justify mirror)
			)
		)
		(duplicate_pad_numbers_are_jumpers no)
		(fp_poly
			(pts
				(xy 0.4953 -0.2032) (xy -0.4953 -0.2032) (xy -0.4953 1.6002) (xy 0.4953 1.6002)
			)
			(stroke
				(width 0)
				(type default)
			)
			(fill no)
			(layer "B.CrtYd")
		)
		(fp_line
			(start 0.4953 -0.2032)
			(end -0.4953 -0.2032)
			(stroke
				(width 0.1)
				(type default)
			)
			(layer "B.Fab")
		)
		(fp_line
			(start -0.4953 -0.2032)
			(end -0.4953 1.6002)
			(stroke
				(width 0.1)
				(type default)
			)
			(layer "B.Fab")
		)
		(fp_line
			(start 0.4953 1.6002)
			(end 0.4953 -0.2032)
			(stroke
				(width 0.1)
				(type default)
			)
			(layer "B.Fab")
		)
		(fp_line
			(start -0.4953 1.6002)
			(end 0.4953 1.6002)
			(stroke
				(width 0.1)
				(type default)
			)
			(layer "B.Fab")
		)
		(pad "1" smd rect
			(at 0 0 270)
			(size 0.762 0.889)
			(layers "B.Cu" "B.Mask" "B.Paste")
			(net "PVPP_ABC")
		)
		(pad "2" smd rect
			(at 0 1.397 270)
			(size 0.762 0.889)
			(layers "B.Cu" "B.Mask" "B.Paste")
			(net "GND")
		)
		(zone
			(layer "B.Cu")
			(hatch none 0.5)
			(connect_pads
				(clearance 0)
			)
			(min_thickness 0.25)
			(keepout
				(tracks not_allowed)
				(vias allowed)
				(pads allowed)
				(copperpour not_allowed)
				(footprints allowed)
			)
			(placement
				(enabled no)
				(sheetname "")
			)
			(fill
				(thermal_gap 0.5)
				(thermal_bridge_width 0.5)
				(island_removal_mode 0)
			)
			(polygon
				(pts
					(xy 320.638932 1.3208) (xy 320.638932 2.0828) (xy 321.146932 2.0828) (xy 321.146932 1.3208)
				)
			)
		)
	)
	(footprint ""
		(layer "B.Cu")
		(at 412.877 -43.053 90)
		(property "Reference" "R25W67"
			(at 0 0 90)
			(layer "B.SilkS")
			(hide yes)
			(effects
				(font
					(size 1.27 1.27)
				)
				(justify mirror)
			)
		)
		(property "Value" "*"
			(at -0.064008 -4.108196 90)
			(unlocked yes)
			(layer "B.Fab")
			(hide yes)
			(effects
				(font
					(size 1.27 1.016)
					(thickness 0.1524)
				)
				(justify mirror)
			)
		)
		(property "Device Type" "200R2F-L1-GP_SMD-RG4-200R2F-L1A"
			(at -0.064008 -5.632196 90)
			(unlocked yes)
			(layer "B.Fab")
			(hide yes)
			(effects
				(font
					(size 1.27 1.016)
					(thickness 0.1524)
				)
				(justify mirror)
			)
		)
		(duplicate_pad_numbers_are_jumpers no)
		(fp_line
			(start 0.508 -0.9398)
			(end 0.508 0.9398)
			(stroke
				(width 0.1524)
				(type default)
			)
			(layer "B.SilkS")
		)
		(fp_line
			(start -0.508 -0.9398)
			(end 0.508 -0.9398)
			(stroke
				(width 0.1524)
				(type default)
			)
			(layer "B.SilkS")
		)
		(fp_rect
			(start 0.508 0.9398)
			(end -0.508 -0.9398)
			(stroke
				(width 0)
				(type default)
			)
			(fill no)
			(layer "B.CrtYd")
		)
		(fp_rect
			(start 0.508 0.9398)
			(end -0.508 -0.9398)
			(stroke
				(width 0)
				(type default)
			)
			(fill no)
			(layer "B.Fab")
		)
		(pad "1" smd custom
			(at 0 -0.4445 270)
			(size 0.1397 0.1397)
			(layers "B.Cu" "B.Mask" "B.Paste")
			(net "PD_PEREXT")
			(options
				(clearance outline)
				(anchor circle)
			)
			(primitives
				(gr_poly
					(pts
						(arc
							(start -0.1778 0.2794)
							(mid -0.249642 0.249642)
							(end -0.2794 0.1778)
						)
						(arc
							(start -0.2794 -0.1778)
							(mid -0.249642 -0.249642)
							(end -0.1778 -0.2794)
						)
						(arc
							(start 0.1778 -0.2794)
							(mid 0.249642 -0.249642)
							(end 0.2794 -0.1778)
						)
						(arc
							(start 0.2794 0.1778)
							(mid 0.249642 0.249642)
							(end 0.1778 0.2794)
						)
					)
					(width 0)
					(fill yes)
				)
			)
		)
		(pad "2" smd custom
			(at 0 0.4445 270)
			(size 0.1397 0.1397)
			(layers "B.Cu" "B.Mask" "B.Paste")
			(net "GND")
			(options
				(clearance outline)
				(anchor circle)
			)
			(primitives
				(gr_poly
					(pts
						(arc
							(start -0.1778 0.2794)
							(mid -0.249642 0.249642)
							(end -0.2794 0.1778)
						)
						(arc
							(start -0.2794 -0.1778)
							(mid -0.249642 -0.249642)
							(end -0.1778 -0.2794)
						)
						(arc
							(start 0.1778 -0.2794)
							(mid 0.249642 -0.249642)
							(end 0.2794 -0.1778)
						)
						(arc
							(start 0.2794 0.1778)
							(mid 0.249642 0.249642)
							(end 0.1778 0.2794)
						)
					)
					(width 0)
					(fill yes)
				)
			)
		)
	)
	(footprint ""
		(layer "B.Cu")
		(at 156.414978 -119.384826 -90)
		(property "Reference" "R7M9"
			(at 0 0 90)
			(layer "B.SilkS")
			(hide yes)
			(effects
				(font
					(size 1.27 1.27)
				)
				(justify mirror)
			)
		)
		(property "Value" ""
			(at 0 0 90)
			(layer "B.Fab")
			(effects
				(font
					(size 1.27 1.27)
				)
				(justify mirror)
			)
		)
		(duplicate_pad_numbers_are_jumpers no)
		(fp_poly
			(pts
				(xy 0.2794 -0.1016) (xy -0.2794 -0.1016) (xy -0.2794 0.9906) (xy 0.2794 0.9906)
			)
			(stroke
				(width 0)
				(type default)
			)
			(fill no)
			(layer "B.CrtYd")
		)
		(fp_line
			(start -0.2794 0.9906)
			(end -0.2794 -0.1016)
			(stroke
				(width 0.1)
				(type default)
			)
			(layer "B.Fab")
		)
		(fp_line
			(start 0.2794 0.9906)
			(end -0.2794 0.9906)
			(stroke
				(width 0.1)
				(type default)
			)
			(layer "B.Fab")
		)
		(fp_line
			(start -0.2794 -0.1016)
			(end 0.2794 -0.1016)
			(stroke
				(width 0.1)
				(type default)
			)
			(layer "B.Fab")
		)
		(fp_line
			(start 0.2794 -0.1016)
			(end 0.2794 0.9906)
			(stroke
				(width 0.1)
				(type default)
			)
			(layer "B.Fab")
		)
		(pad "1" smd rect
			(at 0 0 90)
			(size 0.508 0.508)
			(layers "B.Cu" "B.Mask" "B.Paste")
			(net "PVDDQ_KLM")
		)
		(pad "2" smd rect
			(at 0 0.889 90)
			(size 0.508 0.508)
			(layers "B.Cu" "B.Mask" "B.Paste")
			(net "PWRGD_CPU1_DRAMPWROK_KLM_G")
		)
		(zone
			(layer "B.Cu")
			(hatch none 0.5)
			(connect_pads
				(clearance 0)
			)
			(min_thickness 0.25)
			(keepout
				(tracks not_allowed)
				(vias allowed)
				(pads allowed)
				(copperpour not_allowed)
				(footprints allowed)
			)
			(placement
				(enabled no)
				(sheetname "")
			)
			(fill
				(thermal_gap 0.5)
				(thermal_bridge_width 0.5)
				(island_removal_mode 0)
			)
			(polygon
				(pts
					(xy 155.779978 -119.130826) (xy 155.779978 -119.638826) (xy 156.160978 -119.638826) (xy 156.160978 -119.130826)
				)
			)
		)
		(zone
			(layer "B.Cu")
			(hatch none 0.5)
			(connect_pads
				(clearance 0)
			)
			(min_thickness 0.25)
			(keepout
				(tracks allowed)
				(vias not_allowed)
				(pads allowed)
				(copperpour not_allowed)
				(footprints allowed)
			)
			(placement
				(enabled no)
				(sheetname "")
			)
			(fill
				(thermal_gap 0.5)
				(thermal_bridge_width 0.5)
				(island_removal_mode 0)
			)
			(polygon
				(pts
					(xy 156.160978 -119.130826) (xy 156.160978 -119.638826) (xy 155.779978 -119.638826) (xy 155.779978 -119.130826)
				)
			)
		)
	)
	(footprint ""
		(layer "B.Cu")
		(at 276.000464 -17.7546 90)
		(property "Reference" "C5T5"
			(at -1.848866 0.752348 90)
			(unlocked yes)
			(layer "B.SilkS")
			(effects
				(font
					(size 1.27 0.9652)
					(thickness 0.1524)
				)
				(justify mirror)
			)
		)
		(property "Value" ""
			(at 0 0 90)
			(layer "B.Fab")
			(effects
				(font
					(size 1.27 1.27)
				)
				(justify mirror)
			)
		)
		(duplicate_pad_numbers_are_jumpers no)
		(fp_rect
			(start 0.500126 1.598422)
			(end -0.500126 -0.201422)
			(stroke
				(width 0)
				(type default)
			)
			(fill no)
			(layer "B.CrtYd")
		)
		(fp_line
			(start 0.500126 -0.201422)
			(end -0.500126 -0.201422)
			(stroke
				(width 0.1)
				(type default)
			)
			(layer "B.Fab")
		)
		(fp_line
			(start -0.500126 -0.201422)
			(end -0.500126 1.598422)
			(stroke
				(width 0.1)
				(type default)
			)
			(layer "B.Fab")
		)
		(fp_line
			(start 0.500126 1.598422)
			(end 0.500126 -0.201422)
			(stroke
				(width 0.1)
				(type default)
			)
			(layer "B.Fab")
		)
		(fp_line
			(start -0.500126 1.598422)
			(end 0.500126 1.598422)
			(stroke
				(width 0.1)
				(type default)
			)
			(layer "B.Fab")
		)
		(pad "1" smd rect
			(at 0 0)
			(size 0.889 0.9906)
			(layers "B.Cu" "B.Mask" "B.Paste")
			(net "PVDDQ_ABC")
		)
		(pad "2" smd rect
			(at 0 1.397)
			(size 0.889 0.9906)
			(layers "B.Cu" "B.Mask" "B.Paste")
			(net "GND")
		)
		(zone
			(layer "B.Cu")
			(hatch none 0.5)
			(connect_pads
				(clearance 0)
			)
			(min_thickness 0.25)
			(keepout
				(tracks not_allowed)
				(vias allowed)
				(pads allowed)
				(copperpour not_allowed)
				(footprints allowed)
			)
			(placement
				(enabled no)
				(sheetname "")
			)
			(fill
				(thermal_gap 0.5)
				(thermal_bridge_width 0.5)
				(island_removal_mode 0)
			)
			(polygon
				(pts
					(xy 276.952964 -18.2499) (xy 276.444964 -18.2499) (xy 276.444964 -17.2593) (xy 276.952964 -17.2593)
				)
			)
		)
		(zone
			(layer "B.Cu")
			(hatch none 0.5)
			(connect_pads
				(clearance 0)
			)
			(min_thickness 0.25)
			(keepout
				(tracks allowed)
				(vias not_allowed)
				(pads allowed)
				(copperpour not_allowed)
				(footprints allowed)
			)
			(placement
				(enabled no)
				(sheetname "")
			)
			(fill
				(thermal_gap 0.5)
				(thermal_bridge_width 0.5)
				(island_removal_mode 0)
			)
			(polygon
				(pts
					(xy 276.952964 -18.2499) (xy 276.444964 -18.2499) (xy 276.444964 -17.2593) (xy 276.952964 -17.2593)
				)
			)
		)
	)
	(footprint ""
		(layer "B.Cu")
		(at 484.850186 -121.325894 180)
		(property "Reference" "C9B10"
			(at 0.8382 -0.84963 180)
			(unlocked yes)
			(layer "B.SilkS")
			(effects
				(font
					(size 0.7874 0.5842)
					(thickness 0.1524)
				)
				(justify left mirror)
			)
		)
		(property "Value" ""
			(at 0 0 0)
			(layer "B.Fab")
			(effects
				(font
					(size 1.27 1.27)
				)
				(justify mirror)
			)
		)
		(duplicate_pad_numbers_are_jumpers no)
		(fp_poly
			(pts
				(xy -0.3048 -0.1016) (xy -0.3048 0.9906) (xy 0.3048 0.9906) (xy 0.3048 -0.1016)
			)
			(stroke
				(width 0)
				(type default)
			)
			(fill no)
			(layer "B.CrtYd")
		)
		(fp_line
			(start 0.3048 0.9906)
			(end -0.3048 0.9906)
			(stroke
				(width 0.1)
				(type default)
			)
			(layer "B.Fab")
		)
		(fp_line
			(start 0.3048 -0.1016)
			(end 0.3048 0.9906)
			(stroke
				(width 0.1)
				(type default)
			)
			(layer "B.Fab")
		)
		(fp_line
			(start -0.3048 0.9906)
			(end -0.3048 -0.1016)
			(stroke
				(width 0.1)
				(type default)
			)
			(layer "B.Fab")
		)
		(fp_line
			(start -0.3048 -0.1016)
			(end 0.3048 -0.1016)
			(stroke
				(width 0.1)
				(type default)
			)
			(layer "B.Fab")
		)
		(pad "1" smd rect
			(at 0 0)
			(size 0.508 0.508)
			(layers "B.Cu" "B.Mask" "B.Paste")
			(net "P5V_STBY")
		)
		(pad "2" smd rect
			(at 0 0.889)
			(size 0.508 0.508)
			(layers "B.Cu" "B.Mask" "B.Paste")
			(net "GND")
		)
		(zone
			(layer "B.Cu")
			(hatch none 0.5)
			(connect_pads
				(clearance 0)
			)
			(min_thickness 0.25)
			(keepout
				(tracks not_allowed)
				(vias allowed)
				(pads allowed)
				(copperpour not_allowed)
				(footprints allowed)
			)
			(placement
				(enabled no)
				(sheetname "")
			)
			(fill
				(thermal_gap 0.5)
				(thermal_bridge_width 0.5)
				(island_removal_mode 0)
			)
			(polygon
				(pts
					(xy 484.596186 -121.960894) (xy 485.104186 -121.960894) (xy 485.104186 -121.579894) (xy 484.596186 -121.579894)
				)
			)
		)
		(zone
			(layer "B.Cu")
			(hatch none 0.5)
			(connect_pads
				(clearance 0)
			)
			(min_thickness 0.25)
			(keepout
				(tracks allowed)
				(vias not_allowed)
				(pads allowed)
				(copperpour not_allowed)
				(footprints allowed)
			)
			(placement
				(enabled no)
				(sheetname "")
			)
			(fill
				(thermal_gap 0.5)
				(thermal_bridge_width 0.5)
				(island_removal_mode 0)
			)
			(polygon
				(pts
					(xy 484.596186 -121.579894) (xy 485.104186 -121.579894) (xy 485.104186 -121.960894) (xy 484.596186 -121.960894)
				)
			)
		)
	)
	(footprint ""
		(layer "B.Cu")
		(at 365.887 -23.241)
		(property "Reference" "C3T13"
			(at 3.14833 3.937 270)
			(unlocked yes)
			(layer "B.SilkS")
			(effects
				(font
					(size 0.7874 0.5842)
					(thickness 0.1524)
				)
				(justify mirror)
			)
		)
		(property "Value" ""
			(at 0 0 0)
			(layer "B.Fab")
			(effects
				(font
					(size 1.27 1.27)
				)
				(justify mirror)
			)
		)
		(duplicate_pad_numbers_are_jumpers no)
		(fp_line
			(start -2.504948 -1.616456)
			(end -2.504948 1.633728)
			(stroke
				(width 0.1524)
				(type default)
			)
			(layer "B.SilkS")
		)
		(fp_line
			(start -2.504948 1.633728)
			(end -1.6002 1.633728)
			(stroke
				(width 0.1524)
				(type default)
			)
			(layer "B.SilkS")
		)
		(fp_line
			(start -2.286 7.366)
			(end -2.286 1.63195)
			(stroke
				(width 0.1524)
				(type default)
			)
			(layer "B.SilkS")
		)
		(fp_line
			(start -2.286 7.366)
			(end -1.600708 7.366)
			(stroke
				(width 0.1524)
				(type default)
			)
			(layer "B.SilkS")
		)
		(fp_line
			(start -1.6002 -1.616456)
			(end -2.504948 -1.616456)
			(stroke
				(width 0.1524)
				(type default)
			)
			(layer "B.SilkS")
		)
		(fp_line
			(start 1.6002 -1.616456)
			(end 2.563114 -1.616456)
			(stroke
				(width 0.1524)
				(type default)
			)
			(layer "B.SilkS")
		)
		(fp_line
			(start 2.286 7.366)
			(end 1.60147 7.366)
			(stroke
				(width 0.1524)
				(type default)
			)
			(layer "B.SilkS")
		)
		(fp_line
			(start 2.286 7.366)
			(end 2.286 1.632712)
			(stroke
				(width 0.1524)
				(type default)
			)
			(layer "B.SilkS")
		)
		(fp_line
			(start 2.563114 -1.616456)
			(end 2.563114 1.633728)
			(stroke
				(width 0.1524)
				(type default)
			)
			(layer "B.SilkS")
		)
		(fp_line
			(start 2.563114 1.633728)
			(end 1.6002 1.633728)
			(stroke
				(width 0.1524)
				(type default)
			)
			(layer "B.SilkS")
		)
		(fp_rect
			(start 2.286 7.366)
			(end -2.286 -0.254)
			(stroke
				(width 0)
				(type default)
			)
			(fill no)
			(layer "B.CrtYd")
		)
		(fp_line
			(start -2.286 -0.254)
			(end -2.286 7.366)
			(stroke
				(width 0.1)
				(type default)
			)
			(layer "B.Fab")
		)
		(fp_line
			(start -2.286 7.366)
			(end 2.286 7.366)
			(stroke
				(width 0.1)
				(type default)
			)
			(layer "B.Fab")
		)
		(fp_line
			(start 2.286 -0.254)
			(end -2.286 -0.254)
			(stroke
				(width 0.1)
				(type default)
			)
			(layer "B.Fab")
		)
		(fp_line
			(start 2.286 7.366)
			(end 2.286 -0.254)
			(stroke
				(width 0.1)
				(type default)
			)
			(layer "B.Fab")
		)
		(pad "1" smd rect
			(at 0 0 180)
			(size 2.54 3.048)
			(layers "B.Cu" "B.Mask" "B.Paste")
			(net "P12V_STBY")
		)
		(pad "2" smd rect
			(at 0 7.112 180)
			(size 2.54 3.048)
			(layers "B.Cu" "B.Mask" "B.Paste")
			(net "GND")
		)
	)
	(footprint ""
		(layer "B.Cu")
		(at 407.162 -27.94 90)
		(property "Reference" "R25W109"
			(at 0.8382 -0.67818 90)
			(unlocked yes)
			(layer "B.SilkS")
			(effects
				(font
					(size 0.4064 0.254)
					(thickness 0.1524)
				)
				(justify left mirror)
			)
		)
		(property "Value" ""
			(at 0 0 90)
			(layer "B.Fab")
			(effects
				(font
					(size 1.27 1.27)
				)
				(justify mirror)
			)
		)
		(duplicate_pad_numbers_are_jumpers no)
		(fp_poly
			(pts
				(xy 0.2794 -0.1016) (xy -0.2794 -0.1016) (xy -0.2794 0.9906) (xy 0.2794 0.9906)
			)
			(stroke
				(width 0)
				(type default)
			)
			(fill no)
			(layer "B.CrtYd")
		)
		(fp_line
			(start 0.2794 -0.1016)
			(end 0.2794 0.9906)
			(stroke
				(width 0.1)
				(type default)
			)
			(layer "B.Fab")
		)
		(fp_line
			(start -0.2794 -0.1016)
			(end 0.2794 -0.1016)
			(stroke
				(width 0.1)
				(type default)
			)
			(layer "B.Fab")
		)
		(fp_line
			(start 0.2794 0.9906)
			(end -0.2794 0.9906)
			(stroke
				(width 0.1)
				(type default)
			)
			(layer "B.Fab")
		)
		(fp_line
			(start -0.2794 0.9906)
			(end -0.2794 -0.1016)
			(stroke
				(width 0.1)
				(type default)
			)
			(layer "B.Fab")
		)
		(pad "1" smd rect
			(at 0 0 270)
			(size 0.508 0.508)
			(layers "B.Cu" "B.Mask" "B.Paste")
			(net "P3V3_STBY")
		)
		(pad "2" smd rect
			(at 0 0.889 270)
			(size 0.508 0.508)
			(layers "B.Cu" "B.Mask" "B.Paste")
			(net "TP_RGMII2TXD3_GPIOU3")
		)
		(zone
			(layer "B.Cu")
			(hatch none 0.5)
			(connect_pads
				(clearance 0)
			)
			(min_thickness 0.25)
			(keepout
				(tracks allowed)
				(vias not_allowed)
				(pads allowed)
				(copperpour not_allowed)
				(footprints allowed)
			)
			(placement
				(enabled no)
				(sheetname "")
			)
			(fill
				(thermal_gap 0.5)
				(thermal_bridge_width 0.5)
				(island_removal_mode 0)
			)
			(polygon
				(pts
					(xy 407.416 -28.194) (xy 407.416 -27.686) (xy 407.797 -27.686) (xy 407.797 -28.194)
				)
			)
		)
		(zone
			(layer "B.Cu")
			(hatch none 0.5)
			(connect_pads
				(clearance 0)
			)
			(min_thickness 0.25)
			(keepout
				(tracks not_allowed)
				(vias allowed)
				(pads allowed)
				(copperpour not_allowed)
				(footprints allowed)
			)
			(placement
				(enabled no)
				(sheetname "")
			)
			(fill
				(thermal_gap 0.5)
				(thermal_bridge_width 0.5)
				(island_removal_mode 0)
			)
			(polygon
				(pts
					(xy 407.797 -28.194) (xy 407.797 -27.686) (xy 407.416 -27.686) (xy 407.416 -28.194)
				)
			)
		)
	)
	(footprint ""
		(layer "B.Cu")
		(at 392.498834 -107.356148)
		(property "Reference" "R2N4"
			(at 0 0 0)
			(layer "B.SilkS")
			(hide yes)
			(effects
				(font
					(size 1.27 1.27)
				)
				(justify mirror)
			)
		)
		(property "Value" ""
			(at 0 0 0)
			(layer "B.Fab")
			(effects
				(font
					(size 1.27 1.27)
				)
				(justify mirror)
			)
		)
		(duplicate_pad_numbers_are_jumpers no)
		(fp_poly
			(pts
				(xy 0.2794 -0.1016) (xy -0.2794 -0.1016) (xy -0.2794 0.9906) (xy 0.2794 0.9906)
			)
			(stroke
				(width 0)
				(type default)
			)
			(fill no)
			(layer "B.CrtYd")
		)
		(fp_line
			(start -0.2794 -0.1016)
			(end 0.2794 -0.1016)
			(stroke
				(width 0.1)
				(type default)
			)
			(layer "B.Fab")
		)
		(fp_line
			(start -0.2794 0.9906)
			(end -0.2794 -0.1016)
			(stroke
				(width 0.1)
				(type default)
			)
			(layer "B.Fab")
		)
		(fp_line
			(start 0.2794 -0.1016)
			(end 0.2794 0.9906)
			(stroke
				(width 0.1)
				(type default)
			)
			(layer "B.Fab")
		)
		(fp_line
			(start 0.2794 0.9906)
			(end -0.2794 0.9906)
			(stroke
				(width 0.1)
				(type default)
			)
			(layer "B.Fab")
		)
		(pad "1" smd rect
			(at 0 0 180)
			(size 0.508 0.508)
			(layers "B.Cu" "B.Mask" "B.Paste")
			(net "P1V05_PCH_STBY_KR_PLL")
		)
		(pad "2" smd rect
			(at 0 0.889 180)
			(size 0.508 0.508)
			(layers "B.Cu" "B.Mask" "B.Paste")
			(net "A_KR0_RBIAS")
		)
		(zone
			(layer "B.Cu")
			(hatch none 0.5)
			(connect_pads
				(clearance 0)
			)
			(min_thickness 0.25)
			(keepout
				(tracks allowed)
				(vias not_allowed)
				(pads allowed)
				(copperpour not_allowed)
				(footprints allowed)
			)
			(placement
				(enabled no)
				(sheetname "")
			)
			(fill
				(thermal_gap 0.5)
				(thermal_bridge_width 0.5)
				(island_removal_mode 0)
			)
			(polygon
				(pts
					(xy 392.752834 -107.102148) (xy 392.244834 -107.102148) (xy 392.244834 -106.721148) (xy 392.752834 -106.721148)
				)
			)
		)
		(zone
			(layer "B.Cu")
			(hatch none 0.5)
			(connect_pads
				(clearance 0)
			)
			(min_thickness 0.25)
			(keepout
				(tracks not_allowed)
				(vias allowed)
				(pads allowed)
				(copperpour not_allowed)
				(footprints allowed)
			)
			(placement
				(enabled no)
				(sheetname "")
			)
			(fill
				(thermal_gap 0.5)
				(thermal_bridge_width 0.5)
				(island_removal_mode 0)
			)
			(polygon
				(pts
					(xy 392.752834 -106.721148) (xy 392.244834 -106.721148) (xy 392.244834 -107.102148) (xy 392.752834 -107.102148)
				)
			)
		)
	)
	(footprint ""
		(layer "B.Cu")
		(at 373.944642 -72.295512 180)
		(property "Reference" "C2R5"
			(at 0 0 0)
			(layer "B.SilkS")
			(hide yes)
			(effects
				(font
					(size 1.27 1.27)
				)
				(justify mirror)
			)
		)
		(property "Value" ""
			(at 0 0 0)
			(layer "B.Fab")
			(effects
				(font
					(size 1.27 1.27)
				)
				(justify mirror)
			)
		)
		(duplicate_pad_numbers_are_jumpers no)
		(fp_rect
			(start 0.2794 0.9144)
			(end -0.2794 -0.1143)
			(stroke
				(width 0)
				(type default)
			)
			(fill no)
			(layer "B.CrtYd")
		)
		(fp_line
			(start 0.2794 0.9144)
			(end 0.2794 -0.1143)
			(stroke
				(width 0.1)
				(type default)
			)
			(layer "B.Fab")
		)
		(fp_line
			(start 0.2794 -0.1143)
			(end -0.2794 -0.1143)
			(stroke
				(width 0.1)
				(type default)
			)
			(layer "B.Fab")
		)
		(fp_line
			(start -0.2794 0.9144)
			(end 0.2794 0.9144)
			(stroke
				(width 0.1)
				(type default)
			)
			(layer "B.Fab")
		)
		(fp_line
			(start -0.2794 -0.1143)
			(end -0.2794 0.9144)
			(stroke
				(width 0.1)
				(type default)
			)
			(layer "B.Fab")
		)
		(pad "1" smd custom
			(at 0 0 90)
			(size 0.10414 0.10414)
			(layers "B.Cu" "B.Mask" "B.Paste")
			(net "P3V3_STBY")
			(options
				(clearance outline)
				(anchor circle)
			)
			(primitives
				(gr_poly
					(pts
						(xy -0.20828 -0.08636) (xy -0.20828 0.08636) (xy -0.08636 0.20828) (xy 0.086614 0.20828) (xy 0.20828 0.086614)
						(xy 0.20828 -0.08636) (xy 0.08636 -0.20828) (xy -0.08636 -0.20828)
					)
					(width 0)
					(fill yes)
				)
			)
		)
		(pad "2" smd custom
			(at 0 0.8001 90)
			(size 0.10414 0.10414)
			(layers "B.Cu" "B.Mask" "B.Paste")
			(net "GND")
			(options
				(clearance outline)
				(anchor circle)
			)
			(primitives
				(gr_poly
					(pts
						(xy -0.20828 -0.08636) (xy -0.20828 0.08636) (xy -0.08636 0.20828) (xy 0.086614 0.20828) (xy 0.20828 0.086614)
						(xy 0.20828 -0.08636) (xy 0.08636 -0.20828) (xy -0.08636 -0.20828)
					)
					(width 0)
					(fill yes)
				)
			)
		)
		(zone
			(layer "B.Cu")
			(hatch none 0.5)
			(connect_pads
				(clearance 0)
			)
			(min_thickness 0.25)
			(keepout
				(tracks not_allowed)
				(vias allowed)
				(pads allowed)
				(copperpour not_allowed)
				(footprints allowed)
			)
			(placement
				(enabled no)
				(sheetname "")
			)
			(fill
				(thermal_gap 0.5)
				(thermal_bridge_width 0.5)
				(island_removal_mode 0)
			)
			(polygon
				(pts
					(xy 373.857012 -72.505062) (xy 373.857012 -72.886062) (xy 374.032272 -72.886062) (xy 374.032526 -72.505062)
				)
			)
		)
		(zone
			(layer "B.Cu")
			(hatch none 0.5)
			(connect_pads
				(clearance 0)
			)
			(min_thickness 0.25)
			(keepout
				(tracks allowed)
				(vias not_allowed)
				(pads allowed)
				(copperpour not_allowed)
				(footprints allowed)
			)
			(placement
				(enabled no)
				(sheetname "")
			)
			(fill
				(thermal_gap 0.5)
				(thermal_bridge_width 0.5)
				(island_removal_mode 0)
			)
			(polygon
				(pts
					(xy 373.857012 -72.505062) (xy 373.857012 -72.886062) (xy 374.032272 -72.886062) (xy 374.032526 -72.505062)
				)
			)
		)
	)
	(footprint ""
		(layer "B.Cu")
		(at 408.8765 -4.572 90)
		(property "Reference" "R8D37"
			(at 0 0 90)
			(layer "B.SilkS")
			(hide yes)
			(effects
				(font
					(size 1.27 1.27)
				)
				(justify mirror)
			)
		)
		(property "Value" ""
			(at 0 0 90)
			(layer "B.Fab")
			(effects
				(font
					(size 1.27 1.27)
				)
				(justify mirror)
			)
		)
		(duplicate_pad_numbers_are_jumpers no)
		(fp_poly
			(pts
				(xy 0.2794 -0.1016) (xy -0.2794 -0.1016) (xy -0.2794 0.9906) (xy 0.2794 0.9906)
			)
			(stroke
				(width 0)
				(type default)
			)
			(fill no)
			(layer "B.CrtYd")
		)
		(fp_line
			(start 0.2794 -0.1016)
			(end 0.2794 0.9906)
			(stroke
				(width 0.1)
				(type default)
			)
			(layer "B.Fab")
		)
		(fp_line
			(start -0.2794 -0.1016)
			(end 0.2794 -0.1016)
			(stroke
				(width 0.1)
				(type default)
			)
			(layer "B.Fab")
		)
		(fp_line
			(start 0.2794 0.9906)
			(end -0.2794 0.9906)
			(stroke
				(width 0.1)
				(type default)
			)
			(layer "B.Fab")
		)
		(fp_line
			(start -0.2794 0.9906)
			(end -0.2794 -0.1016)
			(stroke
				(width 0.1)
				(type default)
			)
			(layer "B.Fab")
		)
		(pad "1" smd rect
			(at 0 0 270)
			(size 0.508 0.508)
			(layers "B.Cu" "B.Mask" "B.Paste")
			(net "A_PG_P5V")
		)
		(pad "2" smd rect
			(at 0 0.889 270)
			(size 0.508 0.508)
			(layers "B.Cu" "B.Mask" "B.Paste")
			(net "GND")
		)
		(zone
			(layer "B.Cu")
			(hatch none 0.5)
			(connect_pads
				(clearance 0)
			)
			(min_thickness 0.25)
			(keepout
				(tracks allowed)
				(vias not_allowed)
				(pads allowed)
				(copperpour not_allowed)
				(footprints allowed)
			)
			(placement
				(enabled no)
				(sheetname "")
			)
			(fill
				(thermal_gap 0.5)
				(thermal_bridge_width 0.5)
				(island_removal_mode 0)
			)
			(polygon
				(pts
					(xy 409.1305 -4.826) (xy 409.1305 -4.318) (xy 409.5115 -4.318) (xy 409.5115 -4.826)
				)
			)
		)
		(zone
			(layer "B.Cu")
			(hatch none 0.5)
			(connect_pads
				(clearance 0)
			)
			(min_thickness 0.25)
			(keepout
				(tracks not_allowed)
				(vias allowed)
				(pads allowed)
				(copperpour not_allowed)
				(footprints allowed)
			)
			(placement
				(enabled no)
				(sheetname "")
			)
			(fill
				(thermal_gap 0.5)
				(thermal_bridge_width 0.5)
				(island_removal_mode 0)
			)
			(polygon
				(pts
					(xy 409.5115 -4.826) (xy 409.5115 -4.318) (xy 409.1305 -4.318) (xy 409.1305 -4.826)
				)
			)
		)
	)
	(footprint ""
		(layer "B.Cu")
		(at 162.7886 -76.708 90)
		(property "Reference" "R7P12"
			(at 0 0 90)
			(layer "B.SilkS")
			(hide yes)
			(effects
				(font
					(size 1.27 1.27)
				)
				(justify mirror)
			)
		)
		(property "Value" ""
			(at 0 0 90)
			(layer "B.Fab")
			(effects
				(font
					(size 1.27 1.27)
				)
				(justify mirror)
			)
		)
		(duplicate_pad_numbers_are_jumpers no)
		(fp_poly
			(pts
				(xy 0.2794 -0.1016) (xy -0.2794 -0.1016) (xy -0.2794 0.9906) (xy 0.2794 0.9906)
			)
			(stroke
				(width 0)
				(type default)
			)
			(fill no)
			(layer "B.CrtYd")
		)
		(fp_line
			(start 0.2794 -0.1016)
			(end 0.2794 0.9906)
			(stroke
				(width 0.1)
				(type default)
			)
			(layer "B.Fab")
		)
		(fp_line
			(start -0.2794 -0.1016)
			(end 0.2794 -0.1016)
			(stroke
				(width 0.1)
				(type default)
			)
			(layer "B.Fab")
		)
		(fp_line
			(start 0.2794 0.9906)
			(end -0.2794 0.9906)
			(stroke
				(width 0.1)
				(type default)
			)
			(layer "B.Fab")
		)
		(fp_line
			(start -0.2794 0.9906)
			(end -0.2794 -0.1016)
			(stroke
				(width 0.1)
				(type default)
			)
			(layer "B.Fab")
		)
		(pad "1" smd rect
			(at 0 0 270)
			(size 0.508 0.508)
			(layers "B.Cu" "B.Mask" "B.Paste")
			(net "CLK_100M_CPU1_RC_REFCLK1_DN")
		)
		(pad "2" smd rect
			(at 0 0.889 270)
			(size 0.508 0.508)
			(layers "B.Cu" "B.Mask" "B.Paste")
			(net "GND")
		)
		(zone
			(layer "B.Cu")
			(hatch none 0.5)
			(connect_pads
				(clearance 0)
			)
			(min_thickness 0.25)
			(keepout
				(tracks allowed)
				(vias not_allowed)
				(pads allowed)
				(copperpour not_allowed)
				(footprints allowed)
			)
			(placement
				(enabled no)
				(sheetname "")
			)
			(fill
				(thermal_gap 0.5)
				(thermal_bridge_width 0.5)
				(island_removal_mode 0)
			)
			(polygon
				(pts
					(xy 163.0426 -76.962) (xy 163.0426 -76.454) (xy 163.4236 -76.454) (xy 163.4236 -76.962)
				)
			)
		)
		(zone
			(layer "B.Cu")
			(hatch none 0.5)
			(connect_pads
				(clearance 0)
			)
			(min_thickness 0.25)
			(keepout
				(tracks not_allowed)
				(vias allowed)
				(pads allowed)
				(copperpour not_allowed)
				(footprints allowed)
			)
			(placement
				(enabled no)
				(sheetname "")
			)
			(fill
				(thermal_gap 0.5)
				(thermal_bridge_width 0.5)
				(island_removal_mode 0)
			)
			(polygon
				(pts
					(xy 163.4236 -76.962) (xy 163.4236 -76.454) (xy 163.0426 -76.454) (xy 163.0426 -76.962)
				)
			)
		)
	)
	(footprint ""
		(layer "B.Cu")
		(at 372.169436 -47.436532)
		(property "Reference" "R2T68"
			(at 0 0 0)
			(layer "B.SilkS")
			(hide yes)
			(effects
				(font
					(size 1.27 1.27)
				)
				(justify mirror)
			)
		)
		(property "Value" ""
			(at 0 0 0)
			(layer "B.Fab")
			(effects
				(font
					(size 1.27 1.27)
				)
				(justify mirror)
			)
		)
		(duplicate_pad_numbers_are_jumpers no)
		(fp_poly
			(pts
				(xy 0.2794 -0.1016) (xy -0.2794 -0.1016) (xy -0.2794 0.9906) (xy 0.2794 0.9906)
			)
			(stroke
				(width 0)
				(type default)
			)
			(fill no)
			(layer "B.CrtYd")
		)
		(fp_line
			(start -0.2794 -0.1016)
			(end 0.2794 -0.1016)
			(stroke
				(width 0.1)
				(type default)
			)
			(layer "B.Fab")
		)
		(fp_line
			(start -0.2794 0.9906)
			(end -0.2794 -0.1016)
			(stroke
				(width 0.1)
				(type default)
			)
			(layer "B.Fab")
		)
		(fp_line
			(start 0.2794 -0.1016)
			(end 0.2794 0.9906)
			(stroke
				(width 0.1)
				(type default)
			)
			(layer "B.Fab")
		)
		(fp_line
			(start 0.2794 0.9906)
			(end -0.2794 0.9906)
			(stroke
				(width 0.1)
				(type default)
			)
			(layer "B.Fab")
		)
		(pad "1" smd rect
			(at 0 0 180)
			(size 0.508 0.508)
			(layers "B.Cu" "B.Mask" "B.Paste")
			(net "H_CPU1_PROCHOT_G_N")
		)
		(pad "2" smd rect
			(at 0 0.889 180)
			(size 0.508 0.508)
			(layers "B.Cu" "B.Mask" "B.Paste")
			(net "H_CPU1_PROCHOT_G_R_N")
		)
		(zone
			(layer "B.Cu")
			(hatch none 0.5)
			(connect_pads
				(clearance 0)
			)
			(min_thickness 0.25)
			(keepout
				(tracks allowed)
				(vias not_allowed)
				(pads allowed)
				(copperpour not_allowed)
				(footprints allowed)
			)
			(placement
				(enabled no)
				(sheetname "")
			)
			(fill
				(thermal_gap 0.5)
				(thermal_bridge_width 0.5)
				(island_removal_mode 0)
			)
			(polygon
				(pts
					(xy 372.423436 -47.182532) (xy 371.915436 -47.182532) (xy 371.915436 -46.801532) (xy 372.423436 -46.801532)
				)
			)
		)
		(zone
			(layer "B.Cu")
			(hatch none 0.5)
			(connect_pads
				(clearance 0)
			)
			(min_thickness 0.25)
			(keepout
				(tracks not_allowed)
				(vias allowed)
				(pads allowed)
				(copperpour not_allowed)
				(footprints allowed)
			)
			(placement
				(enabled no)
				(sheetname "")
			)
			(fill
				(thermal_gap 0.5)
				(thermal_bridge_width 0.5)
				(island_removal_mode 0)
			)
			(polygon
				(pts
					(xy 372.423436 -46.801532) (xy 371.915436 -46.801532) (xy 371.915436 -47.182532) (xy 372.423436 -47.182532)
				)
			)
		)
	)
	(footprint ""
		(layer "B.Cu")
		(at 338.7344 -17.272 -90)
		(property "Reference" "R3U2"
			(at 0 0 90)
			(layer "B.SilkS")
			(hide yes)
			(effects
				(font
					(size 1.27 1.27)
				)
				(justify mirror)
			)
		)
		(property "Value" ""
			(at 0 0 90)
			(layer "B.Fab")
			(effects
				(font
					(size 1.27 1.27)
				)
				(justify mirror)
			)
		)
		(duplicate_pad_numbers_are_jumpers no)
		(fp_rect
			(start 0.2794 0.9906)
			(end -0.2794 -0.1016)
			(stroke
				(width 0)
				(type default)
			)
			(fill no)
			(layer "B.CrtYd")
		)
		(fp_line
			(start -0.2794 0.9906)
			(end -0.2794 -0.1016)
			(stroke
				(width 0.1)
				(type default)
			)
			(layer "B.Fab")
		)
		(fp_line
			(start 0.2794 0.9906)
			(end -0.2794 0.9906)
			(stroke
				(width 0.1)
				(type default)
			)
			(layer "B.Fab")
		)
		(fp_line
			(start -0.2794 -0.1016)
			(end 0.2794 -0.1016)
			(stroke
				(width 0.1)
				(type default)
			)
			(layer "B.Fab")
		)
		(fp_line
			(start 0.2794 -0.1016)
			(end 0.2794 0.9906)
			(stroke
				(width 0.1)
				(type default)
			)
			(layer "B.Fab")
		)
		(pad "1" smd rect
			(at 0 0 90)
			(size 0.508 0.508)
			(layers "B.Cu" "B.Mask" "B.Paste")
			(net "PVCCIO_CPU0")
		)
		(pad "2" smd rect
			(at 0 0.889 90)
			(size 0.508 0.508)
			(layers "B.Cu" "B.Mask" "B.Paste")
			(net "SVID_DIO1_CPU0_R")
		)
		(zone
			(layer "B.Cu")
			(hatch none 0.5)
			(connect_pads
				(clearance 0)
			)
			(min_thickness 0.25)
			(keepout
				(tracks not_allowed)
				(vias allowed)
				(pads allowed)
				(copperpour not_allowed)
				(footprints allowed)
			)
			(placement
				(enabled no)
				(sheetname "")
			)
			(fill
				(thermal_gap 0.5)
				(thermal_bridge_width 0.5)
				(island_removal_mode 0)
			)
			(polygon
				(pts
					(xy 338.0994 -17.018) (xy 338.4804 -17.018) (xy 338.4804 -17.526) (xy 338.0994 -17.526)
				)
			)
		)
		(zone
			(layer "B.Cu")
			(hatch none 0.5)
			(connect_pads
				(clearance 0)
			)
			(min_thickness 0.25)
			(keepout
				(tracks allowed)
				(vias not_allowed)
				(pads allowed)
				(copperpour not_allowed)
				(footprints allowed)
			)
			(placement
				(enabled no)
				(sheetname "")
			)
			(fill
				(thermal_gap 0.5)
				(thermal_bridge_width 0.5)
				(island_removal_mode 0)
			)
			(polygon
				(pts
					(xy 338.0994 -17.018) (xy 338.4804 -17.018) (xy 338.4804 -17.526) (xy 338.0994 -17.526)
				)
			)
		)
	)
	(footprint ""
		(layer "B.Cu")
		(at 80.391 -65.151 -90)
		(property "Reference" "R8P3"
			(at 0 0 90)
			(layer "B.SilkS")
			(hide yes)
			(effects
				(font
					(size 1.27 1.27)
				)
				(justify mirror)
			)
		)
		(property "Value" ""
			(at 0 0 90)
			(layer "B.Fab")
			(effects
				(font
					(size 1.27 1.27)
				)
				(justify mirror)
			)
		)
		(duplicate_pad_numbers_are_jumpers no)
		(fp_poly
			(pts
				(xy 0.2794 -0.1016) (xy -0.2794 -0.1016) (xy -0.2794 0.9906) (xy 0.2794 0.9906)
			)
			(stroke
				(width 0)
				(type default)
			)
			(fill no)
			(layer "B.CrtYd")
		)
		(fp_line
			(start -0.2794 0.9906)
			(end -0.2794 -0.1016)
			(stroke
				(width 0.1)
				(type default)
			)
			(layer "B.Fab")
		)
		(fp_line
			(start 0.2794 0.9906)
			(end -0.2794 0.9906)
			(stroke
				(width 0.1)
				(type default)
			)
			(layer "B.Fab")
		)
		(fp_line
			(start -0.2794 -0.1016)
			(end 0.2794 -0.1016)
			(stroke
				(width 0.1)
				(type default)
			)
			(layer "B.Fab")
		)
		(fp_line
			(start 0.2794 -0.1016)
			(end 0.2794 0.9906)
			(stroke
				(width 0.1)
				(type default)
			)
			(layer "B.Fab")
		)
		(pad "1" smd rect
			(at 0 0 90)
			(size 0.508 0.508)
			(layers "B.Cu" "B.Mask" "B.Paste")
			(net "PD_CPU1_RSVD_TEST_2")
		)
		(pad "2" smd rect
			(at 0 0.889 90)
			(size 0.508 0.508)
			(layers "B.Cu" "B.Mask" "B.Paste")
			(net "GND")
		)
		(zone
			(layer "B.Cu")
			(hatch none 0.5)
			(connect_pads
				(clearance 0)
			)
			(min_thickness 0.25)
			(keepout
				(tracks not_allowed)
				(vias allowed)
				(pads allowed)
				(copperpour not_allowed)
				(footprints allowed)
			)
			(placement
				(enabled no)
				(sheetname "")
			)
			(fill
				(thermal_gap 0.5)
				(thermal_bridge_width 0.5)
				(island_removal_mode 0)
			)
			(polygon
				(pts
					(xy 79.756 -64.897) (xy 79.756 -65.405) (xy 80.137 -65.405) (xy 80.137 -64.897)
				)
			)
		)
		(zone
			(layer "B.Cu")
			(hatch none 0.5)
			(connect_pads
				(clearance 0)
			)
			(min_thickness 0.25)
			(keepout
				(tracks allowed)
				(vias not_allowed)
				(pads allowed)
				(copperpour not_allowed)
				(footprints allowed)
			)
			(placement
				(enabled no)
				(sheetname "")
			)
			(fill
				(thermal_gap 0.5)
				(thermal_bridge_width 0.5)
				(island_removal_mode 0)
			)
			(polygon
				(pts
					(xy 80.137 -64.897) (xy 80.137 -65.405) (xy 79.756 -65.405) (xy 79.756 -64.897)
				)
			)
		)
	)
	(footprint ""
		(layer "B.Cu")
		(at 372.4275 -93.853 90)
		(property "Reference" "R3P8"
			(at 0 0 90)
			(layer "B.SilkS")
			(hide yes)
			(effects
				(font
					(size 1.27 1.27)
				)
				(justify mirror)
			)
		)
		(property "Value" ""
			(at 0 0 90)
			(layer "B.Fab")
			(effects
				(font
					(size 1.27 1.27)
				)
				(justify mirror)
			)
		)
		(duplicate_pad_numbers_are_jumpers no)
		(fp_poly
			(pts
				(xy 0.2794 -0.1016) (xy -0.2794 -0.1016) (xy -0.2794 0.9906) (xy 0.2794 0.9906)
			)
			(stroke
				(width 0)
				(type default)
			)
			(fill no)
			(layer "B.CrtYd")
		)
		(fp_line
			(start 0.2794 -0.1016)
			(end 0.2794 0.9906)
			(stroke
				(width 0.1)
				(type default)
			)
			(layer "B.Fab")
		)
		(fp_line
			(start -0.2794 -0.1016)
			(end 0.2794 -0.1016)
			(stroke
				(width 0.1)
				(type default)
			)
			(layer "B.Fab")
		)
		(fp_line
			(start 0.2794 0.9906)
			(end -0.2794 0.9906)
			(stroke
				(width 0.1)
				(type default)
			)
			(layer "B.Fab")
		)
		(fp_line
			(start -0.2794 0.9906)
			(end -0.2794 -0.1016)
			(stroke
				(width 0.1)
				(type default)
			)
			(layer "B.Fab")
		)
		(pad "1" smd rect
			(at 0 0 270)
			(size 0.508 0.508)
			(layers "B.Cu" "B.Mask" "B.Paste")
			(net "P1V05_PCH_STBY")
		)
		(pad "2" smd rect
			(at 0 0.889 270)
			(size 0.508 0.508)
			(layers "B.Cu" "B.Mask" "B.Paste")
			(net "FM_PRSNT_2_6_N")
		)
		(zone
			(layer "B.Cu")
			(hatch none 0.5)
			(connect_pads
				(clearance 0)
			)
			(min_thickness 0.25)
			(keepout
				(tracks allowed)
				(vias not_allowed)
				(pads allowed)
				(copperpour not_allowed)
				(footprints allowed)
			)
			(placement
				(enabled no)
				(sheetname "")
			)
			(fill
				(thermal_gap 0.5)
				(thermal_bridge_width 0.5)
				(island_removal_mode 0)
			)
			(polygon
				(pts
					(xy 372.6815 -94.107) (xy 372.6815 -93.599) (xy 373.0625 -93.599) (xy 373.0625 -94.107)
				)
			)
		)
		(zone
			(layer "B.Cu")
			(hatch none 0.5)
			(connect_pads
				(clearance 0)
			)
			(min_thickness 0.25)
			(keepout
				(tracks not_allowed)
				(vias allowed)
				(pads allowed)
				(copperpour not_allowed)
				(footprints allowed)
			)
			(placement
				(enabled no)
				(sheetname "")
			)
			(fill
				(thermal_gap 0.5)
				(thermal_bridge_width 0.5)
				(island_removal_mode 0)
			)
			(polygon
				(pts
					(xy 373.0625 -94.107) (xy 373.0625 -93.599) (xy 372.6815 -93.599) (xy 372.6815 -94.107)
				)
			)
		)
	)
	(footprint ""
		(layer "B.Cu")
		(at 328.803 -55.626 90)
		(property "Reference" "C4R2"
			(at 0 0 90)
			(layer "B.SilkS")
			(hide yes)
			(effects
				(font
					(size 1.27 1.27)
				)
				(justify mirror)
			)
		)
		(property "Value" ""
			(at 0 0 90)
			(layer "B.Fab")
			(effects
				(font
					(size 1.27 1.27)
				)
				(justify mirror)
			)
		)
		(duplicate_pad_numbers_are_jumpers no)
		(fp_poly
			(pts
				(xy -0.3048 -0.1016) (xy -0.3048 0.9906) (xy 0.3048 0.9906) (xy 0.3048 -0.1016)
			)
			(stroke
				(width 0)
				(type default)
			)
			(fill no)
			(layer "B.CrtYd")
		)
		(fp_line
			(start 0.3048 -0.1016)
			(end 0.3048 0.9906)
			(stroke
				(width 0.1)
				(type default)
			)
			(layer "B.Fab")
		)
		(fp_line
			(start -0.3048 -0.1016)
			(end 0.3048 -0.1016)
			(stroke
				(width 0.1)
				(type default)
			)
			(layer "B.Fab")
		)
		(fp_line
			(start 0.3048 0.9906)
			(end -0.3048 0.9906)
			(stroke
				(width 0.1)
				(type default)
			)
			(layer "B.Fab")
		)
		(fp_line
			(start -0.3048 0.9906)
			(end -0.3048 -0.1016)
			(stroke
				(width 0.1)
				(type default)
			)
			(layer "B.Fab")
		)
		(pad "1" smd rect
			(at 0 0 270)
			(size 0.508 0.508)
			(layers "B.Cu" "B.Mask" "B.Paste")
			(net "JTAG_MCP_CPU0_TDI_R")
		)
		(pad "2" smd rect
			(at 0 0.889 270)
			(size 0.508 0.508)
			(layers "B.Cu" "B.Mask" "B.Paste")
			(net "GND")
		)
		(zone
			(layer "B.Cu")
			(hatch none 0.5)
			(connect_pads
				(clearance 0)
			)
			(min_thickness 0.25)
			(keepout
				(tracks allowed)
				(vias not_allowed)
				(pads allowed)
				(copperpour not_allowed)
				(footprints allowed)
			)
			(placement
				(enabled no)
				(sheetname "")
			)
			(fill
				(thermal_gap 0.5)
				(thermal_bridge_width 0.5)
				(island_removal_mode 0)
			)
			(polygon
				(pts
					(xy 329.057 -55.88) (xy 329.057 -55.372) (xy 329.438 -55.372) (xy 329.438 -55.88)
				)
			)
		)
		(zone
			(layer "B.Cu")
			(hatch none 0.5)
			(connect_pads
				(clearance 0)
			)
			(min_thickness 0.25)
			(keepout
				(tracks not_allowed)
				(vias allowed)
				(pads allowed)
				(copperpour not_allowed)
				(footprints allowed)
			)
			(placement
				(enabled no)
				(sheetname "")
			)
			(fill
				(thermal_gap 0.5)
				(thermal_bridge_width 0.5)
				(island_removal_mode 0)
			)
			(polygon
				(pts
					(xy 329.438 -55.88) (xy 329.438 -55.372) (xy 329.057 -55.372) (xy 329.057 -55.88)
				)
			)
		)
	)
	(footprint ""
		(layer "B.Cu")
		(at 385.6228 -102.489 -90)
		(property "Reference" "C3N29"
			(at 0 0 90)
			(layer "B.SilkS")
			(hide yes)
			(effects
				(font
					(size 1.27 1.27)
				)
				(justify mirror)
			)
		)
		(property "Value" ""
			(at 0 0 90)
			(layer "B.Fab")
			(effects
				(font
					(size 1.27 1.27)
				)
				(justify mirror)
			)
		)
		(duplicate_pad_numbers_are_jumpers no)
		(fp_rect
			(start 0.2794 0.9144)
			(end -0.2794 -0.1143)
			(stroke
				(width 0)
				(type default)
			)
			(fill no)
			(layer "B.CrtYd")
		)
		(fp_line
			(start -0.2794 0.9144)
			(end 0.2794 0.9144)
			(stroke
				(width 0.1)
				(type default)
			)
			(layer "B.Fab")
		)
		(fp_line
			(start 0.2794 0.9144)
			(end 0.2794 -0.1143)
			(stroke
				(width 0.1)
				(type default)
			)
			(layer "B.Fab")
		)
		(fp_line
			(start -0.2794 -0.1143)
			(end -0.2794 0.9144)
			(stroke
				(width 0.1)
				(type default)
			)
			(layer "B.Fab")
		)
		(fp_line
			(start 0.2794 -0.1143)
			(end -0.2794 -0.1143)
			(stroke
				(width 0.1)
				(type default)
			)
			(layer "B.Fab")
		)
		(pad "1" smd custom
			(at 0 0 180)
			(size 0.10414 0.10414)
			(layers "B.Cu" "B.Mask" "B.Paste")
			(net "A_PVCCRTC_EXT_CAP")
			(options
				(clearance outline)
				(anchor circle)
			)
			(primitives
				(gr_poly
					(pts
						(xy -0.20828 -0.08636) (xy -0.20828 0.08636) (xy -0.08636 0.20828) (xy 0.086614 0.20828) (xy 0.20828 0.086614)
						(xy 0.20828 -0.08636) (xy 0.08636 -0.20828) (xy -0.08636 -0.20828)
					)
					(width 0)
					(fill yes)
				)
			)
		)
		(pad "2" smd custom
			(at 0 0.8001 180)
			(size 0.10414 0.10414)
			(layers "B.Cu" "B.Mask" "B.Paste")
			(net "GND")
			(options
				(clearance outline)
				(anchor circle)
			)
			(primitives
				(gr_poly
					(pts
						(xy -0.20828 -0.08636) (xy -0.20828 0.08636) (xy -0.08636 0.20828) (xy 0.086614 0.20828) (xy 0.20828 0.086614)
						(xy 0.20828 -0.08636) (xy 0.08636 -0.20828) (xy -0.08636 -0.20828)
					)
					(width 0)
					(fill yes)
				)
			)
		)
		(zone
			(layer "B.Cu")
			(hatch none 0.5)
			(connect_pads
				(clearance 0)
			)
			(min_thickness 0.25)
			(keepout
				(tracks not_allowed)
				(vias allowed)
				(pads allowed)
				(copperpour not_allowed)
				(footprints allowed)
			)
			(placement
				(enabled no)
				(sheetname "")
			)
			(fill
				(thermal_gap 0.5)
				(thermal_bridge_width 0.5)
				(island_removal_mode 0)
			)
			(polygon
				(pts
					(xy 385.41325 -102.40137) (xy 385.03225 -102.40137) (xy 385.03225 -102.57663) (xy 385.41325 -102.576884)
				)
			)
		)
		(zone
			(layer "B.Cu")
			(hatch none 0.5)
			(connect_pads
				(clearance 0)
			)
			(min_thickness 0.25)
			(keepout
				(tracks allowed)
				(vias not_allowed)
				(pads allowed)
				(copperpour not_allowed)
				(footprints allowed)
			)
			(placement
				(enabled no)
				(sheetname "")
			)
			(fill
				(thermal_gap 0.5)
				(thermal_bridge_width 0.5)
				(island_removal_mode 0)
			)
			(polygon
				(pts
					(xy 385.41325 -102.40137) (xy 385.03225 -102.40137) (xy 385.03225 -102.57663) (xy 385.41325 -102.576884)
				)
			)
		)
	)
	(footprint ""
		(layer "B.Cu")
		(at 424.815 -27.0002 180)
		(property "Reference" "R2W5"
			(at 0.8382 -0.67818 180)
			(unlocked yes)
			(layer "B.SilkS")
			(effects
				(font
					(size 0.4064 0.254)
					(thickness 0.1524)
				)
				(justify left mirror)
			)
		)
		(property "Value" ""
			(at 0 0 0)
			(layer "B.Fab")
			(effects
				(font
					(size 1.27 1.27)
				)
				(justify mirror)
			)
		)
		(duplicate_pad_numbers_are_jumpers no)
		(fp_poly
			(pts
				(xy 0.2794 -0.1016) (xy -0.2794 -0.1016) (xy -0.2794 0.9906) (xy 0.2794 0.9906)
			)
			(stroke
				(width 0)
				(type default)
			)
			(fill no)
			(layer "B.CrtYd")
		)
		(fp_line
			(start 0.2794 0.9906)
			(end -0.2794 0.9906)
			(stroke
				(width 0.1)
				(type default)
			)
			(layer "B.Fab")
		)
		(fp_line
			(start 0.2794 -0.1016)
			(end 0.2794 0.9906)
			(stroke
				(width 0.1)
				(type default)
			)
			(layer "B.Fab")
		)
		(fp_line
			(start -0.2794 0.9906)
			(end -0.2794 -0.1016)
			(stroke
				(width 0.1)
				(type default)
			)
			(layer "B.Fab")
		)
		(fp_line
			(start -0.2794 -0.1016)
			(end 0.2794 -0.1016)
			(stroke
				(width 0.1)
				(type default)
			)
			(layer "B.Fab")
		)
		(pad "1" smd rect
			(at 0 0)
			(size 0.508 0.508)
			(layers "B.Cu" "B.Mask" "B.Paste")
			(net "FM_PMBUS_ALERT_BUF_EN_R3_N")
		)
		(pad "2" smd rect
			(at 0 0.889)
			(size 0.508 0.508)
			(layers "B.Cu" "B.Mask" "B.Paste")
			(net "FM_PMBUS_ALERT_BUF_EN_N")
		)
		(zone
			(layer "B.Cu")
			(hatch none 0.5)
			(connect_pads
				(clearance 0)
			)
			(min_thickness 0.25)
			(keepout
				(tracks not_allowed)
				(vias allowed)
				(pads allowed)
				(copperpour not_allowed)
				(footprints allowed)
			)
			(placement
				(enabled no)
				(sheetname "")
			)
			(fill
				(thermal_gap 0.5)
				(thermal_bridge_width 0.5)
				(island_removal_mode 0)
			)
			(polygon
				(pts
					(xy 424.561 -27.6352) (xy 425.069 -27.6352) (xy 425.069 -27.2542) (xy 424.561 -27.2542)
				)
			)
		)
		(zone
			(layer "B.Cu")
			(hatch none 0.5)
			(connect_pads
				(clearance 0)
			)
			(min_thickness 0.25)
			(keepout
				(tracks allowed)
				(vias not_allowed)
				(pads allowed)
				(copperpour not_allowed)
				(footprints allowed)
			)
			(placement
				(enabled no)
				(sheetname "")
			)
			(fill
				(thermal_gap 0.5)
				(thermal_bridge_width 0.5)
				(island_removal_mode 0)
			)
			(polygon
				(pts
					(xy 424.561 -27.2542) (xy 425.069 -27.2542) (xy 425.069 -27.6352) (xy 424.561 -27.6352)
				)
			)
		)
	)
	(footprint ""
		(layer "B.Cu")
		(at 185.42 -145.923 -90)
		(property "Reference" "R6L9"
			(at 0 0 90)
			(layer "B.SilkS")
			(hide yes)
			(effects
				(font
					(size 1.27 1.27)
				)
				(justify mirror)
			)
		)
		(property "Value" ""
			(at 0 0 90)
			(layer "B.Fab")
			(effects
				(font
					(size 1.27 1.27)
				)
				(justify mirror)
			)
		)
		(duplicate_pad_numbers_are_jumpers no)
		(fp_rect
			(start -0.2794 0.9906)
			(end 0.2794 -0.1016)
			(stroke
				(width 0)
				(type default)
			)
			(fill no)
			(layer "B.CrtYd")
		)
		(fp_line
			(start -0.2794 0.9906)
			(end -0.2794 -0.1016)
			(stroke
				(width 0.1)
				(type default)
			)
			(layer "B.Fab")
		)
		(fp_line
			(start 0.2794 0.9906)
			(end -0.2794 0.9906)
			(stroke
				(width 0.1)
				(type default)
			)
			(layer "B.Fab")
		)
		(fp_line
			(start -0.2794 -0.1016)
			(end 0.2794 -0.1016)
			(stroke
				(width 0.1)
				(type default)
			)
			(layer "B.Fab")
		)
		(fp_line
			(start 0.2794 -0.1016)
			(end 0.2794 0.9906)
			(stroke
				(width 0.1)
				(type default)
			)
			(layer "B.Fab")
		)
		(pad "1" smd rect
			(at 0 0 90)
			(size 0.508 0.508)
			(layers "B.Cu" "B.Mask" "B.Paste")
			(net "P3V3")
		)
		(pad "2" smd rect
			(at 0 0.889 90)
			(size 0.508 0.508)
			(layers "B.Cu" "B.Mask" "B.Paste")
			(net "PWRGD_PVTT_DEF_CPU0_R")
		)
		(zone
			(layer "B.Cu")
			(hatch none 0.5)
			(connect_pads
				(clearance 0)
			)
			(min_thickness 0.25)
			(keepout
				(tracks allowed)
				(vias not_allowed)
				(pads allowed)
				(copperpour not_allowed)
				(footprints allowed)
			)
			(placement
				(enabled no)
				(sheetname "")
			)
			(fill
				(thermal_gap 0.5)
				(thermal_bridge_width 0.5)
				(island_removal_mode 0)
			)
			(polygon
				(pts
					(xy 184.785 -146.177) (xy 184.785 -145.669) (xy 185.166 -145.669) (xy 185.166 -146.177)
				)
			)
		)
		(zone
			(layer "B.Cu")
			(hatch none 0.5)
			(connect_pads
				(clearance 0)
			)
			(min_thickness 0.25)
			(keepout
				(tracks not_allowed)
				(vias allowed)
				(pads allowed)
				(copperpour not_allowed)
				(footprints allowed)
			)
			(placement
				(enabled no)
				(sheetname "")
			)
			(fill
				(thermal_gap 0.5)
				(thermal_bridge_width 0.5)
				(island_removal_mode 0)
			)
			(polygon
				(pts
					(xy 184.785 -146.177) (xy 184.785 -145.669) (xy 185.166 -145.669) (xy 185.166 -146.177)
				)
			)
		)
	)
	(footprint ""
		(layer "B.Cu")
		(at 400.351498 -34.782506)
		(property "Reference" "R25W93"
			(at -1.01473 0.656336 90)
			(unlocked yes)
			(layer "B.SilkS")
			(effects
				(font
					(size 0.4064 0.254)
					(thickness 0.1524)
				)
				(justify mirror)
			)
		)
		(property "Value" ""
			(at 0 0 0)
			(layer "B.Fab")
			(effects
				(font
					(size 1.27 1.27)
				)
				(justify mirror)
			)
		)
		(duplicate_pad_numbers_are_jumpers no)
		(fp_poly
			(pts
				(xy 0.4953 -0.2032) (xy -0.4953 -0.2032) (xy -0.4953 1.6002) (xy 0.4953 1.6002)
			)
			(stroke
				(width 0)
				(type default)
			)
			(fill no)
			(layer "B.CrtYd")
		)
		(fp_line
			(start -0.4953 -0.2032)
			(end -0.4953 1.6002)
			(stroke
				(width 0.1)
				(type default)
			)
			(layer "B.Fab")
		)
		(fp_line
			(start -0.4953 1.6002)
			(end 0.4953 1.6002)
			(stroke
				(width 0.1)
				(type default)
			)
			(layer "B.Fab")
		)
		(fp_line
			(start 0.4953 -0.2032)
			(end -0.4953 -0.2032)
			(stroke
				(width 0.1)
				(type default)
			)
			(layer "B.Fab")
		)
		(fp_line
			(start 0.4953 1.6002)
			(end 0.4953 -0.2032)
			(stroke
				(width 0.1)
				(type default)
			)
			(layer "B.Fab")
		)
		(pad "1" smd rect
			(at 0 0 180)
			(size 0.762 0.889)
			(layers "B.Cu" "B.Mask" "B.Paste")
			(net "P3V3_STBY")
		)
		(pad "2" smd rect
			(at 0 1.397 180)
			(size 0.762 0.889)
			(layers "B.Cu" "B.Mask" "B.Paste")
			(net "VCC_DACAV3V3")
		)
		(zone
			(layer "B.Cu")
			(hatch none 0.5)
			(connect_pads
				(clearance 0)
			)
			(min_thickness 0.25)
			(keepout
				(tracks allowed)
				(vias not_allowed)
				(pads allowed)
				(copperpour not_allowed)
				(footprints allowed)
			)
			(placement
				(enabled no)
				(sheetname "")
			)
			(fill
				(thermal_gap 0.5)
				(thermal_bridge_width 0.5)
				(island_removal_mode 0)
			)
			(polygon
				(pts
					(xy 399.970498 -33.830006) (xy 399.970498 -34.338006) (xy 400.732498 -34.338006) (xy 400.732498 -33.830006)
				)
			)
		)
		(zone
			(layer "B.Cu")
			(hatch none 0.5)
			(connect_pads
				(clearance 0)
			)
			(min_thickness 0.25)
			(keepout
				(tracks not_allowed)
				(vias allowed)
				(pads allowed)
				(copperpour not_allowed)
				(footprints allowed)
			)
			(placement
				(enabled no)
				(sheetname "")
			)
			(fill
				(thermal_gap 0.5)
				(thermal_bridge_width 0.5)
				(island_removal_mode 0)
			)
			(polygon
				(pts
					(xy 400.732498 -33.830006) (xy 400.732498 -34.338006) (xy 399.970498 -34.338006) (xy 399.970498 -33.830006)
				)
			)
		)
	)
	(footprint ""
		(layer "B.Cu")
		(at 390.4742 -61.7728 180)
		(property "Reference" "U2T3"
			(at 5.31368 1.00711 180)
			(unlocked yes)
			(layer "B.SilkS")
			(effects
				(font
					(size 0.7874 0.5842)
					(thickness 0.1524)
				)
				(justify left mirror)
			)
		)
		(property "Value" ""
			(at 0 0 0)
			(layer "B.Fab")
			(effects
				(font
					(size 1.27 1.27)
				)
				(justify mirror)
			)
		)
		(duplicate_pad_numbers_are_jumpers no)
		(fp_circle
			(center 0.4699 -0.8382)
			(end 0.3429 -0.8382)
			(stroke
				(width 0.254)
				(type default)
			)
			(fill no)
			(layer "B.SilkS")
		)
		(fp_poly
			(pts
				(xy -0.21463 -0.450088) (xy -1.56337 -0.450088) (xy -1.56337 1.75006) (xy -0.21463 1.75006)
			)
			(stroke
				(width 0)
				(type default)
			)
			(fill no)
			(layer "B.CrtYd")
		)
		(fp_line
			(start -0.21463 1.75006)
			(end -0.21463 -0.450088)
			(stroke
				(width 0.1)
				(type default)
			)
			(layer "B.Fab")
		)
		(fp_line
			(start -0.21463 -0.450088)
			(end -1.56337 -0.450088)
			(stroke
				(width 0.1)
				(type default)
			)
			(layer "B.Fab")
		)
		(fp_line
			(start -1.56337 1.75006)
			(end -0.21463 1.75006)
			(stroke
				(width 0.1)
				(type default)
			)
			(layer "B.Fab")
		)
		(fp_line
			(start -1.56337 -0.450088)
			(end -1.56337 1.75006)
			(stroke
				(width 0.1)
				(type default)
			)
			(layer "B.Fab")
		)
		(fp_circle
			(center 0.4699 -0.8382)
			(end 0.3429 -0.8382)
			(stroke
				(width 0.254)
				(type default)
			)
			(fill no)
			(layer "B.Fab")
		)
		(pad "1" smd rect
			(at 0 0)
			(size 1.016 0.381)
			(layers "B.Cu" "B.Mask" "B.Paste")
			(net "FM_DUAL_BIOS_SEL_N")
		)
		(pad "2" smd rect
			(at 0 0.649986)
			(size 1.016 0.381)
			(layers "B.Cu" "B.Mask" "B.Paste")
			(net "SPI_SWITCH_CS0_N")
		)
		(pad "3" smd rect
			(at 0 1.299972)
			(size 1.016 0.381)
			(layers "B.Cu" "B.Mask" "B.Paste")
			(net "GND")
		)
		(pad "4" smd rect
			(at -1.778 1.299972)
			(size 1.016 0.381)
			(layers "B.Cu" "B.Mask" "B.Paste")
			(net "SPI_CS0_PRIMARY_N")
		)
		(pad "5" smd rect
			(at -1.778 0)
			(size 1.016 0.381)
			(layers "B.Cu" "B.Mask" "B.Paste")
			(net "P3V3_STBY")
		)
	)
	(footprint ""
		(layer "B.Cu")
		(at 390.13765 -107.85475)
		(property "Reference" "C2N12"
			(at 0 0 0)
			(layer "B.SilkS")
			(hide yes)
			(effects
				(font
					(size 1.27 1.27)
				)
				(justify mirror)
			)
		)
		(property "Value" ""
			(at 0 0 0)
			(layer "B.Fab")
			(effects
				(font
					(size 1.27 1.27)
				)
				(justify mirror)
			)
		)
		(duplicate_pad_numbers_are_jumpers no)
		(fp_rect
			(start 0.2794 0.9144)
			(end -0.2794 -0.1143)
			(stroke
				(width 0)
				(type default)
			)
			(fill no)
			(layer "B.CrtYd")
		)
		(fp_line
			(start -0.2794 -0.1143)
			(end -0.2794 0.9144)
			(stroke
				(width 0.1)
				(type default)
			)
			(layer "B.Fab")
		)
		(fp_line
			(start -0.2794 0.9144)
			(end 0.2794 0.9144)
			(stroke
				(width 0.1)
				(type default)
			)
			(layer "B.Fab")
		)
		(fp_line
			(start 0.2794 -0.1143)
			(end -0.2794 -0.1143)
			(stroke
				(width 0.1)
				(type default)
			)
			(layer "B.Fab")
		)
		(fp_line
			(start 0.2794 0.9144)
			(end 0.2794 -0.1143)
			(stroke
				(width 0.1)
				(type default)
			)
			(layer "B.Fab")
		)
		(pad "1" smd custom
			(at 0 0 270)
			(size 0.10414 0.10414)
			(layers "B.Cu" "B.Mask" "B.Paste")
			(net "PVNN_PCH_STBY")
			(options
				(clearance outline)
				(anchor circle)
			)
			(primitives
				(gr_poly
					(pts
						(xy -0.20828 -0.08636) (xy -0.20828 0.08636) (xy -0.08636 0.20828) (xy 0.086614 0.20828) (xy 0.20828 0.086614)
						(xy 0.20828 -0.08636) (xy 0.08636 -0.20828) (xy -0.08636 -0.20828)
					)
					(width 0)
					(fill yes)
				)
			)
		)
		(pad "2" smd custom
			(at 0 0.8001 270)
			(size 0.10414 0.10414)
			(layers "B.Cu" "B.Mask" "B.Paste")
			(net "GND")
			(options
				(clearance outline)
				(anchor circle)
			)
			(primitives
				(gr_poly
					(pts
						(xy -0.20828 -0.08636) (xy -0.20828 0.08636) (xy -0.08636 0.20828) (xy 0.086614 0.20828) (xy 0.20828 0.086614)
						(xy 0.20828 -0.08636) (xy 0.08636 -0.20828) (xy -0.08636 -0.20828)
					)
					(width 0)
					(fill yes)
				)
			)
		)
		(zone
			(layer "B.Cu")
			(hatch none 0.5)
			(connect_pads
				(clearance 0)
			)
			(min_thickness 0.25)
			(keepout
				(tracks not_allowed)
				(vias allowed)
				(pads allowed)
				(copperpour not_allowed)
				(footprints allowed)
			)
			(placement
				(enabled no)
				(sheetname "")
			)
			(fill
				(thermal_gap 0.5)
				(thermal_bridge_width 0.5)
				(island_removal_mode 0)
			)
			(polygon
				(pts
					(xy 390.22528 -107.6452) (xy 390.22528 -107.2642) (xy 390.05002 -107.2642) (xy 390.049766 -107.6452)
				)
			)
		)
		(zone
			(layer "B.Cu")
			(hatch none 0.5)
			(connect_pads
				(clearance 0)
			)
			(min_thickness 0.25)
			(keepout
				(tracks allowed)
				(vias not_allowed)
				(pads allowed)
				(copperpour not_allowed)
				(footprints allowed)
			)
			(placement
				(enabled no)
				(sheetname "")
			)
			(fill
				(thermal_gap 0.5)
				(thermal_bridge_width 0.5)
				(island_removal_mode 0)
			)
			(polygon
				(pts
					(xy 390.22528 -107.6452) (xy 390.22528 -107.2642) (xy 390.05002 -107.2642) (xy 390.049766 -107.6452)
				)
			)
		)
	)
	(footprint ""
		(layer "B.Cu")
		(at 433.578 -152.4 -90)
		(property "Reference" "R2L12"
			(at 0 0 90)
			(layer "B.SilkS")
			(hide yes)
			(effects
				(font
					(size 1.27 1.27)
				)
				(justify mirror)
			)
		)
		(property "Value" ""
			(at 0 0 90)
			(layer "B.Fab")
			(effects
				(font
					(size 1.27 1.27)
				)
				(justify mirror)
			)
		)
		(duplicate_pad_numbers_are_jumpers no)
		(fp_poly
			(pts
				(xy 0.2794 -0.1016) (xy -0.2794 -0.1016) (xy -0.2794 0.9906) (xy 0.2794 0.9906)
			)
			(stroke
				(width 0)
				(type default)
			)
			(fill no)
			(layer "B.CrtYd")
		)
		(fp_line
			(start -0.2794 0.9906)
			(end -0.2794 -0.1016)
			(stroke
				(width 0.1)
				(type default)
			)
			(layer "B.Fab")
		)
		(fp_line
			(start 0.2794 0.9906)
			(end -0.2794 0.9906)
			(stroke
				(width 0.1)
				(type default)
			)
			(layer "B.Fab")
		)
		(fp_line
			(start -0.2794 -0.1016)
			(end 0.2794 -0.1016)
			(stroke
				(width 0.1)
				(type default)
			)
			(layer "B.Fab")
		)
		(fp_line
			(start 0.2794 -0.1016)
			(end 0.2794 0.9906)
			(stroke
				(width 0.1)
				(type default)
			)
			(layer "B.Fab")
		)
		(pad "1" smd rect
			(at 0 0 90)
			(size 0.508 0.508)
			(layers "B.Cu" "B.Mask" "B.Paste")
			(net "P3V3_STBY")
		)
		(pad "2" smd rect
			(at 0 0.889 90)
			(size 0.508 0.508)
			(layers "B.Cu" "B.Mask" "B.Paste")
			(net "SGPIO_PCH_SATA_LOAD_R")
		)
		(zone
			(layer "B.Cu")
			(hatch none 0.5)
			(connect_pads
				(clearance 0)
			)
			(min_thickness 0.25)
			(keepout
				(tracks not_allowed)
				(vias allowed)
				(pads allowed)
				(copperpour not_allowed)
				(footprints allowed)
			)
			(placement
				(enabled no)
				(sheetname "")
			)
			(fill
				(thermal_gap 0.5)
				(thermal_bridge_width 0.5)
				(island_removal_mode 0)
			)
			(polygon
				(pts
					(xy 432.943 -152.146) (xy 432.943 -152.654) (xy 433.324 -152.654) (xy 433.324 -152.146)
				)
			)
		)
		(zone
			(layer "B.Cu")
			(hatch none 0.5)
			(connect_pads
				(clearance 0)
			)
			(min_thickness 0.25)
			(keepout
				(tracks allowed)
				(vias not_allowed)
				(pads allowed)
				(copperpour not_allowed)
				(footprints allowed)
			)
			(placement
				(enabled no)
				(sheetname "")
			)
			(fill
				(thermal_gap 0.5)
				(thermal_bridge_width 0.5)
				(island_removal_mode 0)
			)
			(polygon
				(pts
					(xy 433.324 -152.146) (xy 433.324 -152.654) (xy 432.943 -152.654) (xy 432.943 -152.146)
				)
			)
		)
	)
	(footprint ""
		(layer "B.Cu")
		(at 22.606 -75.946 90)
		(property "Reference" "C9P14"
			(at 0 0 90)
			(layer "B.SilkS")
			(hide yes)
			(effects
				(font
					(size 1.27 1.27)
				)
				(justify mirror)
			)
		)
		(property "Value" ""
			(at 0 0 90)
			(layer "B.Fab")
			(effects
				(font
					(size 1.27 1.27)
				)
				(justify mirror)
			)
		)
		(duplicate_pad_numbers_are_jumpers no)
		(fp_rect
			(start 0.4953 1.6002)
			(end -0.4953 -0.2032)
			(stroke
				(width 0)
				(type default)
			)
			(fill no)
			(layer "B.CrtYd")
		)
		(fp_line
			(start 0.4953 -0.2032)
			(end -0.4953 -0.2032)
			(stroke
				(width 0.1)
				(type default)
			)
			(layer "B.Fab")
		)
		(fp_line
			(start -0.4953 -0.2032)
			(end -0.4953 1.6002)
			(stroke
				(width 0.1)
				(type default)
			)
			(layer "B.Fab")
		)
		(fp_line
			(start 0.4953 1.6002)
			(end 0.4953 -0.2032)
			(stroke
				(width 0.1)
				(type default)
			)
			(layer "B.Fab")
		)
		(fp_line
			(start -0.4953 1.6002)
			(end 0.4953 1.6002)
			(stroke
				(width 0.1)
				(type default)
			)
			(layer "B.Fab")
		)
		(pad "1" smd rect
			(at 0 0 270)
			(size 0.762 0.889)
			(layers "B.Cu" "B.Mask" "B.Paste")
			(net "A_HSC_TIMER")
		)
		(pad "2" smd rect
			(at 0 1.397 270)
			(size 0.762 0.889)
			(layers "B.Cu" "B.Mask" "B.Paste")
			(net "AGND_HSC")
		)
		(zone
			(layer "B.Cu")
			(hatch none 0.5)
			(connect_pads
				(clearance 0)
			)
			(min_thickness 0.25)
			(keepout
				(tracks not_allowed)
				(vias allowed)
				(pads allowed)
				(copperpour not_allowed)
				(footprints allowed)
			)
			(placement
				(enabled no)
				(sheetname "")
			)
			(fill
				(thermal_gap 0.5)
				(thermal_bridge_width 0.5)
				(island_removal_mode 0)
			)
			(polygon
				(pts
					(xy 23.5585 -76.327) (xy 23.0505 -76.327) (xy 23.0505 -75.565) (xy 23.5585 -75.565)
				)
			)
		)
	)
	(footprint ""
		(layer "B.Cu")
		(at 193.092832 -8.122412 -90)
		(property "Reference" "C6U10"
			(at 0 0 90)
			(layer "B.SilkS")
			(hide yes)
			(effects
				(font
					(size 1.27 1.27)
				)
				(justify mirror)
			)
		)
		(property "Value" ""
			(at 0 0 90)
			(layer "B.Fab")
			(effects
				(font
					(size 1.27 1.27)
				)
				(justify mirror)
			)
		)
		(duplicate_pad_numbers_are_jumpers no)
		(fp_rect
			(start 0.7239 1.9939)
			(end -0.7239 -0.2159)
			(stroke
				(width 0)
				(type default)
			)
			(fill no)
			(layer "B.CrtYd")
		)
		(fp_line
			(start -0.7239 1.9939)
			(end -0.7239 -0.2159)
			(stroke
				(width 0.1)
				(type default)
			)
			(layer "B.Fab")
		)
		(fp_line
			(start 0.7239 1.9939)
			(end -0.7239 1.9939)
			(stroke
				(width 0.1)
				(type default)
			)
			(layer "B.Fab")
		)
		(fp_line
			(start -0.7239 -0.2159)
			(end 0.7239 -0.2159)
			(stroke
				(width 0.1)
				(type default)
			)
			(layer "B.Fab")
		)
		(fp_line
			(start 0.7239 -0.2159)
			(end 0.7239 1.9939)
			(stroke
				(width 0.1)
				(type default)
			)
			(layer "B.Fab")
		)
		(pad "1" smd rect
			(at 0 0 90)
			(size 1.27 1.016)
			(layers "B.Cu" "B.Mask" "B.Paste")
			(net "P12V_NVDIMM_ABC")
		)
		(pad "2" smd rect
			(at 0 1.778 90)
			(size 1.27 1.016)
			(layers "B.Cu" "B.Mask" "B.Paste")
			(net "GND")
		)
		(zone
			(layer "B.Cu")
			(hatch none 0.5)
			(connect_pads
				(clearance 0)
			)
			(min_thickness 0.25)
			(keepout
				(tracks not_allowed)
				(vias allowed)
				(pads allowed)
				(copperpour not_allowed)
				(footprints allowed)
			)
			(placement
				(enabled no)
				(sheetname "")
			)
			(fill
				(thermal_gap 0.5)
				(thermal_bridge_width 0.5)
				(island_removal_mode 0)
			)
			(polygon
				(pts
					(xy 191.822832 -7.487412) (xy 192.584832 -7.487412) (xy 192.584832 -8.757412) (xy 191.822832 -8.757412)
				)
			)
		)
	)
	(footprint ""
		(layer "B.Cu")
		(at 474.814138 -127.242316 -90)
		(property "Reference" "R1W34"
			(at 0.8382 -0.67818 270)
			(unlocked yes)
			(layer "B.SilkS")
			(effects
				(font
					(size 0.4064 0.254)
					(thickness 0.1524)
				)
				(justify left mirror)
			)
		)
		(property "Value" ""
			(at 0 0 90)
			(layer "B.Fab")
			(effects
				(font
					(size 1.27 1.27)
				)
				(justify mirror)
			)
		)
		(duplicate_pad_numbers_are_jumpers no)
		(fp_poly
			(pts
				(xy 0.2794 -0.1016) (xy -0.2794 -0.1016) (xy -0.2794 0.9906) (xy 0.2794 0.9906)
			)
			(stroke
				(width 0)
				(type default)
			)
			(fill no)
			(layer "B.CrtYd")
		)
		(fp_line
			(start -0.2794 0.9906)
			(end -0.2794 -0.1016)
			(stroke
				(width 0.1)
				(type default)
			)
			(layer "B.Fab")
		)
		(fp_line
			(start 0.2794 0.9906)
			(end -0.2794 0.9906)
			(stroke
				(width 0.1)
				(type default)
			)
			(layer "B.Fab")
		)
		(fp_line
			(start -0.2794 -0.1016)
			(end 0.2794 -0.1016)
			(stroke
				(width 0.1)
				(type default)
			)
			(layer "B.Fab")
		)
		(fp_line
			(start 0.2794 -0.1016)
			(end 0.2794 0.9906)
			(stroke
				(width 0.1)
				(type default)
			)
			(layer "B.Fab")
		)
		(pad "1" smd rect
			(at 0 0 90)
			(size 0.508 0.508)
			(layers "B.Cu" "B.Mask" "B.Paste")
			(net "SMB_DEBUG_STBY_LVC3_SDA_R1")
		)
		(pad "2" smd rect
			(at 0 0.889 90)
			(size 0.508 0.508)
			(layers "B.Cu" "B.Mask" "B.Paste")
			(net "SMB_DEBUG_STBY_LVC3_SDA")
		)
		(zone
			(layer "B.Cu")
			(hatch none 0.5)
			(connect_pads
				(clearance 0)
			)
			(min_thickness 0.25)
			(keepout
				(tracks not_allowed)
				(vias allowed)
				(pads allowed)
				(copperpour not_allowed)
				(footprints allowed)
			)
			(placement
				(enabled no)
				(sheetname "")
			)
			(fill
				(thermal_gap 0.5)
				(thermal_bridge_width 0.5)
				(island_removal_mode 0)
			)
			(polygon
				(pts
					(xy 474.179138 -126.988316) (xy 474.179138 -127.496316) (xy 474.560138 -127.496316) (xy 474.560138 -126.988316)
				)
			)
		)
		(zone
			(layer "B.Cu")
			(hatch none 0.5)
			(connect_pads
				(clearance 0)
			)
			(min_thickness 0.25)
			(keepout
				(tracks allowed)
				(vias not_allowed)
				(pads allowed)
				(copperpour not_allowed)
				(footprints allowed)
			)
			(placement
				(enabled no)
				(sheetname "")
			)
			(fill
				(thermal_gap 0.5)
				(thermal_bridge_width 0.5)
				(island_removal_mode 0)
			)
			(polygon
				(pts
					(xy 474.560138 -126.988316) (xy 474.560138 -127.496316) (xy 474.179138 -127.496316) (xy 474.179138 -126.988316)
				)
			)
		)
	)
	(footprint ""
		(layer "B.Cu")
		(at 393.65047 -106.58221)
		(property "Reference" "C2N13"
			(at 0 0 0)
			(layer "B.SilkS")
			(hide yes)
			(effects
				(font
					(size 1.27 1.27)
				)
				(justify mirror)
			)
		)
		(property "Value" ""
			(at 0 0 0)
			(layer "B.Fab")
			(effects
				(font
					(size 1.27 1.27)
				)
				(justify mirror)
			)
		)
		(duplicate_pad_numbers_are_jumpers no)
		(fp_rect
			(start 0.2794 0.9144)
			(end -0.2794 -0.1143)
			(stroke
				(width 0)
				(type default)
			)
			(fill no)
			(layer "B.CrtYd")
		)
		(fp_line
			(start -0.2794 -0.1143)
			(end -0.2794 0.9144)
			(stroke
				(width 0.1)
				(type default)
			)
			(layer "B.Fab")
		)
		(fp_line
			(start -0.2794 0.9144)
			(end 0.2794 0.9144)
			(stroke
				(width 0.1)
				(type default)
			)
			(layer "B.Fab")
		)
		(fp_line
			(start 0.2794 -0.1143)
			(end -0.2794 -0.1143)
			(stroke
				(width 0.1)
				(type default)
			)
			(layer "B.Fab")
		)
		(fp_line
			(start 0.2794 0.9144)
			(end 0.2794 -0.1143)
			(stroke
				(width 0.1)
				(type default)
			)
			(layer "B.Fab")
		)
		(pad "1" smd custom
			(at 0 0 270)
			(size 0.10414 0.10414)
			(layers "B.Cu" "B.Mask" "B.Paste")
			(net "P1V05_PCH_STBY")
			(options
				(clearance outline)
				(anchor circle)
			)
			(primitives
				(gr_poly
					(pts
						(xy -0.20828 -0.08636) (xy -0.20828 0.08636) (xy -0.08636 0.20828) (xy 0.086614 0.20828) (xy 0.20828 0.086614)
						(xy 0.20828 -0.08636) (xy 0.08636 -0.20828) (xy -0.08636 -0.20828)
					)
					(width 0)
					(fill yes)
				)
			)
		)
		(pad "2" smd custom
			(at 0 0.8001 270)
			(size 0.10414 0.10414)
			(layers "B.Cu" "B.Mask" "B.Paste")
			(net "GND")
			(options
				(clearance outline)
				(anchor circle)
			)
			(primitives
				(gr_poly
					(pts
						(xy -0.20828 -0.08636) (xy -0.20828 0.08636) (xy -0.08636 0.20828) (xy 0.086614 0.20828) (xy 0.20828 0.086614)
						(xy 0.20828 -0.08636) (xy 0.08636 -0.20828) (xy -0.08636 -0.20828)
					)
					(width 0)
					(fill yes)
				)
			)
		)
		(zone
			(layer "B.Cu")
			(hatch none 0.5)
			(connect_pads
				(clearance 0)
			)
			(min_thickness 0.25)
			(keepout
				(tracks not_allowed)
				(vias allowed)
				(pads allowed)
				(copperpour not_allowed)
				(footprints allowed)
			)
			(placement
				(enabled no)
				(sheetname "")
			)
			(fill
				(thermal_gap 0.5)
				(thermal_bridge_width 0.5)
				(island_removal_mode 0)
			)
			(polygon
				(pts
					(xy 393.7381 -106.37266) (xy 393.7381 -105.99166) (xy 393.56284 -105.99166) (xy 393.562586 -106.37266)
				)
			)
		)
		(zone
			(layer "B.Cu")
			(hatch none 0.5)
			(connect_pads
				(clearance 0)
			)
			(min_thickness 0.25)
			(keepout
				(tracks allowed)
				(vias not_allowed)
				(pads allowed)
				(copperpour not_allowed)
				(footprints allowed)
			)
			(placement
				(enabled no)
				(sheetname "")
			)
			(fill
				(thermal_gap 0.5)
				(thermal_bridge_width 0.5)
				(island_removal_mode 0)
			)
			(polygon
				(pts
					(xy 393.7381 -106.37266) (xy 393.7381 -105.99166) (xy 393.56284 -105.99166) (xy 393.562586 -106.37266)
				)
			)
		)
	)
	(footprint ""
		(layer "B.Cu")
		(at 493.137698 -46.533816 -90)
		(property "Reference" "Q25W4"
			(at 0 -0.81788 270)
			(unlocked yes)
			(layer "B.SilkS")
			(effects
				(font
					(size 0.4064 0.254)
					(thickness 0.1524)
				)
				(justify left mirror)
			)
		)
		(property "Value" ""
			(at 0 0 90)
			(layer "B.Fab")
			(effects
				(font
					(size 1.27 1.27)
				)
				(justify mirror)
			)
		)
		(duplicate_pad_numbers_are_jumpers no)
		(fp_circle
			(center 0.848614 -0.6477)
			(end 0.848614 -0.7747)
			(stroke
				(width 0.254)
				(type default)
			)
			(fill no)
			(layer "B.SilkS")
		)
		(fp_poly
			(pts
				(xy -0.21463 -0.450088) (xy -1.56337 -0.450088) (xy -1.56337 1.75006) (xy -0.21463 1.75006)
			)
			(stroke
				(width 0)
				(type default)
			)
			(fill no)
			(layer "B.CrtYd")
		)
		(fp_line
			(start -1.56337 1.75006)
			(end -0.21463 1.75006)
			(stroke
				(width 0.1)
				(type default)
			)
			(layer "B.Fab")
		)
		(fp_line
			(start -0.21463 1.75006)
			(end -0.21463 -0.450088)
			(stroke
				(width 0.1)
				(type default)
			)
			(layer "B.Fab")
		)
		(fp_line
			(start -1.56337 -0.450088)
			(end -1.56337 1.75006)
			(stroke
				(width 0.1)
				(type default)
			)
			(layer "B.Fab")
		)
		(fp_line
			(start -0.21463 -0.450088)
			(end -1.56337 -0.450088)
			(stroke
				(width 0.1)
				(type default)
			)
			(layer "B.Fab")
		)
		(fp_circle
			(center 0.848614 -0.6477)
			(end 0.848614 -0.7747)
			(stroke
				(width 0.254)
				(type default)
			)
			(fill no)
			(layer "B.Fab")
		)
		(pad "1" smd rect
			(at 0 0 90)
			(size 1.016 0.381)
			(layers "B.Cu" "B.Mask" "B.Paste")
			(net "I2C_BMC_VGA_DDC_SCL")
		)
		(pad "2" smd rect
			(at 0 0.649986 90)
			(size 1.016 0.381)
			(layers "B.Cu" "B.Mask" "B.Paste")
			(net "Q25W1_GATE")
		)
		(pad "3" smd rect
			(at 0 1.299972 90)
			(size 1.016 0.381)
			(layers "B.Cu" "B.Mask" "B.Paste")
			(net "I2C_BMC_VGA_DDC_SDA_G")
		)
		(pad "4" smd rect
			(at -1.778 1.299972 90)
			(size 1.016 0.381)
			(layers "B.Cu" "B.Mask" "B.Paste")
			(net "I2C_BMC_VGA_DDC_SDA")
		)
		(pad "5" smd rect
			(at -1.778 0.649986 90)
			(size 1.016 0.381)
			(layers "B.Cu" "B.Mask" "B.Paste")
			(net "Q25W2_GATE")
		)
		(pad "6" smd rect
			(at -1.778 0 90)
			(size 1.016 0.381)
			(layers "B.Cu" "B.Mask" "B.Paste")
			(net "I2C_BMC_VGA_DDC_SCL_G")
		)
	)
	(footprint ""
		(layer "B.Cu")
		(at 423.342054 -44.706794 180)
		(property "Reference" "R25W184"
			(at 0.8382 -0.67818 180)
			(unlocked yes)
			(layer "B.SilkS")
			(effects
				(font
					(size 0.4064 0.254)
					(thickness 0.1524)
				)
				(justify left mirror)
			)
		)
		(property "Value" ""
			(at 0 0 0)
			(layer "B.Fab")
			(effects
				(font
					(size 1.27 1.27)
				)
				(justify mirror)
			)
		)
		(duplicate_pad_numbers_are_jumpers no)
		(fp_poly
			(pts
				(xy 0.2794 -0.1016) (xy -0.2794 -0.1016) (xy -0.2794 0.9906) (xy 0.2794 0.9906)
			)
			(stroke
				(width 0)
				(type default)
			)
			(fill no)
			(layer "B.CrtYd")
		)
		(fp_line
			(start 0.2794 0.9906)
			(end -0.2794 0.9906)
			(stroke
				(width 0.1)
				(type default)
			)
			(layer "B.Fab")
		)
		(fp_line
			(start 0.2794 -0.1016)
			(end 0.2794 0.9906)
			(stroke
				(width 0.1)
				(type default)
			)
			(layer "B.Fab")
		)
		(fp_line
			(start -0.2794 0.9906)
			(end -0.2794 -0.1016)
			(stroke
				(width 0.1)
				(type default)
			)
			(layer "B.Fab")
		)
		(fp_line
			(start -0.2794 -0.1016)
			(end 0.2794 -0.1016)
			(stroke
				(width 0.1)
				(type default)
			)
			(layer "B.Fab")
		)
		(pad "1" smd rect
			(at 0 0)
			(size 0.508 0.508)
			(layers "B.Cu" "B.Mask" "B.Paste")
			(net "RST_BMC_PLTRST_BUF_N")
		)
		(pad "2" smd rect
			(at 0 0.889)
			(size 0.508 0.508)
			(layers "B.Cu" "B.Mask" "B.Paste")
			(net "RST_PLTRST_BUF_N")
		)
		(zone
			(layer "B.Cu")
			(hatch none 0.5)
			(connect_pads
				(clearance 0)
			)
			(min_thickness 0.25)
			(keepout
				(tracks not_allowed)
				(vias allowed)
				(pads allowed)
				(copperpour not_allowed)
				(footprints allowed)
			)
			(placement
				(enabled no)
				(sheetname "")
			)
			(fill
				(thermal_gap 0.5)
				(thermal_bridge_width 0.5)
				(island_removal_mode 0)
			)
			(polygon
				(pts
					(xy 423.088054 -45.341794) (xy 423.596054 -45.341794) (xy 423.596054 -44.960794) (xy 423.088054 -44.960794)
				)
			)
		)
		(zone
			(layer "B.Cu")
			(hatch none 0.5)
			(connect_pads
				(clearance 0)
			)
			(min_thickness 0.25)
			(keepout
				(tracks allowed)
				(vias not_allowed)
				(pads allowed)
				(copperpour not_allowed)
				(footprints allowed)
			)
			(placement
				(enabled no)
				(sheetname "")
			)
			(fill
				(thermal_gap 0.5)
				(thermal_bridge_width 0.5)
				(island_removal_mode 0)
			)
			(polygon
				(pts
					(xy 423.088054 -44.960794) (xy 423.596054 -44.960794) (xy 423.596054 -45.341794) (xy 423.088054 -45.341794)
				)
			)
		)
	)
	(footprint ""
		(layer "B.Cu")
		(at 321.1957 -28.36418 90)
		(property "Reference" "R4T8"
			(at 0 0 90)
			(layer "B.SilkS")
			(hide yes)
			(effects
				(font
					(size 1.27 1.27)
				)
				(justify mirror)
			)
		)
		(property "Value" ""
			(at 0 0 90)
			(layer "B.Fab")
			(effects
				(font
					(size 1.27 1.27)
				)
				(justify mirror)
			)
		)
		(duplicate_pad_numbers_are_jumpers no)
		(fp_poly
			(pts
				(xy 0.2794 -0.1016) (xy -0.2794 -0.1016) (xy -0.2794 0.9906) (xy 0.2794 0.9906)
			)
			(stroke
				(width 0)
				(type default)
			)
			(fill no)
			(layer "B.CrtYd")
		)
		(fp_line
			(start 0.2794 -0.1016)
			(end 0.2794 0.9906)
			(stroke
				(width 0.1)
				(type default)
			)
			(layer "B.Fab")
		)
		(fp_line
			(start -0.2794 -0.1016)
			(end 0.2794 -0.1016)
			(stroke
				(width 0.1)
				(type default)
			)
			(layer "B.Fab")
		)
		(fp_line
			(start 0.2794 0.9906)
			(end -0.2794 0.9906)
			(stroke
				(width 0.1)
				(type default)
			)
			(layer "B.Fab")
		)
		(fp_line
			(start -0.2794 0.9906)
			(end -0.2794 -0.1016)
			(stroke
				(width 0.1)
				(type default)
			)
			(layer "B.Fab")
		)
		(pad "1" smd rect
			(at 0 0 270)
			(size 0.508 0.508)
			(layers "B.Cu" "B.Mask" "B.Paste")
			(net "PVPP_ABC")
		)
		(pad "2" smd rect
			(at 0 0.889 270)
			(size 0.508 0.508)
			(layers "B.Cu" "B.Mask" "B.Paste")
			(net "SMB_DDR_ABC_VPP_SDA_R")
		)
		(zone
			(layer "B.Cu")
			(hatch none 0.5)
			(connect_pads
				(clearance 0)
			)
			(min_thickness 0.25)
			(keepout
				(tracks allowed)
				(vias not_allowed)
				(pads allowed)
				(copperpour not_allowed)
				(footprints allowed)
			)
			(placement
				(enabled no)
				(sheetname "")
			)
			(fill
				(thermal_gap 0.5)
				(thermal_bridge_width 0.5)
				(island_removal_mode 0)
			)
			(polygon
				(pts
					(xy 321.4497 -28.61818) (xy 321.4497 -28.11018) (xy 321.8307 -28.11018) (xy 321.8307 -28.61818)
				)
			)
		)
		(zone
			(layer "B.Cu")
			(hatch none 0.5)
			(connect_pads
				(clearance 0)
			)
			(min_thickness 0.25)
			(keepout
				(tracks not_allowed)
				(vias allowed)
				(pads allowed)
				(copperpour not_allowed)
				(footprints allowed)
			)
			(placement
				(enabled no)
				(sheetname "")
			)
			(fill
				(thermal_gap 0.5)
				(thermal_bridge_width 0.5)
				(island_removal_mode 0)
			)
			(polygon
				(pts
					(xy 321.8307 -28.61818) (xy 321.8307 -28.11018) (xy 321.4497 -28.11018) (xy 321.4497 -28.61818)
				)
			)
		)
	)
	(footprint ""
		(layer "B.Cu")
		(at 370.078 -28.448)
		(property "Reference" "RN8F2"
			(at 0.8382 -0.67818 0)
			(unlocked yes)
			(layer "B.SilkS")
			(effects
				(font
					(size 0.4064 0.254)
					(thickness 0.1524)
				)
				(justify left mirror)
			)
		)
		(property "Value" ""
			(at 0 0 0)
			(layer "B.Fab")
			(effects
				(font
					(size 1.27 1.27)
				)
				(justify mirror)
			)
		)
		(duplicate_pad_numbers_are_jumpers no)
		(fp_poly
			(pts
				(xy 0.2794 -0.1016) (xy -0.2794 -0.1016) (xy -0.2794 0.9906) (xy 0.2794 0.9906)
			)
			(stroke
				(width 0)
				(type default)
			)
			(fill no)
			(layer "B.CrtYd")
		)
		(fp_line
			(start -0.2794 -0.1016)
			(end 0.2794 -0.1016)
			(stroke
				(width 0.1)
				(type default)
			)
			(layer "B.Fab")
		)
		(fp_line
			(start -0.2794 0.9906)
			(end -0.2794 -0.1016)
			(stroke
				(width 0.1)
				(type default)
			)
			(layer "B.Fab")
		)
		(fp_line
			(start 0.2794 -0.1016)
			(end 0.2794 0.9906)
			(stroke
				(width 0.1)
				(type default)
			)
			(layer "B.Fab")
		)
		(fp_line
			(start 0.2794 0.9906)
			(end -0.2794 0.9906)
			(stroke
				(width 0.1)
				(type default)
			)
			(layer "B.Fab")
		)
		(pad "1" smd rect
			(at 0 0 180)
			(size 0.508 0.508)
			(layers "B.Cu" "B.Mask" "B.Paste")
			(net "P3V3_STBY")
		)
		(pad "2" smd rect
			(at 0 0.889 180)
			(size 0.508 0.508)
			(layers "B.Cu" "B.Mask" "B.Paste")
			(net "TPM_SPI_BMC_WP_N")
		)
		(zone
			(layer "B.Cu")
			(hatch none 0.5)
			(connect_pads
				(clearance 0)
			)
			(min_thickness 0.25)
			(keepout
				(tracks allowed)
				(vias not_allowed)
				(pads allowed)
				(copperpour not_allowed)
				(footprints allowed)
			)
			(placement
				(enabled no)
				(sheetname "")
			)
			(fill
				(thermal_gap 0.5)
				(thermal_bridge_width 0.5)
				(island_removal_mode 0)
			)
			(polygon
				(pts
					(xy 370.332 -28.194) (xy 369.824 -28.194) (xy 369.824 -27.813) (xy 370.332 -27.813)
				)
			)
		)
		(zone
			(layer "B.Cu")
			(hatch none 0.5)
			(connect_pads
				(clearance 0)
			)
			(min_thickness 0.25)
			(keepout
				(tracks not_allowed)
				(vias allowed)
				(pads allowed)
				(copperpour not_allowed)
				(footprints allowed)
			)
			(placement
				(enabled no)
				(sheetname "")
			)
			(fill
				(thermal_gap 0.5)
				(thermal_bridge_width 0.5)
				(island_removal_mode 0)
			)
			(polygon
				(pts
					(xy 370.332 -27.813) (xy 369.824 -27.813) (xy 369.824 -28.194) (xy 370.332 -28.194)
				)
			)
		)
	)
	(footprint ""
		(layer "B.Cu")
		(at 476.1992 -48.5394 -90)
		(property "Reference" "C9F2"
			(at 0 0 90)
			(layer "B.SilkS")
			(hide yes)
			(effects
				(font
					(size 1.27 1.27)
				)
				(justify mirror)
			)
		)
		(property "Value" "*"
			(at 0.0762 -6.2357 270)
			(unlocked yes)
			(layer "B.Fab")
			(hide yes)
			(effects
				(font
					(size 1.27 1.016)
					(thickness 0.1524)
				)
				(justify mirror)
			)
		)
		(property "Device Type" "SC22U16V5MX-4-GP_SMD-BCG5-SC22A"
			(at 0.0762 -8.2677 270)
			(unlocked yes)
			(layer "B.Fab")
			(hide yes)
			(effects
				(font
					(size 1.27 1.016)
					(thickness 0.1524)
				)
				(justify mirror)
			)
		)
		(duplicate_pad_numbers_are_jumpers no)
		(fp_line
			(start -0.635 0)
			(end 0.635 0)
			(stroke
				(width 0.508)
				(type default)
			)
			(layer "B.SilkS")
		)
		(fp_rect
			(start 0.9652 1.778)
			(end -0.9652 -1.778)
			(stroke
				(width 0)
				(type default)
			)
			(fill no)
			(layer "B.CrtYd")
		)
		(fp_poly
			(pts
				(xy 0.9652 -1.778) (xy -0.9652 -1.778) (xy -0.9652 1.778) (xy 0.9652 1.778)
			)
			(stroke
				(width 0)
				(type default)
			)
			(fill no)
			(layer "B.Fab")
		)
		(pad "1" smd rect
			(at 0 -0.9652 90)
			(size 1.397 1.143)
			(layers "B.Cu" "B.Mask" "B.Paste")
			(net "P3V3_STBY")
		)
		(pad "2" smd rect
			(at 0 0.9652 90)
			(size 1.397 1.143)
			(layers "B.Cu" "B.Mask" "B.Paste")
			(net "GND")
		)
	)
	(footprint ""
		(layer "B.Cu")
		(at 361.444794 -44.845986 -90)
		(property "Reference" "R2T38"
			(at 0 0 90)
			(layer "B.SilkS")
			(hide yes)
			(effects
				(font
					(size 1.27 1.27)
				)
				(justify mirror)
			)
		)
		(property "Value" ""
			(at 0 0 90)
			(layer "B.Fab")
			(effects
				(font
					(size 1.27 1.27)
				)
				(justify mirror)
			)
		)
		(duplicate_pad_numbers_are_jumpers no)
		(fp_poly
			(pts
				(xy 0.2794 -0.1016) (xy -0.2794 -0.1016) (xy -0.2794 0.9906) (xy 0.2794 0.9906)
			)
			(stroke
				(width 0)
				(type default)
			)
			(fill no)
			(layer "B.CrtYd")
		)
		(fp_line
			(start -0.2794 0.9906)
			(end -0.2794 -0.1016)
			(stroke
				(width 0.1)
				(type default)
			)
			(layer "B.Fab")
		)
		(fp_line
			(start 0.2794 0.9906)
			(end -0.2794 0.9906)
			(stroke
				(width 0.1)
				(type default)
			)
			(layer "B.Fab")
		)
		(fp_line
			(start -0.2794 -0.1016)
			(end 0.2794 -0.1016)
			(stroke
				(width 0.1)
				(type default)
			)
			(layer "B.Fab")
		)
		(fp_line
			(start 0.2794 -0.1016)
			(end 0.2794 0.9906)
			(stroke
				(width 0.1)
				(type default)
			)
			(layer "B.Fab")
		)
		(pad "1" smd rect
			(at 0 0 90)
			(size 0.508 0.508)
			(layers "B.Cu" "B.Mask" "B.Paste")
			(net "FM_CPU0_PROCHOT_LVT3_K_N")
		)
		(pad "2" smd rect
			(at 0 0.889 90)
			(size 0.508 0.508)
			(layers "B.Cu" "B.Mask" "B.Paste")
			(net "FM_CPU0_PROCHOT_LVT3_N")
		)
		(zone
			(layer "B.Cu")
			(hatch none 0.5)
			(connect_pads
				(clearance 0)
			)
			(min_thickness 0.25)
			(keepout
				(tracks not_allowed)
				(vias allowed)
				(pads allowed)
				(copperpour not_allowed)
				(footprints allowed)
			)
			(placement
				(enabled no)
				(sheetname "")
			)
			(fill
				(thermal_gap 0.5)
				(thermal_bridge_width 0.5)
				(island_removal_mode 0)
			)
			(polygon
				(pts
					(xy 360.809794 -44.591986) (xy 360.809794 -45.099986) (xy 361.190794 -45.099986) (xy 361.190794 -44.591986)
				)
			)
		)
		(zone
			(layer "B.Cu")
			(hatch none 0.5)
			(connect_pads
				(clearance 0)
			)
			(min_thickness 0.25)
			(keepout
				(tracks allowed)
				(vias not_allowed)
				(pads allowed)
				(copperpour not_allowed)
				(footprints allowed)
			)
			(placement
				(enabled no)
				(sheetname "")
			)
			(fill
				(thermal_gap 0.5)
				(thermal_bridge_width 0.5)
				(island_removal_mode 0)
			)
			(polygon
				(pts
					(xy 361.190794 -44.591986) (xy 361.190794 -45.099986) (xy 360.809794 -45.099986) (xy 360.809794 -44.591986)
				)
			)
		)
	)
	(footprint ""
		(layer "B.Cu")
		(at 281.3812 -75.7174 90)
		(property "Reference" "R4P6"
			(at 0 0 90)
			(layer "B.SilkS")
			(hide yes)
			(effects
				(font
					(size 1.27 1.27)
				)
				(justify mirror)
			)
		)
		(property "Value" ""
			(at 0 0 90)
			(layer "B.Fab")
			(effects
				(font
					(size 1.27 1.27)
				)
				(justify mirror)
			)
		)
		(duplicate_pad_numbers_are_jumpers no)
		(fp_rect
			(start -0.2794 -0.1016)
			(end 0.2794 0.9906)
			(stroke
				(width 0)
				(type default)
			)
			(fill no)
			(layer "B.CrtYd")
		)
		(fp_line
			(start 0.2794 -0.1016)
			(end 0.2794 0.9906)
			(stroke
				(width 0.1)
				(type default)
			)
			(layer "B.Fab")
		)
		(fp_line
			(start -0.2794 -0.1016)
			(end 0.2794 -0.1016)
			(stroke
				(width 0.1)
				(type default)
			)
			(layer "B.Fab")
		)
		(fp_line
			(start 0.2794 0.9906)
			(end -0.2794 0.9906)
			(stroke
				(width 0.1)
				(type default)
			)
			(layer "B.Fab")
		)
		(fp_line
			(start -0.2794 0.9906)
			(end -0.2794 -0.1016)
			(stroke
				(width 0.1)
				(type default)
			)
			(layer "B.Fab")
		)
		(pad "1" smd rect
			(at 0 0 270)
			(size 0.508 0.508)
			(layers "B.Cu" "B.Mask" "B.Paste")
			(net "GND")
		)
		(pad "2" smd rect
			(at 0 0.889 270)
			(size 0.508 0.508)
			(layers "B.Cu" "B.Mask" "B.Paste")
			(net "PD_CPU0_DMIMODE_OVERRIDE")
		)
		(zone
			(layer "B.Cu")
			(hatch none 0.5)
			(connect_pads
				(clearance 0)
			)
			(min_thickness 0.25)
			(keepout
				(tracks not_allowed)
				(vias allowed)
				(pads allowed)
				(copperpour not_allowed)
				(footprints allowed)
			)
			(placement
				(enabled no)
				(sheetname "")
			)
			(fill
				(thermal_gap 0.5)
				(thermal_bridge_width 0.5)
				(island_removal_mode 0)
			)
			(polygon
				(pts
					(xy 281.6352 -75.4634) (xy 282.0162 -75.4634) (xy 282.0162 -75.9714) (xy 281.6352 -75.9714)
				)
			)
		)
		(zone
			(layer "B.Cu")
			(hatch none 0.5)
			(connect_pads
				(clearance 0)
			)
			(min_thickness 0.25)
			(keepout
				(tracks allowed)
				(vias not_allowed)
				(pads allowed)
				(copperpour not_allowed)
				(footprints allowed)
			)
			(placement
				(enabled no)
				(sheetname "")
			)
			(fill
				(thermal_gap 0.5)
				(thermal_bridge_width 0.5)
				(island_removal_mode 0)
			)
			(polygon
				(pts
					(xy 281.6352 -75.4634) (xy 282.0162 -75.4634) (xy 282.0162 -75.9714) (xy 281.6352 -75.9714)
				)
			)
		)
	)
	(footprint ""
		(layer "B.Cu")
		(at 253.392432 -3.3528 90)
		(property "Reference" "C5G53"
			(at -1.14681 0.76708 180)
			(unlocked yes)
			(layer "B.SilkS")
			(effects
				(font
					(size 0.7874 0.5842)
					(thickness 0.1524)
				)
				(justify mirror)
			)
		)
		(property "Value" ""
			(at 0 0 90)
			(layer "B.Fab")
			(effects
				(font
					(size 1.27 1.27)
				)
				(justify mirror)
			)
		)
		(duplicate_pad_numbers_are_jumpers no)
		(fp_rect
			(start -0.4953 -0.2032)
			(end 0.4953 1.6002)
			(stroke
				(width 0)
				(type default)
			)
			(fill no)
			(layer "B.CrtYd")
		)
		(fp_line
			(start 0.4953 -0.2032)
			(end -0.4953 -0.2032)
			(stroke
				(width 0.1)
				(type default)
			)
			(layer "B.Fab")
		)
		(fp_line
			(start -0.4953 -0.2032)
			(end -0.4953 1.6002)
			(stroke
				(width 0.1)
				(type default)
			)
			(layer "B.Fab")
		)
		(fp_line
			(start 0.4953 1.6002)
			(end 0.4953 -0.2032)
			(stroke
				(width 0.1)
				(type default)
			)
			(layer "B.Fab")
		)
		(fp_line
			(start -0.4953 1.6002)
			(end 0.4953 1.6002)
			(stroke
				(width 0.1)
				(type default)
			)
			(layer "B.Fab")
		)
		(pad "1" smd rect
			(at 0 0 270)
			(size 0.762 0.889)
			(layers "B.Cu" "B.Mask" "B.Paste")
			(net "PVDDQ_ABC")
		)
		(pad "2" smd rect
			(at 0 1.397 270)
			(size 0.762 0.889)
			(layers "B.Cu" "B.Mask" "B.Paste")
			(net "GND")
		)
		(zone
			(layer "B.Cu")
			(hatch none 0.5)
			(connect_pads
				(clearance 0)
			)
			(min_thickness 0.25)
			(keepout
				(tracks not_allowed)
				(vias allowed)
				(pads allowed)
				(copperpour not_allowed)
				(footprints allowed)
			)
			(placement
				(enabled no)
				(sheetname "")
			)
			(fill
				(thermal_gap 0.5)
				(thermal_bridge_width 0.5)
				(island_removal_mode 0)
			)
			(polygon
				(pts
					(xy 253.836932 -2.9718) (xy 254.344932 -2.9718) (xy 254.344932 -3.7338) (xy 253.836932 -3.7338)
				)
			)
		)
	)
	(footprint ""
		(layer "B.Cu")
		(at 483.017322 -17.929606 -90)
		(property "Reference" "C9G3"
			(at 0 0 90)
			(layer "B.SilkS")
			(hide yes)
			(effects
				(font
					(size 1.27 1.27)
				)
				(justify mirror)
			)
		)
		(property "Value" ""
			(at 0 0 90)
			(layer "B.Fab")
			(effects
				(font
					(size 1.27 1.27)
				)
				(justify mirror)
			)
		)
		(duplicate_pad_numbers_are_jumpers no)
		(fp_poly
			(pts
				(xy -0.3048 -0.1016) (xy -0.3048 0.9906) (xy 0.3048 0.9906) (xy 0.3048 -0.1016)
			)
			(stroke
				(width 0)
				(type default)
			)
			(fill no)
			(layer "B.CrtYd")
		)
		(fp_line
			(start -0.3048 0.9906)
			(end -0.3048 -0.1016)
			(stroke
				(width 0.1)
				(type default)
			)
			(layer "B.Fab")
		)
		(fp_line
			(start 0.3048 0.9906)
			(end -0.3048 0.9906)
			(stroke
				(width 0.1)
				(type default)
			)
			(layer "B.Fab")
		)
		(fp_line
			(start -0.3048 -0.1016)
			(end 0.3048 -0.1016)
			(stroke
				(width 0.1)
				(type default)
			)
			(layer "B.Fab")
		)
		(fp_line
			(start 0.3048 -0.1016)
			(end 0.3048 0.9906)
			(stroke
				(width 0.1)
				(type default)
			)
			(layer "B.Fab")
		)
		(pad "1" smd rect
			(at 0 0 90)
			(size 0.508 0.508)
			(layers "B.Cu" "B.Mask" "B.Paste")
			(net "LED_LAN_0_N")
		)
		(pad "2" smd rect
			(at 0 0.889 90)
			(size 0.508 0.508)
			(layers "B.Cu" "B.Mask" "B.Paste")
			(net "GND")
		)
		(zone
			(layer "B.Cu")
			(hatch none 0.5)
			(connect_pads
				(clearance 0)
			)
			(min_thickness 0.25)
			(keepout
				(tracks not_allowed)
				(vias allowed)
				(pads allowed)
				(copperpour not_allowed)
				(footprints allowed)
			)
			(placement
				(enabled no)
				(sheetname "")
			)
			(fill
				(thermal_gap 0.5)
				(thermal_bridge_width 0.5)
				(island_removal_mode 0)
			)
			(polygon
				(pts
					(xy 482.382322 -17.675606) (xy 482.382322 -18.183606) (xy 482.763322 -18.183606) (xy 482.763322 -17.675606)
				)
			)
		)
		(zone
			(layer "B.Cu")
			(hatch none 0.5)
			(connect_pads
				(clearance 0)
			)
			(min_thickness 0.25)
			(keepout
				(tracks allowed)
				(vias not_allowed)
				(pads allowed)
				(copperpour not_allowed)
				(footprints allowed)
			)
			(placement
				(enabled no)
				(sheetname "")
			)
			(fill
				(thermal_gap 0.5)
				(thermal_bridge_width 0.5)
				(island_removal_mode 0)
			)
			(polygon
				(pts
					(xy 482.763322 -17.675606) (xy 482.763322 -18.183606) (xy 482.382322 -18.183606) (xy 482.382322 -17.675606)
				)
			)
		)
	)
	(footprint ""
		(layer "B.Cu")
		(at 350.2914 -145.923 180)
		(property "Reference" "CT48"
			(at 0.8382 -0.84963 180)
			(unlocked yes)
			(layer "B.SilkS")
			(effects
				(font
					(size 0.7874 0.5842)
					(thickness 0.1524)
				)
				(justify left mirror)
			)
		)
		(property "Value" ""
			(at 0 0 0)
			(layer "B.Fab")
			(effects
				(font
					(size 1.27 1.27)
				)
				(justify mirror)
			)
		)
		(duplicate_pad_numbers_are_jumpers no)
		(fp_poly
			(pts
				(xy -0.3048 -0.1016) (xy -0.3048 0.9906) (xy 0.3048 0.9906) (xy 0.3048 -0.1016)
			)
			(stroke
				(width 0)
				(type default)
			)
			(fill no)
			(layer "B.CrtYd")
		)
		(fp_line
			(start 0.3048 0.9906)
			(end -0.3048 0.9906)
			(stroke
				(width 0.1)
				(type default)
			)
			(layer "B.Fab")
		)
		(fp_line
			(start 0.3048 -0.1016)
			(end 0.3048 0.9906)
			(stroke
				(width 0.1)
				(type default)
			)
			(layer "B.Fab")
		)
		(fp_line
			(start -0.3048 0.9906)
			(end -0.3048 -0.1016)
			(stroke
				(width 0.1)
				(type default)
			)
			(layer "B.Fab")
		)
		(fp_line
			(start -0.3048 -0.1016)
			(end 0.3048 -0.1016)
			(stroke
				(width 0.1)
				(type default)
			)
			(layer "B.Fab")
		)
		(pad "1" smd rect
			(at 0 0)
			(size 0.508 0.508)
			(layers "B.Cu" "B.Mask" "B.Paste")
			(net "A_TSENSE_PVDDQ_DEF")
		)
		(pad "2" smd rect
			(at 0 0.889)
			(size 0.508 0.508)
			(layers "B.Cu" "B.Mask" "B.Paste")
			(net "GND")
		)
		(zone
			(layer "B.Cu")
			(hatch none 0.5)
			(connect_pads
				(clearance 0)
			)
			(min_thickness 0.25)
			(keepout
				(tracks not_allowed)
				(vias allowed)
				(pads allowed)
				(copperpour not_allowed)
				(footprints allowed)
			)
			(placement
				(enabled no)
				(sheetname "")
			)
			(fill
				(thermal_gap 0.5)
				(thermal_bridge_width 0.5)
				(island_removal_mode 0)
			)
			(polygon
				(pts
					(xy 350.0374 -146.558) (xy 350.5454 -146.558) (xy 350.5454 -146.177) (xy 350.0374 -146.177)
				)
			)
		)
		(zone
			(layer "B.Cu")
			(hatch none 0.5)
			(connect_pads
				(clearance 0)
			)
			(min_thickness 0.25)
			(keepout
				(tracks allowed)
				(vias not_allowed)
				(pads allowed)
				(copperpour not_allowed)
				(footprints allowed)
			)
			(placement
				(enabled no)
				(sheetname "")
			)
			(fill
				(thermal_gap 0.5)
				(thermal_bridge_width 0.5)
				(island_removal_mode 0)
			)
			(polygon
				(pts
					(xy 350.0374 -146.177) (xy 350.5454 -146.177) (xy 350.5454 -146.558) (xy 350.0374 -146.558)
				)
			)
		)
	)
	(footprint ""
		(layer "B.Cu")
		(at 351.028 -28.575 180)
		(property "Reference" "C3T8"
			(at 0 0 0)
			(layer "B.SilkS")
			(hide yes)
			(effects
				(font
					(size 1.27 1.27)
				)
				(justify mirror)
			)
		)
		(property "Value" ""
			(at 0 0 0)
			(layer "B.Fab")
			(effects
				(font
					(size 1.27 1.27)
				)
				(justify mirror)
			)
		)
		(duplicate_pad_numbers_are_jumpers no)
		(fp_poly
			(pts
				(xy 0.7239 -0.2159) (xy -0.7239 -0.2159) (xy -0.7239 1.9939) (xy 0.7239 1.9939)
			)
			(stroke
				(width 0)
				(type default)
			)
			(fill no)
			(layer "B.CrtYd")
		)
		(fp_line
			(start 0.7239 1.9939)
			(end -0.7239 1.9939)
			(stroke
				(width 0.1)
				(type default)
			)
			(layer "B.Fab")
		)
		(fp_line
			(start 0.7239 -0.2159)
			(end 0.7239 1.9939)
			(stroke
				(width 0.1)
				(type default)
			)
			(layer "B.Fab")
		)
		(fp_line
			(start -0.7239 1.9939)
			(end -0.7239 -0.2159)
			(stroke
				(width 0.1)
				(type default)
			)
			(layer "B.Fab")
		)
		(fp_line
			(start -0.7239 -0.2159)
			(end 0.7239 -0.2159)
			(stroke
				(width 0.1)
				(type default)
			)
			(layer "B.Fab")
		)
		(pad "1" smd rect
			(at 0 0)
			(size 1.27 1.016)
			(layers "B.Cu" "B.Mask" "B.Paste")
			(net "VR_FET_SW_P12V_STBY_PVPP_ABC")
		)
		(pad "2" smd rect
			(at 0 1.778)
			(size 1.27 1.016)
			(layers "B.Cu" "B.Mask" "B.Paste")
			(net "GND")
		)
		(zone
			(layer "B.Cu")
			(hatch none 0.5)
			(connect_pads
				(clearance 0)
			)
			(min_thickness 0.25)
			(keepout
				(tracks not_allowed)
				(vias allowed)
				(pads allowed)
				(copperpour not_allowed)
				(footprints allowed)
			)
			(placement
				(enabled no)
				(sheetname "")
			)
			(fill
				(thermal_gap 0.5)
				(thermal_bridge_width 0.5)
				(island_removal_mode 0)
			)
			(polygon
				(pts
					(xy 350.393 -29.083) (xy 351.663 -29.083) (xy 351.663 -29.845) (xy 350.393 -29.845)
				)
			)
		)
	)
	(footprint ""
		(layer "B.Cu")
		(at 183.625998 -5.321808)
		(property "Reference" "R6U4"
			(at 0 0 0)
			(layer "B.SilkS")
			(hide yes)
			(effects
				(font
					(size 1.27 1.27)
				)
				(justify mirror)
			)
		)
		(property "Value" ""
			(at 0 0 0)
			(layer "B.Fab")
			(effects
				(font
					(size 1.27 1.27)
				)
				(justify mirror)
			)
		)
		(duplicate_pad_numbers_are_jumpers no)
		(fp_rect
			(start -0.2794 0.9906)
			(end 0.2794 -0.1016)
			(stroke
				(width 0)
				(type default)
			)
			(fill no)
			(layer "B.CrtYd")
		)
		(fp_line
			(start -0.2794 -0.1016)
			(end 0.2794 -0.1016)
			(stroke
				(width 0.1)
				(type default)
			)
			(layer "B.Fab")
		)
		(fp_line
			(start -0.2794 0.9906)
			(end -0.2794 -0.1016)
			(stroke
				(width 0.1)
				(type default)
			)
			(layer "B.Fab")
		)
		(fp_line
			(start 0.2794 -0.1016)
			(end 0.2794 0.9906)
			(stroke
				(width 0.1)
				(type default)
			)
			(layer "B.Fab")
		)
		(fp_line
			(start 0.2794 0.9906)
			(end -0.2794 0.9906)
			(stroke
				(width 0.1)
				(type default)
			)
			(layer "B.Fab")
		)
		(pad "1" smd rect
			(at 0 0 180)
			(size 0.508 0.508)
			(layers "B.Cu" "B.Mask" "B.Paste")
			(net "P3V3")
		)
		(pad "2" smd rect
			(at 0 0.889 180)
			(size 0.508 0.508)
			(layers "B.Cu" "B.Mask" "B.Paste")
			(net "VR_PVTT_ABC_BIAS")
		)
		(zone
			(layer "B.Cu")
			(hatch none 0.5)
			(connect_pads
				(clearance 0)
			)
			(min_thickness 0.25)
			(keepout
				(tracks allowed)
				(vias not_allowed)
				(pads allowed)
				(copperpour not_allowed)
				(footprints allowed)
			)
			(placement
				(enabled no)
				(sheetname "")
			)
			(fill
				(thermal_gap 0.5)
				(thermal_bridge_width 0.5)
				(island_removal_mode 0)
			)
			(polygon
				(pts
					(xy 183.371998 -4.686808) (xy 183.879998 -4.686808) (xy 183.879998 -5.067808) (xy 183.371998 -5.067808)
				)
			)
		)
	)
	(footprint ""
		(layer "B.Cu")
		(at 264.035286 -77.82814)
		(property "Reference" "C5P24"
			(at 0 0 0)
			(layer "B.SilkS")
			(hide yes)
			(effects
				(font
					(size 1.27 1.27)
				)
				(justify mirror)
			)
		)
		(property "Value" ""
			(at 0 0 0)
			(layer "B.Fab")
			(effects
				(font
					(size 1.27 1.27)
				)
				(justify mirror)
			)
		)
		(duplicate_pad_numbers_are_jumpers no)
		(fp_poly
			(pts
				(xy 0.7239 -0.2159) (xy -0.7239 -0.2159) (xy -0.7239 1.9939) (xy 0.7239 1.9939)
			)
			(stroke
				(width 0)
				(type default)
			)
			(fill no)
			(layer "B.CrtYd")
		)
		(fp_line
			(start -0.7239 -0.2159)
			(end 0.7239 -0.2159)
			(stroke
				(width 0.1)
				(type default)
			)
			(layer "B.Fab")
		)
		(fp_line
			(start -0.7239 1.9939)
			(end -0.7239 -0.2159)
			(stroke
				(width 0.1)
				(type default)
			)
			(layer "B.Fab")
		)
		(fp_line
			(start 0.7239 -0.2159)
			(end 0.7239 1.9939)
			(stroke
				(width 0.1)
				(type default)
			)
			(layer "B.Fab")
		)
		(fp_line
			(start 0.7239 1.9939)
			(end -0.7239 1.9939)
			(stroke
				(width 0.1)
				(type default)
			)
			(layer "B.Fab")
		)
		(pad "1" smd rect
			(at 0 0 180)
			(size 1.27 1.016)
			(layers "B.Cu" "B.Mask" "B.Paste")
			(net "PVCCIN_CPU0")
		)
		(pad "2" smd rect
			(at 0 1.778 180)
			(size 1.27 1.016)
			(layers "B.Cu" "B.Mask" "B.Paste")
			(net "GND")
		)
		(zone
			(layer "B.Cu")
			(hatch none 0.5)
			(connect_pads
				(clearance 0)
			)
			(min_thickness 0.25)
			(keepout
				(tracks not_allowed)
				(vias allowed)
				(pads allowed)
				(copperpour not_allowed)
				(footprints allowed)
			)
			(placement
				(enabled no)
				(sheetname "")
			)
			(fill
				(thermal_gap 0.5)
				(thermal_bridge_width 0.5)
				(island_removal_mode 0)
			)
			(polygon
				(pts
					(xy 264.670286 -77.32014) (xy 263.400286 -77.32014) (xy 263.400286 -76.55814) (xy 264.670286 -76.55814)
				)
			)
		)
	)
	(footprint ""
		(layer "B.Cu")
		(at 437.690006 -41.648126 180)
		(property "Reference" "R25W13"
			(at 0 0 0)
			(layer "B.SilkS")
			(hide yes)
			(effects
				(font
					(size 1.27 1.27)
				)
				(justify mirror)
			)
		)
		(property "Value" "*"
			(at -0.064008 -4.108196 180)
			(unlocked yes)
			(layer "B.Fab")
			(hide yes)
			(effects
				(font
					(size 1.27 1.016)
					(thickness 0.1524)
				)
				(justify mirror)
			)
		)
		(property "Device Type" "120R2F-GP_RCL_GP-120R2F-GP,64.A"
			(at -0.064008 -5.632196 180)
			(unlocked yes)
			(layer "B.Fab")
			(hide yes)
			(effects
				(font
					(size 1.27 1.016)
					(thickness 0.1524)
				)
				(justify mirror)
			)
		)
		(duplicate_pad_numbers_are_jumpers no)
		(fp_line
			(start 0.508 -0.9398)
			(end 0.508 0.9398)
			(stroke
				(width 0.1524)
				(type default)
			)
			(layer "B.SilkS")
		)
		(fp_line
			(start -0.508 -0.9398)
			(end 0.508 -0.9398)
			(stroke
				(width 0.1524)
				(type default)
			)
			(layer "B.SilkS")
		)
		(fp_rect
			(start 0.508 0.9398)
			(end -0.508 -0.9398)
			(stroke
				(width 0)
				(type default)
			)
			(fill no)
			(layer "B.CrtYd")
		)
		(fp_rect
			(start 0.508 0.9398)
			(end -0.508 -0.9398)
			(stroke
				(width 0)
				(type default)
			)
			(fill no)
			(layer "B.Fab")
		)
		(pad "1" smd custom
			(at 0 -0.4445)
			(size 0.1397 0.1397)
			(layers "B.Cu" "B.Mask" "B.Paste")
			(net "GND")
			(options
				(clearance outline)
				(anchor circle)
			)
			(primitives
				(gr_poly
					(pts
						(arc
							(start -0.1778 0.2794)
							(mid -0.249642 0.249642)
							(end -0.2794 0.1778)
						)
						(arc
							(start -0.2794 -0.1778)
							(mid -0.249642 -0.249642)
							(end -0.1778 -0.2794)
						)
						(arc
							(start 0.1778 -0.2794)
							(mid 0.249642 -0.249642)
							(end 0.2794 -0.1778)
						)
						(arc
							(start 0.2794 0.1778)
							(mid 0.249642 0.249642)
							(end 0.1778 0.2794)
						)
					)
					(width 0)
					(fill yes)
				)
			)
		)
		(pad "2" smd custom
			(at 0 0.4445)
			(size 0.1397 0.1397)
			(layers "B.Cu" "B.Mask" "B.Paste")
			(net "BMC_M_A1")
			(options
				(clearance outline)
				(anchor circle)
			)
			(primitives
				(gr_poly
					(pts
						(arc
							(start -0.1778 0.2794)
							(mid -0.249642 0.249642)
							(end -0.2794 0.1778)
						)
						(arc
							(start -0.2794 -0.1778)
							(mid -0.249642 -0.249642)
							(end -0.1778 -0.2794)
						)
						(arc
							(start 0.1778 -0.2794)
							(mid 0.249642 -0.249642)
							(end 0.2794 -0.1778)
						)
						(arc
							(start 0.2794 0.1778)
							(mid 0.249642 0.249642)
							(end 0.1778 0.2794)
						)
					)
					(width 0)
					(fill yes)
				)
			)
		)
	)
	(footprint ""
		(layer "B.Cu")
		(at 106.350054 -73.51014)
		(property "Reference" "C8P22"
			(at 0 0 0)
			(layer "B.SilkS")
			(hide yes)
			(effects
				(font
					(size 1.27 1.27)
				)
				(justify mirror)
			)
		)
		(property "Value" ""
			(at 0 0 0)
			(layer "B.Fab")
			(effects
				(font
					(size 1.27 1.27)
				)
				(justify mirror)
			)
		)
		(duplicate_pad_numbers_are_jumpers no)
		(fp_poly
			(pts
				(xy 0.7239 -0.2159) (xy -0.7239 -0.2159) (xy -0.7239 1.9939) (xy 0.7239 1.9939)
			)
			(stroke
				(width 0)
				(type default)
			)
			(fill no)
			(layer "B.CrtYd")
		)
		(fp_line
			(start -0.7239 -0.2159)
			(end 0.7239 -0.2159)
			(stroke
				(width 0.1)
				(type default)
			)
			(layer "B.Fab")
		)
		(fp_line
			(start -0.7239 1.9939)
			(end -0.7239 -0.2159)
			(stroke
				(width 0.1)
				(type default)
			)
			(layer "B.Fab")
		)
		(fp_line
			(start 0.7239 -0.2159)
			(end 0.7239 1.9939)
			(stroke
				(width 0.1)
				(type default)
			)
			(layer "B.Fab")
		)
		(fp_line
			(start 0.7239 1.9939)
			(end -0.7239 1.9939)
			(stroke
				(width 0.1)
				(type default)
			)
			(layer "B.Fab")
		)
		(pad "1" smd rect
			(at 0 0 180)
			(size 1.27 1.016)
			(layers "B.Cu" "B.Mask" "B.Paste")
			(net "PVCCMCP_CPU1")
		)
		(pad "2" smd rect
			(at 0 1.778 180)
			(size 1.27 1.016)
			(layers "B.Cu" "B.Mask" "B.Paste")
			(net "GND")
		)
		(zone
			(layer "B.Cu")
			(hatch none 0.5)
			(connect_pads
				(clearance 0)
			)
			(min_thickness 0.25)
			(keepout
				(tracks not_allowed)
				(vias allowed)
				(pads allowed)
				(copperpour not_allowed)
				(footprints allowed)
			)
			(placement
				(enabled no)
				(sheetname "")
			)
			(fill
				(thermal_gap 0.5)
				(thermal_bridge_width 0.5)
				(island_removal_mode 0)
			)
			(polygon
				(pts
					(xy 106.985054 -73.00214) (xy 105.715054 -73.00214) (xy 105.715054 -72.24014) (xy 106.985054 -72.24014)
				)
			)
		)
	)
	(footprint ""
		(layer "B.Cu")
		(at 463.690208 -145.415254)
		(property "Reference" "C1L8"
			(at 0 0 0)
			(layer "B.SilkS")
			(hide yes)
			(effects
				(font
					(size 1.27 1.27)
				)
				(justify mirror)
			)
		)
		(property "Value" ""
			(at 0 0 0)
			(layer "B.Fab")
			(effects
				(font
					(size 1.27 1.27)
				)
				(justify mirror)
			)
		)
		(duplicate_pad_numbers_are_jumpers no)
		(fp_poly
			(pts
				(xy -0.3048 -0.1016) (xy -0.3048 0.9906) (xy 0.3048 0.9906) (xy 0.3048 -0.1016)
			)
			(stroke
				(width 0)
				(type default)
			)
			(fill no)
			(layer "B.CrtYd")
		)
		(fp_line
			(start -0.3048 -0.1016)
			(end 0.3048 -0.1016)
			(stroke
				(width 0.1)
				(type default)
			)
			(layer "B.Fab")
		)
		(fp_line
			(start -0.3048 0.9906)
			(end -0.3048 -0.1016)
			(stroke
				(width 0.1)
				(type default)
			)
			(layer "B.Fab")
		)
		(fp_line
			(start 0.3048 -0.1016)
			(end 0.3048 0.9906)
			(stroke
				(width 0.1)
				(type default)
			)
			(layer "B.Fab")
		)
		(fp_line
			(start 0.3048 0.9906)
			(end -0.3048 0.9906)
			(stroke
				(width 0.1)
				(type default)
			)
			(layer "B.Fab")
		)
		(pad "1" smd rect
			(at 0 0 180)
			(size 0.508 0.508)
			(layers "B.Cu" "B.Mask" "B.Paste")
			(net "XDP_PWRGD_RST_N")
		)
		(pad "2" smd rect
			(at 0 0.889 180)
			(size 0.508 0.508)
			(layers "B.Cu" "B.Mask" "B.Paste")
			(net "GND")
		)
		(zone
			(layer "B.Cu")
			(hatch none 0.5)
			(connect_pads
				(clearance 0)
			)
			(min_thickness 0.25)
			(keepout
				(tracks allowed)
				(vias not_allowed)
				(pads allowed)
				(copperpour not_allowed)
				(footprints allowed)
			)
			(placement
				(enabled no)
				(sheetname "")
			)
			(fill
				(thermal_gap 0.5)
				(thermal_bridge_width 0.5)
				(island_removal_mode 0)
			)
			(polygon
				(pts
					(xy 463.944208 -145.161254) (xy 463.436208 -145.161254) (xy 463.436208 -144.780254) (xy 463.944208 -144.780254)
				)
			)
		)
		(zone
			(layer "B.Cu")
			(hatch none 0.5)
			(connect_pads
				(clearance 0)
			)
			(min_thickness 0.25)
			(keepout
				(tracks not_allowed)
				(vias allowed)
				(pads allowed)
				(copperpour not_allowed)
				(footprints allowed)
			)
			(placement
				(enabled no)
				(sheetname "")
			)
			(fill
				(thermal_gap 0.5)
				(thermal_bridge_width 0.5)
				(island_removal_mode 0)
			)
			(polygon
				(pts
					(xy 463.944208 -144.780254) (xy 463.436208 -144.780254) (xy 463.436208 -145.161254) (xy 463.944208 -145.161254)
				)
			)
		)
	)
	(footprint ""
		(layer "B.Cu")
		(at 479.8695 -33.147 -90)
		(property "Reference" "C2T34"
			(at 0 0 90)
			(layer "B.SilkS")
			(hide yes)
			(effects
				(font
					(size 1.27 1.27)
				)
				(justify mirror)
			)
		)
		(property "Value" ""
			(at 0 0 90)
			(layer "B.Fab")
			(effects
				(font
					(size 1.27 1.27)
				)
				(justify mirror)
			)
		)
		(duplicate_pad_numbers_are_jumpers no)
		(fp_poly
			(pts
				(xy -0.3048 -0.1016) (xy -0.3048 0.9906) (xy 0.3048 0.9906) (xy 0.3048 -0.1016)
			)
			(stroke
				(width 0)
				(type default)
			)
			(fill no)
			(layer "B.CrtYd")
		)
		(fp_line
			(start -0.3048 0.9906)
			(end -0.3048 -0.1016)
			(stroke
				(width 0.1)
				(type default)
			)
			(layer "B.Fab")
		)
		(fp_line
			(start 0.3048 0.9906)
			(end -0.3048 0.9906)
			(stroke
				(width 0.1)
				(type default)
			)
			(layer "B.Fab")
		)
		(fp_line
			(start -0.3048 -0.1016)
			(end 0.3048 -0.1016)
			(stroke
				(width 0.1)
				(type default)
			)
			(layer "B.Fab")
		)
		(fp_line
			(start 0.3048 -0.1016)
			(end 0.3048 0.9906)
			(stroke
				(width 0.1)
				(type default)
			)
			(layer "B.Fab")
		)
		(pad "1" smd rect
			(at 0 0 90)
			(size 0.508 0.508)
			(layers "B.Cu" "B.Mask" "B.Paste")
			(net "P3V3_STBY_MNG")
		)
		(pad "2" smd rect
			(at 0 0.889 90)
			(size 0.508 0.508)
			(layers "B.Cu" "B.Mask" "B.Paste")
			(net "GND")
		)
		(zone
			(layer "B.Cu")
			(hatch none 0.5)
			(connect_pads
				(clearance 0)
			)
			(min_thickness 0.25)
			(keepout
				(tracks not_allowed)
				(vias allowed)
				(pads allowed)
				(copperpour not_allowed)
				(footprints allowed)
			)
			(placement
				(enabled no)
				(sheetname "")
			)
			(fill
				(thermal_gap 0.5)
				(thermal_bridge_width 0.5)
				(island_removal_mode 0)
			)
			(polygon
				(pts
					(xy 479.2345 -32.893) (xy 479.2345 -33.401) (xy 479.6155 -33.401) (xy 479.6155 -32.893)
				)
			)
		)
		(zone
			(layer "B.Cu")
			(hatch none 0.5)
			(connect_pads
				(clearance 0)
			)
			(min_thickness 0.25)
			(keepout
				(tracks allowed)
				(vias not_allowed)
				(pads allowed)
				(copperpour not_allowed)
				(footprints allowed)
			)
			(placement
				(enabled no)
				(sheetname "")
			)
			(fill
				(thermal_gap 0.5)
				(thermal_bridge_width 0.5)
				(island_removal_mode 0)
			)
			(polygon
				(pts
					(xy 479.6155 -32.893) (xy 479.6155 -33.401) (xy 479.2345 -33.401) (xy 479.2345 -32.893)
				)
			)
		)
	)
	(footprint ""
		(layer "B.Cu")
		(at 452.857362 -17.749266 -90)
		(property "Reference" "C8W1"
			(at 0 0 90)
			(layer "B.SilkS")
			(hide yes)
			(effects
				(font
					(size 1.27 1.27)
				)
				(justify mirror)
			)
		)
		(property "Value" "*"
			(at 0 -2.9337 270)
			(unlocked yes)
			(layer "B.Fab")
			(hide yes)
			(effects
				(font
					(size 1.27 1.016)
					(thickness 0.1524)
				)
				(justify mirror)
			)
		)
		(property "Device Type" "SC1U16V3KX-2GP_SMD-BCG-SC1U16VA"
			(at 0 -4.4577 270)
			(unlocked yes)
			(layer "B.Fab")
			(hide yes)
			(effects
				(font
					(size 1.27 1.016)
					(thickness 0.1524)
				)
				(justify mirror)
			)
		)
		(duplicate_pad_numbers_are_jumpers no)
		(fp_line
			(start -0.508 0)
			(end 0.508 0)
			(stroke
				(width 0.2032)
				(type default)
			)
			(layer "B.SilkS")
		)
		(fp_rect
			(start 0.5842 1.3335)
			(end -0.5842 -1.3335)
			(stroke
				(width 0)
				(type default)
			)
			(fill no)
			(layer "B.CrtYd")
		)
		(fp_rect
			(start 0.5842 1.3335)
			(end -0.5842 -1.3335)
			(stroke
				(width 0)
				(type default)
			)
			(fill no)
			(layer "B.Fab")
		)
		(pad "1" smd custom
			(at 0 -0.762 90)
			(size 0.2159 0.2159)
			(layers "B.Cu" "B.Mask" "B.Paste")
			(net "BMC_SELF_HW_D_RST")
			(options
				(clearance outline)
				(anchor circle)
			)
			(primitives
				(gr_poly
					(pts
						(arc
							(start -0.3302 0.4318)
							(mid -0.402042 0.402042)
							(end -0.4318 0.3302)
						)
						(arc
							(start -0.4318 -0.3302)
							(mid -0.402042 -0.402042)
							(end -0.3302 -0.4318)
						)
						(arc
							(start 0.3302 -0.4318)
							(mid 0.402042 -0.402042)
							(end 0.4318 -0.3302)
						)
						(arc
							(start 0.4318 0.3302)
							(mid 0.402042 0.402042)
							(end 0.3302 0.4318)
						)
					)
					(width 0)
					(fill yes)
				)
			)
		)
		(pad "2" smd custom
			(at 0 0.762 90)
			(size 0.2159 0.2159)
			(layers "B.Cu" "B.Mask" "B.Paste")
			(net "BMC_TPM_HW_C_RST")
			(options
				(clearance outline)
				(anchor circle)
			)
			(primitives
				(gr_poly
					(pts
						(arc
							(start -0.3302 0.4318)
							(mid -0.402042 0.402042)
							(end -0.4318 0.3302)
						)
						(arc
							(start -0.4318 -0.3302)
							(mid -0.402042 -0.402042)
							(end -0.3302 -0.4318)
						)
						(arc
							(start 0.3302 -0.4318)
							(mid 0.402042 -0.402042)
							(end 0.4318 -0.3302)
						)
						(arc
							(start 0.4318 0.3302)
							(mid 0.402042 0.402042)
							(end 0.3302 0.4318)
						)
					)
					(width 0)
					(fill yes)
				)
			)
		)
	)
	(footprint ""
		(layer "B.Cu")
		(at 419.481 -73.1901 180)
		(property "Reference" "R1R5"
			(at 0 0 0)
			(layer "B.SilkS")
			(hide yes)
			(effects
				(font
					(size 1.27 1.27)
				)
				(justify mirror)
			)
		)
		(property "Value" ""
			(at 0 0 0)
			(layer "B.Fab")
			(effects
				(font
					(size 1.27 1.27)
				)
				(justify mirror)
			)
		)
		(duplicate_pad_numbers_are_jumpers no)
		(fp_poly
			(pts
				(xy 0.2794 -0.1016) (xy -0.2794 -0.1016) (xy -0.2794 0.9906) (xy 0.2794 0.9906)
			)
			(stroke
				(width 0)
				(type default)
			)
			(fill no)
			(layer "B.CrtYd")
		)
		(fp_line
			(start 0.2794 0.9906)
			(end -0.2794 0.9906)
			(stroke
				(width 0.1)
				(type default)
			)
			(layer "B.Fab")
		)
		(fp_line
			(start 0.2794 -0.1016)
			(end 0.2794 0.9906)
			(stroke
				(width 0.1)
				(type default)
			)
			(layer "B.Fab")
		)
		(fp_line
			(start -0.2794 0.9906)
			(end -0.2794 -0.1016)
			(stroke
				(width 0.1)
				(type default)
			)
			(layer "B.Fab")
		)
		(fp_line
			(start -0.2794 -0.1016)
			(end 0.2794 -0.1016)
			(stroke
				(width 0.1)
				(type default)
			)
			(layer "B.Fab")
		)
		(pad "1" smd rect
			(at 0 0)
			(size 0.508 0.508)
			(layers "B.Cu" "B.Mask" "B.Paste")
			(net "P3V3_STBY")
		)
		(pad "2" smd rect
			(at 0 0.889)
			(size 0.508 0.508)
			(layers "B.Cu" "B.Mask" "B.Paste")
			(net "FM_FAST_PROCHOT_THROTTLE_DLY_BU")
		)
		(zone
			(layer "B.Cu")
			(hatch none 0.5)
			(connect_pads
				(clearance 0)
			)
			(min_thickness 0.25)
			(keepout
				(tracks not_allowed)
				(vias allowed)
				(pads allowed)
				(copperpour not_allowed)
				(footprints allowed)
			)
			(placement
				(enabled no)
				(sheetname "")
			)
			(fill
				(thermal_gap 0.5)
				(thermal_bridge_width 0.5)
				(island_removal_mode 0)
			)
			(polygon
				(pts
					(xy 419.227 -73.8251) (xy 419.735 -73.8251) (xy 419.735 -73.4441) (xy 419.227 -73.4441)
				)
			)
		)
		(zone
			(layer "B.Cu")
			(hatch none 0.5)
			(connect_pads
				(clearance 0)
			)
			(min_thickness 0.25)
			(keepout
				(tracks allowed)
				(vias not_allowed)
				(pads allowed)
				(copperpour not_allowed)
				(footprints allowed)
			)
			(placement
				(enabled no)
				(sheetname "")
			)
			(fill
				(thermal_gap 0.5)
				(thermal_bridge_width 0.5)
				(island_removal_mode 0)
			)
			(polygon
				(pts
					(xy 419.227 -73.4441) (xy 419.735 -73.4441) (xy 419.735 -73.8251) (xy 419.227 -73.8251)
				)
			)
		)
	)
	(footprint ""
		(layer "B.Cu")
		(at 155.293568 -144.977612 90)
		(property "Reference" "C7L6"
			(at 0 0 90)
			(layer "B.SilkS")
			(hide yes)
			(effects
				(font
					(size 1.27 1.27)
				)
				(justify mirror)
			)
		)
		(property "Value" ""
			(at 0 0 90)
			(layer "B.Fab")
			(effects
				(font
					(size 1.27 1.27)
				)
				(justify mirror)
			)
		)
		(duplicate_pad_numbers_are_jumpers no)
		(fp_rect
			(start 0.4953 1.6002)
			(end -0.4953 -0.2032)
			(stroke
				(width 0)
				(type default)
			)
			(fill no)
			(layer "B.CrtYd")
		)
		(fp_line
			(start 0.4953 -0.2032)
			(end -0.4953 -0.2032)
			(stroke
				(width 0.1)
				(type default)
			)
			(layer "B.Fab")
		)
		(fp_line
			(start -0.4953 -0.2032)
			(end -0.4953 1.6002)
			(stroke
				(width 0.1)
				(type default)
			)
			(layer "B.Fab")
		)
		(fp_line
			(start 0.4953 1.6002)
			(end 0.4953 -0.2032)
			(stroke
				(width 0.1)
				(type default)
			)
			(layer "B.Fab")
		)
		(fp_line
			(start -0.4953 1.6002)
			(end 0.4953 1.6002)
			(stroke
				(width 0.1)
				(type default)
			)
			(layer "B.Fab")
		)
		(pad "1" smd rect
			(at 0 0 270)
			(size 0.762 0.889)
			(layers "B.Cu" "B.Mask" "B.Paste")
			(net "PVPP_KLM")
		)
		(pad "2" smd rect
			(at 0 1.397 270)
			(size 0.762 0.889)
			(layers "B.Cu" "B.Mask" "B.Paste")
			(net "GND")
		)
		(zone
			(layer "B.Cu")
			(hatch none 0.5)
			(connect_pads
				(clearance 0)
			)
			(min_thickness 0.25)
			(keepout
				(tracks not_allowed)
				(vias allowed)
				(pads allowed)
				(copperpour not_allowed)
				(footprints allowed)
			)
			(placement
				(enabled no)
				(sheetname "")
			)
			(fill
				(thermal_gap 0.5)
				(thermal_bridge_width 0.5)
				(island_removal_mode 0)
			)
			(polygon
				(pts
					(xy 156.246068 -145.358612) (xy 155.738068 -145.358612) (xy 155.738068 -144.596612) (xy 156.246068 -144.596612)
				)
			)
		)
	)
	(footprint ""
		(layer "B.Cu")
		(at 318.61506 -126.31674)
		(property "Reference" "R3R5"
			(at 0 0 0)
			(layer "B.SilkS")
			(hide yes)
			(effects
				(font
					(size 1.27 1.27)
				)
				(justify mirror)
			)
		)
		(property "Value" ""
			(at 0 0 0)
			(layer "B.Fab")
			(effects
				(font
					(size 1.27 1.27)
				)
				(justify mirror)
			)
		)
		(duplicate_pad_numbers_are_jumpers no)
		(fp_poly
			(pts
				(xy 0.2794 -0.1016) (xy -0.2794 -0.1016) (xy -0.2794 0.9906) (xy 0.2794 0.9906)
			)
			(stroke
				(width 0)
				(type default)
			)
			(fill no)
			(layer "B.CrtYd")
		)
		(fp_line
			(start -0.2794 -0.1016)
			(end 0.2794 -0.1016)
			(stroke
				(width 0.1)
				(type default)
			)
			(layer "B.Fab")
		)
		(fp_line
			(start -0.2794 0.9906)
			(end -0.2794 -0.1016)
			(stroke
				(width 0.1)
				(type default)
			)
			(layer "B.Fab")
		)
		(fp_line
			(start 0.2794 -0.1016)
			(end 0.2794 0.9906)
			(stroke
				(width 0.1)
				(type default)
			)
			(layer "B.Fab")
		)
		(fp_line
			(start 0.2794 0.9906)
			(end -0.2794 0.9906)
			(stroke
				(width 0.1)
				(type default)
			)
			(layer "B.Fab")
		)
		(pad "1" smd rect
			(at 0 0 180)
			(size 0.508 0.508)
			(layers "B.Cu" "B.Mask" "B.Paste")
			(net "PVPP_DEF")
		)
		(pad "2" smd rect
			(at 0 0.889 180)
			(size 0.508 0.508)
			(layers "B.Cu" "B.Mask" "B.Paste")
			(net "SMB_DDR_DEF_VPP_SCL_R")
		)
		(zone
			(layer "B.Cu")
			(hatch none 0.5)
			(connect_pads
				(clearance 0)
			)
			(min_thickness 0.25)
			(keepout
				(tracks allowed)
				(vias not_allowed)
				(pads allowed)
				(copperpour not_allowed)
				(footprints allowed)
			)
			(placement
				(enabled no)
				(sheetname "")
			)
			(fill
				(thermal_gap 0.5)
				(thermal_bridge_width 0.5)
				(island_removal_mode 0)
			)
			(polygon
				(pts
					(xy 318.86906 -126.06274) (xy 318.36106 -126.06274) (xy 318.36106 -125.68174) (xy 318.86906 -125.68174)
				)
			)
		)
		(zone
			(layer "B.Cu")
			(hatch none 0.5)
			(connect_pads
				(clearance 0)
			)
			(min_thickness 0.25)
			(keepout
				(tracks not_allowed)
				(vias allowed)
				(pads allowed)
				(copperpour not_allowed)
				(footprints allowed)
			)
			(placement
				(enabled no)
				(sheetname "")
			)
			(fill
				(thermal_gap 0.5)
				(thermal_bridge_width 0.5)
				(island_removal_mode 0)
			)
			(polygon
				(pts
					(xy 318.86906 -125.68174) (xy 318.36106 -125.68174) (xy 318.36106 -126.06274) (xy 318.86906 -126.06274)
				)
			)
		)
	)
	(footprint ""
		(layer "B.Cu")
		(at 337.1596 -85.70722)
		(property "Reference" "R3P54"
			(at 0 0 0)
			(layer "B.SilkS")
			(hide yes)
			(effects
				(font
					(size 1.27 1.27)
				)
				(justify mirror)
			)
		)
		(property "Value" ""
			(at 0 0 0)
			(layer "B.Fab")
			(effects
				(font
					(size 1.27 1.27)
				)
				(justify mirror)
			)
		)
		(duplicate_pad_numbers_are_jumpers no)
		(fp_poly
			(pts
				(xy 0.2794 -0.1016) (xy -0.2794 -0.1016) (xy -0.2794 0.9906) (xy 0.2794 0.9906)
			)
			(stroke
				(width 0)
				(type default)
			)
			(fill no)
			(layer "B.CrtYd")
		)
		(fp_line
			(start -0.2794 -0.1016)
			(end 0.2794 -0.1016)
			(stroke
				(width 0.1)
				(type default)
			)
			(layer "B.Fab")
		)
		(fp_line
			(start -0.2794 0.9906)
			(end -0.2794 -0.1016)
			(stroke
				(width 0.1)
				(type default)
			)
			(layer "B.Fab")
		)
		(fp_line
			(start 0.2794 -0.1016)
			(end 0.2794 0.9906)
			(stroke
				(width 0.1)
				(type default)
			)
			(layer "B.Fab")
		)
		(fp_line
			(start 0.2794 0.9906)
			(end -0.2794 0.9906)
			(stroke
				(width 0.1)
				(type default)
			)
			(layer "B.Fab")
		)
		(pad "1" smd rect
			(at 0 0 180)
			(size 0.508 0.508)
			(layers "B.Cu" "B.Mask" "B.Paste")
			(net "P3V3_STBY")
		)
		(pad "2" smd rect
			(at 0 0.889 180)
			(size 0.508 0.508)
			(layers "B.Cu" "B.Mask" "B.Paste")
			(net "FM_CPU0_SM_WP")
		)
		(zone
			(layer "B.Cu")
			(hatch none 0.5)
			(connect_pads
				(clearance 0)
			)
			(min_thickness 0.25)
			(keepout
				(tracks allowed)
				(vias not_allowed)
				(pads allowed)
				(copperpour not_allowed)
				(footprints allowed)
			)
			(placement
				(enabled no)
				(sheetname "")
			)
			(fill
				(thermal_gap 0.5)
				(thermal_bridge_width 0.5)
				(island_removal_mode 0)
			)
			(polygon
				(pts
					(xy 337.4136 -85.45322) (xy 336.9056 -85.45322) (xy 336.9056 -85.07222) (xy 337.4136 -85.07222)
				)
			)
		)
		(zone
			(layer "B.Cu")
			(hatch none 0.5)
			(connect_pads
				(clearance 0)
			)
			(min_thickness 0.25)
			(keepout
				(tracks not_allowed)
				(vias allowed)
				(pads allowed)
				(copperpour not_allowed)
				(footprints allowed)
			)
			(placement
				(enabled no)
				(sheetname "")
			)
			(fill
				(thermal_gap 0.5)
				(thermal_bridge_width 0.5)
				(island_removal_mode 0)
			)
			(polygon
				(pts
					(xy 337.4136 -85.07222) (xy 336.9056 -85.07222) (xy 336.9056 -85.45322) (xy 337.4136 -85.45322)
				)
			)
		)
	)
	(footprint ""
		(layer "B.Cu")
		(at 393.446 -27.686 -90)
		(property "Reference" "C8F16"
			(at 0 0 90)
			(layer "B.SilkS")
			(hide yes)
			(effects
				(font
					(size 1.27 1.27)
				)
				(justify mirror)
			)
		)
		(property "Value" ""
			(at 0 0 90)
			(layer "B.Fab")
			(effects
				(font
					(size 1.27 1.27)
				)
				(justify mirror)
			)
		)
		(duplicate_pad_numbers_are_jumpers no)
		(fp_poly
			(pts
				(xy -0.3048 -0.1016) (xy -0.3048 0.9906) (xy 0.3048 0.9906) (xy 0.3048 -0.1016)
			)
			(stroke
				(width 0)
				(type default)
			)
			(fill no)
			(layer "B.CrtYd")
		)
		(fp_line
			(start -0.3048 0.9906)
			(end -0.3048 -0.1016)
			(stroke
				(width 0.1)
				(type default)
			)
			(layer "B.Fab")
		)
		(fp_line
			(start 0.3048 0.9906)
			(end -0.3048 0.9906)
			(stroke
				(width 0.1)
				(type default)
			)
			(layer "B.Fab")
		)
		(fp_line
			(start -0.3048 -0.1016)
			(end 0.3048 -0.1016)
			(stroke
				(width 0.1)
				(type default)
			)
			(layer "B.Fab")
		)
		(fp_line
			(start 0.3048 -0.1016)
			(end 0.3048 0.9906)
			(stroke
				(width 0.1)
				(type default)
			)
			(layer "B.Fab")
		)
		(pad "1" smd rect
			(at 0 0 90)
			(size 0.508 0.508)
			(layers "B.Cu" "B.Mask" "B.Paste")
			(net "P3V3_STBY")
		)
		(pad "2" smd rect
			(at 0 0.889 90)
			(size 0.508 0.508)
			(layers "B.Cu" "B.Mask" "B.Paste")
			(net "GND")
		)
		(zone
			(layer "B.Cu")
			(hatch none 0.5)
			(connect_pads
				(clearance 0)
			)
			(min_thickness 0.25)
			(keepout
				(tracks not_allowed)
				(vias allowed)
				(pads allowed)
				(copperpour not_allowed)
				(footprints allowed)
			)
			(placement
				(enabled no)
				(sheetname "")
			)
			(fill
				(thermal_gap 0.5)
				(thermal_bridge_width 0.5)
				(island_removal_mode 0)
			)
			(polygon
				(pts
					(xy 392.811 -27.432) (xy 392.811 -27.94) (xy 393.192 -27.94) (xy 393.192 -27.432)
				)
			)
		)
		(zone
			(layer "B.Cu")
			(hatch none 0.5)
			(connect_pads
				(clearance 0)
			)
			(min_thickness 0.25)
			(keepout
				(tracks allowed)
				(vias not_allowed)
				(pads allowed)
				(copperpour not_allowed)
				(footprints allowed)
			)
			(placement
				(enabled no)
				(sheetname "")
			)
			(fill
				(thermal_gap 0.5)
				(thermal_bridge_width 0.5)
				(island_removal_mode 0)
			)
			(polygon
				(pts
					(xy 393.192 -27.432) (xy 393.192 -27.94) (xy 392.811 -27.94) (xy 392.811 -27.432)
				)
			)
		)
	)
	(footprint ""
		(layer "B.Cu")
		(at 391.075926 -36.564316 90)
		(property "Reference" "R8F36"
			(at 0 0 90)
			(layer "B.SilkS")
			(hide yes)
			(effects
				(font
					(size 1.27 1.27)
				)
				(justify mirror)
			)
		)
		(property "Value" ""
			(at 0 0 90)
			(layer "B.Fab")
			(effects
				(font
					(size 1.27 1.27)
				)
				(justify mirror)
			)
		)
		(duplicate_pad_numbers_are_jumpers no)
		(fp_poly
			(pts
				(xy 0.2794 -0.1016) (xy -0.2794 -0.1016) (xy -0.2794 0.9906) (xy 0.2794 0.9906)
			)
			(stroke
				(width 0)
				(type default)
			)
			(fill no)
			(layer "B.CrtYd")
		)
		(fp_line
			(start 0.2794 -0.1016)
			(end 0.2794 0.9906)
			(stroke
				(width 0.1)
				(type default)
			)
			(layer "B.Fab")
		)
		(fp_line
			(start -0.2794 -0.1016)
			(end 0.2794 -0.1016)
			(stroke
				(width 0.1)
				(type default)
			)
			(layer "B.Fab")
		)
		(fp_line
			(start 0.2794 0.9906)
			(end -0.2794 0.9906)
			(stroke
				(width 0.1)
				(type default)
			)
			(layer "B.Fab")
		)
		(fp_line
			(start -0.2794 0.9906)
			(end -0.2794 -0.1016)
			(stroke
				(width 0.1)
				(type default)
			)
			(layer "B.Fab")
		)
		(pad "1" smd rect
			(at 0 0 270)
			(size 0.508 0.508)
			(layers "B.Cu" "B.Mask" "B.Paste")
			(net "P3V3")
		)
		(pad "2" smd rect
			(at 0 0.889 270)
			(size 0.508 0.508)
			(layers "B.Cu" "B.Mask" "B.Paste")
			(net "PU_M2_CLK_REQ_N")
		)
		(zone
			(layer "B.Cu")
			(hatch none 0.5)
			(connect_pads
				(clearance 0)
			)
			(min_thickness 0.25)
			(keepout
				(tracks allowed)
				(vias not_allowed)
				(pads allowed)
				(copperpour not_allowed)
				(footprints allowed)
			)
			(placement
				(enabled no)
				(sheetname "")
			)
			(fill
				(thermal_gap 0.5)
				(thermal_bridge_width 0.5)
				(island_removal_mode 0)
			)
			(polygon
				(pts
					(xy 391.329926 -36.818316) (xy 391.329926 -36.310316) (xy 391.710926 -36.310316) (xy 391.710926 -36.818316)
				)
			)
		)
		(zone
			(layer "B.Cu")
			(hatch none 0.5)
			(connect_pads
				(clearance 0)
			)
			(min_thickness 0.25)
			(keepout
				(tracks not_allowed)
				(vias allowed)
				(pads allowed)
				(copperpour not_allowed)
				(footprints allowed)
			)
			(placement
				(enabled no)
				(sheetname "")
			)
			(fill
				(thermal_gap 0.5)
				(thermal_bridge_width 0.5)
				(island_removal_mode 0)
			)
			(polygon
				(pts
					(xy 391.710926 -36.818316) (xy 391.710926 -36.310316) (xy 391.329926 -36.310316) (xy 391.329926 -36.818316)
				)
			)
		)
	)
	(footprint ""
		(layer "B.Cu")
		(at 476.4786 -41.1734 -90)
		(property "Reference" "C22W35"
			(at 0 0 90)
			(layer "B.SilkS")
			(hide yes)
			(effects
				(font
					(size 1.27 1.27)
				)
				(justify mirror)
			)
		)
		(property "Value" "*"
			(at 0.0762 -6.2357 270)
			(unlocked yes)
			(layer "B.Fab")
			(hide yes)
			(effects
				(font
					(size 1.27 1.016)
					(thickness 0.1524)
				)
				(justify mirror)
			)
		)
		(property "Device Type" "SC22U16V5MX-4-GP_SMD-BCG5-SC22A"
			(at 0.0762 -8.2677 270)
			(unlocked yes)
			(layer "B.Fab")
			(hide yes)
			(effects
				(font
					(size 1.27 1.016)
					(thickness 0.1524)
				)
				(justify mirror)
			)
		)
		(duplicate_pad_numbers_are_jumpers no)
		(fp_line
			(start -0.635 0)
			(end 0.635 0)
			(stroke
				(width 0.508)
				(type default)
			)
			(layer "B.SilkS")
		)
		(fp_rect
			(start 0.9652 1.778)
			(end -0.9652 -1.778)
			(stroke
				(width 0)
				(type default)
			)
			(fill no)
			(layer "B.CrtYd")
		)
		(fp_poly
			(pts
				(xy 0.9652 -1.778) (xy -0.9652 -1.778) (xy -0.9652 1.778) (xy 0.9652 1.778)
			)
			(stroke
				(width 0)
				(type default)
			)
			(fill no)
			(layer "B.Fab")
		)
		(pad "1" smd rect
			(at 0 -0.9652 90)
			(size 1.397 1.143)
			(layers "B.Cu" "B.Mask" "B.Paste")
			(net "P1V5_LAN")
		)
		(pad "2" smd rect
			(at 0 0.9652 90)
			(size 1.397 1.143)
			(layers "B.Cu" "B.Mask" "B.Paste")
			(net "GND")
		)
	)
	(footprint ""
		(layer "B.Cu")
		(at 169.418 -125.603 90)
		(property "Reference" "R6M8"
			(at 0 0 90)
			(layer "B.SilkS")
			(hide yes)
			(effects
				(font
					(size 1.27 1.27)
				)
				(justify mirror)
			)
		)
		(property "Value" ""
			(at 0 0 90)
			(layer "B.Fab")
			(effects
				(font
					(size 1.27 1.27)
				)
				(justify mirror)
			)
		)
		(duplicate_pad_numbers_are_jumpers no)
		(fp_rect
			(start -0.2794 0.9906)
			(end 0.2794 -0.1016)
			(stroke
				(width 0)
				(type default)
			)
			(fill no)
			(layer "B.CrtYd")
		)
		(fp_line
			(start 0.2794 -0.1016)
			(end 0.2794 0.9906)
			(stroke
				(width 0.1)
				(type default)
			)
			(layer "B.Fab")
		)
		(fp_line
			(start -0.2794 -0.1016)
			(end 0.2794 -0.1016)
			(stroke
				(width 0.1)
				(type default)
			)
			(layer "B.Fab")
		)
		(fp_line
			(start 0.2794 0.9906)
			(end -0.2794 0.9906)
			(stroke
				(width 0.1)
				(type default)
			)
			(layer "B.Fab")
		)
		(fp_line
			(start -0.2794 0.9906)
			(end -0.2794 -0.1016)
			(stroke
				(width 0.1)
				(type default)
			)
			(layer "B.Fab")
		)
		(pad "1" smd rect
			(at 0 0 270)
			(size 0.508 0.508)
			(layers "B.Cu" "B.Mask" "B.Paste")
			(net "JTAG_MCP_CPU1_TDI_R")
		)
		(pad "2" smd rect
			(at 0 0.889 270)
			(size 0.508 0.508)
			(layers "B.Cu" "B.Mask" "B.Paste")
			(net "JTAG_MCP_CPU1_TDI")
		)
		(zone
			(layer "B.Cu")
			(hatch none 0.5)
			(connect_pads
				(clearance 0)
			)
			(min_thickness 0.25)
			(keepout
				(tracks allowed)
				(vias not_allowed)
				(pads allowed)
				(copperpour not_allowed)
				(footprints allowed)
			)
			(placement
				(enabled no)
				(sheetname "")
			)
			(fill
				(thermal_gap 0.5)
				(thermal_bridge_width 0.5)
				(island_removal_mode 0)
			)
			(polygon
				(pts
					(xy 170.053 -125.349) (xy 170.053 -125.857) (xy 169.672 -125.857) (xy 169.672 -125.349)
				)
			)
		)
		(zone
			(layer "B.Cu")
			(hatch none 0.5)
			(connect_pads
				(clearance 0)
			)
			(min_thickness 0.25)
			(keepout
				(tracks not_allowed)
				(vias allowed)
				(pads allowed)
				(copperpour not_allowed)
				(footprints allowed)
			)
			(placement
				(enabled no)
				(sheetname "")
			)
			(fill
				(thermal_gap 0.5)
				(thermal_bridge_width 0.5)
				(island_removal_mode 0)
			)
			(polygon
				(pts
					(xy 170.053 -125.349) (xy 170.053 -125.857) (xy 169.672 -125.857) (xy 169.672 -125.349)
				)
			)
		)
	)
	(footprint ""
		(layer "B.Cu")
		(at 193.092832 -17.723612 -90)
		(property "Reference" "C6T2"
			(at 0 0 90)
			(layer "B.SilkS")
			(hide yes)
			(effects
				(font
					(size 1.27 1.27)
				)
				(justify mirror)
			)
		)
		(property "Value" ""
			(at 0 0 90)
			(layer "B.Fab")
			(effects
				(font
					(size 1.27 1.27)
				)
				(justify mirror)
			)
		)
		(duplicate_pad_numbers_are_jumpers no)
		(fp_rect
			(start 0.7239 1.9939)
			(end -0.7239 -0.2159)
			(stroke
				(width 0)
				(type default)
			)
			(fill no)
			(layer "B.CrtYd")
		)
		(fp_line
			(start -0.7239 1.9939)
			(end -0.7239 -0.2159)
			(stroke
				(width 0.1)
				(type default)
			)
			(layer "B.Fab")
		)
		(fp_line
			(start 0.7239 1.9939)
			(end -0.7239 1.9939)
			(stroke
				(width 0.1)
				(type default)
			)
			(layer "B.Fab")
		)
		(fp_line
			(start -0.7239 -0.2159)
			(end 0.7239 -0.2159)
			(stroke
				(width 0.1)
				(type default)
			)
			(layer "B.Fab")
		)
		(fp_line
			(start 0.7239 -0.2159)
			(end 0.7239 1.9939)
			(stroke
				(width 0.1)
				(type default)
			)
			(layer "B.Fab")
		)
		(pad "1" smd rect
			(at 0 0 90)
			(size 1.27 1.016)
			(layers "B.Cu" "B.Mask" "B.Paste")
			(net "P12V_NVDIMM_ABC")
		)
		(pad "2" smd rect
			(at 0 1.778 90)
			(size 1.27 1.016)
			(layers "B.Cu" "B.Mask" "B.Paste")
			(net "GND")
		)
		(zone
			(layer "B.Cu")
			(hatch none 0.5)
			(connect_pads
				(clearance 0)
			)
			(min_thickness 0.25)
			(keepout
				(tracks not_allowed)
				(vias allowed)
				(pads allowed)
				(copperpour not_allowed)
				(footprints allowed)
			)
			(placement
				(enabled no)
				(sheetname "")
			)
			(fill
				(thermal_gap 0.5)
				(thermal_bridge_width 0.5)
				(island_removal_mode 0)
			)
			(polygon
				(pts
					(xy 191.822832 -17.088612) (xy 192.584832 -17.088612) (xy 192.584832 -18.358612) (xy 191.822832 -18.358612)
				)
			)
		)
	)
	(footprint ""
		(layer "B.Cu")
		(at 94.638368 1.47574 90)
		(property "Reference" "C8U10"
			(at -1.47828 0.78994 180)
			(unlocked yes)
			(layer "B.SilkS")
			(effects
				(font
					(size 0.4064 0.254)
					(thickness 0.1524)
				)
				(justify mirror)
			)
		)
		(property "Value" ""
			(at 0 0 90)
			(layer "B.Fab")
			(effects
				(font
					(size 1.27 1.27)
				)
				(justify mirror)
			)
		)
		(duplicate_pad_numbers_are_jumpers no)
		(fp_poly
			(pts
				(xy 0.7239 -0.2159) (xy -0.7239 -0.2159) (xy -0.7239 1.9939) (xy 0.7239 1.9939)
			)
			(stroke
				(width 0)
				(type default)
			)
			(fill no)
			(layer "B.CrtYd")
		)
		(fp_line
			(start 0.7239 -0.2159)
			(end 0.7239 1.9939)
			(stroke
				(width 0.1)
				(type default)
			)
			(layer "B.Fab")
		)
		(fp_line
			(start -0.7239 -0.2159)
			(end 0.7239 -0.2159)
			(stroke
				(width 0.1)
				(type default)
			)
			(layer "B.Fab")
		)
		(fp_line
			(start 0.7239 1.9939)
			(end -0.7239 1.9939)
			(stroke
				(width 0.1)
				(type default)
			)
			(layer "B.Fab")
		)
		(fp_line
			(start -0.7239 1.9939)
			(end -0.7239 -0.2159)
			(stroke
				(width 0.1)
				(type default)
			)
			(layer "B.Fab")
		)
		(pad "1" smd rect
			(at 0 0 270)
			(size 1.27 1.016)
			(layers "B.Cu" "B.Mask" "B.Paste")
			(net "PVTT_GHJ")
		)
		(pad "2" smd rect
			(at 0 1.778 270)
			(size 1.27 1.016)
			(layers "B.Cu" "B.Mask" "B.Paste")
			(net "GND")
		)
		(zone
			(layer "B.Cu")
			(hatch none 0.5)
			(connect_pads
				(clearance 0)
			)
			(min_thickness 0.25)
			(keepout
				(tracks not_allowed)
				(vias allowed)
				(pads allowed)
				(copperpour not_allowed)
				(footprints allowed)
			)
			(placement
				(enabled no)
				(sheetname "")
			)
			(fill
				(thermal_gap 0.5)
				(thermal_bridge_width 0.5)
				(island_removal_mode 0)
			)
			(polygon
				(pts
					(xy 95.146368 0.84074) (xy 95.146368 2.11074) (xy 95.908368 2.11074) (xy 95.908368 0.84074)
				)
			)
		)
	)
	(footprint ""
		(layer "B.Cu")
		(at 351.507806 -61.257434)
		(property "Reference" "C2U16"
			(at 0 0 0)
			(layer "B.SilkS")
			(hide yes)
			(effects
				(font
					(size 1.27 1.27)
				)
				(justify mirror)
			)
		)
		(property "Value" ""
			(at 0 0 0)
			(layer "B.Fab")
			(effects
				(font
					(size 1.27 1.27)
				)
				(justify mirror)
			)
		)
		(duplicate_pad_numbers_are_jumpers no)
		(fp_poly
			(pts
				(xy -0.3048 -0.1016) (xy -0.3048 0.9906) (xy 0.3048 0.9906) (xy 0.3048 -0.1016)
			)
			(stroke
				(width 0)
				(type default)
			)
			(fill no)
			(layer "B.CrtYd")
		)
		(fp_line
			(start -0.3048 -0.1016)
			(end 0.3048 -0.1016)
			(stroke
				(width 0.1)
				(type default)
			)
			(layer "B.Fab")
		)
		(fp_line
			(start -0.3048 0.9906)
			(end -0.3048 -0.1016)
			(stroke
				(width 0.1)
				(type default)
			)
			(layer "B.Fab")
		)
		(fp_line
			(start 0.3048 -0.1016)
			(end 0.3048 0.9906)
			(stroke
				(width 0.1)
				(type default)
			)
			(layer "B.Fab")
		)
		(fp_line
			(start 0.3048 0.9906)
			(end -0.3048 0.9906)
			(stroke
				(width 0.1)
				(type default)
			)
			(layer "B.Fab")
		)
		(pad "1" smd rect
			(at 0 0 180)
			(size 0.508 0.508)
			(layers "B.Cu" "B.Mask" "B.Paste")
			(net "P3E_CPU0_PE1_PCH_RXN<6>")
		)
		(pad "2" smd rect
			(at 0 0.889 180)
			(size 0.508 0.508)
			(layers "B.Cu" "B.Mask" "B.Paste")
			(net "P3E_CPU0_PE1_SS_RXN<6>")
		)
		(zone
			(layer "B.Cu")
			(hatch none 0.5)
			(connect_pads
				(clearance 0)
			)
			(min_thickness 0.25)
			(keepout
				(tracks allowed)
				(vias not_allowed)
				(pads allowed)
				(copperpour not_allowed)
				(footprints allowed)
			)
			(placement
				(enabled no)
				(sheetname "")
			)
			(fill
				(thermal_gap 0.5)
				(thermal_bridge_width 0.5)
				(island_removal_mode 0)
			)
			(polygon
				(pts
					(xy 351.761806 -61.003434) (xy 351.253806 -61.003434) (xy 351.253806 -60.622434) (xy 351.761806 -60.622434)
				)
			)
		)
		(zone
			(layer "B.Cu")
			(hatch none 0.5)
			(connect_pads
				(clearance 0)
			)
			(min_thickness 0.25)
			(keepout
				(tracks not_allowed)
				(vias allowed)
				(pads allowed)
				(copperpour not_allowed)
				(footprints allowed)
			)
			(placement
				(enabled no)
				(sheetname "")
			)
			(fill
				(thermal_gap 0.5)
				(thermal_bridge_width 0.5)
				(island_removal_mode 0)
			)
			(polygon
				(pts
					(xy 351.761806 -60.622434) (xy 351.253806 -60.622434) (xy 351.253806 -61.003434) (xy 351.761806 -61.003434)
				)
			)
		)
	)
	(footprint ""
		(layer "B.Cu")
		(at 470.379044 -4.56692 -90)
		(property "Reference" "C2U24"
			(at 0 0 90)
			(layer "B.SilkS")
			(hide yes)
			(effects
				(font
					(size 1.27 1.27)
				)
				(justify mirror)
			)
		)
		(property "Value" ""
			(at 0 0 90)
			(layer "B.Fab")
			(effects
				(font
					(size 1.27 1.27)
				)
				(justify mirror)
			)
		)
		(duplicate_pad_numbers_are_jumpers no)
		(fp_poly
			(pts
				(xy -0.3048 -0.1016) (xy -0.3048 0.9906) (xy 0.3048 0.9906) (xy 0.3048 -0.1016)
			)
			(stroke
				(width 0)
				(type default)
			)
			(fill no)
			(layer "B.CrtYd")
		)
		(fp_line
			(start -0.3048 0.9906)
			(end -0.3048 -0.1016)
			(stroke
				(width 0.1)
				(type default)
			)
			(layer "B.Fab")
		)
		(fp_line
			(start 0.3048 0.9906)
			(end -0.3048 0.9906)
			(stroke
				(width 0.1)
				(type default)
			)
			(layer "B.Fab")
		)
		(fp_line
			(start -0.3048 -0.1016)
			(end 0.3048 -0.1016)
			(stroke
				(width 0.1)
				(type default)
			)
			(layer "B.Fab")
		)
		(fp_line
			(start 0.3048 -0.1016)
			(end 0.3048 0.9906)
			(stroke
				(width 0.1)
				(type default)
			)
			(layer "B.Fab")
		)
		(pad "1" smd rect
			(at 0 0 90)
			(size 0.508 0.508)
			(layers "B.Cu" "B.Mask" "B.Paste")
			(net "P12V")
		)
		(pad "2" smd rect
			(at 0 0.889 90)
			(size 0.508 0.508)
			(layers "B.Cu" "B.Mask" "B.Paste")
			(net "GND")
		)
		(zone
			(layer "B.Cu")
			(hatch none 0.5)
			(connect_pads
				(clearance 0)
			)
			(min_thickness 0.25)
			(keepout
				(tracks not_allowed)
				(vias allowed)
				(pads allowed)
				(copperpour not_allowed)
				(footprints allowed)
			)
			(placement
				(enabled no)
				(sheetname "")
			)
			(fill
				(thermal_gap 0.5)
				(thermal_bridge_width 0.5)
				(island_removal_mode 0)
			)
			(polygon
				(pts
					(xy 469.744044 -4.31292) (xy 469.744044 -4.82092) (xy 470.125044 -4.82092) (xy 470.125044 -4.31292)
				)
			)
		)
		(zone
			(layer "B.Cu")
			(hatch none 0.5)
			(connect_pads
				(clearance 0)
			)
			(min_thickness 0.25)
			(keepout
				(tracks allowed)
				(vias not_allowed)
				(pads allowed)
				(copperpour not_allowed)
				(footprints allowed)
			)
			(placement
				(enabled no)
				(sheetname "")
			)
			(fill
				(thermal_gap 0.5)
				(thermal_bridge_width 0.5)
				(island_removal_mode 0)
			)
			(polygon
				(pts
					(xy 470.125044 -4.31292) (xy 470.125044 -4.82092) (xy 469.744044 -4.82092) (xy 469.744044 -4.31292)
				)
			)
		)
	)
	(footprint ""
		(layer "B.Cu")
		(at 350.024192 -77.834236 180)
		(property "Reference" "C3P27"
			(at 0 0 0)
			(layer "B.SilkS")
			(hide yes)
			(effects
				(font
					(size 1.27 1.27)
				)
				(justify mirror)
			)
		)
		(property "Value" ""
			(at 0 0 0)
			(layer "B.Fab")
			(effects
				(font
					(size 1.27 1.27)
				)
				(justify mirror)
			)
		)
		(duplicate_pad_numbers_are_jumpers no)
		(fp_poly
			(pts
				(xy -0.3048 -0.1016) (xy -0.3048 0.9906) (xy 0.3048 0.9906) (xy 0.3048 -0.1016)
			)
			(stroke
				(width 0)
				(type default)
			)
			(fill no)
			(layer "B.CrtYd")
		)
		(fp_line
			(start 0.3048 0.9906)
			(end -0.3048 0.9906)
			(stroke
				(width 0.1)
				(type default)
			)
			(layer "B.Fab")
		)
		(fp_line
			(start 0.3048 -0.1016)
			(end 0.3048 0.9906)
			(stroke
				(width 0.1)
				(type default)
			)
			(layer "B.Fab")
		)
		(fp_line
			(start -0.3048 0.9906)
			(end -0.3048 -0.1016)
			(stroke
				(width 0.1)
				(type default)
			)
			(layer "B.Fab")
		)
		(fp_line
			(start -0.3048 -0.1016)
			(end 0.3048 -0.1016)
			(stroke
				(width 0.1)
				(type default)
			)
			(layer "B.Fab")
		)
		(pad "1" smd rect
			(at 0 0)
			(size 0.508 0.508)
			(layers "B.Cu" "B.Mask" "B.Paste")
			(net "P3E_CPU0_PE1_SS_TXP<4>")
		)
		(pad "2" smd rect
			(at 0 0.889)
			(size 0.508 0.508)
			(layers "B.Cu" "B.Mask" "B.Paste")
			(net "P3E_CPU0_PE1_PCH_TXP<4>")
		)
		(zone
			(layer "B.Cu")
			(hatch none 0.5)
			(connect_pads
				(clearance 0)
			)
			(min_thickness 0.25)
			(keepout
				(tracks not_allowed)
				(vias allowed)
				(pads allowed)
				(copperpour not_allowed)
				(footprints allowed)
			)
			(placement
				(enabled no)
				(sheetname "")
			)
			(fill
				(thermal_gap 0.5)
				(thermal_bridge_width 0.5)
				(island_removal_mode 0)
			)
			(polygon
				(pts
					(xy 349.770192 -78.469236) (xy 350.278192 -78.469236) (xy 350.278192 -78.088236) (xy 349.770192 -78.088236)
				)
			)
		)
		(zone
			(layer "B.Cu")
			(hatch none 0.5)
			(connect_pads
				(clearance 0)
			)
			(min_thickness 0.25)
			(keepout
				(tracks allowed)
				(vias not_allowed)
				(pads allowed)
				(copperpour not_allowed)
				(footprints allowed)
			)
			(placement
				(enabled no)
				(sheetname "")
			)
			(fill
				(thermal_gap 0.5)
				(thermal_bridge_width 0.5)
				(island_removal_mode 0)
			)
			(polygon
				(pts
					(xy 349.770192 -78.088236) (xy 350.278192 -78.088236) (xy 350.278192 -78.469236) (xy 349.770192 -78.469236)
				)
			)
		)
	)
	(footprint ""
		(layer "B.Cu")
		(at 396.06982 -139.69238 180)
		(property "Reference" "C2L46"
			(at -3.10007 3.24612 270)
			(unlocked yes)
			(layer "B.SilkS")
			(effects
				(font
					(size 0.7874 0.5842)
					(thickness 0.1524)
				)
				(justify mirror)
			)
		)
		(property "Value" ""
			(at 0 0 0)
			(layer "B.Fab")
			(effects
				(font
					(size 1.27 1.27)
				)
				(justify mirror)
			)
		)
		(duplicate_pad_numbers_are_jumpers no)
		(fp_line
			(start 2.563114 1.633728)
			(end 1.6002 1.633728)
			(stroke
				(width 0.1524)
				(type default)
			)
			(layer "B.SilkS")
		)
		(fp_line
			(start 2.563114 -1.616456)
			(end 2.563114 1.633728)
			(stroke
				(width 0.1524)
				(type default)
			)
			(layer "B.SilkS")
		)
		(fp_line
			(start 2.286 7.366)
			(end 2.286 1.632712)
			(stroke
				(width 0.1524)
				(type default)
			)
			(layer "B.SilkS")
		)
		(fp_line
			(start 2.286 7.366)
			(end 1.60147 7.366)
			(stroke
				(width 0.1524)
				(type default)
			)
			(layer "B.SilkS")
		)
		(fp_line
			(start 1.6002 -1.616456)
			(end 2.563114 -1.616456)
			(stroke
				(width 0.1524)
				(type default)
			)
			(layer "B.SilkS")
		)
		(fp_line
			(start -1.6002 -1.616456)
			(end -2.504948 -1.616456)
			(stroke
				(width 0.1524)
				(type default)
			)
			(layer "B.SilkS")
		)
		(fp_line
			(start -2.286 7.366)
			(end -1.600708 7.366)
			(stroke
				(width 0.1524)
				(type default)
			)
			(layer "B.SilkS")
		)
		(fp_line
			(start -2.286 7.366)
			(end -2.286 1.63195)
			(stroke
				(width 0.1524)
				(type default)
			)
			(layer "B.SilkS")
		)
		(fp_line
			(start -2.504948 1.633728)
			(end -1.6002 1.633728)
			(stroke
				(width 0.1524)
				(type default)
			)
			(layer "B.SilkS")
		)
		(fp_line
			(start -2.504948 -1.616456)
			(end -2.504948 1.633728)
			(stroke
				(width 0.1524)
				(type default)
			)
			(layer "B.SilkS")
		)
		(fp_rect
			(start 2.286 7.366)
			(end -2.286 -0.254)
			(stroke
				(width 0)
				(type default)
			)
			(fill no)
			(layer "B.CrtYd")
		)
		(fp_line
			(start 2.286 7.366)
			(end 2.286 -0.254)
			(stroke
				(width 0.1)
				(type default)
			)
			(layer "B.Fab")
		)
		(fp_line
			(start 2.286 -0.254)
			(end -2.286 -0.254)
			(stroke
				(width 0.1)
				(type default)
			)
			(layer "B.Fab")
		)
		(fp_line
			(start -2.286 7.366)
			(end 2.286 7.366)
			(stroke
				(width 0.1)
				(type default)
			)
			(layer "B.Fab")
		)
		(fp_line
			(start -2.286 -0.254)
			(end -2.286 7.366)
			(stroke
				(width 0.1)
				(type default)
			)
			(layer "B.Fab")
		)
		(pad "1" smd rect
			(at 0 0)
			(size 2.54 3.048)
			(layers "B.Cu" "B.Mask" "B.Paste")
			(net "P1V05_PCH_STBY")
		)
		(pad "2" smd rect
			(at 0 7.112)
			(size 2.54 3.048)
			(layers "B.Cu" "B.Mask" "B.Paste")
			(net "GND")
		)
	)
	(footprint ""
		(layer "B.Cu")
		(at 488.191302 -46.854872 -90)
		(property "Reference" "C9E1"
			(at 0 0 90)
			(layer "B.SilkS")
			(hide yes)
			(effects
				(font
					(size 1.27 1.27)
				)
				(justify mirror)
			)
		)
		(property "Value" ""
			(at 0 0 90)
			(layer "B.Fab")
			(effects
				(font
					(size 1.27 1.27)
				)
				(justify mirror)
			)
		)
		(duplicate_pad_numbers_are_jumpers no)
		(fp_poly
			(pts
				(xy 0.4953 -0.2032) (xy -0.4953 -0.2032) (xy -0.4953 1.6002) (xy 0.4953 1.6002)
			)
			(stroke
				(width 0)
				(type default)
			)
			(fill no)
			(layer "B.CrtYd")
		)
		(fp_line
			(start -0.4953 1.6002)
			(end 0.4953 1.6002)
			(stroke
				(width 0.1)
				(type default)
			)
			(layer "B.Fab")
		)
		(fp_line
			(start 0.4953 1.6002)
			(end 0.4953 -0.2032)
			(stroke
				(width 0.1)
				(type default)
			)
			(layer "B.Fab")
		)
		(fp_line
			(start -0.4953 -0.2032)
			(end -0.4953 1.6002)
			(stroke
				(width 0.1)
				(type default)
			)
			(layer "B.Fab")
		)
		(fp_line
			(start 0.4953 -0.2032)
			(end -0.4953 -0.2032)
			(stroke
				(width 0.1)
				(type default)
			)
			(layer "B.Fab")
		)
		(pad "1" smd rect
			(at 0 0 90)
			(size 0.762 0.889)
			(layers "B.Cu" "B.Mask" "B.Paste")
			(net "P0V9_LAN")
		)
		(pad "2" smd rect
			(at 0 1.397 90)
			(size 0.762 0.889)
			(layers "B.Cu" "B.Mask" "B.Paste")
			(net "GND")
		)
		(zone
			(layer "B.Cu")
			(hatch none 0.5)
			(connect_pads
				(clearance 0)
			)
			(min_thickness 0.25)
			(keepout
				(tracks not_allowed)
				(vias allowed)
				(pads allowed)
				(copperpour not_allowed)
				(footprints allowed)
			)
			(placement
				(enabled no)
				(sheetname "")
			)
			(fill
				(thermal_gap 0.5)
				(thermal_bridge_width 0.5)
				(island_removal_mode 0)
			)
			(polygon
				(pts
					(xy 487.746802 -46.473872) (xy 487.746802 -47.235872) (xy 487.238802 -47.235872) (xy 487.238802 -46.473872)
				)
			)
		)
	)
	(footprint ""
		(layer "B.Cu")
		(at 94.460568 -17.5514 90)
		(property "Reference" "C8U1"
			(at 0 0 90)
			(layer "B.SilkS")
			(hide yes)
			(effects
				(font
					(size 1.27 1.27)
				)
				(justify mirror)
			)
		)
		(property "Value" ""
			(at 0 0 90)
			(layer "B.Fab")
			(effects
				(font
					(size 1.27 1.27)
				)
				(justify mirror)
			)
		)
		(duplicate_pad_numbers_are_jumpers no)
		(fp_poly
			(pts
				(xy 0.7239 -0.2159) (xy -0.7239 -0.2159) (xy -0.7239 1.9939) (xy 0.7239 1.9939)
			)
			(stroke
				(width 0)
				(type default)
			)
			(fill no)
			(layer "B.CrtYd")
		)
		(fp_line
			(start 0.7239 -0.2159)
			(end 0.7239 1.9939)
			(stroke
				(width 0.1)
				(type default)
			)
			(layer "B.Fab")
		)
		(fp_line
			(start -0.7239 -0.2159)
			(end 0.7239 -0.2159)
			(stroke
				(width 0.1)
				(type default)
			)
			(layer "B.Fab")
		)
		(fp_line
			(start 0.7239 1.9939)
			(end -0.7239 1.9939)
			(stroke
				(width 0.1)
				(type default)
			)
			(layer "B.Fab")
		)
		(fp_line
			(start -0.7239 1.9939)
			(end -0.7239 -0.2159)
			(stroke
				(width 0.1)
				(type default)
			)
			(layer "B.Fab")
		)
		(pad "1" smd rect
			(at 0 0 270)
			(size 1.27 1.016)
			(layers "B.Cu" "B.Mask" "B.Paste")
			(net "PVDDQ_GHJ")
		)
		(pad "2" smd rect
			(at 0 1.778 270)
			(size 1.27 1.016)
			(layers "B.Cu" "B.Mask" "B.Paste")
			(net "GND")
		)
		(zone
			(layer "B.Cu")
			(hatch none 0.5)
			(connect_pads
				(clearance 0)
			)
			(min_thickness 0.25)
			(keepout
				(tracks not_allowed)
				(vias allowed)
				(pads allowed)
				(copperpour not_allowed)
				(footprints allowed)
			)
			(placement
				(enabled no)
				(sheetname "")
			)
			(fill
				(thermal_gap 0.5)
				(thermal_bridge_width 0.5)
				(island_removal_mode 0)
			)
			(polygon
				(pts
					(xy 94.968568 -18.1864) (xy 94.968568 -16.9164) (xy 95.730568 -16.9164) (xy 95.730568 -18.1864)
				)
			)
		)
	)
	(footprint ""
		(layer "B.Cu")
		(at 497.561108 -41.41343)
		(property "Reference" "C25P80"
			(at 0.8382 -0.67818 0)
			(unlocked yes)
			(layer "B.SilkS")
			(effects
				(font
					(size 0.4064 0.254)
					(thickness 0.1524)
				)
				(justify left mirror)
			)
		)
		(property "Value" ""
			(at 0 0 0)
			(layer "B.Fab")
			(effects
				(font
					(size 1.27 1.27)
				)
				(justify mirror)
			)
		)
		(duplicate_pad_numbers_are_jumpers no)
		(fp_poly
			(pts
				(xy -0.3048 -0.1016) (xy -0.3048 0.9906) (xy 0.3048 0.9906) (xy 0.3048 -0.1016)
			)
			(stroke
				(width 0)
				(type default)
			)
			(fill no)
			(layer "B.CrtYd")
		)
		(fp_line
			(start -0.3048 -0.1016)
			(end 0.3048 -0.1016)
			(stroke
				(width 0.1)
				(type default)
			)
			(layer "B.Fab")
		)
		(fp_line
			(start -0.3048 0.9906)
			(end -0.3048 -0.1016)
			(stroke
				(width 0.1)
				(type default)
			)
			(layer "B.Fab")
		)
		(fp_line
			(start 0.3048 -0.1016)
			(end 0.3048 0.9906)
			(stroke
				(width 0.1)
				(type default)
			)
			(layer "B.Fab")
		)
		(fp_line
			(start 0.3048 0.9906)
			(end -0.3048 0.9906)
			(stroke
				(width 0.1)
				(type default)
			)
			(layer "B.Fab")
		)
		(pad "1" smd rect
			(at 0 0 180)
			(size 0.508 0.508)
			(layers "B.Cu" "B.Mask" "B.Paste")
			(net "P5V_VGA_D")
		)
		(pad "2" smd rect
			(at 0 0.889 180)
			(size 0.508 0.508)
			(layers "B.Cu" "B.Mask" "B.Paste")
			(net "GND")
		)
		(zone
			(layer "B.Cu")
			(hatch none 0.5)
			(connect_pads
				(clearance 0)
			)
			(min_thickness 0.25)
			(keepout
				(tracks allowed)
				(vias not_allowed)
				(pads allowed)
				(copperpour not_allowed)
				(footprints allowed)
			)
			(placement
				(enabled no)
				(sheetname "")
			)
			(fill
				(thermal_gap 0.5)
				(thermal_bridge_width 0.5)
				(island_removal_mode 0)
			)
			(polygon
				(pts
					(xy 497.815108 -41.15943) (xy 497.307108 -41.15943) (xy 497.307108 -40.77843) (xy 497.815108 -40.77843)
				)
			)
		)
		(zone
			(layer "B.Cu")
			(hatch none 0.5)
			(connect_pads
				(clearance 0)
			)
			(min_thickness 0.25)
			(keepout
				(tracks not_allowed)
				(vias allowed)
				(pads allowed)
				(copperpour not_allowed)
				(footprints allowed)
			)
			(placement
				(enabled no)
				(sheetname "")
			)
			(fill
				(thermal_gap 0.5)
				(thermal_bridge_width 0.5)
				(island_removal_mode 0)
			)
			(polygon
				(pts
					(xy 497.815108 -40.77843) (xy 497.307108 -40.77843) (xy 497.307108 -41.15943) (xy 497.815108 -41.15943)
				)
			)
		)
	)
	(footprint ""
		(layer "B.Cu")
		(at 405.84882 -52.19192 90)
		(property "Reference" "R1W3"
			(at 0 0 90)
			(layer "B.SilkS")
			(hide yes)
			(effects
				(font
					(size 1.27 1.27)
				)
				(justify mirror)
			)
		)
		(property "Value" "*"
			(at -0.064008 -4.108196 90)
			(unlocked yes)
			(layer "B.Fab")
			(hide yes)
			(effects
				(font
					(size 1.27 1.016)
					(thickness 0.1524)
				)
				(justify mirror)
			)
		)
		(property "Device Type" "1MR2F-L-GP_SMD-RG1-1MR2F-L-GP,A"
			(at -0.064008 -5.632196 90)
			(unlocked yes)
			(layer "B.Fab")
			(hide yes)
			(effects
				(font
					(size 1.27 1.016)
					(thickness 0.1524)
				)
				(justify mirror)
			)
		)
		(duplicate_pad_numbers_are_jumpers no)
		(fp_line
			(start 0.508 -0.9398)
			(end 0.508 0.9398)
			(stroke
				(width 0.1524)
				(type default)
			)
			(layer "B.SilkS")
		)
		(fp_line
			(start -0.508 -0.9398)
			(end 0.508 -0.9398)
			(stroke
				(width 0.1524)
				(type default)
			)
			(layer "B.SilkS")
		)
		(fp_rect
			(start 0.508 0.9398)
			(end -0.508 -0.9398)
			(stroke
				(width 0)
				(type default)
			)
			(fill no)
			(layer "B.CrtYd")
		)
		(fp_rect
			(start 0.508 0.9398)
			(end -0.508 -0.9398)
			(stroke
				(width 0)
				(type default)
			)
			(fill no)
			(layer "B.Fab")
		)
		(pad "1" smd custom
			(at 0 -0.4445 270)
			(size 0.1397 0.1397)
			(layers "B.Cu" "B.Mask" "B.Paste")
			(net "P3V3_STBY")
			(options
				(clearance outline)
				(anchor circle)
			)
			(primitives
				(gr_poly
					(pts
						(arc
							(start -0.1778 0.2794)
							(mid -0.249642 0.249642)
							(end -0.2794 0.1778)
						)
						(arc
							(start -0.2794 -0.1778)
							(mid -0.249642 -0.249642)
							(end -0.1778 -0.2794)
						)
						(arc
							(start 0.1778 -0.2794)
							(mid 0.249642 -0.249642)
							(end 0.2794 -0.1778)
						)
						(arc
							(start 0.2794 0.1778)
							(mid 0.249642 0.249642)
							(end 0.1778 0.2794)
						)
					)
					(width 0)
					(fill yes)
				)
			)
		)
		(pad "2" smd custom
			(at 0 0.4445 270)
			(size 0.1397 0.1397)
			(layers "B.Cu" "B.Mask" "B.Paste")
			(net "FM_OCP_MEZZB_PRES_N")
			(options
				(clearance outline)
				(anchor circle)
			)
			(primitives
				(gr_poly
					(pts
						(arc
							(start -0.1778 0.2794)
							(mid -0.249642 0.249642)
							(end -0.2794 0.1778)
						)
						(arc
							(start -0.2794 -0.1778)
							(mid -0.249642 -0.249642)
							(end -0.1778 -0.2794)
						)
						(arc
							(start 0.1778 -0.2794)
							(mid 0.249642 -0.249642)
							(end 0.2794 -0.1778)
						)
						(arc
							(start 0.2794 0.1778)
							(mid 0.249642 0.249642)
							(end 0.1778 0.2794)
						)
					)
					(width 0)
					(fill yes)
				)
			)
		)
	)
	(footprint ""
		(layer "B.Cu")
		(at 470.027 -58.674 -90)
		(property "Reference" "R1W45"
			(at 0.8382 -0.67818 270)
			(unlocked yes)
			(layer "B.SilkS")
			(effects
				(font
					(size 0.4064 0.254)
					(thickness 0.1524)
				)
				(justify left mirror)
			)
		)
		(property "Value" ""
			(at 0 0 90)
			(layer "B.Fab")
			(effects
				(font
					(size 1.27 1.27)
				)
				(justify mirror)
			)
		)
		(duplicate_pad_numbers_are_jumpers no)
		(fp_poly
			(pts
				(xy 0.2794 -0.1016) (xy -0.2794 -0.1016) (xy -0.2794 0.9906) (xy 0.2794 0.9906)
			)
			(stroke
				(width 0)
				(type default)
			)
			(fill no)
			(layer "B.CrtYd")
		)
		(fp_line
			(start -0.2794 0.9906)
			(end -0.2794 -0.1016)
			(stroke
				(width 0.1)
				(type default)
			)
			(layer "B.Fab")
		)
		(fp_line
			(start 0.2794 0.9906)
			(end -0.2794 0.9906)
			(stroke
				(width 0.1)
				(type default)
			)
			(layer "B.Fab")
		)
		(fp_line
			(start -0.2794 -0.1016)
			(end 0.2794 -0.1016)
			(stroke
				(width 0.1)
				(type default)
			)
			(layer "B.Fab")
		)
		(fp_line
			(start 0.2794 -0.1016)
			(end 0.2794 0.9906)
			(stroke
				(width 0.1)
				(type default)
			)
			(layer "B.Fab")
		)
		(pad "1" smd rect
			(at 0 0 90)
			(size 0.508 0.508)
			(layers "B.Cu" "B.Mask" "B.Paste")
			(net "P3V3_STBY")
		)
		(pad "2" smd rect
			(at 0 0.889 90)
			(size 0.508 0.508)
			(layers "B.Cu" "B.Mask" "B.Paste")
			(net "FM_GBE3_LVC3_MOD_ABS")
		)
		(zone
			(layer "B.Cu")
			(hatch none 0.5)
			(connect_pads
				(clearance 0)
			)
			(min_thickness 0.25)
			(keepout
				(tracks not_allowed)
				(vias allowed)
				(pads allowed)
				(copperpour not_allowed)
				(footprints allowed)
			)
			(placement
				(enabled no)
				(sheetname "")
			)
			(fill
				(thermal_gap 0.5)
				(thermal_bridge_width 0.5)
				(island_removal_mode 0)
			)
			(polygon
				(pts
					(xy 469.392 -58.42) (xy 469.392 -58.928) (xy 469.773 -58.928) (xy 469.773 -58.42)
				)
			)
		)
		(zone
			(layer "B.Cu")
			(hatch none 0.5)
			(connect_pads
				(clearance 0)
			)
			(min_thickness 0.25)
			(keepout
				(tracks allowed)
				(vias not_allowed)
				(pads allowed)
				(copperpour not_allowed)
				(footprints allowed)
			)
			(placement
				(enabled no)
				(sheetname "")
			)
			(fill
				(thermal_gap 0.5)
				(thermal_bridge_width 0.5)
				(island_removal_mode 0)
			)
			(polygon
				(pts
					(xy 469.773 -58.42) (xy 469.773 -58.928) (xy 469.392 -58.928) (xy 469.392 -58.42)
				)
			)
		)
	)
	(footprint ""
		(layer "B.Cu")
		(at 97.206054 -77.82814)
		(property "Reference" "C8P19"
			(at 0 0 0)
			(layer "B.SilkS")
			(hide yes)
			(effects
				(font
					(size 1.27 1.27)
				)
				(justify mirror)
			)
		)
		(property "Value" ""
			(at 0 0 0)
			(layer "B.Fab")
			(effects
				(font
					(size 1.27 1.27)
				)
				(justify mirror)
			)
		)
		(duplicate_pad_numbers_are_jumpers no)
		(fp_poly
			(pts
				(xy 0.7239 -0.2159) (xy -0.7239 -0.2159) (xy -0.7239 1.9939) (xy 0.7239 1.9939)
			)
			(stroke
				(width 0)
				(type default)
			)
			(fill no)
			(layer "B.CrtYd")
		)
		(fp_line
			(start -0.7239 -0.2159)
			(end 0.7239 -0.2159)
			(stroke
				(width 0.1)
				(type default)
			)
			(layer "B.Fab")
		)
		(fp_line
			(start -0.7239 1.9939)
			(end -0.7239 -0.2159)
			(stroke
				(width 0.1)
				(type default)
			)
			(layer "B.Fab")
		)
		(fp_line
			(start 0.7239 -0.2159)
			(end 0.7239 1.9939)
			(stroke
				(width 0.1)
				(type default)
			)
			(layer "B.Fab")
		)
		(fp_line
			(start 0.7239 1.9939)
			(end -0.7239 1.9939)
			(stroke
				(width 0.1)
				(type default)
			)
			(layer "B.Fab")
		)
		(pad "1" smd rect
			(at 0 0 180)
			(size 1.27 1.016)
			(layers "B.Cu" "B.Mask" "B.Paste")
			(net "PVCCIN_CPU1")
		)
		(pad "2" smd rect
			(at 0 1.778 180)
			(size 1.27 1.016)
			(layers "B.Cu" "B.Mask" "B.Paste")
			(net "GND")
		)
		(zone
			(layer "B.Cu")
			(hatch none 0.5)
			(connect_pads
				(clearance 0)
			)
			(min_thickness 0.25)
			(keepout
				(tracks not_allowed)
				(vias allowed)
				(pads allowed)
				(copperpour not_allowed)
				(footprints allowed)
			)
			(placement
				(enabled no)
				(sheetname "")
			)
			(fill
				(thermal_gap 0.5)
				(thermal_bridge_width 0.5)
				(island_removal_mode 0)
			)
			(polygon
				(pts
					(xy 97.841054 -77.32014) (xy 96.571054 -77.32014) (xy 96.571054 -76.55814) (xy 97.841054 -76.55814)
				)
			)
		)
	)
	(footprint ""
		(layer "B.Cu")
		(at 450.5325 -22.733 -90)
		(property "Reference" "R6W20"
			(at 0.8382 -0.67818 270)
			(unlocked yes)
			(layer "B.SilkS")
			(effects
				(font
					(size 0.4064 0.254)
					(thickness 0.1524)
				)
				(justify left mirror)
			)
		)
		(property "Value" ""
			(at 0 0 90)
			(layer "B.Fab")
			(effects
				(font
					(size 1.27 1.27)
				)
				(justify mirror)
			)
		)
		(duplicate_pad_numbers_are_jumpers no)
		(fp_poly
			(pts
				(xy 0.2794 -0.1016) (xy -0.2794 -0.1016) (xy -0.2794 0.9906) (xy 0.2794 0.9906)
			)
			(stroke
				(width 0)
				(type default)
			)
			(fill no)
			(layer "B.CrtYd")
		)
		(fp_line
			(start -0.2794 0.9906)
			(end -0.2794 -0.1016)
			(stroke
				(width 0.1)
				(type default)
			)
			(layer "B.Fab")
		)
		(fp_line
			(start 0.2794 0.9906)
			(end -0.2794 0.9906)
			(stroke
				(width 0.1)
				(type default)
			)
			(layer "B.Fab")
		)
		(fp_line
			(start -0.2794 -0.1016)
			(end 0.2794 -0.1016)
			(stroke
				(width 0.1)
				(type default)
			)
			(layer "B.Fab")
		)
		(fp_line
			(start 0.2794 -0.1016)
			(end 0.2794 0.9906)
			(stroke
				(width 0.1)
				(type default)
			)
			(layer "B.Fab")
		)
		(pad "1" smd rect
			(at 0 0 90)
			(size 0.508 0.508)
			(layers "B.Cu" "B.Mask" "B.Paste")
			(net "SMB_HOST_STBY_LVC3_SDA_R3")
		)
		(pad "2" smd rect
			(at 0 0.889 90)
			(size 0.508 0.508)
			(layers "B.Cu" "B.Mask" "B.Paste")
			(net "SMB_HOST_STBY_LVC3_SDA")
		)
		(zone
			(layer "B.Cu")
			(hatch none 0.5)
			(connect_pads
				(clearance 0)
			)
			(min_thickness 0.25)
			(keepout
				(tracks not_allowed)
				(vias allowed)
				(pads allowed)
				(copperpour not_allowed)
				(footprints allowed)
			)
			(placement
				(enabled no)
				(sheetname "")
			)
			(fill
				(thermal_gap 0.5)
				(thermal_bridge_width 0.5)
				(island_removal_mode 0)
			)
			(polygon
				(pts
					(xy 449.8975 -22.479) (xy 449.8975 -22.987) (xy 450.2785 -22.987) (xy 450.2785 -22.479)
				)
			)
		)
		(zone
			(layer "B.Cu")
			(hatch none 0.5)
			(connect_pads
				(clearance 0)
			)
			(min_thickness 0.25)
			(keepout
				(tracks allowed)
				(vias not_allowed)
				(pads allowed)
				(copperpour not_allowed)
				(footprints allowed)
			)
			(placement
				(enabled no)
				(sheetname "")
			)
			(fill
				(thermal_gap 0.5)
				(thermal_bridge_width 0.5)
				(island_removal_mode 0)
			)
			(polygon
				(pts
					(xy 450.2785 -22.479) (xy 450.2785 -22.987) (xy 449.8975 -22.987) (xy 449.8975 -22.479)
				)
			)
		)
	)
	(footprint ""
		(layer "B.Cu")
		(at 413.5755 -18.288 -90)
		(property "Reference" "R2U46"
			(at 0 0 90)
			(layer "B.SilkS")
			(hide yes)
			(effects
				(font
					(size 1.27 1.27)
				)
				(justify mirror)
			)
		)
		(property "Value" ""
			(at 0 0 90)
			(layer "B.Fab")
			(effects
				(font
					(size 1.27 1.27)
				)
				(justify mirror)
			)
		)
		(duplicate_pad_numbers_are_jumpers no)
		(fp_poly
			(pts
				(xy 0.2794 -0.1016) (xy -0.2794 -0.1016) (xy -0.2794 0.9906) (xy 0.2794 0.9906)
			)
			(stroke
				(width 0)
				(type default)
			)
			(fill no)
			(layer "B.CrtYd")
		)
		(fp_line
			(start -0.2794 0.9906)
			(end -0.2794 -0.1016)
			(stroke
				(width 0.1)
				(type default)
			)
			(layer "B.Fab")
		)
		(fp_line
			(start 0.2794 0.9906)
			(end -0.2794 0.9906)
			(stroke
				(width 0.1)
				(type default)
			)
			(layer "B.Fab")
		)
		(fp_line
			(start -0.2794 -0.1016)
			(end 0.2794 -0.1016)
			(stroke
				(width 0.1)
				(type default)
			)
			(layer "B.Fab")
		)
		(fp_line
			(start 0.2794 -0.1016)
			(end 0.2794 0.9906)
			(stroke
				(width 0.1)
				(type default)
			)
			(layer "B.Fab")
		)
		(pad "1" smd rect
			(at 0 0 90)
			(size 0.508 0.508)
			(layers "B.Cu" "B.Mask" "B.Paste")
			(net "H_CPU1_MEMKLM_MEMHOT_LVT3_N")
		)
		(pad "2" smd rect
			(at 0 0.889 90)
			(size 0.508 0.508)
			(layers "B.Cu" "B.Mask" "B.Paste")
			(net "H_CPU1_MEMKLM_MEMHOT_LVT3_BMC_N")
		)
		(zone
			(layer "B.Cu")
			(hatch none 0.5)
			(connect_pads
				(clearance 0)
			)
			(min_thickness 0.25)
			(keepout
				(tracks not_allowed)
				(vias allowed)
				(pads allowed)
				(copperpour not_allowed)
				(footprints allowed)
			)
			(placement
				(enabled no)
				(sheetname "")
			)
			(fill
				(thermal_gap 0.5)
				(thermal_bridge_width 0.5)
				(island_removal_mode 0)
			)
			(polygon
				(pts
					(xy 412.9405 -18.034) (xy 412.9405 -18.542) (xy 413.3215 -18.542) (xy 413.3215 -18.034)
				)
			)
		)
		(zone
			(layer "B.Cu")
			(hatch none 0.5)
			(connect_pads
				(clearance 0)
			)
			(min_thickness 0.25)
			(keepout
				(tracks allowed)
				(vias not_allowed)
				(pads allowed)
				(copperpour not_allowed)
				(footprints allowed)
			)
			(placement
				(enabled no)
				(sheetname "")
			)
			(fill
				(thermal_gap 0.5)
				(thermal_bridge_width 0.5)
				(island_removal_mode 0)
			)
			(polygon
				(pts
					(xy 413.3215 -18.034) (xy 413.3215 -18.542) (xy 412.9405 -18.542) (xy 412.9405 -18.034)
				)
			)
		)
	)
	(footprint ""
		(layer "B.Cu")
		(at 32.2834 -78.9432 90)
		(property "Reference" "R9P8"
			(at 0 0 90)
			(layer "B.SilkS")
			(hide yes)
			(effects
				(font
					(size 1.27 1.27)
				)
				(justify mirror)
			)
		)
		(property "Value" ""
			(at 0 0 90)
			(layer "B.Fab")
			(effects
				(font
					(size 1.27 1.27)
				)
				(justify mirror)
			)
		)
		(duplicate_pad_numbers_are_jumpers no)
		(fp_poly
			(pts
				(xy 0.2794 -0.1016) (xy -0.2794 -0.1016) (xy -0.2794 0.9906) (xy 0.2794 0.9906)
			)
			(stroke
				(width 0)
				(type default)
			)
			(fill no)
			(layer "B.CrtYd")
		)
		(fp_line
			(start 0.2794 -0.1016)
			(end 0.2794 0.9906)
			(stroke
				(width 0.1)
				(type default)
			)
			(layer "B.Fab")
		)
		(fp_line
			(start -0.2794 -0.1016)
			(end 0.2794 -0.1016)
			(stroke
				(width 0.1)
				(type default)
			)
			(layer "B.Fab")
		)
		(fp_line
			(start 0.2794 0.9906)
			(end -0.2794 0.9906)
			(stroke
				(width 0.1)
				(type default)
			)
			(layer "B.Fab")
		)
		(fp_line
			(start -0.2794 0.9906)
			(end -0.2794 -0.1016)
			(stroke
				(width 0.1)
				(type default)
			)
			(layer "B.Fab")
		)
		(pad "1" smd rect
			(at 0 0 270)
			(size 0.508 0.508)
			(layers "B.Cu" "B.Mask" "B.Paste")
			(net "VR_PVCCIN_CPU1_PH4_VCIN")
		)
		(pad "2" smd rect
			(at 0 0.889 270)
			(size 0.508 0.508)
			(layers "B.Cu" "B.Mask" "B.Paste")
			(net "P5V_STBY")
		)
		(zone
			(layer "B.Cu")
			(hatch none 0.5)
			(connect_pads
				(clearance 0)
			)
			(min_thickness 0.25)
			(keepout
				(tracks allowed)
				(vias not_allowed)
				(pads allowed)
				(copperpour not_allowed)
				(footprints allowed)
			)
			(placement
				(enabled no)
				(sheetname "")
			)
			(fill
				(thermal_gap 0.5)
				(thermal_bridge_width 0.5)
				(island_removal_mode 0)
			)
			(polygon
				(pts
					(xy 32.5374 -79.1972) (xy 32.5374 -78.6892) (xy 32.9184 -78.6892) (xy 32.9184 -79.1972)
				)
			)
		)
		(zone
			(layer "B.Cu")
			(hatch none 0.5)
			(connect_pads
				(clearance 0)
			)
			(min_thickness 0.25)
			(keepout
				(tracks not_allowed)
				(vias allowed)
				(pads allowed)
				(copperpour not_allowed)
				(footprints allowed)
			)
			(placement
				(enabled no)
				(sheetname "")
			)
			(fill
				(thermal_gap 0.5)
				(thermal_bridge_width 0.5)
				(island_removal_mode 0)
			)
			(polygon
				(pts
					(xy 32.9184 -79.1972) (xy 32.9184 -78.6892) (xy 32.5374 -78.6892) (xy 32.5374 -79.1972)
				)
			)
		)
	)
	(footprint ""
		(layer "B.Cu")
		(at 410.455872 -6.0452 -90)
		(property "Reference" "U8D8"
			(at -0.621538 1.822958 90)
			(unlocked yes)
			(layer "B.SilkS")
			(effects
				(font
					(size 0.7874 0.5842)
					(thickness 0.1524)
				)
				(justify mirror)
			)
		)
		(property "Value" ""
			(at 0 0 90)
			(layer "B.Fab")
			(effects
				(font
					(size 1.27 1.27)
				)
				(justify mirror)
			)
		)
		(duplicate_pad_numbers_are_jumpers no)
		(fp_circle
			(center 1.0795 -0.054102)
			(end 1.0795 -0.180848)
			(stroke
				(width 0.254)
				(type default)
			)
			(fill no)
			(layer "B.SilkS")
		)
		(fp_rect
			(start 0.216154 1.27508)
			(end -1.333754 -0.275082)
			(stroke
				(width 0)
				(type default)
			)
			(fill no)
			(layer "B.CrtYd")
		)
		(fp_line
			(start -1.333754 1.27508)
			(end 0.216154 1.27508)
			(stroke
				(width 0.1)
				(type default)
			)
			(layer "B.Fab")
		)
		(fp_line
			(start 0.216154 1.27508)
			(end 0.216154 -0.275082)
			(stroke
				(width 0.1)
				(type default)
			)
			(layer "B.Fab")
		)
		(fp_line
			(start -1.333754 -0.275082)
			(end -1.333754 1.27508)
			(stroke
				(width 0.1)
				(type default)
			)
			(layer "B.Fab")
		)
		(fp_line
			(start 0.216154 -0.275082)
			(end -1.333754 -0.275082)
			(stroke
				(width 0.1)
				(type default)
			)
			(layer "B.Fab")
		)
		(fp_circle
			(center 1.0795 -0.054102)
			(end 1.0795 -0.180848)
			(stroke
				(width 0.254)
				(type default)
			)
			(fill no)
			(layer "B.Fab")
		)
		(pad "1" smd rect
			(at 0 0 90)
			(size 0.9398 0.3048)
			(layers "B.Cu" "B.Mask" "B.Paste")
			(net "PWRGD_P5V_N")
		)
		(pad "2" smd rect
			(at 0.0254 0.500126 90)
			(size 0.889 0.3048)
			(layers "B.Cu" "B.Mask" "B.Paste")
			(net "P3V3_STBY")
		)
		(pad "3" smd rect
			(at 0.0254 0.999998 90)
			(size 0.889 0.3048)
			(layers "B.Cu" "B.Mask" "B.Paste")
			(net "A_PG_P5V")
		)
		(pad "4" smd rect
			(at -1.143 0.999998 90)
			(size 0.889 0.3048)
			(layers "B.Cu" "B.Mask" "B.Paste")
			(net "A_PG_P12V_MAIN")
		)
		(pad "5" smd rect
			(at -1.143 0.500126 90)
			(size 0.889 0.3048)
			(layers "B.Cu" "B.Mask" "B.Paste")
			(net "GND")
		)
		(pad "6" smd rect
			(at -1.143 0 90)
			(size 0.889 0.3048)
			(layers "B.Cu" "B.Mask" "B.Paste")
			(net "PWRGD_P12V_MAIN_R")
		)
	)
	(footprint ""
		(layer "B.Cu")
		(at 3.499104 -15.15237 90)
		(property "Reference" "R9U12"
			(at 0 0 90)
			(layer "B.SilkS")
			(hide yes)
			(effects
				(font
					(size 1.27 1.27)
				)
				(justify mirror)
			)
		)
		(property "Value" ""
			(at 0 0 90)
			(layer "B.Fab")
			(effects
				(font
					(size 1.27 1.27)
				)
				(justify mirror)
			)
		)
		(duplicate_pad_numbers_are_jumpers no)
		(fp_rect
			(start 0.2794 -0.1016)
			(end -0.2794 0.9906)
			(stroke
				(width 0)
				(type default)
			)
			(fill no)
			(layer "B.CrtYd")
		)
		(fp_line
			(start 0.2794 -0.1016)
			(end 0.2794 0.9906)
			(stroke
				(width 0.1)
				(type default)
			)
			(layer "B.Fab")
		)
		(fp_line
			(start -0.2794 -0.1016)
			(end 0.2794 -0.1016)
			(stroke
				(width 0.1)
				(type default)
			)
			(layer "B.Fab")
		)
		(fp_line
			(start 0.2794 0.9906)
			(end -0.2794 0.9906)
			(stroke
				(width 0.1)
				(type default)
			)
			(layer "B.Fab")
		)
		(fp_line
			(start -0.2794 0.9906)
			(end -0.2794 -0.1016)
			(stroke
				(width 0.1)
				(type default)
			)
			(layer "B.Fab")
		)
		(pad "1" smd rect
			(at 0 0 270)
			(size 0.508 0.508)
			(layers "B.Cu" "B.Mask" "B.Paste")
			(net "VR_PVDDQ_GHJ_PH2_VCIN")
		)
		(pad "2" smd rect
			(at 0 0.889 270)
			(size 0.508 0.508)
			(layers "B.Cu" "B.Mask" "B.Paste")
			(net "P5V_STBY")
		)
		(zone
			(layer "B.Cu")
			(hatch none 0.5)
			(connect_pads
				(clearance 0)
			)
			(min_thickness 0.25)
			(keepout
				(tracks not_allowed)
				(vias allowed)
				(pads allowed)
				(copperpour not_allowed)
				(footprints allowed)
			)
			(placement
				(enabled no)
				(sheetname "")
			)
			(fill
				(thermal_gap 0.5)
				(thermal_bridge_width 0.5)
				(island_removal_mode 0)
			)
			(polygon
				(pts
					(xy 3.753104 -15.40637) (xy 3.753104 -14.89837) (xy 4.134104 -14.89837) (xy 4.134104 -15.40637)
				)
			)
		)
		(zone
			(layer "B.Cu")
			(hatch none 0.5)
			(connect_pads
				(clearance 0)
			)
			(min_thickness 0.25)
			(keepout
				(tracks allowed)
				(vias not_allowed)
				(pads allowed)
				(copperpour not_allowed)
				(footprints allowed)
			)
			(placement
				(enabled no)
				(sheetname "")
			)
			(fill
				(thermal_gap 0.5)
				(thermal_bridge_width 0.5)
				(island_removal_mode 0)
			)
			(polygon
				(pts
					(xy 3.753104 -15.40637) (xy 3.753104 -14.89837) (xy 4.134104 -14.89837) (xy 4.134104 -15.40637)
				)
			)
		)
	)
	(footprint ""
		(layer "B.Cu")
		(at 33.622996 -77.552042 90)
		(property "Reference" "C1D5"
			(at 0 0 90)
			(layer "B.SilkS")
			(hide yes)
			(effects
				(font
					(size 1.27 1.27)
				)
				(justify mirror)
			)
		)
		(property "Value" "*"
			(at -1.1811 -2.8194 90)
			(unlocked yes)
			(layer "B.Fab")
			(hide yes)
			(effects
				(font
					(size 1.27 1.016)
					(thickness 0.1524)
				)
				(justify mirror)
			)
		)
		(property "Device Type" "SC1U10V2KX-4-GP_SMD-BCG6-SC1U1A"
			(at -1.1811 -4.3434 90)
			(unlocked yes)
			(layer "B.Fab")
			(hide yes)
			(effects
				(font
					(size 1.27 1.016)
					(thickness 0.1524)
				)
				(justify mirror)
			)
		)
		(duplicate_pad_numbers_are_jumpers no)
		(fp_rect
			(start 0.4318 0.9525)
			(end -0.4318 -0.9525)
			(stroke
				(width 0)
				(type default)
			)
			(fill no)
			(layer "B.CrtYd")
		)
		(fp_rect
			(start 0.4318 0.9525)
			(end -0.4318 -0.9525)
			(stroke
				(width 0)
				(type default)
			)
			(fill no)
			(layer "B.Fab")
		)
		(pad "1" smd custom
			(at 0 -0.4445 270)
			(size 0.1524 0.1524)
			(layers "B.Cu" "B.Mask" "B.Paste")
			(net "P5V_STBY")
			(options
				(clearance outline)
				(anchor circle)
			)
			(primitives
				(gr_poly
					(pts
						(arc
							(start 0.3048 0.2032)
							(mid 0.275042 0.275042)
							(end 0.2032 0.3048)
						)
						(arc
							(start -0.2032 0.3048)
							(mid -0.275042 0.275042)
							(end -0.3048 0.2032)
						)
						(arc
							(start -0.3048 -0.2032)
							(mid -0.275042 -0.275042)
							(end -0.2032 -0.3048)
						)
						(arc
							(start 0.2032 -0.3048)
							(mid 0.275042 -0.275042)
							(end 0.3048 -0.2032)
						)
					)
					(width 0)
					(fill yes)
				)
			)
		)
		(pad "2" smd custom
			(at 0 0.4445 270)
			(size 0.1524 0.1524)
			(layers "B.Cu" "B.Mask" "B.Paste")
			(net "GND")
			(options
				(clearance outline)
				(anchor circle)
			)
			(primitives
				(gr_poly
					(pts
						(arc
							(start 0.3048 0.2032)
							(mid 0.275042 0.275042)
							(end 0.2032 0.3048)
						)
						(arc
							(start -0.2032 0.3048)
							(mid -0.275042 0.275042)
							(end -0.3048 0.2032)
						)
						(arc
							(start -0.3048 -0.2032)
							(mid -0.275042 -0.275042)
							(end -0.2032 -0.3048)
						)
						(arc
							(start 0.2032 -0.3048)
							(mid 0.275042 -0.275042)
							(end 0.3048 -0.2032)
						)
					)
					(width 0)
					(fill yes)
				)
			)
		)
	)
	(footprint ""
		(layer "B.Cu")
		(at 80.757268 -8.1534 -90)
		(property "Reference" "C8U7"
			(at -1.848866 0.752348 270)
			(unlocked yes)
			(layer "B.SilkS")
			(effects
				(font
					(size 1.27 0.9652)
					(thickness 0.1524)
				)
				(justify mirror)
			)
		)
		(property "Value" ""
			(at 0 0 90)
			(layer "B.Fab")
			(effects
				(font
					(size 1.27 1.27)
				)
				(justify mirror)
			)
		)
		(duplicate_pad_numbers_are_jumpers no)
		(fp_rect
			(start 0.500126 1.598422)
			(end -0.500126 -0.201422)
			(stroke
				(width 0)
				(type default)
			)
			(fill no)
			(layer "B.CrtYd")
		)
		(fp_line
			(start -0.500126 1.598422)
			(end 0.500126 1.598422)
			(stroke
				(width 0.1)
				(type default)
			)
			(layer "B.Fab")
		)
		(fp_line
			(start 0.500126 1.598422)
			(end 0.500126 -0.201422)
			(stroke
				(width 0.1)
				(type default)
			)
			(layer "B.Fab")
		)
		(fp_line
			(start -0.500126 -0.201422)
			(end -0.500126 1.598422)
			(stroke
				(width 0.1)
				(type default)
			)
			(layer "B.Fab")
		)
		(fp_line
			(start 0.500126 -0.201422)
			(end -0.500126 -0.201422)
			(stroke
				(width 0.1)
				(type default)
			)
			(layer "B.Fab")
		)
		(pad "1" smd rect
			(at 0 0 180)
			(size 0.889 0.9906)
			(layers "B.Cu" "B.Mask" "B.Paste")
			(net "PVDDQ_GHJ")
		)
		(pad "2" smd rect
			(at 0 1.397 180)
			(size 0.889 0.9906)
			(layers "B.Cu" "B.Mask" "B.Paste")
			(net "GND")
		)
		(zone
			(layer "B.Cu")
			(hatch none 0.5)
			(connect_pads
				(clearance 0)
			)
			(min_thickness 0.25)
			(keepout
				(tracks not_allowed)
				(vias allowed)
				(pads allowed)
				(copperpour not_allowed)
				(footprints allowed)
			)
			(placement
				(enabled no)
				(sheetname "")
			)
			(fill
				(thermal_gap 0.5)
				(thermal_bridge_width 0.5)
				(island_removal_mode 0)
			)
			(polygon
				(pts
					(xy 79.804768 -7.6581) (xy 80.312768 -7.6581) (xy 80.312768 -8.6487) (xy 79.804768 -8.6487)
				)
			)
		)
		(zone
			(layer "B.Cu")
			(hatch none 0.5)
			(connect_pads
				(clearance 0)
			)
			(min_thickness 0.25)
			(keepout
				(tracks allowed)
				(vias not_allowed)
				(pads allowed)
				(copperpour not_allowed)
				(footprints allowed)
			)
			(placement
				(enabled no)
				(sheetname "")
			)
			(fill
				(thermal_gap 0.5)
				(thermal_bridge_width 0.5)
				(island_removal_mode 0)
			)
			(polygon
				(pts
					(xy 79.804768 -7.6581) (xy 80.312768 -7.6581) (xy 80.312768 -8.6487) (xy 79.804768 -8.6487)
				)
			)
		)
	)
	(footprint ""
		(layer "B.Cu")
		(at 266.397232 -149.8092 90)
		(property "Reference" "C5G69"
			(at -1.14681 0.76708 180)
			(unlocked yes)
			(layer "B.SilkS")
			(effects
				(font
					(size 0.7874 0.5842)
					(thickness 0.1524)
				)
				(justify mirror)
			)
		)
		(property "Value" ""
			(at 0 0 90)
			(layer "B.Fab")
			(effects
				(font
					(size 1.27 1.27)
				)
				(justify mirror)
			)
		)
		(duplicate_pad_numbers_are_jumpers no)
		(fp_rect
			(start -0.4953 -0.2032)
			(end 0.4953 1.6002)
			(stroke
				(width 0)
				(type default)
			)
			(fill no)
			(layer "B.CrtYd")
		)
		(fp_line
			(start 0.4953 -0.2032)
			(end -0.4953 -0.2032)
			(stroke
				(width 0.1)
				(type default)
			)
			(layer "B.Fab")
		)
		(fp_line
			(start -0.4953 -0.2032)
			(end -0.4953 1.6002)
			(stroke
				(width 0.1)
				(type default)
			)
			(layer "B.Fab")
		)
		(fp_line
			(start 0.4953 1.6002)
			(end 0.4953 -0.2032)
			(stroke
				(width 0.1)
				(type default)
			)
			(layer "B.Fab")
		)
		(fp_line
			(start -0.4953 1.6002)
			(end 0.4953 1.6002)
			(stroke
				(width 0.1)
				(type default)
			)
			(layer "B.Fab")
		)
		(pad "1" smd rect
			(at 0 0 270)
			(size 0.762 0.889)
			(layers "B.Cu" "B.Mask" "B.Paste")
			(net "PVDDQ_DEF")
		)
		(pad "2" smd rect
			(at 0 1.397 270)
			(size 0.762 0.889)
			(layers "B.Cu" "B.Mask" "B.Paste")
			(net "GND")
		)
		(zone
			(layer "B.Cu")
			(hatch none 0.5)
			(connect_pads
				(clearance 0)
			)
			(min_thickness 0.25)
			(keepout
				(tracks not_allowed)
				(vias allowed)
				(pads allowed)
				(copperpour not_allowed)
				(footprints allowed)
			)
			(placement
				(enabled no)
				(sheetname "")
			)
			(fill
				(thermal_gap 0.5)
				(thermal_bridge_width 0.5)
				(island_removal_mode 0)
			)
			(polygon
				(pts
					(xy 266.841732 -149.4282) (xy 267.349732 -149.4282) (xy 267.349732 -150.1902) (xy 266.841732 -150.1902)
				)
			)
		)
	)
	(footprint ""
		(layer "B.Cu")
		(at 164.973 -69.088 -90)
		(property "Reference" "R6P33"
			(at 0 0 90)
			(layer "B.SilkS")
			(hide yes)
			(effects
				(font
					(size 1.27 1.27)
				)
				(justify mirror)
			)
		)
		(property "Value" ""
			(at 0 0 90)
			(layer "B.Fab")
			(effects
				(font
					(size 1.27 1.27)
				)
				(justify mirror)
			)
		)
		(duplicate_pad_numbers_are_jumpers no)
		(fp_poly
			(pts
				(xy 0.2794 -0.1016) (xy -0.2794 -0.1016) (xy -0.2794 0.9906) (xy 0.2794 0.9906)
			)
			(stroke
				(width 0)
				(type default)
			)
			(fill no)
			(layer "B.CrtYd")
		)
		(fp_line
			(start -0.2794 0.9906)
			(end -0.2794 -0.1016)
			(stroke
				(width 0.1)
				(type default)
			)
			(layer "B.Fab")
		)
		(fp_line
			(start 0.2794 0.9906)
			(end -0.2794 0.9906)
			(stroke
				(width 0.1)
				(type default)
			)
			(layer "B.Fab")
		)
		(fp_line
			(start -0.2794 -0.1016)
			(end 0.2794 -0.1016)
			(stroke
				(width 0.1)
				(type default)
			)
			(layer "B.Fab")
		)
		(fp_line
			(start 0.2794 -0.1016)
			(end 0.2794 0.9906)
			(stroke
				(width 0.1)
				(type default)
			)
			(layer "B.Fab")
		)
		(pad "1" smd rect
			(at 0 0 90)
			(size 0.508 0.508)
			(layers "B.Cu" "B.Mask" "B.Paste")
			(net "PVCCIO_CPU1")
		)
		(pad "2" smd rect
			(at 0 0.889 90)
			(size 0.508 0.508)
			(layers "B.Cu" "B.Mask" "B.Paste")
			(net "SVID_CLK0_CPU1_R")
		)
		(zone
			(layer "B.Cu")
			(hatch none 0.5)
			(connect_pads
				(clearance 0)
			)
			(min_thickness 0.25)
			(keepout
				(tracks not_allowed)
				(vias allowed)
				(pads allowed)
				(copperpour not_allowed)
				(footprints allowed)
			)
			(placement
				(enabled no)
				(sheetname "")
			)
			(fill
				(thermal_gap 0.5)
				(thermal_bridge_width 0.5)
				(island_removal_mode 0)
			)
			(polygon
				(pts
					(xy 164.338 -68.834) (xy 164.338 -69.342) (xy 164.719 -69.342) (xy 164.719 -68.834)
				)
			)
		)
		(zone
			(layer "B.Cu")
			(hatch none 0.5)
			(connect_pads
				(clearance 0)
			)
			(min_thickness 0.25)
			(keepout
				(tracks allowed)
				(vias not_allowed)
				(pads allowed)
				(copperpour not_allowed)
				(footprints allowed)
			)
			(placement
				(enabled no)
				(sheetname "")
			)
			(fill
				(thermal_gap 0.5)
				(thermal_bridge_width 0.5)
				(island_removal_mode 0)
			)
			(polygon
				(pts
					(xy 164.719 -68.834) (xy 164.719 -69.342) (xy 164.338 -69.342) (xy 164.338 -68.834)
				)
			)
		)
	)
	(footprint ""
		(layer "B.Cu")
		(at 479.923602 -58.772298 90)
		(property "Reference" "R8E29"
			(at 0 0 90)
			(layer "B.SilkS")
			(hide yes)
			(effects
				(font
					(size 1.27 1.27)
				)
				(justify mirror)
			)
		)
		(property "Value" ""
			(at 0 0 90)
			(layer "B.Fab")
			(effects
				(font
					(size 1.27 1.27)
				)
				(justify mirror)
			)
		)
		(duplicate_pad_numbers_are_jumpers no)
		(fp_poly
			(pts
				(xy 0.2794 -0.1016) (xy -0.2794 -0.1016) (xy -0.2794 0.9906) (xy 0.2794 0.9906)
			)
			(stroke
				(width 0)
				(type default)
			)
			(fill no)
			(layer "B.CrtYd")
		)
		(fp_line
			(start 0.2794 -0.1016)
			(end 0.2794 0.9906)
			(stroke
				(width 0.1)
				(type default)
			)
			(layer "B.Fab")
		)
		(fp_line
			(start -0.2794 -0.1016)
			(end 0.2794 -0.1016)
			(stroke
				(width 0.1)
				(type default)
			)
			(layer "B.Fab")
		)
		(fp_line
			(start 0.2794 0.9906)
			(end -0.2794 0.9906)
			(stroke
				(width 0.1)
				(type default)
			)
			(layer "B.Fab")
		)
		(fp_line
			(start -0.2794 0.9906)
			(end -0.2794 -0.1016)
			(stroke
				(width 0.1)
				(type default)
			)
			(layer "B.Fab")
		)
		(pad "1" smd rect
			(at 0 0 270)
			(size 0.508 0.508)
			(layers "B.Cu" "B.Mask" "B.Paste")
			(net "FM_PE_BMC_WAKE_N")
		)
		(pad "2" smd rect
			(at 0 0.889 270)
			(size 0.508 0.508)
			(layers "B.Cu" "B.Mask" "B.Paste")
			(net "FM_ALL_WAKE_N")
		)
		(zone
			(layer "B.Cu")
			(hatch none 0.5)
			(connect_pads
				(clearance 0)
			)
			(min_thickness 0.25)
			(keepout
				(tracks allowed)
				(vias not_allowed)
				(pads allowed)
				(copperpour not_allowed)
				(footprints allowed)
			)
			(placement
				(enabled no)
				(sheetname "")
			)
			(fill
				(thermal_gap 0.5)
				(thermal_bridge_width 0.5)
				(island_removal_mode 0)
			)
			(polygon
				(pts
					(xy 480.177602 -59.026298) (xy 480.177602 -58.518298) (xy 480.558602 -58.518298) (xy 480.558602 -59.026298)
				)
			)
		)
		(zone
			(layer "B.Cu")
			(hatch none 0.5)
			(connect_pads
				(clearance 0)
			)
			(min_thickness 0.25)
			(keepout
				(tracks not_allowed)
				(vias allowed)
				(pads allowed)
				(copperpour not_allowed)
				(footprints allowed)
			)
			(placement
				(enabled no)
				(sheetname "")
			)
			(fill
				(thermal_gap 0.5)
				(thermal_bridge_width 0.5)
				(island_removal_mode 0)
			)
			(polygon
				(pts
					(xy 480.558602 -59.026298) (xy 480.558602 -58.518298) (xy 480.177602 -58.518298) (xy 480.177602 -59.026298)
				)
			)
		)
	)
	(footprint ""
		(layer "B.Cu")
		(at 488.3404 -42.5196 -90)
		(property "Reference" "C1R22"
			(at 0 0 90)
			(layer "B.SilkS")
			(hide yes)
			(effects
				(font
					(size 1.27 1.27)
				)
				(justify mirror)
			)
		)
		(property "Value" ""
			(at 0 0 90)
			(layer "B.Fab")
			(effects
				(font
					(size 1.27 1.27)
				)
				(justify mirror)
			)
		)
		(duplicate_pad_numbers_are_jumpers no)
		(fp_poly
			(pts
				(xy 0.4953 -0.2032) (xy -0.4953 -0.2032) (xy -0.4953 1.6002) (xy 0.4953 1.6002)
			)
			(stroke
				(width 0)
				(type default)
			)
			(fill no)
			(layer "B.CrtYd")
		)
		(fp_line
			(start -0.4953 1.6002)
			(end 0.4953 1.6002)
			(stroke
				(width 0.1)
				(type default)
			)
			(layer "B.Fab")
		)
		(fp_line
			(start 0.4953 1.6002)
			(end 0.4953 -0.2032)
			(stroke
				(width 0.1)
				(type default)
			)
			(layer "B.Fab")
		)
		(fp_line
			(start -0.4953 -0.2032)
			(end -0.4953 1.6002)
			(stroke
				(width 0.1)
				(type default)
			)
			(layer "B.Fab")
		)
		(fp_line
			(start 0.4953 -0.2032)
			(end -0.4953 -0.2032)
			(stroke
				(width 0.1)
				(type default)
			)
			(layer "B.Fab")
		)
		(pad "1" smd rect
			(at 0 0 90)
			(size 0.762 0.889)
			(layers "B.Cu" "B.Mask" "B.Paste")
			(net "P3V3_STBY")
		)
		(pad "2" smd rect
			(at 0 1.397 90)
			(size 0.762 0.889)
			(layers "B.Cu" "B.Mask" "B.Paste")
			(net "GND")
		)
		(zone
			(layer "B.Cu")
			(hatch none 0.5)
			(connect_pads
				(clearance 0)
			)
			(min_thickness 0.25)
			(keepout
				(tracks not_allowed)
				(vias allowed)
				(pads allowed)
				(copperpour not_allowed)
				(footprints allowed)
			)
			(placement
				(enabled no)
				(sheetname "")
			)
			(fill
				(thermal_gap 0.5)
				(thermal_bridge_width 0.5)
				(island_removal_mode 0)
			)
			(polygon
				(pts
					(xy 487.8959 -42.1386) (xy 487.8959 -42.9006) (xy 487.3879 -42.9006) (xy 487.3879 -42.1386)
				)
			)
		)
	)
	(footprint ""
		(layer "B.Cu")
		(at 164.846 -87.757)
		(property "Reference" "R6P8"
			(at 0 0 0)
			(layer "B.SilkS")
			(hide yes)
			(effects
				(font
					(size 1.27 1.27)
				)
				(justify mirror)
			)
		)
		(property "Value" ""
			(at 0 0 0)
			(layer "B.Fab")
			(effects
				(font
					(size 1.27 1.27)
				)
				(justify mirror)
			)
		)
		(duplicate_pad_numbers_are_jumpers no)
		(fp_poly
			(pts
				(xy 0.2794 -0.1016) (xy -0.2794 -0.1016) (xy -0.2794 0.9906) (xy 0.2794 0.9906)
			)
			(stroke
				(width 0)
				(type default)
			)
			(fill no)
			(layer "B.CrtYd")
		)
		(fp_line
			(start -0.2794 -0.1016)
			(end 0.2794 -0.1016)
			(stroke
				(width 0.1)
				(type default)
			)
			(layer "B.Fab")
		)
		(fp_line
			(start -0.2794 0.9906)
			(end -0.2794 -0.1016)
			(stroke
				(width 0.1)
				(type default)
			)
			(layer "B.Fab")
		)
		(fp_line
			(start 0.2794 -0.1016)
			(end 0.2794 0.9906)
			(stroke
				(width 0.1)
				(type default)
			)
			(layer "B.Fab")
		)
		(fp_line
			(start 0.2794 0.9906)
			(end -0.2794 0.9906)
			(stroke
				(width 0.1)
				(type default)
			)
			(layer "B.Fab")
		)
		(pad "1" smd rect
			(at 0 0 180)
			(size 0.508 0.508)
			(layers "B.Cu" "B.Mask" "B.Paste")
			(net "CLK_100M_CPU1_BCLK1_DN")
		)
		(pad "2" smd rect
			(at 0 0.889 180)
			(size 0.508 0.508)
			(layers "B.Cu" "B.Mask" "B.Paste")
			(net "GND")
		)
		(zone
			(layer "B.Cu")
			(hatch none 0.5)
			(connect_pads
				(clearance 0)
			)
			(min_thickness 0.25)
			(keepout
				(tracks allowed)
				(vias not_allowed)
				(pads allowed)
				(copperpour not_allowed)
				(footprints allowed)
			)
			(placement
				(enabled no)
				(sheetname "")
			)
			(fill
				(thermal_gap 0.5)
				(thermal_bridge_width 0.5)
				(island_removal_mode 0)
			)
			(polygon
				(pts
					(xy 165.1 -87.503) (xy 164.592 -87.503) (xy 164.592 -87.122) (xy 165.1 -87.122)
				)
			)
		)
		(zone
			(layer "B.Cu")
			(hatch none 0.5)
			(connect_pads
				(clearance 0)
			)
			(min_thickness 0.25)
			(keepout
				(tracks not_allowed)
				(vias allowed)
				(pads allowed)
				(copperpour not_allowed)
				(footprints allowed)
			)
			(placement
				(enabled no)
				(sheetname "")
			)
			(fill
				(thermal_gap 0.5)
				(thermal_bridge_width 0.5)
				(island_removal_mode 0)
			)
			(polygon
				(pts
					(xy 165.1 -87.122) (xy 164.592 -87.122) (xy 164.592 -87.503) (xy 165.1 -87.503)
				)
			)
		)
	)
	(footprint ""
		(layer "B.Cu")
		(at 352.96729 -77.915516)
		(property "Reference" "C3P31"
			(at 0 0 0)
			(layer "B.SilkS")
			(hide yes)
			(effects
				(font
					(size 1.27 1.27)
				)
				(justify mirror)
			)
		)
		(property "Value" ""
			(at 0 0 0)
			(layer "B.Fab")
			(effects
				(font
					(size 1.27 1.27)
				)
				(justify mirror)
			)
		)
		(duplicate_pad_numbers_are_jumpers no)
		(fp_poly
			(pts
				(xy -0.3048 -0.1016) (xy -0.3048 0.9906) (xy 0.3048 0.9906) (xy 0.3048 -0.1016)
			)
			(stroke
				(width 0)
				(type default)
			)
			(fill no)
			(layer "B.CrtYd")
		)
		(fp_line
			(start -0.3048 -0.1016)
			(end 0.3048 -0.1016)
			(stroke
				(width 0.1)
				(type default)
			)
			(layer "B.Fab")
		)
		(fp_line
			(start -0.3048 0.9906)
			(end -0.3048 -0.1016)
			(stroke
				(width 0.1)
				(type default)
			)
			(layer "B.Fab")
		)
		(fp_line
			(start 0.3048 -0.1016)
			(end 0.3048 0.9906)
			(stroke
				(width 0.1)
				(type default)
			)
			(layer "B.Fab")
		)
		(fp_line
			(start 0.3048 0.9906)
			(end -0.3048 0.9906)
			(stroke
				(width 0.1)
				(type default)
			)
			(layer "B.Fab")
		)
		(pad "1" smd rect
			(at 0 0 180)
			(size 0.508 0.508)
			(layers "B.Cu" "B.Mask" "B.Paste")
			(net "P3E_CPU0_PE1_SS_TXP<5>")
		)
		(pad "2" smd rect
			(at 0 0.889 180)
			(size 0.508 0.508)
			(layers "B.Cu" "B.Mask" "B.Paste")
			(net "P3E_CPU0_PE1_SS_C_TXP<5>")
		)
		(zone
			(layer "B.Cu")
			(hatch none 0.5)
			(connect_pads
				(clearance 0)
			)
			(min_thickness 0.25)
			(keepout
				(tracks allowed)
				(vias not_allowed)
				(pads allowed)
				(copperpour not_allowed)
				(footprints allowed)
			)
			(placement
				(enabled no)
				(sheetname "")
			)
			(fill
				(thermal_gap 0.5)
				(thermal_bridge_width 0.5)
				(island_removal_mode 0)
			)
			(polygon
				(pts
					(xy 353.22129 -77.661516) (xy 352.71329 -77.661516) (xy 352.71329 -77.280516) (xy 353.22129 -77.280516)
				)
			)
		)
		(zone
			(layer "B.Cu")
			(hatch none 0.5)
			(connect_pads
				(clearance 0)
			)
			(min_thickness 0.25)
			(keepout
				(tracks not_allowed)
				(vias allowed)
				(pads allowed)
				(copperpour not_allowed)
				(footprints allowed)
			)
			(placement
				(enabled no)
				(sheetname "")
			)
			(fill
				(thermal_gap 0.5)
				(thermal_bridge_width 0.5)
				(island_removal_mode 0)
			)
			(polygon
				(pts
					(xy 353.22129 -77.280516) (xy 352.71329 -77.280516) (xy 352.71329 -77.661516) (xy 353.22129 -77.661516)
				)
			)
		)
	)
	(footprint ""
		(layer "B.Cu")
		(at 433.84089 -43.70578 90)
		(property "Reference" "R25W155"
			(at 0.8382 -0.67818 90)
			(unlocked yes)
			(layer "B.SilkS")
			(effects
				(font
					(size 0.4064 0.254)
					(thickness 0.1524)
				)
				(justify left mirror)
			)
		)
		(property "Value" ""
			(at 0 0 90)
			(layer "B.Fab")
			(effects
				(font
					(size 1.27 1.27)
				)
				(justify mirror)
			)
		)
		(duplicate_pad_numbers_are_jumpers no)
		(fp_poly
			(pts
				(xy 0.2794 -0.1016) (xy -0.2794 -0.1016) (xy -0.2794 0.9906) (xy 0.2794 0.9906)
			)
			(stroke
				(width 0)
				(type default)
			)
			(fill no)
			(layer "B.CrtYd")
		)
		(fp_line
			(start 0.2794 -0.1016)
			(end 0.2794 0.9906)
			(stroke
				(width 0.1)
				(type default)
			)
			(layer "B.Fab")
		)
		(fp_line
			(start -0.2794 -0.1016)
			(end 0.2794 -0.1016)
			(stroke
				(width 0.1)
				(type default)
			)
			(layer "B.Fab")
		)
		(fp_line
			(start 0.2794 0.9906)
			(end -0.2794 0.9906)
			(stroke
				(width 0.1)
				(type default)
			)
			(layer "B.Fab")
		)
		(fp_line
			(start -0.2794 0.9906)
			(end -0.2794 -0.1016)
			(stroke
				(width 0.1)
				(type default)
			)
			(layer "B.Fab")
		)
		(pad "1" smd rect
			(at 0 0 270)
			(size 0.508 0.508)
			(layers "B.Cu" "B.Mask" "B.Paste")
			(net "PVCCIO_CPU0")
		)
		(pad "2" smd rect
			(at 0 0.889 270)
			(size 0.508 0.508)
			(layers "B.Cu" "B.Mask" "B.Paste")
			(net "PVCCIO_CPU0_R")
		)
		(zone
			(layer "B.Cu")
			(hatch none 0.5)
			(connect_pads
				(clearance 0)
			)
			(min_thickness 0.25)
			(keepout
				(tracks allowed)
				(vias not_allowed)
				(pads allowed)
				(copperpour not_allowed)
				(footprints allowed)
			)
			(placement
				(enabled no)
				(sheetname "")
			)
			(fill
				(thermal_gap 0.5)
				(thermal_bridge_width 0.5)
				(island_removal_mode 0)
			)
			(polygon
				(pts
					(xy 434.09489 -43.95978) (xy 434.09489 -43.45178) (xy 434.47589 -43.45178) (xy 434.47589 -43.95978)
				)
			)
		)
		(zone
			(layer "B.Cu")
			(hatch none 0.5)
			(connect_pads
				(clearance 0)
			)
			(min_thickness 0.25)
			(keepout
				(tracks not_allowed)
				(vias allowed)
				(pads allowed)
				(copperpour not_allowed)
				(footprints allowed)
			)
			(placement
				(enabled no)
				(sheetname "")
			)
			(fill
				(thermal_gap 0.5)
				(thermal_bridge_width 0.5)
				(island_removal_mode 0)
			)
			(polygon
				(pts
					(xy 434.47589 -43.95978) (xy 434.47589 -43.45178) (xy 434.09489 -43.45178) (xy 434.09489 -43.95978)
				)
			)
		)
	)
	(footprint ""
		(layer "B.Cu")
		(at 227.584 -93.345 90)
		(property "Reference" "R5N1"
			(at 0 0 90)
			(layer "B.SilkS")
			(hide yes)
			(effects
				(font
					(size 1.27 1.27)
				)
				(justify mirror)
			)
		)
		(property "Value" ""
			(at 0 0 90)
			(layer "B.Fab")
			(effects
				(font
					(size 1.27 1.27)
				)
				(justify mirror)
			)
		)
		(duplicate_pad_numbers_are_jumpers no)
		(fp_poly
			(pts
				(xy 0.2794 -0.1016) (xy -0.2794 -0.1016) (xy -0.2794 0.9906) (xy 0.2794 0.9906)
			)
			(stroke
				(width 0)
				(type default)
			)
			(fill no)
			(layer "B.CrtYd")
		)
		(fp_line
			(start 0.2794 -0.1016)
			(end 0.2794 0.9906)
			(stroke
				(width 0.1)
				(type default)
			)
			(layer "B.Fab")
		)
		(fp_line
			(start -0.2794 -0.1016)
			(end 0.2794 -0.1016)
			(stroke
				(width 0.1)
				(type default)
			)
			(layer "B.Fab")
		)
		(fp_line
			(start 0.2794 0.9906)
			(end -0.2794 0.9906)
			(stroke
				(width 0.1)
				(type default)
			)
			(layer "B.Fab")
		)
		(fp_line
			(start -0.2794 0.9906)
			(end -0.2794 -0.1016)
			(stroke
				(width 0.1)
				(type default)
			)
			(layer "B.Fab")
		)
		(pad "1" smd rect
			(at 0 0 270)
			(size 0.508 0.508)
			(layers "B.Cu" "B.Mask" "B.Paste")
			(net "P3V3_STBY")
		)
		(pad "2" smd rect
			(at 0 0.889 270)
			(size 0.508 0.508)
			(layers "B.Cu" "B.Mask" "B.Paste")
			(net "FM_CPU0_PKGID0")
		)
		(zone
			(layer "B.Cu")
			(hatch none 0.5)
			(connect_pads
				(clearance 0)
			)
			(min_thickness 0.25)
			(keepout
				(tracks allowed)
				(vias not_allowed)
				(pads allowed)
				(copperpour not_allowed)
				(footprints allowed)
			)
			(placement
				(enabled no)
				(sheetname "")
			)
			(fill
				(thermal_gap 0.5)
				(thermal_bridge_width 0.5)
				(island_removal_mode 0)
			)
			(polygon
				(pts
					(xy 227.838 -93.599) (xy 227.838 -93.091) (xy 228.219 -93.091) (xy 228.219 -93.599)
				)
			)
		)
		(zone
			(layer "B.Cu")
			(hatch none 0.5)
			(connect_pads
				(clearance 0)
			)
			(min_thickness 0.25)
			(keepout
				(tracks not_allowed)
				(vias allowed)
				(pads allowed)
				(copperpour not_allowed)
				(footprints allowed)
			)
			(placement
				(enabled no)
				(sheetname "")
			)
			(fill
				(thermal_gap 0.5)
				(thermal_bridge_width 0.5)
				(island_removal_mode 0)
			)
			(polygon
				(pts
					(xy 228.219 -93.599) (xy 228.219 -93.091) (xy 227.838 -93.091) (xy 227.838 -93.599)
				)
			)
		)
	)
	(footprint ""
		(layer "B.Cu")
		(at 111.000032 -12.954 90)
		(property "Reference" "C5G96"
			(at -1.14681 0.76708 180)
			(unlocked yes)
			(layer "B.SilkS")
			(effects
				(font
					(size 0.7874 0.5842)
					(thickness 0.1524)
				)
				(justify mirror)
			)
		)
		(property "Value" ""
			(at 0 0 90)
			(layer "B.Fab")
			(effects
				(font
					(size 1.27 1.27)
				)
				(justify mirror)
			)
		)
		(duplicate_pad_numbers_are_jumpers no)
		(fp_rect
			(start -0.4953 -0.2032)
			(end 0.4953 1.6002)
			(stroke
				(width 0)
				(type default)
			)
			(fill no)
			(layer "B.CrtYd")
		)
		(fp_line
			(start 0.4953 -0.2032)
			(end -0.4953 -0.2032)
			(stroke
				(width 0.1)
				(type default)
			)
			(layer "B.Fab")
		)
		(fp_line
			(start -0.4953 -0.2032)
			(end -0.4953 1.6002)
			(stroke
				(width 0.1)
				(type default)
			)
			(layer "B.Fab")
		)
		(fp_line
			(start 0.4953 1.6002)
			(end 0.4953 -0.2032)
			(stroke
				(width 0.1)
				(type default)
			)
			(layer "B.Fab")
		)
		(fp_line
			(start -0.4953 1.6002)
			(end 0.4953 1.6002)
			(stroke
				(width 0.1)
				(type default)
			)
			(layer "B.Fab")
		)
		(pad "1" smd rect
			(at 0 0 270)
			(size 0.762 0.889)
			(layers "B.Cu" "B.Mask" "B.Paste")
			(net "PVDDQ_GHJ")
		)
		(pad "2" smd rect
			(at 0 1.397 270)
			(size 0.762 0.889)
			(layers "B.Cu" "B.Mask" "B.Paste")
			(net "GND")
		)
		(zone
			(layer "B.Cu")
			(hatch none 0.5)
			(connect_pads
				(clearance 0)
			)
			(min_thickness 0.25)
			(keepout
				(tracks not_allowed)
				(vias allowed)
				(pads allowed)
				(copperpour not_allowed)
				(footprints allowed)
			)
			(placement
				(enabled no)
				(sheetname "")
			)
			(fill
				(thermal_gap 0.5)
				(thermal_bridge_width 0.5)
				(island_removal_mode 0)
			)
			(polygon
				(pts
					(xy 111.444532 -12.573) (xy 111.952532 -12.573) (xy 111.952532 -13.335) (xy 111.444532 -13.335)
				)
			)
		)
	)
	(footprint ""
		(layer "B.Cu")
		(at 465.641944 -7.48792 180)
		(property "Reference" "C2U21"
			(at 0 0 0)
			(layer "B.SilkS")
			(hide yes)
			(effects
				(font
					(size 1.27 1.27)
				)
				(justify mirror)
			)
		)
		(property "Value" ""
			(at 0 0 0)
			(layer "B.Fab")
			(effects
				(font
					(size 1.27 1.27)
				)
				(justify mirror)
			)
		)
		(duplicate_pad_numbers_are_jumpers no)
		(fp_poly
			(pts
				(xy -0.3048 -0.1016) (xy -0.3048 0.9906) (xy 0.3048 0.9906) (xy 0.3048 -0.1016)
			)
			(stroke
				(width 0)
				(type default)
			)
			(fill no)
			(layer "B.CrtYd")
		)
		(fp_line
			(start 0.3048 0.9906)
			(end -0.3048 0.9906)
			(stroke
				(width 0.1)
				(type default)
			)
			(layer "B.Fab")
		)
		(fp_line
			(start 0.3048 -0.1016)
			(end 0.3048 0.9906)
			(stroke
				(width 0.1)
				(type default)
			)
			(layer "B.Fab")
		)
		(fp_line
			(start -0.3048 0.9906)
			(end -0.3048 -0.1016)
			(stroke
				(width 0.1)
				(type default)
			)
			(layer "B.Fab")
		)
		(fp_line
			(start -0.3048 -0.1016)
			(end 0.3048 -0.1016)
			(stroke
				(width 0.1)
				(type default)
			)
			(layer "B.Fab")
		)
		(pad "1" smd rect
			(at 0 0)
			(size 0.508 0.508)
			(layers "B.Cu" "B.Mask" "B.Paste")
			(net "P3V3")
		)
		(pad "2" smd rect
			(at 0 0.889)
			(size 0.508 0.508)
			(layers "B.Cu" "B.Mask" "B.Paste")
			(net "GND")
		)
		(zone
			(layer "B.Cu")
			(hatch none 0.5)
			(connect_pads
				(clearance 0)
			)
			(min_thickness 0.25)
			(keepout
				(tracks not_allowed)
				(vias allowed)
				(pads allowed)
				(copperpour not_allowed)
				(footprints allowed)
			)
			(placement
				(enabled no)
				(sheetname "")
			)
			(fill
				(thermal_gap 0.5)
				(thermal_bridge_width 0.5)
				(island_removal_mode 0)
			)
			(polygon
				(pts
					(xy 465.387944 -8.12292) (xy 465.895944 -8.12292) (xy 465.895944 -7.74192) (xy 465.387944 -7.74192)
				)
			)
		)
		(zone
			(layer "B.Cu")
			(hatch none 0.5)
			(connect_pads
				(clearance 0)
			)
			(min_thickness 0.25)
			(keepout
				(tracks allowed)
				(vias not_allowed)
				(pads allowed)
				(copperpour not_allowed)
				(footprints allowed)
			)
			(placement
				(enabled no)
				(sheetname "")
			)
			(fill
				(thermal_gap 0.5)
				(thermal_bridge_width 0.5)
				(island_removal_mode 0)
			)
			(polygon
				(pts
					(xy 465.387944 -7.74192) (xy 465.895944 -7.74192) (xy 465.895944 -8.12292) (xy 465.387944 -8.12292)
				)
			)
		)
	)
	(footprint ""
		(layer "B.Cu")
		(at 464.82 -12.319 90)
		(property "Reference" "C2T7"
			(at 0 0 90)
			(layer "B.SilkS")
			(hide yes)
			(effects
				(font
					(size 1.27 1.27)
				)
				(justify mirror)
			)
		)
		(property "Value" ""
			(at 0 0 90)
			(layer "B.Fab")
			(effects
				(font
					(size 1.27 1.27)
				)
				(justify mirror)
			)
		)
		(duplicate_pad_numbers_are_jumpers no)
		(fp_rect
			(start 0.7239 -0.2159)
			(end -0.7239 1.9939)
			(stroke
				(width 0)
				(type default)
			)
			(fill no)
			(layer "B.CrtYd")
		)
		(fp_line
			(start 0.7239 -0.2159)
			(end 0.7239 1.9939)
			(stroke
				(width 0.1)
				(type default)
			)
			(layer "B.Fab")
		)
		(fp_line
			(start -0.7239 -0.2159)
			(end 0.7239 -0.2159)
			(stroke
				(width 0.1)
				(type default)
			)
			(layer "B.Fab")
		)
		(fp_line
			(start 0.7239 1.9939)
			(end -0.7239 1.9939)
			(stroke
				(width 0.1)
				(type default)
			)
			(layer "B.Fab")
		)
		(fp_line
			(start -0.7239 1.9939)
			(end -0.7239 -0.2159)
			(stroke
				(width 0.1)
				(type default)
			)
			(layer "B.Fab")
		)
		(pad "1" smd rect
			(at 0 0 270)
			(size 1.27 1.016)
			(layers "B.Cu" "B.Mask" "B.Paste")
			(net "P3V3_STBY")
		)
		(pad "2" smd rect
			(at 0 1.778 270)
			(size 1.27 1.016)
			(layers "B.Cu" "B.Mask" "B.Paste")
			(net "GND")
		)
		(zone
			(layer "B.Cu")
			(hatch none 0.5)
			(connect_pads
				(clearance 0)
			)
			(min_thickness 0.25)
			(keepout
				(tracks not_allowed)
				(vias allowed)
				(pads allowed)
				(copperpour not_allowed)
				(footprints allowed)
			)
			(placement
				(enabled no)
				(sheetname "")
			)
			(fill
				(thermal_gap 0.5)
				(thermal_bridge_width 0.5)
				(island_removal_mode 0)
			)
			(polygon
				(pts
					(xy 465.328 -12.954) (xy 465.328 -11.684) (xy 466.09 -11.684) (xy 466.09 -12.954)
				)
			)
		)
	)
	(footprint ""
		(layer "B.Cu")
		(at 421.513 -141.9606)
		(property "Reference" "C2L44"
			(at 0 0 0)
			(layer "B.SilkS")
			(hide yes)
			(effects
				(font
					(size 1.27 1.27)
				)
				(justify mirror)
			)
		)
		(property "Value" ""
			(at 0 0 0)
			(layer "B.Fab")
			(effects
				(font
					(size 1.27 1.27)
				)
				(justify mirror)
			)
		)
		(duplicate_pad_numbers_are_jumpers no)
		(fp_poly
			(pts
				(xy -0.3048 -0.1016) (xy -0.3048 0.9906) (xy 0.3048 0.9906) (xy 0.3048 -0.1016)
			)
			(stroke
				(width 0)
				(type default)
			)
			(fill no)
			(layer "B.CrtYd")
		)
		(fp_line
			(start -0.3048 -0.1016)
			(end 0.3048 -0.1016)
			(stroke
				(width 0.1)
				(type default)
			)
			(layer "B.Fab")
		)
		(fp_line
			(start -0.3048 0.9906)
			(end -0.3048 -0.1016)
			(stroke
				(width 0.1)
				(type default)
			)
			(layer "B.Fab")
		)
		(fp_line
			(start 0.3048 -0.1016)
			(end 0.3048 0.9906)
			(stroke
				(width 0.1)
				(type default)
			)
			(layer "B.Fab")
		)
		(fp_line
			(start 0.3048 0.9906)
			(end -0.3048 0.9906)
			(stroke
				(width 0.1)
				(type default)
			)
			(layer "B.Fab")
		)
		(pad "1" smd rect
			(at 0 0 180)
			(size 0.508 0.508)
			(layers "B.Cu" "B.Mask" "B.Paste")
			(net "SATA6G_P1_TX_C_DN")
		)
		(pad "2" smd rect
			(at 0 0.889 180)
			(size 0.508 0.508)
			(layers "B.Cu" "B.Mask" "B.Paste")
			(net "SATA6G_PCH_PCIE_UP_SATA_TXN<1>")
		)
		(zone
			(layer "B.Cu")
			(hatch none 0.5)
			(connect_pads
				(clearance 0)
			)
			(min_thickness 0.25)
			(keepout
				(tracks allowed)
				(vias not_allowed)
				(pads allowed)
				(copperpour not_allowed)
				(footprints allowed)
			)
			(placement
				(enabled no)
				(sheetname "")
			)
			(fill
				(thermal_gap 0.5)
				(thermal_bridge_width 0.5)
				(island_removal_mode 0)
			)
			(polygon
				(pts
					(xy 421.767 -141.7066) (xy 421.259 -141.7066) (xy 421.259 -141.3256) (xy 421.767 -141.3256)
				)
			)
		)
		(zone
			(layer "B.Cu")
			(hatch none 0.5)
			(connect_pads
				(clearance 0)
			)
			(min_thickness 0.25)
			(keepout
				(tracks not_allowed)
				(vias allowed)
				(pads allowed)
				(copperpour not_allowed)
				(footprints allowed)
			)
			(placement
				(enabled no)
				(sheetname "")
			)
			(fill
				(thermal_gap 0.5)
				(thermal_bridge_width 0.5)
				(island_removal_mode 0)
			)
			(polygon
				(pts
					(xy 421.767 -141.3256) (xy 421.259 -141.3256) (xy 421.259 -141.7066) (xy 421.767 -141.7066)
				)
			)
		)
	)
	(footprint ""
		(layer "B.Cu")
		(at 383.73685 -111.85525 180)
		(property "Reference" "C3N3"
			(at 0 0 0)
			(layer "B.SilkS")
			(hide yes)
			(effects
				(font
					(size 1.27 1.27)
				)
				(justify mirror)
			)
		)
		(property "Value" ""
			(at 0 0 0)
			(layer "B.Fab")
			(effects
				(font
					(size 1.27 1.27)
				)
				(justify mirror)
			)
		)
		(duplicate_pad_numbers_are_jumpers no)
		(fp_rect
			(start 0.2794 0.9144)
			(end -0.2794 -0.1143)
			(stroke
				(width 0)
				(type default)
			)
			(fill no)
			(layer "B.CrtYd")
		)
		(fp_line
			(start 0.2794 0.9144)
			(end 0.2794 -0.1143)
			(stroke
				(width 0.1)
				(type default)
			)
			(layer "B.Fab")
		)
		(fp_line
			(start 0.2794 -0.1143)
			(end -0.2794 -0.1143)
			(stroke
				(width 0.1)
				(type default)
			)
			(layer "B.Fab")
		)
		(fp_line
			(start -0.2794 0.9144)
			(end 0.2794 0.9144)
			(stroke
				(width 0.1)
				(type default)
			)
			(layer "B.Fab")
		)
		(fp_line
			(start -0.2794 -0.1143)
			(end -0.2794 0.9144)
			(stroke
				(width 0.1)
				(type default)
			)
			(layer "B.Fab")
		)
		(pad "1" smd custom
			(at 0 0 90)
			(size 0.10414 0.10414)
			(layers "B.Cu" "B.Mask" "B.Paste")
			(net "PVNN_PCH_STBY")
			(options
				(clearance outline)
				(anchor circle)
			)
			(primitives
				(gr_poly
					(pts
						(xy -0.20828 -0.08636) (xy -0.20828 0.08636) (xy -0.08636 0.20828) (xy 0.086614 0.20828) (xy 0.20828 0.086614)
						(xy 0.20828 -0.08636) (xy 0.08636 -0.20828) (xy -0.08636 -0.20828)
					)
					(width 0)
					(fill yes)
				)
			)
		)
		(pad "2" smd custom
			(at 0 0.8001 90)
			(size 0.10414 0.10414)
			(layers "B.Cu" "B.Mask" "B.Paste")
			(net "GND")
			(options
				(clearance outline)
				(anchor circle)
			)
			(primitives
				(gr_poly
					(pts
						(xy -0.20828 -0.08636) (xy -0.20828 0.08636) (xy -0.08636 0.20828) (xy 0.086614 0.20828) (xy 0.20828 0.086614)
						(xy 0.20828 -0.08636) (xy 0.08636 -0.20828) (xy -0.08636 -0.20828)
					)
					(width 0)
					(fill yes)
				)
			)
		)
		(zone
			(layer "B.Cu")
			(hatch none 0.5)
			(connect_pads
				(clearance 0)
			)
			(min_thickness 0.25)
			(keepout
				(tracks allowed)
				(vias not_allowed)
				(pads allowed)
				(copperpour not_allowed)
				(footprints allowed)
			)
			(placement
				(enabled no)
				(sheetname "")
			)
			(fill
				(thermal_gap 0.5)
				(thermal_bridge_width 0.5)
				(island_removal_mode 0)
			)
			(polygon
				(pts
					(xy 383.64922 -112.0648) (xy 383.64922 -112.4458) (xy 383.82448 -112.4458) (xy 383.824734 -112.0648)
				)
			)
		)
		(zone
			(layer "B.Cu")
			(hatch none 0.5)
			(connect_pads
				(clearance 0)
			)
			(min_thickness 0.25)
			(keepout
				(tracks not_allowed)
				(vias allowed)
				(pads allowed)
				(copperpour not_allowed)
				(footprints allowed)
			)
			(placement
				(enabled no)
				(sheetname "")
			)
			(fill
				(thermal_gap 0.5)
				(thermal_bridge_width 0.5)
				(island_removal_mode 0)
			)
			(polygon
				(pts
					(xy 383.64922 -112.0648) (xy 383.64922 -112.4458) (xy 383.82448 -112.4458) (xy 383.824734 -112.0648)
				)
			)
		)
	)
	(footprint ""
		(layer "B.Cu")
		(at 413.0294 -94.0308 180)
		(property "Reference" "R7G7"
			(at 0 0 0)
			(layer "B.SilkS")
			(hide yes)
			(effects
				(font
					(size 1.27 1.27)
				)
				(justify mirror)
			)
		)
		(property "Value" ""
			(at 0 0 0)
			(layer "B.Fab")
			(effects
				(font
					(size 1.27 1.27)
				)
				(justify mirror)
			)
		)
		(duplicate_pad_numbers_are_jumpers no)
		(fp_poly
			(pts
				(xy 0.2794 -0.1016) (xy -0.2794 -0.1016) (xy -0.2794 0.9906) (xy 0.2794 0.9906)
			)
			(stroke
				(width 0)
				(type default)
			)
			(fill no)
			(layer "B.CrtYd")
		)
		(fp_line
			(start 0.2794 0.9906)
			(end -0.2794 0.9906)
			(stroke
				(width 0.1)
				(type default)
			)
			(layer "B.Fab")
		)
		(fp_line
			(start 0.2794 -0.1016)
			(end 0.2794 0.9906)
			(stroke
				(width 0.1)
				(type default)
			)
			(layer "B.Fab")
		)
		(fp_line
			(start -0.2794 0.9906)
			(end -0.2794 -0.1016)
			(stroke
				(width 0.1)
				(type default)
			)
			(layer "B.Fab")
		)
		(fp_line
			(start -0.2794 -0.1016)
			(end 0.2794 -0.1016)
			(stroke
				(width 0.1)
				(type default)
			)
			(layer "B.Fab")
		)
		(pad "1" smd rect
			(at 0 0)
			(size 0.508 0.508)
			(layers "B.Cu" "B.Mask" "B.Paste")
			(net "P3V3")
		)
		(pad "2" smd rect
			(at 0 0.889)
			(size 0.508 0.508)
			(layers "B.Cu" "B.Mask" "B.Paste")
			(net "H_CPU0_MEMABC_MEMHOT")
		)
		(zone
			(layer "B.Cu")
			(hatch none 0.5)
			(connect_pads
				(clearance 0)
			)
			(min_thickness 0.25)
			(keepout
				(tracks not_allowed)
				(vias allowed)
				(pads allowed)
				(copperpour not_allowed)
				(footprints allowed)
			)
			(placement
				(enabled no)
				(sheetname "")
			)
			(fill
				(thermal_gap 0.5)
				(thermal_bridge_width 0.5)
				(island_removal_mode 0)
			)
			(polygon
				(pts
					(xy 412.7754 -94.6658) (xy 413.2834 -94.6658) (xy 413.2834 -94.2848) (xy 412.7754 -94.2848)
				)
			)
		)
		(zone
			(layer "B.Cu")
			(hatch none 0.5)
			(connect_pads
				(clearance 0)
			)
			(min_thickness 0.25)
			(keepout
				(tracks allowed)
				(vias not_allowed)
				(pads allowed)
				(copperpour not_allowed)
				(footprints allowed)
			)
			(placement
				(enabled no)
				(sheetname "")
			)
			(fill
				(thermal_gap 0.5)
				(thermal_bridge_width 0.5)
				(island_removal_mode 0)
			)
			(polygon
				(pts
					(xy 412.7754 -94.2848) (xy 413.2834 -94.2848) (xy 413.2834 -94.6658) (xy 412.7754 -94.6658)
				)
			)
		)
	)
	(footprint ""
		(layer "B.Cu")
		(at -3.0861 -14.08684 -90)
		(property "Reference" "C22W3"
			(at 0 0 90)
			(layer "B.SilkS")
			(hide yes)
			(effects
				(font
					(size 1.27 1.27)
				)
				(justify mirror)
			)
		)
		(property "Value" "*"
			(at 0.0762 -6.2357 270)
			(unlocked yes)
			(layer "B.Fab")
			(hide yes)
			(effects
				(font
					(size 1.27 1.016)
					(thickness 0.1524)
				)
				(justify mirror)
			)
		)
		(property "Device Type" "SC22U16V5MX-4-GP_SMD-BCG5-SC22A"
			(at 0.0762 -8.2677 270)
			(unlocked yes)
			(layer "B.Fab")
			(hide yes)
			(effects
				(font
					(size 1.27 1.016)
					(thickness 0.1524)
				)
				(justify mirror)
			)
		)
		(duplicate_pad_numbers_are_jumpers no)
		(fp_line
			(start -0.635 0)
			(end 0.635 0)
			(stroke
				(width 0.508)
				(type default)
			)
			(layer "B.SilkS")
		)
		(fp_rect
			(start 0.9652 1.778)
			(end -0.9652 -1.778)
			(stroke
				(width 0)
				(type default)
			)
			(fill no)
			(layer "B.CrtYd")
		)
		(fp_poly
			(pts
				(xy 0.9652 -1.778) (xy -0.9652 -1.778) (xy -0.9652 1.778) (xy 0.9652 1.778)
			)
			(stroke
				(width 0)
				(type default)
			)
			(fill no)
			(layer "B.Fab")
		)
		(pad "1" smd rect
			(at 0 -0.9652 90)
			(size 1.397 1.143)
			(layers "B.Cu" "B.Mask" "B.Paste")
			(net "VR_FET_SW_P12V_STBY_PVDDQ_GHJ")
		)
		(pad "2" smd rect
			(at 0 0.9652 90)
			(size 1.397 1.143)
			(layers "B.Cu" "B.Mask" "B.Paste")
			(net "GND")
		)
	)
	(footprint ""
		(layer "B.Cu")
		(at 399.737834 -25.690068 90)
		(property "Reference" "R1U47"
			(at 0 0 90)
			(layer "B.SilkS")
			(hide yes)
			(effects
				(font
					(size 1.27 1.27)
				)
				(justify mirror)
			)
		)
		(property "Value" ""
			(at 0 0 90)
			(layer "B.Fab")
			(effects
				(font
					(size 1.27 1.27)
				)
				(justify mirror)
			)
		)
		(duplicate_pad_numbers_are_jumpers no)
		(fp_poly
			(pts
				(xy 0.2794 -0.1016) (xy -0.2794 -0.1016) (xy -0.2794 0.9906) (xy 0.2794 0.9906)
			)
			(stroke
				(width 0)
				(type default)
			)
			(fill no)
			(layer "B.CrtYd")
		)
		(fp_line
			(start 0.2794 -0.1016)
			(end 0.2794 0.9906)
			(stroke
				(width 0.1)
				(type default)
			)
			(layer "B.Fab")
		)
		(fp_line
			(start -0.2794 -0.1016)
			(end 0.2794 -0.1016)
			(stroke
				(width 0.1)
				(type default)
			)
			(layer "B.Fab")
		)
		(fp_line
			(start 0.2794 0.9906)
			(end -0.2794 0.9906)
			(stroke
				(width 0.1)
				(type default)
			)
			(layer "B.Fab")
		)
		(fp_line
			(start -0.2794 0.9906)
			(end -0.2794 -0.1016)
			(stroke
				(width 0.1)
				(type default)
			)
			(layer "B.Fab")
		)
		(pad "1" smd rect
			(at 0 0 270)
			(size 0.508 0.508)
			(layers "B.Cu" "B.Mask" "B.Paste")
			(net "P5V_STBY")
		)
		(pad "2" smd rect
			(at 0 0.889 270)
			(size 0.508 0.508)
			(layers "B.Cu" "B.Mask" "B.Paste")
			(net "A_P5V_STBY_SCALED")
		)
		(zone
			(layer "B.Cu")
			(hatch none 0.5)
			(connect_pads
				(clearance 0)
			)
			(min_thickness 0.25)
			(keepout
				(tracks allowed)
				(vias not_allowed)
				(pads allowed)
				(copperpour not_allowed)
				(footprints allowed)
			)
			(placement
				(enabled no)
				(sheetname "")
			)
			(fill
				(thermal_gap 0.5)
				(thermal_bridge_width 0.5)
				(island_removal_mode 0)
			)
			(polygon
				(pts
					(xy 399.991834 -25.944068) (xy 399.991834 -25.436068) (xy 400.372834 -25.436068) (xy 400.372834 -25.944068)
				)
			)
		)
		(zone
			(layer "B.Cu")
			(hatch none 0.5)
			(connect_pads
				(clearance 0)
			)
			(min_thickness 0.25)
			(keepout
				(tracks not_allowed)
				(vias allowed)
				(pads allowed)
				(copperpour not_allowed)
				(footprints allowed)
			)
			(placement
				(enabled no)
				(sheetname "")
			)
			(fill
				(thermal_gap 0.5)
				(thermal_bridge_width 0.5)
				(island_removal_mode 0)
			)
			(polygon
				(pts
					(xy 400.372834 -25.944068) (xy 400.372834 -25.436068) (xy 399.991834 -25.436068) (xy 399.991834 -25.944068)
				)
			)
		)
	)
	(footprint ""
		(layer "B.Cu")
		(at 168.148 -123.19 180)
		(property "Reference" "R6M9"
			(at 0 0 0)
			(layer "B.SilkS")
			(hide yes)
			(effects
				(font
					(size 1.27 1.27)
				)
				(justify mirror)
			)
		)
		(property "Value" ""
			(at 0 0 0)
			(layer "B.Fab")
			(effects
				(font
					(size 1.27 1.27)
				)
				(justify mirror)
			)
		)
		(duplicate_pad_numbers_are_jumpers no)
		(fp_poly
			(pts
				(xy 0.2794 -0.1016) (xy -0.2794 -0.1016) (xy -0.2794 0.9906) (xy 0.2794 0.9906)
			)
			(stroke
				(width 0)
				(type default)
			)
			(fill no)
			(layer "B.CrtYd")
		)
		(fp_line
			(start 0.2794 0.9906)
			(end -0.2794 0.9906)
			(stroke
				(width 0.1)
				(type default)
			)
			(layer "B.Fab")
		)
		(fp_line
			(start 0.2794 -0.1016)
			(end 0.2794 0.9906)
			(stroke
				(width 0.1)
				(type default)
			)
			(layer "B.Fab")
		)
		(fp_line
			(start -0.2794 0.9906)
			(end -0.2794 -0.1016)
			(stroke
				(width 0.1)
				(type default)
			)
			(layer "B.Fab")
		)
		(fp_line
			(start -0.2794 -0.1016)
			(end 0.2794 -0.1016)
			(stroke
				(width 0.1)
				(type default)
			)
			(layer "B.Fab")
		)
		(pad "1" smd rect
			(at 0 0)
			(size 0.508 0.508)
			(layers "B.Cu" "B.Mask" "B.Paste")
			(net "PVPP_KLM")
		)
		(pad "2" smd rect
			(at 0 0.889)
			(size 0.508 0.508)
			(layers "B.Cu" "B.Mask" "B.Paste")
			(net "RST_CD_CPU1_POR_N")
		)
		(zone
			(layer "B.Cu")
			(hatch none 0.5)
			(connect_pads
				(clearance 0)
			)
			(min_thickness 0.25)
			(keepout
				(tracks not_allowed)
				(vias allowed)
				(pads allowed)
				(copperpour not_allowed)
				(footprints allowed)
			)
			(placement
				(enabled no)
				(sheetname "")
			)
			(fill
				(thermal_gap 0.5)
				(thermal_bridge_width 0.5)
				(island_removal_mode 0)
			)
			(polygon
				(pts
					(xy 167.894 -123.825) (xy 168.402 -123.825) (xy 168.402 -123.444) (xy 167.894 -123.444)
				)
			)
		)
		(zone
			(layer "B.Cu")
			(hatch none 0.5)
			(connect_pads
				(clearance 0)
			)
			(min_thickness 0.25)
			(keepout
				(tracks allowed)
				(vias not_allowed)
				(pads allowed)
				(copperpour not_allowed)
				(footprints allowed)
			)
			(placement
				(enabled no)
				(sheetname "")
			)
			(fill
				(thermal_gap 0.5)
				(thermal_bridge_width 0.5)
				(island_removal_mode 0)
			)
			(polygon
				(pts
					(xy 167.894 -123.444) (xy 168.402 -123.444) (xy 168.402 -123.825) (xy 167.894 -123.825)
				)
			)
		)
	)
	(footprint ""
		(layer "B.Cu")
		(at 252.1585 -12.954 -90)
		(property "Reference" "C5G43"
			(at -1.14681 0.76708 0)
			(unlocked yes)
			(layer "B.SilkS")
			(effects
				(font
					(size 0.7874 0.5842)
					(thickness 0.1524)
				)
				(justify mirror)
			)
		)
		(property "Value" ""
			(at 0 0 90)
			(layer "B.Fab")
			(effects
				(font
					(size 1.27 1.27)
				)
				(justify mirror)
			)
		)
		(duplicate_pad_numbers_are_jumpers no)
		(fp_rect
			(start 0.4953 1.6002)
			(end -0.4953 -0.2032)
			(stroke
				(width 0)
				(type default)
			)
			(fill no)
			(layer "B.CrtYd")
		)
		(fp_line
			(start -0.4953 1.6002)
			(end 0.4953 1.6002)
			(stroke
				(width 0.1)
				(type default)
			)
			(layer "B.Fab")
		)
		(fp_line
			(start 0.4953 1.6002)
			(end 0.4953 -0.2032)
			(stroke
				(width 0.1)
				(type default)
			)
			(layer "B.Fab")
		)
		(fp_line
			(start -0.4953 -0.2032)
			(end -0.4953 1.6002)
			(stroke
				(width 0.1)
				(type default)
			)
			(layer "B.Fab")
		)
		(fp_line
			(start 0.4953 -0.2032)
			(end -0.4953 -0.2032)
			(stroke
				(width 0.1)
				(type default)
			)
			(layer "B.Fab")
		)
		(pad "1" smd rect
			(at 0 0 90)
			(size 0.762 0.889)
			(layers "B.Cu" "B.Mask" "B.Paste")
			(net "PVDDQ_ABC")
		)
		(pad "2" smd rect
			(at 0 1.397 90)
			(size 0.762 0.889)
			(layers "B.Cu" "B.Mask" "B.Paste")
			(net "GND")
		)
		(zone
			(layer "B.Cu")
			(hatch none 0.5)
			(connect_pads
				(clearance 0)
			)
			(min_thickness 0.25)
			(keepout
				(tracks not_allowed)
				(vias allowed)
				(pads allowed)
				(copperpour not_allowed)
				(footprints allowed)
			)
			(placement
				(enabled no)
				(sheetname "")
			)
			(fill
				(thermal_gap 0.5)
				(thermal_bridge_width 0.5)
				(island_removal_mode 0)
			)
			(polygon
				(pts
					(xy 251.206 -12.573) (xy 251.714 -12.573) (xy 251.714 -13.335) (xy 251.206 -13.335)
				)
			)
		)
	)
	(footprint ""
		(layer "B.Cu")
		(at 349.0214 -155.7274 -90)
		(property "Reference" "R3L6"
			(at 0 0 90)
			(layer "B.SilkS")
			(hide yes)
			(effects
				(font
					(size 1.27 1.27)
				)
				(justify mirror)
			)
		)
		(property "Value" ""
			(at 0 0 90)
			(layer "B.Fab")
			(effects
				(font
					(size 1.27 1.27)
				)
				(justify mirror)
			)
		)
		(duplicate_pad_numbers_are_jumpers no)
		(fp_poly
			(pts
				(xy 0.2794 -0.1016) (xy -0.2794 -0.1016) (xy -0.2794 0.9906) (xy 0.2794 0.9906)
			)
			(stroke
				(width 0)
				(type default)
			)
			(fill no)
			(layer "B.CrtYd")
		)
		(fp_line
			(start -0.2794 0.9906)
			(end -0.2794 -0.1016)
			(stroke
				(width 0.1)
				(type default)
			)
			(layer "B.Fab")
		)
		(fp_line
			(start 0.2794 0.9906)
			(end -0.2794 0.9906)
			(stroke
				(width 0.1)
				(type default)
			)
			(layer "B.Fab")
		)
		(fp_line
			(start -0.2794 -0.1016)
			(end 0.2794 -0.1016)
			(stroke
				(width 0.1)
				(type default)
			)
			(layer "B.Fab")
		)
		(fp_line
			(start 0.2794 -0.1016)
			(end 0.2794 0.9906)
			(stroke
				(width 0.1)
				(type default)
			)
			(layer "B.Fab")
		)
		(pad "1" smd rect
			(at 0 0 90)
			(size 0.508 0.508)
			(layers "B.Cu" "B.Mask" "B.Paste")
			(net "VR_PVDDQ_DEF_PH1_VCIN")
		)
		(pad "2" smd rect
			(at 0 0.889 90)
			(size 0.508 0.508)
			(layers "B.Cu" "B.Mask" "B.Paste")
			(net "P5V_STBY")
		)
		(zone
			(layer "B.Cu")
			(hatch none 0.5)
			(connect_pads
				(clearance 0)
			)
			(min_thickness 0.25)
			(keepout
				(tracks not_allowed)
				(vias allowed)
				(pads allowed)
				(copperpour not_allowed)
				(footprints allowed)
			)
			(placement
				(enabled no)
				(sheetname "")
			)
			(fill
				(thermal_gap 0.5)
				(thermal_bridge_width 0.5)
				(island_removal_mode 0)
			)
			(polygon
				(pts
					(xy 348.3864 -155.4734) (xy 348.3864 -155.9814) (xy 348.7674 -155.9814) (xy 348.7674 -155.4734)
				)
			)
		)
		(zone
			(layer "B.Cu")
			(hatch none 0.5)
			(connect_pads
				(clearance 0)
			)
			(min_thickness 0.25)
			(keepout
				(tracks allowed)
				(vias not_allowed)
				(pads allowed)
				(copperpour not_allowed)
				(footprints allowed)
			)
			(placement
				(enabled no)
				(sheetname "")
			)
			(fill
				(thermal_gap 0.5)
				(thermal_bridge_width 0.5)
				(island_removal_mode 0)
			)
			(polygon
				(pts
					(xy 348.7674 -155.4734) (xy 348.7674 -155.9814) (xy 348.3864 -155.9814) (xy 348.3864 -155.4734)
				)
			)
		)
	)
	(footprint ""
		(layer "B.Cu")
		(at 477.634554 -2.513838 -90)
		(property "Reference" "C9G12"
			(at 0 0 90)
			(layer "B.SilkS")
			(hide yes)
			(effects
				(font
					(size 1.27 1.27)
				)
				(justify mirror)
			)
		)
		(property "Value" ""
			(at 0 0 90)
			(layer "B.Fab")
			(effects
				(font
					(size 1.27 1.27)
				)
				(justify mirror)
			)
		)
		(duplicate_pad_numbers_are_jumpers no)
		(fp_poly
			(pts
				(xy -0.3048 -0.1016) (xy -0.3048 0.9906) (xy 0.3048 0.9906) (xy 0.3048 -0.1016)
			)
			(stroke
				(width 0)
				(type default)
			)
			(fill no)
			(layer "B.CrtYd")
		)
		(fp_line
			(start -0.3048 0.9906)
			(end -0.3048 -0.1016)
			(stroke
				(width 0.1)
				(type default)
			)
			(layer "B.Fab")
		)
		(fp_line
			(start 0.3048 0.9906)
			(end -0.3048 0.9906)
			(stroke
				(width 0.1)
				(type default)
			)
			(layer "B.Fab")
		)
		(fp_line
			(start -0.3048 -0.1016)
			(end 0.3048 -0.1016)
			(stroke
				(width 0.1)
				(type default)
			)
			(layer "B.Fab")
		)
		(fp_line
			(start 0.3048 -0.1016)
			(end 0.3048 0.9906)
			(stroke
				(width 0.1)
				(type default)
			)
			(layer "B.Fab")
		)
		(pad "1" smd rect
			(at 0 0 90)
			(size 0.508 0.508)
			(layers "B.Cu" "B.Mask" "B.Paste")
			(net "NIC_SER_N_MDI_3_DN")
		)
		(pad "2" smd rect
			(at 0 0.889 90)
			(size 0.508 0.508)
			(layers "B.Cu" "B.Mask" "B.Paste")
			(net "NIC_MDI_MNG_RX_DN")
		)
		(zone
			(layer "B.Cu")
			(hatch none 0.5)
			(connect_pads
				(clearance 0)
			)
			(min_thickness 0.25)
			(keepout
				(tracks not_allowed)
				(vias allowed)
				(pads allowed)
				(copperpour not_allowed)
				(footprints allowed)
			)
			(placement
				(enabled no)
				(sheetname "")
			)
			(fill
				(thermal_gap 0.5)
				(thermal_bridge_width 0.5)
				(island_removal_mode 0)
			)
			(polygon
				(pts
					(xy 476.999554 -2.259838) (xy 476.999554 -2.767838) (xy 477.380554 -2.767838) (xy 477.380554 -2.259838)
				)
			)
		)
		(zone
			(layer "B.Cu")
			(hatch none 0.5)
			(connect_pads
				(clearance 0)
			)
			(min_thickness 0.25)
			(keepout
				(tracks allowed)
				(vias not_allowed)
				(pads allowed)
				(copperpour not_allowed)
				(footprints allowed)
			)
			(placement
				(enabled no)
				(sheetname "")
			)
			(fill
				(thermal_gap 0.5)
				(thermal_bridge_width 0.5)
				(island_removal_mode 0)
			)
			(polygon
				(pts
					(xy 477.380554 -2.259838) (xy 477.380554 -2.767838) (xy 476.999554 -2.767838) (xy 476.999554 -2.259838)
				)
			)
		)
	)
	(footprint ""
		(layer "B.Cu")
		(at 318.9732 -34.2138 -90)
		(property "Reference" "R4T1"
			(at 0 0 90)
			(layer "B.SilkS")
			(hide yes)
			(effects
				(font
					(size 1.27 1.27)
				)
				(justify mirror)
			)
		)
		(property "Value" ""
			(at 0 0 90)
			(layer "B.Fab")
			(effects
				(font
					(size 1.27 1.27)
				)
				(justify mirror)
			)
		)
		(duplicate_pad_numbers_are_jumpers no)
		(fp_poly
			(pts
				(xy 0.2794 -0.1016) (xy -0.2794 -0.1016) (xy -0.2794 0.9906) (xy 0.2794 0.9906)
			)
			(stroke
				(width 0)
				(type default)
			)
			(fill no)
			(layer "B.CrtYd")
		)
		(fp_line
			(start -0.2794 0.9906)
			(end -0.2794 -0.1016)
			(stroke
				(width 0.1)
				(type default)
			)
			(layer "B.Fab")
		)
		(fp_line
			(start 0.2794 0.9906)
			(end -0.2794 0.9906)
			(stroke
				(width 0.1)
				(type default)
			)
			(layer "B.Fab")
		)
		(fp_line
			(start -0.2794 -0.1016)
			(end 0.2794 -0.1016)
			(stroke
				(width 0.1)
				(type default)
			)
			(layer "B.Fab")
		)
		(fp_line
			(start 0.2794 -0.1016)
			(end 0.2794 0.9906)
			(stroke
				(width 0.1)
				(type default)
			)
			(layer "B.Fab")
		)
		(pad "1" smd rect
			(at 0 0 90)
			(size 0.508 0.508)
			(layers "B.Cu" "B.Mask" "B.Paste")
			(net "FM_ADR_COMPLETE_DLY")
		)
		(pad "2" smd rect
			(at 0 0.889 90)
			(size 0.508 0.508)
			(layers "B.Cu" "B.Mask" "B.Paste")
			(net "FM_ADR_COMPLETE_R")
		)
		(zone
			(layer "B.Cu")
			(hatch none 0.5)
			(connect_pads
				(clearance 0)
			)
			(min_thickness 0.25)
			(keepout
				(tracks not_allowed)
				(vias allowed)
				(pads allowed)
				(copperpour not_allowed)
				(footprints allowed)
			)
			(placement
				(enabled no)
				(sheetname "")
			)
			(fill
				(thermal_gap 0.5)
				(thermal_bridge_width 0.5)
				(island_removal_mode 0)
			)
			(polygon
				(pts
					(xy 318.3382 -33.9598) (xy 318.3382 -34.4678) (xy 318.7192 -34.4678) (xy 318.7192 -33.9598)
				)
			)
		)
		(zone
			(layer "B.Cu")
			(hatch none 0.5)
			(connect_pads
				(clearance 0)
			)
			(min_thickness 0.25)
			(keepout
				(tracks allowed)
				(vias not_allowed)
				(pads allowed)
				(copperpour not_allowed)
				(footprints allowed)
			)
			(placement
				(enabled no)
				(sheetname "")
			)
			(fill
				(thermal_gap 0.5)
				(thermal_bridge_width 0.5)
				(island_removal_mode 0)
			)
			(polygon
				(pts
					(xy 318.7192 -33.9598) (xy 318.7192 -34.4678) (xy 318.3382 -34.4678) (xy 318.3382 -33.9598)
				)
			)
		)
	)
	(footprint ""
		(layer "B.Cu")
		(at 195.453 -8.122412 90)
		(property "Reference" "C6U9"
			(at 0 0 90)
			(layer "B.SilkS")
			(hide yes)
			(effects
				(font
					(size 1.27 1.27)
				)
				(justify mirror)
			)
		)
		(property "Value" ""
			(at 0 0 90)
			(layer "B.Fab")
			(effects
				(font
					(size 1.27 1.27)
				)
				(justify mirror)
			)
		)
		(duplicate_pad_numbers_are_jumpers no)
		(fp_poly
			(pts
				(xy -0.3048 -0.1016) (xy -0.3048 0.9906) (xy 0.3048 0.9906) (xy 0.3048 -0.1016)
			)
			(stroke
				(width 0)
				(type default)
			)
			(fill no)
			(layer "B.CrtYd")
		)
		(fp_line
			(start 0.3048 -0.1016)
			(end 0.3048 0.9906)
			(stroke
				(width 0.1)
				(type default)
			)
			(layer "B.Fab")
		)
		(fp_line
			(start -0.3048 -0.1016)
			(end 0.3048 -0.1016)
			(stroke
				(width 0.1)
				(type default)
			)
			(layer "B.Fab")
		)
		(fp_line
			(start 0.3048 0.9906)
			(end -0.3048 0.9906)
			(stroke
				(width 0.1)
				(type default)
			)
			(layer "B.Fab")
		)
		(fp_line
			(start -0.3048 0.9906)
			(end -0.3048 -0.1016)
			(stroke
				(width 0.1)
				(type default)
			)
			(layer "B.Fab")
		)
		(pad "1" smd rect
			(at 0 0 270)
			(size 0.508 0.508)
			(layers "B.Cu" "B.Mask" "B.Paste")
			(net "M_B_VREF")
		)
		(pad "2" smd rect
			(at 0 0.889 270)
			(size 0.508 0.508)
			(layers "B.Cu" "B.Mask" "B.Paste")
			(net "GND")
		)
		(zone
			(layer "B.Cu")
			(hatch none 0.5)
			(connect_pads
				(clearance 0)
			)
			(min_thickness 0.25)
			(keepout
				(tracks allowed)
				(vias not_allowed)
				(pads allowed)
				(copperpour not_allowed)
				(footprints allowed)
			)
			(placement
				(enabled no)
				(sheetname "")
			)
			(fill
				(thermal_gap 0.5)
				(thermal_bridge_width 0.5)
				(island_removal_mode 0)
			)
			(polygon
				(pts
					(xy 195.707 -8.376412) (xy 195.707 -7.868412) (xy 196.088 -7.868412) (xy 196.088 -8.376412)
				)
			)
		)
		(zone
			(layer "B.Cu")
			(hatch none 0.5)
			(connect_pads
				(clearance 0)
			)
			(min_thickness 0.25)
			(keepout
				(tracks not_allowed)
				(vias allowed)
				(pads allowed)
				(copperpour not_allowed)
				(footprints allowed)
			)
			(placement
				(enabled no)
				(sheetname "")
			)
			(fill
				(thermal_gap 0.5)
				(thermal_bridge_width 0.5)
				(island_removal_mode 0)
			)
			(polygon
				(pts
					(xy 196.088 -8.376412) (xy 196.088 -7.868412) (xy 195.707 -7.868412) (xy 195.707 -8.376412)
				)
			)
		)
	)
	(footprint ""
		(layer "B.Cu")
		(at 192.024 -134.874 180)
		(property "Reference" "C6M2"
			(at 0 0 0)
			(layer "B.SilkS")
			(hide yes)
			(effects
				(font
					(size 1.27 1.27)
				)
				(justify mirror)
			)
		)
		(property "Value" ""
			(at 0 0 0)
			(layer "B.Fab")
			(effects
				(font
					(size 1.27 1.27)
				)
				(justify mirror)
			)
		)
		(duplicate_pad_numbers_are_jumpers no)
		(fp_poly
			(pts
				(xy -0.3048 -0.1016) (xy -0.3048 0.9906) (xy 0.3048 0.9906) (xy 0.3048 -0.1016)
			)
			(stroke
				(width 0)
				(type default)
			)
			(fill no)
			(layer "B.CrtYd")
		)
		(fp_line
			(start 0.3048 0.9906)
			(end -0.3048 0.9906)
			(stroke
				(width 0.1)
				(type default)
			)
			(layer "B.Fab")
		)
		(fp_line
			(start 0.3048 -0.1016)
			(end 0.3048 0.9906)
			(stroke
				(width 0.1)
				(type default)
			)
			(layer "B.Fab")
		)
		(fp_line
			(start -0.3048 0.9906)
			(end -0.3048 -0.1016)
			(stroke
				(width 0.1)
				(type default)
			)
			(layer "B.Fab")
		)
		(fp_line
			(start -0.3048 -0.1016)
			(end 0.3048 -0.1016)
			(stroke
				(width 0.1)
				(type default)
			)
			(layer "B.Fab")
		)
		(pad "1" smd rect
			(at 0 0)
			(size 0.508 0.508)
			(layers "B.Cu" "B.Mask" "B.Paste")
			(net "M_D_CPU_VREF")
		)
		(pad "2" smd rect
			(at 0 0.889)
			(size 0.508 0.508)
			(layers "B.Cu" "B.Mask" "B.Paste")
			(net "GND")
		)
		(zone
			(layer "B.Cu")
			(hatch none 0.5)
			(connect_pads
				(clearance 0)
			)
			(min_thickness 0.25)
			(keepout
				(tracks not_allowed)
				(vias allowed)
				(pads allowed)
				(copperpour not_allowed)
				(footprints allowed)
			)
			(placement
				(enabled no)
				(sheetname "")
			)
			(fill
				(thermal_gap 0.5)
				(thermal_bridge_width 0.5)
				(island_removal_mode 0)
			)
			(polygon
				(pts
					(xy 191.77 -135.509) (xy 192.278 -135.509) (xy 192.278 -135.128) (xy 191.77 -135.128)
				)
			)
		)
		(zone
			(layer "B.Cu")
			(hatch none 0.5)
			(connect_pads
				(clearance 0)
			)
			(min_thickness 0.25)
			(keepout
				(tracks allowed)
				(vias not_allowed)
				(pads allowed)
				(copperpour not_allowed)
				(footprints allowed)
			)
			(placement
				(enabled no)
				(sheetname "")
			)
			(fill
				(thermal_gap 0.5)
				(thermal_bridge_width 0.5)
				(island_removal_mode 0)
			)
			(polygon
				(pts
					(xy 191.77 -135.128) (xy 192.278 -135.128) (xy 192.278 -135.509) (xy 191.77 -135.509)
				)
			)
		)
	)
	(footprint ""
		(layer "B.Cu")
		(at 371.545358 -75.494388)
		(property "Reference" "C2P7"
			(at 0 0 0)
			(layer "B.SilkS")
			(hide yes)
			(effects
				(font
					(size 1.27 1.27)
				)
				(justify mirror)
			)
		)
		(property "Value" ""
			(at 0 0 0)
			(layer "B.Fab")
			(effects
				(font
					(size 1.27 1.27)
				)
				(justify mirror)
			)
		)
		(duplicate_pad_numbers_are_jumpers no)
		(fp_rect
			(start 0.2794 0.9144)
			(end -0.2794 -0.1143)
			(stroke
				(width 0)
				(type default)
			)
			(fill no)
			(layer "B.CrtYd")
		)
		(fp_line
			(start -0.2794 -0.1143)
			(end -0.2794 0.9144)
			(stroke
				(width 0.1)
				(type default)
			)
			(layer "B.Fab")
		)
		(fp_line
			(start -0.2794 0.9144)
			(end 0.2794 0.9144)
			(stroke
				(width 0.1)
				(type default)
			)
			(layer "B.Fab")
		)
		(fp_line
			(start 0.2794 -0.1143)
			(end -0.2794 -0.1143)
			(stroke
				(width 0.1)
				(type default)
			)
			(layer "B.Fab")
		)
		(fp_line
			(start 0.2794 0.9144)
			(end 0.2794 -0.1143)
			(stroke
				(width 0.1)
				(type default)
			)
			(layer "B.Fab")
		)
		(pad "1" smd custom
			(at 0 0 270)
			(size 0.10414 0.10414)
			(layers "B.Cu" "B.Mask" "B.Paste")
			(net "P3V3_STBY")
			(options
				(clearance outline)
				(anchor circle)
			)
			(primitives
				(gr_poly
					(pts
						(xy -0.20828 -0.08636) (xy -0.20828 0.08636) (xy -0.08636 0.20828) (xy 0.086614 0.20828) (xy 0.20828 0.086614)
						(xy 0.20828 -0.08636) (xy 0.08636 -0.20828) (xy -0.08636 -0.20828)
					)
					(width 0)
					(fill yes)
				)
			)
		)
		(pad "2" smd custom
			(at 0 0.8001 270)
			(size 0.10414 0.10414)
			(layers "B.Cu" "B.Mask" "B.Paste")
			(net "GND")
			(options
				(clearance outline)
				(anchor circle)
			)
			(primitives
				(gr_poly
					(pts
						(xy -0.20828 -0.08636) (xy -0.20828 0.08636) (xy -0.08636 0.20828) (xy 0.086614 0.20828) (xy 0.20828 0.086614)
						(xy 0.20828 -0.08636) (xy 0.08636 -0.20828) (xy -0.08636 -0.20828)
					)
					(width 0)
					(fill yes)
				)
			)
		)
		(zone
			(layer "B.Cu")
			(hatch none 0.5)
			(connect_pads
				(clearance 0)
			)
			(min_thickness 0.25)
			(keepout
				(tracks allowed)
				(vias not_allowed)
				(pads allowed)
				(copperpour not_allowed)
				(footprints allowed)
			)
			(placement
				(enabled no)
				(sheetname "")
			)
			(fill
				(thermal_gap 0.5)
				(thermal_bridge_width 0.5)
				(island_removal_mode 0)
			)
			(polygon
				(pts
					(xy 371.632988 -75.284838) (xy 371.632988 -74.903838) (xy 371.457728 -74.903838) (xy 371.457474 -75.284838)
				)
			)
		)
		(zone
			(layer "B.Cu")
			(hatch none 0.5)
			(connect_pads
				(clearance 0)
			)
			(min_thickness 0.25)
			(keepout
				(tracks not_allowed)
				(vias allowed)
				(pads allowed)
				(copperpour not_allowed)
				(footprints allowed)
			)
			(placement
				(enabled no)
				(sheetname "")
			)
			(fill
				(thermal_gap 0.5)
				(thermal_bridge_width 0.5)
				(island_removal_mode 0)
			)
			(polygon
				(pts
					(xy 371.632988 -75.284838) (xy 371.632988 -74.903838) (xy 371.457728 -74.903838) (xy 371.457474 -75.284838)
				)
			)
		)
	)
	(footprint ""
		(layer "B.Cu")
		(at 408.7622 -103.8098)
		(property "Reference" "C2N24"
			(at 0 0 0)
			(layer "B.SilkS")
			(hide yes)
			(effects
				(font
					(size 1.27 1.27)
				)
				(justify mirror)
			)
		)
		(property "Value" ""
			(at 0 0 0)
			(layer "B.Fab")
			(effects
				(font
					(size 1.27 1.27)
				)
				(justify mirror)
			)
		)
		(duplicate_pad_numbers_are_jumpers no)
		(fp_poly
			(pts
				(xy 0.4953 -0.2032) (xy -0.4953 -0.2032) (xy -0.4953 1.6002) (xy 0.4953 1.6002)
			)
			(stroke
				(width 0)
				(type default)
			)
			(fill no)
			(layer "B.CrtYd")
		)
		(fp_line
			(start -0.4953 -0.2032)
			(end -0.4953 1.6002)
			(stroke
				(width 0.1)
				(type default)
			)
			(layer "B.Fab")
		)
		(fp_line
			(start -0.4953 1.6002)
			(end 0.4953 1.6002)
			(stroke
				(width 0.1)
				(type default)
			)
			(layer "B.Fab")
		)
		(fp_line
			(start 0.4953 -0.2032)
			(end -0.4953 -0.2032)
			(stroke
				(width 0.1)
				(type default)
			)
			(layer "B.Fab")
		)
		(fp_line
			(start 0.4953 1.6002)
			(end 0.4953 -0.2032)
			(stroke
				(width 0.1)
				(type default)
			)
			(layer "B.Fab")
		)
		(pad "1" smd rect
			(at 0 0 180)
			(size 0.762 0.889)
			(layers "B.Cu" "B.Mask" "B.Paste")
			(net "P3V3_STBY")
		)
		(pad "2" smd rect
			(at 0 1.397 180)
			(size 0.762 0.889)
			(layers "B.Cu" "B.Mask" "B.Paste")
			(net "GND")
		)
		(zone
			(layer "B.Cu")
			(hatch none 0.5)
			(connect_pads
				(clearance 0)
			)
			(min_thickness 0.25)
			(keepout
				(tracks not_allowed)
				(vias allowed)
				(pads allowed)
				(copperpour not_allowed)
				(footprints allowed)
			)
			(placement
				(enabled no)
				(sheetname "")
			)
			(fill
				(thermal_gap 0.5)
				(thermal_bridge_width 0.5)
				(island_removal_mode 0)
			)
			(polygon
				(pts
					(xy 409.1432 -103.3653) (xy 408.3812 -103.3653) (xy 408.3812 -102.8573) (xy 409.1432 -102.8573)
				)
			)
		)
	)
	(footprint ""
		(layer "B.Cu")
		(at 386.969 -47.244 -90)
		(property "Reference" "R3T9"
			(at 0 0 90)
			(layer "B.SilkS")
			(hide yes)
			(effects
				(font
					(size 1.27 1.27)
				)
				(justify mirror)
			)
		)
		(property "Value" ""
			(at 0 0 90)
			(layer "B.Fab")
			(effects
				(font
					(size 1.27 1.27)
				)
				(justify mirror)
			)
		)
		(duplicate_pad_numbers_are_jumpers no)
		(fp_poly
			(pts
				(xy 0.2794 -0.1016) (xy -0.2794 -0.1016) (xy -0.2794 0.9906) (xy 0.2794 0.9906)
			)
			(stroke
				(width 0)
				(type default)
			)
			(fill no)
			(layer "B.CrtYd")
		)
		(fp_line
			(start -0.2794 0.9906)
			(end -0.2794 -0.1016)
			(stroke
				(width 0.1)
				(type default)
			)
			(layer "B.Fab")
		)
		(fp_line
			(start 0.2794 0.9906)
			(end -0.2794 0.9906)
			(stroke
				(width 0.1)
				(type default)
			)
			(layer "B.Fab")
		)
		(fp_line
			(start -0.2794 -0.1016)
			(end 0.2794 -0.1016)
			(stroke
				(width 0.1)
				(type default)
			)
			(layer "B.Fab")
		)
		(fp_line
			(start 0.2794 -0.1016)
			(end 0.2794 0.9906)
			(stroke
				(width 0.1)
				(type default)
			)
			(layer "B.Fab")
		)
		(pad "1" smd rect
			(at 0 0 90)
			(size 0.508 0.508)
			(layers "B.Cu" "B.Mask" "B.Paste")
			(net "PU_BIOS_SPI_WP1_N")
		)
		(pad "2" smd rect
			(at 0 0.889 90)
			(size 0.508 0.508)
			(layers "B.Cu" "B.Mask" "B.Paste")
			(net "GND")
		)
		(zone
			(layer "B.Cu")
			(hatch none 0.5)
			(connect_pads
				(clearance 0)
			)
			(min_thickness 0.25)
			(keepout
				(tracks not_allowed)
				(vias allowed)
				(pads allowed)
				(copperpour not_allowed)
				(footprints allowed)
			)
			(placement
				(enabled no)
				(sheetname "")
			)
			(fill
				(thermal_gap 0.5)
				(thermal_bridge_width 0.5)
				(island_removal_mode 0)
			)
			(polygon
				(pts
					(xy 386.334 -46.99) (xy 386.334 -47.498) (xy 386.715 -47.498) (xy 386.715 -46.99)
				)
			)
		)
		(zone
			(layer "B.Cu")
			(hatch none 0.5)
			(connect_pads
				(clearance 0)
			)
			(min_thickness 0.25)
			(keepout
				(tracks allowed)
				(vias not_allowed)
				(pads allowed)
				(copperpour not_allowed)
				(footprints allowed)
			)
			(placement
				(enabled no)
				(sheetname "")
			)
			(fill
				(thermal_gap 0.5)
				(thermal_bridge_width 0.5)
				(island_removal_mode 0)
			)
			(polygon
				(pts
					(xy 386.715 -46.99) (xy 386.715 -47.498) (xy 386.334 -47.498) (xy 386.334 -46.99)
				)
			)
		)
	)
	(footprint ""
		(layer "B.Cu")
		(at 95.377254 -77.82814)
		(property "Reference" "C8P20"
			(at 0 0 0)
			(layer "B.SilkS")
			(hide yes)
			(effects
				(font
					(size 1.27 1.27)
				)
				(justify mirror)
			)
		)
		(property "Value" ""
			(at 0 0 0)
			(layer "B.Fab")
			(effects
				(font
					(size 1.27 1.27)
				)
				(justify mirror)
			)
		)
		(duplicate_pad_numbers_are_jumpers no)
		(fp_poly
			(pts
				(xy 0.7239 -0.2159) (xy -0.7239 -0.2159) (xy -0.7239 1.9939) (xy 0.7239 1.9939)
			)
			(stroke
				(width 0)
				(type default)
			)
			(fill no)
			(layer "B.CrtYd")
		)
		(fp_line
			(start -0.7239 -0.2159)
			(end 0.7239 -0.2159)
			(stroke
				(width 0.1)
				(type default)
			)
			(layer "B.Fab")
		)
		(fp_line
			(start -0.7239 1.9939)
			(end -0.7239 -0.2159)
			(stroke
				(width 0.1)
				(type default)
			)
			(layer "B.Fab")
		)
		(fp_line
			(start 0.7239 -0.2159)
			(end 0.7239 1.9939)
			(stroke
				(width 0.1)
				(type default)
			)
			(layer "B.Fab")
		)
		(fp_line
			(start 0.7239 1.9939)
			(end -0.7239 1.9939)
			(stroke
				(width 0.1)
				(type default)
			)
			(layer "B.Fab")
		)
		(pad "1" smd rect
			(at 0 0 180)
			(size 1.27 1.016)
			(layers "B.Cu" "B.Mask" "B.Paste")
			(net "PVCCIN_CPU1")
		)
		(pad "2" smd rect
			(at 0 1.778 180)
			(size 1.27 1.016)
			(layers "B.Cu" "B.Mask" "B.Paste")
			(net "GND")
		)
		(zone
			(layer "B.Cu")
			(hatch none 0.5)
			(connect_pads
				(clearance 0)
			)
			(min_thickness 0.25)
			(keepout
				(tracks not_allowed)
				(vias allowed)
				(pads allowed)
				(copperpour not_allowed)
				(footprints allowed)
			)
			(placement
				(enabled no)
				(sheetname "")
			)
			(fill
				(thermal_gap 0.5)
				(thermal_bridge_width 0.5)
				(island_removal_mode 0)
			)
			(polygon
				(pts
					(xy 96.012254 -77.32014) (xy 94.742254 -77.32014) (xy 94.742254 -76.55814) (xy 96.012254 -76.55814)
				)
			)
		)
	)
	(footprint ""
		(layer "B.Cu")
		(at 479.8695 -40.4114 90)
		(property "Reference" "C1R26"
			(at 0 0 90)
			(layer "B.SilkS")
			(hide yes)
			(effects
				(font
					(size 1.27 1.27)
				)
				(justify mirror)
			)
		)
		(property "Value" ""
			(at 0 0 90)
			(layer "B.Fab")
			(effects
				(font
					(size 1.27 1.27)
				)
				(justify mirror)
			)
		)
		(duplicate_pad_numbers_are_jumpers no)
		(fp_poly
			(pts
				(xy -0.3048 -0.1016) (xy -0.3048 0.9906) (xy 0.3048 0.9906) (xy 0.3048 -0.1016)
			)
			(stroke
				(width 0)
				(type default)
			)
			(fill no)
			(layer "B.CrtYd")
		)
		(fp_line
			(start 0.3048 -0.1016)
			(end 0.3048 0.9906)
			(stroke
				(width 0.1)
				(type default)
			)
			(layer "B.Fab")
		)
		(fp_line
			(start -0.3048 -0.1016)
			(end 0.3048 -0.1016)
			(stroke
				(width 0.1)
				(type default)
			)
			(layer "B.Fab")
		)
		(fp_line
			(start 0.3048 0.9906)
			(end -0.3048 0.9906)
			(stroke
				(width 0.1)
				(type default)
			)
			(layer "B.Fab")
		)
		(fp_line
			(start -0.3048 0.9906)
			(end -0.3048 -0.1016)
			(stroke
				(width 0.1)
				(type default)
			)
			(layer "B.Fab")
		)
		(pad "1" smd rect
			(at 0 0 270)
			(size 0.508 0.508)
			(layers "B.Cu" "B.Mask" "B.Paste")
			(net "P1V5_LAN")
		)
		(pad "2" smd rect
			(at 0 0.889 270)
			(size 0.508 0.508)
			(layers "B.Cu" "B.Mask" "B.Paste")
			(net "GND")
		)
		(zone
			(layer "B.Cu")
			(hatch none 0.5)
			(connect_pads
				(clearance 0)
			)
			(min_thickness 0.25)
			(keepout
				(tracks allowed)
				(vias not_allowed)
				(pads allowed)
				(copperpour not_allowed)
				(footprints allowed)
			)
			(placement
				(enabled no)
				(sheetname "")
			)
			(fill
				(thermal_gap 0.5)
				(thermal_bridge_width 0.5)
				(island_removal_mode 0)
			)
			(polygon
				(pts
					(xy 480.1235 -40.6654) (xy 480.1235 -40.1574) (xy 480.5045 -40.1574) (xy 480.5045 -40.6654)
				)
			)
		)
		(zone
			(layer "B.Cu")
			(hatch none 0.5)
			(connect_pads
				(clearance 0)
			)
			(min_thickness 0.25)
			(keepout
				(tracks not_allowed)
				(vias allowed)
				(pads allowed)
				(copperpour not_allowed)
				(footprints allowed)
			)
			(placement
				(enabled no)
				(sheetname "")
			)
			(fill
				(thermal_gap 0.5)
				(thermal_bridge_width 0.5)
				(island_removal_mode 0)
			)
			(polygon
				(pts
					(xy 480.5045 -40.6654) (xy 480.5045 -40.1574) (xy 480.1235 -40.1574) (xy 480.1235 -40.6654)
				)
			)
		)
	)
	(footprint ""
		(layer "B.Cu")
		(at 485.6734 -39.7256 180)
		(property "Reference" "C1T4"
			(at 0 0 0)
			(layer "B.SilkS")
			(hide yes)
			(effects
				(font
					(size 1.27 1.27)
				)
				(justify mirror)
			)
		)
		(property "Value" ""
			(at 0 0 0)
			(layer "B.Fab")
			(effects
				(font
					(size 1.27 1.27)
				)
				(justify mirror)
			)
		)
		(duplicate_pad_numbers_are_jumpers no)
		(fp_poly
			(pts
				(xy 0.4953 -0.2032) (xy -0.4953 -0.2032) (xy -0.4953 1.6002) (xy 0.4953 1.6002)
			)
			(stroke
				(width 0)
				(type default)
			)
			(fill no)
			(layer "B.CrtYd")
		)
		(fp_line
			(start 0.4953 1.6002)
			(end 0.4953 -0.2032)
			(stroke
				(width 0.1)
				(type default)
			)
			(layer "B.Fab")
		)
		(fp_line
			(start 0.4953 -0.2032)
			(end -0.4953 -0.2032)
			(stroke
				(width 0.1)
				(type default)
			)
			(layer "B.Fab")
		)
		(fp_line
			(start -0.4953 1.6002)
			(end 0.4953 1.6002)
			(stroke
				(width 0.1)
				(type default)
			)
			(layer "B.Fab")
		)
		(fp_line
			(start -0.4953 -0.2032)
			(end -0.4953 1.6002)
			(stroke
				(width 0.1)
				(type default)
			)
			(layer "B.Fab")
		)
		(pad "1" smd rect
			(at 0 0)
			(size 0.762 0.889)
			(layers "B.Cu" "B.Mask" "B.Paste")
			(net "P0V9_LAN")
		)
		(pad "2" smd rect
			(at 0 1.397)
			(size 0.762 0.889)
			(layers "B.Cu" "B.Mask" "B.Paste")
			(net "GND")
		)
		(zone
			(layer "B.Cu")
			(hatch none 0.5)
			(connect_pads
				(clearance 0)
			)
			(min_thickness 0.25)
			(keepout
				(tracks not_allowed)
				(vias allowed)
				(pads allowed)
				(copperpour not_allowed)
				(footprints allowed)
			)
			(placement
				(enabled no)
				(sheetname "")
			)
			(fill
				(thermal_gap 0.5)
				(thermal_bridge_width 0.5)
				(island_removal_mode 0)
			)
			(polygon
				(pts
					(xy 485.2924 -40.1701) (xy 486.0544 -40.1701) (xy 486.0544 -40.6781) (xy 485.2924 -40.6781)
				)
			)
		)
	)
	(footprint ""
		(layer "B.Cu")
		(at 88.392 -149.8092 90)
		(property "Reference" "C5G98"
			(at -1.14681 0.76708 180)
			(unlocked yes)
			(layer "B.SilkS")
			(effects
				(font
					(size 0.7874 0.5842)
					(thickness 0.1524)
				)
				(justify mirror)
			)
		)
		(property "Value" ""
			(at 0 0 90)
			(layer "B.Fab")
			(effects
				(font
					(size 1.27 1.27)
				)
				(justify mirror)
			)
		)
		(duplicate_pad_numbers_are_jumpers no)
		(fp_rect
			(start -0.4953 -0.2032)
			(end 0.4953 1.6002)
			(stroke
				(width 0)
				(type default)
			)
			(fill no)
			(layer "B.CrtYd")
		)
		(fp_line
			(start 0.4953 -0.2032)
			(end -0.4953 -0.2032)
			(stroke
				(width 0.1)
				(type default)
			)
			(layer "B.Fab")
		)
		(fp_line
			(start -0.4953 -0.2032)
			(end -0.4953 1.6002)
			(stroke
				(width 0.1)
				(type default)
			)
			(layer "B.Fab")
		)
		(fp_line
			(start 0.4953 1.6002)
			(end 0.4953 -0.2032)
			(stroke
				(width 0.1)
				(type default)
			)
			(layer "B.Fab")
		)
		(fp_line
			(start -0.4953 1.6002)
			(end 0.4953 1.6002)
			(stroke
				(width 0.1)
				(type default)
			)
			(layer "B.Fab")
		)
		(pad "1" smd rect
			(at 0 0 270)
			(size 0.762 0.889)
			(layers "B.Cu" "B.Mask" "B.Paste")
			(net "PVDDQ_KLM")
		)
		(pad "2" smd rect
			(at 0 1.397 270)
			(size 0.762 0.889)
			(layers "B.Cu" "B.Mask" "B.Paste")
			(net "GND")
		)
		(zone
			(layer "B.Cu")
			(hatch none 0.5)
			(connect_pads
				(clearance 0)
			)
			(min_thickness 0.25)
			(keepout
				(tracks not_allowed)
				(vias allowed)
				(pads allowed)
				(copperpour not_allowed)
				(footprints allowed)
			)
			(placement
				(enabled no)
				(sheetname "")
			)
			(fill
				(thermal_gap 0.5)
				(thermal_bridge_width 0.5)
				(island_removal_mode 0)
			)
			(polygon
				(pts
					(xy 88.8365 -149.4282) (xy 89.3445 -149.4282) (xy 89.3445 -150.1902) (xy 88.8365 -150.1902)
				)
			)
		)
	)
	(footprint ""
		(layer "B.Cu")
		(at 95.374968 -27.051 90)
		(property "Reference" "C8T3"
			(at -1.47828 0.78994 180)
			(unlocked yes)
			(layer "B.SilkS")
			(effects
				(font
					(size 0.4064 0.254)
					(thickness 0.1524)
				)
				(justify mirror)
			)
		)
		(property "Value" ""
			(at 0 0 90)
			(layer "B.Fab")
			(effects
				(font
					(size 1.27 1.27)
				)
				(justify mirror)
			)
		)
		(duplicate_pad_numbers_are_jumpers no)
		(fp_poly
			(pts
				(xy 0.7239 -0.2159) (xy -0.7239 -0.2159) (xy -0.7239 1.9939) (xy 0.7239 1.9939)
			)
			(stroke
				(width 0)
				(type default)
			)
			(fill no)
			(layer "B.CrtYd")
		)
		(fp_line
			(start 0.7239 -0.2159)
			(end 0.7239 1.9939)
			(stroke
				(width 0.1)
				(type default)
			)
			(layer "B.Fab")
		)
		(fp_line
			(start -0.7239 -0.2159)
			(end 0.7239 -0.2159)
			(stroke
				(width 0.1)
				(type default)
			)
			(layer "B.Fab")
		)
		(fp_line
			(start 0.7239 1.9939)
			(end -0.7239 1.9939)
			(stroke
				(width 0.1)
				(type default)
			)
			(layer "B.Fab")
		)
		(fp_line
			(start -0.7239 1.9939)
			(end -0.7239 -0.2159)
			(stroke
				(width 0.1)
				(type default)
			)
			(layer "B.Fab")
		)
		(pad "1" smd rect
			(at 0 0 270)
			(size 1.27 1.016)
			(layers "B.Cu" "B.Mask" "B.Paste")
			(net "PVTT_GHJ")
		)
		(pad "2" smd rect
			(at 0 1.778 270)
			(size 1.27 1.016)
			(layers "B.Cu" "B.Mask" "B.Paste")
			(net "GND")
		)
		(zone
			(layer "B.Cu")
			(hatch none 0.5)
			(connect_pads
				(clearance 0)
			)
			(min_thickness 0.25)
			(keepout
				(tracks not_allowed)
				(vias allowed)
				(pads allowed)
				(copperpour not_allowed)
				(footprints allowed)
			)
			(placement
				(enabled no)
				(sheetname "")
			)
			(fill
				(thermal_gap 0.5)
				(thermal_bridge_width 0.5)
				(island_removal_mode 0)
			)
			(polygon
				(pts
					(xy 95.882968 -27.686) (xy 95.882968 -26.416) (xy 96.644968 -26.416) (xy 96.644968 -27.686)
				)
			)
		)
	)
	(footprint ""
		(layer "B.Cu")
		(at 462.949544 -10.69848 -90)
		(property "Reference" "C2T36"
			(at 0 0 90)
			(layer "B.SilkS")
			(hide yes)
			(effects
				(font
					(size 1.27 1.27)
				)
				(justify mirror)
			)
		)
		(property "Value" ""
			(at 0 0 90)
			(layer "B.Fab")
			(effects
				(font
					(size 1.27 1.27)
				)
				(justify mirror)
			)
		)
		(duplicate_pad_numbers_are_jumpers no)
		(fp_rect
			(start -0.3048 0.9906)
			(end 0.3048 -0.1016)
			(stroke
				(width 0)
				(type default)
			)
			(fill no)
			(layer "B.CrtYd")
		)
		(fp_line
			(start -0.3048 0.9906)
			(end -0.3048 -0.1016)
			(stroke
				(width 0.1)
				(type default)
			)
			(layer "B.Fab")
		)
		(fp_line
			(start 0.3048 0.9906)
			(end -0.3048 0.9906)
			(stroke
				(width 0.1)
				(type default)
			)
			(layer "B.Fab")
		)
		(fp_line
			(start -0.3048 -0.1016)
			(end 0.3048 -0.1016)
			(stroke
				(width 0.1)
				(type default)
			)
			(layer "B.Fab")
		)
		(fp_line
			(start 0.3048 -0.1016)
			(end 0.3048 0.9906)
			(stroke
				(width 0.1)
				(type default)
			)
			(layer "B.Fab")
		)
		(pad "1" smd rect
			(at 0 0 90)
			(size 0.508 0.508)
			(layers "B.Cu" "B.Mask" "B.Paste")
			(net "P3V3_STBY")
		)
		(pad "2" smd rect
			(at 0 0.889 90)
			(size 0.508 0.508)
			(layers "B.Cu" "B.Mask" "B.Paste")
			(net "GND")
		)
		(zone
			(layer "B.Cu")
			(hatch none 0.5)
			(connect_pads
				(clearance 0)
			)
			(min_thickness 0.25)
			(keepout
				(tracks not_allowed)
				(vias allowed)
				(pads allowed)
				(copperpour not_allowed)
				(footprints allowed)
			)
			(placement
				(enabled no)
				(sheetname "")
			)
			(fill
				(thermal_gap 0.5)
				(thermal_bridge_width 0.5)
				(island_removal_mode 0)
			)
			(polygon
				(pts
					(xy 462.314544 -10.95248) (xy 462.314544 -10.44448) (xy 462.695544 -10.44448) (xy 462.695544 -10.95248)
				)
			)
		)
		(zone
			(layer "B.Cu")
			(hatch none 0.5)
			(connect_pads
				(clearance 0)
			)
			(min_thickness 0.25)
			(keepout
				(tracks allowed)
				(vias not_allowed)
				(pads allowed)
				(copperpour not_allowed)
				(footprints allowed)
			)
			(placement
				(enabled no)
				(sheetname "")
			)
			(fill
				(thermal_gap 0.5)
				(thermal_bridge_width 0.5)
				(island_removal_mode 0)
			)
			(polygon
				(pts
					(xy 462.314544 -10.95248) (xy 462.314544 -10.44448) (xy 462.695544 -10.44448) (xy 462.695544 -10.95248)
				)
			)
		)
	)
	(footprint ""
		(layer "B.Cu")
		(at 447.04 -116.49202)
		(property "Reference" "C1M18"
			(at 0 0 0)
			(layer "B.SilkS")
			(hide yes)
			(effects
				(font
					(size 1.27 1.27)
				)
				(justify mirror)
			)
		)
		(property "Value" ""
			(at 0 0 0)
			(layer "B.Fab")
			(effects
				(font
					(size 1.27 1.27)
				)
				(justify mirror)
			)
		)
		(duplicate_pad_numbers_are_jumpers no)
		(fp_rect
			(start -0.3048 0.9906)
			(end 0.3048 -0.1016)
			(stroke
				(width 0)
				(type default)
			)
			(fill no)
			(layer "B.CrtYd")
		)
		(fp_line
			(start -0.3048 -0.1016)
			(end 0.3048 -0.1016)
			(stroke
				(width 0.1)
				(type default)
			)
			(layer "B.Fab")
		)
		(fp_line
			(start -0.3048 0.9906)
			(end -0.3048 -0.1016)
			(stroke
				(width 0.1)
				(type default)
			)
			(layer "B.Fab")
		)
		(fp_line
			(start 0.3048 -0.1016)
			(end 0.3048 0.9906)
			(stroke
				(width 0.1)
				(type default)
			)
			(layer "B.Fab")
		)
		(fp_line
			(start 0.3048 0.9906)
			(end -0.3048 0.9906)
			(stroke
				(width 0.1)
				(type default)
			)
			(layer "B.Fab")
		)
		(pad "1" smd rect
			(at 0 0 180)
			(size 0.508 0.508)
			(layers "B.Cu" "B.Mask" "B.Paste")
			(net "P3E_CPU0_PE3_OCP_TXP<9>")
		)
		(pad "2" smd rect
			(at 0 0.889 180)
			(size 0.508 0.508)
			(layers "B.Cu" "B.Mask" "B.Paste")
			(net "P3E_OCP_CPU0_PE3_C_TXP<9>")
		)
		(zone
			(layer "B.Cu")
			(hatch none 0.5)
			(connect_pads
				(clearance 0)
			)
			(min_thickness 0.25)
			(keepout
				(tracks allowed)
				(vias not_allowed)
				(pads allowed)
				(copperpour not_allowed)
				(footprints allowed)
			)
			(placement
				(enabled no)
				(sheetname "")
			)
			(fill
				(thermal_gap 0.5)
				(thermal_bridge_width 0.5)
				(island_removal_mode 0)
			)
			(polygon
				(pts
					(xy 446.786 -115.85702) (xy 447.294 -115.85702) (xy 447.294 -116.23802) (xy 446.786 -116.23802)
				)
			)
		)
		(zone
			(layer "B.Cu")
			(hatch none 0.5)
			(connect_pads
				(clearance 0)
			)
			(min_thickness 0.25)
			(keepout
				(tracks not_allowed)
				(vias allowed)
				(pads allowed)
				(copperpour not_allowed)
				(footprints allowed)
			)
			(placement
				(enabled no)
				(sheetname "")
			)
			(fill
				(thermal_gap 0.5)
				(thermal_bridge_width 0.5)
				(island_removal_mode 0)
			)
			(polygon
				(pts
					(xy 446.786 -115.85702) (xy 447.294 -115.85702) (xy 447.294 -116.23802) (xy 446.786 -116.23802)
				)
			)
		)
	)
	(footprint ""
		(layer "B.Cu")
		(at 372.9482 -133.8072 -90)
		(property "Reference" "C3M24"
			(at 0 0 90)
			(layer "B.SilkS")
			(hide yes)
			(effects
				(font
					(size 1.27 1.27)
				)
				(justify mirror)
			)
		)
		(property "Value" ""
			(at 0 0 90)
			(layer "B.Fab")
			(effects
				(font
					(size 1.27 1.27)
				)
				(justify mirror)
			)
		)
		(duplicate_pad_numbers_are_jumpers no)
		(fp_rect
			(start 0.4953 1.6002)
			(end -0.4953 -0.2032)
			(stroke
				(width 0)
				(type default)
			)
			(fill no)
			(layer "B.CrtYd")
		)
		(fp_line
			(start -0.4953 1.6002)
			(end 0.4953 1.6002)
			(stroke
				(width 0.1)
				(type default)
			)
			(layer "B.Fab")
		)
		(fp_line
			(start 0.4953 1.6002)
			(end 0.4953 -0.2032)
			(stroke
				(width 0.1)
				(type default)
			)
			(layer "B.Fab")
		)
		(fp_line
			(start -0.4953 -0.2032)
			(end -0.4953 1.6002)
			(stroke
				(width 0.1)
				(type default)
			)
			(layer "B.Fab")
		)
		(fp_line
			(start 0.4953 -0.2032)
			(end -0.4953 -0.2032)
			(stroke
				(width 0.1)
				(type default)
			)
			(layer "B.Fab")
		)
		(pad "1" smd rect
			(at 0 0 90)
			(size 0.762 0.889)
			(layers "B.Cu" "B.Mask" "B.Paste")
			(net "P1V05_PCH_STBY_ISCLK_PLL")
		)
		(pad "2" smd rect
			(at 0 1.397 90)
			(size 0.762 0.889)
			(layers "B.Cu" "B.Mask" "B.Paste")
			(net "GND")
		)
		(zone
			(layer "B.Cu")
			(hatch none 0.5)
			(connect_pads
				(clearance 0)
			)
			(min_thickness 0.25)
			(keepout
				(tracks not_allowed)
				(vias allowed)
				(pads allowed)
				(copperpour not_allowed)
				(footprints allowed)
			)
			(placement
				(enabled no)
				(sheetname "")
			)
			(fill
				(thermal_gap 0.5)
				(thermal_bridge_width 0.5)
				(island_removal_mode 0)
			)
			(polygon
				(pts
					(xy 371.9957 -133.4262) (xy 372.5037 -133.4262) (xy 372.5037 -134.1882) (xy 371.9957 -134.1882)
				)
			)
		)
	)
	(footprint ""
		(layer "B.Cu")
		(at 420.923466 -45.536612 90)
		(property "Reference" "R25W96"
			(at 0.8382 -0.67818 90)
			(unlocked yes)
			(layer "B.SilkS")
			(effects
				(font
					(size 0.4064 0.254)
					(thickness 0.1524)
				)
				(justify left mirror)
			)
		)
		(property "Value" ""
			(at 0 0 90)
			(layer "B.Fab")
			(effects
				(font
					(size 1.27 1.27)
				)
				(justify mirror)
			)
		)
		(duplicate_pad_numbers_are_jumpers no)
		(fp_poly
			(pts
				(xy 0.2794 -0.1016) (xy -0.2794 -0.1016) (xy -0.2794 0.9906) (xy 0.2794 0.9906)
			)
			(stroke
				(width 0)
				(type default)
			)
			(fill no)
			(layer "B.CrtYd")
		)
		(fp_line
			(start 0.2794 -0.1016)
			(end 0.2794 0.9906)
			(stroke
				(width 0.1)
				(type default)
			)
			(layer "B.Fab")
		)
		(fp_line
			(start -0.2794 -0.1016)
			(end 0.2794 -0.1016)
			(stroke
				(width 0.1)
				(type default)
			)
			(layer "B.Fab")
		)
		(fp_line
			(start 0.2794 0.9906)
			(end -0.2794 0.9906)
			(stroke
				(width 0.1)
				(type default)
			)
			(layer "B.Fab")
		)
		(fp_line
			(start -0.2794 0.9906)
			(end -0.2794 -0.1016)
			(stroke
				(width 0.1)
				(type default)
			)
			(layer "B.Fab")
		)
		(pad "1" smd rect
			(at 0 0 270)
			(size 0.508 0.508)
			(layers "B.Cu" "B.Mask" "B.Paste")
			(net "P3V3_STBY")
		)
		(pad "2" smd rect
			(at 0 0.889 270)
			(size 0.508 0.508)
			(layers "B.Cu" "B.Mask" "B.Paste")
			(net "SPI_BMC_BT_DO")
		)
		(zone
			(layer "B.Cu")
			(hatch none 0.5)
			(connect_pads
				(clearance 0)
			)
			(min_thickness 0.25)
			(keepout
				(tracks allowed)
				(vias not_allowed)
				(pads allowed)
				(copperpour not_allowed)
				(footprints allowed)
			)
			(placement
				(enabled no)
				(sheetname "")
			)
			(fill
				(thermal_gap 0.5)
				(thermal_bridge_width 0.5)
				(island_removal_mode 0)
			)
			(polygon
				(pts
					(xy 421.177466 -45.790612) (xy 421.177466 -45.282612) (xy 421.558466 -45.282612) (xy 421.558466 -45.790612)
				)
			)
		)
		(zone
			(layer "B.Cu")
			(hatch none 0.5)
			(connect_pads
				(clearance 0)
			)
			(min_thickness 0.25)
			(keepout
				(tracks not_allowed)
				(vias allowed)
				(pads allowed)
				(copperpour not_allowed)
				(footprints allowed)
			)
			(placement
				(enabled no)
				(sheetname "")
			)
			(fill
				(thermal_gap 0.5)
				(thermal_bridge_width 0.5)
				(island_removal_mode 0)
			)
			(polygon
				(pts
					(xy 421.558466 -45.790612) (xy 421.558466 -45.282612) (xy 421.177466 -45.282612) (xy 421.177466 -45.790612)
				)
			)
		)
	)
	(footprint ""
		(layer "B.Cu")
		(at 400.829526 -149.663912 -90)
		(property "Reference" "R2L17"
			(at 0.8382 -0.84963 270)
			(unlocked yes)
			(layer "B.SilkS")
			(effects
				(font
					(size 0.7874 0.5842)
					(thickness 0.1524)
				)
				(justify left mirror)
			)
		)
		(property "Value" ""
			(at 0 0 90)
			(layer "B.Fab")
			(effects
				(font
					(size 1.27 1.27)
				)
				(justify mirror)
			)
		)
		(duplicate_pad_numbers_are_jumpers no)
		(fp_poly
			(pts
				(xy 0.2794 -0.1016) (xy -0.2794 -0.1016) (xy -0.2794 0.9906) (xy 0.2794 0.9906)
			)
			(stroke
				(width 0)
				(type default)
			)
			(fill no)
			(layer "B.CrtYd")
		)
		(fp_line
			(start -0.2794 0.9906)
			(end -0.2794 -0.1016)
			(stroke
				(width 0.1)
				(type default)
			)
			(layer "B.Fab")
		)
		(fp_line
			(start 0.2794 0.9906)
			(end -0.2794 0.9906)
			(stroke
				(width 0.1)
				(type default)
			)
			(layer "B.Fab")
		)
		(fp_line
			(start -0.2794 -0.1016)
			(end 0.2794 -0.1016)
			(stroke
				(width 0.1)
				(type default)
			)
			(layer "B.Fab")
		)
		(fp_line
			(start 0.2794 -0.1016)
			(end 0.2794 0.9906)
			(stroke
				(width 0.1)
				(type default)
			)
			(layer "B.Fab")
		)
		(pad "1" smd rect
			(at 0 0 90)
			(size 0.508 0.508)
			(layers "B.Cu" "B.Mask" "B.Paste")
			(net "PWRGD_P1V8_PCH_STBY")
		)
		(pad "2" smd rect
			(at 0 0.889 90)
			(size 0.508 0.508)
			(layers "B.Cu" "B.Mask" "B.Paste")
			(net "VR_PVNN_PCH_VREN")
		)
		(zone
			(layer "B.Cu")
			(hatch none 0.5)
			(connect_pads
				(clearance 0)
			)
			(min_thickness 0.25)
			(keepout
				(tracks not_allowed)
				(vias allowed)
				(pads allowed)
				(copperpour not_allowed)
				(footprints allowed)
			)
			(placement
				(enabled no)
				(sheetname "")
			)
			(fill
				(thermal_gap 0.5)
				(thermal_bridge_width 0.5)
				(island_removal_mode 0)
			)
			(polygon
				(pts
					(xy 400.194526 -149.409912) (xy 400.194526 -149.917912) (xy 400.575526 -149.917912) (xy 400.575526 -149.409912)
				)
			)
		)
		(zone
			(layer "B.Cu")
			(hatch none 0.5)
			(connect_pads
				(clearance 0)
			)
			(min_thickness 0.25)
			(keepout
				(tracks allowed)
				(vias not_allowed)
				(pads allowed)
				(copperpour not_allowed)
				(footprints allowed)
			)
			(placement
				(enabled no)
				(sheetname "")
			)
			(fill
				(thermal_gap 0.5)
				(thermal_bridge_width 0.5)
				(island_removal_mode 0)
			)
			(polygon
				(pts
					(xy 400.575526 -149.409912) (xy 400.575526 -149.917912) (xy 400.194526 -149.917912) (xy 400.194526 -149.409912)
				)
			)
		)
	)
	(footprint ""
		(layer "B.Cu")
		(at 474.650816 -145.470372 180)
		(property "Reference" "R6W12"
			(at 0.8382 -0.67818 180)
			(unlocked yes)
			(layer "B.SilkS")
			(effects
				(font
					(size 0.4064 0.254)
					(thickness 0.1524)
				)
				(justify left mirror)
			)
		)
		(property "Value" ""
			(at 0 0 0)
			(layer "B.Fab")
			(effects
				(font
					(size 1.27 1.27)
				)
				(justify mirror)
			)
		)
		(duplicate_pad_numbers_are_jumpers no)
		(fp_poly
			(pts
				(xy 0.2794 -0.1016) (xy -0.2794 -0.1016) (xy -0.2794 0.9906) (xy 0.2794 0.9906)
			)
			(stroke
				(width 0)
				(type default)
			)
			(fill no)
			(layer "B.CrtYd")
		)
		(fp_line
			(start 0.2794 0.9906)
			(end -0.2794 0.9906)
			(stroke
				(width 0.1)
				(type default)
			)
			(layer "B.Fab")
		)
		(fp_line
			(start 0.2794 -0.1016)
			(end 0.2794 0.9906)
			(stroke
				(width 0.1)
				(type default)
			)
			(layer "B.Fab")
		)
		(fp_line
			(start -0.2794 0.9906)
			(end -0.2794 -0.1016)
			(stroke
				(width 0.1)
				(type default)
			)
			(layer "B.Fab")
		)
		(fp_line
			(start -0.2794 -0.1016)
			(end 0.2794 -0.1016)
			(stroke
				(width 0.1)
				(type default)
			)
			(layer "B.Fab")
		)
		(pad "1" smd rect
			(at 0 0)
			(size 0.508 0.508)
			(layers "B.Cu" "B.Mask" "B.Paste")
			(net "SMB_DEBUG_STBY_LVC3_SDA")
		)
		(pad "2" smd rect
			(at 0 0.889)
			(size 0.508 0.508)
			(layers "B.Cu" "B.Mask" "B.Paste")
			(net "P3V3_STBY")
		)
		(zone
			(layer "B.Cu")
			(hatch none 0.5)
			(connect_pads
				(clearance 0)
			)
			(min_thickness 0.25)
			(keepout
				(tracks not_allowed)
				(vias allowed)
				(pads allowed)
				(copperpour not_allowed)
				(footprints allowed)
			)
			(placement
				(enabled no)
				(sheetname "")
			)
			(fill
				(thermal_gap 0.5)
				(thermal_bridge_width 0.5)
				(island_removal_mode 0)
			)
			(polygon
				(pts
					(xy 474.396816 -146.105372) (xy 474.904816 -146.105372) (xy 474.904816 -145.724372) (xy 474.396816 -145.724372)
				)
			)
		)
		(zone
			(layer "B.Cu")
			(hatch none 0.5)
			(connect_pads
				(clearance 0)
			)
			(min_thickness 0.25)
			(keepout
				(tracks allowed)
				(vias not_allowed)
				(pads allowed)
				(copperpour not_allowed)
				(footprints allowed)
			)
			(placement
				(enabled no)
				(sheetname "")
			)
			(fill
				(thermal_gap 0.5)
				(thermal_bridge_width 0.5)
				(island_removal_mode 0)
			)
			(polygon
				(pts
					(xy 474.396816 -145.724372) (xy 474.904816 -145.724372) (xy 474.904816 -146.105372) (xy 474.396816 -146.105372)
				)
			)
		)
	)
	(footprint ""
		(layer "B.Cu")
		(at 371.362986 -47.798482 180)
		(property "Reference" "R2T69"
			(at 0 0 0)
			(layer "B.SilkS")
			(hide yes)
			(effects
				(font
					(size 1.27 1.27)
				)
				(justify mirror)
			)
		)
		(property "Value" ""
			(at 0 0 0)
			(layer "B.Fab")
			(effects
				(font
					(size 1.27 1.27)
				)
				(justify mirror)
			)
		)
		(duplicate_pad_numbers_are_jumpers no)
		(fp_poly
			(pts
				(xy 0.2794 -0.1016) (xy -0.2794 -0.1016) (xy -0.2794 0.9906) (xy 0.2794 0.9906)
			)
			(stroke
				(width 0)
				(type default)
			)
			(fill no)
			(layer "B.CrtYd")
		)
		(fp_line
			(start 0.2794 0.9906)
			(end -0.2794 0.9906)
			(stroke
				(width 0.1)
				(type default)
			)
			(layer "B.Fab")
		)
		(fp_line
			(start 0.2794 -0.1016)
			(end 0.2794 0.9906)
			(stroke
				(width 0.1)
				(type default)
			)
			(layer "B.Fab")
		)
		(fp_line
			(start -0.2794 0.9906)
			(end -0.2794 -0.1016)
			(stroke
				(width 0.1)
				(type default)
			)
			(layer "B.Fab")
		)
		(fp_line
			(start -0.2794 -0.1016)
			(end 0.2794 -0.1016)
			(stroke
				(width 0.1)
				(type default)
			)
			(layer "B.Fab")
		)
		(pad "1" smd rect
			(at 0 0)
			(size 0.508 0.508)
			(layers "B.Cu" "B.Mask" "B.Paste")
			(net "H_CPU1_PROCHOT_G_N")
		)
		(pad "2" smd rect
			(at 0 0.889)
			(size 0.508 0.508)
			(layers "B.Cu" "B.Mask" "B.Paste")
			(net "H_CPU1_PROCHOT_G_PCH_N")
		)
		(zone
			(layer "B.Cu")
			(hatch none 0.5)
			(connect_pads
				(clearance 0)
			)
			(min_thickness 0.25)
			(keepout
				(tracks not_allowed)
				(vias allowed)
				(pads allowed)
				(copperpour not_allowed)
				(footprints allowed)
			)
			(placement
				(enabled no)
				(sheetname "")
			)
			(fill
				(thermal_gap 0.5)
				(thermal_bridge_width 0.5)
				(island_removal_mode 0)
			)
			(polygon
				(pts
					(xy 371.108986 -48.433482) (xy 371.616986 -48.433482) (xy 371.616986 -48.052482) (xy 371.108986 -48.052482)
				)
			)
		)
		(zone
			(layer "B.Cu")
			(hatch none 0.5)
			(connect_pads
				(clearance 0)
			)
			(min_thickness 0.25)
			(keepout
				(tracks allowed)
				(vias not_allowed)
				(pads allowed)
				(copperpour not_allowed)
				(footprints allowed)
			)
			(placement
				(enabled no)
				(sheetname "")
			)
			(fill
				(thermal_gap 0.5)
				(thermal_bridge_width 0.5)
				(island_removal_mode 0)
			)
			(polygon
				(pts
					(xy 371.108986 -48.052482) (xy 371.616986 -48.052482) (xy 371.616986 -48.433482) (xy 371.108986 -48.433482)
				)
			)
		)
	)
	(footprint ""
		(layer "B.Cu")
		(at 101.3968 -149.8092 90)
		(property "Reference" "C5G102"
			(at -1.14681 0.76708 180)
			(unlocked yes)
			(layer "B.SilkS")
			(effects
				(font
					(size 0.7874 0.5842)
					(thickness 0.1524)
				)
				(justify mirror)
			)
		)
		(property "Value" ""
			(at 0 0 90)
			(layer "B.Fab")
			(effects
				(font
					(size 1.27 1.27)
				)
				(justify mirror)
			)
		)
		(duplicate_pad_numbers_are_jumpers no)
		(fp_rect
			(start -0.4953 -0.2032)
			(end 0.4953 1.6002)
			(stroke
				(width 0)
				(type default)
			)
			(fill no)
			(layer "B.CrtYd")
		)
		(fp_line
			(start 0.4953 -0.2032)
			(end -0.4953 -0.2032)
			(stroke
				(width 0.1)
				(type default)
			)
			(layer "B.Fab")
		)
		(fp_line
			(start -0.4953 -0.2032)
			(end -0.4953 1.6002)
			(stroke
				(width 0.1)
				(type default)
			)
			(layer "B.Fab")
		)
		(fp_line
			(start 0.4953 1.6002)
			(end 0.4953 -0.2032)
			(stroke
				(width 0.1)
				(type default)
			)
			(layer "B.Fab")
		)
		(fp_line
			(start -0.4953 1.6002)
			(end 0.4953 1.6002)
			(stroke
				(width 0.1)
				(type default)
			)
			(layer "B.Fab")
		)
		(pad "1" smd rect
			(at 0 0 270)
			(size 0.762 0.889)
			(layers "B.Cu" "B.Mask" "B.Paste")
			(net "PVDDQ_KLM")
		)
		(pad "2" smd rect
			(at 0 1.397 270)
			(size 0.762 0.889)
			(layers "B.Cu" "B.Mask" "B.Paste")
			(net "GND")
		)
		(zone
			(layer "B.Cu")
			(hatch none 0.5)
			(connect_pads
				(clearance 0)
			)
			(min_thickness 0.25)
			(keepout
				(tracks not_allowed)
				(vias allowed)
				(pads allowed)
				(copperpour not_allowed)
				(footprints allowed)
			)
			(placement
				(enabled no)
				(sheetname "")
			)
			(fill
				(thermal_gap 0.5)
				(thermal_bridge_width 0.5)
				(island_removal_mode 0)
			)
			(polygon
				(pts
					(xy 101.8413 -149.4282) (xy 102.3493 -149.4282) (xy 102.3493 -150.1902) (xy 101.8413 -150.1902)
				)
			)
		)
	)
	(footprint ""
		(layer "B.Cu")
		(at 374.84177 -95.568516 90)
		(property "Reference" "R7W19"
			(at 0.8382 -0.67818 90)
			(unlocked yes)
			(layer "B.SilkS")
			(effects
				(font
					(size 0.4064 0.254)
					(thickness 0.1524)
				)
				(justify left mirror)
			)
		)
		(property "Value" ""
			(at 0 0 90)
			(layer "B.Fab")
			(effects
				(font
					(size 1.27 1.27)
				)
				(justify mirror)
			)
		)
		(duplicate_pad_numbers_are_jumpers no)
		(fp_poly
			(pts
				(xy 0.2794 -0.1016) (xy -0.2794 -0.1016) (xy -0.2794 0.9906) (xy 0.2794 0.9906)
			)
			(stroke
				(width 0)
				(type default)
			)
			(fill no)
			(layer "B.CrtYd")
		)
		(fp_line
			(start 0.2794 -0.1016)
			(end 0.2794 0.9906)
			(stroke
				(width 0.1)
				(type default)
			)
			(layer "B.Fab")
		)
		(fp_line
			(start -0.2794 -0.1016)
			(end 0.2794 -0.1016)
			(stroke
				(width 0.1)
				(type default)
			)
			(layer "B.Fab")
		)
		(fp_line
			(start 0.2794 0.9906)
			(end -0.2794 0.9906)
			(stroke
				(width 0.1)
				(type default)
			)
			(layer "B.Fab")
		)
		(fp_line
			(start -0.2794 0.9906)
			(end -0.2794 -0.1016)
			(stroke
				(width 0.1)
				(type default)
			)
			(layer "B.Fab")
		)
		(pad "1" smd rect
			(at 0 0 270)
			(size 0.508 0.508)
			(layers "B.Cu" "B.Mask" "B.Paste")
			(net "P3V3_STBY")
		)
		(pad "2" smd rect
			(at 0 0.889 270)
			(size 0.508 0.508)
			(layers "B.Cu" "B.Mask" "B.Paste")
			(net "FM_BATTERY_SENSE_EN_R_N")
		)
		(zone
			(layer "B.Cu")
			(hatch none 0.5)
			(connect_pads
				(clearance 0)
			)
			(min_thickness 0.25)
			(keepout
				(tracks allowed)
				(vias not_allowed)
				(pads allowed)
				(copperpour not_allowed)
				(footprints allowed)
			)
			(placement
				(enabled no)
				(sheetname "")
			)
			(fill
				(thermal_gap 0.5)
				(thermal_bridge_width 0.5)
				(island_removal_mode 0)
			)
			(polygon
				(pts
					(xy 375.09577 -95.822516) (xy 375.09577 -95.314516) (xy 375.47677 -95.314516) (xy 375.47677 -95.822516)
				)
			)
		)
		(zone
			(layer "B.Cu")
			(hatch none 0.5)
			(connect_pads
				(clearance 0)
			)
			(min_thickness 0.25)
			(keepout
				(tracks not_allowed)
				(vias allowed)
				(pads allowed)
				(copperpour not_allowed)
				(footprints allowed)
			)
			(placement
				(enabled no)
				(sheetname "")
			)
			(fill
				(thermal_gap 0.5)
				(thermal_bridge_width 0.5)
				(island_removal_mode 0)
			)
			(polygon
				(pts
					(xy 375.47677 -95.822516) (xy 375.47677 -95.314516) (xy 375.09577 -95.314516) (xy 375.09577 -95.822516)
				)
			)
		)
	)
	(footprint ""
		(layer "B.Cu")
		(at 442.8871 -20.8788)
		(property "Reference" "Q9W2"
			(at 0.229362 -1.2065 0)
			(unlocked yes)
			(layer "B.SilkS")
			(effects
				(font
					(size 0.4064 0.254)
					(thickness 0.1524)
				)
				(justify left mirror)
			)
		)
		(property "Value" ""
			(at 0 0 0)
			(layer "B.Fab")
			(effects
				(font
					(size 1.27 1.27)
				)
				(justify mirror)
			)
		)
		(duplicate_pad_numbers_are_jumpers no)
		(fp_line
			(start -1.778 -0.5715)
			(end -1.778 0.3175)
			(stroke
				(width 0.1524)
				(type default)
			)
			(layer "B.SilkS")
		)
		(fp_line
			(start -1.778 2.4765)
			(end -1.778 1.5875)
			(stroke
				(width 0.1524)
				(type default)
			)
			(layer "B.SilkS")
		)
		(fp_line
			(start -0.9525 -0.5715)
			(end -1.778 -0.5715)
			(stroke
				(width 0.1524)
				(type default)
			)
			(layer "B.SilkS")
		)
		(fp_line
			(start -0.9525 2.4765)
			(end -1.778 2.4765)
			(stroke
				(width 0.1524)
				(type default)
			)
			(layer "B.SilkS")
		)
		(fp_line
			(start -0.381 0.635)
			(end -0.381 1.27)
			(stroke
				(width 0.1524)
				(type default)
			)
			(layer "B.SilkS")
		)
		(fp_circle
			(center 0.9525 -0.9271)
			(end 1.0795 -0.9271)
			(stroke
				(width 0.254)
				(type default)
			)
			(fill no)
			(layer "B.SilkS")
		)
		(fp_poly
			(pts
				(xy -1.778 2.4765) (xy -0.381 2.4765) (xy -0.381 -0.5715) (xy -1.778 -0.5715)
			)
			(stroke
				(width 0)
				(type default)
			)
			(fill no)
			(layer "B.CrtYd")
		)
		(fp_line
			(start -1.778 -0.5715)
			(end -0.381 -0.5715)
			(stroke
				(width 0.1)
				(type default)
			)
			(layer "B.Fab")
		)
		(fp_line
			(start -1.778 2.4765)
			(end -1.778 -0.5715)
			(stroke
				(width 0.1)
				(type default)
			)
			(layer "B.Fab")
		)
		(fp_line
			(start -0.381 -0.5715)
			(end -0.381 2.4765)
			(stroke
				(width 0.1)
				(type default)
			)
			(layer "B.Fab")
		)
		(fp_line
			(start -0.381 2.4765)
			(end -1.778 2.4765)
			(stroke
				(width 0.1)
				(type default)
			)
			(layer "B.Fab")
		)
		(fp_circle
			(center 0.9525 -0.9271)
			(end 1.0795 -0.9271)
			(stroke
				(width 0.254)
				(type default)
			)
			(fill no)
			(layer "B.Fab")
		)
		(pad "1" smd rect
			(at 0 0 180)
			(size 1.143 0.508)
			(layers "B.Cu" "B.Mask" "B.Paste")
			(net "FM_TPM_PRES_RST_N_R")
		)
		(pad "2" smd rect
			(at 0 1.905 180)
			(size 1.143 0.508)
			(layers "B.Cu" "B.Mask" "B.Paste")
			(net "GND")
		)
		(pad "3" smd rect
			(at -2.159 0.9525 180)
			(size 1.143 0.508)
			(layers "B.Cu" "B.Mask" "B.Paste")
			(net "FM_TPM_PRES_RST")
		)
	)
	(footprint ""
		(layer "B.Cu")
		(at 411.299914 -28.73756 90)
		(property "Reference" "C25W67"
			(at 0.8382 -0.67818 90)
			(unlocked yes)
			(layer "B.SilkS")
			(effects
				(font
					(size 0.4064 0.254)
					(thickness 0.1524)
				)
				(justify left mirror)
			)
		)
		(property "Value" ""
			(at 0 0 90)
			(layer "B.Fab")
			(effects
				(font
					(size 1.27 1.27)
				)
				(justify mirror)
			)
		)
		(duplicate_pad_numbers_are_jumpers no)
		(fp_poly
			(pts
				(xy -0.3048 -0.1016) (xy -0.3048 0.9906) (xy 0.3048 0.9906) (xy 0.3048 -0.1016)
			)
			(stroke
				(width 0)
				(type default)
			)
			(fill no)
			(layer "B.CrtYd")
		)
		(fp_line
			(start 0.3048 -0.1016)
			(end 0.3048 0.9906)
			(stroke
				(width 0.1)
				(type default)
			)
			(layer "B.Fab")
		)
		(fp_line
			(start -0.3048 -0.1016)
			(end 0.3048 -0.1016)
			(stroke
				(width 0.1)
				(type default)
			)
			(layer "B.Fab")
		)
		(fp_line
			(start 0.3048 0.9906)
			(end -0.3048 0.9906)
			(stroke
				(width 0.1)
				(type default)
			)
			(layer "B.Fab")
		)
		(fp_line
			(start -0.3048 0.9906)
			(end -0.3048 -0.1016)
			(stroke
				(width 0.1)
				(type default)
			)
			(layer "B.Fab")
		)
		(pad "1" smd rect
			(at 0 0 270)
			(size 0.508 0.508)
			(layers "B.Cu" "B.Mask" "B.Paste")
			(net "VCC_VA_3V3")
		)
		(pad "2" smd rect
			(at 0 0.889 270)
			(size 0.508 0.508)
			(layers "B.Cu" "B.Mask" "B.Paste")
			(net "GND")
		)
		(zone
			(layer "B.Cu")
			(hatch none 0.5)
			(connect_pads
				(clearance 0)
			)
			(min_thickness 0.25)
			(keepout
				(tracks allowed)
				(vias not_allowed)
				(pads allowed)
				(copperpour not_allowed)
				(footprints allowed)
			)
			(placement
				(enabled no)
				(sheetname "")
			)
			(fill
				(thermal_gap 0.5)
				(thermal_bridge_width 0.5)
				(island_removal_mode 0)
			)
			(polygon
				(pts
					(xy 411.553914 -28.99156) (xy 411.553914 -28.48356) (xy 411.934914 -28.48356) (xy 411.934914 -28.99156)
				)
			)
		)
		(zone
			(layer "B.Cu")
			(hatch none 0.5)
			(connect_pads
				(clearance 0)
			)
			(min_thickness 0.25)
			(keepout
				(tracks not_allowed)
				(vias allowed)
				(pads allowed)
				(copperpour not_allowed)
				(footprints allowed)
			)
			(placement
				(enabled no)
				(sheetname "")
			)
			(fill
				(thermal_gap 0.5)
				(thermal_bridge_width 0.5)
				(island_removal_mode 0)
			)
			(polygon
				(pts
					(xy 411.934914 -28.99156) (xy 411.934914 -28.48356) (xy 411.553914 -28.48356) (xy 411.553914 -28.99156)
				)
			)
		)
	)
	(footprint ""
		(layer "B.Cu")
		(at 80.731868 -12.954 -90)
		(property "Reference" "C5G79"
			(at -1.14681 0.76708 0)
			(unlocked yes)
			(layer "B.SilkS")
			(effects
				(font
					(size 0.7874 0.5842)
					(thickness 0.1524)
				)
				(justify mirror)
			)
		)
		(property "Value" ""
			(at 0 0 90)
			(layer "B.Fab")
			(effects
				(font
					(size 1.27 1.27)
				)
				(justify mirror)
			)
		)
		(duplicate_pad_numbers_are_jumpers no)
		(fp_rect
			(start 0.4953 1.6002)
			(end -0.4953 -0.2032)
			(stroke
				(width 0)
				(type default)
			)
			(fill no)
			(layer "B.CrtYd")
		)
		(fp_line
			(start -0.4953 1.6002)
			(end 0.4953 1.6002)
			(stroke
				(width 0.1)
				(type default)
			)
			(layer "B.Fab")
		)
		(fp_line
			(start 0.4953 1.6002)
			(end 0.4953 -0.2032)
			(stroke
				(width 0.1)
				(type default)
			)
			(layer "B.Fab")
		)
		(fp_line
			(start -0.4953 -0.2032)
			(end -0.4953 1.6002)
			(stroke
				(width 0.1)
				(type default)
			)
			(layer "B.Fab")
		)
		(fp_line
			(start 0.4953 -0.2032)
			(end -0.4953 -0.2032)
			(stroke
				(width 0.1)
				(type default)
			)
			(layer "B.Fab")
		)
		(pad "1" smd rect
			(at 0 0 90)
			(size 0.762 0.889)
			(layers "B.Cu" "B.Mask" "B.Paste")
			(net "PVDDQ_GHJ")
		)
		(pad "2" smd rect
			(at 0 1.397 90)
			(size 0.762 0.889)
			(layers "B.Cu" "B.Mask" "B.Paste")
			(net "GND")
		)
		(zone
			(layer "B.Cu")
			(hatch none 0.5)
			(connect_pads
				(clearance 0)
			)
			(min_thickness 0.25)
			(keepout
				(tracks not_allowed)
				(vias allowed)
				(pads allowed)
				(copperpour not_allowed)
				(footprints allowed)
			)
			(placement
				(enabled no)
				(sheetname "")
			)
			(fill
				(thermal_gap 0.5)
				(thermal_bridge_width 0.5)
				(island_removal_mode 0)
			)
			(polygon
				(pts
					(xy 79.779368 -12.573) (xy 80.287368 -12.573) (xy 80.287368 -13.335) (xy 79.779368 -13.335)
				)
			)
		)
	)
	(footprint ""
		(layer "B.Cu")
		(at 111.7727 -28.88234 90)
		(property "Reference" "C8T4"
			(at 0 0 90)
			(layer "B.SilkS")
			(hide yes)
			(effects
				(font
					(size 1.27 1.27)
				)
				(justify mirror)
			)
		)
		(property "Value" ""
			(at 0 0 90)
			(layer "B.Fab")
			(effects
				(font
					(size 1.27 1.27)
				)
				(justify mirror)
			)
		)
		(duplicate_pad_numbers_are_jumpers no)
		(fp_rect
			(start 0.500126 1.598422)
			(end -0.500126 -0.201422)
			(stroke
				(width 0)
				(type default)
			)
			(fill no)
			(layer "B.CrtYd")
		)
		(fp_line
			(start 0.500126 -0.201422)
			(end -0.500126 -0.201422)
			(stroke
				(width 0.1)
				(type default)
			)
			(layer "B.Fab")
		)
		(fp_line
			(start -0.500126 -0.201422)
			(end -0.500126 1.598422)
			(stroke
				(width 0.1)
				(type default)
			)
			(layer "B.Fab")
		)
		(fp_line
			(start 0.500126 1.598422)
			(end 0.500126 -0.201422)
			(stroke
				(width 0.1)
				(type default)
			)
			(layer "B.Fab")
		)
		(fp_line
			(start -0.500126 1.598422)
			(end 0.500126 1.598422)
			(stroke
				(width 0.1)
				(type default)
			)
			(layer "B.Fab")
		)
		(pad "1" smd rect
			(at 0 0)
			(size 0.889 0.9906)
			(layers "B.Cu" "B.Mask" "B.Paste")
			(net "PVDDQ_GHJ")
		)
		(pad "2" smd rect
			(at 0 1.397)
			(size 0.889 0.9906)
			(layers "B.Cu" "B.Mask" "B.Paste")
			(net "GND")
		)
		(zone
			(layer "B.Cu")
			(hatch none 0.5)
			(connect_pads
				(clearance 0)
			)
			(min_thickness 0.25)
			(keepout
				(tracks allowed)
				(vias not_allowed)
				(pads allowed)
				(copperpour not_allowed)
				(footprints allowed)
			)
			(placement
				(enabled no)
				(sheetname "")
			)
			(fill
				(thermal_gap 0.5)
				(thermal_bridge_width 0.5)
				(island_removal_mode 0)
			)
			(polygon
				(pts
					(xy 112.7252 -29.37764) (xy 112.2172 -29.37764) (xy 112.2172 -28.38704) (xy 112.7252 -28.38704)
				)
			)
		)
		(zone
			(layer "B.Cu")
			(hatch none 0.5)
			(connect_pads
				(clearance 0)
			)
			(min_thickness 0.25)
			(keepout
				(tracks not_allowed)
				(vias allowed)
				(pads allowed)
				(copperpour not_allowed)
				(footprints allowed)
			)
			(placement
				(enabled no)
				(sheetname "")
			)
			(fill
				(thermal_gap 0.5)
				(thermal_bridge_width 0.5)
				(island_removal_mode 0)
			)
			(polygon
				(pts
					(xy 112.7252 -29.37764) (xy 112.2172 -29.37764) (xy 112.2172 -28.38704) (xy 112.7252 -28.38704)
				)
			)
		)
	)
	(footprint ""
		(layer "B.Cu")
		(at 88.392 -135.4074 90)
		(property "Reference" "C8M3"
			(at -1.848866 0.752348 90)
			(unlocked yes)
			(layer "B.SilkS")
			(effects
				(font
					(size 1.27 0.9652)
					(thickness 0.1524)
				)
				(justify mirror)
			)
		)
		(property "Value" ""
			(at 0 0 90)
			(layer "B.Fab")
			(effects
				(font
					(size 1.27 1.27)
				)
				(justify mirror)
			)
		)
		(duplicate_pad_numbers_are_jumpers no)
		(fp_rect
			(start 0.500126 1.598422)
			(end -0.500126 -0.201422)
			(stroke
				(width 0)
				(type default)
			)
			(fill no)
			(layer "B.CrtYd")
		)
		(fp_line
			(start 0.500126 -0.201422)
			(end -0.500126 -0.201422)
			(stroke
				(width 0.1)
				(type default)
			)
			(layer "B.Fab")
		)
		(fp_line
			(start -0.500126 -0.201422)
			(end -0.500126 1.598422)
			(stroke
				(width 0.1)
				(type default)
			)
			(layer "B.Fab")
		)
		(fp_line
			(start 0.500126 1.598422)
			(end 0.500126 -0.201422)
			(stroke
				(width 0.1)
				(type default)
			)
			(layer "B.Fab")
		)
		(fp_line
			(start -0.500126 1.598422)
			(end 0.500126 1.598422)
			(stroke
				(width 0.1)
				(type default)
			)
			(layer "B.Fab")
		)
		(pad "1" smd rect
			(at 0 0)
			(size 0.889 0.9906)
			(layers "B.Cu" "B.Mask" "B.Paste")
			(net "PVDDQ_KLM")
		)
		(pad "2" smd rect
			(at 0 1.397)
			(size 0.889 0.9906)
			(layers "B.Cu" "B.Mask" "B.Paste")
			(net "GND")
		)
		(zone
			(layer "B.Cu")
			(hatch none 0.5)
			(connect_pads
				(clearance 0)
			)
			(min_thickness 0.25)
			(keepout
				(tracks not_allowed)
				(vias allowed)
				(pads allowed)
				(copperpour not_allowed)
				(footprints allowed)
			)
			(placement
				(enabled no)
				(sheetname "")
			)
			(fill
				(thermal_gap 0.5)
				(thermal_bridge_width 0.5)
				(island_removal_mode 0)
			)
			(polygon
				(pts
					(xy 89.3445 -135.9027) (xy 88.8365 -135.9027) (xy 88.8365 -134.9121) (xy 89.3445 -134.9121)
				)
			)
		)
		(zone
			(layer "B.Cu")
			(hatch none 0.5)
			(connect_pads
				(clearance 0)
			)
			(min_thickness 0.25)
			(keepout
				(tracks allowed)
				(vias not_allowed)
				(pads allowed)
				(copperpour not_allowed)
				(footprints allowed)
			)
			(placement
				(enabled no)
				(sheetname "")
			)
			(fill
				(thermal_gap 0.5)
				(thermal_bridge_width 0.5)
				(island_removal_mode 0)
			)
			(polygon
				(pts
					(xy 89.3445 -135.9027) (xy 88.8365 -135.9027) (xy 88.8365 -134.9121) (xy 89.3445 -134.9121)
				)
			)
		)
	)
	(footprint ""
		(layer "B.Cu")
		(at 375.412 -134.8105)
		(property "Reference" "C3M20"
			(at 0 0 0)
			(layer "B.SilkS")
			(hide yes)
			(effects
				(font
					(size 1.27 1.27)
				)
				(justify mirror)
			)
		)
		(property "Value" ""
			(at 0 0 0)
			(layer "B.Fab")
			(effects
				(font
					(size 1.27 1.27)
				)
				(justify mirror)
			)
		)
		(duplicate_pad_numbers_are_jumpers no)
		(fp_poly
			(pts
				(xy -0.3048 -0.1016) (xy -0.3048 0.9906) (xy 0.3048 0.9906) (xy 0.3048 -0.1016)
			)
			(stroke
				(width 0)
				(type default)
			)
			(fill no)
			(layer "B.CrtYd")
		)
		(fp_line
			(start -0.3048 -0.1016)
			(end 0.3048 -0.1016)
			(stroke
				(width 0.1)
				(type default)
			)
			(layer "B.Fab")
		)
		(fp_line
			(start -0.3048 0.9906)
			(end -0.3048 -0.1016)
			(stroke
				(width 0.1)
				(type default)
			)
			(layer "B.Fab")
		)
		(fp_line
			(start 0.3048 -0.1016)
			(end 0.3048 0.9906)
			(stroke
				(width 0.1)
				(type default)
			)
			(layer "B.Fab")
		)
		(fp_line
			(start 0.3048 0.9906)
			(end -0.3048 0.9906)
			(stroke
				(width 0.1)
				(type default)
			)
			(layer "B.Fab")
		)
		(pad "1" smd rect
			(at 0 0 180)
			(size 0.508 0.508)
			(layers "B.Cu" "B.Mask" "B.Paste")
			(net "P1V05_PCH_STBY_VCCA_PLL0")
		)
		(pad "2" smd rect
			(at 0 0.889 180)
			(size 0.508 0.508)
			(layers "B.Cu" "B.Mask" "B.Paste")
			(net "GND")
		)
		(zone
			(layer "B.Cu")
			(hatch none 0.5)
			(connect_pads
				(clearance 0)
			)
			(min_thickness 0.25)
			(keepout
				(tracks allowed)
				(vias not_allowed)
				(pads allowed)
				(copperpour not_allowed)
				(footprints allowed)
			)
			(placement
				(enabled no)
				(sheetname "")
			)
			(fill
				(thermal_gap 0.5)
				(thermal_bridge_width 0.5)
				(island_removal_mode 0)
			)
			(polygon
				(pts
					(xy 375.666 -134.5565) (xy 375.158 -134.5565) (xy 375.158 -134.1755) (xy 375.666 -134.1755)
				)
			)
		)
		(zone
			(layer "B.Cu")
			(hatch none 0.5)
			(connect_pads
				(clearance 0)
			)
			(min_thickness 0.25)
			(keepout
				(tracks not_allowed)
				(vias allowed)
				(pads allowed)
				(copperpour not_allowed)
				(footprints allowed)
			)
			(placement
				(enabled no)
				(sheetname "")
			)
			(fill
				(thermal_gap 0.5)
				(thermal_bridge_width 0.5)
				(island_removal_mode 0)
			)
			(polygon
				(pts
					(xy 375.666 -134.1755) (xy 375.158 -134.1755) (xy 375.158 -134.5565) (xy 375.666 -134.5565)
				)
			)
		)
	)
	(footprint ""
		(layer "B.Cu")
		(at 341.666068 -77.694536)
		(property "Reference" "C3P14"
			(at 0 0 0)
			(layer "B.SilkS")
			(hide yes)
			(effects
				(font
					(size 1.27 1.27)
				)
				(justify mirror)
			)
		)
		(property "Value" ""
			(at 0 0 0)
			(layer "B.Fab")
			(effects
				(font
					(size 1.27 1.27)
				)
				(justify mirror)
			)
		)
		(duplicate_pad_numbers_are_jumpers no)
		(fp_poly
			(pts
				(xy -0.3048 -0.1016) (xy -0.3048 0.9906) (xy 0.3048 0.9906) (xy 0.3048 -0.1016)
			)
			(stroke
				(width 0)
				(type default)
			)
			(fill no)
			(layer "B.CrtYd")
		)
		(fp_line
			(start -0.3048 -0.1016)
			(end 0.3048 -0.1016)
			(stroke
				(width 0.1)
				(type default)
			)
			(layer "B.Fab")
		)
		(fp_line
			(start -0.3048 0.9906)
			(end -0.3048 -0.1016)
			(stroke
				(width 0.1)
				(type default)
			)
			(layer "B.Fab")
		)
		(fp_line
			(start 0.3048 -0.1016)
			(end 0.3048 0.9906)
			(stroke
				(width 0.1)
				(type default)
			)
			(layer "B.Fab")
		)
		(fp_line
			(start 0.3048 0.9906)
			(end -0.3048 0.9906)
			(stroke
				(width 0.1)
				(type default)
			)
			(layer "B.Fab")
		)
		(pad "1" smd rect
			(at 0 0 180)
			(size 0.508 0.508)
			(layers "B.Cu" "B.Mask" "B.Paste")
			(net "P3E_CPU0_PE1_SS_TXP<1>")
		)
		(pad "2" smd rect
			(at 0 0.889 180)
			(size 0.508 0.508)
			(layers "B.Cu" "B.Mask" "B.Paste")
			(net "P3E_CPU0_PE1_SS_C_TXP<1>")
		)
		(zone
			(layer "B.Cu")
			(hatch none 0.5)
			(connect_pads
				(clearance 0)
			)
			(min_thickness 0.25)
			(keepout
				(tracks allowed)
				(vias not_allowed)
				(pads allowed)
				(copperpour not_allowed)
				(footprints allowed)
			)
			(placement
				(enabled no)
				(sheetname "")
			)
			(fill
				(thermal_gap 0.5)
				(thermal_bridge_width 0.5)
				(island_removal_mode 0)
			)
			(polygon
				(pts
					(xy 341.920068 -77.440536) (xy 341.412068 -77.440536) (xy 341.412068 -77.059536) (xy 341.920068 -77.059536)
				)
			)
		)
		(zone
			(layer "B.Cu")
			(hatch none 0.5)
			(connect_pads
				(clearance 0)
			)
			(min_thickness 0.25)
			(keepout
				(tracks not_allowed)
				(vias allowed)
				(pads allowed)
				(copperpour not_allowed)
				(footprints allowed)
			)
			(placement
				(enabled no)
				(sheetname "")
			)
			(fill
				(thermal_gap 0.5)
				(thermal_bridge_width 0.5)
				(island_removal_mode 0)
			)
			(polygon
				(pts
					(xy 341.920068 -77.059536) (xy 341.412068 -77.059536) (xy 341.412068 -77.440536) (xy 341.920068 -77.440536)
				)
			)
		)
	)
	(footprint ""
		(layer "B.Cu")
		(at 210.847432 -73.279 -90)
		(property "Reference" "C6P18"
			(at -1.87833 -3.909568 0)
			(unlocked yes)
			(layer "B.SilkS")
			(effects
				(font
					(size 0.7874 0.5842)
					(thickness 0.1524)
				)
				(justify mirror)
			)
		)
		(property "Value" ""
			(at 0 0 90)
			(layer "B.Fab")
			(effects
				(font
					(size 1.27 1.27)
				)
				(justify mirror)
			)
		)
		(duplicate_pad_numbers_are_jumpers no)
		(fp_line
			(start -2.286 7.366)
			(end -1.600708 7.366)
			(stroke
				(width 0.1524)
				(type default)
			)
			(layer "B.SilkS")
		)
		(fp_line
			(start -2.286 7.366)
			(end -2.286 1.63195)
			(stroke
				(width 0.1524)
				(type default)
			)
			(layer "B.SilkS")
		)
		(fp_line
			(start 2.286 7.366)
			(end 1.60147 7.366)
			(stroke
				(width 0.1524)
				(type default)
			)
			(layer "B.SilkS")
		)
		(fp_line
			(start 2.286 7.366)
			(end 2.286 1.632712)
			(stroke
				(width 0.1524)
				(type default)
			)
			(layer "B.SilkS")
		)
		(fp_line
			(start -2.504948 1.633728)
			(end -1.6002 1.633728)
			(stroke
				(width 0.1524)
				(type default)
			)
			(layer "B.SilkS")
		)
		(fp_line
			(start 2.563114 1.633728)
			(end 1.6002 1.633728)
			(stroke
				(width 0.1524)
				(type default)
			)
			(layer "B.SilkS")
		)
		(fp_line
			(start -2.504948 -1.616456)
			(end -2.504948 1.633728)
			(stroke
				(width 0.1524)
				(type default)
			)
			(layer "B.SilkS")
		)
		(fp_line
			(start -1.6002 -1.616456)
			(end -2.504948 -1.616456)
			(stroke
				(width 0.1524)
				(type default)
			)
			(layer "B.SilkS")
		)
		(fp_line
			(start 1.6002 -1.616456)
			(end 2.563114 -1.616456)
			(stroke
				(width 0.1524)
				(type default)
			)
			(layer "B.SilkS")
		)
		(fp_line
			(start 2.563114 -1.616456)
			(end 2.563114 1.633728)
			(stroke
				(width 0.1524)
				(type default)
			)
			(layer "B.SilkS")
		)
		(fp_rect
			(start 2.286 7.366)
			(end -2.286 -0.254)
			(stroke
				(width 0)
				(type default)
			)
			(fill no)
			(layer "B.CrtYd")
		)
		(fp_line
			(start -2.286 7.366)
			(end 2.286 7.366)
			(stroke
				(width 0.1)
				(type default)
			)
			(layer "B.Fab")
		)
		(fp_line
			(start 2.286 7.366)
			(end 2.286 -0.254)
			(stroke
				(width 0.1)
				(type default)
			)
			(layer "B.Fab")
		)
		(fp_line
			(start -2.286 -0.254)
			(end -2.286 7.366)
			(stroke
				(width 0.1)
				(type default)
			)
			(layer "B.Fab")
		)
		(fp_line
			(start 2.286 -0.254)
			(end -2.286 -0.254)
			(stroke
				(width 0.1)
				(type default)
			)
			(layer "B.Fab")
		)
		(pad "1" smd rect
			(at 0 0 90)
			(size 2.54 3.048)
			(layers "B.Cu" "B.Mask" "B.Paste")
			(net "PVCCIN_CPU0")
		)
		(pad "2" smd rect
			(at 0 7.112 90)
			(size 2.54 3.048)
			(layers "B.Cu" "B.Mask" "B.Paste")
			(net "GND")
		)
	)
	(footprint ""
		(layer "B.Cu")
		(at 4.3942 -115.65382)
		(property "Reference" "Q1B1"
			(at -1.310894 -2.428748 180)
			(unlocked yes)
			(layer "B.SilkS")
			(effects
				(font
					(size 0.7874 0.5842)
					(thickness 0.1524)
				)
				(justify left mirror)
			)
		)
		(property "Value" ""
			(at 0 0 0)
			(layer "B.Fab")
			(effects
				(font
					(size 1.27 1.27)
				)
				(justify mirror)
			)
		)
		(duplicate_pad_numbers_are_jumpers no)
		(fp_line
			(start 0.245364 -1.379982)
			(end -3.15468 -1.379982)
			(stroke
				(width 0.1524)
				(type default)
			)
			(layer "B.SilkS")
		)
		(fp_line
			(start 0.245364 2.020062)
			(end -3.15468 2.020062)
			(stroke
				(width 0.1524)
				(type default)
			)
			(layer "B.SilkS")
		)
		(fp_circle
			(center 0.36703 -1.740408)
			(end 0.49403 -1.740408)
			(stroke
				(width 0.254)
				(type default)
			)
			(fill no)
			(layer "B.SilkS")
		)
		(fp_poly
			(pts
				(xy -0.890016 -0.82296) (xy -0.890016 1.46304) (xy -3.404616 1.46304) (xy -3.404616 1.13284) (xy -2.617216 1.13284)
				(xy -2.617216 0.811022) (xy -3.404616 0.811022) (xy -3.404616 0.480822) (xy -2.617216 0.480822)
				(xy -2.617216 0.159258) (xy -3.404616 0.159258) (xy -3.404616 -0.170942) (xy -2.617216 -0.170942)
				(xy -2.617216 -0.49276) (xy -3.404616 -0.49276) (xy -3.404616 -0.82296)
			)
			(stroke
				(width 0)
				(type default)
			)
			(fill yes)
			(layer "B.Paste")
		)
		(fp_poly
			(pts
				(xy 0.245364 -1.379982) (xy 0.245364 2.020062) (xy -3.15468 2.020062) (xy -3.15468 -1.379982)
			)
			(stroke
				(width 0)
				(type default)
			)
			(fill no)
			(layer "B.CrtYd")
		)
		(fp_line
			(start -3.15468 -1.379982)
			(end -3.15468 2.020062)
			(stroke
				(width 0.1)
				(type default)
			)
			(layer "B.Fab")
		)
		(fp_line
			(start -3.15468 2.020062)
			(end 0.245364 2.020062)
			(stroke
				(width 0.1)
				(type default)
			)
			(layer "B.Fab")
		)
		(fp_line
			(start 0.245364 -1.379982)
			(end -3.15468 -1.379982)
			(stroke
				(width 0.1)
				(type default)
			)
			(layer "B.Fab")
		)
		(fp_line
			(start 0.245364 2.020062)
			(end 0.245364 -1.379982)
			(stroke
				(width 0.1)
				(type default)
			)
			(layer "B.Fab")
		)
		(fp_circle
			(center 0.94996 -1.512316)
			(end 1.07696 -1.512316)
			(stroke
				(width 0.254)
				(type default)
			)
			(fill no)
			(layer "B.Fab")
		)
		(pad "1" smd custom
			(at 0 0 180)
			(size 0.24765 0.24765)
			(layers "B.Cu" "B.Mask" "B.Paste")
			(net "P12V_FAN")
			(options
				(clearance outline)
				(anchor circle)
			)
			(primitives
				(gr_poly
					(pts
						(xy 0.4953 -0.8255) (xy 0.4953 0.8255) (xy -0.4953 0.8255) (xy -0.4953 0.4953) (xy 0.0127 0.4953)
						(xy 0.0127 0.1651) (xy -0.4953 0.1651) (xy -0.4953 -0.1651) (xy 0.0127 -0.1651) (xy 0.0127 -0.4953)
						(xy -0.4953 -0.4953) (xy -0.4953 -0.8255)
					)
					(width 0)
					(fill yes)
				)
			)
		)
		(pad "4" smd rect
			(at 0 1.30048 180)
			(size 0.9906 0.3302)
			(layers "B.Cu" "B.Mask" "B.Paste")
			(net "P12V_FAN_SWITCH_G")
		)
		(pad "5" smd custom
			(at -2.147316 0.32004 180)
			(size 0.5715 0.5715)
			(layers "B.Cu" "B.Mask" "B.Paste")
			(net "P12V_STBY")
			(options
				(clearance outline)
				(anchor circle)
			)
			(primitives
				(gr_poly
					(pts
						(xy -1.2573 1.143) (xy -1.2573 -1.143) (xy 1.2573 -1.143) (xy 1.2573 -0.8128) (xy 0.4699 -0.8128)
						(xy 0.4699 -0.490982) (xy 1.2573 -0.490982) (xy 1.2573 -0.160782) (xy 0.4699 -0.160782) (xy 0.4699 0.160782)
						(xy 1.2573 0.160782) (xy 1.2573 0.490982) (xy 0.4699 0.490982) (xy 0.4699 0.8128) (xy 1.2573 0.8128)
						(xy 1.2573 1.143)
					)
					(width 0)
					(fill yes)
				)
			)
		)
	)
	(footprint ""
		(layer "B.Cu")
		(at 114.046254 -79.60614 180)
		(property "Reference" "C7P4"
			(at 0 0 0)
			(layer "B.SilkS")
			(hide yes)
			(effects
				(font
					(size 1.27 1.27)
				)
				(justify mirror)
			)
		)
		(property "Value" ""
			(at 0 0 0)
			(layer "B.Fab")
			(effects
				(font
					(size 1.27 1.27)
				)
				(justify mirror)
			)
		)
		(duplicate_pad_numbers_are_jumpers no)
		(fp_poly
			(pts
				(xy 0.7239 -0.2159) (xy -0.7239 -0.2159) (xy -0.7239 1.9939) (xy 0.7239 1.9939)
			)
			(stroke
				(width 0)
				(type default)
			)
			(fill no)
			(layer "B.CrtYd")
		)
		(fp_line
			(start 0.7239 1.9939)
			(end -0.7239 1.9939)
			(stroke
				(width 0.1)
				(type default)
			)
			(layer "B.Fab")
		)
		(fp_line
			(start 0.7239 -0.2159)
			(end 0.7239 1.9939)
			(stroke
				(width 0.1)
				(type default)
			)
			(layer "B.Fab")
		)
		(fp_line
			(start -0.7239 1.9939)
			(end -0.7239 -0.2159)
			(stroke
				(width 0.1)
				(type default)
			)
			(layer "B.Fab")
		)
		(fp_line
			(start -0.7239 -0.2159)
			(end 0.7239 -0.2159)
			(stroke
				(width 0.1)
				(type default)
			)
			(layer "B.Fab")
		)
		(pad "1" smd rect
			(at 0 0)
			(size 1.27 1.016)
			(layers "B.Cu" "B.Mask" "B.Paste")
			(net "PVCCMCP_CPU1")
		)
		(pad "2" smd rect
			(at 0 1.778)
			(size 1.27 1.016)
			(layers "B.Cu" "B.Mask" "B.Paste")
			(net "GND")
		)
		(zone
			(layer "B.Cu")
			(hatch none 0.5)
			(connect_pads
				(clearance 0)
			)
			(min_thickness 0.25)
			(keepout
				(tracks not_allowed)
				(vias allowed)
				(pads allowed)
				(copperpour not_allowed)
				(footprints allowed)
			)
			(placement
				(enabled no)
				(sheetname "")
			)
			(fill
				(thermal_gap 0.5)
				(thermal_bridge_width 0.5)
				(island_removal_mode 0)
			)
			(polygon
				(pts
					(xy 113.411254 -80.11414) (xy 114.681254 -80.11414) (xy 114.681254 -80.87614) (xy 113.411254 -80.87614)
				)
			)
		)
	)
	(footprint ""
		(layer "B.Cu")
		(at 442.262006 -43.54195 180)
		(property "Reference" "R25W40"
			(at 0 0 0)
			(layer "B.SilkS")
			(hide yes)
			(effects
				(font
					(size 1.27 1.27)
				)
				(justify mirror)
			)
		)
		(property "Value" "*"
			(at -0.064008 -4.108196 180)
			(unlocked yes)
			(layer "B.Fab")
			(hide yes)
			(effects
				(font
					(size 1.27 1.016)
					(thickness 0.1524)
				)
				(justify mirror)
			)
		)
		(property "Device Type" "120R2F-GP_RCL_GP-120R2F-GP,64.A"
			(at -0.064008 -5.632196 180)
			(unlocked yes)
			(layer "B.Fab")
			(hide yes)
			(effects
				(font
					(size 1.27 1.016)
					(thickness 0.1524)
				)
				(justify mirror)
			)
		)
		(duplicate_pad_numbers_are_jumpers no)
		(fp_line
			(start 0.508 -0.9398)
			(end 0.508 0.9398)
			(stroke
				(width 0.1524)
				(type default)
			)
			(layer "B.SilkS")
		)
		(fp_line
			(start -0.508 -0.9398)
			(end 0.508 -0.9398)
			(stroke
				(width 0.1524)
				(type default)
			)
			(layer "B.SilkS")
		)
		(fp_rect
			(start 0.508 0.9398)
			(end -0.508 -0.9398)
			(stroke
				(width 0)
				(type default)
			)
			(fill no)
			(layer "B.CrtYd")
		)
		(fp_rect
			(start 0.508 0.9398)
			(end -0.508 -0.9398)
			(stroke
				(width 0)
				(type default)
			)
			(fill no)
			(layer "B.Fab")
		)
		(pad "1" smd custom
			(at 0 -0.4445)
			(size 0.1397 0.1397)
			(layers "B.Cu" "B.Mask" "B.Paste")
			(net "BMC_M_A2")
			(options
				(clearance outline)
				(anchor circle)
			)
			(primitives
				(gr_poly
					(pts
						(arc
							(start -0.1778 0.2794)
							(mid -0.249642 0.249642)
							(end -0.2794 0.1778)
						)
						(arc
							(start -0.2794 -0.1778)
							(mid -0.249642 -0.249642)
							(end -0.1778 -0.2794)
						)
						(arc
							(start 0.1778 -0.2794)
							(mid 0.249642 -0.249642)
							(end 0.2794 -0.1778)
						)
						(arc
							(start 0.2794 0.1778)
							(mid 0.249642 0.249642)
							(end 0.1778 0.2794)
						)
					)
					(width 0)
					(fill yes)
				)
			)
		)
		(pad "2" smd custom
			(at 0 0.4445)
			(size 0.1397 0.1397)
			(layers "B.Cu" "B.Mask" "B.Paste")
			(net "P1V2_AUX_BMC")
			(options
				(clearance outline)
				(anchor circle)
			)
			(primitives
				(gr_poly
					(pts
						(arc
							(start -0.1778 0.2794)
							(mid -0.249642 0.249642)
							(end -0.2794 0.1778)
						)
						(arc
							(start -0.2794 -0.1778)
							(mid -0.249642 -0.249642)
							(end -0.1778 -0.2794)
						)
						(arc
							(start 0.1778 -0.2794)
							(mid 0.249642 -0.249642)
							(end 0.2794 -0.1778)
						)
						(arc
							(start 0.2794 0.1778)
							(mid 0.249642 0.249642)
							(end 0.1778 0.2794)
						)
					)
					(width 0)
					(fill yes)
				)
			)
		)
	)
	(footprint ""
		(layer "B.Cu")
		(at 309.436516 -28.944824)
		(property "Reference" "R8W9"
			(at 0.8382 -0.67818 0)
			(unlocked yes)
			(layer "B.SilkS")
			(effects
				(font
					(size 0.4064 0.254)
					(thickness 0.1524)
				)
				(justify left mirror)
			)
		)
		(property "Value" ""
			(at 0 0 0)
			(layer "B.Fab")
			(effects
				(font
					(size 1.27 1.27)
				)
				(justify mirror)
			)
		)
		(duplicate_pad_numbers_are_jumpers no)
		(fp_poly
			(pts
				(xy 0.2794 -0.1016) (xy -0.2794 -0.1016) (xy -0.2794 0.9906) (xy 0.2794 0.9906)
			)
			(stroke
				(width 0)
				(type default)
			)
			(fill no)
			(layer "B.CrtYd")
		)
		(fp_line
			(start -0.2794 -0.1016)
			(end 0.2794 -0.1016)
			(stroke
				(width 0.1)
				(type default)
			)
			(layer "B.Fab")
		)
		(fp_line
			(start -0.2794 0.9906)
			(end -0.2794 -0.1016)
			(stroke
				(width 0.1)
				(type default)
			)
			(layer "B.Fab")
		)
		(fp_line
			(start 0.2794 -0.1016)
			(end 0.2794 0.9906)
			(stroke
				(width 0.1)
				(type default)
			)
			(layer "B.Fab")
		)
		(fp_line
			(start 0.2794 0.9906)
			(end -0.2794 0.9906)
			(stroke
				(width 0.1)
				(type default)
			)
			(layer "B.Fab")
		)
		(pad "1" smd rect
			(at 0 0 180)
			(size 0.508 0.508)
			(layers "B.Cu" "B.Mask" "B.Paste")
			(net "P3V3_STBY")
		)
		(pad "2" smd rect
			(at 0 0.889 180)
			(size 0.508 0.508)
			(layers "B.Cu" "B.Mask" "B.Paste")
			(net "IRQ_DIMM_SAVE_LVT3_CPU1")
		)
		(zone
			(layer "B.Cu")
			(hatch none 0.5)
			(connect_pads
				(clearance 0)
			)
			(min_thickness 0.25)
			(keepout
				(tracks allowed)
				(vias not_allowed)
				(pads allowed)
				(copperpour not_allowed)
				(footprints allowed)
			)
			(placement
				(enabled no)
				(sheetname "")
			)
			(fill
				(thermal_gap 0.5)
				(thermal_bridge_width 0.5)
				(island_removal_mode 0)
			)
			(polygon
				(pts
					(xy 309.690516 -28.690824) (xy 309.182516 -28.690824) (xy 309.182516 -28.309824) (xy 309.690516 -28.309824)
				)
			)
		)
		(zone
			(layer "B.Cu")
			(hatch none 0.5)
			(connect_pads
				(clearance 0)
			)
			(min_thickness 0.25)
			(keepout
				(tracks not_allowed)
				(vias allowed)
				(pads allowed)
				(copperpour not_allowed)
				(footprints allowed)
			)
			(placement
				(enabled no)
				(sheetname "")
			)
			(fill
				(thermal_gap 0.5)
				(thermal_bridge_width 0.5)
				(island_removal_mode 0)
			)
			(polygon
				(pts
					(xy 309.690516 -28.309824) (xy 309.182516 -28.309824) (xy 309.182516 -28.690824) (xy 309.690516 -28.690824)
				)
			)
		)
	)
	(footprint ""
		(layer "B.Cu")
		(at 491.41888 -132.1816 180)
		(property "Reference" "R6W50"
			(at 0.8382 -0.67818 180)
			(unlocked yes)
			(layer "B.SilkS")
			(effects
				(font
					(size 0.4064 0.254)
					(thickness 0.1524)
				)
				(justify left mirror)
			)
		)
		(property "Value" ""
			(at 0 0 0)
			(layer "B.Fab")
			(effects
				(font
					(size 1.27 1.27)
				)
				(justify mirror)
			)
		)
		(duplicate_pad_numbers_are_jumpers no)
		(fp_poly
			(pts
				(xy 0.2794 -0.1016) (xy -0.2794 -0.1016) (xy -0.2794 0.9906) (xy 0.2794 0.9906)
			)
			(stroke
				(width 0)
				(type default)
			)
			(fill no)
			(layer "B.CrtYd")
		)
		(fp_line
			(start 0.2794 0.9906)
			(end -0.2794 0.9906)
			(stroke
				(width 0.1)
				(type default)
			)
			(layer "B.Fab")
		)
		(fp_line
			(start 0.2794 -0.1016)
			(end 0.2794 0.9906)
			(stroke
				(width 0.1)
				(type default)
			)
			(layer "B.Fab")
		)
		(fp_line
			(start -0.2794 0.9906)
			(end -0.2794 -0.1016)
			(stroke
				(width 0.1)
				(type default)
			)
			(layer "B.Fab")
		)
		(fp_line
			(start -0.2794 -0.1016)
			(end 0.2794 -0.1016)
			(stroke
				(width 0.1)
				(type default)
			)
			(layer "B.Fab")
		)
		(pad "1" smd rect
			(at 0 0)
			(size 0.508 0.508)
			(layers "B.Cu" "B.Mask" "B.Paste")
			(net "P3V3_STBY")
		)
		(pad "2" smd rect
			(at 0 0.889)
			(size 0.508 0.508)
			(layers "B.Cu" "B.Mask" "B.Paste")
			(net "SPA_MID_DBG2_RX")
		)
		(zone
			(layer "B.Cu")
			(hatch none 0.5)
			(connect_pads
				(clearance 0)
			)
			(min_thickness 0.25)
			(keepout
				(tracks not_allowed)
				(vias allowed)
				(pads allowed)
				(copperpour not_allowed)
				(footprints allowed)
			)
			(placement
				(enabled no)
				(sheetname "")
			)
			(fill
				(thermal_gap 0.5)
				(thermal_bridge_width 0.5)
				(island_removal_mode 0)
			)
			(polygon
				(pts
					(xy 491.16488 -132.8166) (xy 491.67288 -132.8166) (xy 491.67288 -132.4356) (xy 491.16488 -132.4356)
				)
			)
		)
		(zone
			(layer "B.Cu")
			(hatch none 0.5)
			(connect_pads
				(clearance 0)
			)
			(min_thickness 0.25)
			(keepout
				(tracks allowed)
				(vias not_allowed)
				(pads allowed)
				(copperpour not_allowed)
				(footprints allowed)
			)
			(placement
				(enabled no)
				(sheetname "")
			)
			(fill
				(thermal_gap 0.5)
				(thermal_bridge_width 0.5)
				(island_removal_mode 0)
			)
			(polygon
				(pts
					(xy 491.16488 -132.4356) (xy 491.67288 -132.4356) (xy 491.67288 -132.8166) (xy 491.16488 -132.8166)
				)
			)
		)
	)
	(footprint ""
		(layer "B.Cu")
		(at 440.4614 -52.2986)
		(property "Reference" "C2R10"
			(at 0 0 0)
			(layer "B.SilkS")
			(hide yes)
			(effects
				(font
					(size 1.27 1.27)
				)
				(justify mirror)
			)
		)
		(property "Value" ""
			(at 0 0 0)
			(layer "B.Fab")
			(effects
				(font
					(size 1.27 1.27)
				)
				(justify mirror)
			)
		)
		(duplicate_pad_numbers_are_jumpers no)
		(fp_poly
			(pts
				(xy -0.3048 -0.1016) (xy -0.3048 0.9906) (xy 0.3048 0.9906) (xy 0.3048 -0.1016)
			)
			(stroke
				(width 0)
				(type default)
			)
			(fill no)
			(layer "B.CrtYd")
		)
		(fp_line
			(start -0.3048 -0.1016)
			(end 0.3048 -0.1016)
			(stroke
				(width 0.1)
				(type default)
			)
			(layer "B.Fab")
		)
		(fp_line
			(start -0.3048 0.9906)
			(end -0.3048 -0.1016)
			(stroke
				(width 0.1)
				(type default)
			)
			(layer "B.Fab")
		)
		(fp_line
			(start 0.3048 -0.1016)
			(end 0.3048 0.9906)
			(stroke
				(width 0.1)
				(type default)
			)
			(layer "B.Fab")
		)
		(fp_line
			(start 0.3048 0.9906)
			(end -0.3048 0.9906)
			(stroke
				(width 0.1)
				(type default)
			)
			(layer "B.Fab")
		)
		(pad "1" smd rect
			(at 0 0 180)
			(size 0.508 0.508)
			(layers "B.Cu" "B.Mask" "B.Paste")
			(net "P3E_CPU0_PE3_OCP_TXP<7>")
		)
		(pad "2" smd rect
			(at 0 0.889 180)
			(size 0.508 0.508)
			(layers "B.Cu" "B.Mask" "B.Paste")
			(net "P3E_OCP_CPU0_PE3_C_TXP<7>")
		)
		(zone
			(layer "B.Cu")
			(hatch none 0.5)
			(connect_pads
				(clearance 0)
			)
			(min_thickness 0.25)
			(keepout
				(tracks allowed)
				(vias not_allowed)
				(pads allowed)
				(copperpour not_allowed)
				(footprints allowed)
			)
			(placement
				(enabled no)
				(sheetname "")
			)
			(fill
				(thermal_gap 0.5)
				(thermal_bridge_width 0.5)
				(island_removal_mode 0)
			)
			(polygon
				(pts
					(xy 440.7154 -52.0446) (xy 440.2074 -52.0446) (xy 440.2074 -51.6636) (xy 440.7154 -51.6636)
				)
			)
		)
		(zone
			(layer "B.Cu")
			(hatch none 0.5)
			(connect_pads
				(clearance 0)
			)
			(min_thickness 0.25)
			(keepout
				(tracks not_allowed)
				(vias allowed)
				(pads allowed)
				(copperpour not_allowed)
				(footprints allowed)
			)
			(placement
				(enabled no)
				(sheetname "")
			)
			(fill
				(thermal_gap 0.5)
				(thermal_bridge_width 0.5)
				(island_removal_mode 0)
			)
			(polygon
				(pts
					(xy 440.7154 -51.6636) (xy 440.2074 -51.6636) (xy 440.2074 -52.0446) (xy 440.7154 -52.0446)
				)
			)
		)
	)
	(footprint ""
		(layer "B.Cu")
		(at 269.902686 -79.60614 180)
		(property "Reference" "C5P13"
			(at 0 0 0)
			(layer "B.SilkS")
			(hide yes)
			(effects
				(font
					(size 1.27 1.27)
				)
				(justify mirror)
			)
		)
		(property "Value" ""
			(at 0 0 0)
			(layer "B.Fab")
			(effects
				(font
					(size 1.27 1.27)
				)
				(justify mirror)
			)
		)
		(duplicate_pad_numbers_are_jumpers no)
		(fp_poly
			(pts
				(xy 0.7239 -0.2159) (xy -0.7239 -0.2159) (xy -0.7239 1.9939) (xy 0.7239 1.9939)
			)
			(stroke
				(width 0)
				(type default)
			)
			(fill no)
			(layer "B.CrtYd")
		)
		(fp_line
			(start 0.7239 1.9939)
			(end -0.7239 1.9939)
			(stroke
				(width 0.1)
				(type default)
			)
			(layer "B.Fab")
		)
		(fp_line
			(start 0.7239 -0.2159)
			(end 0.7239 1.9939)
			(stroke
				(width 0.1)
				(type default)
			)
			(layer "B.Fab")
		)
		(fp_line
			(start -0.7239 1.9939)
			(end -0.7239 -0.2159)
			(stroke
				(width 0.1)
				(type default)
			)
			(layer "B.Fab")
		)
		(fp_line
			(start -0.7239 -0.2159)
			(end 0.7239 -0.2159)
			(stroke
				(width 0.1)
				(type default)
			)
			(layer "B.Fab")
		)
		(pad "1" smd rect
			(at 0 0)
			(size 1.27 1.016)
			(layers "B.Cu" "B.Mask" "B.Paste")
			(net "PVCCMCP_CPU0")
		)
		(pad "2" smd rect
			(at 0 1.778)
			(size 1.27 1.016)
			(layers "B.Cu" "B.Mask" "B.Paste")
			(net "GND")
		)
		(zone
			(layer "B.Cu")
			(hatch none 0.5)
			(connect_pads
				(clearance 0)
			)
			(min_thickness 0.25)
			(keepout
				(tracks not_allowed)
				(vias allowed)
				(pads allowed)
				(copperpour not_allowed)
				(footprints allowed)
			)
			(placement
				(enabled no)
				(sheetname "")
			)
			(fill
				(thermal_gap 0.5)
				(thermal_bridge_width 0.5)
				(island_removal_mode 0)
			)
			(polygon
				(pts
					(xy 269.267686 -80.11414) (xy 270.537686 -80.11414) (xy 270.537686 -80.87614) (xy 269.267686 -80.87614)
				)
			)
		)
	)
	(footprint ""
		(layer "B.Cu")
		(at 318.543432 -8.128 -90)
		(property "Reference" "C4U2"
			(at 0 0 90)
			(layer "B.SilkS")
			(hide yes)
			(effects
				(font
					(size 1.27 1.27)
				)
				(justify mirror)
			)
		)
		(property "Value" ""
			(at 0 0 90)
			(layer "B.Fab")
			(effects
				(font
					(size 1.27 1.27)
				)
				(justify mirror)
			)
		)
		(duplicate_pad_numbers_are_jumpers no)
		(fp_poly
			(pts
				(xy 0.4953 -0.2032) (xy -0.4953 -0.2032) (xy -0.4953 1.6002) (xy 0.4953 1.6002)
			)
			(stroke
				(width 0)
				(type default)
			)
			(fill no)
			(layer "B.CrtYd")
		)
		(fp_line
			(start -0.4953 1.6002)
			(end 0.4953 1.6002)
			(stroke
				(width 0.1)
				(type default)
			)
			(layer "B.Fab")
		)
		(fp_line
			(start 0.4953 1.6002)
			(end 0.4953 -0.2032)
			(stroke
				(width 0.1)
				(type default)
			)
			(layer "B.Fab")
		)
		(fp_line
			(start -0.4953 -0.2032)
			(end -0.4953 1.6002)
			(stroke
				(width 0.1)
				(type default)
			)
			(layer "B.Fab")
		)
		(fp_line
			(start 0.4953 -0.2032)
			(end -0.4953 -0.2032)
			(stroke
				(width 0.1)
				(type default)
			)
			(layer "B.Fab")
		)
		(pad "1" smd rect
			(at 0 0 90)
			(size 0.762 0.889)
			(layers "B.Cu" "B.Mask" "B.Paste")
			(net "PVPP_ABC")
		)
		(pad "2" smd rect
			(at 0 1.397 90)
			(size 0.762 0.889)
			(layers "B.Cu" "B.Mask" "B.Paste")
			(net "GND")
		)
		(zone
			(layer "B.Cu")
			(hatch none 0.5)
			(connect_pads
				(clearance 0)
			)
			(min_thickness 0.25)
			(keepout
				(tracks not_allowed)
				(vias allowed)
				(pads allowed)
				(copperpour not_allowed)
				(footprints allowed)
			)
			(placement
				(enabled no)
				(sheetname "")
			)
			(fill
				(thermal_gap 0.5)
				(thermal_bridge_width 0.5)
				(island_removal_mode 0)
			)
			(polygon
				(pts
					(xy 318.098932 -7.747) (xy 318.098932 -8.509) (xy 317.590932 -8.509) (xy 317.590932 -7.747)
				)
			)
		)
	)
	(footprint ""
		(layer "B.Cu")
		(at 416.470846 -44.650152 180)
		(property "Reference" "R9F23"
			(at 0 0 0)
			(layer "B.SilkS")
			(hide yes)
			(effects
				(font
					(size 1.27 1.27)
				)
				(justify mirror)
			)
		)
		(property "Value" ""
			(at 0 0 0)
			(layer "B.Fab")
			(effects
				(font
					(size 1.27 1.27)
				)
				(justify mirror)
			)
		)
		(duplicate_pad_numbers_are_jumpers no)
		(fp_poly
			(pts
				(xy 0.2794 -0.1016) (xy -0.2794 -0.1016) (xy -0.2794 0.9906) (xy 0.2794 0.9906)
			)
			(stroke
				(width 0)
				(type default)
			)
			(fill no)
			(layer "B.CrtYd")
		)
		(fp_line
			(start 0.2794 0.9906)
			(end -0.2794 0.9906)
			(stroke
				(width 0.1)
				(type default)
			)
			(layer "B.Fab")
		)
		(fp_line
			(start 0.2794 -0.1016)
			(end 0.2794 0.9906)
			(stroke
				(width 0.1)
				(type default)
			)
			(layer "B.Fab")
		)
		(fp_line
			(start -0.2794 0.9906)
			(end -0.2794 -0.1016)
			(stroke
				(width 0.1)
				(type default)
			)
			(layer "B.Fab")
		)
		(fp_line
			(start -0.2794 -0.1016)
			(end 0.2794 -0.1016)
			(stroke
				(width 0.1)
				(type default)
			)
			(layer "B.Fab")
		)
		(pad "1" smd rect
			(at 0 0)
			(size 0.508 0.508)
			(layers "B.Cu" "B.Mask" "B.Paste")
			(net "SMB_LAN_STBY_LVC3_SDA_R")
		)
		(pad "2" smd rect
			(at 0 0.889)
			(size 0.508 0.508)
			(layers "B.Cu" "B.Mask" "B.Paste")
			(net "SMB_LAN_STBY_LVC3_SDA")
		)
		(zone
			(layer "B.Cu")
			(hatch none 0.5)
			(connect_pads
				(clearance 0)
			)
			(min_thickness 0.25)
			(keepout
				(tracks not_allowed)
				(vias allowed)
				(pads allowed)
				(copperpour not_allowed)
				(footprints allowed)
			)
			(placement
				(enabled no)
				(sheetname "")
			)
			(fill
				(thermal_gap 0.5)
				(thermal_bridge_width 0.5)
				(island_removal_mode 0)
			)
			(polygon
				(pts
					(xy 416.216846 -45.285152) (xy 416.724846 -45.285152) (xy 416.724846 -44.904152) (xy 416.216846 -44.904152)
				)
			)
		)
		(zone
			(layer "B.Cu")
			(hatch none 0.5)
			(connect_pads
				(clearance 0)
			)
			(min_thickness 0.25)
			(keepout
				(tracks allowed)
				(vias not_allowed)
				(pads allowed)
				(copperpour not_allowed)
				(footprints allowed)
			)
			(placement
				(enabled no)
				(sheetname "")
			)
			(fill
				(thermal_gap 0.5)
				(thermal_bridge_width 0.5)
				(island_removal_mode 0)
			)
			(polygon
				(pts
					(xy 416.216846 -44.904152) (xy 416.724846 -44.904152) (xy 416.724846 -45.285152) (xy 416.216846 -45.285152)
				)
			)
		)
	)
	(footprint ""
		(layer "B.Cu")
		(at 245.7323 -3.3528 -90)
		(property "Reference" "C5G50"
			(at -1.14681 0.76708 0)
			(unlocked yes)
			(layer "B.SilkS")
			(effects
				(font
					(size 0.7874 0.5842)
					(thickness 0.1524)
				)
				(justify mirror)
			)
		)
		(property "Value" ""
			(at 0 0 90)
			(layer "B.Fab")
			(effects
				(font
					(size 1.27 1.27)
				)
				(justify mirror)
			)
		)
		(duplicate_pad_numbers_are_jumpers no)
		(fp_rect
			(start 0.4953 1.6002)
			(end -0.4953 -0.2032)
			(stroke
				(width 0)
				(type default)
			)
			(fill no)
			(layer "B.CrtYd")
		)
		(fp_line
			(start -0.4953 1.6002)
			(end 0.4953 1.6002)
			(stroke
				(width 0.1)
				(type default)
			)
			(layer "B.Fab")
		)
		(fp_line
			(start 0.4953 1.6002)
			(end 0.4953 -0.2032)
			(stroke
				(width 0.1)
				(type default)
			)
			(layer "B.Fab")
		)
		(fp_line
			(start -0.4953 -0.2032)
			(end -0.4953 1.6002)
			(stroke
				(width 0.1)
				(type default)
			)
			(layer "B.Fab")
		)
		(fp_line
			(start 0.4953 -0.2032)
			(end -0.4953 -0.2032)
			(stroke
				(width 0.1)
				(type default)
			)
			(layer "B.Fab")
		)
		(pad "1" smd rect
			(at 0 0 90)
			(size 0.762 0.889)
			(layers "B.Cu" "B.Mask" "B.Paste")
			(net "PVDDQ_ABC")
		)
		(pad "2" smd rect
			(at 0 1.397 90)
			(size 0.762 0.889)
			(layers "B.Cu" "B.Mask" "B.Paste")
			(net "GND")
		)
		(zone
			(layer "B.Cu")
			(hatch none 0.5)
			(connect_pads
				(clearance 0)
			)
			(min_thickness 0.25)
			(keepout
				(tracks not_allowed)
				(vias allowed)
				(pads allowed)
				(copperpour not_allowed)
				(footprints allowed)
			)
			(placement
				(enabled no)
				(sheetname "")
			)
			(fill
				(thermal_gap 0.5)
				(thermal_bridge_width 0.5)
				(island_removal_mode 0)
			)
			(polygon
				(pts
					(xy 244.7798 -2.9718) (xy 245.2878 -2.9718) (xy 245.2878 -3.7338) (xy 244.7798 -3.7338)
				)
			)
		)
	)
	(footprint ""
		(layer "B.Cu")
		(at 372.1354 -131.0894 -90)
		(property "Reference" "FB3M4"
			(at 0 0 90)
			(layer "B.SilkS")
			(hide yes)
			(effects
				(font
					(size 1.27 1.27)
				)
				(justify mirror)
			)
		)
		(property "Value" ""
			(at 0 0 90)
			(layer "B.Fab")
			(effects
				(font
					(size 1.27 1.27)
				)
				(justify mirror)
			)
		)
		(duplicate_pad_numbers_are_jumpers no)
		(fp_rect
			(start 0.15113 0.47498)
			(end -1.59893 -0.47498)
			(stroke
				(width 0)
				(type default)
			)
			(fill no)
			(layer "B.CrtYd")
		)
		(fp_line
			(start -1.59893 0.47498)
			(end 0.15113 0.47498)
			(stroke
				(width 0.1)
				(type default)
			)
			(layer "B.Fab")
		)
		(fp_line
			(start 0.15113 0.47498)
			(end 0.15113 -0.47498)
			(stroke
				(width 0.1)
				(type default)
			)
			(layer "B.Fab")
		)
		(fp_line
			(start -1.59893 -0.47498)
			(end -1.59893 0.47498)
			(stroke
				(width 0.1)
				(type default)
			)
			(layer "B.Fab")
		)
		(fp_line
			(start 0.15113 -0.47498)
			(end -1.59893 -0.47498)
			(stroke
				(width 0.1)
				(type default)
			)
			(layer "B.Fab")
		)
		(pad "1" smd rect
			(at 0 0 90)
			(size 0.9398 0.9398)
			(layers "B.Cu" "B.Mask" "B.Paste")
			(net "P1V05_PCH_STBY")
		)
		(pad "2" smd rect
			(at -1.4478 0 90)
			(size 0.9398 0.9398)
			(layers "B.Cu" "B.Mask" "B.Paste")
			(net "P1V05_PCH_STBY_ISCLK_PLL")
		)
		(zone
			(layer "B.Cu")
			(hatch none 0.5)
			(connect_pads
				(clearance 0)
			)
			(min_thickness 0.25)
			(keepout
				(tracks not_allowed)
				(vias allowed)
				(pads allowed)
				(copperpour not_allowed)
				(footprints allowed)
			)
			(placement
				(enabled no)
				(sheetname "")
			)
			(fill
				(thermal_gap 0.5)
				(thermal_bridge_width 0.5)
				(island_removal_mode 0)
			)
			(polygon
				(pts
					(xy 371.6655 -131.5593) (xy 372.6053 -131.5593) (xy 372.6053 -132.0673) (xy 371.6655 -132.0673)
				)
			)
		)
		(zone
			(layer "B.Cu")
			(hatch none 0.5)
			(connect_pads
				(clearance 0)
			)
			(min_thickness 0.25)
			(keepout
				(tracks allowed)
				(vias not_allowed)
				(pads allowed)
				(copperpour not_allowed)
				(footprints allowed)
			)
			(placement
				(enabled no)
				(sheetname "")
			)
			(fill
				(thermal_gap 0.5)
				(thermal_bridge_width 0.5)
				(island_removal_mode 0)
			)
			(polygon
				(pts
					(xy 371.6655 -131.5593) (xy 372.6053 -131.5593) (xy 372.6053 -132.0673) (xy 371.6655 -132.0673)
				)
			)
		)
	)
	(footprint ""
		(layer "B.Cu")
		(at 33.620456 -53.157882 90)
		(property "Reference" "C1E6"
			(at 0 0 90)
			(layer "B.SilkS")
			(hide yes)
			(effects
				(font
					(size 1.27 1.27)
				)
				(justify mirror)
			)
		)
		(property "Value" "*"
			(at -1.1811 -2.8194 90)
			(unlocked yes)
			(layer "B.Fab")
			(hide yes)
			(effects
				(font
					(size 1.27 1.016)
					(thickness 0.1524)
				)
				(justify mirror)
			)
		)
		(property "Device Type" "SC1U10V2KX-4-GP_SMD-BCG6-SC1U1A"
			(at -1.1811 -4.3434 90)
			(unlocked yes)
			(layer "B.Fab")
			(hide yes)
			(effects
				(font
					(size 1.27 1.016)
					(thickness 0.1524)
				)
				(justify mirror)
			)
		)
		(duplicate_pad_numbers_are_jumpers no)
		(fp_rect
			(start 0.4318 0.9525)
			(end -0.4318 -0.9525)
			(stroke
				(width 0)
				(type default)
			)
			(fill no)
			(layer "B.CrtYd")
		)
		(fp_rect
			(start 0.4318 0.9525)
			(end -0.4318 -0.9525)
			(stroke
				(width 0)
				(type default)
			)
			(fill no)
			(layer "B.Fab")
		)
		(pad "1" smd custom
			(at 0 -0.4445 270)
			(size 0.1524 0.1524)
			(layers "B.Cu" "B.Mask" "B.Paste")
			(net "P5V_STBY")
			(options
				(clearance outline)
				(anchor circle)
			)
			(primitives
				(gr_poly
					(pts
						(arc
							(start 0.3048 0.2032)
							(mid 0.275042 0.275042)
							(end 0.2032 0.3048)
						)
						(arc
							(start -0.2032 0.3048)
							(mid -0.275042 0.275042)
							(end -0.3048 0.2032)
						)
						(arc
							(start -0.3048 -0.2032)
							(mid -0.275042 -0.275042)
							(end -0.2032 -0.3048)
						)
						(arc
							(start 0.2032 -0.3048)
							(mid 0.275042 -0.275042)
							(end 0.3048 -0.2032)
						)
					)
					(width 0)
					(fill yes)
				)
			)
		)
		(pad "2" smd custom
			(at 0 0.4445 270)
			(size 0.1524 0.1524)
			(layers "B.Cu" "B.Mask" "B.Paste")
			(net "GND")
			(options
				(clearance outline)
				(anchor circle)
			)
			(primitives
				(gr_poly
					(pts
						(arc
							(start 0.3048 0.2032)
							(mid 0.275042 0.275042)
							(end 0.2032 0.3048)
						)
						(arc
							(start -0.2032 0.3048)
							(mid -0.275042 0.275042)
							(end -0.3048 0.2032)
						)
						(arc
							(start -0.3048 -0.2032)
							(mid -0.275042 -0.275042)
							(end -0.2032 -0.3048)
						)
						(arc
							(start 0.2032 -0.3048)
							(mid 0.275042 -0.275042)
							(end 0.3048 -0.2032)
						)
					)
					(width 0)
					(fill yes)
				)
			)
		)
	)
	(footprint ""
		(layer "B.Cu")
		(at 101.3968 -145.0086 90)
		(property "Reference" "C8L6"
			(at -1.848866 0.752348 90)
			(unlocked yes)
			(layer "B.SilkS")
			(effects
				(font
					(size 1.27 0.9652)
					(thickness 0.1524)
				)
				(justify mirror)
			)
		)
		(property "Value" ""
			(at 0 0 90)
			(layer "B.Fab")
			(effects
				(font
					(size 1.27 1.27)
				)
				(justify mirror)
			)
		)
		(duplicate_pad_numbers_are_jumpers no)
		(fp_rect
			(start 0.500126 1.598422)
			(end -0.500126 -0.201422)
			(stroke
				(width 0)
				(type default)
			)
			(fill no)
			(layer "B.CrtYd")
		)
		(fp_line
			(start 0.500126 -0.201422)
			(end -0.500126 -0.201422)
			(stroke
				(width 0.1)
				(type default)
			)
			(layer "B.Fab")
		)
		(fp_line
			(start -0.500126 -0.201422)
			(end -0.500126 1.598422)
			(stroke
				(width 0.1)
				(type default)
			)
			(layer "B.Fab")
		)
		(fp_line
			(start 0.500126 1.598422)
			(end 0.500126 -0.201422)
			(stroke
				(width 0.1)
				(type default)
			)
			(layer "B.Fab")
		)
		(fp_line
			(start -0.500126 1.598422)
			(end 0.500126 1.598422)
			(stroke
				(width 0.1)
				(type default)
			)
			(layer "B.Fab")
		)
		(pad "1" smd rect
			(at 0 0)
			(size 0.889 0.9906)
			(layers "B.Cu" "B.Mask" "B.Paste")
			(net "PVDDQ_KLM")
		)
		(pad "2" smd rect
			(at 0 1.397)
			(size 0.889 0.9906)
			(layers "B.Cu" "B.Mask" "B.Paste")
			(net "GND")
		)
		(zone
			(layer "B.Cu")
			(hatch none 0.5)
			(connect_pads
				(clearance 0)
			)
			(min_thickness 0.25)
			(keepout
				(tracks not_allowed)
				(vias allowed)
				(pads allowed)
				(copperpour not_allowed)
				(footprints allowed)
			)
			(placement
				(enabled no)
				(sheetname "")
			)
			(fill
				(thermal_gap 0.5)
				(thermal_bridge_width 0.5)
				(island_removal_mode 0)
			)
			(polygon
				(pts
					(xy 102.3493 -145.5039) (xy 101.8413 -145.5039) (xy 101.8413 -144.5133) (xy 102.3493 -144.5133)
				)
			)
		)
		(zone
			(layer "B.Cu")
			(hatch none 0.5)
			(connect_pads
				(clearance 0)
			)
			(min_thickness 0.25)
			(keepout
				(tracks allowed)
				(vias not_allowed)
				(pads allowed)
				(copperpour not_allowed)
				(footprints allowed)
			)
			(placement
				(enabled no)
				(sheetname "")
			)
			(fill
				(thermal_gap 0.5)
				(thermal_bridge_width 0.5)
				(island_removal_mode 0)
			)
			(polygon
				(pts
					(xy 102.3493 -145.5039) (xy 101.8413 -145.5039) (xy 101.8413 -144.5133) (xy 102.3493 -144.5133)
				)
			)
		)
	)
	(footprint ""
		(layer "B.Cu")
		(at 362.270294 -45.671486)
		(property "Reference" "R2T67"
			(at 0 0 0)
			(layer "B.SilkS")
			(hide yes)
			(effects
				(font
					(size 1.27 1.27)
				)
				(justify mirror)
			)
		)
		(property "Value" ""
			(at 0 0 0)
			(layer "B.Fab")
			(effects
				(font
					(size 1.27 1.27)
				)
				(justify mirror)
			)
		)
		(duplicate_pad_numbers_are_jumpers no)
		(fp_poly
			(pts
				(xy 0.2794 -0.1016) (xy -0.2794 -0.1016) (xy -0.2794 0.9906) (xy 0.2794 0.9906)
			)
			(stroke
				(width 0)
				(type default)
			)
			(fill no)
			(layer "B.CrtYd")
		)
		(fp_line
			(start -0.2794 -0.1016)
			(end 0.2794 -0.1016)
			(stroke
				(width 0.1)
				(type default)
			)
			(layer "B.Fab")
		)
		(fp_line
			(start -0.2794 0.9906)
			(end -0.2794 -0.1016)
			(stroke
				(width 0.1)
				(type default)
			)
			(layer "B.Fab")
		)
		(fp_line
			(start 0.2794 -0.1016)
			(end 0.2794 0.9906)
			(stroke
				(width 0.1)
				(type default)
			)
			(layer "B.Fab")
		)
		(fp_line
			(start 0.2794 0.9906)
			(end -0.2794 0.9906)
			(stroke
				(width 0.1)
				(type default)
			)
			(layer "B.Fab")
		)
		(pad "1" smd rect
			(at 0 0 180)
			(size 0.508 0.508)
			(layers "B.Cu" "B.Mask" "B.Paste")
			(net "FM_CPU0_PROCHOT_LVT3_R_N")
		)
		(pad "2" smd rect
			(at 0 0.889 180)
			(size 0.508 0.508)
			(layers "B.Cu" "B.Mask" "B.Paste")
			(net "FM_CPU0_PROCHOT_LVT3_K_N")
		)
		(zone
			(layer "B.Cu")
			(hatch none 0.5)
			(connect_pads
				(clearance 0)
			)
			(min_thickness 0.25)
			(keepout
				(tracks allowed)
				(vias not_allowed)
				(pads allowed)
				(copperpour not_allowed)
				(footprints allowed)
			)
			(placement
				(enabled no)
				(sheetname "")
			)
			(fill
				(thermal_gap 0.5)
				(thermal_bridge_width 0.5)
				(island_removal_mode 0)
			)
			(polygon
				(pts
					(xy 362.524294 -45.417486) (xy 362.016294 -45.417486) (xy 362.016294 -45.036486) (xy 362.524294 -45.036486)
				)
			)
		)
		(zone
			(layer "B.Cu")
			(hatch none 0.5)
			(connect_pads
				(clearance 0)
			)
			(min_thickness 0.25)
			(keepout
				(tracks not_allowed)
				(vias allowed)
				(pads allowed)
				(copperpour not_allowed)
				(footprints allowed)
			)
			(placement
				(enabled no)
				(sheetname "")
			)
			(fill
				(thermal_gap 0.5)
				(thermal_bridge_width 0.5)
				(island_removal_mode 0)
			)
			(polygon
				(pts
					(xy 362.524294 -45.036486) (xy 362.016294 -45.036486) (xy 362.016294 -45.417486) (xy 362.524294 -45.417486)
				)
			)
		)
	)
	(footprint ""
		(layer "B.Cu")
		(at 375.412 -66.04 180)
		(property "Reference" "R2R7"
			(at 0 0 0)
			(layer "B.SilkS")
			(hide yes)
			(effects
				(font
					(size 1.27 1.27)
				)
				(justify mirror)
			)
		)
		(property "Value" ""
			(at 0 0 0)
			(layer "B.Fab")
			(effects
				(font
					(size 1.27 1.27)
				)
				(justify mirror)
			)
		)
		(duplicate_pad_numbers_are_jumpers no)
		(fp_poly
			(pts
				(xy 0.2794 -0.1016) (xy -0.2794 -0.1016) (xy -0.2794 0.9906) (xy 0.2794 0.9906)
			)
			(stroke
				(width 0)
				(type default)
			)
			(fill no)
			(layer "B.CrtYd")
		)
		(fp_line
			(start 0.2794 0.9906)
			(end -0.2794 0.9906)
			(stroke
				(width 0.1)
				(type default)
			)
			(layer "B.Fab")
		)
		(fp_line
			(start 0.2794 -0.1016)
			(end 0.2794 0.9906)
			(stroke
				(width 0.1)
				(type default)
			)
			(layer "B.Fab")
		)
		(fp_line
			(start -0.2794 0.9906)
			(end -0.2794 -0.1016)
			(stroke
				(width 0.1)
				(type default)
			)
			(layer "B.Fab")
		)
		(fp_line
			(start -0.2794 -0.1016)
			(end 0.2794 -0.1016)
			(stroke
				(width 0.1)
				(type default)
			)
			(layer "B.Fab")
		)
		(pad "1" smd rect
			(at 0 0)
			(size 0.508 0.508)
			(layers "B.Cu" "B.Mask" "B.Paste")
			(net "P3V3_STBY")
		)
		(pad "2" smd rect
			(at 0 0.889)
			(size 0.508 0.508)
			(layers "B.Cu" "B.Mask" "B.Paste")
			(net "FM_FORCE_ADR_N")
		)
		(zone
			(layer "B.Cu")
			(hatch none 0.5)
			(connect_pads
				(clearance 0)
			)
			(min_thickness 0.25)
			(keepout
				(tracks not_allowed)
				(vias allowed)
				(pads allowed)
				(copperpour not_allowed)
				(footprints allowed)
			)
			(placement
				(enabled no)
				(sheetname "")
			)
			(fill
				(thermal_gap 0.5)
				(thermal_bridge_width 0.5)
				(island_removal_mode 0)
			)
			(polygon
				(pts
					(xy 375.158 -66.675) (xy 375.666 -66.675) (xy 375.666 -66.294) (xy 375.158 -66.294)
				)
			)
		)
		(zone
			(layer "B.Cu")
			(hatch none 0.5)
			(connect_pads
				(clearance 0)
			)
			(min_thickness 0.25)
			(keepout
				(tracks allowed)
				(vias not_allowed)
				(pads allowed)
				(copperpour not_allowed)
				(footprints allowed)
			)
			(placement
				(enabled no)
				(sheetname "")
			)
			(fill
				(thermal_gap 0.5)
				(thermal_bridge_width 0.5)
				(island_removal_mode 0)
			)
			(polygon
				(pts
					(xy 375.158 -66.294) (xy 375.666 -66.294) (xy 375.666 -66.675) (xy 375.158 -66.675)
				)
			)
		)
	)
	(footprint ""
		(layer "B.Cu")
		(at 485.942894 4.157472 -90)
		(property "Reference" "C9G2"
			(at 0 0 90)
			(layer "B.SilkS")
			(hide yes)
			(effects
				(font
					(size 1.27 1.27)
				)
				(justify mirror)
			)
		)
		(property "Value" ""
			(at 0 0 90)
			(layer "B.Fab")
			(effects
				(font
					(size 1.27 1.27)
				)
				(justify mirror)
			)
		)
		(duplicate_pad_numbers_are_jumpers no)
		(fp_poly
			(pts
				(xy -0.3048 -0.1016) (xy -0.3048 0.9906) (xy 0.3048 0.9906) (xy 0.3048 -0.1016)
			)
			(stroke
				(width 0)
				(type default)
			)
			(fill no)
			(layer "B.CrtYd")
		)
		(fp_line
			(start -0.3048 0.9906)
			(end -0.3048 -0.1016)
			(stroke
				(width 0.1)
				(type default)
			)
			(layer "B.Fab")
		)
		(fp_line
			(start 0.3048 0.9906)
			(end -0.3048 0.9906)
			(stroke
				(width 0.1)
				(type default)
			)
			(layer "B.Fab")
		)
		(fp_line
			(start -0.3048 -0.1016)
			(end 0.3048 -0.1016)
			(stroke
				(width 0.1)
				(type default)
			)
			(layer "B.Fab")
		)
		(fp_line
			(start 0.3048 -0.1016)
			(end 0.3048 0.9906)
			(stroke
				(width 0.1)
				(type default)
			)
			(layer "B.Fab")
		)
		(pad "1" smd rect
			(at 0 0 90)
			(size 0.508 0.508)
			(layers "B.Cu" "B.Mask" "B.Paste")
			(net "P3V3_STBY")
		)
		(pad "2" smd rect
			(at 0 0.889 90)
			(size 0.508 0.508)
			(layers "B.Cu" "B.Mask" "B.Paste")
			(net "GND")
		)
		(zone
			(layer "B.Cu")
			(hatch none 0.5)
			(connect_pads
				(clearance 0)
			)
			(min_thickness 0.25)
			(keepout
				(tracks not_allowed)
				(vias allowed)
				(pads allowed)
				(copperpour not_allowed)
				(footprints allowed)
			)
			(placement
				(enabled no)
				(sheetname "")
			)
			(fill
				(thermal_gap 0.5)
				(thermal_bridge_width 0.5)
				(island_removal_mode 0)
			)
			(polygon
				(pts
					(xy 485.307894 4.411472) (xy 485.307894 3.903472) (xy 485.688894 3.903472) (xy 485.688894 4.411472)
				)
			)
		)
		(zone
			(layer "B.Cu")
			(hatch none 0.5)
			(connect_pads
				(clearance 0)
			)
			(min_thickness 0.25)
			(keepout
				(tracks allowed)
				(vias not_allowed)
				(pads allowed)
				(copperpour not_allowed)
				(footprints allowed)
			)
			(placement
				(enabled no)
				(sheetname "")
			)
			(fill
				(thermal_gap 0.5)
				(thermal_bridge_width 0.5)
				(island_removal_mode 0)
			)
			(polygon
				(pts
					(xy 485.688894 4.411472) (xy 485.688894 3.903472) (xy 485.307894 3.903472) (xy 485.307894 4.411472)
				)
			)
		)
	)
	(footprint ""
		(layer "B.Cu")
		(at 357.133398 -77.915516)
		(property "Reference" "C3P36"
			(at 0 0 0)
			(layer "B.SilkS")
			(hide yes)
			(effects
				(font
					(size 1.27 1.27)
				)
				(justify mirror)
			)
		)
		(property "Value" ""
			(at 0 0 0)
			(layer "B.Fab")
			(effects
				(font
					(size 1.27 1.27)
				)
				(justify mirror)
			)
		)
		(duplicate_pad_numbers_are_jumpers no)
		(fp_poly
			(pts
				(xy -0.3048 -0.1016) (xy -0.3048 0.9906) (xy 0.3048 0.9906) (xy 0.3048 -0.1016)
			)
			(stroke
				(width 0)
				(type default)
			)
			(fill no)
			(layer "B.CrtYd")
		)
		(fp_line
			(start -0.3048 -0.1016)
			(end 0.3048 -0.1016)
			(stroke
				(width 0.1)
				(type default)
			)
			(layer "B.Fab")
		)
		(fp_line
			(start -0.3048 0.9906)
			(end -0.3048 -0.1016)
			(stroke
				(width 0.1)
				(type default)
			)
			(layer "B.Fab")
		)
		(fp_line
			(start 0.3048 -0.1016)
			(end 0.3048 0.9906)
			(stroke
				(width 0.1)
				(type default)
			)
			(layer "B.Fab")
		)
		(fp_line
			(start 0.3048 0.9906)
			(end -0.3048 0.9906)
			(stroke
				(width 0.1)
				(type default)
			)
			(layer "B.Fab")
		)
		(pad "1" smd rect
			(at 0 0 180)
			(size 0.508 0.508)
			(layers "B.Cu" "B.Mask" "B.Paste")
			(net "P3E_CPU0_PE1_SS_TXN<6>")
		)
		(pad "2" smd rect
			(at 0 0.889 180)
			(size 0.508 0.508)
			(layers "B.Cu" "B.Mask" "B.Paste")
			(net "P3E_CPU0_PE1_SS_C_TXN<6>")
		)
		(zone
			(layer "B.Cu")
			(hatch none 0.5)
			(connect_pads
				(clearance 0)
			)
			(min_thickness 0.25)
			(keepout
				(tracks allowed)
				(vias not_allowed)
				(pads allowed)
				(copperpour not_allowed)
				(footprints allowed)
			)
			(placement
				(enabled no)
				(sheetname "")
			)
			(fill
				(thermal_gap 0.5)
				(thermal_bridge_width 0.5)
				(island_removal_mode 0)
			)
			(polygon
				(pts
					(xy 357.387398 -77.661516) (xy 356.879398 -77.661516) (xy 356.879398 -77.280516) (xy 357.387398 -77.280516)
				)
			)
		)
		(zone
			(layer "B.Cu")
			(hatch none 0.5)
			(connect_pads
				(clearance 0)
			)
			(min_thickness 0.25)
			(keepout
				(tracks not_allowed)
				(vias allowed)
				(pads allowed)
				(copperpour not_allowed)
				(footprints allowed)
			)
			(placement
				(enabled no)
				(sheetname "")
			)
			(fill
				(thermal_gap 0.5)
				(thermal_bridge_width 0.5)
				(island_removal_mode 0)
			)
			(polygon
				(pts
					(xy 357.387398 -77.280516) (xy 356.879398 -77.280516) (xy 356.879398 -77.661516) (xy 357.387398 -77.661516)
				)
			)
		)
	)
	(footprint ""
		(layer "B.Cu")
		(at 333.6798 -28.3083 90)
		(property "Reference" "C3T9"
			(at 0 0 90)
			(layer "B.SilkS")
			(hide yes)
			(effects
				(font
					(size 1.27 1.27)
				)
				(justify mirror)
			)
		)
		(property "Value" ""
			(at 0 0 90)
			(layer "B.Fab")
			(effects
				(font
					(size 1.27 1.27)
				)
				(justify mirror)
			)
		)
		(duplicate_pad_numbers_are_jumpers no)
		(fp_rect
			(start -0.7239 -0.2159)
			(end 0.7239 1.9939)
			(stroke
				(width 0)
				(type default)
			)
			(fill no)
			(layer "B.CrtYd")
		)
		(fp_line
			(start 0.7239 -0.2159)
			(end 0.7239 1.9939)
			(stroke
				(width 0.1)
				(type default)
			)
			(layer "B.Fab")
		)
		(fp_line
			(start -0.7239 -0.2159)
			(end 0.7239 -0.2159)
			(stroke
				(width 0.1)
				(type default)
			)
			(layer "B.Fab")
		)
		(fp_line
			(start 0.7239 1.9939)
			(end -0.7239 1.9939)
			(stroke
				(width 0.1)
				(type default)
			)
			(layer "B.Fab")
		)
		(fp_line
			(start -0.7239 1.9939)
			(end -0.7239 -0.2159)
			(stroke
				(width 0.1)
				(type default)
			)
			(layer "B.Fab")
		)
		(pad "1" smd rect
			(at 0 0 270)
			(size 1.27 1.016)
			(layers "B.Cu" "B.Mask" "B.Paste")
			(net "PVPP_ABC")
		)
		(pad "2" smd rect
			(at 0 1.778 270)
			(size 1.27 1.016)
			(layers "B.Cu" "B.Mask" "B.Paste")
			(net "GND")
		)
		(zone
			(layer "B.Cu")
			(hatch none 0.5)
			(connect_pads
				(clearance 0)
			)
			(min_thickness 0.25)
			(keepout
				(tracks not_allowed)
				(vias allowed)
				(pads allowed)
				(copperpour not_allowed)
				(footprints allowed)
			)
			(placement
				(enabled no)
				(sheetname "")
			)
			(fill
				(thermal_gap 0.5)
				(thermal_bridge_width 0.5)
				(island_removal_mode 0)
			)
			(polygon
				(pts
					(xy 334.1878 -27.6733) (xy 334.9498 -27.6733) (xy 334.9498 -28.9433) (xy 334.1878 -28.9433)
				)
			)
		)
	)
	(footprint ""
		(layer "B.Cu")
		(at 496.17376 -124.0663 180)
		(property "Reference" "R1M10"
			(at 0 0 0)
			(layer "B.SilkS")
			(hide yes)
			(effects
				(font
					(size 1.27 1.27)
				)
				(justify mirror)
			)
		)
		(property "Value" ""
			(at 0 0 0)
			(layer "B.Fab")
			(effects
				(font
					(size 1.27 1.27)
				)
				(justify mirror)
			)
		)
		(duplicate_pad_numbers_are_jumpers no)
		(fp_poly
			(pts
				(xy 0.2794 -0.1016) (xy -0.2794 -0.1016) (xy -0.2794 0.9906) (xy 0.2794 0.9906)
			)
			(stroke
				(width 0)
				(type default)
			)
			(fill no)
			(layer "B.CrtYd")
		)
		(fp_line
			(start 0.2794 0.9906)
			(end -0.2794 0.9906)
			(stroke
				(width 0.1)
				(type default)
			)
			(layer "B.Fab")
		)
		(fp_line
			(start 0.2794 -0.1016)
			(end 0.2794 0.9906)
			(stroke
				(width 0.1)
				(type default)
			)
			(layer "B.Fab")
		)
		(fp_line
			(start -0.2794 0.9906)
			(end -0.2794 -0.1016)
			(stroke
				(width 0.1)
				(type default)
			)
			(layer "B.Fab")
		)
		(fp_line
			(start -0.2794 -0.1016)
			(end 0.2794 -0.1016)
			(stroke
				(width 0.1)
				(type default)
			)
			(layer "B.Fab")
		)
		(pad "1" smd rect
			(at 0 0)
			(size 0.508 0.508)
			(layers "B.Cu" "B.Mask" "B.Paste")
			(net "LED_PCH_SATA_HDD_N")
		)
		(pad "2" smd rect
			(at 0 0.889)
			(size 0.508 0.508)
			(layers "B.Cu" "B.Mask" "B.Paste")
			(net "LED_SATA_ACT_R_N")
		)
		(zone
			(layer "B.Cu")
			(hatch none 0.5)
			(connect_pads
				(clearance 0)
			)
			(min_thickness 0.25)
			(keepout
				(tracks not_allowed)
				(vias allowed)
				(pads allowed)
				(copperpour not_allowed)
				(footprints allowed)
			)
			(placement
				(enabled no)
				(sheetname "")
			)
			(fill
				(thermal_gap 0.5)
				(thermal_bridge_width 0.5)
				(island_removal_mode 0)
			)
			(polygon
				(pts
					(xy 495.91976 -124.7013) (xy 496.42776 -124.7013) (xy 496.42776 -124.3203) (xy 495.91976 -124.3203)
				)
			)
		)
		(zone
			(layer "B.Cu")
			(hatch none 0.5)
			(connect_pads
				(clearance 0)
			)
			(min_thickness 0.25)
			(keepout
				(tracks allowed)
				(vias not_allowed)
				(pads allowed)
				(copperpour not_allowed)
				(footprints allowed)
			)
			(placement
				(enabled no)
				(sheetname "")
			)
			(fill
				(thermal_gap 0.5)
				(thermal_bridge_width 0.5)
				(island_removal_mode 0)
			)
			(polygon
				(pts
					(xy 495.91976 -124.3203) (xy 496.42776 -124.3203) (xy 496.42776 -124.7013) (xy 495.91976 -124.7013)
				)
			)
		)
	)
	(footprint ""
		(layer "B.Cu")
		(at 87.158068 -149.8092 -90)
		(property "Reference" "C5G99"
			(at -1.14681 0.76708 0)
			(unlocked yes)
			(layer "B.SilkS")
			(effects
				(font
					(size 0.7874 0.5842)
					(thickness 0.1524)
				)
				(justify mirror)
			)
		)
		(property "Value" ""
			(at 0 0 90)
			(layer "B.Fab")
			(effects
				(font
					(size 1.27 1.27)
				)
				(justify mirror)
			)
		)
		(duplicate_pad_numbers_are_jumpers no)
		(fp_rect
			(start 0.4953 1.6002)
			(end -0.4953 -0.2032)
			(stroke
				(width 0)
				(type default)
			)
			(fill no)
			(layer "B.CrtYd")
		)
		(fp_line
			(start -0.4953 1.6002)
			(end 0.4953 1.6002)
			(stroke
				(width 0.1)
				(type default)
			)
			(layer "B.Fab")
		)
		(fp_line
			(start 0.4953 1.6002)
			(end 0.4953 -0.2032)
			(stroke
				(width 0.1)
				(type default)
			)
			(layer "B.Fab")
		)
		(fp_line
			(start -0.4953 -0.2032)
			(end -0.4953 1.6002)
			(stroke
				(width 0.1)
				(type default)
			)
			(layer "B.Fab")
		)
		(fp_line
			(start 0.4953 -0.2032)
			(end -0.4953 -0.2032)
			(stroke
				(width 0.1)
				(type default)
			)
			(layer "B.Fab")
		)
		(pad "1" smd rect
			(at 0 0 90)
			(size 0.762 0.889)
			(layers "B.Cu" "B.Mask" "B.Paste")
			(net "PVDDQ_KLM")
		)
		(pad "2" smd rect
			(at 0 1.397 90)
			(size 0.762 0.889)
			(layers "B.Cu" "B.Mask" "B.Paste")
			(net "GND")
		)
		(zone
			(layer "B.Cu")
			(hatch none 0.5)
			(connect_pads
				(clearance 0)
			)
			(min_thickness 0.25)
			(keepout
				(tracks not_allowed)
				(vias allowed)
				(pads allowed)
				(copperpour not_allowed)
				(footprints allowed)
			)
			(placement
				(enabled no)
				(sheetname "")
			)
			(fill
				(thermal_gap 0.5)
				(thermal_bridge_width 0.5)
				(island_removal_mode 0)
			)
			(polygon
				(pts
					(xy 86.205568 -149.4282) (xy 86.713568 -149.4282) (xy 86.713568 -150.1902) (xy 86.205568 -150.1902)
				)
			)
		)
	)
	(footprint ""
		(layer "B.Cu")
		(at 362.671614 -124.440442 -90)
		(property "Reference" "C3M32"
			(at 0 0 90)
			(layer "B.SilkS")
			(hide yes)
			(effects
				(font
					(size 1.27 1.27)
				)
				(justify mirror)
			)
		)
		(property "Value" ""
			(at 0 0 90)
			(layer "B.Fab")
			(effects
				(font
					(size 1.27 1.27)
				)
				(justify mirror)
			)
		)
		(duplicate_pad_numbers_are_jumpers no)
		(fp_poly
			(pts
				(xy -0.3048 -0.1016) (xy -0.3048 0.9906) (xy 0.3048 0.9906) (xy 0.3048 -0.1016)
			)
			(stroke
				(width 0)
				(type default)
			)
			(fill no)
			(layer "B.CrtYd")
		)
		(fp_line
			(start -0.3048 0.9906)
			(end -0.3048 -0.1016)
			(stroke
				(width 0.1)
				(type default)
			)
			(layer "B.Fab")
		)
		(fp_line
			(start 0.3048 0.9906)
			(end -0.3048 0.9906)
			(stroke
				(width 0.1)
				(type default)
			)
			(layer "B.Fab")
		)
		(fp_line
			(start -0.3048 -0.1016)
			(end 0.3048 -0.1016)
			(stroke
				(width 0.1)
				(type default)
			)
			(layer "B.Fab")
		)
		(fp_line
			(start 0.3048 -0.1016)
			(end 0.3048 0.9906)
			(stroke
				(width 0.1)
				(type default)
			)
			(layer "B.Fab")
		)
		(pad "1" smd rect
			(at 0 0 90)
			(size 0.508 0.508)
			(layers "B.Cu" "B.Mask" "B.Paste")
			(net "P3E_CPU0_PE1_PCH_R_RXN<10>")
		)
		(pad "2" smd rect
			(at 0 0.889 90)
			(size 0.508 0.508)
			(layers "B.Cu" "B.Mask" "B.Paste")
			(net "P3E_CPU0_PE1_PCH_RXN<10>")
		)
		(zone
			(layer "B.Cu")
			(hatch none 0.5)
			(connect_pads
				(clearance 0)
			)
			(min_thickness 0.25)
			(keepout
				(tracks not_allowed)
				(vias allowed)
				(pads allowed)
				(copperpour not_allowed)
				(footprints allowed)
			)
			(placement
				(enabled no)
				(sheetname "")
			)
			(fill
				(thermal_gap 0.5)
				(thermal_bridge_width 0.5)
				(island_removal_mode 0)
			)
			(polygon
				(pts
					(xy 362.036614 -124.186442) (xy 362.036614 -124.694442) (xy 362.417614 -124.694442) (xy 362.417614 -124.186442)
				)
			)
		)
		(zone
			(layer "B.Cu")
			(hatch none 0.5)
			(connect_pads
				(clearance 0)
			)
			(min_thickness 0.25)
			(keepout
				(tracks allowed)
				(vias not_allowed)
				(pads allowed)
				(copperpour not_allowed)
				(footprints allowed)
			)
			(placement
				(enabled no)
				(sheetname "")
			)
			(fill
				(thermal_gap 0.5)
				(thermal_bridge_width 0.5)
				(island_removal_mode 0)
			)
			(polygon
				(pts
					(xy 362.417614 -124.186442) (xy 362.417614 -124.694442) (xy 362.036614 -124.694442) (xy 362.036614 -124.186442)
				)
			)
		)
	)
	(footprint ""
		(layer "B.Cu")
		(at 373.017288 -36.096448 90)
		(property "Reference" "C7E3"
			(at 0 0 90)
			(layer "B.SilkS")
			(hide yes)
			(effects
				(font
					(size 1.27 1.27)
				)
				(justify mirror)
			)
		)
		(property "Value" ""
			(at 0 0 90)
			(layer "B.Fab")
			(effects
				(font
					(size 1.27 1.27)
				)
				(justify mirror)
			)
		)
		(duplicate_pad_numbers_are_jumpers no)
		(fp_poly
			(pts
				(xy -0.3048 -0.1016) (xy -0.3048 0.9906) (xy 0.3048 0.9906) (xy 0.3048 -0.1016)
			)
			(stroke
				(width 0)
				(type default)
			)
			(fill no)
			(layer "B.CrtYd")
		)
		(fp_line
			(start 0.3048 -0.1016)
			(end 0.3048 0.9906)
			(stroke
				(width 0.1)
				(type default)
			)
			(layer "B.Fab")
		)
		(fp_line
			(start -0.3048 -0.1016)
			(end 0.3048 -0.1016)
			(stroke
				(width 0.1)
				(type default)
			)
			(layer "B.Fab")
		)
		(fp_line
			(start 0.3048 0.9906)
			(end -0.3048 0.9906)
			(stroke
				(width 0.1)
				(type default)
			)
			(layer "B.Fab")
		)
		(fp_line
			(start -0.3048 0.9906)
			(end -0.3048 -0.1016)
			(stroke
				(width 0.1)
				(type default)
			)
			(layer "B.Fab")
		)
		(pad "1" smd rect
			(at 0 0 270)
			(size 0.508 0.508)
			(layers "B.Cu" "B.Mask" "B.Paste")
			(net "P3V3_STBY")
		)
		(pad "2" smd rect
			(at 0 0.889 270)
			(size 0.508 0.508)
			(layers "B.Cu" "B.Mask" "B.Paste")
			(net "GND")
		)
		(zone
			(layer "B.Cu")
			(hatch none 0.5)
			(connect_pads
				(clearance 0)
			)
			(min_thickness 0.25)
			(keepout
				(tracks allowed)
				(vias not_allowed)
				(pads allowed)
				(copperpour not_allowed)
				(footprints allowed)
			)
			(placement
				(enabled no)
				(sheetname "")
			)
			(fill
				(thermal_gap 0.5)
				(thermal_bridge_width 0.5)
				(island_removal_mode 0)
			)
			(polygon
				(pts
					(xy 373.271288 -36.350448) (xy 373.271288 -35.842448) (xy 373.652288 -35.842448) (xy 373.652288 -36.350448)
				)
			)
		)
		(zone
			(layer "B.Cu")
			(hatch none 0.5)
			(connect_pads
				(clearance 0)
			)
			(min_thickness 0.25)
			(keepout
				(tracks not_allowed)
				(vias allowed)
				(pads allowed)
				(copperpour not_allowed)
				(footprints allowed)
			)
			(placement
				(enabled no)
				(sheetname "")
			)
			(fill
				(thermal_gap 0.5)
				(thermal_bridge_width 0.5)
				(island_removal_mode 0)
			)
			(polygon
				(pts
					(xy 373.652288 -36.350448) (xy 373.652288 -35.842448) (xy 373.271288 -35.842448) (xy 373.271288 -36.350448)
				)
			)
		)
	)
	(footprint ""
		(layer "B.Cu")
		(at 349.463614 -123.576842 -90)
		(property "Reference" "C3M13"
			(at 0 0 90)
			(layer "B.SilkS")
			(hide yes)
			(effects
				(font
					(size 1.27 1.27)
				)
				(justify mirror)
			)
		)
		(property "Value" ""
			(at 0 0 90)
			(layer "B.Fab")
			(effects
				(font
					(size 1.27 1.27)
				)
				(justify mirror)
			)
		)
		(duplicate_pad_numbers_are_jumpers no)
		(fp_poly
			(pts
				(xy -0.3048 -0.1016) (xy -0.3048 0.9906) (xy 0.3048 0.9906) (xy 0.3048 -0.1016)
			)
			(stroke
				(width 0)
				(type default)
			)
			(fill no)
			(layer "B.CrtYd")
		)
		(fp_line
			(start -0.3048 0.9906)
			(end -0.3048 -0.1016)
			(stroke
				(width 0.1)
				(type default)
			)
			(layer "B.Fab")
		)
		(fp_line
			(start 0.3048 0.9906)
			(end -0.3048 0.9906)
			(stroke
				(width 0.1)
				(type default)
			)
			(layer "B.Fab")
		)
		(fp_line
			(start -0.3048 -0.1016)
			(end 0.3048 -0.1016)
			(stroke
				(width 0.1)
				(type default)
			)
			(layer "B.Fab")
		)
		(fp_line
			(start 0.3048 -0.1016)
			(end 0.3048 0.9906)
			(stroke
				(width 0.1)
				(type default)
			)
			(layer "B.Fab")
		)
		(pad "1" smd rect
			(at 0 0 90)
			(size 0.508 0.508)
			(layers "B.Cu" "B.Mask" "B.Paste")
			(net "P3E_CPU0_PE1_PCH_R_RXP<13>")
		)
		(pad "2" smd rect
			(at 0 0.889 90)
			(size 0.508 0.508)
			(layers "B.Cu" "B.Mask" "B.Paste")
			(net "P3E_CPU0_PE1_PCH_RXP<13>")
		)
		(zone
			(layer "B.Cu")
			(hatch none 0.5)
			(connect_pads
				(clearance 0)
			)
			(min_thickness 0.25)
			(keepout
				(tracks not_allowed)
				(vias allowed)
				(pads allowed)
				(copperpour not_allowed)
				(footprints allowed)
			)
			(placement
				(enabled no)
				(sheetname "")
			)
			(fill
				(thermal_gap 0.5)
				(thermal_bridge_width 0.5)
				(island_removal_mode 0)
			)
			(polygon
				(pts
					(xy 348.828614 -123.322842) (xy 348.828614 -123.830842) (xy 349.209614 -123.830842) (xy 349.209614 -123.322842)
				)
			)
		)
		(zone
			(layer "B.Cu")
			(hatch none 0.5)
			(connect_pads
				(clearance 0)
			)
			(min_thickness 0.25)
			(keepout
				(tracks allowed)
				(vias not_allowed)
				(pads allowed)
				(copperpour not_allowed)
				(footprints allowed)
			)
			(placement
				(enabled no)
				(sheetname "")
			)
			(fill
				(thermal_gap 0.5)
				(thermal_bridge_width 0.5)
				(island_removal_mode 0)
			)
			(polygon
				(pts
					(xy 349.209614 -123.322842) (xy 349.209614 -123.830842) (xy 348.828614 -123.830842) (xy 348.828614 -123.322842)
				)
			)
		)
	)
	(footprint ""
		(layer "B.Cu")
		(at 348.5134 -152.038304 -90)
		(property "Reference" "C3L15"
			(at 0 0 90)
			(layer "B.SilkS")
			(hide yes)
			(effects
				(font
					(size 1.27 1.27)
				)
				(justify mirror)
			)
		)
		(property "Value" ""
			(at 0 0 90)
			(layer "B.Fab")
			(effects
				(font
					(size 1.27 1.27)
				)
				(justify mirror)
			)
		)
		(duplicate_pad_numbers_are_jumpers no)
		(fp_poly
			(pts
				(xy 0.7239 -0.2159) (xy -0.7239 -0.2159) (xy -0.7239 1.9939) (xy 0.7239 1.9939)
			)
			(stroke
				(width 0)
				(type default)
			)
			(fill no)
			(layer "B.CrtYd")
		)
		(fp_line
			(start -0.7239 1.9939)
			(end -0.7239 -0.2159)
			(stroke
				(width 0.1)
				(type default)
			)
			(layer "B.Fab")
		)
		(fp_line
			(start 0.7239 1.9939)
			(end -0.7239 1.9939)
			(stroke
				(width 0.1)
				(type default)
			)
			(layer "B.Fab")
		)
		(fp_line
			(start -0.7239 -0.2159)
			(end 0.7239 -0.2159)
			(stroke
				(width 0.1)
				(type default)
			)
			(layer "B.Fab")
		)
		(fp_line
			(start 0.7239 -0.2159)
			(end 0.7239 1.9939)
			(stroke
				(width 0.1)
				(type default)
			)
			(layer "B.Fab")
		)
		(pad "1" smd rect
			(at 0 0 90)
			(size 1.27 1.016)
			(layers "B.Cu" "B.Mask" "B.Paste")
			(net "VR_FET_SW_P12V_STBY_PVDDQ_DEF")
		)
		(pad "2" smd rect
			(at 0 1.778 90)
			(size 1.27 1.016)
			(layers "B.Cu" "B.Mask" "B.Paste")
			(net "GND")
		)
		(zone
			(layer "B.Cu")
			(hatch none 0.5)
			(connect_pads
				(clearance 0)
			)
			(min_thickness 0.25)
			(keepout
				(tracks not_allowed)
				(vias allowed)
				(pads allowed)
				(copperpour not_allowed)
				(footprints allowed)
			)
			(placement
				(enabled no)
				(sheetname "")
			)
			(fill
				(thermal_gap 0.5)
				(thermal_bridge_width 0.5)
				(island_removal_mode 0)
			)
			(polygon
				(pts
					(xy 348.0054 -151.403304) (xy 348.0054 -152.673304) (xy 347.2434 -152.673304) (xy 347.2434 -151.403304)
				)
			)
		)
	)
	(footprint ""
		(layer "B.Cu")
		(at 430.2125 -12.446 -90)
		(property "Reference" "R1U59"
			(at 0 0 90)
			(layer "B.SilkS")
			(hide yes)
			(effects
				(font
					(size 1.27 1.27)
				)
				(justify mirror)
			)
		)
		(property "Value" ""
			(at 0 0 90)
			(layer "B.Fab")
			(effects
				(font
					(size 1.27 1.27)
				)
				(justify mirror)
			)
		)
		(duplicate_pad_numbers_are_jumpers no)
		(fp_poly
			(pts
				(xy 0.2794 -0.1016) (xy -0.2794 -0.1016) (xy -0.2794 0.9906) (xy 0.2794 0.9906)
			)
			(stroke
				(width 0)
				(type default)
			)
			(fill no)
			(layer "B.CrtYd")
		)
		(fp_line
			(start -0.2794 0.9906)
			(end -0.2794 -0.1016)
			(stroke
				(width 0.1)
				(type default)
			)
			(layer "B.Fab")
		)
		(fp_line
			(start 0.2794 0.9906)
			(end -0.2794 0.9906)
			(stroke
				(width 0.1)
				(type default)
			)
			(layer "B.Fab")
		)
		(fp_line
			(start -0.2794 -0.1016)
			(end 0.2794 -0.1016)
			(stroke
				(width 0.1)
				(type default)
			)
			(layer "B.Fab")
		)
		(fp_line
			(start 0.2794 -0.1016)
			(end 0.2794 0.9906)
			(stroke
				(width 0.1)
				(type default)
			)
			(layer "B.Fab")
		)
		(pad "1" smd rect
			(at 0 0 90)
			(size 0.508 0.508)
			(layers "B.Cu" "B.Mask" "B.Paste")
			(net "H_CPU0_ABC_MEMHOT_LVT3_R_N")
		)
		(pad "2" smd rect
			(at 0 0.889 90)
			(size 0.508 0.508)
			(layers "B.Cu" "B.Mask" "B.Paste")
			(net "H_CPU0_MEMABC_MEMHOT_LVT3_K_N")
		)
		(zone
			(layer "B.Cu")
			(hatch none 0.5)
			(connect_pads
				(clearance 0)
			)
			(min_thickness 0.25)
			(keepout
				(tracks not_allowed)
				(vias allowed)
				(pads allowed)
				(copperpour not_allowed)
				(footprints allowed)
			)
			(placement
				(enabled no)
				(sheetname "")
			)
			(fill
				(thermal_gap 0.5)
				(thermal_bridge_width 0.5)
				(island_removal_mode 0)
			)
			(polygon
				(pts
					(xy 429.5775 -12.192) (xy 429.5775 -12.7) (xy 429.9585 -12.7) (xy 429.9585 -12.192)
				)
			)
		)
		(zone
			(layer "B.Cu")
			(hatch none 0.5)
			(connect_pads
				(clearance 0)
			)
			(min_thickness 0.25)
			(keepout
				(tracks allowed)
				(vias not_allowed)
				(pads allowed)
				(copperpour not_allowed)
				(footprints allowed)
			)
			(placement
				(enabled no)
				(sheetname "")
			)
			(fill
				(thermal_gap 0.5)
				(thermal_bridge_width 0.5)
				(island_removal_mode 0)
			)
			(polygon
				(pts
					(xy 429.9585 -12.192) (xy 429.9585 -12.7) (xy 429.5775 -12.7) (xy 429.5775 -12.192)
				)
			)
		)
	)
	(footprint ""
		(layer "B.Cu")
		(at 383.019808 -155.432506)
		(property "Reference" "R3L4"
			(at 0 0 0)
			(layer "B.SilkS")
			(hide yes)
			(effects
				(font
					(size 1.27 1.27)
				)
				(justify mirror)
			)
		)
		(property "Value" ""
			(at 0 0 0)
			(layer "B.Fab")
			(effects
				(font
					(size 1.27 1.27)
				)
				(justify mirror)
			)
		)
		(duplicate_pad_numbers_are_jumpers no)
		(fp_poly
			(pts
				(xy 0.2794 -0.1016) (xy -0.2794 -0.1016) (xy -0.2794 0.9906) (xy 0.2794 0.9906)
			)
			(stroke
				(width 0)
				(type default)
			)
			(fill no)
			(layer "B.CrtYd")
		)
		(fp_line
			(start -0.2794 -0.1016)
			(end 0.2794 -0.1016)
			(stroke
				(width 0.1)
				(type default)
			)
			(layer "B.Fab")
		)
		(fp_line
			(start -0.2794 0.9906)
			(end -0.2794 -0.1016)
			(stroke
				(width 0.1)
				(type default)
			)
			(layer "B.Fab")
		)
		(fp_line
			(start 0.2794 -0.1016)
			(end 0.2794 0.9906)
			(stroke
				(width 0.1)
				(type default)
			)
			(layer "B.Fab")
		)
		(fp_line
			(start 0.2794 0.9906)
			(end -0.2794 0.9906)
			(stroke
				(width 0.1)
				(type default)
			)
			(layer "B.Fab")
		)
		(pad "1" smd rect
			(at 0 0 180)
			(size 0.508 0.508)
			(layers "B.Cu" "B.Mask" "B.Paste")
			(net "VR_P1V05_PCH_STBY_PH1_VCIN")
		)
		(pad "2" smd rect
			(at 0 0.889 180)
			(size 0.508 0.508)
			(layers "B.Cu" "B.Mask" "B.Paste")
			(net "P5V_STBY")
		)
		(zone
			(layer "B.Cu")
			(hatch none 0.5)
			(connect_pads
				(clearance 0)
			)
			(min_thickness 0.25)
			(keepout
				(tracks allowed)
				(vias not_allowed)
				(pads allowed)
				(copperpour not_allowed)
				(footprints allowed)
			)
			(placement
				(enabled no)
				(sheetname "")
			)
			(fill
				(thermal_gap 0.5)
				(thermal_bridge_width 0.5)
				(island_removal_mode 0)
			)
			(polygon
				(pts
					(xy 383.273808 -155.178506) (xy 382.765808 -155.178506) (xy 382.765808 -154.797506) (xy 383.273808 -154.797506)
				)
			)
		)
		(zone
			(layer "B.Cu")
			(hatch none 0.5)
			(connect_pads
				(clearance 0)
			)
			(min_thickness 0.25)
			(keepout
				(tracks not_allowed)
				(vias allowed)
				(pads allowed)
				(copperpour not_allowed)
				(footprints allowed)
			)
			(placement
				(enabled no)
				(sheetname "")
			)
			(fill
				(thermal_gap 0.5)
				(thermal_bridge_width 0.5)
				(island_removal_mode 0)
			)
			(polygon
				(pts
					(xy 383.273808 -154.797506) (xy 382.765808 -154.797506) (xy 382.765808 -155.178506) (xy 383.273808 -155.178506)
				)
			)
		)
	)
	(footprint ""
		(layer "B.Cu")
		(at 382.7272 -114.554 180)
		(property "Reference" "C3M39"
			(at 0 0 0)
			(layer "B.SilkS")
			(hide yes)
			(effects
				(font
					(size 1.27 1.27)
				)
				(justify mirror)
			)
		)
		(property "Value" ""
			(at 0 0 0)
			(layer "B.Fab")
			(effects
				(font
					(size 1.27 1.27)
				)
				(justify mirror)
			)
		)
		(duplicate_pad_numbers_are_jumpers no)
		(fp_poly
			(pts
				(xy -0.3048 -0.1016) (xy -0.3048 0.9906) (xy 0.3048 0.9906) (xy 0.3048 -0.1016)
			)
			(stroke
				(width 0)
				(type default)
			)
			(fill no)
			(layer "B.CrtYd")
		)
		(fp_line
			(start 0.3048 0.9906)
			(end -0.3048 0.9906)
			(stroke
				(width 0.1)
				(type default)
			)
			(layer "B.Fab")
		)
		(fp_line
			(start 0.3048 -0.1016)
			(end 0.3048 0.9906)
			(stroke
				(width 0.1)
				(type default)
			)
			(layer "B.Fab")
		)
		(fp_line
			(start -0.3048 0.9906)
			(end -0.3048 -0.1016)
			(stroke
				(width 0.1)
				(type default)
			)
			(layer "B.Fab")
		)
		(fp_line
			(start -0.3048 -0.1016)
			(end 0.3048 -0.1016)
			(stroke
				(width 0.1)
				(type default)
			)
			(layer "B.Fab")
		)
		(pad "1" smd rect
			(at 0 0)
			(size 0.508 0.508)
			(layers "B.Cu" "B.Mask" "B.Paste")
			(net "P1V05_PCH_STBY")
		)
		(pad "2" smd rect
			(at 0 0.889)
			(size 0.508 0.508)
			(layers "B.Cu" "B.Mask" "B.Paste")
			(net "GND")
		)
		(zone
			(layer "B.Cu")
			(hatch none 0.5)
			(connect_pads
				(clearance 0)
			)
			(min_thickness 0.25)
			(keepout
				(tracks not_allowed)
				(vias allowed)
				(pads allowed)
				(copperpour not_allowed)
				(footprints allowed)
			)
			(placement
				(enabled no)
				(sheetname "")
			)
			(fill
				(thermal_gap 0.5)
				(thermal_bridge_width 0.5)
				(island_removal_mode 0)
			)
			(polygon
				(pts
					(xy 382.4732 -115.189) (xy 382.9812 -115.189) (xy 382.9812 -114.808) (xy 382.4732 -114.808)
				)
			)
		)
		(zone
			(layer "B.Cu")
			(hatch none 0.5)
			(connect_pads
				(clearance 0)
			)
			(min_thickness 0.25)
			(keepout
				(tracks allowed)
				(vias not_allowed)
				(pads allowed)
				(copperpour not_allowed)
				(footprints allowed)
			)
			(placement
				(enabled no)
				(sheetname "")
			)
			(fill
				(thermal_gap 0.5)
				(thermal_bridge_width 0.5)
				(island_removal_mode 0)
			)
			(polygon
				(pts
					(xy 382.4732 -114.808) (xy 382.9812 -114.808) (xy 382.9812 -115.189) (xy 382.4732 -115.189)
				)
			)
		)
	)
	(footprint ""
		(layer "B.Cu")
		(at 480.037902 -54.339998)
		(property "Reference" "C8E5"
			(at 0 0 0)
			(layer "B.SilkS")
			(hide yes)
			(effects
				(font
					(size 1.27 1.27)
				)
				(justify mirror)
			)
		)
		(property "Value" ""
			(at 0 0 0)
			(layer "B.Fab")
			(effects
				(font
					(size 1.27 1.27)
				)
				(justify mirror)
			)
		)
		(duplicate_pad_numbers_are_jumpers no)
		(fp_poly
			(pts
				(xy -0.3048 -0.1016) (xy -0.3048 0.9906) (xy 0.3048 0.9906) (xy 0.3048 -0.1016)
			)
			(stroke
				(width 0)
				(type default)
			)
			(fill no)
			(layer "B.CrtYd")
		)
		(fp_line
			(start -0.3048 -0.1016)
			(end 0.3048 -0.1016)
			(stroke
				(width 0.1)
				(type default)
			)
			(layer "B.Fab")
		)
		(fp_line
			(start -0.3048 0.9906)
			(end -0.3048 -0.1016)
			(stroke
				(width 0.1)
				(type default)
			)
			(layer "B.Fab")
		)
		(fp_line
			(start 0.3048 -0.1016)
			(end 0.3048 0.9906)
			(stroke
				(width 0.1)
				(type default)
			)
			(layer "B.Fab")
		)
		(fp_line
			(start 0.3048 0.9906)
			(end -0.3048 0.9906)
			(stroke
				(width 0.1)
				(type default)
			)
			(layer "B.Fab")
		)
		(pad "1" smd rect
			(at 0 0 180)
			(size 0.508 0.508)
			(layers "B.Cu" "B.Mask" "B.Paste")
			(net "P3V3_STBY")
		)
		(pad "2" smd rect
			(at 0 0.889 180)
			(size 0.508 0.508)
			(layers "B.Cu" "B.Mask" "B.Paste")
			(net "GND")
		)
		(zone
			(layer "B.Cu")
			(hatch none 0.5)
			(connect_pads
				(clearance 0)
			)
			(min_thickness 0.25)
			(keepout
				(tracks allowed)
				(vias not_allowed)
				(pads allowed)
				(copperpour not_allowed)
				(footprints allowed)
			)
			(placement
				(enabled no)
				(sheetname "")
			)
			(fill
				(thermal_gap 0.5)
				(thermal_bridge_width 0.5)
				(island_removal_mode 0)
			)
			(polygon
				(pts
					(xy 480.291902 -54.085998) (xy 479.783902 -54.085998) (xy 479.783902 -53.704998) (xy 480.291902 -53.704998)
				)
			)
		)
		(zone
			(layer "B.Cu")
			(hatch none 0.5)
			(connect_pads
				(clearance 0)
			)
			(min_thickness 0.25)
			(keepout
				(tracks not_allowed)
				(vias allowed)
				(pads allowed)
				(copperpour not_allowed)
				(footprints allowed)
			)
			(placement
				(enabled no)
				(sheetname "")
			)
			(fill
				(thermal_gap 0.5)
				(thermal_bridge_width 0.5)
				(island_removal_mode 0)
			)
			(polygon
				(pts
					(xy 480.291902 -53.704998) (xy 479.783902 -53.704998) (xy 479.783902 -54.085998) (xy 480.291902 -54.085998)
				)
			)
		)
	)
	(footprint ""
		(layer "B.Cu")
		(at 258.445 -17.6276 -90)
		(property "Reference" "C5T13"
			(at 0 0 90)
			(layer "B.SilkS")
			(hide yes)
			(effects
				(font
					(size 1.27 1.27)
				)
				(justify mirror)
			)
		)
		(property "Value" ""
			(at 0 0 90)
			(layer "B.Fab")
			(effects
				(font
					(size 1.27 1.27)
				)
				(justify mirror)
			)
		)
		(duplicate_pad_numbers_are_jumpers no)
		(fp_rect
			(start 0.500126 1.598422)
			(end -0.500126 -0.201422)
			(stroke
				(width 0)
				(type default)
			)
			(fill no)
			(layer "B.CrtYd")
		)
		(fp_line
			(start -0.500126 1.598422)
			(end 0.500126 1.598422)
			(stroke
				(width 0.1)
				(type default)
			)
			(layer "B.Fab")
		)
		(fp_line
			(start 0.500126 1.598422)
			(end 0.500126 -0.201422)
			(stroke
				(width 0.1)
				(type default)
			)
			(layer "B.Fab")
		)
		(fp_line
			(start -0.500126 -0.201422)
			(end -0.500126 1.598422)
			(stroke
				(width 0.1)
				(type default)
			)
			(layer "B.Fab")
		)
		(fp_line
			(start 0.500126 -0.201422)
			(end -0.500126 -0.201422)
			(stroke
				(width 0.1)
				(type default)
			)
			(layer "B.Fab")
		)
		(pad "1" smd rect
			(at 0 0 180)
			(size 0.889 0.9906)
			(layers "B.Cu" "B.Mask" "B.Paste")
			(net "PVDDQ_ABC")
		)
		(pad "2" smd rect
			(at 0 1.397 180)
			(size 0.889 0.9906)
			(layers "B.Cu" "B.Mask" "B.Paste")
			(net "GND")
		)
		(zone
			(layer "B.Cu")
			(hatch none 0.5)
			(connect_pads
				(clearance 0)
			)
			(min_thickness 0.25)
			(keepout
				(tracks not_allowed)
				(vias allowed)
				(pads allowed)
				(copperpour not_allowed)
				(footprints allowed)
			)
			(placement
				(enabled no)
				(sheetname "")
			)
			(fill
				(thermal_gap 0.5)
				(thermal_bridge_width 0.5)
				(island_removal_mode 0)
			)
			(polygon
				(pts
					(xy 257.4925 -17.1323) (xy 258.0005 -17.1323) (xy 258.0005 -18.1229) (xy 257.4925 -18.1229)
				)
			)
		)
		(zone
			(layer "B.Cu")
			(hatch none 0.5)
			(connect_pads
				(clearance 0)
			)
			(min_thickness 0.25)
			(keepout
				(tracks allowed)
				(vias not_allowed)
				(pads allowed)
				(copperpour not_allowed)
				(footprints allowed)
			)
			(placement
				(enabled no)
				(sheetname "")
			)
			(fill
				(thermal_gap 0.5)
				(thermal_bridge_width 0.5)
				(island_removal_mode 0)
			)
			(polygon
				(pts
					(xy 257.4925 -17.1323) (xy 258.0005 -17.1323) (xy 258.0005 -18.1229) (xy 257.4925 -18.1229)
				)
			)
		)
	)
	(footprint ""
		(layer "B.Cu")
		(at 353.64801 -141.689328 90)
		(property "Reference" "C7W11"
			(at 0 0 90)
			(layer "B.SilkS")
			(hide yes)
			(effects
				(font
					(size 1.27 1.27)
				)
				(justify mirror)
			)
		)
		(property "Value" "*"
			(at 0.0762 -6.2357 90)
			(unlocked yes)
			(layer "B.Fab")
			(hide yes)
			(effects
				(font
					(size 1.27 1.016)
					(thickness 0.1524)
				)
				(justify mirror)
			)
		)
		(property "Device Type" "SC22U16V5MX-4-GP_SMD-BCG5-SC22A"
			(at 0.0762 -8.2677 90)
			(unlocked yes)
			(layer "B.Fab")
			(hide yes)
			(effects
				(font
					(size 1.27 1.016)
					(thickness 0.1524)
				)
				(justify mirror)
			)
		)
		(duplicate_pad_numbers_are_jumpers no)
		(fp_line
			(start -0.635 0)
			(end 0.635 0)
			(stroke
				(width 0.508)
				(type default)
			)
			(layer "B.SilkS")
		)
		(fp_rect
			(start 0.9652 1.778)
			(end -0.9652 -1.778)
			(stroke
				(width 0)
				(type default)
			)
			(fill no)
			(layer "B.CrtYd")
		)
		(fp_poly
			(pts
				(xy 0.9652 -1.778) (xy -0.9652 -1.778) (xy -0.9652 1.778) (xy 0.9652 1.778)
			)
			(stroke
				(width 0)
				(type default)
			)
			(fill no)
			(layer "B.Fab")
		)
		(pad "1" smd rect
			(at 0 -0.9652 270)
			(size 1.397 1.143)
			(layers "B.Cu" "B.Mask" "B.Paste")
			(net "VR_FET_SW_P12V_STBY_PVDDQ_DEF")
		)
		(pad "2" smd rect
			(at 0 0.9652 270)
			(size 1.397 1.143)
			(layers "B.Cu" "B.Mask" "B.Paste")
			(net "GND")
		)
	)
	(footprint ""
		(layer "B.Cu")
		(at 157.08122 -124.0917)
		(property "Reference" "R7M2"
			(at 0 0 0)
			(layer "B.SilkS")
			(hide yes)
			(effects
				(font
					(size 1.27 1.27)
				)
				(justify mirror)
			)
		)
		(property "Value" ""
			(at 0 0 0)
			(layer "B.Fab")
			(effects
				(font
					(size 1.27 1.27)
				)
				(justify mirror)
			)
		)
		(duplicate_pad_numbers_are_jumpers no)
		(fp_poly
			(pts
				(xy 0.2794 -0.1016) (xy -0.2794 -0.1016) (xy -0.2794 0.9906) (xy 0.2794 0.9906)
			)
			(stroke
				(width 0)
				(type default)
			)
			(fill no)
			(layer "B.CrtYd")
		)
		(fp_line
			(start -0.2794 -0.1016)
			(end 0.2794 -0.1016)
			(stroke
				(width 0.1)
				(type default)
			)
			(layer "B.Fab")
		)
		(fp_line
			(start -0.2794 0.9906)
			(end -0.2794 -0.1016)
			(stroke
				(width 0.1)
				(type default)
			)
			(layer "B.Fab")
		)
		(fp_line
			(start 0.2794 -0.1016)
			(end 0.2794 0.9906)
			(stroke
				(width 0.1)
				(type default)
			)
			(layer "B.Fab")
		)
		(fp_line
			(start 0.2794 0.9906)
			(end -0.2794 0.9906)
			(stroke
				(width 0.1)
				(type default)
			)
			(layer "B.Fab")
		)
		(pad "1" smd rect
			(at 0 0 180)
			(size 0.508 0.508)
			(layers "B.Cu" "B.Mask" "B.Paste")
			(net "PVCCIO_CPU1")
		)
		(pad "2" smd rect
			(at 0 0.889 180)
			(size 0.508 0.508)
			(layers "B.Cu" "B.Mask" "B.Paste")
			(net "SMB_DDR_KLM_SCL_G")
		)
		(zone
			(layer "B.Cu")
			(hatch none 0.5)
			(connect_pads
				(clearance 0)
			)
			(min_thickness 0.25)
			(keepout
				(tracks allowed)
				(vias not_allowed)
				(pads allowed)
				(copperpour not_allowed)
				(footprints allowed)
			)
			(placement
				(enabled no)
				(sheetname "")
			)
			(fill
				(thermal_gap 0.5)
				(thermal_bridge_width 0.5)
				(island_removal_mode 0)
			)
			(polygon
				(pts
					(xy 157.33522 -123.8377) (xy 156.82722 -123.8377) (xy 156.82722 -123.4567) (xy 157.33522 -123.4567)
				)
			)
		)
		(zone
			(layer "B.Cu")
			(hatch none 0.5)
			(connect_pads
				(clearance 0)
			)
			(min_thickness 0.25)
			(keepout
				(tracks not_allowed)
				(vias allowed)
				(pads allowed)
				(copperpour not_allowed)
				(footprints allowed)
			)
			(placement
				(enabled no)
				(sheetname "")
			)
			(fill
				(thermal_gap 0.5)
				(thermal_bridge_width 0.5)
				(island_removal_mode 0)
			)
			(polygon
				(pts
					(xy 157.33522 -123.4567) (xy 156.82722 -123.4567) (xy 156.82722 -123.8377) (xy 157.33522 -123.8377)
				)
			)
		)
	)
	(footprint ""
		(layer "B.Cu")
		(at 15.75308 -76.37272 90)
		(property "Reference" "C9P12"
			(at 0 0 90)
			(layer "B.SilkS")
			(hide yes)
			(effects
				(font
					(size 1.27 1.27)
				)
				(justify mirror)
			)
		)
		(property "Value" ""
			(at 0 0 90)
			(layer "B.Fab")
			(effects
				(font
					(size 1.27 1.27)
				)
				(justify mirror)
			)
		)
		(duplicate_pad_numbers_are_jumpers no)
		(fp_rect
			(start -0.3048 -0.1016)
			(end 0.3048 0.9906)
			(stroke
				(width 0)
				(type default)
			)
			(fill no)
			(layer "B.CrtYd")
		)
		(fp_line
			(start 0.3048 -0.1016)
			(end 0.3048 0.9906)
			(stroke
				(width 0.1)
				(type default)
			)
			(layer "B.Fab")
		)
		(fp_line
			(start -0.3048 -0.1016)
			(end 0.3048 -0.1016)
			(stroke
				(width 0.1)
				(type default)
			)
			(layer "B.Fab")
		)
		(fp_line
			(start 0.3048 0.9906)
			(end -0.3048 0.9906)
			(stroke
				(width 0.1)
				(type default)
			)
			(layer "B.Fab")
		)
		(fp_line
			(start -0.3048 0.9906)
			(end -0.3048 -0.1016)
			(stroke
				(width 0.1)
				(type default)
			)
			(layer "B.Fab")
		)
		(pad "1" smd rect
			(at 0 0 270)
			(size 0.508 0.508)
			(layers "B.Cu" "B.Mask" "B.Paste")
			(net "A_HSC_VOUT")
		)
		(pad "2" smd rect
			(at 0 0.889 270)
			(size 0.508 0.508)
			(layers "B.Cu" "B.Mask" "B.Paste")
			(net "AGND_HSC")
		)
		(zone
			(layer "B.Cu")
			(hatch none 0.5)
			(connect_pads
				(clearance 0)
			)
			(min_thickness 0.25)
			(keepout
				(tracks allowed)
				(vias not_allowed)
				(pads allowed)
				(copperpour not_allowed)
				(footprints allowed)
			)
			(placement
				(enabled no)
				(sheetname "")
			)
			(fill
				(thermal_gap 0.5)
				(thermal_bridge_width 0.5)
				(island_removal_mode 0)
			)
			(polygon
				(pts
					(xy 16.00708 -76.11872) (xy 16.38808 -76.11872) (xy 16.38808 -76.62672) (xy 16.00708 -76.62672)
				)
			)
		)
		(zone
			(layer "B.Cu")
			(hatch none 0.5)
			(connect_pads
				(clearance 0)
			)
			(min_thickness 0.25)
			(keepout
				(tracks not_allowed)
				(vias allowed)
				(pads allowed)
				(copperpour not_allowed)
				(footprints allowed)
			)
			(placement
				(enabled no)
				(sheetname "")
			)
			(fill
				(thermal_gap 0.5)
				(thermal_bridge_width 0.5)
				(island_removal_mode 0)
			)
			(polygon
				(pts
					(xy 16.00708 -76.11872) (xy 16.38808 -76.11872) (xy 16.38808 -76.62672) (xy 16.00708 -76.62672)
				)
			)
		)
	)
	(footprint ""
		(layer "B.Cu")
		(at 361.444794 -46.496986 -90)
		(property "Reference" "R7D43"
			(at 0 0 90)
			(layer "B.SilkS")
			(hide yes)
			(effects
				(font
					(size 1.27 1.27)
				)
				(justify mirror)
			)
		)
		(property "Value" ""
			(at 0 0 90)
			(layer "B.Fab")
			(effects
				(font
					(size 1.27 1.27)
				)
				(justify mirror)
			)
		)
		(duplicate_pad_numbers_are_jumpers no)
		(fp_poly
			(pts
				(xy 0.2794 -0.1016) (xy -0.2794 -0.1016) (xy -0.2794 0.9906) (xy 0.2794 0.9906)
			)
			(stroke
				(width 0)
				(type default)
			)
			(fill no)
			(layer "B.CrtYd")
		)
		(fp_line
			(start -0.2794 0.9906)
			(end -0.2794 -0.1016)
			(stroke
				(width 0.1)
				(type default)
			)
			(layer "B.Fab")
		)
		(fp_line
			(start 0.2794 0.9906)
			(end -0.2794 0.9906)
			(stroke
				(width 0.1)
				(type default)
			)
			(layer "B.Fab")
		)
		(fp_line
			(start -0.2794 -0.1016)
			(end 0.2794 -0.1016)
			(stroke
				(width 0.1)
				(type default)
			)
			(layer "B.Fab")
		)
		(fp_line
			(start 0.2794 -0.1016)
			(end 0.2794 0.9906)
			(stroke
				(width 0.1)
				(type default)
			)
			(layer "B.Fab")
		)
		(pad "1" smd rect
			(at 0 0 90)
			(size 0.508 0.508)
			(layers "B.Cu" "B.Mask" "B.Paste")
			(net "FM_CPU1_PROCHOT_LVT3_K_N")
		)
		(pad "2" smd rect
			(at 0 0.889 90)
			(size 0.508 0.508)
			(layers "B.Cu" "B.Mask" "B.Paste")
			(net "H_CPU1_PROCHOT_G_PCH_N")
		)
		(zone
			(layer "B.Cu")
			(hatch none 0.5)
			(connect_pads
				(clearance 0)
			)
			(min_thickness 0.25)
			(keepout
				(tracks not_allowed)
				(vias allowed)
				(pads allowed)
				(copperpour not_allowed)
				(footprints allowed)
			)
			(placement
				(enabled no)
				(sheetname "")
			)
			(fill
				(thermal_gap 0.5)
				(thermal_bridge_width 0.5)
				(island_removal_mode 0)
			)
			(polygon
				(pts
					(xy 360.809794 -46.242986) (xy 360.809794 -46.750986) (xy 361.190794 -46.750986) (xy 361.190794 -46.242986)
				)
			)
		)
		(zone
			(layer "B.Cu")
			(hatch none 0.5)
			(connect_pads
				(clearance 0)
			)
			(min_thickness 0.25)
			(keepout
				(tracks allowed)
				(vias not_allowed)
				(pads allowed)
				(copperpour not_allowed)
				(footprints allowed)
			)
			(placement
				(enabled no)
				(sheetname "")
			)
			(fill
				(thermal_gap 0.5)
				(thermal_bridge_width 0.5)
				(island_removal_mode 0)
			)
			(polygon
				(pts
					(xy 361.190794 -46.242986) (xy 361.190794 -46.750986) (xy 360.809794 -46.750986) (xy 360.809794 -46.242986)
				)
			)
		)
	)
	(footprint ""
		(layer "B.Cu")
		(at 454.740772 -35.174174 90)
		(property "Reference" "U8D2"
			(at 0.508 1.92913 270)
			(unlocked yes)
			(layer "B.SilkS")
			(effects
				(font
					(size 0.7874 0.5842)
					(thickness 0.1524)
				)
				(justify left mirror)
			)
		)
		(property "Value" ""
			(at 0 0 90)
			(layer "B.Fab")
			(effects
				(font
					(size 1.27 1.27)
				)
				(justify mirror)
			)
		)
		(duplicate_pad_numbers_are_jumpers no)
		(fp_circle
			(center 0.4699 -0.8382)
			(end 0.4699 -0.7112)
			(stroke
				(width 0.254)
				(type default)
			)
			(fill no)
			(layer "B.SilkS")
		)
		(fp_poly
			(pts
				(xy -0.21463 -0.450088) (xy -1.56337 -0.450088) (xy -1.56337 1.75006) (xy -0.21463 1.75006)
			)
			(stroke
				(width 0)
				(type default)
			)
			(fill no)
			(layer "B.CrtYd")
		)
		(fp_line
			(start -0.21463 -0.450088)
			(end -1.56337 -0.450088)
			(stroke
				(width 0.1)
				(type default)
			)
			(layer "B.Fab")
		)
		(fp_line
			(start -1.56337 -0.450088)
			(end -1.56337 1.75006)
			(stroke
				(width 0.1)
				(type default)
			)
			(layer "B.Fab")
		)
		(fp_line
			(start -0.21463 1.75006)
			(end -0.21463 -0.450088)
			(stroke
				(width 0.1)
				(type default)
			)
			(layer "B.Fab")
		)
		(fp_line
			(start -1.56337 1.75006)
			(end -0.21463 1.75006)
			(stroke
				(width 0.1)
				(type default)
			)
			(layer "B.Fab")
		)
		(fp_circle
			(center 0.4699 -0.8382)
			(end 0.4699 -0.7112)
			(stroke
				(width 0.254)
				(type default)
			)
			(fill no)
			(layer "B.Fab")
		)
		(pad "1" smd rect
			(at 0 0 270)
			(size 1.016 0.381)
			(layers "B.Cu" "B.Mask" "B.Paste")
			(net "Net_6477")
		)
		(pad "2" smd rect
			(at 0 0.649986 270)
			(size 1.016 0.381)
			(layers "B.Cu" "B.Mask" "B.Paste")
			(net "PWRGD_DSW_PWROK")
		)
		(pad "3" smd rect
			(at 0 1.299972 270)
			(size 1.016 0.381)
			(layers "B.Cu" "B.Mask" "B.Paste")
			(net "GND")
		)
		(pad "4" smd rect
			(at -1.778 1.299972 270)
			(size 1.016 0.381)
			(layers "B.Cu" "B.Mask" "B.Paste")
			(net "RST_BMC_SRST_R2_N")
		)
		(pad "5" smd rect
			(at -1.778 0 270)
			(size 1.016 0.381)
			(layers "B.Cu" "B.Mask" "B.Paste")
			(net "P3V3_STBY")
		)
	)
	(footprint ""
		(layer "B.Cu")
		(at 459.867 -116.49202)
		(property "Reference" "C1M10"
			(at 0 0 0)
			(layer "B.SilkS")
			(hide yes)
			(effects
				(font
					(size 1.27 1.27)
				)
				(justify mirror)
			)
		)
		(property "Value" ""
			(at 0 0 0)
			(layer "B.Fab")
			(effects
				(font
					(size 1.27 1.27)
				)
				(justify mirror)
			)
		)
		(duplicate_pad_numbers_are_jumpers no)
		(fp_rect
			(start -0.3048 0.9906)
			(end 0.3048 -0.1016)
			(stroke
				(width 0)
				(type default)
			)
			(fill no)
			(layer "B.CrtYd")
		)
		(fp_line
			(start -0.3048 -0.1016)
			(end 0.3048 -0.1016)
			(stroke
				(width 0.1)
				(type default)
			)
			(layer "B.Fab")
		)
		(fp_line
			(start -0.3048 0.9906)
			(end -0.3048 -0.1016)
			(stroke
				(width 0.1)
				(type default)
			)
			(layer "B.Fab")
		)
		(fp_line
			(start 0.3048 -0.1016)
			(end 0.3048 0.9906)
			(stroke
				(width 0.1)
				(type default)
			)
			(layer "B.Fab")
		)
		(fp_line
			(start 0.3048 0.9906)
			(end -0.3048 0.9906)
			(stroke
				(width 0.1)
				(type default)
			)
			(layer "B.Fab")
		)
		(pad "1" smd rect
			(at 0 0 180)
			(size 0.508 0.508)
			(layers "B.Cu" "B.Mask" "B.Paste")
			(net "P3E_CPU0_PE3_OCP_TXP<13>")
		)
		(pad "2" smd rect
			(at 0 0.889 180)
			(size 0.508 0.508)
			(layers "B.Cu" "B.Mask" "B.Paste")
			(net "P3E_OCP_CPU0_PE3_C_TXP<13>")
		)
		(zone
			(layer "B.Cu")
			(hatch none 0.5)
			(connect_pads
				(clearance 0)
			)
			(min_thickness 0.25)
			(keepout
				(tracks allowed)
				(vias not_allowed)
				(pads allowed)
				(copperpour not_allowed)
				(footprints allowed)
			)
			(placement
				(enabled no)
				(sheetname "")
			)
			(fill
				(thermal_gap 0.5)
				(thermal_bridge_width 0.5)
				(island_removal_mode 0)
			)
			(polygon
				(pts
					(xy 459.613 -115.85702) (xy 460.121 -115.85702) (xy 460.121 -116.23802) (xy 459.613 -116.23802)
				)
			)
		)
		(zone
			(layer "B.Cu")
			(hatch none 0.5)
			(connect_pads
				(clearance 0)
			)
			(min_thickness 0.25)
			(keepout
				(tracks not_allowed)
				(vias allowed)
				(pads allowed)
				(copperpour not_allowed)
				(footprints allowed)
			)
			(placement
				(enabled no)
				(sheetname "")
			)
			(fill
				(thermal_gap 0.5)
				(thermal_bridge_width 0.5)
				(island_removal_mode 0)
			)
			(polygon
				(pts
					(xy 459.613 -115.85702) (xy 460.121 -115.85702) (xy 460.121 -116.23802) (xy 459.613 -116.23802)
				)
			)
		)
	)
	(footprint ""
		(layer "B.Cu")
		(at 377.698 -19.558)
		(property "Reference" "RN8F3"
			(at 0.8382 -0.67818 0)
			(unlocked yes)
			(layer "B.SilkS")
			(effects
				(font
					(size 0.4064 0.254)
					(thickness 0.1524)
				)
				(justify left mirror)
			)
		)
		(property "Value" ""
			(at 0 0 0)
			(layer "B.Fab")
			(effects
				(font
					(size 1.27 1.27)
				)
				(justify mirror)
			)
		)
		(duplicate_pad_numbers_are_jumpers no)
		(fp_poly
			(pts
				(xy 0.2794 -0.1016) (xy -0.2794 -0.1016) (xy -0.2794 0.9906) (xy 0.2794 0.9906)
			)
			(stroke
				(width 0)
				(type default)
			)
			(fill no)
			(layer "B.CrtYd")
		)
		(fp_line
			(start -0.2794 -0.1016)
			(end 0.2794 -0.1016)
			(stroke
				(width 0.1)
				(type default)
			)
			(layer "B.Fab")
		)
		(fp_line
			(start -0.2794 0.9906)
			(end -0.2794 -0.1016)
			(stroke
				(width 0.1)
				(type default)
			)
			(layer "B.Fab")
		)
		(fp_line
			(start 0.2794 -0.1016)
			(end 0.2794 0.9906)
			(stroke
				(width 0.1)
				(type default)
			)
			(layer "B.Fab")
		)
		(fp_line
			(start 0.2794 0.9906)
			(end -0.2794 0.9906)
			(stroke
				(width 0.1)
				(type default)
			)
			(layer "B.Fab")
		)
		(pad "1" smd rect
			(at 0 0 180)
			(size 0.508 0.508)
			(layers "B.Cu" "B.Mask" "B.Paste")
			(net "P3V3_STBY")
		)
		(pad "2" smd rect
			(at 0 0.889 180)
			(size 0.508 0.508)
			(layers "B.Cu" "B.Mask" "B.Paste")
			(net "PU_TPM_SPI_BMC_HOLD_N")
		)
		(zone
			(layer "B.Cu")
			(hatch none 0.5)
			(connect_pads
				(clearance 0)
			)
			(min_thickness 0.25)
			(keepout
				(tracks allowed)
				(vias not_allowed)
				(pads allowed)
				(copperpour not_allowed)
				(footprints allowed)
			)
			(placement
				(enabled no)
				(sheetname "")
			)
			(fill
				(thermal_gap 0.5)
				(thermal_bridge_width 0.5)
				(island_removal_mode 0)
			)
			(polygon
				(pts
					(xy 377.952 -19.304) (xy 377.444 -19.304) (xy 377.444 -18.923) (xy 377.952 -18.923)
				)
			)
		)
		(zone
			(layer "B.Cu")
			(hatch none 0.5)
			(connect_pads
				(clearance 0)
			)
			(min_thickness 0.25)
			(keepout
				(tracks not_allowed)
				(vias allowed)
				(pads allowed)
				(copperpour not_allowed)
				(footprints allowed)
			)
			(placement
				(enabled no)
				(sheetname "")
			)
			(fill
				(thermal_gap 0.5)
				(thermal_bridge_width 0.5)
				(island_removal_mode 0)
			)
			(polygon
				(pts
					(xy 377.952 -18.923) (xy 377.444 -18.923) (xy 377.444 -19.304) (xy 377.952 -19.304)
				)
			)
		)
	)
	(footprint ""
		(layer "B.Cu")
		(at 487.9975 -152.5016 -90)
		(property "Reference" "C1L4"
			(at 0 0 90)
			(layer "B.SilkS")
			(hide yes)
			(effects
				(font
					(size 1.27 1.27)
				)
				(justify mirror)
			)
		)
		(property "Value" ""
			(at 0 0 90)
			(layer "B.Fab")
			(effects
				(font
					(size 1.27 1.27)
				)
				(justify mirror)
			)
		)
		(duplicate_pad_numbers_are_jumpers no)
		(fp_poly
			(pts
				(xy -0.3048 -0.1016) (xy -0.3048 0.9906) (xy 0.3048 0.9906) (xy 0.3048 -0.1016)
			)
			(stroke
				(width 0)
				(type default)
			)
			(fill no)
			(layer "B.CrtYd")
		)
		(fp_line
			(start -0.3048 0.9906)
			(end -0.3048 -0.1016)
			(stroke
				(width 0.1)
				(type default)
			)
			(layer "B.Fab")
		)
		(fp_line
			(start 0.3048 0.9906)
			(end -0.3048 0.9906)
			(stroke
				(width 0.1)
				(type default)
			)
			(layer "B.Fab")
		)
		(fp_line
			(start -0.3048 -0.1016)
			(end 0.3048 -0.1016)
			(stroke
				(width 0.1)
				(type default)
			)
			(layer "B.Fab")
		)
		(fp_line
			(start 0.3048 -0.1016)
			(end 0.3048 0.9906)
			(stroke
				(width 0.1)
				(type default)
			)
			(layer "B.Fab")
		)
		(pad "1" smd rect
			(at 0 0 90)
			(size 0.508 0.508)
			(layers "B.Cu" "B.Mask" "B.Paste")
			(net "P5V_STBY")
		)
		(pad "2" smd rect
			(at 0 0.889 90)
			(size 0.508 0.508)
			(layers "B.Cu" "B.Mask" "B.Paste")
			(net "GND")
		)
		(zone
			(layer "B.Cu")
			(hatch none 0.5)
			(connect_pads
				(clearance 0)
			)
			(min_thickness 0.25)
			(keepout
				(tracks not_allowed)
				(vias allowed)
				(pads allowed)
				(copperpour not_allowed)
				(footprints allowed)
			)
			(placement
				(enabled no)
				(sheetname "")
			)
			(fill
				(thermal_gap 0.5)
				(thermal_bridge_width 0.5)
				(island_removal_mode 0)
			)
			(polygon
				(pts
					(xy 487.3625 -152.2476) (xy 487.3625 -152.7556) (xy 487.7435 -152.7556) (xy 487.7435 -152.2476)
				)
			)
		)
		(zone
			(layer "B.Cu")
			(hatch none 0.5)
			(connect_pads
				(clearance 0)
			)
			(min_thickness 0.25)
			(keepout
				(tracks allowed)
				(vias not_allowed)
				(pads allowed)
				(copperpour not_allowed)
				(footprints allowed)
			)
			(placement
				(enabled no)
				(sheetname "")
			)
			(fill
				(thermal_gap 0.5)
				(thermal_bridge_width 0.5)
				(island_removal_mode 0)
			)
			(polygon
				(pts
					(xy 487.7435 -152.2476) (xy 487.7435 -152.7556) (xy 487.3625 -152.7556) (xy 487.3625 -152.2476)
				)
			)
		)
	)
	(footprint ""
		(layer "B.Cu")
		(at 3.8227 -7.727696 90)
		(property "Reference" "C9U6"
			(at 0 0 90)
			(layer "B.SilkS")
			(hide yes)
			(effects
				(font
					(size 1.27 1.27)
				)
				(justify mirror)
			)
		)
		(property "Value" ""
			(at 0 0 90)
			(layer "B.Fab")
			(effects
				(font
					(size 1.27 1.27)
				)
				(justify mirror)
			)
		)
		(duplicate_pad_numbers_are_jumpers no)
		(fp_rect
			(start -0.7239 -0.2159)
			(end 0.7239 1.9939)
			(stroke
				(width 0)
				(type default)
			)
			(fill no)
			(layer "B.CrtYd")
		)
		(fp_line
			(start 0.7239 -0.2159)
			(end 0.7239 1.9939)
			(stroke
				(width 0.1)
				(type default)
			)
			(layer "B.Fab")
		)
		(fp_line
			(start -0.7239 -0.2159)
			(end 0.7239 -0.2159)
			(stroke
				(width 0.1)
				(type default)
			)
			(layer "B.Fab")
		)
		(fp_line
			(start 0.7239 1.9939)
			(end -0.7239 1.9939)
			(stroke
				(width 0.1)
				(type default)
			)
			(layer "B.Fab")
		)
		(fp_line
			(start -0.7239 1.9939)
			(end -0.7239 -0.2159)
			(stroke
				(width 0.1)
				(type default)
			)
			(layer "B.Fab")
		)
		(pad "1" smd rect
			(at 0 0 270)
			(size 1.27 1.016)
			(layers "B.Cu" "B.Mask" "B.Paste")
			(net "VR_FET_SW_P12V_STBY_PVDDQ_GHJ")
		)
		(pad "2" smd rect
			(at 0 1.778 270)
			(size 1.27 1.016)
			(layers "B.Cu" "B.Mask" "B.Paste")
			(net "GND")
		)
		(zone
			(layer "B.Cu")
			(hatch none 0.5)
			(connect_pads
				(clearance 0)
			)
			(min_thickness 0.25)
			(keepout
				(tracks not_allowed)
				(vias allowed)
				(pads allowed)
				(copperpour not_allowed)
				(footprints allowed)
			)
			(placement
				(enabled no)
				(sheetname "")
			)
			(fill
				(thermal_gap 0.5)
				(thermal_bridge_width 0.5)
				(island_removal_mode 0)
			)
			(polygon
				(pts
					(xy 4.3307 -7.092696) (xy 5.0927 -7.092696) (xy 5.0927 -8.362696) (xy 4.3307 -8.362696)
				)
			)
		)
	)
	(footprint ""
		(layer "B.Cu")
		(at 28.0924 -17.723612 -90)
		(property "Reference" "C9T8"
			(at 0 0 90)
			(layer "B.SilkS")
			(hide yes)
			(effects
				(font
					(size 1.27 1.27)
				)
				(justify mirror)
			)
		)
		(property "Value" ""
			(at 0 0 90)
			(layer "B.Fab")
			(effects
				(font
					(size 1.27 1.27)
				)
				(justify mirror)
			)
		)
		(duplicate_pad_numbers_are_jumpers no)
		(fp_rect
			(start 0.7239 -0.2159)
			(end -0.7239 1.9939)
			(stroke
				(width 0)
				(type default)
			)
			(fill no)
			(layer "B.CrtYd")
		)
		(fp_line
			(start -0.7239 1.9939)
			(end -0.7239 -0.2159)
			(stroke
				(width 0.1)
				(type default)
			)
			(layer "B.Fab")
		)
		(fp_line
			(start 0.7239 1.9939)
			(end -0.7239 1.9939)
			(stroke
				(width 0.1)
				(type default)
			)
			(layer "B.Fab")
		)
		(fp_line
			(start -0.7239 -0.2159)
			(end 0.7239 -0.2159)
			(stroke
				(width 0.1)
				(type default)
			)
			(layer "B.Fab")
		)
		(fp_line
			(start 0.7239 -0.2159)
			(end 0.7239 1.9939)
			(stroke
				(width 0.1)
				(type default)
			)
			(layer "B.Fab")
		)
		(pad "1" smd rect
			(at 0 0 90)
			(size 1.27 1.016)
			(layers "B.Cu" "B.Mask" "B.Paste")
			(net "P12V_NVDIMM_GHJ")
		)
		(pad "2" smd rect
			(at 0 1.778 90)
			(size 1.27 1.016)
			(layers "B.Cu" "B.Mask" "B.Paste")
			(net "GND")
		)
		(zone
			(layer "B.Cu")
			(hatch none 0.5)
			(connect_pads
				(clearance 0)
			)
			(min_thickness 0.25)
			(keepout
				(tracks not_allowed)
				(vias allowed)
				(pads allowed)
				(copperpour not_allowed)
				(footprints allowed)
			)
			(placement
				(enabled no)
				(sheetname "")
			)
			(fill
				(thermal_gap 0.5)
				(thermal_bridge_width 0.5)
				(island_removal_mode 0)
			)
			(polygon
				(pts
					(xy 27.5844 -17.088612) (xy 27.5844 -18.358612) (xy 26.8224 -18.358612) (xy 26.8224 -17.088612)
				)
			)
		)
	)
	(footprint ""
		(layer "B.Cu")
		(at 9.398 -68.0466 180)
		(property "Reference" "R9P27"
			(at 0 0 0)
			(layer "B.SilkS")
			(hide yes)
			(effects
				(font
					(size 1.27 1.27)
				)
				(justify mirror)
			)
		)
		(property "Value" ""
			(at 0 0 0)
			(layer "B.Fab")
			(effects
				(font
					(size 1.27 1.27)
				)
				(justify mirror)
			)
		)
		(duplicate_pad_numbers_are_jumpers no)
		(fp_rect
			(start -0.2794 0.9906)
			(end 0.2794 -0.1016)
			(stroke
				(width 0)
				(type default)
			)
			(fill no)
			(layer "B.CrtYd")
		)
		(fp_line
			(start 0.2794 0.9906)
			(end -0.2794 0.9906)
			(stroke
				(width 0.1)
				(type default)
			)
			(layer "B.Fab")
		)
		(fp_line
			(start 0.2794 -0.1016)
			(end 0.2794 0.9906)
			(stroke
				(width 0.1)
				(type default)
			)
			(layer "B.Fab")
		)
		(fp_line
			(start -0.2794 0.9906)
			(end -0.2794 -0.1016)
			(stroke
				(width 0.1)
				(type default)
			)
			(layer "B.Fab")
		)
		(fp_line
			(start -0.2794 -0.1016)
			(end 0.2794 -0.1016)
			(stroke
				(width 0.1)
				(type default)
			)
			(layer "B.Fab")
		)
		(pad "1" smd rect
			(at 0 0)
			(size 0.508 0.508)
			(layers "B.Cu" "B.Mask" "B.Paste")
			(net "P12V_HSC_SENP1")
		)
		(pad "2" smd rect
			(at 0 0.889)
			(size 0.508 0.508)
			(layers "B.Cu" "B.Mask" "B.Paste")
			(net "A_HSC_HSP")
		)
		(zone
			(layer "B.Cu")
			(hatch none 0.5)
			(connect_pads
				(clearance 0)
			)
			(min_thickness 0.25)
			(keepout
				(tracks allowed)
				(vias not_allowed)
				(pads allowed)
				(copperpour not_allowed)
				(footprints allowed)
			)
			(placement
				(enabled no)
				(sheetname "")
			)
			(fill
				(thermal_gap 0.5)
				(thermal_bridge_width 0.5)
				(island_removal_mode 0)
			)
			(polygon
				(pts
					(xy 9.652 -68.6816) (xy 9.144 -68.6816) (xy 9.144 -68.3006) (xy 9.652 -68.3006)
				)
			)
		)
		(zone
			(layer "B.Cu")
			(hatch none 0.5)
			(connect_pads
				(clearance 0)
			)
			(min_thickness 0.25)
			(keepout
				(tracks not_allowed)
				(vias allowed)
				(pads allowed)
				(copperpour not_allowed)
				(footprints allowed)
			)
			(placement
				(enabled no)
				(sheetname "")
			)
			(fill
				(thermal_gap 0.5)
				(thermal_bridge_width 0.5)
				(island_removal_mode 0)
			)
			(polygon
				(pts
					(xy 9.652 -68.6816) (xy 9.144 -68.6816) (xy 9.144 -68.3006) (xy 9.652 -68.3006)
				)
			)
		)
	)
	(footprint ""
		(layer "B.Cu")
		(at 334.743806 -60.368434)
		(property "Reference" "R2U15"
			(at 0 0 0)
			(layer "B.SilkS")
			(hide yes)
			(effects
				(font
					(size 1.27 1.27)
				)
				(justify mirror)
			)
		)
		(property "Value" ""
			(at 0 0 0)
			(layer "B.Fab")
			(effects
				(font
					(size 1.27 1.27)
				)
				(justify mirror)
			)
		)
		(duplicate_pad_numbers_are_jumpers no)
		(fp_poly
			(pts
				(xy 0.2794 -0.1016) (xy -0.2794 -0.1016) (xy -0.2794 0.9906) (xy 0.2794 0.9906)
			)
			(stroke
				(width 0)
				(type default)
			)
			(fill no)
			(layer "B.CrtYd")
		)
		(fp_line
			(start -0.2794 -0.1016)
			(end 0.2794 -0.1016)
			(stroke
				(width 0.1)
				(type default)
			)
			(layer "B.Fab")
		)
		(fp_line
			(start -0.2794 0.9906)
			(end -0.2794 -0.1016)
			(stroke
				(width 0.1)
				(type default)
			)
			(layer "B.Fab")
		)
		(fp_line
			(start 0.2794 -0.1016)
			(end 0.2794 0.9906)
			(stroke
				(width 0.1)
				(type default)
			)
			(layer "B.Fab")
		)
		(fp_line
			(start 0.2794 0.9906)
			(end -0.2794 0.9906)
			(stroke
				(width 0.1)
				(type default)
			)
			(layer "B.Fab")
		)
		(pad "1" smd rect
			(at 0 0 180)
			(size 0.508 0.508)
			(layers "B.Cu" "B.Mask" "B.Paste")
			(net "P3E_CPU0_PE1_SS_RXN<0>")
		)
		(pad "2" smd rect
			(at 0 0.889 180)
			(size 0.508 0.508)
			(layers "B.Cu" "B.Mask" "B.Paste")
			(net "P3E_CPU0_PE1_SS_R_RXN<0>")
		)
		(zone
			(layer "B.Cu")
			(hatch none 0.5)
			(connect_pads
				(clearance 0)
			)
			(min_thickness 0.25)
			(keepout
				(tracks allowed)
				(vias not_allowed)
				(pads allowed)
				(copperpour not_allowed)
				(footprints allowed)
			)
			(placement
				(enabled no)
				(sheetname "")
			)
			(fill
				(thermal_gap 0.5)
				(thermal_bridge_width 0.5)
				(island_removal_mode 0)
			)
			(polygon
				(pts
					(xy 334.997806 -60.114434) (xy 334.489806 -60.114434) (xy 334.489806 -59.733434) (xy 334.997806 -59.733434)
				)
			)
		)
		(zone
			(layer "B.Cu")
			(hatch none 0.5)
			(connect_pads
				(clearance 0)
			)
			(min_thickness 0.25)
			(keepout
				(tracks not_allowed)
				(vias allowed)
				(pads allowed)
				(copperpour not_allowed)
				(footprints allowed)
			)
			(placement
				(enabled no)
				(sheetname "")
			)
			(fill
				(thermal_gap 0.5)
				(thermal_bridge_width 0.5)
				(island_removal_mode 0)
			)
			(polygon
				(pts
					(xy 334.997806 -59.733434) (xy 334.489806 -59.733434) (xy 334.489806 -60.114434) (xy 334.997806 -60.114434)
				)
			)
		)
	)
	(footprint ""
		(layer "B.Cu")
		(at 476.4151 -37.5412 90)
		(property "Reference" "R1T33"
			(at 0 0 90)
			(layer "B.SilkS")
			(hide yes)
			(effects
				(font
					(size 1.27 1.27)
				)
				(justify mirror)
			)
		)
		(property "Value" ""
			(at 0 0 90)
			(layer "B.Fab")
			(effects
				(font
					(size 1.27 1.27)
				)
				(justify mirror)
			)
		)
		(duplicate_pad_numbers_are_jumpers no)
		(fp_poly
			(pts
				(xy 0.4953 -0.2032) (xy -0.4953 -0.2032) (xy -0.4953 1.6002) (xy 0.4953 1.6002)
			)
			(stroke
				(width 0)
				(type default)
			)
			(fill no)
			(layer "B.CrtYd")
		)
		(fp_line
			(start 0.4953 -0.2032)
			(end -0.4953 -0.2032)
			(stroke
				(width 0.1)
				(type default)
			)
			(layer "B.Fab")
		)
		(fp_line
			(start -0.4953 -0.2032)
			(end -0.4953 1.6002)
			(stroke
				(width 0.1)
				(type default)
			)
			(layer "B.Fab")
		)
		(fp_line
			(start 0.4953 1.6002)
			(end 0.4953 -0.2032)
			(stroke
				(width 0.1)
				(type default)
			)
			(layer "B.Fab")
		)
		(fp_line
			(start -0.4953 1.6002)
			(end 0.4953 1.6002)
			(stroke
				(width 0.1)
				(type default)
			)
			(layer "B.Fab")
		)
		(pad "1" smd rect
			(at 0 0 270)
			(size 0.762 0.889)
			(layers "B.Cu" "B.Mask" "B.Paste")
			(net "P1V5_LAN")
		)
		(pad "2" smd rect
			(at 0 1.397 270)
			(size 0.762 0.889)
			(layers "B.Cu" "B.Mask" "B.Paste")
			(net "P3V3_STBY_P1V5_LAN_I210")
		)
		(zone
			(layer "B.Cu")
			(hatch none 0.5)
			(connect_pads
				(clearance 0)
			)
			(min_thickness 0.25)
			(keepout
				(tracks not_allowed)
				(vias allowed)
				(pads allowed)
				(copperpour not_allowed)
				(footprints allowed)
			)
			(placement
				(enabled no)
				(sheetname "")
			)
			(fill
				(thermal_gap 0.5)
				(thermal_bridge_width 0.5)
				(island_removal_mode 0)
			)
			(polygon
				(pts
					(xy 477.3676 -37.9222) (xy 476.8596 -37.9222) (xy 476.8596 -37.1602) (xy 477.3676 -37.1602)
				)
			)
		)
		(zone
			(layer "B.Cu")
			(hatch none 0.5)
			(connect_pads
				(clearance 0)
			)
			(min_thickness 0.25)
			(keepout
				(tracks allowed)
				(vias not_allowed)
				(pads allowed)
				(copperpour not_allowed)
				(footprints allowed)
			)
			(placement
				(enabled no)
				(sheetname "")
			)
			(fill
				(thermal_gap 0.5)
				(thermal_bridge_width 0.5)
				(island_removal_mode 0)
			)
			(polygon
				(pts
					(xy 477.3676 -37.1602) (xy 476.8596 -37.1602) (xy 476.8596 -37.9222) (xy 477.3676 -37.9222)
				)
			)
		)
	)
	(footprint ""
		(layer "B.Cu")
		(at 340.741 -82.7024 90)
		(property "Reference" "R3P26"
			(at 0 0 90)
			(layer "B.SilkS")
			(hide yes)
			(effects
				(font
					(size 1.27 1.27)
				)
				(justify mirror)
			)
		)
		(property "Value" ""
			(at 0 0 90)
			(layer "B.Fab")
			(effects
				(font
					(size 1.27 1.27)
				)
				(justify mirror)
			)
		)
		(duplicate_pad_numbers_are_jumpers no)
		(fp_poly
			(pts
				(xy 0.2794 -0.1016) (xy -0.2794 -0.1016) (xy -0.2794 0.9906) (xy 0.2794 0.9906)
			)
			(stroke
				(width 0)
				(type default)
			)
			(fill no)
			(layer "B.CrtYd")
		)
		(fp_line
			(start 0.2794 -0.1016)
			(end 0.2794 0.9906)
			(stroke
				(width 0.1)
				(type default)
			)
			(layer "B.Fab")
		)
		(fp_line
			(start -0.2794 -0.1016)
			(end 0.2794 -0.1016)
			(stroke
				(width 0.1)
				(type default)
			)
			(layer "B.Fab")
		)
		(fp_line
			(start 0.2794 0.9906)
			(end -0.2794 0.9906)
			(stroke
				(width 0.1)
				(type default)
			)
			(layer "B.Fab")
		)
		(fp_line
			(start -0.2794 0.9906)
			(end -0.2794 -0.1016)
			(stroke
				(width 0.1)
				(type default)
			)
			(layer "B.Fab")
		)
		(pad "1" smd rect
			(at 0 0 270)
			(size 0.508 0.508)
			(layers "B.Cu" "B.Mask" "B.Paste")
			(net "FM_PVCCIO_CPU0_EN")
		)
		(pad "2" smd rect
			(at 0 0.889 270)
			(size 0.508 0.508)
			(layers "B.Cu" "B.Mask" "B.Paste")
			(net "VR_PVCCIO_CPU0_EN")
		)
		(zone
			(layer "B.Cu")
			(hatch none 0.5)
			(connect_pads
				(clearance 0)
			)
			(min_thickness 0.25)
			(keepout
				(tracks allowed)
				(vias not_allowed)
				(pads allowed)
				(copperpour not_allowed)
				(footprints allowed)
			)
			(placement
				(enabled no)
				(sheetname "")
			)
			(fill
				(thermal_gap 0.5)
				(thermal_bridge_width 0.5)
				(island_removal_mode 0)
			)
			(polygon
				(pts
					(xy 340.995 -82.9564) (xy 340.995 -82.4484) (xy 341.376 -82.4484) (xy 341.376 -82.9564)
				)
			)
		)
		(zone
			(layer "B.Cu")
			(hatch none 0.5)
			(connect_pads
				(clearance 0)
			)
			(min_thickness 0.25)
			(keepout
				(tracks not_allowed)
				(vias allowed)
				(pads allowed)
				(copperpour not_allowed)
				(footprints allowed)
			)
			(placement
				(enabled no)
				(sheetname "")
			)
			(fill
				(thermal_gap 0.5)
				(thermal_bridge_width 0.5)
				(island_removal_mode 0)
			)
			(polygon
				(pts
					(xy 341.376 -82.9564) (xy 341.376 -82.4484) (xy 340.995 -82.4484) (xy 340.995 -82.9564)
				)
			)
		)
	)
	(footprint ""
		(layer "B.Cu")
		(at 374.015 -138.1125)
		(property "Reference" "C3L23"
			(at 0 0 0)
			(layer "B.SilkS")
			(hide yes)
			(effects
				(font
					(size 1.27 1.27)
				)
				(justify mirror)
			)
		)
		(property "Value" ""
			(at 0 0 0)
			(layer "B.Fab")
			(effects
				(font
					(size 1.27 1.27)
				)
				(justify mirror)
			)
		)
		(duplicate_pad_numbers_are_jumpers no)
		(fp_poly
			(pts
				(xy 0.4953 -0.2032) (xy -0.4953 -0.2032) (xy -0.4953 1.6002) (xy 0.4953 1.6002)
			)
			(stroke
				(width 0)
				(type default)
			)
			(fill no)
			(layer "B.CrtYd")
		)
		(fp_line
			(start -0.4953 -0.2032)
			(end -0.4953 1.6002)
			(stroke
				(width 0.1)
				(type default)
			)
			(layer "B.Fab")
		)
		(fp_line
			(start -0.4953 1.6002)
			(end 0.4953 1.6002)
			(stroke
				(width 0.1)
				(type default)
			)
			(layer "B.Fab")
		)
		(fp_line
			(start 0.4953 -0.2032)
			(end -0.4953 -0.2032)
			(stroke
				(width 0.1)
				(type default)
			)
			(layer "B.Fab")
		)
		(fp_line
			(start 0.4953 1.6002)
			(end 0.4953 -0.2032)
			(stroke
				(width 0.1)
				(type default)
			)
			(layer "B.Fab")
		)
		(pad "1" smd rect
			(at 0 0 180)
			(size 0.762 0.889)
			(layers "B.Cu" "B.Mask" "B.Paste")
			(net "PVNN_PCH_STBY")
		)
		(pad "2" smd rect
			(at 0 1.397 180)
			(size 0.762 0.889)
			(layers "B.Cu" "B.Mask" "B.Paste")
			(net "GND")
		)
		(zone
			(layer "B.Cu")
			(hatch none 0.5)
			(connect_pads
				(clearance 0)
			)
			(min_thickness 0.25)
			(keepout
				(tracks not_allowed)
				(vias allowed)
				(pads allowed)
				(copperpour not_allowed)
				(footprints allowed)
			)
			(placement
				(enabled no)
				(sheetname "")
			)
			(fill
				(thermal_gap 0.5)
				(thermal_bridge_width 0.5)
				(island_removal_mode 0)
			)
			(polygon
				(pts
					(xy 374.396 -137.668) (xy 373.634 -137.668) (xy 373.634 -137.16) (xy 374.396 -137.16)
				)
			)
		)
	)
	(footprint ""
		(layer "B.Cu")
		(at 163.531042 -71.982076 180)
		(property "Reference" "R6P46"
			(at 0 0 0)
			(layer "B.SilkS")
			(hide yes)
			(effects
				(font
					(size 1.27 1.27)
				)
				(justify mirror)
			)
		)
		(property "Value" ""
			(at 0 0 0)
			(layer "B.Fab")
			(effects
				(font
					(size 1.27 1.27)
				)
				(justify mirror)
			)
		)
		(duplicate_pad_numbers_are_jumpers no)
		(fp_poly
			(pts
				(xy 0.2794 -0.1016) (xy -0.2794 -0.1016) (xy -0.2794 0.9906) (xy 0.2794 0.9906)
			)
			(stroke
				(width 0)
				(type default)
			)
			(fill no)
			(layer "B.CrtYd")
		)
		(fp_line
			(start 0.2794 0.9906)
			(end -0.2794 0.9906)
			(stroke
				(width 0.1)
				(type default)
			)
			(layer "B.Fab")
		)
		(fp_line
			(start 0.2794 -0.1016)
			(end 0.2794 0.9906)
			(stroke
				(width 0.1)
				(type default)
			)
			(layer "B.Fab")
		)
		(fp_line
			(start -0.2794 0.9906)
			(end -0.2794 -0.1016)
			(stroke
				(width 0.1)
				(type default)
			)
			(layer "B.Fab")
		)
		(fp_line
			(start -0.2794 -0.1016)
			(end 0.2794 -0.1016)
			(stroke
				(width 0.1)
				(type default)
			)
			(layer "B.Fab")
		)
		(pad "1" smd rect
			(at 0 0)
			(size 0.508 0.508)
			(layers "B.Cu" "B.Mask" "B.Paste")
			(net "PVCCIO_CPU0")
		)
		(pad "2" smd rect
			(at 0 0.889)
			(size 0.508 0.508)
			(layers "B.Cu" "B.Mask" "B.Paste")
			(net "XDP_CPU_MBP1_N")
		)
		(zone
			(layer "B.Cu")
			(hatch none 0.5)
			(connect_pads
				(clearance 0)
			)
			(min_thickness 0.25)
			(keepout
				(tracks not_allowed)
				(vias allowed)
				(pads allowed)
				(copperpour not_allowed)
				(footprints allowed)
			)
			(placement
				(enabled no)
				(sheetname "")
			)
			(fill
				(thermal_gap 0.5)
				(thermal_bridge_width 0.5)
				(island_removal_mode 0)
			)
			(polygon
				(pts
					(xy 163.277042 -72.617076) (xy 163.785042 -72.617076) (xy 163.785042 -72.236076) (xy 163.277042 -72.236076)
				)
			)
		)
		(zone
			(layer "B.Cu")
			(hatch none 0.5)
			(connect_pads
				(clearance 0)
			)
			(min_thickness 0.25)
			(keepout
				(tracks allowed)
				(vias not_allowed)
				(pads allowed)
				(copperpour not_allowed)
				(footprints allowed)
			)
			(placement
				(enabled no)
				(sheetname "")
			)
			(fill
				(thermal_gap 0.5)
				(thermal_bridge_width 0.5)
				(island_removal_mode 0)
			)
			(polygon
				(pts
					(xy 163.277042 -72.236076) (xy 163.785042 -72.236076) (xy 163.785042 -72.617076) (xy 163.277042 -72.617076)
				)
			)
		)
	)
	(footprint ""
		(layer "B.Cu")
		(at 107.8611 -3.3528 90)
		(property "Reference" "C5G91"
			(at -1.14681 0.76708 180)
			(unlocked yes)
			(layer "B.SilkS")
			(effects
				(font
					(size 0.7874 0.5842)
					(thickness 0.1524)
				)
				(justify mirror)
			)
		)
		(property "Value" ""
			(at 0 0 90)
			(layer "B.Fab")
			(effects
				(font
					(size 1.27 1.27)
				)
				(justify mirror)
			)
		)
		(duplicate_pad_numbers_are_jumpers no)
		(fp_rect
			(start -0.4953 -0.2032)
			(end 0.4953 1.6002)
			(stroke
				(width 0)
				(type default)
			)
			(fill no)
			(layer "B.CrtYd")
		)
		(fp_line
			(start 0.4953 -0.2032)
			(end -0.4953 -0.2032)
			(stroke
				(width 0.1)
				(type default)
			)
			(layer "B.Fab")
		)
		(fp_line
			(start -0.4953 -0.2032)
			(end -0.4953 1.6002)
			(stroke
				(width 0.1)
				(type default)
			)
			(layer "B.Fab")
		)
		(fp_line
			(start 0.4953 1.6002)
			(end 0.4953 -0.2032)
			(stroke
				(width 0.1)
				(type default)
			)
			(layer "B.Fab")
		)
		(fp_line
			(start -0.4953 1.6002)
			(end 0.4953 1.6002)
			(stroke
				(width 0.1)
				(type default)
			)
			(layer "B.Fab")
		)
		(pad "1" smd rect
			(at 0 0 270)
			(size 0.762 0.889)
			(layers "B.Cu" "B.Mask" "B.Paste")
			(net "PVDDQ_GHJ")
		)
		(pad "2" smd rect
			(at 0 1.397 270)
			(size 0.762 0.889)
			(layers "B.Cu" "B.Mask" "B.Paste")
			(net "GND")
		)
		(zone
			(layer "B.Cu")
			(hatch none 0.5)
			(connect_pads
				(clearance 0)
			)
			(min_thickness 0.25)
			(keepout
				(tracks not_allowed)
				(vias allowed)
				(pads allowed)
				(copperpour not_allowed)
				(footprints allowed)
			)
			(placement
				(enabled no)
				(sheetname "")
			)
			(fill
				(thermal_gap 0.5)
				(thermal_bridge_width 0.5)
				(island_removal_mode 0)
			)
			(polygon
				(pts
					(xy 108.3056 -2.9718) (xy 108.8136 -2.9718) (xy 108.8136 -3.7338) (xy 108.3056 -3.7338)
				)
			)
		)
	)
	(footprint ""
		(layer "B.Cu")
		(at 403.01418 -117.6655 180)
		(property "Reference" "C2M25"
			(at 0 0 0)
			(layer "B.SilkS")
			(hide yes)
			(effects
				(font
					(size 1.27 1.27)
				)
				(justify mirror)
			)
		)
		(property "Value" ""
			(at 0 0 0)
			(layer "B.Fab")
			(effects
				(font
					(size 1.27 1.27)
				)
				(justify mirror)
			)
		)
		(duplicate_pad_numbers_are_jumpers no)
		(fp_poly
			(pts
				(xy -0.3048 -0.1016) (xy -0.3048 0.9906) (xy 0.3048 0.9906) (xy 0.3048 -0.1016)
			)
			(stroke
				(width 0)
				(type default)
			)
			(fill no)
			(layer "B.CrtYd")
		)
		(fp_line
			(start 0.3048 0.9906)
			(end -0.3048 0.9906)
			(stroke
				(width 0.1)
				(type default)
			)
			(layer "B.Fab")
		)
		(fp_line
			(start 0.3048 -0.1016)
			(end 0.3048 0.9906)
			(stroke
				(width 0.1)
				(type default)
			)
			(layer "B.Fab")
		)
		(fp_line
			(start -0.3048 0.9906)
			(end -0.3048 -0.1016)
			(stroke
				(width 0.1)
				(type default)
			)
			(layer "B.Fab")
		)
		(fp_line
			(start -0.3048 -0.1016)
			(end 0.3048 -0.1016)
			(stroke
				(width 0.1)
				(type default)
			)
			(layer "B.Fab")
		)
		(pad "1" smd rect
			(at 0 0)
			(size 0.508 0.508)
			(layers "B.Cu" "B.Mask" "B.Paste")
			(net "P1V05_PCH_STBY")
		)
		(pad "2" smd rect
			(at 0 0.889)
			(size 0.508 0.508)
			(layers "B.Cu" "B.Mask" "B.Paste")
			(net "GND")
		)
		(zone
			(layer "B.Cu")
			(hatch none 0.5)
			(connect_pads
				(clearance 0)
			)
			(min_thickness 0.25)
			(keepout
				(tracks not_allowed)
				(vias allowed)
				(pads allowed)
				(copperpour not_allowed)
				(footprints allowed)
			)
			(placement
				(enabled no)
				(sheetname "")
			)
			(fill
				(thermal_gap 0.5)
				(thermal_bridge_width 0.5)
				(island_removal_mode 0)
			)
			(polygon
				(pts
					(xy 402.76018 -118.3005) (xy 403.26818 -118.3005) (xy 403.26818 -117.9195) (xy 402.76018 -117.9195)
				)
			)
		)
		(zone
			(layer "B.Cu")
			(hatch none 0.5)
			(connect_pads
				(clearance 0)
			)
			(min_thickness 0.25)
			(keepout
				(tracks allowed)
				(vias not_allowed)
				(pads allowed)
				(copperpour not_allowed)
				(footprints allowed)
			)
			(placement
				(enabled no)
				(sheetname "")
			)
			(fill
				(thermal_gap 0.5)
				(thermal_bridge_width 0.5)
				(island_removal_mode 0)
			)
			(polygon
				(pts
					(xy 402.76018 -117.9195) (xy 403.26818 -117.9195) (xy 403.26818 -118.3005) (xy 402.76018 -118.3005)
				)
			)
		)
	)
	(footprint ""
		(layer "B.Cu")
		(at 455.200258 -31.237174 -90)
		(property "Reference" "R8D36"
			(at 0 0 90)
			(layer "B.SilkS")
			(hide yes)
			(effects
				(font
					(size 1.27 1.27)
				)
				(justify mirror)
			)
		)
		(property "Value" ""
			(at 0 0 90)
			(layer "B.Fab")
			(effects
				(font
					(size 1.27 1.27)
				)
				(justify mirror)
			)
		)
		(duplicate_pad_numbers_are_jumpers no)
		(fp_poly
			(pts
				(xy 0.2794 -0.1016) (xy -0.2794 -0.1016) (xy -0.2794 0.9906) (xy 0.2794 0.9906)
			)
			(stroke
				(width 0)
				(type default)
			)
			(fill no)
			(layer "B.CrtYd")
		)
		(fp_line
			(start -0.2794 0.9906)
			(end -0.2794 -0.1016)
			(stroke
				(width 0.1)
				(type default)
			)
			(layer "B.Fab")
		)
		(fp_line
			(start 0.2794 0.9906)
			(end -0.2794 0.9906)
			(stroke
				(width 0.1)
				(type default)
			)
			(layer "B.Fab")
		)
		(fp_line
			(start -0.2794 -0.1016)
			(end 0.2794 -0.1016)
			(stroke
				(width 0.1)
				(type default)
			)
			(layer "B.Fab")
		)
		(fp_line
			(start 0.2794 -0.1016)
			(end 0.2794 0.9906)
			(stroke
				(width 0.1)
				(type default)
			)
			(layer "B.Fab")
		)
		(pad "1" smd rect
			(at 0 0 90)
			(size 0.508 0.508)
			(layers "B.Cu" "B.Mask" "B.Paste")
			(net "RST_BMC_SRST_R2_N")
		)
		(pad "2" smd rect
			(at 0 0.889 90)
			(size 0.508 0.508)
			(layers "B.Cu" "B.Mask" "B.Paste")
			(net "RST_BMC_DDR3_BUF_IN_N")
		)
		(zone
			(layer "B.Cu")
			(hatch none 0.5)
			(connect_pads
				(clearance 0)
			)
			(min_thickness 0.25)
			(keepout
				(tracks not_allowed)
				(vias allowed)
				(pads allowed)
				(copperpour not_allowed)
				(footprints allowed)
			)
			(placement
				(enabled no)
				(sheetname "")
			)
			(fill
				(thermal_gap 0.5)
				(thermal_bridge_width 0.5)
				(island_removal_mode 0)
			)
			(polygon
				(pts
					(xy 454.565258 -30.983174) (xy 454.565258 -31.491174) (xy 454.946258 -31.491174) (xy 454.946258 -30.983174)
				)
			)
		)
		(zone
			(layer "B.Cu")
			(hatch none 0.5)
			(connect_pads
				(clearance 0)
			)
			(min_thickness 0.25)
			(keepout
				(tracks allowed)
				(vias not_allowed)
				(pads allowed)
				(copperpour not_allowed)
				(footprints allowed)
			)
			(placement
				(enabled no)
				(sheetname "")
			)
			(fill
				(thermal_gap 0.5)
				(thermal_bridge_width 0.5)
				(island_removal_mode 0)
			)
			(polygon
				(pts
					(xy 454.946258 -30.983174) (xy 454.946258 -31.491174) (xy 454.565258 -31.491174) (xy 454.565258 -30.983174)
				)
			)
		)
	)
	(footprint ""
		(layer "B.Cu")
		(at 416.889184 -75.296014 180)
		(property "Reference" "U1R2"
			(at -0.35433 2.159 270)
			(unlocked yes)
			(layer "B.SilkS")
			(effects
				(font
					(size 0.7874 0.5842)
					(thickness 0.1524)
				)
				(justify left mirror)
			)
		)
		(property "Value" ""
			(at 0 0 0)
			(layer "B.Fab")
			(effects
				(font
					(size 1.27 1.27)
				)
				(justify mirror)
			)
		)
		(duplicate_pad_numbers_are_jumpers no)
		(fp_circle
			(center 0.4699 -0.8382)
			(end 0.3429 -0.8382)
			(stroke
				(width 0.254)
				(type default)
			)
			(fill no)
			(layer "B.SilkS")
		)
		(fp_poly
			(pts
				(xy -0.21463 -0.450088) (xy -1.56337 -0.450088) (xy -1.56337 1.75006) (xy -0.21463 1.75006)
			)
			(stroke
				(width 0)
				(type default)
			)
			(fill no)
			(layer "B.CrtYd")
		)
		(fp_line
			(start -0.21463 1.75006)
			(end -0.21463 -0.450088)
			(stroke
				(width 0.1)
				(type default)
			)
			(layer "B.Fab")
		)
		(fp_line
			(start -0.21463 -0.450088)
			(end -1.56337 -0.450088)
			(stroke
				(width 0.1)
				(type default)
			)
			(layer "B.Fab")
		)
		(fp_line
			(start -1.56337 1.75006)
			(end -0.21463 1.75006)
			(stroke
				(width 0.1)
				(type default)
			)
			(layer "B.Fab")
		)
		(fp_line
			(start -1.56337 -0.450088)
			(end -1.56337 1.75006)
			(stroke
				(width 0.1)
				(type default)
			)
			(layer "B.Fab")
		)
		(fp_circle
			(center 0.4699 -0.8382)
			(end 0.3429 -0.8382)
			(stroke
				(width 0.254)
				(type default)
			)
			(fill no)
			(layer "B.Fab")
		)
		(pad "1" smd rect
			(at 0 0)
			(size 1.016 0.381)
			(layers "B.Cu" "B.Mask" "B.Paste")
			(net "FM_FAST_PROCHOT_EN")
		)
		(pad "2" smd rect
			(at 0 0.649986)
			(size 1.016 0.381)
			(layers "B.Cu" "B.Mask" "B.Paste")
			(net "FM_FAST_PROCHOT_THROTTLE_DLY_N")
		)
		(pad "3" smd rect
			(at 0 1.299972)
			(size 1.016 0.381)
			(layers "B.Cu" "B.Mask" "B.Paste")
			(net "GND")
		)
		(pad "4" smd rect
			(at -1.778 1.299972)
			(size 1.016 0.381)
			(layers "B.Cu" "B.Mask" "B.Paste")
			(net "FM_FAST_PROCHOT_THROTTLE_DLY_BU")
		)
		(pad "5" smd rect
			(at -1.778 0)
			(size 1.016 0.381)
			(layers "B.Cu" "B.Mask" "B.Paste")
			(net "P3V3_STBY")
		)
	)
	(footprint ""
		(layer "B.Cu")
		(at 382.5875 -54.8005)
		(property "Reference" "U8F1"
			(at -1.43002 5.67563 0)
			(unlocked yes)
			(layer "B.SilkS")
			(effects
				(font
					(size 0.7874 0.5842)
					(thickness 0.1524)
				)
				(justify left mirror)
			)
		)
		(property "Value" ""
			(at 0 0 0)
			(layer "B.Fab")
			(effects
				(font
					(size 1.27 1.27)
				)
				(justify mirror)
			)
		)
		(duplicate_pad_numbers_are_jumpers no)
		(fp_line
			(start -3.9243 -0.2794)
			(end -3.9243 4.7244)
			(stroke
				(width 0.1524)
				(type default)
			)
			(layer "B.SilkS")
		)
		(fp_line
			(start -3.9243 4.7244)
			(end -1.5367 4.7244)
			(stroke
				(width 0.1524)
				(type default)
			)
			(layer "B.SilkS")
		)
		(fp_line
			(start -3.1242 -0.2794)
			(end -3.1242 0.7366)
			(stroke
				(width 0.1524)
				(type default)
			)
			(layer "B.SilkS")
		)
		(fp_line
			(start -3.1242 0.7366)
			(end -2.3622 0.7366)
			(stroke
				(width 0.1524)
				(type default)
			)
			(layer "B.SilkS")
		)
		(fp_line
			(start -2.3622 -0.2794)
			(end -3.1242 -0.2794)
			(stroke
				(width 0.1524)
				(type default)
			)
			(layer "B.SilkS")
		)
		(fp_line
			(start -2.3622 0.7366)
			(end -2.3622 -0.2794)
			(stroke
				(width 0.1524)
				(type default)
			)
			(layer "B.SilkS")
		)
		(fp_line
			(start -1.5367 -0.2794)
			(end -3.9243 -0.2794)
			(stroke
				(width 0.1524)
				(type default)
			)
			(layer "B.SilkS")
		)
		(fp_line
			(start -1.5367 4.7244)
			(end -1.5367 -0.2794)
			(stroke
				(width 0.1524)
				(type default)
			)
			(layer "B.SilkS")
		)
		(fp_circle
			(center 1.5494 -0.6604)
			(end 1.7399 -0.6604)
			(stroke
				(width 0.381)
				(type default)
			)
			(fill no)
			(layer "B.SilkS")
		)
		(fp_poly
			(pts
				(xy -0.7366 -0.2794) (xy -4.7244 -0.2794) (xy -4.7244 4.7244) (xy -0.7366 4.7244)
			)
			(stroke
				(width 0)
				(type default)
			)
			(fill no)
			(layer "B.CrtYd")
		)
		(fp_line
			(start -4.7244 -0.2794)
			(end -4.7244 4.7244)
			(stroke
				(width 0.1)
				(type default)
			)
			(layer "B.Fab")
		)
		(fp_line
			(start -4.7244 4.7244)
			(end -0.7366 4.7244)
			(stroke
				(width 0.1)
				(type default)
			)
			(layer "B.Fab")
		)
		(fp_line
			(start -0.7366 -0.2794)
			(end -4.7244 -0.2794)
			(stroke
				(width 0.1)
				(type default)
			)
			(layer "B.Fab")
		)
		(fp_line
			(start -0.7366 4.7244)
			(end -0.7366 -0.2794)
			(stroke
				(width 0.1)
				(type default)
			)
			(layer "B.Fab")
		)
		(fp_circle
			(center 1.5494 -0.6604)
			(end 1.7399 -0.6604)
			(stroke
				(width 0.381)
				(type default)
			)
			(fill no)
			(layer "B.Fab")
		)
		(pad "1" smd rect
			(at 0 0 180)
			(size 2.159 0.381)
			(layers "B.Cu" "B.Mask" "B.Paste")
			(net "FM_BIOS_SPI_BMC_CTRL")
		)
		(pad "2" smd rect
			(at 0 0.635 180)
			(size 2.159 0.381)
			(layers "B.Cu" "B.Mask" "B.Paste")
			(net "SPI_PCH_CLK")
		)
		(pad "3" smd rect
			(at 0 1.27 180)
			(size 2.159 0.381)
			(layers "B.Cu" "B.Mask" "B.Paste")
			(net "SPI_BMC_CLK")
		)
		(pad "4" smd rect
			(at 0 1.905 180)
			(size 2.159 0.381)
			(layers "B.Cu" "B.Mask" "B.Paste")
			(net "SPI_SWITCH_CLK")
		)
		(pad "5" smd rect
			(at 0 2.54 180)
			(size 2.159 0.381)
			(layers "B.Cu" "B.Mask" "B.Paste")
			(net "SPI_PCH_MOSI")
		)
		(pad "6" smd rect
			(at 0 3.175 180)
			(size 2.159 0.381)
			(layers "B.Cu" "B.Mask" "B.Paste")
			(net "SPI_BMC_DO")
		)
		(pad "7" smd rect
			(at 0 3.81 180)
			(size 2.159 0.381)
			(layers "B.Cu" "B.Mask" "B.Paste")
			(net "SPI_SWITCH_MOSI")
		)
		(pad "8" smd rect
			(at 0 4.445 180)
			(size 2.159 0.381)
			(layers "B.Cu" "B.Mask" "B.Paste")
			(net "GND")
		)
		(pad "9" smd rect
			(at -5.461 4.445 180)
			(size 2.159 0.381)
			(layers "B.Cu" "B.Mask" "B.Paste")
			(net "SPI_SWITCH_CS0_N")
		)
		(pad "10" smd rect
			(at -5.461 3.81 180)
			(size 2.159 0.381)
			(layers "B.Cu" "B.Mask" "B.Paste")
			(net "SPI_BMC_CS0_N")
		)
		(pad "11" smd rect
			(at -5.461 3.175 180)
			(size 2.159 0.381)
			(layers "B.Cu" "B.Mask" "B.Paste")
			(net "SPI_PCH_CS0_N")
		)
		(pad "12" smd rect
			(at -5.461 2.54 180)
			(size 2.159 0.381)
			(layers "B.Cu" "B.Mask" "B.Paste")
			(net "SPI_SWITCH_MISO")
		)
		(pad "13" smd rect
			(at -5.461 1.905 180)
			(size 2.159 0.381)
			(layers "B.Cu" "B.Mask" "B.Paste")
			(net "SPI_BMC_DI")
		)
		(pad "14" smd rect
			(at -5.461 1.27 180)
			(size 2.159 0.381)
			(layers "B.Cu" "B.Mask" "B.Paste")
			(net "SPI_PCH_MISO_R")
		)
		(pad "15" smd rect
			(at -5.461 0.635 180)
			(size 2.159 0.381)
			(layers "B.Cu" "B.Mask" "B.Paste")
			(net "GND")
		)
		(pad "16" smd rect
			(at -5.461 0 180)
			(size 2.159 0.381)
			(layers "B.Cu" "B.Mask" "B.Paste")
			(net "P3V3_STBY")
		)
	)
	(footprint ""
		(layer "B.Cu")
		(at 111.809276 -84.401914)
		(property "Reference" "C8W4"
			(at -1.47828 0.78994 90)
			(unlocked yes)
			(layer "B.SilkS")
			(effects
				(font
					(size 0.4064 0.254)
					(thickness 0.1524)
				)
				(justify mirror)
			)
		)
		(property "Value" ""
			(at 0 0 0)
			(layer "B.Fab")
			(effects
				(font
					(size 1.27 1.27)
				)
				(justify mirror)
			)
		)
		(duplicate_pad_numbers_are_jumpers no)
		(fp_poly
			(pts
				(xy 0.7239 -0.2159) (xy -0.7239 -0.2159) (xy -0.7239 1.9939) (xy 0.7239 1.9939)
			)
			(stroke
				(width 0)
				(type default)
			)
			(fill no)
			(layer "B.CrtYd")
		)
		(fp_line
			(start -0.7239 -0.2159)
			(end 0.7239 -0.2159)
			(stroke
				(width 0.1)
				(type default)
			)
			(layer "B.Fab")
		)
		(fp_line
			(start -0.7239 1.9939)
			(end -0.7239 -0.2159)
			(stroke
				(width 0.1)
				(type default)
			)
			(layer "B.Fab")
		)
		(fp_line
			(start 0.7239 -0.2159)
			(end 0.7239 1.9939)
			(stroke
				(width 0.1)
				(type default)
			)
			(layer "B.Fab")
		)
		(fp_line
			(start 0.7239 1.9939)
			(end -0.7239 1.9939)
			(stroke
				(width 0.1)
				(type default)
			)
			(layer "B.Fab")
		)
		(pad "1" smd rect
			(at 0 0 180)
			(size 1.27 1.016)
			(layers "B.Cu" "B.Mask" "B.Paste")
			(net "PVCCIN_CPU1")
		)
		(pad "2" smd rect
			(at 0 1.778 180)
			(size 1.27 1.016)
			(layers "B.Cu" "B.Mask" "B.Paste")
			(net "GND")
		)
		(zone
			(layer "B.Cu")
			(hatch none 0.5)
			(connect_pads
				(clearance 0)
			)
			(min_thickness 0.25)
			(keepout
				(tracks not_allowed)
				(vias allowed)
				(pads allowed)
				(copperpour not_allowed)
				(footprints allowed)
			)
			(placement
				(enabled no)
				(sheetname "")
			)
			(fill
				(thermal_gap 0.5)
				(thermal_bridge_width 0.5)
				(island_removal_mode 0)
			)
			(polygon
				(pts
					(xy 112.444276 -83.893914) (xy 111.174276 -83.893914) (xy 111.174276 -83.131914) (xy 112.444276 -83.131914)
				)
			)
		)
	)
	(footprint ""
		(layer "B.Cu")
		(at 384.0734 -156.569664 -90)
		(property "Reference" "R3L14"
			(at 0 0 90)
			(layer "B.SilkS")
			(hide yes)
			(effects
				(font
					(size 1.27 1.27)
				)
				(justify mirror)
			)
		)
		(property "Value" ""
			(at 0 0 90)
			(layer "B.Fab")
			(effects
				(font
					(size 1.27 1.27)
				)
				(justify mirror)
			)
		)
		(duplicate_pad_numbers_are_jumpers no)
		(fp_poly
			(pts
				(xy 0.2794 -0.1016) (xy -0.2794 -0.1016) (xy -0.2794 0.9906) (xy 0.2794 0.9906)
			)
			(stroke
				(width 0)
				(type default)
			)
			(fill no)
			(layer "B.CrtYd")
		)
		(fp_line
			(start -0.2794 0.9906)
			(end -0.2794 -0.1016)
			(stroke
				(width 0.1)
				(type default)
			)
			(layer "B.Fab")
		)
		(fp_line
			(start 0.2794 0.9906)
			(end -0.2794 0.9906)
			(stroke
				(width 0.1)
				(type default)
			)
			(layer "B.Fab")
		)
		(fp_line
			(start -0.2794 -0.1016)
			(end 0.2794 -0.1016)
			(stroke
				(width 0.1)
				(type default)
			)
			(layer "B.Fab")
		)
		(fp_line
			(start 0.2794 -0.1016)
			(end 0.2794 0.9906)
			(stroke
				(width 0.1)
				(type default)
			)
			(layer "B.Fab")
		)
		(pad "1" smd rect
			(at 0 0 90)
			(size 0.508 0.508)
			(layers "B.Cu" "B.Mask" "B.Paste")
			(net "VR_P1V05_PCH_STBY_OCSET")
		)
		(pad "2" smd rect
			(at 0 0.889 90)
			(size 0.508 0.508)
			(layers "B.Cu" "B.Mask" "B.Paste")
			(net "GND")
		)
		(zone
			(layer "B.Cu")
			(hatch none 0.5)
			(connect_pads
				(clearance 0)
			)
			(min_thickness 0.25)
			(keepout
				(tracks not_allowed)
				(vias allowed)
				(pads allowed)
				(copperpour not_allowed)
				(footprints allowed)
			)
			(placement
				(enabled no)
				(sheetname "")
			)
			(fill
				(thermal_gap 0.5)
				(thermal_bridge_width 0.5)
				(island_removal_mode 0)
			)
			(polygon
				(pts
					(xy 383.4384 -156.315664) (xy 383.4384 -156.823664) (xy 383.8194 -156.823664) (xy 383.8194 -156.315664)
				)
			)
		)
		(zone
			(layer "B.Cu")
			(hatch none 0.5)
			(connect_pads
				(clearance 0)
			)
			(min_thickness 0.25)
			(keepout
				(tracks allowed)
				(vias not_allowed)
				(pads allowed)
				(copperpour not_allowed)
				(footprints allowed)
			)
			(placement
				(enabled no)
				(sheetname "")
			)
			(fill
				(thermal_gap 0.5)
				(thermal_bridge_width 0.5)
				(island_removal_mode 0)
			)
			(polygon
				(pts
					(xy 383.8194 -156.315664) (xy 383.8194 -156.823664) (xy 383.4384 -156.823664) (xy 383.4384 -156.315664)
				)
			)
		)
	)
	(footprint ""
		(layer "B.Cu")
		(at 482.131116 -144.771872 -90)
		(property "Reference" "R6W5"
			(at 0.8382 -0.67818 270)
			(unlocked yes)
			(layer "B.SilkS")
			(effects
				(font
					(size 0.4064 0.254)
					(thickness 0.1524)
				)
				(justify left mirror)
			)
		)
		(property "Value" ""
			(at 0 0 90)
			(layer "B.Fab")
			(effects
				(font
					(size 1.27 1.27)
				)
				(justify mirror)
			)
		)
		(duplicate_pad_numbers_are_jumpers no)
		(fp_poly
			(pts
				(xy 0.2794 -0.1016) (xy -0.2794 -0.1016) (xy -0.2794 0.9906) (xy 0.2794 0.9906)
			)
			(stroke
				(width 0)
				(type default)
			)
			(fill no)
			(layer "B.CrtYd")
		)
		(fp_line
			(start -0.2794 0.9906)
			(end -0.2794 -0.1016)
			(stroke
				(width 0.1)
				(type default)
			)
			(layer "B.Fab")
		)
		(fp_line
			(start 0.2794 0.9906)
			(end -0.2794 0.9906)
			(stroke
				(width 0.1)
				(type default)
			)
			(layer "B.Fab")
		)
		(fp_line
			(start -0.2794 -0.1016)
			(end 0.2794 -0.1016)
			(stroke
				(width 0.1)
				(type default)
			)
			(layer "B.Fab")
		)
		(fp_line
			(start 0.2794 -0.1016)
			(end 0.2794 0.9906)
			(stroke
				(width 0.1)
				(type default)
			)
			(layer "B.Fab")
		)
		(pad "1" smd rect
			(at 0 0 90)
			(size 0.508 0.508)
			(layers "B.Cu" "B.Mask" "B.Paste")
			(net "P3V3_STBY")
		)
		(pad "2" smd rect
			(at 0 0.889 90)
			(size 0.508 0.508)
			(layers "B.Cu" "B.Mask" "B.Paste")
			(net "PCA9555_A1")
		)
		(zone
			(layer "B.Cu")
			(hatch none 0.5)
			(connect_pads
				(clearance 0)
			)
			(min_thickness 0.25)
			(keepout
				(tracks not_allowed)
				(vias allowed)
				(pads allowed)
				(copperpour not_allowed)
				(footprints allowed)
			)
			(placement
				(enabled no)
				(sheetname "")
			)
			(fill
				(thermal_gap 0.5)
				(thermal_bridge_width 0.5)
				(island_removal_mode 0)
			)
			(polygon
				(pts
					(xy 481.496116 -144.517872) (xy 481.496116 -145.025872) (xy 481.877116 -145.025872) (xy 481.877116 -144.517872)
				)
			)
		)
		(zone
			(layer "B.Cu")
			(hatch none 0.5)
			(connect_pads
				(clearance 0)
			)
			(min_thickness 0.25)
			(keepout
				(tracks allowed)
				(vias not_allowed)
				(pads allowed)
				(copperpour not_allowed)
				(footprints allowed)
			)
			(placement
				(enabled no)
				(sheetname "")
			)
			(fill
				(thermal_gap 0.5)
				(thermal_bridge_width 0.5)
				(island_removal_mode 0)
			)
			(polygon
				(pts
					(xy 481.877116 -144.517872) (xy 481.877116 -145.025872) (xy 481.496116 -145.025872) (xy 481.496116 -144.517872)
				)
			)
		)
	)
	(footprint ""
		(layer "B.Cu")
		(at -0.127 -132.334)
		(property "Reference" "R9M5"
			(at 0 0 0)
			(layer "B.SilkS")
			(hide yes)
			(effects
				(font
					(size 1.27 1.27)
				)
				(justify mirror)
			)
		)
		(property "Value" ""
			(at 0 0 0)
			(layer "B.Fab")
			(effects
				(font
					(size 1.27 1.27)
				)
				(justify mirror)
			)
		)
		(duplicate_pad_numbers_are_jumpers no)
		(fp_poly
			(pts
				(xy 0.2794 -0.1016) (xy -0.2794 -0.1016) (xy -0.2794 0.9906) (xy 0.2794 0.9906)
			)
			(stroke
				(width 0)
				(type default)
			)
			(fill no)
			(layer "B.CrtYd")
		)
		(fp_line
			(start -0.2794 -0.1016)
			(end 0.2794 -0.1016)
			(stroke
				(width 0.1)
				(type default)
			)
			(layer "B.Fab")
		)
		(fp_line
			(start -0.2794 0.9906)
			(end -0.2794 -0.1016)
			(stroke
				(width 0.1)
				(type default)
			)
			(layer "B.Fab")
		)
		(fp_line
			(start 0.2794 -0.1016)
			(end 0.2794 0.9906)
			(stroke
				(width 0.1)
				(type default)
			)
			(layer "B.Fab")
		)
		(fp_line
			(start 0.2794 0.9906)
			(end -0.2794 0.9906)
			(stroke
				(width 0.1)
				(type default)
			)
			(layer "B.Fab")
		)
		(pad "1" smd rect
			(at 0 0 180)
			(size 0.508 0.508)
			(layers "B.Cu" "B.Mask" "B.Paste")
			(net "P3V3_STBY")
		)
		(pad "2" smd rect
			(at 0 0.889 180)
			(size 0.508 0.508)
			(layers "B.Cu" "B.Mask" "B.Paste")
			(net "VR_PVDDQ_KLM_VREN")
		)
		(zone
			(layer "B.Cu")
			(hatch none 0.5)
			(connect_pads
				(clearance 0)
			)
			(min_thickness 0.25)
			(keepout
				(tracks allowed)
				(vias not_allowed)
				(pads allowed)
				(copperpour not_allowed)
				(footprints allowed)
			)
			(placement
				(enabled no)
				(sheetname "")
			)
			(fill
				(thermal_gap 0.5)
				(thermal_bridge_width 0.5)
				(island_removal_mode 0)
			)
			(polygon
				(pts
					(xy 0.127 -132.08) (xy -0.381 -132.08) (xy -0.381 -131.699) (xy 0.127 -131.699)
				)
			)
		)
		(zone
			(layer "B.Cu")
			(hatch none 0.5)
			(connect_pads
				(clearance 0)
			)
			(min_thickness 0.25)
			(keepout
				(tracks not_allowed)
				(vias allowed)
				(pads allowed)
				(copperpour not_allowed)
				(footprints allowed)
			)
			(placement
				(enabled no)
				(sheetname "")
			)
			(fill
				(thermal_gap 0.5)
				(thermal_bridge_width 0.5)
				(island_removal_mode 0)
			)
			(polygon
				(pts
					(xy 0.127 -131.699) (xy -0.381 -131.699) (xy -0.381 -132.08) (xy 0.127 -132.08)
				)
			)
		)
	)
	(footprint ""
		(layer "B.Cu")
		(at -1.3335 -145.8214 90)
		(property "Reference" "CT10"
			(at 0.8382 -0.84963 90)
			(unlocked yes)
			(layer "B.SilkS")
			(effects
				(font
					(size 0.7874 0.5842)
					(thickness 0.1524)
				)
				(justify left mirror)
			)
		)
		(property "Value" ""
			(at 0 0 90)
			(layer "B.Fab")
			(effects
				(font
					(size 1.27 1.27)
				)
				(justify mirror)
			)
		)
		(duplicate_pad_numbers_are_jumpers no)
		(fp_poly
			(pts
				(xy -0.3048 -0.1016) (xy -0.3048 0.9906) (xy 0.3048 0.9906) (xy 0.3048 -0.1016)
			)
			(stroke
				(width 0)
				(type default)
			)
			(fill no)
			(layer "B.CrtYd")
		)
		(fp_line
			(start 0.3048 -0.1016)
			(end 0.3048 0.9906)
			(stroke
				(width 0.1)
				(type default)
			)
			(layer "B.Fab")
		)
		(fp_line
			(start -0.3048 -0.1016)
			(end 0.3048 -0.1016)
			(stroke
				(width 0.1)
				(type default)
			)
			(layer "B.Fab")
		)
		(fp_line
			(start 0.3048 0.9906)
			(end -0.3048 0.9906)
			(stroke
				(width 0.1)
				(type default)
			)
			(layer "B.Fab")
		)
		(fp_line
			(start -0.3048 0.9906)
			(end -0.3048 -0.1016)
			(stroke
				(width 0.1)
				(type default)
			)
			(layer "B.Fab")
		)
		(pad "1" smd rect
			(at 0 0 270)
			(size 0.508 0.508)
			(layers "B.Cu" "B.Mask" "B.Paste")
			(net "A_TSENSE_PVDDQ_KLM")
		)
		(pad "2" smd rect
			(at 0 0.889 270)
			(size 0.508 0.508)
			(layers "B.Cu" "B.Mask" "B.Paste")
			(net "GND")
		)
		(zone
			(layer "B.Cu")
			(hatch none 0.5)
			(connect_pads
				(clearance 0)
			)
			(min_thickness 0.25)
			(keepout
				(tracks allowed)
				(vias not_allowed)
				(pads allowed)
				(copperpour not_allowed)
				(footprints allowed)
			)
			(placement
				(enabled no)
				(sheetname "")
			)
			(fill
				(thermal_gap 0.5)
				(thermal_bridge_width 0.5)
				(island_removal_mode 0)
			)
			(polygon
				(pts
					(xy -1.0795 -146.0754) (xy -1.0795 -145.5674) (xy -0.6985 -145.5674) (xy -0.6985 -146.0754)
				)
			)
		)
		(zone
			(layer "B.Cu")
			(hatch none 0.5)
			(connect_pads
				(clearance 0)
			)
			(min_thickness 0.25)
			(keepout
				(tracks not_allowed)
				(vias allowed)
				(pads allowed)
				(copperpour not_allowed)
				(footprints allowed)
			)
			(placement
				(enabled no)
				(sheetname "")
			)
			(fill
				(thermal_gap 0.5)
				(thermal_bridge_width 0.5)
				(island_removal_mode 0)
			)
			(polygon
				(pts
					(xy -0.6985 -146.0754) (xy -0.6985 -145.5674) (xy -1.0795 -145.5674) (xy -1.0795 -146.0754)
				)
			)
		)
	)
	(footprint ""
		(layer "B.Cu")
		(at 382.397 -2.448814)
		(property "Reference" "C8W6"
			(at 0.8382 -0.67818 0)
			(unlocked yes)
			(layer "B.SilkS")
			(effects
				(font
					(size 0.4064 0.254)
					(thickness 0.1524)
				)
				(justify left mirror)
			)
		)
		(property "Value" ""
			(at 0 0 0)
			(layer "B.Fab")
			(effects
				(font
					(size 1.27 1.27)
				)
				(justify mirror)
			)
		)
		(duplicate_pad_numbers_are_jumpers no)
		(fp_poly
			(pts
				(xy -0.3048 -0.1016) (xy -0.3048 0.9906) (xy 0.3048 0.9906) (xy 0.3048 -0.1016)
			)
			(stroke
				(width 0)
				(type default)
			)
			(fill no)
			(layer "B.CrtYd")
		)
		(fp_line
			(start -0.3048 -0.1016)
			(end 0.3048 -0.1016)
			(stroke
				(width 0.1)
				(type default)
			)
			(layer "B.Fab")
		)
		(fp_line
			(start -0.3048 0.9906)
			(end -0.3048 -0.1016)
			(stroke
				(width 0.1)
				(type default)
			)
			(layer "B.Fab")
		)
		(fp_line
			(start 0.3048 -0.1016)
			(end 0.3048 0.9906)
			(stroke
				(width 0.1)
				(type default)
			)
			(layer "B.Fab")
		)
		(fp_line
			(start 0.3048 0.9906)
			(end -0.3048 0.9906)
			(stroke
				(width 0.1)
				(type default)
			)
			(layer "B.Fab")
		)
		(pad "1" smd rect
			(at 0 0 180)
			(size 0.508 0.508)
			(layers "B.Cu" "B.Mask" "B.Paste")
			(net "P3V3_STBY")
		)
		(pad "2" smd rect
			(at 0 0.889 180)
			(size 0.508 0.508)
			(layers "B.Cu" "B.Mask" "B.Paste")
			(net "GND")
		)
		(zone
			(layer "B.Cu")
			(hatch none 0.5)
			(connect_pads
				(clearance 0)
			)
			(min_thickness 0.25)
			(keepout
				(tracks allowed)
				(vias not_allowed)
				(pads allowed)
				(copperpour not_allowed)
				(footprints allowed)
			)
			(placement
				(enabled no)
				(sheetname "")
			)
			(fill
				(thermal_gap 0.5)
				(thermal_bridge_width 0.5)
				(island_removal_mode 0)
			)
			(polygon
				(pts
					(xy 382.651 -2.194814) (xy 382.143 -2.194814) (xy 382.143 -1.813814) (xy 382.651 -1.813814)
				)
			)
		)
		(zone
			(layer "B.Cu")
			(hatch none 0.5)
			(connect_pads
				(clearance 0)
			)
			(min_thickness 0.25)
			(keepout
				(tracks not_allowed)
				(vias allowed)
				(pads allowed)
				(copperpour not_allowed)
				(footprints allowed)
			)
			(placement
				(enabled no)
				(sheetname "")
			)
			(fill
				(thermal_gap 0.5)
				(thermal_bridge_width 0.5)
				(island_removal_mode 0)
			)
			(polygon
				(pts
					(xy 382.651 -1.813814) (xy 382.143 -1.813814) (xy 382.143 -2.194814) (xy 382.651 -2.194814)
				)
			)
		)
	)
	(footprint ""
		(layer "B.Cu")
		(at 370.156994 -93.915992 -90)
		(property "Reference" "R3P7"
			(at 0 0 90)
			(layer "B.SilkS")
			(hide yes)
			(effects
				(font
					(size 1.27 1.27)
				)
				(justify mirror)
			)
		)
		(property "Value" ""
			(at 0 0 90)
			(layer "B.Fab")
			(effects
				(font
					(size 1.27 1.27)
				)
				(justify mirror)
			)
		)
		(duplicate_pad_numbers_are_jumpers no)
		(fp_poly
			(pts
				(xy 0.2794 -0.1016) (xy -0.2794 -0.1016) (xy -0.2794 0.9906) (xy 0.2794 0.9906)
			)
			(stroke
				(width 0)
				(type default)
			)
			(fill no)
			(layer "B.CrtYd")
		)
		(fp_line
			(start -0.2794 0.9906)
			(end -0.2794 -0.1016)
			(stroke
				(width 0.1)
				(type default)
			)
			(layer "B.Fab")
		)
		(fp_line
			(start 0.2794 0.9906)
			(end -0.2794 0.9906)
			(stroke
				(width 0.1)
				(type default)
			)
			(layer "B.Fab")
		)
		(fp_line
			(start -0.2794 -0.1016)
			(end 0.2794 -0.1016)
			(stroke
				(width 0.1)
				(type default)
			)
			(layer "B.Fab")
		)
		(fp_line
			(start 0.2794 -0.1016)
			(end 0.2794 0.9906)
			(stroke
				(width 0.1)
				(type default)
			)
			(layer "B.Fab")
		)
		(pad "1" smd rect
			(at 0 0 90)
			(size 0.508 0.508)
			(layers "B.Cu" "B.Mask" "B.Paste")
			(net "P1V05_PCH_STBY")
		)
		(pad "2" smd rect
			(at 0 0.889 90)
			(size 0.508 0.508)
			(layers "B.Cu" "B.Mask" "B.Paste")
			(net "FM_PRSNT_2_1_N")
		)
		(zone
			(layer "B.Cu")
			(hatch none 0.5)
			(connect_pads
				(clearance 0)
			)
			(min_thickness 0.25)
			(keepout
				(tracks not_allowed)
				(vias allowed)
				(pads allowed)
				(copperpour not_allowed)
				(footprints allowed)
			)
			(placement
				(enabled no)
				(sheetname "")
			)
			(fill
				(thermal_gap 0.5)
				(thermal_bridge_width 0.5)
				(island_removal_mode 0)
			)
			(polygon
				(pts
					(xy 369.521994 -93.661992) (xy 369.521994 -94.169992) (xy 369.902994 -94.169992) (xy 369.902994 -93.661992)
				)
			)
		)
		(zone
			(layer "B.Cu")
			(hatch none 0.5)
			(connect_pads
				(clearance 0)
			)
			(min_thickness 0.25)
			(keepout
				(tracks allowed)
				(vias not_allowed)
				(pads allowed)
				(copperpour not_allowed)
				(footprints allowed)
			)
			(placement
				(enabled no)
				(sheetname "")
			)
			(fill
				(thermal_gap 0.5)
				(thermal_bridge_width 0.5)
				(island_removal_mode 0)
			)
			(polygon
				(pts
					(xy 369.902994 -93.661992) (xy 369.902994 -94.169992) (xy 369.521994 -94.169992) (xy 369.521994 -93.661992)
				)
			)
		)
	)
	(footprint ""
		(layer "B.Cu")
		(at 445.5922 -155.8544 180)
		(property "Reference" "U25W18"
			(at 0.14986 2.621788 180)
			(unlocked yes)
			(layer "B.SilkS")
			(effects
				(font
					(size 1.27 0.964946)
					(thickness 0.000001)
				)
				(justify left mirror)
			)
		)
		(property "Value" ""
			(at 0 0 0)
			(layer "B.Fab")
			(effects
				(font
					(size 1.27 1.27)
				)
				(justify mirror)
			)
		)
		(duplicate_pad_numbers_are_jumpers no)
		(fp_circle
			(center 0.4699 -0.8382)
			(end 0.3429 -0.8382)
			(stroke
				(width 0.254)
				(type default)
			)
			(fill no)
			(layer "B.SilkS")
		)
		(fp_poly
			(pts
				(xy -0.21463 -0.450088) (xy -1.56337 -0.450088) (xy -1.56337 1.75006) (xy -0.21463 1.75006)
			)
			(stroke
				(width 0)
				(type default)
			)
			(fill no)
			(layer "B.CrtYd")
		)
		(fp_line
			(start -0.21463 1.75006)
			(end -0.21463 -0.450088)
			(stroke
				(width 0.1)
				(type default)
			)
			(layer "B.Fab")
		)
		(fp_line
			(start -0.21463 -0.450088)
			(end -1.56337 -0.450088)
			(stroke
				(width 0.1)
				(type default)
			)
			(layer "B.Fab")
		)
		(fp_line
			(start -1.56337 1.75006)
			(end -0.21463 1.75006)
			(stroke
				(width 0.1)
				(type default)
			)
			(layer "B.Fab")
		)
		(fp_line
			(start -1.56337 -0.450088)
			(end -1.56337 1.75006)
			(stroke
				(width 0.1)
				(type default)
			)
			(layer "B.Fab")
		)
		(fp_circle
			(center 0.4699 -0.8382)
			(end 0.3429 -0.8382)
			(stroke
				(width 0.254)
				(type default)
			)
			(fill no)
			(layer "B.Fab")
		)
		(pad "1" smd rect
			(at 0 0)
			(size 1.016 0.381)
			(layers "B.Cu" "B.Mask" "B.Paste")
			(net "XDP_PRESENT_N")
		)
		(pad "2" smd rect
			(at 0 0.649986)
			(size 1.016 0.381)
			(layers "B.Cu" "B.Mask" "B.Paste")
			(net "BMC_JTAG_SEL")
		)
		(pad "3" smd rect
			(at 0 1.299972)
			(size 1.016 0.381)
			(layers "B.Cu" "B.Mask" "B.Paste")
			(net "GND")
		)
		(pad "4" smd rect
			(at -1.778 1.299972)
			(size 1.016 0.381)
			(layers "B.Cu" "B.Mask" "B.Paste")
			(net "BMC_JTAG_SEL_BUF")
		)
		(pad "5" smd rect
			(at -1.778 0)
			(size 1.016 0.381)
			(layers "B.Cu" "B.Mask" "B.Paste")
			(net "P3V3_STBY")
		)
	)
	(footprint ""
		(layer "B.Cu")
		(at 441.7187 -64.9986 -90)
		(property "Reference" "C2P10"
			(at 0 0 90)
			(layer "B.SilkS")
			(hide yes)
			(effects
				(font
					(size 1.27 1.27)
				)
				(justify mirror)
			)
		)
		(property "Value" ""
			(at 0 0 90)
			(layer "B.Fab")
			(effects
				(font
					(size 1.27 1.27)
				)
				(justify mirror)
			)
		)
		(duplicate_pad_numbers_are_jumpers no)
		(fp_line
			(start -0.9017 1.953768)
			(end -0.9017 0.824484)
			(stroke
				(width 0.1524)
				(type default)
			)
			(layer "B.SilkS")
		)
		(fp_line
			(start 0.9017 1.953006)
			(end 0.9017 0.823976)
			(stroke
				(width 0.1524)
				(type default)
			)
			(layer "B.SilkS")
		)
		(fp_poly
			(pts
				(xy 0.9017 -0.3048) (xy -0.9017 -0.3048) (xy -0.9017 3.0988) (xy 0.9017 3.0988)
			)
			(stroke
				(width 0)
				(type default)
			)
			(fill no)
			(layer "B.CrtYd")
		)
		(fp_line
			(start -0.9017 3.0988)
			(end -0.9017 -0.3048)
			(stroke
				(width 0.1)
				(type default)
			)
			(layer "B.Fab")
		)
		(fp_line
			(start 0.9017 3.0988)
			(end -0.9017 3.0988)
			(stroke
				(width 0.1)
				(type default)
			)
			(layer "B.Fab")
		)
		(fp_line
			(start -0.9017 -0.3048)
			(end 0.9017 -0.3048)
			(stroke
				(width 0.1)
				(type default)
			)
			(layer "B.Fab")
		)
		(fp_line
			(start 0.9017 -0.3048)
			(end 0.9017 3.0988)
			(stroke
				(width 0.1)
				(type default)
			)
			(layer "B.Fab")
		)
		(pad "1" smd rect
			(at 0 0 90)
			(size 1.524 1.016)
			(layers "B.Cu" "B.Mask" "B.Paste")
			(net "P12V_STBY")
		)
		(pad "2" smd rect
			(at 0 2.794 90)
			(size 1.524 1.016)
			(layers "B.Cu" "B.Mask" "B.Paste")
			(net "GND")
		)
		(zone
			(layer "B.Cu")
			(hatch none 0.5)
			(connect_pads
				(clearance 0)
			)
			(min_thickness 0.25)
			(keepout
				(tracks allowed)
				(vias not_allowed)
				(pads allowed)
				(copperpour not_allowed)
				(footprints allowed)
			)
			(placement
				(enabled no)
				(sheetname "")
			)
			(fill
				(thermal_gap 0.5)
				(thermal_bridge_width 0.5)
				(island_removal_mode 0)
			)
			(polygon
				(pts
					(xy 441.2107 -65.7606) (xy 439.4327 -65.7606) (xy 439.4327 -64.2366) (xy 441.2107 -64.2366)
				)
			)
		)
	)
	(footprint ""
		(layer "B.Cu")
		(at 389.33755 -111.05515 180)
		(property "Reference" "C2N4"
			(at 0 0 0)
			(layer "B.SilkS")
			(hide yes)
			(effects
				(font
					(size 1.27 1.27)
				)
				(justify mirror)
			)
		)
		(property "Value" ""
			(at 0 0 0)
			(layer "B.Fab")
			(effects
				(font
					(size 1.27 1.27)
				)
				(justify mirror)
			)
		)
		(duplicate_pad_numbers_are_jumpers no)
		(fp_rect
			(start 0.2794 0.9144)
			(end -0.2794 -0.1143)
			(stroke
				(width 0)
				(type default)
			)
			(fill no)
			(layer "B.CrtYd")
		)
		(fp_line
			(start 0.2794 0.9144)
			(end 0.2794 -0.1143)
			(stroke
				(width 0.1)
				(type default)
			)
			(layer "B.Fab")
		)
		(fp_line
			(start 0.2794 -0.1143)
			(end -0.2794 -0.1143)
			(stroke
				(width 0.1)
				(type default)
			)
			(layer "B.Fab")
		)
		(fp_line
			(start -0.2794 0.9144)
			(end 0.2794 0.9144)
			(stroke
				(width 0.1)
				(type default)
			)
			(layer "B.Fab")
		)
		(fp_line
			(start -0.2794 -0.1143)
			(end -0.2794 0.9144)
			(stroke
				(width 0.1)
				(type default)
			)
			(layer "B.Fab")
		)
		(pad "1" smd custom
			(at 0 0 90)
			(size 0.10414 0.10414)
			(layers "B.Cu" "B.Mask" "B.Paste")
			(net "PVNN_PCH_STBY")
			(options
				(clearance outline)
				(anchor circle)
			)
			(primitives
				(gr_poly
					(pts
						(xy -0.20828 -0.08636) (xy -0.20828 0.08636) (xy -0.08636 0.20828) (xy 0.086614 0.20828) (xy 0.20828 0.086614)
						(xy 0.20828 -0.08636) (xy 0.08636 -0.20828) (xy -0.08636 -0.20828)
					)
					(width 0)
					(fill yes)
				)
			)
		)
		(pad "2" smd custom
			(at 0 0.8001 90)
			(size 0.10414 0.10414)
			(layers "B.Cu" "B.Mask" "B.Paste")
			(net "GND")
			(options
				(clearance outline)
				(anchor circle)
			)
			(primitives
				(gr_poly
					(pts
						(xy -0.20828 -0.08636) (xy -0.20828 0.08636) (xy -0.08636 0.20828) (xy 0.086614 0.20828) (xy 0.20828 0.086614)
						(xy 0.20828 -0.08636) (xy 0.08636 -0.20828) (xy -0.08636 -0.20828)
					)
					(width 0)
					(fill yes)
				)
			)
		)
		(zone
			(layer "B.Cu")
			(hatch none 0.5)
			(connect_pads
				(clearance 0)
			)
			(min_thickness 0.25)
			(keepout
				(tracks allowed)
				(vias not_allowed)
				(pads allowed)
				(copperpour not_allowed)
				(footprints allowed)
			)
			(placement
				(enabled no)
				(sheetname "")
			)
			(fill
				(thermal_gap 0.5)
				(thermal_bridge_width 0.5)
				(island_removal_mode 0)
			)
			(polygon
				(pts
					(xy 389.24992 -111.2647) (xy 389.24992 -111.6457) (xy 389.42518 -111.6457) (xy 389.425434 -111.2647)
				)
			)
		)
		(zone
			(layer "B.Cu")
			(hatch none 0.5)
			(connect_pads
				(clearance 0)
			)
			(min_thickness 0.25)
			(keepout
				(tracks not_allowed)
				(vias allowed)
				(pads allowed)
				(copperpour not_allowed)
				(footprints allowed)
			)
			(placement
				(enabled no)
				(sheetname "")
			)
			(fill
				(thermal_gap 0.5)
				(thermal_bridge_width 0.5)
				(island_removal_mode 0)
			)
			(polygon
				(pts
					(xy 389.24992 -111.2647) (xy 389.24992 -111.6457) (xy 389.42518 -111.6457) (xy 389.425434 -111.2647)
				)
			)
		)
	)
	(footprint ""
		(layer "B.Cu")
		(at 409.829 -48.768)
		(property "Reference" "R1T4"
			(at 0 0 0)
			(layer "B.SilkS")
			(hide yes)
			(effects
				(font
					(size 1.27 1.27)
				)
				(justify mirror)
			)
		)
		(property "Value" ""
			(at 0 0 0)
			(layer "B.Fab")
			(effects
				(font
					(size 1.27 1.27)
				)
				(justify mirror)
			)
		)
		(duplicate_pad_numbers_are_jumpers no)
		(fp_poly
			(pts
				(xy 0.2794 -0.1016) (xy -0.2794 -0.1016) (xy -0.2794 0.9906) (xy 0.2794 0.9906)
			)
			(stroke
				(width 0)
				(type default)
			)
			(fill no)
			(layer "B.CrtYd")
		)
		(fp_line
			(start -0.2794 -0.1016)
			(end 0.2794 -0.1016)
			(stroke
				(width 0.1)
				(type default)
			)
			(layer "B.Fab")
		)
		(fp_line
			(start -0.2794 0.9906)
			(end -0.2794 -0.1016)
			(stroke
				(width 0.1)
				(type default)
			)
			(layer "B.Fab")
		)
		(fp_line
			(start 0.2794 -0.1016)
			(end 0.2794 0.9906)
			(stroke
				(width 0.1)
				(type default)
			)
			(layer "B.Fab")
		)
		(fp_line
			(start 0.2794 0.9906)
			(end -0.2794 0.9906)
			(stroke
				(width 0.1)
				(type default)
			)
			(layer "B.Fab")
		)
		(pad "1" smd rect
			(at 0 0 180)
			(size 0.508 0.508)
			(layers "B.Cu" "B.Mask" "B.Paste")
			(net "P3V3_STBY")
		)
		(pad "2" smd rect
			(at 0 0.889 180)
			(size 0.508 0.508)
			(layers "B.Cu" "B.Mask" "B.Paste")
			(net "FM_BOARD_REV_ID0")
		)
	)
	(footprint ""
		(layer "B.Cu")
		(at 32.3088 -70.7898 90)
		(property "Reference" "R9P22"
			(at 0 0 90)
			(layer "B.SilkS")
			(hide yes)
			(effects
				(font
					(size 1.27 1.27)
				)
				(justify mirror)
			)
		)
		(property "Value" ""
			(at 0 0 90)
			(layer "B.Fab")
			(effects
				(font
					(size 1.27 1.27)
				)
				(justify mirror)
			)
		)
		(duplicate_pad_numbers_are_jumpers no)
		(fp_poly
			(pts
				(xy 0.2794 -0.1016) (xy -0.2794 -0.1016) (xy -0.2794 0.9906) (xy 0.2794 0.9906)
			)
			(stroke
				(width 0)
				(type default)
			)
			(fill no)
			(layer "B.CrtYd")
		)
		(fp_line
			(start 0.2794 -0.1016)
			(end 0.2794 0.9906)
			(stroke
				(width 0.1)
				(type default)
			)
			(layer "B.Fab")
		)
		(fp_line
			(start -0.2794 -0.1016)
			(end 0.2794 -0.1016)
			(stroke
				(width 0.1)
				(type default)
			)
			(layer "B.Fab")
		)
		(fp_line
			(start 0.2794 0.9906)
			(end -0.2794 0.9906)
			(stroke
				(width 0.1)
				(type default)
			)
			(layer "B.Fab")
		)
		(fp_line
			(start -0.2794 0.9906)
			(end -0.2794 -0.1016)
			(stroke
				(width 0.1)
				(type default)
			)
			(layer "B.Fab")
		)
		(pad "1" smd rect
			(at 0 0 270)
			(size 0.508 0.508)
			(layers "B.Cu" "B.Mask" "B.Paste")
			(net "VR_PVCCIN_CPU1_PH3_VCIN")
		)
		(pad "2" smd rect
			(at 0 0.889 270)
			(size 0.508 0.508)
			(layers "B.Cu" "B.Mask" "B.Paste")
			(net "P5V_STBY")
		)
		(zone
			(layer "B.Cu")
			(hatch none 0.5)
			(connect_pads
				(clearance 0)
			)
			(min_thickness 0.25)
			(keepout
				(tracks allowed)
				(vias not_allowed)
				(pads allowed)
				(copperpour not_allowed)
				(footprints allowed)
			)
			(placement
				(enabled no)
				(sheetname "")
			)
			(fill
				(thermal_gap 0.5)
				(thermal_bridge_width 0.5)
				(island_removal_mode 0)
			)
			(polygon
				(pts
					(xy 32.5628 -71.0438) (xy 32.5628 -70.5358) (xy 32.9438 -70.5358) (xy 32.9438 -71.0438)
				)
			)
		)
		(zone
			(layer "B.Cu")
			(hatch none 0.5)
			(connect_pads
				(clearance 0)
			)
			(min_thickness 0.25)
			(keepout
				(tracks not_allowed)
				(vias allowed)
				(pads allowed)
				(copperpour not_allowed)
				(footprints allowed)
			)
			(placement
				(enabled no)
				(sheetname "")
			)
			(fill
				(thermal_gap 0.5)
				(thermal_bridge_width 0.5)
				(island_removal_mode 0)
			)
			(polygon
				(pts
					(xy 32.9438 -71.0438) (xy 32.9438 -70.5358) (xy 32.5628 -70.5358) (xy 32.5628 -71.0438)
				)
			)
		)
	)
	(footprint ""
		(layer "B.Cu")
		(at 362.715556 -122.510042 -90)
		(property "Reference" "C3M26"
			(at 0 0 90)
			(layer "B.SilkS")
			(hide yes)
			(effects
				(font
					(size 1.27 1.27)
				)
				(justify mirror)
			)
		)
		(property "Value" ""
			(at 0 0 90)
			(layer "B.Fab")
			(effects
				(font
					(size 1.27 1.27)
				)
				(justify mirror)
			)
		)
		(duplicate_pad_numbers_are_jumpers no)
		(fp_poly
			(pts
				(xy -0.3048 -0.1016) (xy -0.3048 0.9906) (xy 0.3048 0.9906) (xy 0.3048 -0.1016)
			)
			(stroke
				(width 0)
				(type default)
			)
			(fill no)
			(layer "B.CrtYd")
		)
		(fp_line
			(start -0.3048 0.9906)
			(end -0.3048 -0.1016)
			(stroke
				(width 0.1)
				(type default)
			)
			(layer "B.Fab")
		)
		(fp_line
			(start 0.3048 0.9906)
			(end -0.3048 0.9906)
			(stroke
				(width 0.1)
				(type default)
			)
			(layer "B.Fab")
		)
		(fp_line
			(start -0.3048 -0.1016)
			(end 0.3048 -0.1016)
			(stroke
				(width 0.1)
				(type default)
			)
			(layer "B.Fab")
		)
		(fp_line
			(start 0.3048 -0.1016)
			(end 0.3048 0.9906)
			(stroke
				(width 0.1)
				(type default)
			)
			(layer "B.Fab")
		)
		(pad "1" smd rect
			(at 0 0 90)
			(size 0.508 0.508)
			(layers "B.Cu" "B.Mask" "B.Paste")
			(net "P3E_CPU0_PE1_PCH_R_RXN<11>")
		)
		(pad "2" smd rect
			(at 0 0.889 90)
			(size 0.508 0.508)
			(layers "B.Cu" "B.Mask" "B.Paste")
			(net "P3E_CPU0_PE1_PCH_RXN<11>")
		)
		(zone
			(layer "B.Cu")
			(hatch none 0.5)
			(connect_pads
				(clearance 0)
			)
			(min_thickness 0.25)
			(keepout
				(tracks not_allowed)
				(vias allowed)
				(pads allowed)
				(copperpour not_allowed)
				(footprints allowed)
			)
			(placement
				(enabled no)
				(sheetname "")
			)
			(fill
				(thermal_gap 0.5)
				(thermal_bridge_width 0.5)
				(island_removal_mode 0)
			)
			(polygon
				(pts
					(xy 362.080556 -122.256042) (xy 362.080556 -122.764042) (xy 362.461556 -122.764042) (xy 362.461556 -122.256042)
				)
			)
		)
		(zone
			(layer "B.Cu")
			(hatch none 0.5)
			(connect_pads
				(clearance 0)
			)
			(min_thickness 0.25)
			(keepout
				(tracks allowed)
				(vias not_allowed)
				(pads allowed)
				(copperpour not_allowed)
				(footprints allowed)
			)
			(placement
				(enabled no)
				(sheetname "")
			)
			(fill
				(thermal_gap 0.5)
				(thermal_bridge_width 0.5)
				(island_removal_mode 0)
			)
			(polygon
				(pts
					(xy 362.461556 -122.256042) (xy 362.461556 -122.764042) (xy 362.080556 -122.764042) (xy 362.080556 -122.256042)
				)
			)
		)
	)
	(footprint ""
		(layer "B.Cu")
		(at 395.351 -85.9155)
		(property "Reference" "R2U8"
			(at 0 0 0)
			(layer "B.SilkS")
			(hide yes)
			(effects
				(font
					(size 1.27 1.27)
				)
				(justify mirror)
			)
		)
		(property "Value" ""
			(at 0 0 0)
			(layer "B.Fab")
			(effects
				(font
					(size 1.27 1.27)
				)
				(justify mirror)
			)
		)
		(duplicate_pad_numbers_are_jumpers no)
		(fp_poly
			(pts
				(xy 0.2794 -0.1016) (xy -0.2794 -0.1016) (xy -0.2794 0.9906) (xy 0.2794 0.9906)
			)
			(stroke
				(width 0)
				(type default)
			)
			(fill no)
			(layer "B.CrtYd")
		)
		(fp_line
			(start -0.2794 -0.1016)
			(end 0.2794 -0.1016)
			(stroke
				(width 0.1)
				(type default)
			)
			(layer "B.Fab")
		)
		(fp_line
			(start -0.2794 0.9906)
			(end -0.2794 -0.1016)
			(stroke
				(width 0.1)
				(type default)
			)
			(layer "B.Fab")
		)
		(fp_line
			(start 0.2794 -0.1016)
			(end 0.2794 0.9906)
			(stroke
				(width 0.1)
				(type default)
			)
			(layer "B.Fab")
		)
		(fp_line
			(start 0.2794 0.9906)
			(end -0.2794 0.9906)
			(stroke
				(width 0.1)
				(type default)
			)
			(layer "B.Fab")
		)
		(pad "1" smd rect
			(at 0 0 180)
			(size 0.508 0.508)
			(layers "B.Cu" "B.Mask" "B.Paste")
			(net "SMB_LAN_STBY_LVC3_SCL")
		)
		(pad "2" smd rect
			(at 0 0.889 180)
			(size 0.508 0.508)
			(layers "B.Cu" "B.Mask" "B.Paste")
			(net "SMB_OCP_FRU_STBY_LVC3_SCL")
		)
		(zone
			(layer "B.Cu")
			(hatch none 0.5)
			(connect_pads
				(clearance 0)
			)
			(min_thickness 0.25)
			(keepout
				(tracks allowed)
				(vias not_allowed)
				(pads allowed)
				(copperpour not_allowed)
				(footprints allowed)
			)
			(placement
				(enabled no)
				(sheetname "")
			)
			(fill
				(thermal_gap 0.5)
				(thermal_bridge_width 0.5)
				(island_removal_mode 0)
			)
			(polygon
				(pts
					(xy 395.605 -85.6615) (xy 395.097 -85.6615) (xy 395.097 -85.2805) (xy 395.605 -85.2805)
				)
			)
		)
		(zone
			(layer "B.Cu")
			(hatch none 0.5)
			(connect_pads
				(clearance 0)
			)
			(min_thickness 0.25)
			(keepout
				(tracks not_allowed)
				(vias allowed)
				(pads allowed)
				(copperpour not_allowed)
				(footprints allowed)
			)
			(placement
				(enabled no)
				(sheetname "")
			)
			(fill
				(thermal_gap 0.5)
				(thermal_bridge_width 0.5)
				(island_removal_mode 0)
			)
			(polygon
				(pts
					(xy 395.605 -85.2805) (xy 395.097 -85.2805) (xy 395.097 -85.6615) (xy 395.605 -85.6615)
				)
			)
		)
	)
	(footprint ""
		(layer "B.Cu")
		(at 25.654 -77.978)
		(property "Reference" "C9P11"
			(at 0 0 0)
			(layer "B.SilkS")
			(hide yes)
			(effects
				(font
					(size 1.27 1.27)
				)
				(justify mirror)
			)
		)
		(property "Value" ""
			(at 0 0 0)
			(layer "B.Fab")
			(effects
				(font
					(size 1.27 1.27)
				)
				(justify mirror)
			)
		)
		(duplicate_pad_numbers_are_jumpers no)
		(fp_poly
			(pts
				(xy -0.3048 -0.1016) (xy -0.3048 0.9906) (xy 0.3048 0.9906) (xy 0.3048 -0.1016)
			)
			(stroke
				(width 0)
				(type default)
			)
			(fill no)
			(layer "B.CrtYd")
		)
		(fp_line
			(start -0.3048 -0.1016)
			(end 0.3048 -0.1016)
			(stroke
				(width 0.1)
				(type default)
			)
			(layer "B.Fab")
		)
		(fp_line
			(start -0.3048 0.9906)
			(end -0.3048 -0.1016)
			(stroke
				(width 0.1)
				(type default)
			)
			(layer "B.Fab")
		)
		(fp_line
			(start 0.3048 -0.1016)
			(end 0.3048 0.9906)
			(stroke
				(width 0.1)
				(type default)
			)
			(layer "B.Fab")
		)
		(fp_line
			(start 0.3048 0.9906)
			(end -0.3048 0.9906)
			(stroke
				(width 0.1)
				(type default)
			)
			(layer "B.Fab")
		)
		(pad "1" smd rect
			(at 0 0 180)
			(size 0.508 0.508)
			(layers "B.Cu" "B.Mask" "B.Paste")
			(net "P3V3_STBY")
		)
		(pad "2" smd rect
			(at 0 0.889 180)
			(size 0.508 0.508)
			(layers "B.Cu" "B.Mask" "B.Paste")
			(net "GND")
		)
		(zone
			(layer "B.Cu")
			(hatch none 0.5)
			(connect_pads
				(clearance 0)
			)
			(min_thickness 0.25)
			(keepout
				(tracks allowed)
				(vias not_allowed)
				(pads allowed)
				(copperpour not_allowed)
				(footprints allowed)
			)
			(placement
				(enabled no)
				(sheetname "")
			)
			(fill
				(thermal_gap 0.5)
				(thermal_bridge_width 0.5)
				(island_removal_mode 0)
			)
			(polygon
				(pts
					(xy 25.908 -77.724) (xy 25.4 -77.724) (xy 25.4 -77.343) (xy 25.908 -77.343)
				)
			)
		)
		(zone
			(layer "B.Cu")
			(hatch none 0.5)
			(connect_pads
				(clearance 0)
			)
			(min_thickness 0.25)
			(keepout
				(tracks not_allowed)
				(vias allowed)
				(pads allowed)
				(copperpour not_allowed)
				(footprints allowed)
			)
			(placement
				(enabled no)
				(sheetname "")
			)
			(fill
				(thermal_gap 0.5)
				(thermal_bridge_width 0.5)
				(island_removal_mode 0)
			)
			(polygon
				(pts
					(xy 25.908 -77.343) (xy 25.4 -77.343) (xy 25.4 -77.724) (xy 25.908 -77.724)
				)
			)
		)
	)
	(footprint ""
		(layer "B.Cu")
		(at 331.139038 -37.815266)
		(property "Reference" "C4T2"
			(at 0 0 0)
			(layer "B.SilkS")
			(hide yes)
			(effects
				(font
					(size 1.27 1.27)
				)
				(justify mirror)
			)
		)
		(property "Value" ""
			(at 0 0 0)
			(layer "B.Fab")
			(effects
				(font
					(size 1.27 1.27)
				)
				(justify mirror)
			)
		)
		(duplicate_pad_numbers_are_jumpers no)
		(fp_poly
			(pts
				(xy -0.3048 -0.1016) (xy -0.3048 0.9906) (xy 0.3048 0.9906) (xy 0.3048 -0.1016)
			)
			(stroke
				(width 0)
				(type default)
			)
			(fill no)
			(layer "B.CrtYd")
		)
		(fp_line
			(start -0.3048 -0.1016)
			(end 0.3048 -0.1016)
			(stroke
				(width 0.1)
				(type default)
			)
			(layer "B.Fab")
		)
		(fp_line
			(start -0.3048 0.9906)
			(end -0.3048 -0.1016)
			(stroke
				(width 0.1)
				(type default)
			)
			(layer "B.Fab")
		)
		(fp_line
			(start 0.3048 -0.1016)
			(end 0.3048 0.9906)
			(stroke
				(width 0.1)
				(type default)
			)
			(layer "B.Fab")
		)
		(fp_line
			(start 0.3048 0.9906)
			(end -0.3048 0.9906)
			(stroke
				(width 0.1)
				(type default)
			)
			(layer "B.Fab")
		)
		(pad "1" smd rect
			(at 0 0 180)
			(size 0.508 0.508)
			(layers "B.Cu" "B.Mask" "B.Paste")
			(net "P1V8_MCP_CPU0")
		)
		(pad "2" smd rect
			(at 0 0.889 180)
			(size 0.508 0.508)
			(layers "B.Cu" "B.Mask" "B.Paste")
			(net "GND")
		)
		(zone
			(layer "B.Cu")
			(hatch none 0.5)
			(connect_pads
				(clearance 0)
			)
			(min_thickness 0.25)
			(keepout
				(tracks allowed)
				(vias not_allowed)
				(pads allowed)
				(copperpour not_allowed)
				(footprints allowed)
			)
			(placement
				(enabled no)
				(sheetname "")
			)
			(fill
				(thermal_gap 0.5)
				(thermal_bridge_width 0.5)
				(island_removal_mode 0)
			)
			(polygon
				(pts
					(xy 331.393038 -37.561266) (xy 330.885038 -37.561266) (xy 330.885038 -37.180266) (xy 331.393038 -37.180266)
				)
			)
		)
		(zone
			(layer "B.Cu")
			(hatch none 0.5)
			(connect_pads
				(clearance 0)
			)
			(min_thickness 0.25)
			(keepout
				(tracks not_allowed)
				(vias allowed)
				(pads allowed)
				(copperpour not_allowed)
				(footprints allowed)
			)
			(placement
				(enabled no)
				(sheetname "")
			)
			(fill
				(thermal_gap 0.5)
				(thermal_bridge_width 0.5)
				(island_removal_mode 0)
			)
			(polygon
				(pts
					(xy 331.393038 -37.180266) (xy 330.885038 -37.180266) (xy 330.885038 -37.561266) (xy 331.393038 -37.561266)
				)
			)
		)
	)
	(footprint ""
		(layer "B.Cu")
		(at 418.846 -24.765 90)
		(property "Reference" "L25W3"
			(at 0 0 90)
			(layer "B.SilkS")
			(hide yes)
			(effects
				(font
					(size 1.27 1.27)
				)
				(justify mirror)
			)
		)
		(property "Value" "*"
			(at -0.0254 -2.8829 90)
			(unlocked yes)
			(layer "B.Fab")
			(hide yes)
			(effects
				(font
					(size 1.27 1.016)
					(thickness 0.1524)
				)
				(justify mirror)
			)
		)
		(property "Device Type" "IND-68NH-15-GP_DISCRET-GC1-INDA"
			(at -0.0254 -4.4069 90)
			(unlocked yes)
			(layer "B.Fab")
			(hide yes)
			(effects
				(font
					(size 1.27 1.016)
					(thickness 0.1524)
				)
				(justify mirror)
			)
		)
		(duplicate_pad_numbers_are_jumpers no)
		(fp_line
			(start -0.254 0)
			(end 0.254 0)
			(stroke
				(width 0.2032)
				(type default)
			)
			(layer "B.SilkS")
		)
		(fp_rect
			(start 0.5842 1.3335)
			(end -0.5842 -1.3335)
			(stroke
				(width 0)
				(type default)
			)
			(fill no)
			(layer "B.CrtYd")
		)
		(fp_rect
			(start 0.5842 1.3335)
			(end -0.5842 -1.3335)
			(stroke
				(width 0)
				(type default)
			)
			(fill no)
			(layer "B.Fab")
		)
		(pad "1" smd custom
			(at 0 -0.762 270)
			(size 0.2159 0.2159)
			(layers "B.Cu" "B.Mask" "B.Paste")
			(net "BMC_VGA_RED")
			(options
				(clearance outline)
				(anchor circle)
			)
			(primitives
				(gr_poly
					(pts
						(arc
							(start -0.3302 0.4318)
							(mid -0.402042 0.402042)
							(end -0.4318 0.3302)
						)
						(arc
							(start -0.4318 -0.3302)
							(mid -0.402042 -0.402042)
							(end -0.3302 -0.4318)
						)
						(arc
							(start 0.3302 -0.4318)
							(mid 0.402042 -0.402042)
							(end 0.4318 -0.3302)
						)
						(arc
							(start 0.4318 0.3302)
							(mid 0.402042 0.402042)
							(end 0.3302 0.4318)
						)
					)
					(width 0)
					(fill yes)
				)
			)
		)
		(pad "2" smd custom
			(at 0 0.762 270)
			(size 0.2159 0.2159)
			(layers "B.Cu" "B.Mask" "B.Paste")
			(net "V_IO_R_J")
			(options
				(clearance outline)
				(anchor circle)
			)
			(primitives
				(gr_poly
					(pts
						(arc
							(start -0.3302 0.4318)
							(mid -0.402042 0.402042)
							(end -0.4318 0.3302)
						)
						(arc
							(start -0.4318 -0.3302)
							(mid -0.402042 -0.402042)
							(end -0.3302 -0.4318)
						)
						(arc
							(start 0.3302 -0.4318)
							(mid 0.402042 -0.402042)
							(end 0.4318 -0.3302)
						)
						(arc
							(start 0.4318 0.3302)
							(mid 0.402042 0.402042)
							(end 0.3302 0.4318)
						)
					)
					(width 0)
					(fill yes)
				)
			)
		)
	)
	(footprint ""
		(layer "B.Cu")
		(at 13.843 -89.154 90)
		(property "Reference" "R9N16"
			(at 0 0 90)
			(layer "B.SilkS")
			(hide yes)
			(effects
				(font
					(size 1.27 1.27)
				)
				(justify mirror)
			)
		)
		(property "Value" ""
			(at 0 0 90)
			(layer "B.Fab")
			(effects
				(font
					(size 1.27 1.27)
				)
				(justify mirror)
			)
		)
		(duplicate_pad_numbers_are_jumpers no)
		(fp_rect
			(start -0.2794 -0.1016)
			(end 0.2794 0.9906)
			(stroke
				(width 0)
				(type default)
			)
			(fill no)
			(layer "B.CrtYd")
		)
		(fp_line
			(start 0.2794 -0.1016)
			(end 0.2794 0.9906)
			(stroke
				(width 0.1)
				(type default)
			)
			(layer "B.Fab")
		)
		(fp_line
			(start -0.2794 -0.1016)
			(end 0.2794 -0.1016)
			(stroke
				(width 0.1)
				(type default)
			)
			(layer "B.Fab")
		)
		(fp_line
			(start 0.2794 0.9906)
			(end -0.2794 0.9906)
			(stroke
				(width 0.1)
				(type default)
			)
			(layer "B.Fab")
		)
		(fp_line
			(start -0.2794 0.9906)
			(end -0.2794 -0.1016)
			(stroke
				(width 0.1)
				(type default)
			)
			(layer "B.Fab")
		)
		(pad "1" smd rect
			(at 0 0 270)
			(size 0.508 0.508)
			(layers "B.Cu" "B.Mask" "B.Paste")
			(net "FM_PVCCIN_PVCCSA_CPU1_EN_LVC1")
		)
		(pad "2" smd rect
			(at 0 0.889 270)
			(size 0.508 0.508)
			(layers "B.Cu" "B.Mask" "B.Paste")
			(net "VR_PVCCIN_CPU1_VREN")
		)
		(zone
			(layer "B.Cu")
			(hatch none 0.5)
			(connect_pads
				(clearance 0)
			)
			(min_thickness 0.25)
			(keepout
				(tracks not_allowed)
				(vias allowed)
				(pads allowed)
				(copperpour not_allowed)
				(footprints allowed)
			)
			(placement
				(enabled no)
				(sheetname "")
			)
			(fill
				(thermal_gap 0.5)
				(thermal_bridge_width 0.5)
				(island_removal_mode 0)
			)
			(polygon
				(pts
					(xy 14.097 -88.9) (xy 14.478 -88.9) (xy 14.478 -89.408) (xy 14.097 -89.408)
				)
			)
		)
		(zone
			(layer "B.Cu")
			(hatch none 0.5)
			(connect_pads
				(clearance 0)
			)
			(min_thickness 0.25)
			(keepout
				(tracks allowed)
				(vias not_allowed)
				(pads allowed)
				(copperpour not_allowed)
				(footprints allowed)
			)
			(placement
				(enabled no)
				(sheetname "")
			)
			(fill
				(thermal_gap 0.5)
				(thermal_bridge_width 0.5)
				(island_removal_mode 0)
			)
			(polygon
				(pts
					(xy 14.097 -88.9) (xy 14.478 -88.9) (xy 14.478 -89.408) (xy 14.097 -89.408)
				)
			)
		)
	)
	(footprint ""
		(layer "B.Cu")
		(at 417.919916 -35.202368 -90)
		(property "Reference" "C25W24"
			(at 0.8382 -0.67818 270)
			(unlocked yes)
			(layer "B.SilkS")
			(effects
				(font
					(size 0.4064 0.254)
					(thickness 0.1524)
				)
				(justify left mirror)
			)
		)
		(property "Value" ""
			(at 0 0 90)
			(layer "B.Fab")
			(effects
				(font
					(size 1.27 1.27)
				)
				(justify mirror)
			)
		)
		(duplicate_pad_numbers_are_jumpers no)
		(fp_poly
			(pts
				(xy -0.3048 -0.1016) (xy -0.3048 0.9906) (xy 0.3048 0.9906) (xy 0.3048 -0.1016)
			)
			(stroke
				(width 0)
				(type default)
			)
			(fill no)
			(layer "B.CrtYd")
		)
		(fp_line
			(start -0.3048 0.9906)
			(end -0.3048 -0.1016)
			(stroke
				(width 0.1)
				(type default)
			)
			(layer "B.Fab")
		)
		(fp_line
			(start 0.3048 0.9906)
			(end -0.3048 0.9906)
			(stroke
				(width 0.1)
				(type default)
			)
			(layer "B.Fab")
		)
		(fp_line
			(start -0.3048 -0.1016)
			(end 0.3048 -0.1016)
			(stroke
				(width 0.1)
				(type default)
			)
			(layer "B.Fab")
		)
		(fp_line
			(start 0.3048 -0.1016)
			(end 0.3048 0.9906)
			(stroke
				(width 0.1)
				(type default)
			)
			(layer "B.Fab")
		)
		(pad "1" smd rect
			(at 0 0 90)
			(size 0.508 0.508)
			(layers "B.Cu" "B.Mask" "B.Paste")
			(net "P1V15_AUX_BMC")
		)
		(pad "2" smd rect
			(at 0 0.889 90)
			(size 0.508 0.508)
			(layers "B.Cu" "B.Mask" "B.Paste")
			(net "GND")
		)
		(zone
			(layer "B.Cu")
			(hatch none 0.5)
			(connect_pads
				(clearance 0)
			)
			(min_thickness 0.25)
			(keepout
				(tracks not_allowed)
				(vias allowed)
				(pads allowed)
				(copperpour not_allowed)
				(footprints allowed)
			)
			(placement
				(enabled no)
				(sheetname "")
			)
			(fill
				(thermal_gap 0.5)
				(thermal_bridge_width 0.5)
				(island_removal_mode 0)
			)
			(polygon
				(pts
					(xy 417.284916 -34.948368) (xy 417.284916 -35.456368) (xy 417.665916 -35.456368) (xy 417.665916 -34.948368)
				)
			)
		)
		(zone
			(layer "B.Cu")
			(hatch none 0.5)
			(connect_pads
				(clearance 0)
			)
			(min_thickness 0.25)
			(keepout
				(tracks allowed)
				(vias not_allowed)
				(pads allowed)
				(copperpour not_allowed)
				(footprints allowed)
			)
			(placement
				(enabled no)
				(sheetname "")
			)
			(fill
				(thermal_gap 0.5)
				(thermal_bridge_width 0.5)
				(island_removal_mode 0)
			)
			(polygon
				(pts
					(xy 417.665916 -34.948368) (xy 417.665916 -35.456368) (xy 417.284916 -35.456368) (xy 417.284916 -34.948368)
				)
			)
		)
	)
	(footprint ""
		(layer "B.Cu")
		(at 339.7504 -111.4044 180)
		(property "Reference" "R3N29"
			(at 0 0 0)
			(layer "B.SilkS")
			(hide yes)
			(effects
				(font
					(size 1.27 1.27)
				)
				(justify mirror)
			)
		)
		(property "Value" ""
			(at 0 0 0)
			(layer "B.Fab")
			(effects
				(font
					(size 1.27 1.27)
				)
				(justify mirror)
			)
		)
		(duplicate_pad_numbers_are_jumpers no)
		(fp_poly
			(pts
				(xy 0.2794 -0.1016) (xy -0.2794 -0.1016) (xy -0.2794 0.9906) (xy 0.2794 0.9906)
			)
			(stroke
				(width 0)
				(type default)
			)
			(fill no)
			(layer "B.CrtYd")
		)
		(fp_line
			(start 0.2794 0.9906)
			(end -0.2794 0.9906)
			(stroke
				(width 0.1)
				(type default)
			)
			(layer "B.Fab")
		)
		(fp_line
			(start 0.2794 -0.1016)
			(end 0.2794 0.9906)
			(stroke
				(width 0.1)
				(type default)
			)
			(layer "B.Fab")
		)
		(fp_line
			(start -0.2794 0.9906)
			(end -0.2794 -0.1016)
			(stroke
				(width 0.1)
				(type default)
			)
			(layer "B.Fab")
		)
		(fp_line
			(start -0.2794 -0.1016)
			(end 0.2794 -0.1016)
			(stroke
				(width 0.1)
				(type default)
			)
			(layer "B.Fab")
		)
		(pad "1" smd rect
			(at 0 0)
			(size 0.508 0.508)
			(layers "B.Cu" "B.Mask" "B.Paste")
			(net "VR_PVCCIOMCP_CPU0_XADDR1")
		)
		(pad "2" smd rect
			(at 0 0.889)
			(size 0.508 0.508)
			(layers "B.Cu" "B.Mask" "B.Paste")
			(net "GND")
		)
		(zone
			(layer "B.Cu")
			(hatch none 0.5)
			(connect_pads
				(clearance 0)
			)
			(min_thickness 0.25)
			(keepout
				(tracks not_allowed)
				(vias allowed)
				(pads allowed)
				(copperpour not_allowed)
				(footprints allowed)
			)
			(placement
				(enabled no)
				(sheetname "")
			)
			(fill
				(thermal_gap 0.5)
				(thermal_bridge_width 0.5)
				(island_removal_mode 0)
			)
			(polygon
				(pts
					(xy 339.4964 -112.0394) (xy 340.0044 -112.0394) (xy 340.0044 -111.6584) (xy 339.4964 -111.6584)
				)
			)
		)
		(zone
			(layer "B.Cu")
			(hatch none 0.5)
			(connect_pads
				(clearance 0)
			)
			(min_thickness 0.25)
			(keepout
				(tracks allowed)
				(vias not_allowed)
				(pads allowed)
				(copperpour not_allowed)
				(footprints allowed)
			)
			(placement
				(enabled no)
				(sheetname "")
			)
			(fill
				(thermal_gap 0.5)
				(thermal_bridge_width 0.5)
				(island_removal_mode 0)
			)
			(polygon
				(pts
					(xy 339.4964 -111.6584) (xy 340.0044 -111.6584) (xy 340.0044 -112.0394) (xy 339.4964 -112.0394)
				)
			)
		)
	)
	(footprint ""
		(layer "B.Cu")
		(at 171.059856 -128.850136)
		(property "Reference" "R5W2"
			(at 0.8382 -0.67818 0)
			(unlocked yes)
			(layer "B.SilkS")
			(effects
				(font
					(size 0.4064 0.254)
					(thickness 0.1524)
				)
				(justify left mirror)
			)
		)
		(property "Value" ""
			(at 0 0 0)
			(layer "B.Fab")
			(effects
				(font
					(size 1.27 1.27)
				)
				(justify mirror)
			)
		)
		(duplicate_pad_numbers_are_jumpers no)
		(fp_poly
			(pts
				(xy 0.2794 -0.1016) (xy -0.2794 -0.1016) (xy -0.2794 0.9906) (xy 0.2794 0.9906)
			)
			(stroke
				(width 0)
				(type default)
			)
			(fill no)
			(layer "B.CrtYd")
		)
		(fp_line
			(start -0.2794 -0.1016)
			(end 0.2794 -0.1016)
			(stroke
				(width 0.1)
				(type default)
			)
			(layer "B.Fab")
		)
		(fp_line
			(start -0.2794 0.9906)
			(end -0.2794 -0.1016)
			(stroke
				(width 0.1)
				(type default)
			)
			(layer "B.Fab")
		)
		(fp_line
			(start 0.2794 -0.1016)
			(end 0.2794 0.9906)
			(stroke
				(width 0.1)
				(type default)
			)
			(layer "B.Fab")
		)
		(fp_line
			(start 0.2794 0.9906)
			(end -0.2794 0.9906)
			(stroke
				(width 0.1)
				(type default)
			)
			(layer "B.Fab")
		)
		(pad "1" smd rect
			(at 0 0 180)
			(size 0.508 0.508)
			(layers "B.Cu" "B.Mask" "B.Paste")
			(net "P1V8_MCP_CPU1")
		)
		(pad "2" smd rect
			(at 0 0.889 180)
			(size 0.508 0.508)
			(layers "B.Cu" "B.Mask" "B.Paste")
			(net "JTAG_MCP_CPU1_TDI_R")
		)
		(zone
			(layer "B.Cu")
			(hatch none 0.5)
			(connect_pads
				(clearance 0)
			)
			(min_thickness 0.25)
			(keepout
				(tracks allowed)
				(vias not_allowed)
				(pads allowed)
				(copperpour not_allowed)
				(footprints allowed)
			)
			(placement
				(enabled no)
				(sheetname "")
			)
			(fill
				(thermal_gap 0.5)
				(thermal_bridge_width 0.5)
				(island_removal_mode 0)
			)
			(polygon
				(pts
					(xy 171.313856 -128.596136) (xy 170.805856 -128.596136) (xy 170.805856 -128.215136) (xy 171.313856 -128.215136)
				)
			)
		)
		(zone
			(layer "B.Cu")
			(hatch none 0.5)
			(connect_pads
				(clearance 0)
			)
			(min_thickness 0.25)
			(keepout
				(tracks not_allowed)
				(vias allowed)
				(pads allowed)
				(copperpour not_allowed)
				(footprints allowed)
			)
			(placement
				(enabled no)
				(sheetname "")
			)
			(fill
				(thermal_gap 0.5)
				(thermal_bridge_width 0.5)
				(island_removal_mode 0)
			)
			(polygon
				(pts
					(xy 171.313856 -128.215136) (xy 170.805856 -128.215136) (xy 170.805856 -128.596136) (xy 171.313856 -128.596136)
				)
			)
		)
	)
	(footprint ""
		(layer "B.Cu")
		(at 409.600146 -21.853652 -90)
		(property "Reference" "C9G15"
			(at 0 0 90)
			(layer "B.SilkS")
			(hide yes)
			(effects
				(font
					(size 1.27 1.27)
				)
				(justify mirror)
			)
		)
		(property "Value" ""
			(at 0 0 90)
			(layer "B.Fab")
			(effects
				(font
					(size 1.27 1.27)
				)
				(justify mirror)
			)
		)
		(duplicate_pad_numbers_are_jumpers no)
		(fp_poly
			(pts
				(xy -0.3048 -0.1016) (xy -0.3048 0.9906) (xy 0.3048 0.9906) (xy 0.3048 -0.1016)
			)
			(stroke
				(width 0)
				(type default)
			)
			(fill no)
			(layer "B.CrtYd")
		)
		(fp_line
			(start -0.3048 0.9906)
			(end -0.3048 -0.1016)
			(stroke
				(width 0.1)
				(type default)
			)
			(layer "B.Fab")
		)
		(fp_line
			(start 0.3048 0.9906)
			(end -0.3048 0.9906)
			(stroke
				(width 0.1)
				(type default)
			)
			(layer "B.Fab")
		)
		(fp_line
			(start -0.3048 -0.1016)
			(end 0.3048 -0.1016)
			(stroke
				(width 0.1)
				(type default)
			)
			(layer "B.Fab")
		)
		(fp_line
			(start 0.3048 -0.1016)
			(end 0.3048 0.9906)
			(stroke
				(width 0.1)
				(type default)
			)
			(layer "B.Fab")
		)
		(pad "1" smd rect
			(at 0 0 90)
			(size 0.508 0.508)
			(layers "B.Cu" "B.Mask" "B.Paste")
			(net "A_P5V_SCALED")
		)
		(pad "2" smd rect
			(at 0 0.889 90)
			(size 0.508 0.508)
			(layers "B.Cu" "B.Mask" "B.Paste")
			(net "GND")
		)
		(zone
			(layer "B.Cu")
			(hatch none 0.5)
			(connect_pads
				(clearance 0)
			)
			(min_thickness 0.25)
			(keepout
				(tracks not_allowed)
				(vias allowed)
				(pads allowed)
				(copperpour not_allowed)
				(footprints allowed)
			)
			(placement
				(enabled no)
				(sheetname "")
			)
			(fill
				(thermal_gap 0.5)
				(thermal_bridge_width 0.5)
				(island_removal_mode 0)
			)
			(polygon
				(pts
					(xy 408.965146 -21.599652) (xy 408.965146 -22.107652) (xy 409.346146 -22.107652) (xy 409.346146 -21.599652)
				)
			)
		)
		(zone
			(layer "B.Cu")
			(hatch none 0.5)
			(connect_pads
				(clearance 0)
			)
			(min_thickness 0.25)
			(keepout
				(tracks allowed)
				(vias not_allowed)
				(pads allowed)
				(copperpour not_allowed)
				(footprints allowed)
			)
			(placement
				(enabled no)
				(sheetname "")
			)
			(fill
				(thermal_gap 0.5)
				(thermal_bridge_width 0.5)
				(island_removal_mode 0)
			)
			(polygon
				(pts
					(xy 409.346146 -21.599652) (xy 409.346146 -22.107652) (xy 408.965146 -22.107652) (xy 408.965146 -21.599652)
				)
			)
		)
	)
	(footprint ""
		(layer "B.Cu")
		(at 493.644428 -41.405048 180)
		(property "Reference" "R25W138"
			(at 0.8382 -0.67818 180)
			(unlocked yes)
			(layer "B.SilkS")
			(effects
				(font
					(size 0.4064 0.254)
					(thickness 0.1524)
				)
				(justify left mirror)
			)
		)
		(property "Value" ""
			(at 0 0 0)
			(layer "B.Fab")
			(effects
				(font
					(size 1.27 1.27)
				)
				(justify mirror)
			)
		)
		(duplicate_pad_numbers_are_jumpers no)
		(fp_poly
			(pts
				(xy 0.2794 -0.1016) (xy -0.2794 -0.1016) (xy -0.2794 0.9906) (xy 0.2794 0.9906)
			)
			(stroke
				(width 0)
				(type default)
			)
			(fill no)
			(layer "B.CrtYd")
		)
		(fp_line
			(start 0.2794 0.9906)
			(end -0.2794 0.9906)
			(stroke
				(width 0.1)
				(type default)
			)
			(layer "B.Fab")
		)
		(fp_line
			(start 0.2794 -0.1016)
			(end 0.2794 0.9906)
			(stroke
				(width 0.1)
				(type default)
			)
			(layer "B.Fab")
		)
		(fp_line
			(start -0.2794 0.9906)
			(end -0.2794 -0.1016)
			(stroke
				(width 0.1)
				(type default)
			)
			(layer "B.Fab")
		)
		(fp_line
			(start -0.2794 -0.1016)
			(end 0.2794 -0.1016)
			(stroke
				(width 0.1)
				(type default)
			)
			(layer "B.Fab")
		)
		(pad "1" smd rect
			(at 0 0)
			(size 0.508 0.508)
			(layers "B.Cu" "B.Mask" "B.Paste")
			(net "VGA_REAR_HSYNC_S")
		)
		(pad "2" smd rect
			(at 0 0.889)
			(size 0.508 0.508)
			(layers "B.Cu" "B.Mask" "B.Paste")
			(net "V_IO_HSYNC_J")
		)
		(zone
			(layer "B.Cu")
			(hatch none 0.5)
			(connect_pads
				(clearance 0)
			)
			(min_thickness 0.25)
			(keepout
				(tracks not_allowed)
				(vias allowed)
				(pads allowed)
				(copperpour not_allowed)
				(footprints allowed)
			)
			(placement
				(enabled no)
				(sheetname "")
			)
			(fill
				(thermal_gap 0.5)
				(thermal_bridge_width 0.5)
				(island_removal_mode 0)
			)
			(polygon
				(pts
					(xy 493.390428 -42.040048) (xy 493.898428 -42.040048) (xy 493.898428 -41.659048) (xy 493.390428 -41.659048)
				)
			)
		)
		(zone
			(layer "B.Cu")
			(hatch none 0.5)
			(connect_pads
				(clearance 0)
			)
			(min_thickness 0.25)
			(keepout
				(tracks allowed)
				(vias not_allowed)
				(pads allowed)
				(copperpour not_allowed)
				(footprints allowed)
			)
			(placement
				(enabled no)
				(sheetname "")
			)
			(fill
				(thermal_gap 0.5)
				(thermal_bridge_width 0.5)
				(island_removal_mode 0)
			)
			(polygon
				(pts
					(xy 493.390428 -41.659048) (xy 493.898428 -41.659048) (xy 493.898428 -42.040048) (xy 493.390428 -42.040048)
				)
			)
		)
	)
	(footprint ""
		(layer "B.Cu")
		(at 348.129606 -0.679704 -90)
		(property "Reference" "R3U9"
			(at 0 0 90)
			(layer "B.SilkS")
			(hide yes)
			(effects
				(font
					(size 1.27 1.27)
				)
				(justify mirror)
			)
		)
		(property "Value" ""
			(at 0 0 90)
			(layer "B.Fab")
			(effects
				(font
					(size 1.27 1.27)
				)
				(justify mirror)
			)
		)
		(duplicate_pad_numbers_are_jumpers no)
		(fp_rect
			(start -0.2794 0.9906)
			(end 0.2794 -0.1016)
			(stroke
				(width 0)
				(type default)
			)
			(fill no)
			(layer "B.CrtYd")
		)
		(fp_line
			(start -0.2794 0.9906)
			(end -0.2794 -0.1016)
			(stroke
				(width 0.1)
				(type default)
			)
			(layer "B.Fab")
		)
		(fp_line
			(start 0.2794 0.9906)
			(end -0.2794 0.9906)
			(stroke
				(width 0.1)
				(type default)
			)
			(layer "B.Fab")
		)
		(fp_line
			(start -0.2794 -0.1016)
			(end 0.2794 -0.1016)
			(stroke
				(width 0.1)
				(type default)
			)
			(layer "B.Fab")
		)
		(fp_line
			(start 0.2794 -0.1016)
			(end 0.2794 0.9906)
			(stroke
				(width 0.1)
				(type default)
			)
			(layer "B.Fab")
		)
		(pad "1" smd rect
			(at 0 0 90)
			(size 0.508 0.508)
			(layers "B.Cu" "B.Mask" "B.Paste")
			(net "VR_PVDDQ_ABC_PH2_VCIN")
		)
		(pad "2" smd rect
			(at 0 0.889 90)
			(size 0.508 0.508)
			(layers "B.Cu" "B.Mask" "B.Paste")
			(net "P5V_STBY")
		)
		(zone
			(layer "B.Cu")
			(hatch none 0.5)
			(connect_pads
				(clearance 0)
			)
			(min_thickness 0.25)
			(keepout
				(tracks not_allowed)
				(vias allowed)
				(pads allowed)
				(copperpour not_allowed)
				(footprints allowed)
			)
			(placement
				(enabled no)
				(sheetname "")
			)
			(fill
				(thermal_gap 0.5)
				(thermal_bridge_width 0.5)
				(island_removal_mode 0)
			)
			(polygon
				(pts
					(xy 347.494606 -0.933704) (xy 347.494606 -0.425704) (xy 347.875606 -0.425704) (xy 347.875606 -0.933704)
				)
			)
		)
		(zone
			(layer "B.Cu")
			(hatch none 0.5)
			(connect_pads
				(clearance 0)
			)
			(min_thickness 0.25)
			(keepout
				(tracks allowed)
				(vias not_allowed)
				(pads allowed)
				(copperpour not_allowed)
				(footprints allowed)
			)
			(placement
				(enabled no)
				(sheetname "")
			)
			(fill
				(thermal_gap 0.5)
				(thermal_bridge_width 0.5)
				(island_removal_mode 0)
			)
			(polygon
				(pts
					(xy 347.494606 -0.933704) (xy 347.494606 -0.425704) (xy 347.875606 -0.425704) (xy 347.875606 -0.933704)
				)
			)
		)
	)
	(footprint ""
		(layer "B.Cu")
		(at 405.8285 -22.987 -90)
		(property "Reference" "C25W62"
			(at -0.97536 0.76708 0)
			(unlocked yes)
			(layer "B.SilkS")
			(effects
				(font
					(size 0.4064 0.254)
					(thickness 0.1524)
				)
				(justify mirror)
			)
		)
		(property "Value" ""
			(at 0 0 90)
			(layer "B.Fab")
			(effects
				(font
					(size 1.27 1.27)
				)
				(justify mirror)
			)
		)
		(duplicate_pad_numbers_are_jumpers no)
		(fp_poly
			(pts
				(xy 0.4953 -0.2032) (xy -0.4953 -0.2032) (xy -0.4953 1.6002) (xy 0.4953 1.6002)
			)
			(stroke
				(width 0)
				(type default)
			)
			(fill no)
			(layer "B.CrtYd")
		)
		(fp_line
			(start -0.4953 1.6002)
			(end 0.4953 1.6002)
			(stroke
				(width 0.1)
				(type default)
			)
			(layer "B.Fab")
		)
		(fp_line
			(start 0.4953 1.6002)
			(end 0.4953 -0.2032)
			(stroke
				(width 0.1)
				(type default)
			)
			(layer "B.Fab")
		)
		(fp_line
			(start -0.4953 -0.2032)
			(end -0.4953 1.6002)
			(stroke
				(width 0.1)
				(type default)
			)
			(layer "B.Fab")
		)
		(fp_line
			(start 0.4953 -0.2032)
			(end -0.4953 -0.2032)
			(stroke
				(width 0.1)
				(type default)
			)
			(layer "B.Fab")
		)
		(pad "1" smd rect
			(at 0 0 90)
			(size 0.762 0.889)
			(layers "B.Cu" "B.Mask" "B.Paste")
			(net "P3V3_STBY")
		)
		(pad "2" smd rect
			(at 0 1.397 90)
			(size 0.762 0.889)
			(layers "B.Cu" "B.Mask" "B.Paste")
			(net "GND")
		)
		(zone
			(layer "B.Cu")
			(hatch none 0.5)
			(connect_pads
				(clearance 0)
			)
			(min_thickness 0.25)
			(keepout
				(tracks not_allowed)
				(vias allowed)
				(pads allowed)
				(copperpour not_allowed)
				(footprints allowed)
			)
			(placement
				(enabled no)
				(sheetname "")
			)
			(fill
				(thermal_gap 0.5)
				(thermal_bridge_width 0.5)
				(island_removal_mode 0)
			)
			(polygon
				(pts
					(xy 405.384 -22.606) (xy 405.384 -23.368) (xy 404.876 -23.368) (xy 404.876 -22.606)
				)
			)
		)
	)
	(footprint ""
		(layer "B.Cu")
		(at 39.307516 -106.085386 -90)
		(property "Reference" "R1C3"
			(at 0 0 90)
			(layer "B.SilkS")
			(hide yes)
			(effects
				(font
					(size 1.27 1.27)
				)
				(justify mirror)
			)
		)
		(property "Value" ""
			(at 0 0 90)
			(layer "B.Fab")
			(effects
				(font
					(size 1.27 1.27)
				)
				(justify mirror)
			)
		)
		(duplicate_pad_numbers_are_jumpers no)
		(fp_poly
			(pts
				(xy 0.2794 -0.1016) (xy -0.2794 -0.1016) (xy -0.2794 0.9906) (xy 0.2794 0.9906)
			)
			(stroke
				(width 0)
				(type default)
			)
			(fill no)
			(layer "B.CrtYd")
		)
		(fp_line
			(start -0.2794 0.9906)
			(end -0.2794 -0.1016)
			(stroke
				(width 0.1)
				(type default)
			)
			(layer "B.Fab")
		)
		(fp_line
			(start 0.2794 0.9906)
			(end -0.2794 0.9906)
			(stroke
				(width 0.1)
				(type default)
			)
			(layer "B.Fab")
		)
		(fp_line
			(start -0.2794 -0.1016)
			(end 0.2794 -0.1016)
			(stroke
				(width 0.1)
				(type default)
			)
			(layer "B.Fab")
		)
		(fp_line
			(start 0.2794 -0.1016)
			(end 0.2794 0.9906)
			(stroke
				(width 0.1)
				(type default)
			)
			(layer "B.Fab")
		)
		(pad "1" smd rect
			(at 0 0 90)
			(size 0.508 0.508)
			(layers "B.Cu" "B.Mask" "B.Paste")
			(net "SVID_CLK1_CPU1")
		)
		(pad "2" smd rect
			(at 0 0.889 90)
			(size 0.508 0.508)
			(layers "B.Cu" "B.Mask" "B.Paste")
			(net "SVID_CLK1_CPU1_R")
		)
		(zone
			(layer "B.Cu")
			(hatch none 0.5)
			(connect_pads
				(clearance 0)
			)
			(min_thickness 0.25)
			(keepout
				(tracks not_allowed)
				(vias allowed)
				(pads allowed)
				(copperpour not_allowed)
				(footprints allowed)
			)
			(placement
				(enabled no)
				(sheetname "")
			)
			(fill
				(thermal_gap 0.5)
				(thermal_bridge_width 0.5)
				(island_removal_mode 0)
			)
			(polygon
				(pts
					(xy 38.672516 -105.831386) (xy 38.672516 -106.339386) (xy 39.053516 -106.339386) (xy 39.053516 -105.831386)
				)
			)
		)
		(zone
			(layer "B.Cu")
			(hatch none 0.5)
			(connect_pads
				(clearance 0)
			)
			(min_thickness 0.25)
			(keepout
				(tracks allowed)
				(vias not_allowed)
				(pads allowed)
				(copperpour not_allowed)
				(footprints allowed)
			)
			(placement
				(enabled no)
				(sheetname "")
			)
			(fill
				(thermal_gap 0.5)
				(thermal_bridge_width 0.5)
				(island_removal_mode 0)
			)
			(polygon
				(pts
					(xy 39.053516 -105.831386) (xy 39.053516 -106.339386) (xy 38.672516 -106.339386) (xy 38.672516 -105.831386)
				)
			)
		)
	)
	(footprint ""
		(layer "B.Cu")
		(at 360.555794 -43.956986 90)
		(property "Reference" "R2T62"
			(at 0 0 90)
			(layer "B.SilkS")
			(hide yes)
			(effects
				(font
					(size 1.27 1.27)
				)
				(justify mirror)
			)
		)
		(property "Value" ""
			(at 0 0 90)
			(layer "B.Fab")
			(effects
				(font
					(size 1.27 1.27)
				)
				(justify mirror)
			)
		)
		(duplicate_pad_numbers_are_jumpers no)
		(fp_poly
			(pts
				(xy 0.2794 -0.1016) (xy -0.2794 -0.1016) (xy -0.2794 0.9906) (xy 0.2794 0.9906)
			)
			(stroke
				(width 0)
				(type default)
			)
			(fill no)
			(layer "B.CrtYd")
		)
		(fp_line
			(start 0.2794 -0.1016)
			(end 0.2794 0.9906)
			(stroke
				(width 0.1)
				(type default)
			)
			(layer "B.Fab")
		)
		(fp_line
			(start -0.2794 -0.1016)
			(end 0.2794 -0.1016)
			(stroke
				(width 0.1)
				(type default)
			)
			(layer "B.Fab")
		)
		(fp_line
			(start 0.2794 0.9906)
			(end -0.2794 0.9906)
			(stroke
				(width 0.1)
				(type default)
			)
			(layer "B.Fab")
		)
		(fp_line
			(start -0.2794 0.9906)
			(end -0.2794 -0.1016)
			(stroke
				(width 0.1)
				(type default)
			)
			(layer "B.Fab")
		)
		(pad "1" smd rect
			(at 0 0 270)
			(size 0.508 0.508)
			(layers "B.Cu" "B.Mask" "B.Paste")
			(net "H_CPU_ERR1_PCH_N")
		)
		(pad "2" smd rect
			(at 0 0.889 270)
			(size 0.508 0.508)
			(layers "B.Cu" "B.Mask" "B.Paste")
			(net "FM_CPU_ERR1_LVT3_K_N")
		)
		(zone
			(layer "B.Cu")
			(hatch none 0.5)
			(connect_pads
				(clearance 0)
			)
			(min_thickness 0.25)
			(keepout
				(tracks allowed)
				(vias not_allowed)
				(pads allowed)
				(copperpour not_allowed)
				(footprints allowed)
			)
			(placement
				(enabled no)
				(sheetname "")
			)
			(fill
				(thermal_gap 0.5)
				(thermal_bridge_width 0.5)
				(island_removal_mode 0)
			)
			(polygon
				(pts
					(xy 360.809794 -44.210986) (xy 360.809794 -43.702986) (xy 361.190794 -43.702986) (xy 361.190794 -44.210986)
				)
			)
		)
		(zone
			(layer "B.Cu")
			(hatch none 0.5)
			(connect_pads
				(clearance 0)
			)
			(min_thickness 0.25)
			(keepout
				(tracks not_allowed)
				(vias allowed)
				(pads allowed)
				(copperpour not_allowed)
				(footprints allowed)
			)
			(placement
				(enabled no)
				(sheetname "")
			)
			(fill
				(thermal_gap 0.5)
				(thermal_bridge_width 0.5)
				(island_removal_mode 0)
			)
			(polygon
				(pts
					(xy 361.190794 -44.210986) (xy 361.190794 -43.702986) (xy 360.809794 -43.702986) (xy 360.809794 -44.210986)
				)
			)
		)
	)
	(footprint ""
		(layer "B.Cu")
		(at 343.066878 -91.46413 -90)
		(property "Reference" "CF13"
			(at 0 0 90)
			(layer "B.SilkS")
			(hide yes)
			(effects
				(font
					(size 1.27 1.27)
				)
				(justify mirror)
			)
		)
		(property "Value" "*"
			(at -1.1811 -2.8194 270)
			(unlocked yes)
			(layer "B.Fab")
			(hide yes)
			(effects
				(font
					(size 1.27 1.016)
					(thickness 0.1524)
				)
				(justify mirror)
			)
		)
		(property "Device Type" "SC22P50V2JN-4GP_SMD-BCG-SC22P5A"
			(at -1.1811 -4.3434 270)
			(unlocked yes)
			(layer "B.Fab")
			(hide yes)
			(effects
				(font
					(size 1.27 1.016)
					(thickness 0.1524)
				)
				(justify mirror)
			)
		)
		(duplicate_pad_numbers_are_jumpers no)
		(fp_rect
			(start 0.4318 0.9525)
			(end -0.4318 -0.9525)
			(stroke
				(width 0)
				(type default)
			)
			(fill no)
			(layer "B.CrtYd")
		)
		(fp_rect
			(start 0.4318 0.9525)
			(end -0.4318 -0.9525)
			(stroke
				(width 0)
				(type default)
			)
			(fill no)
			(layer "B.Fab")
		)
		(pad "1" smd custom
			(at 0 -0.4445 90)
			(size 0.1524 0.1524)
			(layers "B.Cu" "B.Mask" "B.Paste")
			(net "VR_PVCCIO_CPU0_AIREF1")
			(options
				(clearance outline)
				(anchor circle)
			)
			(primitives
				(gr_poly
					(pts
						(arc
							(start 0.3048 0.2032)
							(mid 0.275042 0.275042)
							(end 0.2032 0.3048)
						)
						(arc
							(start -0.2032 0.3048)
							(mid -0.275042 0.275042)
							(end -0.3048 0.2032)
						)
						(arc
							(start -0.3048 -0.2032)
							(mid -0.275042 -0.275042)
							(end -0.2032 -0.3048)
						)
						(arc
							(start 0.2032 -0.3048)
							(mid 0.275042 -0.275042)
							(end 0.3048 -0.2032)
						)
					)
					(width 0)
					(fill yes)
				)
			)
		)
		(pad "2" smd custom
			(at 0 0.4445 90)
			(size 0.1524 0.1524)
			(layers "B.Cu" "B.Mask" "B.Paste")
			(net "ISENSE_PVCCIO_CPU0_PH1_IMON")
			(options
				(clearance outline)
				(anchor circle)
			)
			(primitives
				(gr_poly
					(pts
						(arc
							(start 0.3048 0.2032)
							(mid 0.275042 0.275042)
							(end 0.2032 0.3048)
						)
						(arc
							(start -0.2032 0.3048)
							(mid -0.275042 0.275042)
							(end -0.3048 0.2032)
						)
						(arc
							(start -0.3048 -0.2032)
							(mid -0.275042 -0.275042)
							(end -0.2032 -0.3048)
						)
						(arc
							(start 0.2032 -0.3048)
							(mid 0.275042 -0.275042)
							(end 0.3048 -0.2032)
						)
					)
					(width 0)
					(fill yes)
				)
			)
		)
	)
	(footprint ""
		(layer "B.Cu")
		(at 245.7323 -149.8092 -90)
		(property "Reference" "C5G59"
			(at -1.14681 0.76708 0)
			(unlocked yes)
			(layer "B.SilkS")
			(effects
				(font
					(size 0.7874 0.5842)
					(thickness 0.1524)
				)
				(justify mirror)
			)
		)
		(property "Value" ""
			(at 0 0 90)
			(layer "B.Fab")
			(effects
				(font
					(size 1.27 1.27)
				)
				(justify mirror)
			)
		)
		(duplicate_pad_numbers_are_jumpers no)
		(fp_rect
			(start 0.4953 1.6002)
			(end -0.4953 -0.2032)
			(stroke
				(width 0)
				(type default)
			)
			(fill no)
			(layer "B.CrtYd")
		)
		(fp_line
			(start -0.4953 1.6002)
			(end 0.4953 1.6002)
			(stroke
				(width 0.1)
				(type default)
			)
			(layer "B.Fab")
		)
		(fp_line
			(start 0.4953 1.6002)
			(end 0.4953 -0.2032)
			(stroke
				(width 0.1)
				(type default)
			)
			(layer "B.Fab")
		)
		(fp_line
			(start -0.4953 -0.2032)
			(end -0.4953 1.6002)
			(stroke
				(width 0.1)
				(type default)
			)
			(layer "B.Fab")
		)
		(fp_line
			(start 0.4953 -0.2032)
			(end -0.4953 -0.2032)
			(stroke
				(width 0.1)
				(type default)
			)
			(layer "B.Fab")
		)
		(pad "1" smd rect
			(at 0 0 90)
			(size 0.762 0.889)
			(layers "B.Cu" "B.Mask" "B.Paste")
			(net "PVDDQ_DEF")
		)
		(pad "2" smd rect
			(at 0 1.397 90)
			(size 0.762 0.889)
			(layers "B.Cu" "B.Mask" "B.Paste")
			(net "GND")
		)
		(zone
			(layer "B.Cu")
			(hatch none 0.5)
			(connect_pads
				(clearance 0)
			)
			(min_thickness 0.25)
			(keepout
				(tracks not_allowed)
				(vias allowed)
				(pads allowed)
				(copperpour not_allowed)
				(footprints allowed)
			)
			(placement
				(enabled no)
				(sheetname "")
			)
			(fill
				(thermal_gap 0.5)
				(thermal_bridge_width 0.5)
				(island_removal_mode 0)
			)
			(polygon
				(pts
					(xy 244.7798 -149.4282) (xy 245.2878 -149.4282) (xy 245.2878 -150.1902) (xy 244.7798 -150.1902)
				)
			)
		)
	)
	(footprint ""
		(layer "B.Cu")
		(at 185.25109 0.139192 180)
		(property "Reference" "C6U15"
			(at 0 0 0)
			(layer "B.SilkS")
			(hide yes)
			(effects
				(font
					(size 1.27 1.27)
				)
				(justify mirror)
			)
		)
		(property "Value" ""
			(at 0 0 0)
			(layer "B.Fab")
			(effects
				(font
					(size 1.27 1.27)
				)
				(justify mirror)
			)
		)
		(duplicate_pad_numbers_are_jumpers no)
		(fp_rect
			(start 0.4953 -0.2032)
			(end -0.4953 1.6002)
			(stroke
				(width 0)
				(type default)
			)
			(fill no)
			(layer "B.CrtYd")
		)
		(fp_line
			(start 0.4953 1.6002)
			(end 0.4953 -0.2032)
			(stroke
				(width 0.1)
				(type default)
			)
			(layer "B.Fab")
		)
		(fp_line
			(start 0.4953 -0.2032)
			(end -0.4953 -0.2032)
			(stroke
				(width 0.1)
				(type default)
			)
			(layer "B.Fab")
		)
		(fp_line
			(start -0.4953 1.6002)
			(end 0.4953 1.6002)
			(stroke
				(width 0.1)
				(type default)
			)
			(layer "B.Fab")
		)
		(fp_line
			(start -0.4953 -0.2032)
			(end -0.4953 1.6002)
			(stroke
				(width 0.1)
				(type default)
			)
			(layer "B.Fab")
		)
		(pad "1" smd rect
			(at 0 0)
			(size 0.762 0.889)
			(layers "B.Cu" "B.Mask" "B.Paste")
			(net "PVDDQ_ABC")
		)
		(pad "2" smd rect
			(at 0 1.397)
			(size 0.762 0.889)
			(layers "B.Cu" "B.Mask" "B.Paste")
			(net "GND")
		)
		(zone
			(layer "B.Cu")
			(hatch none 0.5)
			(connect_pads
				(clearance 0)
			)
			(min_thickness 0.25)
			(keepout
				(tracks not_allowed)
				(vias allowed)
				(pads allowed)
				(copperpour not_allowed)
				(footprints allowed)
			)
			(placement
				(enabled no)
				(sheetname "")
			)
			(fill
				(thermal_gap 0.5)
				(thermal_bridge_width 0.5)
				(island_removal_mode 0)
			)
			(polygon
				(pts
					(xy 184.87009 -0.305308) (xy 185.63209 -0.305308) (xy 185.63209 -0.813308) (xy 184.87009 -0.813308)
				)
			)
		)
	)
	(footprint ""
		(layer "B.Cu")
		(at 476.1738 -45.6438 -90)
		(property "Reference" "C22W34"
			(at 0 0 90)
			(layer "B.SilkS")
			(hide yes)
			(effects
				(font
					(size 1.27 1.27)
				)
				(justify mirror)
			)
		)
		(property "Value" "*"
			(at 0.0762 -6.2357 270)
			(unlocked yes)
			(layer "B.Fab")
			(hide yes)
			(effects
				(font
					(size 1.27 1.016)
					(thickness 0.1524)
				)
				(justify mirror)
			)
		)
		(property "Device Type" "SC22U16V5MX-4-GP_SMD-BCG5-SC22A"
			(at 0.0762 -8.2677 270)
			(unlocked yes)
			(layer "B.Fab")
			(hide yes)
			(effects
				(font
					(size 1.27 1.016)
					(thickness 0.1524)
				)
				(justify mirror)
			)
		)
		(duplicate_pad_numbers_are_jumpers no)
		(fp_line
			(start -0.635 0)
			(end 0.635 0)
			(stroke
				(width 0.508)
				(type default)
			)
			(layer "B.SilkS")
		)
		(fp_rect
			(start 0.9652 1.778)
			(end -0.9652 -1.778)
			(stroke
				(width 0)
				(type default)
			)
			(fill no)
			(layer "B.CrtYd")
		)
		(fp_poly
			(pts
				(xy 0.9652 -1.778) (xy -0.9652 -1.778) (xy -0.9652 1.778) (xy 0.9652 1.778)
			)
			(stroke
				(width 0)
				(type default)
			)
			(fill no)
			(layer "B.Fab")
		)
		(pad "1" smd rect
			(at 0 -0.9652 90)
			(size 1.397 1.143)
			(layers "B.Cu" "B.Mask" "B.Paste")
			(net "P3V3_STBY")
		)
		(pad "2" smd rect
			(at 0 0.9652 90)
			(size 1.397 1.143)
			(layers "B.Cu" "B.Mask" "B.Paste")
			(net "GND")
		)
	)
	(footprint ""
		(layer "B.Cu")
		(at 49.4284 -59.143392 180)
		(property "Reference" "C9R8"
			(at 0 0 0)
			(layer "B.SilkS")
			(hide yes)
			(effects
				(font
					(size 1.27 1.27)
				)
				(justify mirror)
			)
		)
		(property "Value" ""
			(at 0 0 0)
			(layer "B.Fab")
			(effects
				(font
					(size 1.27 1.27)
				)
				(justify mirror)
			)
		)
		(duplicate_pad_numbers_are_jumpers no)
		(fp_poly
			(pts
				(xy 0.4953 -0.2032) (xy -0.4953 -0.2032) (xy -0.4953 1.6002) (xy 0.4953 1.6002)
			)
			(stroke
				(width 0)
				(type default)
			)
			(fill no)
			(layer "B.CrtYd")
		)
		(fp_line
			(start 0.4953 1.6002)
			(end 0.4953 -0.2032)
			(stroke
				(width 0.1)
				(type default)
			)
			(layer "B.Fab")
		)
		(fp_line
			(start 0.4953 -0.2032)
			(end -0.4953 -0.2032)
			(stroke
				(width 0.1)
				(type default)
			)
			(layer "B.Fab")
		)
		(fp_line
			(start -0.4953 1.6002)
			(end 0.4953 1.6002)
			(stroke
				(width 0.1)
				(type default)
			)
			(layer "B.Fab")
		)
		(fp_line
			(start -0.4953 -0.2032)
			(end -0.4953 1.6002)
			(stroke
				(width 0.1)
				(type default)
			)
			(layer "B.Fab")
		)
		(pad "1" smd rect
			(at 0 0)
			(size 0.762 0.889)
			(layers "B.Cu" "B.Mask" "B.Paste")
			(net "PVCCIN_CPU1")
		)
		(pad "2" smd rect
			(at 0 1.397)
			(size 0.762 0.889)
			(layers "B.Cu" "B.Mask" "B.Paste")
			(net "GND")
		)
		(zone
			(layer "B.Cu")
			(hatch none 0.5)
			(connect_pads
				(clearance 0)
			)
			(min_thickness 0.25)
			(keepout
				(tracks not_allowed)
				(vias allowed)
				(pads allowed)
				(copperpour not_allowed)
				(footprints allowed)
			)
			(placement
				(enabled no)
				(sheetname "")
			)
			(fill
				(thermal_gap 0.5)
				(thermal_bridge_width 0.5)
				(island_removal_mode 0)
			)
			(polygon
				(pts
					(xy 49.0474 -59.587892) (xy 49.8094 -59.587892) (xy 49.8094 -60.095892) (xy 49.0474 -60.095892)
				)
			)
		)
	)
	(footprint ""
		(layer "B.Cu")
		(at 440.284362 -32.184848 180)
		(property "Reference" "C1W20"
			(at 0.8382 -0.67818 180)
			(unlocked yes)
			(layer "B.SilkS")
			(effects
				(font
					(size 0.4064 0.254)
					(thickness 0.1524)
				)
				(justify left mirror)
			)
		)
		(property "Value" ""
			(at 0 0 0)
			(layer "B.Fab")
			(effects
				(font
					(size 1.27 1.27)
				)
				(justify mirror)
			)
		)
		(duplicate_pad_numbers_are_jumpers no)
		(fp_poly
			(pts
				(xy -0.3048 -0.1016) (xy -0.3048 0.9906) (xy 0.3048 0.9906) (xy 0.3048 -0.1016)
			)
			(stroke
				(width 0)
				(type default)
			)
			(fill no)
			(layer "B.CrtYd")
		)
		(fp_line
			(start 0.3048 0.9906)
			(end -0.3048 0.9906)
			(stroke
				(width 0.1)
				(type default)
			)
			(layer "B.Fab")
		)
		(fp_line
			(start 0.3048 -0.1016)
			(end 0.3048 0.9906)
			(stroke
				(width 0.1)
				(type default)
			)
			(layer "B.Fab")
		)
		(fp_line
			(start -0.3048 0.9906)
			(end -0.3048 -0.1016)
			(stroke
				(width 0.1)
				(type default)
			)
			(layer "B.Fab")
		)
		(fp_line
			(start -0.3048 -0.1016)
			(end 0.3048 -0.1016)
			(stroke
				(width 0.1)
				(type default)
			)
			(layer "B.Fab")
		)
		(pad "1" smd rect
			(at 0 0)
			(size 0.508 0.508)
			(layers "B.Cu" "B.Mask" "B.Paste")
			(net "BMC_M_CLK")
		)
		(pad "2" smd rect
			(at 0 0.889)
			(size 0.508 0.508)
			(layers "B.Cu" "B.Mask" "B.Paste")
			(net "GND")
		)
		(zone
			(layer "B.Cu")
			(hatch none 0.5)
			(connect_pads
				(clearance 0)
			)
			(min_thickness 0.25)
			(keepout
				(tracks not_allowed)
				(vias allowed)
				(pads allowed)
				(copperpour not_allowed)
				(footprints allowed)
			)
			(placement
				(enabled no)
				(sheetname "")
			)
			(fill
				(thermal_gap 0.5)
				(thermal_bridge_width 0.5)
				(island_removal_mode 0)
			)
			(polygon
				(pts
					(xy 440.030362 -32.819848) (xy 440.538362 -32.819848) (xy 440.538362 -32.438848) (xy 440.030362 -32.438848)
				)
			)
		)
		(zone
			(layer "B.Cu")
			(hatch none 0.5)
			(connect_pads
				(clearance 0)
			)
			(min_thickness 0.25)
			(keepout
				(tracks allowed)
				(vias not_allowed)
				(pads allowed)
				(copperpour not_allowed)
				(footprints allowed)
			)
			(placement
				(enabled no)
				(sheetname "")
			)
			(fill
				(thermal_gap 0.5)
				(thermal_bridge_width 0.5)
				(island_removal_mode 0)
			)
			(polygon
				(pts
					(xy 440.030362 -32.438848) (xy 440.538362 -32.438848) (xy 440.538362 -32.819848) (xy 440.030362 -32.819848)
				)
			)
		)
	)
	(footprint ""
		(layer "B.Cu")
		(at 443.405006 -43.54195 180)
		(property "Reference" "R25W42"
			(at 0 0 0)
			(layer "B.SilkS")
			(hide yes)
			(effects
				(font
					(size 1.27 1.27)
				)
				(justify mirror)
			)
		)
		(property "Value" "*"
			(at -0.064008 -4.108196 180)
			(unlocked yes)
			(layer "B.Fab")
			(hide yes)
			(effects
				(font
					(size 1.27 1.016)
					(thickness 0.1524)
				)
				(justify mirror)
			)
		)
		(property "Device Type" "120R2F-GP_RCL_GP-120R2F-GP,64.A"
			(at -0.064008 -5.632196 180)
			(unlocked yes)
			(layer "B.Fab")
			(hide yes)
			(effects
				(font
					(size 1.27 1.016)
					(thickness 0.1524)
				)
				(justify mirror)
			)
		)
		(duplicate_pad_numbers_are_jumpers no)
		(fp_line
			(start 0.508 -0.9398)
			(end 0.508 0.9398)
			(stroke
				(width 0.1524)
				(type default)
			)
			(layer "B.SilkS")
		)
		(fp_line
			(start -0.508 -0.9398)
			(end 0.508 -0.9398)
			(stroke
				(width 0.1524)
				(type default)
			)
			(layer "B.SilkS")
		)
		(fp_rect
			(start 0.508 0.9398)
			(end -0.508 -0.9398)
			(stroke
				(width 0)
				(type default)
			)
			(fill no)
			(layer "B.CrtYd")
		)
		(fp_rect
			(start 0.508 0.9398)
			(end -0.508 -0.9398)
			(stroke
				(width 0)
				(type default)
			)
			(fill no)
			(layer "B.Fab")
		)
		(pad "1" smd custom
			(at 0 -0.4445)
			(size 0.1397 0.1397)
			(layers "B.Cu" "B.Mask" "B.Paste")
			(net "BMC_M_A4")
			(options
				(clearance outline)
				(anchor circle)
			)
			(primitives
				(gr_poly
					(pts
						(arc
							(start -0.1778 0.2794)
							(mid -0.249642 0.249642)
							(end -0.2794 0.1778)
						)
						(arc
							(start -0.2794 -0.1778)
							(mid -0.249642 -0.249642)
							(end -0.1778 -0.2794)
						)
						(arc
							(start 0.1778 -0.2794)
							(mid 0.249642 -0.249642)
							(end 0.2794 -0.1778)
						)
						(arc
							(start 0.2794 0.1778)
							(mid 0.249642 0.249642)
							(end 0.1778 0.2794)
						)
					)
					(width 0)
					(fill yes)
				)
			)
		)
		(pad "2" smd custom
			(at 0 0.4445)
			(size 0.1397 0.1397)
			(layers "B.Cu" "B.Mask" "B.Paste")
			(net "P1V2_AUX_BMC")
			(options
				(clearance outline)
				(anchor circle)
			)
			(primitives
				(gr_poly
					(pts
						(arc
							(start -0.1778 0.2794)
							(mid -0.249642 0.249642)
							(end -0.2794 0.1778)
						)
						(arc
							(start -0.2794 -0.1778)
							(mid -0.249642 -0.249642)
							(end -0.1778 -0.2794)
						)
						(arc
							(start 0.1778 -0.2794)
							(mid 0.249642 -0.249642)
							(end 0.2794 -0.1778)
						)
						(arc
							(start 0.2794 0.1778)
							(mid 0.249642 0.249642)
							(end 0.1778 0.2794)
						)
					)
					(width 0)
					(fill yes)
				)
			)
		)
	)
	(footprint ""
		(layer "B.Cu")
		(at 348.5134 -150.387304 -90)
		(property "Reference" "C3L13"
			(at 0 0 90)
			(layer "B.SilkS")
			(hide yes)
			(effects
				(font
					(size 1.27 1.27)
				)
				(justify mirror)
			)
		)
		(property "Value" ""
			(at 0 0 90)
			(layer "B.Fab")
			(effects
				(font
					(size 1.27 1.27)
				)
				(justify mirror)
			)
		)
		(duplicate_pad_numbers_are_jumpers no)
		(fp_poly
			(pts
				(xy 0.7239 -0.2159) (xy -0.7239 -0.2159) (xy -0.7239 1.9939) (xy 0.7239 1.9939)
			)
			(stroke
				(width 0)
				(type default)
			)
			(fill no)
			(layer "B.CrtYd")
		)
		(fp_line
			(start -0.7239 1.9939)
			(end -0.7239 -0.2159)
			(stroke
				(width 0.1)
				(type default)
			)
			(layer "B.Fab")
		)
		(fp_line
			(start 0.7239 1.9939)
			(end -0.7239 1.9939)
			(stroke
				(width 0.1)
				(type default)
			)
			(layer "B.Fab")
		)
		(fp_line
			(start -0.7239 -0.2159)
			(end 0.7239 -0.2159)
			(stroke
				(width 0.1)
				(type default)
			)
			(layer "B.Fab")
		)
		(fp_line
			(start 0.7239 -0.2159)
			(end 0.7239 1.9939)
			(stroke
				(width 0.1)
				(type default)
			)
			(layer "B.Fab")
		)
		(pad "1" smd rect
			(at 0 0 90)
			(size 1.27 1.016)
			(layers "B.Cu" "B.Mask" "B.Paste")
			(net "VR_FET_SW_P12V_STBY_PVDDQ_DEF")
		)
		(pad "2" smd rect
			(at 0 1.778 90)
			(size 1.27 1.016)
			(layers "B.Cu" "B.Mask" "B.Paste")
			(net "GND")
		)
		(zone
			(layer "B.Cu")
			(hatch none 0.5)
			(connect_pads
				(clearance 0)
			)
			(min_thickness 0.25)
			(keepout
				(tracks not_allowed)
				(vias allowed)
				(pads allowed)
				(copperpour not_allowed)
				(footprints allowed)
			)
			(placement
				(enabled no)
				(sheetname "")
			)
			(fill
				(thermal_gap 0.5)
				(thermal_bridge_width 0.5)
				(island_removal_mode 0)
			)
			(polygon
				(pts
					(xy 348.0054 -149.752304) (xy 348.0054 -151.022304) (xy 347.2434 -151.022304) (xy 347.2434 -149.752304)
				)
			)
		)
	)
	(footprint ""
		(layer "B.Cu")
		(at 17.9832 -19.6342 -90)
		(property "Reference" "C9T5"
			(at -3.02133 8.255 0)
			(unlocked yes)
			(layer "B.SilkS")
			(effects
				(font
					(size 0.7874 0.5842)
					(thickness 0.1524)
				)
				(justify mirror)
			)
		)
		(property "Value" ""
			(at 0 0 90)
			(layer "B.Fab")
			(effects
				(font
					(size 1.27 1.27)
				)
				(justify mirror)
			)
		)
		(duplicate_pad_numbers_are_jumpers no)
		(fp_line
			(start -2.286 7.366)
			(end -1.600708 7.366)
			(stroke
				(width 0.1524)
				(type default)
			)
			(layer "B.SilkS")
		)
		(fp_line
			(start -2.286 7.366)
			(end -2.286 1.63195)
			(stroke
				(width 0.1524)
				(type default)
			)
			(layer "B.SilkS")
		)
		(fp_line
			(start 2.286 7.366)
			(end 1.60147 7.366)
			(stroke
				(width 0.1524)
				(type default)
			)
			(layer "B.SilkS")
		)
		(fp_line
			(start 2.286 7.366)
			(end 2.286 1.632712)
			(stroke
				(width 0.1524)
				(type default)
			)
			(layer "B.SilkS")
		)
		(fp_line
			(start -2.504948 1.633728)
			(end -1.6002 1.633728)
			(stroke
				(width 0.1524)
				(type default)
			)
			(layer "B.SilkS")
		)
		(fp_line
			(start 2.563114 1.633728)
			(end 1.6002 1.633728)
			(stroke
				(width 0.1524)
				(type default)
			)
			(layer "B.SilkS")
		)
		(fp_line
			(start -2.504948 -1.616456)
			(end -2.504948 1.633728)
			(stroke
				(width 0.1524)
				(type default)
			)
			(layer "B.SilkS")
		)
		(fp_line
			(start -1.6002 -1.616456)
			(end -2.504948 -1.616456)
			(stroke
				(width 0.1524)
				(type default)
			)
			(layer "B.SilkS")
		)
		(fp_line
			(start 1.6002 -1.616456)
			(end 2.563114 -1.616456)
			(stroke
				(width 0.1524)
				(type default)
			)
			(layer "B.SilkS")
		)
		(fp_line
			(start 2.563114 -1.616456)
			(end 2.563114 1.633728)
			(stroke
				(width 0.1524)
				(type default)
			)
			(layer "B.SilkS")
		)
		(fp_rect
			(start 2.286 -0.254)
			(end -2.286 7.366)
			(stroke
				(width 0)
				(type default)
			)
			(fill no)
			(layer "B.CrtYd")
		)
		(fp_line
			(start -2.286 7.366)
			(end 2.286 7.366)
			(stroke
				(width 0.1)
				(type default)
			)
			(layer "B.Fab")
		)
		(fp_line
			(start 2.286 7.366)
			(end 2.286 -0.254)
			(stroke
				(width 0.1)
				(type default)
			)
			(layer "B.Fab")
		)
		(fp_line
			(start -2.286 -0.254)
			(end -2.286 7.366)
			(stroke
				(width 0.1)
				(type default)
			)
			(layer "B.Fab")
		)
		(fp_line
			(start 2.286 -0.254)
			(end -2.286 -0.254)
			(stroke
				(width 0.1)
				(type default)
			)
			(layer "B.Fab")
		)
		(pad "1" smd rect
			(at 0 0 90)
			(size 2.54 3.048)
			(layers "B.Cu" "B.Mask" "B.Paste")
			(net "PVDDQ_GHJ")
		)
		(pad "2" smd rect
			(at 0 7.112 90)
			(size 2.54 3.048)
			(layers "B.Cu" "B.Mask" "B.Paste")
			(net "GND")
		)
	)
	(footprint ""
		(layer "B.Cu")
		(at 404.483062 -1.524508)
		(property "Reference" "C1L119"
			(at 0.8382 -0.67818 0)
			(unlocked yes)
			(layer "B.SilkS")
			(effects
				(font
					(size 0.4064 0.254)
					(thickness 0.1524)
				)
				(justify left mirror)
			)
		)
		(property "Value" ""
			(at 0 0 0)
			(layer "B.Fab")
			(effects
				(font
					(size 1.27 1.27)
				)
				(justify mirror)
			)
		)
		(duplicate_pad_numbers_are_jumpers no)
		(fp_poly
			(pts
				(xy -0.3048 -0.1016) (xy -0.3048 0.9906) (xy 0.3048 0.9906) (xy 0.3048 -0.1016)
			)
			(stroke
				(width 0)
				(type default)
			)
			(fill no)
			(layer "B.CrtYd")
		)
		(fp_line
			(start -0.3048 -0.1016)
			(end 0.3048 -0.1016)
			(stroke
				(width 0.1)
				(type default)
			)
			(layer "B.Fab")
		)
		(fp_line
			(start -0.3048 0.9906)
			(end -0.3048 -0.1016)
			(stroke
				(width 0.1)
				(type default)
			)
			(layer "B.Fab")
		)
		(fp_line
			(start 0.3048 -0.1016)
			(end 0.3048 0.9906)
			(stroke
				(width 0.1)
				(type default)
			)
			(layer "B.Fab")
		)
		(fp_line
			(start 0.3048 0.9906)
			(end -0.3048 0.9906)
			(stroke
				(width 0.1)
				(type default)
			)
			(layer "B.Fab")
		)
		(pad "1" smd rect
			(at 0 0 180)
			(size 0.508 0.508)
			(layers "B.Cu" "B.Mask" "B.Paste")
			(net "P3V3_STBY")
		)
		(pad "2" smd rect
			(at 0 0.889 180)
			(size 0.508 0.508)
			(layers "B.Cu" "B.Mask" "B.Paste")
			(net "GND")
		)
		(zone
			(layer "B.Cu")
			(hatch none 0.5)
			(connect_pads
				(clearance 0)
			)
			(min_thickness 0.25)
			(keepout
				(tracks allowed)
				(vias not_allowed)
				(pads allowed)
				(copperpour not_allowed)
				(footprints allowed)
			)
			(placement
				(enabled no)
				(sheetname "")
			)
			(fill
				(thermal_gap 0.5)
				(thermal_bridge_width 0.5)
				(island_removal_mode 0)
			)
			(polygon
				(pts
					(xy 404.737062 -1.270508) (xy 404.229062 -1.270508) (xy 404.229062 -0.889508) (xy 404.737062 -0.889508)
				)
			)
		)
		(zone
			(layer "B.Cu")
			(hatch none 0.5)
			(connect_pads
				(clearance 0)
			)
			(min_thickness 0.25)
			(keepout
				(tracks not_allowed)
				(vias allowed)
				(pads allowed)
				(copperpour not_allowed)
				(footprints allowed)
			)
			(placement
				(enabled no)
				(sheetname "")
			)
			(fill
				(thermal_gap 0.5)
				(thermal_bridge_width 0.5)
				(island_removal_mode 0)
			)
			(polygon
				(pts
					(xy 404.737062 -0.889508) (xy 404.229062 -0.889508) (xy 404.229062 -1.270508) (xy 404.737062 -1.270508)
				)
			)
		)
	)
	(footprint ""
		(layer "B.Cu")
		(at 111.381032 -135.4074 90)
		(property "Reference" "C7M1"
			(at -1.848866 0.752348 90)
			(unlocked yes)
			(layer "B.SilkS")
			(effects
				(font
					(size 1.27 0.9652)
					(thickness 0.1524)
				)
				(justify mirror)
			)
		)
		(property "Value" ""
			(at 0 0 90)
			(layer "B.Fab")
			(effects
				(font
					(size 1.27 1.27)
				)
				(justify mirror)
			)
		)
		(duplicate_pad_numbers_are_jumpers no)
		(fp_rect
			(start 0.500126 1.598422)
			(end -0.500126 -0.201422)
			(stroke
				(width 0)
				(type default)
			)
			(fill no)
			(layer "B.CrtYd")
		)
		(fp_line
			(start 0.500126 -0.201422)
			(end -0.500126 -0.201422)
			(stroke
				(width 0.1)
				(type default)
			)
			(layer "B.Fab")
		)
		(fp_line
			(start -0.500126 -0.201422)
			(end -0.500126 1.598422)
			(stroke
				(width 0.1)
				(type default)
			)
			(layer "B.Fab")
		)
		(fp_line
			(start 0.500126 1.598422)
			(end 0.500126 -0.201422)
			(stroke
				(width 0.1)
				(type default)
			)
			(layer "B.Fab")
		)
		(fp_line
			(start -0.500126 1.598422)
			(end 0.500126 1.598422)
			(stroke
				(width 0.1)
				(type default)
			)
			(layer "B.Fab")
		)
		(pad "1" smd rect
			(at 0 0)
			(size 0.889 0.9906)
			(layers "B.Cu" "B.Mask" "B.Paste")
			(net "PVDDQ_KLM")
		)
		(pad "2" smd rect
			(at 0 1.397)
			(size 0.889 0.9906)
			(layers "B.Cu" "B.Mask" "B.Paste")
			(net "GND")
		)
		(zone
			(layer "B.Cu")
			(hatch none 0.5)
			(connect_pads
				(clearance 0)
			)
			(min_thickness 0.25)
			(keepout
				(tracks allowed)
				(vias not_allowed)
				(pads allowed)
				(copperpour not_allowed)
				(footprints allowed)
			)
			(placement
				(enabled no)
				(sheetname "")
			)
			(fill
				(thermal_gap 0.5)
				(thermal_bridge_width 0.5)
				(island_removal_mode 0)
			)
			(polygon
				(pts
					(xy 112.333532 -135.9027) (xy 111.825532 -135.9027) (xy 111.825532 -134.9121) (xy 112.333532 -134.9121)
				)
			)
		)
		(zone
			(layer "B.Cu")
			(hatch none 0.5)
			(connect_pads
				(clearance 0)
			)
			(min_thickness 0.25)
			(keepout
				(tracks not_allowed)
				(vias allowed)
				(pads allowed)
				(copperpour not_allowed)
				(footprints allowed)
			)
			(placement
				(enabled no)
				(sheetname "")
			)
			(fill
				(thermal_gap 0.5)
				(thermal_bridge_width 0.5)
				(island_removal_mode 0)
			)
			(polygon
				(pts
					(xy 112.333532 -135.9027) (xy 111.825532 -135.9027) (xy 111.825532 -134.9121) (xy 112.333532 -134.9121)
				)
			)
		)
	)
	(footprint ""
		(layer "B.Cu")
		(at 394.589 -85.9155)
		(property "Reference" "R2U12"
			(at 0 0 0)
			(layer "B.SilkS")
			(hide yes)
			(effects
				(font
					(size 1.27 1.27)
				)
				(justify mirror)
			)
		)
		(property "Value" ""
			(at 0 0 0)
			(layer "B.Fab")
			(effects
				(font
					(size 1.27 1.27)
				)
				(justify mirror)
			)
		)
		(duplicate_pad_numbers_are_jumpers no)
		(fp_poly
			(pts
				(xy 0.2794 -0.1016) (xy -0.2794 -0.1016) (xy -0.2794 0.9906) (xy 0.2794 0.9906)
			)
			(stroke
				(width 0)
				(type default)
			)
			(fill no)
			(layer "B.CrtYd")
		)
		(fp_line
			(start -0.2794 -0.1016)
			(end 0.2794 -0.1016)
			(stroke
				(width 0.1)
				(type default)
			)
			(layer "B.Fab")
		)
		(fp_line
			(start -0.2794 0.9906)
			(end -0.2794 -0.1016)
			(stroke
				(width 0.1)
				(type default)
			)
			(layer "B.Fab")
		)
		(fp_line
			(start 0.2794 -0.1016)
			(end 0.2794 0.9906)
			(stroke
				(width 0.1)
				(type default)
			)
			(layer "B.Fab")
		)
		(fp_line
			(start 0.2794 0.9906)
			(end -0.2794 0.9906)
			(stroke
				(width 0.1)
				(type default)
			)
			(layer "B.Fab")
		)
		(pad "1" smd rect
			(at 0 0 180)
			(size 0.508 0.508)
			(layers "B.Cu" "B.Mask" "B.Paste")
			(net "SMB_LAN_STBY_LVC3_SDA")
		)
		(pad "2" smd rect
			(at 0 0.889 180)
			(size 0.508 0.508)
			(layers "B.Cu" "B.Mask" "B.Paste")
			(net "SMB_OCP_FRU_STBY_LVC3_SDA")
		)
		(zone
			(layer "B.Cu")
			(hatch none 0.5)
			(connect_pads
				(clearance 0)
			)
			(min_thickness 0.25)
			(keepout
				(tracks allowed)
				(vias not_allowed)
				(pads allowed)
				(copperpour not_allowed)
				(footprints allowed)
			)
			(placement
				(enabled no)
				(sheetname "")
			)
			(fill
				(thermal_gap 0.5)
				(thermal_bridge_width 0.5)
				(island_removal_mode 0)
			)
			(polygon
				(pts
					(xy 394.843 -85.6615) (xy 394.335 -85.6615) (xy 394.335 -85.2805) (xy 394.843 -85.2805)
				)
			)
		)
		(zone
			(layer "B.Cu")
			(hatch none 0.5)
			(connect_pads
				(clearance 0)
			)
			(min_thickness 0.25)
			(keepout
				(tracks not_allowed)
				(vias allowed)
				(pads allowed)
				(copperpour not_allowed)
				(footprints allowed)
			)
			(placement
				(enabled no)
				(sheetname "")
			)
			(fill
				(thermal_gap 0.5)
				(thermal_bridge_width 0.5)
				(island_removal_mode 0)
			)
			(polygon
				(pts
					(xy 394.843 -85.2805) (xy 394.335 -85.2805) (xy 394.335 -85.6615) (xy 394.843 -85.6615)
				)
			)
		)
	)
	(footprint ""
		(layer "B.Cu")
		(at 400.7485 -106.172 -90)
		(property "Reference" "C2N26"
			(at 0 0 90)
			(layer "B.SilkS")
			(hide yes)
			(effects
				(font
					(size 1.27 1.27)
				)
				(justify mirror)
			)
		)
		(property "Value" ""
			(at 0 0 90)
			(layer "B.Fab")
			(effects
				(font
					(size 1.27 1.27)
				)
				(justify mirror)
			)
		)
		(duplicate_pad_numbers_are_jumpers no)
		(fp_poly
			(pts
				(xy -0.3048 -0.1016) (xy -0.3048 0.9906) (xy 0.3048 0.9906) (xy 0.3048 -0.1016)
			)
			(stroke
				(width 0)
				(type default)
			)
			(fill no)
			(layer "B.CrtYd")
		)
		(fp_line
			(start -0.3048 0.9906)
			(end -0.3048 -0.1016)
			(stroke
				(width 0.1)
				(type default)
			)
			(layer "B.Fab")
		)
		(fp_line
			(start 0.3048 0.9906)
			(end -0.3048 0.9906)
			(stroke
				(width 0.1)
				(type default)
			)
			(layer "B.Fab")
		)
		(fp_line
			(start -0.3048 -0.1016)
			(end 0.3048 -0.1016)
			(stroke
				(width 0.1)
				(type default)
			)
			(layer "B.Fab")
		)
		(fp_line
			(start 0.3048 -0.1016)
			(end 0.3048 0.9906)
			(stroke
				(width 0.1)
				(type default)
			)
			(layer "B.Fab")
		)
		(pad "1" smd rect
			(at 0 0 90)
			(size 0.508 0.508)
			(layers "B.Cu" "B.Mask" "B.Paste")
			(net "P3V3_STBY")
		)
		(pad "2" smd rect
			(at 0 0.889 90)
			(size 0.508 0.508)
			(layers "B.Cu" "B.Mask" "B.Paste")
			(net "GND")
		)
		(zone
			(layer "B.Cu")
			(hatch none 0.5)
			(connect_pads
				(clearance 0)
			)
			(min_thickness 0.25)
			(keepout
				(tracks not_allowed)
				(vias allowed)
				(pads allowed)
				(copperpour not_allowed)
				(footprints allowed)
			)
			(placement
				(enabled no)
				(sheetname "")
			)
			(fill
				(thermal_gap 0.5)
				(thermal_bridge_width 0.5)
				(island_removal_mode 0)
			)
			(polygon
				(pts
					(xy 400.1135 -105.918) (xy 400.1135 -106.426) (xy 400.4945 -106.426) (xy 400.4945 -105.918)
				)
			)
		)
		(zone
			(layer "B.Cu")
			(hatch none 0.5)
			(connect_pads
				(clearance 0)
			)
			(min_thickness 0.25)
			(keepout
				(tracks allowed)
				(vias not_allowed)
				(pads allowed)
				(copperpour not_allowed)
				(footprints allowed)
			)
			(placement
				(enabled no)
				(sheetname "")
			)
			(fill
				(thermal_gap 0.5)
				(thermal_bridge_width 0.5)
				(island_removal_mode 0)
			)
			(polygon
				(pts
					(xy 400.4945 -105.918) (xy 400.4945 -106.426) (xy 400.1135 -106.426) (xy 400.1135 -105.918)
				)
			)
		)
	)
	(footprint ""
		(layer "B.Cu")
		(at 446.381632 -37.032692 90)
		(property "Reference" "R25W12"
			(at 0 0 90)
			(layer "B.SilkS")
			(hide yes)
			(effects
				(font
					(size 1.27 1.27)
				)
				(justify mirror)
			)
		)
		(property "Value" "*"
			(at -0.064008 -4.108196 90)
			(unlocked yes)
			(layer "B.Fab")
			(hide yes)
			(effects
				(font
					(size 1.27 1.016)
					(thickness 0.1524)
				)
				(justify mirror)
			)
		)
		(property "Device Type" "120R2F-GP_RCL_GP-120R2F-GP,64.A"
			(at -0.064008 -5.632196 90)
			(unlocked yes)
			(layer "B.Fab")
			(hide yes)
			(effects
				(font
					(size 1.27 1.016)
					(thickness 0.1524)
				)
				(justify mirror)
			)
		)
		(duplicate_pad_numbers_are_jumpers no)
		(fp_line
			(start 0.508 -0.9398)
			(end 0.508 0.9398)
			(stroke
				(width 0.1524)
				(type default)
			)
			(layer "B.SilkS")
		)
		(fp_line
			(start -0.508 -0.9398)
			(end 0.508 -0.9398)
			(stroke
				(width 0.1524)
				(type default)
			)
			(layer "B.SilkS")
		)
		(fp_rect
			(start 0.508 0.9398)
			(end -0.508 -0.9398)
			(stroke
				(width 0)
				(type default)
			)
			(fill no)
			(layer "B.CrtYd")
		)
		(fp_rect
			(start 0.508 0.9398)
			(end -0.508 -0.9398)
			(stroke
				(width 0)
				(type default)
			)
			(fill no)
			(layer "B.Fab")
		)
		(pad "1" smd custom
			(at 0 -0.4445 270)
			(size 0.1397 0.1397)
			(layers "B.Cu" "B.Mask" "B.Paste")
			(net "GND")
			(options
				(clearance outline)
				(anchor circle)
			)
			(primitives
				(gr_poly
					(pts
						(arc
							(start -0.1778 0.2794)
							(mid -0.249642 0.249642)
							(end -0.2794 0.1778)
						)
						(arc
							(start -0.2794 -0.1778)
							(mid -0.249642 -0.249642)
							(end -0.1778 -0.2794)
						)
						(arc
							(start 0.1778 -0.2794)
							(mid 0.249642 -0.249642)
							(end 0.2794 -0.1778)
						)
						(arc
							(start 0.2794 0.1778)
							(mid 0.249642 0.249642)
							(end 0.1778 0.2794)
						)
					)
					(width 0)
					(fill yes)
				)
			)
		)
		(pad "2" smd custom
			(at 0 0.4445 270)
			(size 0.1397 0.1397)
			(layers "B.Cu" "B.Mask" "B.Paste")
			(net "BMC_M_A0")
			(options
				(clearance outline)
				(anchor circle)
			)
			(primitives
				(gr_poly
					(pts
						(arc
							(start -0.1778 0.2794)
							(mid -0.249642 0.249642)
							(end -0.2794 0.1778)
						)
						(arc
							(start -0.2794 -0.1778)
							(mid -0.249642 -0.249642)
							(end -0.1778 -0.2794)
						)
						(arc
							(start 0.1778 -0.2794)
							(mid 0.249642 -0.249642)
							(end 0.2794 -0.1778)
						)
						(arc
							(start 0.2794 0.1778)
							(mid 0.249642 0.249642)
							(end 0.1778 0.2794)
						)
					)
					(width 0)
					(fill yes)
				)
			)
		)
	)
	(footprint ""
		(layer "B.Cu")
		(at 1.3462 -148.336 90)
		(property "Reference" "C9L14"
			(at 0 0 90)
			(layer "B.SilkS")
			(hide yes)
			(effects
				(font
					(size 1.27 1.27)
				)
				(justify mirror)
			)
		)
		(property "Value" ""
			(at 0 0 90)
			(layer "B.Fab")
			(effects
				(font
					(size 1.27 1.27)
				)
				(justify mirror)
			)
		)
		(duplicate_pad_numbers_are_jumpers no)
		(fp_rect
			(start -0.7239 -0.2159)
			(end 0.7239 1.9939)
			(stroke
				(width 0)
				(type default)
			)
			(fill no)
			(layer "B.CrtYd")
		)
		(fp_line
			(start 0.7239 -0.2159)
			(end 0.7239 1.9939)
			(stroke
				(width 0.1)
				(type default)
			)
			(layer "B.Fab")
		)
		(fp_line
			(start -0.7239 -0.2159)
			(end 0.7239 -0.2159)
			(stroke
				(width 0.1)
				(type default)
			)
			(layer "B.Fab")
		)
		(fp_line
			(start 0.7239 1.9939)
			(end -0.7239 1.9939)
			(stroke
				(width 0.1)
				(type default)
			)
			(layer "B.Fab")
		)
		(fp_line
			(start -0.7239 1.9939)
			(end -0.7239 -0.2159)
			(stroke
				(width 0.1)
				(type default)
			)
			(layer "B.Fab")
		)
		(pad "1" smd rect
			(at 0 0 270)
			(size 1.27 1.016)
			(layers "B.Cu" "B.Mask" "B.Paste")
			(net "VR_FET_SW_P12V_STBY_PVDDQ_KLM")
		)
		(pad "2" smd rect
			(at 0 1.778 270)
			(size 1.27 1.016)
			(layers "B.Cu" "B.Mask" "B.Paste")
			(net "GND")
		)
		(zone
			(layer "B.Cu")
			(hatch none 0.5)
			(connect_pads
				(clearance 0)
			)
			(min_thickness 0.25)
			(keepout
				(tracks not_allowed)
				(vias allowed)
				(pads allowed)
				(copperpour not_allowed)
				(footprints allowed)
			)
			(placement
				(enabled no)
				(sheetname "")
			)
			(fill
				(thermal_gap 0.5)
				(thermal_bridge_width 0.5)
				(island_removal_mode 0)
			)
			(polygon
				(pts
					(xy 1.8542 -147.701) (xy 2.6162 -147.701) (xy 2.6162 -148.971) (xy 1.8542 -148.971)
				)
			)
		)
	)
	(footprint ""
		(layer "B.Cu")
		(at 458.2414 -130.9624 90)
		(property "Reference" "C1M30"
			(at 0 0 90)
			(layer "B.SilkS")
			(hide yes)
			(effects
				(font
					(size 1.27 1.27)
				)
				(justify mirror)
			)
		)
		(property "Value" ""
			(at 0 0 90)
			(layer "B.Fab")
			(effects
				(font
					(size 1.27 1.27)
				)
				(justify mirror)
			)
		)
		(duplicate_pad_numbers_are_jumpers no)
		(fp_poly
			(pts
				(xy -0.3048 -0.1016) (xy -0.3048 0.9906) (xy 0.3048 0.9906) (xy 0.3048 -0.1016)
			)
			(stroke
				(width 0)
				(type default)
			)
			(fill no)
			(layer "B.CrtYd")
		)
		(fp_line
			(start 0.3048 -0.1016)
			(end 0.3048 0.9906)
			(stroke
				(width 0.1)
				(type default)
			)
			(layer "B.Fab")
		)
		(fp_line
			(start -0.3048 -0.1016)
			(end 0.3048 -0.1016)
			(stroke
				(width 0.1)
				(type default)
			)
			(layer "B.Fab")
		)
		(fp_line
			(start 0.3048 0.9906)
			(end -0.3048 0.9906)
			(stroke
				(width 0.1)
				(type default)
			)
			(layer "B.Fab")
		)
		(fp_line
			(start -0.3048 0.9906)
			(end -0.3048 -0.1016)
			(stroke
				(width 0.1)
				(type default)
			)
			(layer "B.Fab")
		)
		(pad "1" smd rect
			(at 0 0 270)
			(size 0.508 0.508)
			(layers "B.Cu" "B.Mask" "B.Paste")
			(net "P3V3_STBY")
		)
		(pad "2" smd rect
			(at 0 0.889 270)
			(size 0.508 0.508)
			(layers "B.Cu" "B.Mask" "B.Paste")
			(net "GND")
		)
		(zone
			(layer "B.Cu")
			(hatch none 0.5)
			(connect_pads
				(clearance 0)
			)
			(min_thickness 0.25)
			(keepout
				(tracks allowed)
				(vias not_allowed)
				(pads allowed)
				(copperpour not_allowed)
				(footprints allowed)
			)
			(placement
				(enabled no)
				(sheetname "")
			)
			(fill
				(thermal_gap 0.5)
				(thermal_bridge_width 0.5)
				(island_removal_mode 0)
			)
			(polygon
				(pts
					(xy 458.4954 -131.2164) (xy 458.4954 -130.7084) (xy 458.8764 -130.7084) (xy 458.8764 -131.2164)
				)
			)
		)
		(zone
			(layer "B.Cu")
			(hatch none 0.5)
			(connect_pads
				(clearance 0)
			)
			(min_thickness 0.25)
			(keepout
				(tracks not_allowed)
				(vias allowed)
				(pads allowed)
				(copperpour not_allowed)
				(footprints allowed)
			)
			(placement
				(enabled no)
				(sheetname "")
			)
			(fill
				(thermal_gap 0.5)
				(thermal_bridge_width 0.5)
				(island_removal_mode 0)
			)
			(polygon
				(pts
					(xy 458.8764 -131.2164) (xy 458.8764 -130.7084) (xy 458.4954 -130.7084) (xy 458.4954 -131.2164)
				)
			)
		)
	)
	(footprint ""
		(layer "B.Cu")
		(at 481.364798 -28.131008)
		(property "Reference" "R2T21"
			(at 0 0 0)
			(layer "B.SilkS")
			(hide yes)
			(effects
				(font
					(size 1.27 1.27)
				)
				(justify mirror)
			)
		)
		(property "Value" ""
			(at 0 0 0)
			(layer "B.Fab")
			(effects
				(font
					(size 1.27 1.27)
				)
				(justify mirror)
			)
		)
		(duplicate_pad_numbers_are_jumpers no)
		(fp_poly
			(pts
				(xy 0.4953 -0.2032) (xy -0.4953 -0.2032) (xy -0.4953 1.6002) (xy 0.4953 1.6002)
			)
			(stroke
				(width 0)
				(type default)
			)
			(fill no)
			(layer "B.CrtYd")
		)
		(fp_line
			(start -0.4953 -0.2032)
			(end -0.4953 1.6002)
			(stroke
				(width 0.1)
				(type default)
			)
			(layer "B.Fab")
		)
		(fp_line
			(start -0.4953 1.6002)
			(end 0.4953 1.6002)
			(stroke
				(width 0.1)
				(type default)
			)
			(layer "B.Fab")
		)
		(fp_line
			(start 0.4953 -0.2032)
			(end -0.4953 -0.2032)
			(stroke
				(width 0.1)
				(type default)
			)
			(layer "B.Fab")
		)
		(fp_line
			(start 0.4953 1.6002)
			(end 0.4953 -0.2032)
			(stroke
				(width 0.1)
				(type default)
			)
			(layer "B.Fab")
		)
		(pad "1" smd rect
			(at 0 0 180)
			(size 0.762 0.889)
			(layers "B.Cu" "B.Mask" "B.Paste")
			(net "P3V3_STBY_MNG")
		)
		(pad "2" smd rect
			(at 0 1.397 180)
			(size 0.762 0.889)
			(layers "B.Cu" "B.Mask" "B.Paste")
			(net "P3V3_STBY_MNG_CPU")
		)
		(zone
			(layer "B.Cu")
			(hatch none 0.5)
			(connect_pads
				(clearance 0)
			)
			(min_thickness 0.25)
			(keepout
				(tracks allowed)
				(vias not_allowed)
				(pads allowed)
				(copperpour not_allowed)
				(footprints allowed)
			)
			(placement
				(enabled no)
				(sheetname "")
			)
			(fill
				(thermal_gap 0.5)
				(thermal_bridge_width 0.5)
				(island_removal_mode 0)
			)
			(polygon
				(pts
					(xy 480.983798 -27.178508) (xy 480.983798 -27.686508) (xy 481.745798 -27.686508) (xy 481.745798 -27.178508)
				)
			)
		)
		(zone
			(layer "B.Cu")
			(hatch none 0.5)
			(connect_pads
				(clearance 0)
			)
			(min_thickness 0.25)
			(keepout
				(tracks not_allowed)
				(vias allowed)
				(pads allowed)
				(copperpour not_allowed)
				(footprints allowed)
			)
			(placement
				(enabled no)
				(sheetname "")
			)
			(fill
				(thermal_gap 0.5)
				(thermal_bridge_width 0.5)
				(island_removal_mode 0)
			)
			(polygon
				(pts
					(xy 481.745798 -27.178508) (xy 481.745798 -27.686508) (xy 480.983798 -27.686508) (xy 480.983798 -27.178508)
				)
			)
		)
	)
	(footprint ""
		(layer "B.Cu")
		(at 162.7886 -77.978 90)
		(property "Reference" "R7P9"
			(at 0 0 90)
			(layer "B.SilkS")
			(hide yes)
			(effects
				(font
					(size 1.27 1.27)
				)
				(justify mirror)
			)
		)
		(property "Value" ""
			(at 0 0 90)
			(layer "B.Fab")
			(effects
				(font
					(size 1.27 1.27)
				)
				(justify mirror)
			)
		)
		(duplicate_pad_numbers_are_jumpers no)
		(fp_poly
			(pts
				(xy 0.2794 -0.1016) (xy -0.2794 -0.1016) (xy -0.2794 0.9906) (xy 0.2794 0.9906)
			)
			(stroke
				(width 0)
				(type default)
			)
			(fill no)
			(layer "B.CrtYd")
		)
		(fp_line
			(start 0.2794 -0.1016)
			(end 0.2794 0.9906)
			(stroke
				(width 0.1)
				(type default)
			)
			(layer "B.Fab")
		)
		(fp_line
			(start -0.2794 -0.1016)
			(end 0.2794 -0.1016)
			(stroke
				(width 0.1)
				(type default)
			)
			(layer "B.Fab")
		)
		(fp_line
			(start 0.2794 0.9906)
			(end -0.2794 0.9906)
			(stroke
				(width 0.1)
				(type default)
			)
			(layer "B.Fab")
		)
		(fp_line
			(start -0.2794 0.9906)
			(end -0.2794 -0.1016)
			(stroke
				(width 0.1)
				(type default)
			)
			(layer "B.Fab")
		)
		(pad "1" smd rect
			(at 0 0 270)
			(size 0.508 0.508)
			(layers "B.Cu" "B.Mask" "B.Paste")
			(net "CLK_100M_CPU1_RC_REFCLK1_DP")
		)
		(pad "2" smd rect
			(at 0 0.889 270)
			(size 0.508 0.508)
			(layers "B.Cu" "B.Mask" "B.Paste")
			(net "GND")
		)
		(zone
			(layer "B.Cu")
			(hatch none 0.5)
			(connect_pads
				(clearance 0)
			)
			(min_thickness 0.25)
			(keepout
				(tracks allowed)
				(vias not_allowed)
				(pads allowed)
				(copperpour not_allowed)
				(footprints allowed)
			)
			(placement
				(enabled no)
				(sheetname "")
			)
			(fill
				(thermal_gap 0.5)
				(thermal_bridge_width 0.5)
				(island_removal_mode 0)
			)
			(polygon
				(pts
					(xy 163.0426 -78.232) (xy 163.0426 -77.724) (xy 163.4236 -77.724) (xy 163.4236 -78.232)
				)
			)
		)
		(zone
			(layer "B.Cu")
			(hatch none 0.5)
			(connect_pads
				(clearance 0)
			)
			(min_thickness 0.25)
			(keepout
				(tracks not_allowed)
				(vias allowed)
				(pads allowed)
				(copperpour not_allowed)
				(footprints allowed)
			)
			(placement
				(enabled no)
				(sheetname "")
			)
			(fill
				(thermal_gap 0.5)
				(thermal_bridge_width 0.5)
				(island_removal_mode 0)
			)
			(polygon
				(pts
					(xy 163.4236 -78.232) (xy 163.4236 -77.724) (xy 163.0426 -77.724) (xy 163.0426 -78.232)
				)
			)
		)
	)
	(footprint ""
		(layer "B.Cu")
		(at 351.416874 -26.505916 90)
		(property "Reference" "C3T12"
			(at -1.47828 0.78994 180)
			(unlocked yes)
			(layer "B.SilkS")
			(effects
				(font
					(size 0.4064 0.254)
					(thickness 0.1524)
				)
				(justify mirror)
			)
		)
		(property "Value" ""
			(at 0 0 90)
			(layer "B.Fab")
			(effects
				(font
					(size 1.27 1.27)
				)
				(justify mirror)
			)
		)
		(duplicate_pad_numbers_are_jumpers no)
		(fp_poly
			(pts
				(xy 0.7239 -0.2159) (xy -0.7239 -0.2159) (xy -0.7239 1.9939) (xy 0.7239 1.9939)
			)
			(stroke
				(width 0)
				(type default)
			)
			(fill no)
			(layer "B.CrtYd")
		)
		(fp_line
			(start 0.7239 -0.2159)
			(end 0.7239 1.9939)
			(stroke
				(width 0.1)
				(type default)
			)
			(layer "B.Fab")
		)
		(fp_line
			(start -0.7239 -0.2159)
			(end 0.7239 -0.2159)
			(stroke
				(width 0.1)
				(type default)
			)
			(layer "B.Fab")
		)
		(fp_line
			(start 0.7239 1.9939)
			(end -0.7239 1.9939)
			(stroke
				(width 0.1)
				(type default)
			)
			(layer "B.Fab")
		)
		(fp_line
			(start -0.7239 1.9939)
			(end -0.7239 -0.2159)
			(stroke
				(width 0.1)
				(type default)
			)
			(layer "B.Fab")
		)
		(pad "1" smd rect
			(at 0 0 270)
			(size 1.27 1.016)
			(layers "B.Cu" "B.Mask" "B.Paste")
			(net "VR_FET_SW_P12V_STBY_PVPP_ABC")
		)
		(pad "2" smd rect
			(at 0 1.778 270)
			(size 1.27 1.016)
			(layers "B.Cu" "B.Mask" "B.Paste")
			(net "GND")
		)
		(zone
			(layer "B.Cu")
			(hatch none 0.5)
			(connect_pads
				(clearance 0)
			)
			(min_thickness 0.25)
			(keepout
				(tracks not_allowed)
				(vias allowed)
				(pads allowed)
				(copperpour not_allowed)
				(footprints allowed)
			)
			(placement
				(enabled no)
				(sheetname "")
			)
			(fill
				(thermal_gap 0.5)
				(thermal_bridge_width 0.5)
				(island_removal_mode 0)
			)
			(polygon
				(pts
					(xy 351.924874 -27.140916) (xy 351.924874 -25.870916) (xy 352.686874 -25.870916) (xy 352.686874 -27.140916)
				)
			)
		)
	)
	(footprint ""
		(layer "B.Cu")
		(at 446.8876 -61.8236 -90)
		(property "Reference" "R1W42"
			(at 0.8382 -0.67818 270)
			(unlocked yes)
			(layer "B.SilkS")
			(effects
				(font
					(size 0.4064 0.254)
					(thickness 0.1524)
				)
				(justify left mirror)
			)
		)
		(property "Value" ""
			(at 0 0 90)
			(layer "B.Fab")
			(effects
				(font
					(size 1.27 1.27)
				)
				(justify mirror)
			)
		)
		(duplicate_pad_numbers_are_jumpers no)
		(fp_poly
			(pts
				(xy 0.2794 -0.1016) (xy -0.2794 -0.1016) (xy -0.2794 0.9906) (xy 0.2794 0.9906)
			)
			(stroke
				(width 0)
				(type default)
			)
			(fill no)
			(layer "B.CrtYd")
		)
		(fp_line
			(start -0.2794 0.9906)
			(end -0.2794 -0.1016)
			(stroke
				(width 0.1)
				(type default)
			)
			(layer "B.Fab")
		)
		(fp_line
			(start 0.2794 0.9906)
			(end -0.2794 0.9906)
			(stroke
				(width 0.1)
				(type default)
			)
			(layer "B.Fab")
		)
		(fp_line
			(start -0.2794 -0.1016)
			(end 0.2794 -0.1016)
			(stroke
				(width 0.1)
				(type default)
			)
			(layer "B.Fab")
		)
		(fp_line
			(start 0.2794 -0.1016)
			(end 0.2794 0.9906)
			(stroke
				(width 0.1)
				(type default)
			)
			(layer "B.Fab")
		)
		(pad "1" smd rect
			(at 0 0 90)
			(size 0.508 0.508)
			(layers "B.Cu" "B.Mask" "B.Paste")
			(net "P3V3_STBY")
		)
		(pad "2" smd rect
			(at 0 0.889 90)
			(size 0.508 0.508)
			(layers "B.Cu" "B.Mask" "B.Paste")
			(net "FM_GBE0_LVC3_MOD_ABS")
		)
		(zone
			(layer "B.Cu")
			(hatch none 0.5)
			(connect_pads
				(clearance 0)
			)
			(min_thickness 0.25)
			(keepout
				(tracks not_allowed)
				(vias allowed)
				(pads allowed)
				(copperpour not_allowed)
				(footprints allowed)
			)
			(placement
				(enabled no)
				(sheetname "")
			)
			(fill
				(thermal_gap 0.5)
				(thermal_bridge_width 0.5)
				(island_removal_mode 0)
			)
			(polygon
				(pts
					(xy 446.2526 -61.5696) (xy 446.2526 -62.0776) (xy 446.6336 -62.0776) (xy 446.6336 -61.5696)
				)
			)
		)
		(zone
			(layer "B.Cu")
			(hatch none 0.5)
			(connect_pads
				(clearance 0)
			)
			(min_thickness 0.25)
			(keepout
				(tracks allowed)
				(vias not_allowed)
				(pads allowed)
				(copperpour not_allowed)
				(footprints allowed)
			)
			(placement
				(enabled no)
				(sheetname "")
			)
			(fill
				(thermal_gap 0.5)
				(thermal_bridge_width 0.5)
				(island_removal_mode 0)
			)
			(polygon
				(pts
					(xy 446.6336 -61.5696) (xy 446.6336 -62.0776) (xy 446.2526 -62.0776) (xy 446.2526 -61.5696)
				)
			)
		)
	)
	(footprint ""
		(layer "B.Cu")
		(at 396.875 -37.846 180)
		(property "Reference" "R2U2"
			(at 0 0 0)
			(layer "B.SilkS")
			(hide yes)
			(effects
				(font
					(size 1.27 1.27)
				)
				(justify mirror)
			)
		)
		(property "Value" ""
			(at 0 0 0)
			(layer "B.Fab")
			(effects
				(font
					(size 1.27 1.27)
				)
				(justify mirror)
			)
		)
		(duplicate_pad_numbers_are_jumpers no)
		(fp_poly
			(pts
				(xy 0.2794 -0.1016) (xy -0.2794 -0.1016) (xy -0.2794 0.9906) (xy 0.2794 0.9906)
			)
			(stroke
				(width 0)
				(type default)
			)
			(fill no)
			(layer "B.CrtYd")
		)
		(fp_line
			(start 0.2794 0.9906)
			(end -0.2794 0.9906)
			(stroke
				(width 0.1)
				(type default)
			)
			(layer "B.Fab")
		)
		(fp_line
			(start 0.2794 -0.1016)
			(end 0.2794 0.9906)
			(stroke
				(width 0.1)
				(type default)
			)
			(layer "B.Fab")
		)
		(fp_line
			(start -0.2794 0.9906)
			(end -0.2794 -0.1016)
			(stroke
				(width 0.1)
				(type default)
			)
			(layer "B.Fab")
		)
		(fp_line
			(start -0.2794 -0.1016)
			(end 0.2794 -0.1016)
			(stroke
				(width 0.1)
				(type default)
			)
			(layer "B.Fab")
		)
		(pad "1" smd rect
			(at 0 0)
			(size 0.508 0.508)
			(layers "B.Cu" "B.Mask" "B.Paste")
			(net "P3V3_STBY")
		)
		(pad "2" smd rect
			(at 0 0.889)
			(size 0.508 0.508)
			(layers "B.Cu" "B.Mask" "B.Paste")
			(net "RST_PCH_SYSRST_BTN_OUT_N")
		)
		(zone
			(layer "B.Cu")
			(hatch none 0.5)
			(connect_pads
				(clearance 0)
			)
			(min_thickness 0.25)
			(keepout
				(tracks not_allowed)
				(vias allowed)
				(pads allowed)
				(copperpour not_allowed)
				(footprints allowed)
			)
			(placement
				(enabled no)
				(sheetname "")
			)
			(fill
				(thermal_gap 0.5)
				(thermal_bridge_width 0.5)
				(island_removal_mode 0)
			)
			(polygon
				(pts
					(xy 396.621 -38.481) (xy 397.129 -38.481) (xy 397.129 -38.1) (xy 396.621 -38.1)
				)
			)
		)
		(zone
			(layer "B.Cu")
			(hatch none 0.5)
			(connect_pads
				(clearance 0)
			)
			(min_thickness 0.25)
			(keepout
				(tracks allowed)
				(vias not_allowed)
				(pads allowed)
				(copperpour not_allowed)
				(footprints allowed)
			)
			(placement
				(enabled no)
				(sheetname "")
			)
			(fill
				(thermal_gap 0.5)
				(thermal_bridge_width 0.5)
				(island_removal_mode 0)
			)
			(polygon
				(pts
					(xy 396.621 -38.1) (xy 397.129 -38.1) (xy 397.129 -38.481) (xy 396.621 -38.481)
				)
			)
		)
	)
	(footprint ""
		(layer "B.Cu")
		(at 106.350054 -77.82814)
		(property "Reference" "C8P14"
			(at 0 0 0)
			(layer "B.SilkS")
			(hide yes)
			(effects
				(font
					(size 1.27 1.27)
				)
				(justify mirror)
			)
		)
		(property "Value" ""
			(at 0 0 0)
			(layer "B.Fab")
			(effects
				(font
					(size 1.27 1.27)
				)
				(justify mirror)
			)
		)
		(duplicate_pad_numbers_are_jumpers no)
		(fp_poly
			(pts
				(xy 0.7239 -0.2159) (xy -0.7239 -0.2159) (xy -0.7239 1.9939) (xy 0.7239 1.9939)
			)
			(stroke
				(width 0)
				(type default)
			)
			(fill no)
			(layer "B.CrtYd")
		)
		(fp_line
			(start -0.7239 -0.2159)
			(end 0.7239 -0.2159)
			(stroke
				(width 0.1)
				(type default)
			)
			(layer "B.Fab")
		)
		(fp_line
			(start -0.7239 1.9939)
			(end -0.7239 -0.2159)
			(stroke
				(width 0.1)
				(type default)
			)
			(layer "B.Fab")
		)
		(fp_line
			(start 0.7239 -0.2159)
			(end 0.7239 1.9939)
			(stroke
				(width 0.1)
				(type default)
			)
			(layer "B.Fab")
		)
		(fp_line
			(start 0.7239 1.9939)
			(end -0.7239 1.9939)
			(stroke
				(width 0.1)
				(type default)
			)
			(layer "B.Fab")
		)
		(pad "1" smd rect
			(at 0 0 180)
			(size 1.27 1.016)
			(layers "B.Cu" "B.Mask" "B.Paste")
			(net "PVCCMCP_CPU1")
		)
		(pad "2" smd rect
			(at 0 1.778 180)
			(size 1.27 1.016)
			(layers "B.Cu" "B.Mask" "B.Paste")
			(net "GND")
		)
		(zone
			(layer "B.Cu")
			(hatch none 0.5)
			(connect_pads
				(clearance 0)
			)
			(min_thickness 0.25)
			(keepout
				(tracks not_allowed)
				(vias allowed)
				(pads allowed)
				(copperpour not_allowed)
				(footprints allowed)
			)
			(placement
				(enabled no)
				(sheetname "")
			)
			(fill
				(thermal_gap 0.5)
				(thermal_bridge_width 0.5)
				(island_removal_mode 0)
			)
			(polygon
				(pts
					(xy 106.985054 -77.32014) (xy 105.715054 -77.32014) (xy 105.715054 -76.55814) (xy 106.985054 -76.55814)
				)
			)
		)
	)
	(footprint ""
		(layer "B.Cu")
		(at 109.065568 3.81 90)
		(property "Reference" "C7U7"
			(at 0 0 90)
			(layer "B.SilkS")
			(hide yes)
			(effects
				(font
					(size 1.27 1.27)
				)
				(justify mirror)
			)
		)
		(property "Value" ""
			(at 0 0 90)
			(layer "B.Fab")
			(effects
				(font
					(size 1.27 1.27)
				)
				(justify mirror)
			)
		)
		(duplicate_pad_numbers_are_jumpers no)
		(fp_poly
			(pts
				(xy 0.7239 -0.2159) (xy -0.7239 -0.2159) (xy -0.7239 1.9939) (xy 0.7239 1.9939)
			)
			(stroke
				(width 0)
				(type default)
			)
			(fill no)
			(layer "B.CrtYd")
		)
		(fp_line
			(start 0.7239 -0.2159)
			(end 0.7239 1.9939)
			(stroke
				(width 0.1)
				(type default)
			)
			(layer "B.Fab")
		)
		(fp_line
			(start -0.7239 -0.2159)
			(end 0.7239 -0.2159)
			(stroke
				(width 0.1)
				(type default)
			)
			(layer "B.Fab")
		)
		(fp_line
			(start 0.7239 1.9939)
			(end -0.7239 1.9939)
			(stroke
				(width 0.1)
				(type default)
			)
			(layer "B.Fab")
		)
		(fp_line
			(start -0.7239 1.9939)
			(end -0.7239 -0.2159)
			(stroke
				(width 0.1)
				(type default)
			)
			(layer "B.Fab")
		)
		(pad "1" smd rect
			(at 0 0 270)
			(size 1.27 1.016)
			(layers "B.Cu" "B.Mask" "B.Paste")
			(net "PVDDQ_GHJ")
		)
		(pad "2" smd rect
			(at 0 1.778 270)
			(size 1.27 1.016)
			(layers "B.Cu" "B.Mask" "B.Paste")
			(net "GND")
		)
		(zone
			(layer "B.Cu")
			(hatch none 0.5)
			(connect_pads
				(clearance 0)
			)
			(min_thickness 0.25)
			(keepout
				(tracks not_allowed)
				(vias allowed)
				(pads allowed)
				(copperpour not_allowed)
				(footprints allowed)
			)
			(placement
				(enabled no)
				(sheetname "")
			)
			(fill
				(thermal_gap 0.5)
				(thermal_bridge_width 0.5)
				(island_removal_mode 0)
			)
			(polygon
				(pts
					(xy 109.573568 3.175) (xy 109.573568 4.445) (xy 110.335568 4.445) (xy 110.335568 3.175)
				)
			)
		)
	)
	(footprint ""
		(layer "B.Cu")
		(at 17.145 -92.583 -90)
		(property "Reference" "R6W3"
			(at 0 0 90)
			(layer "B.SilkS")
			(hide yes)
			(effects
				(font
					(size 1.27 1.27)
				)
				(justify mirror)
			)
		)
		(property "Value" "*"
			(at -0.064008 -4.108196 270)
			(unlocked yes)
			(layer "B.Fab")
			(hide yes)
			(effects
				(font
					(size 1.27 1.016)
					(thickness 0.1524)
				)
				(justify mirror)
			)
		)
		(property "Device Type" "232KR2F-2-GP_SMD-RG1-232KR2F-2A"
			(at -0.064008 -5.632196 270)
			(unlocked yes)
			(layer "B.Fab")
			(hide yes)
			(effects
				(font
					(size 1.27 1.016)
					(thickness 0.1524)
				)
				(justify mirror)
			)
		)
		(duplicate_pad_numbers_are_jumpers no)
		(fp_line
			(start -0.508 -0.9398)
			(end 0.508 -0.9398)
			(stroke
				(width 0.1524)
				(type default)
			)
			(layer "B.SilkS")
		)
		(fp_line
			(start 0.508 -0.9398)
			(end 0.508 0.9398)
			(stroke
				(width 0.1524)
				(type default)
			)
			(layer "B.SilkS")
		)
		(fp_rect
			(start 0.508 0.9398)
			(end -0.508 -0.9398)
			(stroke
				(width 0)
				(type default)
			)
			(fill no)
			(layer "B.CrtYd")
		)
		(fp_rect
			(start 0.508 0.9398)
			(end -0.508 -0.9398)
			(stroke
				(width 0)
				(type default)
			)
			(fill no)
			(layer "B.Fab")
		)
		(pad "1" smd custom
			(at 0 -0.4445 90)
			(size 0.1397 0.1397)
			(layers "B.Cu" "B.Mask" "B.Paste")
			(net "UV_HIGH_SET_N")
			(options
				(clearance outline)
				(anchor circle)
			)
			(primitives
				(gr_poly
					(pts
						(arc
							(start -0.1778 0.2794)
							(mid -0.249642 0.249642)
							(end -0.2794 0.1778)
						)
						(arc
							(start -0.2794 -0.1778)
							(mid -0.249642 -0.249642)
							(end -0.1778 -0.2794)
						)
						(arc
							(start 0.1778 -0.2794)
							(mid 0.249642 -0.249642)
							(end 0.2794 -0.1778)
						)
						(arc
							(start 0.2794 0.1778)
							(mid 0.249642 0.249642)
							(end 0.1778 0.2794)
						)
					)
					(width 0)
					(fill yes)
				)
			)
		)
		(pad "2" smd custom
			(at 0 0.4445 90)
			(size 0.1397 0.1397)
			(layers "B.Cu" "B.Mask" "B.Paste")
			(net "A_P12V_STBY_FP_TRIGGER")
			(options
				(clearance outline)
				(anchor circle)
			)
			(primitives
				(gr_poly
					(pts
						(arc
							(start -0.1778 0.2794)
							(mid -0.249642 0.249642)
							(end -0.2794 0.1778)
						)
						(arc
							(start -0.2794 -0.1778)
							(mid -0.249642 -0.249642)
							(end -0.1778 -0.2794)
						)
						(arc
							(start 0.1778 -0.2794)
							(mid 0.249642 -0.249642)
							(end 0.2794 -0.1778)
						)
						(arc
							(start 0.2794 0.1778)
							(mid 0.249642 0.249642)
							(end 0.1778 0.2794)
						)
					)
					(width 0)
					(fill yes)
				)
			)
		)
	)
	(footprint ""
		(layer "B.Cu")
		(at 115.824 -70.739 -90)
		(property "Reference" "R7P21"
			(at 0 0 90)
			(layer "B.SilkS")
			(hide yes)
			(effects
				(font
					(size 1.27 1.27)
				)
				(justify mirror)
			)
		)
		(property "Value" ""
			(at 0 0 90)
			(layer "B.Fab")
			(effects
				(font
					(size 1.27 1.27)
				)
				(justify mirror)
			)
		)
		(duplicate_pad_numbers_are_jumpers no)
		(fp_poly
			(pts
				(xy 0.2794 -0.1016) (xy -0.2794 -0.1016) (xy -0.2794 0.9906) (xy 0.2794 0.9906)
			)
			(stroke
				(width 0)
				(type default)
			)
			(fill no)
			(layer "B.CrtYd")
		)
		(fp_line
			(start -0.2794 0.9906)
			(end -0.2794 -0.1016)
			(stroke
				(width 0.1)
				(type default)
			)
			(layer "B.Fab")
		)
		(fp_line
			(start 0.2794 0.9906)
			(end -0.2794 0.9906)
			(stroke
				(width 0.1)
				(type default)
			)
			(layer "B.Fab")
		)
		(fp_line
			(start -0.2794 -0.1016)
			(end 0.2794 -0.1016)
			(stroke
				(width 0.1)
				(type default)
			)
			(layer "B.Fab")
		)
		(fp_line
			(start 0.2794 -0.1016)
			(end 0.2794 0.9906)
			(stroke
				(width 0.1)
				(type default)
			)
			(layer "B.Fab")
		)
		(pad "1" smd rect
			(at 0 0 90)
			(size 0.508 0.508)
			(layers "B.Cu" "B.Mask" "B.Paste")
			(net "H_CPU1_MEMKLM_MEMHOT_G_N")
		)
		(pad "2" smd rect
			(at 0 0.889 90)
			(size 0.508 0.508)
			(layers "B.Cu" "B.Mask" "B.Paste")
			(net "PVCCIO_CPU1")
		)
		(zone
			(layer "B.Cu")
			(hatch none 0.5)
			(connect_pads
				(clearance 0)
			)
			(min_thickness 0.25)
			(keepout
				(tracks not_allowed)
				(vias allowed)
				(pads allowed)
				(copperpour not_allowed)
				(footprints allowed)
			)
			(placement
				(enabled no)
				(sheetname "")
			)
			(fill
				(thermal_gap 0.5)
				(thermal_bridge_width 0.5)
				(island_removal_mode 0)
			)
			(polygon
				(pts
					(xy 115.189 -70.485) (xy 115.189 -70.993) (xy 115.57 -70.993) (xy 115.57 -70.485)
				)
			)
		)
		(zone
			(layer "B.Cu")
			(hatch none 0.5)
			(connect_pads
				(clearance 0)
			)
			(min_thickness 0.25)
			(keepout
				(tracks allowed)
				(vias not_allowed)
				(pads allowed)
				(copperpour not_allowed)
				(footprints allowed)
			)
			(placement
				(enabled no)
				(sheetname "")
			)
			(fill
				(thermal_gap 0.5)
				(thermal_bridge_width 0.5)
				(island_removal_mode 0)
			)
			(polygon
				(pts
					(xy 115.57 -70.485) (xy 115.57 -70.993) (xy 115.189 -70.993) (xy 115.189 -70.485)
				)
			)
		)
	)
	(footprint ""
		(layer "B.Cu")
		(at 494.702084 -46.184312)
		(property "Reference" "R25W136"
			(at 0.8382 -0.67818 0)
			(unlocked yes)
			(layer "B.SilkS")
			(effects
				(font
					(size 0.4064 0.254)
					(thickness 0.1524)
				)
				(justify left mirror)
			)
		)
		(property "Value" ""
			(at 0 0 0)
			(layer "B.Fab")
			(effects
				(font
					(size 1.27 1.27)
				)
				(justify mirror)
			)
		)
		(duplicate_pad_numbers_are_jumpers no)
		(fp_poly
			(pts
				(xy 0.2794 -0.1016) (xy -0.2794 -0.1016) (xy -0.2794 0.9906) (xy 0.2794 0.9906)
			)
			(stroke
				(width 0)
				(type default)
			)
			(fill no)
			(layer "B.CrtYd")
		)
		(fp_line
			(start -0.2794 -0.1016)
			(end 0.2794 -0.1016)
			(stroke
				(width 0.1)
				(type default)
			)
			(layer "B.Fab")
		)
		(fp_line
			(start -0.2794 0.9906)
			(end -0.2794 -0.1016)
			(stroke
				(width 0.1)
				(type default)
			)
			(layer "B.Fab")
		)
		(fp_line
			(start 0.2794 -0.1016)
			(end 0.2794 0.9906)
			(stroke
				(width 0.1)
				(type default)
			)
			(layer "B.Fab")
		)
		(fp_line
			(start 0.2794 0.9906)
			(end -0.2794 0.9906)
			(stroke
				(width 0.1)
				(type default)
			)
			(layer "B.Fab")
		)
		(pad "1" smd rect
			(at 0 0 180)
			(size 0.508 0.508)
			(layers "B.Cu" "B.Mask" "B.Paste")
			(net "I2C_BMC_VGA_DDC_SDA_G")
		)
		(pad "2" smd rect
			(at 0 0.889 180)
			(size 0.508 0.508)
			(layers "B.Cu" "B.Mask" "B.Paste")
			(net "V_IBMC_5V_DDC_SDA_J")
		)
		(zone
			(layer "B.Cu")
			(hatch none 0.5)
			(connect_pads
				(clearance 0)
			)
			(min_thickness 0.25)
			(keepout
				(tracks allowed)
				(vias not_allowed)
				(pads allowed)
				(copperpour not_allowed)
				(footprints allowed)
			)
			(placement
				(enabled no)
				(sheetname "")
			)
			(fill
				(thermal_gap 0.5)
				(thermal_bridge_width 0.5)
				(island_removal_mode 0)
			)
			(polygon
				(pts
					(xy 494.956084 -45.930312) (xy 494.448084 -45.930312) (xy 494.448084 -45.549312) (xy 494.956084 -45.549312)
				)
			)
		)
		(zone
			(layer "B.Cu")
			(hatch none 0.5)
			(connect_pads
				(clearance 0)
			)
			(min_thickness 0.25)
			(keepout
				(tracks not_allowed)
				(vias allowed)
				(pads allowed)
				(copperpour not_allowed)
				(footprints allowed)
			)
			(placement
				(enabled no)
				(sheetname "")
			)
			(fill
				(thermal_gap 0.5)
				(thermal_bridge_width 0.5)
				(island_removal_mode 0)
			)
			(polygon
				(pts
					(xy 494.956084 -45.549312) (xy 494.448084 -45.549312) (xy 494.448084 -45.930312) (xy 494.956084 -45.930312)
				)
			)
		)
	)
	(footprint ""
		(layer "B.Cu")
		(at 111.836454 -73.51014)
		(property "Reference" "C7P13"
			(at 0 0 0)
			(layer "B.SilkS")
			(hide yes)
			(effects
				(font
					(size 1.27 1.27)
				)
				(justify mirror)
			)
		)
		(property "Value" ""
			(at 0 0 0)
			(layer "B.Fab")
			(effects
				(font
					(size 1.27 1.27)
				)
				(justify mirror)
			)
		)
		(duplicate_pad_numbers_are_jumpers no)
		(fp_poly
			(pts
				(xy 0.7239 -0.2159) (xy -0.7239 -0.2159) (xy -0.7239 1.9939) (xy 0.7239 1.9939)
			)
			(stroke
				(width 0)
				(type default)
			)
			(fill no)
			(layer "B.CrtYd")
		)
		(fp_line
			(start -0.7239 -0.2159)
			(end 0.7239 -0.2159)
			(stroke
				(width 0.1)
				(type default)
			)
			(layer "B.Fab")
		)
		(fp_line
			(start -0.7239 1.9939)
			(end -0.7239 -0.2159)
			(stroke
				(width 0.1)
				(type default)
			)
			(layer "B.Fab")
		)
		(fp_line
			(start 0.7239 -0.2159)
			(end 0.7239 1.9939)
			(stroke
				(width 0.1)
				(type default)
			)
			(layer "B.Fab")
		)
		(fp_line
			(start 0.7239 1.9939)
			(end -0.7239 1.9939)
			(stroke
				(width 0.1)
				(type default)
			)
			(layer "B.Fab")
		)
		(pad "1" smd rect
			(at 0 0 180)
			(size 1.27 1.016)
			(layers "B.Cu" "B.Mask" "B.Paste")
			(net "PVCCMCP_CPU1")
		)
		(pad "2" smd rect
			(at 0 1.778 180)
			(size 1.27 1.016)
			(layers "B.Cu" "B.Mask" "B.Paste")
			(net "GND")
		)
		(zone
			(layer "B.Cu")
			(hatch none 0.5)
			(connect_pads
				(clearance 0)
			)
			(min_thickness 0.25)
			(keepout
				(tracks not_allowed)
				(vias allowed)
				(pads allowed)
				(copperpour not_allowed)
				(footprints allowed)
			)
			(placement
				(enabled no)
				(sheetname "")
			)
			(fill
				(thermal_gap 0.5)
				(thermal_bridge_width 0.5)
				(island_removal_mode 0)
			)
			(polygon
				(pts
					(xy 112.471454 -73.00214) (xy 111.201454 -73.00214) (xy 111.201454 -72.24014) (xy 112.471454 -72.24014)
				)
			)
		)
	)
	(footprint ""
		(layer "B.Cu")
		(at 492.9886 -38.9636)
		(property "Reference" "R9W33"
			(at 0.8382 -0.67818 0)
			(unlocked yes)
			(layer "B.SilkS")
			(effects
				(font
					(size 0.4064 0.254)
					(thickness 0.1524)
				)
				(justify left mirror)
			)
		)
		(property "Value" ""
			(at 0 0 0)
			(layer "B.Fab")
			(effects
				(font
					(size 1.27 1.27)
				)
				(justify mirror)
			)
		)
		(duplicate_pad_numbers_are_jumpers no)
		(fp_poly
			(pts
				(xy 0.2794 -0.1016) (xy -0.2794 -0.1016) (xy -0.2794 0.9906) (xy 0.2794 0.9906)
			)
			(stroke
				(width 0)
				(type default)
			)
			(fill no)
			(layer "B.CrtYd")
		)
		(fp_line
			(start -0.2794 -0.1016)
			(end 0.2794 -0.1016)
			(stroke
				(width 0.1)
				(type default)
			)
			(layer "B.Fab")
		)
		(fp_line
			(start -0.2794 0.9906)
			(end -0.2794 -0.1016)
			(stroke
				(width 0.1)
				(type default)
			)
			(layer "B.Fab")
		)
		(fp_line
			(start 0.2794 -0.1016)
			(end 0.2794 0.9906)
			(stroke
				(width 0.1)
				(type default)
			)
			(layer "B.Fab")
		)
		(fp_line
			(start 0.2794 0.9906)
			(end -0.2794 0.9906)
			(stroke
				(width 0.1)
				(type default)
			)
			(layer "B.Fab")
		)
		(pad "1" smd rect
			(at 0 0 180)
			(size 0.508 0.508)
			(layers "B.Cu" "B.Mask" "B.Paste")
			(net "P3V3_STBY")
		)
		(pad "2" smd rect
			(at 0 0.889 180)
			(size 0.508 0.508)
			(layers "B.Cu" "B.Mask" "B.Paste")
			(net "SP1_BMC_HOST_UART_RX")
		)
		(zone
			(layer "B.Cu")
			(hatch none 0.5)
			(connect_pads
				(clearance 0)
			)
			(min_thickness 0.25)
			(keepout
				(tracks allowed)
				(vias not_allowed)
				(pads allowed)
				(copperpour not_allowed)
				(footprints allowed)
			)
			(placement
				(enabled no)
				(sheetname "")
			)
			(fill
				(thermal_gap 0.5)
				(thermal_bridge_width 0.5)
				(island_removal_mode 0)
			)
			(polygon
				(pts
					(xy 493.2426 -38.7096) (xy 492.7346 -38.7096) (xy 492.7346 -38.3286) (xy 493.2426 -38.3286)
				)
			)
		)
		(zone
			(layer "B.Cu")
			(hatch none 0.5)
			(connect_pads
				(clearance 0)
			)
			(min_thickness 0.25)
			(keepout
				(tracks not_allowed)
				(vias allowed)
				(pads allowed)
				(copperpour not_allowed)
				(footprints allowed)
			)
			(placement
				(enabled no)
				(sheetname "")
			)
			(fill
				(thermal_gap 0.5)
				(thermal_bridge_width 0.5)
				(island_removal_mode 0)
			)
			(polygon
				(pts
					(xy 493.2426 -38.3286) (xy 492.7346 -38.3286) (xy 492.7346 -38.7096) (xy 493.2426 -38.7096)
				)
			)
		)
	)
	(footprint ""
		(layer "B.Cu")
		(at 26.8478 -30.099 180)
		(property "Reference" "R9T8"
			(at 0 0 0)
			(layer "B.SilkS")
			(hide yes)
			(effects
				(font
					(size 1.27 1.27)
				)
				(justify mirror)
			)
		)
		(property "Value" ""
			(at 0 0 0)
			(layer "B.Fab")
			(effects
				(font
					(size 1.27 1.27)
				)
				(justify mirror)
			)
		)
		(duplicate_pad_numbers_are_jumpers no)
		(fp_rect
			(start -0.2794 -0.1016)
			(end 0.2794 0.9906)
			(stroke
				(width 0)
				(type default)
			)
			(fill no)
			(layer "B.CrtYd")
		)
		(fp_line
			(start 0.2794 0.9906)
			(end -0.2794 0.9906)
			(stroke
				(width 0.1)
				(type default)
			)
			(layer "B.Fab")
		)
		(fp_line
			(start 0.2794 -0.1016)
			(end 0.2794 0.9906)
			(stroke
				(width 0.1)
				(type default)
			)
			(layer "B.Fab")
		)
		(fp_line
			(start -0.2794 0.9906)
			(end -0.2794 -0.1016)
			(stroke
				(width 0.1)
				(type default)
			)
			(layer "B.Fab")
		)
		(fp_line
			(start -0.2794 -0.1016)
			(end 0.2794 -0.1016)
			(stroke
				(width 0.1)
				(type default)
			)
			(layer "B.Fab")
		)
		(pad "1" smd rect
			(at 0 0)
			(size 0.508 0.508)
			(layers "B.Cu" "B.Mask" "B.Paste")
			(net "FM_MATED_IN_N")
		)
		(pad "2" smd rect
			(at 0 0.889)
			(size 0.508 0.508)
			(layers "B.Cu" "B.Mask" "B.Paste")
			(net "GND")
		)
		(zone
			(layer "B.Cu")
			(hatch none 0.5)
			(connect_pads
				(clearance 0)
			)
			(min_thickness 0.25)
			(keepout
				(tracks not_allowed)
				(vias allowed)
				(pads allowed)
				(copperpour not_allowed)
				(footprints allowed)
			)
			(placement
				(enabled no)
				(sheetname "")
			)
			(fill
				(thermal_gap 0.5)
				(thermal_bridge_width 0.5)
				(island_removal_mode 0)
			)
			(polygon
				(pts
					(xy 27.1018 -30.353) (xy 27.1018 -30.734) (xy 26.5938 -30.734) (xy 26.5938 -30.353)
				)
			)
		)
		(zone
			(layer "B.Cu")
			(hatch none 0.5)
			(connect_pads
				(clearance 0)
			)
			(min_thickness 0.25)
			(keepout
				(tracks allowed)
				(vias not_allowed)
				(pads allowed)
				(copperpour not_allowed)
				(footprints allowed)
			)
			(placement
				(enabled no)
				(sheetname "")
			)
			(fill
				(thermal_gap 0.5)
				(thermal_bridge_width 0.5)
				(island_removal_mode 0)
			)
			(polygon
				(pts
					(xy 27.1018 -30.353) (xy 27.1018 -30.734) (xy 26.5938 -30.734) (xy 26.5938 -30.353)
				)
			)
		)
	)
	(footprint ""
		(layer "B.Cu")
		(at 166.116 -87.757)
		(property "Reference" "R6P7"
			(at 0 0 0)
			(layer "B.SilkS")
			(hide yes)
			(effects
				(font
					(size 1.27 1.27)
				)
				(justify mirror)
			)
		)
		(property "Value" ""
			(at 0 0 0)
			(layer "B.Fab")
			(effects
				(font
					(size 1.27 1.27)
				)
				(justify mirror)
			)
		)
		(duplicate_pad_numbers_are_jumpers no)
		(fp_poly
			(pts
				(xy 0.2794 -0.1016) (xy -0.2794 -0.1016) (xy -0.2794 0.9906) (xy 0.2794 0.9906)
			)
			(stroke
				(width 0)
				(type default)
			)
			(fill no)
			(layer "B.CrtYd")
		)
		(fp_line
			(start -0.2794 -0.1016)
			(end 0.2794 -0.1016)
			(stroke
				(width 0.1)
				(type default)
			)
			(layer "B.Fab")
		)
		(fp_line
			(start -0.2794 0.9906)
			(end -0.2794 -0.1016)
			(stroke
				(width 0.1)
				(type default)
			)
			(layer "B.Fab")
		)
		(fp_line
			(start 0.2794 -0.1016)
			(end 0.2794 0.9906)
			(stroke
				(width 0.1)
				(type default)
			)
			(layer "B.Fab")
		)
		(fp_line
			(start 0.2794 0.9906)
			(end -0.2794 0.9906)
			(stroke
				(width 0.1)
				(type default)
			)
			(layer "B.Fab")
		)
		(pad "1" smd rect
			(at 0 0 180)
			(size 0.508 0.508)
			(layers "B.Cu" "B.Mask" "B.Paste")
			(net "CLK_100M_CPU1_BCLK1_DP")
		)
		(pad "2" smd rect
			(at 0 0.889 180)
			(size 0.508 0.508)
			(layers "B.Cu" "B.Mask" "B.Paste")
			(net "GND")
		)
		(zone
			(layer "B.Cu")
			(hatch none 0.5)
			(connect_pads
				(clearance 0)
			)
			(min_thickness 0.25)
			(keepout
				(tracks allowed)
				(vias not_allowed)
				(pads allowed)
				(copperpour not_allowed)
				(footprints allowed)
			)
			(placement
				(enabled no)
				(sheetname "")
			)
			(fill
				(thermal_gap 0.5)
				(thermal_bridge_width 0.5)
				(island_removal_mode 0)
			)
			(polygon
				(pts
					(xy 166.37 -87.503) (xy 165.862 -87.503) (xy 165.862 -87.122) (xy 166.37 -87.122)
				)
			)
		)
		(zone
			(layer "B.Cu")
			(hatch none 0.5)
			(connect_pads
				(clearance 0)
			)
			(min_thickness 0.25)
			(keepout
				(tracks not_allowed)
				(vias allowed)
				(pads allowed)
				(copperpour not_allowed)
				(footprints allowed)
			)
			(placement
				(enabled no)
				(sheetname "")
			)
			(fill
				(thermal_gap 0.5)
				(thermal_bridge_width 0.5)
				(island_removal_mode 0)
			)
			(polygon
				(pts
					(xy 166.37 -87.122) (xy 165.862 -87.122) (xy 165.862 -87.503) (xy 166.37 -87.503)
				)
			)
		)
	)
	(footprint ""
		(layer "B.Cu")
		(at 487.172 -139.6746 90)
		(property "Reference" "R1L38"
			(at 0 0 90)
			(layer "B.SilkS")
			(hide yes)
			(effects
				(font
					(size 1.27 1.27)
				)
				(justify mirror)
			)
		)
		(property "Value" ""
			(at 0 0 90)
			(layer "B.Fab")
			(effects
				(font
					(size 1.27 1.27)
				)
				(justify mirror)
			)
		)
		(duplicate_pad_numbers_are_jumpers no)
		(fp_poly
			(pts
				(xy 0.2794 -0.1016) (xy -0.2794 -0.1016) (xy -0.2794 0.9906) (xy 0.2794 0.9906)
			)
			(stroke
				(width 0)
				(type default)
			)
			(fill no)
			(layer "B.CrtYd")
		)
		(fp_line
			(start 0.2794 -0.1016)
			(end 0.2794 0.9906)
			(stroke
				(width 0.1)
				(type default)
			)
			(layer "B.Fab")
		)
		(fp_line
			(start -0.2794 -0.1016)
			(end 0.2794 -0.1016)
			(stroke
				(width 0.1)
				(type default)
			)
			(layer "B.Fab")
		)
		(fp_line
			(start 0.2794 0.9906)
			(end -0.2794 0.9906)
			(stroke
				(width 0.1)
				(type default)
			)
			(layer "B.Fab")
		)
		(fp_line
			(start -0.2794 0.9906)
			(end -0.2794 -0.1016)
			(stroke
				(width 0.1)
				(type default)
			)
			(layer "B.Fab")
		)
		(pad "1" smd rect
			(at 0 0 270)
			(size 0.508 0.508)
			(layers "B.Cu" "B.Mask" "B.Paste")
			(net "P3V3_STBY")
		)
		(pad "2" smd rect
			(at 0 0.889 270)
			(size 0.508 0.508)
			(layers "B.Cu" "B.Mask" "B.Paste")
			(net "FM_POST_CARD_PRES_BMC_N")
		)
		(zone
			(layer "B.Cu")
			(hatch none 0.5)
			(connect_pads
				(clearance 0)
			)
			(min_thickness 0.25)
			(keepout
				(tracks allowed)
				(vias not_allowed)
				(pads allowed)
				(copperpour not_allowed)
				(footprints allowed)
			)
			(placement
				(enabled no)
				(sheetname "")
			)
			(fill
				(thermal_gap 0.5)
				(thermal_bridge_width 0.5)
				(island_removal_mode 0)
			)
			(polygon
				(pts
					(xy 487.426 -139.9286) (xy 487.426 -139.4206) (xy 487.807 -139.4206) (xy 487.807 -139.9286)
				)
			)
		)
		(zone
			(layer "B.Cu")
			(hatch none 0.5)
			(connect_pads
				(clearance 0)
			)
			(min_thickness 0.25)
			(keepout
				(tracks not_allowed)
				(vias allowed)
				(pads allowed)
				(copperpour not_allowed)
				(footprints allowed)
			)
			(placement
				(enabled no)
				(sheetname "")
			)
			(fill
				(thermal_gap 0.5)
				(thermal_bridge_width 0.5)
				(island_removal_mode 0)
			)
			(polygon
				(pts
					(xy 487.807 -139.9286) (xy 487.807 -139.4206) (xy 487.426 -139.4206) (xy 487.426 -139.9286)
				)
			)
		)
	)
	(footprint ""
		(layer "B.Cu")
		(at 4.25704 -12.573 90)
		(property "Reference" "C1G13"
			(at 0 0 90)
			(layer "B.SilkS")
			(hide yes)
			(effects
				(font
					(size 1.27 1.27)
				)
				(justify mirror)
			)
		)
		(property "Value" ""
			(at 0 0 90)
			(layer "B.Fab")
			(effects
				(font
					(size 1.27 1.27)
				)
				(justify mirror)
			)
		)
		(duplicate_pad_numbers_are_jumpers no)
		(fp_poly
			(pts
				(xy -0.3048 -0.1016) (xy -0.3048 0.9906) (xy 0.3048 0.9906) (xy 0.3048 -0.1016)
			)
			(stroke
				(width 0)
				(type default)
			)
			(fill no)
			(layer "B.CrtYd")
		)
		(fp_line
			(start 0.3048 -0.1016)
			(end 0.3048 0.9906)
			(stroke
				(width 0.1)
				(type default)
			)
			(layer "B.Fab")
		)
		(fp_line
			(start -0.3048 -0.1016)
			(end 0.3048 -0.1016)
			(stroke
				(width 0.1)
				(type default)
			)
			(layer "B.Fab")
		)
		(fp_line
			(start 0.3048 0.9906)
			(end -0.3048 0.9906)
			(stroke
				(width 0.1)
				(type default)
			)
			(layer "B.Fab")
		)
		(fp_line
			(start -0.3048 0.9906)
			(end -0.3048 -0.1016)
			(stroke
				(width 0.1)
				(type default)
			)
			(layer "B.Fab")
		)
		(pad "1" smd rect
			(at 0 0 270)
			(size 0.508 0.508)
			(layers "B.Cu" "B.Mask" "B.Paste")
			(net "VR_FET_SW_P12V_STBY_PVDDQ_GHJ")
		)
		(pad "2" smd rect
			(at 0 0.889 270)
			(size 0.508 0.508)
			(layers "B.Cu" "B.Mask" "B.Paste")
			(net "GND")
		)
		(zone
			(layer "B.Cu")
			(hatch none 0.5)
			(connect_pads
				(clearance 0)
			)
			(min_thickness 0.25)
			(keepout
				(tracks allowed)
				(vias not_allowed)
				(pads allowed)
				(copperpour not_allowed)
				(footprints allowed)
			)
			(placement
				(enabled no)
				(sheetname "")
			)
			(fill
				(thermal_gap 0.5)
				(thermal_bridge_width 0.5)
				(island_removal_mode 0)
			)
			(polygon
				(pts
					(xy 4.51104 -12.827) (xy 4.51104 -12.319) (xy 4.89204 -12.319) (xy 4.89204 -12.827)
				)
			)
		)
		(zone
			(layer "B.Cu")
			(hatch none 0.5)
			(connect_pads
				(clearance 0)
			)
			(min_thickness 0.25)
			(keepout
				(tracks not_allowed)
				(vias allowed)
				(pads allowed)
				(copperpour not_allowed)
				(footprints allowed)
			)
			(placement
				(enabled no)
				(sheetname "")
			)
			(fill
				(thermal_gap 0.5)
				(thermal_bridge_width 0.5)
				(island_removal_mode 0)
			)
			(polygon
				(pts
					(xy 4.89204 -12.827) (xy 4.89204 -12.319) (xy 4.51104 -12.319) (xy 4.51104 -12.827)
				)
			)
		)
	)
	(footprint ""
		(layer "B.Cu")
		(at 228.1174 -87.5792 90)
		(property "Reference" "R4C1"
			(at 0.8382 -0.67818 90)
			(unlocked yes)
			(layer "B.SilkS")
			(effects
				(font
					(size 0.4064 0.254)
					(thickness 0.1524)
				)
				(justify left mirror)
			)
		)
		(property "Value" ""
			(at 0 0 90)
			(layer "B.Fab")
			(effects
				(font
					(size 1.27 1.27)
				)
				(justify mirror)
			)
		)
		(duplicate_pad_numbers_are_jumpers no)
		(fp_poly
			(pts
				(xy 0.2794 -0.1016) (xy -0.2794 -0.1016) (xy -0.2794 0.9906) (xy 0.2794 0.9906)
			)
			(stroke
				(width 0)
				(type default)
			)
			(fill no)
			(layer "B.CrtYd")
		)
		(fp_line
			(start 0.2794 -0.1016)
			(end 0.2794 0.9906)
			(stroke
				(width 0.1)
				(type default)
			)
			(layer "B.Fab")
		)
		(fp_line
			(start -0.2794 -0.1016)
			(end 0.2794 -0.1016)
			(stroke
				(width 0.1)
				(type default)
			)
			(layer "B.Fab")
		)
		(fp_line
			(start 0.2794 0.9906)
			(end -0.2794 0.9906)
			(stroke
				(width 0.1)
				(type default)
			)
			(layer "B.Fab")
		)
		(fp_line
			(start -0.2794 0.9906)
			(end -0.2794 -0.1016)
			(stroke
				(width 0.1)
				(type default)
			)
			(layer "B.Fab")
		)
		(pad "1" smd rect
			(at 0 0 270)
			(size 0.508 0.508)
			(layers "B.Cu" "B.Mask" "B.Paste")
			(net "VSENSE_PVSA_CPU0_N")
		)
		(pad "2" smd rect
			(at 0 0.889 270)
			(size 0.508 0.508)
			(layers "B.Cu" "B.Mask" "B.Paste")
			(net "GND")
		)
		(zone
			(layer "B.Cu")
			(hatch none 0.5)
			(connect_pads
				(clearance 0)
			)
			(min_thickness 0.25)
			(keepout
				(tracks allowed)
				(vias not_allowed)
				(pads allowed)
				(copperpour not_allowed)
				(footprints allowed)
			)
			(placement
				(enabled no)
				(sheetname "")
			)
			(fill
				(thermal_gap 0.5)
				(thermal_bridge_width 0.5)
				(island_removal_mode 0)
			)
			(polygon
				(pts
					(xy 228.3714 -87.8332) (xy 228.3714 -87.3252) (xy 228.7524 -87.3252) (xy 228.7524 -87.8332)
				)
			)
		)
		(zone
			(layer "B.Cu")
			(hatch none 0.5)
			(connect_pads
				(clearance 0)
			)
			(min_thickness 0.25)
			(keepout
				(tracks not_allowed)
				(vias allowed)
				(pads allowed)
				(copperpour not_allowed)
				(footprints allowed)
			)
			(placement
				(enabled no)
				(sheetname "")
			)
			(fill
				(thermal_gap 0.5)
				(thermal_bridge_width 0.5)
				(island_removal_mode 0)
			)
			(polygon
				(pts
					(xy 228.7524 -87.8332) (xy 228.7524 -87.3252) (xy 228.3714 -87.3252) (xy 228.3714 -87.8332)
				)
			)
		)
	)
	(footprint ""
		(layer "B.Cu")
		(at 414.5407 -37.76218)
		(property "Reference" "C25W28"
			(at 0.8382 -0.67818 0)
			(unlocked yes)
			(layer "B.SilkS")
			(effects
				(font
					(size 0.4064 0.254)
					(thickness 0.1524)
				)
				(justify left mirror)
			)
		)
		(property "Value" ""
			(at 0 0 0)
			(layer "B.Fab")
			(effects
				(font
					(size 1.27 1.27)
				)
				(justify mirror)
			)
		)
		(duplicate_pad_numbers_are_jumpers no)
		(fp_poly
			(pts
				(xy -0.3048 -0.1016) (xy -0.3048 0.9906) (xy 0.3048 0.9906) (xy 0.3048 -0.1016)
			)
			(stroke
				(width 0)
				(type default)
			)
			(fill no)
			(layer "B.CrtYd")
		)
		(fp_line
			(start -0.3048 -0.1016)
			(end 0.3048 -0.1016)
			(stroke
				(width 0.1)
				(type default)
			)
			(layer "B.Fab")
		)
		(fp_line
			(start -0.3048 0.9906)
			(end -0.3048 -0.1016)
			(stroke
				(width 0.1)
				(type default)
			)
			(layer "B.Fab")
		)
		(fp_line
			(start 0.3048 -0.1016)
			(end 0.3048 0.9906)
			(stroke
				(width 0.1)
				(type default)
			)
			(layer "B.Fab")
		)
		(fp_line
			(start 0.3048 0.9906)
			(end -0.3048 0.9906)
			(stroke
				(width 0.1)
				(type default)
			)
			(layer "B.Fab")
		)
		(pad "1" smd rect
			(at 0 0 180)
			(size 0.508 0.508)
			(layers "B.Cu" "B.Mask" "B.Paste")
			(net "P1V15_AUX_BMC")
		)
		(pad "2" smd rect
			(at 0 0.889 180)
			(size 0.508 0.508)
			(layers "B.Cu" "B.Mask" "B.Paste")
			(net "GND")
		)
		(zone
			(layer "B.Cu")
			(hatch none 0.5)
			(connect_pads
				(clearance 0)
			)
			(min_thickness 0.25)
			(keepout
				(tracks allowed)
				(vias not_allowed)
				(pads allowed)
				(copperpour not_allowed)
				(footprints allowed)
			)
			(placement
				(enabled no)
				(sheetname "")
			)
			(fill
				(thermal_gap 0.5)
				(thermal_bridge_width 0.5)
				(island_removal_mode 0)
			)
			(polygon
				(pts
					(xy 414.7947 -37.50818) (xy 414.2867 -37.50818) (xy 414.2867 -37.12718) (xy 414.7947 -37.12718)
				)
			)
		)
		(zone
			(layer "B.Cu")
			(hatch none 0.5)
			(connect_pads
				(clearance 0)
			)
			(min_thickness 0.25)
			(keepout
				(tracks not_allowed)
				(vias allowed)
				(pads allowed)
				(copperpour not_allowed)
				(footprints allowed)
			)
			(placement
				(enabled no)
				(sheetname "")
			)
			(fill
				(thermal_gap 0.5)
				(thermal_bridge_width 0.5)
				(island_removal_mode 0)
			)
			(polygon
				(pts
					(xy 414.7947 -37.12718) (xy 414.2867 -37.12718) (xy 414.2867 -37.50818) (xy 414.7947 -37.50818)
				)
			)
		)
	)
	(footprint ""
		(layer "B.Cu")
		(at 184.20842 2.63652 -90)
		(property "Reference" "C6W11"
			(at -1.47828 0.78994 0)
			(unlocked yes)
			(layer "B.SilkS")
			(effects
				(font
					(size 0.4064 0.254)
					(thickness 0.1524)
				)
				(justify mirror)
			)
		)
		(property "Value" ""
			(at 0 0 90)
			(layer "B.Fab")
			(effects
				(font
					(size 1.27 1.27)
				)
				(justify mirror)
			)
		)
		(duplicate_pad_numbers_are_jumpers no)
		(fp_poly
			(pts
				(xy 0.7239 -0.2159) (xy -0.7239 -0.2159) (xy -0.7239 1.9939) (xy 0.7239 1.9939)
			)
			(stroke
				(width 0)
				(type default)
			)
			(fill no)
			(layer "B.CrtYd")
		)
		(fp_line
			(start -0.7239 1.9939)
			(end -0.7239 -0.2159)
			(stroke
				(width 0.1)
				(type default)
			)
			(layer "B.Fab")
		)
		(fp_line
			(start 0.7239 1.9939)
			(end -0.7239 1.9939)
			(stroke
				(width 0.1)
				(type default)
			)
			(layer "B.Fab")
		)
		(fp_line
			(start -0.7239 -0.2159)
			(end 0.7239 -0.2159)
			(stroke
				(width 0.1)
				(type default)
			)
			(layer "B.Fab")
		)
		(fp_line
			(start 0.7239 -0.2159)
			(end 0.7239 1.9939)
			(stroke
				(width 0.1)
				(type default)
			)
			(layer "B.Fab")
		)
		(pad "1" smd rect
			(at 0 0 90)
			(size 1.27 1.016)
			(layers "B.Cu" "B.Mask" "B.Paste")
			(net "PVTT_ABC")
		)
		(pad "2" smd rect
			(at 0 1.778 90)
			(size 1.27 1.016)
			(layers "B.Cu" "B.Mask" "B.Paste")
			(net "GND")
		)
		(zone
			(layer "B.Cu")
			(hatch none 0.5)
			(connect_pads
				(clearance 0)
			)
			(min_thickness 0.25)
			(keepout
				(tracks not_allowed)
				(vias allowed)
				(pads allowed)
				(copperpour not_allowed)
				(footprints allowed)
			)
			(placement
				(enabled no)
				(sheetname "")
			)
			(fill
				(thermal_gap 0.5)
				(thermal_bridge_width 0.5)
				(island_removal_mode 0)
			)
			(polygon
				(pts
					(xy 183.70042 3.27152) (xy 183.70042 2.00152) (xy 182.93842 2.00152) (xy 182.93842 3.27152)
				)
			)
		)
	)
	(footprint ""
		(layer "B.Cu")
		(at 393.005818 -14.637004)
		(property "Reference" "U32W1"
			(at 0 0 0)
			(layer "B.SilkS")
			(hide yes)
			(effects
				(font
					(size 1.27 1.27)
				)
				(justify mirror)
			)
		)
		(property "Value" "*"
			(at 0.1143 -9.3091 0)
			(unlocked yes)
			(layer "B.Fab")
			(hide yes)
			(effects
				(font
					(size 1.27 1.016)
					(thickness 0.1524)
				)
				(justify mirror)
			)
		)
		(property "Device Type" "TCA9517DGKR-GP_DISCRET-G8-TCA9A"
			(at 0.1143 -10.9093 0)
			(unlocked yes)
			(layer "B.Fab")
			(hide yes)
			(effects
				(font
					(size 1.27 1.016)
					(thickness 0.1524)
				)
				(justify mirror)
			)
		)
		(duplicate_pad_numbers_are_jumpers no)
		(fp_line
			(start -1.0795 -1.016)
			(end 1.9558 -1.016)
			(stroke
				(width 0.1524)
				(type default)
			)
			(layer "B.SilkS")
		)
		(fp_line
			(start -1.0795 1.016)
			(end -1.0795 -1.016)
			(stroke
				(width 0.1524)
				(type default)
			)
			(layer "B.SilkS")
		)
		(fp_line
			(start 1.4478 -0.0381)
			(end 1.9558 0.4699)
			(stroke
				(width 0.1524)
				(type default)
			)
			(layer "B.SilkS")
		)
		(fp_line
			(start 1.778 1.0922)
			(end 1.778 3.048)
			(stroke
				(width 0.508)
				(type default)
			)
			(layer "B.SilkS")
		)
		(fp_line
			(start 1.9558 -1.016)
			(end 1.9558 1.016)
			(stroke
				(width 0.1524)
				(type default)
			)
			(layer "B.SilkS")
		)
		(fp_line
			(start 1.9558 -0.5461)
			(end 1.4478 -0.0381)
			(stroke
				(width 0.1524)
				(type default)
			)
			(layer "B.SilkS")
		)
		(fp_line
			(start 1.9558 1.016)
			(end -1.0795 1.016)
			(stroke
				(width 0.1524)
				(type default)
			)
			(layer "B.SilkS")
		)
		(fp_poly
			(pts
				(xy 1.1557 -1.016) (xy 1.1557 1.016) (xy -1.1557 1.016) (xy -1.1557 -1.016)
			)
			(stroke
				(width 0)
				(type default)
			)
			(fill yes)
			(layer "B.SilkS")
		)
		(fp_rect
			(start 1.4986 2.4511)
			(end -1.4986 -2.4511)
			(stroke
				(width 0)
				(type default)
			)
			(fill no)
			(layer "B.CrtYd")
		)
		(fp_poly
			(pts
				(xy 2.032 3.302) (xy 2.032 -3.302) (xy -2.032 -3.302) (xy -2.032 -2.1209) (xy -1.4986 -2.1209) (xy -1.4986 -2.4511)
				(xy 1.4986 -2.4511) (xy 1.4986 2.4511) (xy -1.4986 2.4511) (xy -1.4986 -2.1082) (xy -2.032 -2.1082)
				(xy -2.032 3.302)
			)
			(stroke
				(width 0)
				(type default)
			)
			(fill no)
			(layer "B.CrtYd")
		)
		(fp_rect
			(start 2.032 3.302)
			(end -2.032 -3.302)
			(stroke
				(width 0)
				(type default)
			)
			(fill no)
			(layer "B.Fab")
		)
		(pad "1" smd rect
			(at 0.97536 2.05486 180)
			(size 0.3556 1.524)
			(layers "B.Cu" "B.Mask" "B.Paste")
			(net "P1V8_M2")
		)
		(pad "2" smd rect
			(at 0.32512 2.05486 180)
			(size 0.3556 1.524)
			(layers "B.Cu" "B.Mask" "B.Paste")
			(net "SMB_M2_SCL_R")
		)
		(pad "3" smd rect
			(at -0.32512 2.05486 180)
			(size 0.3556 1.524)
			(layers "B.Cu" "B.Mask" "B.Paste")
			(net "SMB_M2_SDA_R")
		)
		(pad "4" smd rect
			(at -0.97536 2.05486 180)
			(size 0.3556 1.524)
			(layers "B.Cu" "B.Mask" "B.Paste")
			(net "GND")
		)
		(pad "5" smd rect
			(at -0.97536 -2.05486 180)
			(size 0.3556 1.524)
			(layers "B.Cu" "B.Mask" "B.Paste")
			(net "PD_SMB_M2_EN")
		)
		(pad "6" smd rect
			(at -0.32512 -2.05486 180)
			(size 0.3556 1.524)
			(layers "B.Cu" "B.Mask" "B.Paste")
			(net "SMB_OCP_LAN_STBY_LVC3_SDA")
		)
		(pad "7" smd rect
			(at 0.32512 -2.05486 180)
			(size 0.3556 1.524)
			(layers "B.Cu" "B.Mask" "B.Paste")
			(net "SMB_OCP_LAN_STBY_LVC3_SCL")
		)
		(pad "8" smd rect
			(at 0.97536 -2.05486 180)
			(size 0.3556 1.524)
			(layers "B.Cu" "B.Mask" "B.Paste")
			(net "P3V3_STBY")
		)
	)
	(footprint ""
		(layer "B.Cu")
		(at 410.464 -125.476 90)
		(property "Reference" "C2M6"
			(at 0 0 90)
			(layer "B.SilkS")
			(hide yes)
			(effects
				(font
					(size 1.27 1.27)
				)
				(justify mirror)
			)
		)
		(property "Value" ""
			(at 0 0 90)
			(layer "B.Fab")
			(effects
				(font
					(size 1.27 1.27)
				)
				(justify mirror)
			)
		)
		(duplicate_pad_numbers_are_jumpers no)
		(fp_poly
			(pts
				(xy -0.3048 -0.1016) (xy -0.3048 0.9906) (xy 0.3048 0.9906) (xy 0.3048 -0.1016)
			)
			(stroke
				(width 0)
				(type default)
			)
			(fill no)
			(layer "B.CrtYd")
		)
		(fp_line
			(start 0.3048 -0.1016)
			(end 0.3048 0.9906)
			(stroke
				(width 0.1)
				(type default)
			)
			(layer "B.Fab")
		)
		(fp_line
			(start -0.3048 -0.1016)
			(end 0.3048 -0.1016)
			(stroke
				(width 0.1)
				(type default)
			)
			(layer "B.Fab")
		)
		(fp_line
			(start 0.3048 0.9906)
			(end -0.3048 0.9906)
			(stroke
				(width 0.1)
				(type default)
			)
			(layer "B.Fab")
		)
		(fp_line
			(start -0.3048 0.9906)
			(end -0.3048 -0.1016)
			(stroke
				(width 0.1)
				(type default)
			)
			(layer "B.Fab")
		)
		(pad "1" smd rect
			(at 0 0 270)
			(size 0.508 0.508)
			(layers "B.Cu" "B.Mask" "B.Paste")
			(net "P1V05_PCH_STBY")
		)
		(pad "2" smd rect
			(at 0 0.889 270)
			(size 0.508 0.508)
			(layers "B.Cu" "B.Mask" "B.Paste")
			(net "GND")
		)
		(zone
			(layer "B.Cu")
			(hatch none 0.5)
			(connect_pads
				(clearance 0)
			)
			(min_thickness 0.25)
			(keepout
				(tracks allowed)
				(vias not_allowed)
				(pads allowed)
				(copperpour not_allowed)
				(footprints allowed)
			)
			(placement
				(enabled no)
				(sheetname "")
			)
			(fill
				(thermal_gap 0.5)
				(thermal_bridge_width 0.5)
				(island_removal_mode 0)
			)
			(polygon
				(pts
					(xy 410.718 -125.73) (xy 410.718 -125.222) (xy 411.099 -125.222) (xy 411.099 -125.73)
				)
			)
		)
		(zone
			(layer "B.Cu")
			(hatch none 0.5)
			(connect_pads
				(clearance 0)
			)
			(min_thickness 0.25)
			(keepout
				(tracks not_allowed)
				(vias allowed)
				(pads allowed)
				(copperpour not_allowed)
				(footprints allowed)
			)
			(placement
				(enabled no)
				(sheetname "")
			)
			(fill
				(thermal_gap 0.5)
				(thermal_bridge_width 0.5)
				(island_removal_mode 0)
			)
			(polygon
				(pts
					(xy 411.099 -125.73) (xy 411.099 -125.222) (xy 410.718 -125.222) (xy 410.718 -125.73)
				)
			)
		)
	)
	(footprint ""
		(layer "B.Cu")
		(at 9.061958 3.20802)
		(property "Reference" "R12W12"
			(at 0 0 0)
			(layer "B.SilkS")
			(hide yes)
			(effects
				(font
					(size 1.27 1.27)
				)
				(justify mirror)
			)
		)
		(property "Value" "*"
			(at 0 -8.9535 0)
			(unlocked yes)
			(layer "B.Fab")
			(hide yes)
			(effects
				(font
					(size 1.27 1.016)
					(thickness 0.1524)
				)
				(justify mirror)
			)
		)
		(property "Device Type" "665KR5B-1-GP_SMD-RG3-665KR5B-1A"
			(at 0 -10.6299 0)
			(unlocked yes)
			(layer "B.Fab")
			(hide yes)
			(effects
				(font
					(size 1.27 1.016)
					(thickness 0.1524)
				)
				(justify mirror)
			)
		)
		(duplicate_pad_numbers_are_jumpers no)
		(fp_line
			(start -0.889 -1.7018)
			(end -0.889 -0.381)
			(stroke
				(width 0.1524)
				(type default)
			)
			(layer "B.SilkS")
		)
		(fp_line
			(start -0.889 -1.7018)
			(end 0.889 -1.7018)
			(stroke
				(width 0.1524)
				(type default)
			)
			(layer "B.SilkS")
		)
		(fp_line
			(start -0.889 1.7018)
			(end -0.889 -0.508)
			(stroke
				(width 0.1524)
				(type default)
			)
			(layer "B.SilkS")
		)
		(fp_line
			(start 0.889 -1.7018)
			(end 0.889 0.2794)
			(stroke
				(width 0.1524)
				(type default)
			)
			(layer "B.SilkS")
		)
		(fp_line
			(start 0.889 0.0762)
			(end 0.889 1.7018)
			(stroke
				(width 0.1524)
				(type default)
			)
			(layer "B.SilkS")
		)
		(fp_line
			(start 0.889 1.7018)
			(end -0.889 1.7018)
			(stroke
				(width 0.1524)
				(type default)
			)
			(layer "B.SilkS")
		)
		(fp_poly
			(pts
				(xy -0.9652 -1.778) (xy -0.9652 1.778) (xy 0.9652 1.778) (xy 0.9652 -1.778)
			)
			(stroke
				(width 0)
				(type default)
			)
			(fill no)
			(layer "B.CrtYd")
		)
		(fp_rect
			(start 0.9652 1.778)
			(end -0.9652 -1.778)
			(stroke
				(width 0)
				(type default)
			)
			(fill no)
			(layer "B.Fab")
		)
		(pad "1" smd rect
			(at 0 -0.9652 180)
			(size 1.397 1.143)
			(layers "B.Cu" "B.Mask" "B.Paste")
			(net "P12V_NVDIMM_GHJ_D")
		)
		(pad "2" smd rect
			(at 0 0.9652 180)
			(size 1.397 1.143)
			(layers "B.Cu" "B.Mask" "B.Paste")
			(net "VR_PVDDQ_GHJ_VINSEN")
		)
	)
	(footprint ""
		(layer "B.Cu")
		(at 23.114 -79.502 -90)
		(property "Reference" "R9P12"
			(at 0 0 90)
			(layer "B.SilkS")
			(hide yes)
			(effects
				(font
					(size 1.27 1.27)
				)
				(justify mirror)
			)
		)
		(property "Value" ""
			(at 0 0 90)
			(layer "B.Fab")
			(effects
				(font
					(size 1.27 1.27)
				)
				(justify mirror)
			)
		)
		(duplicate_pad_numbers_are_jumpers no)
		(fp_poly
			(pts
				(xy 0.2794 -0.1016) (xy -0.2794 -0.1016) (xy -0.2794 0.9906) (xy 0.2794 0.9906)
			)
			(stroke
				(width 0)
				(type default)
			)
			(fill no)
			(layer "B.CrtYd")
		)
		(fp_line
			(start -0.2794 0.9906)
			(end -0.2794 -0.1016)
			(stroke
				(width 0.1)
				(type default)
			)
			(layer "B.Fab")
		)
		(fp_line
			(start 0.2794 0.9906)
			(end -0.2794 0.9906)
			(stroke
				(width 0.1)
				(type default)
			)
			(layer "B.Fab")
		)
		(fp_line
			(start -0.2794 -0.1016)
			(end 0.2794 -0.1016)
			(stroke
				(width 0.1)
				(type default)
			)
			(layer "B.Fab")
		)
		(fp_line
			(start 0.2794 -0.1016)
			(end 0.2794 0.9906)
			(stroke
				(width 0.1)
				(type default)
			)
			(layer "B.Fab")
		)
		(pad "1" smd rect
			(at 0 0 90)
			(size 0.508 0.508)
			(layers "B.Cu" "B.Mask" "B.Paste")
			(net "A_HSC_INAP")
		)
		(pad "2" smd rect
			(at 0 0.889 90)
			(size 0.508 0.508)
			(layers "B.Cu" "B.Mask" "B.Paste")
			(net "AGND_HSC")
		)
		(zone
			(layer "B.Cu")
			(hatch none 0.5)
			(connect_pads
				(clearance 0)
			)
			(min_thickness 0.25)
			(keepout
				(tracks not_allowed)
				(vias allowed)
				(pads allowed)
				(copperpour not_allowed)
				(footprints allowed)
			)
			(placement
				(enabled no)
				(sheetname "")
			)
			(fill
				(thermal_gap 0.5)
				(thermal_bridge_width 0.5)
				(island_removal_mode 0)
			)
			(polygon
				(pts
					(xy 22.479 -79.248) (xy 22.479 -79.756) (xy 22.86 -79.756) (xy 22.86 -79.248)
				)
			)
		)
		(zone
			(layer "B.Cu")
			(hatch none 0.5)
			(connect_pads
				(clearance 0)
			)
			(min_thickness 0.25)
			(keepout
				(tracks allowed)
				(vias not_allowed)
				(pads allowed)
				(copperpour not_allowed)
				(footprints allowed)
			)
			(placement
				(enabled no)
				(sheetname "")
			)
			(fill
				(thermal_gap 0.5)
				(thermal_bridge_width 0.5)
				(island_removal_mode 0)
			)
			(polygon
				(pts
					(xy 22.86 -79.248) (xy 22.86 -79.756) (xy 22.479 -79.756) (xy 22.479 -79.248)
				)
			)
		)
	)
	(footprint ""
		(layer "B.Cu")
		(at 406.7048 -53.848 -90)
		(property "Reference" "Q1W2"
			(at 0 -0.81788 270)
			(unlocked yes)
			(layer "B.SilkS")
			(effects
				(font
					(size 0.4064 0.254)
					(thickness 0.1524)
				)
				(justify left mirror)
			)
		)
		(property "Value" ""
			(at 0 0 90)
			(layer "B.Fab")
			(effects
				(font
					(size 1.27 1.27)
				)
				(justify mirror)
			)
		)
		(duplicate_pad_numbers_are_jumpers no)
		(fp_circle
			(center 0.848614 -0.6477)
			(end 0.848614 -0.7747)
			(stroke
				(width 0.254)
				(type default)
			)
			(fill no)
			(layer "B.SilkS")
		)
		(fp_poly
			(pts
				(xy -0.21463 -0.450088) (xy -1.56337 -0.450088) (xy -1.56337 1.75006) (xy -0.21463 1.75006)
			)
			(stroke
				(width 0)
				(type default)
			)
			(fill no)
			(layer "B.CrtYd")
		)
		(fp_line
			(start -1.56337 1.75006)
			(end -0.21463 1.75006)
			(stroke
				(width 0.1)
				(type default)
			)
			(layer "B.Fab")
		)
		(fp_line
			(start -0.21463 1.75006)
			(end -0.21463 -0.450088)
			(stroke
				(width 0.1)
				(type default)
			)
			(layer "B.Fab")
		)
		(fp_line
			(start -1.56337 -0.450088)
			(end -1.56337 1.75006)
			(stroke
				(width 0.1)
				(type default)
			)
			(layer "B.Fab")
		)
		(fp_line
			(start -0.21463 -0.450088)
			(end -1.56337 -0.450088)
			(stroke
				(width 0.1)
				(type default)
			)
			(layer "B.Fab")
		)
		(fp_circle
			(center 0.848614 -0.6477)
			(end 0.848614 -0.7747)
			(stroke
				(width 0.254)
				(type default)
			)
			(fill no)
			(layer "B.Fab")
		)
		(pad "1" smd rect
			(at 0 0 90)
			(size 1.016 0.381)
			(layers "B.Cu" "B.Mask" "B.Paste")
			(net "GND")
		)
		(pad "2" smd rect
			(at 0 0.649986 90)
			(size 1.016 0.381)
			(layers "B.Cu" "B.Mask" "B.Paste")
			(net "FM_OCP_MEZZB_PRES_N")
		)
		(pad "3" smd rect
			(at 0 1.299972 90)
			(size 1.016 0.381)
			(layers "B.Cu" "B.Mask" "B.Paste")
			(net "FM_OCP_MEZZB_PRES_1V05_PCH_N")
		)
		(pad "4" smd rect
			(at -1.778 1.299972 90)
			(size 1.016 0.381)
			(layers "B.Cu" "B.Mask" "B.Paste")
			(net "GND")
		)
		(pad "5" smd rect
			(at -1.778 0.649986 90)
			(size 1.016 0.381)
			(layers "B.Cu" "B.Mask" "B.Paste")
			(net "FM_OCP_MEZZB_PRES_LVT3_BMC")
		)
		(pad "6" smd rect
			(at -1.778 0 90)
			(size 1.016 0.381)
			(layers "B.Cu" "B.Mask" "B.Paste")
			(net "FM_OCP_MEZZB_PRES_LVT3_BMC")
		)
	)
	(footprint ""
		(layer "B.Cu")
		(at 372.631716 -59.289442 180)
		(property "Reference" "C3P49"
			(at 0 0 0)
			(layer "B.SilkS")
			(hide yes)
			(effects
				(font
					(size 1.27 1.27)
				)
				(justify mirror)
			)
		)
		(property "Value" ""
			(at 0 0 0)
			(layer "B.Fab")
			(effects
				(font
					(size 1.27 1.27)
				)
				(justify mirror)
			)
		)
		(duplicate_pad_numbers_are_jumpers no)
		(fp_poly
			(pts
				(xy -0.3048 -0.1016) (xy -0.3048 0.9906) (xy 0.3048 0.9906) (xy 0.3048 -0.1016)
			)
			(stroke
				(width 0)
				(type default)
			)
			(fill no)
			(layer "B.CrtYd")
		)
		(fp_line
			(start 0.3048 0.9906)
			(end -0.3048 0.9906)
			(stroke
				(width 0.1)
				(type default)
			)
			(layer "B.Fab")
		)
		(fp_line
			(start 0.3048 -0.1016)
			(end 0.3048 0.9906)
			(stroke
				(width 0.1)
				(type default)
			)
			(layer "B.Fab")
		)
		(fp_line
			(start -0.3048 0.9906)
			(end -0.3048 -0.1016)
			(stroke
				(width 0.1)
				(type default)
			)
			(layer "B.Fab")
		)
		(fp_line
			(start -0.3048 -0.1016)
			(end 0.3048 -0.1016)
			(stroke
				(width 0.1)
				(type default)
			)
			(layer "B.Fab")
		)
		(pad "1" smd rect
			(at 0 0)
			(size 0.508 0.508)
			(layers "B.Cu" "B.Mask" "B.Paste")
			(net "P0V7_GTL2104_VREF_1")
		)
		(pad "2" smd rect
			(at 0 0.889)
			(size 0.508 0.508)
			(layers "B.Cu" "B.Mask" "B.Paste")
			(net "GND")
		)
		(zone
			(layer "B.Cu")
			(hatch none 0.5)
			(connect_pads
				(clearance 0)
			)
			(min_thickness 0.25)
			(keepout
				(tracks not_allowed)
				(vias allowed)
				(pads allowed)
				(copperpour not_allowed)
				(footprints allowed)
			)
			(placement
				(enabled no)
				(sheetname "")
			)
			(fill
				(thermal_gap 0.5)
				(thermal_bridge_width 0.5)
				(island_removal_mode 0)
			)
			(polygon
				(pts
					(xy 372.377716 -59.924442) (xy 372.885716 -59.924442) (xy 372.885716 -59.543442) (xy 372.377716 -59.543442)
				)
			)
		)
		(zone
			(layer "B.Cu")
			(hatch none 0.5)
			(connect_pads
				(clearance 0)
			)
			(min_thickness 0.25)
			(keepout
				(tracks allowed)
				(vias not_allowed)
				(pads allowed)
				(copperpour not_allowed)
				(footprints allowed)
			)
			(placement
				(enabled no)
				(sheetname "")
			)
			(fill
				(thermal_gap 0.5)
				(thermal_bridge_width 0.5)
				(island_removal_mode 0)
			)
			(polygon
				(pts
					(xy 372.377716 -59.543442) (xy 372.885716 -59.543442) (xy 372.885716 -59.924442) (xy 372.377716 -59.924442)
				)
			)
		)
	)
	(footprint ""
		(layer "B.Cu")
		(at 474.41866 -29.96692 90)
		(property "Reference" "C2T27"
			(at 0 0 90)
			(layer "B.SilkS")
			(hide yes)
			(effects
				(font
					(size 1.27 1.27)
				)
				(justify mirror)
			)
		)
		(property "Value" ""
			(at 0 0 90)
			(layer "B.Fab")
			(effects
				(font
					(size 1.27 1.27)
				)
				(justify mirror)
			)
		)
		(duplicate_pad_numbers_are_jumpers no)
		(fp_poly
			(pts
				(xy -0.3048 -0.1016) (xy -0.3048 0.9906) (xy 0.3048 0.9906) (xy 0.3048 -0.1016)
			)
			(stroke
				(width 0)
				(type default)
			)
			(fill no)
			(layer "B.CrtYd")
		)
		(fp_line
			(start 0.3048 -0.1016)
			(end 0.3048 0.9906)
			(stroke
				(width 0.1)
				(type default)
			)
			(layer "B.Fab")
		)
		(fp_line
			(start -0.3048 -0.1016)
			(end 0.3048 -0.1016)
			(stroke
				(width 0.1)
				(type default)
			)
			(layer "B.Fab")
		)
		(fp_line
			(start 0.3048 0.9906)
			(end -0.3048 0.9906)
			(stroke
				(width 0.1)
				(type default)
			)
			(layer "B.Fab")
		)
		(fp_line
			(start -0.3048 0.9906)
			(end -0.3048 -0.1016)
			(stroke
				(width 0.1)
				(type default)
			)
			(layer "B.Fab")
		)
		(pad "1" smd rect
			(at 0 0 270)
			(size 0.508 0.508)
			(layers "B.Cu" "B.Mask" "B.Paste")
			(net "P3V3_STBY_MNG_RGMII")
		)
		(pad "2" smd rect
			(at 0 0.889 270)
			(size 0.508 0.508)
			(layers "B.Cu" "B.Mask" "B.Paste")
			(net "GND")
		)
		(zone
			(layer "B.Cu")
			(hatch none 0.5)
			(connect_pads
				(clearance 0)
			)
			(min_thickness 0.25)
			(keepout
				(tracks allowed)
				(vias not_allowed)
				(pads allowed)
				(copperpour not_allowed)
				(footprints allowed)
			)
			(placement
				(enabled no)
				(sheetname "")
			)
			(fill
				(thermal_gap 0.5)
				(thermal_bridge_width 0.5)
				(island_removal_mode 0)
			)
			(polygon
				(pts
					(xy 474.67266 -30.22092) (xy 474.67266 -29.71292) (xy 475.05366 -29.71292) (xy 475.05366 -30.22092)
				)
			)
		)
		(zone
			(layer "B.Cu")
			(hatch none 0.5)
			(connect_pads
				(clearance 0)
			)
			(min_thickness 0.25)
			(keepout
				(tracks not_allowed)
				(vias allowed)
				(pads allowed)
				(copperpour not_allowed)
				(footprints allowed)
			)
			(placement
				(enabled no)
				(sheetname "")
			)
			(fill
				(thermal_gap 0.5)
				(thermal_bridge_width 0.5)
				(island_removal_mode 0)
			)
			(polygon
				(pts
					(xy 475.05366 -30.22092) (xy 475.05366 -29.71292) (xy 474.67266 -29.71292) (xy 474.67266 -30.22092)
				)
			)
		)
	)
	(footprint ""
		(layer "B.Cu")
		(at 276.487128 -156.960824 90)
		(property "Reference" "C5L1"
			(at 0 0 90)
			(layer "B.SilkS")
			(hide yes)
			(effects
				(font
					(size 1.27 1.27)
				)
				(justify mirror)
			)
		)
		(property "Value" ""
			(at 0 0 90)
			(layer "B.Fab")
			(effects
				(font
					(size 1.27 1.27)
				)
				(justify mirror)
			)
		)
		(duplicate_pad_numbers_are_jumpers no)
		(fp_rect
			(start 0.7239 1.9939)
			(end -0.7239 -0.2159)
			(stroke
				(width 0)
				(type default)
			)
			(fill no)
			(layer "B.CrtYd")
		)
		(fp_line
			(start 0.7239 -0.2159)
			(end 0.7239 1.9939)
			(stroke
				(width 0.1)
				(type default)
			)
			(layer "B.Fab")
		)
		(fp_line
			(start -0.7239 -0.2159)
			(end 0.7239 -0.2159)
			(stroke
				(width 0.1)
				(type default)
			)
			(layer "B.Fab")
		)
		(fp_line
			(start 0.7239 1.9939)
			(end -0.7239 1.9939)
			(stroke
				(width 0.1)
				(type default)
			)
			(layer "B.Fab")
		)
		(fp_line
			(start -0.7239 1.9939)
			(end -0.7239 -0.2159)
			(stroke
				(width 0.1)
				(type default)
			)
			(layer "B.Fab")
		)
		(pad "1" smd rect
			(at 0 0 270)
			(size 1.27 1.016)
			(layers "B.Cu" "B.Mask" "B.Paste")
			(net "PVDDQ_DEF")
		)
		(pad "2" smd rect
			(at 0 1.778 270)
			(size 1.27 1.016)
			(layers "B.Cu" "B.Mask" "B.Paste")
			(net "GND")
		)
		(zone
			(layer "B.Cu")
			(hatch none 0.5)
			(connect_pads
				(clearance 0)
			)
			(min_thickness 0.25)
			(keepout
				(tracks not_allowed)
				(vias allowed)
				(pads allowed)
				(copperpour not_allowed)
				(footprints allowed)
			)
			(placement
				(enabled no)
				(sheetname "")
			)
			(fill
				(thermal_gap 0.5)
				(thermal_bridge_width 0.5)
				(island_removal_mode 0)
			)
			(polygon
				(pts
					(xy 277.757128 -157.595824) (xy 276.995128 -157.595824) (xy 276.995128 -156.325824) (xy 277.757128 -156.325824)
				)
			)
		)
	)
	(footprint ""
		(layer "B.Cu")
		(at 404.0124 -105.8545 180)
		(property "Reference" "C2N17"
			(at 0 0 0)
			(layer "B.SilkS")
			(hide yes)
			(effects
				(font
					(size 1.27 1.27)
				)
				(justify mirror)
			)
		)
		(property "Value" ""
			(at 0 0 0)
			(layer "B.Fab")
			(effects
				(font
					(size 1.27 1.27)
				)
				(justify mirror)
			)
		)
		(duplicate_pad_numbers_are_jumpers no)
		(fp_poly
			(pts
				(xy 0.4953 -0.2032) (xy -0.4953 -0.2032) (xy -0.4953 1.6002) (xy 0.4953 1.6002)
			)
			(stroke
				(width 0)
				(type default)
			)
			(fill no)
			(layer "B.CrtYd")
		)
		(fp_line
			(start 0.4953 1.6002)
			(end 0.4953 -0.2032)
			(stroke
				(width 0.1)
				(type default)
			)
			(layer "B.Fab")
		)
		(fp_line
			(start 0.4953 -0.2032)
			(end -0.4953 -0.2032)
			(stroke
				(width 0.1)
				(type default)
			)
			(layer "B.Fab")
		)
		(fp_line
			(start -0.4953 1.6002)
			(end 0.4953 1.6002)
			(stroke
				(width 0.1)
				(type default)
			)
			(layer "B.Fab")
		)
		(fp_line
			(start -0.4953 -0.2032)
			(end -0.4953 1.6002)
			(stroke
				(width 0.1)
				(type default)
			)
			(layer "B.Fab")
		)
		(pad "1" smd rect
			(at 0 0)
			(size 0.762 0.889)
			(layers "B.Cu" "B.Mask" "B.Paste")
			(net "P3V3_STBY")
		)
		(pad "2" smd rect
			(at 0 1.397)
			(size 0.762 0.889)
			(layers "B.Cu" "B.Mask" "B.Paste")
			(net "GND")
		)
		(zone
			(layer "B.Cu")
			(hatch none 0.5)
			(connect_pads
				(clearance 0)
			)
			(min_thickness 0.25)
			(keepout
				(tracks not_allowed)
				(vias allowed)
				(pads allowed)
				(copperpour not_allowed)
				(footprints allowed)
			)
			(placement
				(enabled no)
				(sheetname "")
			)
			(fill
				(thermal_gap 0.5)
				(thermal_bridge_width 0.5)
				(island_removal_mode 0)
			)
			(polygon
				(pts
					(xy 403.6314 -106.299) (xy 404.3934 -106.299) (xy 404.3934 -106.807) (xy 403.6314 -106.807)
				)
			)
		)
	)
	(footprint ""
		(layer "B.Cu")
		(at 373.6975 -55.88 -90)
		(property "Reference" "R3P41"
			(at 0 0 90)
			(layer "B.SilkS")
			(hide yes)
			(effects
				(font
					(size 1.27 1.27)
				)
				(justify mirror)
			)
		)
		(property "Value" ""
			(at 0 0 90)
			(layer "B.Fab")
			(effects
				(font
					(size 1.27 1.27)
				)
				(justify mirror)
			)
		)
		(duplicate_pad_numbers_are_jumpers no)
		(fp_poly
			(pts
				(xy 0.2794 -0.1016) (xy -0.2794 -0.1016) (xy -0.2794 0.9906) (xy 0.2794 0.9906)
			)
			(stroke
				(width 0)
				(type default)
			)
			(fill no)
			(layer "B.CrtYd")
		)
		(fp_line
			(start -0.2794 0.9906)
			(end -0.2794 -0.1016)
			(stroke
				(width 0.1)
				(type default)
			)
			(layer "B.Fab")
		)
		(fp_line
			(start 0.2794 0.9906)
			(end -0.2794 0.9906)
			(stroke
				(width 0.1)
				(type default)
			)
			(layer "B.Fab")
		)
		(fp_line
			(start -0.2794 -0.1016)
			(end 0.2794 -0.1016)
			(stroke
				(width 0.1)
				(type default)
			)
			(layer "B.Fab")
		)
		(fp_line
			(start 0.2794 -0.1016)
			(end 0.2794 0.9906)
			(stroke
				(width 0.1)
				(type default)
			)
			(layer "B.Fab")
		)
		(pad "1" smd rect
			(at 0 0 90)
			(size 0.508 0.508)
			(layers "B.Cu" "B.Mask" "B.Paste")
			(net "PVCCIO_CPU1")
		)
		(pad "2" smd rect
			(at 0 0.889 90)
			(size 0.508 0.508)
			(layers "B.Cu" "B.Mask" "B.Paste")
			(net "H_CPU1_THERMTRIP_G_N")
		)
		(zone
			(layer "B.Cu")
			(hatch none 0.5)
			(connect_pads
				(clearance 0)
			)
			(min_thickness 0.25)
			(keepout
				(tracks not_allowed)
				(vias allowed)
				(pads allowed)
				(copperpour not_allowed)
				(footprints allowed)
			)
			(placement
				(enabled no)
				(sheetname "")
			)
			(fill
				(thermal_gap 0.5)
				(thermal_bridge_width 0.5)
				(island_removal_mode 0)
			)
			(polygon
				(pts
					(xy 373.0625 -55.626) (xy 373.0625 -56.134) (xy 373.4435 -56.134) (xy 373.4435 -55.626)
				)
			)
		)
		(zone
			(layer "B.Cu")
			(hatch none 0.5)
			(connect_pads
				(clearance 0)
			)
			(min_thickness 0.25)
			(keepout
				(tracks allowed)
				(vias not_allowed)
				(pads allowed)
				(copperpour not_allowed)
				(footprints allowed)
			)
			(placement
				(enabled no)
				(sheetname "")
			)
			(fill
				(thermal_gap 0.5)
				(thermal_bridge_width 0.5)
				(island_removal_mode 0)
			)
			(polygon
				(pts
					(xy 373.4435 -55.626) (xy 373.4435 -56.134) (xy 373.0625 -56.134) (xy 373.0625 -55.626)
				)
			)
		)
	)
	(footprint ""
		(layer "B.Cu")
		(at 470.404444 -7.53872 -90)
		(property "Reference" "C2U20"
			(at 0 0 90)
			(layer "B.SilkS")
			(hide yes)
			(effects
				(font
					(size 1.27 1.27)
				)
				(justify mirror)
			)
		)
		(property "Value" ""
			(at 0 0 90)
			(layer "B.Fab")
			(effects
				(font
					(size 1.27 1.27)
				)
				(justify mirror)
			)
		)
		(duplicate_pad_numbers_are_jumpers no)
		(fp_poly
			(pts
				(xy -0.3048 -0.1016) (xy -0.3048 0.9906) (xy 0.3048 0.9906) (xy 0.3048 -0.1016)
			)
			(stroke
				(width 0)
				(type default)
			)
			(fill no)
			(layer "B.CrtYd")
		)
		(fp_line
			(start -0.3048 0.9906)
			(end -0.3048 -0.1016)
			(stroke
				(width 0.1)
				(type default)
			)
			(layer "B.Fab")
		)
		(fp_line
			(start 0.3048 0.9906)
			(end -0.3048 0.9906)
			(stroke
				(width 0.1)
				(type default)
			)
			(layer "B.Fab")
		)
		(fp_line
			(start -0.3048 -0.1016)
			(end 0.3048 -0.1016)
			(stroke
				(width 0.1)
				(type default)
			)
			(layer "B.Fab")
		)
		(fp_line
			(start 0.3048 -0.1016)
			(end 0.3048 0.9906)
			(stroke
				(width 0.1)
				(type default)
			)
			(layer "B.Fab")
		)
		(pad "1" smd rect
			(at 0 0 90)
			(size 0.508 0.508)
			(layers "B.Cu" "B.Mask" "B.Paste")
			(net "P12V")
		)
		(pad "2" smd rect
			(at 0 0.889 90)
			(size 0.508 0.508)
			(layers "B.Cu" "B.Mask" "B.Paste")
			(net "GND")
		)
		(zone
			(layer "B.Cu")
			(hatch none 0.5)
			(connect_pads
				(clearance 0)
			)
			(min_thickness 0.25)
			(keepout
				(tracks not_allowed)
				(vias allowed)
				(pads allowed)
				(copperpour not_allowed)
				(footprints allowed)
			)
			(placement
				(enabled no)
				(sheetname "")
			)
			(fill
				(thermal_gap 0.5)
				(thermal_bridge_width 0.5)
				(island_removal_mode 0)
			)
			(polygon
				(pts
					(xy 469.769444 -7.28472) (xy 469.769444 -7.79272) (xy 470.150444 -7.79272) (xy 470.150444 -7.28472)
				)
			)
		)
		(zone
			(layer "B.Cu")
			(hatch none 0.5)
			(connect_pads
				(clearance 0)
			)
			(min_thickness 0.25)
			(keepout
				(tracks allowed)
				(vias not_allowed)
				(pads allowed)
				(copperpour not_allowed)
				(footprints allowed)
			)
			(placement
				(enabled no)
				(sheetname "")
			)
			(fill
				(thermal_gap 0.5)
				(thermal_bridge_width 0.5)
				(island_removal_mode 0)
			)
			(polygon
				(pts
					(xy 470.150444 -7.28472) (xy 470.150444 -7.79272) (xy 469.769444 -7.79272) (xy 469.769444 -7.28472)
				)
			)
		)
	)
	(footprint ""
		(layer "B.Cu")
		(at 103.333296 -156.910024 -90)
		(property "Reference" "C8L2"
			(at 0 0 90)
			(layer "B.SilkS")
			(hide yes)
			(effects
				(font
					(size 1.27 1.27)
				)
				(justify mirror)
			)
		)
		(property "Value" ""
			(at 0 0 90)
			(layer "B.Fab")
			(effects
				(font
					(size 1.27 1.27)
				)
				(justify mirror)
			)
		)
		(duplicate_pad_numbers_are_jumpers no)
		(fp_poly
			(pts
				(xy 0.7239 -0.2159) (xy -0.7239 -0.2159) (xy -0.7239 1.9939) (xy 0.7239 1.9939)
			)
			(stroke
				(width 0)
				(type default)
			)
			(fill no)
			(layer "B.CrtYd")
		)
		(fp_line
			(start -0.7239 1.9939)
			(end -0.7239 -0.2159)
			(stroke
				(width 0.1)
				(type default)
			)
			(layer "B.Fab")
		)
		(fp_line
			(start 0.7239 1.9939)
			(end -0.7239 1.9939)
			(stroke
				(width 0.1)
				(type default)
			)
			(layer "B.Fab")
		)
		(fp_line
			(start -0.7239 -0.2159)
			(end 0.7239 -0.2159)
			(stroke
				(width 0.1)
				(type default)
			)
			(layer "B.Fab")
		)
		(fp_line
			(start 0.7239 -0.2159)
			(end 0.7239 1.9939)
			(stroke
				(width 0.1)
				(type default)
			)
			(layer "B.Fab")
		)
		(pad "1" smd rect
			(at 0 0 90)
			(size 1.27 1.016)
			(layers "B.Cu" "B.Mask" "B.Paste")
			(net "PVDDQ_KLM")
		)
		(pad "2" smd rect
			(at 0 1.778 90)
			(size 1.27 1.016)
			(layers "B.Cu" "B.Mask" "B.Paste")
			(net "GND")
		)
		(zone
			(layer "B.Cu")
			(hatch none 0.5)
			(connect_pads
				(clearance 0)
			)
			(min_thickness 0.25)
			(keepout
				(tracks not_allowed)
				(vias allowed)
				(pads allowed)
				(copperpour not_allowed)
				(footprints allowed)
			)
			(placement
				(enabled no)
				(sheetname "")
			)
			(fill
				(thermal_gap 0.5)
				(thermal_bridge_width 0.5)
				(island_removal_mode 0)
			)
			(polygon
				(pts
					(xy 102.825296 -156.275024) (xy 102.825296 -157.545024) (xy 102.063296 -157.545024) (xy 102.063296 -156.275024)
				)
			)
		)
	)
	(footprint ""
		(layer "B.Cu")
		(at 400.667474 -22.221698 180)
		(property "Reference" "R1U26"
			(at 0 0 0)
			(layer "B.SilkS")
			(hide yes)
			(effects
				(font
					(size 1.27 1.27)
				)
				(justify mirror)
			)
		)
		(property "Value" ""
			(at 0 0 0)
			(layer "B.Fab")
			(effects
				(font
					(size 1.27 1.27)
				)
				(justify mirror)
			)
		)
		(duplicate_pad_numbers_are_jumpers no)
		(fp_poly
			(pts
				(xy 0.2794 -0.1016) (xy -0.2794 -0.1016) (xy -0.2794 0.9906) (xy 0.2794 0.9906)
			)
			(stroke
				(width 0)
				(type default)
			)
			(fill no)
			(layer "B.CrtYd")
		)
		(fp_line
			(start 0.2794 0.9906)
			(end -0.2794 0.9906)
			(stroke
				(width 0.1)
				(type default)
			)
			(layer "B.Fab")
		)
		(fp_line
			(start 0.2794 -0.1016)
			(end 0.2794 0.9906)
			(stroke
				(width 0.1)
				(type default)
			)
			(layer "B.Fab")
		)
		(fp_line
			(start -0.2794 0.9906)
			(end -0.2794 -0.1016)
			(stroke
				(width 0.1)
				(type default)
			)
			(layer "B.Fab")
		)
		(fp_line
			(start -0.2794 -0.1016)
			(end 0.2794 -0.1016)
			(stroke
				(width 0.1)
				(type default)
			)
			(layer "B.Fab")
		)
		(pad "1" smd rect
			(at 0 0)
			(size 0.508 0.508)
			(layers "B.Cu" "B.Mask" "B.Paste")
			(net "P3V3")
		)
		(pad "2" smd rect
			(at 0 0.889)
			(size 0.508 0.508)
			(layers "B.Cu" "B.Mask" "B.Paste")
			(net "A_P3V3_SCALED")
		)
		(zone
			(layer "B.Cu")
			(hatch none 0.5)
			(connect_pads
				(clearance 0)
			)
			(min_thickness 0.25)
			(keepout
				(tracks not_allowed)
				(vias allowed)
				(pads allowed)
				(copperpour not_allowed)
				(footprints allowed)
			)
			(placement
				(enabled no)
				(sheetname "")
			)
			(fill
				(thermal_gap 0.5)
				(thermal_bridge_width 0.5)
				(island_removal_mode 0)
			)
			(polygon
				(pts
					(xy 400.413474 -22.856698) (xy 400.921474 -22.856698) (xy 400.921474 -22.475698) (xy 400.413474 -22.475698)
				)
			)
		)
		(zone
			(layer "B.Cu")
			(hatch none 0.5)
			(connect_pads
				(clearance 0)
			)
			(min_thickness 0.25)
			(keepout
				(tracks allowed)
				(vias not_allowed)
				(pads allowed)
				(copperpour not_allowed)
				(footprints allowed)
			)
			(placement
				(enabled no)
				(sheetname "")
			)
			(fill
				(thermal_gap 0.5)
				(thermal_bridge_width 0.5)
				(island_removal_mode 0)
			)
			(polygon
				(pts
					(xy 400.413474 -22.475698) (xy 400.921474 -22.475698) (xy 400.921474 -22.856698) (xy 400.413474 -22.856698)
				)
			)
		)
	)
	(footprint ""
		(layer "B.Cu")
		(at 500.3292 -146.8374)
		(property "Reference" "R6W39"
			(at 0.8382 -0.67818 0)
			(unlocked yes)
			(layer "B.SilkS")
			(effects
				(font
					(size 0.4064 0.254)
					(thickness 0.1524)
				)
				(justify left mirror)
			)
		)
		(property "Value" ""
			(at 0 0 0)
			(layer "B.Fab")
			(effects
				(font
					(size 1.27 1.27)
				)
				(justify mirror)
			)
		)
		(duplicate_pad_numbers_are_jumpers no)
		(fp_poly
			(pts
				(xy 0.2794 -0.1016) (xy -0.2794 -0.1016) (xy -0.2794 0.9906) (xy 0.2794 0.9906)
			)
			(stroke
				(width 0)
				(type default)
			)
			(fill no)
			(layer "B.CrtYd")
		)
		(fp_line
			(start -0.2794 -0.1016)
			(end 0.2794 -0.1016)
			(stroke
				(width 0.1)
				(type default)
			)
			(layer "B.Fab")
		)
		(fp_line
			(start -0.2794 0.9906)
			(end -0.2794 -0.1016)
			(stroke
				(width 0.1)
				(type default)
			)
			(layer "B.Fab")
		)
		(fp_line
			(start 0.2794 -0.1016)
			(end 0.2794 0.9906)
			(stroke
				(width 0.1)
				(type default)
			)
			(layer "B.Fab")
		)
		(fp_line
			(start 0.2794 0.9906)
			(end -0.2794 0.9906)
			(stroke
				(width 0.1)
				(type default)
			)
			(layer "B.Fab")
		)
		(pad "1" smd rect
			(at 0 0 180)
			(size 0.508 0.508)
			(layers "B.Cu" "B.Mask" "B.Paste")
			(net "SPA_MID_DBG1_TX_EN")
		)
		(pad "2" smd rect
			(at 0 0.889 180)
			(size 0.508 0.508)
			(layers "B.Cu" "B.Mask" "B.Paste")
			(net "P3V3_STBY")
		)
		(zone
			(layer "B.Cu")
			(hatch none 0.5)
			(connect_pads
				(clearance 0)
			)
			(min_thickness 0.25)
			(keepout
				(tracks allowed)
				(vias not_allowed)
				(pads allowed)
				(copperpour not_allowed)
				(footprints allowed)
			)
			(placement
				(enabled no)
				(sheetname "")
			)
			(fill
				(thermal_gap 0.5)
				(thermal_bridge_width 0.5)
				(island_removal_mode 0)
			)
			(polygon
				(pts
					(xy 500.5832 -146.5834) (xy 500.0752 -146.5834) (xy 500.0752 -146.2024) (xy 500.5832 -146.2024)
				)
			)
		)
		(zone
			(layer "B.Cu")
			(hatch none 0.5)
			(connect_pads
				(clearance 0)
			)
			(min_thickness 0.25)
			(keepout
				(tracks not_allowed)
				(vias allowed)
				(pads allowed)
				(copperpour not_allowed)
				(footprints allowed)
			)
			(placement
				(enabled no)
				(sheetname "")
			)
			(fill
				(thermal_gap 0.5)
				(thermal_bridge_width 0.5)
				(island_removal_mode 0)
			)
			(polygon
				(pts
					(xy 500.5832 -146.2024) (xy 500.0752 -146.2024) (xy 500.0752 -146.5834) (xy 500.5832 -146.5834)
				)
			)
		)
	)
	(footprint ""
		(layer "B.Cu")
		(at 387.457188 -58.57875 90)
		(property "Reference" "R3T10"
			(at 0 0 90)
			(layer "B.SilkS")
			(hide yes)
			(effects
				(font
					(size 1.27 1.27)
				)
				(justify mirror)
			)
		)
		(property "Value" ""
			(at 0 0 90)
			(layer "B.Fab")
			(effects
				(font
					(size 1.27 1.27)
				)
				(justify mirror)
			)
		)
		(duplicate_pad_numbers_are_jumpers no)
		(fp_poly
			(pts
				(xy 0.2794 -0.1016) (xy -0.2794 -0.1016) (xy -0.2794 0.9906) (xy 0.2794 0.9906)
			)
			(stroke
				(width 0)
				(type default)
			)
			(fill no)
			(layer "B.CrtYd")
		)
		(fp_line
			(start 0.2794 -0.1016)
			(end 0.2794 0.9906)
			(stroke
				(width 0.1)
				(type default)
			)
			(layer "B.Fab")
		)
		(fp_line
			(start -0.2794 -0.1016)
			(end 0.2794 -0.1016)
			(stroke
				(width 0.1)
				(type default)
			)
			(layer "B.Fab")
		)
		(fp_line
			(start 0.2794 0.9906)
			(end -0.2794 0.9906)
			(stroke
				(width 0.1)
				(type default)
			)
			(layer "B.Fab")
		)
		(fp_line
			(start -0.2794 0.9906)
			(end -0.2794 -0.1016)
			(stroke
				(width 0.1)
				(type default)
			)
			(layer "B.Fab")
		)
		(pad "1" smd rect
			(at 0 0 270)
			(size 0.508 0.508)
			(layers "B.Cu" "B.Mask" "B.Paste")
			(net "SPI_SWITCH_MOSI")
		)
		(pad "2" smd rect
			(at 0 0.889 270)
			(size 0.508 0.508)
			(layers "B.Cu" "B.Mask" "B.Paste")
			(net "SPI_SWITCH_MOSI_R1")
		)
		(zone
			(layer "B.Cu")
			(hatch none 0.5)
			(connect_pads
				(clearance 0)
			)
			(min_thickness 0.25)
			(keepout
				(tracks allowed)
				(vias not_allowed)
				(pads allowed)
				(copperpour not_allowed)
				(footprints allowed)
			)
			(placement
				(enabled no)
				(sheetname "")
			)
			(fill
				(thermal_gap 0.5)
				(thermal_bridge_width 0.5)
				(island_removal_mode 0)
			)
			(polygon
				(pts
					(xy 387.711188 -58.83275) (xy 387.711188 -58.32475) (xy 388.092188 -58.32475) (xy 388.092188 -58.83275)
				)
			)
		)
		(zone
			(layer "B.Cu")
			(hatch none 0.5)
			(connect_pads
				(clearance 0)
			)
			(min_thickness 0.25)
			(keepout
				(tracks not_allowed)
				(vias allowed)
				(pads allowed)
				(copperpour not_allowed)
				(footprints allowed)
			)
			(placement
				(enabled no)
				(sheetname "")
			)
			(fill
				(thermal_gap 0.5)
				(thermal_bridge_width 0.5)
				(island_removal_mode 0)
			)
			(polygon
				(pts
					(xy 388.092188 -58.83275) (xy 388.092188 -58.32475) (xy 387.711188 -58.32475) (xy 387.711188 -58.83275)
				)
			)
		)
	)
	(footprint ""
		(layer "B.Cu")
		(at 460.0956 -34.9504 90)
		(property "Reference" "R1U15"
			(at 0 0 90)
			(layer "B.SilkS")
			(hide yes)
			(effects
				(font
					(size 1.27 1.27)
				)
				(justify mirror)
			)
		)
		(property "Value" ""
			(at 0 0 90)
			(layer "B.Fab")
			(effects
				(font
					(size 1.27 1.27)
				)
				(justify mirror)
			)
		)
		(duplicate_pad_numbers_are_jumpers no)
		(fp_poly
			(pts
				(xy 0.2794 -0.1016) (xy -0.2794 -0.1016) (xy -0.2794 0.9906) (xy 0.2794 0.9906)
			)
			(stroke
				(width 0)
				(type default)
			)
			(fill no)
			(layer "B.CrtYd")
		)
		(fp_line
			(start 0.2794 -0.1016)
			(end 0.2794 0.9906)
			(stroke
				(width 0.1)
				(type default)
			)
			(layer "B.Fab")
		)
		(fp_line
			(start -0.2794 -0.1016)
			(end 0.2794 -0.1016)
			(stroke
				(width 0.1)
				(type default)
			)
			(layer "B.Fab")
		)
		(fp_line
			(start 0.2794 0.9906)
			(end -0.2794 0.9906)
			(stroke
				(width 0.1)
				(type default)
			)
			(layer "B.Fab")
		)
		(fp_line
			(start -0.2794 0.9906)
			(end -0.2794 -0.1016)
			(stroke
				(width 0.1)
				(type default)
			)
			(layer "B.Fab")
		)
		(pad "1" smd rect
			(at 0 0 270)
			(size 0.508 0.508)
			(layers "B.Cu" "B.Mask" "B.Paste")
			(net "FM_BOARD_SKU_ID3")
		)
		(pad "2" smd rect
			(at 0 0.889 270)
			(size 0.508 0.508)
			(layers "B.Cu" "B.Mask" "B.Paste")
			(net "GND")
		)
		(zone
			(layer "B.Cu")
			(hatch none 0.5)
			(connect_pads
				(clearance 0)
			)
			(min_thickness 0.25)
			(keepout
				(tracks allowed)
				(vias not_allowed)
				(pads allowed)
				(copperpour not_allowed)
				(footprints allowed)
			)
			(placement
				(enabled no)
				(sheetname "")
			)
			(fill
				(thermal_gap 0.5)
				(thermal_bridge_width 0.5)
				(island_removal_mode 0)
			)
			(polygon
				(pts
					(xy 460.3496 -35.2044) (xy 460.3496 -34.6964) (xy 460.7306 -34.6964) (xy 460.7306 -35.2044)
				)
			)
		)
		(zone
			(layer "B.Cu")
			(hatch none 0.5)
			(connect_pads
				(clearance 0)
			)
			(min_thickness 0.25)
			(keepout
				(tracks not_allowed)
				(vias allowed)
				(pads allowed)
				(copperpour not_allowed)
				(footprints allowed)
			)
			(placement
				(enabled no)
				(sheetname "")
			)
			(fill
				(thermal_gap 0.5)
				(thermal_bridge_width 0.5)
				(island_removal_mode 0)
			)
			(polygon
				(pts
					(xy 460.7306 -35.2044) (xy 460.7306 -34.6964) (xy 460.3496 -34.6964) (xy 460.3496 -35.2044)
				)
			)
		)
	)
	(footprint ""
		(layer "B.Cu")
		(at 32.832802 -58.297064 90)
		(property "Reference" "C9R10"
			(at 0 0 90)
			(layer "B.SilkS")
			(hide yes)
			(effects
				(font
					(size 1.27 1.27)
				)
				(justify mirror)
			)
		)
		(property "Value" ""
			(at 0 0 90)
			(layer "B.Fab")
			(effects
				(font
					(size 1.27 1.27)
				)
				(justify mirror)
			)
		)
		(duplicate_pad_numbers_are_jumpers no)
		(fp_poly
			(pts
				(xy 0.7239 -0.2159) (xy -0.7239 -0.2159) (xy -0.7239 1.9939) (xy 0.7239 1.9939)
			)
			(stroke
				(width 0)
				(type default)
			)
			(fill no)
			(layer "B.CrtYd")
		)
		(fp_line
			(start 0.7239 -0.2159)
			(end 0.7239 1.9939)
			(stroke
				(width 0.1)
				(type default)
			)
			(layer "B.Fab")
		)
		(fp_line
			(start -0.7239 -0.2159)
			(end 0.7239 -0.2159)
			(stroke
				(width 0.1)
				(type default)
			)
			(layer "B.Fab")
		)
		(fp_line
			(start 0.7239 1.9939)
			(end -0.7239 1.9939)
			(stroke
				(width 0.1)
				(type default)
			)
			(layer "B.Fab")
		)
		(fp_line
			(start -0.7239 1.9939)
			(end -0.7239 -0.2159)
			(stroke
				(width 0.1)
				(type default)
			)
			(layer "B.Fab")
		)
		(pad "1" smd rect
			(at 0 0 270)
			(size 1.27 1.016)
			(layers "B.Cu" "B.Mask" "B.Paste")
			(net "VR_FET_SW_P12V_STBY_PVCCIN_CPU1")
		)
		(pad "2" smd rect
			(at 0 1.778 270)
			(size 1.27 1.016)
			(layers "B.Cu" "B.Mask" "B.Paste")
			(net "GND")
		)
		(zone
			(layer "B.Cu")
			(hatch none 0.5)
			(connect_pads
				(clearance 0)
			)
			(min_thickness 0.25)
			(keepout
				(tracks not_allowed)
				(vias allowed)
				(pads allowed)
				(copperpour not_allowed)
				(footprints allowed)
			)
			(placement
				(enabled no)
				(sheetname "")
			)
			(fill
				(thermal_gap 0.5)
				(thermal_bridge_width 0.5)
				(island_removal_mode 0)
			)
			(polygon
				(pts
					(xy 33.340802 -58.932064) (xy 33.340802 -57.662064) (xy 34.102802 -57.662064) (xy 34.102802 -58.932064)
				)
			)
		)
	)
	(footprint ""
		(layer "B.Cu")
		(at 108.432854 -68.17614 180)
		(property "Reference" "C7P20"
			(at 0 0 0)
			(layer "B.SilkS")
			(hide yes)
			(effects
				(font
					(size 1.27 1.27)
				)
				(justify mirror)
			)
		)
		(property "Value" ""
			(at 0 0 0)
			(layer "B.Fab")
			(effects
				(font
					(size 1.27 1.27)
				)
				(justify mirror)
			)
		)
		(duplicate_pad_numbers_are_jumpers no)
		(fp_poly
			(pts
				(xy 0.7239 -0.2159) (xy -0.7239 -0.2159) (xy -0.7239 1.9939) (xy 0.7239 1.9939)
			)
			(stroke
				(width 0)
				(type default)
			)
			(fill no)
			(layer "B.CrtYd")
		)
		(fp_line
			(start 0.7239 1.9939)
			(end -0.7239 1.9939)
			(stroke
				(width 0.1)
				(type default)
			)
			(layer "B.Fab")
		)
		(fp_line
			(start 0.7239 -0.2159)
			(end 0.7239 1.9939)
			(stroke
				(width 0.1)
				(type default)
			)
			(layer "B.Fab")
		)
		(fp_line
			(start -0.7239 1.9939)
			(end -0.7239 -0.2159)
			(stroke
				(width 0.1)
				(type default)
			)
			(layer "B.Fab")
		)
		(fp_line
			(start -0.7239 -0.2159)
			(end 0.7239 -0.2159)
			(stroke
				(width 0.1)
				(type default)
			)
			(layer "B.Fab")
		)
		(pad "1" smd rect
			(at 0 0)
			(size 1.27 1.016)
			(layers "B.Cu" "B.Mask" "B.Paste")
			(net "PVDDQ_GHJ")
		)
		(pad "2" smd rect
			(at 0 1.778)
			(size 1.27 1.016)
			(layers "B.Cu" "B.Mask" "B.Paste")
			(net "GND")
		)
		(zone
			(layer "B.Cu")
			(hatch none 0.5)
			(connect_pads
				(clearance 0)
			)
			(min_thickness 0.25)
			(keepout
				(tracks not_allowed)
				(vias allowed)
				(pads allowed)
				(copperpour not_allowed)
				(footprints allowed)
			)
			(placement
				(enabled no)
				(sheetname "")
			)
			(fill
				(thermal_gap 0.5)
				(thermal_bridge_width 0.5)
				(island_removal_mode 0)
			)
			(polygon
				(pts
					(xy 107.797854 -68.68414) (xy 109.067854 -68.68414) (xy 109.067854 -69.44614) (xy 107.797854 -69.44614)
				)
			)
		)
	)
	(footprint ""
		(layer "B.Cu")
		(at 477.848422 -132.838444)
		(property "Reference" "R1W39"
			(at 0.8382 -0.67818 0)
			(unlocked yes)
			(layer "B.SilkS")
			(effects
				(font
					(size 0.4064 0.254)
					(thickness 0.1524)
				)
				(justify left mirror)
			)
		)
		(property "Value" ""
			(at 0 0 0)
			(layer "B.Fab")
			(effects
				(font
					(size 1.27 1.27)
				)
				(justify mirror)
			)
		)
		(duplicate_pad_numbers_are_jumpers no)
		(fp_poly
			(pts
				(xy 0.2794 -0.1016) (xy -0.2794 -0.1016) (xy -0.2794 0.9906) (xy 0.2794 0.9906)
			)
			(stroke
				(width 0)
				(type default)
			)
			(fill no)
			(layer "B.CrtYd")
		)
		(fp_line
			(start -0.2794 -0.1016)
			(end 0.2794 -0.1016)
			(stroke
				(width 0.1)
				(type default)
			)
			(layer "B.Fab")
		)
		(fp_line
			(start -0.2794 0.9906)
			(end -0.2794 -0.1016)
			(stroke
				(width 0.1)
				(type default)
			)
			(layer "B.Fab")
		)
		(fp_line
			(start 0.2794 -0.1016)
			(end 0.2794 0.9906)
			(stroke
				(width 0.1)
				(type default)
			)
			(layer "B.Fab")
		)
		(fp_line
			(start 0.2794 0.9906)
			(end -0.2794 0.9906)
			(stroke
				(width 0.1)
				(type default)
			)
			(layer "B.Fab")
		)
		(pad "1" smd rect
			(at 0 0 180)
			(size 0.508 0.508)
			(layers "B.Cu" "B.Mask" "B.Paste")
			(net "SMB_DEBUG_STBY_LVC3_SDA_CONN")
		)
		(pad "2" smd rect
			(at 0 0.889 180)
			(size 0.508 0.508)
			(layers "B.Cu" "B.Mask" "B.Paste")
			(net "SMB_DEBUG_STBY_LVC3_SDA_R1")
		)
		(zone
			(layer "B.Cu")
			(hatch none 0.5)
			(connect_pads
				(clearance 0)
			)
			(min_thickness 0.25)
			(keepout
				(tracks allowed)
				(vias not_allowed)
				(pads allowed)
				(copperpour not_allowed)
				(footprints allowed)
			)
			(placement
				(enabled no)
				(sheetname "")
			)
			(fill
				(thermal_gap 0.5)
				(thermal_bridge_width 0.5)
				(island_removal_mode 0)
			)
			(polygon
				(pts
					(xy 478.102422 -132.584444) (xy 477.594422 -132.584444) (xy 477.594422 -132.203444) (xy 478.102422 -132.203444)
				)
			)
		)
		(zone
			(layer "B.Cu")
			(hatch none 0.5)
			(connect_pads
				(clearance 0)
			)
			(min_thickness 0.25)
			(keepout
				(tracks not_allowed)
				(vias allowed)
				(pads allowed)
				(copperpour not_allowed)
				(footprints allowed)
			)
			(placement
				(enabled no)
				(sheetname "")
			)
			(fill
				(thermal_gap 0.5)
				(thermal_bridge_width 0.5)
				(island_removal_mode 0)
			)
			(polygon
				(pts
					(xy 478.102422 -132.203444) (xy 477.594422 -132.203444) (xy 477.594422 -132.584444) (xy 478.102422 -132.584444)
				)
			)
		)
	)
	(footprint ""
		(layer "B.Cu")
		(at 94.06636 -149.7711 90)
		(property "Reference" "C5G116"
			(at -1.64973 0.78994 180)
			(unlocked yes)
			(layer "B.SilkS")
			(effects
				(font
					(size 0.7874 0.5842)
					(thickness 0.1524)
				)
				(justify mirror)
			)
		)
		(property "Value" ""
			(at 0 0 90)
			(layer "B.Fab")
			(effects
				(font
					(size 1.27 1.27)
				)
				(justify mirror)
			)
		)
		(duplicate_pad_numbers_are_jumpers no)
		(fp_rect
			(start -0.7239 -0.2159)
			(end 0.7239 1.9939)
			(stroke
				(width 0)
				(type default)
			)
			(fill no)
			(layer "B.CrtYd")
		)
		(fp_line
			(start 0.7239 -0.2159)
			(end 0.7239 1.9939)
			(stroke
				(width 0.1)
				(type default)
			)
			(layer "B.Fab")
		)
		(fp_line
			(start -0.7239 -0.2159)
			(end 0.7239 -0.2159)
			(stroke
				(width 0.1)
				(type default)
			)
			(layer "B.Fab")
		)
		(fp_line
			(start 0.7239 1.9939)
			(end -0.7239 1.9939)
			(stroke
				(width 0.1)
				(type default)
			)
			(layer "B.Fab")
		)
		(fp_line
			(start -0.7239 1.9939)
			(end -0.7239 -0.2159)
			(stroke
				(width 0.1)
				(type default)
			)
			(layer "B.Fab")
		)
		(pad "1" smd rect
			(at 0 0 270)
			(size 1.27 1.016)
			(layers "B.Cu" "B.Mask" "B.Paste")
			(net "PVDDQ_KLM")
		)
		(pad "2" smd rect
			(at 0 1.778 270)
			(size 1.27 1.016)
			(layers "B.Cu" "B.Mask" "B.Paste")
			(net "GND")
		)
		(zone
			(layer "B.Cu")
			(hatch none 0.5)
			(connect_pads
				(clearance 0)
			)
			(min_thickness 0.25)
			(keepout
				(tracks not_allowed)
				(vias allowed)
				(pads allowed)
				(copperpour not_allowed)
				(footprints allowed)
			)
			(placement
				(enabled no)
				(sheetname "")
			)
			(fill
				(thermal_gap 0.5)
				(thermal_bridge_width 0.5)
				(island_removal_mode 0)
			)
			(polygon
				(pts
					(xy 94.57436 -149.1361) (xy 95.33636 -149.1361) (xy 95.33636 -150.4061) (xy 94.57436 -150.4061)
				)
			)
		)
	)
	(footprint ""
		(layer "B.Cu")
		(at 475.187518 -15.517876 180)
		(property "Reference" "C8F17"
			(at 0 0 0)
			(layer "B.SilkS")
			(hide yes)
			(effects
				(font
					(size 1.27 1.27)
				)
				(justify mirror)
			)
		)
		(property "Value" ""
			(at 0 0 0)
			(layer "B.Fab")
			(effects
				(font
					(size 1.27 1.27)
				)
				(justify mirror)
			)
		)
		(duplicate_pad_numbers_are_jumpers no)
		(fp_rect
			(start 0.3048 0.9906)
			(end -0.3048 -0.1016)
			(stroke
				(width 0)
				(type default)
			)
			(fill no)
			(layer "B.CrtYd")
		)
		(fp_line
			(start 0.3048 0.9906)
			(end -0.3048 0.9906)
			(stroke
				(width 0.1)
				(type default)
			)
			(layer "B.Fab")
		)
		(fp_line
			(start 0.3048 -0.1016)
			(end 0.3048 0.9906)
			(stroke
				(width 0.1)
				(type default)
			)
			(layer "B.Fab")
		)
		(fp_line
			(start -0.3048 0.9906)
			(end -0.3048 -0.1016)
			(stroke
				(width 0.1)
				(type default)
			)
			(layer "B.Fab")
		)
		(fp_line
			(start -0.3048 -0.1016)
			(end 0.3048 -0.1016)
			(stroke
				(width 0.1)
				(type default)
			)
			(layer "B.Fab")
		)
		(pad "1" smd rect
			(at 0 0)
			(size 0.508 0.508)
			(layers "B.Cu" "B.Mask" "B.Paste")
			(net "P5V_STBY")
		)
		(pad "2" smd rect
			(at 0 0.889)
			(size 0.508 0.508)
			(layers "B.Cu" "B.Mask" "B.Paste")
			(net "GND")
		)
		(zone
			(layer "B.Cu")
			(hatch none 0.5)
			(connect_pads
				(clearance 0)
			)
			(min_thickness 0.25)
			(keepout
				(tracks not_allowed)
				(vias allowed)
				(pads allowed)
				(copperpour not_allowed)
				(footprints allowed)
			)
			(placement
				(enabled no)
				(sheetname "")
			)
			(fill
				(thermal_gap 0.5)
				(thermal_bridge_width 0.5)
				(island_removal_mode 0)
			)
			(polygon
				(pts
					(xy 474.933518 -16.152876) (xy 474.933518 -15.771876) (xy 475.441518 -15.771876) (xy 475.441518 -16.152876)
				)
			)
		)
		(zone
			(layer "B.Cu")
			(hatch none 0.5)
			(connect_pads
				(clearance 0)
			)
			(min_thickness 0.25)
			(keepout
				(tracks allowed)
				(vias not_allowed)
				(pads allowed)
				(copperpour not_allowed)
				(footprints allowed)
			)
			(placement
				(enabled no)
				(sheetname "")
			)
			(fill
				(thermal_gap 0.5)
				(thermal_bridge_width 0.5)
				(island_removal_mode 0)
			)
			(polygon
				(pts
					(xy 474.933518 -16.152876) (xy 474.933518 -15.771876) (xy 475.441518 -15.771876) (xy 475.441518 -16.152876)
				)
			)
		)
	)
	(footprint ""
		(layer "B.Cu")
		(at 385.33705 -107.05465 90)
		(property "Reference" "C3N18"
			(at 0 0 90)
			(layer "B.SilkS")
			(hide yes)
			(effects
				(font
					(size 1.27 1.27)
				)
				(justify mirror)
			)
		)
		(property "Value" ""
			(at 0 0 90)
			(layer "B.Fab")
			(effects
				(font
					(size 1.27 1.27)
				)
				(justify mirror)
			)
		)
		(duplicate_pad_numbers_are_jumpers no)
		(fp_rect
			(start 0.2794 0.9144)
			(end -0.2794 -0.1143)
			(stroke
				(width 0)
				(type default)
			)
			(fill no)
			(layer "B.CrtYd")
		)
		(fp_line
			(start 0.2794 -0.1143)
			(end -0.2794 -0.1143)
			(stroke
				(width 0.1)
				(type default)
			)
			(layer "B.Fab")
		)
		(fp_line
			(start -0.2794 -0.1143)
			(end -0.2794 0.9144)
			(stroke
				(width 0.1)
				(type default)
			)
			(layer "B.Fab")
		)
		(fp_line
			(start 0.2794 0.9144)
			(end 0.2794 -0.1143)
			(stroke
				(width 0.1)
				(type default)
			)
			(layer "B.Fab")
		)
		(fp_line
			(start -0.2794 0.9144)
			(end 0.2794 0.9144)
			(stroke
				(width 0.1)
				(type default)
			)
			(layer "B.Fab")
		)
		(pad "1" smd custom
			(at 0 0)
			(size 0.10414 0.10414)
			(layers "B.Cu" "B.Mask" "B.Paste")
			(net "PVNN_PCH_STBY")
			(options
				(clearance outline)
				(anchor circle)
			)
			(primitives
				(gr_poly
					(pts
						(xy -0.20828 -0.08636) (xy -0.20828 0.08636) (xy -0.08636 0.20828) (xy 0.086614 0.20828) (xy 0.20828 0.086614)
						(xy 0.20828 -0.08636) (xy 0.08636 -0.20828) (xy -0.08636 -0.20828)
					)
					(width 0)
					(fill yes)
				)
			)
		)
		(pad "2" smd custom
			(at 0 0.8001)
			(size 0.10414 0.10414)
			(layers "B.Cu" "B.Mask" "B.Paste")
			(net "GND")
			(options
				(clearance outline)
				(anchor circle)
			)
			(primitives
				(gr_poly
					(pts
						(xy -0.20828 -0.08636) (xy -0.20828 0.08636) (xy -0.08636 0.20828) (xy 0.086614 0.20828) (xy 0.20828 0.086614)
						(xy 0.20828 -0.08636) (xy 0.08636 -0.20828) (xy -0.08636 -0.20828)
					)
					(width 0)
					(fill yes)
				)
			)
		)
		(zone
			(layer "B.Cu")
			(hatch none 0.5)
			(connect_pads
				(clearance 0)
			)
			(min_thickness 0.25)
			(keepout
				(tracks allowed)
				(vias not_allowed)
				(pads allowed)
				(copperpour not_allowed)
				(footprints allowed)
			)
			(placement
				(enabled no)
				(sheetname "")
			)
			(fill
				(thermal_gap 0.5)
				(thermal_bridge_width 0.5)
				(island_removal_mode 0)
			)
			(polygon
				(pts
					(xy 385.5466 -107.14228) (xy 385.9276 -107.14228) (xy 385.9276 -106.96702) (xy 385.5466 -106.966766)
				)
			)
		)
		(zone
			(layer "B.Cu")
			(hatch none 0.5)
			(connect_pads
				(clearance 0)
			)
			(min_thickness 0.25)
			(keepout
				(tracks not_allowed)
				(vias allowed)
				(pads allowed)
				(copperpour not_allowed)
				(footprints allowed)
			)
			(placement
				(enabled no)
				(sheetname "")
			)
			(fill
				(thermal_gap 0.5)
				(thermal_bridge_width 0.5)
				(island_removal_mode 0)
			)
			(polygon
				(pts
					(xy 385.5466 -107.14228) (xy 385.9276 -107.14228) (xy 385.9276 -106.96702) (xy 385.5466 -106.966766)
				)
			)
		)
	)
	(footprint ""
		(layer "B.Cu")
		(at 394.251434 -33.139634)
		(property "Reference" "R25W181"
			(at 0.8382 -0.67818 0)
			(unlocked yes)
			(layer "B.SilkS")
			(effects
				(font
					(size 0.4064 0.254)
					(thickness 0.1524)
				)
				(justify left mirror)
			)
		)
		(property "Value" ""
			(at 0 0 0)
			(layer "B.Fab")
			(effects
				(font
					(size 1.27 1.27)
				)
				(justify mirror)
			)
		)
		(duplicate_pad_numbers_are_jumpers no)
		(fp_poly
			(pts
				(xy 0.2794 -0.1016) (xy -0.2794 -0.1016) (xy -0.2794 0.9906) (xy 0.2794 0.9906)
			)
			(stroke
				(width 0)
				(type default)
			)
			(fill no)
			(layer "B.CrtYd")
		)
		(fp_line
			(start -0.2794 -0.1016)
			(end 0.2794 -0.1016)
			(stroke
				(width 0.1)
				(type default)
			)
			(layer "B.Fab")
		)
		(fp_line
			(start -0.2794 0.9906)
			(end -0.2794 -0.1016)
			(stroke
				(width 0.1)
				(type default)
			)
			(layer "B.Fab")
		)
		(fp_line
			(start 0.2794 -0.1016)
			(end 0.2794 0.9906)
			(stroke
				(width 0.1)
				(type default)
			)
			(layer "B.Fab")
		)
		(fp_line
			(start 0.2794 0.9906)
			(end -0.2794 0.9906)
			(stroke
				(width 0.1)
				(type default)
			)
			(layer "B.Fab")
		)
		(pad "1" smd rect
			(at 0 0 180)
			(size 0.508 0.508)
			(layers "B.Cu" "B.Mask" "B.Paste")
			(net "RST_RSMRST_N")
		)
		(pad "2" smd rect
			(at 0 0.889 180)
			(size 0.508 0.508)
			(layers "B.Cu" "B.Mask" "B.Paste")
			(net "BMC_RSMRST_B_N")
		)
		(zone
			(layer "B.Cu")
			(hatch none 0.5)
			(connect_pads
				(clearance 0)
			)
			(min_thickness 0.25)
			(keepout
				(tracks allowed)
				(vias not_allowed)
				(pads allowed)
				(copperpour not_allowed)
				(footprints allowed)
			)
			(placement
				(enabled no)
				(sheetname "")
			)
			(fill
				(thermal_gap 0.5)
				(thermal_bridge_width 0.5)
				(island_removal_mode 0)
			)
			(polygon
				(pts
					(xy 394.505434 -32.885634) (xy 393.997434 -32.885634) (xy 393.997434 -32.504634) (xy 394.505434 -32.504634)
				)
			)
		)
		(zone
			(layer "B.Cu")
			(hatch none 0.5)
			(connect_pads
				(clearance 0)
			)
			(min_thickness 0.25)
			(keepout
				(tracks not_allowed)
				(vias allowed)
				(pads allowed)
				(copperpour not_allowed)
				(footprints allowed)
			)
			(placement
				(enabled no)
				(sheetname "")
			)
			(fill
				(thermal_gap 0.5)
				(thermal_bridge_width 0.5)
				(island_removal_mode 0)
			)
			(polygon
				(pts
					(xy 394.505434 -32.504634) (xy 393.997434 -32.504634) (xy 393.997434 -32.885634) (xy 394.505434 -32.885634)
				)
			)
		)
	)
	(footprint ""
		(layer "B.Cu")
		(at 404.3172 -148.082 -90)
		(property "Reference" "R2L20"
			(at 0 0 90)
			(layer "B.SilkS")
			(hide yes)
			(effects
				(font
					(size 1.27 1.27)
				)
				(justify mirror)
			)
		)
		(property "Value" ""
			(at 0 0 90)
			(layer "B.Fab")
			(effects
				(font
					(size 1.27 1.27)
				)
				(justify mirror)
			)
		)
		(duplicate_pad_numbers_are_jumpers no)
		(fp_poly
			(pts
				(xy 0.2794 -0.1016) (xy -0.2794 -0.1016) (xy -0.2794 0.9906) (xy 0.2794 0.9906)
			)
			(stroke
				(width 0)
				(type default)
			)
			(fill no)
			(layer "B.CrtYd")
		)
		(fp_line
			(start -0.2794 0.9906)
			(end -0.2794 -0.1016)
			(stroke
				(width 0.1)
				(type default)
			)
			(layer "B.Fab")
		)
		(fp_line
			(start 0.2794 0.9906)
			(end -0.2794 0.9906)
			(stroke
				(width 0.1)
				(type default)
			)
			(layer "B.Fab")
		)
		(fp_line
			(start -0.2794 -0.1016)
			(end 0.2794 -0.1016)
			(stroke
				(width 0.1)
				(type default)
			)
			(layer "B.Fab")
		)
		(fp_line
			(start 0.2794 -0.1016)
			(end 0.2794 0.9906)
			(stroke
				(width 0.1)
				(type default)
			)
			(layer "B.Fab")
		)
		(pad "1" smd rect
			(at 0 0 90)
			(size 0.508 0.508)
			(layers "B.Cu" "B.Mask" "B.Paste")
			(net "P1V8_PCH_STBY")
		)
		(pad "2" smd rect
			(at 0 0.889 90)
			(size 0.508 0.508)
			(layers "B.Cu" "B.Mask" "B.Paste")
			(net "VR_P1V8_PCH_STBY_FB")
		)
		(zone
			(layer "B.Cu")
			(hatch none 0.5)
			(connect_pads
				(clearance 0)
			)
			(min_thickness 0.25)
			(keepout
				(tracks not_allowed)
				(vias allowed)
				(pads allowed)
				(copperpour not_allowed)
				(footprints allowed)
			)
			(placement
				(enabled no)
				(sheetname "")
			)
			(fill
				(thermal_gap 0.5)
				(thermal_bridge_width 0.5)
				(island_removal_mode 0)
			)
			(polygon
				(pts
					(xy 403.6822 -147.828) (xy 403.6822 -148.336) (xy 404.0632 -148.336) (xy 404.0632 -147.828)
				)
			)
		)
		(zone
			(layer "B.Cu")
			(hatch none 0.5)
			(connect_pads
				(clearance 0)
			)
			(min_thickness 0.25)
			(keepout
				(tracks allowed)
				(vias not_allowed)
				(pads allowed)
				(copperpour not_allowed)
				(footprints allowed)
			)
			(placement
				(enabled no)
				(sheetname "")
			)
			(fill
				(thermal_gap 0.5)
				(thermal_bridge_width 0.5)
				(island_removal_mode 0)
			)
			(polygon
				(pts
					(xy 404.0632 -147.828) (xy 404.0632 -148.336) (xy 403.6822 -148.336) (xy 403.6822 -147.828)
				)
			)
		)
	)
	(footprint ""
		(layer "B.Cu")
		(at -2.59842 -18.11782 -90)
		(property "Reference" "C1G7"
			(at 0 0 90)
			(layer "B.SilkS")
			(hide yes)
			(effects
				(font
					(size 1.27 1.27)
				)
				(justify mirror)
			)
		)
		(property "Value" "*"
			(at 2.3114 0.10795 270)
			(unlocked yes)
			(layer "B.Fab")
			(hide yes)
			(effects
				(font
					(size 0.889 0.889)
					(thickness 0.1524)
				)
				(justify mirror)
			)
		)
		(property "Device Type" "ST270U2D5VBM-GP_SMD-TCG2-ST270A"
			(at 2.3114 -1.41605 270)
			(unlocked yes)
			(layer "B.Fab")
			(hide yes)
			(effects
				(font
					(size 0.889 0.889)
					(thickness 0.1524)
				)
				(justify mirror)
			)
		)
		(duplicate_pad_numbers_are_jumpers no)
		(fp_line
			(start 1.5494 0.4826)
			(end 1.5494 -0.4826)
			(stroke
				(width 0.1524)
				(type default)
			)
			(layer "B.SilkS")
		)
		(fp_line
			(start -1.5494 -0.4826)
			(end -1.5494 0.4826)
			(stroke
				(width 0.1524)
				(type default)
			)
			(layer "B.SilkS")
		)
		(fp_line
			(start 1.0922 -2.35458)
			(end -1.0922 -2.35458)
			(stroke
				(width 0.508)
				(type default)
			)
			(layer "B.SilkS")
		)
		(fp_poly
			(pts
				(xy 1.3462 1.9558) (xy 1.3462 1.905) (xy 1.5494 1.905) (xy 1.5494 -1.905) (xy 1.3462 -1.905) (xy 1.3462 -1.9558)
				(xy -1.3462 -1.9558) (xy -1.3462 -1.905) (xy -1.5494 -1.905) (xy -1.5494 1.905) (xy -1.3462 1.905)
				(xy -1.3462 1.9558)
			)
			(stroke
				(width 0)
				(type default)
			)
			(fill no)
			(layer "B.CrtYd")
		)
		(fp_poly
			(pts
				(xy 1.3462 1.9558) (xy 1.3462 1.905) (xy 1.5494 1.905) (xy 1.5494 -1.905) (xy 1.3462 -1.905) (xy 1.3462 -1.9558)
				(xy -1.3462 -1.9558) (xy -1.3462 -1.905) (xy -1.5494 -1.905) (xy -1.5494 1.905) (xy -1.3462 1.905)
				(xy -1.3462 1.9558)
			)
			(stroke
				(width 0)
				(type default)
			)
			(fill no)
			(layer "B.Fab")
		)
		(pad "1" smd rect
			(at 0 -1.27508 90)
			(size 2.6924 1.3462)
			(layers "B.Cu" "B.Mask" "B.Paste")
			(net "VR_FET_SW_P12V_STBY_PVDDQ_GHJ")
		)
		(pad "2" smd rect
			(at 0 1.27508 90)
			(size 2.6924 1.3462)
			(layers "B.Cu" "B.Mask" "B.Paste")
			(net "GND")
		)
	)
	(footprint ""
		(layer "B.Cu")
		(at 359.8164 -134.112)
		(property "Reference" "R3M3"
			(at 0 0 0)
			(layer "B.SilkS")
			(hide yes)
			(effects
				(font
					(size 1.27 1.27)
				)
				(justify mirror)
			)
		)
		(property "Value" ""
			(at 0 0 0)
			(layer "B.Fab")
			(effects
				(font
					(size 1.27 1.27)
				)
				(justify mirror)
			)
		)
		(duplicate_pad_numbers_are_jumpers no)
		(fp_rect
			(start 0.2794 0.9906)
			(end -0.2794 -0.1016)
			(stroke
				(width 0)
				(type default)
			)
			(fill no)
			(layer "B.CrtYd")
		)
		(fp_line
			(start -0.2794 -0.1016)
			(end 0.2794 -0.1016)
			(stroke
				(width 0.1)
				(type default)
			)
			(layer "B.Fab")
		)
		(fp_line
			(start -0.2794 0.9906)
			(end -0.2794 -0.1016)
			(stroke
				(width 0.1)
				(type default)
			)
			(layer "B.Fab")
		)
		(fp_line
			(start 0.2794 -0.1016)
			(end 0.2794 0.9906)
			(stroke
				(width 0.1)
				(type default)
			)
			(layer "B.Fab")
		)
		(fp_line
			(start 0.2794 0.9906)
			(end -0.2794 0.9906)
			(stroke
				(width 0.1)
				(type default)
			)
			(layer "B.Fab")
		)
		(pad "1" smd rect
			(at 0 0 180)
			(size 0.508 0.508)
			(layers "B.Cu" "B.Mask" "B.Paste")
			(net "PWRGD_PVDDQ_DEF_R")
		)
		(pad "2" smd rect
			(at 0 0.889 180)
			(size 0.508 0.508)
			(layers "B.Cu" "B.Mask" "B.Paste")
			(net "PWRGD_PVDDQ_DEF")
		)
		(zone
			(layer "B.Cu")
			(hatch none 0.5)
			(connect_pads
				(clearance 0)
			)
			(min_thickness 0.25)
			(keepout
				(tracks not_allowed)
				(vias allowed)
				(pads allowed)
				(copperpour not_allowed)
				(footprints allowed)
			)
			(placement
				(enabled no)
				(sheetname "")
			)
			(fill
				(thermal_gap 0.5)
				(thermal_bridge_width 0.5)
				(island_removal_mode 0)
			)
			(polygon
				(pts
					(xy 360.0704 -133.477) (xy 360.0704 -133.858) (xy 359.5624 -133.858) (xy 359.5624 -133.477)
				)
			)
		)
		(zone
			(layer "B.Cu")
			(hatch none 0.5)
			(connect_pads
				(clearance 0)
			)
			(min_thickness 0.25)
			(keepout
				(tracks allowed)
				(vias not_allowed)
				(pads allowed)
				(copperpour not_allowed)
				(footprints allowed)
			)
			(placement
				(enabled no)
				(sheetname "")
			)
			(fill
				(thermal_gap 0.5)
				(thermal_bridge_width 0.5)
				(island_removal_mode 0)
			)
			(polygon
				(pts
					(xy 360.0704 -133.477) (xy 360.0704 -133.858) (xy 359.5624 -133.858) (xy 359.5624 -133.477)
				)
			)
		)
	)
	(footprint ""
		(layer "B.Cu")
		(at 385.3688 -3.0988)
		(property "Reference" "U8W2"
			(at 0 -1.2065 0)
			(unlocked yes)
			(layer "B.SilkS")
			(effects
				(font
					(size 1.27 0.9652)
					(thickness 0.1524)
				)
				(justify left mirror)
			)
		)
		(property "Value" ""
			(at 0 0 0)
			(layer "B.Fab")
			(effects
				(font
					(size 1.27 1.27)
				)
				(justify mirror)
			)
		)
		(duplicate_pad_numbers_are_jumpers no)
		(fp_circle
			(center 0.848614 -0.6477)
			(end 0.975614 -0.6477)
			(stroke
				(width 0.254)
				(type default)
			)
			(fill no)
			(layer "B.SilkS")
		)
		(fp_poly
			(pts
				(xy -0.21463 -0.450088) (xy -1.56337 -0.450088) (xy -1.56337 1.75006) (xy -0.21463 1.75006)
			)
			(stroke
				(width 0)
				(type default)
			)
			(fill no)
			(layer "B.CrtYd")
		)
		(fp_line
			(start -1.56337 -0.450088)
			(end -1.56337 1.75006)
			(stroke
				(width 0.1)
				(type default)
			)
			(layer "B.Fab")
		)
		(fp_line
			(start -1.56337 1.75006)
			(end -0.21463 1.75006)
			(stroke
				(width 0.1)
				(type default)
			)
			(layer "B.Fab")
		)
		(fp_line
			(start -0.21463 -0.450088)
			(end -1.56337 -0.450088)
			(stroke
				(width 0.1)
				(type default)
			)
			(layer "B.Fab")
		)
		(fp_line
			(start -0.21463 1.75006)
			(end -0.21463 -0.450088)
			(stroke
				(width 0.1)
				(type default)
			)
			(layer "B.Fab")
		)
		(fp_circle
			(center 0.848614 -0.6477)
			(end 0.975614 -0.6477)
			(stroke
				(width 0.254)
				(type default)
			)
			(fill no)
			(layer "B.Fab")
		)
		(pad "1" smd rect
			(at 0 0 180)
			(size 1.016 0.381)
			(layers "B.Cu" "B.Mask" "B.Paste")
			(net "JTAG_PLD_TDO")
		)
		(pad "2" smd rect
			(at 0 0.649986 180)
			(size 1.016 0.381)
			(layers "B.Cu" "B.Mask" "B.Paste")
			(net "GND")
		)
		(pad "3" smd rect
			(at 0 1.299972 180)
			(size 1.016 0.381)
			(layers "B.Cu" "B.Mask" "B.Paste")
			(net "JTAG_RISER_TDO_R")
		)
		(pad "4" smd rect
			(at -1.778 1.299972 180)
			(size 1.016 0.381)
			(layers "B.Cu" "B.Mask" "B.Paste")
			(net "JTAG_PLD_TDO_MUX_R")
		)
		(pad "5" smd rect
			(at -1.778 0.649986 180)
			(size 1.016 0.381)
			(layers "B.Cu" "B.Mask" "B.Paste")
			(net "P3V3_STBY")
		)
		(pad "6" smd rect
			(at -1.778 0 180)
			(size 1.016 0.381)
			(layers "B.Cu" "B.Mask" "B.Paste")
			(net "JTAG_RISER_N")
		)
	)
	(footprint ""
		(layer "B.Cu")
		(at 482.65969 -57.307988 -90)
		(property "Reference" "R8E27"
			(at 0 0 90)
			(layer "B.SilkS")
			(hide yes)
			(effects
				(font
					(size 1.27 1.27)
				)
				(justify mirror)
			)
		)
		(property "Value" ""
			(at 0 0 90)
			(layer "B.Fab")
			(effects
				(font
					(size 1.27 1.27)
				)
				(justify mirror)
			)
		)
		(duplicate_pad_numbers_are_jumpers no)
		(fp_poly
			(pts
				(xy 0.2794 -0.1016) (xy -0.2794 -0.1016) (xy -0.2794 0.9906) (xy 0.2794 0.9906)
			)
			(stroke
				(width 0)
				(type default)
			)
			(fill no)
			(layer "B.CrtYd")
		)
		(fp_line
			(start -0.2794 0.9906)
			(end -0.2794 -0.1016)
			(stroke
				(width 0.1)
				(type default)
			)
			(layer "B.Fab")
		)
		(fp_line
			(start 0.2794 0.9906)
			(end -0.2794 0.9906)
			(stroke
				(width 0.1)
				(type default)
			)
			(layer "B.Fab")
		)
		(fp_line
			(start -0.2794 -0.1016)
			(end 0.2794 -0.1016)
			(stroke
				(width 0.1)
				(type default)
			)
			(layer "B.Fab")
		)
		(fp_line
			(start 0.2794 -0.1016)
			(end 0.2794 0.9906)
			(stroke
				(width 0.1)
				(type default)
			)
			(layer "B.Fab")
		)
		(pad "1" smd rect
			(at 0 0 90)
			(size 0.508 0.508)
			(layers "B.Cu" "B.Mask" "B.Paste")
			(net "FM_PE_M2_WAKE_N")
		)
		(pad "2" smd rect
			(at 0 0.889 90)
			(size 0.508 0.508)
			(layers "B.Cu" "B.Mask" "B.Paste")
			(net "FM_ALL_WAKE_N")
		)
		(zone
			(layer "B.Cu")
			(hatch none 0.5)
			(connect_pads
				(clearance 0)
			)
			(min_thickness 0.25)
			(keepout
				(tracks not_allowed)
				(vias allowed)
				(pads allowed)
				(copperpour not_allowed)
				(footprints allowed)
			)
			(placement
				(enabled no)
				(sheetname "")
			)
			(fill
				(thermal_gap 0.5)
				(thermal_bridge_width 0.5)
				(island_removal_mode 0)
			)
			(polygon
				(pts
					(xy 482.02469 -57.053988) (xy 482.02469 -57.561988) (xy 482.40569 -57.561988) (xy 482.40569 -57.053988)
				)
			)
		)
		(zone
			(layer "B.Cu")
			(hatch none 0.5)
			(connect_pads
				(clearance 0)
			)
			(min_thickness 0.25)
			(keepout
				(tracks allowed)
				(vias not_allowed)
				(pads allowed)
				(copperpour not_allowed)
				(footprints allowed)
			)
			(placement
				(enabled no)
				(sheetname "")
			)
			(fill
				(thermal_gap 0.5)
				(thermal_bridge_width 0.5)
				(island_removal_mode 0)
			)
			(polygon
				(pts
					(xy 482.40569 -57.053988) (xy 482.40569 -57.561988) (xy 482.02469 -57.561988) (xy 482.02469 -57.053988)
				)
			)
		)
	)
	(footprint ""
		(layer "B.Cu")
		(at 433.578 -153.543 -90)
		(property "Reference" "R2L11"
			(at 0 0 90)
			(layer "B.SilkS")
			(hide yes)
			(effects
				(font
					(size 1.27 1.27)
				)
				(justify mirror)
			)
		)
		(property "Value" ""
			(at 0 0 90)
			(layer "B.Fab")
			(effects
				(font
					(size 1.27 1.27)
				)
				(justify mirror)
			)
		)
		(duplicate_pad_numbers_are_jumpers no)
		(fp_poly
			(pts
				(xy 0.2794 -0.1016) (xy -0.2794 -0.1016) (xy -0.2794 0.9906) (xy 0.2794 0.9906)
			)
			(stroke
				(width 0)
				(type default)
			)
			(fill no)
			(layer "B.CrtYd")
		)
		(fp_line
			(start -0.2794 0.9906)
			(end -0.2794 -0.1016)
			(stroke
				(width 0.1)
				(type default)
			)
			(layer "B.Fab")
		)
		(fp_line
			(start 0.2794 0.9906)
			(end -0.2794 0.9906)
			(stroke
				(width 0.1)
				(type default)
			)
			(layer "B.Fab")
		)
		(fp_line
			(start -0.2794 -0.1016)
			(end 0.2794 -0.1016)
			(stroke
				(width 0.1)
				(type default)
			)
			(layer "B.Fab")
		)
		(fp_line
			(start 0.2794 -0.1016)
			(end 0.2794 0.9906)
			(stroke
				(width 0.1)
				(type default)
			)
			(layer "B.Fab")
		)
		(pad "1" smd rect
			(at 0 0 90)
			(size 0.508 0.508)
			(layers "B.Cu" "B.Mask" "B.Paste")
			(net "P3V3_STBY")
		)
		(pad "2" smd rect
			(at 0 0.889 90)
			(size 0.508 0.508)
			(layers "B.Cu" "B.Mask" "B.Paste")
			(net "SGPIO_PCH_SATA_CLOCK_R")
		)
		(zone
			(layer "B.Cu")
			(hatch none 0.5)
			(connect_pads
				(clearance 0)
			)
			(min_thickness 0.25)
			(keepout
				(tracks not_allowed)
				(vias allowed)
				(pads allowed)
				(copperpour not_allowed)
				(footprints allowed)
			)
			(placement
				(enabled no)
				(sheetname "")
			)
			(fill
				(thermal_gap 0.5)
				(thermal_bridge_width 0.5)
				(island_removal_mode 0)
			)
			(polygon
				(pts
					(xy 432.943 -153.289) (xy 432.943 -153.797) (xy 433.324 -153.797) (xy 433.324 -153.289)
				)
			)
		)
		(zone
			(layer "B.Cu")
			(hatch none 0.5)
			(connect_pads
				(clearance 0)
			)
			(min_thickness 0.25)
			(keepout
				(tracks allowed)
				(vias not_allowed)
				(pads allowed)
				(copperpour not_allowed)
				(footprints allowed)
			)
			(placement
				(enabled no)
				(sheetname "")
			)
			(fill
				(thermal_gap 0.5)
				(thermal_bridge_width 0.5)
				(island_removal_mode 0)
			)
			(polygon
				(pts
					(xy 433.324 -153.289) (xy 433.324 -153.797) (xy 432.943 -153.797) (xy 432.943 -153.289)
				)
			)
		)
	)
	(footprint ""
		(layer "B.Cu")
		(at 350.3168 -153.8732 180)
		(property "Reference" "CT43"
			(at 0.8382 -0.84963 180)
			(unlocked yes)
			(layer "B.SilkS")
			(effects
				(font
					(size 0.7874 0.5842)
					(thickness 0.1524)
				)
				(justify left mirror)
			)
		)
		(property "Value" ""
			(at 0 0 0)
			(layer "B.Fab")
			(effects
				(font
					(size 1.27 1.27)
				)
				(justify mirror)
			)
		)
		(duplicate_pad_numbers_are_jumpers no)
		(fp_poly
			(pts
				(xy -0.3048 -0.1016) (xy -0.3048 0.9906) (xy 0.3048 0.9906) (xy 0.3048 -0.1016)
			)
			(stroke
				(width 0)
				(type default)
			)
			(fill no)
			(layer "B.CrtYd")
		)
		(fp_line
			(start 0.3048 0.9906)
			(end -0.3048 0.9906)
			(stroke
				(width 0.1)
				(type default)
			)
			(layer "B.Fab")
		)
		(fp_line
			(start 0.3048 -0.1016)
			(end 0.3048 0.9906)
			(stroke
				(width 0.1)
				(type default)
			)
			(layer "B.Fab")
		)
		(fp_line
			(start -0.3048 0.9906)
			(end -0.3048 -0.1016)
			(stroke
				(width 0.1)
				(type default)
			)
			(layer "B.Fab")
		)
		(fp_line
			(start -0.3048 -0.1016)
			(end 0.3048 -0.1016)
			(stroke
				(width 0.1)
				(type default)
			)
			(layer "B.Fab")
		)
		(pad "1" smd rect
			(at 0 0)
			(size 0.508 0.508)
			(layers "B.Cu" "B.Mask" "B.Paste")
			(net "A_TSENSE_PVDDQ_DEF")
		)
		(pad "2" smd rect
			(at 0 0.889)
			(size 0.508 0.508)
			(layers "B.Cu" "B.Mask" "B.Paste")
			(net "GND")
		)
		(zone
			(layer "B.Cu")
			(hatch none 0.5)
			(connect_pads
				(clearance 0)
			)
			(min_thickness 0.25)
			(keepout
				(tracks not_allowed)
				(vias allowed)
				(pads allowed)
				(copperpour not_allowed)
				(footprints allowed)
			)
			(placement
				(enabled no)
				(sheetname "")
			)
			(fill
				(thermal_gap 0.5)
				(thermal_bridge_width 0.5)
				(island_removal_mode 0)
			)
			(polygon
				(pts
					(xy 350.0628 -154.5082) (xy 350.5708 -154.5082) (xy 350.5708 -154.1272) (xy 350.0628 -154.1272)
				)
			)
		)
		(zone
			(layer "B.Cu")
			(hatch none 0.5)
			(connect_pads
				(clearance 0)
			)
			(min_thickness 0.25)
			(keepout
				(tracks allowed)
				(vias not_allowed)
				(pads allowed)
				(copperpour not_allowed)
				(footprints allowed)
			)
			(placement
				(enabled no)
				(sheetname "")
			)
			(fill
				(thermal_gap 0.5)
				(thermal_bridge_width 0.5)
				(island_removal_mode 0)
			)
			(polygon
				(pts
					(xy 350.0628 -154.1272) (xy 350.5708 -154.1272) (xy 350.5708 -154.5082) (xy 350.0628 -154.5082)
				)
			)
		)
	)
	(footprint ""
		(layer "B.Cu")
		(at 344.678 -82.677 180)
		(property "Reference" "R3P25"
			(at 0 0 0)
			(layer "B.SilkS")
			(hide yes)
			(effects
				(font
					(size 1.27 1.27)
				)
				(justify mirror)
			)
		)
		(property "Value" ""
			(at 0 0 0)
			(layer "B.Fab")
			(effects
				(font
					(size 1.27 1.27)
				)
				(justify mirror)
			)
		)
		(duplicate_pad_numbers_are_jumpers no)
		(fp_poly
			(pts
				(xy 0.2794 -0.1016) (xy -0.2794 -0.1016) (xy -0.2794 0.9906) (xy 0.2794 0.9906)
			)
			(stroke
				(width 0)
				(type default)
			)
			(fill no)
			(layer "B.CrtYd")
		)
		(fp_line
			(start 0.2794 0.9906)
			(end -0.2794 0.9906)
			(stroke
				(width 0.1)
				(type default)
			)
			(layer "B.Fab")
		)
		(fp_line
			(start 0.2794 -0.1016)
			(end 0.2794 0.9906)
			(stroke
				(width 0.1)
				(type default)
			)
			(layer "B.Fab")
		)
		(fp_line
			(start -0.2794 0.9906)
			(end -0.2794 -0.1016)
			(stroke
				(width 0.1)
				(type default)
			)
			(layer "B.Fab")
		)
		(fp_line
			(start -0.2794 -0.1016)
			(end 0.2794 -0.1016)
			(stroke
				(width 0.1)
				(type default)
			)
			(layer "B.Fab")
		)
		(pad "1" smd rect
			(at 0 0)
			(size 0.508 0.508)
			(layers "B.Cu" "B.Mask" "B.Paste")
			(net "P3V3_STBY")
		)
		(pad "2" smd rect
			(at 0 0.889)
			(size 0.508 0.508)
			(layers "B.Cu" "B.Mask" "B.Paste")
			(net "PWRGD_PVCCIO_CPU0_R")
		)
		(zone
			(layer "B.Cu")
			(hatch none 0.5)
			(connect_pads
				(clearance 0)
			)
			(min_thickness 0.25)
			(keepout
				(tracks not_allowed)
				(vias allowed)
				(pads allowed)
				(copperpour not_allowed)
				(footprints allowed)
			)
			(placement
				(enabled no)
				(sheetname "")
			)
			(fill
				(thermal_gap 0.5)
				(thermal_bridge_width 0.5)
				(island_removal_mode 0)
			)
			(polygon
				(pts
					(xy 344.424 -83.312) (xy 344.932 -83.312) (xy 344.932 -82.931) (xy 344.424 -82.931)
				)
			)
		)
		(zone
			(layer "B.Cu")
			(hatch none 0.5)
			(connect_pads
				(clearance 0)
			)
			(min_thickness 0.25)
			(keepout
				(tracks allowed)
				(vias not_allowed)
				(pads allowed)
				(copperpour not_allowed)
				(footprints allowed)
			)
			(placement
				(enabled no)
				(sheetname "")
			)
			(fill
				(thermal_gap 0.5)
				(thermal_bridge_width 0.5)
				(island_removal_mode 0)
			)
			(polygon
				(pts
					(xy 344.424 -82.931) (xy 344.932 -82.931) (xy 344.932 -83.312) (xy 344.424 -83.312)
				)
			)
		)
	)
	(footprint ""
		(layer "B.Cu")
		(at 276.479 -68.58 90)
		(property "Reference" "R4P17"
			(at 0 0 90)
			(layer "B.SilkS")
			(hide yes)
			(effects
				(font
					(size 1.27 1.27)
				)
				(justify mirror)
			)
		)
		(property "Value" ""
			(at 0 0 90)
			(layer "B.Fab")
			(effects
				(font
					(size 1.27 1.27)
				)
				(justify mirror)
			)
		)
		(duplicate_pad_numbers_are_jumpers no)
		(fp_poly
			(pts
				(xy 0.2794 -0.1016) (xy -0.2794 -0.1016) (xy -0.2794 0.9906) (xy 0.2794 0.9906)
			)
			(stroke
				(width 0)
				(type default)
			)
			(fill no)
			(layer "B.CrtYd")
		)
		(fp_line
			(start 0.2794 -0.1016)
			(end 0.2794 0.9906)
			(stroke
				(width 0.1)
				(type default)
			)
			(layer "B.Fab")
		)
		(fp_line
			(start -0.2794 -0.1016)
			(end 0.2794 -0.1016)
			(stroke
				(width 0.1)
				(type default)
			)
			(layer "B.Fab")
		)
		(fp_line
			(start 0.2794 0.9906)
			(end -0.2794 0.9906)
			(stroke
				(width 0.1)
				(type default)
			)
			(layer "B.Fab")
		)
		(fp_line
			(start -0.2794 0.9906)
			(end -0.2794 -0.1016)
			(stroke
				(width 0.1)
				(type default)
			)
			(layer "B.Fab")
		)
		(pad "1" smd rect
			(at 0 0 270)
			(size 0.508 0.508)
			(layers "B.Cu" "B.Mask" "B.Paste")
			(net "H_CPU0_MEMABC_MEMHOT_G_N")
		)
		(pad "2" smd rect
			(at 0 0.889 270)
			(size 0.508 0.508)
			(layers "B.Cu" "B.Mask" "B.Paste")
			(net "PVCCIO_CPU0")
		)
		(zone
			(layer "B.Cu")
			(hatch none 0.5)
			(connect_pads
				(clearance 0)
			)
			(min_thickness 0.25)
			(keepout
				(tracks allowed)
				(vias not_allowed)
				(pads allowed)
				(copperpour not_allowed)
				(footprints allowed)
			)
			(placement
				(enabled no)
				(sheetname "")
			)
			(fill
				(thermal_gap 0.5)
				(thermal_bridge_width 0.5)
				(island_removal_mode 0)
			)
			(polygon
				(pts
					(xy 276.733 -68.834) (xy 276.733 -68.326) (xy 277.114 -68.326) (xy 277.114 -68.834)
				)
			)
		)
		(zone
			(layer "B.Cu")
			(hatch none 0.5)
			(connect_pads
				(clearance 0)
			)
			(min_thickness 0.25)
			(keepout
				(tracks not_allowed)
				(vias allowed)
				(pads allowed)
				(copperpour not_allowed)
				(footprints allowed)
			)
			(placement
				(enabled no)
				(sheetname "")
			)
			(fill
				(thermal_gap 0.5)
				(thermal_bridge_width 0.5)
				(island_removal_mode 0)
			)
			(polygon
				(pts
					(xy 277.114 -68.834) (xy 277.114 -68.326) (xy 276.733 -68.326) (xy 276.733 -68.834)
				)
			)
		)
	)
	(footprint ""
		(layer "B.Cu")
		(at 468.884 -127.635 180)
		(property "Reference" "R1M25"
			(at 0 0 0)
			(layer "B.SilkS")
			(hide yes)
			(effects
				(font
					(size 1.27 1.27)
				)
				(justify mirror)
			)
		)
		(property "Value" ""
			(at 0 0 0)
			(layer "B.Fab")
			(effects
				(font
					(size 1.27 1.27)
				)
				(justify mirror)
			)
		)
		(duplicate_pad_numbers_are_jumpers no)
		(fp_poly
			(pts
				(xy 0.2794 -0.1016) (xy -0.2794 -0.1016) (xy -0.2794 0.9906) (xy 0.2794 0.9906)
			)
			(stroke
				(width 0)
				(type default)
			)
			(fill no)
			(layer "B.CrtYd")
		)
		(fp_line
			(start 0.2794 0.9906)
			(end -0.2794 0.9906)
			(stroke
				(width 0.1)
				(type default)
			)
			(layer "B.Fab")
		)
		(fp_line
			(start 0.2794 -0.1016)
			(end 0.2794 0.9906)
			(stroke
				(width 0.1)
				(type default)
			)
			(layer "B.Fab")
		)
		(fp_line
			(start -0.2794 0.9906)
			(end -0.2794 -0.1016)
			(stroke
				(width 0.1)
				(type default)
			)
			(layer "B.Fab")
		)
		(fp_line
			(start -0.2794 -0.1016)
			(end 0.2794 -0.1016)
			(stroke
				(width 0.1)
				(type default)
			)
			(layer "B.Fab")
		)
		(pad "1" smd rect
			(at 0 0)
			(size 0.508 0.508)
			(layers "B.Cu" "B.Mask" "B.Paste")
			(net "FM_USB_P0_EN_R_N")
		)
		(pad "2" smd rect
			(at 0 0.889)
			(size 0.508 0.508)
			(layers "B.Cu" "B.Mask" "B.Paste")
			(net "GND")
		)
		(zone
			(layer "B.Cu")
			(hatch none 0.5)
			(connect_pads
				(clearance 0)
			)
			(min_thickness 0.25)
			(keepout
				(tracks not_allowed)
				(vias allowed)
				(pads allowed)
				(copperpour not_allowed)
				(footprints allowed)
			)
			(placement
				(enabled no)
				(sheetname "")
			)
			(fill
				(thermal_gap 0.5)
				(thermal_bridge_width 0.5)
				(island_removal_mode 0)
			)
			(polygon
				(pts
					(xy 468.63 -128.27) (xy 469.138 -128.27) (xy 469.138 -127.889) (xy 468.63 -127.889)
				)
			)
		)
		(zone
			(layer "B.Cu")
			(hatch none 0.5)
			(connect_pads
				(clearance 0)
			)
			(min_thickness 0.25)
			(keepout
				(tracks allowed)
				(vias not_allowed)
				(pads allowed)
				(copperpour not_allowed)
				(footprints allowed)
			)
			(placement
				(enabled no)
				(sheetname "")
			)
			(fill
				(thermal_gap 0.5)
				(thermal_bridge_width 0.5)
				(island_removal_mode 0)
			)
			(polygon
				(pts
					(xy 468.63 -127.889) (xy 469.138 -127.889) (xy 469.138 -128.27) (xy 468.63 -128.27)
				)
			)
		)
	)
	(footprint ""
		(layer "B.Cu")
		(at 104.5591 -8.1534 90)
		(property "Reference" "C8U2"
			(at -1.848866 0.752348 90)
			(unlocked yes)
			(layer "B.SilkS")
			(effects
				(font
					(size 1.27 0.9652)
					(thickness 0.1524)
				)
				(justify mirror)
			)
		)
		(property "Value" ""
			(at 0 0 90)
			(layer "B.Fab")
			(effects
				(font
					(size 1.27 1.27)
				)
				(justify mirror)
			)
		)
		(duplicate_pad_numbers_are_jumpers no)
		(fp_rect
			(start 0.500126 1.598422)
			(end -0.500126 -0.201422)
			(stroke
				(width 0)
				(type default)
			)
			(fill no)
			(layer "B.CrtYd")
		)
		(fp_line
			(start 0.500126 -0.201422)
			(end -0.500126 -0.201422)
			(stroke
				(width 0.1)
				(type default)
			)
			(layer "B.Fab")
		)
		(fp_line
			(start -0.500126 -0.201422)
			(end -0.500126 1.598422)
			(stroke
				(width 0.1)
				(type default)
			)
			(layer "B.Fab")
		)
		(fp_line
			(start 0.500126 1.598422)
			(end 0.500126 -0.201422)
			(stroke
				(width 0.1)
				(type default)
			)
			(layer "B.Fab")
		)
		(fp_line
			(start -0.500126 1.598422)
			(end 0.500126 1.598422)
			(stroke
				(width 0.1)
				(type default)
			)
			(layer "B.Fab")
		)
		(pad "1" smd rect
			(at 0 0)
			(size 0.889 0.9906)
			(layers "B.Cu" "B.Mask" "B.Paste")
			(net "PVDDQ_GHJ")
		)
		(pad "2" smd rect
			(at 0 1.397)
			(size 0.889 0.9906)
			(layers "B.Cu" "B.Mask" "B.Paste")
			(net "GND")
		)
		(zone
			(layer "B.Cu")
			(hatch none 0.5)
			(connect_pads
				(clearance 0)
			)
			(min_thickness 0.25)
			(keepout
				(tracks allowed)
				(vias not_allowed)
				(pads allowed)
				(copperpour not_allowed)
				(footprints allowed)
			)
			(placement
				(enabled no)
				(sheetname "")
			)
			(fill
				(thermal_gap 0.5)
				(thermal_bridge_width 0.5)
				(island_removal_mode 0)
			)
			(polygon
				(pts
					(xy 105.5116 -8.6487) (xy 105.0036 -8.6487) (xy 105.0036 -7.6581) (xy 105.5116 -7.6581)
				)
			)
		)
		(zone
			(layer "B.Cu")
			(hatch none 0.5)
			(connect_pads
				(clearance 0)
			)
			(min_thickness 0.25)
			(keepout
				(tracks not_allowed)
				(vias allowed)
				(pads allowed)
				(copperpour not_allowed)
				(footprints allowed)
			)
			(placement
				(enabled no)
				(sheetname "")
			)
			(fill
				(thermal_gap 0.5)
				(thermal_bridge_width 0.5)
				(island_removal_mode 0)
			)
			(polygon
				(pts
					(xy 105.5116 -8.6487) (xy 105.0036 -8.6487) (xy 105.0036 -7.6581) (xy 105.5116 -7.6581)
				)
			)
		)
	)
	(footprint ""
		(layer "B.Cu")
		(at 499.62816 -128.52654 -90)
		(property "Reference" "U1M6"
			(at -1.6383 -1.23317 270)
			(unlocked yes)
			(layer "B.SilkS")
			(effects
				(font
					(size 0.7874 0.5842)
					(thickness 0.1524)
				)
				(justify left mirror)
			)
		)
		(property "Value" ""
			(at 0 0 90)
			(layer "B.Fab")
			(effects
				(font
					(size 1.27 1.27)
				)
				(justify mirror)
			)
		)
		(duplicate_pad_numbers_are_jumpers no)
		(fp_circle
			(center 0.4699 -0.8382)
			(end 0.4699 -0.9652)
			(stroke
				(width 0.254)
				(type default)
			)
			(fill no)
			(layer "B.SilkS")
		)
		(fp_poly
			(pts
				(xy -0.21463 -0.450088) (xy -1.56337 -0.450088) (xy -1.56337 1.75006) (xy -0.21463 1.75006)
			)
			(stroke
				(width 0)
				(type default)
			)
			(fill no)
			(layer "B.CrtYd")
		)
		(fp_line
			(start -1.56337 1.75006)
			(end -0.21463 1.75006)
			(stroke
				(width 0.1)
				(type default)
			)
			(layer "B.Fab")
		)
		(fp_line
			(start -0.21463 1.75006)
			(end -0.21463 -0.450088)
			(stroke
				(width 0.1)
				(type default)
			)
			(layer "B.Fab")
		)
		(fp_line
			(start -1.56337 -0.450088)
			(end -1.56337 1.75006)
			(stroke
				(width 0.1)
				(type default)
			)
			(layer "B.Fab")
		)
		(fp_line
			(start -0.21463 -0.450088)
			(end -1.56337 -0.450088)
			(stroke
				(width 0.1)
				(type default)
			)
			(layer "B.Fab")
		)
		(fp_circle
			(center 0.4699 -0.8382)
			(end 0.4699 -0.9652)
			(stroke
				(width 0.254)
				(type default)
			)
			(fill no)
			(layer "B.Fab")
		)
		(pad "1" smd rect
			(at 0 0 90)
			(size 1.016 0.381)
			(layers "B.Cu" "B.Mask" "B.Paste")
			(net "FM_CPU0_AND_CPU1_MCP_PRES")
		)
		(pad "2" smd rect
			(at 0 0.649986 90)
			(size 1.016 0.381)
			(layers "B.Cu" "B.Mask" "B.Paste")
			(net "JTAG_MCP_CPU0_TDO")
		)
		(pad "3" smd rect
			(at 0 1.299972 90)
			(size 1.016 0.381)
			(layers "B.Cu" "B.Mask" "B.Paste")
			(net "GND")
		)
		(pad "4" smd rect
			(at -1.778 1.299972 90)
			(size 1.016 0.381)
			(layers "B.Cu" "B.Mask" "B.Paste")
			(net "JTAG_MCP_CPU1_TDI")
		)
		(pad "5" smd rect
			(at -1.778 0 90)
			(size 1.016 0.381)
			(layers "B.Cu" "B.Mask" "B.Paste")
			(net "P3V3_STBY")
		)
	)
	(footprint ""
		(layer "B.Cu")
		(at 88.392 -17.7546 90)
		(property "Reference" "C8T7"
			(at -1.848866 0.752348 90)
			(unlocked yes)
			(layer "B.SilkS")
			(effects
				(font
					(size 1.27 0.9652)
					(thickness 0.1524)
				)
				(justify mirror)
			)
		)
		(property "Value" ""
			(at 0 0 90)
			(layer "B.Fab")
			(effects
				(font
					(size 1.27 1.27)
				)
				(justify mirror)
			)
		)
		(duplicate_pad_numbers_are_jumpers no)
		(fp_rect
			(start 0.500126 1.598422)
			(end -0.500126 -0.201422)
			(stroke
				(width 0)
				(type default)
			)
			(fill no)
			(layer "B.CrtYd")
		)
		(fp_line
			(start 0.500126 -0.201422)
			(end -0.500126 -0.201422)
			(stroke
				(width 0.1)
				(type default)
			)
			(layer "B.Fab")
		)
		(fp_line
			(start -0.500126 -0.201422)
			(end -0.500126 1.598422)
			(stroke
				(width 0.1)
				(type default)
			)
			(layer "B.Fab")
		)
		(fp_line
			(start 0.500126 1.598422)
			(end 0.500126 -0.201422)
			(stroke
				(width 0.1)
				(type default)
			)
			(layer "B.Fab")
		)
		(fp_line
			(start -0.500126 1.598422)
			(end 0.500126 1.598422)
			(stroke
				(width 0.1)
				(type default)
			)
			(layer "B.Fab")
		)
		(pad "1" smd rect
			(at 0 0)
			(size 0.889 0.9906)
			(layers "B.Cu" "B.Mask" "B.Paste")
			(net "PVDDQ_GHJ")
		)
		(pad "2" smd rect
			(at 0 1.397)
			(size 0.889 0.9906)
			(layers "B.Cu" "B.Mask" "B.Paste")
			(net "GND")
		)
		(zone
			(layer "B.Cu")
			(hatch none 0.5)
			(connect_pads
				(clearance 0)
			)
			(min_thickness 0.25)
			(keepout
				(tracks allowed)
				(vias not_allowed)
				(pads allowed)
				(copperpour not_allowed)
				(footprints allowed)
			)
			(placement
				(enabled no)
				(sheetname "")
			)
			(fill
				(thermal_gap 0.5)
				(thermal_bridge_width 0.5)
				(island_removal_mode 0)
			)
			(polygon
				(pts
					(xy 89.3445 -18.2499) (xy 88.8365 -18.2499) (xy 88.8365 -17.2593) (xy 89.3445 -17.2593)
				)
			)
		)
		(zone
			(layer "B.Cu")
			(hatch none 0.5)
			(connect_pads
				(clearance 0)
			)
			(min_thickness 0.25)
			(keepout
				(tracks not_allowed)
				(vias allowed)
				(pads allowed)
				(copperpour not_allowed)
				(footprints allowed)
			)
			(placement
				(enabled no)
				(sheetname "")
			)
			(fill
				(thermal_gap 0.5)
				(thermal_bridge_width 0.5)
				(island_removal_mode 0)
			)
			(polygon
				(pts
					(xy 89.3445 -18.2499) (xy 88.8365 -18.2499) (xy 88.8365 -17.2593) (xy 89.3445 -17.2593)
				)
			)
		)
	)
	(footprint ""
		(layer "B.Cu")
		(at 374.74271 -75.492864 180)
		(property "Reference" "C3R1"
			(at 0 0 0)
			(layer "B.SilkS")
			(hide yes)
			(effects
				(font
					(size 1.27 1.27)
				)
				(justify mirror)
			)
		)
		(property "Value" ""
			(at 0 0 0)
			(layer "B.Fab")
			(effects
				(font
					(size 1.27 1.27)
				)
				(justify mirror)
			)
		)
		(duplicate_pad_numbers_are_jumpers no)
		(fp_rect
			(start 0.2794 0.9144)
			(end -0.2794 -0.1143)
			(stroke
				(width 0)
				(type default)
			)
			(fill no)
			(layer "B.CrtYd")
		)
		(fp_line
			(start 0.2794 0.9144)
			(end 0.2794 -0.1143)
			(stroke
				(width 0.1)
				(type default)
			)
			(layer "B.Fab")
		)
		(fp_line
			(start 0.2794 -0.1143)
			(end -0.2794 -0.1143)
			(stroke
				(width 0.1)
				(type default)
			)
			(layer "B.Fab")
		)
		(fp_line
			(start -0.2794 0.9144)
			(end 0.2794 0.9144)
			(stroke
				(width 0.1)
				(type default)
			)
			(layer "B.Fab")
		)
		(fp_line
			(start -0.2794 -0.1143)
			(end -0.2794 0.9144)
			(stroke
				(width 0.1)
				(type default)
			)
			(layer "B.Fab")
		)
		(pad "1" smd custom
			(at 0 0 90)
			(size 0.10414 0.10414)
			(layers "B.Cu" "B.Mask" "B.Paste")
			(net "P3V3_STBY")
			(options
				(clearance outline)
				(anchor circle)
			)
			(primitives
				(gr_poly
					(pts
						(xy -0.20828 -0.08636) (xy -0.20828 0.08636) (xy -0.08636 0.20828) (xy 0.086614 0.20828) (xy 0.20828 0.086614)
						(xy 0.20828 -0.08636) (xy 0.08636 -0.20828) (xy -0.08636 -0.20828)
					)
					(width 0)
					(fill yes)
				)
			)
		)
		(pad "2" smd custom
			(at 0 0.8001 90)
			(size 0.10414 0.10414)
			(layers "B.Cu" "B.Mask" "B.Paste")
			(net "GND")
			(options
				(clearance outline)
				(anchor circle)
			)
			(primitives
				(gr_poly
					(pts
						(xy -0.20828 -0.08636) (xy -0.20828 0.08636) (xy -0.08636 0.20828) (xy 0.086614 0.20828) (xy 0.20828 0.086614)
						(xy 0.20828 -0.08636) (xy 0.08636 -0.20828) (xy -0.08636 -0.20828)
					)
					(width 0)
					(fill yes)
				)
			)
		)
		(zone
			(layer "B.Cu")
			(hatch none 0.5)
			(connect_pads
				(clearance 0)
			)
			(min_thickness 0.25)
			(keepout
				(tracks allowed)
				(vias not_allowed)
				(pads allowed)
				(copperpour not_allowed)
				(footprints allowed)
			)
			(placement
				(enabled no)
				(sheetname "")
			)
			(fill
				(thermal_gap 0.5)
				(thermal_bridge_width 0.5)
				(island_removal_mode 0)
			)
			(polygon
				(pts
					(xy 374.65508 -75.702414) (xy 374.65508 -76.083414) (xy 374.83034 -76.083414) (xy 374.830594 -75.702414)
				)
			)
		)
		(zone
			(layer "B.Cu")
			(hatch none 0.5)
			(connect_pads
				(clearance 0)
			)
			(min_thickness 0.25)
			(keepout
				(tracks not_allowed)
				(vias allowed)
				(pads allowed)
				(copperpour not_allowed)
				(footprints allowed)
			)
			(placement
				(enabled no)
				(sheetname "")
			)
			(fill
				(thermal_gap 0.5)
				(thermal_bridge_width 0.5)
				(island_removal_mode 0)
			)
			(polygon
				(pts
					(xy 374.65508 -75.702414) (xy 374.65508 -76.083414) (xy 374.83034 -76.083414) (xy 374.830594 -75.702414)
				)
			)
		)
	)
	(footprint ""
		(layer "B.Cu")
		(at 269.559532 -135.4074 90)
		(property "Reference" "C5M2"
			(at -1.848866 0.752348 90)
			(unlocked yes)
			(layer "B.SilkS")
			(effects
				(font
					(size 1.27 0.9652)
					(thickness 0.1524)
				)
				(justify mirror)
			)
		)
		(property "Value" ""
			(at 0 0 90)
			(layer "B.Fab")
			(effects
				(font
					(size 1.27 1.27)
				)
				(justify mirror)
			)
		)
		(duplicate_pad_numbers_are_jumpers no)
		(fp_rect
			(start 0.500126 1.598422)
			(end -0.500126 -0.201422)
			(stroke
				(width 0)
				(type default)
			)
			(fill no)
			(layer "B.CrtYd")
		)
		(fp_line
			(start 0.500126 -0.201422)
			(end -0.500126 -0.201422)
			(stroke
				(width 0.1)
				(type default)
			)
			(layer "B.Fab")
		)
		(fp_line
			(start -0.500126 -0.201422)
			(end -0.500126 1.598422)
			(stroke
				(width 0.1)
				(type default)
			)
			(layer "B.Fab")
		)
		(fp_line
			(start 0.500126 1.598422)
			(end 0.500126 -0.201422)
			(stroke
				(width 0.1)
				(type default)
			)
			(layer "B.Fab")
		)
		(fp_line
			(start -0.500126 1.598422)
			(end 0.500126 1.598422)
			(stroke
				(width 0.1)
				(type default)
			)
			(layer "B.Fab")
		)
		(pad "1" smd rect
			(at 0 0)
			(size 0.889 0.9906)
			(layers "B.Cu" "B.Mask" "B.Paste")
			(net "PVDDQ_DEF")
		)
		(pad "2" smd rect
			(at 0 1.397)
			(size 0.889 0.9906)
			(layers "B.Cu" "B.Mask" "B.Paste")
			(net "GND")
		)
		(zone
			(layer "B.Cu")
			(hatch none 0.5)
			(connect_pads
				(clearance 0)
			)
			(min_thickness 0.25)
			(keepout
				(tracks not_allowed)
				(vias allowed)
				(pads allowed)
				(copperpour not_allowed)
				(footprints allowed)
			)
			(placement
				(enabled no)
				(sheetname "")
			)
			(fill
				(thermal_gap 0.5)
				(thermal_bridge_width 0.5)
				(island_removal_mode 0)
			)
			(polygon
				(pts
					(xy 270.512032 -135.9027) (xy 270.004032 -135.9027) (xy 270.004032 -134.9121) (xy 270.512032 -134.9121)
				)
			)
		)
		(zone
			(layer "B.Cu")
			(hatch none 0.5)
			(connect_pads
				(clearance 0)
			)
			(min_thickness 0.25)
			(keepout
				(tracks allowed)
				(vias not_allowed)
				(pads allowed)
				(copperpour not_allowed)
				(footprints allowed)
			)
			(placement
				(enabled no)
				(sheetname "")
			)
			(fill
				(thermal_gap 0.5)
				(thermal_bridge_width 0.5)
				(island_removal_mode 0)
			)
			(polygon
				(pts
					(xy 270.512032 -135.9027) (xy 270.004032 -135.9027) (xy 270.004032 -134.9121) (xy 270.512032 -134.9121)
				)
			)
		)
	)
	(footprint ""
		(layer "B.Cu")
		(at 451.9422 -129.9464)
		(property "Reference" "C1M33"
			(at 0 0 0)
			(layer "B.SilkS")
			(hide yes)
			(effects
				(font
					(size 1.27 1.27)
				)
				(justify mirror)
			)
		)
		(property "Value" ""
			(at 0 0 0)
			(layer "B.Fab")
			(effects
				(font
					(size 1.27 1.27)
				)
				(justify mirror)
			)
		)
		(duplicate_pad_numbers_are_jumpers no)
		(fp_poly
			(pts
				(xy -0.3048 -0.1016) (xy -0.3048 0.9906) (xy 0.3048 0.9906) (xy 0.3048 -0.1016)
			)
			(stroke
				(width 0)
				(type default)
			)
			(fill no)
			(layer "B.CrtYd")
		)
		(fp_line
			(start -0.3048 -0.1016)
			(end 0.3048 -0.1016)
			(stroke
				(width 0.1)
				(type default)
			)
			(layer "B.Fab")
		)
		(fp_line
			(start -0.3048 0.9906)
			(end -0.3048 -0.1016)
			(stroke
				(width 0.1)
				(type default)
			)
			(layer "B.Fab")
		)
		(fp_line
			(start 0.3048 -0.1016)
			(end 0.3048 0.9906)
			(stroke
				(width 0.1)
				(type default)
			)
			(layer "B.Fab")
		)
		(fp_line
			(start 0.3048 0.9906)
			(end -0.3048 0.9906)
			(stroke
				(width 0.1)
				(type default)
			)
			(layer "B.Fab")
		)
		(pad "1" smd rect
			(at 0 0 180)
			(size 0.508 0.508)
			(layers "B.Cu" "B.Mask" "B.Paste")
			(net "JTAG_MCP_TMS_R1")
		)
		(pad "2" smd rect
			(at 0 0.889 180)
			(size 0.508 0.508)
			(layers "B.Cu" "B.Mask" "B.Paste")
			(net "GND")
		)
		(zone
			(layer "B.Cu")
			(hatch none 0.5)
			(connect_pads
				(clearance 0)
			)
			(min_thickness 0.25)
			(keepout
				(tracks allowed)
				(vias not_allowed)
				(pads allowed)
				(copperpour not_allowed)
				(footprints allowed)
			)
			(placement
				(enabled no)
				(sheetname "")
			)
			(fill
				(thermal_gap 0.5)
				(thermal_bridge_width 0.5)
				(island_removal_mode 0)
			)
			(polygon
				(pts
					(xy 452.1962 -129.6924) (xy 451.6882 -129.6924) (xy 451.6882 -129.3114) (xy 452.1962 -129.3114)
				)
			)
		)
		(zone
			(layer "B.Cu")
			(hatch none 0.5)
			(connect_pads
				(clearance 0)
			)
			(min_thickness 0.25)
			(keepout
				(tracks not_allowed)
				(vias allowed)
				(pads allowed)
				(copperpour not_allowed)
				(footprints allowed)
			)
			(placement
				(enabled no)
				(sheetname "")
			)
			(fill
				(thermal_gap 0.5)
				(thermal_bridge_width 0.5)
				(island_removal_mode 0)
			)
			(polygon
				(pts
					(xy 452.1962 -129.3114) (xy 451.6882 -129.3114) (xy 451.6882 -129.6924) (xy 452.1962 -129.6924)
				)
			)
		)
	)
	(footprint ""
		(layer "B.Cu")
		(at 491.07344 -123.56592 -90)
		(property "Reference" "R9B6"
			(at 0 0 90)
			(layer "B.SilkS")
			(hide yes)
			(effects
				(font
					(size 1.27 1.27)
				)
				(justify mirror)
			)
		)
		(property "Value" ""
			(at 0 0 90)
			(layer "B.Fab")
			(effects
				(font
					(size 1.27 1.27)
				)
				(justify mirror)
			)
		)
		(duplicate_pad_numbers_are_jumpers no)
		(fp_rect
			(start 0.2794 -0.1016)
			(end -0.2794 0.9906)
			(stroke
				(width 0)
				(type default)
			)
			(fill no)
			(layer "B.CrtYd")
		)
		(fp_line
			(start -0.2794 0.9906)
			(end -0.2794 -0.1016)
			(stroke
				(width 0.1)
				(type default)
			)
			(layer "B.Fab")
		)
		(fp_line
			(start 0.2794 0.9906)
			(end -0.2794 0.9906)
			(stroke
				(width 0.1)
				(type default)
			)
			(layer "B.Fab")
		)
		(fp_line
			(start -0.2794 -0.1016)
			(end 0.2794 -0.1016)
			(stroke
				(width 0.1)
				(type default)
			)
			(layer "B.Fab")
		)
		(fp_line
			(start 0.2794 -0.1016)
			(end 0.2794 0.9906)
			(stroke
				(width 0.1)
				(type default)
			)
			(layer "B.Fab")
		)
		(pad "1" smd rect
			(at 0 0 90)
			(size 0.508 0.508)
			(layers "B.Cu" "B.Mask" "B.Paste")
			(net "P3V3_STBY")
		)
		(pad "2" smd rect
			(at 0 0.889 90)
			(size 0.508 0.508)
			(layers "B.Cu" "B.Mask" "B.Paste")
			(net "PU_TMP421_1_A1")
		)
		(zone
			(layer "B.Cu")
			(hatch none 0.5)
			(connect_pads
				(clearance 0)
			)
			(min_thickness 0.25)
			(keepout
				(tracks not_allowed)
				(vias allowed)
				(pads allowed)
				(copperpour not_allowed)
				(footprints allowed)
			)
			(placement
				(enabled no)
				(sheetname "")
			)
			(fill
				(thermal_gap 0.5)
				(thermal_bridge_width 0.5)
				(island_removal_mode 0)
			)
			(polygon
				(pts
					(xy 490.81944 -123.31192) (xy 490.81944 -123.81992) (xy 490.43844 -123.81992) (xy 490.43844 -123.31192)
				)
			)
		)
		(zone
			(layer "B.Cu")
			(hatch none 0.5)
			(connect_pads
				(clearance 0)
			)
			(min_thickness 0.25)
			(keepout
				(tracks allowed)
				(vias not_allowed)
				(pads allowed)
				(copperpour not_allowed)
				(footprints allowed)
			)
			(placement
				(enabled no)
				(sheetname "")
			)
			(fill
				(thermal_gap 0.5)
				(thermal_bridge_width 0.5)
				(island_removal_mode 0)
			)
			(polygon
				(pts
					(xy 490.81944 -123.31192) (xy 490.81944 -123.81992) (xy 490.43844 -123.81992) (xy 490.43844 -123.31192)
				)
			)
		)
	)
	(footprint ""
		(layer "B.Cu")
		(at 387.75894 -85.51672 90)
		(property "Reference" "R8D16"
			(at 0.8382 -0.67818 90)
			(unlocked yes)
			(layer "B.SilkS")
			(effects
				(font
					(size 0.4064 0.254)
					(thickness 0.1524)
				)
				(justify left mirror)
			)
		)
		(property "Value" ""
			(at 0 0 90)
			(layer "B.Fab")
			(effects
				(font
					(size 1.27 1.27)
				)
				(justify mirror)
			)
		)
		(duplicate_pad_numbers_are_jumpers no)
		(fp_poly
			(pts
				(xy 0.2794 -0.1016) (xy -0.2794 -0.1016) (xy -0.2794 0.9906) (xy 0.2794 0.9906)
			)
			(stroke
				(width 0)
				(type default)
			)
			(fill no)
			(layer "B.CrtYd")
		)
		(fp_line
			(start 0.2794 -0.1016)
			(end 0.2794 0.9906)
			(stroke
				(width 0.1)
				(type default)
			)
			(layer "B.Fab")
		)
		(fp_line
			(start -0.2794 -0.1016)
			(end 0.2794 -0.1016)
			(stroke
				(width 0.1)
				(type default)
			)
			(layer "B.Fab")
		)
		(fp_line
			(start 0.2794 0.9906)
			(end -0.2794 0.9906)
			(stroke
				(width 0.1)
				(type default)
			)
			(layer "B.Fab")
		)
		(fp_line
			(start -0.2794 0.9906)
			(end -0.2794 -0.1016)
			(stroke
				(width 0.1)
				(type default)
			)
			(layer "B.Fab")
		)
		(pad "1" smd rect
			(at 0 0 270)
			(size 0.508 0.508)
			(layers "B.Cu" "B.Mask" "B.Paste")
			(net "P3V3_STBY")
		)
		(pad "2" smd rect
			(at 0 0.889 270)
			(size 0.508 0.508)
			(layers "B.Cu" "B.Mask" "B.Paste")
			(net "RMII_PCH_SPRNGVLLE_ARB_OUT")
		)
		(zone
			(layer "B.Cu")
			(hatch none 0.5)
			(connect_pads
				(clearance 0)
			)
			(min_thickness 0.25)
			(keepout
				(tracks allowed)
				(vias not_allowed)
				(pads allowed)
				(copperpour not_allowed)
				(footprints allowed)
			)
			(placement
				(enabled no)
				(sheetname "")
			)
			(fill
				(thermal_gap 0.5)
				(thermal_bridge_width 0.5)
				(island_removal_mode 0)
			)
			(polygon
				(pts
					(xy 388.01294 -85.77072) (xy 388.01294 -85.26272) (xy 388.39394 -85.26272) (xy 388.39394 -85.77072)
				)
			)
		)
		(zone
			(layer "B.Cu")
			(hatch none 0.5)
			(connect_pads
				(clearance 0)
			)
			(min_thickness 0.25)
			(keepout
				(tracks not_allowed)
				(vias allowed)
				(pads allowed)
				(copperpour not_allowed)
				(footprints allowed)
			)
			(placement
				(enabled no)
				(sheetname "")
			)
			(fill
				(thermal_gap 0.5)
				(thermal_bridge_width 0.5)
				(island_removal_mode 0)
			)
			(polygon
				(pts
					(xy 388.39394 -85.77072) (xy 388.39394 -85.26272) (xy 388.01294 -85.26272) (xy 388.01294 -85.77072)
				)
			)
		)
	)
	(footprint ""
		(layer "B.Cu")
		(at 362.270294 -42.369486)
		(property "Reference" "R2T65"
			(at 0 0 0)
			(layer "B.SilkS")
			(hide yes)
			(effects
				(font
					(size 1.27 1.27)
				)
				(justify mirror)
			)
		)
		(property "Value" ""
			(at 0 0 0)
			(layer "B.Fab")
			(effects
				(font
					(size 1.27 1.27)
				)
				(justify mirror)
			)
		)
		(duplicate_pad_numbers_are_jumpers no)
		(fp_poly
			(pts
				(xy 0.2794 -0.1016) (xy -0.2794 -0.1016) (xy -0.2794 0.9906) (xy 0.2794 0.9906)
			)
			(stroke
				(width 0)
				(type default)
			)
			(fill no)
			(layer "B.CrtYd")
		)
		(fp_line
			(start -0.2794 -0.1016)
			(end 0.2794 -0.1016)
			(stroke
				(width 0.1)
				(type default)
			)
			(layer "B.Fab")
		)
		(fp_line
			(start -0.2794 0.9906)
			(end -0.2794 -0.1016)
			(stroke
				(width 0.1)
				(type default)
			)
			(layer "B.Fab")
		)
		(fp_line
			(start 0.2794 -0.1016)
			(end 0.2794 0.9906)
			(stroke
				(width 0.1)
				(type default)
			)
			(layer "B.Fab")
		)
		(fp_line
			(start 0.2794 0.9906)
			(end -0.2794 0.9906)
			(stroke
				(width 0.1)
				(type default)
			)
			(layer "B.Fab")
		)
		(pad "1" smd rect
			(at 0 0 180)
			(size 0.508 0.508)
			(layers "B.Cu" "B.Mask" "B.Paste")
			(net "FM_CPU_ERR0_LVT3_R_N")
		)
		(pad "2" smd rect
			(at 0 0.889 180)
			(size 0.508 0.508)
			(layers "B.Cu" "B.Mask" "B.Paste")
			(net "FM_CPU_ERR0_LVT3_K_N")
		)
		(zone
			(layer "B.Cu")
			(hatch none 0.5)
			(connect_pads
				(clearance 0)
			)
			(min_thickness 0.25)
			(keepout
				(tracks allowed)
				(vias not_allowed)
				(pads allowed)
				(copperpour not_allowed)
				(footprints allowed)
			)
			(placement
				(enabled no)
				(sheetname "")
			)
			(fill
				(thermal_gap 0.5)
				(thermal_bridge_width 0.5)
				(island_removal_mode 0)
			)
			(polygon
				(pts
					(xy 362.524294 -42.115486) (xy 362.016294 -42.115486) (xy 362.016294 -41.734486) (xy 362.524294 -41.734486)
				)
			)
		)
		(zone
			(layer "B.Cu")
			(hatch none 0.5)
			(connect_pads
				(clearance 0)
			)
			(min_thickness 0.25)
			(keepout
				(tracks not_allowed)
				(vias allowed)
				(pads allowed)
				(copperpour not_allowed)
				(footprints allowed)
			)
			(placement
				(enabled no)
				(sheetname "")
			)
			(fill
				(thermal_gap 0.5)
				(thermal_bridge_width 0.5)
				(island_removal_mode 0)
			)
			(polygon
				(pts
					(xy 362.524294 -41.734486) (xy 362.016294 -41.734486) (xy 362.016294 -42.115486) (xy 362.524294 -42.115486)
				)
			)
		)
	)
	(footprint ""
		(layer "B.Cu")
		(at 393.375896 -51.66868 90)
		(property "Reference" "U3T1"
			(at 0 0 90)
			(layer "B.SilkS")
			(hide yes)
			(effects
				(font
					(size 1.27 1.27)
				)
				(justify mirror)
			)
		)
		(property "Value" "*"
			(at 6.7945 -2.3241 90)
			(unlocked yes)
			(layer "B.Fab")
			(hide yes)
			(effects
				(font
					(size 1.27 1.016)
					(thickness 0.1524)
				)
				(justify mirror)
			)
		)
		(property "Device Type" "W25Q256FVFIG-GP_MEMORY-G4-W25QA"
			(at 6.7945 -3.8481 90)
			(unlocked yes)
			(layer "B.Fab")
			(hide yes)
			(effects
				(font
					(size 1.27 1.016)
					(thickness 0.1524)
				)
				(justify mirror)
			)
		)
		(duplicate_pad_numbers_are_jumpers no)
		(fp_line
			(start 5.588 -3.2258)
			(end -4.7498 -3.2258)
			(stroke
				(width 0.1524)
				(type default)
			)
			(layer "B.SilkS")
		)
		(fp_line
			(start -4.7498 -3.2258)
			(end -4.7498 3.2258)
			(stroke
				(width 0.1524)
				(type default)
			)
			(layer "B.SilkS")
		)
		(fp_line
			(start 5.588 -0.50038)
			(end 5.08762 0)
			(stroke
				(width 0.1524)
				(type default)
			)
			(layer "B.SilkS")
		)
		(fp_line
			(start 5.08762 0)
			(end 5.588 0.50038)
			(stroke
				(width 0.1524)
				(type default)
			)
			(layer "B.SilkS")
		)
		(fp_line
			(start 5.588 3.2258)
			(end 5.588 -3.2258)
			(stroke
				(width 0.1524)
				(type default)
			)
			(layer "B.SilkS")
		)
		(fp_line
			(start 5.4102 3.2258)
			(end 5.4102 5.7912)
			(stroke
				(width 0.508)
				(type default)
			)
			(layer "B.SilkS")
		)
		(fp_line
			(start -4.7498 3.2258)
			(end 5.588 3.2258)
			(stroke
				(width 0.1524)
				(type default)
			)
			(layer "B.SilkS")
		)
		(fp_poly
			(pts
				(xy 4.764786 -3.2258) (xy -4.7625 -3.2258) (xy -4.7625 3.2258) (xy 4.764786 3.2258)
			)
			(stroke
				(width 0)
				(type default)
			)
			(fill yes)
			(layer "B.SilkS")
		)
		(fp_rect
			(start 5.1435 5.1562)
			(end -5.1435 -5.1562)
			(stroke
				(width 0)
				(type default)
			)
			(fill no)
			(layer "B.CrtYd")
		)
		(fp_poly
			(pts
				(xy 5.6642 6.0452) (xy 5.6642 -6.0452) (xy -5.6642 -6.0452) (xy -5.6642 -1.7653) (xy -5.1435 -1.7653)
				(xy -5.1435 -5.1562) (xy 5.1435 -5.1562) (xy 5.1435 5.1562) (xy -5.1435 5.1562) (xy -5.1435 -1.7526)
				(xy -5.6642 -1.7526) (xy -5.6642 6.0452)
			)
			(stroke
				(width 0)
				(type default)
			)
			(fill no)
			(layer "B.CrtYd")
		)
		(fp_rect
			(start 5.6642 6.0452)
			(end -5.6642 -6.0452)
			(stroke
				(width 0)
				(type default)
			)
			(fill no)
			(layer "B.Fab")
		)
		(pad "1" smd rect
			(at 4.445 4.71805 270)
			(size 0.635 1.651)
			(layers "B.Cu" "B.Mask" "B.Paste")
			(net "PU_BIOS_SPI_HOLD1_N")
		)
		(pad "2" smd rect
			(at 3.175 4.71805 270)
			(size 0.635 1.651)
			(layers "B.Cu" "B.Mask" "B.Paste")
			(net "P3V3_STBY")
		)
		(pad "3" smd rect
			(at 1.905 4.71805 270)
			(size 0.635 1.651)
			(layers "B.Cu" "B.Mask" "B.Paste")
			(net "PU_SPI1_RST")
		)
		(pad "4" smd rect
			(at 0.635 4.71805 270)
			(size 0.635 1.651)
			(layers "B.Cu" "B.Mask" "B.Paste")
			(net "TP_SPI_1_6")
		)
		(pad "5" smd rect
			(at -0.635 4.71805 270)
			(size 0.635 1.651)
			(layers "B.Cu" "B.Mask" "B.Paste")
			(net "TP_SPI_1_5")
		)
		(pad "6" smd rect
			(at -1.905 4.71805 270)
			(size 0.635 1.651)
			(layers "B.Cu" "B.Mask" "B.Paste")
			(net "TP_SPI_1_4")
		)
		(pad "7" smd rect
			(at -3.175 4.71805 270)
			(size 0.635 1.651)
			(layers "B.Cu" "B.Mask" "B.Paste")
			(net "SPI_CS0_SECONDARY_R_N")
		)
		(pad "8" smd rect
			(at -4.445 4.71805 270)
			(size 0.635 1.651)
			(layers "B.Cu" "B.Mask" "B.Paste")
			(net "SPI_MISO_R1")
		)
		(pad "9" smd rect
			(at -4.445 -4.71805 270)
			(size 0.635 1.651)
			(layers "B.Cu" "B.Mask" "B.Paste")
			(net "PU_BIOS_SPI_WP1_N")
		)
		(pad "10" smd rect
			(at -3.175 -4.71805 270)
			(size 0.635 1.651)
			(layers "B.Cu" "B.Mask" "B.Paste")
			(net "GND")
		)
		(pad "11" smd rect
			(at -1.905 -4.71805 270)
			(size 0.635 1.651)
			(layers "B.Cu" "B.Mask" "B.Paste")
			(net "TP_SPI_1_3")
		)
		(pad "12" smd rect
			(at -0.635 -4.71805 270)
			(size 0.635 1.651)
			(layers "B.Cu" "B.Mask" "B.Paste")
			(net "TP_SPI_1_2")
		)
		(pad "13" smd rect
			(at 0.635 -4.71805 270)
			(size 0.635 1.651)
			(layers "B.Cu" "B.Mask" "B.Paste")
			(net "TP_SPI_1_1")
		)
		(pad "14" smd rect
			(at 1.905 -4.71805 270)
			(size 0.635 1.651)
			(layers "B.Cu" "B.Mask" "B.Paste")
			(net "TP_SPI_1_0")
		)
		(pad "15" smd rect
			(at 3.175 -4.71805 270)
			(size 0.635 1.651)
			(layers "B.Cu" "B.Mask" "B.Paste")
			(net "SPI_SWITCH_MOSI_R1")
		)
		(pad "16" smd rect
			(at 4.445 -4.71805 270)
			(size 0.635 1.651)
			(layers "B.Cu" "B.Mask" "B.Paste")
			(net "SPI_CLK_R1")
		)
	)
	(footprint ""
		(layer "B.Cu")
		(at 351.663 -133.223 180)
		(property "Reference" "C3M16"
			(at 0 0 0)
			(layer "B.SilkS")
			(hide yes)
			(effects
				(font
					(size 1.27 1.27)
				)
				(justify mirror)
			)
		)
		(property "Value" ""
			(at 0 0 0)
			(layer "B.Fab")
			(effects
				(font
					(size 1.27 1.27)
				)
				(justify mirror)
			)
		)
		(duplicate_pad_numbers_are_jumpers no)
		(fp_poly
			(pts
				(xy 0.7239 -0.2159) (xy -0.7239 -0.2159) (xy -0.7239 1.9939) (xy 0.7239 1.9939)
			)
			(stroke
				(width 0)
				(type default)
			)
			(fill no)
			(layer "B.CrtYd")
		)
		(fp_line
			(start 0.7239 1.9939)
			(end -0.7239 1.9939)
			(stroke
				(width 0.1)
				(type default)
			)
			(layer "B.Fab")
		)
		(fp_line
			(start 0.7239 -0.2159)
			(end 0.7239 1.9939)
			(stroke
				(width 0.1)
				(type default)
			)
			(layer "B.Fab")
		)
		(fp_line
			(start -0.7239 1.9939)
			(end -0.7239 -0.2159)
			(stroke
				(width 0.1)
				(type default)
			)
			(layer "B.Fab")
		)
		(fp_line
			(start -0.7239 -0.2159)
			(end 0.7239 -0.2159)
			(stroke
				(width 0.1)
				(type default)
			)
			(layer "B.Fab")
		)
		(pad "1" smd rect
			(at 0 0)
			(size 1.27 1.016)
			(layers "B.Cu" "B.Mask" "B.Paste")
			(net "VR_FET_SW_P12V_STBY_PVPP_DEF")
		)
		(pad "2" smd rect
			(at 0 1.778)
			(size 1.27 1.016)
			(layers "B.Cu" "B.Mask" "B.Paste")
			(net "GND")
		)
		(zone
			(layer "B.Cu")
			(hatch none 0.5)
			(connect_pads
				(clearance 0)
			)
			(min_thickness 0.25)
			(keepout
				(tracks not_allowed)
				(vias allowed)
				(pads allowed)
				(copperpour not_allowed)
				(footprints allowed)
			)
			(placement
				(enabled no)
				(sheetname "")
			)
			(fill
				(thermal_gap 0.5)
				(thermal_bridge_width 0.5)
				(island_removal_mode 0)
			)
			(polygon
				(pts
					(xy 351.028 -133.731) (xy 352.298 -133.731) (xy 352.298 -134.493) (xy 351.028 -134.493)
				)
			)
		)
	)
	(footprint ""
		(layer "B.Cu")
		(at 352.904806 -60.368434)
		(property "Reference" "R2U28"
			(at 0 0 0)
			(layer "B.SilkS")
			(hide yes)
			(effects
				(font
					(size 1.27 1.27)
				)
				(justify mirror)
			)
		)
		(property "Value" ""
			(at 0 0 0)
			(layer "B.Fab")
			(effects
				(font
					(size 1.27 1.27)
				)
				(justify mirror)
			)
		)
		(duplicate_pad_numbers_are_jumpers no)
		(fp_poly
			(pts
				(xy 0.2794 -0.1016) (xy -0.2794 -0.1016) (xy -0.2794 0.9906) (xy 0.2794 0.9906)
			)
			(stroke
				(width 0)
				(type default)
			)
			(fill no)
			(layer "B.CrtYd")
		)
		(fp_line
			(start -0.2794 -0.1016)
			(end 0.2794 -0.1016)
			(stroke
				(width 0.1)
				(type default)
			)
			(layer "B.Fab")
		)
		(fp_line
			(start -0.2794 0.9906)
			(end -0.2794 -0.1016)
			(stroke
				(width 0.1)
				(type default)
			)
			(layer "B.Fab")
		)
		(fp_line
			(start 0.2794 -0.1016)
			(end 0.2794 0.9906)
			(stroke
				(width 0.1)
				(type default)
			)
			(layer "B.Fab")
		)
		(fp_line
			(start 0.2794 0.9906)
			(end -0.2794 0.9906)
			(stroke
				(width 0.1)
				(type default)
			)
			(layer "B.Fab")
		)
		(pad "1" smd rect
			(at 0 0 180)
			(size 0.508 0.508)
			(layers "B.Cu" "B.Mask" "B.Paste")
			(net "P3E_CPU0_PE1_SS_RXP<7>")
		)
		(pad "2" smd rect
			(at 0 0.889 180)
			(size 0.508 0.508)
			(layers "B.Cu" "B.Mask" "B.Paste")
			(net "P3E_CPU0_PE1_SS_R_RXP<7>")
		)
		(zone
			(layer "B.Cu")
			(hatch none 0.5)
			(connect_pads
				(clearance 0)
			)
			(min_thickness 0.25)
			(keepout
				(tracks allowed)
				(vias not_allowed)
				(pads allowed)
				(copperpour not_allowed)
				(footprints allowed)
			)
			(placement
				(enabled no)
				(sheetname "")
			)
			(fill
				(thermal_gap 0.5)
				(thermal_bridge_width 0.5)
				(island_removal_mode 0)
			)
			(polygon
				(pts
					(xy 353.158806 -60.114434) (xy 352.650806 -60.114434) (xy 352.650806 -59.733434) (xy 353.158806 -59.733434)
				)
			)
		)
		(zone
			(layer "B.Cu")
			(hatch none 0.5)
			(connect_pads
				(clearance 0)
			)
			(min_thickness 0.25)
			(keepout
				(tracks not_allowed)
				(vias allowed)
				(pads allowed)
				(copperpour not_allowed)
				(footprints allowed)
			)
			(placement
				(enabled no)
				(sheetname "")
			)
			(fill
				(thermal_gap 0.5)
				(thermal_bridge_width 0.5)
				(island_removal_mode 0)
			)
			(polygon
				(pts
					(xy 353.158806 -59.733434) (xy 352.650806 -59.733434) (xy 352.650806 -60.114434) (xy 353.158806 -60.114434)
				)
			)
		)
	)
	(footprint ""
		(layer "B.Cu")
		(at 210.612228 -100.676202 -90)
		(property "Reference" "C6N1"
			(at -1.659128 -3.382772 0)
			(unlocked yes)
			(layer "B.SilkS")
			(effects
				(font
					(size 0.7874 0.5842)
					(thickness 0.1524)
				)
				(justify mirror)
			)
		)
		(property "Value" ""
			(at 0 0 90)
			(layer "B.Fab")
			(effects
				(font
					(size 1.27 1.27)
				)
				(justify mirror)
			)
		)
		(duplicate_pad_numbers_are_jumpers no)
		(fp_line
			(start -2.286 7.366)
			(end -1.600708 7.366)
			(stroke
				(width 0.1524)
				(type default)
			)
			(layer "B.SilkS")
		)
		(fp_line
			(start -2.286 7.366)
			(end -2.286 1.63195)
			(stroke
				(width 0.1524)
				(type default)
			)
			(layer "B.SilkS")
		)
		(fp_line
			(start 2.286 7.366)
			(end 1.60147 7.366)
			(stroke
				(width 0.1524)
				(type default)
			)
			(layer "B.SilkS")
		)
		(fp_line
			(start 2.286 7.366)
			(end 2.286 1.632712)
			(stroke
				(width 0.1524)
				(type default)
			)
			(layer "B.SilkS")
		)
		(fp_line
			(start -2.504948 1.633728)
			(end -1.6002 1.633728)
			(stroke
				(width 0.1524)
				(type default)
			)
			(layer "B.SilkS")
		)
		(fp_line
			(start 2.563114 1.633728)
			(end 1.6002 1.633728)
			(stroke
				(width 0.1524)
				(type default)
			)
			(layer "B.SilkS")
		)
		(fp_line
			(start -2.504948 -1.616456)
			(end -2.504948 1.633728)
			(stroke
				(width 0.1524)
				(type default)
			)
			(layer "B.SilkS")
		)
		(fp_line
			(start -1.6002 -1.616456)
			(end -2.504948 -1.616456)
			(stroke
				(width 0.1524)
				(type default)
			)
			(layer "B.SilkS")
		)
		(fp_line
			(start 1.6002 -1.616456)
			(end 2.563114 -1.616456)
			(stroke
				(width 0.1524)
				(type default)
			)
			(layer "B.SilkS")
		)
		(fp_line
			(start 2.563114 -1.616456)
			(end 2.563114 1.633728)
			(stroke
				(width 0.1524)
				(type default)
			)
			(layer "B.SilkS")
		)
		(fp_rect
			(start 2.286 7.366)
			(end -2.286 -0.254)
			(stroke
				(width 0)
				(type default)
			)
			(fill no)
			(layer "B.CrtYd")
		)
		(fp_line
			(start -2.286 7.366)
			(end 2.286 7.366)
			(stroke
				(width 0.1)
				(type default)
			)
			(layer "B.Fab")
		)
		(fp_line
			(start 2.286 7.366)
			(end 2.286 -0.254)
			(stroke
				(width 0.1)
				(type default)
			)
			(layer "B.Fab")
		)
		(fp_line
			(start -2.286 -0.254)
			(end -2.286 7.366)
			(stroke
				(width 0.1)
				(type default)
			)
			(layer "B.Fab")
		)
		(fp_line
			(start 2.286 -0.254)
			(end -2.286 -0.254)
			(stroke
				(width 0.1)
				(type default)
			)
			(layer "B.Fab")
		)
		(pad "1" smd rect
			(at 0 0 90)
			(size 2.54 3.048)
			(layers "B.Cu" "B.Mask" "B.Paste")
			(net "PVSA_CPU0")
		)
		(pad "2" smd rect
			(at 0 7.112 90)
			(size 2.54 3.048)
			(layers "B.Cu" "B.Mask" "B.Paste")
			(net "GND")
		)
	)
	(footprint ""
		(layer "B.Cu")
		(at 271.604486 -68.17614 180)
		(property "Reference" "C5P42"
			(at 0 0 0)
			(layer "B.SilkS")
			(hide yes)
			(effects
				(font
					(size 1.27 1.27)
				)
				(justify mirror)
			)
		)
		(property "Value" ""
			(at 0 0 0)
			(layer "B.Fab")
			(effects
				(font
					(size 1.27 1.27)
				)
				(justify mirror)
			)
		)
		(duplicate_pad_numbers_are_jumpers no)
		(fp_poly
			(pts
				(xy 0.7239 -0.2159) (xy -0.7239 -0.2159) (xy -0.7239 1.9939) (xy 0.7239 1.9939)
			)
			(stroke
				(width 0)
				(type default)
			)
			(fill no)
			(layer "B.CrtYd")
		)
		(fp_line
			(start 0.7239 1.9939)
			(end -0.7239 1.9939)
			(stroke
				(width 0.1)
				(type default)
			)
			(layer "B.Fab")
		)
		(fp_line
			(start 0.7239 -0.2159)
			(end 0.7239 1.9939)
			(stroke
				(width 0.1)
				(type default)
			)
			(layer "B.Fab")
		)
		(fp_line
			(start -0.7239 1.9939)
			(end -0.7239 -0.2159)
			(stroke
				(width 0.1)
				(type default)
			)
			(layer "B.Fab")
		)
		(fp_line
			(start -0.7239 -0.2159)
			(end 0.7239 -0.2159)
			(stroke
				(width 0.1)
				(type default)
			)
			(layer "B.Fab")
		)
		(pad "1" smd rect
			(at 0 0)
			(size 1.27 1.016)
			(layers "B.Cu" "B.Mask" "B.Paste")
			(net "PVDDQ_ABC")
		)
		(pad "2" smd rect
			(at 0 1.778)
			(size 1.27 1.016)
			(layers "B.Cu" "B.Mask" "B.Paste")
			(net "GND")
		)
		(zone
			(layer "B.Cu")
			(hatch none 0.5)
			(connect_pads
				(clearance 0)
			)
			(min_thickness 0.25)
			(keepout
				(tracks not_allowed)
				(vias allowed)
				(pads allowed)
				(copperpour not_allowed)
				(footprints allowed)
			)
			(placement
				(enabled no)
				(sheetname "")
			)
			(fill
				(thermal_gap 0.5)
				(thermal_bridge_width 0.5)
				(island_removal_mode 0)
			)
			(polygon
				(pts
					(xy 270.969486 -68.68414) (xy 272.239486 -68.68414) (xy 272.239486 -69.44614) (xy 270.969486 -69.44614)
				)
			)
		)
	)
	(footprint ""
		(layer "B.Cu")
		(at 348.794578 -99.966272 -90)
		(property "Reference" "R3N7"
			(at 0 0 90)
			(layer "B.SilkS")
			(hide yes)
			(effects
				(font
					(size 1.27 1.27)
				)
				(justify mirror)
			)
		)
		(property "Value" ""
			(at 0 0 90)
			(layer "B.Fab")
			(effects
				(font
					(size 1.27 1.27)
				)
				(justify mirror)
			)
		)
		(duplicate_pad_numbers_are_jumpers no)
		(fp_poly
			(pts
				(xy 0.2794 -0.1016) (xy -0.2794 -0.1016) (xy -0.2794 0.9906) (xy 0.2794 0.9906)
			)
			(stroke
				(width 0)
				(type default)
			)
			(fill no)
			(layer "B.CrtYd")
		)
		(fp_line
			(start -0.2794 0.9906)
			(end -0.2794 -0.1016)
			(stroke
				(width 0.1)
				(type default)
			)
			(layer "B.Fab")
		)
		(fp_line
			(start 0.2794 0.9906)
			(end -0.2794 0.9906)
			(stroke
				(width 0.1)
				(type default)
			)
			(layer "B.Fab")
		)
		(fp_line
			(start -0.2794 -0.1016)
			(end 0.2794 -0.1016)
			(stroke
				(width 0.1)
				(type default)
			)
			(layer "B.Fab")
		)
		(fp_line
			(start 0.2794 -0.1016)
			(end 0.2794 0.9906)
			(stroke
				(width 0.1)
				(type default)
			)
			(layer "B.Fab")
		)
		(pad "1" smd rect
			(at 0 0 90)
			(size 0.508 0.508)
			(layers "B.Cu" "B.Mask" "B.Paste")
			(net "VR_PVCCIO_CPU0_PH1_VCIN")
		)
		(pad "2" smd rect
			(at 0 0.889 90)
			(size 0.508 0.508)
			(layers "B.Cu" "B.Mask" "B.Paste")
			(net "P5V_STBY")
		)
		(zone
			(layer "B.Cu")
			(hatch none 0.5)
			(connect_pads
				(clearance 0)
			)
			(min_thickness 0.25)
			(keepout
				(tracks not_allowed)
				(vias allowed)
				(pads allowed)
				(copperpour not_allowed)
				(footprints allowed)
			)
			(placement
				(enabled no)
				(sheetname "")
			)
			(fill
				(thermal_gap 0.5)
				(thermal_bridge_width 0.5)
				(island_removal_mode 0)
			)
			(polygon
				(pts
					(xy 348.159578 -99.712272) (xy 348.159578 -100.220272) (xy 348.540578 -100.220272) (xy 348.540578 -99.712272)
				)
			)
		)
		(zone
			(layer "B.Cu")
			(hatch none 0.5)
			(connect_pads
				(clearance 0)
			)
			(min_thickness 0.25)
			(keepout
				(tracks allowed)
				(vias not_allowed)
				(pads allowed)
				(copperpour not_allowed)
				(footprints allowed)
			)
			(placement
				(enabled no)
				(sheetname "")
			)
			(fill
				(thermal_gap 0.5)
				(thermal_bridge_width 0.5)
				(island_removal_mode 0)
			)
			(polygon
				(pts
					(xy 348.540578 -99.712272) (xy 348.540578 -100.220272) (xy 348.159578 -100.220272) (xy 348.159578 -99.712272)
				)
			)
		)
	)
	(footprint ""
		(layer "B.Cu")
		(at 472.2368 -124.8791 90)
		(property "Reference" "R1M5"
			(at 0 0 90)
			(layer "B.SilkS")
			(hide yes)
			(effects
				(font
					(size 1.27 1.27)
				)
				(justify mirror)
			)
		)
		(property "Value" ""
			(at 0 0 90)
			(layer "B.Fab")
			(effects
				(font
					(size 1.27 1.27)
				)
				(justify mirror)
			)
		)
		(duplicate_pad_numbers_are_jumpers no)
		(fp_rect
			(start -0.2794 -0.1016)
			(end 0.2794 0.9906)
			(stroke
				(width 0)
				(type default)
			)
			(fill no)
			(layer "B.CrtYd")
		)
		(fp_line
			(start 0.2794 -0.1016)
			(end 0.2794 0.9906)
			(stroke
				(width 0.1)
				(type default)
			)
			(layer "B.Fab")
		)
		(fp_line
			(start -0.2794 -0.1016)
			(end 0.2794 -0.1016)
			(stroke
				(width 0.1)
				(type default)
			)
			(layer "B.Fab")
		)
		(fp_line
			(start 0.2794 0.9906)
			(end -0.2794 0.9906)
			(stroke
				(width 0.1)
				(type default)
			)
			(layer "B.Fab")
		)
		(fp_line
			(start -0.2794 0.9906)
			(end -0.2794 -0.1016)
			(stroke
				(width 0.1)
				(type default)
			)
			(layer "B.Fab")
		)
		(pad "1" smd rect
			(at 0 0 270)
			(size 0.508 0.508)
			(layers "B.Cu" "B.Mask" "B.Paste")
			(net "USB2_P01_DP")
		)
		(pad "2" smd rect
			(at 0 0.889 270)
			(size 0.508 0.508)
			(layers "B.Cu" "B.Mask" "B.Paste")
			(net "USB2_P01_ESD_DP")
		)
		(zone
			(layer "B.Cu")
			(hatch none 0.5)
			(connect_pads
				(clearance 0)
			)
			(min_thickness 0.25)
			(keepout
				(tracks allowed)
				(vias not_allowed)
				(pads allowed)
				(copperpour not_allowed)
				(footprints allowed)
			)
			(placement
				(enabled no)
				(sheetname "")
			)
			(fill
				(thermal_gap 0.5)
				(thermal_bridge_width 0.5)
				(island_removal_mode 0)
			)
			(polygon
				(pts
					(xy 472.4908 -124.6251) (xy 472.8718 -124.6251) (xy 472.8718 -125.1331) (xy 472.4908 -125.1331)
				)
			)
		)
	)
	(footprint ""
		(layer "B.Cu")
		(at 269.559532 -17.7546 90)
		(property "Reference" "C5T7"
			(at -1.848866 0.752348 90)
			(unlocked yes)
			(layer "B.SilkS")
			(effects
				(font
					(size 1.27 0.9652)
					(thickness 0.1524)
				)
				(justify mirror)
			)
		)
		(property "Value" ""
			(at 0 0 90)
			(layer "B.Fab")
			(effects
				(font
					(size 1.27 1.27)
				)
				(justify mirror)
			)
		)
		(duplicate_pad_numbers_are_jumpers no)
		(fp_rect
			(start 0.500126 1.598422)
			(end -0.500126 -0.201422)
			(stroke
				(width 0)
				(type default)
			)
			(fill no)
			(layer "B.CrtYd")
		)
		(fp_line
			(start 0.500126 -0.201422)
			(end -0.500126 -0.201422)
			(stroke
				(width 0.1)
				(type default)
			)
			(layer "B.Fab")
		)
		(fp_line
			(start -0.500126 -0.201422)
			(end -0.500126 1.598422)
			(stroke
				(width 0.1)
				(type default)
			)
			(layer "B.Fab")
		)
		(fp_line
			(start 0.500126 1.598422)
			(end 0.500126 -0.201422)
			(stroke
				(width 0.1)
				(type default)
			)
			(layer "B.Fab")
		)
		(fp_line
			(start -0.500126 1.598422)
			(end 0.500126 1.598422)
			(stroke
				(width 0.1)
				(type default)
			)
			(layer "B.Fab")
		)
		(pad "1" smd rect
			(at 0 0)
			(size 0.889 0.9906)
			(layers "B.Cu" "B.Mask" "B.Paste")
			(net "PVDDQ_ABC")
		)
		(pad "2" smd rect
			(at 0 1.397)
			(size 0.889 0.9906)
			(layers "B.Cu" "B.Mask" "B.Paste")
			(net "GND")
		)
		(zone
			(layer "B.Cu")
			(hatch none 0.5)
			(connect_pads
				(clearance 0)
			)
			(min_thickness 0.25)
			(keepout
				(tracks not_allowed)
				(vias allowed)
				(pads allowed)
				(copperpour not_allowed)
				(footprints allowed)
			)
			(placement
				(enabled no)
				(sheetname "")
			)
			(fill
				(thermal_gap 0.5)
				(thermal_bridge_width 0.5)
				(island_removal_mode 0)
			)
			(polygon
				(pts
					(xy 270.512032 -18.2499) (xy 270.004032 -18.2499) (xy 270.004032 -17.2593) (xy 270.512032 -17.2593)
				)
			)
		)
		(zone
			(layer "B.Cu")
			(hatch none 0.5)
			(connect_pads
				(clearance 0)
			)
			(min_thickness 0.25)
			(keepout
				(tracks allowed)
				(vias not_allowed)
				(pads allowed)
				(copperpour not_allowed)
				(footprints allowed)
			)
			(placement
				(enabled no)
				(sheetname "")
			)
			(fill
				(thermal_gap 0.5)
				(thermal_bridge_width 0.5)
				(island_removal_mode 0)
			)
			(polygon
				(pts
					(xy 270.512032 -18.2499) (xy 270.004032 -18.2499) (xy 270.004032 -17.2593) (xy 270.512032 -17.2593)
				)
			)
		)
	)
	(footprint ""
		(layer "B.Cu")
		(at 466.5472 -125.095 -90)
		(property "Reference" "R1W11"
			(at -1.47828 0.78994 0)
			(unlocked yes)
			(layer "B.SilkS")
			(effects
				(font
					(size 0.4064 0.254)
					(thickness 0.1524)
				)
				(justify mirror)
			)
		)
		(property "Value" ""
			(at 0 0 90)
			(layer "B.Fab")
			(effects
				(font
					(size 1.27 1.27)
				)
				(justify mirror)
			)
		)
		(duplicate_pad_numbers_are_jumpers no)
		(fp_poly
			(pts
				(xy 0.7239 -0.2159) (xy -0.7239 -0.2159) (xy -0.7239 1.9939) (xy 0.7239 1.9939)
			)
			(stroke
				(width 0)
				(type default)
			)
			(fill no)
			(layer "B.CrtYd")
		)
		(fp_line
			(start -0.7239 1.9939)
			(end -0.7239 -0.2159)
			(stroke
				(width 0.1)
				(type default)
			)
			(layer "B.Fab")
		)
		(fp_line
			(start 0.7239 1.9939)
			(end -0.7239 1.9939)
			(stroke
				(width 0.1)
				(type default)
			)
			(layer "B.Fab")
		)
		(fp_line
			(start -0.7239 -0.2159)
			(end 0.7239 -0.2159)
			(stroke
				(width 0.1)
				(type default)
			)
			(layer "B.Fab")
		)
		(fp_line
			(start 0.7239 -0.2159)
			(end 0.7239 1.9939)
			(stroke
				(width 0.1)
				(type default)
			)
			(layer "B.Fab")
		)
		(pad "1" smd rect
			(at 0 0 90)
			(size 1.27 1.016)
			(layers "B.Cu" "B.Mask" "B.Paste")
			(net "P5V")
		)
		(pad "2" smd rect
			(at 0 1.778 90)
			(size 1.27 1.016)
			(layers "B.Cu" "B.Mask" "B.Paste")
			(net "P5V_TPS2061")
		)
		(zone
			(layer "B.Cu")
			(hatch none 0.5)
			(connect_pads
				(clearance 0)
			)
			(min_thickness 0.25)
			(keepout
				(tracks not_allowed)
				(vias allowed)
				(pads allowed)
				(copperpour not_allowed)
				(footprints allowed)
			)
			(placement
				(enabled no)
				(sheetname "")
			)
			(fill
				(thermal_gap 0.5)
				(thermal_bridge_width 0.5)
				(island_removal_mode 0)
			)
			(polygon
				(pts
					(xy 466.0392 -125.73) (xy 465.2772 -125.73) (xy 465.2772 -125.6411) (xy 465.2772 -124.46) (xy 466.0392 -124.46)
				)
			)
		)
	)
	(footprint ""
		(layer "B.Cu")
		(at 93.05798 -140.16228 -90)
		(property "Reference" "C5G110"
			(at -1.14681 0.76708 0)
			(unlocked yes)
			(layer "B.SilkS")
			(effects
				(font
					(size 0.7874 0.5842)
					(thickness 0.1524)
				)
				(justify mirror)
			)
		)
		(property "Value" ""
			(at 0 0 90)
			(layer "B.Fab")
			(effects
				(font
					(size 1.27 1.27)
				)
				(justify mirror)
			)
		)
		(duplicate_pad_numbers_are_jumpers no)
		(fp_rect
			(start -0.4953 -0.2032)
			(end 0.4953 1.6002)
			(stroke
				(width 0)
				(type default)
			)
			(fill no)
			(layer "B.CrtYd")
		)
		(fp_line
			(start -0.4953 1.6002)
			(end 0.4953 1.6002)
			(stroke
				(width 0.1)
				(type default)
			)
			(layer "B.Fab")
		)
		(fp_line
			(start 0.4953 1.6002)
			(end 0.4953 -0.2032)
			(stroke
				(width 0.1)
				(type default)
			)
			(layer "B.Fab")
		)
		(fp_line
			(start -0.4953 -0.2032)
			(end -0.4953 1.6002)
			(stroke
				(width 0.1)
				(type default)
			)
			(layer "B.Fab")
		)
		(fp_line
			(start 0.4953 -0.2032)
			(end -0.4953 -0.2032)
			(stroke
				(width 0.1)
				(type default)
			)
			(layer "B.Fab")
		)
		(pad "1" smd rect
			(at 0 0 90)
			(size 0.762 0.889)
			(layers "B.Cu" "B.Mask" "B.Paste")
			(net "PVDDQ_KLM")
		)
		(pad "2" smd rect
			(at 0 1.397 90)
			(size 0.762 0.889)
			(layers "B.Cu" "B.Mask" "B.Paste")
			(net "GND")
		)
		(zone
			(layer "B.Cu")
			(hatch none 0.5)
			(connect_pads
				(clearance 0)
			)
			(min_thickness 0.25)
			(keepout
				(tracks not_allowed)
				(vias allowed)
				(pads allowed)
				(copperpour not_allowed)
				(footprints allowed)
			)
			(placement
				(enabled no)
				(sheetname "")
			)
			(fill
				(thermal_gap 0.5)
				(thermal_bridge_width 0.5)
				(island_removal_mode 0)
			)
			(polygon
				(pts
					(xy 92.61348 -140.54328) (xy 92.10548 -140.54328) (xy 92.10548 -139.78128) (xy 92.61348 -139.78128)
				)
			)
		)
	)
	(footprint ""
		(layer "B.Cu")
		(at 248.8565 -8.1534 -90)
		(property "Reference" "C5U8"
			(at -1.848866 0.752348 270)
			(unlocked yes)
			(layer "B.SilkS")
			(effects
				(font
					(size 1.27 0.9652)
					(thickness 0.1524)
				)
				(justify mirror)
			)
		)
		(property "Value" ""
			(at 0 0 90)
			(layer "B.Fab")
			(effects
				(font
					(size 1.27 1.27)
				)
				(justify mirror)
			)
		)
		(duplicate_pad_numbers_are_jumpers no)
		(fp_rect
			(start 0.500126 1.598422)
			(end -0.500126 -0.201422)
			(stroke
				(width 0)
				(type default)
			)
			(fill no)
			(layer "B.CrtYd")
		)
		(fp_line
			(start -0.500126 1.598422)
			(end 0.500126 1.598422)
			(stroke
				(width 0.1)
				(type default)
			)
			(layer "B.Fab")
		)
		(fp_line
			(start 0.500126 1.598422)
			(end 0.500126 -0.201422)
			(stroke
				(width 0.1)
				(type default)
			)
			(layer "B.Fab")
		)
		(fp_line
			(start -0.500126 -0.201422)
			(end -0.500126 1.598422)
			(stroke
				(width 0.1)
				(type default)
			)
			(layer "B.Fab")
		)
		(fp_line
			(start 0.500126 -0.201422)
			(end -0.500126 -0.201422)
			(stroke
				(width 0.1)
				(type default)
			)
			(layer "B.Fab")
		)
		(pad "1" smd rect
			(at 0 0 180)
			(size 0.889 0.9906)
			(layers "B.Cu" "B.Mask" "B.Paste")
			(net "PVDDQ_ABC")
		)
		(pad "2" smd rect
			(at 0 1.397 180)
			(size 0.889 0.9906)
			(layers "B.Cu" "B.Mask" "B.Paste")
			(net "GND")
		)
		(zone
			(layer "B.Cu")
			(hatch none 0.5)
			(connect_pads
				(clearance 0)
			)
			(min_thickness 0.25)
			(keepout
				(tracks allowed)
				(vias not_allowed)
				(pads allowed)
				(copperpour not_allowed)
				(footprints allowed)
			)
			(placement
				(enabled no)
				(sheetname "")
			)
			(fill
				(thermal_gap 0.5)
				(thermal_bridge_width 0.5)
				(island_removal_mode 0)
			)
			(polygon
				(pts
					(xy 247.904 -7.6581) (xy 248.412 -7.6581) (xy 248.412 -8.6487) (xy 247.904 -8.6487)
				)
			)
		)
		(zone
			(layer "B.Cu")
			(hatch none 0.5)
			(connect_pads
				(clearance 0)
			)
			(min_thickness 0.25)
			(keepout
				(tracks not_allowed)
				(vias allowed)
				(pads allowed)
				(copperpour not_allowed)
				(footprints allowed)
			)
			(placement
				(enabled no)
				(sheetname "")
			)
			(fill
				(thermal_gap 0.5)
				(thermal_bridge_width 0.5)
				(island_removal_mode 0)
			)
			(polygon
				(pts
					(xy 247.904 -7.6581) (xy 248.412 -7.6581) (xy 248.412 -8.6487) (xy 247.904 -8.6487)
				)
			)
		)
	)
	(footprint ""
		(layer "B.Cu")
		(at 359.84688 -77.923136 180)
		(property "Reference" "C3P39"
			(at 0 0 0)
			(layer "B.SilkS")
			(hide yes)
			(effects
				(font
					(size 1.27 1.27)
				)
				(justify mirror)
			)
		)
		(property "Value" ""
			(at 0 0 0)
			(layer "B.Fab")
			(effects
				(font
					(size 1.27 1.27)
				)
				(justify mirror)
			)
		)
		(duplicate_pad_numbers_are_jumpers no)
		(fp_poly
			(pts
				(xy -0.3048 -0.1016) (xy -0.3048 0.9906) (xy 0.3048 0.9906) (xy 0.3048 -0.1016)
			)
			(stroke
				(width 0)
				(type default)
			)
			(fill no)
			(layer "B.CrtYd")
		)
		(fp_line
			(start 0.3048 0.9906)
			(end -0.3048 0.9906)
			(stroke
				(width 0.1)
				(type default)
			)
			(layer "B.Fab")
		)
		(fp_line
			(start 0.3048 -0.1016)
			(end 0.3048 0.9906)
			(stroke
				(width 0.1)
				(type default)
			)
			(layer "B.Fab")
		)
		(fp_line
			(start -0.3048 0.9906)
			(end -0.3048 -0.1016)
			(stroke
				(width 0.1)
				(type default)
			)
			(layer "B.Fab")
		)
		(fp_line
			(start -0.3048 -0.1016)
			(end 0.3048 -0.1016)
			(stroke
				(width 0.1)
				(type default)
			)
			(layer "B.Fab")
		)
		(pad "1" smd rect
			(at 0 0)
			(size 0.508 0.508)
			(layers "B.Cu" "B.Mask" "B.Paste")
			(net "P3E_CPU0_PE1_SS_TXP<7>")
		)
		(pad "2" smd rect
			(at 0 0.889)
			(size 0.508 0.508)
			(layers "B.Cu" "B.Mask" "B.Paste")
			(net "P3E_CPU0_PE1_PCH_TXP<7>")
		)
		(zone
			(layer "B.Cu")
			(hatch none 0.5)
			(connect_pads
				(clearance 0)
			)
			(min_thickness 0.25)
			(keepout
				(tracks not_allowed)
				(vias allowed)
				(pads allowed)
				(copperpour not_allowed)
				(footprints allowed)
			)
			(placement
				(enabled no)
				(sheetname "")
			)
			(fill
				(thermal_gap 0.5)
				(thermal_bridge_width 0.5)
				(island_removal_mode 0)
			)
			(polygon
				(pts
					(xy 359.59288 -78.558136) (xy 360.10088 -78.558136) (xy 360.10088 -78.177136) (xy 359.59288 -78.177136)
				)
			)
		)
		(zone
			(layer "B.Cu")
			(hatch none 0.5)
			(connect_pads
				(clearance 0)
			)
			(min_thickness 0.25)
			(keepout
				(tracks allowed)
				(vias not_allowed)
				(pads allowed)
				(copperpour not_allowed)
				(footprints allowed)
			)
			(placement
				(enabled no)
				(sheetname "")
			)
			(fill
				(thermal_gap 0.5)
				(thermal_bridge_width 0.5)
				(island_removal_mode 0)
			)
			(polygon
				(pts
					(xy 359.59288 -78.177136) (xy 360.10088 -78.177136) (xy 360.10088 -78.558136) (xy 359.59288 -78.558136)
				)
			)
		)
	)
	(footprint ""
		(layer "B.Cu")
		(at 426.72 -142.0876)
		(property "Reference" "C2L40"
			(at 0 0 0)
			(layer "B.SilkS")
			(hide yes)
			(effects
				(font
					(size 1.27 1.27)
				)
				(justify mirror)
			)
		)
		(property "Value" ""
			(at 0 0 0)
			(layer "B.Fab")
			(effects
				(font
					(size 1.27 1.27)
				)
				(justify mirror)
			)
		)
		(duplicate_pad_numbers_are_jumpers no)
		(fp_poly
			(pts
				(xy -0.3048 -0.1016) (xy -0.3048 0.9906) (xy 0.3048 0.9906) (xy 0.3048 -0.1016)
			)
			(stroke
				(width 0)
				(type default)
			)
			(fill no)
			(layer "B.CrtYd")
		)
		(fp_line
			(start -0.3048 -0.1016)
			(end 0.3048 -0.1016)
			(stroke
				(width 0.1)
				(type default)
			)
			(layer "B.Fab")
		)
		(fp_line
			(start -0.3048 0.9906)
			(end -0.3048 -0.1016)
			(stroke
				(width 0.1)
				(type default)
			)
			(layer "B.Fab")
		)
		(fp_line
			(start 0.3048 -0.1016)
			(end 0.3048 0.9906)
			(stroke
				(width 0.1)
				(type default)
			)
			(layer "B.Fab")
		)
		(fp_line
			(start 0.3048 0.9906)
			(end -0.3048 0.9906)
			(stroke
				(width 0.1)
				(type default)
			)
			(layer "B.Fab")
		)
		(pad "1" smd rect
			(at 0 0 180)
			(size 0.508 0.508)
			(layers "B.Cu" "B.Mask" "B.Paste")
			(net "SATA6G_P0_TX_C_DN")
		)
		(pad "2" smd rect
			(at 0 0.889 180)
			(size 0.508 0.508)
			(layers "B.Cu" "B.Mask" "B.Paste")
			(net "SATA6G_PCH_PCIE_UP_SATA_TXN<0>")
		)
		(zone
			(layer "B.Cu")
			(hatch none 0.5)
			(connect_pads
				(clearance 0)
			)
			(min_thickness 0.25)
			(keepout
				(tracks allowed)
				(vias not_allowed)
				(pads allowed)
				(copperpour not_allowed)
				(footprints allowed)
			)
			(placement
				(enabled no)
				(sheetname "")
			)
			(fill
				(thermal_gap 0.5)
				(thermal_bridge_width 0.5)
				(island_removal_mode 0)
			)
			(polygon
				(pts
					(xy 426.974 -141.8336) (xy 426.466 -141.8336) (xy 426.466 -141.4526) (xy 426.974 -141.4526)
				)
			)
		)
		(zone
			(layer "B.Cu")
			(hatch none 0.5)
			(connect_pads
				(clearance 0)
			)
			(min_thickness 0.25)
			(keepout
				(tracks not_allowed)
				(vias allowed)
				(pads allowed)
				(copperpour not_allowed)
				(footprints allowed)
			)
			(placement
				(enabled no)
				(sheetname "")
			)
			(fill
				(thermal_gap 0.5)
				(thermal_bridge_width 0.5)
				(island_removal_mode 0)
			)
			(polygon
				(pts
					(xy 426.974 -141.4526) (xy 426.466 -141.4526) (xy 426.466 -141.8336) (xy 426.974 -141.8336)
				)
			)
		)
	)
	(footprint ""
		(layer "B.Cu")
		(at 348.615 -144.565624 -90)
		(property "Reference" "C3L17"
			(at 0 0 90)
			(layer "B.SilkS")
			(hide yes)
			(effects
				(font
					(size 1.27 1.27)
				)
				(justify mirror)
			)
		)
		(property "Value" ""
			(at 0 0 90)
			(layer "B.Fab")
			(effects
				(font
					(size 1.27 1.27)
				)
				(justify mirror)
			)
		)
		(duplicate_pad_numbers_are_jumpers no)
		(fp_poly
			(pts
				(xy 0.7239 -0.2159) (xy -0.7239 -0.2159) (xy -0.7239 1.9939) (xy 0.7239 1.9939)
			)
			(stroke
				(width 0)
				(type default)
			)
			(fill no)
			(layer "B.CrtYd")
		)
		(fp_line
			(start -0.7239 1.9939)
			(end -0.7239 -0.2159)
			(stroke
				(width 0.1)
				(type default)
			)
			(layer "B.Fab")
		)
		(fp_line
			(start 0.7239 1.9939)
			(end -0.7239 1.9939)
			(stroke
				(width 0.1)
				(type default)
			)
			(layer "B.Fab")
		)
		(fp_line
			(start -0.7239 -0.2159)
			(end 0.7239 -0.2159)
			(stroke
				(width 0.1)
				(type default)
			)
			(layer "B.Fab")
		)
		(fp_line
			(start 0.7239 -0.2159)
			(end 0.7239 1.9939)
			(stroke
				(width 0.1)
				(type default)
			)
			(layer "B.Fab")
		)
		(pad "1" smd rect
			(at 0 0 90)
			(size 1.27 1.016)
			(layers "B.Cu" "B.Mask" "B.Paste")
			(net "VR_FET_SW_P12V_STBY_PVDDQ_DEF")
		)
		(pad "2" smd rect
			(at 0 1.778 90)
			(size 1.27 1.016)
			(layers "B.Cu" "B.Mask" "B.Paste")
			(net "GND")
		)
		(zone
			(layer "B.Cu")
			(hatch none 0.5)
			(connect_pads
				(clearance 0)
			)
			(min_thickness 0.25)
			(keepout
				(tracks not_allowed)
				(vias allowed)
				(pads allowed)
				(copperpour not_allowed)
				(footprints allowed)
			)
			(placement
				(enabled no)
				(sheetname "")
			)
			(fill
				(thermal_gap 0.5)
				(thermal_bridge_width 0.5)
				(island_removal_mode 0)
			)
			(polygon
				(pts
					(xy 348.107 -143.930624) (xy 348.107 -145.200624) (xy 347.345 -145.200624) (xy 347.345 -143.930624)
				)
			)
		)
	)
	(footprint ""
		(layer "B.Cu")
		(at 434.365654 -141.002512 180)
		(property "Reference" "C2L50"
			(at 0 0 0)
			(layer "B.SilkS")
			(hide yes)
			(effects
				(font
					(size 1.27 1.27)
				)
				(justify mirror)
			)
		)
		(property "Value" ""
			(at 0 0 0)
			(layer "B.Fab")
			(effects
				(font
					(size 1.27 1.27)
				)
				(justify mirror)
			)
		)
		(duplicate_pad_numbers_are_jumpers no)
		(fp_poly
			(pts
				(xy -0.3048 -0.1016) (xy -0.3048 0.9906) (xy 0.3048 0.9906) (xy 0.3048 -0.1016)
			)
			(stroke
				(width 0)
				(type default)
			)
			(fill no)
			(layer "B.CrtYd")
		)
		(fp_line
			(start 0.3048 0.9906)
			(end -0.3048 0.9906)
			(stroke
				(width 0.1)
				(type default)
			)
			(layer "B.Fab")
		)
		(fp_line
			(start 0.3048 -0.1016)
			(end 0.3048 0.9906)
			(stroke
				(width 0.1)
				(type default)
			)
			(layer "B.Fab")
		)
		(fp_line
			(start -0.3048 0.9906)
			(end -0.3048 -0.1016)
			(stroke
				(width 0.1)
				(type default)
			)
			(layer "B.Fab")
		)
		(fp_line
			(start -0.3048 -0.1016)
			(end 0.3048 -0.1016)
			(stroke
				(width 0.1)
				(type default)
			)
			(layer "B.Fab")
		)
		(pad "1" smd rect
			(at 0 0)
			(size 0.508 0.508)
			(layers "B.Cu" "B.Mask" "B.Paste")
			(net "SATA6G_S1_RX_C_DN")
		)
		(pad "2" smd rect
			(at 0 0.889)
			(size 0.508 0.508)
			(layers "B.Cu" "B.Mask" "B.Paste")
			(net "SATA6G_S1_RX_DN")
		)
		(zone
			(layer "B.Cu")
			(hatch none 0.5)
			(connect_pads
				(clearance 0)
			)
			(min_thickness 0.25)
			(keepout
				(tracks not_allowed)
				(vias allowed)
				(pads allowed)
				(copperpour not_allowed)
				(footprints allowed)
			)
			(placement
				(enabled no)
				(sheetname "")
			)
			(fill
				(thermal_gap 0.5)
				(thermal_bridge_width 0.5)
				(island_removal_mode 0)
			)
			(polygon
				(pts
					(xy 434.111654 -141.637512) (xy 434.619654 -141.637512) (xy 434.619654 -141.256512) (xy 434.111654 -141.256512)
				)
			)
		)
		(zone
			(layer "B.Cu")
			(hatch none 0.5)
			(connect_pads
				(clearance 0)
			)
			(min_thickness 0.25)
			(keepout
				(tracks allowed)
				(vias not_allowed)
				(pads allowed)
				(copperpour not_allowed)
				(footprints allowed)
			)
			(placement
				(enabled no)
				(sheetname "")
			)
			(fill
				(thermal_gap 0.5)
				(thermal_bridge_width 0.5)
				(island_removal_mode 0)
			)
			(polygon
				(pts
					(xy 434.111654 -141.256512) (xy 434.619654 -141.256512) (xy 434.619654 -141.637512) (xy 434.111654 -141.637512)
				)
			)
		)
	)
	(footprint ""
		(layer "B.Cu")
		(at 361.782614 -124.440442 -90)
		(property "Reference" "R780"
			(at 0.8382 -0.67818 270)
			(unlocked yes)
			(layer "B.SilkS")
			(effects
				(font
					(size 0.4064 0.254)
					(thickness 0.1524)
				)
				(justify left mirror)
			)
		)
		(property "Value" ""
			(at 0 0 90)
			(layer "B.Fab")
			(effects
				(font
					(size 1.27 1.27)
				)
				(justify mirror)
			)
		)
		(duplicate_pad_numbers_are_jumpers no)
		(fp_poly
			(pts
				(xy 0.2794 -0.1016) (xy -0.2794 -0.1016) (xy -0.2794 0.9906) (xy 0.2794 0.9906)
			)
			(stroke
				(width 0)
				(type default)
			)
			(fill no)
			(layer "B.CrtYd")
		)
		(fp_line
			(start -0.2794 0.9906)
			(end -0.2794 -0.1016)
			(stroke
				(width 0.1)
				(type default)
			)
			(layer "B.Fab")
		)
		(fp_line
			(start 0.2794 0.9906)
			(end -0.2794 0.9906)
			(stroke
				(width 0.1)
				(type default)
			)
			(layer "B.Fab")
		)
		(fp_line
			(start -0.2794 -0.1016)
			(end 0.2794 -0.1016)
			(stroke
				(width 0.1)
				(type default)
			)
			(layer "B.Fab")
		)
		(fp_line
			(start 0.2794 -0.1016)
			(end 0.2794 0.9906)
			(stroke
				(width 0.1)
				(type default)
			)
			(layer "B.Fab")
		)
		(pad "1" smd rect
			(at 0 0 90)
			(size 0.508 0.508)
			(layers "B.Cu" "B.Mask" "B.Paste")
			(net "P3E_CPU0_PE1_PCH_RXN<10>")
		)
		(pad "2" smd rect
			(at 0 0.889 90)
			(size 0.508 0.508)
			(layers "B.Cu" "B.Mask" "B.Paste")
			(net "P3E_CPU0_PE1_PCH_CON_RXN<10>")
		)
		(zone
			(layer "B.Cu")
			(hatch none 0.5)
			(connect_pads
				(clearance 0)
			)
			(min_thickness 0.25)
			(keepout
				(tracks not_allowed)
				(vias allowed)
				(pads allowed)
				(copperpour not_allowed)
				(footprints allowed)
			)
			(placement
				(enabled no)
				(sheetname "")
			)
			(fill
				(thermal_gap 0.5)
				(thermal_bridge_width 0.5)
				(island_removal_mode 0)
			)
			(polygon
				(pts
					(xy 361.147614 -124.186442) (xy 361.147614 -124.694442) (xy 361.528614 -124.694442) (xy 361.528614 -124.186442)
				)
			)
		)
		(zone
			(layer "B.Cu")
			(hatch none 0.5)
			(connect_pads
				(clearance 0)
			)
			(min_thickness 0.25)
			(keepout
				(tracks allowed)
				(vias not_allowed)
				(pads allowed)
				(copperpour not_allowed)
				(footprints allowed)
			)
			(placement
				(enabled no)
				(sheetname "")
			)
			(fill
				(thermal_gap 0.5)
				(thermal_bridge_width 0.5)
				(island_removal_mode 0)
			)
			(polygon
				(pts
					(xy 361.528614 -124.186442) (xy 361.528614 -124.694442) (xy 361.147614 -124.694442) (xy 361.147614 -124.186442)
				)
			)
		)
	)
	(footprint ""
		(layer "B.Cu")
		(at 350.9772 -86.741 90)
		(property "Reference" "R3P16"
			(at 0 0 90)
			(layer "B.SilkS")
			(hide yes)
			(effects
				(font
					(size 1.27 1.27)
				)
				(justify mirror)
			)
		)
		(property "Value" ""
			(at 0 0 90)
			(layer "B.Fab")
			(effects
				(font
					(size 1.27 1.27)
				)
				(justify mirror)
			)
		)
		(duplicate_pad_numbers_are_jumpers no)
		(fp_poly
			(pts
				(xy 0.2794 -0.1016) (xy -0.2794 -0.1016) (xy -0.2794 0.9906) (xy 0.2794 0.9906)
			)
			(stroke
				(width 0)
				(type default)
			)
			(fill no)
			(layer "B.CrtYd")
		)
		(fp_line
			(start 0.2794 -0.1016)
			(end 0.2794 0.9906)
			(stroke
				(width 0.1)
				(type default)
			)
			(layer "B.Fab")
		)
		(fp_line
			(start -0.2794 -0.1016)
			(end 0.2794 -0.1016)
			(stroke
				(width 0.1)
				(type default)
			)
			(layer "B.Fab")
		)
		(fp_line
			(start 0.2794 0.9906)
			(end -0.2794 0.9906)
			(stroke
				(width 0.1)
				(type default)
			)
			(layer "B.Fab")
		)
		(fp_line
			(start -0.2794 0.9906)
			(end -0.2794 -0.1016)
			(stroke
				(width 0.1)
				(type default)
			)
			(layer "B.Fab")
		)
		(pad "1" smd rect
			(at 0 0 270)
			(size 0.508 0.508)
			(layers "B.Cu" "B.Mask" "B.Paste")
			(net "VR_PVCCIO_CPU0_VINSEN")
		)
		(pad "2" smd rect
			(at 0 0.889 270)
			(size 0.508 0.508)
			(layers "B.Cu" "B.Mask" "B.Paste")
			(net "GND")
		)
		(zone
			(layer "B.Cu")
			(hatch none 0.5)
			(connect_pads
				(clearance 0)
			)
			(min_thickness 0.25)
			(keepout
				(tracks allowed)
				(vias not_allowed)
				(pads allowed)
				(copperpour not_allowed)
				(footprints allowed)
			)
			(placement
				(enabled no)
				(sheetname "")
			)
			(fill
				(thermal_gap 0.5)
				(thermal_bridge_width 0.5)
				(island_removal_mode 0)
			)
			(polygon
				(pts
					(xy 351.2312 -86.995) (xy 351.2312 -86.487) (xy 351.6122 -86.487) (xy 351.6122 -86.995)
				)
			)
		)
		(zone
			(layer "B.Cu")
			(hatch none 0.5)
			(connect_pads
				(clearance 0)
			)
			(min_thickness 0.25)
			(keepout
				(tracks not_allowed)
				(vias allowed)
				(pads allowed)
				(copperpour not_allowed)
				(footprints allowed)
			)
			(placement
				(enabled no)
				(sheetname "")
			)
			(fill
				(thermal_gap 0.5)
				(thermal_bridge_width 0.5)
				(island_removal_mode 0)
			)
			(polygon
				(pts
					(xy 351.6122 -86.995) (xy 351.6122 -86.487) (xy 351.2312 -86.487) (xy 351.2312 -86.995)
				)
			)
		)
	)
	(footprint ""
		(layer "B.Cu")
		(at 265.698732 -135.4074 90)
		(property "Reference" "C5M3"
			(at 0 0 90)
			(layer "B.SilkS")
			(hide yes)
			(effects
				(font
					(size 1.27 1.27)
				)
				(justify mirror)
			)
		)
		(property "Value" ""
			(at 0 0 90)
			(layer "B.Fab")
			(effects
				(font
					(size 1.27 1.27)
				)
				(justify mirror)
			)
		)
		(duplicate_pad_numbers_are_jumpers no)
		(fp_rect
			(start 0.500126 1.598422)
			(end -0.500126 -0.201422)
			(stroke
				(width 0)
				(type default)
			)
			(fill no)
			(layer "B.CrtYd")
		)
		(fp_line
			(start 0.500126 -0.201422)
			(end -0.500126 -0.201422)
			(stroke
				(width 0.1)
				(type default)
			)
			(layer "B.Fab")
		)
		(fp_line
			(start -0.500126 -0.201422)
			(end -0.500126 1.598422)
			(stroke
				(width 0.1)
				(type default)
			)
			(layer "B.Fab")
		)
		(fp_line
			(start 0.500126 1.598422)
			(end 0.500126 -0.201422)
			(stroke
				(width 0.1)
				(type default)
			)
			(layer "B.Fab")
		)
		(fp_line
			(start -0.500126 1.598422)
			(end 0.500126 1.598422)
			(stroke
				(width 0.1)
				(type default)
			)
			(layer "B.Fab")
		)
		(pad "1" smd rect
			(at 0 0)
			(size 0.889 0.9906)
			(layers "B.Cu" "B.Mask" "B.Paste")
			(net "PVDDQ_DEF")
		)
		(pad "2" smd rect
			(at 0 1.397)
			(size 0.889 0.9906)
			(layers "B.Cu" "B.Mask" "B.Paste")
			(net "GND")
		)
		(zone
			(layer "B.Cu")
			(hatch none 0.5)
			(connect_pads
				(clearance 0)
			)
			(min_thickness 0.25)
			(keepout
				(tracks not_allowed)
				(vias allowed)
				(pads allowed)
				(copperpour not_allowed)
				(footprints allowed)
			)
			(placement
				(enabled no)
				(sheetname "")
			)
			(fill
				(thermal_gap 0.5)
				(thermal_bridge_width 0.5)
				(island_removal_mode 0)
			)
			(polygon
				(pts
					(xy 266.651232 -135.9027) (xy 266.143232 -135.9027) (xy 266.143232 -134.9121) (xy 266.651232 -134.9121)
				)
			)
		)
		(zone
			(layer "B.Cu")
			(hatch none 0.5)
			(connect_pads
				(clearance 0)
			)
			(min_thickness 0.25)
			(keepout
				(tracks allowed)
				(vias not_allowed)
				(pads allowed)
				(copperpour not_allowed)
				(footprints allowed)
			)
			(placement
				(enabled no)
				(sheetname "")
			)
			(fill
				(thermal_gap 0.5)
				(thermal_bridge_width 0.5)
				(island_removal_mode 0)
			)
			(polygon
				(pts
					(xy 266.651232 -135.9027) (xy 266.143232 -135.9027) (xy 266.143232 -134.9121) (xy 266.651232 -134.9121)
				)
			)
		)
	)
	(footprint ""
		(layer "B.Cu")
		(at 318.543432 -145.034 -90)
		(property "Reference" "C4L4"
			(at 0 0 90)
			(layer "B.SilkS")
			(hide yes)
			(effects
				(font
					(size 1.27 1.27)
				)
				(justify mirror)
			)
		)
		(property "Value" ""
			(at 0 0 90)
			(layer "B.Fab")
			(effects
				(font
					(size 1.27 1.27)
				)
				(justify mirror)
			)
		)
		(duplicate_pad_numbers_are_jumpers no)
		(fp_poly
			(pts
				(xy 0.4953 -0.2032) (xy -0.4953 -0.2032) (xy -0.4953 1.6002) (xy 0.4953 1.6002)
			)
			(stroke
				(width 0)
				(type default)
			)
			(fill no)
			(layer "B.CrtYd")
		)
		(fp_line
			(start -0.4953 1.6002)
			(end 0.4953 1.6002)
			(stroke
				(width 0.1)
				(type default)
			)
			(layer "B.Fab")
		)
		(fp_line
			(start 0.4953 1.6002)
			(end 0.4953 -0.2032)
			(stroke
				(width 0.1)
				(type default)
			)
			(layer "B.Fab")
		)
		(fp_line
			(start -0.4953 -0.2032)
			(end -0.4953 1.6002)
			(stroke
				(width 0.1)
				(type default)
			)
			(layer "B.Fab")
		)
		(fp_line
			(start 0.4953 -0.2032)
			(end -0.4953 -0.2032)
			(stroke
				(width 0.1)
				(type default)
			)
			(layer "B.Fab")
		)
		(pad "1" smd rect
			(at 0 0 90)
			(size 0.762 0.889)
			(layers "B.Cu" "B.Mask" "B.Paste")
			(net "PVPP_DEF")
		)
		(pad "2" smd rect
			(at 0 1.397 90)
			(size 0.762 0.889)
			(layers "B.Cu" "B.Mask" "B.Paste")
			(net "GND")
		)
		(zone
			(layer "B.Cu")
			(hatch none 0.5)
			(connect_pads
				(clearance 0)
			)
			(min_thickness 0.25)
			(keepout
				(tracks not_allowed)
				(vias allowed)
				(pads allowed)
				(copperpour not_allowed)
				(footprints allowed)
			)
			(placement
				(enabled no)
				(sheetname "")
			)
			(fill
				(thermal_gap 0.5)
				(thermal_bridge_width 0.5)
				(island_removal_mode 0)
			)
			(polygon
				(pts
					(xy 318.098932 -144.653) (xy 318.098932 -145.415) (xy 317.590932 -145.415) (xy 317.590932 -144.653)
				)
			)
		)
	)
	(footprint ""
		(layer "B.Cu")
		(at 393.1412 -156.083 90)
		(property "Reference" "R2L8"
			(at 0 0 90)
			(layer "B.SilkS")
			(hide yes)
			(effects
				(font
					(size 1.27 1.27)
				)
				(justify mirror)
			)
		)
		(property "Value" ""
			(at 0 0 90)
			(layer "B.Fab")
			(effects
				(font
					(size 1.27 1.27)
				)
				(justify mirror)
			)
		)
		(duplicate_pad_numbers_are_jumpers no)
		(fp_poly
			(pts
				(xy 0.4953 -0.2032) (xy -0.4953 -0.2032) (xy -0.4953 1.6002) (xy 0.4953 1.6002)
			)
			(stroke
				(width 0)
				(type default)
			)
			(fill no)
			(layer "B.CrtYd")
		)
		(fp_line
			(start 0.4953 -0.2032)
			(end -0.4953 -0.2032)
			(stroke
				(width 0.1)
				(type default)
			)
			(layer "B.Fab")
		)
		(fp_line
			(start -0.4953 -0.2032)
			(end -0.4953 1.6002)
			(stroke
				(width 0.1)
				(type default)
			)
			(layer "B.Fab")
		)
		(fp_line
			(start 0.4953 1.6002)
			(end 0.4953 -0.2032)
			(stroke
				(width 0.1)
				(type default)
			)
			(layer "B.Fab")
		)
		(fp_line
			(start -0.4953 1.6002)
			(end 0.4953 1.6002)
			(stroke
				(width 0.1)
				(type default)
			)
			(layer "B.Fab")
		)
		(pad "1" smd rect
			(at 0 0 270)
			(size 0.762 0.889)
			(layers "B.Cu" "B.Mask" "B.Paste")
			(net "VSENSE_P1V05_PCH_STBY_AVSP")
		)
		(pad "2" smd rect
			(at 0 1.397 270)
			(size 0.762 0.889)
			(layers "B.Cu" "B.Mask" "B.Paste")
			(net "VR_P1V05_PCH_STBY_AVSP")
		)
		(zone
			(layer "B.Cu")
			(hatch none 0.5)
			(connect_pads
				(clearance 0)
			)
			(min_thickness 0.25)
			(keepout
				(tracks not_allowed)
				(vias allowed)
				(pads allowed)
				(copperpour not_allowed)
				(footprints allowed)
			)
			(placement
				(enabled no)
				(sheetname "")
			)
			(fill
				(thermal_gap 0.5)
				(thermal_bridge_width 0.5)
				(island_removal_mode 0)
			)
			(polygon
				(pts
					(xy 394.0937 -156.464) (xy 393.5857 -156.464) (xy 393.5857 -155.702) (xy 394.0937 -155.702)
				)
			)
		)
		(zone
			(layer "B.Cu")
			(hatch none 0.5)
			(connect_pads
				(clearance 0)
			)
			(min_thickness 0.25)
			(keepout
				(tracks allowed)
				(vias not_allowed)
				(pads allowed)
				(copperpour not_allowed)
				(footprints allowed)
			)
			(placement
				(enabled no)
				(sheetname "")
			)
			(fill
				(thermal_gap 0.5)
				(thermal_bridge_width 0.5)
				(island_removal_mode 0)
			)
			(polygon
				(pts
					(xy 394.0937 -155.702) (xy 393.5857 -155.702) (xy 393.5857 -156.464) (xy 394.0937 -156.464)
				)
			)
		)
	)
	(footprint ""
		(layer "B.Cu")
		(at 13.35024 -165.01618 -90)
		(property "Reference" "T1D12"
			(at 0 0 90)
			(layer "B.SilkS")
			(hide yes)
			(effects
				(font
					(size 1.27 1.27)
				)
				(justify mirror)
			)
		)
		(property "Value" "*"
			(at 3.4036 -4.46405 270)
			(unlocked yes)
			(layer "B.Fab")
			(hide yes)
			(effects
				(font
					(size 0.889 0.889)
					(thickness 0.1524)
				)
				(justify mirror)
			)
		)
		(property "Device Type" "TEST-PAD-12P-1-GP-U_DISCRET-GBA"
			(at 3.4036 -5.98805 270)
			(unlocked yes)
			(layer "B.Fab")
			(hide yes)
			(effects
				(font
					(size 0.889 0.889)
					(thickness 0.1524)
				)
				(justify mirror)
			)
		)
		(duplicate_pad_numbers_are_jumpers no)
		(fp_line
			(start -2.3622 3.4798)
			(end 2.3876 3.4798)
			(stroke
				(width 0.1524)
				(type default)
			)
			(layer "B.SilkS")
		)
		(fp_line
			(start 2.3876 3.4798)
			(end 2.3876 -4.826)
			(stroke
				(width 0.1524)
				(type default)
			)
			(layer "B.SilkS")
		)
		(fp_line
			(start -2.3622 -4.826)
			(end -2.3622 3.4798)
			(stroke
				(width 0.1524)
				(type default)
			)
			(layer "B.SilkS")
		)
		(fp_line
			(start 2.3876 -4.826)
			(end -2.3622 -4.826)
			(stroke
				(width 0.1524)
				(type default)
			)
			(layer "B.SilkS")
		)
		(fp_rect
			(start 2.6416 3.7338)
			(end -2.6162 -5.08)
			(stroke
				(width 0)
				(type default)
			)
			(fill no)
			(layer "B.CrtYd")
		)
		(fp_rect
			(start 2.6416 3.7338)
			(end -2.6162 -5.08)
			(stroke
				(width 0)
				(type default)
			)
			(fill no)
			(layer "B.Fab")
		)
		(pad "1" smd circle
			(at -0.496824 -1.301496 90)
			(size 0.6604 0.6604)
			(layers "B.Cu" "B.Mask" "B.Paste")
			(net "L14_85OHM_5INCH_DN")
		)
		(pad "2" smd circle
			(at 0.503936 -1.301496 90)
			(size 0.6604 0.6604)
			(layers "B.Cu" "B.Mask" "B.Paste")
			(net "L14_85OHM_5INCH_DP")
		)
		(pad "3" smd custom
			(at 0.00889 0.370078 90)
			(size 0.74295 0.74295)
			(layers "B.Cu" "B.Mask" "B.Paste")
			(net "GND")
			(options
				(clearance outline)
				(anchor circle)
			)
			(primitives
				(gr_poly
					(pts
						(xy -2.1209 -1.4859) (xy 2.1209 -1.4859) (xy 2.1209 1.4859) (xy 1.08585 1.4859) (xy 1.08585 0.4699)
						(xy -1.08585 0.4699) (xy -1.08585 1.4859) (xy -2.1209 1.4859)
					)
					(width 0)
					(fill yes)
				)
			)
		)
		(pad "4" thru_hole circle
			(at -1.266444 -3.851656 90)
			(size 1.4478 1.4478)
			(drill 1.0414)
			(layers "*.Cu" "*.Mask")
			(remove_unused_layers no)
			(net "GND")
			(clearance 0.1524)
			(thermal_gap 0.1524)
		)
		(pad "5" thru_hole circle
			(at 1.273556 -3.851656 90)
			(size 1.4478 1.4478)
			(drill 1.0414)
			(layers "*.Cu" "*.Mask")
			(remove_unused_layers no)
			(net "GND")
			(clearance 0.1524)
			(thermal_gap 0.1524)
		)
		(pad "6" thru_hole circle
			(at -1.266444 2.498344 90)
			(size 1.4478 1.4478)
			(drill 1.0414)
			(layers "*.Cu" "*.Mask")
			(remove_unused_layers no)
			(net "GND")
			(clearance 0.1524)
			(thermal_gap 0.1524)
		)
		(pad "7" thru_hole circle
			(at 1.273556 2.498344 90)
			(size 1.4478 1.4478)
			(drill 1.0414)
			(layers "*.Cu" "*.Mask")
			(remove_unused_layers no)
			(net "GND")
			(clearance 0.1524)
			(thermal_gap 0.1524)
		)
		(pad "8" thru_hole circle
			(at -1.27 -0.4572 90)
			(size 0.7112 0.7112)
			(drill 0.4064)
			(layers "*.Cu" "*.Mask")
			(remove_unused_layers no)
			(net "GND")
			(clearance 0.1016)
			(thermal_gap 0.1016)
		)
		(pad "9" thru_hole circle
			(at -1.27 0.762 90)
			(size 0.7112 0.7112)
			(drill 0.4064)
			(layers "*.Cu" "*.Mask")
			(remove_unused_layers no)
			(net "GND")
			(clearance 0.1016)
			(thermal_gap 0.1016)
		)
		(pad "10" thru_hole circle
			(at 0.0254 0.762 90)
			(size 0.7112 0.7112)
			(drill 0.4064)
			(layers "*.Cu" "*.Mask")
			(remove_unused_layers no)
			(net "GND")
			(clearance 0.1016)
			(thermal_gap 0.1016)
		)
		(pad "11" thru_hole circle
			(at 1.27 0.762 90)
			(size 0.7112 0.7112)
			(drill 0.4064)
			(layers "*.Cu" "*.Mask")
			(remove_unused_layers no)
			(net "GND")
			(clearance 0.1016)
			(thermal_gap 0.1016)
		)
		(pad "12" thru_hole circle
			(at 1.27 -0.4572 90)
			(size 0.7112 0.7112)
			(drill 0.4064)
			(layers "*.Cu" "*.Mask")
			(remove_unused_layers no)
			(net "GND")
			(clearance 0.1016)
			(thermal_gap 0.1016)
		)
	)
	(footprint ""
		(layer "B.Cu")
		(at 389.255 -66.167 90)
		(property "Reference" "R2T6"
			(at 0 0 90)
			(layer "B.SilkS")
			(hide yes)
			(effects
				(font
					(size 1.27 1.27)
				)
				(justify mirror)
			)
		)
		(property "Value" ""
			(at 0 0 90)
			(layer "B.Fab")
			(effects
				(font
					(size 1.27 1.27)
				)
				(justify mirror)
			)
		)
		(duplicate_pad_numbers_are_jumpers no)
		(fp_poly
			(pts
				(xy 0.2794 -0.1016) (xy -0.2794 -0.1016) (xy -0.2794 0.9906) (xy 0.2794 0.9906)
			)
			(stroke
				(width 0)
				(type default)
			)
			(fill no)
			(layer "B.CrtYd")
		)
		(fp_line
			(start 0.2794 -0.1016)
			(end 0.2794 0.9906)
			(stroke
				(width 0.1)
				(type default)
			)
			(layer "B.Fab")
		)
		(fp_line
			(start -0.2794 -0.1016)
			(end 0.2794 -0.1016)
			(stroke
				(width 0.1)
				(type default)
			)
			(layer "B.Fab")
		)
		(fp_line
			(start 0.2794 0.9906)
			(end -0.2794 0.9906)
			(stroke
				(width 0.1)
				(type default)
			)
			(layer "B.Fab")
		)
		(fp_line
			(start -0.2794 0.9906)
			(end -0.2794 -0.1016)
			(stroke
				(width 0.1)
				(type default)
			)
			(layer "B.Fab")
		)
		(pad "1" smd rect
			(at 0 0 270)
			(size 0.508 0.508)
			(layers "B.Cu" "B.Mask" "B.Paste")
			(net "P3V3_STBY")
		)
		(pad "2" smd rect
			(at 0 0.889 270)
			(size 0.508 0.508)
			(layers "B.Cu" "B.Mask" "B.Paste")
			(net "FM_BACKUP_BIOS_SEL_N")
		)
		(zone
			(layer "B.Cu")
			(hatch none 0.5)
			(connect_pads
				(clearance 0)
			)
			(min_thickness 0.25)
			(keepout
				(tracks allowed)
				(vias not_allowed)
				(pads allowed)
				(copperpour not_allowed)
				(footprints allowed)
			)
			(placement
				(enabled no)
				(sheetname "")
			)
			(fill
				(thermal_gap 0.5)
				(thermal_bridge_width 0.5)
				(island_removal_mode 0)
			)
			(polygon
				(pts
					(xy 389.509 -66.421) (xy 389.509 -65.913) (xy 389.89 -65.913) (xy 389.89 -66.421)
				)
			)
		)
		(zone
			(layer "B.Cu")
			(hatch none 0.5)
			(connect_pads
				(clearance 0)
			)
			(min_thickness 0.25)
			(keepout
				(tracks not_allowed)
				(vias allowed)
				(pads allowed)
				(copperpour not_allowed)
				(footprints allowed)
			)
			(placement
				(enabled no)
				(sheetname "")
			)
			(fill
				(thermal_gap 0.5)
				(thermal_bridge_width 0.5)
				(island_removal_mode 0)
			)
			(polygon
				(pts
					(xy 389.89 -66.421) (xy 389.89 -65.913) (xy 389.509 -65.913) (xy 389.509 -66.421)
				)
			)
		)
	)
	(footprint ""
		(layer "B.Cu")
		(at 346.5322 -87.4522 -90)
		(property "Reference" "EU3P1"
			(at -1.80975 3.2893 0)
			(unlocked yes)
			(layer "B.SilkS")
			(effects
				(font
					(size 0.7874 0.5842)
					(thickness 0.1524)
				)
				(justify left mirror)
			)
		)
		(property "Value" ""
			(at 0 0 90)
			(layer "B.Fab")
			(effects
				(font
					(size 1.27 1.27)
				)
				(justify mirror)
			)
		)
		(duplicate_pad_numbers_are_jumpers no)
		(fp_line
			(start -3.0607 3.0607)
			(end 3.0607 3.0607)
			(stroke
				(width 0.1524)
				(type default)
			)
			(layer "B.SilkS")
		)
		(fp_line
			(start 3.0607 3.0607)
			(end 3.0607 -3.0607)
			(stroke
				(width 0.1524)
				(type default)
			)
			(layer "B.SilkS")
		)
		(fp_line
			(start -2.549906 2.549906)
			(end -2.249678 2.549906)
			(stroke
				(width 0.1524)
				(type default)
			)
			(layer "B.SilkS")
		)
		(fp_line
			(start 2.277618 2.549906)
			(end 2.549906 2.549906)
			(stroke
				(width 0.1524)
				(type default)
			)
			(layer "B.SilkS")
		)
		(fp_line
			(start 2.549906 2.549906)
			(end 2.549906 2.267204)
			(stroke
				(width 0.1524)
				(type default)
			)
			(layer "B.SilkS")
		)
		(fp_line
			(start -2.549906 2.233422)
			(end -2.549906 2.549906)
			(stroke
				(width 0.1524)
				(type default)
			)
			(layer "B.SilkS")
		)
		(fp_line
			(start 2.549906 -2.29362)
			(end 2.549906 -2.549906)
			(stroke
				(width 0.1524)
				(type default)
			)
			(layer "B.SilkS")
		)
		(fp_line
			(start -2.549906 -2.549906)
			(end -2.549906 -2.258314)
			(stroke
				(width 0.1524)
				(type default)
			)
			(layer "B.SilkS")
		)
		(fp_line
			(start -2.245614 -2.549906)
			(end -2.549906 -2.549906)
			(stroke
				(width 0.1524)
				(type default)
			)
			(layer "B.SilkS")
		)
		(fp_line
			(start 2.549906 -2.549906)
			(end 2.249678 -2.549906)
			(stroke
				(width 0.1524)
				(type default)
			)
			(layer "B.SilkS")
		)
		(fp_line
			(start -3.0607 -3.0607)
			(end -3.0607 3.0607)
			(stroke
				(width 0.1524)
				(type default)
			)
			(layer "B.SilkS")
		)
		(fp_line
			(start 3.0607 -3.0607)
			(end -3.0607 -3.0607)
			(stroke
				(width 0.1524)
				(type default)
			)
			(layer "B.SilkS")
		)
		(fp_circle
			(center 3.237738 -2.256536)
			(end 3.237738 -2.383536)
			(stroke
				(width 0.254)
				(type default)
			)
			(fill no)
			(layer "B.SilkS")
		)
		(fp_poly
			(pts
				(xy 3.0607 -3.0607) (xy 3.0607 -2.0193) (xy 2.0193 -3.0607)
			)
			(stroke
				(width 0)
				(type default)
			)
			(fill yes)
			(layer "B.SilkS")
		)
		(fp_rect
			(start 1.8415 1.8415)
			(end -1.8415 -1.8415)
			(stroke
				(width 0)
				(type default)
			)
			(fill yes)
			(layer "B.Paste")
		)
		(fp_rect
			(start 2.549906 2.549906)
			(end -2.549906 -2.549906)
			(stroke
				(width 0)
				(type default)
			)
			(fill no)
			(layer "B.CrtYd")
		)
		(fp_line
			(start -2.549906 2.549906)
			(end 2.549906 2.549906)
			(stroke
				(width 0.1)
				(type default)
			)
			(layer "B.Fab")
		)
		(fp_line
			(start 2.549906 2.549906)
			(end 2.549906 -2.549906)
			(stroke
				(width 0.1)
				(type default)
			)
			(layer "B.Fab")
		)
		(fp_line
			(start -2.549906 -2.549906)
			(end -2.549906 2.549906)
			(stroke
				(width 0.1)
				(type default)
			)
			(layer "B.Fab")
		)
		(fp_line
			(start 2.549906 -2.549906)
			(end -2.549906 -2.549906)
			(stroke
				(width 0.1)
				(type default)
			)
			(layer "B.Fab")
		)
		(fp_circle
			(center 3.237738 -2.256536)
			(end 3.237738 -2.383536)
			(stroke
				(width 0.254)
				(type default)
			)
			(fill no)
			(layer "B.Fab")
		)
		(pad "1" smd custom
			(at 2.4511 -1.800098 90)
			(size 0.0508 0.0508)
			(layers "B.Cu" "B.Mask" "B.Paste")
			(net "Net_331")
			(options
				(clearance outline)
				(anchor circle)
			)
			(primitives
				(gr_poly
					(pts
						(arc
							(start 0.254 0.1016)
							(mid 0.3556 0)
							(end 0.254 -0.1016)
						)
						(xy -0.3556 -0.1016) (xy -0.3556 0.1016)
					)
					(width 0)
					(fill yes)
				)
			)
		)
		(pad "2" smd custom
			(at 2.4511 -1.400048 90)
			(size 0.0508 0.0508)
			(layers "B.Cu" "B.Mask" "B.Paste")
			(net "Net_332")
			(options
				(clearance outline)
				(anchor circle)
			)
			(primitives
				(gr_poly
					(pts
						(arc
							(start 0.254 0.1016)
							(mid 0.3556 0)
							(end 0.254 -0.1016)
						)
						(xy -0.3556 -0.1016) (xy -0.3556 0.1016)
					)
					(width 0)
					(fill yes)
				)
			)
		)
		(pad "3" smd custom
			(at 2.4511 -0.999998 90)
			(size 0.0508 0.0508)
			(layers "B.Cu" "B.Mask" "B.Paste")
			(net "Net_269")
			(options
				(clearance outline)
				(anchor circle)
			)
			(primitives
				(gr_poly
					(pts
						(arc
							(start 0.254 0.1016)
							(mid 0.3556 0)
							(end 0.254 -0.1016)
						)
						(xy -0.3556 -0.1016) (xy -0.3556 0.1016)
					)
					(width 0)
					(fill yes)
				)
			)
		)
		(pad "4" smd custom
			(at 2.4511 -0.599948 90)
			(size 0.0508 0.0508)
			(layers "B.Cu" "B.Mask" "B.Paste")
			(net "Net_333")
			(options
				(clearance outline)
				(anchor circle)
			)
			(primitives
				(gr_poly
					(pts
						(arc
							(start 0.254 0.1016)
							(mid 0.3556 0)
							(end 0.254 -0.1016)
						)
						(xy -0.3556 -0.1016) (xy -0.3556 0.1016)
					)
					(width 0)
					(fill yes)
				)
			)
		)
		(pad "5" smd custom
			(at 2.4511 -0.199898 90)
			(size 0.0508 0.0508)
			(layers "B.Cu" "B.Mask" "B.Paste")
			(net "VR_PVCCIO_CPU0_PWM1")
			(options
				(clearance outline)
				(anchor circle)
			)
			(primitives
				(gr_poly
					(pts
						(arc
							(start 0.254 0.1016)
							(mid 0.3556 0)
							(end 0.254 -0.1016)
						)
						(xy -0.3556 -0.1016) (xy -0.3556 0.1016)
					)
					(width 0)
					(fill yes)
				)
			)
		)
		(pad "6" smd custom
			(at 2.4511 0.199898 90)
			(size 0.0508 0.0508)
			(layers "B.Cu" "B.Mask" "B.Paste")
			(net "SMB_VR_STBY_LVC3_SDA")
			(options
				(clearance outline)
				(anchor circle)
			)
			(primitives
				(gr_poly
					(pts
						(arc
							(start 0.254 0.1016)
							(mid 0.3556 0)
							(end 0.254 -0.1016)
						)
						(xy -0.3556 -0.1016) (xy -0.3556 0.1016)
					)
					(width 0)
					(fill yes)
				)
			)
		)
		(pad "7" smd custom
			(at 2.4511 0.599948 90)
			(size 0.0508 0.0508)
			(layers "B.Cu" "B.Mask" "B.Paste")
			(net "SMB_VR_STBY_LVC3_SCL")
			(options
				(clearance outline)
				(anchor circle)
			)
			(primitives
				(gr_poly
					(pts
						(arc
							(start 0.254 0.1016)
							(mid 0.3556 0)
							(end 0.254 -0.1016)
						)
						(xy -0.3556 -0.1016) (xy -0.3556 0.1016)
					)
					(width 0)
					(fill yes)
				)
			)
		)
		(pad "8" smd custom
			(at 2.4511 0.999998 90)
			(size 0.0508 0.0508)
			(layers "B.Cu" "B.Mask" "B.Paste")
			(net "Net_270")
			(options
				(clearance outline)
				(anchor circle)
			)
			(primitives
				(gr_poly
					(pts
						(arc
							(start 0.254 0.1016)
							(mid 0.3556 0)
							(end 0.254 -0.1016)
						)
						(xy -0.3556 -0.1016) (xy -0.3556 0.1016)
					)
					(width 0)
					(fill yes)
				)
			)
		)
		(pad "9" smd custom
			(at 2.4511 1.400048 90)
			(size 0.0508 0.0508)
			(layers "B.Cu" "B.Mask" "B.Paste")
			(net "PWRGD_PVCCIO_CPU0_R")
			(options
				(clearance outline)
				(anchor circle)
			)
			(primitives
				(gr_poly
					(pts
						(arc
							(start 0.254 0.1016)
							(mid 0.3556 0)
							(end 0.254 -0.1016)
						)
						(xy -0.3556 -0.1016) (xy -0.3556 0.1016)
					)
					(width 0)
					(fill yes)
				)
			)
		)
		(pad "10" smd custom
			(at 2.4511 1.800098 90)
			(size 0.0508 0.0508)
			(layers "B.Cu" "B.Mask" "B.Paste")
			(net "VR_PVCCIO_CPU0_EN")
			(options
				(clearance outline)
				(anchor circle)
			)
			(primitives
				(gr_poly
					(pts
						(arc
							(start 0.254 0.1016)
							(mid 0.3556 0)
							(end 0.254 -0.1016)
						)
						(xy -0.3556 -0.1016) (xy -0.3556 0.1016)
					)
					(width 0)
					(fill yes)
				)
			)
		)
		(pad "11" smd custom
			(at 1.800098 2.4511 90)
			(size 0.0508 0.0508)
			(layers "B.Cu" "B.Mask" "B.Paste")
			(net "IRQ_PVCCIO_CPU0_VRHOT_N")
			(options
				(clearance outline)
				(anchor circle)
			)
			(primitives
				(gr_poly
					(pts
						(arc
							(start -0.1016 0.254)
							(mid 0 0.3556)
							(end 0.1016 0.254)
						)
						(xy 0.1016 -0.3556) (xy -0.1016 -0.3556)
					)
					(width 0)
					(fill yes)
				)
			)
		)
		(pad "12" smd custom
			(at 1.400048 2.4511 90)
			(size 0.0508 0.0508)
			(layers "B.Cu" "B.Mask" "B.Paste")
			(net "Net_257")
			(options
				(clearance outline)
				(anchor circle)
			)
			(primitives
				(gr_poly
					(pts
						(arc
							(start -0.1016 0.254)
							(mid 0 0.3556)
							(end 0.1016 0.254)
						)
						(xy 0.1016 -0.3556) (xy -0.1016 -0.3556)
					)
					(width 0)
					(fill yes)
				)
			)
		)
		(pad "13" smd custom
			(at 0.999998 2.4511 90)
			(size 0.0508 0.0508)
			(layers "B.Cu" "B.Mask" "B.Paste")
			(net "Net_255")
			(options
				(clearance outline)
				(anchor circle)
			)
			(primitives
				(gr_poly
					(pts
						(arc
							(start -0.1016 0.254)
							(mid 0 0.3556)
							(end 0.1016 0.254)
						)
						(xy 0.1016 -0.3556) (xy -0.1016 -0.3556)
					)
					(width 0)
					(fill yes)
				)
			)
		)
		(pad "14" smd custom
			(at 0.599948 2.4511 90)
			(size 0.0508 0.0508)
			(layers "B.Cu" "B.Mask" "B.Paste")
			(net "Net_256")
			(options
				(clearance outline)
				(anchor circle)
			)
			(primitives
				(gr_poly
					(pts
						(arc
							(start -0.1016 0.254)
							(mid 0 0.3556)
							(end 0.1016 0.254)
						)
						(xy 0.1016 -0.3556) (xy -0.1016 -0.3556)
					)
					(width 0)
					(fill yes)
				)
			)
		)
		(pad "15" smd custom
			(at 0.199898 2.4511 90)
			(size 0.0508 0.0508)
			(layers "B.Cu" "B.Mask" "B.Paste")
			(net "SVID_CLK_PVCCIO_CPU0")
			(options
				(clearance outline)
				(anchor circle)
			)
			(primitives
				(gr_poly
					(pts
						(arc
							(start -0.1016 0.254)
							(mid 0 0.3556)
							(end 0.1016 0.254)
						)
						(xy 0.1016 -0.3556) (xy -0.1016 -0.3556)
					)
					(width 0)
					(fill yes)
				)
			)
		)
		(pad "16" smd custom
			(at -0.199898 2.4511 90)
			(size 0.0508 0.0508)
			(layers "B.Cu" "B.Mask" "B.Paste")
			(net "SVID_VDIO_PVCCIO_CPU0")
			(options
				(clearance outline)
				(anchor circle)
			)
			(primitives
				(gr_poly
					(pts
						(arc
							(start -0.1016 0.254)
							(mid 0 0.3556)
							(end 0.1016 0.254)
						)
						(xy 0.1016 -0.3556) (xy -0.1016 -0.3556)
					)
					(width 0)
					(fill yes)
				)
			)
		)
		(pad "17" smd custom
			(at -0.599948 2.4511 90)
			(size 0.0508 0.0508)
			(layers "B.Cu" "B.Mask" "B.Paste")
			(net "SVID_ALERT_PVCCIO_CPU0")
			(options
				(clearance outline)
				(anchor circle)
			)
			(primitives
				(gr_poly
					(pts
						(arc
							(start -0.1016 0.254)
							(mid 0 0.3556)
							(end 0.1016 0.254)
						)
						(xy 0.1016 -0.3556) (xy -0.1016 -0.3556)
					)
					(width 0)
					(fill yes)
				)
			)
		)
		(pad "18" smd custom
			(at -0.999998 2.4511 90)
			(size 0.0508 0.0508)
			(layers "B.Cu" "B.Mask" "B.Paste")
			(net "Net_300")
			(options
				(clearance outline)
				(anchor circle)
			)
			(primitives
				(gr_poly
					(pts
						(arc
							(start -0.1016 0.254)
							(mid 0 0.3556)
							(end 0.1016 0.254)
						)
						(xy 0.1016 -0.3556) (xy -0.1016 -0.3556)
					)
					(width 0)
					(fill yes)
				)
			)
		)
		(pad "19" smd custom
			(at -1.400048 2.4511 90)
			(size 0.0508 0.0508)
			(layers "B.Cu" "B.Mask" "B.Paste")
			(net "VR_PVCCIO_CPU0_AVSP")
			(options
				(clearance outline)
				(anchor circle)
			)
			(primitives
				(gr_poly
					(pts
						(arc
							(start -0.1016 0.254)
							(mid 0 0.3556)
							(end 0.1016 0.254)
						)
						(xy 0.1016 -0.3556) (xy -0.1016 -0.3556)
					)
					(width 0)
					(fill yes)
				)
			)
		)
		(pad "20" smd custom
			(at -1.800098 2.4511 90)
			(size 0.0508 0.0508)
			(layers "B.Cu" "B.Mask" "B.Paste")
			(net "VSENSE_PVCCIO_CPU0_AVSN")
			(options
				(clearance outline)
				(anchor circle)
			)
			(primitives
				(gr_poly
					(pts
						(arc
							(start -0.1016 0.254)
							(mid 0 0.3556)
							(end 0.1016 0.254)
						)
						(xy 0.1016 -0.3556) (xy -0.1016 -0.3556)
					)
					(width 0)
					(fill yes)
				)
			)
		)
		(pad "21" smd custom
			(at -2.4511 1.800098 90)
			(size 0.0508 0.0508)
			(layers "B.Cu" "B.Mask" "B.Paste")
			(net "VR_PVCCIO_CPU0_AIREF1")
			(options
				(clearance outline)
				(anchor circle)
			)
			(primitives
				(gr_poly
					(pts
						(arc
							(start -0.254 -0.1016)
							(mid -0.3556 0)
							(end -0.254 0.1016)
						)
						(xy 0.3556 0.1016) (xy 0.3556 -0.1016)
					)
					(width 0)
					(fill yes)
				)
			)
		)
		(pad "22" smd custom
			(at -2.4511 1.400048 90)
			(size 0.0508 0.0508)
			(layers "B.Cu" "B.Mask" "B.Paste")
			(net "ISENSE_PVCCIO_CPU0_PH1_IMON")
			(options
				(clearance outline)
				(anchor circle)
			)
			(primitives
				(gr_poly
					(pts
						(arc
							(start -0.254 -0.1016)
							(mid -0.3556 0)
							(end -0.254 0.1016)
						)
						(xy 0.3556 0.1016) (xy 0.3556 -0.1016)
					)
					(width 0)
					(fill yes)
				)
			)
		)
		(pad "23" smd custom
			(at -2.4511 0.999998 90)
			(size 0.0508 0.0508)
			(layers "B.Cu" "B.Mask" "B.Paste")
			(net "GND")
			(options
				(clearance outline)
				(anchor circle)
			)
			(primitives
				(gr_poly
					(pts
						(arc
							(start -0.254 -0.1016)
							(mid -0.3556 0)
							(end -0.254 0.1016)
						)
						(xy 0.3556 0.1016) (xy 0.3556 -0.1016)
					)
					(width 0)
					(fill yes)
				)
			)
		)
		(pad "24" smd custom
			(at -2.4511 0.599948 90)
			(size 0.0508 0.0508)
			(layers "B.Cu" "B.Mask" "B.Paste")
			(net "Net_334")
			(options
				(clearance outline)
				(anchor circle)
			)
			(primitives
				(gr_poly
					(pts
						(arc
							(start -0.254 -0.1016)
							(mid -0.3556 0)
							(end -0.254 0.1016)
						)
						(xy 0.3556 0.1016) (xy 0.3556 -0.1016)
					)
					(width 0)
					(fill yes)
				)
			)
		)
		(pad "25" smd custom
			(at -2.4511 0.199898 90)
			(size 0.0508 0.0508)
			(layers "B.Cu" "B.Mask" "B.Paste")
			(net "Net_251")
			(options
				(clearance outline)
				(anchor circle)
			)
			(primitives
				(gr_poly
					(pts
						(arc
							(start -0.254 -0.1016)
							(mid -0.3556 0)
							(end -0.254 0.1016)
						)
						(xy 0.3556 0.1016) (xy 0.3556 -0.1016)
					)
					(width 0)
					(fill yes)
				)
			)
		)
		(pad "26" smd custom
			(at -2.4511 -0.199898 90)
			(size 0.0508 0.0508)
			(layers "B.Cu" "B.Mask" "B.Paste")
			(net "GND")
			(options
				(clearance outline)
				(anchor circle)
			)
			(primitives
				(gr_poly
					(pts
						(arc
							(start -0.254 -0.1016)
							(mid -0.3556 0)
							(end -0.254 0.1016)
						)
						(xy 0.3556 0.1016) (xy 0.3556 -0.1016)
					)
					(width 0)
					(fill yes)
				)
			)
		)
		(pad "27" smd custom
			(at -2.4511 -0.599948 90)
			(size 0.0508 0.0508)
			(layers "B.Cu" "B.Mask" "B.Paste")
			(net "GND")
			(options
				(clearance outline)
				(anchor circle)
			)
			(primitives
				(gr_poly
					(pts
						(arc
							(start -0.254 -0.1016)
							(mid -0.3556 0)
							(end -0.254 0.1016)
						)
						(xy 0.3556 0.1016) (xy 0.3556 -0.1016)
					)
					(width 0)
					(fill yes)
				)
			)
		)
		(pad "28" smd custom
			(at -2.4511 -0.999998 90)
			(size 0.0508 0.0508)
			(layers "B.Cu" "B.Mask" "B.Paste")
			(net "Net_335")
			(options
				(clearance outline)
				(anchor circle)
			)
			(primitives
				(gr_poly
					(pts
						(arc
							(start -0.254 -0.1016)
							(mid -0.3556 0)
							(end -0.254 0.1016)
						)
						(xy 0.3556 0.1016) (xy 0.3556 -0.1016)
					)
					(width 0)
					(fill yes)
				)
			)
		)
		(pad "29" smd custom
			(at -2.4511 -1.400048 90)
			(size 0.0508 0.0508)
			(layers "B.Cu" "B.Mask" "B.Paste")
			(net "Net_254")
			(options
				(clearance outline)
				(anchor circle)
			)
			(primitives
				(gr_poly
					(pts
						(arc
							(start -0.254 -0.1016)
							(mid -0.3556 0)
							(end -0.254 0.1016)
						)
						(xy 0.3556 0.1016) (xy 0.3556 -0.1016)
					)
					(width 0)
					(fill yes)
				)
			)
		)
		(pad "30" smd custom
			(at -2.4511 -1.800098 90)
			(size 0.0508 0.0508)
			(layers "B.Cu" "B.Mask" "B.Paste")
			(net "Net_253")
			(options
				(clearance outline)
				(anchor circle)
			)
			(primitives
				(gr_poly
					(pts
						(arc
							(start -0.254 -0.1016)
							(mid -0.3556 0)
							(end -0.254 0.1016)
						)
						(xy 0.3556 0.1016) (xy 0.3556 -0.1016)
					)
					(width 0)
					(fill yes)
				)
			)
		)
		(pad "31" smd custom
			(at -1.800098 -2.4511 90)
			(size 0.0508 0.0508)
			(layers "B.Cu" "B.Mask" "B.Paste")
			(net "Net_301")
			(options
				(clearance outline)
				(anchor circle)
			)
			(primitives
				(gr_poly
					(pts
						(arc
							(start 0.1016 -0.254)
							(mid 0 -0.3556)
							(end -0.1016 -0.254)
						)
						(xy -0.1016 0.3556) (xy 0.1016 0.3556)
					)
					(width 0)
					(fill yes)
				)
			)
		)
		(pad "32" smd custom
			(at -1.400048 -2.4511 90)
			(size 0.0508 0.0508)
			(layers "B.Cu" "B.Mask" "B.Paste")
			(net "PU_VR_PVCCIO_CPU0_FAULT1")
			(options
				(clearance outline)
				(anchor circle)
			)
			(primitives
				(gr_poly
					(pts
						(arc
							(start 0.1016 -0.254)
							(mid 0 -0.3556)
							(end -0.1016 -0.254)
						)
						(xy -0.1016 0.3556) (xy 0.1016 0.3556)
					)
					(width 0)
					(fill yes)
				)
			)
		)
		(pad "33" smd custom
			(at -0.999998 -2.4511 90)
			(size 0.0508 0.0508)
			(layers "B.Cu" "B.Mask" "B.Paste")
			(net "VR_PVCCIO_CPU0_XADDR2")
			(options
				(clearance outline)
				(anchor circle)
			)
			(primitives
				(gr_poly
					(pts
						(arc
							(start 0.1016 -0.254)
							(mid 0 -0.3556)
							(end -0.1016 -0.254)
						)
						(xy -0.1016 0.3556) (xy 0.1016 0.3556)
					)
					(width 0)
					(fill yes)
				)
			)
		)
		(pad "34" smd custom
			(at -0.599948 -2.4511 90)
			(size 0.0508 0.0508)
			(layers "B.Cu" "B.Mask" "B.Paste")
			(net "Net_252")
			(options
				(clearance outline)
				(anchor circle)
			)
			(primitives
				(gr_poly
					(pts
						(arc
							(start 0.1016 -0.254)
							(mid 0 -0.3556)
							(end -0.1016 -0.254)
						)
						(xy -0.1016 0.3556) (xy 0.1016 0.3556)
					)
					(width 0)
					(fill yes)
				)
			)
		)
		(pad "35" smd custom
			(at -0.199898 -2.4511 90)
			(size 0.0508 0.0508)
			(layers "B.Cu" "B.Mask" "B.Paste")
			(net "A_TSENSE_PVCCIO_CPU0")
			(options
				(clearance outline)
				(anchor circle)
			)
			(primitives
				(gr_poly
					(pts
						(arc
							(start 0.1016 -0.254)
							(mid 0 -0.3556)
							(end -0.1016 -0.254)
						)
						(xy -0.1016 0.3556) (xy 0.1016 0.3556)
					)
					(width 0)
					(fill yes)
				)
			)
		)
		(pad "36" smd custom
			(at 0.199898 -2.4511 90)
			(size 0.0508 0.0508)
			(layers "B.Cu" "B.Mask" "B.Paste")
			(net "VR_PVCCIO_CPU0_XADDR1")
			(options
				(clearance outline)
				(anchor circle)
			)
			(primitives
				(gr_poly
					(pts
						(arc
							(start 0.1016 -0.254)
							(mid 0 -0.3556)
							(end -0.1016 -0.254)
						)
						(xy -0.1016 0.3556) (xy 0.1016 0.3556)
					)
					(width 0)
					(fill yes)
				)
			)
		)
		(pad "37" smd custom
			(at 0.599948 -2.4511 90)
			(size 0.0508 0.0508)
			(layers "B.Cu" "B.Mask" "B.Paste")
			(net "VR_PVCCIO_CPU0_VINSEN")
			(options
				(clearance outline)
				(anchor circle)
			)
			(primitives
				(gr_poly
					(pts
						(arc
							(start 0.1016 -0.254)
							(mid 0 -0.3556)
							(end -0.1016 -0.254)
						)
						(xy -0.1016 0.3556) (xy 0.1016 0.3556)
					)
					(width 0)
					(fill yes)
				)
			)
		)
		(pad "38" smd custom
			(at 0.999998 -2.4511 90)
			(size 0.0508 0.0508)
			(layers "B.Cu" "B.Mask" "B.Paste")
			(net "Net_265")
			(options
				(clearance outline)
				(anchor circle)
			)
			(primitives
				(gr_poly
					(pts
						(arc
							(start 0.1016 -0.254)
							(mid 0 -0.3556)
							(end -0.1016 -0.254)
						)
						(xy -0.1016 0.3556) (xy 0.1016 0.3556)
					)
					(width 0)
					(fill yes)
				)
			)
		)
		(pad "39" smd custom
			(at 1.400048 -2.4511 90)
			(size 0.0508 0.0508)
			(layers "B.Cu" "B.Mask" "B.Paste")
			(net "VR_PVCCIO_CPU0_VDD")
			(options
				(clearance outline)
				(anchor circle)
			)
			(primitives
				(gr_poly
					(pts
						(arc
							(start 0.1016 -0.254)
							(mid 0 -0.3556)
							(end -0.1016 -0.254)
						)
						(xy -0.1016 0.3556) (xy 0.1016 0.3556)
					)
					(width 0)
					(fill yes)
				)
			)
		)
		(pad "40" smd custom
			(at 1.800098 -2.4511 90)
			(size 0.0508 0.0508)
			(layers "B.Cu" "B.Mask" "B.Paste")
			(net "VR_PVCCIO_CPU0_VD12")
			(options
				(clearance outline)
				(anchor circle)
			)
			(primitives
				(gr_poly
					(pts
						(arc
							(start 0.1016 -0.254)
							(mid 0 -0.3556)
							(end -0.1016 -0.254)
						)
						(xy -0.1016 0.3556) (xy 0.1016 0.3556)
					)
					(width 0)
					(fill yes)
				)
			)
		)
		(pad "41" smd rect
			(at 0 0 90)
			(size 3.683 3.683)
			(layers "B.Cu" "B.Mask" "B.Paste")
			(net "GND")
		)
		(zone
			(layer "B.Cu")
			(hatch none 0.5)
			(connect_pads
				(clearance 0)
			)
			(min_thickness 0.25)
			(keepout
				(tracks not_allowed)
				(vias allowed)
				(pads allowed)
				(copperpour not_allowed)
				(footprints allowed)
			)
			(placement
				(enabled no)
				(sheetname "")
			)
			(fill
				(thermal_gap 0.5)
				(thermal_bridge_width 0.5)
				(island_removal_mode 0)
			)
			(polygon
				(pts
					(xy 344.4367 -85.3567) (xy 344.89771 -85.3567) (xy 344.89771 -85.6107) (xy 344.6907 -85.6107) (xy 344.6907 -89.2937)
					(xy 348.3737 -89.2937) (xy 348.3737 -85.6107) (xy 344.899742 -85.6107) (xy 344.899742 -85.3567)
					(xy 348.6277 -85.3567) (xy 348.6277 -89.5477) (xy 344.4367 -89.5477)
				)
			)
		)
		(zone
			(layer "B.Cu")
			(hatch none 0.5)
			(connect_pads
				(clearance 0)
			)
			(min_thickness 0.25)
			(keepout
				(tracks allowed)
				(vias not_allowed)
				(pads allowed)
				(copperpour not_allowed)
				(footprints allowed)
			)
			(placement
				(enabled no)
				(sheetname "")
			)
			(fill
				(thermal_gap 0.5)
				(thermal_bridge_width 0.5)
				(island_removal_mode 0)
			)
			(polygon
				(pts
					(xy 344.4367 -85.3567) (xy 344.89771 -85.3567) (xy 344.89771 -85.6107) (xy 344.6907 -85.6107) (xy 344.6907 -89.2937)
					(xy 348.3737 -89.2937) (xy 348.3737 -85.6107) (xy 344.899742 -85.6107) (xy 344.899742 -85.3567)
					(xy 348.6277 -85.3567) (xy 348.6277 -89.5477) (xy 344.4367 -89.5477)
				)
			)
		)
	)
	(footprint ""
		(layer "B.Cu")
		(at 485.734868 -121.774712 180)
		(property "Reference" "C9B9"
			(at 0 0 0)
			(layer "B.SilkS")
			(hide yes)
			(effects
				(font
					(size 1.27 1.27)
				)
				(justify mirror)
			)
		)
		(property "Value" "*"
			(at -1.1811 -2.8194 180)
			(unlocked yes)
			(layer "B.Fab")
			(hide yes)
			(effects
				(font
					(size 1.27 1.016)
					(thickness 0.1524)
				)
				(justify mirror)
			)
		)
		(property "Device Type" "SC1U10V2KX-4-GP_SMD-BCG6-SC1U1A"
			(at -1.1811 -4.3434 180)
			(unlocked yes)
			(layer "B.Fab")
			(hide yes)
			(effects
				(font
					(size 1.27 1.016)
					(thickness 0.1524)
				)
				(justify mirror)
			)
		)
		(duplicate_pad_numbers_are_jumpers no)
		(fp_rect
			(start 0.4318 0.9525)
			(end -0.4318 -0.9525)
			(stroke
				(width 0)
				(type default)
			)
			(fill no)
			(layer "B.CrtYd")
		)
		(fp_rect
			(start 0.4318 0.9525)
			(end -0.4318 -0.9525)
			(stroke
				(width 0)
				(type default)
			)
			(fill no)
			(layer "B.Fab")
		)
		(pad "1" smd custom
			(at 0 -0.4445)
			(size 0.1524 0.1524)
			(layers "B.Cu" "B.Mask" "B.Paste")
			(net "P5V_STBY")
			(options
				(clearance outline)
				(anchor circle)
			)
			(primitives
				(gr_poly
					(pts
						(arc
							(start 0.3048 0.2032)
							(mid 0.275042 0.275042)
							(end 0.2032 0.3048)
						)
						(arc
							(start -0.2032 0.3048)
							(mid -0.275042 0.275042)
							(end -0.3048 0.2032)
						)
						(arc
							(start -0.3048 -0.2032)
							(mid -0.275042 -0.275042)
							(end -0.2032 -0.3048)
						)
						(arc
							(start 0.2032 -0.3048)
							(mid 0.275042 -0.275042)
							(end 0.3048 -0.2032)
						)
					)
					(width 0)
					(fill yes)
				)
			)
		)
		(pad "2" smd custom
			(at 0 0.4445)
			(size 0.1524 0.1524)
			(layers "B.Cu" "B.Mask" "B.Paste")
			(net "GND")
			(options
				(clearance outline)
				(anchor circle)
			)
			(primitives
				(gr_poly
					(pts
						(arc
							(start 0.3048 0.2032)
							(mid 0.275042 0.275042)
							(end 0.2032 0.3048)
						)
						(arc
							(start -0.2032 0.3048)
							(mid -0.275042 0.275042)
							(end -0.3048 0.2032)
						)
						(arc
							(start -0.3048 -0.2032)
							(mid -0.275042 -0.275042)
							(end -0.2032 -0.3048)
						)
						(arc
							(start 0.2032 -0.3048)
							(mid 0.275042 -0.275042)
							(end 0.3048 -0.2032)
						)
					)
					(width 0)
					(fill yes)
				)
			)
		)
	)
	(footprint ""
		(layer "B.Cu")
		(at 378.587 -82.677 -90)
		(property "Reference" "C7W1"
			(at 0.8382 -0.67818 270)
			(unlocked yes)
			(layer "B.SilkS")
			(effects
				(font
					(size 0.4064 0.254)
					(thickness 0.1524)
				)
				(justify left mirror)
			)
		)
		(property "Value" ""
			(at 0 0 90)
			(layer "B.Fab")
			(effects
				(font
					(size 1.27 1.27)
				)
				(justify mirror)
			)
		)
		(duplicate_pad_numbers_are_jumpers no)
		(fp_poly
			(pts
				(xy -0.3048 -0.1016) (xy -0.3048 0.9906) (xy 0.3048 0.9906) (xy 0.3048 -0.1016)
			)
			(stroke
				(width 0)
				(type default)
			)
			(fill no)
			(layer "B.CrtYd")
		)
		(fp_line
			(start -0.3048 0.9906)
			(end -0.3048 -0.1016)
			(stroke
				(width 0.1)
				(type default)
			)
			(layer "B.Fab")
		)
		(fp_line
			(start 0.3048 0.9906)
			(end -0.3048 0.9906)
			(stroke
				(width 0.1)
				(type default)
			)
			(layer "B.Fab")
		)
		(fp_line
			(start -0.3048 -0.1016)
			(end 0.3048 -0.1016)
			(stroke
				(width 0.1)
				(type default)
			)
			(layer "B.Fab")
		)
		(fp_line
			(start 0.3048 -0.1016)
			(end 0.3048 0.9906)
			(stroke
				(width 0.1)
				(type default)
			)
			(layer "B.Fab")
		)
		(pad "1" smd rect
			(at 0 0 90)
			(size 0.508 0.508)
			(layers "B.Cu" "B.Mask" "B.Paste")
			(net "P3V3_STBY")
		)
		(pad "2" smd rect
			(at 0 0.889 90)
			(size 0.508 0.508)
			(layers "B.Cu" "B.Mask" "B.Paste")
			(net "GND")
		)
		(zone
			(layer "B.Cu")
			(hatch none 0.5)
			(connect_pads
				(clearance 0)
			)
			(min_thickness 0.25)
			(keepout
				(tracks not_allowed)
				(vias allowed)
				(pads allowed)
				(copperpour not_allowed)
				(footprints allowed)
			)
			(placement
				(enabled no)
				(sheetname "")
			)
			(fill
				(thermal_gap 0.5)
				(thermal_bridge_width 0.5)
				(island_removal_mode 0)
			)
			(polygon
				(pts
					(xy 377.952 -82.423) (xy 377.952 -82.931) (xy 378.333 -82.931) (xy 378.333 -82.423)
				)
			)
		)
		(zone
			(layer "B.Cu")
			(hatch none 0.5)
			(connect_pads
				(clearance 0)
			)
			(min_thickness 0.25)
			(keepout
				(tracks allowed)
				(vias not_allowed)
				(pads allowed)
				(copperpour not_allowed)
				(footprints allowed)
			)
			(placement
				(enabled no)
				(sheetname "")
			)
			(fill
				(thermal_gap 0.5)
				(thermal_bridge_width 0.5)
				(island_removal_mode 0)
			)
			(polygon
				(pts
					(xy 378.333 -82.423) (xy 378.333 -82.931) (xy 377.952 -82.931) (xy 377.952 -82.423)
				)
			)
		)
	)
	(footprint ""
		(layer "B.Cu")
		(at 272.861532 -12.954 90)
		(property "Reference" "C5G48"
			(at -1.14681 0.76708 180)
			(unlocked yes)
			(layer "B.SilkS")
			(effects
				(font
					(size 0.7874 0.5842)
					(thickness 0.1524)
				)
				(justify mirror)
			)
		)
		(property "Value" ""
			(at 0 0 90)
			(layer "B.Fab")
			(effects
				(font
					(size 1.27 1.27)
				)
				(justify mirror)
			)
		)
		(duplicate_pad_numbers_are_jumpers no)
		(fp_rect
			(start -0.4953 -0.2032)
			(end 0.4953 1.6002)
			(stroke
				(width 0)
				(type default)
			)
			(fill no)
			(layer "B.CrtYd")
		)
		(fp_line
			(start 0.4953 -0.2032)
			(end -0.4953 -0.2032)
			(stroke
				(width 0.1)
				(type default)
			)
			(layer "B.Fab")
		)
		(fp_line
			(start -0.4953 -0.2032)
			(end -0.4953 1.6002)
			(stroke
				(width 0.1)
				(type default)
			)
			(layer "B.Fab")
		)
		(fp_line
			(start 0.4953 1.6002)
			(end 0.4953 -0.2032)
			(stroke
				(width 0.1)
				(type default)
			)
			(layer "B.Fab")
		)
		(fp_line
			(start -0.4953 1.6002)
			(end 0.4953 1.6002)
			(stroke
				(width 0.1)
				(type default)
			)
			(layer "B.Fab")
		)
		(pad "1" smd rect
			(at 0 0 270)
			(size 0.762 0.889)
			(layers "B.Cu" "B.Mask" "B.Paste")
			(net "PVDDQ_ABC")
		)
		(pad "2" smd rect
			(at 0 1.397 270)
			(size 0.762 0.889)
			(layers "B.Cu" "B.Mask" "B.Paste")
			(net "GND")
		)
		(zone
			(layer "B.Cu")
			(hatch none 0.5)
			(connect_pads
				(clearance 0)
			)
			(min_thickness 0.25)
			(keepout
				(tracks not_allowed)
				(vias allowed)
				(pads allowed)
				(copperpour not_allowed)
				(footprints allowed)
			)
			(placement
				(enabled no)
				(sheetname "")
			)
			(fill
				(thermal_gap 0.5)
				(thermal_bridge_width 0.5)
				(island_removal_mode 0)
			)
			(polygon
				(pts
					(xy 273.306032 -12.573) (xy 273.814032 -12.573) (xy 273.814032 -13.335) (xy 273.306032 -13.335)
				)
			)
		)
	)
	(footprint ""
		(layer "B.Cu")
		(at 496.34648 -130.52552)
		(property "Reference" "C1M31"
			(at 0 0 0)
			(layer "B.SilkS")
			(hide yes)
			(effects
				(font
					(size 1.27 1.27)
				)
				(justify mirror)
			)
		)
		(property "Value" ""
			(at 0 0 0)
			(layer "B.Fab")
			(effects
				(font
					(size 1.27 1.27)
				)
				(justify mirror)
			)
		)
		(duplicate_pad_numbers_are_jumpers no)
		(fp_poly
			(pts
				(xy -0.3048 -0.1016) (xy -0.3048 0.9906) (xy 0.3048 0.9906) (xy 0.3048 -0.1016)
			)
			(stroke
				(width 0)
				(type default)
			)
			(fill no)
			(layer "B.CrtYd")
		)
		(fp_line
			(start -0.3048 -0.1016)
			(end 0.3048 -0.1016)
			(stroke
				(width 0.1)
				(type default)
			)
			(layer "B.Fab")
		)
		(fp_line
			(start -0.3048 0.9906)
			(end -0.3048 -0.1016)
			(stroke
				(width 0.1)
				(type default)
			)
			(layer "B.Fab")
		)
		(fp_line
			(start 0.3048 -0.1016)
			(end 0.3048 0.9906)
			(stroke
				(width 0.1)
				(type default)
			)
			(layer "B.Fab")
		)
		(fp_line
			(start 0.3048 0.9906)
			(end -0.3048 0.9906)
			(stroke
				(width 0.1)
				(type default)
			)
			(layer "B.Fab")
		)
		(pad "1" smd rect
			(at 0 0 180)
			(size 0.508 0.508)
			(layers "B.Cu" "B.Mask" "B.Paste")
			(net "P3V3_STBY")
		)
		(pad "2" smd rect
			(at 0 0.889 180)
			(size 0.508 0.508)
			(layers "B.Cu" "B.Mask" "B.Paste")
			(net "GND")
		)
		(zone
			(layer "B.Cu")
			(hatch none 0.5)
			(connect_pads
				(clearance 0)
			)
			(min_thickness 0.25)
			(keepout
				(tracks allowed)
				(vias not_allowed)
				(pads allowed)
				(copperpour not_allowed)
				(footprints allowed)
			)
			(placement
				(enabled no)
				(sheetname "")
			)
			(fill
				(thermal_gap 0.5)
				(thermal_bridge_width 0.5)
				(island_removal_mode 0)
			)
			(polygon
				(pts
					(xy 496.60048 -130.27152) (xy 496.09248 -130.27152) (xy 496.09248 -129.89052) (xy 496.60048 -129.89052)
				)
			)
		)
		(zone
			(layer "B.Cu")
			(hatch none 0.5)
			(connect_pads
				(clearance 0)
			)
			(min_thickness 0.25)
			(keepout
				(tracks not_allowed)
				(vias allowed)
				(pads allowed)
				(copperpour not_allowed)
				(footprints allowed)
			)
			(placement
				(enabled no)
				(sheetname "")
			)
			(fill
				(thermal_gap 0.5)
				(thermal_bridge_width 0.5)
				(island_removal_mode 0)
			)
			(polygon
				(pts
					(xy 496.60048 -129.89052) (xy 496.09248 -129.89052) (xy 496.09248 -130.27152) (xy 496.60048 -130.27152)
				)
			)
		)
	)
	(footprint ""
		(layer "B.Cu")
		(at 112.0775 -126.08306 90)
		(property "Reference" "C8M11"
			(at 0 0 90)
			(layer "B.SilkS")
			(hide yes)
			(effects
				(font
					(size 1.27 1.27)
				)
				(justify mirror)
			)
		)
		(property "Value" ""
			(at 0 0 90)
			(layer "B.Fab")
			(effects
				(font
					(size 1.27 1.27)
				)
				(justify mirror)
			)
		)
		(duplicate_pad_numbers_are_jumpers no)
		(fp_poly
			(pts
				(xy 0.7239 -0.2159) (xy -0.7239 -0.2159) (xy -0.7239 1.9939) (xy 0.7239 1.9939)
			)
			(stroke
				(width 0)
				(type default)
			)
			(fill no)
			(layer "B.CrtYd")
		)
		(fp_line
			(start 0.7239 -0.2159)
			(end 0.7239 1.9939)
			(stroke
				(width 0.1)
				(type default)
			)
			(layer "B.Fab")
		)
		(fp_line
			(start -0.7239 -0.2159)
			(end 0.7239 -0.2159)
			(stroke
				(width 0.1)
				(type default)
			)
			(layer "B.Fab")
		)
		(fp_line
			(start 0.7239 1.9939)
			(end -0.7239 1.9939)
			(stroke
				(width 0.1)
				(type default)
			)
			(layer "B.Fab")
		)
		(fp_line
			(start -0.7239 1.9939)
			(end -0.7239 -0.2159)
			(stroke
				(width 0.1)
				(type default)
			)
			(layer "B.Fab")
		)
		(pad "1" smd rect
			(at 0 0 270)
			(size 1.27 1.016)
			(layers "B.Cu" "B.Mask" "B.Paste")
			(net "PVDDQ_KLM")
		)
		(pad "2" smd rect
			(at 0 1.778 270)
			(size 1.27 1.016)
			(layers "B.Cu" "B.Mask" "B.Paste")
			(net "GND")
		)
		(zone
			(layer "B.Cu")
			(hatch none 0.5)
			(connect_pads
				(clearance 0)
			)
			(min_thickness 0.25)
			(keepout
				(tracks not_allowed)
				(vias allowed)
				(pads allowed)
				(copperpour not_allowed)
				(footprints allowed)
			)
			(placement
				(enabled no)
				(sheetname "")
			)
			(fill
				(thermal_gap 0.5)
				(thermal_bridge_width 0.5)
				(island_removal_mode 0)
			)
			(polygon
				(pts
					(xy 112.5855 -126.71806) (xy 112.5855 -125.44806) (xy 113.3475 -125.44806) (xy 113.3475 -126.71806)
				)
			)
		)
	)
	(footprint ""
		(layer "B.Cu")
		(at 277.217886 -79.60614 180)
		(property "Reference" "C4P3"
			(at 0 0 0)
			(layer "B.SilkS")
			(hide yes)
			(effects
				(font
					(size 1.27 1.27)
				)
				(justify mirror)
			)
		)
		(property "Value" ""
			(at 0 0 0)
			(layer "B.Fab")
			(effects
				(font
					(size 1.27 1.27)
				)
				(justify mirror)
			)
		)
		(duplicate_pad_numbers_are_jumpers no)
		(fp_poly
			(pts
				(xy 0.7239 -0.2159) (xy -0.7239 -0.2159) (xy -0.7239 1.9939) (xy 0.7239 1.9939)
			)
			(stroke
				(width 0)
				(type default)
			)
			(fill no)
			(layer "B.CrtYd")
		)
		(fp_line
			(start 0.7239 1.9939)
			(end -0.7239 1.9939)
			(stroke
				(width 0.1)
				(type default)
			)
			(layer "B.Fab")
		)
		(fp_line
			(start 0.7239 -0.2159)
			(end 0.7239 1.9939)
			(stroke
				(width 0.1)
				(type default)
			)
			(layer "B.Fab")
		)
		(fp_line
			(start -0.7239 1.9939)
			(end -0.7239 -0.2159)
			(stroke
				(width 0.1)
				(type default)
			)
			(layer "B.Fab")
		)
		(fp_line
			(start -0.7239 -0.2159)
			(end 0.7239 -0.2159)
			(stroke
				(width 0.1)
				(type default)
			)
			(layer "B.Fab")
		)
		(pad "1" smd rect
			(at 0 0)
			(size 1.27 1.016)
			(layers "B.Cu" "B.Mask" "B.Paste")
			(net "PVCCMCP_CPU0")
		)
		(pad "2" smd rect
			(at 0 1.778)
			(size 1.27 1.016)
			(layers "B.Cu" "B.Mask" "B.Paste")
			(net "GND")
		)
		(zone
			(layer "B.Cu")
			(hatch none 0.5)
			(connect_pads
				(clearance 0)
			)
			(min_thickness 0.25)
			(keepout
				(tracks not_allowed)
				(vias allowed)
				(pads allowed)
				(copperpour not_allowed)
				(footprints allowed)
			)
			(placement
				(enabled no)
				(sheetname "")
			)
			(fill
				(thermal_gap 0.5)
				(thermal_bridge_width 0.5)
				(island_removal_mode 0)
			)
			(polygon
				(pts
					(xy 276.582886 -80.11414) (xy 277.852886 -80.11414) (xy 277.852886 -80.87614) (xy 276.582886 -80.87614)
				)
			)
		)
	)
	(footprint ""
		(layer "B.Cu")
		(at 417.746434 -34.186368 -90)
		(property "Reference" "C25W29"
			(at -0.97536 0.76708 0)
			(unlocked yes)
			(layer "B.SilkS")
			(effects
				(font
					(size 0.4064 0.254)
					(thickness 0.1524)
				)
				(justify mirror)
			)
		)
		(property "Value" ""
			(at 0 0 90)
			(layer "B.Fab")
			(effects
				(font
					(size 1.27 1.27)
				)
				(justify mirror)
			)
		)
		(duplicate_pad_numbers_are_jumpers no)
		(fp_poly
			(pts
				(xy 0.4953 -0.2032) (xy -0.4953 -0.2032) (xy -0.4953 1.6002) (xy 0.4953 1.6002)
			)
			(stroke
				(width 0)
				(type default)
			)
			(fill no)
			(layer "B.CrtYd")
		)
		(fp_line
			(start -0.4953 1.6002)
			(end 0.4953 1.6002)
			(stroke
				(width 0.1)
				(type default)
			)
			(layer "B.Fab")
		)
		(fp_line
			(start 0.4953 1.6002)
			(end 0.4953 -0.2032)
			(stroke
				(width 0.1)
				(type default)
			)
			(layer "B.Fab")
		)
		(fp_line
			(start -0.4953 -0.2032)
			(end -0.4953 1.6002)
			(stroke
				(width 0.1)
				(type default)
			)
			(layer "B.Fab")
		)
		(fp_line
			(start 0.4953 -0.2032)
			(end -0.4953 -0.2032)
			(stroke
				(width 0.1)
				(type default)
			)
			(layer "B.Fab")
		)
		(pad "1" smd rect
			(at 0 0 90)
			(size 0.762 0.889)
			(layers "B.Cu" "B.Mask" "B.Paste")
			(net "P1V15_AUX_BMC")
		)
		(pad "2" smd rect
			(at 0 1.397 90)
			(size 0.762 0.889)
			(layers "B.Cu" "B.Mask" "B.Paste")
			(net "GND")
		)
		(zone
			(layer "B.Cu")
			(hatch none 0.5)
			(connect_pads
				(clearance 0)
			)
			(min_thickness 0.25)
			(keepout
				(tracks not_allowed)
				(vias allowed)
				(pads allowed)
				(copperpour not_allowed)
				(footprints allowed)
			)
			(placement
				(enabled no)
				(sheetname "")
			)
			(fill
				(thermal_gap 0.5)
				(thermal_bridge_width 0.5)
				(island_removal_mode 0)
			)
			(polygon
				(pts
					(xy 417.301934 -33.805368) (xy 417.301934 -34.567368) (xy 416.793934 -34.567368) (xy 416.793934 -33.805368)
				)
			)
		)
	)
	(footprint ""
		(layer "B.Cu")
		(at 167.288718 -74.135234)
		(property "Reference" "R6P22"
			(at 0 0 0)
			(layer "B.SilkS")
			(hide yes)
			(effects
				(font
					(size 1.27 1.27)
				)
				(justify mirror)
			)
		)
		(property "Value" ""
			(at 0 0 0)
			(layer "B.Fab")
			(effects
				(font
					(size 1.27 1.27)
				)
				(justify mirror)
			)
		)
		(duplicate_pad_numbers_are_jumpers no)
		(fp_poly
			(pts
				(xy 0.2794 -0.1016) (xy -0.2794 -0.1016) (xy -0.2794 0.9906) (xy 0.2794 0.9906)
			)
			(stroke
				(width 0)
				(type default)
			)
			(fill no)
			(layer "B.CrtYd")
		)
		(fp_line
			(start -0.2794 -0.1016)
			(end 0.2794 -0.1016)
			(stroke
				(width 0.1)
				(type default)
			)
			(layer "B.Fab")
		)
		(fp_line
			(start -0.2794 0.9906)
			(end -0.2794 -0.1016)
			(stroke
				(width 0.1)
				(type default)
			)
			(layer "B.Fab")
		)
		(fp_line
			(start 0.2794 -0.1016)
			(end 0.2794 0.9906)
			(stroke
				(width 0.1)
				(type default)
			)
			(layer "B.Fab")
		)
		(fp_line
			(start 0.2794 0.9906)
			(end -0.2794 0.9906)
			(stroke
				(width 0.1)
				(type default)
			)
			(layer "B.Fab")
		)
		(pad "1" smd rect
			(at 0 0 180)
			(size 0.508 0.508)
			(layers "B.Cu" "B.Mask" "B.Paste")
			(net "FM_HBW_BYPASS_LOWBW_N")
		)
		(pad "2" smd rect
			(at 0 0.889 180)
			(size 0.508 0.508)
			(layers "B.Cu" "B.Mask" "B.Paste")
			(net "GND")
		)
		(zone
			(layer "B.Cu")
			(hatch none 0.5)
			(connect_pads
				(clearance 0)
			)
			(min_thickness 0.25)
			(keepout
				(tracks allowed)
				(vias not_allowed)
				(pads allowed)
				(copperpour not_allowed)
				(footprints allowed)
			)
			(placement
				(enabled no)
				(sheetname "")
			)
			(fill
				(thermal_gap 0.5)
				(thermal_bridge_width 0.5)
				(island_removal_mode 0)
			)
			(polygon
				(pts
					(xy 167.542718 -73.881234) (xy 167.034718 -73.881234) (xy 167.034718 -73.500234) (xy 167.542718 -73.500234)
				)
			)
		)
		(zone
			(layer "B.Cu")
			(hatch none 0.5)
			(connect_pads
				(clearance 0)
			)
			(min_thickness 0.25)
			(keepout
				(tracks not_allowed)
				(vias allowed)
				(pads allowed)
				(copperpour not_allowed)
				(footprints allowed)
			)
			(placement
				(enabled no)
				(sheetname "")
			)
			(fill
				(thermal_gap 0.5)
				(thermal_bridge_width 0.5)
				(island_removal_mode 0)
			)
			(polygon
				(pts
					(xy 167.542718 -73.500234) (xy 167.034718 -73.500234) (xy 167.034718 -73.881234) (xy 167.542718 -73.881234)
				)
			)
		)
	)
	(footprint ""
		(layer "B.Cu")
		(at 214.503 -94.4372)
		(property "Reference" "C6N7"
			(at 0 0 0)
			(layer "B.SilkS")
			(hide yes)
			(effects
				(font
					(size 1.27 1.27)
				)
				(justify mirror)
			)
		)
		(property "Value" ""
			(at 0 0 0)
			(layer "B.Fab")
			(effects
				(font
					(size 1.27 1.27)
				)
				(justify mirror)
			)
		)
		(duplicate_pad_numbers_are_jumpers no)
		(fp_poly
			(pts
				(xy 0.4953 -0.2032) (xy -0.4953 -0.2032) (xy -0.4953 1.6002) (xy 0.4953 1.6002)
			)
			(stroke
				(width 0)
				(type default)
			)
			(fill no)
			(layer "B.CrtYd")
		)
		(fp_line
			(start -0.4953 -0.2032)
			(end -0.4953 1.6002)
			(stroke
				(width 0.1)
				(type default)
			)
			(layer "B.Fab")
		)
		(fp_line
			(start -0.4953 1.6002)
			(end 0.4953 1.6002)
			(stroke
				(width 0.1)
				(type default)
			)
			(layer "B.Fab")
		)
		(fp_line
			(start 0.4953 -0.2032)
			(end -0.4953 -0.2032)
			(stroke
				(width 0.1)
				(type default)
			)
			(layer "B.Fab")
		)
		(fp_line
			(start 0.4953 1.6002)
			(end 0.4953 -0.2032)
			(stroke
				(width 0.1)
				(type default)
			)
			(layer "B.Fab")
		)
		(pad "1" smd rect
			(at 0 0 180)
			(size 0.762 0.889)
			(layers "B.Cu" "B.Mask" "B.Paste")
			(net "PVSA_CPU0")
		)
		(pad "2" smd rect
			(at 0 1.397 180)
			(size 0.762 0.889)
			(layers "B.Cu" "B.Mask" "B.Paste")
			(net "GND")
		)
		(zone
			(layer "B.Cu")
			(hatch none 0.5)
			(connect_pads
				(clearance 0)
			)
			(min_thickness 0.25)
			(keepout
				(tracks not_allowed)
				(vias allowed)
				(pads allowed)
				(copperpour not_allowed)
				(footprints allowed)
			)
			(placement
				(enabled no)
				(sheetname "")
			)
			(fill
				(thermal_gap 0.5)
				(thermal_bridge_width 0.5)
				(island_removal_mode 0)
			)
			(polygon
				(pts
					(xy 214.884 -93.9927) (xy 214.122 -93.9927) (xy 214.122 -93.4847) (xy 214.884 -93.4847)
				)
			)
		)
	)
	(footprint ""
		(layer "B.Cu")
		(at 485.267 -48.5775)
		(property "Reference" "C1R13"
			(at 0 0 0)
			(layer "B.SilkS")
			(hide yes)
			(effects
				(font
					(size 1.27 1.27)
				)
				(justify mirror)
			)
		)
		(property "Value" ""
			(at 0 0 0)
			(layer "B.Fab")
			(effects
				(font
					(size 1.27 1.27)
				)
				(justify mirror)
			)
		)
		(duplicate_pad_numbers_are_jumpers no)
		(fp_poly
			(pts
				(xy 0.4953 -0.2032) (xy -0.4953 -0.2032) (xy -0.4953 1.6002) (xy 0.4953 1.6002)
			)
			(stroke
				(width 0)
				(type default)
			)
			(fill no)
			(layer "B.CrtYd")
		)
		(fp_line
			(start -0.4953 -0.2032)
			(end -0.4953 1.6002)
			(stroke
				(width 0.1)
				(type default)
			)
			(layer "B.Fab")
		)
		(fp_line
			(start -0.4953 1.6002)
			(end 0.4953 1.6002)
			(stroke
				(width 0.1)
				(type default)
			)
			(layer "B.Fab")
		)
		(fp_line
			(start 0.4953 -0.2032)
			(end -0.4953 -0.2032)
			(stroke
				(width 0.1)
				(type default)
			)
			(layer "B.Fab")
		)
		(fp_line
			(start 0.4953 1.6002)
			(end 0.4953 -0.2032)
			(stroke
				(width 0.1)
				(type default)
			)
			(layer "B.Fab")
		)
		(pad "1" smd rect
			(at 0 0 180)
			(size 0.762 0.889)
			(layers "B.Cu" "B.Mask" "B.Paste")
			(net "P3V3_STBY")
		)
		(pad "2" smd rect
			(at 0 1.397 180)
			(size 0.762 0.889)
			(layers "B.Cu" "B.Mask" "B.Paste")
			(net "GND")
		)
		(zone
			(layer "B.Cu")
			(hatch none 0.5)
			(connect_pads
				(clearance 0)
			)
			(min_thickness 0.25)
			(keepout
				(tracks not_allowed)
				(vias allowed)
				(pads allowed)
				(copperpour not_allowed)
				(footprints allowed)
			)
			(placement
				(enabled no)
				(sheetname "")
			)
			(fill
				(thermal_gap 0.5)
				(thermal_bridge_width 0.5)
				(island_removal_mode 0)
			)
			(polygon
				(pts
					(xy 485.648 -48.133) (xy 484.886 -48.133) (xy 484.886 -47.625) (xy 485.648 -47.625)
				)
			)
		)
	)
	(footprint ""
		(layer "B.Cu")
		(at 411.2895 -11.000994 90)
		(property "Reference" "R8E32"
			(at 0 0 90)
			(layer "B.SilkS")
			(hide yes)
			(effects
				(font
					(size 1.27 1.27)
				)
				(justify mirror)
			)
		)
		(property "Value" ""
			(at 0 0 90)
			(layer "B.Fab")
			(effects
				(font
					(size 1.27 1.27)
				)
				(justify mirror)
			)
		)
		(duplicate_pad_numbers_are_jumpers no)
		(fp_poly
			(pts
				(xy 0.2794 -0.1016) (xy -0.2794 -0.1016) (xy -0.2794 0.9906) (xy 0.2794 0.9906)
			)
			(stroke
				(width 0)
				(type default)
			)
			(fill no)
			(layer "B.CrtYd")
		)
		(fp_line
			(start 0.2794 -0.1016)
			(end 0.2794 0.9906)
			(stroke
				(width 0.1)
				(type default)
			)
			(layer "B.Fab")
		)
		(fp_line
			(start -0.2794 -0.1016)
			(end 0.2794 -0.1016)
			(stroke
				(width 0.1)
				(type default)
			)
			(layer "B.Fab")
		)
		(fp_line
			(start 0.2794 0.9906)
			(end -0.2794 0.9906)
			(stroke
				(width 0.1)
				(type default)
			)
			(layer "B.Fab")
		)
		(fp_line
			(start -0.2794 0.9906)
			(end -0.2794 -0.1016)
			(stroke
				(width 0.1)
				(type default)
			)
			(layer "B.Fab")
		)
		(pad "1" smd rect
			(at 0 0 270)
			(size 0.508 0.508)
			(layers "B.Cu" "B.Mask" "B.Paste")
			(net "P3V3_STBY")
		)
		(pad "2" smd rect
			(at 0 0.889 270)
			(size 0.508 0.508)
			(layers "B.Cu" "B.Mask" "B.Paste")
			(net "FP_NMI_BTN_OUT_R_N")
		)
		(zone
			(layer "B.Cu")
			(hatch none 0.5)
			(connect_pads
				(clearance 0)
			)
			(min_thickness 0.25)
			(keepout
				(tracks allowed)
				(vias not_allowed)
				(pads allowed)
				(copperpour not_allowed)
				(footprints allowed)
			)
			(placement
				(enabled no)
				(sheetname "")
			)
			(fill
				(thermal_gap 0.5)
				(thermal_bridge_width 0.5)
				(island_removal_mode 0)
			)
			(polygon
				(pts
					(xy 411.5435 -11.254994) (xy 411.5435 -10.746994) (xy 411.9245 -10.746994) (xy 411.9245 -11.254994)
				)
			)
		)
		(zone
			(layer "B.Cu")
			(hatch none 0.5)
			(connect_pads
				(clearance 0)
			)
			(min_thickness 0.25)
			(keepout
				(tracks not_allowed)
				(vias allowed)
				(pads allowed)
				(copperpour not_allowed)
				(footprints allowed)
			)
			(placement
				(enabled no)
				(sheetname "")
			)
			(fill
				(thermal_gap 0.5)
				(thermal_bridge_width 0.5)
				(island_removal_mode 0)
			)
			(polygon
				(pts
					(xy 411.9245 -11.254994) (xy 411.9245 -10.746994) (xy 411.5435 -10.746994) (xy 411.5435 -11.254994)
				)
			)
		)
	)
	(footprint ""
		(layer "B.Cu")
		(at 39.329614 -107.807506 -90)
		(property "Reference" "R1C1"
			(at 0 0 90)
			(layer "B.SilkS")
			(hide yes)
			(effects
				(font
					(size 1.27 1.27)
				)
				(justify mirror)
			)
		)
		(property "Value" ""
			(at 0 0 90)
			(layer "B.Fab")
			(effects
				(font
					(size 1.27 1.27)
				)
				(justify mirror)
			)
		)
		(duplicate_pad_numbers_are_jumpers no)
		(fp_poly
			(pts
				(xy 0.2794 -0.1016) (xy -0.2794 -0.1016) (xy -0.2794 0.9906) (xy 0.2794 0.9906)
			)
			(stroke
				(width 0)
				(type default)
			)
			(fill no)
			(layer "B.CrtYd")
		)
		(fp_line
			(start -0.2794 0.9906)
			(end -0.2794 -0.1016)
			(stroke
				(width 0.1)
				(type default)
			)
			(layer "B.Fab")
		)
		(fp_line
			(start 0.2794 0.9906)
			(end -0.2794 0.9906)
			(stroke
				(width 0.1)
				(type default)
			)
			(layer "B.Fab")
		)
		(fp_line
			(start -0.2794 -0.1016)
			(end 0.2794 -0.1016)
			(stroke
				(width 0.1)
				(type default)
			)
			(layer "B.Fab")
		)
		(fp_line
			(start 0.2794 -0.1016)
			(end 0.2794 0.9906)
			(stroke
				(width 0.1)
				(type default)
			)
			(layer "B.Fab")
		)
		(pad "1" smd rect
			(at 0 0 90)
			(size 0.508 0.508)
			(layers "B.Cu" "B.Mask" "B.Paste")
			(net "SVID_ALERT1_CPU1_N")
		)
		(pad "2" smd rect
			(at 0 0.889 90)
			(size 0.508 0.508)
			(layers "B.Cu" "B.Mask" "B.Paste")
			(net "SVID_ALERT1_CPU1_R_N")
		)
		(zone
			(layer "B.Cu")
			(hatch none 0.5)
			(connect_pads
				(clearance 0)
			)
			(min_thickness 0.25)
			(keepout
				(tracks not_allowed)
				(vias allowed)
				(pads allowed)
				(copperpour not_allowed)
				(footprints allowed)
			)
			(placement
				(enabled no)
				(sheetname "")
			)
			(fill
				(thermal_gap 0.5)
				(thermal_bridge_width 0.5)
				(island_removal_mode 0)
			)
			(polygon
				(pts
					(xy 38.694614 -107.553506) (xy 38.694614 -108.061506) (xy 39.075614 -108.061506) (xy 39.075614 -107.553506)
				)
			)
		)
		(zone
			(layer "B.Cu")
			(hatch none 0.5)
			(connect_pads
				(clearance 0)
			)
			(min_thickness 0.25)
			(keepout
				(tracks allowed)
				(vias not_allowed)
				(pads allowed)
				(copperpour not_allowed)
				(footprints allowed)
			)
			(placement
				(enabled no)
				(sheetname "")
			)
			(fill
				(thermal_gap 0.5)
				(thermal_bridge_width 0.5)
				(island_removal_mode 0)
			)
			(polygon
				(pts
					(xy 39.075614 -107.553506) (xy 39.075614 -108.061506) (xy 38.694614 -108.061506) (xy 38.694614 -107.553506)
				)
			)
		)
	)
	(footprint ""
		(layer "B.Cu")
		(at 13.84046 -107.48518 90)
		(property "Reference" "C9N3"
			(at 0 0 90)
			(layer "B.SilkS")
			(hide yes)
			(effects
				(font
					(size 1.27 1.27)
				)
				(justify mirror)
			)
		)
		(property "Value" ""
			(at 0 0 90)
			(layer "B.Fab")
			(effects
				(font
					(size 1.27 1.27)
				)
				(justify mirror)
			)
		)
		(duplicate_pad_numbers_are_jumpers no)
		(fp_poly
			(pts
				(xy -0.3048 -0.1016) (xy -0.3048 0.9906) (xy 0.3048 0.9906) (xy 0.3048 -0.1016)
			)
			(stroke
				(width 0)
				(type default)
			)
			(fill no)
			(layer "B.CrtYd")
		)
		(fp_line
			(start 0.3048 -0.1016)
			(end 0.3048 0.9906)
			(stroke
				(width 0.1)
				(type default)
			)
			(layer "B.Fab")
		)
		(fp_line
			(start -0.3048 -0.1016)
			(end 0.3048 -0.1016)
			(stroke
				(width 0.1)
				(type default)
			)
			(layer "B.Fab")
		)
		(fp_line
			(start 0.3048 0.9906)
			(end -0.3048 0.9906)
			(stroke
				(width 0.1)
				(type default)
			)
			(layer "B.Fab")
		)
		(fp_line
			(start -0.3048 0.9906)
			(end -0.3048 -0.1016)
			(stroke
				(width 0.1)
				(type default)
			)
			(layer "B.Fab")
		)
		(pad "1" smd rect
			(at 0 0 270)
			(size 0.508 0.508)
			(layers "B.Cu" "B.Mask" "B.Paste")
			(net "P3E_CPU1_PE3_MP_C_TXN<11>")
		)
		(pad "2" smd rect
			(at 0 0.889 270)
			(size 0.508 0.508)
			(layers "B.Cu" "B.Mask" "B.Paste")
			(net "P3E_CPU1_PE3_MP_TXN<11>")
		)
		(zone
			(layer "B.Cu")
			(hatch none 0.5)
			(connect_pads
				(clearance 0)
			)
			(min_thickness 0.25)
			(keepout
				(tracks allowed)
				(vias not_allowed)
				(pads allowed)
				(copperpour not_allowed)
				(footprints allowed)
			)
			(placement
				(enabled no)
				(sheetname "")
			)
			(fill
				(thermal_gap 0.5)
				(thermal_bridge_width 0.5)
				(island_removal_mode 0)
			)
			(polygon
				(pts
					(xy 14.09446 -107.73918) (xy 14.09446 -107.23118) (xy 14.47546 -107.23118) (xy 14.47546 -107.73918)
				)
			)
		)
		(zone
			(layer "B.Cu")
			(hatch none 0.5)
			(connect_pads
				(clearance 0)
			)
			(min_thickness 0.25)
			(keepout
				(tracks not_allowed)
				(vias allowed)
				(pads allowed)
				(copperpour not_allowed)
				(footprints allowed)
			)
			(placement
				(enabled no)
				(sheetname "")
			)
			(fill
				(thermal_gap 0.5)
				(thermal_bridge_width 0.5)
				(island_removal_mode 0)
			)
			(polygon
				(pts
					(xy 14.47546 -107.73918) (xy 14.47546 -107.23118) (xy 14.09446 -107.23118) (xy 14.09446 -107.73918)
				)
			)
		)
	)
	(footprint ""
		(layer "B.Cu")
		(at 430.4792 -22.5298 180)
		(property "Reference" "R1U23"
			(at 0 0 0)
			(layer "B.SilkS")
			(hide yes)
			(effects
				(font
					(size 1.27 1.27)
				)
				(justify mirror)
			)
		)
		(property "Value" ""
			(at 0 0 0)
			(layer "B.Fab")
			(effects
				(font
					(size 1.27 1.27)
				)
				(justify mirror)
			)
		)
		(duplicate_pad_numbers_are_jumpers no)
		(fp_poly
			(pts
				(xy 0.2794 -0.1016) (xy -0.2794 -0.1016) (xy -0.2794 0.9906) (xy 0.2794 0.9906)
			)
			(stroke
				(width 0)
				(type default)
			)
			(fill no)
			(layer "B.CrtYd")
		)
		(fp_line
			(start 0.2794 0.9906)
			(end -0.2794 0.9906)
			(stroke
				(width 0.1)
				(type default)
			)
			(layer "B.Fab")
		)
		(fp_line
			(start 0.2794 -0.1016)
			(end 0.2794 0.9906)
			(stroke
				(width 0.1)
				(type default)
			)
			(layer "B.Fab")
		)
		(fp_line
			(start -0.2794 0.9906)
			(end -0.2794 -0.1016)
			(stroke
				(width 0.1)
				(type default)
			)
			(layer "B.Fab")
		)
		(fp_line
			(start -0.2794 -0.1016)
			(end 0.2794 -0.1016)
			(stroke
				(width 0.1)
				(type default)
			)
			(layer "B.Fab")
		)
		(pad "1" smd rect
			(at 0 0)
			(size 0.508 0.508)
			(layers "B.Cu" "B.Mask" "B.Paste")
			(net "P3V3_STBY")
		)
		(pad "2" smd rect
			(at 0 0.889)
			(size 0.508 0.508)
			(layers "B.Cu" "B.Mask" "B.Paste")
			(net "FM_BOARD_SKU_ID0")
		)
		(zone
			(layer "B.Cu")
			(hatch none 0.5)
			(connect_pads
				(clearance 0)
			)
			(min_thickness 0.25)
			(keepout
				(tracks not_allowed)
				(vias allowed)
				(pads allowed)
				(copperpour not_allowed)
				(footprints allowed)
			)
			(placement
				(enabled no)
				(sheetname "")
			)
			(fill
				(thermal_gap 0.5)
				(thermal_bridge_width 0.5)
				(island_removal_mode 0)
			)
			(polygon
				(pts
					(xy 430.2252 -23.1648) (xy 430.7332 -23.1648) (xy 430.7332 -22.7838) (xy 430.2252 -22.7838)
				)
			)
		)
		(zone
			(layer "B.Cu")
			(hatch none 0.5)
			(connect_pads
				(clearance 0)
			)
			(min_thickness 0.25)
			(keepout
				(tracks allowed)
				(vias not_allowed)
				(pads allowed)
				(copperpour not_allowed)
				(footprints allowed)
			)
			(placement
				(enabled no)
				(sheetname "")
			)
			(fill
				(thermal_gap 0.5)
				(thermal_bridge_width 0.5)
				(island_removal_mode 0)
			)
			(polygon
				(pts
					(xy 430.2252 -22.7838) (xy 430.7332 -22.7838) (xy 430.7332 -23.1648) (xy 430.2252 -23.1648)
				)
			)
		)
	)
	(footprint ""
		(layer "B.Cu")
		(at 438.833006 -43.54195 180)
		(property "Reference" "R25W36"
			(at 0 0 0)
			(layer "B.SilkS")
			(hide yes)
			(effects
				(font
					(size 1.27 1.27)
				)
				(justify mirror)
			)
		)
		(property "Value" "*"
			(at -0.064008 -4.108196 180)
			(unlocked yes)
			(layer "B.Fab")
			(hide yes)
			(effects
				(font
					(size 1.27 1.016)
					(thickness 0.1524)
				)
				(justify mirror)
			)
		)
		(property "Device Type" "120R2F-GP_RCL_GP-120R2F-GP,64.A"
			(at -0.064008 -5.632196 180)
			(unlocked yes)
			(layer "B.Fab")
			(hide yes)
			(effects
				(font
					(size 1.27 1.016)
					(thickness 0.1524)
				)
				(justify mirror)
			)
		)
		(duplicate_pad_numbers_are_jumpers no)
		(fp_line
			(start 0.508 -0.9398)
			(end 0.508 0.9398)
			(stroke
				(width 0.1524)
				(type default)
			)
			(layer "B.SilkS")
		)
		(fp_line
			(start -0.508 -0.9398)
			(end 0.508 -0.9398)
			(stroke
				(width 0.1524)
				(type default)
			)
			(layer "B.SilkS")
		)
		(fp_rect
			(start 0.508 0.9398)
			(end -0.508 -0.9398)
			(stroke
				(width 0)
				(type default)
			)
			(fill no)
			(layer "B.CrtYd")
		)
		(fp_rect
			(start 0.508 0.9398)
			(end -0.508 -0.9398)
			(stroke
				(width 0)
				(type default)
			)
			(fill no)
			(layer "B.Fab")
		)
		(pad "1" smd custom
			(at 0 -0.4445)
			(size 0.1397 0.1397)
			(layers "B.Cu" "B.Mask" "B.Paste")
			(net "BMC_M_BA1")
			(options
				(clearance outline)
				(anchor circle)
			)
			(primitives
				(gr_poly
					(pts
						(arc
							(start -0.1778 0.2794)
							(mid -0.249642 0.249642)
							(end -0.2794 0.1778)
						)
						(arc
							(start -0.2794 -0.1778)
							(mid -0.249642 -0.249642)
							(end -0.1778 -0.2794)
						)
						(arc
							(start 0.1778 -0.2794)
							(mid 0.249642 -0.249642)
							(end 0.2794 -0.1778)
						)
						(arc
							(start 0.2794 0.1778)
							(mid 0.249642 0.249642)
							(end 0.1778 0.2794)
						)
					)
					(width 0)
					(fill yes)
				)
			)
		)
		(pad "2" smd custom
			(at 0 0.4445)
			(size 0.1397 0.1397)
			(layers "B.Cu" "B.Mask" "B.Paste")
			(net "P1V2_AUX_BMC")
			(options
				(clearance outline)
				(anchor circle)
			)
			(primitives
				(gr_poly
					(pts
						(arc
							(start -0.1778 0.2794)
							(mid -0.249642 0.249642)
							(end -0.2794 0.1778)
						)
						(arc
							(start -0.2794 -0.1778)
							(mid -0.249642 -0.249642)
							(end -0.1778 -0.2794)
						)
						(arc
							(start 0.1778 -0.2794)
							(mid 0.249642 -0.249642)
							(end 0.2794 -0.1778)
						)
						(arc
							(start 0.2794 0.1778)
							(mid 0.249642 0.249642)
							(end 0.1778 0.2794)
						)
					)
					(width 0)
					(fill yes)
				)
			)
		)
	)
	(footprint ""
		(layer "B.Cu")
		(at 411.505146 -34.934652 -90)
		(property "Reference" "C25W49"
			(at 0.8382 -0.67818 270)
			(unlocked yes)
			(layer "B.SilkS")
			(effects
				(font
					(size 0.4064 0.254)
					(thickness 0.1524)
				)
				(justify left mirror)
			)
		)
		(property "Value" ""
			(at 0 0 90)
			(layer "B.Fab")
			(effects
				(font
					(size 1.27 1.27)
				)
				(justify mirror)
			)
		)
		(duplicate_pad_numbers_are_jumpers no)
		(fp_poly
			(pts
				(xy -0.3048 -0.1016) (xy -0.3048 0.9906) (xy 0.3048 0.9906) (xy 0.3048 -0.1016)
			)
			(stroke
				(width 0)
				(type default)
			)
			(fill no)
			(layer "B.CrtYd")
		)
		(fp_line
			(start -0.3048 0.9906)
			(end -0.3048 -0.1016)
			(stroke
				(width 0.1)
				(type default)
			)
			(layer "B.Fab")
		)
		(fp_line
			(start 0.3048 0.9906)
			(end -0.3048 0.9906)
			(stroke
				(width 0.1)
				(type default)
			)
			(layer "B.Fab")
		)
		(fp_line
			(start -0.3048 -0.1016)
			(end 0.3048 -0.1016)
			(stroke
				(width 0.1)
				(type default)
			)
			(layer "B.Fab")
		)
		(fp_line
			(start 0.3048 -0.1016)
			(end 0.3048 0.9906)
			(stroke
				(width 0.1)
				(type default)
			)
			(layer "B.Fab")
		)
		(pad "1" smd rect
			(at 0 0 90)
			(size 0.508 0.508)
			(layers "B.Cu" "B.Mask" "B.Paste")
			(net "P3V3_STBY")
		)
		(pad "2" smd rect
			(at 0 0.889 90)
			(size 0.508 0.508)
			(layers "B.Cu" "B.Mask" "B.Paste")
			(net "GND")
		)
		(zone
			(layer "B.Cu")
			(hatch none 0.5)
			(connect_pads
				(clearance 0)
			)
			(min_thickness 0.25)
			(keepout
				(tracks not_allowed)
				(vias allowed)
				(pads allowed)
				(copperpour not_allowed)
				(footprints allowed)
			)
			(placement
				(enabled no)
				(sheetname "")
			)
			(fill
				(thermal_gap 0.5)
				(thermal_bridge_width 0.5)
				(island_removal_mode 0)
			)
			(polygon
				(pts
					(xy 410.870146 -34.680652) (xy 410.870146 -35.188652) (xy 411.251146 -35.188652) (xy 411.251146 -34.680652)
				)
			)
		)
		(zone
			(layer "B.Cu")
			(hatch none 0.5)
			(connect_pads
				(clearance 0)
			)
			(min_thickness 0.25)
			(keepout
				(tracks allowed)
				(vias not_allowed)
				(pads allowed)
				(copperpour not_allowed)
				(footprints allowed)
			)
			(placement
				(enabled no)
				(sheetname "")
			)
			(fill
				(thermal_gap 0.5)
				(thermal_bridge_width 0.5)
				(island_removal_mode 0)
			)
			(polygon
				(pts
					(xy 411.251146 -34.680652) (xy 411.251146 -35.188652) (xy 410.870146 -35.188652) (xy 410.870146 -34.680652)
				)
			)
		)
	)
	(footprint ""
		(layer "B.Cu")
		(at 482.592888 -154.917902 -90)
		(property "Reference" "F1L1"
			(at 0 0 90)
			(layer "B.SilkS")
			(hide yes)
			(effects
				(font
					(size 1.27 1.27)
				)
				(justify mirror)
			)
		)
		(property "Value" ""
			(at 0 0 90)
			(layer "B.Fab")
			(effects
				(font
					(size 1.27 1.27)
				)
				(justify mirror)
			)
		)
		(duplicate_pad_numbers_are_jumpers no)
		(fp_poly
			(pts
				(xy 0.2032 -0.4953) (xy 0.2032 0.4953) (xy -1.6002 0.4953) (xy -1.6002 -0.4953)
			)
			(stroke
				(width 0)
				(type default)
			)
			(fill no)
			(layer "B.CrtYd")
		)
		(fp_line
			(start -1.6002 0.4953)
			(end 0.2032 0.4953)
			(stroke
				(width 0.1)
				(type default)
			)
			(layer "B.Fab")
		)
		(fp_line
			(start 0.2032 0.4953)
			(end 0.2032 -0.4953)
			(stroke
				(width 0.1)
				(type default)
			)
			(layer "B.Fab")
		)
		(fp_line
			(start -1.6002 -0.4953)
			(end -1.6002 0.4953)
			(stroke
				(width 0.1)
				(type default)
			)
			(layer "B.Fab")
		)
		(fp_line
			(start 0.2032 -0.4953)
			(end -1.6002 -0.4953)
			(stroke
				(width 0.1)
				(type default)
			)
			(layer "B.Fab")
		)
		(pad "1" smd rect
			(at 0 0 90)
			(size 0.889 0.9906)
			(layers "B.Cu" "B.Mask" "B.Paste")
			(net "P5V_STBY_DBG")
		)
		(pad "2" smd rect
			(at -1.397 0 90)
			(size 0.889 0.9906)
			(layers "B.Cu" "B.Mask" "B.Paste")
			(net "P5V_STBY_DGB_FS")
		)
		(zone
			(layer "B.Cu")
			(hatch none 0.5)
			(connect_pads
				(clearance 0)
			)
			(min_thickness 0.25)
			(keepout
				(tracks not_allowed)
				(vias allowed)
				(pads allowed)
				(copperpour not_allowed)
				(footprints allowed)
			)
			(placement
				(enabled no)
				(sheetname "")
			)
			(fill
				(thermal_gap 0.5)
				(thermal_bridge_width 0.5)
				(island_removal_mode 0)
			)
			(polygon
				(pts
					(xy 483.088188 -155.362402) (xy 482.097588 -155.362402) (xy 482.097588 -155.870402) (xy 483.088188 -155.870402)
				)
			)
		)
	)
	(footprint ""
		(layer "B.Cu")
		(at 451.030594 -17.1831 -90)
		(property "Reference" "R3W1"
			(at 0.8382 -0.67818 270)
			(unlocked yes)
			(layer "B.SilkS")
			(effects
				(font
					(size 0.4064 0.254)
					(thickness 0.1524)
				)
				(justify left mirror)
			)
		)
		(property "Value" ""
			(at 0 0 90)
			(layer "B.Fab")
			(effects
				(font
					(size 1.27 1.27)
				)
				(justify mirror)
			)
		)
		(duplicate_pad_numbers_are_jumpers no)
		(fp_poly
			(pts
				(xy 0.2794 -0.1016) (xy -0.2794 -0.1016) (xy -0.2794 0.9906) (xy 0.2794 0.9906)
			)
			(stroke
				(width 0)
				(type default)
			)
			(fill no)
			(layer "B.CrtYd")
		)
		(fp_line
			(start -0.2794 0.9906)
			(end -0.2794 -0.1016)
			(stroke
				(width 0.1)
				(type default)
			)
			(layer "B.Fab")
		)
		(fp_line
			(start 0.2794 0.9906)
			(end -0.2794 0.9906)
			(stroke
				(width 0.1)
				(type default)
			)
			(layer "B.Fab")
		)
		(fp_line
			(start -0.2794 -0.1016)
			(end 0.2794 -0.1016)
			(stroke
				(width 0.1)
				(type default)
			)
			(layer "B.Fab")
		)
		(fp_line
			(start 0.2794 -0.1016)
			(end 0.2794 0.9906)
			(stroke
				(width 0.1)
				(type default)
			)
			(layer "B.Fab")
		)
		(pad "1" smd rect
			(at 0 0 90)
			(size 0.508 0.508)
			(layers "B.Cu" "B.Mask" "B.Paste")
			(net "BMC_SELF_HW_D_RST")
		)
		(pad "2" smd rect
			(at 0 0.889 90)
			(size 0.508 0.508)
			(layers "B.Cu" "B.Mask" "B.Paste")
			(net "GND")
		)
		(zone
			(layer "B.Cu")
			(hatch none 0.5)
			(connect_pads
				(clearance 0)
			)
			(min_thickness 0.25)
			(keepout
				(tracks not_allowed)
				(vias allowed)
				(pads allowed)
				(copperpour not_allowed)
				(footprints allowed)
			)
			(placement
				(enabled no)
				(sheetname "")
			)
			(fill
				(thermal_gap 0.5)
				(thermal_bridge_width 0.5)
				(island_removal_mode 0)
			)
			(polygon
				(pts
					(xy 450.395594 -16.9291) (xy 450.395594 -17.4371) (xy 450.776594 -17.4371) (xy 450.776594 -16.9291)
				)
			)
		)
		(zone
			(layer "B.Cu")
			(hatch none 0.5)
			(connect_pads
				(clearance 0)
			)
			(min_thickness 0.25)
			(keepout
				(tracks allowed)
				(vias not_allowed)
				(pads allowed)
				(copperpour not_allowed)
				(footprints allowed)
			)
			(placement
				(enabled no)
				(sheetname "")
			)
			(fill
				(thermal_gap 0.5)
				(thermal_bridge_width 0.5)
				(island_removal_mode 0)
			)
			(polygon
				(pts
					(xy 450.776594 -16.9291) (xy 450.776594 -17.4371) (xy 450.395594 -17.4371) (xy 450.395594 -16.9291)
				)
			)
		)
	)
	(footprint ""
		(layer "B.Cu")
		(at 454.5838 -146.7612 -90)
		(property "Reference" "C9A5"
			(at 0 0 90)
			(layer "B.SilkS")
			(hide yes)
			(effects
				(font
					(size 1.27 1.27)
				)
				(justify mirror)
			)
		)
		(property "Value" ""
			(at 0 0 90)
			(layer "B.Fab")
			(effects
				(font
					(size 1.27 1.27)
				)
				(justify mirror)
			)
		)
		(duplicate_pad_numbers_are_jumpers no)
		(fp_poly
			(pts
				(xy -0.3048 -0.1016) (xy -0.3048 0.9906) (xy 0.3048 0.9906) (xy 0.3048 -0.1016)
			)
			(stroke
				(width 0)
				(type default)
			)
			(fill no)
			(layer "B.CrtYd")
		)
		(fp_line
			(start -0.3048 0.9906)
			(end -0.3048 -0.1016)
			(stroke
				(width 0.1)
				(type default)
			)
			(layer "B.Fab")
		)
		(fp_line
			(start 0.3048 0.9906)
			(end -0.3048 0.9906)
			(stroke
				(width 0.1)
				(type default)
			)
			(layer "B.Fab")
		)
		(fp_line
			(start -0.3048 -0.1016)
			(end 0.3048 -0.1016)
			(stroke
				(width 0.1)
				(type default)
			)
			(layer "B.Fab")
		)
		(fp_line
			(start 0.3048 -0.1016)
			(end 0.3048 0.9906)
			(stroke
				(width 0.1)
				(type default)
			)
			(layer "B.Fab")
		)
		(pad "1" smd rect
			(at 0 0 90)
			(size 0.508 0.508)
			(layers "B.Cu" "B.Mask" "B.Paste")
			(net "XDP_RST_CO_N")
		)
		(pad "2" smd rect
			(at 0 0.889 90)
			(size 0.508 0.508)
			(layers "B.Cu" "B.Mask" "B.Paste")
			(net "GND")
		)
		(zone
			(layer "B.Cu")
			(hatch none 0.5)
			(connect_pads
				(clearance 0)
			)
			(min_thickness 0.25)
			(keepout
				(tracks not_allowed)
				(vias allowed)
				(pads allowed)
				(copperpour not_allowed)
				(footprints allowed)
			)
			(placement
				(enabled no)
				(sheetname "")
			)
			(fill
				(thermal_gap 0.5)
				(thermal_bridge_width 0.5)
				(island_removal_mode 0)
			)
			(polygon
				(pts
					(xy 453.9488 -146.5072) (xy 453.9488 -147.0152) (xy 454.3298 -147.0152) (xy 454.3298 -146.5072)
				)
			)
		)
		(zone
			(layer "B.Cu")
			(hatch none 0.5)
			(connect_pads
				(clearance 0)
			)
			(min_thickness 0.25)
			(keepout
				(tracks allowed)
				(vias not_allowed)
				(pads allowed)
				(copperpour not_allowed)
				(footprints allowed)
			)
			(placement
				(enabled no)
				(sheetname "")
			)
			(fill
				(thermal_gap 0.5)
				(thermal_bridge_width 0.5)
				(island_removal_mode 0)
			)
			(polygon
				(pts
					(xy 454.3298 -146.5072) (xy 454.3298 -147.0152) (xy 453.9488 -147.0152) (xy 453.9488 -146.5072)
				)
			)
		)
	)
	(footprint ""
		(layer "B.Cu")
		(at 427.4185 -20.32 90)
		(property "Reference" "R1U9"
			(at 0 0 90)
			(layer "B.SilkS")
			(hide yes)
			(effects
				(font
					(size 1.27 1.27)
				)
				(justify mirror)
			)
		)
		(property "Value" ""
			(at 0 0 90)
			(layer "B.Fab")
			(effects
				(font
					(size 1.27 1.27)
				)
				(justify mirror)
			)
		)
		(duplicate_pad_numbers_are_jumpers no)
		(fp_poly
			(pts
				(xy 0.2794 -0.1016) (xy -0.2794 -0.1016) (xy -0.2794 0.9906) (xy 0.2794 0.9906)
			)
			(stroke
				(width 0)
				(type default)
			)
			(fill no)
			(layer "B.CrtYd")
		)
		(fp_line
			(start 0.2794 -0.1016)
			(end 0.2794 0.9906)
			(stroke
				(width 0.1)
				(type default)
			)
			(layer "B.Fab")
		)
		(fp_line
			(start -0.2794 -0.1016)
			(end 0.2794 -0.1016)
			(stroke
				(width 0.1)
				(type default)
			)
			(layer "B.Fab")
		)
		(fp_line
			(start 0.2794 0.9906)
			(end -0.2794 0.9906)
			(stroke
				(width 0.1)
				(type default)
			)
			(layer "B.Fab")
		)
		(fp_line
			(start -0.2794 0.9906)
			(end -0.2794 -0.1016)
			(stroke
				(width 0.1)
				(type default)
			)
			(layer "B.Fab")
		)
		(pad "1" smd rect
			(at 0 0 270)
			(size 0.508 0.508)
			(layers "B.Cu" "B.Mask" "B.Paste")
			(net "SMB_SMLINK0_STBY_LVC3_SCL_R")
		)
		(pad "2" smd rect
			(at 0 0.889 270)
			(size 0.508 0.508)
			(layers "B.Cu" "B.Mask" "B.Paste")
			(net "SMB_SMLINK0_STBY_LVC3_SCL")
		)
		(zone
			(layer "B.Cu")
			(hatch none 0.5)
			(connect_pads
				(clearance 0)
			)
			(min_thickness 0.25)
			(keepout
				(tracks allowed)
				(vias not_allowed)
				(pads allowed)
				(copperpour not_allowed)
				(footprints allowed)
			)
			(placement
				(enabled no)
				(sheetname "")
			)
			(fill
				(thermal_gap 0.5)
				(thermal_bridge_width 0.5)
				(island_removal_mode 0)
			)
			(polygon
				(pts
					(xy 427.6725 -20.574) (xy 427.6725 -20.066) (xy 428.0535 -20.066) (xy 428.0535 -20.574)
				)
			)
		)
		(zone
			(layer "B.Cu")
			(hatch none 0.5)
			(connect_pads
				(clearance 0)
			)
			(min_thickness 0.25)
			(keepout
				(tracks not_allowed)
				(vias allowed)
				(pads allowed)
				(copperpour not_allowed)
				(footprints allowed)
			)
			(placement
				(enabled no)
				(sheetname "")
			)
			(fill
				(thermal_gap 0.5)
				(thermal_bridge_width 0.5)
				(island_removal_mode 0)
			)
			(polygon
				(pts
					(xy 428.0535 -20.574) (xy 428.0535 -20.066) (xy 427.6725 -20.066) (xy 427.6725 -20.574)
				)
			)
		)
	)
	(footprint ""
		(layer "B.Cu")
		(at 422.47312 -73.962514)
		(property "Reference" "C1R27"
			(at 0 0 0)
			(layer "B.SilkS")
			(hide yes)
			(effects
				(font
					(size 1.27 1.27)
				)
				(justify mirror)
			)
		)
		(property "Value" ""
			(at 0 0 0)
			(layer "B.Fab")
			(effects
				(font
					(size 1.27 1.27)
				)
				(justify mirror)
			)
		)
		(duplicate_pad_numbers_are_jumpers no)
		(fp_poly
			(pts
				(xy -0.3048 -0.1016) (xy -0.3048 0.9906) (xy 0.3048 0.9906) (xy 0.3048 -0.1016)
			)
			(stroke
				(width 0)
				(type default)
			)
			(fill no)
			(layer "B.CrtYd")
		)
		(fp_line
			(start -0.3048 -0.1016)
			(end 0.3048 -0.1016)
			(stroke
				(width 0.1)
				(type default)
			)
			(layer "B.Fab")
		)
		(fp_line
			(start -0.3048 0.9906)
			(end -0.3048 -0.1016)
			(stroke
				(width 0.1)
				(type default)
			)
			(layer "B.Fab")
		)
		(fp_line
			(start 0.3048 -0.1016)
			(end 0.3048 0.9906)
			(stroke
				(width 0.1)
				(type default)
			)
			(layer "B.Fab")
		)
		(fp_line
			(start 0.3048 0.9906)
			(end -0.3048 0.9906)
			(stroke
				(width 0.1)
				(type default)
			)
			(layer "B.Fab")
		)
		(pad "1" smd rect
			(at 0 0 180)
			(size 0.508 0.508)
			(layers "B.Cu" "B.Mask" "B.Paste")
			(net "P3V3_STBY")
		)
		(pad "2" smd rect
			(at 0 0.889 180)
			(size 0.508 0.508)
			(layers "B.Cu" "B.Mask" "B.Paste")
			(net "GND")
		)
		(zone
			(layer "B.Cu")
			(hatch none 0.5)
			(connect_pads
				(clearance 0)
			)
			(min_thickness 0.25)
			(keepout
				(tracks allowed)
				(vias not_allowed)
				(pads allowed)
				(copperpour not_allowed)
				(footprints allowed)
			)
			(placement
				(enabled no)
				(sheetname "")
			)
			(fill
				(thermal_gap 0.5)
				(thermal_bridge_width 0.5)
				(island_removal_mode 0)
			)
			(polygon
				(pts
					(xy 422.72712 -73.708514) (xy 422.21912 -73.708514) (xy 422.21912 -73.327514) (xy 422.72712 -73.327514)
				)
			)
		)
		(zone
			(layer "B.Cu")
			(hatch none 0.5)
			(connect_pads
				(clearance 0)
			)
			(min_thickness 0.25)
			(keepout
				(tracks not_allowed)
				(vias allowed)
				(pads allowed)
				(copperpour not_allowed)
				(footprints allowed)
			)
			(placement
				(enabled no)
				(sheetname "")
			)
			(fill
				(thermal_gap 0.5)
				(thermal_bridge_width 0.5)
				(island_removal_mode 0)
			)
			(polygon
				(pts
					(xy 422.72712 -73.327514) (xy 422.21912 -73.327514) (xy 422.21912 -73.708514) (xy 422.72712 -73.708514)
				)
			)
		)
	)
	(footprint ""
		(layer "B.Cu")
		(at 83.856068 -135.4074 -90)
		(property "Reference" "C8M5"
			(at -1.848866 0.752348 270)
			(unlocked yes)
			(layer "B.SilkS")
			(effects
				(font
					(size 1.27 0.9652)
					(thickness 0.1524)
				)
				(justify mirror)
			)
		)
		(property "Value" ""
			(at 0 0 90)
			(layer "B.Fab")
			(effects
				(font
					(size 1.27 1.27)
				)
				(justify mirror)
			)
		)
		(duplicate_pad_numbers_are_jumpers no)
		(fp_rect
			(start 0.500126 1.598422)
			(end -0.500126 -0.201422)
			(stroke
				(width 0)
				(type default)
			)
			(fill no)
			(layer "B.CrtYd")
		)
		(fp_line
			(start -0.500126 1.598422)
			(end 0.500126 1.598422)
			(stroke
				(width 0.1)
				(type default)
			)
			(layer "B.Fab")
		)
		(fp_line
			(start 0.500126 1.598422)
			(end 0.500126 -0.201422)
			(stroke
				(width 0.1)
				(type default)
			)
			(layer "B.Fab")
		)
		(fp_line
			(start -0.500126 -0.201422)
			(end -0.500126 1.598422)
			(stroke
				(width 0.1)
				(type default)
			)
			(layer "B.Fab")
		)
		(fp_line
			(start 0.500126 -0.201422)
			(end -0.500126 -0.201422)
			(stroke
				(width 0.1)
				(type default)
			)
			(layer "B.Fab")
		)
		(pad "1" smd rect
			(at 0 0 180)
			(size 0.889 0.9906)
			(layers "B.Cu" "B.Mask" "B.Paste")
			(net "PVDDQ_KLM")
		)
		(pad "2" smd rect
			(at 0 1.397 180)
			(size 0.889 0.9906)
			(layers "B.Cu" "B.Mask" "B.Paste")
			(net "GND")
		)
		(zone
			(layer "B.Cu")
			(hatch none 0.5)
			(connect_pads
				(clearance 0)
			)
			(min_thickness 0.25)
			(keepout
				(tracks not_allowed)
				(vias allowed)
				(pads allowed)
				(copperpour not_allowed)
				(footprints allowed)
			)
			(placement
				(enabled no)
				(sheetname "")
			)
			(fill
				(thermal_gap 0.5)
				(thermal_bridge_width 0.5)
				(island_removal_mode 0)
			)
			(polygon
				(pts
					(xy 82.903568 -134.9121) (xy 83.411568 -134.9121) (xy 83.411568 -135.9027) (xy 82.903568 -135.9027)
				)
			)
		)
		(zone
			(layer "B.Cu")
			(hatch none 0.5)
			(connect_pads
				(clearance 0)
			)
			(min_thickness 0.25)
			(keepout
				(tracks allowed)
				(vias not_allowed)
				(pads allowed)
				(copperpour not_allowed)
				(footprints allowed)
			)
			(placement
				(enabled no)
				(sheetname "")
			)
			(fill
				(thermal_gap 0.5)
				(thermal_bridge_width 0.5)
				(island_removal_mode 0)
			)
			(polygon
				(pts
					(xy 82.903568 -134.9121) (xy 83.411568 -134.9121) (xy 83.411568 -135.9027) (xy 82.903568 -135.9027)
				)
			)
		)
	)
	(footprint ""
		(layer "B.Cu")
		(at 17.907 -47.371 -90)
		(property "Reference" "R9R5"
			(at 0 0 90)
			(layer "B.SilkS")
			(hide yes)
			(effects
				(font
					(size 1.27 1.27)
				)
				(justify mirror)
			)
		)
		(property "Value" ""
			(at 0 0 90)
			(layer "B.Fab")
			(effects
				(font
					(size 1.27 1.27)
				)
				(justify mirror)
			)
		)
		(duplicate_pad_numbers_are_jumpers no)
		(fp_poly
			(pts
				(xy 0.2794 -0.1016) (xy -0.2794 -0.1016) (xy -0.2794 0.9906) (xy 0.2794 0.9906)
			)
			(stroke
				(width 0)
				(type default)
			)
			(fill no)
			(layer "B.CrtYd")
		)
		(fp_line
			(start -0.2794 0.9906)
			(end -0.2794 -0.1016)
			(stroke
				(width 0.1)
				(type default)
			)
			(layer "B.Fab")
		)
		(fp_line
			(start 0.2794 0.9906)
			(end -0.2794 0.9906)
			(stroke
				(width 0.1)
				(type default)
			)
			(layer "B.Fab")
		)
		(fp_line
			(start -0.2794 -0.1016)
			(end 0.2794 -0.1016)
			(stroke
				(width 0.1)
				(type default)
			)
			(layer "B.Fab")
		)
		(fp_line
			(start 0.2794 -0.1016)
			(end 0.2794 0.9906)
			(stroke
				(width 0.1)
				(type default)
			)
			(layer "B.Fab")
		)
		(pad "1" smd rect
			(at 0 0 90)
			(size 0.508 0.508)
			(layers "B.Cu" "B.Mask" "B.Paste")
			(net "ISENSE_TMP421_2_E")
		)
		(pad "2" smd rect
			(at 0 0.889 90)
			(size 0.508 0.508)
			(layers "B.Cu" "B.Mask" "B.Paste")
			(net "ISENSE_TMP421_2_DXP")
		)
		(zone
			(layer "B.Cu")
			(hatch none 0.5)
			(connect_pads
				(clearance 0)
			)
			(min_thickness 0.25)
			(keepout
				(tracks not_allowed)
				(vias allowed)
				(pads allowed)
				(copperpour not_allowed)
				(footprints allowed)
			)
			(placement
				(enabled no)
				(sheetname "")
			)
			(fill
				(thermal_gap 0.5)
				(thermal_bridge_width 0.5)
				(island_removal_mode 0)
			)
			(polygon
				(pts
					(xy 17.272 -47.117) (xy 17.272 -47.625) (xy 17.653 -47.625) (xy 17.653 -47.117)
				)
			)
		)
		(zone
			(layer "B.Cu")
			(hatch none 0.5)
			(connect_pads
				(clearance 0)
			)
			(min_thickness 0.25)
			(keepout
				(tracks allowed)
				(vias not_allowed)
				(pads allowed)
				(copperpour not_allowed)
				(footprints allowed)
			)
			(placement
				(enabled no)
				(sheetname "")
			)
			(fill
				(thermal_gap 0.5)
				(thermal_bridge_width 0.5)
				(island_removal_mode 0)
			)
			(polygon
				(pts
					(xy 17.653 -47.117) (xy 17.653 -47.625) (xy 17.272 -47.625) (xy 17.272 -47.117)
				)
			)
		)
	)
	(footprint ""
		(layer "B.Cu")
		(at 157.08122 -121.4247 180)
		(property "Reference" "R7M7"
			(at 0 0 0)
			(layer "B.SilkS")
			(hide yes)
			(effects
				(font
					(size 1.27 1.27)
				)
				(justify mirror)
			)
		)
		(property "Value" ""
			(at 0 0 0)
			(layer "B.Fab")
			(effects
				(font
					(size 1.27 1.27)
				)
				(justify mirror)
			)
		)
		(duplicate_pad_numbers_are_jumpers no)
		(fp_poly
			(pts
				(xy 0.2794 -0.1016) (xy -0.2794 -0.1016) (xy -0.2794 0.9906) (xy 0.2794 0.9906)
			)
			(stroke
				(width 0)
				(type default)
			)
			(fill no)
			(layer "B.CrtYd")
		)
		(fp_line
			(start 0.2794 0.9906)
			(end -0.2794 0.9906)
			(stroke
				(width 0.1)
				(type default)
			)
			(layer "B.Fab")
		)
		(fp_line
			(start 0.2794 -0.1016)
			(end 0.2794 0.9906)
			(stroke
				(width 0.1)
				(type default)
			)
			(layer "B.Fab")
		)
		(fp_line
			(start -0.2794 0.9906)
			(end -0.2794 -0.1016)
			(stroke
				(width 0.1)
				(type default)
			)
			(layer "B.Fab")
		)
		(fp_line
			(start -0.2794 -0.1016)
			(end 0.2794 -0.1016)
			(stroke
				(width 0.1)
				(type default)
			)
			(layer "B.Fab")
		)
		(pad "1" smd rect
			(at 0 0)
			(size 0.508 0.508)
			(layers "B.Cu" "B.Mask" "B.Paste")
			(net "PVCCIO_CPU1")
		)
		(pad "2" smd rect
			(at 0 0.889)
			(size 0.508 0.508)
			(layers "B.Cu" "B.Mask" "B.Paste")
			(net "SMB_DDR_KLM_SDA_G")
		)
		(zone
			(layer "B.Cu")
			(hatch none 0.5)
			(connect_pads
				(clearance 0)
			)
			(min_thickness 0.25)
			(keepout
				(tracks not_allowed)
				(vias allowed)
				(pads allowed)
				(copperpour not_allowed)
				(footprints allowed)
			)
			(placement
				(enabled no)
				(sheetname "")
			)
			(fill
				(thermal_gap 0.5)
				(thermal_bridge_width 0.5)
				(island_removal_mode 0)
			)
			(polygon
				(pts
					(xy 156.82722 -122.0597) (xy 157.33522 -122.0597) (xy 157.33522 -121.6787) (xy 156.82722 -121.6787)
				)
			)
		)
		(zone
			(layer "B.Cu")
			(hatch none 0.5)
			(connect_pads
				(clearance 0)
			)
			(min_thickness 0.25)
			(keepout
				(tracks allowed)
				(vias not_allowed)
				(pads allowed)
				(copperpour not_allowed)
				(footprints allowed)
			)
			(placement
				(enabled no)
				(sheetname "")
			)
			(fill
				(thermal_gap 0.5)
				(thermal_bridge_width 0.5)
				(island_removal_mode 0)
			)
			(polygon
				(pts
					(xy 156.82722 -121.6787) (xy 157.33522 -121.6787) (xy 157.33522 -122.0597) (xy 156.82722 -122.0597)
				)
			)
		)
	)
	(footprint ""
		(layer "B.Cu")
		(at 476.414084 -135.41756 -90)
		(property "Reference" "R1W37"
			(at 0.8382 -0.67818 270)
			(unlocked yes)
			(layer "B.SilkS")
			(effects
				(font
					(size 0.4064 0.254)
					(thickness 0.1524)
				)
				(justify left mirror)
			)
		)
		(property "Value" ""
			(at 0 0 90)
			(layer "B.Fab")
			(effects
				(font
					(size 1.27 1.27)
				)
				(justify mirror)
			)
		)
		(duplicate_pad_numbers_are_jumpers no)
		(fp_poly
			(pts
				(xy 0.2794 -0.1016) (xy -0.2794 -0.1016) (xy -0.2794 0.9906) (xy 0.2794 0.9906)
			)
			(stroke
				(width 0)
				(type default)
			)
			(fill no)
			(layer "B.CrtYd")
		)
		(fp_line
			(start -0.2794 0.9906)
			(end -0.2794 -0.1016)
			(stroke
				(width 0.1)
				(type default)
			)
			(layer "B.Fab")
		)
		(fp_line
			(start 0.2794 0.9906)
			(end -0.2794 0.9906)
			(stroke
				(width 0.1)
				(type default)
			)
			(layer "B.Fab")
		)
		(fp_line
			(start -0.2794 -0.1016)
			(end 0.2794 -0.1016)
			(stroke
				(width 0.1)
				(type default)
			)
			(layer "B.Fab")
		)
		(fp_line
			(start 0.2794 -0.1016)
			(end 0.2794 0.9906)
			(stroke
				(width 0.1)
				(type default)
			)
			(layer "B.Fab")
		)
		(pad "1" smd rect
			(at 0 0 90)
			(size 0.508 0.508)
			(layers "B.Cu" "B.Mask" "B.Paste")
			(net "P3V3_STBY")
		)
		(pad "2" smd rect
			(at 0 0.889 90)
			(size 0.508 0.508)
			(layers "B.Cu" "B.Mask" "B.Paste")
			(net "SMB_DEBUG_STBY_LVC3_SDA_CONN")
		)
		(zone
			(layer "B.Cu")
			(hatch none 0.5)
			(connect_pads
				(clearance 0)
			)
			(min_thickness 0.25)
			(keepout
				(tracks not_allowed)
				(vias allowed)
				(pads allowed)
				(copperpour not_allowed)
				(footprints allowed)
			)
			(placement
				(enabled no)
				(sheetname "")
			)
			(fill
				(thermal_gap 0.5)
				(thermal_bridge_width 0.5)
				(island_removal_mode 0)
			)
			(polygon
				(pts
					(xy 475.779084 -135.16356) (xy 475.779084 -135.67156) (xy 476.160084 -135.67156) (xy 476.160084 -135.16356)
				)
			)
		)
		(zone
			(layer "B.Cu")
			(hatch none 0.5)
			(connect_pads
				(clearance 0)
			)
			(min_thickness 0.25)
			(keepout
				(tracks allowed)
				(vias not_allowed)
				(pads allowed)
				(copperpour not_allowed)
				(footprints allowed)
			)
			(placement
				(enabled no)
				(sheetname "")
			)
			(fill
				(thermal_gap 0.5)
				(thermal_bridge_width 0.5)
				(island_removal_mode 0)
			)
			(polygon
				(pts
					(xy 476.160084 -135.16356) (xy 476.160084 -135.67156) (xy 475.779084 -135.67156) (xy 475.779084 -135.16356)
				)
			)
		)
	)
	(footprint ""
		(layer "B.Cu")
		(at 414.2105 -4.318 -90)
		(property "Reference" "R2P20"
			(at 0 0 90)
			(layer "B.SilkS")
			(hide yes)
			(effects
				(font
					(size 1.27 1.27)
				)
				(justify mirror)
			)
		)
		(property "Value" ""
			(at 0 0 90)
			(layer "B.Fab")
			(effects
				(font
					(size 1.27 1.27)
				)
				(justify mirror)
			)
		)
		(duplicate_pad_numbers_are_jumpers no)
		(fp_rect
			(start 0.2794 -0.1016)
			(end -0.2794 0.9906)
			(stroke
				(width 0)
				(type default)
			)
			(fill no)
			(layer "B.CrtYd")
		)
		(fp_line
			(start -0.2794 0.9906)
			(end -0.2794 -0.1016)
			(stroke
				(width 0.1)
				(type default)
			)
			(layer "B.Fab")
		)
		(fp_line
			(start 0.2794 0.9906)
			(end -0.2794 0.9906)
			(stroke
				(width 0.1)
				(type default)
			)
			(layer "B.Fab")
		)
		(fp_line
			(start -0.2794 -0.1016)
			(end 0.2794 -0.1016)
			(stroke
				(width 0.1)
				(type default)
			)
			(layer "B.Fab")
		)
		(fp_line
			(start 0.2794 -0.1016)
			(end 0.2794 0.9906)
			(stroke
				(width 0.1)
				(type default)
			)
			(layer "B.Fab")
		)
		(pad "1" smd rect
			(at 0 0 90)
			(size 0.508 0.508)
			(layers "B.Cu" "B.Mask" "B.Paste")
			(net "PWRGD_P5V_R")
		)
		(pad "2" smd rect
			(at 0 0.889 90)
			(size 0.508 0.508)
			(layers "B.Cu" "B.Mask" "B.Paste")
			(net "PWRGD_P5V")
		)
		(zone
			(layer "B.Cu")
			(hatch none 0.5)
			(connect_pads
				(clearance 0)
			)
			(min_thickness 0.25)
			(keepout
				(tracks allowed)
				(vias not_allowed)
				(pads allowed)
				(copperpour not_allowed)
				(footprints allowed)
			)
			(placement
				(enabled no)
				(sheetname "")
			)
			(fill
				(thermal_gap 0.5)
				(thermal_bridge_width 0.5)
				(island_removal_mode 0)
			)
			(polygon
				(pts
					(xy 413.9565 -4.064) (xy 413.9565 -4.572) (xy 413.5755 -4.572) (xy 413.5755 -4.064)
				)
			)
		)
		(zone
			(layer "B.Cu")
			(hatch none 0.5)
			(connect_pads
				(clearance 0)
			)
			(min_thickness 0.25)
			(keepout
				(tracks not_allowed)
				(vias allowed)
				(pads allowed)
				(copperpour not_allowed)
				(footprints allowed)
			)
			(placement
				(enabled no)
				(sheetname "")
			)
			(fill
				(thermal_gap 0.5)
				(thermal_bridge_width 0.5)
				(island_removal_mode 0)
			)
			(polygon
				(pts
					(xy 413.9565 -4.064) (xy 413.9565 -4.572) (xy 413.5755 -4.572) (xy 413.5755 -4.064)
				)
			)
		)
	)
	(footprint ""
		(layer "B.Cu")
		(at 348.57436 -77.788516 180)
		(property "Reference" "C3P25"
			(at 0 0 0)
			(layer "B.SilkS")
			(hide yes)
			(effects
				(font
					(size 1.27 1.27)
				)
				(justify mirror)
			)
		)
		(property "Value" ""
			(at 0 0 0)
			(layer "B.Fab")
			(effects
				(font
					(size 1.27 1.27)
				)
				(justify mirror)
			)
		)
		(duplicate_pad_numbers_are_jumpers no)
		(fp_poly
			(pts
				(xy -0.3048 -0.1016) (xy -0.3048 0.9906) (xy 0.3048 0.9906) (xy 0.3048 -0.1016)
			)
			(stroke
				(width 0)
				(type default)
			)
			(fill no)
			(layer "B.CrtYd")
		)
		(fp_line
			(start 0.3048 0.9906)
			(end -0.3048 0.9906)
			(stroke
				(width 0.1)
				(type default)
			)
			(layer "B.Fab")
		)
		(fp_line
			(start 0.3048 -0.1016)
			(end 0.3048 0.9906)
			(stroke
				(width 0.1)
				(type default)
			)
			(layer "B.Fab")
		)
		(fp_line
			(start -0.3048 0.9906)
			(end -0.3048 -0.1016)
			(stroke
				(width 0.1)
				(type default)
			)
			(layer "B.Fab")
		)
		(fp_line
			(start -0.3048 -0.1016)
			(end 0.3048 -0.1016)
			(stroke
				(width 0.1)
				(type default)
			)
			(layer "B.Fab")
		)
		(pad "1" smd rect
			(at 0 0)
			(size 0.508 0.508)
			(layers "B.Cu" "B.Mask" "B.Paste")
			(net "P3E_CPU0_PE1_SS_TXN<3>")
		)
		(pad "2" smd rect
			(at 0 0.889)
			(size 0.508 0.508)
			(layers "B.Cu" "B.Mask" "B.Paste")
			(net "P3E_CPU0_PE1_PCH_TXN<3>")
		)
		(zone
			(layer "B.Cu")
			(hatch none 0.5)
			(connect_pads
				(clearance 0)
			)
			(min_thickness 0.25)
			(keepout
				(tracks not_allowed)
				(vias allowed)
				(pads allowed)
				(copperpour not_allowed)
				(footprints allowed)
			)
			(placement
				(enabled no)
				(sheetname "")
			)
			(fill
				(thermal_gap 0.5)
				(thermal_bridge_width 0.5)
				(island_removal_mode 0)
			)
			(polygon
				(pts
					(xy 348.32036 -78.423516) (xy 348.82836 -78.423516) (xy 348.82836 -78.042516) (xy 348.32036 -78.042516)
				)
			)
		)
		(zone
			(layer "B.Cu")
			(hatch none 0.5)
			(connect_pads
				(clearance 0)
			)
			(min_thickness 0.25)
			(keepout
				(tracks allowed)
				(vias not_allowed)
				(pads allowed)
				(copperpour not_allowed)
				(footprints allowed)
			)
			(placement
				(enabled no)
				(sheetname "")
			)
			(fill
				(thermal_gap 0.5)
				(thermal_bridge_width 0.5)
				(island_removal_mode 0)
			)
			(polygon
				(pts
					(xy 348.32036 -78.042516) (xy 348.82836 -78.042516) (xy 348.82836 -78.423516) (xy 348.32036 -78.423516)
				)
			)
		)
	)
	(footprint ""
		(layer "B.Cu")
		(at 371.8306 -51.3207 180)
		(property "Reference" "R3P32"
			(at 0 0 0)
			(layer "B.SilkS")
			(hide yes)
			(effects
				(font
					(size 1.27 1.27)
				)
				(justify mirror)
			)
		)
		(property "Value" ""
			(at 0 0 0)
			(layer "B.Fab")
			(effects
				(font
					(size 1.27 1.27)
				)
				(justify mirror)
			)
		)
		(duplicate_pad_numbers_are_jumpers no)
		(fp_poly
			(pts
				(xy 0.2794 -0.1016) (xy -0.2794 -0.1016) (xy -0.2794 0.9906) (xy 0.2794 0.9906)
			)
			(stroke
				(width 0)
				(type default)
			)
			(fill no)
			(layer "B.CrtYd")
		)
		(fp_line
			(start 0.2794 0.9906)
			(end -0.2794 0.9906)
			(stroke
				(width 0.1)
				(type default)
			)
			(layer "B.Fab")
		)
		(fp_line
			(start 0.2794 -0.1016)
			(end 0.2794 0.9906)
			(stroke
				(width 0.1)
				(type default)
			)
			(layer "B.Fab")
		)
		(fp_line
			(start -0.2794 0.9906)
			(end -0.2794 -0.1016)
			(stroke
				(width 0.1)
				(type default)
			)
			(layer "B.Fab")
		)
		(fp_line
			(start -0.2794 -0.1016)
			(end 0.2794 -0.1016)
			(stroke
				(width 0.1)
				(type default)
			)
			(layer "B.Fab")
		)
		(pad "1" smd rect
			(at 0 0)
			(size 0.508 0.508)
			(layers "B.Cu" "B.Mask" "B.Paste")
			(net "GND")
		)
		(pad "2" smd rect
			(at 0 0.889)
			(size 0.508 0.508)
			(layers "B.Cu" "B.Mask" "B.Paste")
			(net "PD_GTL2014_1_VREF")
		)
		(zone
			(layer "B.Cu")
			(hatch none 0.5)
			(connect_pads
				(clearance 0)
			)
			(min_thickness 0.25)
			(keepout
				(tracks not_allowed)
				(vias allowed)
				(pads allowed)
				(copperpour not_allowed)
				(footprints allowed)
			)
			(placement
				(enabled no)
				(sheetname "")
			)
			(fill
				(thermal_gap 0.5)
				(thermal_bridge_width 0.5)
				(island_removal_mode 0)
			)
			(polygon
				(pts
					(xy 371.5766 -51.9557) (xy 372.0846 -51.9557) (xy 372.0846 -51.5747) (xy 371.5766 -51.5747)
				)
			)
		)
		(zone
			(layer "B.Cu")
			(hatch none 0.5)
			(connect_pads
				(clearance 0)
			)
			(min_thickness 0.25)
			(keepout
				(tracks allowed)
				(vias not_allowed)
				(pads allowed)
				(copperpour not_allowed)
				(footprints allowed)
			)
			(placement
				(enabled no)
				(sheetname "")
			)
			(fill
				(thermal_gap 0.5)
				(thermal_bridge_width 0.5)
				(island_removal_mode 0)
			)
			(polygon
				(pts
					(xy 371.5766 -51.5747) (xy 372.0846 -51.5747) (xy 372.0846 -51.9557) (xy 371.5766 -51.9557)
				)
			)
		)
	)
	(footprint ""
		(layer "B.Cu")
		(at 166.497 -74.549)
		(property "Reference" "R6P23"
			(at 0 0 0)
			(layer "B.SilkS")
			(hide yes)
			(effects
				(font
					(size 1.27 1.27)
				)
				(justify mirror)
			)
		)
		(property "Value" ""
			(at 0 0 0)
			(layer "B.Fab")
			(effects
				(font
					(size 1.27 1.27)
				)
				(justify mirror)
			)
		)
		(duplicate_pad_numbers_are_jumpers no)
		(fp_poly
			(pts
				(xy 0.2794 -0.1016) (xy -0.2794 -0.1016) (xy -0.2794 0.9906) (xy 0.2794 0.9906)
			)
			(stroke
				(width 0)
				(type default)
			)
			(fill no)
			(layer "B.CrtYd")
		)
		(fp_line
			(start -0.2794 -0.1016)
			(end 0.2794 -0.1016)
			(stroke
				(width 0.1)
				(type default)
			)
			(layer "B.Fab")
		)
		(fp_line
			(start -0.2794 0.9906)
			(end -0.2794 -0.1016)
			(stroke
				(width 0.1)
				(type default)
			)
			(layer "B.Fab")
		)
		(fp_line
			(start 0.2794 -0.1016)
			(end 0.2794 0.9906)
			(stroke
				(width 0.1)
				(type default)
			)
			(layer "B.Fab")
		)
		(fp_line
			(start 0.2794 0.9906)
			(end -0.2794 0.9906)
			(stroke
				(width 0.1)
				(type default)
			)
			(layer "B.Fab")
		)
		(pad "1" smd rect
			(at 0 0 180)
			(size 0.508 0.508)
			(layers "B.Cu" "B.Mask" "B.Paste")
			(net "FM_100M_N")
		)
		(pad "2" smd rect
			(at 0 0.889 180)
			(size 0.508 0.508)
			(layers "B.Cu" "B.Mask" "B.Paste")
			(net "GND")
		)
		(zone
			(layer "B.Cu")
			(hatch none 0.5)
			(connect_pads
				(clearance 0)
			)
			(min_thickness 0.25)
			(keepout
				(tracks allowed)
				(vias not_allowed)
				(pads allowed)
				(copperpour not_allowed)
				(footprints allowed)
			)
			(placement
				(enabled no)
				(sheetname "")
			)
			(fill
				(thermal_gap 0.5)
				(thermal_bridge_width 0.5)
				(island_removal_mode 0)
			)
			(polygon
				(pts
					(xy 166.751 -74.295) (xy 166.243 -74.295) (xy 166.243 -73.914) (xy 166.751 -73.914)
				)
			)
		)
		(zone
			(layer "B.Cu")
			(hatch none 0.5)
			(connect_pads
				(clearance 0)
			)
			(min_thickness 0.25)
			(keepout
				(tracks not_allowed)
				(vias allowed)
				(pads allowed)
				(copperpour not_allowed)
				(footprints allowed)
			)
			(placement
				(enabled no)
				(sheetname "")
			)
			(fill
				(thermal_gap 0.5)
				(thermal_bridge_width 0.5)
				(island_removal_mode 0)
			)
			(polygon
				(pts
					(xy 166.751 -73.914) (xy 166.243 -73.914) (xy 166.243 -74.295) (xy 166.751 -74.295)
				)
			)
		)
	)
	(footprint ""
		(layer "B.Cu")
		(at 392.041888 -115.315746 90)
		(property "Reference" "C2M16"
			(at 0 0 90)
			(layer "B.SilkS")
			(hide yes)
			(effects
				(font
					(size 1.27 1.27)
				)
				(justify mirror)
			)
		)
		(property "Value" ""
			(at 0 0 90)
			(layer "B.Fab")
			(effects
				(font
					(size 1.27 1.27)
				)
				(justify mirror)
			)
		)
		(duplicate_pad_numbers_are_jumpers no)
		(fp_poly
			(pts
				(xy -0.3048 -0.1016) (xy -0.3048 0.9906) (xy 0.3048 0.9906) (xy 0.3048 -0.1016)
			)
			(stroke
				(width 0)
				(type default)
			)
			(fill no)
			(layer "B.CrtYd")
		)
		(fp_line
			(start 0.3048 -0.1016)
			(end 0.3048 0.9906)
			(stroke
				(width 0.1)
				(type default)
			)
			(layer "B.Fab")
		)
		(fp_line
			(start -0.3048 -0.1016)
			(end 0.3048 -0.1016)
			(stroke
				(width 0.1)
				(type default)
			)
			(layer "B.Fab")
		)
		(fp_line
			(start 0.3048 0.9906)
			(end -0.3048 0.9906)
			(stroke
				(width 0.1)
				(type default)
			)
			(layer "B.Fab")
		)
		(fp_line
			(start -0.3048 0.9906)
			(end -0.3048 -0.1016)
			(stroke
				(width 0.1)
				(type default)
			)
			(layer "B.Fab")
		)
		(pad "1" smd rect
			(at 0 0 270)
			(size 0.508 0.508)
			(layers "B.Cu" "B.Mask" "B.Paste")
			(net "P3V3_STBY")
		)
		(pad "2" smd rect
			(at 0 0.889 270)
			(size 0.508 0.508)
			(layers "B.Cu" "B.Mask" "B.Paste")
			(net "GND")
		)
		(zone
			(layer "B.Cu")
			(hatch none 0.5)
			(connect_pads
				(clearance 0)
			)
			(min_thickness 0.25)
			(keepout
				(tracks allowed)
				(vias not_allowed)
				(pads allowed)
				(copperpour not_allowed)
				(footprints allowed)
			)
			(placement
				(enabled no)
				(sheetname "")
			)
			(fill
				(thermal_gap 0.5)
				(thermal_bridge_width 0.5)
				(island_removal_mode 0)
			)
			(polygon
				(pts
					(xy 392.295888 -115.569746) (xy 392.295888 -115.061746) (xy 392.676888 -115.061746) (xy 392.676888 -115.569746)
				)
			)
		)
		(zone
			(layer "B.Cu")
			(hatch none 0.5)
			(connect_pads
				(clearance 0)
			)
			(min_thickness 0.25)
			(keepout
				(tracks not_allowed)
				(vias allowed)
				(pads allowed)
				(copperpour not_allowed)
				(footprints allowed)
			)
			(placement
				(enabled no)
				(sheetname "")
			)
			(fill
				(thermal_gap 0.5)
				(thermal_bridge_width 0.5)
				(island_removal_mode 0)
			)
			(polygon
				(pts
					(xy 392.676888 -115.569746) (xy 392.676888 -115.061746) (xy 392.295888 -115.061746) (xy 392.295888 -115.569746)
				)
			)
		)
	)
	(footprint ""
		(layer "B.Cu")
		(at 28.564332 -31.06674 -90)
		(property "Reference" "R12W13"
			(at 0 0 90)
			(layer "B.SilkS")
			(hide yes)
			(effects
				(font
					(size 1.27 1.27)
				)
				(justify mirror)
			)
		)
		(property "Value" "*"
			(at -0.064008 -4.108196 270)
			(unlocked yes)
			(layer "B.Fab")
			(hide yes)
			(effects
				(font
					(size 1.27 1.016)
					(thickness 0.1524)
				)
				(justify mirror)
			)
		)
		(property "Device Type" "4D02R2F-GP_SMD-RG2-4D02R2F-GP,A"
			(at -0.064008 -5.632196 270)
			(unlocked yes)
			(layer "B.Fab")
			(hide yes)
			(effects
				(font
					(size 1.27 1.016)
					(thickness 0.1524)
				)
				(justify mirror)
			)
		)
		(duplicate_pad_numbers_are_jumpers no)
		(fp_line
			(start -0.508 -0.9398)
			(end 0.508 -0.9398)
			(stroke
				(width 0.1524)
				(type default)
			)
			(layer "B.SilkS")
		)
		(fp_line
			(start 0.508 -0.9398)
			(end 0.508 0.9398)
			(stroke
				(width 0.1524)
				(type default)
			)
			(layer "B.SilkS")
		)
		(fp_rect
			(start 0.508 0.9398)
			(end -0.508 -0.9398)
			(stroke
				(width 0)
				(type default)
			)
			(fill no)
			(layer "B.CrtYd")
		)
		(fp_rect
			(start 0.508 0.9398)
			(end -0.508 -0.9398)
			(stroke
				(width 0)
				(type default)
			)
			(fill no)
			(layer "B.Fab")
		)
		(pad "1" smd custom
			(at 0 -0.4445 90)
			(size 0.1397 0.1397)
			(layers "B.Cu" "B.Mask" "B.Paste")
			(net "P12V_STBY")
			(options
				(clearance outline)
				(anchor circle)
			)
			(primitives
				(gr_poly
					(pts
						(arc
							(start -0.1778 0.2794)
							(mid -0.249642 0.249642)
							(end -0.2794 0.1778)
						)
						(arc
							(start -0.2794 -0.1778)
							(mid -0.249642 -0.249642)
							(end -0.1778 -0.2794)
						)
						(arc
							(start 0.1778 -0.2794)
							(mid 0.249642 -0.249642)
							(end 0.2794 -0.1778)
						)
						(arc
							(start 0.2794 0.1778)
							(mid 0.249642 0.249642)
							(end 0.1778 0.2794)
						)
					)
					(width 0)
					(fill yes)
				)
			)
		)
		(pad "2" smd custom
			(at 0 0.4445 90)
			(size 0.1397 0.1397)
			(layers "B.Cu" "B.Mask" "B.Paste")
			(net "P12V_NVDIMM_GHJ_D")
			(options
				(clearance outline)
				(anchor circle)
			)
			(primitives
				(gr_poly
					(pts
						(arc
							(start -0.1778 0.2794)
							(mid -0.249642 0.249642)
							(end -0.2794 0.1778)
						)
						(arc
							(start -0.2794 -0.1778)
							(mid -0.249642 -0.249642)
							(end -0.1778 -0.2794)
						)
						(arc
							(start 0.1778 -0.2794)
							(mid 0.249642 -0.249642)
							(end 0.2794 -0.1778)
						)
						(arc
							(start 0.2794 0.1778)
							(mid 0.249642 0.249642)
							(end 0.1778 0.2794)
						)
					)
					(width 0)
					(fill yes)
				)
			)
		)
	)
	(footprint ""
		(layer "B.Cu")
		(at 20.14982 -134.965694 -90)
		(property "Reference" "R9M20"
			(at 0 0 90)
			(layer "B.SilkS")
			(hide yes)
			(effects
				(font
					(size 1.27 1.27)
				)
				(justify mirror)
			)
		)
		(property "Value" ""
			(at 0 0 90)
			(layer "B.Fab")
			(effects
				(font
					(size 1.27 1.27)
				)
				(justify mirror)
			)
		)
		(duplicate_pad_numbers_are_jumpers no)
		(fp_poly
			(pts
				(xy 0.2794 -0.1016) (xy -0.2794 -0.1016) (xy -0.2794 0.9906) (xy 0.2794 0.9906)
			)
			(stroke
				(width 0)
				(type default)
			)
			(fill no)
			(layer "B.CrtYd")
		)
		(fp_line
			(start -0.2794 0.9906)
			(end -0.2794 -0.1016)
			(stroke
				(width 0.1)
				(type default)
			)
			(layer "B.Fab")
		)
		(fp_line
			(start 0.2794 0.9906)
			(end -0.2794 0.9906)
			(stroke
				(width 0.1)
				(type default)
			)
			(layer "B.Fab")
		)
		(fp_line
			(start -0.2794 -0.1016)
			(end 0.2794 -0.1016)
			(stroke
				(width 0.1)
				(type default)
			)
			(layer "B.Fab")
		)
		(fp_line
			(start 0.2794 -0.1016)
			(end 0.2794 0.9906)
			(stroke
				(width 0.1)
				(type default)
			)
			(layer "B.Fab")
		)
		(pad "1" smd rect
			(at 0 0 90)
			(size 0.508 0.508)
			(layers "B.Cu" "B.Mask" "B.Paste")
			(net "SMB_LAN_STBY_LVC3_SCL")
		)
		(pad "2" smd rect
			(at 0 0.889 90)
			(size 0.508 0.508)
			(layers "B.Cu" "B.Mask" "B.Paste")
			(net "SMB_PIROM_CPU1_SCL")
		)
		(zone
			(layer "B.Cu")
			(hatch none 0.5)
			(connect_pads
				(clearance 0)
			)
			(min_thickness 0.25)
			(keepout
				(tracks not_allowed)
				(vias allowed)
				(pads allowed)
				(copperpour not_allowed)
				(footprints allowed)
			)
			(placement
				(enabled no)
				(sheetname "")
			)
			(fill
				(thermal_gap 0.5)
				(thermal_bridge_width 0.5)
				(island_removal_mode 0)
			)
			(polygon
				(pts
					(xy 19.51482 -134.711694) (xy 19.51482 -135.219694) (xy 19.89582 -135.219694) (xy 19.89582 -134.711694)
				)
			)
		)
		(zone
			(layer "B.Cu")
			(hatch none 0.5)
			(connect_pads
				(clearance 0)
			)
			(min_thickness 0.25)
			(keepout
				(tracks allowed)
				(vias not_allowed)
				(pads allowed)
				(copperpour not_allowed)
				(footprints allowed)
			)
			(placement
				(enabled no)
				(sheetname "")
			)
			(fill
				(thermal_gap 0.5)
				(thermal_bridge_width 0.5)
				(island_removal_mode 0)
			)
			(polygon
				(pts
					(xy 19.89582 -134.711694) (xy 19.89582 -135.219694) (xy 19.51482 -135.219694) (xy 19.51482 -134.711694)
				)
			)
		)
	)
	(footprint ""
		(layer "B.Cu")
		(at -3.22326 -121.47296 180)
		(property "Reference" "R9M14"
			(at 0 0 0)
			(layer "B.SilkS")
			(hide yes)
			(effects
				(font
					(size 1.27 1.27)
				)
				(justify mirror)
			)
		)
		(property "Value" ""
			(at 0 0 0)
			(layer "B.Fab")
			(effects
				(font
					(size 1.27 1.27)
				)
				(justify mirror)
			)
		)
		(duplicate_pad_numbers_are_jumpers no)
		(fp_rect
			(start 0.2794 -0.1016)
			(end -0.2794 0.9906)
			(stroke
				(width 0)
				(type default)
			)
			(fill no)
			(layer "B.CrtYd")
		)
		(fp_line
			(start 0.2794 0.9906)
			(end -0.2794 0.9906)
			(stroke
				(width 0.1)
				(type default)
			)
			(layer "B.Fab")
		)
		(fp_line
			(start 0.2794 -0.1016)
			(end 0.2794 0.9906)
			(stroke
				(width 0.1)
				(type default)
			)
			(layer "B.Fab")
		)
		(fp_line
			(start -0.2794 0.9906)
			(end -0.2794 -0.1016)
			(stroke
				(width 0.1)
				(type default)
			)
			(layer "B.Fab")
		)
		(fp_line
			(start -0.2794 -0.1016)
			(end 0.2794 -0.1016)
			(stroke
				(width 0.1)
				(type default)
			)
			(layer "B.Fab")
		)
		(pad "1" smd rect
			(at 0 0)
			(size 0.508 0.508)
			(layers "B.Cu" "B.Mask" "B.Paste")
			(net "SMB_PEHPCPU1_STBY_LVC3_R_SCL")
		)
		(pad "2" smd rect
			(at 0 0.889)
			(size 0.508 0.508)
			(layers "B.Cu" "B.Mask" "B.Paste")
			(net "SMB_PEHPCPU1_STBY_LVC3_SCL")
		)
		(zone
			(layer "B.Cu")
			(hatch none 0.5)
			(connect_pads
				(clearance 0)
			)
			(min_thickness 0.25)
			(keepout
				(tracks not_allowed)
				(vias allowed)
				(pads allowed)
				(copperpour not_allowed)
				(footprints allowed)
			)
			(placement
				(enabled no)
				(sheetname "")
			)
			(fill
				(thermal_gap 0.5)
				(thermal_bridge_width 0.5)
				(island_removal_mode 0)
			)
			(polygon
				(pts
					(xy -3.47726 -121.72696) (xy -2.96926 -121.72696) (xy -2.96926 -122.10796) (xy -3.47726 -122.10796)
				)
			)
		)
		(zone
			(layer "B.Cu")
			(hatch none 0.5)
			(connect_pads
				(clearance 0)
			)
			(min_thickness 0.25)
			(keepout
				(tracks allowed)
				(vias not_allowed)
				(pads allowed)
				(copperpour not_allowed)
				(footprints allowed)
			)
			(placement
				(enabled no)
				(sheetname "")
			)
			(fill
				(thermal_gap 0.5)
				(thermal_bridge_width 0.5)
				(island_removal_mode 0)
			)
			(polygon
				(pts
					(xy -3.47726 -121.72696) (xy -2.96926 -121.72696) (xy -2.96926 -122.10796) (xy -3.47726 -122.10796)
				)
			)
		)
	)
	(footprint ""
		(layer "B.Cu")
		(at 185.2549 -127.3048 180)
		(property "Reference" "R12W9"
			(at -1.01473 0.656336 270)
			(unlocked yes)
			(layer "B.SilkS")
			(effects
				(font
					(size 0.4064 0.254)
					(thickness 0.1524)
				)
				(justify mirror)
			)
		)
		(property "Value" ""
			(at 0 0 0)
			(layer "B.Fab")
			(effects
				(font
					(size 1.27 1.27)
				)
				(justify mirror)
			)
		)
		(duplicate_pad_numbers_are_jumpers no)
		(fp_poly
			(pts
				(xy 0.4953 -0.2032) (xy -0.4953 -0.2032) (xy -0.4953 1.6002) (xy 0.4953 1.6002)
			)
			(stroke
				(width 0)
				(type default)
			)
			(fill no)
			(layer "B.CrtYd")
		)
		(fp_line
			(start 0.4953 1.6002)
			(end 0.4953 -0.2032)
			(stroke
				(width 0.1)
				(type default)
			)
			(layer "B.Fab")
		)
		(fp_line
			(start 0.4953 -0.2032)
			(end -0.4953 -0.2032)
			(stroke
				(width 0.1)
				(type default)
			)
			(layer "B.Fab")
		)
		(fp_line
			(start -0.4953 1.6002)
			(end 0.4953 1.6002)
			(stroke
				(width 0.1)
				(type default)
			)
			(layer "B.Fab")
		)
		(fp_line
			(start -0.4953 -0.2032)
			(end -0.4953 1.6002)
			(stroke
				(width 0.1)
				(type default)
			)
			(layer "B.Fab")
		)
		(pad "1" smd rect
			(at 0 0)
			(size 0.762 0.889)
			(layers "B.Cu" "B.Mask" "B.Paste")
			(net "P12V_NVDIMM_DEF")
		)
		(pad "2" smd rect
			(at 0 1.397)
			(size 0.762 0.889)
			(layers "B.Cu" "B.Mask" "B.Paste")
			(net "PWRGD_PVDDQ_DEF_N")
		)
		(zone
			(layer "B.Cu")
			(hatch none 0.5)
			(connect_pads
				(clearance 0)
			)
			(min_thickness 0.25)
			(keepout
				(tracks not_allowed)
				(vias allowed)
				(pads allowed)
				(copperpour not_allowed)
				(footprints allowed)
			)
			(placement
				(enabled no)
				(sheetname "")
			)
			(fill
				(thermal_gap 0.5)
				(thermal_bridge_width 0.5)
				(island_removal_mode 0)
			)
			(polygon
				(pts
					(xy 184.8739 -128.2573) (xy 184.8739 -127.7493) (xy 185.6359 -127.7493) (xy 185.6359 -128.2573)
				)
			)
		)
		(zone
			(layer "B.Cu")
			(hatch none 0.5)
			(connect_pads
				(clearance 0)
			)
			(min_thickness 0.25)
			(keepout
				(tracks allowed)
				(vias not_allowed)
				(pads allowed)
				(copperpour not_allowed)
				(footprints allowed)
			)
			(placement
				(enabled no)
				(sheetname "")
			)
			(fill
				(thermal_gap 0.5)
				(thermal_bridge_width 0.5)
				(island_removal_mode 0)
			)
			(polygon
				(pts
					(xy 185.6359 -128.2573) (xy 185.6359 -127.7493) (xy 184.8739 -127.7493) (xy 184.8739 -128.2573)
				)
			)
		)
	)
	(footprint ""
		(layer "B.Cu")
		(at 427.4185 -23.368 90)
		(property "Reference" "R1U4"
			(at 0 0 90)
			(layer "B.SilkS")
			(hide yes)
			(effects
				(font
					(size 1.27 1.27)
				)
				(justify mirror)
			)
		)
		(property "Value" ""
			(at 0 0 90)
			(layer "B.Fab")
			(effects
				(font
					(size 1.27 1.27)
				)
				(justify mirror)
			)
		)
		(duplicate_pad_numbers_are_jumpers no)
		(fp_poly
			(pts
				(xy 0.2794 -0.1016) (xy -0.2794 -0.1016) (xy -0.2794 0.9906) (xy 0.2794 0.9906)
			)
			(stroke
				(width 0)
				(type default)
			)
			(fill no)
			(layer "B.CrtYd")
		)
		(fp_line
			(start 0.2794 -0.1016)
			(end 0.2794 0.9906)
			(stroke
				(width 0.1)
				(type default)
			)
			(layer "B.Fab")
		)
		(fp_line
			(start -0.2794 -0.1016)
			(end 0.2794 -0.1016)
			(stroke
				(width 0.1)
				(type default)
			)
			(layer "B.Fab")
		)
		(fp_line
			(start 0.2794 0.9906)
			(end -0.2794 0.9906)
			(stroke
				(width 0.1)
				(type default)
			)
			(layer "B.Fab")
		)
		(fp_line
			(start -0.2794 0.9906)
			(end -0.2794 -0.1016)
			(stroke
				(width 0.1)
				(type default)
			)
			(layer "B.Fab")
		)
		(pad "1" smd rect
			(at 0 0 270)
			(size 0.508 0.508)
			(layers "B.Cu" "B.Mask" "B.Paste")
			(net "FAN_TACH1")
		)
		(pad "2" smd rect
			(at 0 0.889 270)
			(size 0.508 0.508)
			(layers "B.Cu" "B.Mask" "B.Paste")
			(net "GND")
		)
		(zone
			(layer "B.Cu")
			(hatch none 0.5)
			(connect_pads
				(clearance 0)
			)
			(min_thickness 0.25)
			(keepout
				(tracks allowed)
				(vias not_allowed)
				(pads allowed)
				(copperpour not_allowed)
				(footprints allowed)
			)
			(placement
				(enabled no)
				(sheetname "")
			)
			(fill
				(thermal_gap 0.5)
				(thermal_bridge_width 0.5)
				(island_removal_mode 0)
			)
			(polygon
				(pts
					(xy 427.6725 -23.622) (xy 427.6725 -23.114) (xy 428.0535 -23.114) (xy 428.0535 -23.622)
				)
			)
		)
		(zone
			(layer "B.Cu")
			(hatch none 0.5)
			(connect_pads
				(clearance 0)
			)
			(min_thickness 0.25)
			(keepout
				(tracks not_allowed)
				(vias allowed)
				(pads allowed)
				(copperpour not_allowed)
				(footprints allowed)
			)
			(placement
				(enabled no)
				(sheetname "")
			)
			(fill
				(thermal_gap 0.5)
				(thermal_bridge_width 0.5)
				(island_removal_mode 0)
			)
			(polygon
				(pts
					(xy 428.0535 -23.622) (xy 428.0535 -23.114) (xy 427.6725 -23.114) (xy 427.6725 -23.622)
				)
			)
		)
	)
	(footprint ""
		(layer "B.Cu")
		(at 372.4275 -138.049 -90)
		(property "Reference" "C3M18"
			(at 0 0 90)
			(layer "B.SilkS")
			(hide yes)
			(effects
				(font
					(size 1.27 1.27)
				)
				(justify mirror)
			)
		)
		(property "Value" ""
			(at 0 0 90)
			(layer "B.Fab")
			(effects
				(font
					(size 1.27 1.27)
				)
				(justify mirror)
			)
		)
		(duplicate_pad_numbers_are_jumpers no)
		(fp_poly
			(pts
				(xy 0.4953 -0.2032) (xy -0.4953 -0.2032) (xy -0.4953 1.6002) (xy 0.4953 1.6002)
			)
			(stroke
				(width 0)
				(type default)
			)
			(fill no)
			(layer "B.CrtYd")
		)
		(fp_line
			(start -0.4953 1.6002)
			(end 0.4953 1.6002)
			(stroke
				(width 0.1)
				(type default)
			)
			(layer "B.Fab")
		)
		(fp_line
			(start 0.4953 1.6002)
			(end 0.4953 -0.2032)
			(stroke
				(width 0.1)
				(type default)
			)
			(layer "B.Fab")
		)
		(fp_line
			(start -0.4953 -0.2032)
			(end -0.4953 1.6002)
			(stroke
				(width 0.1)
				(type default)
			)
			(layer "B.Fab")
		)
		(fp_line
			(start 0.4953 -0.2032)
			(end -0.4953 -0.2032)
			(stroke
				(width 0.1)
				(type default)
			)
			(layer "B.Fab")
		)
		(pad "1" smd rect
			(at 0 0 90)
			(size 0.762 0.889)
			(layers "B.Cu" "B.Mask" "B.Paste")
			(net "P1V05_PCH_STBY_VCCA_PLL0")
		)
		(pad "2" smd rect
			(at 0 1.397 90)
			(size 0.762 0.889)
			(layers "B.Cu" "B.Mask" "B.Paste")
			(net "GND")
		)
		(zone
			(layer "B.Cu")
			(hatch none 0.5)
			(connect_pads
				(clearance 0)
			)
			(min_thickness 0.25)
			(keepout
				(tracks not_allowed)
				(vias allowed)
				(pads allowed)
				(copperpour not_allowed)
				(footprints allowed)
			)
			(placement
				(enabled no)
				(sheetname "")
			)
			(fill
				(thermal_gap 0.5)
				(thermal_bridge_width 0.5)
				(island_removal_mode 0)
			)
			(polygon
				(pts
					(xy 371.983 -137.668) (xy 371.983 -138.43) (xy 371.475 -138.43) (xy 371.475 -137.668)
				)
			)
		)
	)
	(footprint ""
		(layer "B.Cu")
		(at 259.5626 -140.081 90)
		(property "Reference" "C5G78"
			(at -1.64973 0.78994 180)
			(unlocked yes)
			(layer "B.SilkS")
			(effects
				(font
					(size 0.7874 0.5842)
					(thickness 0.1524)
				)
				(justify mirror)
			)
		)
		(property "Value" ""
			(at 0 0 90)
			(layer "B.Fab")
			(effects
				(font
					(size 1.27 1.27)
				)
				(justify mirror)
			)
		)
		(duplicate_pad_numbers_are_jumpers no)
		(fp_rect
			(start -0.7239 -0.2159)
			(end 0.7239 1.9939)
			(stroke
				(width 0)
				(type default)
			)
			(fill no)
			(layer "B.CrtYd")
		)
		(fp_line
			(start 0.7239 -0.2159)
			(end 0.7239 1.9939)
			(stroke
				(width 0.1)
				(type default)
			)
			(layer "B.Fab")
		)
		(fp_line
			(start -0.7239 -0.2159)
			(end 0.7239 -0.2159)
			(stroke
				(width 0.1)
				(type default)
			)
			(layer "B.Fab")
		)
		(fp_line
			(start 0.7239 1.9939)
			(end -0.7239 1.9939)
			(stroke
				(width 0.1)
				(type default)
			)
			(layer "B.Fab")
		)
		(fp_line
			(start -0.7239 1.9939)
			(end -0.7239 -0.2159)
			(stroke
				(width 0.1)
				(type default)
			)
			(layer "B.Fab")
		)
		(pad "1" smd rect
			(at 0 0 270)
			(size 1.27 1.016)
			(layers "B.Cu" "B.Mask" "B.Paste")
			(net "PVDDQ_DEF")
		)
		(pad "2" smd rect
			(at 0 1.778 270)
			(size 1.27 1.016)
			(layers "B.Cu" "B.Mask" "B.Paste")
			(net "GND")
		)
		(zone
			(layer "B.Cu")
			(hatch none 0.5)
			(connect_pads
				(clearance 0)
			)
			(min_thickness 0.25)
			(keepout
				(tracks not_allowed)
				(vias allowed)
				(pads allowed)
				(copperpour not_allowed)
				(footprints allowed)
			)
			(placement
				(enabled no)
				(sheetname "")
			)
			(fill
				(thermal_gap 0.5)
				(thermal_bridge_width 0.5)
				(island_removal_mode 0)
			)
			(polygon
				(pts
					(xy 260.0706 -139.446) (xy 260.8326 -139.446) (xy 260.8326 -140.716) (xy 260.0706 -140.716)
				)
			)
		)
	)
	(footprint ""
		(layer "B.Cu")
		(at 28.547568 -144.4752 180)
		(property "Reference" "R9L7"
			(at 0 0 0)
			(layer "B.SilkS")
			(hide yes)
			(effects
				(font
					(size 1.27 1.27)
				)
				(justify mirror)
			)
		)
		(property "Value" ""
			(at 0 0 0)
			(layer "B.Fab")
			(effects
				(font
					(size 1.27 1.27)
				)
				(justify mirror)
			)
		)
		(duplicate_pad_numbers_are_jumpers no)
		(fp_poly
			(pts
				(xy 0.2794 -0.1016) (xy -0.2794 -0.1016) (xy -0.2794 0.9906) (xy 0.2794 0.9906)
			)
			(stroke
				(width 0)
				(type default)
			)
			(fill no)
			(layer "B.CrtYd")
		)
		(fp_line
			(start 0.2794 0.9906)
			(end -0.2794 0.9906)
			(stroke
				(width 0.1)
				(type default)
			)
			(layer "B.Fab")
		)
		(fp_line
			(start 0.2794 -0.1016)
			(end 0.2794 0.9906)
			(stroke
				(width 0.1)
				(type default)
			)
			(layer "B.Fab")
		)
		(fp_line
			(start -0.2794 0.9906)
			(end -0.2794 -0.1016)
			(stroke
				(width 0.1)
				(type default)
			)
			(layer "B.Fab")
		)
		(fp_line
			(start -0.2794 -0.1016)
			(end 0.2794 -0.1016)
			(stroke
				(width 0.1)
				(type default)
			)
			(layer "B.Fab")
		)
		(pad "1" smd rect
			(at 0 0)
			(size 0.508 0.508)
			(layers "B.Cu" "B.Mask" "B.Paste")
			(net "PVDDQ_KLM")
		)
		(pad "2" smd rect
			(at 0 0.889)
			(size 0.508 0.508)
			(layers "B.Cu" "B.Mask" "B.Paste")
			(net "M_L_VREF")
		)
		(zone
			(layer "B.Cu")
			(hatch none 0.5)
			(connect_pads
				(clearance 0)
			)
			(min_thickness 0.25)
			(keepout
				(tracks not_allowed)
				(vias allowed)
				(pads allowed)
				(copperpour not_allowed)
				(footprints allowed)
			)
			(placement
				(enabled no)
				(sheetname "")
			)
			(fill
				(thermal_gap 0.5)
				(thermal_bridge_width 0.5)
				(island_removal_mode 0)
			)
			(polygon
				(pts
					(xy 28.293568 -145.1102) (xy 28.801568 -145.1102) (xy 28.801568 -144.7292) (xy 28.293568 -144.7292)
				)
			)
		)
		(zone
			(layer "B.Cu")
			(hatch none 0.5)
			(connect_pads
				(clearance 0)
			)
			(min_thickness 0.25)
			(keepout
				(tracks allowed)
				(vias not_allowed)
				(pads allowed)
				(copperpour not_allowed)
				(footprints allowed)
			)
			(placement
				(enabled no)
				(sheetname "")
			)
			(fill
				(thermal_gap 0.5)
				(thermal_bridge_width 0.5)
				(island_removal_mode 0)
			)
			(polygon
				(pts
					(xy 28.293568 -144.7292) (xy 28.801568 -144.7292) (xy 28.801568 -145.1102) (xy 28.293568 -145.1102)
				)
			)
		)
	)
	(footprint ""
		(layer "B.Cu")
		(at 92.85986 -149.77872 -90)
		(property "Reference" "C5G97"
			(at -1.14681 0.76708 0)
			(unlocked yes)
			(layer "B.SilkS")
			(effects
				(font
					(size 0.7874 0.5842)
					(thickness 0.1524)
				)
				(justify mirror)
			)
		)
		(property "Value" ""
			(at 0 0 90)
			(layer "B.Fab")
			(effects
				(font
					(size 1.27 1.27)
				)
				(justify mirror)
			)
		)
		(duplicate_pad_numbers_are_jumpers no)
		(fp_rect
			(start -0.4953 -0.2032)
			(end 0.4953 1.6002)
			(stroke
				(width 0)
				(type default)
			)
			(fill no)
			(layer "B.CrtYd")
		)
		(fp_line
			(start -0.4953 1.6002)
			(end 0.4953 1.6002)
			(stroke
				(width 0.1)
				(type default)
			)
			(layer "B.Fab")
		)
		(fp_line
			(start 0.4953 1.6002)
			(end 0.4953 -0.2032)
			(stroke
				(width 0.1)
				(type default)
			)
			(layer "B.Fab")
		)
		(fp_line
			(start -0.4953 -0.2032)
			(end -0.4953 1.6002)
			(stroke
				(width 0.1)
				(type default)
			)
			(layer "B.Fab")
		)
		(fp_line
			(start 0.4953 -0.2032)
			(end -0.4953 -0.2032)
			(stroke
				(width 0.1)
				(type default)
			)
			(layer "B.Fab")
		)
		(pad "1" smd rect
			(at 0 0 90)
			(size 0.762 0.889)
			(layers "B.Cu" "B.Mask" "B.Paste")
			(net "PVDDQ_KLM")
		)
		(pad "2" smd rect
			(at 0 1.397 90)
			(size 0.762 0.889)
			(layers "B.Cu" "B.Mask" "B.Paste")
			(net "GND")
		)
		(zone
			(layer "B.Cu")
			(hatch none 0.5)
			(connect_pads
				(clearance 0)
			)
			(min_thickness 0.25)
			(keepout
				(tracks not_allowed)
				(vias allowed)
				(pads allowed)
				(copperpour not_allowed)
				(footprints allowed)
			)
			(placement
				(enabled no)
				(sheetname "")
			)
			(fill
				(thermal_gap 0.5)
				(thermal_bridge_width 0.5)
				(island_removal_mode 0)
			)
			(polygon
				(pts
					(xy 92.41536 -150.15972) (xy 91.90736 -150.15972) (xy 91.90736 -149.39772) (xy 92.41536 -149.39772)
				)
			)
		)
	)
	(footprint ""
		(layer "B.Cu")
		(at 372.609618 -88.89111 180)
		(property "Reference" "R7C11"
			(at 0 0 0)
			(layer "B.SilkS")
			(hide yes)
			(effects
				(font
					(size 1.27 1.27)
				)
				(justify mirror)
			)
		)
		(property "Value" ""
			(at 0 0 0)
			(layer "B.Fab")
			(effects
				(font
					(size 1.27 1.27)
				)
				(justify mirror)
			)
		)
		(duplicate_pad_numbers_are_jumpers no)
		(fp_poly
			(pts
				(xy 0.2794 -0.1016) (xy -0.2794 -0.1016) (xy -0.2794 0.9906) (xy 0.2794 0.9906)
			)
			(stroke
				(width 0)
				(type default)
			)
			(fill no)
			(layer "B.CrtYd")
		)
		(fp_line
			(start 0.2794 0.9906)
			(end -0.2794 0.9906)
			(stroke
				(width 0.1)
				(type default)
			)
			(layer "B.Fab")
		)
		(fp_line
			(start 0.2794 -0.1016)
			(end 0.2794 0.9906)
			(stroke
				(width 0.1)
				(type default)
			)
			(layer "B.Fab")
		)
		(fp_line
			(start -0.2794 0.9906)
			(end -0.2794 -0.1016)
			(stroke
				(width 0.1)
				(type default)
			)
			(layer "B.Fab")
		)
		(fp_line
			(start -0.2794 -0.1016)
			(end 0.2794 -0.1016)
			(stroke
				(width 0.1)
				(type default)
			)
			(layer "B.Fab")
		)
		(pad "1" smd rect
			(at 0 0)
			(size 0.508 0.508)
			(layers "B.Cu" "B.Mask" "B.Paste")
			(net "GND")
		)
		(pad "2" smd rect
			(at 0 0.889)
			(size 0.508 0.508)
			(layers "B.Cu" "B.Mask" "B.Paste")
			(net "RST_RTCRST_N")
		)
		(zone
			(layer "B.Cu")
			(hatch none 0.5)
			(connect_pads
				(clearance 0)
			)
			(min_thickness 0.25)
			(keepout
				(tracks not_allowed)
				(vias allowed)
				(pads allowed)
				(copperpour not_allowed)
				(footprints allowed)
			)
			(placement
				(enabled no)
				(sheetname "")
			)
			(fill
				(thermal_gap 0.5)
				(thermal_bridge_width 0.5)
				(island_removal_mode 0)
			)
			(polygon
				(pts
					(xy 372.355618 -89.52611) (xy 372.863618 -89.52611) (xy 372.863618 -89.14511) (xy 372.355618 -89.14511)
				)
			)
		)
		(zone
			(layer "B.Cu")
			(hatch none 0.5)
			(connect_pads
				(clearance 0)
			)
			(min_thickness 0.25)
			(keepout
				(tracks allowed)
				(vias not_allowed)
				(pads allowed)
				(copperpour not_allowed)
				(footprints allowed)
			)
			(placement
				(enabled no)
				(sheetname "")
			)
			(fill
				(thermal_gap 0.5)
				(thermal_bridge_width 0.5)
				(island_removal_mode 0)
			)
			(polygon
				(pts
					(xy 372.355618 -89.14511) (xy 372.863618 -89.14511) (xy 372.863618 -89.52611) (xy 372.355618 -89.52611)
				)
			)
		)
	)
	(footprint ""
		(layer "B.Cu")
		(at 16.0782 -84.455 90)
		(property "Reference" "Q9P1"
			(at -2.286 -1.37287 270)
			(unlocked yes)
			(layer "B.SilkS")
			(effects
				(font
					(size 0.7874 0.5842)
					(thickness 0.1524)
				)
				(justify left mirror)
			)
		)
		(property "Value" ""
			(at 0 0 90)
			(layer "B.Fab")
			(effects
				(font
					(size 1.27 1.27)
				)
				(justify mirror)
			)
		)
		(duplicate_pad_numbers_are_jumpers no)
		(fp_circle
			(center 0.848614 -0.6477)
			(end 0.848614 -0.5207)
			(stroke
				(width 0.254)
				(type default)
			)
			(fill no)
			(layer "B.SilkS")
		)
		(fp_poly
			(pts
				(xy -0.21463 -0.450088) (xy -1.56337 -0.450088) (xy -1.56337 1.75006) (xy -0.21463 1.75006)
			)
			(stroke
				(width 0)
				(type default)
			)
			(fill no)
			(layer "B.CrtYd")
		)
		(fp_line
			(start -0.21463 -0.450088)
			(end -1.56337 -0.450088)
			(stroke
				(width 0.1)
				(type default)
			)
			(layer "B.Fab")
		)
		(fp_line
			(start -1.56337 -0.450088)
			(end -1.56337 1.75006)
			(stroke
				(width 0.1)
				(type default)
			)
			(layer "B.Fab")
		)
		(fp_line
			(start -0.21463 1.75006)
			(end -0.21463 -0.450088)
			(stroke
				(width 0.1)
				(type default)
			)
			(layer "B.Fab")
		)
		(fp_line
			(start -1.56337 1.75006)
			(end -0.21463 1.75006)
			(stroke
				(width 0.1)
				(type default)
			)
			(layer "B.Fab")
		)
		(fp_circle
			(center 0.848614 -0.6477)
			(end 0.848614 -0.5207)
			(stroke
				(width 0.254)
				(type default)
			)
			(fill no)
			(layer "B.Fab")
		)
		(pad "1" smd rect
			(at 0 0 270)
			(size 1.016 0.381)
			(layers "B.Cu" "B.Mask" "B.Paste")
			(net "GND")
		)
		(pad "2" smd rect
			(at 0 0.649986 270)
			(size 1.016 0.381)
			(layers "B.Cu" "B.Mask" "B.Paste")
			(net "A_HSC_LOW_GATE")
		)
		(pad "3" smd rect
			(at 0 1.299972 270)
			(size 1.016 0.381)
			(layers "B.Cu" "B.Mask" "B.Paste")
			(net "IRQ_UV_DETECT_N")
		)
		(pad "4" smd rect
			(at -1.778 1.299972 270)
			(size 1.016 0.381)
			(layers "B.Cu" "B.Mask" "B.Paste")
			(net "GND")
		)
		(pad "5" smd rect
			(at -1.778 0.649986 270)
			(size 1.016 0.381)
			(layers "B.Cu" "B.Mask" "B.Paste")
			(net "A_P12V_STBY_FPH_GATE")
		)
		(pad "6" smd rect
			(at -1.778 0 270)
			(size 1.016 0.381)
			(layers "B.Cu" "B.Mask" "B.Paste")
			(net "A_HSC_LOW_DRAIN")
		)
	)
	(footprint ""
		(layer "B.Cu")
		(at 450.5325 -25.273 -90)
		(property "Reference" "R6W23"
			(at 0.8382 -0.67818 270)
			(unlocked yes)
			(layer "B.SilkS")
			(effects
				(font
					(size 0.4064 0.254)
					(thickness 0.1524)
				)
				(justify left mirror)
			)
		)
		(property "Value" ""
			(at 0 0 90)
			(layer "B.Fab")
			(effects
				(font
					(size 1.27 1.27)
				)
				(justify mirror)
			)
		)
		(duplicate_pad_numbers_are_jumpers no)
		(fp_poly
			(pts
				(xy 0.2794 -0.1016) (xy -0.2794 -0.1016) (xy -0.2794 0.9906) (xy 0.2794 0.9906)
			)
			(stroke
				(width 0)
				(type default)
			)
			(fill no)
			(layer "B.CrtYd")
		)
		(fp_line
			(start -0.2794 0.9906)
			(end -0.2794 -0.1016)
			(stroke
				(width 0.1)
				(type default)
			)
			(layer "B.Fab")
		)
		(fp_line
			(start 0.2794 0.9906)
			(end -0.2794 0.9906)
			(stroke
				(width 0.1)
				(type default)
			)
			(layer "B.Fab")
		)
		(fp_line
			(start -0.2794 -0.1016)
			(end 0.2794 -0.1016)
			(stroke
				(width 0.1)
				(type default)
			)
			(layer "B.Fab")
		)
		(fp_line
			(start 0.2794 -0.1016)
			(end 0.2794 0.9906)
			(stroke
				(width 0.1)
				(type default)
			)
			(layer "B.Fab")
		)
		(pad "1" smd rect
			(at 0 0 90)
			(size 0.508 0.508)
			(layers "B.Cu" "B.Mask" "B.Paste")
			(net "PD_ID_EEPROM_WP")
		)
		(pad "2" smd rect
			(at 0 0.889 90)
			(size 0.508 0.508)
			(layers "B.Cu" "B.Mask" "B.Paste")
			(net "GND")
		)
		(zone
			(layer "B.Cu")
			(hatch none 0.5)
			(connect_pads
				(clearance 0)
			)
			(min_thickness 0.25)
			(keepout
				(tracks not_allowed)
				(vias allowed)
				(pads allowed)
				(copperpour not_allowed)
				(footprints allowed)
			)
			(placement
				(enabled no)
				(sheetname "")
			)
			(fill
				(thermal_gap 0.5)
				(thermal_bridge_width 0.5)
				(island_removal_mode 0)
			)
			(polygon
				(pts
					(xy 449.8975 -25.019) (xy 449.8975 -25.527) (xy 450.2785 -25.527) (xy 450.2785 -25.019)
				)
			)
		)
		(zone
			(layer "B.Cu")
			(hatch none 0.5)
			(connect_pads
				(clearance 0)
			)
			(min_thickness 0.25)
			(keepout
				(tracks allowed)
				(vias not_allowed)
				(pads allowed)
				(copperpour not_allowed)
				(footprints allowed)
			)
			(placement
				(enabled no)
				(sheetname "")
			)
			(fill
				(thermal_gap 0.5)
				(thermal_bridge_width 0.5)
				(island_removal_mode 0)
			)
			(polygon
				(pts
					(xy 450.2785 -25.019) (xy 450.2785 -25.527) (xy 449.8975 -25.527) (xy 449.8975 -25.019)
				)
			)
		)
	)
	(footprint ""
		(layer "B.Cu")
		(at 420.624 -23.114 180)
		(property "Reference" "C25W76"
			(at 0.8382 -0.67818 180)
			(unlocked yes)
			(layer "B.SilkS")
			(effects
				(font
					(size 0.4064 0.254)
					(thickness 0.1524)
				)
				(justify left mirror)
			)
		)
		(property "Value" ""
			(at 0 0 0)
			(layer "B.Fab")
			(effects
				(font
					(size 1.27 1.27)
				)
				(justify mirror)
			)
		)
		(duplicate_pad_numbers_are_jumpers no)
		(fp_poly
			(pts
				(xy -0.3048 -0.1016) (xy -0.3048 0.9906) (xy 0.3048 0.9906) (xy 0.3048 -0.1016)
			)
			(stroke
				(width 0)
				(type default)
			)
			(fill no)
			(layer "B.CrtYd")
		)
		(fp_line
			(start 0.3048 0.9906)
			(end -0.3048 0.9906)
			(stroke
				(width 0.1)
				(type default)
			)
			(layer "B.Fab")
		)
		(fp_line
			(start 0.3048 -0.1016)
			(end 0.3048 0.9906)
			(stroke
				(width 0.1)
				(type default)
			)
			(layer "B.Fab")
		)
		(fp_line
			(start -0.3048 0.9906)
			(end -0.3048 -0.1016)
			(stroke
				(width 0.1)
				(type default)
			)
			(layer "B.Fab")
		)
		(fp_line
			(start -0.3048 -0.1016)
			(end 0.3048 -0.1016)
			(stroke
				(width 0.1)
				(type default)
			)
			(layer "B.Fab")
		)
		(pad "1" smd rect
			(at 0 0)
			(size 0.508 0.508)
			(layers "B.Cu" "B.Mask" "B.Paste")
			(net "V_IO_G_J")
		)
		(pad "2" smd rect
			(at 0 0.889)
			(size 0.508 0.508)
			(layers "B.Cu" "B.Mask" "B.Paste")
			(net "GND")
		)
		(zone
			(layer "B.Cu")
			(hatch none 0.5)
			(connect_pads
				(clearance 0)
			)
			(min_thickness 0.25)
			(keepout
				(tracks not_allowed)
				(vias allowed)
				(pads allowed)
				(copperpour not_allowed)
				(footprints allowed)
			)
			(placement
				(enabled no)
				(sheetname "")
			)
			(fill
				(thermal_gap 0.5)
				(thermal_bridge_width 0.5)
				(island_removal_mode 0)
			)
			(polygon
				(pts
					(xy 420.37 -23.749) (xy 420.878 -23.749) (xy 420.878 -23.368) (xy 420.37 -23.368)
				)
			)
		)
		(zone
			(layer "B.Cu")
			(hatch none 0.5)
			(connect_pads
				(clearance 0)
			)
			(min_thickness 0.25)
			(keepout
				(tracks allowed)
				(vias not_allowed)
				(pads allowed)
				(copperpour not_allowed)
				(footprints allowed)
			)
			(placement
				(enabled no)
				(sheetname "")
			)
			(fill
				(thermal_gap 0.5)
				(thermal_bridge_width 0.5)
				(island_removal_mode 0)
			)
			(polygon
				(pts
					(xy 420.37 -23.368) (xy 420.878 -23.368) (xy 420.878 -23.749) (xy 420.37 -23.749)
				)
			)
		)
	)
	(footprint ""
		(layer "B.Cu")
		(at 14.224 -76.1238)
		(property "Reference" "R9P23"
			(at 0 0 0)
			(layer "B.SilkS")
			(hide yes)
			(effects
				(font
					(size 1.27 1.27)
				)
				(justify mirror)
			)
		)
		(property "Value" ""
			(at 0 0 0)
			(layer "B.Fab")
			(effects
				(font
					(size 1.27 1.27)
				)
				(justify mirror)
			)
		)
		(duplicate_pad_numbers_are_jumpers no)
		(fp_poly
			(pts
				(xy 0.2794 -0.1016) (xy -0.2794 -0.1016) (xy -0.2794 0.9906) (xy 0.2794 0.9906)
			)
			(stroke
				(width 0)
				(type default)
			)
			(fill no)
			(layer "B.CrtYd")
		)
		(fp_line
			(start -0.2794 -0.1016)
			(end 0.2794 -0.1016)
			(stroke
				(width 0.1)
				(type default)
			)
			(layer "B.Fab")
		)
		(fp_line
			(start -0.2794 0.9906)
			(end -0.2794 -0.1016)
			(stroke
				(width 0.1)
				(type default)
			)
			(layer "B.Fab")
		)
		(fp_line
			(start 0.2794 -0.1016)
			(end 0.2794 0.9906)
			(stroke
				(width 0.1)
				(type default)
			)
			(layer "B.Fab")
		)
		(fp_line
			(start 0.2794 0.9906)
			(end -0.2794 0.9906)
			(stroke
				(width 0.1)
				(type default)
			)
			(layer "B.Fab")
		)
		(pad "1" smd rect
			(at 0 0 180)
			(size 0.508 0.508)
			(layers "B.Cu" "B.Mask" "B.Paste")
			(net "P12V_STBY")
		)
		(pad "2" smd rect
			(at 0 0.889 180)
			(size 0.508 0.508)
			(layers "B.Cu" "B.Mask" "B.Paste")
			(net "A_HSC_PWGIN")
		)
		(zone
			(layer "B.Cu")
			(hatch none 0.5)
			(connect_pads
				(clearance 0)
			)
			(min_thickness 0.25)
			(keepout
				(tracks allowed)
				(vias not_allowed)
				(pads allowed)
				(copperpour not_allowed)
				(footprints allowed)
			)
			(placement
				(enabled no)
				(sheetname "")
			)
			(fill
				(thermal_gap 0.5)
				(thermal_bridge_width 0.5)
				(island_removal_mode 0)
			)
			(polygon
				(pts
					(xy 14.478 -75.8698) (xy 13.97 -75.8698) (xy 13.97 -75.4888) (xy 14.478 -75.4888)
				)
			)
		)
		(zone
			(layer "B.Cu")
			(hatch none 0.5)
			(connect_pads
				(clearance 0)
			)
			(min_thickness 0.25)
			(keepout
				(tracks not_allowed)
				(vias allowed)
				(pads allowed)
				(copperpour not_allowed)
				(footprints allowed)
			)
			(placement
				(enabled no)
				(sheetname "")
			)
			(fill
				(thermal_gap 0.5)
				(thermal_bridge_width 0.5)
				(island_removal_mode 0)
			)
			(polygon
				(pts
					(xy 14.478 -75.4888) (xy 13.97 -75.4888) (xy 13.97 -75.8698) (xy 14.478 -75.8698)
				)
			)
		)
	)
	(footprint ""
		(layer "B.Cu")
		(at 450.2277 -149.3774 -90)
		(property "Reference" "R25W165"
			(at 0.8382 -0.67818 270)
			(unlocked yes)
			(layer "B.SilkS")
			(effects
				(font
					(size 0.4064 0.254)
					(thickness 0.1524)
				)
				(justify left mirror)
			)
		)
		(property "Value" ""
			(at 0 0 90)
			(layer "B.Fab")
			(effects
				(font
					(size 1.27 1.27)
				)
				(justify mirror)
			)
		)
		(duplicate_pad_numbers_are_jumpers no)
		(fp_poly
			(pts
				(xy 0.2794 -0.1016) (xy -0.2794 -0.1016) (xy -0.2794 0.9906) (xy 0.2794 0.9906)
			)
			(stroke
				(width 0)
				(type default)
			)
			(fill no)
			(layer "B.CrtYd")
		)
		(fp_line
			(start -0.2794 0.9906)
			(end -0.2794 -0.1016)
			(stroke
				(width 0.1)
				(type default)
			)
			(layer "B.Fab")
		)
		(fp_line
			(start 0.2794 0.9906)
			(end -0.2794 0.9906)
			(stroke
				(width 0.1)
				(type default)
			)
			(layer "B.Fab")
		)
		(fp_line
			(start -0.2794 -0.1016)
			(end 0.2794 -0.1016)
			(stroke
				(width 0.1)
				(type default)
			)
			(layer "B.Fab")
		)
		(fp_line
			(start 0.2794 -0.1016)
			(end 0.2794 0.9906)
			(stroke
				(width 0.1)
				(type default)
			)
			(layer "B.Fab")
		)
		(pad "1" smd rect
			(at 0 0 90)
			(size 0.508 0.508)
			(layers "B.Cu" "B.Mask" "B.Paste")
			(net "P0V7_GTL2014_VREF_6")
		)
		(pad "2" smd rect
			(at 0 0.889 90)
			(size 0.508 0.508)
			(layers "B.Cu" "B.Mask" "B.Paste")
			(net "GND")
		)
		(zone
			(layer "B.Cu")
			(hatch none 0.5)
			(connect_pads
				(clearance 0)
			)
			(min_thickness 0.25)
			(keepout
				(tracks not_allowed)
				(vias allowed)
				(pads allowed)
				(copperpour not_allowed)
				(footprints allowed)
			)
			(placement
				(enabled no)
				(sheetname "")
			)
			(fill
				(thermal_gap 0.5)
				(thermal_bridge_width 0.5)
				(island_removal_mode 0)
			)
			(polygon
				(pts
					(xy 449.5927 -149.1234) (xy 449.5927 -149.6314) (xy 449.9737 -149.6314) (xy 449.9737 -149.1234)
				)
			)
		)
		(zone
			(layer "B.Cu")
			(hatch none 0.5)
			(connect_pads
				(clearance 0)
			)
			(min_thickness 0.25)
			(keepout
				(tracks allowed)
				(vias not_allowed)
				(pads allowed)
				(copperpour not_allowed)
				(footprints allowed)
			)
			(placement
				(enabled no)
				(sheetname "")
			)
			(fill
				(thermal_gap 0.5)
				(thermal_bridge_width 0.5)
				(island_removal_mode 0)
			)
			(polygon
				(pts
					(xy 449.9737 -149.1234) (xy 449.9737 -149.6314) (xy 449.5927 -149.6314) (xy 449.5927 -149.1234)
				)
			)
		)
	)
	(footprint ""
		(layer "B.Cu")
		(at 210.847432 -78.867 -90)
		(property "Reference" "C6P14"
			(at -2.00533 -3.909568 0)
			(unlocked yes)
			(layer "B.SilkS")
			(effects
				(font
					(size 0.7874 0.5842)
					(thickness 0.1524)
				)
				(justify mirror)
			)
		)
		(property "Value" ""
			(at 0 0 90)
			(layer "B.Fab")
			(effects
				(font
					(size 1.27 1.27)
				)
				(justify mirror)
			)
		)
		(duplicate_pad_numbers_are_jumpers no)
		(fp_line
			(start -2.286 7.366)
			(end -1.600708 7.366)
			(stroke
				(width 0.1524)
				(type default)
			)
			(layer "B.SilkS")
		)
		(fp_line
			(start -2.286 7.366)
			(end -2.286 1.63195)
			(stroke
				(width 0.1524)
				(type default)
			)
			(layer "B.SilkS")
		)
		(fp_line
			(start 2.286 7.366)
			(end 1.60147 7.366)
			(stroke
				(width 0.1524)
				(type default)
			)
			(layer "B.SilkS")
		)
		(fp_line
			(start 2.286 7.366)
			(end 2.286 1.632712)
			(stroke
				(width 0.1524)
				(type default)
			)
			(layer "B.SilkS")
		)
		(fp_line
			(start -2.504948 1.633728)
			(end -1.6002 1.633728)
			(stroke
				(width 0.1524)
				(type default)
			)
			(layer "B.SilkS")
		)
		(fp_line
			(start 2.563114 1.633728)
			(end 1.6002 1.633728)
			(stroke
				(width 0.1524)
				(type default)
			)
			(layer "B.SilkS")
		)
		(fp_line
			(start -2.504948 -1.616456)
			(end -2.504948 1.633728)
			(stroke
				(width 0.1524)
				(type default)
			)
			(layer "B.SilkS")
		)
		(fp_line
			(start -1.6002 -1.616456)
			(end -2.504948 -1.616456)
			(stroke
				(width 0.1524)
				(type default)
			)
			(layer "B.SilkS")
		)
		(fp_line
			(start 1.6002 -1.616456)
			(end 2.563114 -1.616456)
			(stroke
				(width 0.1524)
				(type default)
			)
			(layer "B.SilkS")
		)
		(fp_line
			(start 2.563114 -1.616456)
			(end 2.563114 1.633728)
			(stroke
				(width 0.1524)
				(type default)
			)
			(layer "B.SilkS")
		)
		(fp_rect
			(start 2.286 7.366)
			(end -2.286 -0.254)
			(stroke
				(width 0)
				(type default)
			)
			(fill no)
			(layer "B.CrtYd")
		)
		(fp_line
			(start -2.286 7.366)
			(end 2.286 7.366)
			(stroke
				(width 0.1)
				(type default)
			)
			(layer "B.Fab")
		)
		(fp_line
			(start 2.286 7.366)
			(end 2.286 -0.254)
			(stroke
				(width 0.1)
				(type default)
			)
			(layer "B.Fab")
		)
		(fp_line
			(start -2.286 -0.254)
			(end -2.286 7.366)
			(stroke
				(width 0.1)
				(type default)
			)
			(layer "B.Fab")
		)
		(fp_line
			(start 2.286 -0.254)
			(end -2.286 -0.254)
			(stroke
				(width 0.1)
				(type default)
			)
			(layer "B.Fab")
		)
		(pad "1" smd rect
			(at 0 0 90)
			(size 2.54 3.048)
			(layers "B.Cu" "B.Mask" "B.Paste")
			(net "PVCCIN_CPU0")
		)
		(pad "2" smd rect
			(at 0 7.112 90)
			(size 2.54 3.048)
			(layers "B.Cu" "B.Mask" "B.Paste")
			(net "GND")
		)
	)
	(footprint ""
		(layer "B.Cu")
		(at 348.57436 -77.788516)
		(property "Reference" "C3P24"
			(at 0 0 0)
			(layer "B.SilkS")
			(hide yes)
			(effects
				(font
					(size 1.27 1.27)
				)
				(justify mirror)
			)
		)
		(property "Value" ""
			(at 0 0 0)
			(layer "B.Fab")
			(effects
				(font
					(size 1.27 1.27)
				)
				(justify mirror)
			)
		)
		(duplicate_pad_numbers_are_jumpers no)
		(fp_poly
			(pts
				(xy -0.3048 -0.1016) (xy -0.3048 0.9906) (xy 0.3048 0.9906) (xy 0.3048 -0.1016)
			)
			(stroke
				(width 0)
				(type default)
			)
			(fill no)
			(layer "B.CrtYd")
		)
		(fp_line
			(start -0.3048 -0.1016)
			(end 0.3048 -0.1016)
			(stroke
				(width 0.1)
				(type default)
			)
			(layer "B.Fab")
		)
		(fp_line
			(start -0.3048 0.9906)
			(end -0.3048 -0.1016)
			(stroke
				(width 0.1)
				(type default)
			)
			(layer "B.Fab")
		)
		(fp_line
			(start 0.3048 -0.1016)
			(end 0.3048 0.9906)
			(stroke
				(width 0.1)
				(type default)
			)
			(layer "B.Fab")
		)
		(fp_line
			(start 0.3048 0.9906)
			(end -0.3048 0.9906)
			(stroke
				(width 0.1)
				(type default)
			)
			(layer "B.Fab")
		)
		(pad "1" smd rect
			(at 0 0 180)
			(size 0.508 0.508)
			(layers "B.Cu" "B.Mask" "B.Paste")
			(net "P3E_CPU0_PE1_SS_TXN<3>")
		)
		(pad "2" smd rect
			(at 0 0.889 180)
			(size 0.508 0.508)
			(layers "B.Cu" "B.Mask" "B.Paste")
			(net "P3E_CPU0_PE1_SS_C_TXN<3>")
		)
		(zone
			(layer "B.Cu")
			(hatch none 0.5)
			(connect_pads
				(clearance 0)
			)
			(min_thickness 0.25)
			(keepout
				(tracks allowed)
				(vias not_allowed)
				(pads allowed)
				(copperpour not_allowed)
				(footprints allowed)
			)
			(placement
				(enabled no)
				(sheetname "")
			)
			(fill
				(thermal_gap 0.5)
				(thermal_bridge_width 0.5)
				(island_removal_mode 0)
			)
			(polygon
				(pts
					(xy 348.82836 -77.534516) (xy 348.32036 -77.534516) (xy 348.32036 -77.153516) (xy 348.82836 -77.153516)
				)
			)
		)
		(zone
			(layer "B.Cu")
			(hatch none 0.5)
			(connect_pads
				(clearance 0)
			)
			(min_thickness 0.25)
			(keepout
				(tracks not_allowed)
				(vias allowed)
				(pads allowed)
				(copperpour not_allowed)
				(footprints allowed)
			)
			(placement
				(enabled no)
				(sheetname "")
			)
			(fill
				(thermal_gap 0.5)
				(thermal_bridge_width 0.5)
				(island_removal_mode 0)
			)
			(polygon
				(pts
					(xy 348.82836 -77.153516) (xy 348.32036 -77.153516) (xy 348.32036 -77.534516) (xy 348.82836 -77.534516)
				)
			)
		)
	)
	(footprint ""
		(layer "B.Cu")
		(at 397.002 -85.0265 180)
		(property "Reference" "R8D15"
			(at 0.8382 -0.67818 180)
			(unlocked yes)
			(layer "B.SilkS")
			(effects
				(font
					(size 0.4064 0.254)
					(thickness 0.1524)
				)
				(justify left mirror)
			)
		)
		(property "Value" ""
			(at 0 0 0)
			(layer "B.Fab")
			(effects
				(font
					(size 1.27 1.27)
				)
				(justify mirror)
			)
		)
		(duplicate_pad_numbers_are_jumpers no)
		(fp_poly
			(pts
				(xy 0.2794 -0.1016) (xy -0.2794 -0.1016) (xy -0.2794 0.9906) (xy 0.2794 0.9906)
			)
			(stroke
				(width 0)
				(type default)
			)
			(fill no)
			(layer "B.CrtYd")
		)
		(fp_line
			(start 0.2794 0.9906)
			(end -0.2794 0.9906)
			(stroke
				(width 0.1)
				(type default)
			)
			(layer "B.Fab")
		)
		(fp_line
			(start 0.2794 -0.1016)
			(end 0.2794 0.9906)
			(stroke
				(width 0.1)
				(type default)
			)
			(layer "B.Fab")
		)
		(fp_line
			(start -0.2794 0.9906)
			(end -0.2794 -0.1016)
			(stroke
				(width 0.1)
				(type default)
			)
			(layer "B.Fab")
		)
		(fp_line
			(start -0.2794 -0.1016)
			(end 0.2794 -0.1016)
			(stroke
				(width 0.1)
				(type default)
			)
			(layer "B.Fab")
		)
		(pad "1" smd rect
			(at 0 0)
			(size 0.508 0.508)
			(layers "B.Cu" "B.Mask" "B.Paste")
			(net "P3V3_STBY")
		)
		(pad "2" smd rect
			(at 0 0.889)
			(size 0.508 0.508)
			(layers "B.Cu" "B.Mask" "B.Paste")
			(net "SMB_VR_STBY_LVC3_SCL")
		)
		(zone
			(layer "B.Cu")
			(hatch none 0.5)
			(connect_pads
				(clearance 0)
			)
			(min_thickness 0.25)
			(keepout
				(tracks not_allowed)
				(vias allowed)
				(pads allowed)
				(copperpour not_allowed)
				(footprints allowed)
			)
			(placement
				(enabled no)
				(sheetname "")
			)
			(fill
				(thermal_gap 0.5)
				(thermal_bridge_width 0.5)
				(island_removal_mode 0)
			)
			(polygon
				(pts
					(xy 396.748 -85.6615) (xy 397.256 -85.6615) (xy 397.256 -85.2805) (xy 396.748 -85.2805)
				)
			)
		)
		(zone
			(layer "B.Cu")
			(hatch none 0.5)
			(connect_pads
				(clearance 0)
			)
			(min_thickness 0.25)
			(keepout
				(tracks allowed)
				(vias not_allowed)
				(pads allowed)
				(copperpour not_allowed)
				(footprints allowed)
			)
			(placement
				(enabled no)
				(sheetname "")
			)
			(fill
				(thermal_gap 0.5)
				(thermal_bridge_width 0.5)
				(island_removal_mode 0)
			)
			(polygon
				(pts
					(xy 396.748 -85.2805) (xy 397.256 -85.2805) (xy 397.256 -85.6615) (xy 396.748 -85.6615)
				)
			)
		)
	)
	(footprint ""
		(layer "B.Cu")
		(at 365.001302 -145.471642)
		(property "Reference" "C7W6"
			(at 0 0 0)
			(layer "B.SilkS")
			(hide yes)
			(effects
				(font
					(size 1.27 1.27)
				)
				(justify mirror)
			)
		)
		(property "Value" "*"
			(at 0.0762 -6.2357 0)
			(unlocked yes)
			(layer "B.Fab")
			(hide yes)
			(effects
				(font
					(size 1.27 1.016)
					(thickness 0.1524)
				)
				(justify mirror)
			)
		)
		(property "Device Type" "SC22U16V5MX-4-GP_SMD-BCG5-SC22A"
			(at 0.0762 -8.2677 0)
			(unlocked yes)
			(layer "B.Fab")
			(hide yes)
			(effects
				(font
					(size 1.27 1.016)
					(thickness 0.1524)
				)
				(justify mirror)
			)
		)
		(duplicate_pad_numbers_are_jumpers no)
		(fp_line
			(start -0.635 0)
			(end 0.635 0)
			(stroke
				(width 0.508)
				(type default)
			)
			(layer "B.SilkS")
		)
		(fp_rect
			(start 0.9652 1.778)
			(end -0.9652 -1.778)
			(stroke
				(width 0)
				(type default)
			)
			(fill no)
			(layer "B.CrtYd")
		)
		(fp_poly
			(pts
				(xy 0.9652 -1.778) (xy -0.9652 -1.778) (xy -0.9652 1.778) (xy 0.9652 1.778)
			)
			(stroke
				(width 0)
				(type default)
			)
			(fill no)
			(layer "B.Fab")
		)
		(pad "1" smd rect
			(at 0 -0.9652 180)
			(size 1.397 1.143)
			(layers "B.Cu" "B.Mask" "B.Paste")
			(net "VR_FET_SW_P12V_STBY_PVDDQ_DEF")
		)
		(pad "2" smd rect
			(at 0 0.9652 180)
			(size 1.397 1.143)
			(layers "B.Cu" "B.Mask" "B.Paste")
			(net "GND")
		)
	)
	(footprint ""
		(layer "B.Cu")
		(at 197.848728 -90.838782 90)
		(property "Reference" "C6N10"
			(at 0 0 90)
			(layer "B.SilkS")
			(hide yes)
			(effects
				(font
					(size 1.27 1.27)
				)
				(justify mirror)
			)
		)
		(property "Value" ""
			(at 0 0 90)
			(layer "B.Fab")
			(effects
				(font
					(size 1.27 1.27)
				)
				(justify mirror)
			)
		)
		(duplicate_pad_numbers_are_jumpers no)
		(fp_rect
			(start 0.7239 1.9939)
			(end -0.7239 -0.2159)
			(stroke
				(width 0)
				(type default)
			)
			(fill no)
			(layer "B.CrtYd")
		)
		(fp_line
			(start 0.7239 -0.2159)
			(end 0.7239 1.9939)
			(stroke
				(width 0.1)
				(type default)
			)
			(layer "B.Fab")
		)
		(fp_line
			(start -0.7239 -0.2159)
			(end 0.7239 -0.2159)
			(stroke
				(width 0.1)
				(type default)
			)
			(layer "B.Fab")
		)
		(fp_line
			(start 0.7239 1.9939)
			(end -0.7239 1.9939)
			(stroke
				(width 0.1)
				(type default)
			)
			(layer "B.Fab")
		)
		(fp_line
			(start -0.7239 1.9939)
			(end -0.7239 -0.2159)
			(stroke
				(width 0.1)
				(type default)
			)
			(layer "B.Fab")
		)
		(pad "1" smd rect
			(at 0 0 270)
			(size 1.27 1.016)
			(layers "B.Cu" "B.Mask" "B.Paste")
			(net "VR_FET_SW_P12V_STBY_PVCCIN_CPU0")
		)
		(pad "2" smd rect
			(at 0 1.778 270)
			(size 1.27 1.016)
			(layers "B.Cu" "B.Mask" "B.Paste")
			(net "GND")
		)
		(zone
			(layer "B.Cu")
			(hatch none 0.5)
			(connect_pads
				(clearance 0)
			)
			(min_thickness 0.25)
			(keepout
				(tracks not_allowed)
				(vias allowed)
				(pads allowed)
				(copperpour not_allowed)
				(footprints allowed)
			)
			(placement
				(enabled no)
				(sheetname "")
			)
			(fill
				(thermal_gap 0.5)
				(thermal_bridge_width 0.5)
				(island_removal_mode 0)
			)
			(polygon
				(pts
					(xy 199.118728 -91.473782) (xy 198.356728 -91.473782) (xy 198.356728 -90.203782) (xy 199.118728 -90.203782)
				)
			)
		)
	)
	(footprint ""
		(layer "B.Cu")
		(at 345.832176 -77.694536 180)
		(property "Reference" "C3P20"
			(at 0 0 0)
			(layer "B.SilkS")
			(hide yes)
			(effects
				(font
					(size 1.27 1.27)
				)
				(justify mirror)
			)
		)
		(property "Value" ""
			(at 0 0 0)
			(layer "B.Fab")
			(effects
				(font
					(size 1.27 1.27)
				)
				(justify mirror)
			)
		)
		(duplicate_pad_numbers_are_jumpers no)
		(fp_poly
			(pts
				(xy -0.3048 -0.1016) (xy -0.3048 0.9906) (xy 0.3048 0.9906) (xy 0.3048 -0.1016)
			)
			(stroke
				(width 0)
				(type default)
			)
			(fill no)
			(layer "B.CrtYd")
		)
		(fp_line
			(start 0.3048 0.9906)
			(end -0.3048 0.9906)
			(stroke
				(width 0.1)
				(type default)
			)
			(layer "B.Fab")
		)
		(fp_line
			(start 0.3048 -0.1016)
			(end 0.3048 0.9906)
			(stroke
				(width 0.1)
				(type default)
			)
			(layer "B.Fab")
		)
		(fp_line
			(start -0.3048 0.9906)
			(end -0.3048 -0.1016)
			(stroke
				(width 0.1)
				(type default)
			)
			(layer "B.Fab")
		)
		(fp_line
			(start -0.3048 -0.1016)
			(end 0.3048 -0.1016)
			(stroke
				(width 0.1)
				(type default)
			)
			(layer "B.Fab")
		)
		(pad "1" smd rect
			(at 0 0)
			(size 0.508 0.508)
			(layers "B.Cu" "B.Mask" "B.Paste")
			(net "P3E_CPU0_PE1_SS_TXN<2>")
		)
		(pad "2" smd rect
			(at 0 0.889)
			(size 0.508 0.508)
			(layers "B.Cu" "B.Mask" "B.Paste")
			(net "P3E_CPU0_PE1_PCH_TXN<2>")
		)
		(zone
			(layer "B.Cu")
			(hatch none 0.5)
			(connect_pads
				(clearance 0)
			)
			(min_thickness 0.25)
			(keepout
				(tracks allowed)
				(vias not_allowed)
				(pads allowed)
				(copperpour not_allowed)
				(footprints allowed)
			)
			(placement
				(enabled no)
				(sheetname "")
			)
			(fill
				(thermal_gap 0.5)
				(thermal_bridge_width 0.5)
				(island_removal_mode 0)
			)
			(polygon
				(pts
					(xy 345.578176 -77.948536) (xy 346.086176 -77.948536) (xy 346.086176 -78.329536) (xy 345.578176 -78.329536)
				)
			)
		)
	)
	(footprint ""
		(layer "B.Cu")
		(at 490.9058 -51.64709 180)
		(property "Reference" "C25P83"
			(at 0.8382 -0.67818 180)
			(unlocked yes)
			(layer "B.SilkS")
			(effects
				(font
					(size 0.4064 0.254)
					(thickness 0.1524)
				)
				(justify left mirror)
			)
		)
		(property "Value" ""
			(at 0 0 0)
			(layer "B.Fab")
			(effects
				(font
					(size 1.27 1.27)
				)
				(justify mirror)
			)
		)
		(duplicate_pad_numbers_are_jumpers no)
		(fp_poly
			(pts
				(xy -0.3048 -0.1016) (xy -0.3048 0.9906) (xy 0.3048 0.9906) (xy 0.3048 -0.1016)
			)
			(stroke
				(width 0)
				(type default)
			)
			(fill no)
			(layer "B.CrtYd")
		)
		(fp_line
			(start 0.3048 0.9906)
			(end -0.3048 0.9906)
			(stroke
				(width 0.1)
				(type default)
			)
			(layer "B.Fab")
		)
		(fp_line
			(start 0.3048 -0.1016)
			(end 0.3048 0.9906)
			(stroke
				(width 0.1)
				(type default)
			)
			(layer "B.Fab")
		)
		(fp_line
			(start -0.3048 0.9906)
			(end -0.3048 -0.1016)
			(stroke
				(width 0.1)
				(type default)
			)
			(layer "B.Fab")
		)
		(fp_line
			(start -0.3048 -0.1016)
			(end 0.3048 -0.1016)
			(stroke
				(width 0.1)
				(type default)
			)
			(layer "B.Fab")
		)
		(pad "1" smd rect
			(at 0 0)
			(size 0.508 0.508)
			(layers "B.Cu" "B.Mask" "B.Paste")
			(net "P5V_VGA")
		)
		(pad "2" smd rect
			(at 0 0.889)
			(size 0.508 0.508)
			(layers "B.Cu" "B.Mask" "B.Paste")
			(net "GND")
		)
		(zone
			(layer "B.Cu")
			(hatch none 0.5)
			(connect_pads
				(clearance 0)
			)
			(min_thickness 0.25)
			(keepout
				(tracks not_allowed)
				(vias allowed)
				(pads allowed)
				(copperpour not_allowed)
				(footprints allowed)
			)
			(placement
				(enabled no)
				(sheetname "")
			)
			(fill
				(thermal_gap 0.5)
				(thermal_bridge_width 0.5)
				(island_removal_mode 0)
			)
			(polygon
				(pts
					(xy 490.6518 -52.28209) (xy 491.1598 -52.28209) (xy 491.1598 -51.90109) (xy 490.6518 -51.90109)
				)
			)
		)
		(zone
			(layer "B.Cu")
			(hatch none 0.5)
			(connect_pads
				(clearance 0)
			)
			(min_thickness 0.25)
			(keepout
				(tracks allowed)
				(vias not_allowed)
				(pads allowed)
				(copperpour not_allowed)
				(footprints allowed)
			)
			(placement
				(enabled no)
				(sheetname "")
			)
			(fill
				(thermal_gap 0.5)
				(thermal_bridge_width 0.5)
				(island_removal_mode 0)
			)
			(polygon
				(pts
					(xy 490.6518 -51.90109) (xy 491.1598 -51.90109) (xy 491.1598 -52.28209) (xy 490.6518 -52.28209)
				)
			)
		)
	)
	(footprint ""
		(layer "B.Cu")
		(at 370.29009 -66.300604)
		(property "Reference" "R3R11"
			(at 0 0 0)
			(layer "B.SilkS")
			(hide yes)
			(effects
				(font
					(size 1.27 1.27)
				)
				(justify mirror)
			)
		)
		(property "Value" ""
			(at 0 0 0)
			(layer "B.Fab")
			(effects
				(font
					(size 1.27 1.27)
				)
				(justify mirror)
			)
		)
		(duplicate_pad_numbers_are_jumpers no)
		(fp_poly
			(pts
				(xy 0.2794 -0.1016) (xy -0.2794 -0.1016) (xy -0.2794 0.9906) (xy 0.2794 0.9906)
			)
			(stroke
				(width 0)
				(type default)
			)
			(fill no)
			(layer "B.CrtYd")
		)
		(fp_line
			(start -0.2794 -0.1016)
			(end 0.2794 -0.1016)
			(stroke
				(width 0.1)
				(type default)
			)
			(layer "B.Fab")
		)
		(fp_line
			(start -0.2794 0.9906)
			(end -0.2794 -0.1016)
			(stroke
				(width 0.1)
				(type default)
			)
			(layer "B.Fab")
		)
		(fp_line
			(start 0.2794 -0.1016)
			(end 0.2794 0.9906)
			(stroke
				(width 0.1)
				(type default)
			)
			(layer "B.Fab")
		)
		(fp_line
			(start 0.2794 0.9906)
			(end -0.2794 0.9906)
			(stroke
				(width 0.1)
				(type default)
			)
			(layer "B.Fab")
		)
		(pad "1" smd rect
			(at 0 0 180)
			(size 0.508 0.508)
			(layers "B.Cu" "B.Mask" "B.Paste")
			(net "FM_JTAG_PLD_EN_DEBUG")
		)
		(pad "2" smd rect
			(at 0 0.889 180)
			(size 0.508 0.508)
			(layers "B.Cu" "B.Mask" "B.Paste")
			(net "GND")
		)
		(zone
			(layer "B.Cu")
			(hatch none 0.5)
			(connect_pads
				(clearance 0)
			)
			(min_thickness 0.25)
			(keepout
				(tracks allowed)
				(vias not_allowed)
				(pads allowed)
				(copperpour not_allowed)
				(footprints allowed)
			)
			(placement
				(enabled no)
				(sheetname "")
			)
			(fill
				(thermal_gap 0.5)
				(thermal_bridge_width 0.5)
				(island_removal_mode 0)
			)
			(polygon
				(pts
					(xy 370.54409 -66.046604) (xy 370.03609 -66.046604) (xy 370.03609 -65.665604) (xy 370.54409 -65.665604)
				)
			)
		)
		(zone
			(layer "B.Cu")
			(hatch none 0.5)
			(connect_pads
				(clearance 0)
			)
			(min_thickness 0.25)
			(keepout
				(tracks not_allowed)
				(vias allowed)
				(pads allowed)
				(copperpour not_allowed)
				(footprints allowed)
			)
			(placement
				(enabled no)
				(sheetname "")
			)
			(fill
				(thermal_gap 0.5)
				(thermal_bridge_width 0.5)
				(island_removal_mode 0)
			)
			(polygon
				(pts
					(xy 370.54409 -65.665604) (xy 370.03609 -65.665604) (xy 370.03609 -66.046604) (xy 370.54409 -66.046604)
				)
			)
		)
	)
	(footprint ""
		(layer "B.Cu")
		(at 373.761 -6.1595)
		(property "Reference" "R7G31"
			(at 0 0 0)
			(layer "B.SilkS")
			(hide yes)
			(effects
				(font
					(size 1.27 1.27)
				)
				(justify mirror)
			)
		)
		(property "Value" ""
			(at 0 0 0)
			(layer "B.Fab")
			(effects
				(font
					(size 1.27 1.27)
				)
				(justify mirror)
			)
		)
		(duplicate_pad_numbers_are_jumpers no)
		(fp_poly
			(pts
				(xy 0.2794 -0.1016) (xy -0.2794 -0.1016) (xy -0.2794 0.9906) (xy 0.2794 0.9906)
			)
			(stroke
				(width 0)
				(type default)
			)
			(fill no)
			(layer "B.CrtYd")
		)
		(fp_line
			(start -0.2794 -0.1016)
			(end 0.2794 -0.1016)
			(stroke
				(width 0.1)
				(type default)
			)
			(layer "B.Fab")
		)
		(fp_line
			(start -0.2794 0.9906)
			(end -0.2794 -0.1016)
			(stroke
				(width 0.1)
				(type default)
			)
			(layer "B.Fab")
		)
		(fp_line
			(start 0.2794 -0.1016)
			(end 0.2794 0.9906)
			(stroke
				(width 0.1)
				(type default)
			)
			(layer "B.Fab")
		)
		(fp_line
			(start 0.2794 0.9906)
			(end -0.2794 0.9906)
			(stroke
				(width 0.1)
				(type default)
			)
			(layer "B.Fab")
		)
		(pad "1" smd rect
			(at 0 0 180)
			(size 0.508 0.508)
			(layers "B.Cu" "B.Mask" "B.Paste")
			(net "P3V3_STBY")
		)
		(pad "2" smd rect
			(at 0 0.889 180)
			(size 0.508 0.508)
			(layers "B.Cu" "B.Mask" "B.Paste")
			(net "PU_BIOS_RECOVER_BOOT")
		)
		(zone
			(layer "B.Cu")
			(hatch none 0.5)
			(connect_pads
				(clearance 0)
			)
			(min_thickness 0.25)
			(keepout
				(tracks allowed)
				(vias not_allowed)
				(pads allowed)
				(copperpour not_allowed)
				(footprints allowed)
			)
			(placement
				(enabled no)
				(sheetname "")
			)
			(fill
				(thermal_gap 0.5)
				(thermal_bridge_width 0.5)
				(island_removal_mode 0)
			)
			(polygon
				(pts
					(xy 374.015 -5.9055) (xy 373.507 -5.9055) (xy 373.507 -5.5245) (xy 374.015 -5.5245)
				)
			)
		)
		(zone
			(layer "B.Cu")
			(hatch none 0.5)
			(connect_pads
				(clearance 0)
			)
			(min_thickness 0.25)
			(keepout
				(tracks not_allowed)
				(vias allowed)
				(pads allowed)
				(copperpour not_allowed)
				(footprints allowed)
			)
			(placement
				(enabled no)
				(sheetname "")
			)
			(fill
				(thermal_gap 0.5)
				(thermal_bridge_width 0.5)
				(island_removal_mode 0)
			)
			(polygon
				(pts
					(xy 374.015 -5.5245) (xy 373.507 -5.5245) (xy 373.507 -5.9055) (xy 374.015 -5.9055)
				)
			)
		)
	)
	(footprint ""
		(layer "B.Cu")
		(at 210.847432 -57.023 -90)
		(property "Reference" "C6R9"
			(at -0.86233 -3.401568 0)
			(unlocked yes)
			(layer "B.SilkS")
			(effects
				(font
					(size 0.7874 0.5842)
					(thickness 0.1524)
				)
				(justify mirror)
			)
		)
		(property "Value" ""
			(at 0 0 90)
			(layer "B.Fab")
			(effects
				(font
					(size 1.27 1.27)
				)
				(justify mirror)
			)
		)
		(duplicate_pad_numbers_are_jumpers no)
		(fp_line
			(start -2.286 7.366)
			(end -1.600708 7.366)
			(stroke
				(width 0.1524)
				(type default)
			)
			(layer "B.SilkS")
		)
		(fp_line
			(start -2.286 7.366)
			(end -2.286 1.63195)
			(stroke
				(width 0.1524)
				(type default)
			)
			(layer "B.SilkS")
		)
		(fp_line
			(start 2.286 7.366)
			(end 1.60147 7.366)
			(stroke
				(width 0.1524)
				(type default)
			)
			(layer "B.SilkS")
		)
		(fp_line
			(start 2.286 7.366)
			(end 2.286 1.632712)
			(stroke
				(width 0.1524)
				(type default)
			)
			(layer "B.SilkS")
		)
		(fp_line
			(start -2.504948 1.633728)
			(end -1.6002 1.633728)
			(stroke
				(width 0.1524)
				(type default)
			)
			(layer "B.SilkS")
		)
		(fp_line
			(start 2.563114 1.633728)
			(end 1.6002 1.633728)
			(stroke
				(width 0.1524)
				(type default)
			)
			(layer "B.SilkS")
		)
		(fp_line
			(start -2.504948 -1.616456)
			(end -2.504948 1.633728)
			(stroke
				(width 0.1524)
				(type default)
			)
			(layer "B.SilkS")
		)
		(fp_line
			(start -1.6002 -1.616456)
			(end -2.504948 -1.616456)
			(stroke
				(width 0.1524)
				(type default)
			)
			(layer "B.SilkS")
		)
		(fp_line
			(start 1.6002 -1.616456)
			(end 2.563114 -1.616456)
			(stroke
				(width 0.1524)
				(type default)
			)
			(layer "B.SilkS")
		)
		(fp_line
			(start 2.563114 -1.616456)
			(end 2.563114 1.633728)
			(stroke
				(width 0.1524)
				(type default)
			)
			(layer "B.SilkS")
		)
		(fp_rect
			(start 2.286 7.366)
			(end -2.286 -0.254)
			(stroke
				(width 0)
				(type default)
			)
			(fill no)
			(layer "B.CrtYd")
		)
		(fp_line
			(start -2.286 7.366)
			(end 2.286 7.366)
			(stroke
				(width 0.1)
				(type default)
			)
			(layer "B.Fab")
		)
		(fp_line
			(start 2.286 7.366)
			(end 2.286 -0.254)
			(stroke
				(width 0.1)
				(type default)
			)
			(layer "B.Fab")
		)
		(fp_line
			(start -2.286 -0.254)
			(end -2.286 7.366)
			(stroke
				(width 0.1)
				(type default)
			)
			(layer "B.Fab")
		)
		(fp_line
			(start 2.286 -0.254)
			(end -2.286 -0.254)
			(stroke
				(width 0.1)
				(type default)
			)
			(layer "B.Fab")
		)
		(pad "1" smd rect
			(at 0 0 90)
			(size 2.54 3.048)
			(layers "B.Cu" "B.Mask" "B.Paste")
			(net "PVCCIN_CPU0")
		)
		(pad "2" smd rect
			(at 0 7.112 90)
			(size 2.54 3.048)
			(layers "B.Cu" "B.Mask" "B.Paste")
			(net "GND")
		)
	)
	(footprint ""
		(layer "B.Cu")
		(at 10.414 -68.0466 180)
		(property "Reference" "R9P26"
			(at 0 0 0)
			(layer "B.SilkS")
			(hide yes)
			(effects
				(font
					(size 1.27 1.27)
				)
				(justify mirror)
			)
		)
		(property "Value" ""
			(at 0 0 0)
			(layer "B.Fab")
			(effects
				(font
					(size 1.27 1.27)
				)
				(justify mirror)
			)
		)
		(duplicate_pad_numbers_are_jumpers no)
		(fp_rect
			(start -0.2794 0.9906)
			(end 0.2794 -0.1016)
			(stroke
				(width 0)
				(type default)
			)
			(fill no)
			(layer "B.CrtYd")
		)
		(fp_line
			(start 0.2794 0.9906)
			(end -0.2794 0.9906)
			(stroke
				(width 0.1)
				(type default)
			)
			(layer "B.Fab")
		)
		(fp_line
			(start 0.2794 -0.1016)
			(end 0.2794 0.9906)
			(stroke
				(width 0.1)
				(type default)
			)
			(layer "B.Fab")
		)
		(fp_line
			(start -0.2794 0.9906)
			(end -0.2794 -0.1016)
			(stroke
				(width 0.1)
				(type default)
			)
			(layer "B.Fab")
		)
		(fp_line
			(start -0.2794 -0.1016)
			(end 0.2794 -0.1016)
			(stroke
				(width 0.1)
				(type default)
			)
			(layer "B.Fab")
		)
		(pad "1" smd rect
			(at 0 0)
			(size 0.508 0.508)
			(layers "B.Cu" "B.Mask" "B.Paste")
			(net "P12V_HSC_SENN1")
		)
		(pad "2" smd rect
			(at 0 0.889)
			(size 0.508 0.508)
			(layers "B.Cu" "B.Mask" "B.Paste")
			(net "A_HSC_HSN")
		)
		(zone
			(layer "B.Cu")
			(hatch none 0.5)
			(connect_pads
				(clearance 0)
			)
			(min_thickness 0.25)
			(keepout
				(tracks allowed)
				(vias not_allowed)
				(pads allowed)
				(copperpour not_allowed)
				(footprints allowed)
			)
			(placement
				(enabled no)
				(sheetname "")
			)
			(fill
				(thermal_gap 0.5)
				(thermal_bridge_width 0.5)
				(island_removal_mode 0)
			)
			(polygon
				(pts
					(xy 10.668 -68.6816) (xy 10.16 -68.6816) (xy 10.16 -68.3006) (xy 10.668 -68.3006)
				)
			)
		)
		(zone
			(layer "B.Cu")
			(hatch none 0.5)
			(connect_pads
				(clearance 0)
			)
			(min_thickness 0.25)
			(keepout
				(tracks not_allowed)
				(vias allowed)
				(pads allowed)
				(copperpour not_allowed)
				(footprints allowed)
			)
			(placement
				(enabled no)
				(sheetname "")
			)
			(fill
				(thermal_gap 0.5)
				(thermal_bridge_width 0.5)
				(island_removal_mode 0)
			)
			(polygon
				(pts
					(xy 10.668 -68.6816) (xy 10.16 -68.6816) (xy 10.16 -68.3006) (xy 10.668 -68.3006)
				)
			)
		)
	)
	(footprint ""
		(layer "B.Cu")
		(at 487.934 -111.94542 90)
		(property "Reference" "C1M26"
			(at 0 0 90)
			(layer "B.SilkS")
			(hide yes)
			(effects
				(font
					(size 1.27 1.27)
				)
				(justify mirror)
			)
		)
		(property "Value" ""
			(at 0 0 90)
			(layer "B.Fab")
			(effects
				(font
					(size 1.27 1.27)
				)
				(justify mirror)
			)
		)
		(duplicate_pad_numbers_are_jumpers no)
		(fp_rect
			(start -0.7239 -0.2159)
			(end 0.7239 1.9939)
			(stroke
				(width 0)
				(type default)
			)
			(fill no)
			(layer "B.CrtYd")
		)
		(fp_line
			(start 0.7239 -0.2159)
			(end 0.7239 1.9939)
			(stroke
				(width 0.1)
				(type default)
			)
			(layer "B.Fab")
		)
		(fp_line
			(start -0.7239 -0.2159)
			(end 0.7239 -0.2159)
			(stroke
				(width 0.1)
				(type default)
			)
			(layer "B.Fab")
		)
		(fp_line
			(start 0.7239 1.9939)
			(end -0.7239 1.9939)
			(stroke
				(width 0.1)
				(type default)
			)
			(layer "B.Fab")
		)
		(fp_line
			(start -0.7239 1.9939)
			(end -0.7239 -0.2159)
			(stroke
				(width 0.1)
				(type default)
			)
			(layer "B.Fab")
		)
		(pad "1" smd rect
			(at 0 0 270)
			(size 1.27 1.016)
			(layers "B.Cu" "B.Mask" "B.Paste")
			(net "P12V_STBY")
		)
		(pad "2" smd rect
			(at 0 1.778 270)
			(size 1.27 1.016)
			(layers "B.Cu" "B.Mask" "B.Paste")
			(net "GND")
		)
		(zone
			(layer "B.Cu")
			(hatch none 0.5)
			(connect_pads
				(clearance 0)
			)
			(min_thickness 0.25)
			(keepout
				(tracks not_allowed)
				(vias allowed)
				(pads allowed)
				(copperpour not_allowed)
				(footprints allowed)
			)
			(placement
				(enabled no)
				(sheetname "")
			)
			(fill
				(thermal_gap 0.5)
				(thermal_bridge_width 0.5)
				(island_removal_mode 0)
			)
			(polygon
				(pts
					(xy 488.442 -111.31042) (xy 489.204 -111.31042) (xy 489.204 -112.58042) (xy 488.442 -112.58042)
				)
			)
		)
	)
	(footprint ""
		(layer "B.Cu")
		(at 460.6544 -52.457858)
		(property "Reference" "C1R3"
			(at 0 0 0)
			(layer "B.SilkS")
			(hide yes)
			(effects
				(font
					(size 1.27 1.27)
				)
				(justify mirror)
			)
		)
		(property "Value" ""
			(at 0 0 0)
			(layer "B.Fab")
			(effects
				(font
					(size 1.27 1.27)
				)
				(justify mirror)
			)
		)
		(duplicate_pad_numbers_are_jumpers no)
		(fp_poly
			(pts
				(xy -0.3048 -0.1016) (xy -0.3048 0.9906) (xy 0.3048 0.9906) (xy 0.3048 -0.1016)
			)
			(stroke
				(width 0)
				(type default)
			)
			(fill no)
			(layer "B.CrtYd")
		)
		(fp_line
			(start -0.3048 -0.1016)
			(end 0.3048 -0.1016)
			(stroke
				(width 0.1)
				(type default)
			)
			(layer "B.Fab")
		)
		(fp_line
			(start -0.3048 0.9906)
			(end -0.3048 -0.1016)
			(stroke
				(width 0.1)
				(type default)
			)
			(layer "B.Fab")
		)
		(fp_line
			(start 0.3048 -0.1016)
			(end 0.3048 0.9906)
			(stroke
				(width 0.1)
				(type default)
			)
			(layer "B.Fab")
		)
		(fp_line
			(start 0.3048 0.9906)
			(end -0.3048 0.9906)
			(stroke
				(width 0.1)
				(type default)
			)
			(layer "B.Fab")
		)
		(pad "1" smd rect
			(at 0 0 180)
			(size 0.508 0.508)
			(layers "B.Cu" "B.Mask" "B.Paste")
			(net "P3E_CPU0_PE3_OCP_TXN<1>")
		)
		(pad "2" smd rect
			(at 0 0.889 180)
			(size 0.508 0.508)
			(layers "B.Cu" "B.Mask" "B.Paste")
			(net "P3E_OCP_CPU0_PE3_C_TXN<1>")
		)
		(zone
			(layer "B.Cu")
			(hatch none 0.5)
			(connect_pads
				(clearance 0)
			)
			(min_thickness 0.25)
			(keepout
				(tracks allowed)
				(vias not_allowed)
				(pads allowed)
				(copperpour not_allowed)
				(footprints allowed)
			)
			(placement
				(enabled no)
				(sheetname "")
			)
			(fill
				(thermal_gap 0.5)
				(thermal_bridge_width 0.5)
				(island_removal_mode 0)
			)
			(polygon
				(pts
					(xy 460.9084 -52.203858) (xy 460.4004 -52.203858) (xy 460.4004 -51.822858) (xy 460.9084 -51.822858)
				)
			)
		)
		(zone
			(layer "B.Cu")
			(hatch none 0.5)
			(connect_pads
				(clearance 0)
			)
			(min_thickness 0.25)
			(keepout
				(tracks not_allowed)
				(vias allowed)
				(pads allowed)
				(copperpour not_allowed)
				(footprints allowed)
			)
			(placement
				(enabled no)
				(sheetname "")
			)
			(fill
				(thermal_gap 0.5)
				(thermal_bridge_width 0.5)
				(island_removal_mode 0)
			)
			(polygon
				(pts
					(xy 460.9084 -51.822858) (xy 460.4004 -51.822858) (xy 460.4004 -52.203858) (xy 460.9084 -52.203858)
				)
			)
		)
	)
	(footprint ""
		(layer "B.Cu")
		(at 415.29 -31.0515 180)
		(property "Reference" "C25W38"
			(at 0.8382 -0.67818 180)
			(unlocked yes)
			(layer "B.SilkS")
			(effects
				(font
					(size 0.4064 0.254)
					(thickness 0.1524)
				)
				(justify left mirror)
			)
		)
		(property "Value" ""
			(at 0 0 0)
			(layer "B.Fab")
			(effects
				(font
					(size 1.27 1.27)
				)
				(justify mirror)
			)
		)
		(duplicate_pad_numbers_are_jumpers no)
		(fp_poly
			(pts
				(xy -0.3048 -0.1016) (xy -0.3048 0.9906) (xy 0.3048 0.9906) (xy 0.3048 -0.1016)
			)
			(stroke
				(width 0)
				(type default)
			)
			(fill no)
			(layer "B.CrtYd")
		)
		(fp_line
			(start 0.3048 0.9906)
			(end -0.3048 0.9906)
			(stroke
				(width 0.1)
				(type default)
			)
			(layer "B.Fab")
		)
		(fp_line
			(start 0.3048 -0.1016)
			(end 0.3048 0.9906)
			(stroke
				(width 0.1)
				(type default)
			)
			(layer "B.Fab")
		)
		(fp_line
			(start -0.3048 0.9906)
			(end -0.3048 -0.1016)
			(stroke
				(width 0.1)
				(type default)
			)
			(layer "B.Fab")
		)
		(fp_line
			(start -0.3048 -0.1016)
			(end 0.3048 -0.1016)
			(stroke
				(width 0.1)
				(type default)
			)
			(layer "B.Fab")
		)
		(pad "1" smd rect
			(at 0 0)
			(size 0.508 0.508)
			(layers "B.Cu" "B.Mask" "B.Paste")
			(net "VCC_A_1V1")
		)
		(pad "2" smd rect
			(at 0 0.889)
			(size 0.508 0.508)
			(layers "B.Cu" "B.Mask" "B.Paste")
			(net "GND")
		)
		(zone
			(layer "B.Cu")
			(hatch none 0.5)
			(connect_pads
				(clearance 0)
			)
			(min_thickness 0.25)
			(keepout
				(tracks not_allowed)
				(vias allowed)
				(pads allowed)
				(copperpour not_allowed)
				(footprints allowed)
			)
			(placement
				(enabled no)
				(sheetname "")
			)
			(fill
				(thermal_gap 0.5)
				(thermal_bridge_width 0.5)
				(island_removal_mode 0)
			)
			(polygon
				(pts
					(xy 415.036 -31.6865) (xy 415.544 -31.6865) (xy 415.544 -31.3055) (xy 415.036 -31.3055)
				)
			)
		)
		(zone
			(layer "B.Cu")
			(hatch none 0.5)
			(connect_pads
				(clearance 0)
			)
			(min_thickness 0.25)
			(keepout
				(tracks allowed)
				(vias not_allowed)
				(pads allowed)
				(copperpour not_allowed)
				(footprints allowed)
			)
			(placement
				(enabled no)
				(sheetname "")
			)
			(fill
				(thermal_gap 0.5)
				(thermal_bridge_width 0.5)
				(island_removal_mode 0)
			)
			(polygon
				(pts
					(xy 415.036 -31.3055) (xy 415.544 -31.3055) (xy 415.544 -31.6865) (xy 415.036 -31.6865)
				)
			)
		)
	)
	(footprint ""
		(layer "B.Cu")
		(at 334.01 -155.448 90)
		(property "Reference" "C3L6"
			(at -2.05867 9.144 0)
			(unlocked yes)
			(layer "B.SilkS")
			(effects
				(font
					(size 0.7874 0.5842)
					(thickness 0.1524)
				)
				(justify mirror)
			)
		)
		(property "Value" ""
			(at 0 0 90)
			(layer "B.Fab")
			(effects
				(font
					(size 1.27 1.27)
				)
				(justify mirror)
			)
		)
		(duplicate_pad_numbers_are_jumpers no)
		(fp_line
			(start 2.563114 -1.616456)
			(end 2.563114 1.633728)
			(stroke
				(width 0.1524)
				(type default)
			)
			(layer "B.SilkS")
		)
		(fp_line
			(start 1.6002 -1.616456)
			(end 2.563114 -1.616456)
			(stroke
				(width 0.1524)
				(type default)
			)
			(layer "B.SilkS")
		)
		(fp_line
			(start -1.6002 -1.616456)
			(end -2.504948 -1.616456)
			(stroke
				(width 0.1524)
				(type default)
			)
			(layer "B.SilkS")
		)
		(fp_line
			(start -2.504948 -1.616456)
			(end -2.504948 1.633728)
			(stroke
				(width 0.1524)
				(type default)
			)
			(layer "B.SilkS")
		)
		(fp_line
			(start 2.563114 1.633728)
			(end 1.6002 1.633728)
			(stroke
				(width 0.1524)
				(type default)
			)
			(layer "B.SilkS")
		)
		(fp_line
			(start -2.504948 1.633728)
			(end -1.6002 1.633728)
			(stroke
				(width 0.1524)
				(type default)
			)
			(layer "B.SilkS")
		)
		(fp_line
			(start 2.286 7.366)
			(end 2.286 1.632712)
			(stroke
				(width 0.1524)
				(type default)
			)
			(layer "B.SilkS")
		)
		(fp_line
			(start 2.286 7.366)
			(end 1.60147 7.366)
			(stroke
				(width 0.1524)
				(type default)
			)
			(layer "B.SilkS")
		)
		(fp_line
			(start -2.286 7.366)
			(end -2.286 1.63195)
			(stroke
				(width 0.1524)
				(type default)
			)
			(layer "B.SilkS")
		)
		(fp_line
			(start -2.286 7.366)
			(end -1.600708 7.366)
			(stroke
				(width 0.1524)
				(type default)
			)
			(layer "B.SilkS")
		)
		(fp_rect
			(start 2.286 7.366)
			(end -2.286 -0.254)
			(stroke
				(width 0)
				(type default)
			)
			(fill no)
			(layer "B.CrtYd")
		)
		(fp_line
			(start 2.286 -0.254)
			(end -2.286 -0.254)
			(stroke
				(width 0.1)
				(type default)
			)
			(layer "B.Fab")
		)
		(fp_line
			(start -2.286 -0.254)
			(end -2.286 7.366)
			(stroke
				(width 0.1)
				(type default)
			)
			(layer "B.Fab")
		)
		(fp_line
			(start 2.286 7.366)
			(end 2.286 -0.254)
			(stroke
				(width 0.1)
				(type default)
			)
			(layer "B.Fab")
		)
		(fp_line
			(start -2.286 7.366)
			(end 2.286 7.366)
			(stroke
				(width 0.1)
				(type default)
			)
			(layer "B.Fab")
		)
		(pad "1" smd rect
			(at 0 0 270)
			(size 2.54 3.048)
			(layers "B.Cu" "B.Mask" "B.Paste")
			(net "PVDDQ_DEF")
		)
		(pad "2" smd rect
			(at 0 7.112 270)
			(size 2.54 3.048)
			(layers "B.Cu" "B.Mask" "B.Paste")
			(net "GND")
		)
	)
	(footprint ""
		(layer "B.Cu")
		(at 496.523772 -46.198028 -90)
		(property "Reference" "R25W135"
			(at 0.8382 -0.67818 270)
			(unlocked yes)
			(layer "B.SilkS")
			(effects
				(font
					(size 0.4064 0.254)
					(thickness 0.1524)
				)
				(justify left mirror)
			)
		)
		(property "Value" ""
			(at 0 0 90)
			(layer "B.Fab")
			(effects
				(font
					(size 1.27 1.27)
				)
				(justify mirror)
			)
		)
		(duplicate_pad_numbers_are_jumpers no)
		(fp_poly
			(pts
				(xy 0.2794 -0.1016) (xy -0.2794 -0.1016) (xy -0.2794 0.9906) (xy 0.2794 0.9906)
			)
			(stroke
				(width 0)
				(type default)
			)
			(fill no)
			(layer "B.CrtYd")
		)
		(fp_line
			(start -0.2794 0.9906)
			(end -0.2794 -0.1016)
			(stroke
				(width 0.1)
				(type default)
			)
			(layer "B.Fab")
		)
		(fp_line
			(start 0.2794 0.9906)
			(end -0.2794 0.9906)
			(stroke
				(width 0.1)
				(type default)
			)
			(layer "B.Fab")
		)
		(fp_line
			(start -0.2794 -0.1016)
			(end 0.2794 -0.1016)
			(stroke
				(width 0.1)
				(type default)
			)
			(layer "B.Fab")
		)
		(fp_line
			(start 0.2794 -0.1016)
			(end 0.2794 0.9906)
			(stroke
				(width 0.1)
				(type default)
			)
			(layer "B.Fab")
		)
		(pad "1" smd rect
			(at 0 0 90)
			(size 0.508 0.508)
			(layers "B.Cu" "B.Mask" "B.Paste")
			(net "P5V_VGA_D")
		)
		(pad "2" smd rect
			(at 0 0.889 90)
			(size 0.508 0.508)
			(layers "B.Cu" "B.Mask" "B.Paste")
			(net "I2C_BMC_VGA_DDC_SDA_G")
		)
		(zone
			(layer "B.Cu")
			(hatch none 0.5)
			(connect_pads
				(clearance 0)
			)
			(min_thickness 0.25)
			(keepout
				(tracks not_allowed)
				(vias allowed)
				(pads allowed)
				(copperpour not_allowed)
				(footprints allowed)
			)
			(placement
				(enabled no)
				(sheetname "")
			)
			(fill
				(thermal_gap 0.5)
				(thermal_bridge_width 0.5)
				(island_removal_mode 0)
			)
			(polygon
				(pts
					(xy 495.888772 -45.944028) (xy 495.888772 -46.452028) (xy 496.269772 -46.452028) (xy 496.269772 -45.944028)
				)
			)
		)
		(zone
			(layer "B.Cu")
			(hatch none 0.5)
			(connect_pads
				(clearance 0)
			)
			(min_thickness 0.25)
			(keepout
				(tracks allowed)
				(vias not_allowed)
				(pads allowed)
				(copperpour not_allowed)
				(footprints allowed)
			)
			(placement
				(enabled no)
				(sheetname "")
			)
			(fill
				(thermal_gap 0.5)
				(thermal_bridge_width 0.5)
				(island_removal_mode 0)
			)
			(polygon
				(pts
					(xy 496.269772 -45.944028) (xy 496.269772 -46.452028) (xy 495.888772 -46.452028) (xy 495.888772 -45.944028)
				)
			)
		)
	)
	(footprint ""
		(layer "B.Cu")
		(at 259.272024 -82.001614)
		(property "Reference" "C5P9"
			(at 0 0 0)
			(layer "B.SilkS")
			(hide yes)
			(effects
				(font
					(size 1.27 1.27)
				)
				(justify mirror)
			)
		)
		(property "Value" ""
			(at 0 0 0)
			(layer "B.Fab")
			(effects
				(font
					(size 1.27 1.27)
				)
				(justify mirror)
			)
		)
		(duplicate_pad_numbers_are_jumpers no)
		(fp_poly
			(pts
				(xy 0.7239 -0.2159) (xy -0.7239 -0.2159) (xy -0.7239 1.9939) (xy 0.7239 1.9939)
			)
			(stroke
				(width 0)
				(type default)
			)
			(fill no)
			(layer "B.CrtYd")
		)
		(fp_line
			(start -0.7239 -0.2159)
			(end 0.7239 -0.2159)
			(stroke
				(width 0.1)
				(type default)
			)
			(layer "B.Fab")
		)
		(fp_line
			(start -0.7239 1.9939)
			(end -0.7239 -0.2159)
			(stroke
				(width 0.1)
				(type default)
			)
			(layer "B.Fab")
		)
		(fp_line
			(start 0.7239 -0.2159)
			(end 0.7239 1.9939)
			(stroke
				(width 0.1)
				(type default)
			)
			(layer "B.Fab")
		)
		(fp_line
			(start 0.7239 1.9939)
			(end -0.7239 1.9939)
			(stroke
				(width 0.1)
				(type default)
			)
			(layer "B.Fab")
		)
		(pad "1" smd rect
			(at 0 0 180)
			(size 1.27 1.016)
			(layers "B.Cu" "B.Mask" "B.Paste")
			(net "PVSA_CPU0")
		)
		(pad "2" smd rect
			(at 0 1.778 180)
			(size 1.27 1.016)
			(layers "B.Cu" "B.Mask" "B.Paste")
			(net "GND")
		)
		(zone
			(layer "B.Cu")
			(hatch none 0.5)
			(connect_pads
				(clearance 0)
			)
			(min_thickness 0.25)
			(keepout
				(tracks not_allowed)
				(vias allowed)
				(pads allowed)
				(copperpour not_allowed)
				(footprints allowed)
			)
			(placement
				(enabled no)
				(sheetname "")
			)
			(fill
				(thermal_gap 0.5)
				(thermal_bridge_width 0.5)
				(island_removal_mode 0)
			)
			(polygon
				(pts
					(xy 259.907024 -81.493614) (xy 258.637024 -81.493614) (xy 258.637024 -80.731614) (xy 259.907024 -80.731614)
				)
			)
		)
	)
	(footprint ""
		(layer "B.Cu")
		(at 485.256586 -60.009532 90)
		(property "Reference" "C30W2"
			(at 0.8382 -0.67818 90)
			(unlocked yes)
			(layer "B.SilkS")
			(effects
				(font
					(size 0.4064 0.254)
					(thickness 0.1524)
				)
				(justify left mirror)
			)
		)
		(property "Value" ""
			(at 0 0 90)
			(layer "B.Fab")
			(effects
				(font
					(size 1.27 1.27)
				)
				(justify mirror)
			)
		)
		(duplicate_pad_numbers_are_jumpers no)
		(fp_poly
			(pts
				(xy -0.3048 -0.1016) (xy -0.3048 0.9906) (xy 0.3048 0.9906) (xy 0.3048 -0.1016)
			)
			(stroke
				(width 0)
				(type default)
			)
			(fill no)
			(layer "B.CrtYd")
		)
		(fp_line
			(start 0.3048 -0.1016)
			(end 0.3048 0.9906)
			(stroke
				(width 0.1)
				(type default)
			)
			(layer "B.Fab")
		)
		(fp_line
			(start -0.3048 -0.1016)
			(end 0.3048 -0.1016)
			(stroke
				(width 0.1)
				(type default)
			)
			(layer "B.Fab")
		)
		(fp_line
			(start 0.3048 0.9906)
			(end -0.3048 0.9906)
			(stroke
				(width 0.1)
				(type default)
			)
			(layer "B.Fab")
		)
		(fp_line
			(start -0.3048 0.9906)
			(end -0.3048 -0.1016)
			(stroke
				(width 0.1)
				(type default)
			)
			(layer "B.Fab")
		)
		(pad "1" smd rect
			(at 0 0 270)
			(size 0.508 0.508)
			(layers "B.Cu" "B.Mask" "B.Paste")
			(net "USB3_P01_TXP")
		)
		(pad "2" smd rect
			(at 0 0.889 270)
			(size 0.508 0.508)
			(layers "B.Cu" "B.Mask" "B.Paste")
			(net "USB3_P01_C_TXP")
		)
		(zone
			(layer "B.Cu")
			(hatch none 0.5)
			(connect_pads
				(clearance 0)
			)
			(min_thickness 0.25)
			(keepout
				(tracks allowed)
				(vias not_allowed)
				(pads allowed)
				(copperpour not_allowed)
				(footprints allowed)
			)
			(placement
				(enabled no)
				(sheetname "")
			)
			(fill
				(thermal_gap 0.5)
				(thermal_bridge_width 0.5)
				(island_removal_mode 0)
			)
			(polygon
				(pts
					(xy 485.510586 -60.263532) (xy 485.510586 -59.755532) (xy 485.891586 -59.755532) (xy 485.891586 -60.263532)
				)
			)
		)
		(zone
			(layer "B.Cu")
			(hatch none 0.5)
			(connect_pads
				(clearance 0)
			)
			(min_thickness 0.25)
			(keepout
				(tracks not_allowed)
				(vias allowed)
				(pads allowed)
				(copperpour not_allowed)
				(footprints allowed)
			)
			(placement
				(enabled no)
				(sheetname "")
			)
			(fill
				(thermal_gap 0.5)
				(thermal_bridge_width 0.5)
				(island_removal_mode 0)
			)
			(polygon
				(pts
					(xy 485.891586 -60.263532) (xy 485.891586 -59.755532) (xy 485.510586 -59.755532) (xy 485.510586 -60.263532)
				)
			)
		)
	)
	(footprint ""
		(layer "B.Cu")
		(at 340.16696 -77.694536 180)
		(property "Reference" "C3P13"
			(at 0 0 0)
			(layer "B.SilkS")
			(hide yes)
			(effects
				(font
					(size 1.27 1.27)
				)
				(justify mirror)
			)
		)
		(property "Value" ""
			(at 0 0 0)
			(layer "B.Fab")
			(effects
				(font
					(size 1.27 1.27)
				)
				(justify mirror)
			)
		)
		(duplicate_pad_numbers_are_jumpers no)
		(fp_poly
			(pts
				(xy -0.3048 -0.1016) (xy -0.3048 0.9906) (xy 0.3048 0.9906) (xy 0.3048 -0.1016)
			)
			(stroke
				(width 0)
				(type default)
			)
			(fill no)
			(layer "B.CrtYd")
		)
		(fp_line
			(start 0.3048 0.9906)
			(end -0.3048 0.9906)
			(stroke
				(width 0.1)
				(type default)
			)
			(layer "B.Fab")
		)
		(fp_line
			(start 0.3048 -0.1016)
			(end 0.3048 0.9906)
			(stroke
				(width 0.1)
				(type default)
			)
			(layer "B.Fab")
		)
		(fp_line
			(start -0.3048 0.9906)
			(end -0.3048 -0.1016)
			(stroke
				(width 0.1)
				(type default)
			)
			(layer "B.Fab")
		)
		(fp_line
			(start -0.3048 -0.1016)
			(end 0.3048 -0.1016)
			(stroke
				(width 0.1)
				(type default)
			)
			(layer "B.Fab")
		)
		(pad "1" smd rect
			(at 0 0)
			(size 0.508 0.508)
			(layers "B.Cu" "B.Mask" "B.Paste")
			(net "P3E_CPU0_PE1_SS_TXN<0>")
		)
		(pad "2" smd rect
			(at 0 0.889)
			(size 0.508 0.508)
			(layers "B.Cu" "B.Mask" "B.Paste")
			(net "P3E_CPU0_PE1_PCH_TXN<0>")
		)
		(zone
			(layer "B.Cu")
			(hatch none 0.5)
			(connect_pads
				(clearance 0)
			)
			(min_thickness 0.25)
			(keepout
				(tracks not_allowed)
				(vias allowed)
				(pads allowed)
				(copperpour not_allowed)
				(footprints allowed)
			)
			(placement
				(enabled no)
				(sheetname "")
			)
			(fill
				(thermal_gap 0.5)
				(thermal_bridge_width 0.5)
				(island_removal_mode 0)
			)
			(polygon
				(pts
					(xy 339.91296 -78.329536) (xy 340.42096 -78.329536) (xy 340.42096 -77.948536) (xy 339.91296 -77.948536)
				)
			)
		)
		(zone
			(layer "B.Cu")
			(hatch none 0.5)
			(connect_pads
				(clearance 0)
			)
			(min_thickness 0.25)
			(keepout
				(tracks allowed)
				(vias not_allowed)
				(pads allowed)
				(copperpour not_allowed)
				(footprints allowed)
			)
			(placement
				(enabled no)
				(sheetname "")
			)
			(fill
				(thermal_gap 0.5)
				(thermal_bridge_width 0.5)
				(island_removal_mode 0)
			)
			(polygon
				(pts
					(xy 339.91296 -77.948536) (xy 340.42096 -77.948536) (xy 340.42096 -78.329536) (xy 339.91296 -78.329536)
				)
			)
		)
	)
	(footprint ""
		(layer "B.Cu")
		(at 154.023568 -144.977612 -90)
		(property "Reference" "C7L7"
			(at 0 0 90)
			(layer "B.SilkS")
			(hide yes)
			(effects
				(font
					(size 1.27 1.27)
				)
				(justify mirror)
			)
		)
		(property "Value" ""
			(at 0 0 90)
			(layer "B.Fab")
			(effects
				(font
					(size 1.27 1.27)
				)
				(justify mirror)
			)
		)
		(duplicate_pad_numbers_are_jumpers no)
		(fp_rect
			(start 0.4953 1.6002)
			(end -0.4953 -0.2032)
			(stroke
				(width 0)
				(type default)
			)
			(fill no)
			(layer "B.CrtYd")
		)
		(fp_line
			(start -0.4953 1.6002)
			(end 0.4953 1.6002)
			(stroke
				(width 0.1)
				(type default)
			)
			(layer "B.Fab")
		)
		(fp_line
			(start 0.4953 1.6002)
			(end 0.4953 -0.2032)
			(stroke
				(width 0.1)
				(type default)
			)
			(layer "B.Fab")
		)
		(fp_line
			(start -0.4953 -0.2032)
			(end -0.4953 1.6002)
			(stroke
				(width 0.1)
				(type default)
			)
			(layer "B.Fab")
		)
		(fp_line
			(start 0.4953 -0.2032)
			(end -0.4953 -0.2032)
			(stroke
				(width 0.1)
				(type default)
			)
			(layer "B.Fab")
		)
		(pad "1" smd rect
			(at 0 0 90)
			(size 0.762 0.889)
			(layers "B.Cu" "B.Mask" "B.Paste")
			(net "PVPP_KLM")
		)
		(pad "2" smd rect
			(at 0 1.397 90)
			(size 0.762 0.889)
			(layers "B.Cu" "B.Mask" "B.Paste")
			(net "GND")
		)
		(zone
			(layer "B.Cu")
			(hatch none 0.5)
			(connect_pads
				(clearance 0)
			)
			(min_thickness 0.25)
			(keepout
				(tracks not_allowed)
				(vias allowed)
				(pads allowed)
				(copperpour not_allowed)
				(footprints allowed)
			)
			(placement
				(enabled no)
				(sheetname "")
			)
			(fill
				(thermal_gap 0.5)
				(thermal_bridge_width 0.5)
				(island_removal_mode 0)
			)
			(polygon
				(pts
					(xy 153.071068 -144.596612) (xy 153.579068 -144.596612) (xy 153.579068 -145.358612) (xy 153.071068 -145.358612)
				)
			)
		)
	)
	(footprint ""
		(layer "B.Cu")
		(at 407.465022 -17.838166 -90)
		(property "Reference" "FB1U4"
			(at 0 0 90)
			(layer "B.SilkS")
			(hide yes)
			(effects
				(font
					(size 1.27 1.27)
				)
				(justify mirror)
			)
		)
		(property "Value" ""
			(at 0 0 90)
			(layer "B.Fab")
			(effects
				(font
					(size 1.27 1.27)
				)
				(justify mirror)
			)
		)
		(duplicate_pad_numbers_are_jumpers no)
		(fp_poly
			(pts
				(xy 0.47625 -0.2413) (xy -0.47625 -0.2413) (xy -0.47625 1.5113) (xy 0.47625 1.5113)
			)
			(stroke
				(width 0)
				(type default)
			)
			(fill no)
			(layer "B.CrtYd")
		)
		(fp_line
			(start -0.47625 1.5113)
			(end 0.47625 1.5113)
			(stroke
				(width 0.1)
				(type default)
			)
			(layer "B.Fab")
		)
		(fp_line
			(start 0.47625 1.5113)
			(end 0.47625 -0.2413)
			(stroke
				(width 0.1)
				(type default)
			)
			(layer "B.Fab")
		)
		(fp_line
			(start -0.47625 -0.2413)
			(end -0.47625 1.5113)
			(stroke
				(width 0.1)
				(type default)
			)
			(layer "B.Fab")
		)
		(fp_line
			(start 0.47625 -0.2413)
			(end -0.47625 -0.2413)
			(stroke
				(width 0.1)
				(type default)
			)
			(layer "B.Fab")
		)
		(pad "1" smd rect
			(at 0 0 90)
			(size 0.762 0.889)
			(layers "B.Cu" "B.Mask" "B.Paste")
			(net "A_PVNN_STBY_PCH_SENSOR")
		)
		(pad "2" smd rect
			(at 0 1.27 90)
			(size 0.762 0.889)
			(layers "B.Cu" "B.Mask" "B.Paste")
			(net "PVNN_PCH_STBY")
		)
		(zone
			(layer "B.Cu")
			(hatch none 0.5)
			(connect_pads
				(clearance 0)
			)
			(min_thickness 0.25)
			(keepout
				(tracks not_allowed)
				(vias allowed)
				(pads allowed)
				(copperpour not_allowed)
				(footprints allowed)
			)
			(placement
				(enabled no)
				(sheetname "")
			)
			(fill
				(thermal_gap 0.5)
				(thermal_bridge_width 0.5)
				(island_removal_mode 0)
			)
			(polygon
				(pts
					(xy 406.639522 -17.452086) (xy 407.015442 -17.452086) (xy 407.015442 -18.219166) (xy 406.639522 -18.219166)
				)
			)
		)
		(zone
			(layer "B.Cu")
			(hatch none 0.5)
			(connect_pads
				(clearance 0)
			)
			(min_thickness 0.25)
			(keepout
				(tracks allowed)
				(vias not_allowed)
				(pads allowed)
				(copperpour not_allowed)
				(footprints allowed)
			)
			(placement
				(enabled no)
				(sheetname "")
			)
			(fill
				(thermal_gap 0.5)
				(thermal_bridge_width 0.5)
				(island_removal_mode 0)
			)
			(polygon
				(pts
					(xy 407.015442 -17.452086) (xy 407.015442 -18.219166) (xy 406.639522 -18.219166) (xy 406.639522 -17.452086)
				)
			)
		)
	)
	(footprint ""
		(layer "B.Cu")
		(at 437.339232 -152.32507 180)
		(property "Reference" "FB25W3"
			(at 0 0 0)
			(layer "B.SilkS")
			(hide yes)
			(effects
				(font
					(size 1.27 1.27)
				)
				(justify mirror)
			)
		)
		(property "Value" "*"
			(at 0.0127 -7.01675 180)
			(unlocked yes)
			(layer "B.Fab")
			(hide yes)
			(effects
				(font
					(size 0.889 0.889)
					(thickness 0.1524)
				)
				(justify mirror)
			)
		)
		(property "Device Type" "BLM15AG121SN-1GP_DISCRET-G-BLMA"
			(at 0.0127 -8.54075 180)
			(unlocked yes)
			(layer "B.Fab")
			(hide yes)
			(effects
				(font
					(size 0.889 0.889)
					(thickness 0.1524)
				)
				(justify mirror)
			)
		)
		(duplicate_pad_numbers_are_jumpers no)
		(fp_line
			(start 0.508 0.9398)
			(end 0.508 0.8636)
			(stroke
				(width 0.1524)
				(type default)
			)
			(layer "B.SilkS")
		)
		(fp_line
			(start 0.508 -0.9398)
			(end 0.508 0.9398)
			(stroke
				(width 0.1524)
				(type default)
			)
			(layer "B.SilkS")
		)
		(fp_line
			(start -0.508 -0.9398)
			(end 0.508 -0.9398)
			(stroke
				(width 0.1524)
				(type default)
			)
			(layer "B.SilkS")
		)
		(fp_rect
			(start 0.508 0.9398)
			(end -0.508 -0.9398)
			(stroke
				(width 0)
				(type default)
			)
			(fill no)
			(layer "B.CrtYd")
		)
		(fp_rect
			(start 0.508 0.9398)
			(end -0.508 -0.9398)
			(stroke
				(width 0)
				(type default)
			)
			(fill no)
			(layer "B.Fab")
		)
		(pad "1" smd custom
			(at 0 -0.4445)
			(size 0.1397 0.1397)
			(layers "B.Cu" "B.Mask" "B.Paste")
			(net "XDP_TRST_R_N")
			(options
				(clearance outline)
				(anchor circle)
			)
			(primitives
				(gr_poly
					(pts
						(arc
							(start -0.1778 0.2794)
							(mid -0.249642 0.249642)
							(end -0.2794 0.1778)
						)
						(arc
							(start -0.2794 -0.1778)
							(mid -0.249642 -0.249642)
							(end -0.1778 -0.2794)
						)
						(arc
							(start 0.1778 -0.2794)
							(mid 0.249642 -0.249642)
							(end 0.2794 -0.1778)
						)
						(arc
							(start 0.2794 0.1778)
							(mid 0.249642 0.249642)
							(end 0.1778 0.2794)
						)
					)
					(width 0)
					(fill yes)
				)
			)
		)
		(pad "2" smd custom
			(at 0 0.4445)
			(size 0.1397 0.1397)
			(layers "B.Cu" "B.Mask" "B.Paste")
			(net "XDP_TRST_N")
			(options
				(clearance outline)
				(anchor circle)
			)
			(primitives
				(gr_poly
					(pts
						(arc
							(start -0.1778 0.2794)
							(mid -0.249642 0.249642)
							(end -0.2794 0.1778)
						)
						(arc
							(start -0.2794 -0.1778)
							(mid -0.249642 -0.249642)
							(end -0.1778 -0.2794)
						)
						(arc
							(start 0.1778 -0.2794)
							(mid 0.249642 -0.249642)
							(end 0.2794 -0.1778)
						)
						(arc
							(start 0.2794 0.1778)
							(mid 0.249642 0.249642)
							(end 0.1778 0.2794)
						)
					)
					(width 0)
					(fill yes)
				)
			)
		)
	)
	(footprint ""
		(layer "B.Cu")
		(at 17.83842 -106.09072 90)
		(property "Reference" "C9N5"
			(at 0 0 90)
			(layer "B.SilkS")
			(hide yes)
			(effects
				(font
					(size 1.27 1.27)
				)
				(justify mirror)
			)
		)
		(property "Value" ""
			(at 0 0 90)
			(layer "B.Fab")
			(effects
				(font
					(size 1.27 1.27)
				)
				(justify mirror)
			)
		)
		(duplicate_pad_numbers_are_jumpers no)
		(fp_poly
			(pts
				(xy -0.3048 -0.1016) (xy -0.3048 0.9906) (xy 0.3048 0.9906) (xy 0.3048 -0.1016)
			)
			(stroke
				(width 0)
				(type default)
			)
			(fill no)
			(layer "B.CrtYd")
		)
		(fp_line
			(start 0.3048 -0.1016)
			(end 0.3048 0.9906)
			(stroke
				(width 0.1)
				(type default)
			)
			(layer "B.Fab")
		)
		(fp_line
			(start -0.3048 -0.1016)
			(end 0.3048 -0.1016)
			(stroke
				(width 0.1)
				(type default)
			)
			(layer "B.Fab")
		)
		(fp_line
			(start 0.3048 0.9906)
			(end -0.3048 0.9906)
			(stroke
				(width 0.1)
				(type default)
			)
			(layer "B.Fab")
		)
		(fp_line
			(start -0.3048 0.9906)
			(end -0.3048 -0.1016)
			(stroke
				(width 0.1)
				(type default)
			)
			(layer "B.Fab")
		)
		(pad "1" smd rect
			(at 0 0 270)
			(size 0.508 0.508)
			(layers "B.Cu" "B.Mask" "B.Paste")
			(net "P3E_CPU1_PE3_MP_C_TXP<13>")
		)
		(pad "2" smd rect
			(at 0 0.889 270)
			(size 0.508 0.508)
			(layers "B.Cu" "B.Mask" "B.Paste")
			(net "P3E_CPU1_PE3_MP_TXP<13>")
		)
		(zone
			(layer "B.Cu")
			(hatch none 0.5)
			(connect_pads
				(clearance 0)
			)
			(min_thickness 0.25)
			(keepout
				(tracks allowed)
				(vias not_allowed)
				(pads allowed)
				(copperpour not_allowed)
				(footprints allowed)
			)
			(placement
				(enabled no)
				(sheetname "")
			)
			(fill
				(thermal_gap 0.5)
				(thermal_bridge_width 0.5)
				(island_removal_mode 0)
			)
			(polygon
				(pts
					(xy 18.09242 -106.34472) (xy 18.09242 -105.83672) (xy 18.47342 -105.83672) (xy 18.47342 -106.34472)
				)
			)
		)
		(zone
			(layer "B.Cu")
			(hatch none 0.5)
			(connect_pads
				(clearance 0)
			)
			(min_thickness 0.25)
			(keepout
				(tracks not_allowed)
				(vias allowed)
				(pads allowed)
				(copperpour not_allowed)
				(footprints allowed)
			)
			(placement
				(enabled no)
				(sheetname "")
			)
			(fill
				(thermal_gap 0.5)
				(thermal_bridge_width 0.5)
				(island_removal_mode 0)
			)
			(polygon
				(pts
					(xy 18.47342 -106.34472) (xy 18.47342 -105.83672) (xy 18.09242 -105.83672) (xy 18.09242 -106.34472)
				)
			)
		)
	)
	(footprint ""
		(layer "B.Cu")
		(at 195.453 -144.977612 90)
		(property "Reference" "C6L6"
			(at 0 0 90)
			(layer "B.SilkS")
			(hide yes)
			(effects
				(font
					(size 1.27 1.27)
				)
				(justify mirror)
			)
		)
		(property "Value" ""
			(at 0 0 90)
			(layer "B.Fab")
			(effects
				(font
					(size 1.27 1.27)
				)
				(justify mirror)
			)
		)
		(duplicate_pad_numbers_are_jumpers no)
		(fp_poly
			(pts
				(xy -0.3048 -0.1016) (xy -0.3048 0.9906) (xy 0.3048 0.9906) (xy 0.3048 -0.1016)
			)
			(stroke
				(width 0)
				(type default)
			)
			(fill no)
			(layer "B.CrtYd")
		)
		(fp_line
			(start 0.3048 -0.1016)
			(end 0.3048 0.9906)
			(stroke
				(width 0.1)
				(type default)
			)
			(layer "B.Fab")
		)
		(fp_line
			(start -0.3048 -0.1016)
			(end 0.3048 -0.1016)
			(stroke
				(width 0.1)
				(type default)
			)
			(layer "B.Fab")
		)
		(fp_line
			(start 0.3048 0.9906)
			(end -0.3048 0.9906)
			(stroke
				(width 0.1)
				(type default)
			)
			(layer "B.Fab")
		)
		(fp_line
			(start -0.3048 0.9906)
			(end -0.3048 -0.1016)
			(stroke
				(width 0.1)
				(type default)
			)
			(layer "B.Fab")
		)
		(pad "1" smd rect
			(at 0 0 270)
			(size 0.508 0.508)
			(layers "B.Cu" "B.Mask" "B.Paste")
			(net "M_E_VREF")
		)
		(pad "2" smd rect
			(at 0 0.889 270)
			(size 0.508 0.508)
			(layers "B.Cu" "B.Mask" "B.Paste")
			(net "GND")
		)
		(zone
			(layer "B.Cu")
			(hatch none 0.5)
			(connect_pads
				(clearance 0)
			)
			(min_thickness 0.25)
			(keepout
				(tracks allowed)
				(vias not_allowed)
				(pads allowed)
				(copperpour not_allowed)
				(footprints allowed)
			)
			(placement
				(enabled no)
				(sheetname "")
			)
			(fill
				(thermal_gap 0.5)
				(thermal_bridge_width 0.5)
				(island_removal_mode 0)
			)
			(polygon
				(pts
					(xy 195.707 -145.231612) (xy 195.707 -144.723612) (xy 196.088 -144.723612) (xy 196.088 -145.231612)
				)
			)
		)
		(zone
			(layer "B.Cu")
			(hatch none 0.5)
			(connect_pads
				(clearance 0)
			)
			(min_thickness 0.25)
			(keepout
				(tracks not_allowed)
				(vias allowed)
				(pads allowed)
				(copperpour not_allowed)
				(footprints allowed)
			)
			(placement
				(enabled no)
				(sheetname "")
			)
			(fill
				(thermal_gap 0.5)
				(thermal_bridge_width 0.5)
				(island_removal_mode 0)
			)
			(polygon
				(pts
					(xy 196.088 -145.231612) (xy 196.088 -144.723612) (xy 195.707 -144.723612) (xy 195.707 -145.231612)
				)
			)
		)
	)
	(footprint ""
		(layer "B.Cu")
		(at 444.701168 -146.393662 180)
		(property "Reference" "U25W15"
			(at 0.14986 2.621788 180)
			(unlocked yes)
			(layer "B.SilkS")
			(effects
				(font
					(size 1.27 0.964946)
					(thickness 0.000001)
				)
				(justify left mirror)
			)
		)
		(property "Value" ""
			(at 0 0 0)
			(layer "B.Fab")
			(effects
				(font
					(size 1.27 1.27)
				)
				(justify mirror)
			)
		)
		(duplicate_pad_numbers_are_jumpers no)
		(fp_circle
			(center 0.4699 -0.8382)
			(end 0.3429 -0.8382)
			(stroke
				(width 0.254)
				(type default)
			)
			(fill no)
			(layer "B.SilkS")
		)
		(fp_poly
			(pts
				(xy -0.21463 -0.450088) (xy -1.56337 -0.450088) (xy -1.56337 1.75006) (xy -0.21463 1.75006)
			)
			(stroke
				(width 0)
				(type default)
			)
			(fill no)
			(layer "B.CrtYd")
		)
		(fp_line
			(start -0.21463 1.75006)
			(end -0.21463 -0.450088)
			(stroke
				(width 0.1)
				(type default)
			)
			(layer "B.Fab")
		)
		(fp_line
			(start -0.21463 -0.450088)
			(end -1.56337 -0.450088)
			(stroke
				(width 0.1)
				(type default)
			)
			(layer "B.Fab")
		)
		(fp_line
			(start -1.56337 1.75006)
			(end -0.21463 1.75006)
			(stroke
				(width 0.1)
				(type default)
			)
			(layer "B.Fab")
		)
		(fp_line
			(start -1.56337 -0.450088)
			(end -1.56337 1.75006)
			(stroke
				(width 0.1)
				(type default)
			)
			(layer "B.Fab")
		)
		(fp_circle
			(center 0.4699 -0.8382)
			(end 0.3429 -0.8382)
			(stroke
				(width 0.254)
				(type default)
			)
			(fill no)
			(layer "B.Fab")
		)
		(pad "1" smd rect
			(at 0 0)
			(size 1.016 0.381)
			(layers "B.Cu" "B.Mask" "B.Paste")
			(net "Net_6508")
		)
		(pad "2" smd rect
			(at 0 0.649986)
			(size 1.016 0.381)
			(layers "B.Cu" "B.Mask" "B.Paste")
			(net "BMC_DEBUG_EN_N")
		)
		(pad "3" smd rect
			(at 0 1.299972)
			(size 1.016 0.381)
			(layers "B.Cu" "B.Mask" "B.Paste")
			(net "GND")
		)
		(pad "4" smd rect
			(at -1.778 1.299972)
			(size 1.016 0.381)
			(layers "B.Cu" "B.Mask" "B.Paste")
			(net "CPU_XDP_PRESENT_N")
		)
		(pad "5" smd rect
			(at -1.778 0)
			(size 1.016 0.381)
			(layers "B.Cu" "B.Mask" "B.Paste")
			(net "P3V3_STBY")
		)
	)
	(footprint ""
		(layer "B.Cu")
		(at 481.3808 -113.1062 90)
		(property "Reference" "C1M24"
			(at 0 0 90)
			(layer "B.SilkS")
			(hide yes)
			(effects
				(font
					(size 1.27 1.27)
				)
				(justify mirror)
			)
		)
		(property "Value" ""
			(at 0 0 90)
			(layer "B.Fab")
			(effects
				(font
					(size 1.27 1.27)
				)
				(justify mirror)
			)
		)
		(duplicate_pad_numbers_are_jumpers no)
		(fp_rect
			(start 0.3048 0.9906)
			(end -0.3048 -0.1016)
			(stroke
				(width 0)
				(type default)
			)
			(fill no)
			(layer "B.CrtYd")
		)
		(fp_line
			(start 0.3048 -0.1016)
			(end 0.3048 0.9906)
			(stroke
				(width 0.1)
				(type default)
			)
			(layer "B.Fab")
		)
		(fp_line
			(start -0.3048 -0.1016)
			(end 0.3048 -0.1016)
			(stroke
				(width 0.1)
				(type default)
			)
			(layer "B.Fab")
		)
		(fp_line
			(start 0.3048 0.9906)
			(end -0.3048 0.9906)
			(stroke
				(width 0.1)
				(type default)
			)
			(layer "B.Fab")
		)
		(fp_line
			(start -0.3048 0.9906)
			(end -0.3048 -0.1016)
			(stroke
				(width 0.1)
				(type default)
			)
			(layer "B.Fab")
		)
		(pad "1" smd rect
			(at 0 0 270)
			(size 0.508 0.508)
			(layers "B.Cu" "B.Mask" "B.Paste")
			(net "P3V3")
		)
		(pad "2" smd rect
			(at 0 0.889 270)
			(size 0.508 0.508)
			(layers "B.Cu" "B.Mask" "B.Paste")
			(net "GND")
		)
		(zone
			(layer "B.Cu")
			(hatch none 0.5)
			(connect_pads
				(clearance 0)
			)
			(min_thickness 0.25)
			(keepout
				(tracks allowed)
				(vias not_allowed)
				(pads allowed)
				(copperpour not_allowed)
				(footprints allowed)
			)
			(placement
				(enabled no)
				(sheetname "")
			)
			(fill
				(thermal_gap 0.5)
				(thermal_bridge_width 0.5)
				(island_removal_mode 0)
			)
			(polygon
				(pts
					(xy 482.0158 -113.3602) (xy 481.6348 -113.3602) (xy 481.6348 -112.8522) (xy 482.0158 -112.8522)
				)
			)
		)
		(zone
			(layer "B.Cu")
			(hatch none 0.5)
			(connect_pads
				(clearance 0)
			)
			(min_thickness 0.25)
			(keepout
				(tracks not_allowed)
				(vias allowed)
				(pads allowed)
				(copperpour not_allowed)
				(footprints allowed)
			)
			(placement
				(enabled no)
				(sheetname "")
			)
			(fill
				(thermal_gap 0.5)
				(thermal_bridge_width 0.5)
				(island_removal_mode 0)
			)
			(polygon
				(pts
					(xy 482.0158 -113.3602) (xy 481.6348 -113.3602) (xy 481.6348 -112.8522) (xy 482.0158 -112.8522)
				)
			)
		)
	)
	(footprint ""
		(layer "B.Cu")
		(at 427.482 -42.0751 -90)
		(property "Reference" "FB2T5"
			(at 0 0 90)
			(layer "B.SilkS")
			(hide yes)
			(effects
				(font
					(size 1.27 1.27)
				)
				(justify mirror)
			)
		)
		(property "Value" "*"
			(at -0.0254 -2.8829 270)
			(unlocked yes)
			(layer "B.Fab")
			(hide yes)
			(effects
				(font
					(size 1.27 1.016)
					(thickness 0.1524)
				)
				(justify mirror)
			)
		)
		(property "Device Type" "HCB1608KF-800T30-GP_DISCRET-G9A"
			(at -0.0254 -4.4069 270)
			(unlocked yes)
			(layer "B.Fab")
			(hide yes)
			(effects
				(font
					(size 1.27 1.016)
					(thickness 0.1524)
				)
				(justify mirror)
			)
		)
		(duplicate_pad_numbers_are_jumpers no)
		(fp_line
			(start -0.254 0)
			(end 0.254 0)
			(stroke
				(width 0.2032)
				(type default)
			)
			(layer "B.SilkS")
		)
		(fp_rect
			(start 0.5842 1.3335)
			(end -0.5842 -1.3335)
			(stroke
				(width 0)
				(type default)
			)
			(fill no)
			(layer "B.CrtYd")
		)
		(fp_rect
			(start 0.5842 1.3335)
			(end -0.5842 -1.3335)
			(stroke
				(width 0)
				(type default)
			)
			(fill no)
			(layer "B.Fab")
		)
		(pad "1" smd custom
			(at 0 -0.762 90)
			(size 0.2159 0.2159)
			(layers "B.Cu" "B.Mask" "B.Paste")
			(net "P3V3_STBY")
			(options
				(clearance outline)
				(anchor circle)
			)
			(primitives
				(gr_poly
					(pts
						(arc
							(start -0.3302 0.4318)
							(mid -0.402042 0.402042)
							(end -0.4318 0.3302)
						)
						(arc
							(start -0.4318 -0.3302)
							(mid -0.402042 -0.402042)
							(end -0.3302 -0.4318)
						)
						(arc
							(start 0.3302 -0.4318)
							(mid 0.402042 -0.402042)
							(end 0.4318 -0.3302)
						)
						(arc
							(start 0.4318 0.3302)
							(mid 0.402042 0.402042)
							(end 0.3302 0.4318)
						)
					)
					(width 0)
					(fill yes)
				)
			)
		)
		(pad "2" smd custom
			(at 0 0.762 90)
			(size 0.2159 0.2159)
			(layers "B.Cu" "B.Mask" "B.Paste")
			(net "VCC_PA_3V3")
			(options
				(clearance outline)
				(anchor circle)
			)
			(primitives
				(gr_poly
					(pts
						(arc
							(start -0.3302 0.4318)
							(mid -0.402042 0.402042)
							(end -0.4318 0.3302)
						)
						(arc
							(start -0.4318 -0.3302)
							(mid -0.402042 -0.402042)
							(end -0.3302 -0.4318)
						)
						(arc
							(start 0.3302 -0.4318)
							(mid 0.402042 -0.402042)
							(end 0.4318 -0.3302)
						)
						(arc
							(start 0.4318 0.3302)
							(mid 0.402042 0.402042)
							(end 0.3302 0.4318)
						)
					)
					(width 0)
					(fill yes)
				)
			)
		)
	)
	(footprint ""
		(layer "B.Cu")
		(at 348.234 -83.5406)
		(property "Reference" "C3P4"
			(at 0 0 0)
			(layer "B.SilkS")
			(hide yes)
			(effects
				(font
					(size 1.27 1.27)
				)
				(justify mirror)
			)
		)
		(property "Value" ""
			(at 0 0 0)
			(layer "B.Fab")
			(effects
				(font
					(size 1.27 1.27)
				)
				(justify mirror)
			)
		)
		(duplicate_pad_numbers_are_jumpers no)
		(fp_poly
			(pts
				(xy -0.3048 -0.1016) (xy -0.3048 0.9906) (xy 0.3048 0.9906) (xy 0.3048 -0.1016)
			)
			(stroke
				(width 0)
				(type default)
			)
			(fill no)
			(layer "B.CrtYd")
		)
		(fp_line
			(start -0.3048 -0.1016)
			(end 0.3048 -0.1016)
			(stroke
				(width 0.1)
				(type default)
			)
			(layer "B.Fab")
		)
		(fp_line
			(start -0.3048 0.9906)
			(end -0.3048 -0.1016)
			(stroke
				(width 0.1)
				(type default)
			)
			(layer "B.Fab")
		)
		(fp_line
			(start 0.3048 -0.1016)
			(end 0.3048 0.9906)
			(stroke
				(width 0.1)
				(type default)
			)
			(layer "B.Fab")
		)
		(fp_line
			(start 0.3048 0.9906)
			(end -0.3048 0.9906)
			(stroke
				(width 0.1)
				(type default)
			)
			(layer "B.Fab")
		)
		(pad "1" smd rect
			(at 0 0 180)
			(size 0.508 0.508)
			(layers "B.Cu" "B.Mask" "B.Paste")
			(net "VR_PVCCIO_CPU0_VD12")
		)
		(pad "2" smd rect
			(at 0 0.889 180)
			(size 0.508 0.508)
			(layers "B.Cu" "B.Mask" "B.Paste")
			(net "GND")
		)
		(zone
			(layer "B.Cu")
			(hatch none 0.5)
			(connect_pads
				(clearance 0)
			)
			(min_thickness 0.25)
			(keepout
				(tracks allowed)
				(vias not_allowed)
				(pads allowed)
				(copperpour not_allowed)
				(footprints allowed)
			)
			(placement
				(enabled no)
				(sheetname "")
			)
			(fill
				(thermal_gap 0.5)
				(thermal_bridge_width 0.5)
				(island_removal_mode 0)
			)
			(polygon
				(pts
					(xy 348.488 -83.2866) (xy 347.98 -83.2866) (xy 347.98 -82.9056) (xy 348.488 -82.9056)
				)
			)
		)
		(zone
			(layer "B.Cu")
			(hatch none 0.5)
			(connect_pads
				(clearance 0)
			)
			(min_thickness 0.25)
			(keepout
				(tracks not_allowed)
				(vias allowed)
				(pads allowed)
				(copperpour not_allowed)
				(footprints allowed)
			)
			(placement
				(enabled no)
				(sheetname "")
			)
			(fill
				(thermal_gap 0.5)
				(thermal_bridge_width 0.5)
				(island_removal_mode 0)
			)
			(polygon
				(pts
					(xy 348.488 -82.9056) (xy 347.98 -82.9056) (xy 347.98 -83.2866) (xy 348.488 -83.2866)
				)
			)
		)
	)
	(footprint ""
		(layer "B.Cu")
		(at 449.9864 -8.0518 -90)
		(property "Reference" "R2U43"
			(at 0 0 90)
			(layer "B.SilkS")
			(hide yes)
			(effects
				(font
					(size 1.27 1.27)
				)
				(justify mirror)
			)
		)
		(property "Value" ""
			(at 0 0 90)
			(layer "B.Fab")
			(effects
				(font
					(size 1.27 1.27)
				)
				(justify mirror)
			)
		)
		(duplicate_pad_numbers_are_jumpers no)
		(fp_poly
			(pts
				(xy 0.2794 -0.1016) (xy -0.2794 -0.1016) (xy -0.2794 0.9906) (xy 0.2794 0.9906)
			)
			(stroke
				(width 0)
				(type default)
			)
			(fill no)
			(layer "B.CrtYd")
		)
		(fp_line
			(start -0.2794 0.9906)
			(end -0.2794 -0.1016)
			(stroke
				(width 0.1)
				(type default)
			)
			(layer "B.Fab")
		)
		(fp_line
			(start 0.2794 0.9906)
			(end -0.2794 0.9906)
			(stroke
				(width 0.1)
				(type default)
			)
			(layer "B.Fab")
		)
		(fp_line
			(start -0.2794 -0.1016)
			(end 0.2794 -0.1016)
			(stroke
				(width 0.1)
				(type default)
			)
			(layer "B.Fab")
		)
		(fp_line
			(start 0.2794 -0.1016)
			(end 0.2794 0.9906)
			(stroke
				(width 0.1)
				(type default)
			)
			(layer "B.Fab")
		)
		(pad "1" smd rect
			(at 0 0 90)
			(size 0.508 0.508)
			(layers "B.Cu" "B.Mask" "B.Paste")
			(net "P3V_BAT_SOURCE")
		)
		(pad "2" smd rect
			(at 0 0.889 90)
			(size 0.508 0.508)
			(layers "B.Cu" "B.Mask" "B.Paste")
			(net "A_P3V_BAT_R")
		)
		(zone
			(layer "B.Cu")
			(hatch none 0.5)
			(connect_pads
				(clearance 0)
			)
			(min_thickness 0.25)
			(keepout
				(tracks not_allowed)
				(vias allowed)
				(pads allowed)
				(copperpour not_allowed)
				(footprints allowed)
			)
			(placement
				(enabled no)
				(sheetname "")
			)
			(fill
				(thermal_gap 0.5)
				(thermal_bridge_width 0.5)
				(island_removal_mode 0)
			)
			(polygon
				(pts
					(xy 449.3514 -7.7978) (xy 449.3514 -8.3058) (xy 449.7324 -8.3058) (xy 449.7324 -7.7978)
				)
			)
		)
		(zone
			(layer "B.Cu")
			(hatch none 0.5)
			(connect_pads
				(clearance 0)
			)
			(min_thickness 0.25)
			(keepout
				(tracks allowed)
				(vias not_allowed)
				(pads allowed)
				(copperpour not_allowed)
				(footprints allowed)
			)
			(placement
				(enabled no)
				(sheetname "")
			)
			(fill
				(thermal_gap 0.5)
				(thermal_bridge_width 0.5)
				(island_removal_mode 0)
			)
			(polygon
				(pts
					(xy 449.7324 -7.7978) (xy 449.7324 -8.3058) (xy 449.3514 -8.3058) (xy 449.3514 -7.7978)
				)
			)
		)
	)
	(footprint ""
		(layer "B.Cu")
		(at 472.127326 -15.951962)
		(property "Reference" "C2U2"
			(at 0 0 0)
			(layer "B.SilkS")
			(hide yes)
			(effects
				(font
					(size 1.27 1.27)
				)
				(justify mirror)
			)
		)
		(property "Value" ""
			(at 0 0 0)
			(layer "B.Fab")
			(effects
				(font
					(size 1.27 1.27)
				)
				(justify mirror)
			)
		)
		(duplicate_pad_numbers_are_jumpers no)
		(fp_rect
			(start 0.7239 -0.2159)
			(end -0.7239 1.9939)
			(stroke
				(width 0)
				(type default)
			)
			(fill no)
			(layer "B.CrtYd")
		)
		(fp_line
			(start -0.7239 -0.2159)
			(end 0.7239 -0.2159)
			(stroke
				(width 0.1)
				(type default)
			)
			(layer "B.Fab")
		)
		(fp_line
			(start -0.7239 1.9939)
			(end -0.7239 -0.2159)
			(stroke
				(width 0.1)
				(type default)
			)
			(layer "B.Fab")
		)
		(fp_line
			(start 0.7239 -0.2159)
			(end 0.7239 1.9939)
			(stroke
				(width 0.1)
				(type default)
			)
			(layer "B.Fab")
		)
		(fp_line
			(start 0.7239 1.9939)
			(end -0.7239 1.9939)
			(stroke
				(width 0.1)
				(type default)
			)
			(layer "B.Fab")
		)
		(pad "1" smd rect
			(at 0 0 180)
			(size 1.27 1.016)
			(layers "B.Cu" "B.Mask" "B.Paste")
			(net "P3V3")
		)
		(pad "2" smd rect
			(at 0 1.778 180)
			(size 1.27 1.016)
			(layers "B.Cu" "B.Mask" "B.Paste")
			(net "GND")
		)
		(zone
			(layer "B.Cu")
			(hatch none 0.5)
			(connect_pads
				(clearance 0)
			)
			(min_thickness 0.25)
			(keepout
				(tracks not_allowed)
				(vias allowed)
				(pads allowed)
				(copperpour not_allowed)
				(footprints allowed)
			)
			(placement
				(enabled no)
				(sheetname "")
			)
			(fill
				(thermal_gap 0.5)
				(thermal_bridge_width 0.5)
				(island_removal_mode 0)
			)
			(polygon
				(pts
					(xy 472.762326 -15.443962) (xy 471.492326 -15.443962) (xy 471.492326 -14.681962) (xy 472.762326 -14.681962)
				)
			)
		)
	)
	(footprint ""
		(layer "B.Cu")
		(at 80.153002 -86.743286 -90)
		(property "Reference" "R8P2"
			(at 0 0 90)
			(layer "B.SilkS")
			(hide yes)
			(effects
				(font
					(size 1.27 1.27)
				)
				(justify mirror)
			)
		)
		(property "Value" ""
			(at 0 0 90)
			(layer "B.Fab")
			(effects
				(font
					(size 1.27 1.27)
				)
				(justify mirror)
			)
		)
		(duplicate_pad_numbers_are_jumpers no)
		(fp_poly
			(pts
				(xy 0.2794 -0.1016) (xy -0.2794 -0.1016) (xy -0.2794 0.9906) (xy 0.2794 0.9906)
			)
			(stroke
				(width 0)
				(type default)
			)
			(fill no)
			(layer "B.CrtYd")
		)
		(fp_line
			(start -0.2794 0.9906)
			(end -0.2794 -0.1016)
			(stroke
				(width 0.1)
				(type default)
			)
			(layer "B.Fab")
		)
		(fp_line
			(start 0.2794 0.9906)
			(end -0.2794 0.9906)
			(stroke
				(width 0.1)
				(type default)
			)
			(layer "B.Fab")
		)
		(fp_line
			(start -0.2794 -0.1016)
			(end 0.2794 -0.1016)
			(stroke
				(width 0.1)
				(type default)
			)
			(layer "B.Fab")
		)
		(fp_line
			(start 0.2794 -0.1016)
			(end 0.2794 0.9906)
			(stroke
				(width 0.1)
				(type default)
			)
			(layer "B.Fab")
		)
		(pad "1" smd rect
			(at 0 0 90)
			(size 0.508 0.508)
			(layers "B.Cu" "B.Mask" "B.Paste")
			(net "PD_CPU1_TEST13")
		)
		(pad "2" smd rect
			(at 0 0.889 90)
			(size 0.508 0.508)
			(layers "B.Cu" "B.Mask" "B.Paste")
			(net "GND")
		)
		(zone
			(layer "B.Cu")
			(hatch none 0.5)
			(connect_pads
				(clearance 0)
			)
			(min_thickness 0.25)
			(keepout
				(tracks not_allowed)
				(vias allowed)
				(pads allowed)
				(copperpour not_allowed)
				(footprints allowed)
			)
			(placement
				(enabled no)
				(sheetname "")
			)
			(fill
				(thermal_gap 0.5)
				(thermal_bridge_width 0.5)
				(island_removal_mode 0)
			)
			(polygon
				(pts
					(xy 79.518002 -86.489286) (xy 79.518002 -86.997286) (xy 79.899002 -86.997286) (xy 79.899002 -86.489286)
				)
			)
		)
		(zone
			(layer "B.Cu")
			(hatch none 0.5)
			(connect_pads
				(clearance 0)
			)
			(min_thickness 0.25)
			(keepout
				(tracks allowed)
				(vias not_allowed)
				(pads allowed)
				(copperpour not_allowed)
				(footprints allowed)
			)
			(placement
				(enabled no)
				(sheetname "")
			)
			(fill
				(thermal_gap 0.5)
				(thermal_bridge_width 0.5)
				(island_removal_mode 0)
			)
			(polygon
				(pts
					(xy 79.899002 -86.489286) (xy 79.899002 -86.997286) (xy 79.518002 -86.997286) (xy 79.518002 -86.489286)
				)
			)
		)
	)
	(footprint ""
		(layer "B.Cu")
		(at 393.286234 -152.73274 90)
		(property "Reference" "C2L8"
			(at 0 0 90)
			(layer "B.SilkS")
			(hide yes)
			(effects
				(font
					(size 1.27 1.27)
				)
				(justify mirror)
			)
		)
		(property "Value" ""
			(at 0 0 90)
			(layer "B.Fab")
			(effects
				(font
					(size 1.27 1.27)
				)
				(justify mirror)
			)
		)
		(duplicate_pad_numbers_are_jumpers no)
		(fp_poly
			(pts
				(xy -0.3048 -0.1016) (xy -0.3048 0.9906) (xy 0.3048 0.9906) (xy 0.3048 -0.1016)
			)
			(stroke
				(width 0)
				(type default)
			)
			(fill no)
			(layer "B.CrtYd")
		)
		(fp_line
			(start 0.3048 -0.1016)
			(end 0.3048 0.9906)
			(stroke
				(width 0.1)
				(type default)
			)
			(layer "B.Fab")
		)
		(fp_line
			(start -0.3048 -0.1016)
			(end 0.3048 -0.1016)
			(stroke
				(width 0.1)
				(type default)
			)
			(layer "B.Fab")
		)
		(fp_line
			(start 0.3048 0.9906)
			(end -0.3048 0.9906)
			(stroke
				(width 0.1)
				(type default)
			)
			(layer "B.Fab")
		)
		(fp_line
			(start -0.3048 0.9906)
			(end -0.3048 -0.1016)
			(stroke
				(width 0.1)
				(type default)
			)
			(layer "B.Fab")
		)
		(pad "1" smd rect
			(at 0 0 270)
			(size 0.508 0.508)
			(layers "B.Cu" "B.Mask" "B.Paste")
			(net "VR_PVNN_PCH_VDD")
		)
		(pad "2" smd rect
			(at 0 0.889 270)
			(size 0.508 0.508)
			(layers "B.Cu" "B.Mask" "B.Paste")
			(net "GND")
		)
		(zone
			(layer "B.Cu")
			(hatch none 0.5)
			(connect_pads
				(clearance 0)
			)
			(min_thickness 0.25)
			(keepout
				(tracks allowed)
				(vias not_allowed)
				(pads allowed)
				(copperpour not_allowed)
				(footprints allowed)
			)
			(placement
				(enabled no)
				(sheetname "")
			)
			(fill
				(thermal_gap 0.5)
				(thermal_bridge_width 0.5)
				(island_removal_mode 0)
			)
			(polygon
				(pts
					(xy 393.540234 -152.98674) (xy 393.540234 -152.47874) (xy 393.921234 -152.47874) (xy 393.921234 -152.98674)
				)
			)
		)
		(zone
			(layer "B.Cu")
			(hatch none 0.5)
			(connect_pads
				(clearance 0)
			)
			(min_thickness 0.25)
			(keepout
				(tracks not_allowed)
				(vias allowed)
				(pads allowed)
				(copperpour not_allowed)
				(footprints allowed)
			)
			(placement
				(enabled no)
				(sheetname "")
			)
			(fill
				(thermal_gap 0.5)
				(thermal_bridge_width 0.5)
				(island_removal_mode 0)
			)
			(polygon
				(pts
					(xy 393.921234 -152.98674) (xy 393.921234 -152.47874) (xy 393.540234 -152.47874) (xy 393.540234 -152.98674)
				)
			)
		)
	)
	(footprint ""
		(layer "B.Cu")
		(at 401.599146 -36.331652 90)
		(property "Reference" "R25W105"
			(at 0.8382 -0.67818 90)
			(unlocked yes)
			(layer "B.SilkS")
			(effects
				(font
					(size 0.4064 0.254)
					(thickness 0.1524)
				)
				(justify left mirror)
			)
		)
		(property "Value" ""
			(at 0 0 90)
			(layer "B.Fab")
			(effects
				(font
					(size 1.27 1.27)
				)
				(justify mirror)
			)
		)
		(duplicate_pad_numbers_are_jumpers no)
		(fp_poly
			(pts
				(xy 0.2794 -0.1016) (xy -0.2794 -0.1016) (xy -0.2794 0.9906) (xy 0.2794 0.9906)
			)
			(stroke
				(width 0)
				(type default)
			)
			(fill no)
			(layer "B.CrtYd")
		)
		(fp_line
			(start 0.2794 -0.1016)
			(end 0.2794 0.9906)
			(stroke
				(width 0.1)
				(type default)
			)
			(layer "B.Fab")
		)
		(fp_line
			(start -0.2794 -0.1016)
			(end 0.2794 -0.1016)
			(stroke
				(width 0.1)
				(type default)
			)
			(layer "B.Fab")
		)
		(fp_line
			(start 0.2794 0.9906)
			(end -0.2794 0.9906)
			(stroke
				(width 0.1)
				(type default)
			)
			(layer "B.Fab")
		)
		(fp_line
			(start -0.2794 0.9906)
			(end -0.2794 -0.1016)
			(stroke
				(width 0.1)
				(type default)
			)
			(layer "B.Fab")
		)
		(pad "1" smd rect
			(at 0 0 270)
			(size 0.508 0.508)
			(layers "B.Cu" "B.Mask" "B.Paste")
			(net "P3V3_STBY")
		)
		(pad "2" smd rect
			(at 0 0.889 270)
			(size 0.508 0.508)
			(layers "B.Cu" "B.Mask" "B.Paste")
			(net "PU_JTAG_BMC_RTCK")
		)
		(zone
			(layer "B.Cu")
			(hatch none 0.5)
			(connect_pads
				(clearance 0)
			)
			(min_thickness 0.25)
			(keepout
				(tracks allowed)
				(vias not_allowed)
				(pads allowed)
				(copperpour not_allowed)
				(footprints allowed)
			)
			(placement
				(enabled no)
				(sheetname "")
			)
			(fill
				(thermal_gap 0.5)
				(thermal_bridge_width 0.5)
				(island_removal_mode 0)
			)
			(polygon
				(pts
					(xy 401.853146 -36.585652) (xy 401.853146 -36.077652) (xy 402.234146 -36.077652) (xy 402.234146 -36.585652)
				)
			)
		)
		(zone
			(layer "B.Cu")
			(hatch none 0.5)
			(connect_pads
				(clearance 0)
			)
			(min_thickness 0.25)
			(keepout
				(tracks not_allowed)
				(vias allowed)
				(pads allowed)
				(copperpour not_allowed)
				(footprints allowed)
			)
			(placement
				(enabled no)
				(sheetname "")
			)
			(fill
				(thermal_gap 0.5)
				(thermal_bridge_width 0.5)
				(island_removal_mode 0)
			)
			(polygon
				(pts
					(xy 402.234146 -36.585652) (xy 402.234146 -36.077652) (xy 401.853146 -36.077652) (xy 401.853146 -36.585652)
				)
			)
		)
	)
	(footprint ""
		(layer "B.Cu")
		(at 410.464 -152.273 90)
		(property "Reference" "C2L12"
			(at 0 0 90)
			(layer "B.SilkS")
			(hide yes)
			(effects
				(font
					(size 1.27 1.27)
				)
				(justify mirror)
			)
		)
		(property "Value" ""
			(at 0 0 90)
			(layer "B.Fab")
			(effects
				(font
					(size 1.27 1.27)
				)
				(justify mirror)
			)
		)
		(duplicate_pad_numbers_are_jumpers no)
		(fp_poly
			(pts
				(xy -0.3048 -0.1016) (xy -0.3048 0.9906) (xy 0.3048 0.9906) (xy 0.3048 -0.1016)
			)
			(stroke
				(width 0)
				(type default)
			)
			(fill no)
			(layer "B.CrtYd")
		)
		(fp_line
			(start 0.3048 -0.1016)
			(end 0.3048 0.9906)
			(stroke
				(width 0.1)
				(type default)
			)
			(layer "B.Fab")
		)
		(fp_line
			(start -0.3048 -0.1016)
			(end 0.3048 -0.1016)
			(stroke
				(width 0.1)
				(type default)
			)
			(layer "B.Fab")
		)
		(fp_line
			(start 0.3048 0.9906)
			(end -0.3048 0.9906)
			(stroke
				(width 0.1)
				(type default)
			)
			(layer "B.Fab")
		)
		(fp_line
			(start -0.3048 0.9906)
			(end -0.3048 -0.1016)
			(stroke
				(width 0.1)
				(type default)
			)
			(layer "B.Fab")
		)
		(pad "1" smd rect
			(at 0 0 270)
			(size 0.508 0.508)
			(layers "B.Cu" "B.Mask" "B.Paste")
			(net "SATA6G_PCH_PCIE_UP_SATA_RXP<5>")
		)
		(pad "2" smd rect
			(at 0 0.889 270)
			(size 0.508 0.508)
			(layers "B.Cu" "B.Mask" "B.Paste")
			(net "SATA6G_P5_RX_C_DP")
		)
		(zone
			(layer "B.Cu")
			(hatch none 0.5)
			(connect_pads
				(clearance 0)
			)
			(min_thickness 0.25)
			(keepout
				(tracks allowed)
				(vias not_allowed)
				(pads allowed)
				(copperpour not_allowed)
				(footprints allowed)
			)
			(placement
				(enabled no)
				(sheetname "")
			)
			(fill
				(thermal_gap 0.5)
				(thermal_bridge_width 0.5)
				(island_removal_mode 0)
			)
			(polygon
				(pts
					(xy 410.718 -152.527) (xy 410.718 -152.019) (xy 411.099 -152.019) (xy 411.099 -152.527)
				)
			)
		)
		(zone
			(layer "B.Cu")
			(hatch none 0.5)
			(connect_pads
				(clearance 0)
			)
			(min_thickness 0.25)
			(keepout
				(tracks not_allowed)
				(vias allowed)
				(pads allowed)
				(copperpour not_allowed)
				(footprints allowed)
			)
			(placement
				(enabled no)
				(sheetname "")
			)
			(fill
				(thermal_gap 0.5)
				(thermal_bridge_width 0.5)
				(island_removal_mode 0)
			)
			(polygon
				(pts
					(xy 411.099 -152.527) (xy 411.099 -152.019) (xy 410.718 -152.019) (xy 410.718 -152.527)
				)
			)
		)
	)
	(footprint ""
		(layer "B.Cu")
		(at 450.8627 -144.1831 -90)
		(property "Reference" "FB25W4"
			(at 0 0 90)
			(layer "B.SilkS")
			(hide yes)
			(effects
				(font
					(size 1.27 1.27)
				)
				(justify mirror)
			)
		)
		(property "Value" "*"
			(at 0.0127 -7.01675 270)
			(unlocked yes)
			(layer "B.Fab")
			(hide yes)
			(effects
				(font
					(size 0.889 0.889)
					(thickness 0.1524)
				)
				(justify mirror)
			)
		)
		(property "Device Type" "BLM15AG121SN-1GP_DISCRET-G-BLMA"
			(at 0.0127 -8.54075 270)
			(unlocked yes)
			(layer "B.Fab")
			(hide yes)
			(effects
				(font
					(size 0.889 0.889)
					(thickness 0.1524)
				)
				(justify mirror)
			)
		)
		(duplicate_pad_numbers_are_jumpers no)
		(fp_line
			(start 0.508 0.9398)
			(end 0.508 0.8636)
			(stroke
				(width 0.1524)
				(type default)
			)
			(layer "B.SilkS")
		)
		(fp_line
			(start -0.508 -0.9398)
			(end 0.508 -0.9398)
			(stroke
				(width 0.1524)
				(type default)
			)
			(layer "B.SilkS")
		)
		(fp_line
			(start 0.508 -0.9398)
			(end 0.508 0.9398)
			(stroke
				(width 0.1524)
				(type default)
			)
			(layer "B.SilkS")
		)
		(fp_rect
			(start 0.508 0.9398)
			(end -0.508 -0.9398)
			(stroke
				(width 0)
				(type default)
			)
			(fill no)
			(layer "B.CrtYd")
		)
		(fp_rect
			(start 0.508 0.9398)
			(end -0.508 -0.9398)
			(stroke
				(width 0)
				(type default)
			)
			(fill no)
			(layer "B.Fab")
		)
		(pad "1" smd custom
			(at 0 -0.4445 90)
			(size 0.1397 0.1397)
			(layers "B.Cu" "B.Mask" "B.Paste")
			(net "XDP_TDI_R")
			(options
				(clearance outline)
				(anchor circle)
			)
			(primitives
				(gr_poly
					(pts
						(arc
							(start -0.1778 0.2794)
							(mid -0.249642 0.249642)
							(end -0.2794 0.1778)
						)
						(arc
							(start -0.2794 -0.1778)
							(mid -0.249642 -0.249642)
							(end -0.1778 -0.2794)
						)
						(arc
							(start 0.1778 -0.2794)
							(mid 0.249642 -0.249642)
							(end 0.2794 -0.1778)
						)
						(arc
							(start 0.2794 0.1778)
							(mid 0.249642 0.249642)
							(end 0.1778 0.2794)
						)
					)
					(width 0)
					(fill yes)
				)
			)
		)
		(pad "2" smd custom
			(at 0 0.4445 90)
			(size 0.1397 0.1397)
			(layers "B.Cu" "B.Mask" "B.Paste")
			(net "XDP_TDI")
			(options
				(clearance outline)
				(anchor circle)
			)
			(primitives
				(gr_poly
					(pts
						(arc
							(start -0.1778 0.2794)
							(mid -0.249642 0.249642)
							(end -0.2794 0.1778)
						)
						(arc
							(start -0.2794 -0.1778)
							(mid -0.249642 -0.249642)
							(end -0.1778 -0.2794)
						)
						(arc
							(start 0.1778 -0.2794)
							(mid 0.249642 -0.249642)
							(end 0.2794 -0.1778)
						)
						(arc
							(start 0.2794 0.1778)
							(mid 0.249642 0.249642)
							(end 0.1778 0.2794)
						)
					)
					(width 0)
					(fill yes)
				)
			)
		)
	)
	(footprint ""
		(layer "B.Cu")
		(at 420.116 -32.512 90)
		(property "Reference" "C25W22"
			(at 0.8382 -0.67818 90)
			(unlocked yes)
			(layer "B.SilkS")
			(effects
				(font
					(size 0.4064 0.254)
					(thickness 0.1524)
				)
				(justify left mirror)
			)
		)
		(property "Value" ""
			(at 0 0 90)
			(layer "B.Fab")
			(effects
				(font
					(size 1.27 1.27)
				)
				(justify mirror)
			)
		)
		(duplicate_pad_numbers_are_jumpers no)
		(fp_poly
			(pts
				(xy -0.3048 -0.1016) (xy -0.3048 0.9906) (xy 0.3048 0.9906) (xy 0.3048 -0.1016)
			)
			(stroke
				(width 0)
				(type default)
			)
			(fill no)
			(layer "B.CrtYd")
		)
		(fp_line
			(start 0.3048 -0.1016)
			(end 0.3048 0.9906)
			(stroke
				(width 0.1)
				(type default)
			)
			(layer "B.Fab")
		)
		(fp_line
			(start -0.3048 -0.1016)
			(end 0.3048 -0.1016)
			(stroke
				(width 0.1)
				(type default)
			)
			(layer "B.Fab")
		)
		(fp_line
			(start 0.3048 0.9906)
			(end -0.3048 0.9906)
			(stroke
				(width 0.1)
				(type default)
			)
			(layer "B.Fab")
		)
		(fp_line
			(start -0.3048 0.9906)
			(end -0.3048 -0.1016)
			(stroke
				(width 0.1)
				(type default)
			)
			(layer "B.Fab")
		)
		(pad "1" smd rect
			(at 0 0 270)
			(size 0.508 0.508)
			(layers "B.Cu" "B.Mask" "B.Paste")
			(net "BMC_M_VREFCA")
		)
		(pad "2" smd rect
			(at 0 0.889 270)
			(size 0.508 0.508)
			(layers "B.Cu" "B.Mask" "B.Paste")
			(net "GND")
		)
		(zone
			(layer "B.Cu")
			(hatch none 0.5)
			(connect_pads
				(clearance 0)
			)
			(min_thickness 0.25)
			(keepout
				(tracks allowed)
				(vias not_allowed)
				(pads allowed)
				(copperpour not_allowed)
				(footprints allowed)
			)
			(placement
				(enabled no)
				(sheetname "")
			)
			(fill
				(thermal_gap 0.5)
				(thermal_bridge_width 0.5)
				(island_removal_mode 0)
			)
			(polygon
				(pts
					(xy 420.37 -32.766) (xy 420.37 -32.258) (xy 420.751 -32.258) (xy 420.751 -32.766)
				)
			)
		)
		(zone
			(layer "B.Cu")
			(hatch none 0.5)
			(connect_pads
				(clearance 0)
			)
			(min_thickness 0.25)
			(keepout
				(tracks not_allowed)
				(vias allowed)
				(pads allowed)
				(copperpour not_allowed)
				(footprints allowed)
			)
			(placement
				(enabled no)
				(sheetname "")
			)
			(fill
				(thermal_gap 0.5)
				(thermal_bridge_width 0.5)
				(island_removal_mode 0)
			)
			(polygon
				(pts
					(xy 420.751 -32.766) (xy 420.751 -32.258) (xy 420.37 -32.258) (xy 420.37 -32.766)
				)
			)
		)
	)
	(footprint ""
		(layer "B.Cu")
		(at 481.6475 -46.5582 -90)
		(property "Reference" "R1R15"
			(at 0 0 90)
			(layer "B.SilkS")
			(hide yes)
			(effects
				(font
					(size 1.27 1.27)
				)
				(justify mirror)
			)
		)
		(property "Value" ""
			(at 0 0 90)
			(layer "B.Fab")
			(effects
				(font
					(size 1.27 1.27)
				)
				(justify mirror)
			)
		)
		(duplicate_pad_numbers_are_jumpers no)
		(fp_poly
			(pts
				(xy 0.4953 -0.2032) (xy -0.4953 -0.2032) (xy -0.4953 1.6002) (xy 0.4953 1.6002)
			)
			(stroke
				(width 0)
				(type default)
			)
			(fill no)
			(layer "B.CrtYd")
		)
		(fp_line
			(start -0.4953 1.6002)
			(end 0.4953 1.6002)
			(stroke
				(width 0.1)
				(type default)
			)
			(layer "B.Fab")
		)
		(fp_line
			(start 0.4953 1.6002)
			(end 0.4953 -0.2032)
			(stroke
				(width 0.1)
				(type default)
			)
			(layer "B.Fab")
		)
		(fp_line
			(start -0.4953 -0.2032)
			(end -0.4953 1.6002)
			(stroke
				(width 0.1)
				(type default)
			)
			(layer "B.Fab")
		)
		(fp_line
			(start 0.4953 -0.2032)
			(end -0.4953 -0.2032)
			(stroke
				(width 0.1)
				(type default)
			)
			(layer "B.Fab")
		)
		(pad "1" smd rect
			(at 0 0 90)
			(size 0.762 0.889)
			(layers "B.Cu" "B.Mask" "B.Paste")
			(net "P0V9_LAN")
		)
		(pad "2" smd rect
			(at 0 1.397 90)
			(size 0.762 0.889)
			(layers "B.Cu" "B.Mask" "B.Paste")
			(net "P0V9_LAN_I210")
		)
		(zone
			(layer "B.Cu")
			(hatch none 0.5)
			(connect_pads
				(clearance 0)
			)
			(min_thickness 0.25)
			(keepout
				(tracks allowed)
				(vias not_allowed)
				(pads allowed)
				(copperpour not_allowed)
				(footprints allowed)
			)
			(placement
				(enabled no)
				(sheetname "")
			)
			(fill
				(thermal_gap 0.5)
				(thermal_bridge_width 0.5)
				(island_removal_mode 0)
			)
			(polygon
				(pts
					(xy 480.695 -46.9392) (xy 481.203 -46.9392) (xy 481.203 -46.1772) (xy 480.695 -46.1772)
				)
			)
		)
		(zone
			(layer "B.Cu")
			(hatch none 0.5)
			(connect_pads
				(clearance 0)
			)
			(min_thickness 0.25)
			(keepout
				(tracks not_allowed)
				(vias allowed)
				(pads allowed)
				(copperpour not_allowed)
				(footprints allowed)
			)
			(placement
				(enabled no)
				(sheetname "")
			)
			(fill
				(thermal_gap 0.5)
				(thermal_bridge_width 0.5)
				(island_removal_mode 0)
			)
			(polygon
				(pts
					(xy 480.695 -46.1772) (xy 481.203 -46.1772) (xy 481.203 -46.9392) (xy 480.695 -46.9392)
				)
			)
		)
	)
	(footprint ""
		(layer "B.Cu")
		(at 345.919806 -60.368434)
		(property "Reference" "R2U23"
			(at 0 0 0)
			(layer "B.SilkS")
			(hide yes)
			(effects
				(font
					(size 1.27 1.27)
				)
				(justify mirror)
			)
		)
		(property "Value" ""
			(at 0 0 0)
			(layer "B.Fab")
			(effects
				(font
					(size 1.27 1.27)
				)
				(justify mirror)
			)
		)
		(duplicate_pad_numbers_are_jumpers no)
		(fp_poly
			(pts
				(xy 0.2794 -0.1016) (xy -0.2794 -0.1016) (xy -0.2794 0.9906) (xy 0.2794 0.9906)
			)
			(stroke
				(width 0)
				(type default)
			)
			(fill no)
			(layer "B.CrtYd")
		)
		(fp_line
			(start -0.2794 -0.1016)
			(end 0.2794 -0.1016)
			(stroke
				(width 0.1)
				(type default)
			)
			(layer "B.Fab")
		)
		(fp_line
			(start -0.2794 0.9906)
			(end -0.2794 -0.1016)
			(stroke
				(width 0.1)
				(type default)
			)
			(layer "B.Fab")
		)
		(fp_line
			(start 0.2794 -0.1016)
			(end 0.2794 0.9906)
			(stroke
				(width 0.1)
				(type default)
			)
			(layer "B.Fab")
		)
		(fp_line
			(start 0.2794 0.9906)
			(end -0.2794 0.9906)
			(stroke
				(width 0.1)
				(type default)
			)
			(layer "B.Fab")
		)
		(pad "1" smd rect
			(at 0 0 180)
			(size 0.508 0.508)
			(layers "B.Cu" "B.Mask" "B.Paste")
			(net "P3E_CPU0_PE1_SS_RXN<4>")
		)
		(pad "2" smd rect
			(at 0 0.889 180)
			(size 0.508 0.508)
			(layers "B.Cu" "B.Mask" "B.Paste")
			(net "P3E_CPU0_PE1_SS_R_RXN<4>")
		)
		(zone
			(layer "B.Cu")
			(hatch none 0.5)
			(connect_pads
				(clearance 0)
			)
			(min_thickness 0.25)
			(keepout
				(tracks allowed)
				(vias not_allowed)
				(pads allowed)
				(copperpour not_allowed)
				(footprints allowed)
			)
			(placement
				(enabled no)
				(sheetname "")
			)
			(fill
				(thermal_gap 0.5)
				(thermal_bridge_width 0.5)
				(island_removal_mode 0)
			)
			(polygon
				(pts
					(xy 346.173806 -60.114434) (xy 345.665806 -60.114434) (xy 345.665806 -59.733434) (xy 346.173806 -59.733434)
				)
			)
		)
	)
	(footprint ""
		(layer "B.Cu")
		(at 468.884 -125.984 180)
		(property "Reference" "R1W13"
			(at 0.8382 -0.67818 180)
			(unlocked yes)
			(layer "B.SilkS")
			(effects
				(font
					(size 0.4064 0.254)
					(thickness 0.1524)
				)
				(justify left mirror)
			)
		)
		(property "Value" ""
			(at 0 0 0)
			(layer "B.Fab")
			(effects
				(font
					(size 1.27 1.27)
				)
				(justify mirror)
			)
		)
		(duplicate_pad_numbers_are_jumpers no)
		(fp_poly
			(pts
				(xy 0.2794 -0.1016) (xy -0.2794 -0.1016) (xy -0.2794 0.9906) (xy 0.2794 0.9906)
			)
			(stroke
				(width 0)
				(type default)
			)
			(fill no)
			(layer "B.CrtYd")
		)
		(fp_line
			(start 0.2794 0.9906)
			(end -0.2794 0.9906)
			(stroke
				(width 0.1)
				(type default)
			)
			(layer "B.Fab")
		)
		(fp_line
			(start 0.2794 -0.1016)
			(end 0.2794 0.9906)
			(stroke
				(width 0.1)
				(type default)
			)
			(layer "B.Fab")
		)
		(fp_line
			(start -0.2794 0.9906)
			(end -0.2794 -0.1016)
			(stroke
				(width 0.1)
				(type default)
			)
			(layer "B.Fab")
		)
		(fp_line
			(start -0.2794 -0.1016)
			(end 0.2794 -0.1016)
			(stroke
				(width 0.1)
				(type default)
			)
			(layer "B.Fab")
		)
		(pad "1" smd rect
			(at 0 0)
			(size 0.508 0.508)
			(layers "B.Cu" "B.Mask" "B.Paste")
			(net "FM_USB_P0_EN_BOOT_BIOS_STRAP_N")
		)
		(pad "2" smd rect
			(at 0 0.889)
			(size 0.508 0.508)
			(layers "B.Cu" "B.Mask" "B.Paste")
			(net "FM_USB_P0_EN_R_N")
		)
		(zone
			(layer "B.Cu")
			(hatch none 0.5)
			(connect_pads
				(clearance 0)
			)
			(min_thickness 0.25)
			(keepout
				(tracks not_allowed)
				(vias allowed)
				(pads allowed)
				(copperpour not_allowed)
				(footprints allowed)
			)
			(placement
				(enabled no)
				(sheetname "")
			)
			(fill
				(thermal_gap 0.5)
				(thermal_bridge_width 0.5)
				(island_removal_mode 0)
			)
			(polygon
				(pts
					(xy 468.63 -126.619) (xy 469.138 -126.619) (xy 469.138 -126.238) (xy 468.63 -126.238)
				)
			)
		)
		(zone
			(layer "B.Cu")
			(hatch none 0.5)
			(connect_pads
				(clearance 0)
			)
			(min_thickness 0.25)
			(keepout
				(tracks allowed)
				(vias not_allowed)
				(pads allowed)
				(copperpour not_allowed)
				(footprints allowed)
			)
			(placement
				(enabled no)
				(sheetname "")
			)
			(fill
				(thermal_gap 0.5)
				(thermal_bridge_width 0.5)
				(island_removal_mode 0)
			)
			(polygon
				(pts
					(xy 468.63 -126.238) (xy 469.138 -126.238) (xy 469.138 -126.619) (xy 468.63 -126.619)
				)
			)
		)
	)
	(footprint ""
		(layer "B.Cu")
		(at 94.26448 -140.04544 90)
		(property "Reference" "C5G115"
			(at -1.64973 0.78994 180)
			(unlocked yes)
			(layer "B.SilkS")
			(effects
				(font
					(size 0.7874 0.5842)
					(thickness 0.1524)
				)
				(justify mirror)
			)
		)
		(property "Value" ""
			(at 0 0 90)
			(layer "B.Fab")
			(effects
				(font
					(size 1.27 1.27)
				)
				(justify mirror)
			)
		)
		(duplicate_pad_numbers_are_jumpers no)
		(fp_rect
			(start -0.7239 -0.2159)
			(end 0.7239 1.9939)
			(stroke
				(width 0)
				(type default)
			)
			(fill no)
			(layer "B.CrtYd")
		)
		(fp_line
			(start 0.7239 -0.2159)
			(end 0.7239 1.9939)
			(stroke
				(width 0.1)
				(type default)
			)
			(layer "B.Fab")
		)
		(fp_line
			(start -0.7239 -0.2159)
			(end 0.7239 -0.2159)
			(stroke
				(width 0.1)
				(type default)
			)
			(layer "B.Fab")
		)
		(fp_line
			(start 0.7239 1.9939)
			(end -0.7239 1.9939)
			(stroke
				(width 0.1)
				(type default)
			)
			(layer "B.Fab")
		)
		(fp_line
			(start -0.7239 1.9939)
			(end -0.7239 -0.2159)
			(stroke
				(width 0.1)
				(type default)
			)
			(layer "B.Fab")
		)
		(pad "1" smd rect
			(at 0 0 270)
			(size 1.27 1.016)
			(layers "B.Cu" "B.Mask" "B.Paste")
			(net "PVDDQ_KLM")
		)
		(pad "2" smd rect
			(at 0 1.778 270)
			(size 1.27 1.016)
			(layers "B.Cu" "B.Mask" "B.Paste")
			(net "GND")
		)
		(zone
			(layer "B.Cu")
			(hatch none 0.5)
			(connect_pads
				(clearance 0)
			)
			(min_thickness 0.25)
			(keepout
				(tracks not_allowed)
				(vias allowed)
				(pads allowed)
				(copperpour not_allowed)
				(footprints allowed)
			)
			(placement
				(enabled no)
				(sheetname "")
			)
			(fill
				(thermal_gap 0.5)
				(thermal_bridge_width 0.5)
				(island_removal_mode 0)
			)
			(polygon
				(pts
					(xy 94.77248 -139.41044) (xy 95.53448 -139.41044) (xy 95.53448 -140.68044) (xy 94.77248 -140.68044)
				)
			)
		)
	)
	(footprint ""
		(layer "B.Cu")
		(at 475.484952 -14.0589 90)
		(property "Reference" "EU2T1"
			(at 1.40843 2.0574 0)
			(unlocked yes)
			(layer "B.SilkS")
			(effects
				(font
					(size 0.7874 0.5842)
					(thickness 0.1524)
				)
				(justify left mirror)
			)
		)
		(property "Value" ""
			(at 0 0 90)
			(layer "B.Fab")
			(effects
				(font
					(size 1.27 1.27)
				)
				(justify mirror)
			)
		)
		(duplicate_pad_numbers_are_jumpers no)
		(fp_circle
			(center 0.702056 -0.595376)
			(end 0.702056 -0.468376)
			(stroke
				(width 0.254)
				(type default)
			)
			(fill no)
			(layer "B.SilkS")
		)
		(fp_rect
			(start -1.4732 1.549908)
			(end -0.5842 -0.050292)
			(stroke
				(width 0)
				(type default)
			)
			(fill yes)
			(layer "B.Paste")
		)
		(fp_rect
			(start -2.078736 1.799844)
			(end 0.021336 -0.300228)
			(stroke
				(width 0)
				(type default)
			)
			(fill no)
			(layer "B.CrtYd")
		)
		(fp_line
			(start 0.021336 -0.300228)
			(end -2.078736 -0.300228)
			(stroke
				(width 0.1)
				(type default)
			)
			(layer "B.Fab")
		)
		(fp_line
			(start -2.078736 -0.300228)
			(end -2.078736 1.799844)
			(stroke
				(width 0.1)
				(type default)
			)
			(layer "B.Fab")
		)
		(fp_line
			(start 0.021336 1.799844)
			(end 0.021336 -0.300228)
			(stroke
				(width 0.1)
				(type default)
			)
			(layer "B.Fab")
		)
		(fp_line
			(start -2.078736 1.799844)
			(end 0.021336 1.799844)
			(stroke
				(width 0.1)
				(type default)
			)
			(layer "B.Fab")
		)
		(fp_circle
			(center 0.702056 -0.595376)
			(end 0.702056 -0.468376)
			(stroke
				(width 0.254)
				(type default)
			)
			(fill no)
			(layer "B.Fab")
		)
		(pad "1" smd rect
			(at 0 0 270)
			(size 0.6604 0.3048)
			(layers "B.Cu" "B.Mask" "B.Paste")
			(net "P5V_STBY")
		)
		(pad "2" smd rect
			(at 0 0.499872 270)
			(size 0.6604 0.3048)
			(layers "B.Cu" "B.Mask" "B.Paste")
			(net "FM_P3V3_CPLD_EN")
		)
		(pad "3" smd rect
			(at 0 0.999744 270)
			(size 0.6604 0.3048)
			(layers "B.Cu" "B.Mask" "B.Paste")
			(net "P5V_STBY")
		)
		(pad "4" smd rect
			(at 0 1.499616 270)
			(size 0.6604 0.3048)
			(layers "B.Cu" "B.Mask" "B.Paste")
			(net "GND")
		)
		(pad "5" smd rect
			(at -2.0574 1.499616 270)
			(size 0.6604 0.3048)
			(layers "B.Cu" "B.Mask" "B.Paste")
			(net "P3V3_STBY")
		)
		(pad "6" smd rect
			(at -2.0574 0.999744 270)
			(size 0.6604 0.3048)
			(layers "B.Cu" "B.Mask" "B.Paste")
			(net "P3V3")
		)
		(pad "7" smd rect
			(at -2.0574 0.499872 270)
			(size 0.6604 0.3048)
			(layers "B.Cu" "B.Mask" "B.Paste")
			(net "P3V3_SWITCH_G")
		)
		(pad "8" smd rect
			(at -2.0574 0 270)
			(size 0.6604 0.3048)
			(layers "B.Cu" "B.Mask" "B.Paste")
			(net "TP_SLG55021_P3V3_8")
		)
		(pad "9" smd rect
			(at -1.0287 0.749808 270)
			(size 0.889 1.6002)
			(layers "B.Cu" "B.Mask" "B.Paste")
			(net "GND")
		)
	)
	(footprint ""
		(layer "B.Cu")
		(at 20.7264 -31.6738 90)
		(property "Reference" "Q9T1"
			(at 1.37033 2.921 0)
			(unlocked yes)
			(layer "B.SilkS")
			(effects
				(font
					(size 0.7874 0.5842)
					(thickness 0.1524)
				)
				(justify left mirror)
			)
		)
		(property "Value" ""
			(at 0 0 90)
			(layer "B.Fab")
			(effects
				(font
					(size 1.27 1.27)
				)
				(justify mirror)
			)
		)
		(duplicate_pad_numbers_are_jumpers no)
		(fp_line
			(start -0.9525 -0.5715)
			(end -1.778 -0.5715)
			(stroke
				(width 0.1524)
				(type default)
			)
			(layer "B.SilkS")
		)
		(fp_line
			(start -1.778 -0.5715)
			(end -1.778 0.3175)
			(stroke
				(width 0.1524)
				(type default)
			)
			(layer "B.SilkS")
		)
		(fp_line
			(start -0.381 0.635)
			(end -0.381 1.27)
			(stroke
				(width 0.1524)
				(type default)
			)
			(layer "B.SilkS")
		)
		(fp_line
			(start -0.9525 2.4765)
			(end -1.778 2.4765)
			(stroke
				(width 0.1524)
				(type default)
			)
			(layer "B.SilkS")
		)
		(fp_line
			(start -1.778 2.4765)
			(end -1.778 1.5875)
			(stroke
				(width 0.1524)
				(type default)
			)
			(layer "B.SilkS")
		)
		(fp_circle
			(center 0.9525 -0.9271)
			(end 0.9525 -0.8001)
			(stroke
				(width 0.254)
				(type default)
			)
			(fill no)
			(layer "B.SilkS")
		)
		(fp_poly
			(pts
				(xy -1.778 2.4765) (xy -0.381 2.4765) (xy -0.381 -0.5715) (xy -1.778 -0.5715)
			)
			(stroke
				(width 0)
				(type default)
			)
			(fill no)
			(layer "B.CrtYd")
		)
		(fp_line
			(start -0.381 -0.5715)
			(end -0.381 2.4765)
			(stroke
				(width 0.1)
				(type default)
			)
			(layer "B.Fab")
		)
		(fp_line
			(start -1.778 -0.5715)
			(end -0.381 -0.5715)
			(stroke
				(width 0.1)
				(type default)
			)
			(layer "B.Fab")
		)
		(fp_line
			(start -0.381 2.4765)
			(end -1.778 2.4765)
			(stroke
				(width 0.1)
				(type default)
			)
			(layer "B.Fab")
		)
		(fp_line
			(start -1.778 2.4765)
			(end -1.778 -0.5715)
			(stroke
				(width 0.1)
				(type default)
			)
			(layer "B.Fab")
		)
		(fp_circle
			(center 0.9525 -0.9271)
			(end 0.9525 -0.8001)
			(stroke
				(width 0.254)
				(type default)
			)
			(fill no)
			(layer "B.Fab")
		)
		(pad "1" smd rect
			(at 0 0 270)
			(size 1.143 0.508)
			(layers "B.Cu" "B.Mask" "B.Paste")
			(net "FM_MATED_IN_D2_N")
		)
		(pad "2" smd rect
			(at 0 1.905 270)
			(size 1.143 0.508)
			(layers "B.Cu" "B.Mask" "B.Paste")
			(net "GND")
		)
		(pad "3" smd rect
			(at -2.159 0.9525 270)
			(size 1.143 0.508)
			(layers "B.Cu" "B.Mask" "B.Paste")
			(net "FM_P12V_HOTSWAP0_EN")
		)
	)
	(footprint ""
		(layer "B.Cu")
		(at 456.4888 -52.483258)
		(property "Reference" "C1R6"
			(at 0 0 0)
			(layer "B.SilkS")
			(hide yes)
			(effects
				(font
					(size 1.27 1.27)
				)
				(justify mirror)
			)
		)
		(property "Value" ""
			(at 0 0 0)
			(layer "B.Fab")
			(effects
				(font
					(size 1.27 1.27)
				)
				(justify mirror)
			)
		)
		(duplicate_pad_numbers_are_jumpers no)
		(fp_poly
			(pts
				(xy -0.3048 -0.1016) (xy -0.3048 0.9906) (xy 0.3048 0.9906) (xy 0.3048 -0.1016)
			)
			(stroke
				(width 0)
				(type default)
			)
			(fill no)
			(layer "B.CrtYd")
		)
		(fp_line
			(start -0.3048 -0.1016)
			(end 0.3048 -0.1016)
			(stroke
				(width 0.1)
				(type default)
			)
			(layer "B.Fab")
		)
		(fp_line
			(start -0.3048 0.9906)
			(end -0.3048 -0.1016)
			(stroke
				(width 0.1)
				(type default)
			)
			(layer "B.Fab")
		)
		(fp_line
			(start 0.3048 -0.1016)
			(end 0.3048 0.9906)
			(stroke
				(width 0.1)
				(type default)
			)
			(layer "B.Fab")
		)
		(fp_line
			(start 0.3048 0.9906)
			(end -0.3048 0.9906)
			(stroke
				(width 0.1)
				(type default)
			)
			(layer "B.Fab")
		)
		(pad "1" smd rect
			(at 0 0 180)
			(size 0.508 0.508)
			(layers "B.Cu" "B.Mask" "B.Paste")
			(net "P3E_CPU0_PE3_OCP_TXP<2>")
		)
		(pad "2" smd rect
			(at 0 0.889 180)
			(size 0.508 0.508)
			(layers "B.Cu" "B.Mask" "B.Paste")
			(net "P3E_OCP_CPU0_PE3_C_TXP<2>")
		)
		(zone
			(layer "B.Cu")
			(hatch none 0.5)
			(connect_pads
				(clearance 0)
			)
			(min_thickness 0.25)
			(keepout
				(tracks allowed)
				(vias not_allowed)
				(pads allowed)
				(copperpour not_allowed)
				(footprints allowed)
			)
			(placement
				(enabled no)
				(sheetname "")
			)
			(fill
				(thermal_gap 0.5)
				(thermal_bridge_width 0.5)
				(island_removal_mode 0)
			)
			(polygon
				(pts
					(xy 456.7428 -52.229258) (xy 456.2348 -52.229258) (xy 456.2348 -51.848258) (xy 456.7428 -51.848258)
				)
			)
		)
	)
	(footprint ""
		(layer "B.Cu")
		(at 460.4512 -129.6924 90)
		(property "Reference" "U1M4"
			(at -0.34036 2.28473 270)
			(unlocked yes)
			(layer "B.SilkS")
			(effects
				(font
					(size 0.7874 0.5842)
					(thickness 0.1524)
				)
				(justify left mirror)
			)
		)
		(property "Value" ""
			(at 0 0 90)
			(layer "B.Fab")
			(effects
				(font
					(size 1.27 1.27)
				)
				(justify mirror)
			)
		)
		(duplicate_pad_numbers_are_jumpers no)
		(fp_circle
			(center 0.858012 -0.008636)
			(end 0.858012 0.118364)
			(stroke
				(width 0.254)
				(type default)
			)
			(fill no)
			(layer "B.SilkS")
		)
		(fp_poly
			(pts
				(xy -0.21463 -0.450088) (xy -1.56337 -0.450088) (xy -1.56337 1.75006) (xy -0.21463 1.75006)
			)
			(stroke
				(width 0)
				(type default)
			)
			(fill no)
			(layer "B.CrtYd")
		)
		(fp_line
			(start -0.21463 -0.450088)
			(end -1.56337 -0.450088)
			(stroke
				(width 0.1)
				(type default)
			)
			(layer "B.Fab")
		)
		(fp_line
			(start -1.56337 -0.450088)
			(end -1.56337 1.75006)
			(stroke
				(width 0.1)
				(type default)
			)
			(layer "B.Fab")
		)
		(fp_line
			(start -0.21463 1.75006)
			(end -0.21463 -0.450088)
			(stroke
				(width 0.1)
				(type default)
			)
			(layer "B.Fab")
		)
		(fp_line
			(start -1.56337 1.75006)
			(end -0.21463 1.75006)
			(stroke
				(width 0.1)
				(type default)
			)
			(layer "B.Fab")
		)
		(fp_circle
			(center 0.4699 -0.8382)
			(end 0.4699 -0.7112)
			(stroke
				(width 0.254)
				(type default)
			)
			(fill no)
			(layer "B.Fab")
		)
		(pad "1" smd rect
			(at 0 0 270)
			(size 1.016 0.381)
			(layers "B.Cu" "B.Mask" "B.Paste")
			(net "FM_CPU1_SKTOCC_LVT3_N")
		)
		(pad "2" smd rect
			(at 0 0.649986 270)
			(size 1.016 0.381)
			(layers "B.Cu" "B.Mask" "B.Paste")
			(net "XDP_CPU0_TDO")
		)
		(pad "3" smd rect
			(at 0 1.299972 270)
			(size 1.016 0.381)
			(layers "B.Cu" "B.Mask" "B.Paste")
			(net "GND")
		)
		(pad "4" smd rect
			(at -1.778 1.299972 270)
			(size 1.016 0.381)
			(layers "B.Cu" "B.Mask" "B.Paste")
			(net "XDP_CPU1_TDI")
		)
		(pad "5" smd rect
			(at -1.778 0 270)
			(size 1.016 0.381)
			(layers "B.Cu" "B.Mask" "B.Paste")
			(net "P3V3_STBY")
		)
	)
	(footprint ""
		(layer "B.Cu")
		(at 486.119424 -58.104024 90)
		(property "Reference" "R30W2"
			(at 0.8382 -0.67818 90)
			(unlocked yes)
			(layer "B.SilkS")
			(effects
				(font
					(size 0.4064 0.254)
					(thickness 0.1524)
				)
				(justify left mirror)
			)
		)
		(property "Value" ""
			(at 0 0 90)
			(layer "B.Fab")
			(effects
				(font
					(size 1.27 1.27)
				)
				(justify mirror)
			)
		)
		(duplicate_pad_numbers_are_jumpers no)
		(fp_poly
			(pts
				(xy 0.2794 -0.1016) (xy -0.2794 -0.1016) (xy -0.2794 0.9906) (xy 0.2794 0.9906)
			)
			(stroke
				(width 0)
				(type default)
			)
			(fill no)
			(layer "B.CrtYd")
		)
		(fp_line
			(start 0.2794 -0.1016)
			(end 0.2794 0.9906)
			(stroke
				(width 0.1)
				(type default)
			)
			(layer "B.Fab")
		)
		(fp_line
			(start -0.2794 -0.1016)
			(end 0.2794 -0.1016)
			(stroke
				(width 0.1)
				(type default)
			)
			(layer "B.Fab")
		)
		(fp_line
			(start 0.2794 0.9906)
			(end -0.2794 0.9906)
			(stroke
				(width 0.1)
				(type default)
			)
			(layer "B.Fab")
		)
		(fp_line
			(start -0.2794 0.9906)
			(end -0.2794 -0.1016)
			(stroke
				(width 0.1)
				(type default)
			)
			(layer "B.Fab")
		)
		(pad "1" smd rect
			(at 0 0 270)
			(size 0.508 0.508)
			(layers "B.Cu" "B.Mask" "B.Paste")
			(net "USB3_P01_RXP")
		)
		(pad "2" smd rect
			(at 0 0.889 270)
			(size 0.508 0.508)
			(layers "B.Cu" "B.Mask" "B.Paste")
			(net "USB3_P01_FB_RXP")
		)
		(zone
			(layer "B.Cu")
			(hatch none 0.5)
			(connect_pads
				(clearance 0)
			)
			(min_thickness 0.25)
			(keepout
				(tracks allowed)
				(vias not_allowed)
				(pads allowed)
				(copperpour not_allowed)
				(footprints allowed)
			)
			(placement
				(enabled no)
				(sheetname "")
			)
			(fill
				(thermal_gap 0.5)
				(thermal_bridge_width 0.5)
				(island_removal_mode 0)
			)
			(polygon
				(pts
					(xy 486.373424 -58.358024) (xy 486.373424 -57.850024) (xy 486.754424 -57.850024) (xy 486.754424 -58.358024)
				)
			)
		)
		(zone
			(layer "B.Cu")
			(hatch none 0.5)
			(connect_pads
				(clearance 0)
			)
			(min_thickness 0.25)
			(keepout
				(tracks not_allowed)
				(vias allowed)
				(pads allowed)
				(copperpour not_allowed)
				(footprints allowed)
			)
			(placement
				(enabled no)
				(sheetname "")
			)
			(fill
				(thermal_gap 0.5)
				(thermal_bridge_width 0.5)
				(island_removal_mode 0)
			)
			(polygon
				(pts
					(xy 486.754424 -58.358024) (xy 486.754424 -57.850024) (xy 486.373424 -57.850024) (xy 486.373424 -58.358024)
				)
			)
		)
	)
	(footprint ""
		(layer "B.Cu")
		(at 94.300548 -135.376412 90)
		(property "Reference" "C8M7"
			(at 0 0 90)
			(layer "B.SilkS")
			(hide yes)
			(effects
				(font
					(size 1.27 1.27)
				)
				(justify mirror)
			)
		)
		(property "Value" ""
			(at 0 0 90)
			(layer "B.Fab")
			(effects
				(font
					(size 1.27 1.27)
				)
				(justify mirror)
			)
		)
		(duplicate_pad_numbers_are_jumpers no)
		(fp_poly
			(pts
				(xy 0.7239 -0.2159) (xy -0.7239 -0.2159) (xy -0.7239 1.9939) (xy 0.7239 1.9939)
			)
			(stroke
				(width 0)
				(type default)
			)
			(fill no)
			(layer "B.CrtYd")
		)
		(fp_line
			(start 0.7239 -0.2159)
			(end 0.7239 1.9939)
			(stroke
				(width 0.1)
				(type default)
			)
			(layer "B.Fab")
		)
		(fp_line
			(start -0.7239 -0.2159)
			(end 0.7239 -0.2159)
			(stroke
				(width 0.1)
				(type default)
			)
			(layer "B.Fab")
		)
		(fp_line
			(start 0.7239 1.9939)
			(end -0.7239 1.9939)
			(stroke
				(width 0.1)
				(type default)
			)
			(layer "B.Fab")
		)
		(fp_line
			(start -0.7239 1.9939)
			(end -0.7239 -0.2159)
			(stroke
				(width 0.1)
				(type default)
			)
			(layer "B.Fab")
		)
		(pad "1" smd rect
			(at 0 0 270)
			(size 1.27 1.016)
			(layers "B.Cu" "B.Mask" "B.Paste")
			(net "PVDDQ_KLM")
		)
		(pad "2" smd rect
			(at 0 1.778 270)
			(size 1.27 1.016)
			(layers "B.Cu" "B.Mask" "B.Paste")
			(net "GND")
		)
		(zone
			(layer "B.Cu")
			(hatch none 0.5)
			(connect_pads
				(clearance 0)
			)
			(min_thickness 0.25)
			(keepout
				(tracks not_allowed)
				(vias allowed)
				(pads allowed)
				(copperpour not_allowed)
				(footprints allowed)
			)
			(placement
				(enabled no)
				(sheetname "")
			)
			(fill
				(thermal_gap 0.5)
				(thermal_bridge_width 0.5)
				(island_removal_mode 0)
			)
			(polygon
				(pts
					(xy 94.808548 -136.011412) (xy 94.808548 -134.741412) (xy 95.570548 -134.741412) (xy 95.570548 -136.011412)
				)
			)
		)
	)
	(footprint ""
		(layer "B.Cu")
		(at 487.62412 -60.016644 180)
		(property "Reference" "L30W2"
			(at -0.127 -1.07188 180)
			(unlocked yes)
			(layer "B.SilkS")
			(effects
				(font
					(size 0.4064 0.254)
					(thickness 0.1524)
				)
				(justify left mirror)
			)
		)
		(property "Value" ""
			(at 0 0 0)
			(layer "B.Fab")
			(effects
				(font
					(size 1.27 1.27)
				)
				(justify mirror)
			)
		)
		(duplicate_pad_numbers_are_jumpers no)
		(fp_rect
			(start 0.08382 1.09982)
			(end -2.11582 -0.29972)
			(stroke
				(width 0)
				(type default)
			)
			(fill no)
			(layer "B.CrtYd")
		)
		(fp_line
			(start 0.08382 1.09982)
			(end 0.08382 -0.29972)
			(stroke
				(width 0.1)
				(type default)
			)
			(layer "B.Fab")
		)
		(fp_line
			(start 0.08382 -0.29972)
			(end -2.11582 -0.29972)
			(stroke
				(width 0.1)
				(type default)
			)
			(layer "B.Fab")
		)
		(fp_line
			(start -2.11582 1.09982)
			(end 0.08382 1.09982)
			(stroke
				(width 0.1)
				(type default)
			)
			(layer "B.Fab")
		)
		(fp_line
			(start -2.11582 -0.29972)
			(end -2.11582 1.09982)
			(stroke
				(width 0.1)
				(type default)
			)
			(layer "B.Fab")
		)
		(pad "1" smd rect
			(at 0 0)
			(size 1.27 0.508)
			(layers "B.Cu" "B.Mask" "B.Paste")
			(net "USB3_P01_C_TXP")
		)
		(pad "2" smd rect
			(at -2.032 0)
			(size 1.27 0.508)
			(layers "B.Cu" "B.Mask" "B.Paste")
			(net "USB3_P01_FB_TXP")
		)
		(pad "3" smd rect
			(at -2.032 0.8001)
			(size 1.27 0.508)
			(layers "B.Cu" "B.Mask" "B.Paste")
			(net "USB3_P01_FB_TXN")
		)
		(pad "4" smd rect
			(at 0 0.8001)
			(size 1.27 0.508)
			(layers "B.Cu" "B.Mask" "B.Paste")
			(net "USB3_P01_C_TXN")
		)
		(zone
			(layer "B.Cu")
			(hatch none 0.5)
			(connect_pads
				(clearance 0)
			)
			(min_thickness 0.25)
			(keepout
				(tracks not_allowed)
				(vias allowed)
				(pads allowed)
				(copperpour not_allowed)
				(footprints allowed)
			)
			(placement
				(enabled no)
				(sheetname "")
			)
			(fill
				(thermal_gap 0.5)
				(thermal_bridge_width 0.5)
				(island_removal_mode 0)
			)
			(polygon
				(pts
					(xy 486.98912 -60.562744) (xy 486.98912 -60.270644) (xy 488.25912 -60.270644) (xy 488.25912 -60.562744)
				)
			)
		)
		(zone
			(layer "B.Cu")
			(hatch none 0.5)
			(connect_pads
				(clearance 0)
			)
			(min_thickness 0.25)
			(keepout
				(tracks not_allowed)
				(vias allowed)
				(pads allowed)
				(copperpour not_allowed)
				(footprints allowed)
			)
			(placement
				(enabled no)
				(sheetname "")
			)
			(fill
				(thermal_gap 0.5)
				(thermal_bridge_width 0.5)
				(island_removal_mode 0)
			)
			(polygon
				(pts
					(xy 488.25912 -61.070744) (xy 489.02112 -61.070744) (xy 489.02112 -59.762644) (xy 488.25912 -59.762644)
				)
			)
		)
		(zone
			(layer "B.Cu")
			(hatch none 0.5)
			(connect_pads
				(clearance 0)
			)
			(min_thickness 0.25)
			(keepout
				(tracks allowed)
				(vias not_allowed)
				(pads allowed)
				(copperpour not_allowed)
				(footprints allowed)
			)
			(placement
				(enabled no)
				(sheetname "")
			)
			(fill
				(thermal_gap 0.5)
				(thermal_bridge_width 0.5)
				(island_removal_mode 0)
			)
			(polygon
				(pts
					(xy 488.25912 -59.762644) (xy 488.25912 -61.070744) (xy 489.02112 -61.070744) (xy 489.02112 -59.762644)
				)
			)
		)
		(zone
			(layer "B.Cu")
			(hatch none 0.5)
			(connect_pads
				(clearance 0)
			)
			(min_thickness 0.25)
			(keepout
				(tracks not_allowed)
				(vias allowed)
				(pads allowed)
				(copperpour not_allowed)
				(footprints allowed)
			)
			(placement
				(enabled no)
				(sheetname "")
			)
			(fill
				(thermal_gap 0.5)
				(thermal_bridge_width 0.5)
				(island_removal_mode 0)
			)
			(polygon
				(pts
					(xy 489.02112 -60.562744) (xy 489.02112 -60.270644) (xy 490.29112 -60.270644) (xy 490.29112 -60.562744)
				)
			)
		)
	)
	(footprint ""
		(layer "B.Cu")
		(at 465.595208 -147.066254)
		(property "Reference" "R1L17"
			(at 0 0 0)
			(layer "B.SilkS")
			(hide yes)
			(effects
				(font
					(size 1.27 1.27)
				)
				(justify mirror)
			)
		)
		(property "Value" ""
			(at 0 0 0)
			(layer "B.Fab")
			(effects
				(font
					(size 1.27 1.27)
				)
				(justify mirror)
			)
		)
		(duplicate_pad_numbers_are_jumpers no)
		(fp_poly
			(pts
				(xy 0.2794 -0.1016) (xy -0.2794 -0.1016) (xy -0.2794 0.9906) (xy 0.2794 0.9906)
			)
			(stroke
				(width 0)
				(type default)
			)
			(fill no)
			(layer "B.CrtYd")
		)
		(fp_line
			(start -0.2794 -0.1016)
			(end 0.2794 -0.1016)
			(stroke
				(width 0.1)
				(type default)
			)
			(layer "B.Fab")
		)
		(fp_line
			(start -0.2794 0.9906)
			(end -0.2794 -0.1016)
			(stroke
				(width 0.1)
				(type default)
			)
			(layer "B.Fab")
		)
		(fp_line
			(start 0.2794 -0.1016)
			(end 0.2794 0.9906)
			(stroke
				(width 0.1)
				(type default)
			)
			(layer "B.Fab")
		)
		(fp_line
			(start 0.2794 0.9906)
			(end -0.2794 0.9906)
			(stroke
				(width 0.1)
				(type default)
			)
			(layer "B.Fab")
		)
		(pad "1" smd rect
			(at 0 0 180)
			(size 0.508 0.508)
			(layers "B.Cu" "B.Mask" "B.Paste")
			(net "XDP_CPU_PWR_DEBUG_N")
		)
		(pad "2" smd rect
			(at 0 0.889 180)
			(size 0.508 0.508)
			(layers "B.Cu" "B.Mask" "B.Paste")
			(net "PVCCIO_CPU0")
		)
		(zone
			(layer "B.Cu")
			(hatch none 0.5)
			(connect_pads
				(clearance 0)
			)
			(min_thickness 0.25)
			(keepout
				(tracks allowed)
				(vias not_allowed)
				(pads allowed)
				(copperpour not_allowed)
				(footprints allowed)
			)
			(placement
				(enabled no)
				(sheetname "")
			)
			(fill
				(thermal_gap 0.5)
				(thermal_bridge_width 0.5)
				(island_removal_mode 0)
			)
			(polygon
				(pts
					(xy 465.849208 -146.812254) (xy 465.341208 -146.812254) (xy 465.341208 -146.431254) (xy 465.849208 -146.431254)
				)
			)
		)
		(zone
			(layer "B.Cu")
			(hatch none 0.5)
			(connect_pads
				(clearance 0)
			)
			(min_thickness 0.25)
			(keepout
				(tracks not_allowed)
				(vias allowed)
				(pads allowed)
				(copperpour not_allowed)
				(footprints allowed)
			)
			(placement
				(enabled no)
				(sheetname "")
			)
			(fill
				(thermal_gap 0.5)
				(thermal_bridge_width 0.5)
				(island_removal_mode 0)
			)
			(polygon
				(pts
					(xy 465.849208 -146.431254) (xy 465.341208 -146.431254) (xy 465.341208 -146.812254) (xy 465.849208 -146.812254)
				)
			)
		)
	)
	(footprint ""
		(layer "B.Cu")
		(at 260.923024 -82.001614)
		(property "Reference" "C5P8"
			(at 0 0 0)
			(layer "B.SilkS")
			(hide yes)
			(effects
				(font
					(size 1.27 1.27)
				)
				(justify mirror)
			)
		)
		(property "Value" ""
			(at 0 0 0)
			(layer "B.Fab")
			(effects
				(font
					(size 1.27 1.27)
				)
				(justify mirror)
			)
		)
		(duplicate_pad_numbers_are_jumpers no)
		(fp_poly
			(pts
				(xy 0.7239 -0.2159) (xy -0.7239 -0.2159) (xy -0.7239 1.9939) (xy 0.7239 1.9939)
			)
			(stroke
				(width 0)
				(type default)
			)
			(fill no)
			(layer "B.CrtYd")
		)
		(fp_line
			(start -0.7239 -0.2159)
			(end 0.7239 -0.2159)
			(stroke
				(width 0.1)
				(type default)
			)
			(layer "B.Fab")
		)
		(fp_line
			(start -0.7239 1.9939)
			(end -0.7239 -0.2159)
			(stroke
				(width 0.1)
				(type default)
			)
			(layer "B.Fab")
		)
		(fp_line
			(start 0.7239 -0.2159)
			(end 0.7239 1.9939)
			(stroke
				(width 0.1)
				(type default)
			)
			(layer "B.Fab")
		)
		(fp_line
			(start 0.7239 1.9939)
			(end -0.7239 1.9939)
			(stroke
				(width 0.1)
				(type default)
			)
			(layer "B.Fab")
		)
		(pad "1" smd rect
			(at 0 0 180)
			(size 1.27 1.016)
			(layers "B.Cu" "B.Mask" "B.Paste")
			(net "PVSA_CPU0")
		)
		(pad "2" smd rect
			(at 0 1.778 180)
			(size 1.27 1.016)
			(layers "B.Cu" "B.Mask" "B.Paste")
			(net "GND")
		)
		(zone
			(layer "B.Cu")
			(hatch none 0.5)
			(connect_pads
				(clearance 0)
			)
			(min_thickness 0.25)
			(keepout
				(tracks not_allowed)
				(vias allowed)
				(pads allowed)
				(copperpour not_allowed)
				(footprints allowed)
			)
			(placement
				(enabled no)
				(sheetname "")
			)
			(fill
				(thermal_gap 0.5)
				(thermal_bridge_width 0.5)
				(island_removal_mode 0)
			)
			(polygon
				(pts
					(xy 261.558024 -81.493614) (xy 260.288024 -81.493614) (xy 260.288024 -80.731614) (xy 261.558024 -80.731614)
				)
			)
		)
	)
	(footprint ""
		(layer "B.Cu")
		(at 385.813808 -84.729828 180)
		(property "Reference" "R7D44"
			(at 0.8382 -0.67818 180)
			(unlocked yes)
			(layer "B.SilkS")
			(effects
				(font
					(size 0.4064 0.254)
					(thickness 0.1524)
				)
				(justify left mirror)
			)
		)
		(property "Value" ""
			(at 0 0 0)
			(layer "B.Fab")
			(effects
				(font
					(size 1.27 1.27)
				)
				(justify mirror)
			)
		)
		(duplicate_pad_numbers_are_jumpers no)
		(fp_poly
			(pts
				(xy 0.2794 -0.1016) (xy -0.2794 -0.1016) (xy -0.2794 0.9906) (xy 0.2794 0.9906)
			)
			(stroke
				(width 0)
				(type default)
			)
			(fill no)
			(layer "B.CrtYd")
		)
		(fp_line
			(start 0.2794 0.9906)
			(end -0.2794 0.9906)
			(stroke
				(width 0.1)
				(type default)
			)
			(layer "B.Fab")
		)
		(fp_line
			(start 0.2794 -0.1016)
			(end 0.2794 0.9906)
			(stroke
				(width 0.1)
				(type default)
			)
			(layer "B.Fab")
		)
		(fp_line
			(start -0.2794 0.9906)
			(end -0.2794 -0.1016)
			(stroke
				(width 0.1)
				(type default)
			)
			(layer "B.Fab")
		)
		(fp_line
			(start -0.2794 -0.1016)
			(end 0.2794 -0.1016)
			(stroke
				(width 0.1)
				(type default)
			)
			(layer "B.Fab")
		)
		(pad "1" smd rect
			(at 0 0)
			(size 0.508 0.508)
			(layers "B.Cu" "B.Mask" "B.Paste")
			(net "P1V05_PCH_STBY")
		)
		(pad "2" smd rect
			(at 0 0.889)
			(size 0.508 0.508)
			(layers "B.Cu" "B.Mask" "B.Paste")
			(net "FM_OCP_MEZZB_PRES_1V05_PCH_N")
		)
		(zone
			(layer "B.Cu")
			(hatch none 0.5)
			(connect_pads
				(clearance 0)
			)
			(min_thickness 0.25)
			(keepout
				(tracks not_allowed)
				(vias allowed)
				(pads allowed)
				(copperpour not_allowed)
				(footprints allowed)
			)
			(placement
				(enabled no)
				(sheetname "")
			)
			(fill
				(thermal_gap 0.5)
				(thermal_bridge_width 0.5)
				(island_removal_mode 0)
			)
			(polygon
				(pts
					(xy 385.559808 -85.364828) (xy 386.067808 -85.364828) (xy 386.067808 -84.983828) (xy 385.559808 -84.983828)
				)
			)
		)
		(zone
			(layer "B.Cu")
			(hatch none 0.5)
			(connect_pads
				(clearance 0)
			)
			(min_thickness 0.25)
			(keepout
				(tracks allowed)
				(vias not_allowed)
				(pads allowed)
				(copperpour not_allowed)
				(footprints allowed)
			)
			(placement
				(enabled no)
				(sheetname "")
			)
			(fill
				(thermal_gap 0.5)
				(thermal_bridge_width 0.5)
				(island_removal_mode 0)
			)
			(polygon
				(pts
					(xy 385.559808 -84.983828) (xy 386.067808 -84.983828) (xy 386.067808 -85.364828) (xy 385.559808 -85.364828)
				)
			)
		)
	)
	(footprint ""
		(layer "B.Cu")
		(at 198.623428 -69.477382 90)
		(property "Reference" "C4D14"
			(at 0 0 90)
			(layer "B.SilkS")
			(hide yes)
			(effects
				(font
					(size 1.27 1.27)
				)
				(justify mirror)
			)
		)
		(property "Value" "*"
			(at -1.1811 -2.8194 90)
			(unlocked yes)
			(layer "B.Fab")
			(hide yes)
			(effects
				(font
					(size 1.27 1.016)
					(thickness 0.1524)
				)
				(justify mirror)
			)
		)
		(property "Device Type" "SC1U10V2KX-4-GP_SMD-BCG6-SC1U1A"
			(at -1.1811 -4.3434 90)
			(unlocked yes)
			(layer "B.Fab")
			(hide yes)
			(effects
				(font
					(size 1.27 1.016)
					(thickness 0.1524)
				)
				(justify mirror)
			)
		)
		(duplicate_pad_numbers_are_jumpers no)
		(fp_rect
			(start 0.4318 0.9525)
			(end -0.4318 -0.9525)
			(stroke
				(width 0)
				(type default)
			)
			(fill no)
			(layer "B.CrtYd")
		)
		(fp_rect
			(start 0.4318 0.9525)
			(end -0.4318 -0.9525)
			(stroke
				(width 0)
				(type default)
			)
			(fill no)
			(layer "B.Fab")
		)
		(pad "1" smd custom
			(at 0 -0.4445 270)
			(size 0.1524 0.1524)
			(layers "B.Cu" "B.Mask" "B.Paste")
			(net "P5V_STBY")
			(options
				(clearance outline)
				(anchor circle)
			)
			(primitives
				(gr_poly
					(pts
						(arc
							(start 0.3048 0.2032)
							(mid 0.275042 0.275042)
							(end 0.2032 0.3048)
						)
						(arc
							(start -0.2032 0.3048)
							(mid -0.275042 0.275042)
							(end -0.3048 0.2032)
						)
						(arc
							(start -0.3048 -0.2032)
							(mid -0.275042 -0.275042)
							(end -0.2032 -0.3048)
						)
						(arc
							(start 0.2032 -0.3048)
							(mid 0.275042 -0.275042)
							(end 0.3048 -0.2032)
						)
					)
					(width 0)
					(fill yes)
				)
			)
		)
		(pad "2" smd custom
			(at 0 0.4445 270)
			(size 0.1524 0.1524)
			(layers "B.Cu" "B.Mask" "B.Paste")
			(net "GND")
			(options
				(clearance outline)
				(anchor circle)
			)
			(primitives
				(gr_poly
					(pts
						(arc
							(start 0.3048 0.2032)
							(mid 0.275042 0.275042)
							(end 0.2032 0.3048)
						)
						(arc
							(start -0.2032 0.3048)
							(mid -0.275042 0.275042)
							(end -0.3048 0.2032)
						)
						(arc
							(start -0.3048 -0.2032)
							(mid -0.275042 -0.275042)
							(end -0.2032 -0.3048)
						)
						(arc
							(start 0.2032 -0.3048)
							(mid 0.275042 -0.275042)
							(end 0.3048 -0.2032)
						)
					)
					(width 0)
					(fill yes)
				)
			)
		)
	)
	(footprint ""
		(layer "B.Cu")
		(at 258.2037 -144.8816 -90)
		(property "Reference" "C5L15"
			(at 0 0 90)
			(layer "B.SilkS")
			(hide yes)
			(effects
				(font
					(size 1.27 1.27)
				)
				(justify mirror)
			)
		)
		(property "Value" ""
			(at 0 0 90)
			(layer "B.Fab")
			(effects
				(font
					(size 1.27 1.27)
				)
				(justify mirror)
			)
		)
		(duplicate_pad_numbers_are_jumpers no)
		(fp_rect
			(start 0.500126 1.598422)
			(end -0.500126 -0.201422)
			(stroke
				(width 0)
				(type default)
			)
			(fill no)
			(layer "B.CrtYd")
		)
		(fp_line
			(start -0.500126 1.598422)
			(end 0.500126 1.598422)
			(stroke
				(width 0.1)
				(type default)
			)
			(layer "B.Fab")
		)
		(fp_line
			(start 0.500126 1.598422)
			(end 0.500126 -0.201422)
			(stroke
				(width 0.1)
				(type default)
			)
			(layer "B.Fab")
		)
		(fp_line
			(start -0.500126 -0.201422)
			(end -0.500126 1.598422)
			(stroke
				(width 0.1)
				(type default)
			)
			(layer "B.Fab")
		)
		(fp_line
			(start 0.500126 -0.201422)
			(end -0.500126 -0.201422)
			(stroke
				(width 0.1)
				(type default)
			)
			(layer "B.Fab")
		)
		(pad "1" smd rect
			(at 0 0 180)
			(size 0.889 0.9906)
			(layers "B.Cu" "B.Mask" "B.Paste")
			(net "PVDDQ_DEF")
		)
		(pad "2" smd rect
			(at 0 1.397 180)
			(size 0.889 0.9906)
			(layers "B.Cu" "B.Mask" "B.Paste")
			(net "GND")
		)
		(zone
			(layer "B.Cu")
			(hatch none 0.5)
			(connect_pads
				(clearance 0)
			)
			(min_thickness 0.25)
			(keepout
				(tracks allowed)
				(vias not_allowed)
				(pads allowed)
				(copperpour not_allowed)
				(footprints allowed)
			)
			(placement
				(enabled no)
				(sheetname "")
			)
			(fill
				(thermal_gap 0.5)
				(thermal_bridge_width 0.5)
				(island_removal_mode 0)
			)
			(polygon
				(pts
					(xy 257.2512 -144.3863) (xy 257.7592 -144.3863) (xy 257.7592 -145.3769) (xy 257.2512 -145.3769)
				)
			)
		)
		(zone
			(layer "B.Cu")
			(hatch none 0.5)
			(connect_pads
				(clearance 0)
			)
			(min_thickness 0.25)
			(keepout
				(tracks not_allowed)
				(vias allowed)
				(pads allowed)
				(copperpour not_allowed)
				(footprints allowed)
			)
			(placement
				(enabled no)
				(sheetname "")
			)
			(fill
				(thermal_gap 0.5)
				(thermal_bridge_width 0.5)
				(island_removal_mode 0)
			)
			(polygon
				(pts
					(xy 257.2512 -144.3863) (xy 257.7592 -144.3863) (xy 257.7592 -145.3769) (xy 257.2512 -145.3769)
				)
			)
		)
	)
	(footprint ""
		(layer "B.Cu")
		(at 439.293 -52.3875)
		(property "Reference" "C2R15"
			(at 0 0 0)
			(layer "B.SilkS")
			(hide yes)
			(effects
				(font
					(size 1.27 1.27)
				)
				(justify mirror)
			)
		)
		(property "Value" ""
			(at 0 0 0)
			(layer "B.Fab")
			(effects
				(font
					(size 1.27 1.27)
				)
				(justify mirror)
			)
		)
		(duplicate_pad_numbers_are_jumpers no)
		(fp_poly
			(pts
				(xy -0.3048 -0.1016) (xy -0.3048 0.9906) (xy 0.3048 0.9906) (xy 0.3048 -0.1016)
			)
			(stroke
				(width 0)
				(type default)
			)
			(fill no)
			(layer "B.CrtYd")
		)
		(fp_line
			(start -0.3048 -0.1016)
			(end 0.3048 -0.1016)
			(stroke
				(width 0.1)
				(type default)
			)
			(layer "B.Fab")
		)
		(fp_line
			(start -0.3048 0.9906)
			(end -0.3048 -0.1016)
			(stroke
				(width 0.1)
				(type default)
			)
			(layer "B.Fab")
		)
		(fp_line
			(start 0.3048 -0.1016)
			(end 0.3048 0.9906)
			(stroke
				(width 0.1)
				(type default)
			)
			(layer "B.Fab")
		)
		(fp_line
			(start 0.3048 0.9906)
			(end -0.3048 0.9906)
			(stroke
				(width 0.1)
				(type default)
			)
			(layer "B.Fab")
		)
		(pad "1" smd rect
			(at 0 0 180)
			(size 0.508 0.508)
			(layers "B.Cu" "B.Mask" "B.Paste")
			(net "P12V_STBY")
		)
		(pad "2" smd rect
			(at 0 0.889 180)
			(size 0.508 0.508)
			(layers "B.Cu" "B.Mask" "B.Paste")
			(net "GND")
		)
		(zone
			(layer "B.Cu")
			(hatch none 0.5)
			(connect_pads
				(clearance 0)
			)
			(min_thickness 0.25)
			(keepout
				(tracks allowed)
				(vias not_allowed)
				(pads allowed)
				(copperpour not_allowed)
				(footprints allowed)
			)
			(placement
				(enabled no)
				(sheetname "")
			)
			(fill
				(thermal_gap 0.5)
				(thermal_bridge_width 0.5)
				(island_removal_mode 0)
			)
			(polygon
				(pts
					(xy 439.547 -52.1335) (xy 439.039 -52.1335) (xy 439.039 -51.7525) (xy 439.547 -51.7525)
				)
			)
		)
		(zone
			(layer "B.Cu")
			(hatch none 0.5)
			(connect_pads
				(clearance 0)
			)
			(min_thickness 0.25)
			(keepout
				(tracks not_allowed)
				(vias allowed)
				(pads allowed)
				(copperpour not_allowed)
				(footprints allowed)
			)
			(placement
				(enabled no)
				(sheetname "")
			)
			(fill
				(thermal_gap 0.5)
				(thermal_bridge_width 0.5)
				(island_removal_mode 0)
			)
			(polygon
				(pts
					(xy 439.547 -51.7525) (xy 439.039 -51.7525) (xy 439.039 -52.1335) (xy 439.547 -52.1335)
				)
			)
		)
	)
	(footprint ""
		(layer "B.Cu")
		(at 421.956992 -77.523594 180)
		(property "Reference" "R1R8"
			(at 0 0 0)
			(layer "B.SilkS")
			(hide yes)
			(effects
				(font
					(size 1.27 1.27)
				)
				(justify mirror)
			)
		)
		(property "Value" ""
			(at 0 0 0)
			(layer "B.Fab")
			(effects
				(font
					(size 1.27 1.27)
				)
				(justify mirror)
			)
		)
		(duplicate_pad_numbers_are_jumpers no)
		(fp_poly
			(pts
				(xy 0.2794 -0.1016) (xy -0.2794 -0.1016) (xy -0.2794 0.9906) (xy 0.2794 0.9906)
			)
			(stroke
				(width 0)
				(type default)
			)
			(fill no)
			(layer "B.CrtYd")
		)
		(fp_line
			(start 0.2794 0.9906)
			(end -0.2794 0.9906)
			(stroke
				(width 0.1)
				(type default)
			)
			(layer "B.Fab")
		)
		(fp_line
			(start 0.2794 -0.1016)
			(end 0.2794 0.9906)
			(stroke
				(width 0.1)
				(type default)
			)
			(layer "B.Fab")
		)
		(fp_line
			(start -0.2794 0.9906)
			(end -0.2794 -0.1016)
			(stroke
				(width 0.1)
				(type default)
			)
			(layer "B.Fab")
		)
		(fp_line
			(start -0.2794 -0.1016)
			(end 0.2794 -0.1016)
			(stroke
				(width 0.1)
				(type default)
			)
			(layer "B.Fab")
		)
		(pad "1" smd rect
			(at 0 0)
			(size 0.508 0.508)
			(layers "B.Cu" "B.Mask" "B.Paste")
			(net "FM_THROTTLE_R1_N")
		)
		(pad "2" smd rect
			(at 0 0.889)
			(size 0.508 0.508)
			(layers "B.Cu" "B.Mask" "B.Paste")
			(net "FM_THROTTLE_N")
		)
		(zone
			(layer "B.Cu")
			(hatch none 0.5)
			(connect_pads
				(clearance 0)
			)
			(min_thickness 0.25)
			(keepout
				(tracks not_allowed)
				(vias allowed)
				(pads allowed)
				(copperpour not_allowed)
				(footprints allowed)
			)
			(placement
				(enabled no)
				(sheetname "")
			)
			(fill
				(thermal_gap 0.5)
				(thermal_bridge_width 0.5)
				(island_removal_mode 0)
			)
			(polygon
				(pts
					(xy 421.702992 -78.158594) (xy 422.210992 -78.158594) (xy 422.210992 -77.777594) (xy 421.702992 -77.777594)
				)
			)
		)
		(zone
			(layer "B.Cu")
			(hatch none 0.5)
			(connect_pads
				(clearance 0)
			)
			(min_thickness 0.25)
			(keepout
				(tracks allowed)
				(vias not_allowed)
				(pads allowed)
				(copperpour not_allowed)
				(footprints allowed)
			)
			(placement
				(enabled no)
				(sheetname "")
			)
			(fill
				(thermal_gap 0.5)
				(thermal_bridge_width 0.5)
				(island_removal_mode 0)
			)
			(polygon
				(pts
					(xy 421.702992 -77.777594) (xy 422.210992 -77.777594) (xy 422.210992 -78.158594) (xy 421.702992 -78.158594)
				)
			)
		)
	)
	(footprint ""
		(layer "B.Cu")
		(at 477.081088 -132.83311)
		(property "Reference" "R1W38"
			(at 0.8382 -0.67818 0)
			(unlocked yes)
			(layer "B.SilkS")
			(effects
				(font
					(size 0.4064 0.254)
					(thickness 0.1524)
				)
				(justify left mirror)
			)
		)
		(property "Value" ""
			(at 0 0 0)
			(layer "B.Fab")
			(effects
				(font
					(size 1.27 1.27)
				)
				(justify mirror)
			)
		)
		(duplicate_pad_numbers_are_jumpers no)
		(fp_poly
			(pts
				(xy 0.2794 -0.1016) (xy -0.2794 -0.1016) (xy -0.2794 0.9906) (xy 0.2794 0.9906)
			)
			(stroke
				(width 0)
				(type default)
			)
			(fill no)
			(layer "B.CrtYd")
		)
		(fp_line
			(start -0.2794 -0.1016)
			(end 0.2794 -0.1016)
			(stroke
				(width 0.1)
				(type default)
			)
			(layer "B.Fab")
		)
		(fp_line
			(start -0.2794 0.9906)
			(end -0.2794 -0.1016)
			(stroke
				(width 0.1)
				(type default)
			)
			(layer "B.Fab")
		)
		(fp_line
			(start 0.2794 -0.1016)
			(end 0.2794 0.9906)
			(stroke
				(width 0.1)
				(type default)
			)
			(layer "B.Fab")
		)
		(fp_line
			(start 0.2794 0.9906)
			(end -0.2794 0.9906)
			(stroke
				(width 0.1)
				(type default)
			)
			(layer "B.Fab")
		)
		(pad "1" smd rect
			(at 0 0 180)
			(size 0.508 0.508)
			(layers "B.Cu" "B.Mask" "B.Paste")
			(net "SMB_DEBUG_STBY_LVC3_SCL_CONN")
		)
		(pad "2" smd rect
			(at 0 0.889 180)
			(size 0.508 0.508)
			(layers "B.Cu" "B.Mask" "B.Paste")
			(net "SMB_DEBUG_STBY_LVC3_SCL_R1")
		)
		(zone
			(layer "B.Cu")
			(hatch none 0.5)
			(connect_pads
				(clearance 0)
			)
			(min_thickness 0.25)
			(keepout
				(tracks allowed)
				(vias not_allowed)
				(pads allowed)
				(copperpour not_allowed)
				(footprints allowed)
			)
			(placement
				(enabled no)
				(sheetname "")
			)
			(fill
				(thermal_gap 0.5)
				(thermal_bridge_width 0.5)
				(island_removal_mode 0)
			)
			(polygon
				(pts
					(xy 477.335088 -132.57911) (xy 476.827088 -132.57911) (xy 476.827088 -132.19811) (xy 477.335088 -132.19811)
				)
			)
		)
		(zone
			(layer "B.Cu")
			(hatch none 0.5)
			(connect_pads
				(clearance 0)
			)
			(min_thickness 0.25)
			(keepout
				(tracks not_allowed)
				(vias allowed)
				(pads allowed)
				(copperpour not_allowed)
				(footprints allowed)
			)
			(placement
				(enabled no)
				(sheetname "")
			)
			(fill
				(thermal_gap 0.5)
				(thermal_bridge_width 0.5)
				(island_removal_mode 0)
			)
			(polygon
				(pts
					(xy 477.335088 -132.19811) (xy 476.827088 -132.19811) (xy 476.827088 -132.57911) (xy 477.335088 -132.57911)
				)
			)
		)
	)
	(footprint ""
		(layer "B.Cu")
		(at 365.506 -77.5716 -90)
		(property "Reference" "R7D36"
			(at 0 0 90)
			(layer "B.SilkS")
			(hide yes)
			(effects
				(font
					(size 1.27 1.27)
				)
				(justify mirror)
			)
		)
		(property "Value" ""
			(at 0 0 90)
			(layer "B.Fab")
			(effects
				(font
					(size 1.27 1.27)
				)
				(justify mirror)
			)
		)
		(duplicate_pad_numbers_are_jumpers no)
		(fp_poly
			(pts
				(xy 0.2794 -0.1016) (xy -0.2794 -0.1016) (xy -0.2794 0.9906) (xy 0.2794 0.9906)
			)
			(stroke
				(width 0)
				(type default)
			)
			(fill no)
			(layer "B.CrtYd")
		)
		(fp_line
			(start -0.2794 0.9906)
			(end -0.2794 -0.1016)
			(stroke
				(width 0.1)
				(type default)
			)
			(layer "B.Fab")
		)
		(fp_line
			(start 0.2794 0.9906)
			(end -0.2794 0.9906)
			(stroke
				(width 0.1)
				(type default)
			)
			(layer "B.Fab")
		)
		(fp_line
			(start -0.2794 -0.1016)
			(end 0.2794 -0.1016)
			(stroke
				(width 0.1)
				(type default)
			)
			(layer "B.Fab")
		)
		(fp_line
			(start 0.2794 -0.1016)
			(end 0.2794 0.9906)
			(stroke
				(width 0.1)
				(type default)
			)
			(layer "B.Fab")
		)
		(pad "1" smd rect
			(at 0 0 90)
			(size 0.508 0.508)
			(layers "B.Cu" "B.Mask" "B.Paste")
			(net "FM_156M_CPU1_BRD_OSC_EN")
		)
		(pad "2" smd rect
			(at 0 0.889 90)
			(size 0.508 0.508)
			(layers "B.Cu" "B.Mask" "B.Paste")
			(net "FM_CPU1_STL_BRD_OSC_EN")
		)
		(zone
			(layer "B.Cu")
			(hatch none 0.5)
			(connect_pads
				(clearance 0)
			)
			(min_thickness 0.25)
			(keepout
				(tracks not_allowed)
				(vias allowed)
				(pads allowed)
				(copperpour not_allowed)
				(footprints allowed)
			)
			(placement
				(enabled no)
				(sheetname "")
			)
			(fill
				(thermal_gap 0.5)
				(thermal_bridge_width 0.5)
				(island_removal_mode 0)
			)
			(polygon
				(pts
					(xy 364.871 -77.3176) (xy 364.871 -77.8256) (xy 365.252 -77.8256) (xy 365.252 -77.3176)
				)
			)
		)
		(zone
			(layer "B.Cu")
			(hatch none 0.5)
			(connect_pads
				(clearance 0)
			)
			(min_thickness 0.25)
			(keepout
				(tracks allowed)
				(vias not_allowed)
				(pads allowed)
				(copperpour not_allowed)
				(footprints allowed)
			)
			(placement
				(enabled no)
				(sheetname "")
			)
			(fill
				(thermal_gap 0.5)
				(thermal_bridge_width 0.5)
				(island_removal_mode 0)
			)
			(polygon
				(pts
					(xy 365.252 -77.3176) (xy 365.252 -77.8256) (xy 364.871 -77.8256) (xy 364.871 -77.3176)
				)
			)
		)
	)
	(footprint ""
		(layer "B.Cu")
		(at 13.10894 -97.11436 90)
		(property "Reference" "C9N18"
			(at 0 0 90)
			(layer "B.SilkS")
			(hide yes)
			(effects
				(font
					(size 1.27 1.27)
				)
				(justify mirror)
			)
		)
		(property "Value" ""
			(at 0 0 90)
			(layer "B.Fab")
			(effects
				(font
					(size 1.27 1.27)
				)
				(justify mirror)
			)
		)
		(duplicate_pad_numbers_are_jumpers no)
		(fp_poly
			(pts
				(xy -0.3048 -0.1016) (xy -0.3048 0.9906) (xy 0.3048 0.9906) (xy 0.3048 -0.1016)
			)
			(stroke
				(width 0)
				(type default)
			)
			(fill no)
			(layer "B.CrtYd")
		)
		(fp_line
			(start 0.3048 -0.1016)
			(end 0.3048 0.9906)
			(stroke
				(width 0.1)
				(type default)
			)
			(layer "B.Fab")
		)
		(fp_line
			(start -0.3048 -0.1016)
			(end 0.3048 -0.1016)
			(stroke
				(width 0.1)
				(type default)
			)
			(layer "B.Fab")
		)
		(fp_line
			(start 0.3048 0.9906)
			(end -0.3048 0.9906)
			(stroke
				(width 0.1)
				(type default)
			)
			(layer "B.Fab")
		)
		(fp_line
			(start -0.3048 0.9906)
			(end -0.3048 -0.1016)
			(stroke
				(width 0.1)
				(type default)
			)
			(layer "B.Fab")
		)
		(pad "1" smd rect
			(at 0 0 270)
			(size 0.508 0.508)
			(layers "B.Cu" "B.Mask" "B.Paste")
			(net "P3E_CPU1_PE3_MP_C_TXN<8>")
		)
		(pad "2" smd rect
			(at 0 0.889 270)
			(size 0.508 0.508)
			(layers "B.Cu" "B.Mask" "B.Paste")
			(net "P3E_CPU1_PE3_MP_TXN<8>")
		)
		(zone
			(layer "B.Cu")
			(hatch none 0.5)
			(connect_pads
				(clearance 0)
			)
			(min_thickness 0.25)
			(keepout
				(tracks allowed)
				(vias not_allowed)
				(pads allowed)
				(copperpour not_allowed)
				(footprints allowed)
			)
			(placement
				(enabled no)
				(sheetname "")
			)
			(fill
				(thermal_gap 0.5)
				(thermal_bridge_width 0.5)
				(island_removal_mode 0)
			)
			(polygon
				(pts
					(xy 13.36294 -97.36836) (xy 13.36294 -96.86036) (xy 13.74394 -96.86036) (xy 13.74394 -97.36836)
				)
			)
		)
		(zone
			(layer "B.Cu")
			(hatch none 0.5)
			(connect_pads
				(clearance 0)
			)
			(min_thickness 0.25)
			(keepout
				(tracks not_allowed)
				(vias allowed)
				(pads allowed)
				(copperpour not_allowed)
				(footprints allowed)
			)
			(placement
				(enabled no)
				(sheetname "")
			)
			(fill
				(thermal_gap 0.5)
				(thermal_bridge_width 0.5)
				(island_removal_mode 0)
			)
			(polygon
				(pts
					(xy 13.74394 -97.36836) (xy 13.74394 -96.86036) (xy 13.36294 -96.86036) (xy 13.36294 -97.36836)
				)
			)
		)
	)
	(footprint ""
		(layer "B.Cu")
		(at 379.6792 -137.2108)
		(property "Reference" "C3M19"
			(at 0 0 0)
			(layer "B.SilkS")
			(hide yes)
			(effects
				(font
					(size 1.27 1.27)
				)
				(justify mirror)
			)
		)
		(property "Value" ""
			(at 0 0 0)
			(layer "B.Fab")
			(effects
				(font
					(size 1.27 1.27)
				)
				(justify mirror)
			)
		)
		(duplicate_pad_numbers_are_jumpers no)
		(fp_poly
			(pts
				(xy -0.3048 -0.1016) (xy -0.3048 0.9906) (xy 0.3048 0.9906) (xy 0.3048 -0.1016)
			)
			(stroke
				(width 0)
				(type default)
			)
			(fill no)
			(layer "B.CrtYd")
		)
		(fp_line
			(start -0.3048 -0.1016)
			(end 0.3048 -0.1016)
			(stroke
				(width 0.1)
				(type default)
			)
			(layer "B.Fab")
		)
		(fp_line
			(start -0.3048 0.9906)
			(end -0.3048 -0.1016)
			(stroke
				(width 0.1)
				(type default)
			)
			(layer "B.Fab")
		)
		(fp_line
			(start 0.3048 -0.1016)
			(end 0.3048 0.9906)
			(stroke
				(width 0.1)
				(type default)
			)
			(layer "B.Fab")
		)
		(fp_line
			(start 0.3048 0.9906)
			(end -0.3048 0.9906)
			(stroke
				(width 0.1)
				(type default)
			)
			(layer "B.Fab")
		)
		(pad "1" smd rect
			(at 0 0 180)
			(size 0.508 0.508)
			(layers "B.Cu" "B.Mask" "B.Paste")
			(net "P1V05_PCH_STBY_VCCA_PLL1")
		)
		(pad "2" smd rect
			(at 0 0.889 180)
			(size 0.508 0.508)
			(layers "B.Cu" "B.Mask" "B.Paste")
			(net "GND")
		)
		(zone
			(layer "B.Cu")
			(hatch none 0.5)
			(connect_pads
				(clearance 0)
			)
			(min_thickness 0.25)
			(keepout
				(tracks allowed)
				(vias not_allowed)
				(pads allowed)
				(copperpour not_allowed)
				(footprints allowed)
			)
			(placement
				(enabled no)
				(sheetname "")
			)
			(fill
				(thermal_gap 0.5)
				(thermal_bridge_width 0.5)
				(island_removal_mode 0)
			)
			(polygon
				(pts
					(xy 379.9332 -136.9568) (xy 379.4252 -136.9568) (xy 379.4252 -136.5758) (xy 379.9332 -136.5758)
				)
			)
		)
		(zone
			(layer "B.Cu")
			(hatch none 0.5)
			(connect_pads
				(clearance 0)
			)
			(min_thickness 0.25)
			(keepout
				(tracks not_allowed)
				(vias allowed)
				(pads allowed)
				(copperpour not_allowed)
				(footprints allowed)
			)
			(placement
				(enabled no)
				(sheetname "")
			)
			(fill
				(thermal_gap 0.5)
				(thermal_bridge_width 0.5)
				(island_removal_mode 0)
			)
			(polygon
				(pts
					(xy 379.9332 -136.5758) (xy 379.4252 -136.5758) (xy 379.4252 -136.9568) (xy 379.9332 -136.9568)
				)
			)
		)
	)
	(footprint ""
		(layer "B.Cu")
		(at 354.460048 -86.93404 180)
		(property "Reference" "SH3P2"
			(at 0 0 0)
			(layer "B.SilkS")
			(hide yes)
			(effects
				(font
					(size 1.27 1.27)
				)
				(justify mirror)
			)
		)
		(property "Value" ""
			(at 0 0 0)
			(layer "B.Fab")
			(effects
				(font
					(size 1.27 1.27)
				)
				(justify mirror)
			)
		)
		(duplicate_pad_numbers_are_jumpers no)
		(fp_poly
			(pts
				(xy 0.1651 -0.0508) (xy 0.1651 0.5842) (xy -0.1651 0.5842) (xy -0.1651 -0.0508)
			)
			(stroke
				(width 0)
				(type default)
			)
			(fill no)
			(layer "B.CrtYd")
		)
		(fp_line
			(start 0.1651 0.5842)
			(end 0.1651 -0.0508)
			(stroke
				(width 0.1)
				(type default)
			)
			(layer "B.Fab")
		)
		(fp_line
			(start 0.1651 -0.0508)
			(end -0.1651 -0.0508)
			(stroke
				(width 0.1)
				(type default)
			)
			(layer "B.Fab")
		)
		(fp_line
			(start -0.1651 0.5842)
			(end 0.1651 0.5842)
			(stroke
				(width 0.1)
				(type default)
			)
			(layer "B.Fab")
		)
		(fp_line
			(start -0.1651 -0.0508)
			(end -0.1651 0.5842)
			(stroke
				(width 0.1)
				(type default)
			)
			(layer "B.Fab")
		)
		(pad "1" smd custom
			(at 0 0 180)
			(size 0.0762 0.0762)
			(layers "B.Cu" "B.Mask" "B.Paste")
			(net "VSENSE_PVCCIO_CPU0_SKT_VRTN")
			(options
				(clearance outline)
				(anchor circle)
			)
			(primitives
				(gr_poly
					(pts
						(arc
							(start -0.1524 0.10795)
							(mid -0.098518 0.130268)
							(end -0.0762 0.18415)
						)
						(xy -0.0762 0.22225) (xy 0.0762 0.22225)
						(arc
							(start 0.0762 0.18415)
							(mid 0.098518 0.130268)
							(end 0.1524 0.10795)
						)
						(xy 0.1524 -0.22225) (xy -0.1524 -0.22225)
					)
					(width 0)
					(fill yes)
				)
			)
		)
		(pad "2" smd custom
			(at 0 0.5334)
			(size 0.0762 0.0762)
			(layers "B.Cu" "B.Mask" "B.Paste")
			(net "VSENSE_PVCCIO_CPU0_AVSN")
			(options
				(clearance outline)
				(anchor circle)
			)
			(primitives
				(gr_poly
					(pts
						(arc
							(start -0.1524 0.10795)
							(mid -0.098518 0.130268)
							(end -0.0762 0.18415)
						)
						(xy -0.0762 0.22225) (xy 0.0762 0.22225)
						(arc
							(start 0.0762 0.18415)
							(mid 0.098518 0.130268)
							(end 0.1524 0.10795)
						)
						(xy 0.1524 -0.22225) (xy -0.1524 -0.22225)
					)
					(width 0)
					(fill yes)
				)
			)
		)
	)
	(footprint ""
		(layer "B.Cu")
		(at 485.8512 -128.2065 180)
		(property "Reference" "R1U19"
			(at 0 0 0)
			(layer "B.SilkS")
			(hide yes)
			(effects
				(font
					(size 1.27 1.27)
				)
				(justify mirror)
			)
		)
		(property "Value" ""
			(at 0 0 0)
			(layer "B.Fab")
			(effects
				(font
					(size 1.27 1.27)
				)
				(justify mirror)
			)
		)
		(duplicate_pad_numbers_are_jumpers no)
		(fp_poly
			(pts
				(xy 0.2794 -0.1016) (xy -0.2794 -0.1016) (xy -0.2794 0.9906) (xy 0.2794 0.9906)
			)
			(stroke
				(width 0)
				(type default)
			)
			(fill no)
			(layer "B.CrtYd")
		)
		(fp_line
			(start 0.2794 0.9906)
			(end -0.2794 0.9906)
			(stroke
				(width 0.1)
				(type default)
			)
			(layer "B.Fab")
		)
		(fp_line
			(start 0.2794 -0.1016)
			(end 0.2794 0.9906)
			(stroke
				(width 0.1)
				(type default)
			)
			(layer "B.Fab")
		)
		(fp_line
			(start -0.2794 0.9906)
			(end -0.2794 -0.1016)
			(stroke
				(width 0.1)
				(type default)
			)
			(layer "B.Fab")
		)
		(fp_line
			(start -0.2794 -0.1016)
			(end 0.2794 -0.1016)
			(stroke
				(width 0.1)
				(type default)
			)
			(layer "B.Fab")
		)
		(pad "1" smd rect
			(at 0 0)
			(size 0.508 0.508)
			(layers "B.Cu" "B.Mask" "B.Paste")
			(net "SMB_SMLINK0_STBY_LVC3_SCL")
		)
		(pad "2" smd rect
			(at 0 0.889)
			(size 0.508 0.508)
			(layers "B.Cu" "B.Mask" "B.Paste")
			(net "SMB_SPRINGVILLE_STBY_LVC3_SCL")
		)
		(zone
			(layer "B.Cu")
			(hatch none 0.5)
			(connect_pads
				(clearance 0)
			)
			(min_thickness 0.25)
			(keepout
				(tracks not_allowed)
				(vias allowed)
				(pads allowed)
				(copperpour not_allowed)
				(footprints allowed)
			)
			(placement
				(enabled no)
				(sheetname "")
			)
			(fill
				(thermal_gap 0.5)
				(thermal_bridge_width 0.5)
				(island_removal_mode 0)
			)
			(polygon
				(pts
					(xy 485.5972 -128.8415) (xy 486.1052 -128.8415) (xy 486.1052 -128.4605) (xy 485.5972 -128.4605)
				)
			)
		)
		(zone
			(layer "B.Cu")
			(hatch none 0.5)
			(connect_pads
				(clearance 0)
			)
			(min_thickness 0.25)
			(keepout
				(tracks allowed)
				(vias not_allowed)
				(pads allowed)
				(copperpour not_allowed)
				(footprints allowed)
			)
			(placement
				(enabled no)
				(sheetname "")
			)
			(fill
				(thermal_gap 0.5)
				(thermal_bridge_width 0.5)
				(island_removal_mode 0)
			)
			(polygon
				(pts
					(xy 485.5972 -128.4605) (xy 486.1052 -128.4605) (xy 486.1052 -128.8415) (xy 485.5972 -128.8415)
				)
			)
		)
	)
	(footprint ""
		(layer "B.Cu")
		(at 295.1226 -65.462404 90)
		(property "Reference" "R4P23"
			(at 0 0 90)
			(layer "B.SilkS")
			(hide yes)
			(effects
				(font
					(size 1.27 1.27)
				)
				(justify mirror)
			)
		)
		(property "Value" ""
			(at 0 0 90)
			(layer "B.Fab")
			(effects
				(font
					(size 1.27 1.27)
				)
				(justify mirror)
			)
		)
		(duplicate_pad_numbers_are_jumpers no)
		(fp_poly
			(pts
				(xy 0.2794 -0.1016) (xy -0.2794 -0.1016) (xy -0.2794 0.9906) (xy 0.2794 0.9906)
			)
			(stroke
				(width 0)
				(type default)
			)
			(fill no)
			(layer "B.CrtYd")
		)
		(fp_line
			(start 0.2794 -0.1016)
			(end 0.2794 0.9906)
			(stroke
				(width 0.1)
				(type default)
			)
			(layer "B.Fab")
		)
		(fp_line
			(start -0.2794 -0.1016)
			(end 0.2794 -0.1016)
			(stroke
				(width 0.1)
				(type default)
			)
			(layer "B.Fab")
		)
		(fp_line
			(start 0.2794 0.9906)
			(end -0.2794 0.9906)
			(stroke
				(width 0.1)
				(type default)
			)
			(layer "B.Fab")
		)
		(fp_line
			(start -0.2794 0.9906)
			(end -0.2794 -0.1016)
			(stroke
				(width 0.1)
				(type default)
			)
			(layer "B.Fab")
		)
		(pad "1" smd rect
			(at 0 0 270)
			(size 0.508 0.508)
			(layers "B.Cu" "B.Mask" "B.Paste")
			(net "PVCCIO_CPU0")
		)
		(pad "2" smd rect
			(at 0 0.889 270)
			(size 0.508 0.508)
			(layers "B.Cu" "B.Mask" "B.Paste")
			(net "XDP_CPU0_TDO")
		)
		(zone
			(layer "B.Cu")
			(hatch none 0.5)
			(connect_pads
				(clearance 0)
			)
			(min_thickness 0.25)
			(keepout
				(tracks allowed)
				(vias not_allowed)
				(pads allowed)
				(copperpour not_allowed)
				(footprints allowed)
			)
			(placement
				(enabled no)
				(sheetname "")
			)
			(fill
				(thermal_gap 0.5)
				(thermal_bridge_width 0.5)
				(island_removal_mode 0)
			)
			(polygon
				(pts
					(xy 295.3766 -65.716404) (xy 295.3766 -65.208404) (xy 295.7576 -65.208404) (xy 295.7576 -65.716404)
				)
			)
		)
		(zone
			(layer "B.Cu")
			(hatch none 0.5)
			(connect_pads
				(clearance 0)
			)
			(min_thickness 0.25)
			(keepout
				(tracks not_allowed)
				(vias allowed)
				(pads allowed)
				(copperpour not_allowed)
				(footprints allowed)
			)
			(placement
				(enabled no)
				(sheetname "")
			)
			(fill
				(thermal_gap 0.5)
				(thermal_bridge_width 0.5)
				(island_removal_mode 0)
			)
			(polygon
				(pts
					(xy 295.7576 -65.716404) (xy 295.7576 -65.208404) (xy 295.3766 -65.208404) (xy 295.3766 -65.716404)
				)
			)
		)
	)
	(footprint ""
		(layer "B.Cu")
		(at 488.442 -113.2332 90)
		(property "Reference" "C1M22"
			(at 0 0 90)
			(layer "B.SilkS")
			(hide yes)
			(effects
				(font
					(size 1.27 1.27)
				)
				(justify mirror)
			)
		)
		(property "Value" ""
			(at 0 0 90)
			(layer "B.Fab")
			(effects
				(font
					(size 1.27 1.27)
				)
				(justify mirror)
			)
		)
		(duplicate_pad_numbers_are_jumpers no)
		(fp_rect
			(start -0.3048 -0.1016)
			(end 0.3048 0.9906)
			(stroke
				(width 0)
				(type default)
			)
			(fill no)
			(layer "B.CrtYd")
		)
		(fp_line
			(start 0.3048 -0.1016)
			(end 0.3048 0.9906)
			(stroke
				(width 0.1)
				(type default)
			)
			(layer "B.Fab")
		)
		(fp_line
			(start -0.3048 -0.1016)
			(end 0.3048 -0.1016)
			(stroke
				(width 0.1)
				(type default)
			)
			(layer "B.Fab")
		)
		(fp_line
			(start 0.3048 0.9906)
			(end -0.3048 0.9906)
			(stroke
				(width 0.1)
				(type default)
			)
			(layer "B.Fab")
		)
		(fp_line
			(start -0.3048 0.9906)
			(end -0.3048 -0.1016)
			(stroke
				(width 0.1)
				(type default)
			)
			(layer "B.Fab")
		)
		(pad "1" smd rect
			(at 0 0 270)
			(size 0.508 0.508)
			(layers "B.Cu" "B.Mask" "B.Paste")
			(net "P12V_STBY")
		)
		(pad "2" smd rect
			(at 0 0.889 270)
			(size 0.508 0.508)
			(layers "B.Cu" "B.Mask" "B.Paste")
			(net "GND")
		)
		(zone
			(layer "B.Cu")
			(hatch none 0.5)
			(connect_pads
				(clearance 0)
			)
			(min_thickness 0.25)
			(keepout
				(tracks allowed)
				(vias not_allowed)
				(pads allowed)
				(copperpour not_allowed)
				(footprints allowed)
			)
			(placement
				(enabled no)
				(sheetname "")
			)
			(fill
				(thermal_gap 0.5)
				(thermal_bridge_width 0.5)
				(island_removal_mode 0)
			)
			(polygon
				(pts
					(xy 488.696 -112.9792) (xy 489.077 -112.9792) (xy 489.077 -113.4872) (xy 488.696 -113.4872)
				)
			)
		)
		(zone
			(layer "B.Cu")
			(hatch none 0.5)
			(connect_pads
				(clearance 0)
			)
			(min_thickness 0.25)
			(keepout
				(tracks not_allowed)
				(vias allowed)
				(pads allowed)
				(copperpour not_allowed)
				(footprints allowed)
			)
			(placement
				(enabled no)
				(sheetname "")
			)
			(fill
				(thermal_gap 0.5)
				(thermal_bridge_width 0.5)
				(island_removal_mode 0)
			)
			(polygon
				(pts
					(xy 488.696 -112.9792) (xy 489.077 -112.9792) (xy 489.077 -113.4872) (xy 488.696 -113.4872)
				)
			)
		)
	)
	(footprint ""
		(layer "B.Cu")
		(at 214.503 -78.4098)
		(property "Reference" "C6P16"
			(at 0 0 0)
			(layer "B.SilkS")
			(hide yes)
			(effects
				(font
					(size 1.27 1.27)
				)
				(justify mirror)
			)
		)
		(property "Value" ""
			(at 0 0 0)
			(layer "B.Fab")
			(effects
				(font
					(size 1.27 1.27)
				)
				(justify mirror)
			)
		)
		(duplicate_pad_numbers_are_jumpers no)
		(fp_poly
			(pts
				(xy 0.4953 -0.2032) (xy -0.4953 -0.2032) (xy -0.4953 1.6002) (xy 0.4953 1.6002)
			)
			(stroke
				(width 0)
				(type default)
			)
			(fill no)
			(layer "B.CrtYd")
		)
		(fp_line
			(start -0.4953 -0.2032)
			(end -0.4953 1.6002)
			(stroke
				(width 0.1)
				(type default)
			)
			(layer "B.Fab")
		)
		(fp_line
			(start -0.4953 1.6002)
			(end 0.4953 1.6002)
			(stroke
				(width 0.1)
				(type default)
			)
			(layer "B.Fab")
		)
		(fp_line
			(start 0.4953 -0.2032)
			(end -0.4953 -0.2032)
			(stroke
				(width 0.1)
				(type default)
			)
			(layer "B.Fab")
		)
		(fp_line
			(start 0.4953 1.6002)
			(end 0.4953 -0.2032)
			(stroke
				(width 0.1)
				(type default)
			)
			(layer "B.Fab")
		)
		(pad "1" smd rect
			(at 0 0 180)
			(size 0.762 0.889)
			(layers "B.Cu" "B.Mask" "B.Paste")
			(net "PVCCIN_CPU0")
		)
		(pad "2" smd rect
			(at 0 1.397 180)
			(size 0.762 0.889)
			(layers "B.Cu" "B.Mask" "B.Paste")
			(net "GND")
		)
		(zone
			(layer "B.Cu")
			(hatch none 0.5)
			(connect_pads
				(clearance 0)
			)
			(min_thickness 0.25)
			(keepout
				(tracks not_allowed)
				(vias allowed)
				(pads allowed)
				(copperpour not_allowed)
				(footprints allowed)
			)
			(placement
				(enabled no)
				(sheetname "")
			)
			(fill
				(thermal_gap 0.5)
				(thermal_bridge_width 0.5)
				(island_removal_mode 0)
			)
			(polygon
				(pts
					(xy 214.884 -77.9653) (xy 214.122 -77.9653) (xy 214.122 -77.4573) (xy 214.884 -77.4573)
				)
			)
		)
	)
	(footprint ""
		(layer "B.Cu")
		(at 176.212754 -85.217 -90)
		(property "Reference" "R6P9"
			(at 0 0 90)
			(layer "B.SilkS")
			(hide yes)
			(effects
				(font
					(size 1.27 1.27)
				)
				(justify mirror)
			)
		)
		(property "Value" ""
			(at 0 0 90)
			(layer "B.Fab")
			(effects
				(font
					(size 1.27 1.27)
				)
				(justify mirror)
			)
		)
		(duplicate_pad_numbers_are_jumpers no)
		(fp_poly
			(pts
				(xy 0.2794 -0.1016) (xy -0.2794 -0.1016) (xy -0.2794 0.9906) (xy 0.2794 0.9906)
			)
			(stroke
				(width 0)
				(type default)
			)
			(fill no)
			(layer "B.CrtYd")
		)
		(fp_line
			(start -0.2794 0.9906)
			(end -0.2794 -0.1016)
			(stroke
				(width 0.1)
				(type default)
			)
			(layer "B.Fab")
		)
		(fp_line
			(start 0.2794 0.9906)
			(end -0.2794 0.9906)
			(stroke
				(width 0.1)
				(type default)
			)
			(layer "B.Fab")
		)
		(fp_line
			(start -0.2794 -0.1016)
			(end 0.2794 -0.1016)
			(stroke
				(width 0.1)
				(type default)
			)
			(layer "B.Fab")
		)
		(fp_line
			(start 0.2794 -0.1016)
			(end 0.2794 0.9906)
			(stroke
				(width 0.1)
				(type default)
			)
			(layer "B.Fab")
		)
		(pad "1" smd rect
			(at 0 0 90)
			(size 0.508 0.508)
			(layers "B.Cu" "B.Mask" "B.Paste")
			(net "CLK_100M_CPU0_PE_REFCLK_DN")
		)
		(pad "2" smd rect
			(at 0 0.889 90)
			(size 0.508 0.508)
			(layers "B.Cu" "B.Mask" "B.Paste")
			(net "GND")
		)
		(zone
			(layer "B.Cu")
			(hatch none 0.5)
			(connect_pads
				(clearance 0)
			)
			(min_thickness 0.25)
			(keepout
				(tracks not_allowed)
				(vias allowed)
				(pads allowed)
				(copperpour not_allowed)
				(footprints allowed)
			)
			(placement
				(enabled no)
				(sheetname "")
			)
			(fill
				(thermal_gap 0.5)
				(thermal_bridge_width 0.5)
				(island_removal_mode 0)
			)
			(polygon
				(pts
					(xy 175.577754 -84.963) (xy 175.577754 -85.471) (xy 175.958754 -85.471) (xy 175.958754 -84.963)
				)
			)
		)
		(zone
			(layer "B.Cu")
			(hatch none 0.5)
			(connect_pads
				(clearance 0)
			)
			(min_thickness 0.25)
			(keepout
				(tracks allowed)
				(vias not_allowed)
				(pads allowed)
				(copperpour not_allowed)
				(footprints allowed)
			)
			(placement
				(enabled no)
				(sheetname "")
			)
			(fill
				(thermal_gap 0.5)
				(thermal_bridge_width 0.5)
				(island_removal_mode 0)
			)
			(polygon
				(pts
					(xy 175.958754 -84.963) (xy 175.958754 -85.471) (xy 175.577754 -85.471) (xy 175.577754 -84.963)
				)
			)
		)
	)
	(footprint ""
		(layer "B.Cu")
		(at 372.5418 -90.805 90)
		(property "Reference" "R7D23"
			(at 0 0 90)
			(layer "B.SilkS")
			(hide yes)
			(effects
				(font
					(size 1.27 1.27)
				)
				(justify mirror)
			)
		)
		(property "Value" ""
			(at 0 0 90)
			(layer "B.Fab")
			(effects
				(font
					(size 1.27 1.27)
				)
				(justify mirror)
			)
		)
		(duplicate_pad_numbers_are_jumpers no)
		(fp_poly
			(pts
				(xy 0.2794 -0.1016) (xy -0.2794 -0.1016) (xy -0.2794 0.9906) (xy 0.2794 0.9906)
			)
			(stroke
				(width 0)
				(type default)
			)
			(fill no)
			(layer "B.CrtYd")
		)
		(fp_line
			(start 0.2794 -0.1016)
			(end 0.2794 0.9906)
			(stroke
				(width 0.1)
				(type default)
			)
			(layer "B.Fab")
		)
		(fp_line
			(start -0.2794 -0.1016)
			(end 0.2794 -0.1016)
			(stroke
				(width 0.1)
				(type default)
			)
			(layer "B.Fab")
		)
		(fp_line
			(start 0.2794 0.9906)
			(end -0.2794 0.9906)
			(stroke
				(width 0.1)
				(type default)
			)
			(layer "B.Fab")
		)
		(fp_line
			(start -0.2794 0.9906)
			(end -0.2794 -0.1016)
			(stroke
				(width 0.1)
				(type default)
			)
			(layer "B.Fab")
		)
		(pad "1" smd rect
			(at 0 0 270)
			(size 0.508 0.508)
			(layers "B.Cu" "B.Mask" "B.Paste")
			(net "RST_BMC_SRST_N")
		)
		(pad "2" smd rect
			(at 0 0.889 270)
			(size 0.508 0.508)
			(layers "B.Cu" "B.Mask" "B.Paste")
			(net "RST_BMC_SRST_R_N")
		)
		(zone
			(layer "B.Cu")
			(hatch none 0.5)
			(connect_pads
				(clearance 0)
			)
			(min_thickness 0.25)
			(keepout
				(tracks allowed)
				(vias not_allowed)
				(pads allowed)
				(copperpour not_allowed)
				(footprints allowed)
			)
			(placement
				(enabled no)
				(sheetname "")
			)
			(fill
				(thermal_gap 0.5)
				(thermal_bridge_width 0.5)
				(island_removal_mode 0)
			)
			(polygon
				(pts
					(xy 372.7958 -91.059) (xy 372.7958 -90.551) (xy 373.1768 -90.551) (xy 373.1768 -91.059)
				)
			)
		)
		(zone
			(layer "B.Cu")
			(hatch none 0.5)
			(connect_pads
				(clearance 0)
			)
			(min_thickness 0.25)
			(keepout
				(tracks not_allowed)
				(vias allowed)
				(pads allowed)
				(copperpour not_allowed)
				(footprints allowed)
			)
			(placement
				(enabled no)
				(sheetname "")
			)
			(fill
				(thermal_gap 0.5)
				(thermal_bridge_width 0.5)
				(island_removal_mode 0)
			)
			(polygon
				(pts
					(xy 373.1768 -91.059) (xy 373.1768 -90.551) (xy 372.7958 -90.551) (xy 372.7958 -91.059)
				)
			)
		)
	)
	(footprint ""
		(layer "B.Cu")
		(at 177.1015 -57.531 -90)
		(property "Reference" "C4E28"
			(at 0 0 90)
			(layer "B.SilkS")
			(hide yes)
			(effects
				(font
					(size 1.27 1.27)
				)
				(justify mirror)
			)
		)
		(property "Value" "*"
			(at -1.1811 -2.8194 270)
			(unlocked yes)
			(layer "B.Fab")
			(hide yes)
			(effects
				(font
					(size 1.27 1.016)
					(thickness 0.1524)
				)
				(justify mirror)
			)
		)
		(property "Device Type" "SC1U10V2KX-4-GP_SMD-BCG6-SC1U1A"
			(at -1.1811 -4.3434 270)
			(unlocked yes)
			(layer "B.Fab")
			(hide yes)
			(effects
				(font
					(size 1.27 1.016)
					(thickness 0.1524)
				)
				(justify mirror)
			)
		)
		(duplicate_pad_numbers_are_jumpers no)
		(fp_rect
			(start 0.4318 0.9525)
			(end -0.4318 -0.9525)
			(stroke
				(width 0)
				(type default)
			)
			(fill no)
			(layer "B.CrtYd")
		)
		(fp_rect
			(start 0.4318 0.9525)
			(end -0.4318 -0.9525)
			(stroke
				(width 0)
				(type default)
			)
			(fill no)
			(layer "B.Fab")
		)
		(pad "1" smd custom
			(at 0 -0.4445 90)
			(size 0.1524 0.1524)
			(layers "B.Cu" "B.Mask" "B.Paste")
			(net "P5V_STBY")
			(options
				(clearance outline)
				(anchor circle)
			)
			(primitives
				(gr_poly
					(pts
						(arc
							(start 0.3048 0.2032)
							(mid 0.275042 0.275042)
							(end 0.2032 0.3048)
						)
						(arc
							(start -0.2032 0.3048)
							(mid -0.275042 0.275042)
							(end -0.3048 0.2032)
						)
						(arc
							(start -0.3048 -0.2032)
							(mid -0.275042 -0.275042)
							(end -0.2032 -0.3048)
						)
						(arc
							(start 0.2032 -0.3048)
							(mid 0.275042 -0.275042)
							(end 0.3048 -0.2032)
						)
					)
					(width 0)
					(fill yes)
				)
			)
		)
		(pad "2" smd custom
			(at 0 0.4445 90)
			(size 0.1524 0.1524)
			(layers "B.Cu" "B.Mask" "B.Paste")
			(net "GND")
			(options
				(clearance outline)
				(anchor circle)
			)
			(primitives
				(gr_poly
					(pts
						(arc
							(start 0.3048 0.2032)
							(mid 0.275042 0.275042)
							(end 0.2032 0.3048)
						)
						(arc
							(start -0.2032 0.3048)
							(mid -0.275042 0.275042)
							(end -0.3048 0.2032)
						)
						(arc
							(start -0.3048 -0.2032)
							(mid -0.275042 -0.275042)
							(end -0.2032 -0.3048)
						)
						(arc
							(start 0.2032 -0.3048)
							(mid 0.275042 -0.275042)
							(end 0.3048 -0.2032)
						)
					)
					(width 0)
					(fill yes)
				)
			)
		)
	)
	(footprint ""
		(layer "B.Cu")
		(at 411.48 0.2794)
		(property "Reference" "U8G2"
			(at -5.334 1.24333 180)
			(unlocked yes)
			(layer "B.SilkS")
			(effects
				(font
					(size 0.7874 0.5842)
					(thickness 0.1524)
				)
				(justify left mirror)
			)
		)
		(property "Value" ""
			(at 0 0 0)
			(layer "B.Fab")
			(effects
				(font
					(size 1.27 1.27)
				)
				(justify mirror)
			)
		)
		(duplicate_pad_numbers_are_jumpers no)
		(fp_circle
			(center 1.03124 -0.04826)
			(end 1.15824 -0.04826)
			(stroke
				(width 0.254)
				(type default)
			)
			(fill no)
			(layer "B.SilkS")
		)
		(fp_poly
			(pts
				(xy -0.21463 -0.450088) (xy -1.56337 -0.450088) (xy -1.56337 1.75006) (xy -0.21463 1.75006)
			)
			(stroke
				(width 0)
				(type default)
			)
			(fill no)
			(layer "B.CrtYd")
		)
		(fp_line
			(start -1.56337 -0.450088)
			(end -1.56337 1.75006)
			(stroke
				(width 0.1)
				(type default)
			)
			(layer "B.Fab")
		)
		(fp_line
			(start -1.56337 1.75006)
			(end -0.21463 1.75006)
			(stroke
				(width 0.1)
				(type default)
			)
			(layer "B.Fab")
		)
		(fp_line
			(start -0.21463 -0.450088)
			(end -1.56337 -0.450088)
			(stroke
				(width 0.1)
				(type default)
			)
			(layer "B.Fab")
		)
		(fp_line
			(start -0.21463 1.75006)
			(end -0.21463 -0.450088)
			(stroke
				(width 0.1)
				(type default)
			)
			(layer "B.Fab")
		)
		(fp_circle
			(center 0.4699 -0.8382)
			(end 0.5969 -0.8382)
			(stroke
				(width 0.254)
				(type default)
			)
			(fill no)
			(layer "B.Fab")
		)
		(pad "1" smd rect
			(at 0 0 180)
			(size 1.016 0.381)
			(layers "B.Cu" "B.Mask" "B.Paste")
			(net "Net_6469")
		)
		(pad "2" smd rect
			(at 0 0.649986 180)
			(size 1.016 0.381)
			(layers "B.Cu" "B.Mask" "B.Paste")
			(net "FAN_PWM_OUT_SYS0")
		)
		(pad "3" smd rect
			(at 0 1.299972 180)
			(size 1.016 0.381)
			(layers "B.Cu" "B.Mask" "B.Paste")
			(net "GND")
		)
		(pad "4" smd rect
			(at -1.778 1.299972 180)
			(size 1.016 0.381)
			(layers "B.Cu" "B.Mask" "B.Paste")
			(net "FAN_PWM_OUT_SYS0_BUF")
		)
		(pad "5" smd rect
			(at -1.778 0 180)
			(size 1.016 0.381)
			(layers "B.Cu" "B.Mask" "B.Paste")
			(net "P3V3_STBY")
		)
	)
	(footprint ""
		(layer "B.Cu")
		(at 413.270446 -39.735252 -90)
		(property "Reference" "FB2T4"
			(at 0 0 90)
			(layer "B.SilkS")
			(hide yes)
			(effects
				(font
					(size 1.27 1.27)
				)
				(justify mirror)
			)
		)
		(property "Value" "*"
			(at -0.0254 -2.8829 270)
			(unlocked yes)
			(layer "B.Fab")
			(hide yes)
			(effects
				(font
					(size 1.27 1.016)
					(thickness 0.1524)
				)
				(justify mirror)
			)
		)
		(property "Device Type" "HCB1608KF-800T30-GP_DISCRET-G9A"
			(at -0.0254 -4.4069 270)
			(unlocked yes)
			(layer "B.Fab")
			(hide yes)
			(effects
				(font
					(size 1.27 1.016)
					(thickness 0.1524)
				)
				(justify mirror)
			)
		)
		(duplicate_pad_numbers_are_jumpers no)
		(fp_line
			(start -0.254 0)
			(end 0.254 0)
			(stroke
				(width 0.2032)
				(type default)
			)
			(layer "B.SilkS")
		)
		(fp_rect
			(start 0.5842 1.3335)
			(end -0.5842 -1.3335)
			(stroke
				(width 0)
				(type default)
			)
			(fill no)
			(layer "B.CrtYd")
		)
		(fp_rect
			(start 0.5842 1.3335)
			(end -0.5842 -1.3335)
			(stroke
				(width 0)
				(type default)
			)
			(fill no)
			(layer "B.Fab")
		)
		(pad "1" smd custom
			(at 0 -0.762 90)
			(size 0.2159 0.2159)
			(layers "B.Cu" "B.Mask" "B.Paste")
			(net "P3V3_STBY")
			(options
				(clearance outline)
				(anchor circle)
			)
			(primitives
				(gr_poly
					(pts
						(arc
							(start -0.3302 0.4318)
							(mid -0.402042 0.402042)
							(end -0.4318 0.3302)
						)
						(arc
							(start -0.4318 -0.3302)
							(mid -0.402042 -0.402042)
							(end -0.3302 -0.4318)
						)
						(arc
							(start 0.3302 -0.4318)
							(mid 0.402042 -0.402042)
							(end 0.4318 -0.3302)
						)
						(arc
							(start 0.4318 0.3302)
							(mid 0.402042 0.402042)
							(end 0.3302 0.4318)
						)
					)
					(width 0)
					(fill yes)
				)
			)
		)
		(pad "2" smd custom
			(at 0 0.762 90)
			(size 0.2159 0.2159)
			(layers "B.Cu" "B.Mask" "B.Paste")
			(net "VCC_D_3V3")
			(options
				(clearance outline)
				(anchor circle)
			)
			(primitives
				(gr_poly
					(pts
						(arc
							(start -0.3302 0.4318)
							(mid -0.402042 0.402042)
							(end -0.4318 0.3302)
						)
						(arc
							(start -0.4318 -0.3302)
							(mid -0.402042 -0.402042)
							(end -0.3302 -0.4318)
						)
						(arc
							(start 0.3302 -0.4318)
							(mid 0.402042 -0.402042)
							(end 0.4318 -0.3302)
						)
						(arc
							(start 0.4318 0.3302)
							(mid 0.402042 0.402042)
							(end 0.3302 0.4318)
						)
					)
					(width 0)
					(fill yes)
				)
			)
		)
	)
	(footprint ""
		(layer "B.Cu")
		(at 356.08768 -96.062292 90)
		(property "Reference" "C7C8"
			(at 0 0 90)
			(layer "B.SilkS")
			(hide yes)
			(effects
				(font
					(size 1.27 1.27)
				)
				(justify mirror)
			)
		)
		(property "Value" "*"
			(at 0.0762 -6.2357 90)
			(unlocked yes)
			(layer "B.Fab")
			(hide yes)
			(effects
				(font
					(size 1.27 1.016)
					(thickness 0.1524)
				)
				(justify mirror)
			)
		)
		(property "Device Type" "SC22U16V5MX-4-GP_SMD-BCG5-SC22A"
			(at 0.0762 -8.2677 90)
			(unlocked yes)
			(layer "B.Fab")
			(hide yes)
			(effects
				(font
					(size 1.27 1.016)
					(thickness 0.1524)
				)
				(justify mirror)
			)
		)
		(duplicate_pad_numbers_are_jumpers no)
		(fp_line
			(start -0.635 0)
			(end 0.635 0)
			(stroke
				(width 0.508)
				(type default)
			)
			(layer "B.SilkS")
		)
		(fp_rect
			(start 0.9652 1.778)
			(end -0.9652 -1.778)
			(stroke
				(width 0)
				(type default)
			)
			(fill no)
			(layer "B.CrtYd")
		)
		(fp_poly
			(pts
				(xy 0.9652 -1.778) (xy -0.9652 -1.778) (xy -0.9652 1.778) (xy 0.9652 1.778)
			)
			(stroke
				(width 0)
				(type default)
			)
			(fill no)
			(layer "B.Fab")
		)
		(pad "1" smd rect
			(at 0 -0.9652 270)
			(size 1.397 1.143)
			(layers "B.Cu" "B.Mask" "B.Paste")
			(net "VR_FET_SW_P12V_STBY_PVCCIO_CPU0")
		)
		(pad "2" smd rect
			(at 0 0.9652 270)
			(size 1.397 1.143)
			(layers "B.Cu" "B.Mask" "B.Paste")
			(net "GND")
		)
	)
	(footprint ""
		(layer "B.Cu")
		(at 468.58809 -6.011672)
		(property "Reference" "R7E21"
			(at 0 0 0)
			(layer "B.SilkS")
			(hide yes)
			(effects
				(font
					(size 1.27 1.27)
				)
				(justify mirror)
			)
		)
		(property "Value" ""
			(at 0 0 0)
			(layer "B.Fab")
			(effects
				(font
					(size 1.27 1.27)
				)
				(justify mirror)
			)
		)
		(duplicate_pad_numbers_are_jumpers no)
		(fp_poly
			(pts
				(xy 0.2794 -0.1016) (xy -0.2794 -0.1016) (xy -0.2794 0.9906) (xy 0.2794 0.9906)
			)
			(stroke
				(width 0)
				(type default)
			)
			(fill no)
			(layer "B.CrtYd")
		)
		(fp_line
			(start -0.2794 -0.1016)
			(end 0.2794 -0.1016)
			(stroke
				(width 0.1)
				(type default)
			)
			(layer "B.Fab")
		)
		(fp_line
			(start -0.2794 0.9906)
			(end -0.2794 -0.1016)
			(stroke
				(width 0.1)
				(type default)
			)
			(layer "B.Fab")
		)
		(fp_line
			(start 0.2794 -0.1016)
			(end 0.2794 0.9906)
			(stroke
				(width 0.1)
				(type default)
			)
			(layer "B.Fab")
		)
		(fp_line
			(start 0.2794 0.9906)
			(end -0.2794 0.9906)
			(stroke
				(width 0.1)
				(type default)
			)
			(layer "B.Fab")
		)
		(pad "1" smd rect
			(at 0 0 180)
			(size 0.508 0.508)
			(layers "B.Cu" "B.Mask" "B.Paste")
			(net "P3V3")
		)
		(pad "2" smd rect
			(at 0 0.889 180)
			(size 0.508 0.508)
			(layers "B.Cu" "B.Mask" "B.Paste")
			(net "FM_PWRBRK_N")
		)
		(zone
			(layer "B.Cu")
			(hatch none 0.5)
			(connect_pads
				(clearance 0)
			)
			(min_thickness 0.25)
			(keepout
				(tracks allowed)
				(vias not_allowed)
				(pads allowed)
				(copperpour not_allowed)
				(footprints allowed)
			)
			(placement
				(enabled no)
				(sheetname "")
			)
			(fill
				(thermal_gap 0.5)
				(thermal_bridge_width 0.5)
				(island_removal_mode 0)
			)
			(polygon
				(pts
					(xy 468.84209 -5.757672) (xy 468.33409 -5.757672) (xy 468.33409 -5.376672) (xy 468.84209 -5.376672)
				)
			)
		)
		(zone
			(layer "B.Cu")
			(hatch none 0.5)
			(connect_pads
				(clearance 0)
			)
			(min_thickness 0.25)
			(keepout
				(tracks not_allowed)
				(vias allowed)
				(pads allowed)
				(copperpour not_allowed)
				(footprints allowed)
			)
			(placement
				(enabled no)
				(sheetname "")
			)
			(fill
				(thermal_gap 0.5)
				(thermal_bridge_width 0.5)
				(island_removal_mode 0)
			)
			(polygon
				(pts
					(xy 468.84209 -5.376672) (xy 468.33409 -5.376672) (xy 468.33409 -5.757672) (xy 468.84209 -5.757672)
				)
			)
		)
	)
	(footprint ""
		(layer "B.Cu")
		(at 375.991374 -83.86953 -90)
		(property "Reference" "Q7D1"
			(at 0.229362 -1.2065 270)
			(unlocked yes)
			(layer "B.SilkS")
			(effects
				(font
					(size 0.4064 0.254)
					(thickness 0.1524)
				)
				(justify left mirror)
			)
		)
		(property "Value" ""
			(at 0 0 90)
			(layer "B.Fab")
			(effects
				(font
					(size 1.27 1.27)
				)
				(justify mirror)
			)
		)
		(duplicate_pad_numbers_are_jumpers no)
		(fp_line
			(start -1.778 2.4765)
			(end -1.778 1.5875)
			(stroke
				(width 0.1524)
				(type default)
			)
			(layer "B.SilkS")
		)
		(fp_line
			(start -0.9525 2.4765)
			(end -1.778 2.4765)
			(stroke
				(width 0.1524)
				(type default)
			)
			(layer "B.SilkS")
		)
		(fp_line
			(start -0.381 0.635)
			(end -0.381 1.27)
			(stroke
				(width 0.1524)
				(type default)
			)
			(layer "B.SilkS")
		)
		(fp_line
			(start -1.778 -0.5715)
			(end -1.778 0.3175)
			(stroke
				(width 0.1524)
				(type default)
			)
			(layer "B.SilkS")
		)
		(fp_line
			(start -0.9525 -0.5715)
			(end -1.778 -0.5715)
			(stroke
				(width 0.1524)
				(type default)
			)
			(layer "B.SilkS")
		)
		(fp_circle
			(center 0.9525 -0.9271)
			(end 0.9525 -1.0541)
			(stroke
				(width 0.254)
				(type default)
			)
			(fill no)
			(layer "B.SilkS")
		)
		(fp_poly
			(pts
				(xy -1.778 2.4765) (xy -0.381 2.4765) (xy -0.381 -0.5715) (xy -1.778 -0.5715)
			)
			(stroke
				(width 0)
				(type default)
			)
			(fill no)
			(layer "B.CrtYd")
		)
		(fp_line
			(start -1.778 2.4765)
			(end -1.778 -0.5715)
			(stroke
				(width 0.1)
				(type default)
			)
			(layer "B.Fab")
		)
		(fp_line
			(start -0.381 2.4765)
			(end -1.778 2.4765)
			(stroke
				(width 0.1)
				(type default)
			)
			(layer "B.Fab")
		)
		(fp_line
			(start -1.778 -0.5715)
			(end -0.381 -0.5715)
			(stroke
				(width 0.1)
				(type default)
			)
			(layer "B.Fab")
		)
		(fp_line
			(start -0.381 -0.5715)
			(end -0.381 2.4765)
			(stroke
				(width 0.1)
				(type default)
			)
			(layer "B.Fab")
		)
		(fp_circle
			(center 0.9525 -0.9271)
			(end 0.9525 -1.0541)
			(stroke
				(width 0.254)
				(type default)
			)
			(fill no)
			(layer "B.Fab")
		)
		(pad "1" smd rect
			(at 0 0 90)
			(size 1.143 0.508)
			(layers "B.Cu" "B.Mask" "B.Paste")
			(net "FM_THERMTRIP_DLY_R")
		)
		(pad "2" smd rect
			(at 0 1.905 90)
			(size 1.143 0.508)
			(layers "B.Cu" "B.Mask" "B.Paste")
			(net "GND")
		)
		(pad "3" smd rect
			(at -2.159 0.9525 90)
			(size 1.143 0.508)
			(layers "B.Cu" "B.Mask" "B.Paste")
			(net "FM_PCH_LVC1_THERMTRIP_N")
		)
	)
	(footprint ""
		(layer "B.Cu")
		(at 358.44988 -77.923136)
		(property "Reference" "C3P41"
			(at 0 0 0)
			(layer "B.SilkS")
			(hide yes)
			(effects
				(font
					(size 1.27 1.27)
				)
				(justify mirror)
			)
		)
		(property "Value" ""
			(at 0 0 0)
			(layer "B.Fab")
			(effects
				(font
					(size 1.27 1.27)
				)
				(justify mirror)
			)
		)
		(duplicate_pad_numbers_are_jumpers no)
		(fp_poly
			(pts
				(xy -0.3048 -0.1016) (xy -0.3048 0.9906) (xy 0.3048 0.9906) (xy 0.3048 -0.1016)
			)
			(stroke
				(width 0)
				(type default)
			)
			(fill no)
			(layer "B.CrtYd")
		)
		(fp_line
			(start -0.3048 -0.1016)
			(end 0.3048 -0.1016)
			(stroke
				(width 0.1)
				(type default)
			)
			(layer "B.Fab")
		)
		(fp_line
			(start -0.3048 0.9906)
			(end -0.3048 -0.1016)
			(stroke
				(width 0.1)
				(type default)
			)
			(layer "B.Fab")
		)
		(fp_line
			(start 0.3048 -0.1016)
			(end 0.3048 0.9906)
			(stroke
				(width 0.1)
				(type default)
			)
			(layer "B.Fab")
		)
		(fp_line
			(start 0.3048 0.9906)
			(end -0.3048 0.9906)
			(stroke
				(width 0.1)
				(type default)
			)
			(layer "B.Fab")
		)
		(pad "1" smd rect
			(at 0 0 180)
			(size 0.508 0.508)
			(layers "B.Cu" "B.Mask" "B.Paste")
			(net "P3E_CPU0_PE1_SS_TXN<7>")
		)
		(pad "2" smd rect
			(at 0 0.889 180)
			(size 0.508 0.508)
			(layers "B.Cu" "B.Mask" "B.Paste")
			(net "P3E_CPU0_PE1_SS_C_TXN<7>")
		)
		(zone
			(layer "B.Cu")
			(hatch none 0.5)
			(connect_pads
				(clearance 0)
			)
			(min_thickness 0.25)
			(keepout
				(tracks allowed)
				(vias not_allowed)
				(pads allowed)
				(copperpour not_allowed)
				(footprints allowed)
			)
			(placement
				(enabled no)
				(sheetname "")
			)
			(fill
				(thermal_gap 0.5)
				(thermal_bridge_width 0.5)
				(island_removal_mode 0)
			)
			(polygon
				(pts
					(xy 358.70388 -77.669136) (xy 358.19588 -77.669136) (xy 358.19588 -77.288136) (xy 358.70388 -77.288136)
				)
			)
		)
		(zone
			(layer "B.Cu")
			(hatch none 0.5)
			(connect_pads
				(clearance 0)
			)
			(min_thickness 0.25)
			(keepout
				(tracks not_allowed)
				(vias allowed)
				(pads allowed)
				(copperpour not_allowed)
				(footprints allowed)
			)
			(placement
				(enabled no)
				(sheetname "")
			)
			(fill
				(thermal_gap 0.5)
				(thermal_bridge_width 0.5)
				(island_removal_mode 0)
			)
			(polygon
				(pts
					(xy 358.70388 -77.288136) (xy 358.19588 -77.288136) (xy 358.19588 -77.669136) (xy 358.70388 -77.669136)
				)
			)
		)
	)
	(footprint ""
		(layer "B.Cu")
		(at 17.907 -46.482 -90)
		(property "Reference" "R9R6"
			(at 0 0 90)
			(layer "B.SilkS")
			(hide yes)
			(effects
				(font
					(size 1.27 1.27)
				)
				(justify mirror)
			)
		)
		(property "Value" ""
			(at 0 0 90)
			(layer "B.Fab")
			(effects
				(font
					(size 1.27 1.27)
				)
				(justify mirror)
			)
		)
		(duplicate_pad_numbers_are_jumpers no)
		(fp_poly
			(pts
				(xy 0.2794 -0.1016) (xy -0.2794 -0.1016) (xy -0.2794 0.9906) (xy 0.2794 0.9906)
			)
			(stroke
				(width 0)
				(type default)
			)
			(fill no)
			(layer "B.CrtYd")
		)
		(fp_line
			(start -0.2794 0.9906)
			(end -0.2794 -0.1016)
			(stroke
				(width 0.1)
				(type default)
			)
			(layer "B.Fab")
		)
		(fp_line
			(start 0.2794 0.9906)
			(end -0.2794 0.9906)
			(stroke
				(width 0.1)
				(type default)
			)
			(layer "B.Fab")
		)
		(fp_line
			(start -0.2794 -0.1016)
			(end 0.2794 -0.1016)
			(stroke
				(width 0.1)
				(type default)
			)
			(layer "B.Fab")
		)
		(fp_line
			(start 0.2794 -0.1016)
			(end 0.2794 0.9906)
			(stroke
				(width 0.1)
				(type default)
			)
			(layer "B.Fab")
		)
		(pad "1" smd rect
			(at 0 0 90)
			(size 0.508 0.508)
			(layers "B.Cu" "B.Mask" "B.Paste")
			(net "ISENSE_TMP421_2_BC")
		)
		(pad "2" smd rect
			(at 0 0.889 90)
			(size 0.508 0.508)
			(layers "B.Cu" "B.Mask" "B.Paste")
			(net "ISENSE_TMP421_2_DXN")
		)
		(zone
			(layer "B.Cu")
			(hatch none 0.5)
			(connect_pads
				(clearance 0)
			)
			(min_thickness 0.25)
			(keepout
				(tracks not_allowed)
				(vias allowed)
				(pads allowed)
				(copperpour not_allowed)
				(footprints allowed)
			)
			(placement
				(enabled no)
				(sheetname "")
			)
			(fill
				(thermal_gap 0.5)
				(thermal_bridge_width 0.5)
				(island_removal_mode 0)
			)
			(polygon
				(pts
					(xy 17.272 -46.228) (xy 17.272 -46.736) (xy 17.653 -46.736) (xy 17.653 -46.228)
				)
			)
		)
		(zone
			(layer "B.Cu")
			(hatch none 0.5)
			(connect_pads
				(clearance 0)
			)
			(min_thickness 0.25)
			(keepout
				(tracks allowed)
				(vias not_allowed)
				(pads allowed)
				(copperpour not_allowed)
				(footprints allowed)
			)
			(placement
				(enabled no)
				(sheetname "")
			)
			(fill
				(thermal_gap 0.5)
				(thermal_bridge_width 0.5)
				(island_removal_mode 0)
			)
			(polygon
				(pts
					(xy 17.653 -46.228) (xy 17.653 -46.736) (xy 17.272 -46.736) (xy 17.272 -46.228)
				)
			)
		)
	)
	(footprint ""
		(layer "B.Cu")
		(at 476.1865 -117.6655 90)
		(property "Reference" "Q1W1"
			(at 0.229362 -1.2065 90)
			(unlocked yes)
			(layer "B.SilkS")
			(effects
				(font
					(size 0.4064 0.254)
					(thickness 0.1524)
				)
				(justify left mirror)
			)
		)
		(property "Value" ""
			(at 0 0 90)
			(layer "B.Fab")
			(effects
				(font
					(size 1.27 1.27)
				)
				(justify mirror)
			)
		)
		(duplicate_pad_numbers_are_jumpers no)
		(fp_line
			(start -0.9525 -0.5715)
			(end -1.778 -0.5715)
			(stroke
				(width 0.1524)
				(type default)
			)
			(layer "B.SilkS")
		)
		(fp_line
			(start -1.778 -0.5715)
			(end -1.778 0.3175)
			(stroke
				(width 0.1524)
				(type default)
			)
			(layer "B.SilkS")
		)
		(fp_line
			(start -0.381 0.635)
			(end -0.381 1.27)
			(stroke
				(width 0.1524)
				(type default)
			)
			(layer "B.SilkS")
		)
		(fp_line
			(start -0.9525 2.4765)
			(end -1.778 2.4765)
			(stroke
				(width 0.1524)
				(type default)
			)
			(layer "B.SilkS")
		)
		(fp_line
			(start -1.778 2.4765)
			(end -1.778 1.5875)
			(stroke
				(width 0.1524)
				(type default)
			)
			(layer "B.SilkS")
		)
		(fp_circle
			(center 0.9525 -0.9271)
			(end 0.9525 -0.8001)
			(stroke
				(width 0.254)
				(type default)
			)
			(fill no)
			(layer "B.SilkS")
		)
		(fp_poly
			(pts
				(xy -1.778 2.4765) (xy -0.381 2.4765) (xy -0.381 -0.5715) (xy -1.778 -0.5715)
			)
			(stroke
				(width 0)
				(type default)
			)
			(fill no)
			(layer "B.CrtYd")
		)
		(fp_line
			(start -0.381 -0.5715)
			(end -0.381 2.4765)
			(stroke
				(width 0.1)
				(type default)
			)
			(layer "B.Fab")
		)
		(fp_line
			(start -1.778 -0.5715)
			(end -0.381 -0.5715)
			(stroke
				(width 0.1)
				(type default)
			)
			(layer "B.Fab")
		)
		(fp_line
			(start -0.381 2.4765)
			(end -1.778 2.4765)
			(stroke
				(width 0.1)
				(type default)
			)
			(layer "B.Fab")
		)
		(fp_line
			(start -1.778 2.4765)
			(end -1.778 -0.5715)
			(stroke
				(width 0.1)
				(type default)
			)
			(layer "B.Fab")
		)
		(fp_circle
			(center 0.9525 -0.9271)
			(end 0.9525 -0.8001)
			(stroke
				(width 0.254)
				(type default)
			)
			(fill no)
			(layer "B.Fab")
		)
		(pad "1" smd rect
			(at 0 0 270)
			(size 1.143 0.508)
			(layers "B.Cu" "B.Mask" "B.Paste")
			(net "FM_OCP_MEZZA_PRES_N")
		)
		(pad "2" smd rect
			(at 0 1.905 270)
			(size 1.143 0.508)
			(layers "B.Cu" "B.Mask" "B.Paste")
			(net "GND")
		)
		(pad "3" smd rect
			(at -2.159 0.9525 270)
			(size 1.143 0.508)
			(layers "B.Cu" "B.Mask" "B.Paste")
			(net "FM_OCP_MEZZA_PRES")
		)
	)
	(footprint ""
		(layer "B.Cu")
		(at 369.8875 -55.16372)
		(property "Reference" "U3P1"
			(at -4.578096 -1.320292 180)
			(unlocked yes)
			(layer "B.SilkS")
			(effects
				(font
					(size 0.7874 0.5842)
					(thickness 0.1524)
				)
				(justify left mirror)
			)
		)
		(property "Value" ""
			(at 0 0 0)
			(layer "B.Fab")
			(effects
				(font
					(size 1.27 1.27)
				)
				(justify mirror)
			)
		)
		(duplicate_pad_numbers_are_jumpers no)
		(fp_line
			(start -4.4323 -0.64008)
			(end -4.4323 4.52628)
			(stroke
				(width 0.1524)
				(type default)
			)
			(layer "B.SilkS")
		)
		(fp_line
			(start -4.4323 4.52628)
			(end -1.5367 4.52628)
			(stroke
				(width 0.1524)
				(type default)
			)
			(layer "B.SilkS")
		)
		(fp_line
			(start -3.302 0.49022)
			(end -3.302 -0.64008)
			(stroke
				(width 0.1524)
				(type default)
			)
			(layer "B.SilkS")
		)
		(fp_line
			(start -2.667 -0.64008)
			(end -2.667 0.49022)
			(stroke
				(width 0.1524)
				(type default)
			)
			(layer "B.SilkS")
		)
		(fp_line
			(start -2.667 0.49022)
			(end -3.302 0.49022)
			(stroke
				(width 0.1524)
				(type default)
			)
			(layer "B.SilkS")
		)
		(fp_line
			(start -1.5367 -0.64008)
			(end -4.4323 -0.64008)
			(stroke
				(width 0.1524)
				(type default)
			)
			(layer "B.SilkS")
		)
		(fp_line
			(start -1.5367 4.52628)
			(end -1.5367 -0.64008)
			(stroke
				(width 0.1524)
				(type default)
			)
			(layer "B.SilkS")
		)
		(fp_circle
			(center 1.104138 -0.684784)
			(end 1.231138 -0.684784)
			(stroke
				(width 0.254)
				(type default)
			)
			(fill no)
			(layer "B.SilkS")
		)
		(fp_poly
			(pts
				(xy -0.7366 4.54152) (xy -0.7366 -0.64008) (xy -4.7244 -0.64008) (xy -5.2324 -0.64008) (xy -5.2324 4.54152)
				(xy -4.7244 4.54152)
			)
			(stroke
				(width 0)
				(type default)
			)
			(fill no)
			(layer "B.CrtYd")
		)
		(fp_line
			(start -5.2324 -0.64008)
			(end -5.2324 4.54152)
			(stroke
				(width 0.1)
				(type default)
			)
			(layer "B.Fab")
		)
		(fp_line
			(start -5.2324 4.54152)
			(end -0.7366 4.54152)
			(stroke
				(width 0.1)
				(type default)
			)
			(layer "B.Fab")
		)
		(fp_line
			(start -3.302 0.49022)
			(end -3.302 -0.64008)
			(stroke
				(width 0.1)
				(type default)
			)
			(layer "B.Fab")
		)
		(fp_line
			(start -2.667 -0.64008)
			(end -2.667 0.49022)
			(stroke
				(width 0.1)
				(type default)
			)
			(layer "B.Fab")
		)
		(fp_line
			(start -2.667 0.49022)
			(end -3.302 0.49022)
			(stroke
				(width 0.1)
				(type default)
			)
			(layer "B.Fab")
		)
		(fp_line
			(start -0.7366 -0.64008)
			(end -5.2324 -0.64008)
			(stroke
				(width 0.1)
				(type default)
			)
			(layer "B.Fab")
		)
		(fp_line
			(start -0.7366 4.54152)
			(end -0.7366 -0.64008)
			(stroke
				(width 0.1)
				(type default)
			)
			(layer "B.Fab")
		)
		(fp_circle
			(center 1.612138 -0.684784)
			(end 1.739138 -0.684784)
			(stroke
				(width 0.254)
				(type default)
			)
			(fill no)
			(layer "B.Fab")
		)
		(pad "1" smd rect
			(at 0 0 180)
			(size 2.159 0.381)
			(layers "B.Cu" "B.Mask" "B.Paste")
			(net "PU_GTL2014_1_DIR")
		)
		(pad "2" smd rect
			(at 0 0.65024 180)
			(size 2.159 0.381)
			(layers "B.Cu" "B.Mask" "B.Paste")
			(net "PWRGD_CPU0_DRAMPWROK_DEF_G")
		)
		(pad "3" smd rect
			(at 0 1.30048 180)
			(size 2.159 0.381)
			(layers "B.Cu" "B.Mask" "B.Paste")
			(net "PWRGD_CPU0_DRAMPWROK_ABC_G")
		)
		(pad "4" smd rect
			(at 0 1.95072 180)
			(size 2.159 0.381)
			(layers "B.Cu" "B.Mask" "B.Paste")
			(net "PD_GTL2014_1_VREF")
		)
		(pad "5" smd rect
			(at 0 2.60096 180)
			(size 2.159 0.381)
			(layers "B.Cu" "B.Mask" "B.Paste")
			(net "RST_CPU0_G_N")
		)
		(pad "6" smd rect
			(at 0 3.2512 180)
			(size 2.159 0.381)
			(layers "B.Cu" "B.Mask" "B.Paste")
			(net "PWRGD_CPU0_G")
		)
		(pad "7" smd rect
			(at 0 3.90144 180)
			(size 2.159 0.381)
			(layers "B.Cu" "B.Mask" "B.Paste")
			(net "GND")
		)
		(pad "8" smd rect
			(at -5.969 3.90144 180)
			(size 2.159 0.381)
			(layers "B.Cu" "B.Mask" "B.Paste")
			(net "GND")
		)
		(pad "9" smd rect
			(at -5.969 3.2512 180)
			(size 2.159 0.381)
			(layers "B.Cu" "B.Mask" "B.Paste")
			(net "PWRGD_CPU0_LVC3")
		)
		(pad "10" smd rect
			(at -5.969 2.60096 180)
			(size 2.159 0.381)
			(layers "B.Cu" "B.Mask" "B.Paste")
			(net "RST_CPU0_LVC3_N")
		)
		(pad "11" smd rect
			(at -5.969 1.95072 180)
			(size 2.159 0.381)
			(layers "B.Cu" "B.Mask" "B.Paste")
			(net "GND")
		)
		(pad "12" smd rect
			(at -5.969 1.30048 180)
			(size 2.159 0.381)
			(layers "B.Cu" "B.Mask" "B.Paste")
			(net "PWRGD_DRAMPWRGD")
		)
		(pad "13" smd rect
			(at -5.969 0.65024 180)
			(size 2.159 0.381)
			(layers "B.Cu" "B.Mask" "B.Paste")
			(net "PWRGD_DRAMPWRGD")
		)
		(pad "14" smd rect
			(at -5.969 0 180)
			(size 2.159 0.381)
			(layers "B.Cu" "B.Mask" "B.Paste")
			(net "P3V3_STBY")
		)
	)
	(footprint ""
		(layer "B.Cu")
		(at 274.881086 -85.06714)
		(property "Reference" "C5P3"
			(at 0 0 0)
			(layer "B.SilkS")
			(hide yes)
			(effects
				(font
					(size 1.27 1.27)
				)
				(justify mirror)
			)
		)
		(property "Value" ""
			(at 0 0 0)
			(layer "B.Fab")
			(effects
				(font
					(size 1.27 1.27)
				)
				(justify mirror)
			)
		)
		(duplicate_pad_numbers_are_jumpers no)
		(fp_poly
			(pts
				(xy 0.7239 -0.2159) (xy -0.7239 -0.2159) (xy -0.7239 1.9939) (xy 0.7239 1.9939)
			)
			(stroke
				(width 0)
				(type default)
			)
			(fill no)
			(layer "B.CrtYd")
		)
		(fp_line
			(start -0.7239 -0.2159)
			(end 0.7239 -0.2159)
			(stroke
				(width 0.1)
				(type default)
			)
			(layer "B.Fab")
		)
		(fp_line
			(start -0.7239 1.9939)
			(end -0.7239 -0.2159)
			(stroke
				(width 0.1)
				(type default)
			)
			(layer "B.Fab")
		)
		(fp_line
			(start 0.7239 -0.2159)
			(end 0.7239 1.9939)
			(stroke
				(width 0.1)
				(type default)
			)
			(layer "B.Fab")
		)
		(fp_line
			(start 0.7239 1.9939)
			(end -0.7239 1.9939)
			(stroke
				(width 0.1)
				(type default)
			)
			(layer "B.Fab")
		)
		(pad "1" smd rect
			(at 0 0 180)
			(size 1.27 1.016)
			(layers "B.Cu" "B.Mask" "B.Paste")
			(net "PVDDQ_DEF")
		)
		(pad "2" smd rect
			(at 0 1.778 180)
			(size 1.27 1.016)
			(layers "B.Cu" "B.Mask" "B.Paste")
			(net "GND")
		)
		(zone
			(layer "B.Cu")
			(hatch none 0.5)
			(connect_pads
				(clearance 0)
			)
			(min_thickness 0.25)
			(keepout
				(tracks not_allowed)
				(vias allowed)
				(pads allowed)
				(copperpour not_allowed)
				(footprints allowed)
			)
			(placement
				(enabled no)
				(sheetname "")
			)
			(fill
				(thermal_gap 0.5)
				(thermal_bridge_width 0.5)
				(island_removal_mode 0)
			)
			(polygon
				(pts
					(xy 275.516086 -84.55914) (xy 274.246086 -84.55914) (xy 274.246086 -83.79714) (xy 275.516086 -83.79714)
				)
			)
		)
	)
	(footprint ""
		(layer "B.Cu")
		(at 494.4872 -137.7696 180)
		(property "Reference" "R1L30"
			(at 0 0 0)
			(layer "B.SilkS")
			(hide yes)
			(effects
				(font
					(size 1.27 1.27)
				)
				(justify mirror)
			)
		)
		(property "Value" ""
			(at 0 0 0)
			(layer "B.Fab")
			(effects
				(font
					(size 1.27 1.27)
				)
				(justify mirror)
			)
		)
		(duplicate_pad_numbers_are_jumpers no)
		(fp_poly
			(pts
				(xy 0.2794 -0.1016) (xy -0.2794 -0.1016) (xy -0.2794 0.9906) (xy 0.2794 0.9906)
			)
			(stroke
				(width 0)
				(type default)
			)
			(fill no)
			(layer "B.CrtYd")
		)
		(fp_line
			(start 0.2794 0.9906)
			(end -0.2794 0.9906)
			(stroke
				(width 0.1)
				(type default)
			)
			(layer "B.Fab")
		)
		(fp_line
			(start 0.2794 -0.1016)
			(end 0.2794 0.9906)
			(stroke
				(width 0.1)
				(type default)
			)
			(layer "B.Fab")
		)
		(fp_line
			(start -0.2794 0.9906)
			(end -0.2794 -0.1016)
			(stroke
				(width 0.1)
				(type default)
			)
			(layer "B.Fab")
		)
		(fp_line
			(start -0.2794 -0.1016)
			(end 0.2794 -0.1016)
			(stroke
				(width 0.1)
				(type default)
			)
			(layer "B.Fab")
		)
		(pad "1" smd rect
			(at 0 0)
			(size 0.508 0.508)
			(layers "B.Cu" "B.Mask" "B.Paste")
			(net "LED_POSTCODE_1")
		)
		(pad "2" smd rect
			(at 0 0.889)
			(size 0.508 0.508)
			(layers "B.Cu" "B.Mask" "B.Paste")
			(net "LED_POSTCODE_1_R")
		)
		(zone
			(layer "B.Cu")
			(hatch none 0.5)
			(connect_pads
				(clearance 0)
			)
			(min_thickness 0.25)
			(keepout
				(tracks not_allowed)
				(vias allowed)
				(pads allowed)
				(copperpour not_allowed)
				(footprints allowed)
			)
			(placement
				(enabled no)
				(sheetname "")
			)
			(fill
				(thermal_gap 0.5)
				(thermal_bridge_width 0.5)
				(island_removal_mode 0)
			)
			(polygon
				(pts
					(xy 494.2332 -138.4046) (xy 494.7412 -138.4046) (xy 494.7412 -138.0236) (xy 494.2332 -138.0236)
				)
			)
		)
		(zone
			(layer "B.Cu")
			(hatch none 0.5)
			(connect_pads
				(clearance 0)
			)
			(min_thickness 0.25)
			(keepout
				(tracks allowed)
				(vias not_allowed)
				(pads allowed)
				(copperpour not_allowed)
				(footprints allowed)
			)
			(placement
				(enabled no)
				(sheetname "")
			)
			(fill
				(thermal_gap 0.5)
				(thermal_bridge_width 0.5)
				(island_removal_mode 0)
			)
			(polygon
				(pts
					(xy 494.2332 -138.0236) (xy 494.7412 -138.0236) (xy 494.7412 -138.4046) (xy 494.2332 -138.4046)
				)
			)
		)
	)
	(footprint ""
		(layer "B.Cu")
		(at 13.97 -40.513 -90)
		(property "Reference" "R9T1"
			(at 0 0 90)
			(layer "B.SilkS")
			(hide yes)
			(effects
				(font
					(size 1.27 1.27)
				)
				(justify mirror)
			)
		)
		(property "Value" ""
			(at 0 0 90)
			(layer "B.Fab")
			(effects
				(font
					(size 1.27 1.27)
				)
				(justify mirror)
			)
		)
		(duplicate_pad_numbers_are_jumpers no)
		(fp_poly
			(pts
				(xy 0.2794 -0.1016) (xy -0.2794 -0.1016) (xy -0.2794 0.9906) (xy 0.2794 0.9906)
			)
			(stroke
				(width 0)
				(type default)
			)
			(fill no)
			(layer "B.CrtYd")
		)
		(fp_line
			(start -0.2794 0.9906)
			(end -0.2794 -0.1016)
			(stroke
				(width 0.1)
				(type default)
			)
			(layer "B.Fab")
		)
		(fp_line
			(start 0.2794 0.9906)
			(end -0.2794 0.9906)
			(stroke
				(width 0.1)
				(type default)
			)
			(layer "B.Fab")
		)
		(fp_line
			(start -0.2794 -0.1016)
			(end 0.2794 -0.1016)
			(stroke
				(width 0.1)
				(type default)
			)
			(layer "B.Fab")
		)
		(fp_line
			(start 0.2794 -0.1016)
			(end 0.2794 0.9906)
			(stroke
				(width 0.1)
				(type default)
			)
			(layer "B.Fab")
		)
		(pad "1" smd rect
			(at 0 0 90)
			(size 0.508 0.508)
			(layers "B.Cu" "B.Mask" "B.Paste")
			(net "FAN_PWM_OUT_SYS0_R")
		)
		(pad "2" smd rect
			(at 0 0.889 90)
			(size 0.508 0.508)
			(layers "B.Cu" "B.Mask" "B.Paste")
			(net "FAN_PWM_OUT_SYS0_R1")
		)
		(zone
			(layer "B.Cu")
			(hatch none 0.5)
			(connect_pads
				(clearance 0)
			)
			(min_thickness 0.25)
			(keepout
				(tracks not_allowed)
				(vias allowed)
				(pads allowed)
				(copperpour not_allowed)
				(footprints allowed)
			)
			(placement
				(enabled no)
				(sheetname "")
			)
			(fill
				(thermal_gap 0.5)
				(thermal_bridge_width 0.5)
				(island_removal_mode 0)
			)
			(polygon
				(pts
					(xy 13.335 -40.259) (xy 13.335 -40.767) (xy 13.716 -40.767) (xy 13.716 -40.259)
				)
			)
		)
		(zone
			(layer "B.Cu")
			(hatch none 0.5)
			(connect_pads
				(clearance 0)
			)
			(min_thickness 0.25)
			(keepout
				(tracks allowed)
				(vias not_allowed)
				(pads allowed)
				(copperpour not_allowed)
				(footprints allowed)
			)
			(placement
				(enabled no)
				(sheetname "")
			)
			(fill
				(thermal_gap 0.5)
				(thermal_bridge_width 0.5)
				(island_removal_mode 0)
			)
			(polygon
				(pts
					(xy 13.716 -40.259) (xy 13.716 -40.767) (xy 13.335 -40.767) (xy 13.335 -40.259)
				)
			)
		)
	)
	(footprint ""
		(layer "B.Cu")
		(at 386.93725 -113.45545)
		(property "Reference" "C3M43"
			(at 0 0 0)
			(layer "B.SilkS")
			(hide yes)
			(effects
				(font
					(size 1.27 1.27)
				)
				(justify mirror)
			)
		)
		(property "Value" ""
			(at 0 0 0)
			(layer "B.Fab")
			(effects
				(font
					(size 1.27 1.27)
				)
				(justify mirror)
			)
		)
		(duplicate_pad_numbers_are_jumpers no)
		(fp_rect
			(start 0.2794 0.9144)
			(end -0.2794 -0.1143)
			(stroke
				(width 0)
				(type default)
			)
			(fill no)
			(layer "B.CrtYd")
		)
		(fp_line
			(start -0.2794 -0.1143)
			(end -0.2794 0.9144)
			(stroke
				(width 0.1)
				(type default)
			)
			(layer "B.Fab")
		)
		(fp_line
			(start -0.2794 0.9144)
			(end 0.2794 0.9144)
			(stroke
				(width 0.1)
				(type default)
			)
			(layer "B.Fab")
		)
		(fp_line
			(start 0.2794 -0.1143)
			(end -0.2794 -0.1143)
			(stroke
				(width 0.1)
				(type default)
			)
			(layer "B.Fab")
		)
		(fp_line
			(start 0.2794 0.9144)
			(end 0.2794 -0.1143)
			(stroke
				(width 0.1)
				(type default)
			)
			(layer "B.Fab")
		)
		(pad "1" smd custom
			(at 0 0 270)
			(size 0.10414 0.10414)
			(layers "B.Cu" "B.Mask" "B.Paste")
			(net "P1V05_PCH_STBY")
			(options
				(clearance outline)
				(anchor circle)
			)
			(primitives
				(gr_poly
					(pts
						(xy -0.20828 -0.08636) (xy -0.20828 0.08636) (xy -0.08636 0.20828) (xy 0.086614 0.20828) (xy 0.20828 0.086614)
						(xy 0.20828 -0.08636) (xy 0.08636 -0.20828) (xy -0.08636 -0.20828)
					)
					(width 0)
					(fill yes)
				)
			)
		)
		(pad "2" smd custom
			(at 0 0.8001 270)
			(size 0.10414 0.10414)
			(layers "B.Cu" "B.Mask" "B.Paste")
			(net "GND")
			(options
				(clearance outline)
				(anchor circle)
			)
			(primitives
				(gr_poly
					(pts
						(xy -0.20828 -0.08636) (xy -0.20828 0.08636) (xy -0.08636 0.20828) (xy 0.086614 0.20828) (xy 0.20828 0.086614)
						(xy 0.20828 -0.08636) (xy 0.08636 -0.20828) (xy -0.08636 -0.20828)
					)
					(width 0)
					(fill yes)
				)
			)
		)
		(zone
			(layer "B.Cu")
			(hatch none 0.5)
			(connect_pads
				(clearance 0)
			)
			(min_thickness 0.25)
			(keepout
				(tracks allowed)
				(vias not_allowed)
				(pads allowed)
				(copperpour not_allowed)
				(footprints allowed)
			)
			(placement
				(enabled no)
				(sheetname "")
			)
			(fill
				(thermal_gap 0.5)
				(thermal_bridge_width 0.5)
				(island_removal_mode 0)
			)
			(polygon
				(pts
					(xy 387.02488 -113.2459) (xy 387.02488 -112.8649) (xy 386.84962 -112.8649) (xy 386.849366 -113.2459)
				)
			)
		)
		(zone
			(layer "B.Cu")
			(hatch none 0.5)
			(connect_pads
				(clearance 0)
			)
			(min_thickness 0.25)
			(keepout
				(tracks not_allowed)
				(vias allowed)
				(pads allowed)
				(copperpour not_allowed)
				(footprints allowed)
			)
			(placement
				(enabled no)
				(sheetname "")
			)
			(fill
				(thermal_gap 0.5)
				(thermal_bridge_width 0.5)
				(island_removal_mode 0)
			)
			(polygon
				(pts
					(xy 387.02488 -113.2459) (xy 387.02488 -112.8649) (xy 386.84962 -112.8649) (xy 386.849366 -113.2459)
				)
			)
		)
	)
	(footprint ""
		(layer "B.Cu")
		(at 401.272756 -111.636556)
		(property "Reference" "C2N6"
			(at 0 0 0)
			(layer "B.SilkS")
			(hide yes)
			(effects
				(font
					(size 1.27 1.27)
				)
				(justify mirror)
			)
		)
		(property "Value" ""
			(at 0 0 0)
			(layer "B.Fab")
			(effects
				(font
					(size 1.27 1.27)
				)
				(justify mirror)
			)
		)
		(duplicate_pad_numbers_are_jumpers no)
		(fp_poly
			(pts
				(xy 0.4953 -0.2032) (xy -0.4953 -0.2032) (xy -0.4953 1.6002) (xy 0.4953 1.6002)
			)
			(stroke
				(width 0)
				(type default)
			)
			(fill no)
			(layer "B.CrtYd")
		)
		(fp_line
			(start -0.4953 -0.2032)
			(end -0.4953 1.6002)
			(stroke
				(width 0.1)
				(type default)
			)
			(layer "B.Fab")
		)
		(fp_line
			(start -0.4953 1.6002)
			(end 0.4953 1.6002)
			(stroke
				(width 0.1)
				(type default)
			)
			(layer "B.Fab")
		)
		(fp_line
			(start 0.4953 -0.2032)
			(end -0.4953 -0.2032)
			(stroke
				(width 0.1)
				(type default)
			)
			(layer "B.Fab")
		)
		(fp_line
			(start 0.4953 1.6002)
			(end 0.4953 -0.2032)
			(stroke
				(width 0.1)
				(type default)
			)
			(layer "B.Fab")
		)
		(pad "1" smd rect
			(at 0 0 180)
			(size 0.762 0.889)
			(layers "B.Cu" "B.Mask" "B.Paste")
			(net "P1V05_PCH_STBY_KR_PLL")
		)
		(pad "2" smd rect
			(at 0 1.397 180)
			(size 0.762 0.889)
			(layers "B.Cu" "B.Mask" "B.Paste")
			(net "GND")
		)
		(zone
			(layer "B.Cu")
			(hatch none 0.5)
			(connect_pads
				(clearance 0)
			)
			(min_thickness 0.25)
			(keepout
				(tracks not_allowed)
				(vias allowed)
				(pads allowed)
				(copperpour not_allowed)
				(footprints allowed)
			)
			(placement
				(enabled no)
				(sheetname "")
			)
			(fill
				(thermal_gap 0.5)
				(thermal_bridge_width 0.5)
				(island_removal_mode 0)
			)
			(polygon
				(pts
					(xy 401.653756 -111.192056) (xy 400.891756 -111.192056) (xy 400.891756 -110.684056) (xy 401.653756 -110.684056)
				)
			)
		)
	)
	(footprint ""
		(layer "B.Cu")
		(at 336.042 -94.234 90)
		(property "Reference" "C3N38"
			(at 0.73533 -3.937 0)
			(unlocked yes)
			(layer "B.SilkS")
			(effects
				(font
					(size 0.7874 0.5842)
					(thickness 0.1524)
				)
				(justify mirror)
			)
		)
		(property "Value" ""
			(at 0 0 90)
			(layer "B.Fab")
			(effects
				(font
					(size 1.27 1.27)
				)
				(justify mirror)
			)
		)
		(duplicate_pad_numbers_are_jumpers no)
		(fp_line
			(start 2.563114 -1.616456)
			(end 2.563114 1.633728)
			(stroke
				(width 0.1524)
				(type default)
			)
			(layer "B.SilkS")
		)
		(fp_line
			(start 1.6002 -1.616456)
			(end 2.563114 -1.616456)
			(stroke
				(width 0.1524)
				(type default)
			)
			(layer "B.SilkS")
		)
		(fp_line
			(start -1.6002 -1.616456)
			(end -2.504948 -1.616456)
			(stroke
				(width 0.1524)
				(type default)
			)
			(layer "B.SilkS")
		)
		(fp_line
			(start -2.504948 -1.616456)
			(end -2.504948 1.633728)
			(stroke
				(width 0.1524)
				(type default)
			)
			(layer "B.SilkS")
		)
		(fp_line
			(start 2.563114 1.633728)
			(end 1.6002 1.633728)
			(stroke
				(width 0.1524)
				(type default)
			)
			(layer "B.SilkS")
		)
		(fp_line
			(start -2.504948 1.633728)
			(end -1.6002 1.633728)
			(stroke
				(width 0.1524)
				(type default)
			)
			(layer "B.SilkS")
		)
		(fp_line
			(start 2.286 7.366)
			(end 2.286 1.632712)
			(stroke
				(width 0.1524)
				(type default)
			)
			(layer "B.SilkS")
		)
		(fp_line
			(start 2.286 7.366)
			(end 1.60147 7.366)
			(stroke
				(width 0.1524)
				(type default)
			)
			(layer "B.SilkS")
		)
		(fp_line
			(start -2.286 7.366)
			(end -2.286 1.63195)
			(stroke
				(width 0.1524)
				(type default)
			)
			(layer "B.SilkS")
		)
		(fp_line
			(start -2.286 7.366)
			(end -1.600708 7.366)
			(stroke
				(width 0.1524)
				(type default)
			)
			(layer "B.SilkS")
		)
		(fp_rect
			(start 2.286 7.366)
			(end -2.286 -0.254)
			(stroke
				(width 0)
				(type default)
			)
			(fill no)
			(layer "B.CrtYd")
		)
		(fp_line
			(start 2.286 -0.254)
			(end -2.286 -0.254)
			(stroke
				(width 0.1)
				(type default)
			)
			(layer "B.Fab")
		)
		(fp_line
			(start -2.286 -0.254)
			(end -2.286 7.366)
			(stroke
				(width 0.1)
				(type default)
			)
			(layer "B.Fab")
		)
		(fp_line
			(start 2.286 7.366)
			(end 2.286 -0.254)
			(stroke
				(width 0.1)
				(type default)
			)
			(layer "B.Fab")
		)
		(fp_line
			(start -2.286 7.366)
			(end 2.286 7.366)
			(stroke
				(width 0.1)
				(type default)
			)
			(layer "B.Fab")
		)
		(pad "1" smd rect
			(at 0 0 270)
			(size 2.54 3.048)
			(layers "B.Cu" "B.Mask" "B.Paste")
			(net "PVCCIO_CPU0")
		)
		(pad "2" smd rect
			(at 0 7.112 270)
			(size 2.54 3.048)
			(layers "B.Cu" "B.Mask" "B.Paste")
			(net "GND")
		)
	)
	(footprint ""
		(layer "B.Cu")
		(at 375.9708 -154.457146)
		(property "Reference" "C3L12"
			(at 0 0 0)
			(layer "B.SilkS")
			(hide yes)
			(effects
				(font
					(size 1.27 1.27)
				)
				(justify mirror)
			)
		)
		(property "Value" ""
			(at 0 0 0)
			(layer "B.Fab")
			(effects
				(font
					(size 1.27 1.27)
				)
				(justify mirror)
			)
		)
		(duplicate_pad_numbers_are_jumpers no)
		(fp_poly
			(pts
				(xy 0.7239 -0.2159) (xy -0.7239 -0.2159) (xy -0.7239 1.9939) (xy 0.7239 1.9939)
			)
			(stroke
				(width 0)
				(type default)
			)
			(fill no)
			(layer "B.CrtYd")
		)
		(fp_line
			(start -0.7239 -0.2159)
			(end 0.7239 -0.2159)
			(stroke
				(width 0.1)
				(type default)
			)
			(layer "B.Fab")
		)
		(fp_line
			(start -0.7239 1.9939)
			(end -0.7239 -0.2159)
			(stroke
				(width 0.1)
				(type default)
			)
			(layer "B.Fab")
		)
		(fp_line
			(start 0.7239 -0.2159)
			(end 0.7239 1.9939)
			(stroke
				(width 0.1)
				(type default)
			)
			(layer "B.Fab")
		)
		(fp_line
			(start 0.7239 1.9939)
			(end -0.7239 1.9939)
			(stroke
				(width 0.1)
				(type default)
			)
			(layer "B.Fab")
		)
		(pad "1" smd rect
			(at 0 0 180)
			(size 1.27 1.016)
			(layers "B.Cu" "B.Mask" "B.Paste")
			(net "VR_FET_SW_P12V_STBY_PVDDQ_DEF")
		)
		(pad "2" smd rect
			(at 0 1.778 180)
			(size 1.27 1.016)
			(layers "B.Cu" "B.Mask" "B.Paste")
			(net "GND")
		)
		(zone
			(layer "B.Cu")
			(hatch none 0.5)
			(connect_pads
				(clearance 0)
			)
			(min_thickness 0.25)
			(keepout
				(tracks not_allowed)
				(vias allowed)
				(pads allowed)
				(copperpour not_allowed)
				(footprints allowed)
			)
			(placement
				(enabled no)
				(sheetname "")
			)
			(fill
				(thermal_gap 0.5)
				(thermal_bridge_width 0.5)
				(island_removal_mode 0)
			)
			(polygon
				(pts
					(xy 376.6058 -153.949146) (xy 375.3358 -153.949146) (xy 375.3358 -153.187146) (xy 376.6058 -153.187146)
				)
			)
		)
	)
	(footprint ""
		(layer "B.Cu")
		(at 329.438 -8.382)
		(property "Reference" "R4U3"
			(at 0 0 0)
			(layer "B.SilkS")
			(hide yes)
			(effects
				(font
					(size 1.27 1.27)
				)
				(justify mirror)
			)
		)
		(property "Value" ""
			(at 0 0 0)
			(layer "B.Fab")
			(effects
				(font
					(size 1.27 1.27)
				)
				(justify mirror)
			)
		)
		(duplicate_pad_numbers_are_jumpers no)
		(fp_poly
			(pts
				(xy 0.2794 -0.1016) (xy -0.2794 -0.1016) (xy -0.2794 0.9906) (xy 0.2794 0.9906)
			)
			(stroke
				(width 0)
				(type default)
			)
			(fill no)
			(layer "B.CrtYd")
		)
		(fp_line
			(start -0.2794 -0.1016)
			(end 0.2794 -0.1016)
			(stroke
				(width 0.1)
				(type default)
			)
			(layer "B.Fab")
		)
		(fp_line
			(start -0.2794 0.9906)
			(end -0.2794 -0.1016)
			(stroke
				(width 0.1)
				(type default)
			)
			(layer "B.Fab")
		)
		(fp_line
			(start 0.2794 -0.1016)
			(end 0.2794 0.9906)
			(stroke
				(width 0.1)
				(type default)
			)
			(layer "B.Fab")
		)
		(fp_line
			(start 0.2794 0.9906)
			(end -0.2794 0.9906)
			(stroke
				(width 0.1)
				(type default)
			)
			(layer "B.Fab")
		)
		(pad "1" smd rect
			(at 0 0 180)
			(size 0.508 0.508)
			(layers "B.Cu" "B.Mask" "B.Paste")
			(net "PVPP_ABC")
		)
		(pad "2" smd rect
			(at 0 0.889 180)
			(size 0.508 0.508)
			(layers "B.Cu" "B.Mask" "B.Paste")
			(net "FM_DIMM_EVENT_FET")
		)
		(zone
			(layer "B.Cu")
			(hatch none 0.5)
			(connect_pads
				(clearance 0)
			)
			(min_thickness 0.25)
			(keepout
				(tracks allowed)
				(vias not_allowed)
				(pads allowed)
				(copperpour not_allowed)
				(footprints allowed)
			)
			(placement
				(enabled no)
				(sheetname "")
			)
			(fill
				(thermal_gap 0.5)
				(thermal_bridge_width 0.5)
				(island_removal_mode 0)
			)
			(polygon
				(pts
					(xy 329.692 -8.128) (xy 329.184 -8.128) (xy 329.184 -7.747) (xy 329.692 -7.747)
				)
			)
		)
		(zone
			(layer "B.Cu")
			(hatch none 0.5)
			(connect_pads
				(clearance 0)
			)
			(min_thickness 0.25)
			(keepout
				(tracks not_allowed)
				(vias allowed)
				(pads allowed)
				(copperpour not_allowed)
				(footprints allowed)
			)
			(placement
				(enabled no)
				(sheetname "")
			)
			(fill
				(thermal_gap 0.5)
				(thermal_bridge_width 0.5)
				(island_removal_mode 0)
			)
			(polygon
				(pts
					(xy 329.692 -7.747) (xy 329.184 -7.747) (xy 329.184 -8.128) (xy 329.692 -8.128)
				)
			)
		)
	)
	(footprint ""
		(layer "B.Cu")
		(at 434.6575 -18.288 -90)
		(property "Reference" "R1U34"
			(at 0 0 90)
			(layer "B.SilkS")
			(hide yes)
			(effects
				(font
					(size 1.27 1.27)
				)
				(justify mirror)
			)
		)
		(property "Value" ""
			(at 0 0 90)
			(layer "B.Fab")
			(effects
				(font
					(size 1.27 1.27)
				)
				(justify mirror)
			)
		)
		(duplicate_pad_numbers_are_jumpers no)
		(fp_poly
			(pts
				(xy 0.2794 -0.1016) (xy -0.2794 -0.1016) (xy -0.2794 0.9906) (xy 0.2794 0.9906)
			)
			(stroke
				(width 0)
				(type default)
			)
			(fill no)
			(layer "B.CrtYd")
		)
		(fp_line
			(start -0.2794 0.9906)
			(end -0.2794 -0.1016)
			(stroke
				(width 0.1)
				(type default)
			)
			(layer "B.Fab")
		)
		(fp_line
			(start 0.2794 0.9906)
			(end -0.2794 0.9906)
			(stroke
				(width 0.1)
				(type default)
			)
			(layer "B.Fab")
		)
		(fp_line
			(start -0.2794 -0.1016)
			(end 0.2794 -0.1016)
			(stroke
				(width 0.1)
				(type default)
			)
			(layer "B.Fab")
		)
		(fp_line
			(start 0.2794 -0.1016)
			(end 0.2794 0.9906)
			(stroke
				(width 0.1)
				(type default)
			)
			(layer "B.Fab")
		)
		(pad "1" smd rect
			(at 0 0 90)
			(size 0.508 0.508)
			(layers "B.Cu" "B.Mask" "B.Paste")
			(net "H_CPU1_MEMKLM_MEMHOT_LVT3_K_N")
		)
		(pad "2" smd rect
			(at 0 0.889 90)
			(size 0.508 0.508)
			(layers "B.Cu" "B.Mask" "B.Paste")
			(net "H_CPU1_MEMKLM_MEMHOT_LVT3_N")
		)
		(zone
			(layer "B.Cu")
			(hatch none 0.5)
			(connect_pads
				(clearance 0)
			)
			(min_thickness 0.25)
			(keepout
				(tracks not_allowed)
				(vias allowed)
				(pads allowed)
				(copperpour not_allowed)
				(footprints allowed)
			)
			(placement
				(enabled no)
				(sheetname "")
			)
			(fill
				(thermal_gap 0.5)
				(thermal_bridge_width 0.5)
				(island_removal_mode 0)
			)
			(polygon
				(pts
					(xy 434.0225 -18.034) (xy 434.0225 -18.542) (xy 434.4035 -18.542) (xy 434.4035 -18.034)
				)
			)
		)
		(zone
			(layer "B.Cu")
			(hatch none 0.5)
			(connect_pads
				(clearance 0)
			)
			(min_thickness 0.25)
			(keepout
				(tracks allowed)
				(vias not_allowed)
				(pads allowed)
				(copperpour not_allowed)
				(footprints allowed)
			)
			(placement
				(enabled no)
				(sheetname "")
			)
			(fill
				(thermal_gap 0.5)
				(thermal_bridge_width 0.5)
				(island_removal_mode 0)
			)
			(polygon
				(pts
					(xy 434.4035 -18.034) (xy 434.4035 -18.542) (xy 434.0225 -18.542) (xy 434.0225 -18.034)
				)
			)
		)
	)
	(footprint ""
		(layer "B.Cu")
		(at 340.331806 -60.368434)
		(property "Reference" "R2U19"
			(at 0 0 0)
			(layer "B.SilkS")
			(hide yes)
			(effects
				(font
					(size 1.27 1.27)
				)
				(justify mirror)
			)
		)
		(property "Value" ""
			(at 0 0 0)
			(layer "B.Fab")
			(effects
				(font
					(size 1.27 1.27)
				)
				(justify mirror)
			)
		)
		(duplicate_pad_numbers_are_jumpers no)
		(fp_poly
			(pts
				(xy 0.2794 -0.1016) (xy -0.2794 -0.1016) (xy -0.2794 0.9906) (xy 0.2794 0.9906)
			)
			(stroke
				(width 0)
				(type default)
			)
			(fill no)
			(layer "B.CrtYd")
		)
		(fp_line
			(start -0.2794 -0.1016)
			(end 0.2794 -0.1016)
			(stroke
				(width 0.1)
				(type default)
			)
			(layer "B.Fab")
		)
		(fp_line
			(start -0.2794 0.9906)
			(end -0.2794 -0.1016)
			(stroke
				(width 0.1)
				(type default)
			)
			(layer "B.Fab")
		)
		(fp_line
			(start 0.2794 -0.1016)
			(end 0.2794 0.9906)
			(stroke
				(width 0.1)
				(type default)
			)
			(layer "B.Fab")
		)
		(fp_line
			(start 0.2794 0.9906)
			(end -0.2794 0.9906)
			(stroke
				(width 0.1)
				(type default)
			)
			(layer "B.Fab")
		)
		(pad "1" smd rect
			(at 0 0 180)
			(size 0.508 0.508)
			(layers "B.Cu" "B.Mask" "B.Paste")
			(net "P3E_CPU0_PE1_SS_RXN<2>")
		)
		(pad "2" smd rect
			(at 0 0.889 180)
			(size 0.508 0.508)
			(layers "B.Cu" "B.Mask" "B.Paste")
			(net "P3E_CPU0_PE1_SS_R_RXN<2>")
		)
		(zone
			(layer "B.Cu")
			(hatch none 0.5)
			(connect_pads
				(clearance 0)
			)
			(min_thickness 0.25)
			(keepout
				(tracks allowed)
				(vias not_allowed)
				(pads allowed)
				(copperpour not_allowed)
				(footprints allowed)
			)
			(placement
				(enabled no)
				(sheetname "")
			)
			(fill
				(thermal_gap 0.5)
				(thermal_bridge_width 0.5)
				(island_removal_mode 0)
			)
			(polygon
				(pts
					(xy 340.585806 -60.114434) (xy 340.077806 -60.114434) (xy 340.077806 -59.733434) (xy 340.585806 -59.733434)
				)
			)
		)
		(zone
			(layer "B.Cu")
			(hatch none 0.5)
			(connect_pads
				(clearance 0)
			)
			(min_thickness 0.25)
			(keepout
				(tracks not_allowed)
				(vias allowed)
				(pads allowed)
				(copperpour not_allowed)
				(footprints allowed)
			)
			(placement
				(enabled no)
				(sheetname "")
			)
			(fill
				(thermal_gap 0.5)
				(thermal_bridge_width 0.5)
				(island_removal_mode 0)
			)
			(polygon
				(pts
					(xy 340.585806 -59.733434) (xy 340.077806 -59.733434) (xy 340.077806 -60.114434) (xy 340.585806 -60.114434)
				)
			)
		)
	)
	(footprint ""
		(layer "B.Cu")
		(at 365.506 -79.0956 -90)
		(property "Reference" "R7D37"
			(at 0 0 90)
			(layer "B.SilkS")
			(hide yes)
			(effects
				(font
					(size 1.27 1.27)
				)
				(justify mirror)
			)
		)
		(property "Value" ""
			(at 0 0 90)
			(layer "B.Fab")
			(effects
				(font
					(size 1.27 1.27)
				)
				(justify mirror)
			)
		)
		(duplicate_pad_numbers_are_jumpers no)
		(fp_poly
			(pts
				(xy 0.2794 -0.1016) (xy -0.2794 -0.1016) (xy -0.2794 0.9906) (xy 0.2794 0.9906)
			)
			(stroke
				(width 0)
				(type default)
			)
			(fill no)
			(layer "B.CrtYd")
		)
		(fp_line
			(start -0.2794 0.9906)
			(end -0.2794 -0.1016)
			(stroke
				(width 0.1)
				(type default)
			)
			(layer "B.Fab")
		)
		(fp_line
			(start 0.2794 0.9906)
			(end -0.2794 0.9906)
			(stroke
				(width 0.1)
				(type default)
			)
			(layer "B.Fab")
		)
		(fp_line
			(start -0.2794 -0.1016)
			(end 0.2794 -0.1016)
			(stroke
				(width 0.1)
				(type default)
			)
			(layer "B.Fab")
		)
		(fp_line
			(start 0.2794 -0.1016)
			(end 0.2794 0.9906)
			(stroke
				(width 0.1)
				(type default)
			)
			(layer "B.Fab")
		)
		(pad "1" smd rect
			(at 0 0 90)
			(size 0.508 0.508)
			(layers "B.Cu" "B.Mask" "B.Paste")
			(net "FM_CPU1_VRM_OSC_EN")
		)
		(pad "2" smd rect
			(at 0 0.889 90)
			(size 0.508 0.508)
			(layers "B.Cu" "B.Mask" "B.Paste")
			(net "FM_CPU1_VRM_322M_156M_OSC_EN")
		)
		(zone
			(layer "B.Cu")
			(hatch none 0.5)
			(connect_pads
				(clearance 0)
			)
			(min_thickness 0.25)
			(keepout
				(tracks not_allowed)
				(vias allowed)
				(pads allowed)
				(copperpour not_allowed)
				(footprints allowed)
			)
			(placement
				(enabled no)
				(sheetname "")
			)
			(fill
				(thermal_gap 0.5)
				(thermal_bridge_width 0.5)
				(island_removal_mode 0)
			)
			(polygon
				(pts
					(xy 364.871 -78.8416) (xy 364.871 -79.3496) (xy 365.252 -79.3496) (xy 365.252 -78.8416)
				)
			)
		)
		(zone
			(layer "B.Cu")
			(hatch none 0.5)
			(connect_pads
				(clearance 0)
			)
			(min_thickness 0.25)
			(keepout
				(tracks allowed)
				(vias not_allowed)
				(pads allowed)
				(copperpour not_allowed)
				(footprints allowed)
			)
			(placement
				(enabled no)
				(sheetname "")
			)
			(fill
				(thermal_gap 0.5)
				(thermal_bridge_width 0.5)
				(island_removal_mode 0)
			)
			(polygon
				(pts
					(xy 365.252 -78.8416) (xy 365.252 -79.3496) (xy 364.871 -79.3496) (xy 364.871 -78.8416)
				)
			)
		)
	)
	(footprint ""
		(layer "B.Cu")
		(at 21.209 -60.9092)
		(property "Reference" "EU9R1"
			(at -2.159 -1.67513 0)
			(unlocked yes)
			(layer "B.SilkS")
			(effects
				(font
					(size 0.7874 0.5842)
					(thickness 0.1524)
				)
				(justify mirror)
			)
		)
		(property "Value" ""
			(at 0 0 0)
			(layer "B.Fab")
			(effects
				(font
					(size 1.27 1.27)
				)
				(justify mirror)
			)
		)
		(duplicate_pad_numbers_are_jumpers no)
		(fp_line
			(start -4.8006 -0.7493)
			(end -4.8006 -0.635254)
			(stroke
				(width 0.1524)
				(type default)
			)
			(layer "B.SilkS")
		)
		(fp_line
			(start -4.8006 4.5593)
			(end -4.8006 4.445254)
			(stroke
				(width 0.1524)
				(type default)
			)
			(layer "B.SilkS")
		)
		(fp_line
			(start -0.4064 -0.7493)
			(end -4.8006 -0.7493)
			(stroke
				(width 0.1524)
				(type default)
			)
			(layer "B.SilkS")
		)
		(fp_line
			(start -0.4064 -0.635254)
			(end -0.4064 -0.7493)
			(stroke
				(width 0.1524)
				(type default)
			)
			(layer "B.SilkS")
		)
		(fp_line
			(start -0.4064 4.445254)
			(end -0.4064 4.5593)
			(stroke
				(width 0.1524)
				(type default)
			)
			(layer "B.SilkS")
		)
		(fp_line
			(start -0.4064 4.5593)
			(end -4.8006 4.5593)
			(stroke
				(width 0.1524)
				(type default)
			)
			(layer "B.SilkS")
		)
		(fp_circle
			(center 1.076706 -0.704342)
			(end 1.203706 -0.704342)
			(stroke
				(width 0.254)
				(type default)
			)
			(fill no)
			(layer "B.SilkS")
		)
		(fp_rect
			(start -4.8006 4.5593)
			(end -0.4064 -0.7493)
			(stroke
				(width 0)
				(type default)
			)
			(fill no)
			(layer "B.CrtYd")
		)
		(fp_line
			(start -4.8006 -0.7493)
			(end -4.8006 4.5593)
			(stroke
				(width 0.1)
				(type default)
			)
			(layer "B.Fab")
		)
		(fp_line
			(start -4.8006 4.5593)
			(end -0.4064 4.5593)
			(stroke
				(width 0.1)
				(type default)
			)
			(layer "B.Fab")
		)
		(fp_line
			(start -0.4064 -0.7493)
			(end -4.8006 -0.7493)
			(stroke
				(width 0.1)
				(type default)
			)
			(layer "B.Fab")
		)
		(fp_line
			(start -0.4064 4.5593)
			(end -0.4064 -0.7493)
			(stroke
				(width 0.1)
				(type default)
			)
			(layer "B.Fab")
		)
		(fp_circle
			(center 1.076706 -0.704342)
			(end 1.203706 -0.704342)
			(stroke
				(width 0.254)
				(type default)
			)
			(fill no)
			(layer "B.Fab")
		)
		(pad "1" smd rect
			(at 0 0 180)
			(size 1.651 0.508)
			(layers "B.Cu" "B.Mask" "B.Paste")
			(net "P12V_STBY")
		)
		(pad "2" smd rect
			(at 0 1.27 180)
			(size 1.651 0.508)
			(layers "B.Cu" "B.Mask" "B.Paste")
			(net "P12V_STBY")
		)
		(pad "3" smd rect
			(at 0 2.54 180)
			(size 1.651 0.508)
			(layers "B.Cu" "B.Mask" "B.Paste")
			(net "P12V_STBY")
		)
		(pad "4" smd rect
			(at 0 3.81 180)
			(size 1.651 0.508)
			(layers "B.Cu" "B.Mask" "B.Paste")
			(net "A_HSC_GATE2_R")
		)
		(pad "5" smd custom
			(at -3.937 1.905 180)
			(size 1.04775 1.04775)
			(layers "B.Cu" "B.Mask" "B.Paste")
			(net "P12V_MB0_SW")
			(options
				(clearance outline)
				(anchor circle)
			)
			(primitives
				(gr_poly
					(pts
						(xy -2.0955 1.651) (xy -2.0955 -1.651) (xy 0.4445 -1.651) (xy 0.4445 -2.2098) (xy 2.0955 -2.2098)
						(xy 2.0955 2.2098) (xy 0.4445 2.2098) (xy 0.4445 1.651)
					)
					(width 0)
					(fill yes)
				)
			)
		)
	)
	(footprint ""
		(layer "B.Cu")
		(at 183.515 -72.8472)
		(property "Reference" "R6P28"
			(at 0 0 0)
			(layer "B.SilkS")
			(hide yes)
			(effects
				(font
					(size 1.27 1.27)
				)
				(justify mirror)
			)
		)
		(property "Value" ""
			(at 0 0 0)
			(layer "B.Fab")
			(effects
				(font
					(size 1.27 1.27)
				)
				(justify mirror)
			)
		)
		(duplicate_pad_numbers_are_jumpers no)
		(fp_rect
			(start -0.2794 0.9906)
			(end 0.2794 -0.1016)
			(stroke
				(width 0)
				(type default)
			)
			(fill no)
			(layer "B.CrtYd")
		)
		(fp_line
			(start -0.2794 -0.1016)
			(end 0.2794 -0.1016)
			(stroke
				(width 0.1)
				(type default)
			)
			(layer "B.Fab")
		)
		(fp_line
			(start -0.2794 0.9906)
			(end -0.2794 -0.1016)
			(stroke
				(width 0.1)
				(type default)
			)
			(layer "B.Fab")
		)
		(fp_line
			(start 0.2794 -0.1016)
			(end 0.2794 0.9906)
			(stroke
				(width 0.1)
				(type default)
			)
			(layer "B.Fab")
		)
		(fp_line
			(start 0.2794 0.9906)
			(end -0.2794 0.9906)
			(stroke
				(width 0.1)
				(type default)
			)
			(layer "B.Fab")
		)
		(pad "1" smd rect
			(at 0 0 180)
			(size 0.508 0.508)
			(layers "B.Cu" "B.Mask" "B.Paste")
			(net "VR_PVCCIN_CPU0_XADDR1")
		)
		(pad "2" smd rect
			(at 0 0.889 180)
			(size 0.508 0.508)
			(layers "B.Cu" "B.Mask" "B.Paste")
			(net "GND")
		)
		(zone
			(layer "B.Cu")
			(hatch none 0.5)
			(connect_pads
				(clearance 0)
			)
			(min_thickness 0.25)
			(keepout
				(tracks not_allowed)
				(vias allowed)
				(pads allowed)
				(copperpour not_allowed)
				(footprints allowed)
			)
			(placement
				(enabled no)
				(sheetname "")
			)
			(fill
				(thermal_gap 0.5)
				(thermal_bridge_width 0.5)
				(island_removal_mode 0)
			)
			(polygon
				(pts
					(xy 183.261 -72.2122) (xy 183.769 -72.2122) (xy 183.769 -72.5932) (xy 183.261 -72.5932)
				)
			)
		)
		(zone
			(layer "B.Cu")
			(hatch none 0.5)
			(connect_pads
				(clearance 0)
			)
			(min_thickness 0.25)
			(keepout
				(tracks allowed)
				(vias not_allowed)
				(pads allowed)
				(copperpour not_allowed)
				(footprints allowed)
			)
			(placement
				(enabled no)
				(sheetname "")
			)
			(fill
				(thermal_gap 0.5)
				(thermal_bridge_width 0.5)
				(island_removal_mode 0)
			)
			(polygon
				(pts
					(xy 183.261 -72.2122) (xy 183.769 -72.2122) (xy 183.769 -72.5932) (xy 183.261 -72.5932)
				)
			)
		)
	)
	(footprint ""
		(layer "B.Cu")
		(at 100.6983 -135.4074 90)
		(property "Reference" "C8M2"
			(at 0 0 90)
			(layer "B.SilkS")
			(hide yes)
			(effects
				(font
					(size 1.27 1.27)
				)
				(justify mirror)
			)
		)
		(property "Value" ""
			(at 0 0 90)
			(layer "B.Fab")
			(effects
				(font
					(size 1.27 1.27)
				)
				(justify mirror)
			)
		)
		(duplicate_pad_numbers_are_jumpers no)
		(fp_rect
			(start 0.500126 1.598422)
			(end -0.500126 -0.201422)
			(stroke
				(width 0)
				(type default)
			)
			(fill no)
			(layer "B.CrtYd")
		)
		(fp_line
			(start 0.500126 -0.201422)
			(end -0.500126 -0.201422)
			(stroke
				(width 0.1)
				(type default)
			)
			(layer "B.Fab")
		)
		(fp_line
			(start -0.500126 -0.201422)
			(end -0.500126 1.598422)
			(stroke
				(width 0.1)
				(type default)
			)
			(layer "B.Fab")
		)
		(fp_line
			(start 0.500126 1.598422)
			(end 0.500126 -0.201422)
			(stroke
				(width 0.1)
				(type default)
			)
			(layer "B.Fab")
		)
		(fp_line
			(start -0.500126 1.598422)
			(end 0.500126 1.598422)
			(stroke
				(width 0.1)
				(type default)
			)
			(layer "B.Fab")
		)
		(pad "1" smd rect
			(at 0 0)
			(size 0.889 0.9906)
			(layers "B.Cu" "B.Mask" "B.Paste")
			(net "PVDDQ_KLM")
		)
		(pad "2" smd rect
			(at 0 1.397)
			(size 0.889 0.9906)
			(layers "B.Cu" "B.Mask" "B.Paste")
			(net "GND")
		)
		(zone
			(layer "B.Cu")
			(hatch none 0.5)
			(connect_pads
				(clearance 0)
			)
			(min_thickness 0.25)
			(keepout
				(tracks allowed)
				(vias not_allowed)
				(pads allowed)
				(copperpour not_allowed)
				(footprints allowed)
			)
			(placement
				(enabled no)
				(sheetname "")
			)
			(fill
				(thermal_gap 0.5)
				(thermal_bridge_width 0.5)
				(island_removal_mode 0)
			)
			(polygon
				(pts
					(xy 101.6508 -135.9027) (xy 101.1428 -135.9027) (xy 101.1428 -134.9121) (xy 101.6508 -134.9121)
				)
			)
		)
		(zone
			(layer "B.Cu")
			(hatch none 0.5)
			(connect_pads
				(clearance 0)
			)
			(min_thickness 0.25)
			(keepout
				(tracks not_allowed)
				(vias allowed)
				(pads allowed)
				(copperpour not_allowed)
				(footprints allowed)
			)
			(placement
				(enabled no)
				(sheetname "")
			)
			(fill
				(thermal_gap 0.5)
				(thermal_bridge_width 0.5)
				(island_removal_mode 0)
			)
			(polygon
				(pts
					(xy 101.6508 -135.9027) (xy 101.1428 -135.9027) (xy 101.1428 -134.9121) (xy 101.6508 -134.9121)
				)
			)
		)
	)
	(footprint ""
		(layer "B.Cu")
		(at 367.820956 -122.560842 -90)
		(property "Reference" "R784"
			(at 0.8382 -0.67818 270)
			(unlocked yes)
			(layer "B.SilkS")
			(effects
				(font
					(size 0.4064 0.254)
					(thickness 0.1524)
				)
				(justify left mirror)
			)
		)
		(property "Value" ""
			(at 0 0 90)
			(layer "B.Fab")
			(effects
				(font
					(size 1.27 1.27)
				)
				(justify mirror)
			)
		)
		(duplicate_pad_numbers_are_jumpers no)
		(fp_poly
			(pts
				(xy 0.2794 -0.1016) (xy -0.2794 -0.1016) (xy -0.2794 0.9906) (xy 0.2794 0.9906)
			)
			(stroke
				(width 0)
				(type default)
			)
			(fill no)
			(layer "B.CrtYd")
		)
		(fp_line
			(start -0.2794 0.9906)
			(end -0.2794 -0.1016)
			(stroke
				(width 0.1)
				(type default)
			)
			(layer "B.Fab")
		)
		(fp_line
			(start 0.2794 0.9906)
			(end -0.2794 0.9906)
			(stroke
				(width 0.1)
				(type default)
			)
			(layer "B.Fab")
		)
		(fp_line
			(start -0.2794 -0.1016)
			(end 0.2794 -0.1016)
			(stroke
				(width 0.1)
				(type default)
			)
			(layer "B.Fab")
		)
		(fp_line
			(start 0.2794 -0.1016)
			(end 0.2794 0.9906)
			(stroke
				(width 0.1)
				(type default)
			)
			(layer "B.Fab")
		)
		(pad "1" smd rect
			(at 0 0 90)
			(size 0.508 0.508)
			(layers "B.Cu" "B.Mask" "B.Paste")
			(net "P3E_CPU0_PE1_PCH_RXN<8>")
		)
		(pad "2" smd rect
			(at 0 0.889 90)
			(size 0.508 0.508)
			(layers "B.Cu" "B.Mask" "B.Paste")
			(net "P3E_CPU0_PE1_PCH_CON_RXN<8>")
		)
		(zone
			(layer "B.Cu")
			(hatch none 0.5)
			(connect_pads
				(clearance 0)
			)
			(min_thickness 0.25)
			(keepout
				(tracks not_allowed)
				(vias allowed)
				(pads allowed)
				(copperpour not_allowed)
				(footprints allowed)
			)
			(placement
				(enabled no)
				(sheetname "")
			)
			(fill
				(thermal_gap 0.5)
				(thermal_bridge_width 0.5)
				(island_removal_mode 0)
			)
			(polygon
				(pts
					(xy 367.185956 -122.306842) (xy 367.185956 -122.814842) (xy 367.566956 -122.814842) (xy 367.566956 -122.306842)
				)
			)
		)
		(zone
			(layer "B.Cu")
			(hatch none 0.5)
			(connect_pads
				(clearance 0)
			)
			(min_thickness 0.25)
			(keepout
				(tracks allowed)
				(vias not_allowed)
				(pads allowed)
				(copperpour not_allowed)
				(footprints allowed)
			)
			(placement
				(enabled no)
				(sheetname "")
			)
			(fill
				(thermal_gap 0.5)
				(thermal_bridge_width 0.5)
				(island_removal_mode 0)
			)
			(polygon
				(pts
					(xy 367.566956 -122.306842) (xy 367.566956 -122.814842) (xy 367.185956 -122.814842) (xy 367.185956 -122.306842)
				)
			)
		)
	)
	(footprint ""
		(layer "B.Cu")
		(at 162.179 -70.358 180)
		(property "Reference" "R7P18"
			(at 0 0 0)
			(layer "B.SilkS")
			(hide yes)
			(effects
				(font
					(size 1.27 1.27)
				)
				(justify mirror)
			)
		)
		(property "Value" ""
			(at 0 0 0)
			(layer "B.Fab")
			(effects
				(font
					(size 1.27 1.27)
				)
				(justify mirror)
			)
		)
		(duplicate_pad_numbers_are_jumpers no)
		(fp_poly
			(pts
				(xy 0.2794 -0.1016) (xy -0.2794 -0.1016) (xy -0.2794 0.9906) (xy 0.2794 0.9906)
			)
			(stroke
				(width 0)
				(type default)
			)
			(fill no)
			(layer "B.CrtYd")
		)
		(fp_line
			(start 0.2794 0.9906)
			(end -0.2794 0.9906)
			(stroke
				(width 0.1)
				(type default)
			)
			(layer "B.Fab")
		)
		(fp_line
			(start 0.2794 -0.1016)
			(end 0.2794 0.9906)
			(stroke
				(width 0.1)
				(type default)
			)
			(layer "B.Fab")
		)
		(fp_line
			(start -0.2794 0.9906)
			(end -0.2794 -0.1016)
			(stroke
				(width 0.1)
				(type default)
			)
			(layer "B.Fab")
		)
		(fp_line
			(start -0.2794 -0.1016)
			(end 0.2794 -0.1016)
			(stroke
				(width 0.1)
				(type default)
			)
			(layer "B.Fab")
		)
		(pad "1" smd rect
			(at 0 0)
			(size 0.508 0.508)
			(layers "B.Cu" "B.Mask" "B.Paste")
			(net "PVCCIO_CPU0")
		)
		(pad "2" smd rect
			(at 0 0.889)
			(size 0.508 0.508)
			(layers "B.Cu" "B.Mask" "B.Paste")
			(net "H_CPU1_CATERR_G_N")
		)
		(zone
			(layer "B.Cu")
			(hatch none 0.5)
			(connect_pads
				(clearance 0)
			)
			(min_thickness 0.25)
			(keepout
				(tracks not_allowed)
				(vias allowed)
				(pads allowed)
				(copperpour not_allowed)
				(footprints allowed)
			)
			(placement
				(enabled no)
				(sheetname "")
			)
			(fill
				(thermal_gap 0.5)
				(thermal_bridge_width 0.5)
				(island_removal_mode 0)
			)
			(polygon
				(pts
					(xy 161.925 -70.993) (xy 162.433 -70.993) (xy 162.433 -70.612) (xy 161.925 -70.612)
				)
			)
		)
		(zone
			(layer "B.Cu")
			(hatch none 0.5)
			(connect_pads
				(clearance 0)
			)
			(min_thickness 0.25)
			(keepout
				(tracks allowed)
				(vias not_allowed)
				(pads allowed)
				(copperpour not_allowed)
				(footprints allowed)
			)
			(placement
				(enabled no)
				(sheetname "")
			)
			(fill
				(thermal_gap 0.5)
				(thermal_bridge_width 0.5)
				(island_removal_mode 0)
			)
			(polygon
				(pts
					(xy 161.925 -70.612) (xy 162.433 -70.612) (xy 162.433 -70.993) (xy 161.925 -70.993)
				)
			)
		)
	)
	(footprint ""
		(layer "B.Cu")
		(at 162.175952 -62.487302 180)
		(property "Reference" "R7R1"
			(at 0 0 0)
			(layer "B.SilkS")
			(hide yes)
			(effects
				(font
					(size 1.27 1.27)
				)
				(justify mirror)
			)
		)
		(property "Value" ""
			(at 0 0 0)
			(layer "B.Fab")
			(effects
				(font
					(size 1.27 1.27)
				)
				(justify mirror)
			)
		)
		(duplicate_pad_numbers_are_jumpers no)
		(fp_poly
			(pts
				(xy 0.2794 -0.1016) (xy -0.2794 -0.1016) (xy -0.2794 0.9906) (xy 0.2794 0.9906)
			)
			(stroke
				(width 0)
				(type default)
			)
			(fill no)
			(layer "B.CrtYd")
		)
		(fp_line
			(start 0.2794 0.9906)
			(end -0.2794 0.9906)
			(stroke
				(width 0.1)
				(type default)
			)
			(layer "B.Fab")
		)
		(fp_line
			(start 0.2794 -0.1016)
			(end 0.2794 0.9906)
			(stroke
				(width 0.1)
				(type default)
			)
			(layer "B.Fab")
		)
		(fp_line
			(start -0.2794 0.9906)
			(end -0.2794 -0.1016)
			(stroke
				(width 0.1)
				(type default)
			)
			(layer "B.Fab")
		)
		(fp_line
			(start -0.2794 -0.1016)
			(end 0.2794 -0.1016)
			(stroke
				(width 0.1)
				(type default)
			)
			(layer "B.Fab")
		)
		(pad "1" smd rect
			(at 0 0)
			(size 0.508 0.508)
			(layers "B.Cu" "B.Mask" "B.Paste")
			(net "PVCCIO_CPU1")
		)
		(pad "2" smd rect
			(at 0 0.889)
			(size 0.508 0.508)
			(layers "B.Cu" "B.Mask" "B.Paste")
			(net "GND")
		)
		(zone
			(layer "B.Cu")
			(hatch none 0.5)
			(connect_pads
				(clearance 0)
			)
			(min_thickness 0.25)
			(keepout
				(tracks not_allowed)
				(vias allowed)
				(pads allowed)
				(copperpour not_allowed)
				(footprints allowed)
			)
			(placement
				(enabled no)
				(sheetname "")
			)
			(fill
				(thermal_gap 0.5)
				(thermal_bridge_width 0.5)
				(island_removal_mode 0)
			)
			(polygon
				(pts
					(xy 161.921952 -63.122302) (xy 162.429952 -63.122302) (xy 162.429952 -62.741302) (xy 161.921952 -62.741302)
				)
			)
		)
		(zone
			(layer "B.Cu")
			(hatch none 0.5)
			(connect_pads
				(clearance 0)
			)
			(min_thickness 0.25)
			(keepout
				(tracks allowed)
				(vias not_allowed)
				(pads allowed)
				(copperpour not_allowed)
				(footprints allowed)
			)
			(placement
				(enabled no)
				(sheetname "")
			)
			(fill
				(thermal_gap 0.5)
				(thermal_bridge_width 0.5)
				(island_removal_mode 0)
			)
			(polygon
				(pts
					(xy 161.921952 -62.741302) (xy 162.429952 -62.741302) (xy 162.429952 -63.122302) (xy 161.921952 -63.122302)
				)
			)
		)
	)
	(footprint ""
		(layer "B.Cu")
		(at 32.258 -62.6364 90)
		(property "Reference" "R9R11"
			(at 0 0 90)
			(layer "B.SilkS")
			(hide yes)
			(effects
				(font
					(size 1.27 1.27)
				)
				(justify mirror)
			)
		)
		(property "Value" ""
			(at 0 0 90)
			(layer "B.Fab")
			(effects
				(font
					(size 1.27 1.27)
				)
				(justify mirror)
			)
		)
		(duplicate_pad_numbers_are_jumpers no)
		(fp_poly
			(pts
				(xy 0.2794 -0.1016) (xy -0.2794 -0.1016) (xy -0.2794 0.9906) (xy 0.2794 0.9906)
			)
			(stroke
				(width 0)
				(type default)
			)
			(fill no)
			(layer "B.CrtYd")
		)
		(fp_line
			(start 0.2794 -0.1016)
			(end 0.2794 0.9906)
			(stroke
				(width 0.1)
				(type default)
			)
			(layer "B.Fab")
		)
		(fp_line
			(start -0.2794 -0.1016)
			(end 0.2794 -0.1016)
			(stroke
				(width 0.1)
				(type default)
			)
			(layer "B.Fab")
		)
		(fp_line
			(start 0.2794 0.9906)
			(end -0.2794 0.9906)
			(stroke
				(width 0.1)
				(type default)
			)
			(layer "B.Fab")
		)
		(fp_line
			(start -0.2794 0.9906)
			(end -0.2794 -0.1016)
			(stroke
				(width 0.1)
				(type default)
			)
			(layer "B.Fab")
		)
		(pad "1" smd rect
			(at 0 0 270)
			(size 0.508 0.508)
			(layers "B.Cu" "B.Mask" "B.Paste")
			(net "VR_PVCCIN_CPU1_PH2_VCIN")
		)
		(pad "2" smd rect
			(at 0 0.889 270)
			(size 0.508 0.508)
			(layers "B.Cu" "B.Mask" "B.Paste")
			(net "P5V_STBY")
		)
		(zone
			(layer "B.Cu")
			(hatch none 0.5)
			(connect_pads
				(clearance 0)
			)
			(min_thickness 0.25)
			(keepout
				(tracks allowed)
				(vias not_allowed)
				(pads allowed)
				(copperpour not_allowed)
				(footprints allowed)
			)
			(placement
				(enabled no)
				(sheetname "")
			)
			(fill
				(thermal_gap 0.5)
				(thermal_bridge_width 0.5)
				(island_removal_mode 0)
			)
			(polygon
				(pts
					(xy 32.512 -62.8904) (xy 32.512 -62.3824) (xy 32.893 -62.3824) (xy 32.893 -62.8904)
				)
			)
		)
		(zone
			(layer "B.Cu")
			(hatch none 0.5)
			(connect_pads
				(clearance 0)
			)
			(min_thickness 0.25)
			(keepout
				(tracks not_allowed)
				(vias allowed)
				(pads allowed)
				(copperpour not_allowed)
				(footprints allowed)
			)
			(placement
				(enabled no)
				(sheetname "")
			)
			(fill
				(thermal_gap 0.5)
				(thermal_bridge_width 0.5)
				(island_removal_mode 0)
			)
			(polygon
				(pts
					(xy 32.893 -62.8904) (xy 32.893 -62.3824) (xy 32.512 -62.3824) (xy 32.512 -62.8904)
				)
			)
		)
	)
	(footprint ""
		(layer "B.Cu")
		(at 264.428224 -69.098414 -90)
		(property "Reference" "C5P38"
			(at 0 0 90)
			(layer "B.SilkS")
			(hide yes)
			(effects
				(font
					(size 1.27 1.27)
				)
				(justify mirror)
			)
		)
		(property "Value" ""
			(at 0 0 90)
			(layer "B.Fab")
			(effects
				(font
					(size 1.27 1.27)
				)
				(justify mirror)
			)
		)
		(duplicate_pad_numbers_are_jumpers no)
		(fp_poly
			(pts
				(xy 0.7239 -0.2159) (xy -0.7239 -0.2159) (xy -0.7239 1.9939) (xy 0.7239 1.9939)
			)
			(stroke
				(width 0)
				(type default)
			)
			(fill no)
			(layer "B.CrtYd")
		)
		(fp_line
			(start -0.7239 1.9939)
			(end -0.7239 -0.2159)
			(stroke
				(width 0.1)
				(type default)
			)
			(layer "B.Fab")
		)
		(fp_line
			(start 0.7239 1.9939)
			(end -0.7239 1.9939)
			(stroke
				(width 0.1)
				(type default)
			)
			(layer "B.Fab")
		)
		(fp_line
			(start -0.7239 -0.2159)
			(end 0.7239 -0.2159)
			(stroke
				(width 0.1)
				(type default)
			)
			(layer "B.Fab")
		)
		(fp_line
			(start 0.7239 -0.2159)
			(end 0.7239 1.9939)
			(stroke
				(width 0.1)
				(type default)
			)
			(layer "B.Fab")
		)
		(pad "1" smd rect
			(at 0 0 90)
			(size 1.27 1.016)
			(layers "B.Cu" "B.Mask" "B.Paste")
			(net "PVDDQ_ABC")
		)
		(pad "2" smd rect
			(at 0 1.778 90)
			(size 1.27 1.016)
			(layers "B.Cu" "B.Mask" "B.Paste")
			(net "GND")
		)
		(zone
			(layer "B.Cu")
			(hatch none 0.5)
			(connect_pads
				(clearance 0)
			)
			(min_thickness 0.25)
			(keepout
				(tracks not_allowed)
				(vias allowed)
				(pads allowed)
				(copperpour not_allowed)
				(footprints allowed)
			)
			(placement
				(enabled no)
				(sheetname "")
			)
			(fill
				(thermal_gap 0.5)
				(thermal_bridge_width 0.5)
				(island_removal_mode 0)
			)
			(polygon
				(pts
					(xy 263.920224 -68.463414) (xy 263.920224 -69.733414) (xy 263.158224 -69.733414) (xy 263.158224 -68.463414)
				)
			)
		)
	)
	(footprint ""
		(layer "B.Cu")
		(at 422.70172 -149.098 90)
		(property "Reference" "C2L19"
			(at 0 0 90)
			(layer "B.SilkS")
			(hide yes)
			(effects
				(font
					(size 1.27 1.27)
				)
				(justify mirror)
			)
		)
		(property "Value" ""
			(at 0 0 90)
			(layer "B.Fab")
			(effects
				(font
					(size 1.27 1.27)
				)
				(justify mirror)
			)
		)
		(duplicate_pad_numbers_are_jumpers no)
		(fp_poly
			(pts
				(xy -0.3048 -0.1016) (xy -0.3048 0.9906) (xy 0.3048 0.9906) (xy 0.3048 -0.1016)
			)
			(stroke
				(width 0)
				(type default)
			)
			(fill no)
			(layer "B.CrtYd")
		)
		(fp_line
			(start 0.3048 -0.1016)
			(end 0.3048 0.9906)
			(stroke
				(width 0.1)
				(type default)
			)
			(layer "B.Fab")
		)
		(fp_line
			(start -0.3048 -0.1016)
			(end 0.3048 -0.1016)
			(stroke
				(width 0.1)
				(type default)
			)
			(layer "B.Fab")
		)
		(fp_line
			(start 0.3048 0.9906)
			(end -0.3048 0.9906)
			(stroke
				(width 0.1)
				(type default)
			)
			(layer "B.Fab")
		)
		(fp_line
			(start -0.3048 0.9906)
			(end -0.3048 -0.1016)
			(stroke
				(width 0.1)
				(type default)
			)
			(layer "B.Fab")
		)
		(pad "1" smd rect
			(at 0 0 270)
			(size 0.508 0.508)
			(layers "B.Cu" "B.Mask" "B.Paste")
			(net "SATA6G_PCH_PCIE_UP_SATA_RXP<0>")
		)
		(pad "2" smd rect
			(at 0 0.889 270)
			(size 0.508 0.508)
			(layers "B.Cu" "B.Mask" "B.Paste")
			(net "SATA6G_P0_RX_C_DP")
		)
		(zone
			(layer "B.Cu")
			(hatch none 0.5)
			(connect_pads
				(clearance 0)
			)
			(min_thickness 0.25)
			(keepout
				(tracks allowed)
				(vias not_allowed)
				(pads allowed)
				(copperpour not_allowed)
				(footprints allowed)
			)
			(placement
				(enabled no)
				(sheetname "")
			)
			(fill
				(thermal_gap 0.5)
				(thermal_bridge_width 0.5)
				(island_removal_mode 0)
			)
			(polygon
				(pts
					(xy 422.95572 -149.352) (xy 422.95572 -148.844) (xy 423.33672 -148.844) (xy 423.33672 -149.352)
				)
			)
		)
		(zone
			(layer "B.Cu")
			(hatch none 0.5)
			(connect_pads
				(clearance 0)
			)
			(min_thickness 0.25)
			(keepout
				(tracks not_allowed)
				(vias allowed)
				(pads allowed)
				(copperpour not_allowed)
				(footprints allowed)
			)
			(placement
				(enabled no)
				(sheetname "")
			)
			(fill
				(thermal_gap 0.5)
				(thermal_bridge_width 0.5)
				(island_removal_mode 0)
			)
			(polygon
				(pts
					(xy 423.33672 -149.352) (xy 423.33672 -148.844) (xy 422.95572 -148.844) (xy 422.95572 -149.352)
				)
			)
		)
	)
	(footprint ""
		(layer "B.Cu")
		(at 393.446 -28.575 -90)
		(property "Reference" "C2T35"
			(at 0 0 90)
			(layer "B.SilkS")
			(hide yes)
			(effects
				(font
					(size 1.27 1.27)
				)
				(justify mirror)
			)
		)
		(property "Value" ""
			(at 0 0 90)
			(layer "B.Fab")
			(effects
				(font
					(size 1.27 1.27)
				)
				(justify mirror)
			)
		)
		(duplicate_pad_numbers_are_jumpers no)
		(fp_poly
			(pts
				(xy -0.3048 -0.1016) (xy -0.3048 0.9906) (xy 0.3048 0.9906) (xy 0.3048 -0.1016)
			)
			(stroke
				(width 0)
				(type default)
			)
			(fill no)
			(layer "B.CrtYd")
		)
		(fp_line
			(start -0.3048 0.9906)
			(end -0.3048 -0.1016)
			(stroke
				(width 0.1)
				(type default)
			)
			(layer "B.Fab")
		)
		(fp_line
			(start 0.3048 0.9906)
			(end -0.3048 0.9906)
			(stroke
				(width 0.1)
				(type default)
			)
			(layer "B.Fab")
		)
		(fp_line
			(start -0.3048 -0.1016)
			(end 0.3048 -0.1016)
			(stroke
				(width 0.1)
				(type default)
			)
			(layer "B.Fab")
		)
		(fp_line
			(start 0.3048 -0.1016)
			(end 0.3048 0.9906)
			(stroke
				(width 0.1)
				(type default)
			)
			(layer "B.Fab")
		)
		(pad "1" smd rect
			(at 0 0 90)
			(size 0.508 0.508)
			(layers "B.Cu" "B.Mask" "B.Paste")
			(net "P3V3_STBY")
		)
		(pad "2" smd rect
			(at 0 0.889 90)
			(size 0.508 0.508)
			(layers "B.Cu" "B.Mask" "B.Paste")
			(net "GND")
		)
	)
	(footprint ""
		(layer "B.Cu")
		(at 8.653272 -121.94413 90)
		(property "Reference" "C9M6"
			(at 0 0 90)
			(layer "B.SilkS")
			(hide yes)
			(effects
				(font
					(size 1.27 1.27)
				)
				(justify mirror)
			)
		)
		(property "Value" ""
			(at 0 0 90)
			(layer "B.Fab")
			(effects
				(font
					(size 1.27 1.27)
				)
				(justify mirror)
			)
		)
		(duplicate_pad_numbers_are_jumpers no)
		(fp_rect
			(start 0.3048 0.9906)
			(end -0.3048 -0.1016)
			(stroke
				(width 0)
				(type default)
			)
			(fill no)
			(layer "B.CrtYd")
		)
		(fp_line
			(start 0.3048 -0.1016)
			(end 0.3048 0.9906)
			(stroke
				(width 0.1)
				(type default)
			)
			(layer "B.Fab")
		)
		(fp_line
			(start -0.3048 -0.1016)
			(end 0.3048 -0.1016)
			(stroke
				(width 0.1)
				(type default)
			)
			(layer "B.Fab")
		)
		(fp_line
			(start 0.3048 0.9906)
			(end -0.3048 0.9906)
			(stroke
				(width 0.1)
				(type default)
			)
			(layer "B.Fab")
		)
		(fp_line
			(start -0.3048 0.9906)
			(end -0.3048 -0.1016)
			(stroke
				(width 0.1)
				(type default)
			)
			(layer "B.Fab")
		)
		(pad "1" smd rect
			(at 0 0 270)
			(size 0.508 0.508)
			(layers "B.Cu" "B.Mask" "B.Paste")
			(net "P5V_STBY")
		)
		(pad "2" smd rect
			(at 0 0.889 270)
			(size 0.508 0.508)
			(layers "B.Cu" "B.Mask" "B.Paste")
			(net "GND")
		)
		(zone
			(layer "B.Cu")
			(hatch none 0.5)
			(connect_pads
				(clearance 0)
			)
			(min_thickness 0.25)
			(keepout
				(tracks allowed)
				(vias not_allowed)
				(pads allowed)
				(copperpour not_allowed)
				(footprints allowed)
			)
			(placement
				(enabled no)
				(sheetname "")
			)
			(fill
				(thermal_gap 0.5)
				(thermal_bridge_width 0.5)
				(island_removal_mode 0)
			)
			(polygon
				(pts
					(xy 9.288272 -122.19813) (xy 8.907272 -122.19813) (xy 8.907272 -121.69013) (xy 9.288272 -121.69013)
				)
			)
		)
		(zone
			(layer "B.Cu")
			(hatch none 0.5)
			(connect_pads
				(clearance 0)
			)
			(min_thickness 0.25)
			(keepout
				(tracks not_allowed)
				(vias allowed)
				(pads allowed)
				(copperpour not_allowed)
				(footprints allowed)
			)
			(placement
				(enabled no)
				(sheetname "")
			)
			(fill
				(thermal_gap 0.5)
				(thermal_bridge_width 0.5)
				(island_removal_mode 0)
			)
			(polygon
				(pts
					(xy 9.288272 -122.19813) (xy 8.907272 -122.19813) (xy 8.907272 -121.69013) (xy 9.288272 -121.69013)
				)
			)
		)
	)
	(footprint ""
		(layer "B.Cu")
		(at 444.6778 -64.7446 180)
		(property "Reference" "C2P14"
			(at 0 0 0)
			(layer "B.SilkS")
			(hide yes)
			(effects
				(font
					(size 1.27 1.27)
				)
				(justify mirror)
			)
		)
		(property "Value" ""
			(at 0 0 0)
			(layer "B.Fab")
			(effects
				(font
					(size 1.27 1.27)
				)
				(justify mirror)
			)
		)
		(duplicate_pad_numbers_are_jumpers no)
		(fp_poly
			(pts
				(xy -0.3048 -0.1016) (xy -0.3048 0.9906) (xy 0.3048 0.9906) (xy 0.3048 -0.1016)
			)
			(stroke
				(width 0)
				(type default)
			)
			(fill no)
			(layer "B.CrtYd")
		)
		(fp_line
			(start 0.3048 0.9906)
			(end -0.3048 0.9906)
			(stroke
				(width 0.1)
				(type default)
			)
			(layer "B.Fab")
		)
		(fp_line
			(start 0.3048 -0.1016)
			(end 0.3048 0.9906)
			(stroke
				(width 0.1)
				(type default)
			)
			(layer "B.Fab")
		)
		(fp_line
			(start -0.3048 0.9906)
			(end -0.3048 -0.1016)
			(stroke
				(width 0.1)
				(type default)
			)
			(layer "B.Fab")
		)
		(fp_line
			(start -0.3048 -0.1016)
			(end 0.3048 -0.1016)
			(stroke
				(width 0.1)
				(type default)
			)
			(layer "B.Fab")
		)
		(pad "1" smd rect
			(at 0 0)
			(size 0.508 0.508)
			(layers "B.Cu" "B.Mask" "B.Paste")
			(net "P12V_STBY")
		)
		(pad "2" smd rect
			(at 0 0.889)
			(size 0.508 0.508)
			(layers "B.Cu" "B.Mask" "B.Paste")
			(net "GND")
		)
		(zone
			(layer "B.Cu")
			(hatch none 0.5)
			(connect_pads
				(clearance 0)
			)
			(min_thickness 0.25)
			(keepout
				(tracks not_allowed)
				(vias allowed)
				(pads allowed)
				(copperpour not_allowed)
				(footprints allowed)
			)
			(placement
				(enabled no)
				(sheetname "")
			)
			(fill
				(thermal_gap 0.5)
				(thermal_bridge_width 0.5)
				(island_removal_mode 0)
			)
			(polygon
				(pts
					(xy 444.4238 -65.3796) (xy 444.9318 -65.3796) (xy 444.9318 -64.9986) (xy 444.4238 -64.9986)
				)
			)
		)
		(zone
			(layer "B.Cu")
			(hatch none 0.5)
			(connect_pads
				(clearance 0)
			)
			(min_thickness 0.25)
			(keepout
				(tracks allowed)
				(vias not_allowed)
				(pads allowed)
				(copperpour not_allowed)
				(footprints allowed)
			)
			(placement
				(enabled no)
				(sheetname "")
			)
			(fill
				(thermal_gap 0.5)
				(thermal_bridge_width 0.5)
				(island_removal_mode 0)
			)
			(polygon
				(pts
					(xy 444.4238 -64.9986) (xy 444.9318 -64.9986) (xy 444.9318 -65.3796) (xy 444.4238 -65.3796)
				)
			)
		)
	)
	(footprint ""
		(layer "B.Cu")
		(at 379.481842 -91.021662 180)
		(property "Reference" "R7C26"
			(at 0.8382 -0.67818 180)
			(unlocked yes)
			(layer "B.SilkS")
			(effects
				(font
					(size 0.4064 0.254)
					(thickness 0.1524)
				)
				(justify left mirror)
			)
		)
		(property "Value" ""
			(at 0 0 0)
			(layer "B.Fab")
			(effects
				(font
					(size 1.27 1.27)
				)
				(justify mirror)
			)
		)
		(duplicate_pad_numbers_are_jumpers no)
		(fp_poly
			(pts
				(xy 0.2794 -0.1016) (xy -0.2794 -0.1016) (xy -0.2794 0.9906) (xy 0.2794 0.9906)
			)
			(stroke
				(width 0)
				(type default)
			)
			(fill no)
			(layer "B.CrtYd")
		)
		(fp_line
			(start 0.2794 0.9906)
			(end -0.2794 0.9906)
			(stroke
				(width 0.1)
				(type default)
			)
			(layer "B.Fab")
		)
		(fp_line
			(start 0.2794 -0.1016)
			(end 0.2794 0.9906)
			(stroke
				(width 0.1)
				(type default)
			)
			(layer "B.Fab")
		)
		(fp_line
			(start -0.2794 0.9906)
			(end -0.2794 -0.1016)
			(stroke
				(width 0.1)
				(type default)
			)
			(layer "B.Fab")
		)
		(fp_line
			(start -0.2794 -0.1016)
			(end 0.2794 -0.1016)
			(stroke
				(width 0.1)
				(type default)
			)
			(layer "B.Fab")
		)
		(pad "1" smd rect
			(at 0 0)
			(size 0.508 0.508)
			(layers "B.Cu" "B.Mask" "B.Paste")
			(net "CLK_24M_BMC_LPC")
		)
		(pad "2" smd rect
			(at 0 0.889)
			(size 0.508 0.508)
			(layers "B.Cu" "B.Mask" "B.Paste")
			(net "CLK_24M_BMC_LPC_R")
		)
		(zone
			(layer "B.Cu")
			(hatch none 0.5)
			(connect_pads
				(clearance 0)
			)
			(min_thickness 0.25)
			(keepout
				(tracks not_allowed)
				(vias allowed)
				(pads allowed)
				(copperpour not_allowed)
				(footprints allowed)
			)
			(placement
				(enabled no)
				(sheetname "")
			)
			(fill
				(thermal_gap 0.5)
				(thermal_bridge_width 0.5)
				(island_removal_mode 0)
			)
			(polygon
				(pts
					(xy 379.227842 -91.656662) (xy 379.735842 -91.656662) (xy 379.735842 -91.275662) (xy 379.227842 -91.275662)
				)
			)
		)
		(zone
			(layer "B.Cu")
			(hatch none 0.5)
			(connect_pads
				(clearance 0)
			)
			(min_thickness 0.25)
			(keepout
				(tracks allowed)
				(vias not_allowed)
				(pads allowed)
				(copperpour not_allowed)
				(footprints allowed)
			)
			(placement
				(enabled no)
				(sheetname "")
			)
			(fill
				(thermal_gap 0.5)
				(thermal_bridge_width 0.5)
				(island_removal_mode 0)
			)
			(polygon
				(pts
					(xy 379.227842 -91.275662) (xy 379.735842 -91.275662) (xy 379.735842 -91.656662) (xy 379.227842 -91.656662)
				)
			)
		)
	)
	(footprint ""
		(layer "B.Cu")
		(at 376.7328 -135.5598 180)
		(property "Reference" "C3M21"
			(at 0 0 0)
			(layer "B.SilkS")
			(hide yes)
			(effects
				(font
					(size 1.27 1.27)
				)
				(justify mirror)
			)
		)
		(property "Value" ""
			(at 0 0 0)
			(layer "B.Fab")
			(effects
				(font
					(size 1.27 1.27)
				)
				(justify mirror)
			)
		)
		(duplicate_pad_numbers_are_jumpers no)
		(fp_rect
			(start 0.3048 -0.1016)
			(end -0.3048 0.9906)
			(stroke
				(width 0)
				(type default)
			)
			(fill no)
			(layer "B.CrtYd")
		)
		(fp_line
			(start 0.3048 0.9906)
			(end -0.3048 0.9906)
			(stroke
				(width 0.1)
				(type default)
			)
			(layer "B.Fab")
		)
		(fp_line
			(start 0.3048 -0.1016)
			(end 0.3048 0.9906)
			(stroke
				(width 0.1)
				(type default)
			)
			(layer "B.Fab")
		)
		(fp_line
			(start -0.3048 0.9906)
			(end -0.3048 -0.1016)
			(stroke
				(width 0.1)
				(type default)
			)
			(layer "B.Fab")
		)
		(fp_line
			(start -0.3048 -0.1016)
			(end 0.3048 -0.1016)
			(stroke
				(width 0.1)
				(type default)
			)
			(layer "B.Fab")
		)
		(pad "1" smd rect
			(at 0 0)
			(size 0.508 0.508)
			(layers "B.Cu" "B.Mask" "B.Paste")
			(net "P1V05_PCH_STBY")
		)
		(pad "2" smd rect
			(at 0 0.889)
			(size 0.508 0.508)
			(layers "B.Cu" "B.Mask" "B.Paste")
			(net "GND")
		)
		(zone
			(layer "B.Cu")
			(hatch none 0.5)
			(connect_pads
				(clearance 0)
			)
			(min_thickness 0.25)
			(keepout
				(tracks allowed)
				(vias not_allowed)
				(pads allowed)
				(copperpour not_allowed)
				(footprints allowed)
			)
			(placement
				(enabled no)
				(sheetname "")
			)
			(fill
				(thermal_gap 0.5)
				(thermal_bridge_width 0.5)
				(island_removal_mode 0)
			)
			(polygon
				(pts
					(xy 376.4788 -135.8138) (xy 376.9868 -135.8138) (xy 376.9868 -136.1948) (xy 376.4788 -136.1948)
				)
			)
		)
		(zone
			(layer "B.Cu")
			(hatch none 0.5)
			(connect_pads
				(clearance 0)
			)
			(min_thickness 0.25)
			(keepout
				(tracks not_allowed)
				(vias allowed)
				(pads allowed)
				(copperpour not_allowed)
				(footprints allowed)
			)
			(placement
				(enabled no)
				(sheetname "")
			)
			(fill
				(thermal_gap 0.5)
				(thermal_bridge_width 0.5)
				(island_removal_mode 0)
			)
			(polygon
				(pts
					(xy 376.4788 -135.8138) (xy 376.9868 -135.8138) (xy 376.9868 -136.1948) (xy 376.4788 -136.1948)
				)
			)
		)
	)
	(footprint ""
		(layer "B.Cu")
		(at 106.604054 -68.17614 180)
		(property "Reference" "C8P32"
			(at 0 0 0)
			(layer "B.SilkS")
			(hide yes)
			(effects
				(font
					(size 1.27 1.27)
				)
				(justify mirror)
			)
		)
		(property "Value" ""
			(at 0 0 0)
			(layer "B.Fab")
			(effects
				(font
					(size 1.27 1.27)
				)
				(justify mirror)
			)
		)
		(duplicate_pad_numbers_are_jumpers no)
		(fp_poly
			(pts
				(xy 0.7239 -0.2159) (xy -0.7239 -0.2159) (xy -0.7239 1.9939) (xy 0.7239 1.9939)
			)
			(stroke
				(width 0)
				(type default)
			)
			(fill no)
			(layer "B.CrtYd")
		)
		(fp_line
			(start 0.7239 1.9939)
			(end -0.7239 1.9939)
			(stroke
				(width 0.1)
				(type default)
			)
			(layer "B.Fab")
		)
		(fp_line
			(start 0.7239 -0.2159)
			(end 0.7239 1.9939)
			(stroke
				(width 0.1)
				(type default)
			)
			(layer "B.Fab")
		)
		(fp_line
			(start -0.7239 1.9939)
			(end -0.7239 -0.2159)
			(stroke
				(width 0.1)
				(type default)
			)
			(layer "B.Fab")
		)
		(fp_line
			(start -0.7239 -0.2159)
			(end 0.7239 -0.2159)
			(stroke
				(width 0.1)
				(type default)
			)
			(layer "B.Fab")
		)
		(pad "1" smd rect
			(at 0 0)
			(size 1.27 1.016)
			(layers "B.Cu" "B.Mask" "B.Paste")
			(net "PVDDQ_GHJ")
		)
		(pad "2" smd rect
			(at 0 1.778)
			(size 1.27 1.016)
			(layers "B.Cu" "B.Mask" "B.Paste")
			(net "GND")
		)
		(zone
			(layer "B.Cu")
			(hatch none 0.5)
			(connect_pads
				(clearance 0)
			)
			(min_thickness 0.25)
			(keepout
				(tracks not_allowed)
				(vias allowed)
				(pads allowed)
				(copperpour not_allowed)
				(footprints allowed)
			)
			(placement
				(enabled no)
				(sheetname "")
			)
			(fill
				(thermal_gap 0.5)
				(thermal_bridge_width 0.5)
				(island_removal_mode 0)
			)
			(polygon
				(pts
					(xy 105.969054 -68.68414) (xy 107.239054 -68.68414) (xy 107.239054 -69.44614) (xy 105.969054 -69.44614)
				)
			)
		)
	)
	(footprint ""
		(layer "B.Cu")
		(at 20.3835 -90.1065 -90)
		(property "Reference" "Q6W1"
			(at 0.229362 -1.2065 270)
			(unlocked yes)
			(layer "B.SilkS")
			(effects
				(font
					(size 0.4064 0.254)
					(thickness 0.1524)
				)
				(justify left mirror)
			)
		)
		(property "Value" ""
			(at 0 0 90)
			(layer "B.Fab")
			(effects
				(font
					(size 1.27 1.27)
				)
				(justify mirror)
			)
		)
		(duplicate_pad_numbers_are_jumpers no)
		(fp_line
			(start -1.778 2.4765)
			(end -1.778 1.5875)
			(stroke
				(width 0.1524)
				(type default)
			)
			(layer "B.SilkS")
		)
		(fp_line
			(start -0.9525 2.4765)
			(end -1.778 2.4765)
			(stroke
				(width 0.1524)
				(type default)
			)
			(layer "B.SilkS")
		)
		(fp_line
			(start -0.381 0.635)
			(end -0.381 1.27)
			(stroke
				(width 0.1524)
				(type default)
			)
			(layer "B.SilkS")
		)
		(fp_line
			(start -1.778 -0.5715)
			(end -1.778 0.3175)
			(stroke
				(width 0.1524)
				(type default)
			)
			(layer "B.SilkS")
		)
		(fp_line
			(start -0.9525 -0.5715)
			(end -1.778 -0.5715)
			(stroke
				(width 0.1524)
				(type default)
			)
			(layer "B.SilkS")
		)
		(fp_circle
			(center 0.9525 -0.9271)
			(end 0.9525 -1.0541)
			(stroke
				(width 0.254)
				(type default)
			)
			(fill no)
			(layer "B.SilkS")
		)
		(fp_poly
			(pts
				(xy -1.778 2.4765) (xy -0.381 2.4765) (xy -0.381 -0.5715) (xy -1.778 -0.5715)
			)
			(stroke
				(width 0)
				(type default)
			)
			(fill no)
			(layer "B.CrtYd")
		)
		(fp_line
			(start -1.778 2.4765)
			(end -1.778 -0.5715)
			(stroke
				(width 0.1)
				(type default)
			)
			(layer "B.Fab")
		)
		(fp_line
			(start -0.381 2.4765)
			(end -1.778 2.4765)
			(stroke
				(width 0.1)
				(type default)
			)
			(layer "B.Fab")
		)
		(fp_line
			(start -1.778 -0.5715)
			(end -0.381 -0.5715)
			(stroke
				(width 0.1)
				(type default)
			)
			(layer "B.Fab")
		)
		(fp_line
			(start -0.381 -0.5715)
			(end -0.381 2.4765)
			(stroke
				(width 0.1)
				(type default)
			)
			(layer "B.Fab")
		)
		(fp_circle
			(center 0.9525 -0.9271)
			(end 0.9525 -1.0541)
			(stroke
				(width 0.254)
				(type default)
			)
			(fill no)
			(layer "B.Fab")
		)
		(pad "1" smd rect
			(at 0 0 90)
			(size 1.143 0.508)
			(layers "B.Cu" "B.Mask" "B.Paste")
			(net "UV_HIGH_SET")
		)
		(pad "2" smd rect
			(at 0 1.905 90)
			(size 1.143 0.508)
			(layers "B.Cu" "B.Mask" "B.Paste")
			(net "GND")
		)
		(pad "3" smd rect
			(at -2.159 0.9525 90)
			(size 1.143 0.508)
			(layers "B.Cu" "B.Mask" "B.Paste")
			(net "UV_HIGH_SET_N")
		)
	)
	(footprint ""
		(layer "B.Cu")
		(at 272.861532 -17.7546 90)
		(property "Reference" "C5T6"
			(at -1.848866 0.752348 90)
			(unlocked yes)
			(layer "B.SilkS")
			(effects
				(font
					(size 1.27 0.9652)
					(thickness 0.1524)
				)
				(justify mirror)
			)
		)
		(property "Value" ""
			(at 0 0 90)
			(layer "B.Fab")
			(effects
				(font
					(size 1.27 1.27)
				)
				(justify mirror)
			)
		)
		(duplicate_pad_numbers_are_jumpers no)
		(fp_rect
			(start 0.500126 1.598422)
			(end -0.500126 -0.201422)
			(stroke
				(width 0)
				(type default)
			)
			(fill no)
			(layer "B.CrtYd")
		)
		(fp_line
			(start 0.500126 -0.201422)
			(end -0.500126 -0.201422)
			(stroke
				(width 0.1)
				(type default)
			)
			(layer "B.Fab")
		)
		(fp_line
			(start -0.500126 -0.201422)
			(end -0.500126 1.598422)
			(stroke
				(width 0.1)
				(type default)
			)
			(layer "B.Fab")
		)
		(fp_line
			(start 0.500126 1.598422)
			(end 0.500126 -0.201422)
			(stroke
				(width 0.1)
				(type default)
			)
			(layer "B.Fab")
		)
		(fp_line
			(start -0.500126 1.598422)
			(end 0.500126 1.598422)
			(stroke
				(width 0.1)
				(type default)
			)
			(layer "B.Fab")
		)
		(pad "1" smd rect
			(at 0 0)
			(size 0.889 0.9906)
			(layers "B.Cu" "B.Mask" "B.Paste")
			(net "PVDDQ_ABC")
		)
		(pad "2" smd rect
			(at 0 1.397)
			(size 0.889 0.9906)
			(layers "B.Cu" "B.Mask" "B.Paste")
			(net "GND")
		)
		(zone
			(layer "B.Cu")
			(hatch none 0.5)
			(connect_pads
				(clearance 0)
			)
			(min_thickness 0.25)
			(keepout
				(tracks not_allowed)
				(vias allowed)
				(pads allowed)
				(copperpour not_allowed)
				(footprints allowed)
			)
			(placement
				(enabled no)
				(sheetname "")
			)
			(fill
				(thermal_gap 0.5)
				(thermal_bridge_width 0.5)
				(island_removal_mode 0)
			)
			(polygon
				(pts
					(xy 273.814032 -18.2499) (xy 273.306032 -18.2499) (xy 273.306032 -17.2593) (xy 273.814032 -17.2593)
				)
			)
		)
		(zone
			(layer "B.Cu")
			(hatch none 0.5)
			(connect_pads
				(clearance 0)
			)
			(min_thickness 0.25)
			(keepout
				(tracks allowed)
				(vias not_allowed)
				(pads allowed)
				(copperpour not_allowed)
				(footprints allowed)
			)
			(placement
				(enabled no)
				(sheetname "")
			)
			(fill
				(thermal_gap 0.5)
				(thermal_bridge_width 0.5)
				(island_removal_mode 0)
			)
			(polygon
				(pts
					(xy 273.814032 -18.2499) (xy 273.306032 -18.2499) (xy 273.306032 -17.2593) (xy 273.814032 -17.2593)
				)
			)
		)
	)
	(footprint ""
		(layer "B.Cu")
		(at 361.444794 -43.194986 -90)
		(property "Reference" "R2T33"
			(at 0 0 90)
			(layer "B.SilkS")
			(hide yes)
			(effects
				(font
					(size 1.27 1.27)
				)
				(justify mirror)
			)
		)
		(property "Value" ""
			(at 0 0 90)
			(layer "B.Fab")
			(effects
				(font
					(size 1.27 1.27)
				)
				(justify mirror)
			)
		)
		(duplicate_pad_numbers_are_jumpers no)
		(fp_poly
			(pts
				(xy 0.2794 -0.1016) (xy -0.2794 -0.1016) (xy -0.2794 0.9906) (xy 0.2794 0.9906)
			)
			(stroke
				(width 0)
				(type default)
			)
			(fill no)
			(layer "B.CrtYd")
		)
		(fp_line
			(start -0.2794 0.9906)
			(end -0.2794 -0.1016)
			(stroke
				(width 0.1)
				(type default)
			)
			(layer "B.Fab")
		)
		(fp_line
			(start 0.2794 0.9906)
			(end -0.2794 0.9906)
			(stroke
				(width 0.1)
				(type default)
			)
			(layer "B.Fab")
		)
		(fp_line
			(start -0.2794 -0.1016)
			(end 0.2794 -0.1016)
			(stroke
				(width 0.1)
				(type default)
			)
			(layer "B.Fab")
		)
		(fp_line
			(start 0.2794 -0.1016)
			(end 0.2794 0.9906)
			(stroke
				(width 0.1)
				(type default)
			)
			(layer "B.Fab")
		)
		(pad "1" smd rect
			(at 0 0 90)
			(size 0.508 0.508)
			(layers "B.Cu" "B.Mask" "B.Paste")
			(net "FM_CPU_ERR1_LVT3_K_N")
		)
		(pad "2" smd rect
			(at 0 0.889 90)
			(size 0.508 0.508)
			(layers "B.Cu" "B.Mask" "B.Paste")
			(net "FM_CPU_ERR1_LVT3_N")
		)
		(zone
			(layer "B.Cu")
			(hatch none 0.5)
			(connect_pads
				(clearance 0)
			)
			(min_thickness 0.25)
			(keepout
				(tracks not_allowed)
				(vias allowed)
				(pads allowed)
				(copperpour not_allowed)
				(footprints allowed)
			)
			(placement
				(enabled no)
				(sheetname "")
			)
			(fill
				(thermal_gap 0.5)
				(thermal_bridge_width 0.5)
				(island_removal_mode 0)
			)
			(polygon
				(pts
					(xy 360.809794 -42.940986) (xy 360.809794 -43.448986) (xy 361.190794 -43.448986) (xy 361.190794 -42.940986)
				)
			)
		)
		(zone
			(layer "B.Cu")
			(hatch none 0.5)
			(connect_pads
				(clearance 0)
			)
			(min_thickness 0.25)
			(keepout
				(tracks allowed)
				(vias not_allowed)
				(pads allowed)
				(copperpour not_allowed)
				(footprints allowed)
			)
			(placement
				(enabled no)
				(sheetname "")
			)
			(fill
				(thermal_gap 0.5)
				(thermal_bridge_width 0.5)
				(island_removal_mode 0)
			)
			(polygon
				(pts
					(xy 361.190794 -42.940986) (xy 361.190794 -43.448986) (xy 360.809794 -43.448986) (xy 360.809794 -42.940986)
				)
			)
		)
	)
	(footprint ""
		(layer "B.Cu")
		(at 33.5407 -69.4182 90)
		(property "Reference" "C1D15"
			(at 0 0 90)
			(layer "B.SilkS")
			(hide yes)
			(effects
				(font
					(size 1.27 1.27)
				)
				(justify mirror)
			)
		)
		(property "Value" "*"
			(at -1.1811 -2.8194 90)
			(unlocked yes)
			(layer "B.Fab")
			(hide yes)
			(effects
				(font
					(size 1.27 1.016)
					(thickness 0.1524)
				)
				(justify mirror)
			)
		)
		(property "Device Type" "SC1U10V2KX-4-GP_SMD-BCG6-SC1U1A"
			(at -1.1811 -4.3434 90)
			(unlocked yes)
			(layer "B.Fab")
			(hide yes)
			(effects
				(font
					(size 1.27 1.016)
					(thickness 0.1524)
				)
				(justify mirror)
			)
		)
		(duplicate_pad_numbers_are_jumpers no)
		(fp_rect
			(start 0.4318 0.9525)
			(end -0.4318 -0.9525)
			(stroke
				(width 0)
				(type default)
			)
			(fill no)
			(layer "B.CrtYd")
		)
		(fp_rect
			(start 0.4318 0.9525)
			(end -0.4318 -0.9525)
			(stroke
				(width 0)
				(type default)
			)
			(fill no)
			(layer "B.Fab")
		)
		(pad "1" smd custom
			(at 0 -0.4445 270)
			(size 0.1524 0.1524)
			(layers "B.Cu" "B.Mask" "B.Paste")
			(net "P5V_STBY")
			(options
				(clearance outline)
				(anchor circle)
			)
			(primitives
				(gr_poly
					(pts
						(arc
							(start 0.3048 0.2032)
							(mid 0.275042 0.275042)
							(end 0.2032 0.3048)
						)
						(arc
							(start -0.2032 0.3048)
							(mid -0.275042 0.275042)
							(end -0.3048 0.2032)
						)
						(arc
							(start -0.3048 -0.2032)
							(mid -0.275042 -0.275042)
							(end -0.2032 -0.3048)
						)
						(arc
							(start 0.2032 -0.3048)
							(mid 0.275042 -0.275042)
							(end 0.3048 -0.2032)
						)
					)
					(width 0)
					(fill yes)
				)
			)
		)
		(pad "2" smd custom
			(at 0 0.4445 270)
			(size 0.1524 0.1524)
			(layers "B.Cu" "B.Mask" "B.Paste")
			(net "GND")
			(options
				(clearance outline)
				(anchor circle)
			)
			(primitives
				(gr_poly
					(pts
						(arc
							(start 0.3048 0.2032)
							(mid 0.275042 0.275042)
							(end 0.2032 0.3048)
						)
						(arc
							(start -0.2032 0.3048)
							(mid -0.275042 0.275042)
							(end -0.3048 0.2032)
						)
						(arc
							(start -0.3048 -0.2032)
							(mid -0.275042 -0.275042)
							(end -0.2032 -0.3048)
						)
						(arc
							(start 0.2032 -0.3048)
							(mid 0.275042 -0.275042)
							(end 0.3048 -0.2032)
						)
					)
					(width 0)
					(fill yes)
				)
			)
		)
	)
	(footprint ""
		(layer "B.Cu")
		(at 431.2412 -22.5298 180)
		(property "Reference" "R1U24"
			(at 0 0 0)
			(layer "B.SilkS")
			(hide yes)
			(effects
				(font
					(size 1.27 1.27)
				)
				(justify mirror)
			)
		)
		(property "Value" ""
			(at 0 0 0)
			(layer "B.Fab")
			(effects
				(font
					(size 1.27 1.27)
				)
				(justify mirror)
			)
		)
		(duplicate_pad_numbers_are_jumpers no)
		(fp_poly
			(pts
				(xy 0.2794 -0.1016) (xy -0.2794 -0.1016) (xy -0.2794 0.9906) (xy 0.2794 0.9906)
			)
			(stroke
				(width 0)
				(type default)
			)
			(fill no)
			(layer "B.CrtYd")
		)
		(fp_line
			(start 0.2794 0.9906)
			(end -0.2794 0.9906)
			(stroke
				(width 0.1)
				(type default)
			)
			(layer "B.Fab")
		)
		(fp_line
			(start 0.2794 -0.1016)
			(end 0.2794 0.9906)
			(stroke
				(width 0.1)
				(type default)
			)
			(layer "B.Fab")
		)
		(fp_line
			(start -0.2794 0.9906)
			(end -0.2794 -0.1016)
			(stroke
				(width 0.1)
				(type default)
			)
			(layer "B.Fab")
		)
		(fp_line
			(start -0.2794 -0.1016)
			(end 0.2794 -0.1016)
			(stroke
				(width 0.1)
				(type default)
			)
			(layer "B.Fab")
		)
		(pad "1" smd rect
			(at 0 0)
			(size 0.508 0.508)
			(layers "B.Cu" "B.Mask" "B.Paste")
			(net "P3V3_STBY")
		)
		(pad "2" smd rect
			(at 0 0.889)
			(size 0.508 0.508)
			(layers "B.Cu" "B.Mask" "B.Paste")
			(net "FM_BOARD_SKU_ID2")
		)
		(zone
			(layer "B.Cu")
			(hatch none 0.5)
			(connect_pads
				(clearance 0)
			)
			(min_thickness 0.25)
			(keepout
				(tracks not_allowed)
				(vias allowed)
				(pads allowed)
				(copperpour not_allowed)
				(footprints allowed)
			)
			(placement
				(enabled no)
				(sheetname "")
			)
			(fill
				(thermal_gap 0.5)
				(thermal_bridge_width 0.5)
				(island_removal_mode 0)
			)
			(polygon
				(pts
					(xy 430.9872 -23.1648) (xy 431.4952 -23.1648) (xy 431.4952 -22.7838) (xy 430.9872 -22.7838)
				)
			)
		)
		(zone
			(layer "B.Cu")
			(hatch none 0.5)
			(connect_pads
				(clearance 0)
			)
			(min_thickness 0.25)
			(keepout
				(tracks allowed)
				(vias not_allowed)
				(pads allowed)
				(copperpour not_allowed)
				(footprints allowed)
			)
			(placement
				(enabled no)
				(sheetname "")
			)
			(fill
				(thermal_gap 0.5)
				(thermal_bridge_width 0.5)
				(island_removal_mode 0)
			)
			(polygon
				(pts
					(xy 430.9872 -22.7838) (xy 431.4952 -22.7838) (xy 431.4952 -23.1648) (xy 430.9872 -23.1648)
				)
			)
		)
	)
	(footprint ""
		(layer "B.Cu")
		(at 444.91275 -29.6164)
		(property "Reference" "C25W12"
			(at 0.8382 -0.67818 0)
			(unlocked yes)
			(layer "B.SilkS")
			(effects
				(font
					(size 0.4064 0.254)
					(thickness 0.1524)
				)
				(justify left mirror)
			)
		)
		(property "Value" ""
			(at 0 0 0)
			(layer "B.Fab")
			(effects
				(font
					(size 1.27 1.27)
				)
				(justify mirror)
			)
		)
		(duplicate_pad_numbers_are_jumpers no)
		(fp_poly
			(pts
				(xy -0.3048 -0.1016) (xy -0.3048 0.9906) (xy 0.3048 0.9906) (xy 0.3048 -0.1016)
			)
			(stroke
				(width 0)
				(type default)
			)
			(fill no)
			(layer "B.CrtYd")
		)
		(fp_line
			(start -0.3048 -0.1016)
			(end 0.3048 -0.1016)
			(stroke
				(width 0.1)
				(type default)
			)
			(layer "B.Fab")
		)
		(fp_line
			(start -0.3048 0.9906)
			(end -0.3048 -0.1016)
			(stroke
				(width 0.1)
				(type default)
			)
			(layer "B.Fab")
		)
		(fp_line
			(start 0.3048 -0.1016)
			(end 0.3048 0.9906)
			(stroke
				(width 0.1)
				(type default)
			)
			(layer "B.Fab")
		)
		(fp_line
			(start 0.3048 0.9906)
			(end -0.3048 0.9906)
			(stroke
				(width 0.1)
				(type default)
			)
			(layer "B.Fab")
		)
		(pad "1" smd rect
			(at 0 0 180)
			(size 0.508 0.508)
			(layers "B.Cu" "B.Mask" "B.Paste")
			(net "BMC_M_VREFCA")
		)
		(pad "2" smd rect
			(at 0 0.889 180)
			(size 0.508 0.508)
			(layers "B.Cu" "B.Mask" "B.Paste")
			(net "GND")
		)
		(zone
			(layer "B.Cu")
			(hatch none 0.5)
			(connect_pads
				(clearance 0)
			)
			(min_thickness 0.25)
			(keepout
				(tracks allowed)
				(vias not_allowed)
				(pads allowed)
				(copperpour not_allowed)
				(footprints allowed)
			)
			(placement
				(enabled no)
				(sheetname "")
			)
			(fill
				(thermal_gap 0.5)
				(thermal_bridge_width 0.5)
				(island_removal_mode 0)
			)
			(polygon
				(pts
					(xy 445.16675 -29.3624) (xy 444.65875 -29.3624) (xy 444.65875 -28.9814) (xy 445.16675 -28.9814)
				)
			)
		)
		(zone
			(layer "B.Cu")
			(hatch none 0.5)
			(connect_pads
				(clearance 0)
			)
			(min_thickness 0.25)
			(keepout
				(tracks not_allowed)
				(vias allowed)
				(pads allowed)
				(copperpour not_allowed)
				(footprints allowed)
			)
			(placement
				(enabled no)
				(sheetname "")
			)
			(fill
				(thermal_gap 0.5)
				(thermal_bridge_width 0.5)
				(island_removal_mode 0)
			)
			(polygon
				(pts
					(xy 445.16675 -28.9814) (xy 444.65875 -28.9814) (xy 444.65875 -29.3624) (xy 445.16675 -29.3624)
				)
			)
		)
	)
	(footprint ""
		(layer "B.Cu")
		(at 447.14668 -64.752982 180)
		(property "Reference" "C2P11"
			(at 0 0 0)
			(layer "B.SilkS")
			(hide yes)
			(effects
				(font
					(size 1.27 1.27)
				)
				(justify mirror)
			)
		)
		(property "Value" ""
			(at 0 0 0)
			(layer "B.Fab")
			(effects
				(font
					(size 1.27 1.27)
				)
				(justify mirror)
			)
		)
		(duplicate_pad_numbers_are_jumpers no)
		(fp_poly
			(pts
				(xy -0.3048 -0.1016) (xy -0.3048 0.9906) (xy 0.3048 0.9906) (xy 0.3048 -0.1016)
			)
			(stroke
				(width 0)
				(type default)
			)
			(fill no)
			(layer "B.CrtYd")
		)
		(fp_line
			(start 0.3048 0.9906)
			(end -0.3048 0.9906)
			(stroke
				(width 0.1)
				(type default)
			)
			(layer "B.Fab")
		)
		(fp_line
			(start 0.3048 -0.1016)
			(end 0.3048 0.9906)
			(stroke
				(width 0.1)
				(type default)
			)
			(layer "B.Fab")
		)
		(fp_line
			(start -0.3048 0.9906)
			(end -0.3048 -0.1016)
			(stroke
				(width 0.1)
				(type default)
			)
			(layer "B.Fab")
		)
		(fp_line
			(start -0.3048 -0.1016)
			(end 0.3048 -0.1016)
			(stroke
				(width 0.1)
				(type default)
			)
			(layer "B.Fab")
		)
		(pad "1" smd rect
			(at 0 0)
			(size 0.508 0.508)
			(layers "B.Cu" "B.Mask" "B.Paste")
			(net "P12V_STBY")
		)
		(pad "2" smd rect
			(at 0 0.889)
			(size 0.508 0.508)
			(layers "B.Cu" "B.Mask" "B.Paste")
			(net "GND")
		)
		(zone
			(layer "B.Cu")
			(hatch none 0.5)
			(connect_pads
				(clearance 0)
			)
			(min_thickness 0.25)
			(keepout
				(tracks not_allowed)
				(vias allowed)
				(pads allowed)
				(copperpour not_allowed)
				(footprints allowed)
			)
			(placement
				(enabled no)
				(sheetname "")
			)
			(fill
				(thermal_gap 0.5)
				(thermal_bridge_width 0.5)
				(island_removal_mode 0)
			)
			(polygon
				(pts
					(xy 446.89268 -65.387982) (xy 447.40068 -65.387982) (xy 447.40068 -65.006982) (xy 446.89268 -65.006982)
				)
			)
		)
		(zone
			(layer "B.Cu")
			(hatch none 0.5)
			(connect_pads
				(clearance 0)
			)
			(min_thickness 0.25)
			(keepout
				(tracks allowed)
				(vias not_allowed)
				(pads allowed)
				(copperpour not_allowed)
				(footprints allowed)
			)
			(placement
				(enabled no)
				(sheetname "")
			)
			(fill
				(thermal_gap 0.5)
				(thermal_bridge_width 0.5)
				(island_removal_mode 0)
			)
			(polygon
				(pts
					(xy 446.89268 -65.006982) (xy 447.40068 -65.006982) (xy 447.40068 -65.387982) (xy 446.89268 -65.387982)
				)
			)
		)
	)
	(footprint ""
		(layer "B.Cu")
		(at 328.041 -55.626 -90)
		(property "Reference" "R4R6"
			(at 0 0 90)
			(layer "B.SilkS")
			(hide yes)
			(effects
				(font
					(size 1.27 1.27)
				)
				(justify mirror)
			)
		)
		(property "Value" ""
			(at 0 0 90)
			(layer "B.Fab")
			(effects
				(font
					(size 1.27 1.27)
				)
				(justify mirror)
			)
		)
		(duplicate_pad_numbers_are_jumpers no)
		(fp_poly
			(pts
				(xy 0.2794 -0.1016) (xy -0.2794 -0.1016) (xy -0.2794 0.9906) (xy 0.2794 0.9906)
			)
			(stroke
				(width 0)
				(type default)
			)
			(fill no)
			(layer "B.CrtYd")
		)
		(fp_line
			(start -0.2794 0.9906)
			(end -0.2794 -0.1016)
			(stroke
				(width 0.1)
				(type default)
			)
			(layer "B.Fab")
		)
		(fp_line
			(start 0.2794 0.9906)
			(end -0.2794 0.9906)
			(stroke
				(width 0.1)
				(type default)
			)
			(layer "B.Fab")
		)
		(fp_line
			(start -0.2794 -0.1016)
			(end 0.2794 -0.1016)
			(stroke
				(width 0.1)
				(type default)
			)
			(layer "B.Fab")
		)
		(fp_line
			(start 0.2794 -0.1016)
			(end 0.2794 0.9906)
			(stroke
				(width 0.1)
				(type default)
			)
			(layer "B.Fab")
		)
		(pad "1" smd rect
			(at 0 0 90)
			(size 0.508 0.508)
			(layers "B.Cu" "B.Mask" "B.Paste")
			(net "JTAG_MCP_CPU0_TDI_R")
		)
		(pad "2" smd rect
			(at 0 0.889 90)
			(size 0.508 0.508)
			(layers "B.Cu" "B.Mask" "B.Paste")
			(net "JTAG_MCP_CPU0_TDI")
		)
		(zone
			(layer "B.Cu")
			(hatch none 0.5)
			(connect_pads
				(clearance 0)
			)
			(min_thickness 0.25)
			(keepout
				(tracks not_allowed)
				(vias allowed)
				(pads allowed)
				(copperpour not_allowed)
				(footprints allowed)
			)
			(placement
				(enabled no)
				(sheetname "")
			)
			(fill
				(thermal_gap 0.5)
				(thermal_bridge_width 0.5)
				(island_removal_mode 0)
			)
			(polygon
				(pts
					(xy 327.406 -55.372) (xy 327.406 -55.88) (xy 327.787 -55.88) (xy 327.787 -55.372)
				)
			)
		)
		(zone
			(layer "B.Cu")
			(hatch none 0.5)
			(connect_pads
				(clearance 0)
			)
			(min_thickness 0.25)
			(keepout
				(tracks allowed)
				(vias not_allowed)
				(pads allowed)
				(copperpour not_allowed)
				(footprints allowed)
			)
			(placement
				(enabled no)
				(sheetname "")
			)
			(fill
				(thermal_gap 0.5)
				(thermal_bridge_width 0.5)
				(island_removal_mode 0)
			)
			(polygon
				(pts
					(xy 327.787 -55.372) (xy 327.787 -55.88) (xy 327.406 -55.88) (xy 327.406 -55.372)
				)
			)
		)
	)
	(footprint ""
		(layer "B.Cu")
		(at 454.787 -142.0114)
		(property "Reference" "C9A6"
			(at 0 0 0)
			(layer "B.SilkS")
			(hide yes)
			(effects
				(font
					(size 1.27 1.27)
				)
				(justify mirror)
			)
		)
		(property "Value" ""
			(at 0 0 0)
			(layer "B.Fab")
			(effects
				(font
					(size 1.27 1.27)
				)
				(justify mirror)
			)
		)
		(duplicate_pad_numbers_are_jumpers no)
		(fp_poly
			(pts
				(xy -0.3048 -0.1016) (xy -0.3048 0.9906) (xy 0.3048 0.9906) (xy 0.3048 -0.1016)
			)
			(stroke
				(width 0)
				(type default)
			)
			(fill no)
			(layer "B.CrtYd")
		)
		(fp_line
			(start -0.3048 -0.1016)
			(end 0.3048 -0.1016)
			(stroke
				(width 0.1)
				(type default)
			)
			(layer "B.Fab")
		)
		(fp_line
			(start -0.3048 0.9906)
			(end -0.3048 -0.1016)
			(stroke
				(width 0.1)
				(type default)
			)
			(layer "B.Fab")
		)
		(fp_line
			(start 0.3048 -0.1016)
			(end 0.3048 0.9906)
			(stroke
				(width 0.1)
				(type default)
			)
			(layer "B.Fab")
		)
		(fp_line
			(start 0.3048 0.9906)
			(end -0.3048 0.9906)
			(stroke
				(width 0.1)
				(type default)
			)
			(layer "B.Fab")
		)
		(pad "1" smd rect
			(at 0 0 180)
			(size 0.508 0.508)
			(layers "B.Cu" "B.Mask" "B.Paste")
			(net "P1V05_PCH_STBY")
		)
		(pad "2" smd rect
			(at 0 0.889 180)
			(size 0.508 0.508)
			(layers "B.Cu" "B.Mask" "B.Paste")
			(net "GND")
		)
		(zone
			(layer "B.Cu")
			(hatch none 0.5)
			(connect_pads
				(clearance 0)
			)
			(min_thickness 0.25)
			(keepout
				(tracks allowed)
				(vias not_allowed)
				(pads allowed)
				(copperpour not_allowed)
				(footprints allowed)
			)
			(placement
				(enabled no)
				(sheetname "")
			)
			(fill
				(thermal_gap 0.5)
				(thermal_bridge_width 0.5)
				(island_removal_mode 0)
			)
			(polygon
				(pts
					(xy 455.041 -141.7574) (xy 454.533 -141.7574) (xy 454.533 -141.3764) (xy 455.041 -141.3764)
				)
			)
		)
		(zone
			(layer "B.Cu")
			(hatch none 0.5)
			(connect_pads
				(clearance 0)
			)
			(min_thickness 0.25)
			(keepout
				(tracks not_allowed)
				(vias allowed)
				(pads allowed)
				(copperpour not_allowed)
				(footprints allowed)
			)
			(placement
				(enabled no)
				(sheetname "")
			)
			(fill
				(thermal_gap 0.5)
				(thermal_bridge_width 0.5)
				(island_removal_mode 0)
			)
			(polygon
				(pts
					(xy 455.041 -141.3764) (xy 454.533 -141.3764) (xy 454.533 -141.7574) (xy 455.041 -141.7574)
				)
			)
		)
	)
	(footprint ""
		(layer "B.Cu")
		(at 479.11766 -27.70632 180)
		(property "Reference" "C2T18"
			(at 0 0 0)
			(layer "B.SilkS")
			(hide yes)
			(effects
				(font
					(size 1.27 1.27)
				)
				(justify mirror)
			)
		)
		(property "Value" ""
			(at 0 0 0)
			(layer "B.Fab")
			(effects
				(font
					(size 1.27 1.27)
				)
				(justify mirror)
			)
		)
		(duplicate_pad_numbers_are_jumpers no)
		(fp_poly
			(pts
				(xy -0.3048 -0.1016) (xy -0.3048 0.9906) (xy 0.3048 0.9906) (xy 0.3048 -0.1016)
			)
			(stroke
				(width 0)
				(type default)
			)
			(fill no)
			(layer "B.CrtYd")
		)
		(fp_line
			(start 0.3048 0.9906)
			(end -0.3048 0.9906)
			(stroke
				(width 0.1)
				(type default)
			)
			(layer "B.Fab")
		)
		(fp_line
			(start 0.3048 -0.1016)
			(end 0.3048 0.9906)
			(stroke
				(width 0.1)
				(type default)
			)
			(layer "B.Fab")
		)
		(fp_line
			(start -0.3048 0.9906)
			(end -0.3048 -0.1016)
			(stroke
				(width 0.1)
				(type default)
			)
			(layer "B.Fab")
		)
		(fp_line
			(start -0.3048 -0.1016)
			(end 0.3048 -0.1016)
			(stroke
				(width 0.1)
				(type default)
			)
			(layer "B.Fab")
		)
		(pad "1" smd rect
			(at 0 0)
			(size 0.508 0.508)
			(layers "B.Cu" "B.Mask" "B.Paste")
			(net "P3V3_STBY_MNG_CPU")
		)
		(pad "2" smd rect
			(at 0 0.889)
			(size 0.508 0.508)
			(layers "B.Cu" "B.Mask" "B.Paste")
			(net "GND")
		)
		(zone
			(layer "B.Cu")
			(hatch none 0.5)
			(connect_pads
				(clearance 0)
			)
			(min_thickness 0.25)
			(keepout
				(tracks not_allowed)
				(vias allowed)
				(pads allowed)
				(copperpour not_allowed)
				(footprints allowed)
			)
			(placement
				(enabled no)
				(sheetname "")
			)
			(fill
				(thermal_gap 0.5)
				(thermal_bridge_width 0.5)
				(island_removal_mode 0)
			)
			(polygon
				(pts
					(xy 478.86366 -28.34132) (xy 479.37166 -28.34132) (xy 479.37166 -27.96032) (xy 478.86366 -27.96032)
				)
			)
		)
		(zone
			(layer "B.Cu")
			(hatch none 0.5)
			(connect_pads
				(clearance 0)
			)
			(min_thickness 0.25)
			(keepout
				(tracks allowed)
				(vias not_allowed)
				(pads allowed)
				(copperpour not_allowed)
				(footprints allowed)
			)
			(placement
				(enabled no)
				(sheetname "")
			)
			(fill
				(thermal_gap 0.5)
				(thermal_bridge_width 0.5)
				(island_removal_mode 0)
			)
			(polygon
				(pts
					(xy 478.86366 -27.96032) (xy 479.37166 -27.96032) (xy 479.37166 -28.34132) (xy 478.86366 -28.34132)
				)
			)
		)
	)
	(footprint ""
		(layer "B.Cu")
		(at 448.544188 -37.032692 90)
		(property "Reference" "R25W38"
			(at 0 0 90)
			(layer "B.SilkS")
			(hide yes)
			(effects
				(font
					(size 1.27 1.27)
				)
				(justify mirror)
			)
		)
		(property "Value" "*"
			(at -0.064008 -4.108196 90)
			(unlocked yes)
			(layer "B.Fab")
			(hide yes)
			(effects
				(font
					(size 1.27 1.016)
					(thickness 0.1524)
				)
				(justify mirror)
			)
		)
		(property "Device Type" "120R2F-GP_RCL_GP-120R2F-GP,64.A"
			(at -0.064008 -5.632196 90)
			(unlocked yes)
			(layer "B.Fab")
			(hide yes)
			(effects
				(font
					(size 1.27 1.016)
					(thickness 0.1524)
				)
				(justify mirror)
			)
		)
		(duplicate_pad_numbers_are_jumpers no)
		(fp_line
			(start 0.508 -0.9398)
			(end 0.508 0.9398)
			(stroke
				(width 0.1524)
				(type default)
			)
			(layer "B.SilkS")
		)
		(fp_line
			(start -0.508 -0.9398)
			(end 0.508 -0.9398)
			(stroke
				(width 0.1524)
				(type default)
			)
			(layer "B.SilkS")
		)
		(fp_rect
			(start 0.508 0.9398)
			(end -0.508 -0.9398)
			(stroke
				(width 0)
				(type default)
			)
			(fill no)
			(layer "B.CrtYd")
		)
		(fp_rect
			(start 0.508 0.9398)
			(end -0.508 -0.9398)
			(stroke
				(width 0)
				(type default)
			)
			(fill no)
			(layer "B.Fab")
		)
		(pad "1" smd custom
			(at 0 -0.4445 270)
			(size 0.1397 0.1397)
			(layers "B.Cu" "B.Mask" "B.Paste")
			(net "BMC_M_A0")
			(options
				(clearance outline)
				(anchor circle)
			)
			(primitives
				(gr_poly
					(pts
						(arc
							(start -0.1778 0.2794)
							(mid -0.249642 0.249642)
							(end -0.2794 0.1778)
						)
						(arc
							(start -0.2794 -0.1778)
							(mid -0.249642 -0.249642)
							(end -0.1778 -0.2794)
						)
						(arc
							(start 0.1778 -0.2794)
							(mid 0.249642 -0.249642)
							(end 0.2794 -0.1778)
						)
						(arc
							(start 0.2794 0.1778)
							(mid 0.249642 0.249642)
							(end 0.1778 0.2794)
						)
					)
					(width 0)
					(fill yes)
				)
			)
		)
		(pad "2" smd custom
			(at 0 0.4445 270)
			(size 0.1397 0.1397)
			(layers "B.Cu" "B.Mask" "B.Paste")
			(net "P1V2_AUX_BMC")
			(options
				(clearance outline)
				(anchor circle)
			)
			(primitives
				(gr_poly
					(pts
						(arc
							(start -0.1778 0.2794)
							(mid -0.249642 0.249642)
							(end -0.2794 0.1778)
						)
						(arc
							(start -0.2794 -0.1778)
							(mid -0.249642 -0.249642)
							(end -0.1778 -0.2794)
						)
						(arc
							(start 0.1778 -0.2794)
							(mid 0.249642 -0.249642)
							(end 0.2794 -0.1778)
						)
						(arc
							(start 0.2794 0.1778)
							(mid 0.249642 0.249642)
							(end 0.1778 0.2794)
						)
					)
					(width 0)
					(fill yes)
				)
			)
		)
	)
	(footprint ""
		(layer "B.Cu")
		(at 394.171932 -25.143714 180)
		(property "Reference" "C32W5"
			(at 0.8382 -0.67818 180)
			(unlocked yes)
			(layer "B.SilkS")
			(effects
				(font
					(size 0.4064 0.254)
					(thickness 0.1524)
				)
				(justify left mirror)
			)
		)
		(property "Value" ""
			(at 0 0 0)
			(layer "B.Fab")
			(effects
				(font
					(size 1.27 1.27)
				)
				(justify mirror)
			)
		)
		(duplicate_pad_numbers_are_jumpers no)
		(fp_poly
			(pts
				(xy -0.3048 -0.1016) (xy -0.3048 0.9906) (xy 0.3048 0.9906) (xy 0.3048 -0.1016)
			)
			(stroke
				(width 0)
				(type default)
			)
			(fill no)
			(layer "B.CrtYd")
		)
		(fp_line
			(start 0.3048 0.9906)
			(end -0.3048 0.9906)
			(stroke
				(width 0.1)
				(type default)
			)
			(layer "B.Fab")
		)
		(fp_line
			(start 0.3048 -0.1016)
			(end 0.3048 0.9906)
			(stroke
				(width 0.1)
				(type default)
			)
			(layer "B.Fab")
		)
		(fp_line
			(start -0.3048 0.9906)
			(end -0.3048 -0.1016)
			(stroke
				(width 0.1)
				(type default)
			)
			(layer "B.Fab")
		)
		(fp_line
			(start -0.3048 -0.1016)
			(end 0.3048 -0.1016)
			(stroke
				(width 0.1)
				(type default)
			)
			(layer "B.Fab")
		)
		(pad "1" smd rect
			(at 0 0)
			(size 0.508 0.508)
			(layers "B.Cu" "B.Mask" "B.Paste")
			(net "P1V8_M2")
		)
		(pad "2" smd rect
			(at 0 0.889)
			(size 0.508 0.508)
			(layers "B.Cu" "B.Mask" "B.Paste")
			(net "GND")
		)
		(zone
			(layer "B.Cu")
			(hatch none 0.5)
			(connect_pads
				(clearance 0)
			)
			(min_thickness 0.25)
			(keepout
				(tracks not_allowed)
				(vias allowed)
				(pads allowed)
				(copperpour not_allowed)
				(footprints allowed)
			)
			(placement
				(enabled no)
				(sheetname "")
			)
			(fill
				(thermal_gap 0.5)
				(thermal_bridge_width 0.5)
				(island_removal_mode 0)
			)
			(polygon
				(pts
					(xy 393.917932 -25.778714) (xy 394.425932 -25.778714) (xy 394.425932 -25.397714) (xy 393.917932 -25.397714)
				)
			)
		)
		(zone
			(layer "B.Cu")
			(hatch none 0.5)
			(connect_pads
				(clearance 0)
			)
			(min_thickness 0.25)
			(keepout
				(tracks allowed)
				(vias not_allowed)
				(pads allowed)
				(copperpour not_allowed)
				(footprints allowed)
			)
			(placement
				(enabled no)
				(sheetname "")
			)
			(fill
				(thermal_gap 0.5)
				(thermal_bridge_width 0.5)
				(island_removal_mode 0)
			)
			(polygon
				(pts
					(xy 393.917932 -25.397714) (xy 394.425932 -25.397714) (xy 394.425932 -25.778714) (xy 393.917932 -25.778714)
				)
			)
		)
	)
	(footprint ""
		(layer "B.Cu")
		(at 424.18 -141.986)
		(property "Reference" "C2L42"
			(at 0 0 0)
			(layer "B.SilkS")
			(hide yes)
			(effects
				(font
					(size 1.27 1.27)
				)
				(justify mirror)
			)
		)
		(property "Value" ""
			(at 0 0 0)
			(layer "B.Fab")
			(effects
				(font
					(size 1.27 1.27)
				)
				(justify mirror)
			)
		)
		(duplicate_pad_numbers_are_jumpers no)
		(fp_poly
			(pts
				(xy -0.3048 -0.1016) (xy -0.3048 0.9906) (xy 0.3048 0.9906) (xy 0.3048 -0.1016)
			)
			(stroke
				(width 0)
				(type default)
			)
			(fill no)
			(layer "B.CrtYd")
		)
		(fp_line
			(start -0.3048 -0.1016)
			(end 0.3048 -0.1016)
			(stroke
				(width 0.1)
				(type default)
			)
			(layer "B.Fab")
		)
		(fp_line
			(start -0.3048 0.9906)
			(end -0.3048 -0.1016)
			(stroke
				(width 0.1)
				(type default)
			)
			(layer "B.Fab")
		)
		(fp_line
			(start 0.3048 -0.1016)
			(end 0.3048 0.9906)
			(stroke
				(width 0.1)
				(type default)
			)
			(layer "B.Fab")
		)
		(fp_line
			(start 0.3048 0.9906)
			(end -0.3048 0.9906)
			(stroke
				(width 0.1)
				(type default)
			)
			(layer "B.Fab")
		)
		(pad "1" smd rect
			(at 0 0 180)
			(size 0.508 0.508)
			(layers "B.Cu" "B.Mask" "B.Paste")
			(net "SATA6G_P2_TX_C_DN")
		)
		(pad "2" smd rect
			(at 0 0.889 180)
			(size 0.508 0.508)
			(layers "B.Cu" "B.Mask" "B.Paste")
			(net "SATA6G_PCH_PCIE_UP_SATA_TXN<2>")
		)
		(zone
			(layer "B.Cu")
			(hatch none 0.5)
			(connect_pads
				(clearance 0)
			)
			(min_thickness 0.25)
			(keepout
				(tracks allowed)
				(vias not_allowed)
				(pads allowed)
				(copperpour not_allowed)
				(footprints allowed)
			)
			(placement
				(enabled no)
				(sheetname "")
			)
			(fill
				(thermal_gap 0.5)
				(thermal_bridge_width 0.5)
				(island_removal_mode 0)
			)
			(polygon
				(pts
					(xy 424.434 -141.732) (xy 423.926 -141.732) (xy 423.926 -141.351) (xy 424.434 -141.351)
				)
			)
		)
		(zone
			(layer "B.Cu")
			(hatch none 0.5)
			(connect_pads
				(clearance 0)
			)
			(min_thickness 0.25)
			(keepout
				(tracks not_allowed)
				(vias allowed)
				(pads allowed)
				(copperpour not_allowed)
				(footprints allowed)
			)
			(placement
				(enabled no)
				(sheetname "")
			)
			(fill
				(thermal_gap 0.5)
				(thermal_bridge_width 0.5)
				(island_removal_mode 0)
			)
			(polygon
				(pts
					(xy 424.434 -141.351) (xy 423.926 -141.351) (xy 423.926 -141.732) (xy 424.434 -141.732)
				)
			)
		)
	)
	(footprint ""
		(layer "B.Cu")
		(at 417.81222 -39.0398 180)
		(property "Reference" "C25W41"
			(at 0.8382 -0.67818 180)
			(unlocked yes)
			(layer "B.SilkS")
			(effects
				(font
					(size 0.4064 0.254)
					(thickness 0.1524)
				)
				(justify left mirror)
			)
		)
		(property "Value" ""
			(at 0 0 0)
			(layer "B.Fab")
			(effects
				(font
					(size 1.27 1.27)
				)
				(justify mirror)
			)
		)
		(duplicate_pad_numbers_are_jumpers no)
		(fp_poly
			(pts
				(xy -0.3048 -0.1016) (xy -0.3048 0.9906) (xy 0.3048 0.9906) (xy 0.3048 -0.1016)
			)
			(stroke
				(width 0)
				(type default)
			)
			(fill no)
			(layer "B.CrtYd")
		)
		(fp_line
			(start 0.3048 0.9906)
			(end -0.3048 0.9906)
			(stroke
				(width 0.1)
				(type default)
			)
			(layer "B.Fab")
		)
		(fp_line
			(start 0.3048 -0.1016)
			(end 0.3048 0.9906)
			(stroke
				(width 0.1)
				(type default)
			)
			(layer "B.Fab")
		)
		(fp_line
			(start -0.3048 0.9906)
			(end -0.3048 -0.1016)
			(stroke
				(width 0.1)
				(type default)
			)
			(layer "B.Fab")
		)
		(fp_line
			(start -0.3048 -0.1016)
			(end 0.3048 -0.1016)
			(stroke
				(width 0.1)
				(type default)
			)
			(layer "B.Fab")
		)
		(pad "1" smd rect
			(at 0 0)
			(size 0.508 0.508)
			(layers "B.Cu" "B.Mask" "B.Paste")
			(net "VCC_D_3V3")
		)
		(pad "2" smd rect
			(at 0 0.889)
			(size 0.508 0.508)
			(layers "B.Cu" "B.Mask" "B.Paste")
			(net "GND")
		)
		(zone
			(layer "B.Cu")
			(hatch none 0.5)
			(connect_pads
				(clearance 0)
			)
			(min_thickness 0.25)
			(keepout
				(tracks not_allowed)
				(vias allowed)
				(pads allowed)
				(copperpour not_allowed)
				(footprints allowed)
			)
			(placement
				(enabled no)
				(sheetname "")
			)
			(fill
				(thermal_gap 0.5)
				(thermal_bridge_width 0.5)
				(island_removal_mode 0)
			)
			(polygon
				(pts
					(xy 417.55822 -39.6748) (xy 418.06622 -39.6748) (xy 418.06622 -39.2938) (xy 417.55822 -39.2938)
				)
			)
		)
		(zone
			(layer "B.Cu")
			(hatch none 0.5)
			(connect_pads
				(clearance 0)
			)
			(min_thickness 0.25)
			(keepout
				(tracks allowed)
				(vias not_allowed)
				(pads allowed)
				(copperpour not_allowed)
				(footprints allowed)
			)
			(placement
				(enabled no)
				(sheetname "")
			)
			(fill
				(thermal_gap 0.5)
				(thermal_bridge_width 0.5)
				(island_removal_mode 0)
			)
			(polygon
				(pts
					(xy 417.55822 -39.2938) (xy 418.06622 -39.2938) (xy 418.06622 -39.6748) (xy 417.55822 -39.6748)
				)
			)
		)
	)
	(footprint ""
		(layer "B.Cu")
		(at 30.452568 -8.122412 90)
		(property "Reference" "C9U7"
			(at 0 0 90)
			(layer "B.SilkS")
			(hide yes)
			(effects
				(font
					(size 1.27 1.27)
				)
				(justify mirror)
			)
		)
		(property "Value" ""
			(at 0 0 90)
			(layer "B.Fab")
			(effects
				(font
					(size 1.27 1.27)
				)
				(justify mirror)
			)
		)
		(duplicate_pad_numbers_are_jumpers no)
		(fp_poly
			(pts
				(xy -0.3048 -0.1016) (xy -0.3048 0.9906) (xy 0.3048 0.9906) (xy 0.3048 -0.1016)
			)
			(stroke
				(width 0)
				(type default)
			)
			(fill no)
			(layer "B.CrtYd")
		)
		(fp_line
			(start 0.3048 -0.1016)
			(end 0.3048 0.9906)
			(stroke
				(width 0.1)
				(type default)
			)
			(layer "B.Fab")
		)
		(fp_line
			(start -0.3048 -0.1016)
			(end 0.3048 -0.1016)
			(stroke
				(width 0.1)
				(type default)
			)
			(layer "B.Fab")
		)
		(fp_line
			(start 0.3048 0.9906)
			(end -0.3048 0.9906)
			(stroke
				(width 0.1)
				(type default)
			)
			(layer "B.Fab")
		)
		(fp_line
			(start -0.3048 0.9906)
			(end -0.3048 -0.1016)
			(stroke
				(width 0.1)
				(type default)
			)
			(layer "B.Fab")
		)
		(pad "1" smd rect
			(at 0 0 270)
			(size 0.508 0.508)
			(layers "B.Cu" "B.Mask" "B.Paste")
			(net "M_H_VREF")
		)
		(pad "2" smd rect
			(at 0 0.889 270)
			(size 0.508 0.508)
			(layers "B.Cu" "B.Mask" "B.Paste")
			(net "GND")
		)
		(zone
			(layer "B.Cu")
			(hatch none 0.5)
			(connect_pads
				(clearance 0)
			)
			(min_thickness 0.25)
			(keepout
				(tracks allowed)
				(vias not_allowed)
				(pads allowed)
				(copperpour not_allowed)
				(footprints allowed)
			)
			(placement
				(enabled no)
				(sheetname "")
			)
			(fill
				(thermal_gap 0.5)
				(thermal_bridge_width 0.5)
				(island_removal_mode 0)
			)
			(polygon
				(pts
					(xy 30.706568 -8.376412) (xy 30.706568 -7.868412) (xy 31.087568 -7.868412) (xy 31.087568 -8.376412)
				)
			)
		)
		(zone
			(layer "B.Cu")
			(hatch none 0.5)
			(connect_pads
				(clearance 0)
			)
			(min_thickness 0.25)
			(keepout
				(tracks not_allowed)
				(vias allowed)
				(pads allowed)
				(copperpour not_allowed)
				(footprints allowed)
			)
			(placement
				(enabled no)
				(sheetname "")
			)
			(fill
				(thermal_gap 0.5)
				(thermal_bridge_width 0.5)
				(island_removal_mode 0)
			)
			(polygon
				(pts
					(xy 31.087568 -8.376412) (xy 31.087568 -7.868412) (xy 30.706568 -7.868412) (xy 30.706568 -8.376412)
				)
			)
		)
	)
	(footprint ""
		(layer "B.Cu")
		(at 29.699458 -24.824182 90)
		(property "Reference" "J9T1"
			(at 2.200148 39.261542 0)
			(unlocked yes)
			(layer "B.SilkS")
			(effects
				(font
					(size 0.7874 0.5842)
					(thickness 0.1524)
				)
				(justify left mirror)
			)
		)
		(property "Value" ""
			(at 0 0 90)
			(layer "B.Fab")
			(effects
				(font
					(size 1.27 1.27)
				)
				(justify mirror)
			)
		)
		(duplicate_pad_numbers_are_jumpers no)
		(fp_line
			(start 0.94996 -7.675118)
			(end -5.5499 -7.675118)
			(stroke
				(width 0.1524)
				(type default)
			)
			(layer "B.SilkS")
		)
		(fp_line
			(start -5.5499 -7.675118)
			(end -5.5499 -1.480058)
			(stroke
				(width 0.1524)
				(type default)
			)
			(layer "B.SilkS")
		)
		(fp_line
			(start 0.94996 -1.480058)
			(end 0.94996 -7.675118)
			(stroke
				(width 0.1524)
				(type default)
			)
			(layer "B.SilkS")
		)
		(fp_line
			(start -5.5499 128.130046)
			(end -5.5499 134.325106)
			(stroke
				(width 0.1524)
				(type default)
			)
			(layer "B.SilkS")
		)
		(fp_line
			(start 0.94996 134.325106)
			(end 0.94996 128.130046)
			(stroke
				(width 0.1524)
				(type default)
			)
			(layer "B.SilkS")
		)
		(fp_line
			(start -5.5499 134.325106)
			(end 0.94996 134.325106)
			(stroke
				(width 0.1524)
				(type default)
			)
			(layer "B.SilkS")
		)
		(fp_poly
			(pts
				(xy 2.984246 -0.461264) (xy 2.984246 0.554736) (xy 1.714246 0.046736)
			)
			(stroke
				(width 0)
				(type default)
			)
			(fill yes)
			(layer "B.SilkS")
		)
		(fp_poly
			(pts
				(xy 0.94996 -7.675118) (xy 0.94996 134.325106) (xy -5.5499 134.325106) (xy -5.5499 -7.675118)
			)
			(stroke
				(width 0)
				(type default)
			)
			(fill no)
			(layer "B.CrtYd")
		)
		(fp_line
			(start 0.94996 -7.675118)
			(end -5.5499 -7.675118)
			(stroke
				(width 0.1)
				(type default)
			)
			(layer "B.Fab")
		)
		(fp_line
			(start -5.5499 -7.675118)
			(end -5.5499 134.325106)
			(stroke
				(width 0.1)
				(type default)
			)
			(layer "B.Fab")
		)
		(fp_line
			(start 0.94996 134.325106)
			(end 0.94996 -7.675118)
			(stroke
				(width 0.1)
				(type default)
			)
			(layer "B.Fab")
		)
		(fp_line
			(start -5.5499 134.325106)
			(end 0.94996 134.325106)
			(stroke
				(width 0.1)
				(type default)
			)
			(layer "B.Fab")
		)
		(fp_poly
			(pts
				(xy 2.984246 -0.461264) (xy 2.984246 0.554736) (xy 1.714246 0.046736)
			)
			(stroke
				(width 0)
				(type default)
			)
			(fill yes)
			(layer "B.Fab")
		)
		(fp_text user "145"
			(at -6.181852 1.288542 0)
			(unlocked yes)
			(layer "B.SilkS")
			(effects
				(font
					(size 0.7874 0.5842)
					(thickness 0.1524)
				)
				(justify left mirror)
			)
		)
		(fp_text user "77"
			(at 0.930148 66.439542 0)
			(unlocked yes)
			(layer "B.SilkS")
			(effects
				(font
					(size 0.7874 0.5842)
					(thickness 0.1524)
				)
				(justify left mirror)
			)
		)
		(fp_text user "221"
			(at -5.419852 67.582542 0)
			(unlocked yes)
			(layer "B.SilkS")
			(effects
				(font
					(size 0.7874 0.5842)
					(thickness 0.1524)
				)
				(justify left mirror)
			)
		)
		(fp_text user "78"
			(at 0.930148 70.122542 0)
			(unlocked yes)
			(layer "B.SilkS")
			(effects
				(font
					(size 0.7874 0.5842)
					(thickness 0.1524)
				)
				(justify left mirror)
			)
		)
		(fp_text user "222"
			(at -6.054852 71.900542 0)
			(unlocked yes)
			(layer "B.SilkS")
			(effects
				(font
					(size 0.7874 0.5842)
					(thickness 0.1524)
				)
				(justify left mirror)
			)
		)
		(fp_text user "144"
			(at 1.692148 127.932942 0)
			(unlocked yes)
			(layer "B.SilkS")
			(effects
				(font
					(size 0.7874 0.5842)
					(thickness 0.1524)
				)
				(justify left mirror)
			)
		)
		(fp_text user "288"
			(at -6.181852 129.685542 0)
			(unlocked yes)
			(layer "B.SilkS")
			(effects
				(font
					(size 0.7874 0.5842)
					(thickness 0.1524)
				)
				(justify left mirror)
			)
		)
		(fp_text user "145"
			(at -3.234182 -1.478788 90)
			(unlocked yes)
			(layer "B.Fab")
			(effects
				(font
					(size 0.7874 0.5842)
					(thickness 0.1524)
				)
				(justify left mirror)
			)
		)
		(fp_text user "77"
			(at 0.575818 65.831212 90)
			(unlocked yes)
			(layer "B.Fab")
			(effects
				(font
					(size 0.7874 0.5842)
					(thickness 0.1524)
				)
				(justify left mirror)
			)
		)
		(fp_text user "221"
			(at -3.234182 65.831212 90)
			(unlocked yes)
			(layer "B.Fab")
			(effects
				(font
					(size 0.7874 0.5842)
					(thickness 0.1524)
				)
				(justify left mirror)
			)
		)
		(fp_text user "78"
			(at 0.575818 69.641212 90)
			(unlocked yes)
			(layer "B.Fab")
			(effects
				(font
					(size 0.7874 0.5842)
					(thickness 0.1524)
				)
				(justify left mirror)
			)
		)
		(fp_text user "222"
			(at -3.869182 69.641212 90)
			(unlocked yes)
			(layer "B.Fab")
			(effects
				(font
					(size 0.7874 0.5842)
					(thickness 0.1524)
				)
				(justify left mirror)
			)
		)
		(fp_text user "144"
			(at 0.575818 128.061212 90)
			(unlocked yes)
			(layer "B.Fab")
			(effects
				(font
					(size 0.7874 0.5842)
					(thickness 0.1524)
				)
				(justify left mirror)
			)
		)
		(fp_text user "288"
			(at -3.234182 128.061212 90)
			(unlocked yes)
			(layer "B.Fab")
			(effects
				(font
					(size 0.7874 0.5842)
					(thickness 0.1524)
				)
				(justify left mirror)
			)
		)
		(pad "" thru_hole circle
			(at -2.29997 -5.649976 270)
			(size 2.8194 2.8194)
			(drill 2.4384)
			(layers "*.Cu" "*.Mask")
			(remove_unused_layers no)
			(clearance 0.127)
			(thermal_gap 0.127)
		)
		(pad "" thru_hole oval
			(at -2.29997 68.90004 270)
			(size 2.8194 1.5748)
			(drill oval 2.4384 1.1938)
			(layers "*.Cu" "*.Mask")
			(remove_unused_layers no)
			(clearance 0.127)
			(thermal_gap 0.127)
		)
		(pad "" thru_hole circle
			(at -2.29997 132.299964 270)
			(size 2.8194 2.8194)
			(drill 2.4384)
			(layers "*.Cu" "*.Mask")
			(remove_unused_layers no)
			(clearance 0.127)
			(thermal_gap 0.127)
		)
		(pad "1" smd rect
			(at 0 0 270)
			(size 1.8034 0.508)
			(layers "B.Cu" "B.Mask" "B.Paste")
			(net "P12V_NVDIMM_GHJ")
		)
		(pad "2" smd rect
			(at 0 0.849884 270)
			(size 1.8034 0.508)
			(layers "B.Cu" "B.Mask" "B.Paste")
			(net "GND")
		)
		(pad "3" smd rect
			(at 0 1.700022 270)
			(size 1.8034 0.508)
			(layers "B.Cu" "B.Mask" "B.Paste")
			(net "M_G_DQ<4>")
		)
		(pad "4" smd rect
			(at 0 2.549906 270)
			(size 1.8034 0.508)
			(layers "B.Cu" "B.Mask" "B.Paste")
			(net "GND")
		)
		(pad "5" smd rect
			(at 0 3.400044 270)
			(size 1.8034 0.508)
			(layers "B.Cu" "B.Mask" "B.Paste")
			(net "M_G_DQ<0>")
		)
		(pad "6" smd rect
			(at 0 4.249928 270)
			(size 1.8034 0.508)
			(layers "B.Cu" "B.Mask" "B.Paste")
			(net "GND")
		)
		(pad "7" smd rect
			(at 0 5.100066 270)
			(size 1.8034 0.508)
			(layers "B.Cu" "B.Mask" "B.Paste")
			(net "M_G_DQS_DP<9>")
		)
		(pad "8" smd rect
			(at 0 5.94995 270)
			(size 1.8034 0.508)
			(layers "B.Cu" "B.Mask" "B.Paste")
			(net "M_G_DQS_DN<9>")
		)
		(pad "9" smd rect
			(at 0 6.800088 270)
			(size 1.8034 0.508)
			(layers "B.Cu" "B.Mask" "B.Paste")
			(net "GND")
		)
		(pad "10" smd rect
			(at 0 7.649972 270)
			(size 1.8034 0.508)
			(layers "B.Cu" "B.Mask" "B.Paste")
			(net "M_G_DQ<6>")
		)
		(pad "11" smd rect
			(at 0 8.50011 270)
			(size 1.8034 0.508)
			(layers "B.Cu" "B.Mask" "B.Paste")
			(net "GND")
		)
		(pad "12" smd rect
			(at 0 9.349994 270)
			(size 1.8034 0.508)
			(layers "B.Cu" "B.Mask" "B.Paste")
			(net "M_G_DQ<2>")
		)
		(pad "13" smd rect
			(at 0 10.199878 270)
			(size 1.8034 0.508)
			(layers "B.Cu" "B.Mask" "B.Paste")
			(net "GND")
		)
		(pad "14" smd rect
			(at 0 11.050016 270)
			(size 1.8034 0.508)
			(layers "B.Cu" "B.Mask" "B.Paste")
			(net "M_G_DQ<12>")
		)
		(pad "15" smd rect
			(at 0 11.8999 270)
			(size 1.8034 0.508)
			(layers "B.Cu" "B.Mask" "B.Paste")
			(net "GND")
		)
		(pad "16" smd rect
			(at 0 12.750038 270)
			(size 1.8034 0.508)
			(layers "B.Cu" "B.Mask" "B.Paste")
			(net "M_G_DQ<8>")
		)
		(pad "17" smd rect
			(at 0 13.599922 270)
			(size 1.8034 0.508)
			(layers "B.Cu" "B.Mask" "B.Paste")
			(net "GND")
		)
		(pad "18" smd rect
			(at 0 14.45006 270)
			(size 1.8034 0.508)
			(layers "B.Cu" "B.Mask" "B.Paste")
			(net "M_G_DQS_DP<10>")
		)
		(pad "19" smd rect
			(at 0 15.299944 270)
			(size 1.8034 0.508)
			(layers "B.Cu" "B.Mask" "B.Paste")
			(net "M_G_DQS_DN<10>")
		)
		(pad "20" smd rect
			(at 0 16.150082 270)
			(size 1.8034 0.508)
			(layers "B.Cu" "B.Mask" "B.Paste")
			(net "GND")
		)
		(pad "21" smd rect
			(at 0 16.999966 270)
			(size 1.8034 0.508)
			(layers "B.Cu" "B.Mask" "B.Paste")
			(net "M_G_DQ<14>")
		)
		(pad "22" smd rect
			(at 0 17.850104 270)
			(size 1.8034 0.508)
			(layers "B.Cu" "B.Mask" "B.Paste")
			(net "GND")
		)
		(pad "23" smd rect
			(at 0 18.699988 270)
			(size 1.8034 0.508)
			(layers "B.Cu" "B.Mask" "B.Paste")
			(net "M_G_DQ<10>")
		)
		(pad "24" smd rect
			(at 0 19.550126 270)
			(size 1.8034 0.508)
			(layers "B.Cu" "B.Mask" "B.Paste")
			(net "GND")
		)
		(pad "25" smd rect
			(at 0 20.40001 270)
			(size 1.8034 0.508)
			(layers "B.Cu" "B.Mask" "B.Paste")
			(net "M_G_DQ<20>")
		)
		(pad "26" smd rect
			(at 0 21.249894 270)
			(size 1.8034 0.508)
			(layers "B.Cu" "B.Mask" "B.Paste")
			(net "GND")
		)
		(pad "27" smd rect
			(at 0 22.100032 270)
			(size 1.8034 0.508)
			(layers "B.Cu" "B.Mask" "B.Paste")
			(net "M_G_DQ<16>")
		)
		(pad "28" smd rect
			(at 0 22.949916 270)
			(size 1.8034 0.508)
			(layers "B.Cu" "B.Mask" "B.Paste")
			(net "GND")
		)
		(pad "29" smd rect
			(at 0 23.800054 270)
			(size 1.8034 0.508)
			(layers "B.Cu" "B.Mask" "B.Paste")
			(net "M_G_DQS_DP<11>")
		)
		(pad "30" smd rect
			(at 0 24.649938 270)
			(size 1.8034 0.508)
			(layers "B.Cu" "B.Mask" "B.Paste")
			(net "M_G_DQS_DN<11>")
		)
		(pad "31" smd rect
			(at 0 25.500076 270)
			(size 1.8034 0.508)
			(layers "B.Cu" "B.Mask" "B.Paste")
			(net "GND")
		)
		(pad "32" smd rect
			(at 0 26.34996 270)
			(size 1.8034 0.508)
			(layers "B.Cu" "B.Mask" "B.Paste")
			(net "M_G_DQ<22>")
		)
		(pad "33" smd rect
			(at 0 27.200098 270)
			(size 1.8034 0.508)
			(layers "B.Cu" "B.Mask" "B.Paste")
			(net "GND")
		)
		(pad "34" smd rect
			(at 0 28.049982 270)
			(size 1.8034 0.508)
			(layers "B.Cu" "B.Mask" "B.Paste")
			(net "M_G_DQ<18>")
		)
		(pad "35" smd rect
			(at 0 28.90012 270)
			(size 1.8034 0.508)
			(layers "B.Cu" "B.Mask" "B.Paste")
			(net "GND")
		)
		(pad "36" smd rect
			(at 0 29.750004 270)
			(size 1.8034 0.508)
			(layers "B.Cu" "B.Mask" "B.Paste")
			(net "M_G_DQ<28>")
		)
		(pad "37" smd rect
			(at 0 30.599888 270)
			(size 1.8034 0.508)
			(layers "B.Cu" "B.Mask" "B.Paste")
			(net "GND")
		)
		(pad "38" smd rect
			(at 0 31.450026 270)
			(size 1.8034 0.508)
			(layers "B.Cu" "B.Mask" "B.Paste")
			(net "M_G_DQ<24>")
		)
		(pad "39" smd rect
			(at 0 32.29991 270)
			(size 1.8034 0.508)
			(layers "B.Cu" "B.Mask" "B.Paste")
			(net "GND")
		)
		(pad "40" smd rect
			(at 0 33.150048 270)
			(size 1.8034 0.508)
			(layers "B.Cu" "B.Mask" "B.Paste")
			(net "M_G_DQS_DP<12>")
		)
		(pad "41" smd rect
			(at 0 33.999932 270)
			(size 1.8034 0.508)
			(layers "B.Cu" "B.Mask" "B.Paste")
			(net "M_G_DQS_DN<12>")
		)
		(pad "42" smd rect
			(at 0 34.85007 270)
			(size 1.8034 0.508)
			(layers "B.Cu" "B.Mask" "B.Paste")
			(net "GND")
		)
		(pad "43" smd rect
			(at 0 35.699954 270)
			(size 1.8034 0.508)
			(layers "B.Cu" "B.Mask" "B.Paste")
			(net "M_G_DQ<30>")
		)
		(pad "44" smd rect
			(at 0 36.550092 270)
			(size 1.8034 0.508)
			(layers "B.Cu" "B.Mask" "B.Paste")
			(net "GND")
		)
		(pad "45" smd rect
			(at 0 37.399976 270)
			(size 1.8034 0.508)
			(layers "B.Cu" "B.Mask" "B.Paste")
			(net "M_G_DQ<26>")
		)
		(pad "46" smd rect
			(at 0 38.250114 270)
			(size 1.8034 0.508)
			(layers "B.Cu" "B.Mask" "B.Paste")
			(net "GND")
		)
		(pad "47" smd rect
			(at 0 39.099998 270)
			(size 1.8034 0.508)
			(layers "B.Cu" "B.Mask" "B.Paste")
			(net "M_G_ECC<4>")
		)
		(pad "48" smd rect
			(at 0 39.949882 270)
			(size 1.8034 0.508)
			(layers "B.Cu" "B.Mask" "B.Paste")
			(net "GND")
		)
		(pad "49" smd rect
			(at 0 40.80002 270)
			(size 1.8034 0.508)
			(layers "B.Cu" "B.Mask" "B.Paste")
			(net "M_G_ECC<0>")
		)
		(pad "50" smd rect
			(at 0 41.649904 270)
			(size 1.8034 0.508)
			(layers "B.Cu" "B.Mask" "B.Paste")
			(net "GND")
		)
		(pad "51" smd rect
			(at 0 42.500042 270)
			(size 1.8034 0.508)
			(layers "B.Cu" "B.Mask" "B.Paste")
			(net "M_G_DQS_DP<17>")
		)
		(pad "52" smd rect
			(at 0 43.349926 270)
			(size 1.8034 0.508)
			(layers "B.Cu" "B.Mask" "B.Paste")
			(net "M_G_DQS_DN<17>")
		)
		(pad "53" smd rect
			(at 0 44.200064 270)
			(size 1.8034 0.508)
			(layers "B.Cu" "B.Mask" "B.Paste")
			(net "GND")
		)
		(pad "54" smd rect
			(at 0 45.049948 270)
			(size 1.8034 0.508)
			(layers "B.Cu" "B.Mask" "B.Paste")
			(net "M_G_ECC<6>")
		)
		(pad "55" smd rect
			(at 0 45.900086 270)
			(size 1.8034 0.508)
			(layers "B.Cu" "B.Mask" "B.Paste")
			(net "GND")
		)
		(pad "56" smd rect
			(at 0 46.74997 270)
			(size 1.8034 0.508)
			(layers "B.Cu" "B.Mask" "B.Paste")
			(net "M_G_ECC<2>")
		)
		(pad "57" smd rect
			(at 0 47.600108 270)
			(size 1.8034 0.508)
			(layers "B.Cu" "B.Mask" "B.Paste")
			(net "GND")
		)
		(pad "58" smd rect
			(at 0 48.449992 270)
			(size 1.8034 0.508)
			(layers "B.Cu" "B.Mask" "B.Paste")
			(net "M_GHJ_RST_N")
		)
		(pad "59" smd rect
			(at 0 49.299876 270)
			(size 1.8034 0.508)
			(layers "B.Cu" "B.Mask" "B.Paste")
			(net "PVDDQ_GHJ")
		)
		(pad "60" smd rect
			(at 0 50.150014 270)
			(size 1.8034 0.508)
			(layers "B.Cu" "B.Mask" "B.Paste")
			(net "M_G_CKE<2>")
		)
		(pad "61" smd rect
			(at 0 50.999898 270)
			(size 1.8034 0.508)
			(layers "B.Cu" "B.Mask" "B.Paste")
			(net "PVDDQ_GHJ")
		)
		(pad "62" smd rect
			(at 0 51.850036 270)
			(size 1.8034 0.508)
			(layers "B.Cu" "B.Mask" "B.Paste")
			(net "M_G_ACT_N")
		)
		(pad "63" smd rect
			(at 0 52.69992 270)
			(size 1.8034 0.508)
			(layers "B.Cu" "B.Mask" "B.Paste")
			(net "M_G_BG<0>")
		)
		(pad "64" smd rect
			(at 0 53.550058 270)
			(size 1.8034 0.508)
			(layers "B.Cu" "B.Mask" "B.Paste")
			(net "PVDDQ_GHJ")
		)
		(pad "65" smd rect
			(at 0 54.399942 270)
			(size 1.8034 0.508)
			(layers "B.Cu" "B.Mask" "B.Paste")
			(net "M_G_MA<12>")
		)
		(pad "66" smd rect
			(at 0 55.25008 270)
			(size 1.8034 0.508)
			(layers "B.Cu" "B.Mask" "B.Paste")
			(net "M_G_MA<9>")
		)
		(pad "67" smd rect
			(at 0 56.099964 270)
			(size 1.8034 0.508)
			(layers "B.Cu" "B.Mask" "B.Paste")
			(net "PVDDQ_GHJ")
		)
		(pad "68" smd rect
			(at 0 56.950102 270)
			(size 1.8034 0.508)
			(layers "B.Cu" "B.Mask" "B.Paste")
			(net "M_G_MA<8>")
		)
		(pad "69" smd rect
			(at 0 57.799986 270)
			(size 1.8034 0.508)
			(layers "B.Cu" "B.Mask" "B.Paste")
			(net "M_G_MA<6>")
		)
		(pad "70" smd rect
			(at 0 58.650124 270)
			(size 1.8034 0.508)
			(layers "B.Cu" "B.Mask" "B.Paste")
			(net "PVDDQ_GHJ")
		)
		(pad "71" smd rect
			(at 0 59.500008 270)
			(size 1.8034 0.508)
			(layers "B.Cu" "B.Mask" "B.Paste")
			(net "M_G_MA<3>")
		)
		(pad "72" smd rect
			(at 0 60.349892 270)
			(size 1.8034 0.508)
			(layers "B.Cu" "B.Mask" "B.Paste")
			(net "M_G_MA<1>")
		)
		(pad "73" smd rect
			(at 0 61.20003 270)
			(size 1.8034 0.508)
			(layers "B.Cu" "B.Mask" "B.Paste")
			(net "PVDDQ_GHJ")
		)
		(pad "74" smd rect
			(at 0 62.049914 270)
			(size 1.8034 0.508)
			(layers "B.Cu" "B.Mask" "B.Paste")
			(net "M_G_CLK_DP<2>")
		)
		(pad "75" smd rect
			(at 0 62.900052 270)
			(size 1.8034 0.508)
			(layers "B.Cu" "B.Mask" "B.Paste")
			(net "M_G_CLK_DN<2>")
		)
		(pad "76" smd rect
			(at 0 63.749936 270)
			(size 1.8034 0.508)
			(layers "B.Cu" "B.Mask" "B.Paste")
			(net "PVDDQ_GHJ")
		)
		(pad "77" smd rect
			(at 0 64.600074 270)
			(size 1.8034 0.508)
			(layers "B.Cu" "B.Mask" "B.Paste")
			(net "PVTT_GHJ")
		)
		(pad "78" smd rect
			(at 0 70.550024 270)
			(size 1.8034 0.508)
			(layers "B.Cu" "B.Mask" "B.Paste")
			(net "FM_DIMM_EVENT_COD_N")
		)
		(pad "79" smd rect
			(at 0 71.399908 270)
			(size 1.8034 0.508)
			(layers "B.Cu" "B.Mask" "B.Paste")
			(net "M_G_MA<0>")
		)
		(pad "80" smd rect
			(at 0 72.250046 270)
			(size 1.8034 0.508)
			(layers "B.Cu" "B.Mask" "B.Paste")
			(net "PVDDQ_GHJ")
		)
		(pad "81" smd rect
			(at 0 73.09993 270)
			(size 1.8034 0.508)
			(layers "B.Cu" "B.Mask" "B.Paste")
			(net "M_G_BA<0>")
		)
		(pad "82" smd rect
			(at 0 73.950068 270)
			(size 1.8034 0.508)
			(layers "B.Cu" "B.Mask" "B.Paste")
			(net "M_G_MA<16>")
		)
		(pad "83" smd rect
			(at 0 74.799952 270)
			(size 1.8034 0.508)
			(layers "B.Cu" "B.Mask" "B.Paste")
			(net "PVDDQ_GHJ")
		)
		(pad "84" smd rect
			(at 0 75.65009 270)
			(size 1.8034 0.508)
			(layers "B.Cu" "B.Mask" "B.Paste")
			(net "M_G_CS_N<4>")
		)
		(pad "85" smd rect
			(at 0 76.499974 270)
			(size 1.8034 0.508)
			(layers "B.Cu" "B.Mask" "B.Paste")
			(net "PVDDQ_GHJ")
		)
		(pad "86" smd rect
			(at 0 77.350112 270)
			(size 1.8034 0.508)
			(layers "B.Cu" "B.Mask" "B.Paste")
			(net "M_G_MA<15>")
		)
		(pad "87" smd rect
			(at 0 78.199996 270)
			(size 1.8034 0.508)
			(layers "B.Cu" "B.Mask" "B.Paste")
			(net "M_G_ODT<2>")
		)
		(pad "88" smd rect
			(at 0 79.04988 270)
			(size 1.8034 0.508)
			(layers "B.Cu" "B.Mask" "B.Paste")
			(net "PVDDQ_GHJ")
		)
		(pad "89" smd rect
			(at 0 79.900018 270)
			(size 1.8034 0.508)
			(layers "B.Cu" "B.Mask" "B.Paste")
			(net "M_G_CS_N<5>")
		)
		(pad "90" smd rect
			(at 0 80.749902 270)
			(size 1.8034 0.508)
			(layers "B.Cu" "B.Mask" "B.Paste")
			(net "PVDDQ_GHJ")
		)
		(pad "91" smd rect
			(at 0 81.60004 270)
			(size 1.8034 0.508)
			(layers "B.Cu" "B.Mask" "B.Paste")
			(net "M_G_ODT<3>")
		)
		(pad "92" smd rect
			(at 0 82.449924 270)
			(size 1.8034 0.508)
			(layers "B.Cu" "B.Mask" "B.Paste")
			(net "PVDDQ_GHJ")
		)
		(pad "93" smd rect
			(at 0 83.300062 270)
			(size 1.8034 0.508)
			(layers "B.Cu" "B.Mask" "B.Paste")
			(net "M_G_CS_N<6>")
		)
		(pad "94" smd rect
			(at 0 84.149946 270)
			(size 1.8034 0.508)
			(layers "B.Cu" "B.Mask" "B.Paste")
			(net "GND")
		)
		(pad "95" smd rect
			(at 0 85.000084 270)
			(size 1.8034 0.508)
			(layers "B.Cu" "B.Mask" "B.Paste")
			(net "M_G_DQ<36>")
		)
		(pad "96" smd rect
			(at 0 85.849968 270)
			(size 1.8034 0.508)
			(layers "B.Cu" "B.Mask" "B.Paste")
			(net "GND")
		)
		(pad "97" smd rect
			(at 0 86.700106 270)
			(size 1.8034 0.508)
			(layers "B.Cu" "B.Mask" "B.Paste")
			(net "M_G_DQ<32>")
		)
		(pad "98" smd rect
			(at 0 87.54999 270)
			(size 1.8034 0.508)
			(layers "B.Cu" "B.Mask" "B.Paste")
			(net "GND")
		)
		(pad "99" smd rect
			(at 0 88.399874 270)
			(size 1.8034 0.508)
			(layers "B.Cu" "B.Mask" "B.Paste")
			(net "M_G_DQS_DP<13>")
		)
		(pad "100" smd rect
			(at 0 89.250012 270)
			(size 1.8034 0.508)
			(layers "B.Cu" "B.Mask" "B.Paste")
			(net "M_G_DQS_DN<13>")
		)
		(pad "101" smd rect
			(at 0 90.099896 270)
			(size 1.8034 0.508)
			(layers "B.Cu" "B.Mask" "B.Paste")
			(net "GND")
		)
		(pad "102" smd rect
			(at 0 90.950034 270)
			(size 1.8034 0.508)
			(layers "B.Cu" "B.Mask" "B.Paste")
			(net "M_G_DQ<38>")
		)
		(pad "103" smd rect
			(at 0 91.799918 270)
			(size 1.8034 0.508)
			(layers "B.Cu" "B.Mask" "B.Paste")
			(net "GND")
		)
		(pad "104" smd rect
			(at 0 92.650056 270)
			(size 1.8034 0.508)
			(layers "B.Cu" "B.Mask" "B.Paste")
			(net "M_G_DQ<34>")
		)
		(pad "105" smd rect
			(at 0 93.49994 270)
			(size 1.8034 0.508)
			(layers "B.Cu" "B.Mask" "B.Paste")
			(net "GND")
		)
		(pad "106" smd rect
			(at 0 94.350078 270)
			(size 1.8034 0.508)
			(layers "B.Cu" "B.Mask" "B.Paste")
			(net "M_G_DQ<44>")
		)
		(pad "107" smd rect
			(at 0 95.199962 270)
			(size 1.8034 0.508)
			(layers "B.Cu" "B.Mask" "B.Paste")
			(net "GND")
		)
		(pad "108" smd rect
			(at 0 96.0501 270)
			(size 1.8034 0.508)
			(layers "B.Cu" "B.Mask" "B.Paste")
			(net "M_G_DQ<40>")
		)
		(pad "109" smd rect
			(at 0 96.899984 270)
			(size 1.8034 0.508)
			(layers "B.Cu" "B.Mask" "B.Paste")
			(net "GND")
		)
		(pad "110" smd rect
			(at 0 97.750122 270)
			(size 1.8034 0.508)
			(layers "B.Cu" "B.Mask" "B.Paste")
			(net "M_G_DQS_DP<14>")
		)
		(pad "111" smd rect
			(at 0 98.600006 270)
			(size 1.8034 0.508)
			(layers "B.Cu" "B.Mask" "B.Paste")
			(net "M_G_DQS_DN<14>")
		)
		(pad "112" smd rect
			(at 0 99.44989 270)
			(size 1.8034 0.508)
			(layers "B.Cu" "B.Mask" "B.Paste")
			(net "GND")
		)
		(pad "113" smd rect
			(at 0 100.300028 270)
			(size 1.8034 0.508)
			(layers "B.Cu" "B.Mask" "B.Paste")
			(net "M_G_DQ<46>")
		)
		(pad "114" smd rect
			(at 0 101.149912 270)
			(size 1.8034 0.508)
			(layers "B.Cu" "B.Mask" "B.Paste")
			(net "GND")
		)
		(pad "115" smd rect
			(at 0 102.00005 270)
			(size 1.8034 0.508)
			(layers "B.Cu" "B.Mask" "B.Paste")
			(net "M_G_DQ<42>")
		)
		(pad "116" smd rect
			(at 0 102.849934 270)
			(size 1.8034 0.508)
			(layers "B.Cu" "B.Mask" "B.Paste")
			(net "GND")
		)
		(pad "117" smd rect
			(at 0 103.700072 270)
			(size 1.8034 0.508)
			(layers "B.Cu" "B.Mask" "B.Paste")
			(net "M_G_DQ<52>")
		)
		(pad "118" smd rect
			(at 0 104.549956 270)
			(size 1.8034 0.508)
			(layers "B.Cu" "B.Mask" "B.Paste")
			(net "GND")
		)
		(pad "119" smd rect
			(at 0 105.400094 270)
			(size 1.8034 0.508)
			(layers "B.Cu" "B.Mask" "B.Paste")
			(net "M_G_DQ<48>")
		)
		(pad "120" smd rect
			(at 0 106.249978 270)
			(size 1.8034 0.508)
			(layers "B.Cu" "B.Mask" "B.Paste")
			(net "GND")
		)
		(pad "121" smd rect
			(at 0 107.100116 270)
			(size 1.8034 0.508)
			(layers "B.Cu" "B.Mask" "B.Paste")
			(net "M_G_DQS_DP<15>")
		)
		(pad "122" smd rect
			(at 0 107.95 270)
			(size 1.8034 0.508)
			(layers "B.Cu" "B.Mask" "B.Paste")
			(net "M_G_DQS_DN<15>")
		)
		(pad "123" smd rect
			(at 0 108.799884 270)
			(size 1.8034 0.508)
			(layers "B.Cu" "B.Mask" "B.Paste")
			(net "GND")
		)
		(pad "124" smd rect
			(at 0 109.650022 270)
			(size 1.8034 0.508)
			(layers "B.Cu" "B.Mask" "B.Paste")
			(net "M_G_DQ<54>")
		)
		(pad "125" smd rect
			(at 0 110.499906 270)
			(size 1.8034 0.508)
			(layers "B.Cu" "B.Mask" "B.Paste")
			(net "GND")
		)
		(pad "126" smd rect
			(at 0 111.350044 270)
			(size 1.8034 0.508)
			(layers "B.Cu" "B.Mask" "B.Paste")
			(net "M_G_DQ<50>")
		)
		(pad "127" smd rect
			(at 0 112.199928 270)
			(size 1.8034 0.508)
			(layers "B.Cu" "B.Mask" "B.Paste")
			(net "GND")
		)
		(pad "128" smd rect
			(at 0 113.050066 270)
			(size 1.8034 0.508)
			(layers "B.Cu" "B.Mask" "B.Paste")
			(net "M_G_DQ<60>")
		)
		(pad "129" smd rect
			(at 0 113.89995 270)
			(size 1.8034 0.508)
			(layers "B.Cu" "B.Mask" "B.Paste")
			(net "GND")
		)
		(pad "130" smd rect
			(at 0 114.750088 270)
			(size 1.8034 0.508)
			(layers "B.Cu" "B.Mask" "B.Paste")
			(net "M_G_DQ<56>")
		)
		(pad "131" smd rect
			(at 0 115.599972 270)
			(size 1.8034 0.508)
			(layers "B.Cu" "B.Mask" "B.Paste")
			(net "GND")
		)
		(pad "132" smd rect
			(at 0 116.45011 270)
			(size 1.8034 0.508)
			(layers "B.Cu" "B.Mask" "B.Paste")
			(net "M_G_DQS_DP<16>")
		)
		(pad "133" smd rect
			(at 0 117.299994 270)
			(size 1.8034 0.508)
			(layers "B.Cu" "B.Mask" "B.Paste")
			(net "M_G_DQS_DN<16>")
		)
		(pad "134" smd rect
			(at 0 118.149878 270)
			(size 1.8034 0.508)
			(layers "B.Cu" "B.Mask" "B.Paste")
			(net "GND")
		)
		(pad "135" smd rect
			(at 0 119.000016 270)
			(size 1.8034 0.508)
			(layers "B.Cu" "B.Mask" "B.Paste")
			(net "M_G_DQ<62>")
		)
		(pad "136" smd rect
			(at 0 119.8499 270)
			(size 1.8034 0.508)
			(layers "B.Cu" "B.Mask" "B.Paste")
			(net "GND")
		)
		(pad "137" smd rect
			(at 0 120.700038 270)
			(size 1.8034 0.508)
			(layers "B.Cu" "B.Mask" "B.Paste")
			(net "M_G_DQ<58>")
		)
		(pad "138" smd rect
			(at 0 121.549922 270)
			(size 1.8034 0.508)
			(layers "B.Cu" "B.Mask" "B.Paste")
			(net "GND")
		)
		(pad "139" smd rect
			(at 0 122.40006 270)
			(size 1.8034 0.508)
			(layers "B.Cu" "B.Mask" "B.Paste")
			(net "PVPP_GHJ")
		)
		(pad "140" smd rect
			(at 0 123.249944 270)
			(size 1.8034 0.508)
			(layers "B.Cu" "B.Mask" "B.Paste")
			(net "GND")
		)
		(pad "141" smd rect
			(at 0 124.100082 270)
			(size 1.8034 0.508)
			(layers "B.Cu" "B.Mask" "B.Paste")
			(net "SMB_DDR_GHJ_VPP_SCL")
		)
		(pad "142" smd rect
			(at 0 124.949966 270)
			(size 1.8034 0.508)
			(layers "B.Cu" "B.Mask" "B.Paste")
			(net "PVPP_GHJ")
		)
		(pad "143" smd rect
			(at 0 125.800104 270)
			(size 1.8034 0.508)
			(layers "B.Cu" "B.Mask" "B.Paste")
			(net "PVPP_GHJ")
		)
		(pad "144" smd rect
			(at 0 126.649988 270)
			(size 1.8034 0.508)
			(layers "B.Cu" "B.Mask" "B.Paste")
			(net "TP_CH_G_DIMM0_RFU_2")
		)
		(pad "145" smd rect
			(at -4.59994 0 270)
			(size 1.8034 0.508)
			(layers "B.Cu" "B.Mask" "B.Paste")
			(net "P12V_NVDIMM_GHJ")
		)
		(pad "146" smd rect
			(at -4.59994 0.849884 270)
			(size 1.8034 0.508)
			(layers "B.Cu" "B.Mask" "B.Paste")
			(net "M_G_VREF")
		)
		(pad "147" smd rect
			(at -4.59994 1.700022 270)
			(size 1.8034 0.508)
			(layers "B.Cu" "B.Mask" "B.Paste")
			(net "GND")
		)
		(pad "148" smd rect
			(at -4.59994 2.549906 270)
			(size 1.8034 0.508)
			(layers "B.Cu" "B.Mask" "B.Paste")
			(net "M_G_DQ<5>")
		)
		(pad "149" smd rect
			(at -4.59994 3.400044 270)
			(size 1.8034 0.508)
			(layers "B.Cu" "B.Mask" "B.Paste")
			(net "GND")
		)
		(pad "150" smd rect
			(at -4.59994 4.249928 270)
			(size 1.8034 0.508)
			(layers "B.Cu" "B.Mask" "B.Paste")
			(net "M_G_DQ<1>")
		)
		(pad "151" smd rect
			(at -4.59994 5.100066 270)
			(size 1.8034 0.508)
			(layers "B.Cu" "B.Mask" "B.Paste")
			(net "GND")
		)
		(pad "152" smd rect
			(at -4.59994 5.94995 270)
			(size 1.8034 0.508)
			(layers "B.Cu" "B.Mask" "B.Paste")
			(net "M_G_DQS_DN<0>")
		)
		(pad "153" smd rect
			(at -4.59994 6.800088 270)
			(size 1.8034 0.508)
			(layers "B.Cu" "B.Mask" "B.Paste")
			(net "M_G_DQS_DP<0>")
		)
		(pad "154" smd rect
			(at -4.59994 7.649972 270)
			(size 1.8034 0.508)
			(layers "B.Cu" "B.Mask" "B.Paste")
			(net "GND")
		)
		(pad "155" smd rect
			(at -4.59994 8.50011 270)
			(size 1.8034 0.508)
			(layers "B.Cu" "B.Mask" "B.Paste")
			(net "M_G_DQ<7>")
		)
		(pad "156" smd rect
			(at -4.59994 9.349994 270)
			(size 1.8034 0.508)
			(layers "B.Cu" "B.Mask" "B.Paste")
			(net "GND")
		)
		(pad "157" smd rect
			(at -4.59994 10.199878 270)
			(size 1.8034 0.508)
			(layers "B.Cu" "B.Mask" "B.Paste")
			(net "M_G_DQ<3>")
		)
		(pad "158" smd rect
			(at -4.59994 11.050016 270)
			(size 1.8034 0.508)
			(layers "B.Cu" "B.Mask" "B.Paste")
			(net "GND")
		)
		(pad "159" smd rect
			(at -4.59994 11.8999 270)
			(size 1.8034 0.508)
			(layers "B.Cu" "B.Mask" "B.Paste")
			(net "M_G_DQ<13>")
		)
		(pad "160" smd rect
			(at -4.59994 12.750038 270)
			(size 1.8034 0.508)
			(layers "B.Cu" "B.Mask" "B.Paste")
			(net "GND")
		)
		(pad "161" smd rect
			(at -4.59994 13.599922 270)
			(size 1.8034 0.508)
			(layers "B.Cu" "B.Mask" "B.Paste")
			(net "M_G_DQ<9>")
		)
		(pad "162" smd rect
			(at -4.59994 14.45006 270)
			(size 1.8034 0.508)
			(layers "B.Cu" "B.Mask" "B.Paste")
			(net "GND")
		)
		(pad "163" smd rect
			(at -4.59994 15.299944 270)
			(size 1.8034 0.508)
			(layers "B.Cu" "B.Mask" "B.Paste")
			(net "M_G_DQS_DN<1>")
		)
		(pad "164" smd rect
			(at -4.59994 16.150082 270)
			(size 1.8034 0.508)
			(layers "B.Cu" "B.Mask" "B.Paste")
			(net "M_G_DQS_DP<1>")
		)
		(pad "165" smd rect
			(at -4.59994 16.999966 270)
			(size 1.8034 0.508)
			(layers "B.Cu" "B.Mask" "B.Paste")
			(net "GND")
		)
		(pad "166" smd rect
			(at -4.59994 17.850104 270)
			(size 1.8034 0.508)
			(layers "B.Cu" "B.Mask" "B.Paste")
			(net "M_G_DQ<15>")
		)
		(pad "167" smd rect
			(at -4.59994 18.699988 270)
			(size 1.8034 0.508)
			(layers "B.Cu" "B.Mask" "B.Paste")
			(net "GND")
		)
		(pad "168" smd rect
			(at -4.59994 19.550126 270)
			(size 1.8034 0.508)
			(layers "B.Cu" "B.Mask" "B.Paste")
			(net "M_G_DQ<11>")
		)
		(pad "169" smd rect
			(at -4.59994 20.40001 270)
			(size 1.8034 0.508)
			(layers "B.Cu" "B.Mask" "B.Paste")
			(net "GND")
		)
		(pad "170" smd rect
			(at -4.59994 21.249894 270)
			(size 1.8034 0.508)
			(layers "B.Cu" "B.Mask" "B.Paste")
			(net "M_G_DQ<21>")
		)
		(pad "171" smd rect
			(at -4.59994 22.100032 270)
			(size 1.8034 0.508)
			(layers "B.Cu" "B.Mask" "B.Paste")
			(net "GND")
		)
		(pad "172" smd rect
			(at -4.59994 22.949916 270)
			(size 1.8034 0.508)
			(layers "B.Cu" "B.Mask" "B.Paste")
			(net "M_G_DQ<17>")
		)
		(pad "173" smd rect
			(at -4.59994 23.800054 270)
			(size 1.8034 0.508)
			(layers "B.Cu" "B.Mask" "B.Paste")
			(net "GND")
		)
		(pad "174" smd rect
			(at -4.59994 24.649938 270)
			(size 1.8034 0.508)
			(layers "B.Cu" "B.Mask" "B.Paste")
			(net "M_G_DQS_DN<2>")
		)
		(pad "175" smd rect
			(at -4.59994 25.500076 270)
			(size 1.8034 0.508)
			(layers "B.Cu" "B.Mask" "B.Paste")
			(net "M_G_DQS_DP<2>")
		)
		(pad "176" smd rect
			(at -4.59994 26.34996 270)
			(size 1.8034 0.508)
			(layers "B.Cu" "B.Mask" "B.Paste")
			(net "GND")
		)
		(pad "177" smd rect
			(at -4.59994 27.200098 270)
			(size 1.8034 0.508)
			(layers "B.Cu" "B.Mask" "B.Paste")
			(net "M_G_DQ<23>")
		)
		(pad "178" smd rect
			(at -4.59994 28.049982 270)
			(size 1.8034 0.508)
			(layers "B.Cu" "B.Mask" "B.Paste")
			(net "GND")
		)
		(pad "179" smd rect
			(at -4.59994 28.90012 270)
			(size 1.8034 0.508)
			(layers "B.Cu" "B.Mask" "B.Paste")
			(net "M_G_DQ<19>")
		)
		(pad "180" smd rect
			(at -4.59994 29.750004 270)
			(size 1.8034 0.508)
			(layers "B.Cu" "B.Mask" "B.Paste")
			(net "GND")
		)
		(pad "181" smd rect
			(at -4.59994 30.599888 270)
			(size 1.8034 0.508)
			(layers "B.Cu" "B.Mask" "B.Paste")
			(net "M_G_DQ<29>")
		)
		(pad "182" smd rect
			(at -4.59994 31.450026 270)
			(size 1.8034 0.508)
			(layers "B.Cu" "B.Mask" "B.Paste")
			(net "GND")
		)
		(pad "183" smd rect
			(at -4.59994 32.29991 270)
			(size 1.8034 0.508)
			(layers "B.Cu" "B.Mask" "B.Paste")
			(net "M_G_DQ<25>")
		)
		(pad "184" smd rect
			(at -4.59994 33.150048 270)
			(size 1.8034 0.508)
			(layers "B.Cu" "B.Mask" "B.Paste")
			(net "GND")
		)
		(pad "185" smd rect
			(at -4.59994 33.999932 270)
			(size 1.8034 0.508)
			(layers "B.Cu" "B.Mask" "B.Paste")
			(net "M_G_DQS_DN<3>")
		)
		(pad "186" smd rect
			(at -4.59994 34.85007 270)
			(size 1.8034 0.508)
			(layers "B.Cu" "B.Mask" "B.Paste")
			(net "M_G_DQS_DP<3>")
		)
		(pad "187" smd rect
			(at -4.59994 35.699954 270)
			(size 1.8034 0.508)
			(layers "B.Cu" "B.Mask" "B.Paste")
			(net "GND")
		)
		(pad "188" smd rect
			(at -4.59994 36.550092 270)
			(size 1.8034 0.508)
			(layers "B.Cu" "B.Mask" "B.Paste")
			(net "M_G_DQ<31>")
		)
		(pad "189" smd rect
			(at -4.59994 37.399976 270)
			(size 1.8034 0.508)
			(layers "B.Cu" "B.Mask" "B.Paste")
			(net "GND")
		)
		(pad "190" smd rect
			(at -4.59994 38.250114 270)
			(size 1.8034 0.508)
			(layers "B.Cu" "B.Mask" "B.Paste")
			(net "M_G_DQ<27>")
		)
		(pad "191" smd rect
			(at -4.59994 39.099998 270)
			(size 1.8034 0.508)
			(layers "B.Cu" "B.Mask" "B.Paste")
			(net "GND")
		)
		(pad "192" smd rect
			(at -4.59994 39.949882 270)
			(size 1.8034 0.508)
			(layers "B.Cu" "B.Mask" "B.Paste")
			(net "M_G_ECC<5>")
		)
		(pad "193" smd rect
			(at -4.59994 40.80002 270)
			(size 1.8034 0.508)
			(layers "B.Cu" "B.Mask" "B.Paste")
			(net "GND")
		)
		(pad "194" smd rect
			(at -4.59994 41.649904 270)
			(size 1.8034 0.508)
			(layers "B.Cu" "B.Mask" "B.Paste")
			(net "M_G_ECC<1>")
		)
		(pad "195" smd rect
			(at -4.59994 42.500042 270)
			(size 1.8034 0.508)
			(layers "B.Cu" "B.Mask" "B.Paste")
			(net "GND")
		)
		(pad "196" smd rect
			(at -4.59994 43.349926 270)
			(size 1.8034 0.508)
			(layers "B.Cu" "B.Mask" "B.Paste")
			(net "M_G_DQS_DN<8>")
		)
		(pad "197" smd rect
			(at -4.59994 44.200064 270)
			(size 1.8034 0.508)
			(layers "B.Cu" "B.Mask" "B.Paste")
			(net "M_G_DQS_DP<8>")
		)
		(pad "198" smd rect
			(at -4.59994 45.049948 270)
			(size 1.8034 0.508)
			(layers "B.Cu" "B.Mask" "B.Paste")
			(net "GND")
		)
		(pad "199" smd rect
			(at -4.59994 45.900086 270)
			(size 1.8034 0.508)
			(layers "B.Cu" "B.Mask" "B.Paste")
			(net "M_G_ECC<7>")
		)
		(pad "200" smd rect
			(at -4.59994 46.74997 270)
			(size 1.8034 0.508)
			(layers "B.Cu" "B.Mask" "B.Paste")
			(net "GND")
		)
		(pad "201" smd rect
			(at -4.59994 47.600108 270)
			(size 1.8034 0.508)
			(layers "B.Cu" "B.Mask" "B.Paste")
			(net "M_G_ECC<3>")
		)
		(pad "202" smd rect
			(at -4.59994 48.449992 270)
			(size 1.8034 0.508)
			(layers "B.Cu" "B.Mask" "B.Paste")
			(net "GND")
		)
		(pad "203" smd rect
			(at -4.59994 49.299876 270)
			(size 1.8034 0.508)
			(layers "B.Cu" "B.Mask" "B.Paste")
			(net "M_G_CKE<3>")
		)
		(pad "204" smd rect
			(at -4.59994 50.150014 270)
			(size 1.8034 0.508)
			(layers "B.Cu" "B.Mask" "B.Paste")
			(net "PVDDQ_GHJ")
		)
		(pad "205" smd rect
			(at -4.59994 50.999898 270)
			(size 1.8034 0.508)
			(layers "B.Cu" "B.Mask" "B.Paste")
			(net "TP_CH_G_DIMM0_RFU_0")
		)
		(pad "206" smd rect
			(at -4.59994 51.850036 270)
			(size 1.8034 0.508)
			(layers "B.Cu" "B.Mask" "B.Paste")
			(net "PVDDQ_GHJ")
		)
		(pad "207" smd rect
			(at -4.59994 52.69992 270)
			(size 1.8034 0.508)
			(layers "B.Cu" "B.Mask" "B.Paste")
			(net "M_G_BG<1>")
		)
		(pad "208" smd rect
			(at -4.59994 53.550058 270)
			(size 1.8034 0.508)
			(layers "B.Cu" "B.Mask" "B.Paste")
			(net "M_G_ALERT_N")
		)
		(pad "209" smd rect
			(at -4.59994 54.399942 270)
			(size 1.8034 0.508)
			(layers "B.Cu" "B.Mask" "B.Paste")
			(net "PVDDQ_GHJ")
		)
		(pad "210" smd rect
			(at -4.59994 55.25008 270)
			(size 1.8034 0.508)
			(layers "B.Cu" "B.Mask" "B.Paste")
			(net "M_G_MA<11>")
		)
		(pad "211" smd rect
			(at -4.59994 56.099964 270)
			(size 1.8034 0.508)
			(layers "B.Cu" "B.Mask" "B.Paste")
			(net "M_G_MA<7>")
		)
		(pad "212" smd rect
			(at -4.59994 56.950102 270)
			(size 1.8034 0.508)
			(layers "B.Cu" "B.Mask" "B.Paste")
			(net "PVDDQ_GHJ")
		)
		(pad "213" smd rect
			(at -4.59994 57.799986 270)
			(size 1.8034 0.508)
			(layers "B.Cu" "B.Mask" "B.Paste")
			(net "M_G_MA<5>")
		)
		(pad "214" smd rect
			(at -4.59994 58.650124 270)
			(size 1.8034 0.508)
			(layers "B.Cu" "B.Mask" "B.Paste")
			(net "M_G_MA<4>")
		)
		(pad "215" smd rect
			(at -4.59994 59.500008 270)
			(size 1.8034 0.508)
			(layers "B.Cu" "B.Mask" "B.Paste")
			(net "PVDDQ_GHJ")
		)
		(pad "216" smd rect
			(at -4.59994 60.349892 270)
			(size 1.8034 0.508)
			(layers "B.Cu" "B.Mask" "B.Paste")
			(net "M_G_MA<2>")
		)
		(pad "217" smd rect
			(at -4.59994 61.20003 270)
			(size 1.8034 0.508)
			(layers "B.Cu" "B.Mask" "B.Paste")
			(net "PVDDQ_GHJ")
		)
		(pad "218" smd rect
			(at -4.59994 62.049914 270)
			(size 1.8034 0.508)
			(layers "B.Cu" "B.Mask" "B.Paste")
			(net "M_G_CLK_DP<3>")
		)
		(pad "219" smd rect
			(at -4.59994 62.900052 270)
			(size 1.8034 0.508)
			(layers "B.Cu" "B.Mask" "B.Paste")
			(net "M_G_CLK_DN<3>")
		)
		(pad "220" smd rect
			(at -4.59994 63.749936 270)
			(size 1.8034 0.508)
			(layers "B.Cu" "B.Mask" "B.Paste")
			(net "PVDDQ_GHJ")
		)
		(pad "221" smd rect
			(at -4.59994 64.600074 270)
			(size 1.8034 0.508)
			(layers "B.Cu" "B.Mask" "B.Paste")
			(net "PVTT_GHJ")
		)
		(pad "222" smd rect
			(at -4.59994 70.550024 270)
			(size 1.8034 0.508)
			(layers "B.Cu" "B.Mask" "B.Paste")
			(net "M_G_PAR")
		)
		(pad "223" smd rect
			(at -4.59994 71.399908 270)
			(size 1.8034 0.508)
			(layers "B.Cu" "B.Mask" "B.Paste")
			(net "PVDDQ_GHJ")
		)
		(pad "224" smd rect
			(at -4.59994 72.250046 270)
			(size 1.8034 0.508)
			(layers "B.Cu" "B.Mask" "B.Paste")
			(net "M_G_BA<1>")
		)
		(pad "225" smd rect
			(at -4.59994 73.09993 270)
			(size 1.8034 0.508)
			(layers "B.Cu" "B.Mask" "B.Paste")
			(net "M_G_MA<10>")
		)
		(pad "226" smd rect
			(at -4.59994 73.950068 270)
			(size 1.8034 0.508)
			(layers "B.Cu" "B.Mask" "B.Paste")
			(net "PVDDQ_GHJ")
		)
		(pad "227" smd rect
			(at -4.59994 74.799952 270)
			(size 1.8034 0.508)
			(layers "B.Cu" "B.Mask" "B.Paste")
			(net "TP_CH_G_DIMM0_RFU_1")
		)
		(pad "228" smd rect
			(at -4.59994 75.65009 270)
			(size 1.8034 0.508)
			(layers "B.Cu" "B.Mask" "B.Paste")
			(net "M_G_MA<14>")
		)
		(pad "229" smd rect
			(at -4.59994 76.499974 270)
			(size 1.8034 0.508)
			(layers "B.Cu" "B.Mask" "B.Paste")
			(net "PVDDQ_GHJ")
		)
		(pad "230" smd rect
			(at -4.59994 77.350112 270)
			(size 1.8034 0.508)
			(layers "B.Cu" "B.Mask" "B.Paste")
			(net "FM_ADR_COMPLETE_GHJ_N")
		)
		(pad "231" smd rect
			(at -4.59994 78.199996 270)
			(size 1.8034 0.508)
			(layers "B.Cu" "B.Mask" "B.Paste")
			(net "PVDDQ_GHJ")
		)
		(pad "232" smd rect
			(at -4.59994 79.04988 270)
			(size 1.8034 0.508)
			(layers "B.Cu" "B.Mask" "B.Paste")
			(net "M_G_MA<13>")
		)
		(pad "233" smd rect
			(at -4.59994 79.900018 270)
			(size 1.8034 0.508)
			(layers "B.Cu" "B.Mask" "B.Paste")
			(net "PVDDQ_GHJ")
		)
		(pad "234" smd rect
			(at -4.59994 80.749902 270)
			(size 1.8034 0.508)
			(layers "B.Cu" "B.Mask" "B.Paste")
			(net "M_G_MA<17>")
		)
		(pad "235" smd rect
			(at -4.59994 81.60004 270)
			(size 1.8034 0.508)
			(layers "B.Cu" "B.Mask" "B.Paste")
			(net "M_G_C<2>")
		)
		(pad "236" smd rect
			(at -4.59994 82.449924 270)
			(size 1.8034 0.508)
			(layers "B.Cu" "B.Mask" "B.Paste")
			(net "PVDDQ_GHJ")
		)
		(pad "237" smd rect
			(at -4.59994 83.300062 270)
			(size 1.8034 0.508)
			(layers "B.Cu" "B.Mask" "B.Paste")
			(net "M_G_CS_N<7>")
		)
		(pad "238" smd rect
			(at -4.59994 84.149946 270)
			(size 1.8034 0.508)
			(layers "B.Cu" "B.Mask" "B.Paste")
			(net "GND")
		)
		(pad "239" smd rect
			(at -4.59994 85.000084 270)
			(size 1.8034 0.508)
			(layers "B.Cu" "B.Mask" "B.Paste")
			(net "GND")
		)
		(pad "240" smd rect
			(at -4.59994 85.849968 270)
			(size 1.8034 0.508)
			(layers "B.Cu" "B.Mask" "B.Paste")
			(net "M_G_DQ<37>")
		)
		(pad "241" smd rect
			(at -4.59994 86.700106 270)
			(size 1.8034 0.508)
			(layers "B.Cu" "B.Mask" "B.Paste")
			(net "GND")
		)
		(pad "242" smd rect
			(at -4.59994 87.54999 270)
			(size 1.8034 0.508)
			(layers "B.Cu" "B.Mask" "B.Paste")
			(net "M_G_DQ<33>")
		)
		(pad "243" smd rect
			(at -4.59994 88.399874 270)
			(size 1.8034 0.508)
			(layers "B.Cu" "B.Mask" "B.Paste")
			(net "GND")
		)
		(pad "244" smd rect
			(at -4.59994 89.250012 270)
			(size 1.8034 0.508)
			(layers "B.Cu" "B.Mask" "B.Paste")
			(net "M_G_DQS_DN<4>")
		)
		(pad "245" smd rect
			(at -4.59994 90.099896 270)
			(size 1.8034 0.508)
			(layers "B.Cu" "B.Mask" "B.Paste")
			(net "M_G_DQS_DP<4>")
		)
		(pad "246" smd rect
			(at -4.59994 90.950034 270)
			(size 1.8034 0.508)
			(layers "B.Cu" "B.Mask" "B.Paste")
			(net "GND")
		)
		(pad "247" smd rect
			(at -4.59994 91.799918 270)
			(size 1.8034 0.508)
			(layers "B.Cu" "B.Mask" "B.Paste")
			(net "M_G_DQ<39>")
		)
		(pad "248" smd rect
			(at -4.59994 92.650056 270)
			(size 1.8034 0.508)
			(layers "B.Cu" "B.Mask" "B.Paste")
			(net "GND")
		)
		(pad "249" smd rect
			(at -4.59994 93.49994 270)
			(size 1.8034 0.508)
			(layers "B.Cu" "B.Mask" "B.Paste")
			(net "M_G_DQ<35>")
		)
		(pad "250" smd rect
			(at -4.59994 94.350078 270)
			(size 1.8034 0.508)
			(layers "B.Cu" "B.Mask" "B.Paste")
			(net "GND")
		)
		(pad "251" smd rect
			(at -4.59994 95.199962 270)
			(size 1.8034 0.508)
			(layers "B.Cu" "B.Mask" "B.Paste")
			(net "M_G_DQ<45>")
		)
		(pad "252" smd rect
			(at -4.59994 96.0501 270)
			(size 1.8034 0.508)
			(layers "B.Cu" "B.Mask" "B.Paste")
			(net "GND")
		)
		(pad "253" smd rect
			(at -4.59994 96.899984 270)
			(size 1.8034 0.508)
			(layers "B.Cu" "B.Mask" "B.Paste")
			(net "M_G_DQ<41>")
		)
		(pad "254" smd rect
			(at -4.59994 97.750122 270)
			(size 1.8034 0.508)
			(layers "B.Cu" "B.Mask" "B.Paste")
			(net "GND")
		)
		(pad "255" smd rect
			(at -4.59994 98.600006 270)
			(size 1.8034 0.508)
			(layers "B.Cu" "B.Mask" "B.Paste")
			(net "M_G_DQS_DN<5>")
		)
		(pad "256" smd rect
			(at -4.59994 99.44989 270)
			(size 1.8034 0.508)
			(layers "B.Cu" "B.Mask" "B.Paste")
			(net "M_G_DQS_DP<5>")
		)
		(pad "257" smd rect
			(at -4.59994 100.300028 270)
			(size 1.8034 0.508)
			(layers "B.Cu" "B.Mask" "B.Paste")
			(net "GND")
		)
		(pad "258" smd rect
			(at -4.59994 101.149912 270)
			(size 1.8034 0.508)
			(layers "B.Cu" "B.Mask" "B.Paste")
			(net "M_G_DQ<47>")
		)
		(pad "259" smd rect
			(at -4.59994 102.00005 270)
			(size 1.8034 0.508)
			(layers "B.Cu" "B.Mask" "B.Paste")
			(net "GND")
		)
		(pad "260" smd rect
			(at -4.59994 102.849934 270)
			(size 1.8034 0.508)
			(layers "B.Cu" "B.Mask" "B.Paste")
			(net "M_G_DQ<43>")
		)
		(pad "261" smd rect
			(at -4.59994 103.700072 270)
			(size 1.8034 0.508)
			(layers "B.Cu" "B.Mask" "B.Paste")
			(net "GND")
		)
		(pad "262" smd rect
			(at -4.59994 104.549956 270)
			(size 1.8034 0.508)
			(layers "B.Cu" "B.Mask" "B.Paste")
			(net "M_G_DQ<53>")
		)
		(pad "263" smd rect
			(at -4.59994 105.400094 270)
			(size 1.8034 0.508)
			(layers "B.Cu" "B.Mask" "B.Paste")
			(net "GND")
		)
		(pad "264" smd rect
			(at -4.59994 106.249978 270)
			(size 1.8034 0.508)
			(layers "B.Cu" "B.Mask" "B.Paste")
			(net "M_G_DQ<49>")
		)
		(pad "265" smd rect
			(at -4.59994 107.100116 270)
			(size 1.8034 0.508)
			(layers "B.Cu" "B.Mask" "B.Paste")
			(net "GND")
		)
		(pad "266" smd rect
			(at -4.59994 107.95 270)
			(size 1.8034 0.508)
			(layers "B.Cu" "B.Mask" "B.Paste")
			(net "M_G_DQS_DN<6>")
		)
		(pad "267" smd rect
			(at -4.59994 108.799884 270)
			(size 1.8034 0.508)
			(layers "B.Cu" "B.Mask" "B.Paste")
			(net "M_G_DQS_DP<6>")
		)
		(pad "268" smd rect
			(at -4.59994 109.650022 270)
			(size 1.8034 0.508)
			(layers "B.Cu" "B.Mask" "B.Paste")
			(net "GND")
		)
		(pad "269" smd rect
			(at -4.59994 110.499906 270)
			(size 1.8034 0.508)
			(layers "B.Cu" "B.Mask" "B.Paste")
			(net "M_G_DQ<55>")
		)
		(pad "270" smd rect
			(at -4.59994 111.350044 270)
			(size 1.8034 0.508)
			(layers "B.Cu" "B.Mask" "B.Paste")
			(net "GND")
		)
		(pad "271" smd rect
			(at -4.59994 112.199928 270)
			(size 1.8034 0.508)
			(layers "B.Cu" "B.Mask" "B.Paste")
			(net "M_G_DQ<51>")
		)
		(pad "272" smd rect
			(at -4.59994 113.050066 270)
			(size 1.8034 0.508)
			(layers "B.Cu" "B.Mask" "B.Paste")
			(net "GND")
		)
		(pad "273" smd rect
			(at -4.59994 113.89995 270)
			(size 1.8034 0.508)
			(layers "B.Cu" "B.Mask" "B.Paste")
			(net "M_G_DQ<61>")
		)
		(pad "274" smd rect
			(at -4.59994 114.750088 270)
			(size 1.8034 0.508)
			(layers "B.Cu" "B.Mask" "B.Paste")
			(net "GND")
		)
		(pad "275" smd rect
			(at -4.59994 115.599972 270)
			(size 1.8034 0.508)
			(layers "B.Cu" "B.Mask" "B.Paste")
			(net "M_G_DQ<57>")
		)
		(pad "276" smd rect
			(at -4.59994 116.45011 270)
			(size 1.8034 0.508)
			(layers "B.Cu" "B.Mask" "B.Paste")
			(net "GND")
		)
		(pad "277" smd rect
			(at -4.59994 117.299994 270)
			(size 1.8034 0.508)
			(layers "B.Cu" "B.Mask" "B.Paste")
			(net "M_G_DQS_DN<7>")
		)
		(pad "278" smd rect
			(at -4.59994 118.149878 270)
			(size 1.8034 0.508)
			(layers "B.Cu" "B.Mask" "B.Paste")
			(net "M_G_DQS_DP<7>")
		)
		(pad "279" smd rect
			(at -4.59994 119.000016 270)
			(size 1.8034 0.508)
			(layers "B.Cu" "B.Mask" "B.Paste")
			(net "GND")
		)
		(pad "280" smd rect
			(at -4.59994 119.8499 270)
			(size 1.8034 0.508)
			(layers "B.Cu" "B.Mask" "B.Paste")
			(net "M_G_DQ<63>")
		)
		(pad "281" smd rect
			(at -4.59994 120.700038 270)
			(size 1.8034 0.508)
			(layers "B.Cu" "B.Mask" "B.Paste")
			(net "GND")
		)
		(pad "282" smd rect
			(at -4.59994 121.549922 270)
			(size 1.8034 0.508)
			(layers "B.Cu" "B.Mask" "B.Paste")
			(net "M_G_DQ<59>")
		)
		(pad "283" smd rect
			(at -4.59994 122.40006 270)
			(size 1.8034 0.508)
			(layers "B.Cu" "B.Mask" "B.Paste")
			(net "GND")
		)
		(pad "284" smd rect
			(at -4.59994 123.249944 270)
			(size 1.8034 0.508)
			(layers "B.Cu" "B.Mask" "B.Paste")
			(net "PVPP_GHJ")
		)
		(pad "285" smd rect
			(at -4.59994 124.100082 270)
			(size 1.8034 0.508)
			(layers "B.Cu" "B.Mask" "B.Paste")
			(net "SMB_DDR_GHJ_VPP_SDA")
		)
		(pad "286" smd rect
			(at -4.59994 124.949966 270)
			(size 1.8034 0.508)
			(layers "B.Cu" "B.Mask" "B.Paste")
			(net "PVPP_GHJ")
		)
		(pad "287" smd rect
			(at -4.59994 125.800104 270)
			(size 1.8034 0.508)
			(layers "B.Cu" "B.Mask" "B.Paste")
			(net "PVPP_GHJ")
		)
		(pad "288" smd rect
			(at -4.59994 126.649988 270)
			(size 1.8034 0.508)
			(layers "B.Cu" "B.Mask" "B.Paste")
			(net "PVPP_GHJ")
		)
	)
	(footprint ""
		(layer "B.Cu")
		(at 471.14206 -130.0734)
		(property "Reference" "C1M29"
			(at 0 0 0)
			(layer "B.SilkS")
			(hide yes)
			(effects
				(font
					(size 1.27 1.27)
				)
				(justify mirror)
			)
		)
		(property "Value" ""
			(at 0 0 0)
			(layer "B.Fab")
			(effects
				(font
					(size 1.27 1.27)
				)
				(justify mirror)
			)
		)
		(duplicate_pad_numbers_are_jumpers no)
		(fp_poly
			(pts
				(xy -0.3048 -0.1016) (xy -0.3048 0.9906) (xy 0.3048 0.9906) (xy 0.3048 -0.1016)
			)
			(stroke
				(width 0)
				(type default)
			)
			(fill no)
			(layer "B.CrtYd")
		)
		(fp_line
			(start -0.3048 -0.1016)
			(end 0.3048 -0.1016)
			(stroke
				(width 0.1)
				(type default)
			)
			(layer "B.Fab")
		)
		(fp_line
			(start -0.3048 0.9906)
			(end -0.3048 -0.1016)
			(stroke
				(width 0.1)
				(type default)
			)
			(layer "B.Fab")
		)
		(fp_line
			(start 0.3048 -0.1016)
			(end 0.3048 0.9906)
			(stroke
				(width 0.1)
				(type default)
			)
			(layer "B.Fab")
		)
		(fp_line
			(start 0.3048 0.9906)
			(end -0.3048 0.9906)
			(stroke
				(width 0.1)
				(type default)
			)
			(layer "B.Fab")
		)
		(pad "1" smd rect
			(at 0 0 180)
			(size 0.508 0.508)
			(layers "B.Cu" "B.Mask" "B.Paste")
			(net "P1V8_MCP_CPU0")
		)
		(pad "2" smd rect
			(at 0 0.889 180)
			(size 0.508 0.508)
			(layers "B.Cu" "B.Mask" "B.Paste")
			(net "GND")
		)
		(zone
			(layer "B.Cu")
			(hatch none 0.5)
			(connect_pads
				(clearance 0)
			)
			(min_thickness 0.25)
			(keepout
				(tracks allowed)
				(vias not_allowed)
				(pads allowed)
				(copperpour not_allowed)
				(footprints allowed)
			)
			(placement
				(enabled no)
				(sheetname "")
			)
			(fill
				(thermal_gap 0.5)
				(thermal_bridge_width 0.5)
				(island_removal_mode 0)
			)
			(polygon
				(pts
					(xy 471.39606 -129.8194) (xy 470.88806 -129.8194) (xy 470.88806 -129.4384) (xy 471.39606 -129.4384)
				)
			)
		)
		(zone
			(layer "B.Cu")
			(hatch none 0.5)
			(connect_pads
				(clearance 0)
			)
			(min_thickness 0.25)
			(keepout
				(tracks not_allowed)
				(vias allowed)
				(pads allowed)
				(copperpour not_allowed)
				(footprints allowed)
			)
			(placement
				(enabled no)
				(sheetname "")
			)
			(fill
				(thermal_gap 0.5)
				(thermal_bridge_width 0.5)
				(island_removal_mode 0)
			)
			(polygon
				(pts
					(xy 471.39606 -129.4384) (xy 470.88806 -129.4384) (xy 470.88806 -129.8194) (xy 471.39606 -129.8194)
				)
			)
		)
	)
	(footprint ""
		(layer "B.Cu")
		(at 31.0134 -80.4926 180)
		(property "Reference" "CT19"
			(at 0.8382 -0.84963 180)
			(unlocked yes)
			(layer "B.SilkS")
			(effects
				(font
					(size 0.7874 0.5842)
					(thickness 0.1524)
				)
				(justify left mirror)
			)
		)
		(property "Value" ""
			(at 0 0 0)
			(layer "B.Fab")
			(effects
				(font
					(size 1.27 1.27)
				)
				(justify mirror)
			)
		)
		(duplicate_pad_numbers_are_jumpers no)
		(fp_poly
			(pts
				(xy -0.3048 -0.1016) (xy -0.3048 0.9906) (xy 0.3048 0.9906) (xy 0.3048 -0.1016)
			)
			(stroke
				(width 0)
				(type default)
			)
			(fill no)
			(layer "B.CrtYd")
		)
		(fp_line
			(start 0.3048 0.9906)
			(end -0.3048 0.9906)
			(stroke
				(width 0.1)
				(type default)
			)
			(layer "B.Fab")
		)
		(fp_line
			(start 0.3048 -0.1016)
			(end 0.3048 0.9906)
			(stroke
				(width 0.1)
				(type default)
			)
			(layer "B.Fab")
		)
		(fp_line
			(start -0.3048 0.9906)
			(end -0.3048 -0.1016)
			(stroke
				(width 0.1)
				(type default)
			)
			(layer "B.Fab")
		)
		(fp_line
			(start -0.3048 -0.1016)
			(end 0.3048 -0.1016)
			(stroke
				(width 0.1)
				(type default)
			)
			(layer "B.Fab")
		)
		(pad "1" smd rect
			(at 0 0)
			(size 0.508 0.508)
			(layers "B.Cu" "B.Mask" "B.Paste")
			(net "A_TSENSE_PVCCIN_CPU1")
		)
		(pad "2" smd rect
			(at 0 0.889)
			(size 0.508 0.508)
			(layers "B.Cu" "B.Mask" "B.Paste")
			(net "GND")
		)
		(zone
			(layer "B.Cu")
			(hatch none 0.5)
			(connect_pads
				(clearance 0)
			)
			(min_thickness 0.25)
			(keepout
				(tracks not_allowed)
				(vias allowed)
				(pads allowed)
				(copperpour not_allowed)
				(footprints allowed)
			)
			(placement
				(enabled no)
				(sheetname "")
			)
			(fill
				(thermal_gap 0.5)
				(thermal_bridge_width 0.5)
				(island_removal_mode 0)
			)
			(polygon
				(pts
					(xy 30.7594 -81.1276) (xy 31.2674 -81.1276) (xy 31.2674 -80.7466) (xy 30.7594 -80.7466)
				)
			)
		)
		(zone
			(layer "B.Cu")
			(hatch none 0.5)
			(connect_pads
				(clearance 0)
			)
			(min_thickness 0.25)
			(keepout
				(tracks allowed)
				(vias not_allowed)
				(pads allowed)
				(copperpour not_allowed)
				(footprints allowed)
			)
			(placement
				(enabled no)
				(sheetname "")
			)
			(fill
				(thermal_gap 0.5)
				(thermal_bridge_width 0.5)
				(island_removal_mode 0)
			)
			(polygon
				(pts
					(xy 30.7594 -80.7466) (xy 31.2674 -80.7466) (xy 31.2674 -81.1276) (xy 30.7594 -81.1276)
				)
			)
		)
	)
	(footprint ""
		(layer "B.Cu")
		(at 401.599146 -35.569652 90)
		(property "Reference" "R25W107"
			(at 0.8382 -0.67818 90)
			(unlocked yes)
			(layer "B.SilkS")
			(effects
				(font
					(size 0.4064 0.254)
					(thickness 0.1524)
				)
				(justify left mirror)
			)
		)
		(property "Value" ""
			(at 0 0 90)
			(layer "B.Fab")
			(effects
				(font
					(size 1.27 1.27)
				)
				(justify mirror)
			)
		)
		(duplicate_pad_numbers_are_jumpers no)
		(fp_poly
			(pts
				(xy 0.2794 -0.1016) (xy -0.2794 -0.1016) (xy -0.2794 0.9906) (xy 0.2794 0.9906)
			)
			(stroke
				(width 0)
				(type default)
			)
			(fill no)
			(layer "B.CrtYd")
		)
		(fp_line
			(start 0.2794 -0.1016)
			(end 0.2794 0.9906)
			(stroke
				(width 0.1)
				(type default)
			)
			(layer "B.Fab")
		)
		(fp_line
			(start -0.2794 -0.1016)
			(end 0.2794 -0.1016)
			(stroke
				(width 0.1)
				(type default)
			)
			(layer "B.Fab")
		)
		(fp_line
			(start 0.2794 0.9906)
			(end -0.2794 0.9906)
			(stroke
				(width 0.1)
				(type default)
			)
			(layer "B.Fab")
		)
		(fp_line
			(start -0.2794 0.9906)
			(end -0.2794 -0.1016)
			(stroke
				(width 0.1)
				(type default)
			)
			(layer "B.Fab")
		)
		(pad "1" smd rect
			(at 0 0 270)
			(size 0.508 0.508)
			(layers "B.Cu" "B.Mask" "B.Paste")
			(net "P3V3_STBY")
		)
		(pad "2" smd rect
			(at 0 0.889 270)
			(size 0.508 0.508)
			(layers "B.Cu" "B.Mask" "B.Paste")
			(net "RMII_BMC_OCP_TXD0_R")
		)
		(zone
			(layer "B.Cu")
			(hatch none 0.5)
			(connect_pads
				(clearance 0)
			)
			(min_thickness 0.25)
			(keepout
				(tracks allowed)
				(vias not_allowed)
				(pads allowed)
				(copperpour not_allowed)
				(footprints allowed)
			)
			(placement
				(enabled no)
				(sheetname "")
			)
			(fill
				(thermal_gap 0.5)
				(thermal_bridge_width 0.5)
				(island_removal_mode 0)
			)
			(polygon
				(pts
					(xy 401.853146 -35.823652) (xy 401.853146 -35.315652) (xy 402.234146 -35.315652) (xy 402.234146 -35.823652)
				)
			)
		)
		(zone
			(layer "B.Cu")
			(hatch none 0.5)
			(connect_pads
				(clearance 0)
			)
			(min_thickness 0.25)
			(keepout
				(tracks not_allowed)
				(vias allowed)
				(pads allowed)
				(copperpour not_allowed)
				(footprints allowed)
			)
			(placement
				(enabled no)
				(sheetname "")
			)
			(fill
				(thermal_gap 0.5)
				(thermal_bridge_width 0.5)
				(island_removal_mode 0)
			)
			(polygon
				(pts
					(xy 402.234146 -35.823652) (xy 402.234146 -35.315652) (xy 401.853146 -35.315652) (xy 401.853146 -35.823652)
				)
			)
		)
	)
	(footprint ""
		(layer "B.Cu")
		(at 248.8565 -135.4074 -90)
		(property "Reference" "C5M6"
			(at -1.848866 0.752348 270)
			(unlocked yes)
			(layer "B.SilkS")
			(effects
				(font
					(size 1.27 0.9652)
					(thickness 0.1524)
				)
				(justify mirror)
			)
		)
		(property "Value" ""
			(at 0 0 90)
			(layer "B.Fab")
			(effects
				(font
					(size 1.27 1.27)
				)
				(justify mirror)
			)
		)
		(duplicate_pad_numbers_are_jumpers no)
		(fp_rect
			(start 0.500126 1.598422)
			(end -0.500126 -0.201422)
			(stroke
				(width 0)
				(type default)
			)
			(fill no)
			(layer "B.CrtYd")
		)
		(fp_line
			(start -0.500126 1.598422)
			(end 0.500126 1.598422)
			(stroke
				(width 0.1)
				(type default)
			)
			(layer "B.Fab")
		)
		(fp_line
			(start 0.500126 1.598422)
			(end 0.500126 -0.201422)
			(stroke
				(width 0.1)
				(type default)
			)
			(layer "B.Fab")
		)
		(fp_line
			(start -0.500126 -0.201422)
			(end -0.500126 1.598422)
			(stroke
				(width 0.1)
				(type default)
			)
			(layer "B.Fab")
		)
		(fp_line
			(start 0.500126 -0.201422)
			(end -0.500126 -0.201422)
			(stroke
				(width 0.1)
				(type default)
			)
			(layer "B.Fab")
		)
		(pad "1" smd rect
			(at 0 0 180)
			(size 0.889 0.9906)
			(layers "B.Cu" "B.Mask" "B.Paste")
			(net "PVDDQ_DEF")
		)
		(pad "2" smd rect
			(at 0 1.397 180)
			(size 0.889 0.9906)
			(layers "B.Cu" "B.Mask" "B.Paste")
			(net "GND")
		)
		(zone
			(layer "B.Cu")
			(hatch none 0.5)
			(connect_pads
				(clearance 0)
			)
			(min_thickness 0.25)
			(keepout
				(tracks not_allowed)
				(vias allowed)
				(pads allowed)
				(copperpour not_allowed)
				(footprints allowed)
			)
			(placement
				(enabled no)
				(sheetname "")
			)
			(fill
				(thermal_gap 0.5)
				(thermal_bridge_width 0.5)
				(island_removal_mode 0)
			)
			(polygon
				(pts
					(xy 247.904 -134.9121) (xy 248.412 -134.9121) (xy 248.412 -135.9027) (xy 247.904 -135.9027)
				)
			)
		)
		(zone
			(layer "B.Cu")
			(hatch none 0.5)
			(connect_pads
				(clearance 0)
			)
			(min_thickness 0.25)
			(keepout
				(tracks allowed)
				(vias not_allowed)
				(pads allowed)
				(copperpour not_allowed)
				(footprints allowed)
			)
			(placement
				(enabled no)
				(sheetname "")
			)
			(fill
				(thermal_gap 0.5)
				(thermal_bridge_width 0.5)
				(island_removal_mode 0)
			)
			(polygon
				(pts
					(xy 247.904 -134.9121) (xy 248.412 -134.9121) (xy 248.412 -135.9027) (xy 247.904 -135.9027)
				)
			)
		)
	)
	(footprint ""
		(layer "B.Cu")
		(at 405.219408 -92.993718 -90)
		(property "Reference" "R2N17"
			(at 0 0 90)
			(layer "B.SilkS")
			(hide yes)
			(effects
				(font
					(size 1.27 1.27)
				)
				(justify mirror)
			)
		)
		(property "Value" ""
			(at 0 0 90)
			(layer "B.Fab")
			(effects
				(font
					(size 1.27 1.27)
				)
				(justify mirror)
			)
		)
		(duplicate_pad_numbers_are_jumpers no)
		(fp_poly
			(pts
				(xy 0.2794 -0.1016) (xy -0.2794 -0.1016) (xy -0.2794 0.9906) (xy 0.2794 0.9906)
			)
			(stroke
				(width 0)
				(type default)
			)
			(fill no)
			(layer "B.CrtYd")
		)
		(fp_line
			(start -0.2794 0.9906)
			(end -0.2794 -0.1016)
			(stroke
				(width 0.1)
				(type default)
			)
			(layer "B.Fab")
		)
		(fp_line
			(start 0.2794 0.9906)
			(end -0.2794 0.9906)
			(stroke
				(width 0.1)
				(type default)
			)
			(layer "B.Fab")
		)
		(fp_line
			(start -0.2794 -0.1016)
			(end 0.2794 -0.1016)
			(stroke
				(width 0.1)
				(type default)
			)
			(layer "B.Fab")
		)
		(fp_line
			(start 0.2794 -0.1016)
			(end 0.2794 0.9906)
			(stroke
				(width 0.1)
				(type default)
			)
			(layer "B.Fab")
		)
		(pad "1" smd rect
			(at 0 0 90)
			(size 0.508 0.508)
			(layers "B.Cu" "B.Mask" "B.Paste")
			(net "P3V3_STBY")
		)
		(pad "2" smd rect
			(at 0 0.889 90)
			(size 0.508 0.508)
			(layers "B.Cu" "B.Mask" "B.Paste")
			(net "FM_BOARD_SKU_ID4")
		)
		(zone
			(layer "B.Cu")
			(hatch none 0.5)
			(connect_pads
				(clearance 0)
			)
			(min_thickness 0.25)
			(keepout
				(tracks not_allowed)
				(vias allowed)
				(pads allowed)
				(copperpour not_allowed)
				(footprints allowed)
			)
			(placement
				(enabled no)
				(sheetname "")
			)
			(fill
				(thermal_gap 0.5)
				(thermal_bridge_width 0.5)
				(island_removal_mode 0)
			)
			(polygon
				(pts
					(xy 404.584408 -92.739718) (xy 404.584408 -93.247718) (xy 404.965408 -93.247718) (xy 404.965408 -92.739718)
				)
			)
		)
		(zone
			(layer "B.Cu")
			(hatch none 0.5)
			(connect_pads
				(clearance 0)
			)
			(min_thickness 0.25)
			(keepout
				(tracks allowed)
				(vias not_allowed)
				(pads allowed)
				(copperpour not_allowed)
				(footprints allowed)
			)
			(placement
				(enabled no)
				(sheetname "")
			)
			(fill
				(thermal_gap 0.5)
				(thermal_bridge_width 0.5)
				(island_removal_mode 0)
			)
			(polygon
				(pts
					(xy 404.965408 -92.739718) (xy 404.965408 -93.247718) (xy 404.584408 -93.247718) (xy 404.584408 -92.739718)
				)
			)
		)
	)
	(footprint ""
		(layer "B.Cu")
		(at 131.04622 -65.670938 -90)
		(property "Reference" "R7P28"
			(at 0 0 90)
			(layer "B.SilkS")
			(hide yes)
			(effects
				(font
					(size 1.27 1.27)
				)
				(justify mirror)
			)
		)
		(property "Value" ""
			(at 0 0 90)
			(layer "B.Fab")
			(effects
				(font
					(size 1.27 1.27)
				)
				(justify mirror)
			)
		)
		(duplicate_pad_numbers_are_jumpers no)
		(fp_poly
			(pts
				(xy 0.2794 -0.1016) (xy -0.2794 -0.1016) (xy -0.2794 0.9906) (xy 0.2794 0.9906)
			)
			(stroke
				(width 0)
				(type default)
			)
			(fill no)
			(layer "B.CrtYd")
		)
		(fp_line
			(start -0.2794 0.9906)
			(end -0.2794 -0.1016)
			(stroke
				(width 0.1)
				(type default)
			)
			(layer "B.Fab")
		)
		(fp_line
			(start 0.2794 0.9906)
			(end -0.2794 0.9906)
			(stroke
				(width 0.1)
				(type default)
			)
			(layer "B.Fab")
		)
		(fp_line
			(start -0.2794 -0.1016)
			(end 0.2794 -0.1016)
			(stroke
				(width 0.1)
				(type default)
			)
			(layer "B.Fab")
		)
		(fp_line
			(start 0.2794 -0.1016)
			(end 0.2794 0.9906)
			(stroke
				(width 0.1)
				(type default)
			)
			(layer "B.Fab")
		)
		(pad "1" smd rect
			(at 0 0 90)
			(size 0.508 0.508)
			(layers "B.Cu" "B.Mask" "B.Paste")
			(net "PVCCIO_CPU1")
		)
		(pad "2" smd rect
			(at 0 0.889 90)
			(size 0.508 0.508)
			(layers "B.Cu" "B.Mask" "B.Paste")
			(net "H_CPU1_PROCHOT_G_N")
		)
		(zone
			(layer "B.Cu")
			(hatch none 0.5)
			(connect_pads
				(clearance 0)
			)
			(min_thickness 0.25)
			(keepout
				(tracks not_allowed)
				(vias allowed)
				(pads allowed)
				(copperpour not_allowed)
				(footprints allowed)
			)
			(placement
				(enabled no)
				(sheetname "")
			)
			(fill
				(thermal_gap 0.5)
				(thermal_bridge_width 0.5)
				(island_removal_mode 0)
			)
			(polygon
				(pts
					(xy 130.41122 -65.416938) (xy 130.41122 -65.924938) (xy 130.79222 -65.924938) (xy 130.79222 -65.416938)
				)
			)
		)
		(zone
			(layer "B.Cu")
			(hatch none 0.5)
			(connect_pads
				(clearance 0)
			)
			(min_thickness 0.25)
			(keepout
				(tracks allowed)
				(vias not_allowed)
				(pads allowed)
				(copperpour not_allowed)
				(footprints allowed)
			)
			(placement
				(enabled no)
				(sheetname "")
			)
			(fill
				(thermal_gap 0.5)
				(thermal_bridge_width 0.5)
				(island_removal_mode 0)
			)
			(polygon
				(pts
					(xy 130.79222 -65.416938) (xy 130.79222 -65.924938) (xy 130.41122 -65.924938) (xy 130.41122 -65.416938)
				)
			)
		)
	)
	(footprint ""
		(layer "B.Cu")
		(at 402.606256 -29.603446 180)
		(property "Reference" "R25W120"
			(at -1.01473 0.656336 270)
			(unlocked yes)
			(layer "B.SilkS")
			(effects
				(font
					(size 0.4064 0.254)
					(thickness 0.1524)
				)
				(justify mirror)
			)
		)
		(property "Value" ""
			(at 0 0 0)
			(layer "B.Fab")
			(effects
				(font
					(size 1.27 1.27)
				)
				(justify mirror)
			)
		)
		(duplicate_pad_numbers_are_jumpers no)
		(fp_poly
			(pts
				(xy 0.4953 -0.2032) (xy -0.4953 -0.2032) (xy -0.4953 1.6002) (xy 0.4953 1.6002)
			)
			(stroke
				(width 0)
				(type default)
			)
			(fill no)
			(layer "B.CrtYd")
		)
		(fp_line
			(start 0.4953 1.6002)
			(end 0.4953 -0.2032)
			(stroke
				(width 0.1)
				(type default)
			)
			(layer "B.Fab")
		)
		(fp_line
			(start 0.4953 -0.2032)
			(end -0.4953 -0.2032)
			(stroke
				(width 0.1)
				(type default)
			)
			(layer "B.Fab")
		)
		(fp_line
			(start -0.4953 1.6002)
			(end 0.4953 1.6002)
			(stroke
				(width 0.1)
				(type default)
			)
			(layer "B.Fab")
		)
		(fp_line
			(start -0.4953 -0.2032)
			(end -0.4953 1.6002)
			(stroke
				(width 0.1)
				(type default)
			)
			(layer "B.Fab")
		)
		(pad "1" smd rect
			(at 0 0)
			(size 0.762 0.889)
			(layers "B.Cu" "B.Mask" "B.Paste")
			(net "P3V3_STBY")
		)
		(pad "2" smd rect
			(at 0 1.397)
			(size 0.762 0.889)
			(layers "B.Cu" "B.Mask" "B.Paste")
			(net "P3V3_USB2A_ALG")
		)
		(zone
			(layer "B.Cu")
			(hatch none 0.5)
			(connect_pads
				(clearance 0)
			)
			(min_thickness 0.25)
			(keepout
				(tracks not_allowed)
				(vias allowed)
				(pads allowed)
				(copperpour not_allowed)
				(footprints allowed)
			)
			(placement
				(enabled no)
				(sheetname "")
			)
			(fill
				(thermal_gap 0.5)
				(thermal_bridge_width 0.5)
				(island_removal_mode 0)
			)
			(polygon
				(pts
					(xy 402.225256 -30.555946) (xy 402.225256 -30.047946) (xy 402.987256 -30.047946) (xy 402.987256 -30.555946)
				)
			)
		)
		(zone
			(layer "B.Cu")
			(hatch none 0.5)
			(connect_pads
				(clearance 0)
			)
			(min_thickness 0.25)
			(keepout
				(tracks allowed)
				(vias not_allowed)
				(pads allowed)
				(copperpour not_allowed)
				(footprints allowed)
			)
			(placement
				(enabled no)
				(sheetname "")
			)
			(fill
				(thermal_gap 0.5)
				(thermal_bridge_width 0.5)
				(island_removal_mode 0)
			)
			(polygon
				(pts
					(xy 402.987256 -30.555946) (xy 402.987256 -30.047946) (xy 402.225256 -30.047946) (xy 402.225256 -30.555946)
				)
			)
		)
	)
	(footprint ""
		(layer "B.Cu")
		(at 367.968276 -156.15158 180)
		(property "Reference" "C22W27"
			(at 0 0 0)
			(layer "B.SilkS")
			(hide yes)
			(effects
				(font
					(size 1.27 1.27)
				)
				(justify mirror)
			)
		)
		(property "Value" "*"
			(at 0.0762 -6.2357 180)
			(unlocked yes)
			(layer "B.Fab")
			(hide yes)
			(effects
				(font
					(size 1.27 1.016)
					(thickness 0.1524)
				)
				(justify mirror)
			)
		)
		(property "Device Type" "SC22U16V5MX-4-GP_SMD-BCG5-SC22A"
			(at 0.0762 -8.2677 180)
			(unlocked yes)
			(layer "B.Fab")
			(hide yes)
			(effects
				(font
					(size 1.27 1.016)
					(thickness 0.1524)
				)
				(justify mirror)
			)
		)
		(duplicate_pad_numbers_are_jumpers no)
		(fp_line
			(start -0.635 0)
			(end 0.635 0)
			(stroke
				(width 0.508)
				(type default)
			)
			(layer "B.SilkS")
		)
		(fp_rect
			(start 0.9652 1.778)
			(end -0.9652 -1.778)
			(stroke
				(width 0)
				(type default)
			)
			(fill no)
			(layer "B.CrtYd")
		)
		(fp_poly
			(pts
				(xy 0.9652 -1.778) (xy -0.9652 -1.778) (xy -0.9652 1.778) (xy 0.9652 1.778)
			)
			(stroke
				(width 0)
				(type default)
			)
			(fill no)
			(layer "B.Fab")
		)
		(pad "1" smd rect
			(at 0 -0.9652)
			(size 1.397 1.143)
			(layers "B.Cu" "B.Mask" "B.Paste")
			(net "VR_FET_SW_P12V_STBY_PVDDQ_DEF")
		)
		(pad "2" smd rect
			(at 0 0.9652)
			(size 1.397 1.143)
			(layers "B.Cu" "B.Mask" "B.Paste")
			(net "GND")
		)
	)
	(footprint ""
		(layer "B.Cu")
		(at 176.276 -20.193)
		(property "Reference" "R6T5"
			(at 0 0 0)
			(layer "B.SilkS")
			(hide yes)
			(effects
				(font
					(size 1.27 1.27)
				)
				(justify mirror)
			)
		)
		(property "Value" ""
			(at 0 0 0)
			(layer "B.Fab")
			(effects
				(font
					(size 1.27 1.27)
				)
				(justify mirror)
			)
		)
		(duplicate_pad_numbers_are_jumpers no)
		(fp_poly
			(pts
				(xy 0.2794 -0.1016) (xy -0.2794 -0.1016) (xy -0.2794 0.9906) (xy 0.2794 0.9906)
			)
			(stroke
				(width 0)
				(type default)
			)
			(fill no)
			(layer "B.CrtYd")
		)
		(fp_line
			(start -0.2794 -0.1016)
			(end 0.2794 -0.1016)
			(stroke
				(width 0.1)
				(type default)
			)
			(layer "B.Fab")
		)
		(fp_line
			(start -0.2794 0.9906)
			(end -0.2794 -0.1016)
			(stroke
				(width 0.1)
				(type default)
			)
			(layer "B.Fab")
		)
		(fp_line
			(start 0.2794 -0.1016)
			(end 0.2794 0.9906)
			(stroke
				(width 0.1)
				(type default)
			)
			(layer "B.Fab")
		)
		(fp_line
			(start 0.2794 0.9906)
			(end -0.2794 0.9906)
			(stroke
				(width 0.1)
				(type default)
			)
			(layer "B.Fab")
		)
		(pad "1" smd rect
			(at 0 0 180)
			(size 0.508 0.508)
			(layers "B.Cu" "B.Mask" "B.Paste")
			(net "XDP_CPU_TRST_N")
		)
		(pad "2" smd rect
			(at 0 0.889 180)
			(size 0.508 0.508)
			(layers "B.Cu" "B.Mask" "B.Paste")
			(net "GND")
		)
		(zone
			(layer "B.Cu")
			(hatch none 0.5)
			(connect_pads
				(clearance 0)
			)
			(min_thickness 0.25)
			(keepout
				(tracks allowed)
				(vias not_allowed)
				(pads allowed)
				(copperpour not_allowed)
				(footprints allowed)
			)
			(placement
				(enabled no)
				(sheetname "")
			)
			(fill
				(thermal_gap 0.5)
				(thermal_bridge_width 0.5)
				(island_removal_mode 0)
			)
			(polygon
				(pts
					(xy 176.53 -19.939) (xy 176.022 -19.939) (xy 176.022 -19.558) (xy 176.53 -19.558)
				)
			)
		)
		(zone
			(layer "B.Cu")
			(hatch none 0.5)
			(connect_pads
				(clearance 0)
			)
			(min_thickness 0.25)
			(keepout
				(tracks not_allowed)
				(vias allowed)
				(pads allowed)
				(copperpour not_allowed)
				(footprints allowed)
			)
			(placement
				(enabled no)
				(sheetname "")
			)
			(fill
				(thermal_gap 0.5)
				(thermal_bridge_width 0.5)
				(island_removal_mode 0)
			)
			(polygon
				(pts
					(xy 176.53 -19.558) (xy 176.022 -19.558) (xy 176.022 -19.939) (xy 176.53 -19.939)
				)
			)
		)
	)
	(footprint ""
		(layer "B.Cu")
		(at 433.578 -151.257 -90)
		(property "Reference" "R2L15"
			(at 0 0 90)
			(layer "B.SilkS")
			(hide yes)
			(effects
				(font
					(size 1.27 1.27)
				)
				(justify mirror)
			)
		)
		(property "Value" ""
			(at 0 0 90)
			(layer "B.Fab")
			(effects
				(font
					(size 1.27 1.27)
				)
				(justify mirror)
			)
		)
		(duplicate_pad_numbers_are_jumpers no)
		(fp_poly
			(pts
				(xy 0.2794 -0.1016) (xy -0.2794 -0.1016) (xy -0.2794 0.9906) (xy 0.2794 0.9906)
			)
			(stroke
				(width 0)
				(type default)
			)
			(fill no)
			(layer "B.CrtYd")
		)
		(fp_line
			(start -0.2794 0.9906)
			(end -0.2794 -0.1016)
			(stroke
				(width 0.1)
				(type default)
			)
			(layer "B.Fab")
		)
		(fp_line
			(start 0.2794 0.9906)
			(end -0.2794 0.9906)
			(stroke
				(width 0.1)
				(type default)
			)
			(layer "B.Fab")
		)
		(fp_line
			(start -0.2794 -0.1016)
			(end 0.2794 -0.1016)
			(stroke
				(width 0.1)
				(type default)
			)
			(layer "B.Fab")
		)
		(fp_line
			(start 0.2794 -0.1016)
			(end 0.2794 0.9906)
			(stroke
				(width 0.1)
				(type default)
			)
			(layer "B.Fab")
		)
		(pad "1" smd rect
			(at 0 0 90)
			(size 0.508 0.508)
			(layers "B.Cu" "B.Mask" "B.Paste")
			(net "P3V3_STBY")
		)
		(pad "2" smd rect
			(at 0 0.889 90)
			(size 0.508 0.508)
			(layers "B.Cu" "B.Mask" "B.Paste")
			(net "SGPIO_PCH_SATA_DOUT0_R")
		)
		(zone
			(layer "B.Cu")
			(hatch none 0.5)
			(connect_pads
				(clearance 0)
			)
			(min_thickness 0.25)
			(keepout
				(tracks not_allowed)
				(vias allowed)
				(pads allowed)
				(copperpour not_allowed)
				(footprints allowed)
			)
			(placement
				(enabled no)
				(sheetname "")
			)
			(fill
				(thermal_gap 0.5)
				(thermal_bridge_width 0.5)
				(island_removal_mode 0)
			)
			(polygon
				(pts
					(xy 432.943 -151.003) (xy 432.943 -151.511) (xy 433.324 -151.511) (xy 433.324 -151.003)
				)
			)
		)
		(zone
			(layer "B.Cu")
			(hatch none 0.5)
			(connect_pads
				(clearance 0)
			)
			(min_thickness 0.25)
			(keepout
				(tracks allowed)
				(vias not_allowed)
				(pads allowed)
				(copperpour not_allowed)
				(footprints allowed)
			)
			(placement
				(enabled no)
				(sheetname "")
			)
			(fill
				(thermal_gap 0.5)
				(thermal_bridge_width 0.5)
				(island_removal_mode 0)
			)
			(polygon
				(pts
					(xy 433.324 -151.003) (xy 433.324 -151.511) (xy 432.943 -151.511) (xy 432.943 -151.003)
				)
			)
		)
	)
	(footprint ""
		(layer "B.Cu")
		(at 169.545 -65.024)
		(property "Reference" "CF14"
			(at 0 0 0)
			(layer "B.SilkS")
			(hide yes)
			(effects
				(font
					(size 1.27 1.27)
				)
				(justify mirror)
			)
		)
		(property "Value" "*"
			(at -1.1811 -2.8194 0)
			(unlocked yes)
			(layer "B.Fab")
			(hide yes)
			(effects
				(font
					(size 1.27 1.016)
					(thickness 0.1524)
				)
				(justify mirror)
			)
		)
		(property "Device Type" "SC22P50V2JN-4GP_SMD-BCG-SC22P5A"
			(at -1.1811 -4.3434 0)
			(unlocked yes)
			(layer "B.Fab")
			(hide yes)
			(effects
				(font
					(size 1.27 1.016)
					(thickness 0.1524)
				)
				(justify mirror)
			)
		)
		(duplicate_pad_numbers_are_jumpers no)
		(fp_rect
			(start 0.4318 0.9525)
			(end -0.4318 -0.9525)
			(stroke
				(width 0)
				(type default)
			)
			(fill no)
			(layer "B.CrtYd")
		)
		(fp_rect
			(start 0.4318 0.9525)
			(end -0.4318 -0.9525)
			(stroke
				(width 0)
				(type default)
			)
			(fill no)
			(layer "B.Fab")
		)
		(pad "1" smd custom
			(at 0 -0.4445 180)
			(size 0.1524 0.1524)
			(layers "B.Cu" "B.Mask" "B.Paste")
			(net "VR_PVCCIO_CPU1_AIREF1")
			(options
				(clearance outline)
				(anchor circle)
			)
			(primitives
				(gr_poly
					(pts
						(arc
							(start 0.3048 0.2032)
							(mid 0.275042 0.275042)
							(end 0.2032 0.3048)
						)
						(arc
							(start -0.2032 0.3048)
							(mid -0.275042 0.275042)
							(end -0.3048 0.2032)
						)
						(arc
							(start -0.3048 -0.2032)
							(mid -0.275042 -0.275042)
							(end -0.2032 -0.3048)
						)
						(arc
							(start 0.2032 -0.3048)
							(mid 0.275042 -0.275042)
							(end 0.3048 -0.2032)
						)
					)
					(width 0)
					(fill yes)
				)
			)
		)
		(pad "2" smd custom
			(at 0 0.4445 180)
			(size 0.1524 0.1524)
			(layers "B.Cu" "B.Mask" "B.Paste")
			(net "ISENSE_PVCCIO_CPU1_PH1_IMON")
			(options
				(clearance outline)
				(anchor circle)
			)
			(primitives
				(gr_poly
					(pts
						(arc
							(start 0.3048 0.2032)
							(mid 0.275042 0.275042)
							(end 0.2032 0.3048)
						)
						(arc
							(start -0.2032 0.3048)
							(mid -0.275042 0.275042)
							(end -0.3048 0.2032)
						)
						(arc
							(start -0.3048 -0.2032)
							(mid -0.275042 -0.275042)
							(end -0.2032 -0.3048)
						)
						(arc
							(start 0.2032 -0.3048)
							(mid 0.275042 -0.275042)
							(end 0.3048 -0.2032)
						)
					)
					(width 0)
					(fill yes)
				)
			)
		)
	)
	(footprint ""
		(layer "B.Cu")
		(at 349.133414 -125.227842 -90)
		(property "Reference" "R768"
			(at 0.8382 -0.67818 270)
			(unlocked yes)
			(layer "B.SilkS")
			(effects
				(font
					(size 0.4064 0.254)
					(thickness 0.1524)
				)
				(justify left mirror)
			)
		)
		(property "Value" ""
			(at 0 0 90)
			(layer "B.Fab")
			(effects
				(font
					(size 1.27 1.27)
				)
				(justify mirror)
			)
		)
		(duplicate_pad_numbers_are_jumpers no)
		(fp_poly
			(pts
				(xy 0.2794 -0.1016) (xy -0.2794 -0.1016) (xy -0.2794 0.9906) (xy 0.2794 0.9906)
			)
			(stroke
				(width 0)
				(type default)
			)
			(fill no)
			(layer "B.CrtYd")
		)
		(fp_line
			(start -0.2794 0.9906)
			(end -0.2794 -0.1016)
			(stroke
				(width 0.1)
				(type default)
			)
			(layer "B.Fab")
		)
		(fp_line
			(start 0.2794 0.9906)
			(end -0.2794 0.9906)
			(stroke
				(width 0.1)
				(type default)
			)
			(layer "B.Fab")
		)
		(fp_line
			(start -0.2794 -0.1016)
			(end 0.2794 -0.1016)
			(stroke
				(width 0.1)
				(type default)
			)
			(layer "B.Fab")
		)
		(fp_line
			(start 0.2794 -0.1016)
			(end 0.2794 0.9906)
			(stroke
				(width 0.1)
				(type default)
			)
			(layer "B.Fab")
		)
		(pad "1" smd rect
			(at 0 0 90)
			(size 0.508 0.508)
			(layers "B.Cu" "B.Mask" "B.Paste")
			(net "P3E_CPU0_PE1_PCH_RXN<14>")
		)
		(pad "2" smd rect
			(at 0 0.889 90)
			(size 0.508 0.508)
			(layers "B.Cu" "B.Mask" "B.Paste")
			(net "P3E_CPU0_PE1_PCH_CON_RXN<14>")
		)
		(zone
			(layer "B.Cu")
			(hatch none 0.5)
			(connect_pads
				(clearance 0)
			)
			(min_thickness 0.25)
			(keepout
				(tracks not_allowed)
				(vias allowed)
				(pads allowed)
				(copperpour not_allowed)
				(footprints allowed)
			)
			(placement
				(enabled no)
				(sheetname "")
			)
			(fill
				(thermal_gap 0.5)
				(thermal_bridge_width 0.5)
				(island_removal_mode 0)
			)
			(polygon
				(pts
					(xy 348.498414 -124.973842) (xy 348.498414 -125.481842) (xy 348.879414 -125.481842) (xy 348.879414 -124.973842)
				)
			)
		)
		(zone
			(layer "B.Cu")
			(hatch none 0.5)
			(connect_pads
				(clearance 0)
			)
			(min_thickness 0.25)
			(keepout
				(tracks allowed)
				(vias not_allowed)
				(pads allowed)
				(copperpour not_allowed)
				(footprints allowed)
			)
			(placement
				(enabled no)
				(sheetname "")
			)
			(fill
				(thermal_gap 0.5)
				(thermal_bridge_width 0.5)
				(island_removal_mode 0)
			)
			(polygon
				(pts
					(xy 348.879414 -124.973842) (xy 348.879414 -125.481842) (xy 348.498414 -125.481842) (xy 348.498414 -124.973842)
				)
			)
		)
	)
	(footprint ""
		(layer "B.Cu")
		(at 18.4404 -4.445)
		(property "Reference" "C9U9"
			(at -3.60807 0.254 270)
			(unlocked yes)
			(layer "B.SilkS")
			(effects
				(font
					(size 0.7874 0.5842)
					(thickness 0.1524)
				)
				(justify mirror)
			)
		)
		(property "Value" ""
			(at 0 0 0)
			(layer "B.Fab")
			(effects
				(font
					(size 1.27 1.27)
				)
				(justify mirror)
			)
		)
		(duplicate_pad_numbers_are_jumpers no)
		(fp_line
			(start -2.504948 -1.616456)
			(end -2.504948 1.633728)
			(stroke
				(width 0.1524)
				(type default)
			)
			(layer "B.SilkS")
		)
		(fp_line
			(start -2.504948 1.633728)
			(end -1.6002 1.633728)
			(stroke
				(width 0.1524)
				(type default)
			)
			(layer "B.SilkS")
		)
		(fp_line
			(start -2.286 7.366)
			(end -2.286 1.63195)
			(stroke
				(width 0.1524)
				(type default)
			)
			(layer "B.SilkS")
		)
		(fp_line
			(start -2.286 7.366)
			(end -1.600708 7.366)
			(stroke
				(width 0.1524)
				(type default)
			)
			(layer "B.SilkS")
		)
		(fp_line
			(start -1.6002 -1.616456)
			(end -2.504948 -1.616456)
			(stroke
				(width 0.1524)
				(type default)
			)
			(layer "B.SilkS")
		)
		(fp_line
			(start 1.6002 -1.616456)
			(end 2.563114 -1.616456)
			(stroke
				(width 0.1524)
				(type default)
			)
			(layer "B.SilkS")
		)
		(fp_line
			(start 2.286 7.366)
			(end 1.60147 7.366)
			(stroke
				(width 0.1524)
				(type default)
			)
			(layer "B.SilkS")
		)
		(fp_line
			(start 2.286 7.366)
			(end 2.286 1.632712)
			(stroke
				(width 0.1524)
				(type default)
			)
			(layer "B.SilkS")
		)
		(fp_line
			(start 2.563114 -1.616456)
			(end 2.563114 1.633728)
			(stroke
				(width 0.1524)
				(type default)
			)
			(layer "B.SilkS")
		)
		(fp_line
			(start 2.563114 1.633728)
			(end 1.6002 1.633728)
			(stroke
				(width 0.1524)
				(type default)
			)
			(layer "B.SilkS")
		)
		(fp_rect
			(start 2.286 -0.254)
			(end -2.286 7.366)
			(stroke
				(width 0)
				(type default)
			)
			(fill no)
			(layer "B.CrtYd")
		)
		(fp_line
			(start -2.286 -0.254)
			(end -2.286 7.366)
			(stroke
				(width 0.1)
				(type default)
			)
			(layer "B.Fab")
		)
		(fp_line
			(start -2.286 7.366)
			(end 2.286 7.366)
			(stroke
				(width 0.1)
				(type default)
			)
			(layer "B.Fab")
		)
		(fp_line
			(start 2.286 -0.254)
			(end -2.286 -0.254)
			(stroke
				(width 0.1)
				(type default)
			)
			(layer "B.Fab")
		)
		(fp_line
			(start 2.286 7.366)
			(end 2.286 -0.254)
			(stroke
				(width 0.1)
				(type default)
			)
			(layer "B.Fab")
		)
		(pad "1" smd rect
			(at 0 0 180)
			(size 2.54 3.048)
			(layers "B.Cu" "B.Mask" "B.Paste")
			(net "PVDDQ_GHJ")
		)
		(pad "2" smd rect
			(at 0 7.112 180)
			(size 2.54 3.048)
			(layers "B.Cu" "B.Mask" "B.Paste")
			(net "GND")
		)
	)
	(footprint ""
		(layer "B.Cu")
		(at 177.906426 -20.2057 90)
		(property "Reference" "R6T7"
			(at 0 0 90)
			(layer "B.SilkS")
			(hide yes)
			(effects
				(font
					(size 1.27 1.27)
				)
				(justify mirror)
			)
		)
		(property "Value" ""
			(at 0 0 90)
			(layer "B.Fab")
			(effects
				(font
					(size 1.27 1.27)
				)
				(justify mirror)
			)
		)
		(duplicate_pad_numbers_are_jumpers no)
		(fp_poly
			(pts
				(xy 0.2794 -0.1016) (xy -0.2794 -0.1016) (xy -0.2794 0.9906) (xy 0.2794 0.9906)
			)
			(stroke
				(width 0)
				(type default)
			)
			(fill no)
			(layer "B.CrtYd")
		)
		(fp_line
			(start 0.2794 -0.1016)
			(end 0.2794 0.9906)
			(stroke
				(width 0.1)
				(type default)
			)
			(layer "B.Fab")
		)
		(fp_line
			(start -0.2794 -0.1016)
			(end 0.2794 -0.1016)
			(stroke
				(width 0.1)
				(type default)
			)
			(layer "B.Fab")
		)
		(fp_line
			(start 0.2794 0.9906)
			(end -0.2794 0.9906)
			(stroke
				(width 0.1)
				(type default)
			)
			(layer "B.Fab")
		)
		(fp_line
			(start -0.2794 0.9906)
			(end -0.2794 -0.1016)
			(stroke
				(width 0.1)
				(type default)
			)
			(layer "B.Fab")
		)
		(pad "1" smd rect
			(at 0 0 270)
			(size 0.508 0.508)
			(layers "B.Cu" "B.Mask" "B.Paste")
			(net "PVCCIO_CPU1")
		)
		(pad "2" smd rect
			(at 0 0.889 270)
			(size 0.508 0.508)
			(layers "B.Cu" "B.Mask" "B.Paste")
			(net "XDP_CPU1_TDO")
		)
		(zone
			(layer "B.Cu")
			(hatch none 0.5)
			(connect_pads
				(clearance 0)
			)
			(min_thickness 0.25)
			(keepout
				(tracks allowed)
				(vias not_allowed)
				(pads allowed)
				(copperpour not_allowed)
				(footprints allowed)
			)
			(placement
				(enabled no)
				(sheetname "")
			)
			(fill
				(thermal_gap 0.5)
				(thermal_bridge_width 0.5)
				(island_removal_mode 0)
			)
			(polygon
				(pts
					(xy 178.160426 -20.4597) (xy 178.160426 -19.9517) (xy 178.541426 -19.9517) (xy 178.541426 -20.4597)
				)
			)
		)
		(zone
			(layer "B.Cu")
			(hatch none 0.5)
			(connect_pads
				(clearance 0)
			)
			(min_thickness 0.25)
			(keepout
				(tracks not_allowed)
				(vias allowed)
				(pads allowed)
				(copperpour not_allowed)
				(footprints allowed)
			)
			(placement
				(enabled no)
				(sheetname "")
			)
			(fill
				(thermal_gap 0.5)
				(thermal_bridge_width 0.5)
				(island_removal_mode 0)
			)
			(polygon
				(pts
					(xy 178.541426 -20.4597) (xy 178.541426 -19.9517) (xy 178.160426 -19.9517) (xy 178.160426 -20.4597)
				)
			)
		)
	)
	(footprint ""
		(layer "B.Cu")
		(at 370.929916 -37.08654 180)
		(property "Reference" "U7E2"
			(at -3.302 2.274316 0)
			(unlocked yes)
			(layer "B.SilkS")
			(effects
				(font
					(size 0.7874 0.5842)
					(thickness 0.1524)
				)
				(justify left mirror)
			)
		)
		(property "Value" ""
			(at 0 0 0)
			(layer "B.Fab")
			(effects
				(font
					(size 1.27 1.27)
				)
				(justify mirror)
			)
		)
		(duplicate_pad_numbers_are_jumpers no)
		(fp_circle
			(center 0.4699 -0.8382)
			(end 0.3429 -0.8382)
			(stroke
				(width 0.254)
				(type default)
			)
			(fill no)
			(layer "B.SilkS")
		)
		(fp_poly
			(pts
				(xy -0.21463 -0.450088) (xy -1.56337 -0.450088) (xy -1.56337 1.75006) (xy -0.21463 1.75006)
			)
			(stroke
				(width 0)
				(type default)
			)
			(fill no)
			(layer "B.CrtYd")
		)
		(fp_line
			(start -0.21463 1.75006)
			(end -0.21463 -0.450088)
			(stroke
				(width 0.1)
				(type default)
			)
			(layer "B.Fab")
		)
		(fp_line
			(start -0.21463 -0.450088)
			(end -1.56337 -0.450088)
			(stroke
				(width 0.1)
				(type default)
			)
			(layer "B.Fab")
		)
		(fp_line
			(start -1.56337 1.75006)
			(end -0.21463 1.75006)
			(stroke
				(width 0.1)
				(type default)
			)
			(layer "B.Fab")
		)
		(fp_line
			(start -1.56337 -0.450088)
			(end -1.56337 1.75006)
			(stroke
				(width 0.1)
				(type default)
			)
			(layer "B.Fab")
		)
		(fp_circle
			(center 0.4699 -0.8382)
			(end 0.3429 -0.8382)
			(stroke
				(width 0.254)
				(type default)
			)
			(fill no)
			(layer "B.Fab")
		)
		(pad "1" smd rect
			(at 0 0)
			(size 1.016 0.381)
			(layers "B.Cu" "B.Mask" "B.Paste")
			(net "FM_PVCCIN_CPU0_PWR_IN_ALERT_N")
		)
		(pad "2" smd rect
			(at 0 0.649986)
			(size 1.016 0.381)
			(layers "B.Cu" "B.Mask" "B.Paste")
			(net "IRQ_PVCCIN_CPU0_VRHOT_LVC3_N")
		)
		(pad "3" smd rect
			(at 0 1.299972)
			(size 1.016 0.381)
			(layers "B.Cu" "B.Mask" "B.Paste")
			(net "GND")
		)
		(pad "4" smd rect
			(at -1.778 1.299972)
			(size 1.016 0.381)
			(layers "B.Cu" "B.Mask" "B.Paste")
			(net "IRQ_CPU0_PROCHOT_G_N")
		)
		(pad "5" smd rect
			(at -1.778 0)
			(size 1.016 0.381)
			(layers "B.Cu" "B.Mask" "B.Paste")
			(net "P3V3_STBY")
		)
	)
	(footprint ""
		(layer "B.Cu")
		(at 481.2665 -30.226 -90)
		(property "Reference" "C2T30"
			(at 0 0 90)
			(layer "B.SilkS")
			(hide yes)
			(effects
				(font
					(size 1.27 1.27)
				)
				(justify mirror)
			)
		)
		(property "Value" ""
			(at 0 0 90)
			(layer "B.Fab")
			(effects
				(font
					(size 1.27 1.27)
				)
				(justify mirror)
			)
		)
		(duplicate_pad_numbers_are_jumpers no)
		(fp_poly
			(pts
				(xy -0.3048 -0.1016) (xy -0.3048 0.9906) (xy 0.3048 0.9906) (xy 0.3048 -0.1016)
			)
			(stroke
				(width 0)
				(type default)
			)
			(fill no)
			(layer "B.CrtYd")
		)
		(fp_line
			(start -0.3048 0.9906)
			(end -0.3048 -0.1016)
			(stroke
				(width 0.1)
				(type default)
			)
			(layer "B.Fab")
		)
		(fp_line
			(start 0.3048 0.9906)
			(end -0.3048 0.9906)
			(stroke
				(width 0.1)
				(type default)
			)
			(layer "B.Fab")
		)
		(fp_line
			(start -0.3048 -0.1016)
			(end 0.3048 -0.1016)
			(stroke
				(width 0.1)
				(type default)
			)
			(layer "B.Fab")
		)
		(fp_line
			(start 0.3048 -0.1016)
			(end 0.3048 0.9906)
			(stroke
				(width 0.1)
				(type default)
			)
			(layer "B.Fab")
		)
		(pad "1" smd rect
			(at 0 0 90)
			(size 0.508 0.508)
			(layers "B.Cu" "B.Mask" "B.Paste")
			(net "P3V3_STBY_MNG")
		)
		(pad "2" smd rect
			(at 0 0.889 90)
			(size 0.508 0.508)
			(layers "B.Cu" "B.Mask" "B.Paste")
			(net "GND")
		)
		(zone
			(layer "B.Cu")
			(hatch none 0.5)
			(connect_pads
				(clearance 0)
			)
			(min_thickness 0.25)
			(keepout
				(tracks not_allowed)
				(vias allowed)
				(pads allowed)
				(copperpour not_allowed)
				(footprints allowed)
			)
			(placement
				(enabled no)
				(sheetname "")
			)
			(fill
				(thermal_gap 0.5)
				(thermal_bridge_width 0.5)
				(island_removal_mode 0)
			)
			(polygon
				(pts
					(xy 480.6315 -29.972) (xy 480.6315 -30.48) (xy 481.0125 -30.48) (xy 481.0125 -29.972)
				)
			)
		)
		(zone
			(layer "B.Cu")
			(hatch none 0.5)
			(connect_pads
				(clearance 0)
			)
			(min_thickness 0.25)
			(keepout
				(tracks allowed)
				(vias not_allowed)
				(pads allowed)
				(copperpour not_allowed)
				(footprints allowed)
			)
			(placement
				(enabled no)
				(sheetname "")
			)
			(fill
				(thermal_gap 0.5)
				(thermal_bridge_width 0.5)
				(island_removal_mode 0)
			)
			(polygon
				(pts
					(xy 481.0125 -29.972) (xy 481.0125 -30.48) (xy 480.6315 -30.48) (xy 480.6315 -29.972)
				)
			)
		)
	)
	(footprint ""
		(layer "B.Cu")
		(at 435.381654 -141.002512 180)
		(property "Reference" "C2L49"
			(at 0 0 0)
			(layer "B.SilkS")
			(hide yes)
			(effects
				(font
					(size 1.27 1.27)
				)
				(justify mirror)
			)
		)
		(property "Value" ""
			(at 0 0 0)
			(layer "B.Fab")
			(effects
				(font
					(size 1.27 1.27)
				)
				(justify mirror)
			)
		)
		(duplicate_pad_numbers_are_jumpers no)
		(fp_poly
			(pts
				(xy -0.3048 -0.1016) (xy -0.3048 0.9906) (xy 0.3048 0.9906) (xy 0.3048 -0.1016)
			)
			(stroke
				(width 0)
				(type default)
			)
			(fill no)
			(layer "B.CrtYd")
		)
		(fp_line
			(start 0.3048 0.9906)
			(end -0.3048 0.9906)
			(stroke
				(width 0.1)
				(type default)
			)
			(layer "B.Fab")
		)
		(fp_line
			(start 0.3048 -0.1016)
			(end 0.3048 0.9906)
			(stroke
				(width 0.1)
				(type default)
			)
			(layer "B.Fab")
		)
		(fp_line
			(start -0.3048 0.9906)
			(end -0.3048 -0.1016)
			(stroke
				(width 0.1)
				(type default)
			)
			(layer "B.Fab")
		)
		(fp_line
			(start -0.3048 -0.1016)
			(end 0.3048 -0.1016)
			(stroke
				(width 0.1)
				(type default)
			)
			(layer "B.Fab")
		)
		(pad "1" smd rect
			(at 0 0)
			(size 0.508 0.508)
			(layers "B.Cu" "B.Mask" "B.Paste")
			(net "SATA6G_S1_RX_C_DP")
		)
		(pad "2" smd rect
			(at 0 0.889)
			(size 0.508 0.508)
			(layers "B.Cu" "B.Mask" "B.Paste")
			(net "SATA6G_S1_RX_DP")
		)
		(zone
			(layer "B.Cu")
			(hatch none 0.5)
			(connect_pads
				(clearance 0)
			)
			(min_thickness 0.25)
			(keepout
				(tracks not_allowed)
				(vias allowed)
				(pads allowed)
				(copperpour not_allowed)
				(footprints allowed)
			)
			(placement
				(enabled no)
				(sheetname "")
			)
			(fill
				(thermal_gap 0.5)
				(thermal_bridge_width 0.5)
				(island_removal_mode 0)
			)
			(polygon
				(pts
					(xy 435.127654 -141.637512) (xy 435.635654 -141.637512) (xy 435.635654 -141.256512) (xy 435.127654 -141.256512)
				)
			)
		)
		(zone
			(layer "B.Cu")
			(hatch none 0.5)
			(connect_pads
				(clearance 0)
			)
			(min_thickness 0.25)
			(keepout
				(tracks allowed)
				(vias not_allowed)
				(pads allowed)
				(copperpour not_allowed)
				(footprints allowed)
			)
			(placement
				(enabled no)
				(sheetname "")
			)
			(fill
				(thermal_gap 0.5)
				(thermal_bridge_width 0.5)
				(island_removal_mode 0)
			)
			(polygon
				(pts
					(xy 435.127654 -141.256512) (xy 435.635654 -141.256512) (xy 435.635654 -141.637512) (xy 435.127654 -141.637512)
				)
			)
		)
	)
	(footprint ""
		(layer "B.Cu")
		(at 477.29521 -150.174706)
		(property "Reference" "Q1L2"
			(at -1.8796 2.23647 0)
			(unlocked yes)
			(layer "B.SilkS")
			(effects
				(font
					(size 0.7874 0.5842)
					(thickness 0.1524)
				)
				(justify left mirror)
			)
		)
		(property "Value" ""
			(at 0 0 0)
			(layer "B.Fab")
			(effects
				(font
					(size 1.27 1.27)
				)
				(justify mirror)
			)
		)
		(duplicate_pad_numbers_are_jumpers no)
		(fp_circle
			(center 0.508 -0.7874)
			(end 0.635 -0.7874)
			(stroke
				(width 0.254)
				(type default)
			)
			(fill no)
			(layer "B.SilkS")
		)
		(fp_poly
			(pts
				(xy -0.2159 1.7526) (xy -1.5621 1.7526) (xy -1.5621 -0.4572) (xy -0.2159 -0.4572)
			)
			(stroke
				(width 0)
				(type default)
			)
			(fill no)
			(layer "B.CrtYd")
		)
		(fp_line
			(start -1.5621 -0.45466)
			(end -0.2159 -0.45466)
			(stroke
				(width 0.1)
				(type default)
			)
			(layer "B.Fab")
		)
		(fp_line
			(start -1.5621 1.75514)
			(end -1.5621 -0.45466)
			(stroke
				(width 0.1)
				(type default)
			)
			(layer "B.Fab")
		)
		(fp_line
			(start -0.2159 -0.45466)
			(end -0.2159 1.75514)
			(stroke
				(width 0.1)
				(type default)
			)
			(layer "B.Fab")
		)
		(fp_line
			(start -0.2159 1.75514)
			(end -1.5621 1.75514)
			(stroke
				(width 0.1)
				(type default)
			)
			(layer "B.Fab")
		)
		(fp_circle
			(center 0.508 -0.7874)
			(end 0.635 -0.7874)
			(stroke
				(width 0.254)
				(type default)
			)
			(fill no)
			(layer "B.Fab")
		)
		(pad "1" smd rect
			(at 0 0 180)
			(size 1.016 0.381)
			(layers "B.Cu" "B.Mask" "B.Paste")
			(net "P5V_STBY_DBG")
		)
		(pad "2" smd rect
			(at 0 0.65024 180)
			(size 1.016 0.381)
			(layers "B.Cu" "B.Mask" "B.Paste")
			(net "FM_CPLD_DBG_PWR_EN")
		)
		(pad "3" smd rect
			(at 0 1.30048 180)
			(size 1.016 0.381)
			(layers "B.Cu" "B.Mask" "B.Paste")
			(net "FM_CPLD_DBG_PWR_EN")
		)
		(pad "4" smd rect
			(at -1.778 1.30048 180)
			(size 1.016 0.381)
			(layers "B.Cu" "B.Mask" "B.Paste")
			(net "GND")
		)
		(pad "5" smd rect
			(at -1.778 0.65024 180)
			(size 1.016 0.381)
			(layers "B.Cu" "B.Mask" "B.Paste")
			(net "FM_CPLD_DBG_PWR_EN_R_N")
		)
		(pad "6" smd rect
			(at -1.778 0 180)
			(size 1.016 0.381)
			(layers "B.Cu" "B.Mask" "B.Paste")
			(net "P5V_STBY")
		)
		(zone
			(layer "B.Cu")
			(hatch none 0.5)
			(connect_pads
				(clearance 0)
			)
			(min_thickness 0.25)
			(keepout
				(tracks allowed)
				(vias not_allowed)
				(pads allowed)
				(copperpour not_allowed)
				(footprints allowed)
			)
			(placement
				(enabled no)
				(sheetname "")
			)
			(fill
				(thermal_gap 0.5)
				(thermal_bridge_width 0.5)
				(island_removal_mode 0)
			)
			(polygon
				(pts
					(xy 476.02521 -150.365206) (xy 475.00921 -150.365206) (xy 475.00921 -148.676106) (xy 476.02521 -148.676106)
				)
			)
		)
		(zone
			(layer "B.Cu")
			(hatch none 0.5)
			(connect_pads
				(clearance 0)
			)
			(min_thickness 0.25)
			(keepout
				(tracks allowed)
				(vias not_allowed)
				(pads allowed)
				(copperpour not_allowed)
				(footprints allowed)
			)
			(placement
				(enabled no)
				(sheetname "")
			)
			(fill
				(thermal_gap 0.5)
				(thermal_bridge_width 0.5)
				(island_removal_mode 0)
			)
			(polygon
				(pts
					(xy 477.80321 -150.365206) (xy 476.78721 -150.365206) (xy 476.78721 -148.676106) (xy 477.80321 -148.676106)
				)
			)
		)
	)
	(footprint ""
		(layer "B.Cu")
		(at 276.933152 -125.69444 90)
		(property "Reference" "C4M5"
			(at -1.76911 0.942848 0)
			(unlocked yes)
			(layer "B.SilkS")
			(effects
				(font
					(size 0.7874 0.5842)
					(thickness 0.1524)
				)
				(justify mirror)
			)
		)
		(property "Value" ""
			(at 0 0 90)
			(layer "B.Fab")
			(effects
				(font
					(size 1.27 1.27)
				)
				(justify mirror)
			)
		)
		(duplicate_pad_numbers_are_jumpers no)
		(fp_rect
			(start 0.500126 1.598422)
			(end -0.500126 -0.201422)
			(stroke
				(width 0)
				(type default)
			)
			(fill no)
			(layer "B.CrtYd")
		)
		(fp_line
			(start 0.500126 -0.201422)
			(end -0.500126 -0.201422)
			(stroke
				(width 0.1)
				(type default)
			)
			(layer "B.Fab")
		)
		(fp_line
			(start -0.500126 -0.201422)
			(end -0.500126 1.598422)
			(stroke
				(width 0.1)
				(type default)
			)
			(layer "B.Fab")
		)
		(fp_line
			(start 0.500126 1.598422)
			(end 0.500126 -0.201422)
			(stroke
				(width 0.1)
				(type default)
			)
			(layer "B.Fab")
		)
		(fp_line
			(start -0.500126 1.598422)
			(end 0.500126 1.598422)
			(stroke
				(width 0.1)
				(type default)
			)
			(layer "B.Fab")
		)
		(pad "1" smd rect
			(at 0 0)
			(size 0.889 0.9906)
			(layers "B.Cu" "B.Mask" "B.Paste")
			(net "PVDDQ_DEF")
		)
		(pad "2" smd rect
			(at 0 1.397)
			(size 0.889 0.9906)
			(layers "B.Cu" "B.Mask" "B.Paste")
			(net "GND")
		)
		(zone
			(layer "B.Cu")
			(hatch none 0.5)
			(connect_pads
				(clearance 0)
			)
			(min_thickness 0.25)
			(keepout
				(tracks allowed)
				(vias not_allowed)
				(pads allowed)
				(copperpour not_allowed)
				(footprints allowed)
			)
			(placement
				(enabled no)
				(sheetname "")
			)
			(fill
				(thermal_gap 0.5)
				(thermal_bridge_width 0.5)
				(island_removal_mode 0)
			)
			(polygon
				(pts
					(xy 277.885652 -126.18974) (xy 277.377652 -126.18974) (xy 277.377652 -125.19914) (xy 277.885652 -125.19914)
				)
			)
		)
		(zone
			(layer "B.Cu")
			(hatch none 0.5)
			(connect_pads
				(clearance 0)
			)
			(min_thickness 0.25)
			(keepout
				(tracks not_allowed)
				(vias allowed)
				(pads allowed)
				(copperpour not_allowed)
				(footprints allowed)
			)
			(placement
				(enabled no)
				(sheetname "")
			)
			(fill
				(thermal_gap 0.5)
				(thermal_bridge_width 0.5)
				(island_removal_mode 0)
			)
			(polygon
				(pts
					(xy 277.885652 -126.18974) (xy 277.377652 -126.18974) (xy 277.377652 -125.19914) (xy 277.885652 -125.19914)
				)
			)
		)
	)
	(footprint ""
		(layer "B.Cu")
		(at 94.313248 -12.999212 90)
		(property "Reference" "C5G118"
			(at -1.64973 0.78994 180)
			(unlocked yes)
			(layer "B.SilkS")
			(effects
				(font
					(size 0.7874 0.5842)
					(thickness 0.1524)
				)
				(justify mirror)
			)
		)
		(property "Value" ""
			(at 0 0 90)
			(layer "B.Fab")
			(effects
				(font
					(size 1.27 1.27)
				)
				(justify mirror)
			)
		)
		(duplicate_pad_numbers_are_jumpers no)
		(fp_rect
			(start -0.7239 -0.2159)
			(end 0.7239 1.9939)
			(stroke
				(width 0)
				(type default)
			)
			(fill no)
			(layer "B.CrtYd")
		)
		(fp_line
			(start 0.7239 -0.2159)
			(end 0.7239 1.9939)
			(stroke
				(width 0.1)
				(type default)
			)
			(layer "B.Fab")
		)
		(fp_line
			(start -0.7239 -0.2159)
			(end 0.7239 -0.2159)
			(stroke
				(width 0.1)
				(type default)
			)
			(layer "B.Fab")
		)
		(fp_line
			(start 0.7239 1.9939)
			(end -0.7239 1.9939)
			(stroke
				(width 0.1)
				(type default)
			)
			(layer "B.Fab")
		)
		(fp_line
			(start -0.7239 1.9939)
			(end -0.7239 -0.2159)
			(stroke
				(width 0.1)
				(type default)
			)
			(layer "B.Fab")
		)
		(pad "1" smd rect
			(at 0 0 270)
			(size 1.27 1.016)
			(layers "B.Cu" "B.Mask" "B.Paste")
			(net "PVDDQ_GHJ")
		)
		(pad "2" smd rect
			(at 0 1.778 270)
			(size 1.27 1.016)
			(layers "B.Cu" "B.Mask" "B.Paste")
			(net "GND")
		)
		(zone
			(layer "B.Cu")
			(hatch none 0.5)
			(connect_pads
				(clearance 0)
			)
			(min_thickness 0.25)
			(keepout
				(tracks not_allowed)
				(vias allowed)
				(pads allowed)
				(copperpour not_allowed)
				(footprints allowed)
			)
			(placement
				(enabled no)
				(sheetname "")
			)
			(fill
				(thermal_gap 0.5)
				(thermal_bridge_width 0.5)
				(island_removal_mode 0)
			)
			(polygon
				(pts
					(xy 94.821248 -12.364212) (xy 95.583248 -12.364212) (xy 95.583248 -13.634212) (xy 94.821248 -13.634212)
				)
			)
		)
	)
	(footprint ""
		(layer "B.Cu")
		(at 156.19222 -121.4247 180)
		(property "Reference" "R7M8"
			(at 0 0 0)
			(layer "B.SilkS")
			(hide yes)
			(effects
				(font
					(size 1.27 1.27)
				)
				(justify mirror)
			)
		)
		(property "Value" ""
			(at 0 0 0)
			(layer "B.Fab")
			(effects
				(font
					(size 1.27 1.27)
				)
				(justify mirror)
			)
		)
		(duplicate_pad_numbers_are_jumpers no)
		(fp_poly
			(pts
				(xy 0.2794 -0.1016) (xy -0.2794 -0.1016) (xy -0.2794 0.9906) (xy 0.2794 0.9906)
			)
			(stroke
				(width 0)
				(type default)
			)
			(fill no)
			(layer "B.CrtYd")
		)
		(fp_line
			(start 0.2794 0.9906)
			(end -0.2794 0.9906)
			(stroke
				(width 0.1)
				(type default)
			)
			(layer "B.Fab")
		)
		(fp_line
			(start 0.2794 -0.1016)
			(end 0.2794 0.9906)
			(stroke
				(width 0.1)
				(type default)
			)
			(layer "B.Fab")
		)
		(fp_line
			(start -0.2794 0.9906)
			(end -0.2794 -0.1016)
			(stroke
				(width 0.1)
				(type default)
			)
			(layer "B.Fab")
		)
		(fp_line
			(start -0.2794 -0.1016)
			(end 0.2794 -0.1016)
			(stroke
				(width 0.1)
				(type default)
			)
			(layer "B.Fab")
		)
		(pad "1" smd rect
			(at 0 0)
			(size 0.508 0.508)
			(layers "B.Cu" "B.Mask" "B.Paste")
			(net "SMB_DDR_KLM_SDA_G_R")
		)
		(pad "2" smd rect
			(at 0 0.889)
			(size 0.508 0.508)
			(layers "B.Cu" "B.Mask" "B.Paste")
			(net "SMB_DDR_KLM_SDA_G")
		)
		(zone
			(layer "B.Cu")
			(hatch none 0.5)
			(connect_pads
				(clearance 0)
			)
			(min_thickness 0.25)
			(keepout
				(tracks not_allowed)
				(vias allowed)
				(pads allowed)
				(copperpour not_allowed)
				(footprints allowed)
			)
			(placement
				(enabled no)
				(sheetname "")
			)
			(fill
				(thermal_gap 0.5)
				(thermal_bridge_width 0.5)
				(island_removal_mode 0)
			)
			(polygon
				(pts
					(xy 155.93822 -122.0597) (xy 156.44622 -122.0597) (xy 156.44622 -121.6787) (xy 155.93822 -121.6787)
				)
			)
		)
		(zone
			(layer "B.Cu")
			(hatch none 0.5)
			(connect_pads
				(clearance 0)
			)
			(min_thickness 0.25)
			(keepout
				(tracks allowed)
				(vias not_allowed)
				(pads allowed)
				(copperpour not_allowed)
				(footprints allowed)
			)
			(placement
				(enabled no)
				(sheetname "")
			)
			(fill
				(thermal_gap 0.5)
				(thermal_bridge_width 0.5)
				(island_removal_mode 0)
			)
			(polygon
				(pts
					(xy 155.93822 -121.6787) (xy 156.44622 -121.6787) (xy 156.44622 -122.0597) (xy 155.93822 -122.0597)
				)
			)
		)
	)
	(footprint ""
		(layer "B.Cu")
		(at 187.071 -53.975)
		(property "Reference" "C4E8"
			(at 0 0 0)
			(layer "B.SilkS")
			(hide yes)
			(effects
				(font
					(size 1.27 1.27)
				)
				(justify mirror)
			)
		)
		(property "Value" "*"
			(at 0.0762 -6.2357 0)
			(unlocked yes)
			(layer "B.Fab")
			(hide yes)
			(effects
				(font
					(size 1.27 1.016)
					(thickness 0.1524)
				)
				(justify mirror)
			)
		)
		(property "Device Type" "SC22U16V5MX-4-GP_SMD-BCG5-SC22A"
			(at 0.0762 -8.2677 0)
			(unlocked yes)
			(layer "B.Fab")
			(hide yes)
			(effects
				(font
					(size 1.27 1.016)
					(thickness 0.1524)
				)
				(justify mirror)
			)
		)
		(duplicate_pad_numbers_are_jumpers no)
		(fp_line
			(start -0.635 0)
			(end 0.635 0)
			(stroke
				(width 0.508)
				(type default)
			)
			(layer "B.SilkS")
		)
		(fp_rect
			(start 0.9652 1.778)
			(end -0.9652 -1.778)
			(stroke
				(width 0)
				(type default)
			)
			(fill no)
			(layer "B.CrtYd")
		)
		(fp_poly
			(pts
				(xy 0.9652 -1.778) (xy -0.9652 -1.778) (xy -0.9652 1.778) (xy 0.9652 1.778)
			)
			(stroke
				(width 0)
				(type default)
			)
			(fill no)
			(layer "B.Fab")
		)
		(pad "1" smd rect
			(at 0 -0.9652 180)
			(size 1.397 1.143)
			(layers "B.Cu" "B.Mask" "B.Paste")
			(net "VR_FET_SW_P12V_STBY_PVCCIN_CPU0")
		)
		(pad "2" smd rect
			(at 0 0.9652 180)
			(size 1.397 1.143)
			(layers "B.Cu" "B.Mask" "B.Paste")
			(net "GND")
		)
	)
	(footprint ""
		(layer "B.Cu")
		(at 398.4244 -88.2777)
		(property "Reference" "R8D7"
			(at 0 0 0)
			(layer "B.SilkS")
			(hide yes)
			(effects
				(font
					(size 1.27 1.27)
				)
				(justify mirror)
			)
		)
		(property "Value" ""
			(at 0 0 0)
			(layer "B.Fab")
			(effects
				(font
					(size 1.27 1.27)
				)
				(justify mirror)
			)
		)
		(duplicate_pad_numbers_are_jumpers no)
		(fp_poly
			(pts
				(xy 0.2794 -0.1016) (xy -0.2794 -0.1016) (xy -0.2794 0.9906) (xy 0.2794 0.9906)
			)
			(stroke
				(width 0)
				(type default)
			)
			(fill no)
			(layer "B.CrtYd")
		)
		(fp_line
			(start -0.2794 -0.1016)
			(end 0.2794 -0.1016)
			(stroke
				(width 0.1)
				(type default)
			)
			(layer "B.Fab")
		)
		(fp_line
			(start -0.2794 0.9906)
			(end -0.2794 -0.1016)
			(stroke
				(width 0.1)
				(type default)
			)
			(layer "B.Fab")
		)
		(fp_line
			(start 0.2794 -0.1016)
			(end 0.2794 0.9906)
			(stroke
				(width 0.1)
				(type default)
			)
			(layer "B.Fab")
		)
		(fp_line
			(start 0.2794 0.9906)
			(end -0.2794 0.9906)
			(stroke
				(width 0.1)
				(type default)
			)
			(layer "B.Fab")
		)
		(pad "1" smd rect
			(at 0 0 180)
			(size 0.508 0.508)
			(layers "B.Cu" "B.Mask" "B.Paste")
			(net "SMB_VR_STBY_LVC3_SDA_R1")
		)
		(pad "2" smd rect
			(at 0 0.889 180)
			(size 0.508 0.508)
			(layers "B.Cu" "B.Mask" "B.Paste")
			(net "SMB_VR_STBY_LVC3_SDA")
		)
		(zone
			(layer "B.Cu")
			(hatch none 0.5)
			(connect_pads
				(clearance 0)
			)
			(min_thickness 0.25)
			(keepout
				(tracks allowed)
				(vias not_allowed)
				(pads allowed)
				(copperpour not_allowed)
				(footprints allowed)
			)
			(placement
				(enabled no)
				(sheetname "")
			)
			(fill
				(thermal_gap 0.5)
				(thermal_bridge_width 0.5)
				(island_removal_mode 0)
			)
			(polygon
				(pts
					(xy 398.6784 -88.0237) (xy 398.1704 -88.0237) (xy 398.1704 -87.6427) (xy 398.6784 -87.6427)
				)
			)
		)
		(zone
			(layer "B.Cu")
			(hatch none 0.5)
			(connect_pads
				(clearance 0)
			)
			(min_thickness 0.25)
			(keepout
				(tracks not_allowed)
				(vias allowed)
				(pads allowed)
				(copperpour not_allowed)
				(footprints allowed)
			)
			(placement
				(enabled no)
				(sheetname "")
			)
			(fill
				(thermal_gap 0.5)
				(thermal_bridge_width 0.5)
				(island_removal_mode 0)
			)
			(polygon
				(pts
					(xy 398.6784 -87.6427) (xy 398.1704 -87.6427) (xy 398.1704 -88.0237) (xy 398.6784 -88.0237)
				)
			)
		)
	)
	(footprint ""
		(layer "B.Cu")
		(at 442.663326 -147.663154 90)
		(property "Reference" "C25W97"
			(at 0.8382 -0.67818 90)
			(unlocked yes)
			(layer "B.SilkS")
			(effects
				(font
					(size 0.4064 0.254)
					(thickness 0.1524)
				)
				(justify left mirror)
			)
		)
		(property "Value" ""
			(at 0 0 90)
			(layer "B.Fab")
			(effects
				(font
					(size 1.27 1.27)
				)
				(justify mirror)
			)
		)
		(duplicate_pad_numbers_are_jumpers no)
		(fp_poly
			(pts
				(xy -0.3048 -0.1016) (xy -0.3048 0.9906) (xy 0.3048 0.9906) (xy 0.3048 -0.1016)
			)
			(stroke
				(width 0)
				(type default)
			)
			(fill no)
			(layer "B.CrtYd")
		)
		(fp_line
			(start 0.3048 -0.1016)
			(end 0.3048 0.9906)
			(stroke
				(width 0.1)
				(type default)
			)
			(layer "B.Fab")
		)
		(fp_line
			(start -0.3048 -0.1016)
			(end 0.3048 -0.1016)
			(stroke
				(width 0.1)
				(type default)
			)
			(layer "B.Fab")
		)
		(fp_line
			(start 0.3048 0.9906)
			(end -0.3048 0.9906)
			(stroke
				(width 0.1)
				(type default)
			)
			(layer "B.Fab")
		)
		(fp_line
			(start -0.3048 0.9906)
			(end -0.3048 -0.1016)
			(stroke
				(width 0.1)
				(type default)
			)
			(layer "B.Fab")
		)
		(pad "1" smd rect
			(at 0 0 270)
			(size 0.508 0.508)
			(layers "B.Cu" "B.Mask" "B.Paste")
			(net "P3V3_STBY")
		)
		(pad "2" smd rect
			(at 0 0.889 270)
			(size 0.508 0.508)
			(layers "B.Cu" "B.Mask" "B.Paste")
			(net "GND")
		)
		(zone
			(layer "B.Cu")
			(hatch none 0.5)
			(connect_pads
				(clearance 0)
			)
			(min_thickness 0.25)
			(keepout
				(tracks allowed)
				(vias not_allowed)
				(pads allowed)
				(copperpour not_allowed)
				(footprints allowed)
			)
			(placement
				(enabled no)
				(sheetname "")
			)
			(fill
				(thermal_gap 0.5)
				(thermal_bridge_width 0.5)
				(island_removal_mode 0)
			)
			(polygon
				(pts
					(xy 442.917326 -147.917154) (xy 442.917326 -147.409154) (xy 443.298326 -147.409154) (xy 443.298326 -147.917154)
				)
			)
		)
		(zone
			(layer "B.Cu")
			(hatch none 0.5)
			(connect_pads
				(clearance 0)
			)
			(min_thickness 0.25)
			(keepout
				(tracks not_allowed)
				(vias allowed)
				(pads allowed)
				(copperpour not_allowed)
				(footprints allowed)
			)
			(placement
				(enabled no)
				(sheetname "")
			)
			(fill
				(thermal_gap 0.5)
				(thermal_bridge_width 0.5)
				(island_removal_mode 0)
			)
			(polygon
				(pts
					(xy 443.298326 -147.917154) (xy 443.298326 -147.409154) (xy 442.917326 -147.409154) (xy 442.917326 -147.917154)
				)
			)
		)
	)
	(footprint ""
		(layer "B.Cu")
		(at 377.493022 -27.253438)
		(property "Reference" "RN8F5"
			(at 0.8382 -0.67818 0)
			(unlocked yes)
			(layer "B.SilkS")
			(effects
				(font
					(size 0.4064 0.254)
					(thickness 0.1524)
				)
				(justify left mirror)
			)
		)
		(property "Value" ""
			(at 0 0 0)
			(layer "B.Fab")
			(effects
				(font
					(size 1.27 1.27)
				)
				(justify mirror)
			)
		)
		(duplicate_pad_numbers_are_jumpers no)
		(fp_poly
			(pts
				(xy 0.2794 -0.1016) (xy -0.2794 -0.1016) (xy -0.2794 0.9906) (xy 0.2794 0.9906)
			)
			(stroke
				(width 0)
				(type default)
			)
			(fill no)
			(layer "B.CrtYd")
		)
		(fp_line
			(start -0.2794 -0.1016)
			(end 0.2794 -0.1016)
			(stroke
				(width 0.1)
				(type default)
			)
			(layer "B.Fab")
		)
		(fp_line
			(start -0.2794 0.9906)
			(end -0.2794 -0.1016)
			(stroke
				(width 0.1)
				(type default)
			)
			(layer "B.Fab")
		)
		(fp_line
			(start 0.2794 -0.1016)
			(end 0.2794 0.9906)
			(stroke
				(width 0.1)
				(type default)
			)
			(layer "B.Fab")
		)
		(fp_line
			(start 0.2794 0.9906)
			(end -0.2794 0.9906)
			(stroke
				(width 0.1)
				(type default)
			)
			(layer "B.Fab")
		)
		(pad "1" smd rect
			(at 0 0 180)
			(size 0.508 0.508)
			(layers "B.Cu" "B.Mask" "B.Paste")
			(net "SPI_BMC_BT_DI")
		)
		(pad "2" smd rect
			(at 0 0.889 180)
			(size 0.508 0.508)
			(layers "B.Cu" "B.Mask" "B.Paste")
			(net "SPI_TPM_BMC_DI_R")
		)
		(zone
			(layer "B.Cu")
			(hatch none 0.5)
			(connect_pads
				(clearance 0)
			)
			(min_thickness 0.25)
			(keepout
				(tracks allowed)
				(vias not_allowed)
				(pads allowed)
				(copperpour not_allowed)
				(footprints allowed)
			)
			(placement
				(enabled no)
				(sheetname "")
			)
			(fill
				(thermal_gap 0.5)
				(thermal_bridge_width 0.5)
				(island_removal_mode 0)
			)
			(polygon
				(pts
					(xy 377.747022 -26.999438) (xy 377.239022 -26.999438) (xy 377.239022 -26.618438) (xy 377.747022 -26.618438)
				)
			)
		)
		(zone
			(layer "B.Cu")
			(hatch none 0.5)
			(connect_pads
				(clearance 0)
			)
			(min_thickness 0.25)
			(keepout
				(tracks not_allowed)
				(vias allowed)
				(pads allowed)
				(copperpour not_allowed)
				(footprints allowed)
			)
			(placement
				(enabled no)
				(sheetname "")
			)
			(fill
				(thermal_gap 0.5)
				(thermal_bridge_width 0.5)
				(island_removal_mode 0)
			)
			(polygon
				(pts
					(xy 377.747022 -26.618438) (xy 377.239022 -26.618438) (xy 377.239022 -26.999438) (xy 377.747022 -26.999438)
				)
			)
		)
	)
	(footprint ""
		(layer "B.Cu")
		(at 354.36429 -77.915516 180)
		(property "Reference" "C3P32"
			(at 0 0 0)
			(layer "B.SilkS")
			(hide yes)
			(effects
				(font
					(size 1.27 1.27)
				)
				(justify mirror)
			)
		)
		(property "Value" ""
			(at 0 0 0)
			(layer "B.Fab")
			(effects
				(font
					(size 1.27 1.27)
				)
				(justify mirror)
			)
		)
		(duplicate_pad_numbers_are_jumpers no)
		(fp_poly
			(pts
				(xy -0.3048 -0.1016) (xy -0.3048 0.9906) (xy 0.3048 0.9906) (xy 0.3048 -0.1016)
			)
			(stroke
				(width 0)
				(type default)
			)
			(fill no)
			(layer "B.CrtYd")
		)
		(fp_line
			(start 0.3048 0.9906)
			(end -0.3048 0.9906)
			(stroke
				(width 0.1)
				(type default)
			)
			(layer "B.Fab")
		)
		(fp_line
			(start 0.3048 -0.1016)
			(end 0.3048 0.9906)
			(stroke
				(width 0.1)
				(type default)
			)
			(layer "B.Fab")
		)
		(fp_line
			(start -0.3048 0.9906)
			(end -0.3048 -0.1016)
			(stroke
				(width 0.1)
				(type default)
			)
			(layer "B.Fab")
		)
		(fp_line
			(start -0.3048 -0.1016)
			(end 0.3048 -0.1016)
			(stroke
				(width 0.1)
				(type default)
			)
			(layer "B.Fab")
		)
		(pad "1" smd rect
			(at 0 0)
			(size 0.508 0.508)
			(layers "B.Cu" "B.Mask" "B.Paste")
			(net "P3E_CPU0_PE1_SS_TXN<5>")
		)
		(pad "2" smd rect
			(at 0 0.889)
			(size 0.508 0.508)
			(layers "B.Cu" "B.Mask" "B.Paste")
			(net "P3E_CPU0_PE1_PCH_TXN<5>")
		)
		(zone
			(layer "B.Cu")
			(hatch none 0.5)
			(connect_pads
				(clearance 0)
			)
			(min_thickness 0.25)
			(keepout
				(tracks not_allowed)
				(vias allowed)
				(pads allowed)
				(copperpour not_allowed)
				(footprints allowed)
			)
			(placement
				(enabled no)
				(sheetname "")
			)
			(fill
				(thermal_gap 0.5)
				(thermal_bridge_width 0.5)
				(island_removal_mode 0)
			)
			(polygon
				(pts
					(xy 354.11029 -78.550516) (xy 354.61829 -78.550516) (xy 354.61829 -78.169516) (xy 354.11029 -78.169516)
				)
			)
		)
		(zone
			(layer "B.Cu")
			(hatch none 0.5)
			(connect_pads
				(clearance 0)
			)
			(min_thickness 0.25)
			(keepout
				(tracks allowed)
				(vias not_allowed)
				(pads allowed)
				(copperpour not_allowed)
				(footprints allowed)
			)
			(placement
				(enabled no)
				(sheetname "")
			)
			(fill
				(thermal_gap 0.5)
				(thermal_bridge_width 0.5)
				(island_removal_mode 0)
			)
			(polygon
				(pts
					(xy 354.11029 -78.169516) (xy 354.61829 -78.169516) (xy 354.61829 -78.550516) (xy 354.11029 -78.550516)
				)
			)
		)
	)
	(footprint ""
		(layer "B.Cu")
		(at 481.27666 -29.35732 -90)
		(property "Reference" "C2T25"
			(at 0 0 90)
			(layer "B.SilkS")
			(hide yes)
			(effects
				(font
					(size 1.27 1.27)
				)
				(justify mirror)
			)
		)
		(property "Value" ""
			(at 0 0 90)
			(layer "B.Fab")
			(effects
				(font
					(size 1.27 1.27)
				)
				(justify mirror)
			)
		)
		(duplicate_pad_numbers_are_jumpers no)
		(fp_poly
			(pts
				(xy -0.3048 -0.1016) (xy -0.3048 0.9906) (xy 0.3048 0.9906) (xy 0.3048 -0.1016)
			)
			(stroke
				(width 0)
				(type default)
			)
			(fill no)
			(layer "B.CrtYd")
		)
		(fp_line
			(start -0.3048 0.9906)
			(end -0.3048 -0.1016)
			(stroke
				(width 0.1)
				(type default)
			)
			(layer "B.Fab")
		)
		(fp_line
			(start 0.3048 0.9906)
			(end -0.3048 0.9906)
			(stroke
				(width 0.1)
				(type default)
			)
			(layer "B.Fab")
		)
		(fp_line
			(start -0.3048 -0.1016)
			(end 0.3048 -0.1016)
			(stroke
				(width 0.1)
				(type default)
			)
			(layer "B.Fab")
		)
		(fp_line
			(start 0.3048 -0.1016)
			(end 0.3048 0.9906)
			(stroke
				(width 0.1)
				(type default)
			)
			(layer "B.Fab")
		)
		(pad "1" smd rect
			(at 0 0 90)
			(size 0.508 0.508)
			(layers "B.Cu" "B.Mask" "B.Paste")
			(net "P3V3_STBY_MNG")
		)
		(pad "2" smd rect
			(at 0 0.889 90)
			(size 0.508 0.508)
			(layers "B.Cu" "B.Mask" "B.Paste")
			(net "GND")
		)
		(zone
			(layer "B.Cu")
			(hatch none 0.5)
			(connect_pads
				(clearance 0)
			)
			(min_thickness 0.25)
			(keepout
				(tracks not_allowed)
				(vias allowed)
				(pads allowed)
				(copperpour not_allowed)
				(footprints allowed)
			)
			(placement
				(enabled no)
				(sheetname "")
			)
			(fill
				(thermal_gap 0.5)
				(thermal_bridge_width 0.5)
				(island_removal_mode 0)
			)
			(polygon
				(pts
					(xy 480.64166 -29.10332) (xy 480.64166 -29.61132) (xy 481.02266 -29.61132) (xy 481.02266 -29.10332)
				)
			)
		)
		(zone
			(layer "B.Cu")
			(hatch none 0.5)
			(connect_pads
				(clearance 0)
			)
			(min_thickness 0.25)
			(keepout
				(tracks allowed)
				(vias not_allowed)
				(pads allowed)
				(copperpour not_allowed)
				(footprints allowed)
			)
			(placement
				(enabled no)
				(sheetname "")
			)
			(fill
				(thermal_gap 0.5)
				(thermal_bridge_width 0.5)
				(island_removal_mode 0)
			)
			(polygon
				(pts
					(xy 481.02266 -29.10332) (xy 481.02266 -29.61132) (xy 480.64166 -29.61132) (xy 480.64166 -29.10332)
				)
			)
		)
	)
	(footprint ""
		(layer "B.Cu")
		(at 253.392432 -149.8092 90)
		(property "Reference" "C5G62"
			(at -1.14681 0.76708 180)
			(unlocked yes)
			(layer "B.SilkS")
			(effects
				(font
					(size 0.7874 0.5842)
					(thickness 0.1524)
				)
				(justify mirror)
			)
		)
		(property "Value" ""
			(at 0 0 90)
			(layer "B.Fab")
			(effects
				(font
					(size 1.27 1.27)
				)
				(justify mirror)
			)
		)
		(duplicate_pad_numbers_are_jumpers no)
		(fp_rect
			(start -0.4953 -0.2032)
			(end 0.4953 1.6002)
			(stroke
				(width 0)
				(type default)
			)
			(fill no)
			(layer "B.CrtYd")
		)
		(fp_line
			(start 0.4953 -0.2032)
			(end -0.4953 -0.2032)
			(stroke
				(width 0.1)
				(type default)
			)
			(layer "B.Fab")
		)
		(fp_line
			(start -0.4953 -0.2032)
			(end -0.4953 1.6002)
			(stroke
				(width 0.1)
				(type default)
			)
			(layer "B.Fab")
		)
		(fp_line
			(start 0.4953 1.6002)
			(end 0.4953 -0.2032)
			(stroke
				(width 0.1)
				(type default)
			)
			(layer "B.Fab")
		)
		(fp_line
			(start -0.4953 1.6002)
			(end 0.4953 1.6002)
			(stroke
				(width 0.1)
				(type default)
			)
			(layer "B.Fab")
		)
		(pad "1" smd rect
			(at 0 0 270)
			(size 0.762 0.889)
			(layers "B.Cu" "B.Mask" "B.Paste")
			(net "PVDDQ_DEF")
		)
		(pad "2" smd rect
			(at 0 1.397 270)
			(size 0.762 0.889)
			(layers "B.Cu" "B.Mask" "B.Paste")
			(net "GND")
		)
		(zone
			(layer "B.Cu")
			(hatch none 0.5)
			(connect_pads
				(clearance 0)
			)
			(min_thickness 0.25)
			(keepout
				(tracks not_allowed)
				(vias allowed)
				(pads allowed)
				(copperpour not_allowed)
				(footprints allowed)
			)
			(placement
				(enabled no)
				(sheetname "")
			)
			(fill
				(thermal_gap 0.5)
				(thermal_bridge_width 0.5)
				(island_removal_mode 0)
			)
			(polygon
				(pts
					(xy 253.836932 -149.4282) (xy 254.344932 -149.4282) (xy 254.344932 -150.1902) (xy 253.836932 -150.1902)
				)
			)
		)
	)
	(footprint ""
		(layer "B.Cu")
		(at 360.2228 -141.833092 -90)
		(property "Reference" "CF18"
			(at 0 0 90)
			(layer "B.SilkS")
			(hide yes)
			(effects
				(font
					(size 1.27 1.27)
				)
				(justify mirror)
			)
		)
		(property "Value" "*"
			(at -1.1811 -2.8194 270)
			(unlocked yes)
			(layer "B.Fab")
			(hide yes)
			(effects
				(font
					(size 1.27 1.016)
					(thickness 0.1524)
				)
				(justify mirror)
			)
		)
		(property "Device Type" "SC22P50V2JN-4GP_SMD-BCG-SC22P5A"
			(at -1.1811 -4.3434 270)
			(unlocked yes)
			(layer "B.Fab")
			(hide yes)
			(effects
				(font
					(size 1.27 1.016)
					(thickness 0.1524)
				)
				(justify mirror)
			)
		)
		(duplicate_pad_numbers_are_jumpers no)
		(fp_rect
			(start 0.4318 0.9525)
			(end -0.4318 -0.9525)
			(stroke
				(width 0)
				(type default)
			)
			(fill no)
			(layer "B.CrtYd")
		)
		(fp_rect
			(start 0.4318 0.9525)
			(end -0.4318 -0.9525)
			(stroke
				(width 0)
				(type default)
			)
			(fill no)
			(layer "B.Fab")
		)
		(pad "1" smd custom
			(at 0 -0.4445 90)
			(size 0.1524 0.1524)
			(layers "B.Cu" "B.Mask" "B.Paste")
			(net "VR_PVDDQ_DEF_AIREF2")
			(options
				(clearance outline)
				(anchor circle)
			)
			(primitives
				(gr_poly
					(pts
						(arc
							(start 0.3048 0.2032)
							(mid 0.275042 0.275042)
							(end 0.2032 0.3048)
						)
						(arc
							(start -0.2032 0.3048)
							(mid -0.275042 0.275042)
							(end -0.3048 0.2032)
						)
						(arc
							(start -0.3048 -0.2032)
							(mid -0.275042 -0.275042)
							(end -0.2032 -0.3048)
						)
						(arc
							(start 0.2032 -0.3048)
							(mid 0.275042 -0.275042)
							(end 0.3048 -0.2032)
						)
					)
					(width 0)
					(fill yes)
				)
			)
		)
		(pad "2" smd custom
			(at 0 0.4445 90)
			(size 0.1524 0.1524)
			(layers "B.Cu" "B.Mask" "B.Paste")
			(net "ISENSE_PVDDQ_DEF_PH2_IMON")
			(options
				(clearance outline)
				(anchor circle)
			)
			(primitives
				(gr_poly
					(pts
						(arc
							(start 0.3048 0.2032)
							(mid 0.275042 0.275042)
							(end 0.2032 0.3048)
						)
						(arc
							(start -0.2032 0.3048)
							(mid -0.275042 0.275042)
							(end -0.3048 0.2032)
						)
						(arc
							(start -0.3048 -0.2032)
							(mid -0.275042 -0.275042)
							(end -0.2032 -0.3048)
						)
						(arc
							(start 0.2032 -0.3048)
							(mid 0.275042 -0.275042)
							(end 0.3048 -0.2032)
						)
					)
					(width 0)
					(fill yes)
				)
			)
		)
	)
	(footprint ""
		(layer "B.Cu")
		(at 420.624 -151.765 90)
		(property "Reference" "C2L13"
			(at 0 0 90)
			(layer "B.SilkS")
			(hide yes)
			(effects
				(font
					(size 1.27 1.27)
				)
				(justify mirror)
			)
		)
		(property "Value" ""
			(at 0 0 90)
			(layer "B.Fab")
			(effects
				(font
					(size 1.27 1.27)
				)
				(justify mirror)
			)
		)
		(duplicate_pad_numbers_are_jumpers no)
		(fp_poly
			(pts
				(xy -0.3048 -0.1016) (xy -0.3048 0.9906) (xy 0.3048 0.9906) (xy 0.3048 -0.1016)
			)
			(stroke
				(width 0)
				(type default)
			)
			(fill no)
			(layer "B.CrtYd")
		)
		(fp_line
			(start 0.3048 -0.1016)
			(end 0.3048 0.9906)
			(stroke
				(width 0.1)
				(type default)
			)
			(layer "B.Fab")
		)
		(fp_line
			(start -0.3048 -0.1016)
			(end 0.3048 -0.1016)
			(stroke
				(width 0.1)
				(type default)
			)
			(layer "B.Fab")
		)
		(fp_line
			(start 0.3048 0.9906)
			(end -0.3048 0.9906)
			(stroke
				(width 0.1)
				(type default)
			)
			(layer "B.Fab")
		)
		(fp_line
			(start -0.3048 0.9906)
			(end -0.3048 -0.1016)
			(stroke
				(width 0.1)
				(type default)
			)
			(layer "B.Fab")
		)
		(pad "1" smd rect
			(at 0 0 270)
			(size 0.508 0.508)
			(layers "B.Cu" "B.Mask" "B.Paste")
			(net "SATA6G_PCH_PCIE_UP_SATA_RXN<2>")
		)
		(pad "2" smd rect
			(at 0 0.889 270)
			(size 0.508 0.508)
			(layers "B.Cu" "B.Mask" "B.Paste")
			(net "SATA6G_P2_RX_C_DN")
		)
		(zone
			(layer "B.Cu")
			(hatch none 0.5)
			(connect_pads
				(clearance 0)
			)
			(min_thickness 0.25)
			(keepout
				(tracks allowed)
				(vias not_allowed)
				(pads allowed)
				(copperpour not_allowed)
				(footprints allowed)
			)
			(placement
				(enabled no)
				(sheetname "")
			)
			(fill
				(thermal_gap 0.5)
				(thermal_bridge_width 0.5)
				(island_removal_mode 0)
			)
			(polygon
				(pts
					(xy 420.878 -152.019) (xy 420.878 -151.511) (xy 421.259 -151.511) (xy 421.259 -152.019)
				)
			)
		)
		(zone
			(layer "B.Cu")
			(hatch none 0.5)
			(connect_pads
				(clearance 0)
			)
			(min_thickness 0.25)
			(keepout
				(tracks not_allowed)
				(vias allowed)
				(pads allowed)
				(copperpour not_allowed)
				(footprints allowed)
			)
			(placement
				(enabled no)
				(sheetname "")
			)
			(fill
				(thermal_gap 0.5)
				(thermal_bridge_width 0.5)
				(island_removal_mode 0)
			)
			(polygon
				(pts
					(xy 421.259 -152.019) (xy 421.259 -151.511) (xy 420.878 -151.511) (xy 420.878 -152.019)
				)
			)
		)
	)
	(footprint ""
		(layer "B.Cu")
		(at 357.988616 -146.777202)
		(property "Reference" "C7W8"
			(at 0 0 0)
			(layer "B.SilkS")
			(hide yes)
			(effects
				(font
					(size 1.27 1.27)
				)
				(justify mirror)
			)
		)
		(property "Value" "*"
			(at 0.0762 -6.2357 0)
			(unlocked yes)
			(layer "B.Fab")
			(hide yes)
			(effects
				(font
					(size 1.27 1.016)
					(thickness 0.1524)
				)
				(justify mirror)
			)
		)
		(property "Device Type" "SC22U16V5MX-4-GP_SMD-BCG5-SC22A"
			(at 0.0762 -8.2677 0)
			(unlocked yes)
			(layer "B.Fab")
			(hide yes)
			(effects
				(font
					(size 1.27 1.016)
					(thickness 0.1524)
				)
				(justify mirror)
			)
		)
		(duplicate_pad_numbers_are_jumpers no)
		(fp_line
			(start -0.635 0)
			(end 0.635 0)
			(stroke
				(width 0.508)
				(type default)
			)
			(layer "B.SilkS")
		)
		(fp_rect
			(start 0.9652 1.778)
			(end -0.9652 -1.778)
			(stroke
				(width 0)
				(type default)
			)
			(fill no)
			(layer "B.CrtYd")
		)
		(fp_poly
			(pts
				(xy 0.9652 -1.778) (xy -0.9652 -1.778) (xy -0.9652 1.778) (xy 0.9652 1.778)
			)
			(stroke
				(width 0)
				(type default)
			)
			(fill no)
			(layer "B.Fab")
		)
		(pad "1" smd rect
			(at 0 -0.9652 180)
			(size 1.397 1.143)
			(layers "B.Cu" "B.Mask" "B.Paste")
			(net "VR_FET_SW_P12V_STBY_PVDDQ_DEF")
		)
		(pad "2" smd rect
			(at 0 0.9652 180)
			(size 1.397 1.143)
			(layers "B.Cu" "B.Mask" "B.Paste")
			(net "GND")
		)
	)
	(footprint ""
		(layer "B.Cu")
		(at 452.35241 -4.614672 90)
		(property "Reference" "R1U64"
			(at 0 0 90)
			(layer "B.SilkS")
			(hide yes)
			(effects
				(font
					(size 1.27 1.27)
				)
				(justify mirror)
			)
		)
		(property "Value" ""
			(at 0 0 90)
			(layer "B.Fab")
			(effects
				(font
					(size 1.27 1.27)
				)
				(justify mirror)
			)
		)
		(duplicate_pad_numbers_are_jumpers no)
		(fp_poly
			(pts
				(xy 0.2794 -0.1016) (xy -0.2794 -0.1016) (xy -0.2794 0.990854) (xy 0.2794 0.990854)
			)
			(stroke
				(width 0)
				(type default)
			)
			(fill no)
			(layer "B.CrtYd")
		)
		(fp_line
			(start 0.2794 -0.1016)
			(end 0.2794 0.990854)
			(stroke
				(width 0.1)
				(type default)
			)
			(layer "B.Fab")
		)
		(fp_line
			(start -0.2794 -0.1016)
			(end 0.2794 -0.1016)
			(stroke
				(width 0.1)
				(type default)
			)
			(layer "B.Fab")
		)
		(fp_line
			(start 0.2794 0.990854)
			(end -0.2794 0.990854)
			(stroke
				(width 0.1)
				(type default)
			)
			(layer "B.Fab")
		)
		(fp_line
			(start -0.2794 0.990854)
			(end -0.2794 -0.1016)
			(stroke
				(width 0.1)
				(type default)
			)
			(layer "B.Fab")
		)
		(pad "1" smd rect
			(at 0 0 270)
			(size 0.508 0.508)
			(layers "B.Cu" "B.Mask" "B.Paste")
			(net "PD_IE_DEBUG_MODE")
		)
		(pad "2" smd rect
			(at 0 0.889 270)
			(size 0.508 0.508)
			(layers "B.Cu" "B.Mask" "B.Paste")
			(net "GND")
		)
		(zone
			(layer "B.Cu")
			(hatch none 0.5)
			(connect_pads
				(clearance 0)
			)
			(min_thickness 0.25)
			(keepout
				(tracks allowed)
				(vias not_allowed)
				(pads allowed)
				(copperpour not_allowed)
				(footprints allowed)
			)
			(placement
				(enabled no)
				(sheetname "")
			)
			(fill
				(thermal_gap 0.5)
				(thermal_bridge_width 0.5)
				(island_removal_mode 0)
			)
			(polygon
				(pts
					(xy 452.60641 -4.868672) (xy 452.60641 -4.360672) (xy 452.987664 -4.360672) (xy 452.987664 -4.868672)
				)
			)
		)
		(zone
			(layer "B.Cu")
			(hatch none 0.5)
			(connect_pads
				(clearance 0)
			)
			(min_thickness 0.25)
			(keepout
				(tracks not_allowed)
				(vias allowed)
				(pads allowed)
				(copperpour not_allowed)
				(footprints allowed)
			)
			(placement
				(enabled no)
				(sheetname "")
			)
			(fill
				(thermal_gap 0.5)
				(thermal_bridge_width 0.5)
				(island_removal_mode 0)
			)
			(polygon
				(pts
					(xy 452.987664 -4.868672) (xy 452.987664 -4.360672) (xy 452.60641 -4.360672) (xy 452.60641 -4.868672)
				)
			)
		)
	)
	(footprint ""
		(layer "B.Cu")
		(at 183.67629 0.139192 180)
		(property "Reference" "C6U16"
			(at 0 0 0)
			(layer "B.SilkS")
			(hide yes)
			(effects
				(font
					(size 1.27 1.27)
				)
				(justify mirror)
			)
		)
		(property "Value" ""
			(at 0 0 0)
			(layer "B.Fab")
			(effects
				(font
					(size 1.27 1.27)
				)
				(justify mirror)
			)
		)
		(duplicate_pad_numbers_are_jumpers no)
		(fp_rect
			(start 0.4953 -0.2032)
			(end -0.4953 1.6002)
			(stroke
				(width 0)
				(type default)
			)
			(fill no)
			(layer "B.CrtYd")
		)
		(fp_line
			(start 0.4953 1.6002)
			(end 0.4953 -0.2032)
			(stroke
				(width 0.1)
				(type default)
			)
			(layer "B.Fab")
		)
		(fp_line
			(start 0.4953 -0.2032)
			(end -0.4953 -0.2032)
			(stroke
				(width 0.1)
				(type default)
			)
			(layer "B.Fab")
		)
		(fp_line
			(start -0.4953 1.6002)
			(end 0.4953 1.6002)
			(stroke
				(width 0.1)
				(type default)
			)
			(layer "B.Fab")
		)
		(fp_line
			(start -0.4953 -0.2032)
			(end -0.4953 1.6002)
			(stroke
				(width 0.1)
				(type default)
			)
			(layer "B.Fab")
		)
		(pad "1" smd rect
			(at 0 0)
			(size 0.762 0.889)
			(layers "B.Cu" "B.Mask" "B.Paste")
			(net "PVDDQ_ABC")
		)
		(pad "2" smd rect
			(at 0 1.397)
			(size 0.762 0.889)
			(layers "B.Cu" "B.Mask" "B.Paste")
			(net "GND")
		)
		(zone
			(layer "B.Cu")
			(hatch none 0.5)
			(connect_pads
				(clearance 0)
			)
			(min_thickness 0.25)
			(keepout
				(tracks not_allowed)
				(vias allowed)
				(pads allowed)
				(copperpour not_allowed)
				(footprints allowed)
			)
			(placement
				(enabled no)
				(sheetname "")
			)
			(fill
				(thermal_gap 0.5)
				(thermal_bridge_width 0.5)
				(island_removal_mode 0)
			)
			(polygon
				(pts
					(xy 183.29529 -0.305308) (xy 184.05729 -0.305308) (xy 184.05729 -0.813308) (xy 183.29529 -0.813308)
				)
			)
		)
	)
	(footprint ""
		(layer "B.Cu")
		(at 101.448616 -164.9857 90)
		(property "Reference" "T1D4"
			(at 0 0 90)
			(layer "B.SilkS")
			(hide yes)
			(effects
				(font
					(size 1.27 1.27)
				)
				(justify mirror)
			)
		)
		(property "Value" "*"
			(at 3.4036 -4.46405 90)
			(unlocked yes)
			(layer "B.Fab")
			(hide yes)
			(effects
				(font
					(size 0.889 0.889)
					(thickness 0.1524)
				)
				(justify mirror)
			)
		)
		(property "Device Type" "TEST-PAD-12P-1-GP-U_DISCRET-GBA"
			(at 3.4036 -5.98805 90)
			(unlocked yes)
			(layer "B.Fab")
			(hide yes)
			(effects
				(font
					(size 0.889 0.889)
					(thickness 0.1524)
				)
				(justify mirror)
			)
		)
		(duplicate_pad_numbers_are_jumpers no)
		(fp_line
			(start 2.3876 -4.826)
			(end -2.3622 -4.826)
			(stroke
				(width 0.1524)
				(type default)
			)
			(layer "B.SilkS")
		)
		(fp_line
			(start -2.3622 -4.826)
			(end -2.3622 3.4798)
			(stroke
				(width 0.1524)
				(type default)
			)
			(layer "B.SilkS")
		)
		(fp_line
			(start 2.3876 3.4798)
			(end 2.3876 -4.826)
			(stroke
				(width 0.1524)
				(type default)
			)
			(layer "B.SilkS")
		)
		(fp_line
			(start -2.3622 3.4798)
			(end 2.3876 3.4798)
			(stroke
				(width 0.1524)
				(type default)
			)
			(layer "B.SilkS")
		)
		(fp_rect
			(start 2.6416 3.7338)
			(end -2.6162 -5.08)
			(stroke
				(width 0)
				(type default)
			)
			(fill no)
			(layer "B.CrtYd")
		)
		(fp_rect
			(start 2.6416 3.7338)
			(end -2.6162 -5.08)
			(stroke
				(width 0)
				(type default)
			)
			(fill no)
			(layer "B.Fab")
		)
		(pad "1" smd circle
			(at -0.496824 -1.301496 270)
			(size 0.6604 0.6604)
			(layers "B.Cu" "B.Mask" "B.Paste")
			(net "L3_85OHM_5INCH_DN")
		)
		(pad "2" smd circle
			(at 0.503936 -1.301496 270)
			(size 0.6604 0.6604)
			(layers "B.Cu" "B.Mask" "B.Paste")
			(net "L3_85OHM_5INCH_DP")
		)
		(pad "3" smd custom
			(at 0.00889 0.370078 270)
			(size 0.74295 0.74295)
			(layers "B.Cu" "B.Mask" "B.Paste")
			(net "GND")
			(options
				(clearance outline)
				(anchor circle)
			)
			(primitives
				(gr_poly
					(pts
						(xy -2.1209 -1.4859) (xy 2.1209 -1.4859) (xy 2.1209 1.4859) (xy 1.08585 1.4859) (xy 1.08585 0.4699)
						(xy -1.08585 0.4699) (xy -1.08585 1.4859) (xy -2.1209 1.4859)
					)
					(width 0)
					(fill yes)
				)
			)
		)
		(pad "4" thru_hole circle
			(at -1.266444 -3.851656 270)
			(size 1.4478 1.4478)
			(drill 1.0414)
			(layers "*.Cu" "*.Mask")
			(remove_unused_layers no)
			(net "GND")
			(clearance 0.1524)
			(thermal_gap 0.1524)
		)
		(pad "5" thru_hole circle
			(at 1.273556 -3.851656 270)
			(size 1.4478 1.4478)
			(drill 1.0414)
			(layers "*.Cu" "*.Mask")
			(remove_unused_layers no)
			(net "GND")
			(clearance 0.1524)
			(thermal_gap 0.1524)
		)
		(pad "6" thru_hole circle
			(at -1.266444 2.498344 270)
			(size 1.4478 1.4478)
			(drill 1.0414)
			(layers "*.Cu" "*.Mask")
			(remove_unused_layers no)
			(net "GND")
			(clearance 0.1524)
			(thermal_gap 0.1524)
		)
		(pad "7" thru_hole circle
			(at 1.273556 2.498344 270)
			(size 1.4478 1.4478)
			(drill 1.0414)
			(layers "*.Cu" "*.Mask")
			(remove_unused_layers no)
			(net "GND")
			(clearance 0.1524)
			(thermal_gap 0.1524)
		)
		(pad "8" thru_hole circle
			(at -1.27 -0.4572 270)
			(size 0.7112 0.7112)
			(drill 0.4064)
			(layers "*.Cu" "*.Mask")
			(remove_unused_layers no)
			(net "GND")
			(clearance 0.1016)
			(thermal_gap 0.1016)
		)
		(pad "9" thru_hole circle
			(at -1.27 0.762 270)
			(size 0.7112 0.7112)
			(drill 0.4064)
			(layers "*.Cu" "*.Mask")
			(remove_unused_layers no)
			(net "GND")
			(clearance 0.1016)
			(thermal_gap 0.1016)
		)
		(pad "10" thru_hole circle
			(at 0.0254 0.762 270)
			(size 0.7112 0.7112)
			(drill 0.4064)
			(layers "*.Cu" "*.Mask")
			(remove_unused_layers no)
			(net "GND")
			(clearance 0.1016)
			(thermal_gap 0.1016)
		)
		(pad "11" thru_hole circle
			(at 1.27 0.762 270)
			(size 0.7112 0.7112)
			(drill 0.4064)
			(layers "*.Cu" "*.Mask")
			(remove_unused_layers no)
			(net "GND")
			(clearance 0.1016)
			(thermal_gap 0.1016)
		)
		(pad "12" thru_hole circle
			(at 1.27 -0.4572 270)
			(size 0.7112 0.7112)
			(drill 0.4064)
			(layers "*.Cu" "*.Mask")
			(remove_unused_layers no)
			(net "GND")
			(clearance 0.1016)
			(thermal_gap 0.1016)
		)
	)
	(footprint ""
		(layer "B.Cu")
		(at 474.218 -38.354 -90)
		(property "Reference" "R9F12"
			(at 0 0 90)
			(layer "B.SilkS")
			(hide yes)
			(effects
				(font
					(size 1.27 1.27)
				)
				(justify mirror)
			)
		)
		(property "Value" ""
			(at 0 0 90)
			(layer "B.Fab")
			(effects
				(font
					(size 1.27 1.27)
				)
				(justify mirror)
			)
		)
		(duplicate_pad_numbers_are_jumpers no)
		(fp_poly
			(pts
				(xy 0.2794 -0.1016) (xy -0.2794 -0.1016) (xy -0.2794 0.9906) (xy 0.2794 0.9906)
			)
			(stroke
				(width 0)
				(type default)
			)
			(fill no)
			(layer "B.CrtYd")
		)
		(fp_line
			(start -0.2794 0.9906)
			(end -0.2794 -0.1016)
			(stroke
				(width 0.1)
				(type default)
			)
			(layer "B.Fab")
		)
		(fp_line
			(start 0.2794 0.9906)
			(end -0.2794 0.9906)
			(stroke
				(width 0.1)
				(type default)
			)
			(layer "B.Fab")
		)
		(fp_line
			(start -0.2794 -0.1016)
			(end 0.2794 -0.1016)
			(stroke
				(width 0.1)
				(type default)
			)
			(layer "B.Fab")
		)
		(fp_line
			(start 0.2794 -0.1016)
			(end 0.2794 0.9906)
			(stroke
				(width 0.1)
				(type default)
			)
			(layer "B.Fab")
		)
		(pad "1" smd rect
			(at 0 0 90)
			(size 0.508 0.508)
			(layers "B.Cu" "B.Mask" "B.Paste")
			(net "P3V3_STBY")
		)
		(pad "2" smd rect
			(at 0 0.889 90)
			(size 0.508 0.508)
			(layers "B.Cu" "B.Mask" "B.Paste")
			(net "PWRGD_P1V2_BMC_STBY_R")
		)
		(zone
			(layer "B.Cu")
			(hatch none 0.5)
			(connect_pads
				(clearance 0)
			)
			(min_thickness 0.25)
			(keepout
				(tracks not_allowed)
				(vias allowed)
				(pads allowed)
				(copperpour not_allowed)
				(footprints allowed)
			)
			(placement
				(enabled no)
				(sheetname "")
			)
			(fill
				(thermal_gap 0.5)
				(thermal_bridge_width 0.5)
				(island_removal_mode 0)
			)
			(polygon
				(pts
					(xy 473.583 -38.1) (xy 473.583 -38.608) (xy 473.964 -38.608) (xy 473.964 -38.1)
				)
			)
		)
		(zone
			(layer "B.Cu")
			(hatch none 0.5)
			(connect_pads
				(clearance 0)
			)
			(min_thickness 0.25)
			(keepout
				(tracks allowed)
				(vias not_allowed)
				(pads allowed)
				(copperpour not_allowed)
				(footprints allowed)
			)
			(placement
				(enabled no)
				(sheetname "")
			)
			(fill
				(thermal_gap 0.5)
				(thermal_bridge_width 0.5)
				(island_removal_mode 0)
			)
			(polygon
				(pts
					(xy 473.964 -38.1) (xy 473.964 -38.608) (xy 473.583 -38.608) (xy 473.583 -38.1)
				)
			)
		)
	)
	(footprint ""
		(layer "B.Cu")
		(at 248.8565 -17.7546 -90)
		(property "Reference" "C5T11"
			(at -1.848866 0.752348 270)
			(unlocked yes)
			(layer "B.SilkS")
			(effects
				(font
					(size 1.27 0.9652)
					(thickness 0.1524)
				)
				(justify mirror)
			)
		)
		(property "Value" ""
			(at 0 0 90)
			(layer "B.Fab")
			(effects
				(font
					(size 1.27 1.27)
				)
				(justify mirror)
			)
		)
		(duplicate_pad_numbers_are_jumpers no)
		(fp_rect
			(start 0.500126 1.598422)
			(end -0.500126 -0.201422)
			(stroke
				(width 0)
				(type default)
			)
			(fill no)
			(layer "B.CrtYd")
		)
		(fp_line
			(start -0.500126 1.598422)
			(end 0.500126 1.598422)
			(stroke
				(width 0.1)
				(type default)
			)
			(layer "B.Fab")
		)
		(fp_line
			(start 0.500126 1.598422)
			(end 0.500126 -0.201422)
			(stroke
				(width 0.1)
				(type default)
			)
			(layer "B.Fab")
		)
		(fp_line
			(start -0.500126 -0.201422)
			(end -0.500126 1.598422)
			(stroke
				(width 0.1)
				(type default)
			)
			(layer "B.Fab")
		)
		(fp_line
			(start 0.500126 -0.201422)
			(end -0.500126 -0.201422)
			(stroke
				(width 0.1)
				(type default)
			)
			(layer "B.Fab")
		)
		(pad "1" smd rect
			(at 0 0 180)
			(size 0.889 0.9906)
			(layers "B.Cu" "B.Mask" "B.Paste")
			(net "PVDDQ_ABC")
		)
		(pad "2" smd rect
			(at 0 1.397 180)
			(size 0.889 0.9906)
			(layers "B.Cu" "B.Mask" "B.Paste")
			(net "GND")
		)
		(zone
			(layer "B.Cu")
			(hatch none 0.5)
			(connect_pads
				(clearance 0)
			)
			(min_thickness 0.25)
			(keepout
				(tracks not_allowed)
				(vias allowed)
				(pads allowed)
				(copperpour not_allowed)
				(footprints allowed)
			)
			(placement
				(enabled no)
				(sheetname "")
			)
			(fill
				(thermal_gap 0.5)
				(thermal_bridge_width 0.5)
				(island_removal_mode 0)
			)
			(polygon
				(pts
					(xy 247.904 -17.2593) (xy 248.412 -17.2593) (xy 248.412 -18.2499) (xy 247.904 -18.2499)
				)
			)
		)
		(zone
			(layer "B.Cu")
			(hatch none 0.5)
			(connect_pads
				(clearance 0)
			)
			(min_thickness 0.25)
			(keepout
				(tracks allowed)
				(vias not_allowed)
				(pads allowed)
				(copperpour not_allowed)
				(footprints allowed)
			)
			(placement
				(enabled no)
				(sheetname "")
			)
			(fill
				(thermal_gap 0.5)
				(thermal_bridge_width 0.5)
				(island_removal_mode 0)
			)
			(polygon
				(pts
					(xy 247.904 -17.2593) (xy 248.412 -17.2593) (xy 248.412 -18.2499) (xy 247.904 -18.2499)
				)
			)
		)
	)
	(footprint ""
		(layer "B.Cu")
		(at 276.000464 -145.0086 90)
		(property "Reference" "C5L6"
			(at -1.848866 0.752348 90)
			(unlocked yes)
			(layer "B.SilkS")
			(effects
				(font
					(size 1.27 0.9652)
					(thickness 0.1524)
				)
				(justify mirror)
			)
		)
		(property "Value" ""
			(at 0 0 90)
			(layer "B.Fab")
			(effects
				(font
					(size 1.27 1.27)
				)
				(justify mirror)
			)
		)
		(duplicate_pad_numbers_are_jumpers no)
		(fp_rect
			(start 0.500126 1.598422)
			(end -0.500126 -0.201422)
			(stroke
				(width 0)
				(type default)
			)
			(fill no)
			(layer "B.CrtYd")
		)
		(fp_line
			(start 0.500126 -0.201422)
			(end -0.500126 -0.201422)
			(stroke
				(width 0.1)
				(type default)
			)
			(layer "B.Fab")
		)
		(fp_line
			(start -0.500126 -0.201422)
			(end -0.500126 1.598422)
			(stroke
				(width 0.1)
				(type default)
			)
			(layer "B.Fab")
		)
		(fp_line
			(start 0.500126 1.598422)
			(end 0.500126 -0.201422)
			(stroke
				(width 0.1)
				(type default)
			)
			(layer "B.Fab")
		)
		(fp_line
			(start -0.500126 1.598422)
			(end 0.500126 1.598422)
			(stroke
				(width 0.1)
				(type default)
			)
			(layer "B.Fab")
		)
		(pad "1" smd rect
			(at 0 0)
			(size 0.889 0.9906)
			(layers "B.Cu" "B.Mask" "B.Paste")
			(net "PVDDQ_DEF")
		)
		(pad "2" smd rect
			(at 0 1.397)
			(size 0.889 0.9906)
			(layers "B.Cu" "B.Mask" "B.Paste")
			(net "GND")
		)
		(zone
			(layer "B.Cu")
			(hatch none 0.5)
			(connect_pads
				(clearance 0)
			)
			(min_thickness 0.25)
			(keepout
				(tracks not_allowed)
				(vias allowed)
				(pads allowed)
				(copperpour not_allowed)
				(footprints allowed)
			)
			(placement
				(enabled no)
				(sheetname "")
			)
			(fill
				(thermal_gap 0.5)
				(thermal_bridge_width 0.5)
				(island_removal_mode 0)
			)
			(polygon
				(pts
					(xy 276.952964 -145.5039) (xy 276.444964 -145.5039) (xy 276.444964 -144.5133) (xy 276.952964 -144.5133)
				)
			)
		)
		(zone
			(layer "B.Cu")
			(hatch none 0.5)
			(connect_pads
				(clearance 0)
			)
			(min_thickness 0.25)
			(keepout
				(tracks allowed)
				(vias not_allowed)
				(pads allowed)
				(copperpour not_allowed)
				(footprints allowed)
			)
			(placement
				(enabled no)
				(sheetname "")
			)
			(fill
				(thermal_gap 0.5)
				(thermal_bridge_width 0.5)
				(island_removal_mode 0)
			)
			(polygon
				(pts
					(xy 276.952964 -145.5039) (xy 276.444964 -145.5039) (xy 276.444964 -144.5133) (xy 276.952964 -144.5133)
				)
			)
		)
	)
	(footprint ""
		(layer "B.Cu")
		(at 266.245086 -79.60614 180)
		(property "Reference" "C5P15"
			(at 0 0 0)
			(layer "B.SilkS")
			(hide yes)
			(effects
				(font
					(size 1.27 1.27)
				)
				(justify mirror)
			)
		)
		(property "Value" ""
			(at 0 0 0)
			(layer "B.Fab")
			(effects
				(font
					(size 1.27 1.27)
				)
				(justify mirror)
			)
		)
		(duplicate_pad_numbers_are_jumpers no)
		(fp_poly
			(pts
				(xy 0.7239 -0.2159) (xy -0.7239 -0.2159) (xy -0.7239 1.9939) (xy 0.7239 1.9939)
			)
			(stroke
				(width 0)
				(type default)
			)
			(fill no)
			(layer "B.CrtYd")
		)
		(fp_line
			(start 0.7239 1.9939)
			(end -0.7239 1.9939)
			(stroke
				(width 0.1)
				(type default)
			)
			(layer "B.Fab")
		)
		(fp_line
			(start 0.7239 -0.2159)
			(end 0.7239 1.9939)
			(stroke
				(width 0.1)
				(type default)
			)
			(layer "B.Fab")
		)
		(fp_line
			(start -0.7239 1.9939)
			(end -0.7239 -0.2159)
			(stroke
				(width 0.1)
				(type default)
			)
			(layer "B.Fab")
		)
		(fp_line
			(start -0.7239 -0.2159)
			(end 0.7239 -0.2159)
			(stroke
				(width 0.1)
				(type default)
			)
			(layer "B.Fab")
		)
		(pad "1" smd rect
			(at 0 0)
			(size 1.27 1.016)
			(layers "B.Cu" "B.Mask" "B.Paste")
			(net "PVCCIN_CPU0")
		)
		(pad "2" smd rect
			(at 0 1.778)
			(size 1.27 1.016)
			(layers "B.Cu" "B.Mask" "B.Paste")
			(net "GND")
		)
		(zone
			(layer "B.Cu")
			(hatch none 0.5)
			(connect_pads
				(clearance 0)
			)
			(min_thickness 0.25)
			(keepout
				(tracks not_allowed)
				(vias allowed)
				(pads allowed)
				(copperpour not_allowed)
				(footprints allowed)
			)
			(placement
				(enabled no)
				(sheetname "")
			)
			(fill
				(thermal_gap 0.5)
				(thermal_bridge_width 0.5)
				(island_removal_mode 0)
			)
			(polygon
				(pts
					(xy 265.610086 -80.11414) (xy 266.880086 -80.11414) (xy 266.880086 -80.87614) (xy 265.610086 -80.87614)
				)
			)
		)
	)
	(footprint ""
		(layer "B.Cu")
		(at 372.872 -6.1595)
		(property "Reference" "R7G27"
			(at 0 0 0)
			(layer "B.SilkS")
			(hide yes)
			(effects
				(font
					(size 1.27 1.27)
				)
				(justify mirror)
			)
		)
		(property "Value" ""
			(at 0 0 0)
			(layer "B.Fab")
			(effects
				(font
					(size 1.27 1.27)
				)
				(justify mirror)
			)
		)
		(duplicate_pad_numbers_are_jumpers no)
		(fp_poly
			(pts
				(xy 0.2794 -0.1016) (xy -0.2794 -0.1016) (xy -0.2794 0.9906) (xy 0.2794 0.9906)
			)
			(stroke
				(width 0)
				(type default)
			)
			(fill no)
			(layer "B.CrtYd")
		)
		(fp_line
			(start -0.2794 -0.1016)
			(end 0.2794 -0.1016)
			(stroke
				(width 0.1)
				(type default)
			)
			(layer "B.Fab")
		)
		(fp_line
			(start -0.2794 0.9906)
			(end -0.2794 -0.1016)
			(stroke
				(width 0.1)
				(type default)
			)
			(layer "B.Fab")
		)
		(fp_line
			(start 0.2794 -0.1016)
			(end 0.2794 0.9906)
			(stroke
				(width 0.1)
				(type default)
			)
			(layer "B.Fab")
		)
		(fp_line
			(start 0.2794 0.9906)
			(end -0.2794 0.9906)
			(stroke
				(width 0.1)
				(type default)
			)
			(layer "B.Fab")
		)
		(pad "1" smd rect
			(at 0 0 180)
			(size 0.508 0.508)
			(layers "B.Cu" "B.Mask" "B.Paste")
			(net "P3V3_STBY")
		)
		(pad "2" smd rect
			(at 0 0.889 180)
			(size 0.508 0.508)
			(layers "B.Cu" "B.Mask" "B.Paste")
			(net "PU_BIOS_USB_RECOVERY")
		)
		(zone
			(layer "B.Cu")
			(hatch none 0.5)
			(connect_pads
				(clearance 0)
			)
			(min_thickness 0.25)
			(keepout
				(tracks allowed)
				(vias not_allowed)
				(pads allowed)
				(copperpour not_allowed)
				(footprints allowed)
			)
			(placement
				(enabled no)
				(sheetname "")
			)
			(fill
				(thermal_gap 0.5)
				(thermal_bridge_width 0.5)
				(island_removal_mode 0)
			)
			(polygon
				(pts
					(xy 373.126 -5.9055) (xy 372.618 -5.9055) (xy 372.618 -5.5245) (xy 373.126 -5.5245)
				)
			)
		)
		(zone
			(layer "B.Cu")
			(hatch none 0.5)
			(connect_pads
				(clearance 0)
			)
			(min_thickness 0.25)
			(keepout
				(tracks not_allowed)
				(vias allowed)
				(pads allowed)
				(copperpour not_allowed)
				(footprints allowed)
			)
			(placement
				(enabled no)
				(sheetname "")
			)
			(fill
				(thermal_gap 0.5)
				(thermal_bridge_width 0.5)
				(island_removal_mode 0)
			)
			(polygon
				(pts
					(xy 373.126 -5.5245) (xy 372.618 -5.5245) (xy 372.618 -5.9055) (xy 373.126 -5.9055)
				)
			)
		)
	)
	(footprint ""
		(layer "B.Cu")
		(at 421.513 -81.4705)
		(property "Reference" "R2P13"
			(at 0 0 0)
			(layer "B.SilkS")
			(hide yes)
			(effects
				(font
					(size 1.27 1.27)
				)
				(justify mirror)
			)
		)
		(property "Value" ""
			(at 0 0 0)
			(layer "B.Fab")
			(effects
				(font
					(size 1.27 1.27)
				)
				(justify mirror)
			)
		)
		(duplicate_pad_numbers_are_jumpers no)
		(fp_poly
			(pts
				(xy 0.2794 -0.1016) (xy -0.2794 -0.1016) (xy -0.2794 0.9906) (xy 0.2794 0.9906)
			)
			(stroke
				(width 0)
				(type default)
			)
			(fill no)
			(layer "B.CrtYd")
		)
		(fp_line
			(start -0.2794 -0.1016)
			(end 0.2794 -0.1016)
			(stroke
				(width 0.1)
				(type default)
			)
			(layer "B.Fab")
		)
		(fp_line
			(start -0.2794 0.9906)
			(end -0.2794 -0.1016)
			(stroke
				(width 0.1)
				(type default)
			)
			(layer "B.Fab")
		)
		(fp_line
			(start 0.2794 -0.1016)
			(end 0.2794 0.9906)
			(stroke
				(width 0.1)
				(type default)
			)
			(layer "B.Fab")
		)
		(fp_line
			(start 0.2794 0.9906)
			(end -0.2794 0.9906)
			(stroke
				(width 0.1)
				(type default)
			)
			(layer "B.Fab")
		)
		(pad "1" smd rect
			(at 0 0 180)
			(size 0.508 0.508)
			(layers "B.Cu" "B.Mask" "B.Paste")
			(net "P3V3_STBY")
		)
		(pad "2" smd rect
			(at 0 0.889 180)
			(size 0.508 0.508)
			(layers "B.Cu" "B.Mask" "B.Paste")
			(net "FM_PMBUS_ALERT_BUF_EN_N")
		)
		(zone
			(layer "B.Cu")
			(hatch none 0.5)
			(connect_pads
				(clearance 0)
			)
			(min_thickness 0.25)
			(keepout
				(tracks allowed)
				(vias not_allowed)
				(pads allowed)
				(copperpour not_allowed)
				(footprints allowed)
			)
			(placement
				(enabled no)
				(sheetname "")
			)
			(fill
				(thermal_gap 0.5)
				(thermal_bridge_width 0.5)
				(island_removal_mode 0)
			)
			(polygon
				(pts
					(xy 421.767 -81.2165) (xy 421.259 -81.2165) (xy 421.259 -80.8355) (xy 421.767 -80.8355)
				)
			)
		)
		(zone
			(layer "B.Cu")
			(hatch none 0.5)
			(connect_pads
				(clearance 0)
			)
			(min_thickness 0.25)
			(keepout
				(tracks not_allowed)
				(vias allowed)
				(pads allowed)
				(copperpour not_allowed)
				(footprints allowed)
			)
			(placement
				(enabled no)
				(sheetname "")
			)
			(fill
				(thermal_gap 0.5)
				(thermal_bridge_width 0.5)
				(island_removal_mode 0)
			)
			(polygon
				(pts
					(xy 421.767 -80.8355) (xy 421.259 -80.8355) (xy 421.259 -81.2165) (xy 421.767 -81.2165)
				)
			)
		)
	)
	(footprint ""
		(layer "B.Cu")
		(at 64.262 -64.7954 180)
		(property "Reference" "R1E8"
			(at 0 0 0)
			(layer "B.SilkS")
			(hide yes)
			(effects
				(font
					(size 1.27 1.27)
				)
				(justify mirror)
			)
		)
		(property "Value" ""
			(at 0 0 0)
			(layer "B.Fab")
			(effects
				(font
					(size 1.27 1.27)
				)
				(justify mirror)
			)
		)
		(duplicate_pad_numbers_are_jumpers no)
		(fp_poly
			(pts
				(xy 0.2794 -0.1016) (xy -0.2794 -0.1016) (xy -0.2794 0.9906) (xy 0.2794 0.9906)
			)
			(stroke
				(width 0)
				(type default)
			)
			(fill no)
			(layer "B.CrtYd")
		)
		(fp_line
			(start 0.2794 0.9906)
			(end -0.2794 0.9906)
			(stroke
				(width 0.1)
				(type default)
			)
			(layer "B.Fab")
		)
		(fp_line
			(start 0.2794 -0.1016)
			(end 0.2794 0.9906)
			(stroke
				(width 0.1)
				(type default)
			)
			(layer "B.Fab")
		)
		(fp_line
			(start -0.2794 0.9906)
			(end -0.2794 -0.1016)
			(stroke
				(width 0.1)
				(type default)
			)
			(layer "B.Fab")
		)
		(fp_line
			(start -0.2794 -0.1016)
			(end 0.2794 -0.1016)
			(stroke
				(width 0.1)
				(type default)
			)
			(layer "B.Fab")
		)
		(pad "1" smd rect
			(at 0 0)
			(size 0.508 0.508)
			(layers "B.Cu" "B.Mask" "B.Paste")
			(net "VSENSE_PVCCIN_CPU1_N")
		)
		(pad "2" smd rect
			(at 0 0.889)
			(size 0.508 0.508)
			(layers "B.Cu" "B.Mask" "B.Paste")
			(net "GND")
		)
		(zone
			(layer "B.Cu")
			(hatch none 0.5)
			(connect_pads
				(clearance 0)
			)
			(min_thickness 0.25)
			(keepout
				(tracks not_allowed)
				(vias allowed)
				(pads allowed)
				(copperpour not_allowed)
				(footprints allowed)
			)
			(placement
				(enabled no)
				(sheetname "")
			)
			(fill
				(thermal_gap 0.5)
				(thermal_bridge_width 0.5)
				(island_removal_mode 0)
			)
			(polygon
				(pts
					(xy 64.008 -65.4304) (xy 64.516 -65.4304) (xy 64.516 -65.0494) (xy 64.008 -65.0494)
				)
			)
		)
		(zone
			(layer "B.Cu")
			(hatch none 0.5)
			(connect_pads
				(clearance 0)
			)
			(min_thickness 0.25)
			(keepout
				(tracks allowed)
				(vias not_allowed)
				(pads allowed)
				(copperpour not_allowed)
				(footprints allowed)
			)
			(placement
				(enabled no)
				(sheetname "")
			)
			(fill
				(thermal_gap 0.5)
				(thermal_bridge_width 0.5)
				(island_removal_mode 0)
			)
			(polygon
				(pts
					(xy 64.008 -65.0494) (xy 64.516 -65.0494) (xy 64.516 -65.4304) (xy 64.008 -65.4304)
				)
			)
		)
	)
	(footprint ""
		(layer "B.Cu")
		(at 96.45904 -157.02788 -90)
		(property "Reference" "C8L4"
			(at -1.47828 0.78994 0)
			(unlocked yes)
			(layer "B.SilkS")
			(effects
				(font
					(size 0.4064 0.254)
					(thickness 0.1524)
				)
				(justify mirror)
			)
		)
		(property "Value" ""
			(at 0 0 90)
			(layer "B.Fab")
			(effects
				(font
					(size 1.27 1.27)
				)
				(justify mirror)
			)
		)
		(duplicate_pad_numbers_are_jumpers no)
		(fp_poly
			(pts
				(xy 0.7239 -0.2159) (xy -0.7239 -0.2159) (xy -0.7239 1.9939) (xy 0.7239 1.9939)
			)
			(stroke
				(width 0)
				(type default)
			)
			(fill no)
			(layer "B.CrtYd")
		)
		(fp_line
			(start -0.7239 1.9939)
			(end -0.7239 -0.2159)
			(stroke
				(width 0.1)
				(type default)
			)
			(layer "B.Fab")
		)
		(fp_line
			(start 0.7239 1.9939)
			(end -0.7239 1.9939)
			(stroke
				(width 0.1)
				(type default)
			)
			(layer "B.Fab")
		)
		(fp_line
			(start -0.7239 -0.2159)
			(end 0.7239 -0.2159)
			(stroke
				(width 0.1)
				(type default)
			)
			(layer "B.Fab")
		)
		(fp_line
			(start 0.7239 -0.2159)
			(end 0.7239 1.9939)
			(stroke
				(width 0.1)
				(type default)
			)
			(layer "B.Fab")
		)
		(pad "1" smd rect
			(at 0 0 90)
			(size 1.27 1.016)
			(layers "B.Cu" "B.Mask" "B.Paste")
			(net "PVTT_KLM")
		)
		(pad "2" smd rect
			(at 0 1.778 90)
			(size 1.27 1.016)
			(layers "B.Cu" "B.Mask" "B.Paste")
			(net "GND")
		)
		(zone
			(layer "B.Cu")
			(hatch none 0.5)
			(connect_pads
				(clearance 0)
			)
			(min_thickness 0.25)
			(keepout
				(tracks not_allowed)
				(vias allowed)
				(pads allowed)
				(copperpour not_allowed)
				(footprints allowed)
			)
			(placement
				(enabled no)
				(sheetname "")
			)
			(fill
				(thermal_gap 0.5)
				(thermal_bridge_width 0.5)
				(island_removal_mode 0)
			)
			(polygon
				(pts
					(xy 95.95104 -156.39288) (xy 95.95104 -157.66288) (xy 95.18904 -157.66288) (xy 95.18904 -156.39288)
				)
			)
		)
	)
	(footprint ""
		(layer "B.Cu")
		(at 117.094 -81.483962)
		(property "Reference" "R7P5"
			(at 0 0 0)
			(layer "B.SilkS")
			(hide yes)
			(effects
				(font
					(size 1.27 1.27)
				)
				(justify mirror)
			)
		)
		(property "Value" ""
			(at 0 0 0)
			(layer "B.Fab")
			(effects
				(font
					(size 1.27 1.27)
				)
				(justify mirror)
			)
		)
		(duplicate_pad_numbers_are_jumpers no)
		(fp_poly
			(pts
				(xy 0.2794 -0.1016) (xy -0.2794 -0.1016) (xy -0.2794 0.9906) (xy 0.2794 0.9906)
			)
			(stroke
				(width 0)
				(type default)
			)
			(fill no)
			(layer "B.CrtYd")
		)
		(fp_line
			(start -0.2794 -0.1016)
			(end 0.2794 -0.1016)
			(stroke
				(width 0.1)
				(type default)
			)
			(layer "B.Fab")
		)
		(fp_line
			(start -0.2794 0.9906)
			(end -0.2794 -0.1016)
			(stroke
				(width 0.1)
				(type default)
			)
			(layer "B.Fab")
		)
		(fp_line
			(start 0.2794 -0.1016)
			(end 0.2794 0.9906)
			(stroke
				(width 0.1)
				(type default)
			)
			(layer "B.Fab")
		)
		(fp_line
			(start 0.2794 0.9906)
			(end -0.2794 0.9906)
			(stroke
				(width 0.1)
				(type default)
			)
			(layer "B.Fab")
		)
		(pad "1" smd rect
			(at 0 0 180)
			(size 0.508 0.508)
			(layers "B.Cu" "B.Mask" "B.Paste")
			(net "H_CPU1_MEMGHJ_MEMHOT_G_N")
		)
		(pad "2" smd rect
			(at 0 0.889 180)
			(size 0.508 0.508)
			(layers "B.Cu" "B.Mask" "B.Paste")
			(net "PVCCIO_CPU1")
		)
		(zone
			(layer "B.Cu")
			(hatch none 0.5)
			(connect_pads
				(clearance 0)
			)
			(min_thickness 0.25)
			(keepout
				(tracks allowed)
				(vias not_allowed)
				(pads allowed)
				(copperpour not_allowed)
				(footprints allowed)
			)
			(placement
				(enabled no)
				(sheetname "")
			)
			(fill
				(thermal_gap 0.5)
				(thermal_bridge_width 0.5)
				(island_removal_mode 0)
			)
			(polygon
				(pts
					(xy 117.348 -81.229962) (xy 116.84 -81.229962) (xy 116.84 -80.848962) (xy 117.348 -80.848962)
				)
			)
		)
		(zone
			(layer "B.Cu")
			(hatch none 0.5)
			(connect_pads
				(clearance 0)
			)
			(min_thickness 0.25)
			(keepout
				(tracks not_allowed)
				(vias allowed)
				(pads allowed)
				(copperpour not_allowed)
				(footprints allowed)
			)
			(placement
				(enabled no)
				(sheetname "")
			)
			(fill
				(thermal_gap 0.5)
				(thermal_bridge_width 0.5)
				(island_removal_mode 0)
			)
			(polygon
				(pts
					(xy 117.348 -80.848962) (xy 116.84 -80.848962) (xy 116.84 -81.229962) (xy 117.348 -81.229962)
				)
			)
		)
	)
	(footprint ""
		(layer "B.Cu")
		(at 418.61486 -30.13456 90)
		(property "Reference" "C25W43"
			(at 0.8382 -0.67818 90)
			(unlocked yes)
			(layer "B.SilkS")
			(effects
				(font
					(size 0.4064 0.254)
					(thickness 0.1524)
				)
				(justify left mirror)
			)
		)
		(property "Value" ""
			(at 0 0 90)
			(layer "B.Fab")
			(effects
				(font
					(size 1.27 1.27)
				)
				(justify mirror)
			)
		)
		(duplicate_pad_numbers_are_jumpers no)
		(fp_poly
			(pts
				(xy -0.3048 -0.1016) (xy -0.3048 0.9906) (xy 0.3048 0.9906) (xy 0.3048 -0.1016)
			)
			(stroke
				(width 0)
				(type default)
			)
			(fill no)
			(layer "B.CrtYd")
		)
		(fp_line
			(start 0.3048 -0.1016)
			(end 0.3048 0.9906)
			(stroke
				(width 0.1)
				(type default)
			)
			(layer "B.Fab")
		)
		(fp_line
			(start -0.3048 -0.1016)
			(end 0.3048 -0.1016)
			(stroke
				(width 0.1)
				(type default)
			)
			(layer "B.Fab")
		)
		(fp_line
			(start 0.3048 0.9906)
			(end -0.3048 0.9906)
			(stroke
				(width 0.1)
				(type default)
			)
			(layer "B.Fab")
		)
		(fp_line
			(start -0.3048 0.9906)
			(end -0.3048 -0.1016)
			(stroke
				(width 0.1)
				(type default)
			)
			(layer "B.Fab")
		)
		(pad "1" smd rect
			(at 0 0 270)
			(size 0.508 0.508)
			(layers "B.Cu" "B.Mask" "B.Paste")
			(net "VCC_D_3V3")
		)
		(pad "2" smd rect
			(at 0 0.889 270)
			(size 0.508 0.508)
			(layers "B.Cu" "B.Mask" "B.Paste")
			(net "GND")
		)
		(zone
			(layer "B.Cu")
			(hatch none 0.5)
			(connect_pads
				(clearance 0)
			)
			(min_thickness 0.25)
			(keepout
				(tracks allowed)
				(vias not_allowed)
				(pads allowed)
				(copperpour not_allowed)
				(footprints allowed)
			)
			(placement
				(enabled no)
				(sheetname "")
			)
			(fill
				(thermal_gap 0.5)
				(thermal_bridge_width 0.5)
				(island_removal_mode 0)
			)
			(polygon
				(pts
					(xy 418.86886 -30.38856) (xy 418.86886 -29.88056) (xy 419.24986 -29.88056) (xy 419.24986 -30.38856)
				)
			)
		)
		(zone
			(layer "B.Cu")
			(hatch none 0.5)
			(connect_pads
				(clearance 0)
			)
			(min_thickness 0.25)
			(keepout
				(tracks not_allowed)
				(vias allowed)
				(pads allowed)
				(copperpour not_allowed)
				(footprints allowed)
			)
			(placement
				(enabled no)
				(sheetname "")
			)
			(fill
				(thermal_gap 0.5)
				(thermal_bridge_width 0.5)
				(island_removal_mode 0)
			)
			(polygon
				(pts
					(xy 419.24986 -30.38856) (xy 419.24986 -29.88056) (xy 418.86886 -29.88056) (xy 418.86886 -30.38856)
				)
			)
		)
	)
	(footprint ""
		(layer "B.Cu")
		(at 194.700398 -152.078436 90)
		(property "Reference" "J6L1"
			(at 2.200148 37.96411 0)
			(unlocked yes)
			(layer "B.SilkS")
			(effects
				(font
					(size 0.7874 0.5842)
					(thickness 0.1524)
				)
				(justify left mirror)
			)
		)
		(property "Value" ""
			(at 0 0 90)
			(layer "B.Fab")
			(effects
				(font
					(size 1.27 1.27)
				)
				(justify mirror)
			)
		)
		(duplicate_pad_numbers_are_jumpers no)
		(fp_line
			(start 0.94996 -7.675118)
			(end -5.5499 -7.675118)
			(stroke
				(width 0.1524)
				(type default)
			)
			(layer "B.SilkS")
		)
		(fp_line
			(start -5.5499 -7.675118)
			(end -5.5499 -1.480058)
			(stroke
				(width 0.1524)
				(type default)
			)
			(layer "B.SilkS")
		)
		(fp_line
			(start 0.94996 -1.480058)
			(end 0.94996 -7.675118)
			(stroke
				(width 0.1524)
				(type default)
			)
			(layer "B.SilkS")
		)
		(fp_line
			(start -5.5499 128.130046)
			(end -5.5499 134.325106)
			(stroke
				(width 0.1524)
				(type default)
			)
			(layer "B.SilkS")
		)
		(fp_line
			(start 0.94996 134.325106)
			(end 0.94996 128.130046)
			(stroke
				(width 0.1524)
				(type default)
			)
			(layer "B.SilkS")
		)
		(fp_line
			(start -5.5499 134.325106)
			(end 0.94996 134.325106)
			(stroke
				(width 0.1524)
				(type default)
			)
			(layer "B.SilkS")
		)
		(fp_poly
			(pts
				(xy 3.646424 -4.23799) (xy 3.646424 -3.22199) (xy 2.376424 -3.72999)
			)
			(stroke
				(width 0)
				(type default)
			)
			(fill yes)
			(layer "B.SilkS")
		)
		(fp_poly
			(pts
				(xy 0.94996 -7.675118) (xy 0.94996 134.325106) (xy -5.5499 134.325106) (xy -5.5499 -7.675118)
			)
			(stroke
				(width 0)
				(type default)
			)
			(fill no)
			(layer "B.CrtYd")
		)
		(fp_line
			(start 0.94996 -7.675118)
			(end -5.5499 -7.675118)
			(stroke
				(width 0.1)
				(type default)
			)
			(layer "B.Fab")
		)
		(fp_line
			(start -5.5499 -7.675118)
			(end -5.5499 134.325106)
			(stroke
				(width 0.1)
				(type default)
			)
			(layer "B.Fab")
		)
		(fp_line
			(start 0.94996 134.325106)
			(end 0.94996 -7.675118)
			(stroke
				(width 0.1)
				(type default)
			)
			(layer "B.Fab")
		)
		(fp_line
			(start -5.5499 134.325106)
			(end 0.94996 134.325106)
			(stroke
				(width 0.1)
				(type default)
			)
			(layer "B.Fab")
		)
		(fp_poly
			(pts
				(xy 2.984246 -0.461264) (xy 2.984246 0.554736) (xy 1.714246 0.046736)
			)
			(stroke
				(width 0)
				(type default)
			)
			(fill yes)
			(layer "B.Fab")
		)
		(fp_text user "145"
			(at 1.683512 -1.977898 0)
			(unlocked yes)
			(layer "B.SilkS")
			(effects
				(font
					(size 0.7874 0.5842)
					(thickness 0.1524)
				)
				(justify left mirror)
			)
		)
		(fp_text user "221"
			(at -5.747512 65.26911 180)
			(unlocked yes)
			(layer "B.SilkS")
			(effects
				(font
					(size 0.7874 0.5842)
					(thickness 0.1524)
				)
				(justify left mirror)
			)
		)
		(fp_text user "77"
			(at 1.565148 66.15811 0)
			(unlocked yes)
			(layer "B.SilkS")
			(effects
				(font
					(size 0.7874 0.5842)
					(thickness 0.1524)
				)
				(justify left mirror)
			)
		)
		(fp_text user "78"
			(at 1.692148 71.23811 0)
			(unlocked yes)
			(layer "B.SilkS")
			(effects
				(font
					(size 0.7874 0.5842)
					(thickness 0.1524)
				)
				(justify left mirror)
			)
		)
		(fp_text user "222"
			(at -6.054852 71.87311 0)
			(unlocked yes)
			(layer "B.SilkS")
			(effects
				(font
					(size 0.7874 0.5842)
					(thickness 0.1524)
				)
				(justify left mirror)
			)
		)
		(fp_text user "144"
			(at 1.692148 129.53111 0)
			(unlocked yes)
			(layer "B.SilkS")
			(effects
				(font
					(size 0.7874 0.5842)
					(thickness 0.1524)
				)
				(justify left mirror)
			)
		)
		(fp_text user "288"
			(at -6.181852 129.78511 0)
			(unlocked yes)
			(layer "B.SilkS")
			(effects
				(font
					(size 0.7874 0.5842)
					(thickness 0.1524)
				)
				(justify left mirror)
			)
		)
		(fp_text user "145"
			(at -2.853182 -1.37922 90)
			(unlocked yes)
			(layer "B.Fab")
			(effects
				(font
					(size 0.7874 0.5842)
					(thickness 0.1524)
				)
				(justify left mirror)
			)
		)
		(fp_text user "77"
			(at 0.321818 65.93078 90)
			(unlocked yes)
			(layer "B.Fab")
			(effects
				(font
					(size 0.7874 0.5842)
					(thickness 0.1524)
				)
				(justify left mirror)
			)
		)
		(fp_text user "221"
			(at -2.853182 65.93078 90)
			(unlocked yes)
			(layer "B.Fab")
			(effects
				(font
					(size 0.7874 0.5842)
					(thickness 0.1524)
				)
				(justify left mirror)
			)
		)
		(fp_text user "222"
			(at -3.488182 69.10578 90)
			(unlocked yes)
			(layer "B.Fab")
			(effects
				(font
					(size 0.7874 0.5842)
					(thickness 0.1524)
				)
				(justify left mirror)
			)
		)
		(fp_text user "78"
			(at 0.956818 69.74078 90)
			(unlocked yes)
			(layer "B.Fab")
			(effects
				(font
					(size 0.7874 0.5842)
					(thickness 0.1524)
				)
				(justify left mirror)
			)
		)
		(fp_text user "144"
			(at 0.321818 128.16078 90)
			(unlocked yes)
			(layer "B.Fab")
			(effects
				(font
					(size 0.7874 0.5842)
					(thickness 0.1524)
				)
				(justify left mirror)
			)
		)
		(fp_text user "288"
			(at -2.853182 128.16078 90)
			(unlocked yes)
			(layer "B.Fab")
			(effects
				(font
					(size 0.7874 0.5842)
					(thickness 0.1524)
				)
				(justify left mirror)
			)
		)
		(pad "" thru_hole circle
			(at -2.29997 -5.649976 270)
			(size 2.8194 2.8194)
			(drill 2.4384)
			(layers "*.Cu" "*.Mask")
			(remove_unused_layers no)
			(clearance 0.127)
			(thermal_gap 0.127)
		)
		(pad "" thru_hole oval
			(at -2.29997 68.90004 270)
			(size 2.8194 1.5748)
			(drill oval 2.4384 1.1938)
			(layers "*.Cu" "*.Mask")
			(remove_unused_layers no)
			(clearance 0.127)
			(thermal_gap 0.127)
		)
		(pad "" thru_hole circle
			(at -2.29997 132.299964 270)
			(size 2.8194 2.8194)
			(drill 2.4384)
			(layers "*.Cu" "*.Mask")
			(remove_unused_layers no)
			(clearance 0.127)
			(thermal_gap 0.127)
		)
		(pad "1" smd rect
			(at 0 0 270)
			(size 1.8034 0.508)
			(layers "B.Cu" "B.Mask" "B.Paste")
			(net "P12V_NVDIMM_DEF")
		)
		(pad "2" smd rect
			(at 0 0.849884 270)
			(size 1.8034 0.508)
			(layers "B.Cu" "B.Mask" "B.Paste")
			(net "GND")
		)
		(pad "3" smd rect
			(at 0 1.700022 270)
			(size 1.8034 0.508)
			(layers "B.Cu" "B.Mask" "B.Paste")
			(net "M_F_DQ<4>")
		)
		(pad "4" smd rect
			(at 0 2.549906 270)
			(size 1.8034 0.508)
			(layers "B.Cu" "B.Mask" "B.Paste")
			(net "GND")
		)
		(pad "5" smd rect
			(at 0 3.400044 270)
			(size 1.8034 0.508)
			(layers "B.Cu" "B.Mask" "B.Paste")
			(net "M_F_DQ<0>")
		)
		(pad "6" smd rect
			(at 0 4.249928 270)
			(size 1.8034 0.508)
			(layers "B.Cu" "B.Mask" "B.Paste")
			(net "GND")
		)
		(pad "7" smd rect
			(at 0 5.100066 270)
			(size 1.8034 0.508)
			(layers "B.Cu" "B.Mask" "B.Paste")
			(net "M_F_DQS_DP<9>")
		)
		(pad "8" smd rect
			(at 0 5.94995 270)
			(size 1.8034 0.508)
			(layers "B.Cu" "B.Mask" "B.Paste")
			(net "M_F_DQS_DN<9>")
		)
		(pad "9" smd rect
			(at 0 6.800088 270)
			(size 1.8034 0.508)
			(layers "B.Cu" "B.Mask" "B.Paste")
			(net "GND")
		)
		(pad "10" smd rect
			(at 0 7.649972 270)
			(size 1.8034 0.508)
			(layers "B.Cu" "B.Mask" "B.Paste")
			(net "M_F_DQ<6>")
		)
		(pad "11" smd rect
			(at 0 8.50011 270)
			(size 1.8034 0.508)
			(layers "B.Cu" "B.Mask" "B.Paste")
			(net "GND")
		)
		(pad "12" smd rect
			(at 0 9.349994 270)
			(size 1.8034 0.508)
			(layers "B.Cu" "B.Mask" "B.Paste")
			(net "M_F_DQ<2>")
		)
		(pad "13" smd rect
			(at 0 10.199878 270)
			(size 1.8034 0.508)
			(layers "B.Cu" "B.Mask" "B.Paste")
			(net "GND")
		)
		(pad "14" smd rect
			(at 0 11.050016 270)
			(size 1.8034 0.508)
			(layers "B.Cu" "B.Mask" "B.Paste")
			(net "M_F_DQ<12>")
		)
		(pad "15" smd rect
			(at 0 11.8999 270)
			(size 1.8034 0.508)
			(layers "B.Cu" "B.Mask" "B.Paste")
			(net "GND")
		)
		(pad "16" smd rect
			(at 0 12.750038 270)
			(size 1.8034 0.508)
			(layers "B.Cu" "B.Mask" "B.Paste")
			(net "M_F_DQ<8>")
		)
		(pad "17" smd rect
			(at 0 13.599922 270)
			(size 1.8034 0.508)
			(layers "B.Cu" "B.Mask" "B.Paste")
			(net "GND")
		)
		(pad "18" smd rect
			(at 0 14.45006 270)
			(size 1.8034 0.508)
			(layers "B.Cu" "B.Mask" "B.Paste")
			(net "M_F_DQS_DP<10>")
		)
		(pad "19" smd rect
			(at 0 15.299944 270)
			(size 1.8034 0.508)
			(layers "B.Cu" "B.Mask" "B.Paste")
			(net "M_F_DQS_DN<10>")
		)
		(pad "20" smd rect
			(at 0 16.150082 270)
			(size 1.8034 0.508)
			(layers "B.Cu" "B.Mask" "B.Paste")
			(net "GND")
		)
		(pad "21" smd rect
			(at 0 16.999966 270)
			(size 1.8034 0.508)
			(layers "B.Cu" "B.Mask" "B.Paste")
			(net "M_F_DQ<14>")
		)
		(pad "22" smd rect
			(at 0 17.850104 270)
			(size 1.8034 0.508)
			(layers "B.Cu" "B.Mask" "B.Paste")
			(net "GND")
		)
		(pad "23" smd rect
			(at 0 18.699988 270)
			(size 1.8034 0.508)
			(layers "B.Cu" "B.Mask" "B.Paste")
			(net "M_F_DQ<10>")
		)
		(pad "24" smd rect
			(at 0 19.550126 270)
			(size 1.8034 0.508)
			(layers "B.Cu" "B.Mask" "B.Paste")
			(net "GND")
		)
		(pad "25" smd rect
			(at 0 20.40001 270)
			(size 1.8034 0.508)
			(layers "B.Cu" "B.Mask" "B.Paste")
			(net "M_F_DQ<20>")
		)
		(pad "26" smd rect
			(at 0 21.249894 270)
			(size 1.8034 0.508)
			(layers "B.Cu" "B.Mask" "B.Paste")
			(net "GND")
		)
		(pad "27" smd rect
			(at 0 22.100032 270)
			(size 1.8034 0.508)
			(layers "B.Cu" "B.Mask" "B.Paste")
			(net "M_F_DQ<16>")
		)
		(pad "28" smd rect
			(at 0 22.949916 270)
			(size 1.8034 0.508)
			(layers "B.Cu" "B.Mask" "B.Paste")
			(net "GND")
		)
		(pad "29" smd rect
			(at 0 23.800054 270)
			(size 1.8034 0.508)
			(layers "B.Cu" "B.Mask" "B.Paste")
			(net "M_F_DQS_DP<11>")
		)
		(pad "30" smd rect
			(at 0 24.649938 270)
			(size 1.8034 0.508)
			(layers "B.Cu" "B.Mask" "B.Paste")
			(net "M_F_DQS_DN<11>")
		)
		(pad "31" smd rect
			(at 0 25.500076 270)
			(size 1.8034 0.508)
			(layers "B.Cu" "B.Mask" "B.Paste")
			(net "GND")
		)
		(pad "32" smd rect
			(at 0 26.34996 270)
			(size 1.8034 0.508)
			(layers "B.Cu" "B.Mask" "B.Paste")
			(net "M_F_DQ<22>")
		)
		(pad "33" smd rect
			(at 0 27.200098 270)
			(size 1.8034 0.508)
			(layers "B.Cu" "B.Mask" "B.Paste")
			(net "GND")
		)
		(pad "34" smd rect
			(at 0 28.049982 270)
			(size 1.8034 0.508)
			(layers "B.Cu" "B.Mask" "B.Paste")
			(net "M_F_DQ<18>")
		)
		(pad "35" smd rect
			(at 0 28.90012 270)
			(size 1.8034 0.508)
			(layers "B.Cu" "B.Mask" "B.Paste")
			(net "GND")
		)
		(pad "36" smd rect
			(at 0 29.750004 270)
			(size 1.8034 0.508)
			(layers "B.Cu" "B.Mask" "B.Paste")
			(net "M_F_DQ<28>")
		)
		(pad "37" smd rect
			(at 0 30.599888 270)
			(size 1.8034 0.508)
			(layers "B.Cu" "B.Mask" "B.Paste")
			(net "GND")
		)
		(pad "38" smd rect
			(at 0 31.450026 270)
			(size 1.8034 0.508)
			(layers "B.Cu" "B.Mask" "B.Paste")
			(net "M_F_DQ<24>")
		)
		(pad "39" smd rect
			(at 0 32.29991 270)
			(size 1.8034 0.508)
			(layers "B.Cu" "B.Mask" "B.Paste")
			(net "GND")
		)
		(pad "40" smd rect
			(at 0 33.150048 270)
			(size 1.8034 0.508)
			(layers "B.Cu" "B.Mask" "B.Paste")
			(net "M_F_DQS_DP<12>")
		)
		(pad "41" smd rect
			(at 0 33.999932 270)
			(size 1.8034 0.508)
			(layers "B.Cu" "B.Mask" "B.Paste")
			(net "M_F_DQS_DN<12>")
		)
		(pad "42" smd rect
			(at 0 34.85007 270)
			(size 1.8034 0.508)
			(layers "B.Cu" "B.Mask" "B.Paste")
			(net "GND")
		)
		(pad "43" smd rect
			(at 0 35.699954 270)
			(size 1.8034 0.508)
			(layers "B.Cu" "B.Mask" "B.Paste")
			(net "M_F_DQ<30>")
		)
		(pad "44" smd rect
			(at 0 36.550092 270)
			(size 1.8034 0.508)
			(layers "B.Cu" "B.Mask" "B.Paste")
			(net "GND")
		)
		(pad "45" smd rect
			(at 0 37.399976 270)
			(size 1.8034 0.508)
			(layers "B.Cu" "B.Mask" "B.Paste")
			(net "M_F_DQ<26>")
		)
		(pad "46" smd rect
			(at 0 38.250114 270)
			(size 1.8034 0.508)
			(layers "B.Cu" "B.Mask" "B.Paste")
			(net "GND")
		)
		(pad "47" smd rect
			(at 0 39.099998 270)
			(size 1.8034 0.508)
			(layers "B.Cu" "B.Mask" "B.Paste")
			(net "M_F_ECC<4>")
		)
		(pad "48" smd rect
			(at 0 39.949882 270)
			(size 1.8034 0.508)
			(layers "B.Cu" "B.Mask" "B.Paste")
			(net "GND")
		)
		(pad "49" smd rect
			(at 0 40.80002 270)
			(size 1.8034 0.508)
			(layers "B.Cu" "B.Mask" "B.Paste")
			(net "M_F_ECC<0>")
		)
		(pad "50" smd rect
			(at 0 41.649904 270)
			(size 1.8034 0.508)
			(layers "B.Cu" "B.Mask" "B.Paste")
			(net "GND")
		)
		(pad "51" smd rect
			(at 0 42.500042 270)
			(size 1.8034 0.508)
			(layers "B.Cu" "B.Mask" "B.Paste")
			(net "M_F_DQS_DP<17>")
		)
		(pad "52" smd rect
			(at 0 43.349926 270)
			(size 1.8034 0.508)
			(layers "B.Cu" "B.Mask" "B.Paste")
			(net "M_F_DQS_DN<17>")
		)
		(pad "53" smd rect
			(at 0 44.200064 270)
			(size 1.8034 0.508)
			(layers "B.Cu" "B.Mask" "B.Paste")
			(net "GND")
		)
		(pad "54" smd rect
			(at 0 45.049948 270)
			(size 1.8034 0.508)
			(layers "B.Cu" "B.Mask" "B.Paste")
			(net "M_F_ECC<6>")
		)
		(pad "55" smd rect
			(at 0 45.900086 270)
			(size 1.8034 0.508)
			(layers "B.Cu" "B.Mask" "B.Paste")
			(net "GND")
		)
		(pad "56" smd rect
			(at 0 46.74997 270)
			(size 1.8034 0.508)
			(layers "B.Cu" "B.Mask" "B.Paste")
			(net "M_F_ECC<2>")
		)
		(pad "57" smd rect
			(at 0 47.600108 270)
			(size 1.8034 0.508)
			(layers "B.Cu" "B.Mask" "B.Paste")
			(net "GND")
		)
		(pad "58" smd rect
			(at 0 48.449992 270)
			(size 1.8034 0.508)
			(layers "B.Cu" "B.Mask" "B.Paste")
			(net "M_DEF_RST_N")
		)
		(pad "59" smd rect
			(at 0 49.299876 270)
			(size 1.8034 0.508)
			(layers "B.Cu" "B.Mask" "B.Paste")
			(net "PVDDQ_DEF")
		)
		(pad "60" smd rect
			(at 0 50.150014 270)
			(size 1.8034 0.508)
			(layers "B.Cu" "B.Mask" "B.Paste")
			(net "M_F_CKE<2>")
		)
		(pad "61" smd rect
			(at 0 50.999898 270)
			(size 1.8034 0.508)
			(layers "B.Cu" "B.Mask" "B.Paste")
			(net "PVDDQ_DEF")
		)
		(pad "62" smd rect
			(at 0 51.850036 270)
			(size 1.8034 0.508)
			(layers "B.Cu" "B.Mask" "B.Paste")
			(net "M_F_ACT_N")
		)
		(pad "63" smd rect
			(at 0 52.69992 270)
			(size 1.8034 0.508)
			(layers "B.Cu" "B.Mask" "B.Paste")
			(net "M_F_BG<0>")
		)
		(pad "64" smd rect
			(at 0 53.550058 270)
			(size 1.8034 0.508)
			(layers "B.Cu" "B.Mask" "B.Paste")
			(net "PVDDQ_DEF")
		)
		(pad "65" smd rect
			(at 0 54.399942 270)
			(size 1.8034 0.508)
			(layers "B.Cu" "B.Mask" "B.Paste")
			(net "M_F_MA<12>")
		)
		(pad "66" smd rect
			(at 0 55.25008 270)
			(size 1.8034 0.508)
			(layers "B.Cu" "B.Mask" "B.Paste")
			(net "M_F_MA<9>")
		)
		(pad "67" smd rect
			(at 0 56.099964 270)
			(size 1.8034 0.508)
			(layers "B.Cu" "B.Mask" "B.Paste")
			(net "PVDDQ_DEF")
		)
		(pad "68" smd rect
			(at 0 56.950102 270)
			(size 1.8034 0.508)
			(layers "B.Cu" "B.Mask" "B.Paste")
			(net "M_F_MA<8>")
		)
		(pad "69" smd rect
			(at 0 57.799986 270)
			(size 1.8034 0.508)
			(layers "B.Cu" "B.Mask" "B.Paste")
			(net "M_F_MA<6>")
		)
		(pad "70" smd rect
			(at 0 58.650124 270)
			(size 1.8034 0.508)
			(layers "B.Cu" "B.Mask" "B.Paste")
			(net "PVDDQ_DEF")
		)
		(pad "71" smd rect
			(at 0 59.500008 270)
			(size 1.8034 0.508)
			(layers "B.Cu" "B.Mask" "B.Paste")
			(net "M_F_MA<3>")
		)
		(pad "72" smd rect
			(at 0 60.349892 270)
			(size 1.8034 0.508)
			(layers "B.Cu" "B.Mask" "B.Paste")
			(net "M_F_MA<1>")
		)
		(pad "73" smd rect
			(at 0 61.20003 270)
			(size 1.8034 0.508)
			(layers "B.Cu" "B.Mask" "B.Paste")
			(net "PVDDQ_DEF")
		)
		(pad "74" smd rect
			(at 0 62.049914 270)
			(size 1.8034 0.508)
			(layers "B.Cu" "B.Mask" "B.Paste")
			(net "M_F_CLK_DP<2>")
		)
		(pad "75" smd rect
			(at 0 62.900052 270)
			(size 1.8034 0.508)
			(layers "B.Cu" "B.Mask" "B.Paste")
			(net "M_F_CLK_DN<2>")
		)
		(pad "76" smd rect
			(at 0 63.749936 270)
			(size 1.8034 0.508)
			(layers "B.Cu" "B.Mask" "B.Paste")
			(net "PVDDQ_DEF")
		)
		(pad "77" smd rect
			(at 0 64.600074 270)
			(size 1.8034 0.508)
			(layers "B.Cu" "B.Mask" "B.Paste")
			(net "PVTT_DEF")
		)
		(pad "78" smd rect
			(at 0 70.550024 270)
			(size 1.8034 0.508)
			(layers "B.Cu" "B.Mask" "B.Paste")
			(net "FM_DIMM_EVENT_COD_N")
		)
		(pad "79" smd rect
			(at 0 71.399908 270)
			(size 1.8034 0.508)
			(layers "B.Cu" "B.Mask" "B.Paste")
			(net "M_F_MA<0>")
		)
		(pad "80" smd rect
			(at 0 72.250046 270)
			(size 1.8034 0.508)
			(layers "B.Cu" "B.Mask" "B.Paste")
			(net "PVDDQ_DEF")
		)
		(pad "81" smd rect
			(at 0 73.09993 270)
			(size 1.8034 0.508)
			(layers "B.Cu" "B.Mask" "B.Paste")
			(net "M_F_BA<0>")
		)
		(pad "82" smd rect
			(at 0 73.950068 270)
			(size 1.8034 0.508)
			(layers "B.Cu" "B.Mask" "B.Paste")
			(net "M_F_MA<16>")
		)
		(pad "83" smd rect
			(at 0 74.799952 270)
			(size 1.8034 0.508)
			(layers "B.Cu" "B.Mask" "B.Paste")
			(net "PVDDQ_DEF")
		)
		(pad "84" smd rect
			(at 0 75.65009 270)
			(size 1.8034 0.508)
			(layers "B.Cu" "B.Mask" "B.Paste")
			(net "M_F_CS_N<4>")
		)
		(pad "85" smd rect
			(at 0 76.499974 270)
			(size 1.8034 0.508)
			(layers "B.Cu" "B.Mask" "B.Paste")
			(net "PVDDQ_DEF")
		)
		(pad "86" smd rect
			(at 0 77.350112 270)
			(size 1.8034 0.508)
			(layers "B.Cu" "B.Mask" "B.Paste")
			(net "M_F_MA<15>")
		)
		(pad "87" smd rect
			(at 0 78.199996 270)
			(size 1.8034 0.508)
			(layers "B.Cu" "B.Mask" "B.Paste")
			(net "M_F_ODT<2>")
		)
		(pad "88" smd rect
			(at 0 79.04988 270)
			(size 1.8034 0.508)
			(layers "B.Cu" "B.Mask" "B.Paste")
			(net "PVDDQ_DEF")
		)
		(pad "89" smd rect
			(at 0 79.900018 270)
			(size 1.8034 0.508)
			(layers "B.Cu" "B.Mask" "B.Paste")
			(net "M_F_CS_N<5>")
		)
		(pad "90" smd rect
			(at 0 80.749902 270)
			(size 1.8034 0.508)
			(layers "B.Cu" "B.Mask" "B.Paste")
			(net "PVDDQ_DEF")
		)
		(pad "91" smd rect
			(at 0 81.60004 270)
			(size 1.8034 0.508)
			(layers "B.Cu" "B.Mask" "B.Paste")
			(net "M_F_ODT<3>")
		)
		(pad "92" smd rect
			(at 0 82.449924 270)
			(size 1.8034 0.508)
			(layers "B.Cu" "B.Mask" "B.Paste")
			(net "PVDDQ_DEF")
		)
		(pad "93" smd rect
			(at 0 83.300062 270)
			(size 1.8034 0.508)
			(layers "B.Cu" "B.Mask" "B.Paste")
			(net "M_F_CS_N<6>")
		)
		(pad "94" smd rect
			(at 0 84.149946 270)
			(size 1.8034 0.508)
			(layers "B.Cu" "B.Mask" "B.Paste")
			(net "GND")
		)
		(pad "95" smd rect
			(at 0 85.000084 270)
			(size 1.8034 0.508)
			(layers "B.Cu" "B.Mask" "B.Paste")
			(net "M_F_DQ<36>")
		)
		(pad "96" smd rect
			(at 0 85.849968 270)
			(size 1.8034 0.508)
			(layers "B.Cu" "B.Mask" "B.Paste")
			(net "GND")
		)
		(pad "97" smd rect
			(at 0 86.700106 270)
			(size 1.8034 0.508)
			(layers "B.Cu" "B.Mask" "B.Paste")
			(net "M_F_DQ<32>")
		)
		(pad "98" smd rect
			(at 0 87.54999 270)
			(size 1.8034 0.508)
			(layers "B.Cu" "B.Mask" "B.Paste")
			(net "GND")
		)
		(pad "99" smd rect
			(at 0 88.399874 270)
			(size 1.8034 0.508)
			(layers "B.Cu" "B.Mask" "B.Paste")
			(net "M_F_DQS_DP<13>")
		)
		(pad "100" smd rect
			(at 0 89.250012 270)
			(size 1.8034 0.508)
			(layers "B.Cu" "B.Mask" "B.Paste")
			(net "M_F_DQS_DN<13>")
		)
		(pad "101" smd rect
			(at 0 90.099896 270)
			(size 1.8034 0.508)
			(layers "B.Cu" "B.Mask" "B.Paste")
			(net "GND")
		)
		(pad "102" smd rect
			(at 0 90.950034 270)
			(size 1.8034 0.508)
			(layers "B.Cu" "B.Mask" "B.Paste")
			(net "M_F_DQ<38>")
		)
		(pad "103" smd rect
			(at 0 91.799918 270)
			(size 1.8034 0.508)
			(layers "B.Cu" "B.Mask" "B.Paste")
			(net "GND")
		)
		(pad "104" smd rect
			(at 0 92.650056 270)
			(size 1.8034 0.508)
			(layers "B.Cu" "B.Mask" "B.Paste")
			(net "M_F_DQ<34>")
		)
		(pad "105" smd rect
			(at 0 93.49994 270)
			(size 1.8034 0.508)
			(layers "B.Cu" "B.Mask" "B.Paste")
			(net "GND")
		)
		(pad "106" smd rect
			(at 0 94.350078 270)
			(size 1.8034 0.508)
			(layers "B.Cu" "B.Mask" "B.Paste")
			(net "M_F_DQ<44>")
		)
		(pad "107" smd rect
			(at 0 95.199962 270)
			(size 1.8034 0.508)
			(layers "B.Cu" "B.Mask" "B.Paste")
			(net "GND")
		)
		(pad "108" smd rect
			(at 0 96.0501 270)
			(size 1.8034 0.508)
			(layers "B.Cu" "B.Mask" "B.Paste")
			(net "M_F_DQ<40>")
		)
		(pad "109" smd rect
			(at 0 96.899984 270)
			(size 1.8034 0.508)
			(layers "B.Cu" "B.Mask" "B.Paste")
			(net "GND")
		)
		(pad "110" smd rect
			(at 0 97.750122 270)
			(size 1.8034 0.508)
			(layers "B.Cu" "B.Mask" "B.Paste")
			(net "M_F_DQS_DP<14>")
		)
		(pad "111" smd rect
			(at 0 98.600006 270)
			(size 1.8034 0.508)
			(layers "B.Cu" "B.Mask" "B.Paste")
			(net "M_F_DQS_DN<14>")
		)
		(pad "112" smd rect
			(at 0 99.44989 270)
			(size 1.8034 0.508)
			(layers "B.Cu" "B.Mask" "B.Paste")
			(net "GND")
		)
		(pad "113" smd rect
			(at 0 100.300028 270)
			(size 1.8034 0.508)
			(layers "B.Cu" "B.Mask" "B.Paste")
			(net "M_F_DQ<46>")
		)
		(pad "114" smd rect
			(at 0 101.149912 270)
			(size 1.8034 0.508)
			(layers "B.Cu" "B.Mask" "B.Paste")
			(net "GND")
		)
		(pad "115" smd rect
			(at 0 102.00005 270)
			(size 1.8034 0.508)
			(layers "B.Cu" "B.Mask" "B.Paste")
			(net "M_F_DQ<42>")
		)
		(pad "116" smd rect
			(at 0 102.849934 270)
			(size 1.8034 0.508)
			(layers "B.Cu" "B.Mask" "B.Paste")
			(net "GND")
		)
		(pad "117" smd rect
			(at 0 103.700072 270)
			(size 1.8034 0.508)
			(layers "B.Cu" "B.Mask" "B.Paste")
			(net "M_F_DQ<52>")
		)
		(pad "118" smd rect
			(at 0 104.549956 270)
			(size 1.8034 0.508)
			(layers "B.Cu" "B.Mask" "B.Paste")
			(net "GND")
		)
		(pad "119" smd rect
			(at 0 105.400094 270)
			(size 1.8034 0.508)
			(layers "B.Cu" "B.Mask" "B.Paste")
			(net "M_F_DQ<48>")
		)
		(pad "120" smd rect
			(at 0 106.249978 270)
			(size 1.8034 0.508)
			(layers "B.Cu" "B.Mask" "B.Paste")
			(net "GND")
		)
		(pad "121" smd rect
			(at 0 107.100116 270)
			(size 1.8034 0.508)
			(layers "B.Cu" "B.Mask" "B.Paste")
			(net "M_F_DQS_DP<15>")
		)
		(pad "122" smd rect
			(at 0 107.95 270)
			(size 1.8034 0.508)
			(layers "B.Cu" "B.Mask" "B.Paste")
			(net "M_F_DQS_DN<15>")
		)
		(pad "123" smd rect
			(at 0 108.799884 270)
			(size 1.8034 0.508)
			(layers "B.Cu" "B.Mask" "B.Paste")
			(net "GND")
		)
		(pad "124" smd rect
			(at 0 109.650022 270)
			(size 1.8034 0.508)
			(layers "B.Cu" "B.Mask" "B.Paste")
			(net "M_F_DQ<54>")
		)
		(pad "125" smd rect
			(at 0 110.499906 270)
			(size 1.8034 0.508)
			(layers "B.Cu" "B.Mask" "B.Paste")
			(net "GND")
		)
		(pad "126" smd rect
			(at 0 111.350044 270)
			(size 1.8034 0.508)
			(layers "B.Cu" "B.Mask" "B.Paste")
			(net "M_F_DQ<50>")
		)
		(pad "127" smd rect
			(at 0 112.199928 270)
			(size 1.8034 0.508)
			(layers "B.Cu" "B.Mask" "B.Paste")
			(net "GND")
		)
		(pad "128" smd rect
			(at 0 113.050066 270)
			(size 1.8034 0.508)
			(layers "B.Cu" "B.Mask" "B.Paste")
			(net "M_F_DQ<60>")
		)
		(pad "129" smd rect
			(at 0 113.89995 270)
			(size 1.8034 0.508)
			(layers "B.Cu" "B.Mask" "B.Paste")
			(net "GND")
		)
		(pad "130" smd rect
			(at 0 114.750088 270)
			(size 1.8034 0.508)
			(layers "B.Cu" "B.Mask" "B.Paste")
			(net "M_F_DQ<56>")
		)
		(pad "131" smd rect
			(at 0 115.599972 270)
			(size 1.8034 0.508)
			(layers "B.Cu" "B.Mask" "B.Paste")
			(net "GND")
		)
		(pad "132" smd rect
			(at 0 116.45011 270)
			(size 1.8034 0.508)
			(layers "B.Cu" "B.Mask" "B.Paste")
			(net "M_F_DQS_DP<16>")
		)
		(pad "133" smd rect
			(at 0 117.299994 270)
			(size 1.8034 0.508)
			(layers "B.Cu" "B.Mask" "B.Paste")
			(net "M_F_DQS_DN<16>")
		)
		(pad "134" smd rect
			(at 0 118.149878 270)
			(size 1.8034 0.508)
			(layers "B.Cu" "B.Mask" "B.Paste")
			(net "GND")
		)
		(pad "135" smd rect
			(at 0 119.000016 270)
			(size 1.8034 0.508)
			(layers "B.Cu" "B.Mask" "B.Paste")
			(net "M_F_DQ<62>")
		)
		(pad "136" smd rect
			(at 0 119.8499 270)
			(size 1.8034 0.508)
			(layers "B.Cu" "B.Mask" "B.Paste")
			(net "GND")
		)
		(pad "137" smd rect
			(at 0 120.700038 270)
			(size 1.8034 0.508)
			(layers "B.Cu" "B.Mask" "B.Paste")
			(net "M_F_DQ<58>")
		)
		(pad "138" smd rect
			(at 0 121.549922 270)
			(size 1.8034 0.508)
			(layers "B.Cu" "B.Mask" "B.Paste")
			(net "GND")
		)
		(pad "139" smd rect
			(at 0 122.40006 270)
			(size 1.8034 0.508)
			(layers "B.Cu" "B.Mask" "B.Paste")
			(net "PVPP_DEF")
		)
		(pad "140" smd rect
			(at 0 123.249944 270)
			(size 1.8034 0.508)
			(layers "B.Cu" "B.Mask" "B.Paste")
			(net "GND")
		)
		(pad "141" smd rect
			(at 0 124.100082 270)
			(size 1.8034 0.508)
			(layers "B.Cu" "B.Mask" "B.Paste")
			(net "SMB_DDR_DEF_VPP_SCL")
		)
		(pad "142" smd rect
			(at 0 124.949966 270)
			(size 1.8034 0.508)
			(layers "B.Cu" "B.Mask" "B.Paste")
			(net "PVPP_DEF")
		)
		(pad "143" smd rect
			(at 0 125.800104 270)
			(size 1.8034 0.508)
			(layers "B.Cu" "B.Mask" "B.Paste")
			(net "PVPP_DEF")
		)
		(pad "144" smd rect
			(at 0 126.649988 270)
			(size 1.8034 0.508)
			(layers "B.Cu" "B.Mask" "B.Paste")
			(net "TP_CH_F_DIMM_F1_RFU_2")
		)
		(pad "145" smd rect
			(at -4.59994 0 270)
			(size 1.8034 0.508)
			(layers "B.Cu" "B.Mask" "B.Paste")
			(net "P12V_NVDIMM_DEF")
		)
		(pad "146" smd rect
			(at -4.59994 0.849884 270)
			(size 1.8034 0.508)
			(layers "B.Cu" "B.Mask" "B.Paste")
			(net "M_F_VREF")
		)
		(pad "147" smd rect
			(at -4.59994 1.700022 270)
			(size 1.8034 0.508)
			(layers "B.Cu" "B.Mask" "B.Paste")
			(net "GND")
		)
		(pad "148" smd rect
			(at -4.59994 2.549906 270)
			(size 1.8034 0.508)
			(layers "B.Cu" "B.Mask" "B.Paste")
			(net "M_F_DQ<5>")
		)
		(pad "149" smd rect
			(at -4.59994 3.400044 270)
			(size 1.8034 0.508)
			(layers "B.Cu" "B.Mask" "B.Paste")
			(net "GND")
		)
		(pad "150" smd rect
			(at -4.59994 4.249928 270)
			(size 1.8034 0.508)
			(layers "B.Cu" "B.Mask" "B.Paste")
			(net "M_F_DQ<1>")
		)
		(pad "151" smd rect
			(at -4.59994 5.100066 270)
			(size 1.8034 0.508)
			(layers "B.Cu" "B.Mask" "B.Paste")
			(net "GND")
		)
		(pad "152" smd rect
			(at -4.59994 5.94995 270)
			(size 1.8034 0.508)
			(layers "B.Cu" "B.Mask" "B.Paste")
			(net "M_F_DQS_DN<0>")
		)
		(pad "153" smd rect
			(at -4.59994 6.800088 270)
			(size 1.8034 0.508)
			(layers "B.Cu" "B.Mask" "B.Paste")
			(net "M_F_DQS_DP<0>")
		)
		(pad "154" smd rect
			(at -4.59994 7.649972 270)
			(size 1.8034 0.508)
			(layers "B.Cu" "B.Mask" "B.Paste")
			(net "GND")
		)
		(pad "155" smd rect
			(at -4.59994 8.50011 270)
			(size 1.8034 0.508)
			(layers "B.Cu" "B.Mask" "B.Paste")
			(net "M_F_DQ<7>")
		)
		(pad "156" smd rect
			(at -4.59994 9.349994 270)
			(size 1.8034 0.508)
			(layers "B.Cu" "B.Mask" "B.Paste")
			(net "GND")
		)
		(pad "157" smd rect
			(at -4.59994 10.199878 270)
			(size 1.8034 0.508)
			(layers "B.Cu" "B.Mask" "B.Paste")
			(net "M_F_DQ<3>")
		)
		(pad "158" smd rect
			(at -4.59994 11.050016 270)
			(size 1.8034 0.508)
			(layers "B.Cu" "B.Mask" "B.Paste")
			(net "GND")
		)
		(pad "159" smd rect
			(at -4.59994 11.8999 270)
			(size 1.8034 0.508)
			(layers "B.Cu" "B.Mask" "B.Paste")
			(net "M_F_DQ<13>")
		)
		(pad "160" smd rect
			(at -4.59994 12.750038 270)
			(size 1.8034 0.508)
			(layers "B.Cu" "B.Mask" "B.Paste")
			(net "GND")
		)
		(pad "161" smd rect
			(at -4.59994 13.599922 270)
			(size 1.8034 0.508)
			(layers "B.Cu" "B.Mask" "B.Paste")
			(net "M_F_DQ<9>")
		)
		(pad "162" smd rect
			(at -4.59994 14.45006 270)
			(size 1.8034 0.508)
			(layers "B.Cu" "B.Mask" "B.Paste")
			(net "GND")
		)
		(pad "163" smd rect
			(at -4.59994 15.299944 270)
			(size 1.8034 0.508)
			(layers "B.Cu" "B.Mask" "B.Paste")
			(net "M_F_DQS_DN<1>")
		)
		(pad "164" smd rect
			(at -4.59994 16.150082 270)
			(size 1.8034 0.508)
			(layers "B.Cu" "B.Mask" "B.Paste")
			(net "M_F_DQS_DP<1>")
		)
		(pad "165" smd rect
			(at -4.59994 16.999966 270)
			(size 1.8034 0.508)
			(layers "B.Cu" "B.Mask" "B.Paste")
			(net "GND")
		)
		(pad "166" smd rect
			(at -4.59994 17.850104 270)
			(size 1.8034 0.508)
			(layers "B.Cu" "B.Mask" "B.Paste")
			(net "M_F_DQ<15>")
		)
		(pad "167" smd rect
			(at -4.59994 18.699988 270)
			(size 1.8034 0.508)
			(layers "B.Cu" "B.Mask" "B.Paste")
			(net "GND")
		)
		(pad "168" smd rect
			(at -4.59994 19.550126 270)
			(size 1.8034 0.508)
			(layers "B.Cu" "B.Mask" "B.Paste")
			(net "M_F_DQ<11>")
		)
		(pad "169" smd rect
			(at -4.59994 20.40001 270)
			(size 1.8034 0.508)
			(layers "B.Cu" "B.Mask" "B.Paste")
			(net "GND")
		)
		(pad "170" smd rect
			(at -4.59994 21.249894 270)
			(size 1.8034 0.508)
			(layers "B.Cu" "B.Mask" "B.Paste")
			(net "M_F_DQ<21>")
		)
		(pad "171" smd rect
			(at -4.59994 22.100032 270)
			(size 1.8034 0.508)
			(layers "B.Cu" "B.Mask" "B.Paste")
			(net "GND")
		)
		(pad "172" smd rect
			(at -4.59994 22.949916 270)
			(size 1.8034 0.508)
			(layers "B.Cu" "B.Mask" "B.Paste")
			(net "M_F_DQ<17>")
		)
		(pad "173" smd rect
			(at -4.59994 23.800054 270)
			(size 1.8034 0.508)
			(layers "B.Cu" "B.Mask" "B.Paste")
			(net "GND")
		)
		(pad "174" smd rect
			(at -4.59994 24.649938 270)
			(size 1.8034 0.508)
			(layers "B.Cu" "B.Mask" "B.Paste")
			(net "M_F_DQS_DN<2>")
		)
		(pad "175" smd rect
			(at -4.59994 25.500076 270)
			(size 1.8034 0.508)
			(layers "B.Cu" "B.Mask" "B.Paste")
			(net "M_F_DQS_DP<2>")
		)
		(pad "176" smd rect
			(at -4.59994 26.34996 270)
			(size 1.8034 0.508)
			(layers "B.Cu" "B.Mask" "B.Paste")
			(net "GND")
		)
		(pad "177" smd rect
			(at -4.59994 27.200098 270)
			(size 1.8034 0.508)
			(layers "B.Cu" "B.Mask" "B.Paste")
			(net "M_F_DQ<23>")
		)
		(pad "178" smd rect
			(at -4.59994 28.049982 270)
			(size 1.8034 0.508)
			(layers "B.Cu" "B.Mask" "B.Paste")
			(net "GND")
		)
		(pad "179" smd rect
			(at -4.59994 28.90012 270)
			(size 1.8034 0.508)
			(layers "B.Cu" "B.Mask" "B.Paste")
			(net "M_F_DQ<19>")
		)
		(pad "180" smd rect
			(at -4.59994 29.750004 270)
			(size 1.8034 0.508)
			(layers "B.Cu" "B.Mask" "B.Paste")
			(net "GND")
		)
		(pad "181" smd rect
			(at -4.59994 30.599888 270)
			(size 1.8034 0.508)
			(layers "B.Cu" "B.Mask" "B.Paste")
			(net "M_F_DQ<29>")
		)
		(pad "182" smd rect
			(at -4.59994 31.450026 270)
			(size 1.8034 0.508)
			(layers "B.Cu" "B.Mask" "B.Paste")
			(net "GND")
		)
		(pad "183" smd rect
			(at -4.59994 32.29991 270)
			(size 1.8034 0.508)
			(layers "B.Cu" "B.Mask" "B.Paste")
			(net "M_F_DQ<25>")
		)
		(pad "184" smd rect
			(at -4.59994 33.150048 270)
			(size 1.8034 0.508)
			(layers "B.Cu" "B.Mask" "B.Paste")
			(net "GND")
		)
		(pad "185" smd rect
			(at -4.59994 33.999932 270)
			(size 1.8034 0.508)
			(layers "B.Cu" "B.Mask" "B.Paste")
			(net "M_F_DQS_DN<3>")
		)
		(pad "186" smd rect
			(at -4.59994 34.85007 270)
			(size 1.8034 0.508)
			(layers "B.Cu" "B.Mask" "B.Paste")
			(net "M_F_DQS_DP<3>")
		)
		(pad "187" smd rect
			(at -4.59994 35.699954 270)
			(size 1.8034 0.508)
			(layers "B.Cu" "B.Mask" "B.Paste")
			(net "GND")
		)
		(pad "188" smd rect
			(at -4.59994 36.550092 270)
			(size 1.8034 0.508)
			(layers "B.Cu" "B.Mask" "B.Paste")
			(net "M_F_DQ<31>")
		)
		(pad "189" smd rect
			(at -4.59994 37.399976 270)
			(size 1.8034 0.508)
			(layers "B.Cu" "B.Mask" "B.Paste")
			(net "GND")
		)
		(pad "190" smd rect
			(at -4.59994 38.250114 270)
			(size 1.8034 0.508)
			(layers "B.Cu" "B.Mask" "B.Paste")
			(net "M_F_DQ<27>")
		)
		(pad "191" smd rect
			(at -4.59994 39.099998 270)
			(size 1.8034 0.508)
			(layers "B.Cu" "B.Mask" "B.Paste")
			(net "GND")
		)
		(pad "192" smd rect
			(at -4.59994 39.949882 270)
			(size 1.8034 0.508)
			(layers "B.Cu" "B.Mask" "B.Paste")
			(net "M_F_ECC<5>")
		)
		(pad "193" smd rect
			(at -4.59994 40.80002 270)
			(size 1.8034 0.508)
			(layers "B.Cu" "B.Mask" "B.Paste")
			(net "GND")
		)
		(pad "194" smd rect
			(at -4.59994 41.649904 270)
			(size 1.8034 0.508)
			(layers "B.Cu" "B.Mask" "B.Paste")
			(net "M_F_ECC<1>")
		)
		(pad "195" smd rect
			(at -4.59994 42.500042 270)
			(size 1.8034 0.508)
			(layers "B.Cu" "B.Mask" "B.Paste")
			(net "GND")
		)
		(pad "196" smd rect
			(at -4.59994 43.349926 270)
			(size 1.8034 0.508)
			(layers "B.Cu" "B.Mask" "B.Paste")
			(net "M_F_DQS_DN<8>")
		)
		(pad "197" smd rect
			(at -4.59994 44.200064 270)
			(size 1.8034 0.508)
			(layers "B.Cu" "B.Mask" "B.Paste")
			(net "M_F_DQS_DP<8>")
		)
		(pad "198" smd rect
			(at -4.59994 45.049948 270)
			(size 1.8034 0.508)
			(layers "B.Cu" "B.Mask" "B.Paste")
			(net "GND")
		)
		(pad "199" smd rect
			(at -4.59994 45.900086 270)
			(size 1.8034 0.508)
			(layers "B.Cu" "B.Mask" "B.Paste")
			(net "M_F_ECC<7>")
		)
		(pad "200" smd rect
			(at -4.59994 46.74997 270)
			(size 1.8034 0.508)
			(layers "B.Cu" "B.Mask" "B.Paste")
			(net "GND")
		)
		(pad "201" smd rect
			(at -4.59994 47.600108 270)
			(size 1.8034 0.508)
			(layers "B.Cu" "B.Mask" "B.Paste")
			(net "M_F_ECC<3>")
		)
		(pad "202" smd rect
			(at -4.59994 48.449992 270)
			(size 1.8034 0.508)
			(layers "B.Cu" "B.Mask" "B.Paste")
			(net "GND")
		)
		(pad "203" smd rect
			(at -4.59994 49.299876 270)
			(size 1.8034 0.508)
			(layers "B.Cu" "B.Mask" "B.Paste")
			(net "M_F_CKE<3>")
		)
		(pad "204" smd rect
			(at -4.59994 50.150014 270)
			(size 1.8034 0.508)
			(layers "B.Cu" "B.Mask" "B.Paste")
			(net "PVDDQ_DEF")
		)
		(pad "205" smd rect
			(at -4.59994 50.999898 270)
			(size 1.8034 0.508)
			(layers "B.Cu" "B.Mask" "B.Paste")
			(net "TP_CH_F_DIMM_F1_RFU_0")
		)
		(pad "206" smd rect
			(at -4.59994 51.850036 270)
			(size 1.8034 0.508)
			(layers "B.Cu" "B.Mask" "B.Paste")
			(net "PVDDQ_DEF")
		)
		(pad "207" smd rect
			(at -4.59994 52.69992 270)
			(size 1.8034 0.508)
			(layers "B.Cu" "B.Mask" "B.Paste")
			(net "M_F_BG<1>")
		)
		(pad "208" smd rect
			(at -4.59994 53.550058 270)
			(size 1.8034 0.508)
			(layers "B.Cu" "B.Mask" "B.Paste")
			(net "M_F_ALERT_N")
		)
		(pad "209" smd rect
			(at -4.59994 54.399942 270)
			(size 1.8034 0.508)
			(layers "B.Cu" "B.Mask" "B.Paste")
			(net "PVDDQ_DEF")
		)
		(pad "210" smd rect
			(at -4.59994 55.25008 270)
			(size 1.8034 0.508)
			(layers "B.Cu" "B.Mask" "B.Paste")
			(net "M_F_MA<11>")
		)
		(pad "211" smd rect
			(at -4.59994 56.099964 270)
			(size 1.8034 0.508)
			(layers "B.Cu" "B.Mask" "B.Paste")
			(net "M_F_MA<7>")
		)
		(pad "212" smd rect
			(at -4.59994 56.950102 270)
			(size 1.8034 0.508)
			(layers "B.Cu" "B.Mask" "B.Paste")
			(net "PVDDQ_DEF")
		)
		(pad "213" smd rect
			(at -4.59994 57.799986 270)
			(size 1.8034 0.508)
			(layers "B.Cu" "B.Mask" "B.Paste")
			(net "M_F_MA<5>")
		)
		(pad "214" smd rect
			(at -4.59994 58.650124 270)
			(size 1.8034 0.508)
			(layers "B.Cu" "B.Mask" "B.Paste")
			(net "M_F_MA<4>")
		)
		(pad "215" smd rect
			(at -4.59994 59.500008 270)
			(size 1.8034 0.508)
			(layers "B.Cu" "B.Mask" "B.Paste")
			(net "PVDDQ_DEF")
		)
		(pad "216" smd rect
			(at -4.59994 60.349892 270)
			(size 1.8034 0.508)
			(layers "B.Cu" "B.Mask" "B.Paste")
			(net "M_F_MA<2>")
		)
		(pad "217" smd rect
			(at -4.59994 61.20003 270)
			(size 1.8034 0.508)
			(layers "B.Cu" "B.Mask" "B.Paste")
			(net "PVDDQ_DEF")
		)
		(pad "218" smd rect
			(at -4.59994 62.049914 270)
			(size 1.8034 0.508)
			(layers "B.Cu" "B.Mask" "B.Paste")
			(net "M_F_CLK_DP<3>")
		)
		(pad "219" smd rect
			(at -4.59994 62.900052 270)
			(size 1.8034 0.508)
			(layers "B.Cu" "B.Mask" "B.Paste")
			(net "M_F_CLK_DN<3>")
		)
		(pad "220" smd rect
			(at -4.59994 63.749936 270)
			(size 1.8034 0.508)
			(layers "B.Cu" "B.Mask" "B.Paste")
			(net "PVDDQ_DEF")
		)
		(pad "221" smd rect
			(at -4.59994 64.600074 270)
			(size 1.8034 0.508)
			(layers "B.Cu" "B.Mask" "B.Paste")
			(net "PVTT_DEF")
		)
		(pad "222" smd rect
			(at -4.59994 70.550024 270)
			(size 1.8034 0.508)
			(layers "B.Cu" "B.Mask" "B.Paste")
			(net "M_F_PAR")
		)
		(pad "223" smd rect
			(at -4.59994 71.399908 270)
			(size 1.8034 0.508)
			(layers "B.Cu" "B.Mask" "B.Paste")
			(net "PVDDQ_DEF")
		)
		(pad "224" smd rect
			(at -4.59994 72.250046 270)
			(size 1.8034 0.508)
			(layers "B.Cu" "B.Mask" "B.Paste")
			(net "M_F_BA<1>")
		)
		(pad "225" smd rect
			(at -4.59994 73.09993 270)
			(size 1.8034 0.508)
			(layers "B.Cu" "B.Mask" "B.Paste")
			(net "M_F_MA<10>")
		)
		(pad "226" smd rect
			(at -4.59994 73.950068 270)
			(size 1.8034 0.508)
			(layers "B.Cu" "B.Mask" "B.Paste")
			(net "PVDDQ_DEF")
		)
		(pad "227" smd rect
			(at -4.59994 74.799952 270)
			(size 1.8034 0.508)
			(layers "B.Cu" "B.Mask" "B.Paste")
			(net "TP_CH_F_DIMM_F1_RFU_1")
		)
		(pad "228" smd rect
			(at -4.59994 75.65009 270)
			(size 1.8034 0.508)
			(layers "B.Cu" "B.Mask" "B.Paste")
			(net "M_F_MA<14>")
		)
		(pad "229" smd rect
			(at -4.59994 76.499974 270)
			(size 1.8034 0.508)
			(layers "B.Cu" "B.Mask" "B.Paste")
			(net "PVDDQ_DEF")
		)
		(pad "230" smd rect
			(at -4.59994 77.350112 270)
			(size 1.8034 0.508)
			(layers "B.Cu" "B.Mask" "B.Paste")
			(net "FM_ADR_COMPLETE_DEF_N")
		)
		(pad "231" smd rect
			(at -4.59994 78.199996 270)
			(size 1.8034 0.508)
			(layers "B.Cu" "B.Mask" "B.Paste")
			(net "PVDDQ_DEF")
		)
		(pad "232" smd rect
			(at -4.59994 79.04988 270)
			(size 1.8034 0.508)
			(layers "B.Cu" "B.Mask" "B.Paste")
			(net "M_F_MA<13>")
		)
		(pad "233" smd rect
			(at -4.59994 79.900018 270)
			(size 1.8034 0.508)
			(layers "B.Cu" "B.Mask" "B.Paste")
			(net "PVDDQ_DEF")
		)
		(pad "234" smd rect
			(at -4.59994 80.749902 270)
			(size 1.8034 0.508)
			(layers "B.Cu" "B.Mask" "B.Paste")
			(net "M_F_MA<17>")
		)
		(pad "235" smd rect
			(at -4.59994 81.60004 270)
			(size 1.8034 0.508)
			(layers "B.Cu" "B.Mask" "B.Paste")
			(net "M_F_C<2>")
		)
		(pad "236" smd rect
			(at -4.59994 82.449924 270)
			(size 1.8034 0.508)
			(layers "B.Cu" "B.Mask" "B.Paste")
			(net "PVDDQ_DEF")
		)
		(pad "237" smd rect
			(at -4.59994 83.300062 270)
			(size 1.8034 0.508)
			(layers "B.Cu" "B.Mask" "B.Paste")
			(net "M_F_CS_N<7>")
		)
		(pad "238" smd rect
			(at -4.59994 84.149946 270)
			(size 1.8034 0.508)
			(layers "B.Cu" "B.Mask" "B.Paste")
			(net "PVPP_DEF")
		)
		(pad "239" smd rect
			(at -4.59994 85.000084 270)
			(size 1.8034 0.508)
			(layers "B.Cu" "B.Mask" "B.Paste")
			(net "GND")
		)
		(pad "240" smd rect
			(at -4.59994 85.849968 270)
			(size 1.8034 0.508)
			(layers "B.Cu" "B.Mask" "B.Paste")
			(net "M_F_DQ<37>")
		)
		(pad "241" smd rect
			(at -4.59994 86.700106 270)
			(size 1.8034 0.508)
			(layers "B.Cu" "B.Mask" "B.Paste")
			(net "GND")
		)
		(pad "242" smd rect
			(at -4.59994 87.54999 270)
			(size 1.8034 0.508)
			(layers "B.Cu" "B.Mask" "B.Paste")
			(net "M_F_DQ<33>")
		)
		(pad "243" smd rect
			(at -4.59994 88.399874 270)
			(size 1.8034 0.508)
			(layers "B.Cu" "B.Mask" "B.Paste")
			(net "GND")
		)
		(pad "244" smd rect
			(at -4.59994 89.250012 270)
			(size 1.8034 0.508)
			(layers "B.Cu" "B.Mask" "B.Paste")
			(net "M_F_DQS_DN<4>")
		)
		(pad "245" smd rect
			(at -4.59994 90.099896 270)
			(size 1.8034 0.508)
			(layers "B.Cu" "B.Mask" "B.Paste")
			(net "M_F_DQS_DP<4>")
		)
		(pad "246" smd rect
			(at -4.59994 90.950034 270)
			(size 1.8034 0.508)
			(layers "B.Cu" "B.Mask" "B.Paste")
			(net "GND")
		)
		(pad "247" smd rect
			(at -4.59994 91.799918 270)
			(size 1.8034 0.508)
			(layers "B.Cu" "B.Mask" "B.Paste")
			(net "M_F_DQ<39>")
		)
		(pad "248" smd rect
			(at -4.59994 92.650056 270)
			(size 1.8034 0.508)
			(layers "B.Cu" "B.Mask" "B.Paste")
			(net "GND")
		)
		(pad "249" smd rect
			(at -4.59994 93.49994 270)
			(size 1.8034 0.508)
			(layers "B.Cu" "B.Mask" "B.Paste")
			(net "M_F_DQ<35>")
		)
		(pad "250" smd rect
			(at -4.59994 94.350078 270)
			(size 1.8034 0.508)
			(layers "B.Cu" "B.Mask" "B.Paste")
			(net "GND")
		)
		(pad "251" smd rect
			(at -4.59994 95.199962 270)
			(size 1.8034 0.508)
			(layers "B.Cu" "B.Mask" "B.Paste")
			(net "M_F_DQ<45>")
		)
		(pad "252" smd rect
			(at -4.59994 96.0501 270)
			(size 1.8034 0.508)
			(layers "B.Cu" "B.Mask" "B.Paste")
			(net "GND")
		)
		(pad "253" smd rect
			(at -4.59994 96.899984 270)
			(size 1.8034 0.508)
			(layers "B.Cu" "B.Mask" "B.Paste")
			(net "M_F_DQ<41>")
		)
		(pad "254" smd rect
			(at -4.59994 97.750122 270)
			(size 1.8034 0.508)
			(layers "B.Cu" "B.Mask" "B.Paste")
			(net "GND")
		)
		(pad "255" smd rect
			(at -4.59994 98.600006 270)
			(size 1.8034 0.508)
			(layers "B.Cu" "B.Mask" "B.Paste")
			(net "M_F_DQS_DN<5>")
		)
		(pad "256" smd rect
			(at -4.59994 99.44989 270)
			(size 1.8034 0.508)
			(layers "B.Cu" "B.Mask" "B.Paste")
			(net "M_F_DQS_DP<5>")
		)
		(pad "257" smd rect
			(at -4.59994 100.300028 270)
			(size 1.8034 0.508)
			(layers "B.Cu" "B.Mask" "B.Paste")
			(net "GND")
		)
		(pad "258" smd rect
			(at -4.59994 101.149912 270)
			(size 1.8034 0.508)
			(layers "B.Cu" "B.Mask" "B.Paste")
			(net "M_F_DQ<47>")
		)
		(pad "259" smd rect
			(at -4.59994 102.00005 270)
			(size 1.8034 0.508)
			(layers "B.Cu" "B.Mask" "B.Paste")
			(net "GND")
		)
		(pad "260" smd rect
			(at -4.59994 102.849934 270)
			(size 1.8034 0.508)
			(layers "B.Cu" "B.Mask" "B.Paste")
			(net "M_F_DQ<43>")
		)
		(pad "261" smd rect
			(at -4.59994 103.700072 270)
			(size 1.8034 0.508)
			(layers "B.Cu" "B.Mask" "B.Paste")
			(net "GND")
		)
		(pad "262" smd rect
			(at -4.59994 104.549956 270)
			(size 1.8034 0.508)
			(layers "B.Cu" "B.Mask" "B.Paste")
			(net "M_F_DQ<53>")
		)
		(pad "263" smd rect
			(at -4.59994 105.400094 270)
			(size 1.8034 0.508)
			(layers "B.Cu" "B.Mask" "B.Paste")
			(net "GND")
		)
		(pad "264" smd rect
			(at -4.59994 106.249978 270)
			(size 1.8034 0.508)
			(layers "B.Cu" "B.Mask" "B.Paste")
			(net "M_F_DQ<49>")
		)
		(pad "265" smd rect
			(at -4.59994 107.100116 270)
			(size 1.8034 0.508)
			(layers "B.Cu" "B.Mask" "B.Paste")
			(net "GND")
		)
		(pad "266" smd rect
			(at -4.59994 107.95 270)
			(size 1.8034 0.508)
			(layers "B.Cu" "B.Mask" "B.Paste")
			(net "M_F_DQS_DN<6>")
		)
		(pad "267" smd rect
			(at -4.59994 108.799884 270)
			(size 1.8034 0.508)
			(layers "B.Cu" "B.Mask" "B.Paste")
			(net "M_F_DQS_DP<6>")
		)
		(pad "268" smd rect
			(at -4.59994 109.650022 270)
			(size 1.8034 0.508)
			(layers "B.Cu" "B.Mask" "B.Paste")
			(net "GND")
		)
		(pad "269" smd rect
			(at -4.59994 110.499906 270)
			(size 1.8034 0.508)
			(layers "B.Cu" "B.Mask" "B.Paste")
			(net "M_F_DQ<55>")
		)
		(pad "270" smd rect
			(at -4.59994 111.350044 270)
			(size 1.8034 0.508)
			(layers "B.Cu" "B.Mask" "B.Paste")
			(net "GND")
		)
		(pad "271" smd rect
			(at -4.59994 112.199928 270)
			(size 1.8034 0.508)
			(layers "B.Cu" "B.Mask" "B.Paste")
			(net "M_F_DQ<51>")
		)
		(pad "272" smd rect
			(at -4.59994 113.050066 270)
			(size 1.8034 0.508)
			(layers "B.Cu" "B.Mask" "B.Paste")
			(net "GND")
		)
		(pad "273" smd rect
			(at -4.59994 113.89995 270)
			(size 1.8034 0.508)
			(layers "B.Cu" "B.Mask" "B.Paste")
			(net "M_F_DQ<61>")
		)
		(pad "274" smd rect
			(at -4.59994 114.750088 270)
			(size 1.8034 0.508)
			(layers "B.Cu" "B.Mask" "B.Paste")
			(net "GND")
		)
		(pad "275" smd rect
			(at -4.59994 115.599972 270)
			(size 1.8034 0.508)
			(layers "B.Cu" "B.Mask" "B.Paste")
			(net "M_F_DQ<57>")
		)
		(pad "276" smd rect
			(at -4.59994 116.45011 270)
			(size 1.8034 0.508)
			(layers "B.Cu" "B.Mask" "B.Paste")
			(net "GND")
		)
		(pad "277" smd rect
			(at -4.59994 117.299994 270)
			(size 1.8034 0.508)
			(layers "B.Cu" "B.Mask" "B.Paste")
			(net "M_F_DQS_DN<7>")
		)
		(pad "278" smd rect
			(at -4.59994 118.149878 270)
			(size 1.8034 0.508)
			(layers "B.Cu" "B.Mask" "B.Paste")
			(net "M_F_DQS_DP<7>")
		)
		(pad "279" smd rect
			(at -4.59994 119.000016 270)
			(size 1.8034 0.508)
			(layers "B.Cu" "B.Mask" "B.Paste")
			(net "GND")
		)
		(pad "280" smd rect
			(at -4.59994 119.8499 270)
			(size 1.8034 0.508)
			(layers "B.Cu" "B.Mask" "B.Paste")
			(net "M_F_DQ<63>")
		)
		(pad "281" smd rect
			(at -4.59994 120.700038 270)
			(size 1.8034 0.508)
			(layers "B.Cu" "B.Mask" "B.Paste")
			(net "GND")
		)
		(pad "282" smd rect
			(at -4.59994 121.549922 270)
			(size 1.8034 0.508)
			(layers "B.Cu" "B.Mask" "B.Paste")
			(net "M_F_DQ<59>")
		)
		(pad "283" smd rect
			(at -4.59994 122.40006 270)
			(size 1.8034 0.508)
			(layers "B.Cu" "B.Mask" "B.Paste")
			(net "GND")
		)
		(pad "284" smd rect
			(at -4.59994 123.249944 270)
			(size 1.8034 0.508)
			(layers "B.Cu" "B.Mask" "B.Paste")
			(net "PVPP_DEF")
		)
		(pad "285" smd rect
			(at -4.59994 124.100082 270)
			(size 1.8034 0.508)
			(layers "B.Cu" "B.Mask" "B.Paste")
			(net "SMB_DDR_DEF_VPP_SDA")
		)
		(pad "286" smd rect
			(at -4.59994 124.949966 270)
			(size 1.8034 0.508)
			(layers "B.Cu" "B.Mask" "B.Paste")
			(net "PVPP_DEF")
		)
		(pad "287" smd rect
			(at -4.59994 125.800104 270)
			(size 1.8034 0.508)
			(layers "B.Cu" "B.Mask" "B.Paste")
			(net "PVPP_DEF")
		)
		(pad "288" smd rect
			(at -4.59994 126.649988 270)
			(size 1.8034 0.508)
			(layers "B.Cu" "B.Mask" "B.Paste")
			(net "PVPP_DEF")
		)
	)
	(footprint ""
		(layer "B.Cu")
		(at 104.5591 -140.208 90)
		(property "Reference" "C5G107"
			(at -1.14681 0.76708 180)
			(unlocked yes)
			(layer "B.SilkS")
			(effects
				(font
					(size 0.7874 0.5842)
					(thickness 0.1524)
				)
				(justify mirror)
			)
		)
		(property "Value" ""
			(at 0 0 90)
			(layer "B.Fab")
			(effects
				(font
					(size 1.27 1.27)
				)
				(justify mirror)
			)
		)
		(duplicate_pad_numbers_are_jumpers no)
		(fp_rect
			(start -0.4953 -0.2032)
			(end 0.4953 1.6002)
			(stroke
				(width 0)
				(type default)
			)
			(fill no)
			(layer "B.CrtYd")
		)
		(fp_line
			(start 0.4953 -0.2032)
			(end -0.4953 -0.2032)
			(stroke
				(width 0.1)
				(type default)
			)
			(layer "B.Fab")
		)
		(fp_line
			(start -0.4953 -0.2032)
			(end -0.4953 1.6002)
			(stroke
				(width 0.1)
				(type default)
			)
			(layer "B.Fab")
		)
		(fp_line
			(start 0.4953 1.6002)
			(end 0.4953 -0.2032)
			(stroke
				(width 0.1)
				(type default)
			)
			(layer "B.Fab")
		)
		(fp_line
			(start -0.4953 1.6002)
			(end 0.4953 1.6002)
			(stroke
				(width 0.1)
				(type default)
			)
			(layer "B.Fab")
		)
		(pad "1" smd rect
			(at 0 0 270)
			(size 0.762 0.889)
			(layers "B.Cu" "B.Mask" "B.Paste")
			(net "PVDDQ_KLM")
		)
		(pad "2" smd rect
			(at 0 1.397 270)
			(size 0.762 0.889)
			(layers "B.Cu" "B.Mask" "B.Paste")
			(net "GND")
		)
		(zone
			(layer "B.Cu")
			(hatch none 0.5)
			(connect_pads
				(clearance 0)
			)
			(min_thickness 0.25)
			(keepout
				(tracks not_allowed)
				(vias allowed)
				(pads allowed)
				(copperpour not_allowed)
				(footprints allowed)
			)
			(placement
				(enabled no)
				(sheetname "")
			)
			(fill
				(thermal_gap 0.5)
				(thermal_bridge_width 0.5)
				(island_removal_mode 0)
			)
			(polygon
				(pts
					(xy 105.0036 -139.827) (xy 105.5116 -139.827) (xy 105.5116 -140.589) (xy 105.0036 -140.589)
				)
			)
		)
	)
	(footprint ""
		(layer "B.Cu")
		(at 466.1535 -4.445 90)
		(property "Reference" "R2U50"
			(at 0 0 90)
			(layer "B.SilkS")
			(hide yes)
			(effects
				(font
					(size 1.27 1.27)
				)
				(justify mirror)
			)
		)
		(property "Value" ""
			(at 0 0 90)
			(layer "B.Fab")
			(effects
				(font
					(size 1.27 1.27)
				)
				(justify mirror)
			)
		)
		(duplicate_pad_numbers_are_jumpers no)
		(fp_poly
			(pts
				(xy 0.2794 -0.1016) (xy -0.2794 -0.1016) (xy -0.2794 0.9906) (xy 0.2794 0.9906)
			)
			(stroke
				(width 0)
				(type default)
			)
			(fill no)
			(layer "B.CrtYd")
		)
		(fp_line
			(start 0.2794 -0.1016)
			(end 0.2794 0.9906)
			(stroke
				(width 0.1)
				(type default)
			)
			(layer "B.Fab")
		)
		(fp_line
			(start -0.2794 -0.1016)
			(end 0.2794 -0.1016)
			(stroke
				(width 0.1)
				(type default)
			)
			(layer "B.Fab")
		)
		(fp_line
			(start 0.2794 0.9906)
			(end -0.2794 0.9906)
			(stroke
				(width 0.1)
				(type default)
			)
			(layer "B.Fab")
		)
		(fp_line
			(start -0.2794 0.9906)
			(end -0.2794 -0.1016)
			(stroke
				(width 0.1)
				(type default)
			)
			(layer "B.Fab")
		)
		(pad "1" smd rect
			(at 0 0 270)
			(size 0.508 0.508)
			(layers "B.Cu" "B.Mask" "B.Paste")
			(net "FM_SLT_CFG2_R")
		)
		(pad "2" smd rect
			(at 0 0.889 270)
			(size 0.508 0.508)
			(layers "B.Cu" "B.Mask" "B.Paste")
			(net "FM_PWRBRK_SLOT_N")
		)
		(zone
			(layer "B.Cu")
			(hatch none 0.5)
			(connect_pads
				(clearance 0)
			)
			(min_thickness 0.25)
			(keepout
				(tracks allowed)
				(vias not_allowed)
				(pads allowed)
				(copperpour not_allowed)
				(footprints allowed)
			)
			(placement
				(enabled no)
				(sheetname "")
			)
			(fill
				(thermal_gap 0.5)
				(thermal_bridge_width 0.5)
				(island_removal_mode 0)
			)
			(polygon
				(pts
					(xy 466.4075 -4.699) (xy 466.4075 -4.191) (xy 466.7885 -4.191) (xy 466.7885 -4.699)
				)
			)
		)
		(zone
			(layer "B.Cu")
			(hatch none 0.5)
			(connect_pads
				(clearance 0)
			)
			(min_thickness 0.25)
			(keepout
				(tracks not_allowed)
				(vias allowed)
				(pads allowed)
				(copperpour not_allowed)
				(footprints allowed)
			)
			(placement
				(enabled no)
				(sheetname "")
			)
			(fill
				(thermal_gap 0.5)
				(thermal_bridge_width 0.5)
				(island_removal_mode 0)
			)
			(polygon
				(pts
					(xy 466.7885 -4.699) (xy 466.7885 -4.191) (xy 466.4075 -4.191) (xy 466.4075 -4.699)
				)
			)
		)
	)
	(footprint ""
		(layer "B.Cu")
		(at 269.394686 -85.06714)
		(property "Reference" "C5P6"
			(at 0 0 0)
			(layer "B.SilkS")
			(hide yes)
			(effects
				(font
					(size 1.27 1.27)
				)
				(justify mirror)
			)
		)
		(property "Value" ""
			(at 0 0 0)
			(layer "B.Fab")
			(effects
				(font
					(size 1.27 1.27)
				)
				(justify mirror)
			)
		)
		(duplicate_pad_numbers_are_jumpers no)
		(fp_poly
			(pts
				(xy 0.7239 -0.2159) (xy -0.7239 -0.2159) (xy -0.7239 1.9939) (xy 0.7239 1.9939)
			)
			(stroke
				(width 0)
				(type default)
			)
			(fill no)
			(layer "B.CrtYd")
		)
		(fp_line
			(start -0.7239 -0.2159)
			(end 0.7239 -0.2159)
			(stroke
				(width 0.1)
				(type default)
			)
			(layer "B.Fab")
		)
		(fp_line
			(start -0.7239 1.9939)
			(end -0.7239 -0.2159)
			(stroke
				(width 0.1)
				(type default)
			)
			(layer "B.Fab")
		)
		(fp_line
			(start 0.7239 -0.2159)
			(end 0.7239 1.9939)
			(stroke
				(width 0.1)
				(type default)
			)
			(layer "B.Fab")
		)
		(fp_line
			(start 0.7239 1.9939)
			(end -0.7239 1.9939)
			(stroke
				(width 0.1)
				(type default)
			)
			(layer "B.Fab")
		)
		(pad "1" smd rect
			(at 0 0 180)
			(size 1.27 1.016)
			(layers "B.Cu" "B.Mask" "B.Paste")
			(net "PVDDQ_DEF")
		)
		(pad "2" smd rect
			(at 0 1.778 180)
			(size 1.27 1.016)
			(layers "B.Cu" "B.Mask" "B.Paste")
			(net "GND")
		)
		(zone
			(layer "B.Cu")
			(hatch none 0.5)
			(connect_pads
				(clearance 0)
			)
			(min_thickness 0.25)
			(keepout
				(tracks not_allowed)
				(vias allowed)
				(pads allowed)
				(copperpour not_allowed)
				(footprints allowed)
			)
			(placement
				(enabled no)
				(sheetname "")
			)
			(fill
				(thermal_gap 0.5)
				(thermal_bridge_width 0.5)
				(island_removal_mode 0)
			)
			(polygon
				(pts
					(xy 270.029686 -84.55914) (xy 268.759686 -84.55914) (xy 268.759686 -83.79714) (xy 270.029686 -83.79714)
				)
			)
		)
	)
	(footprint ""
		(layer "B.Cu")
		(at 16.256 -81.153 90)
		(property "Reference" "R9P15"
			(at 0 0 90)
			(layer "B.SilkS")
			(hide yes)
			(effects
				(font
					(size 1.27 1.27)
				)
				(justify mirror)
			)
		)
		(property "Value" ""
			(at 0 0 90)
			(layer "B.Fab")
			(effects
				(font
					(size 1.27 1.27)
				)
				(justify mirror)
			)
		)
		(duplicate_pad_numbers_are_jumpers no)
		(fp_poly
			(pts
				(xy 0.2794 -0.1016) (xy -0.2794 -0.1016) (xy -0.2794 0.9906) (xy 0.2794 0.9906)
			)
			(stroke
				(width 0)
				(type default)
			)
			(fill no)
			(layer "B.CrtYd")
		)
		(fp_line
			(start 0.2794 -0.1016)
			(end 0.2794 0.9906)
			(stroke
				(width 0.1)
				(type default)
			)
			(layer "B.Fab")
		)
		(fp_line
			(start -0.2794 -0.1016)
			(end 0.2794 -0.1016)
			(stroke
				(width 0.1)
				(type default)
			)
			(layer "B.Fab")
		)
		(fp_line
			(start 0.2794 0.9906)
			(end -0.2794 0.9906)
			(stroke
				(width 0.1)
				(type default)
			)
			(layer "B.Fab")
		)
		(fp_line
			(start -0.2794 0.9906)
			(end -0.2794 -0.1016)
			(stroke
				(width 0.1)
				(type default)
			)
			(layer "B.Fab")
		)
		(pad "1" smd rect
			(at 0 0 270)
			(size 0.508 0.508)
			(layers "B.Cu" "B.Mask" "B.Paste")
			(net "A_HSC_LOW_DRAIN")
		)
		(pad "2" smd rect
			(at 0 0.889 270)
			(size 0.508 0.508)
			(layers "B.Cu" "B.Mask" "B.Paste")
			(net "IRQ_OC_DETECT_N")
		)
		(zone
			(layer "B.Cu")
			(hatch none 0.5)
			(connect_pads
				(clearance 0)
			)
			(min_thickness 0.25)
			(keepout
				(tracks allowed)
				(vias not_allowed)
				(pads allowed)
				(copperpour not_allowed)
				(footprints allowed)
			)
			(placement
				(enabled no)
				(sheetname "")
			)
			(fill
				(thermal_gap 0.5)
				(thermal_bridge_width 0.5)
				(island_removal_mode 0)
			)
			(polygon
				(pts
					(xy 16.51 -81.407) (xy 16.51 -80.899) (xy 16.891 -80.899) (xy 16.891 -81.407)
				)
			)
		)
		(zone
			(layer "B.Cu")
			(hatch none 0.5)
			(connect_pads
				(clearance 0)
			)
			(min_thickness 0.25)
			(keepout
				(tracks not_allowed)
				(vias allowed)
				(pads allowed)
				(copperpour not_allowed)
				(footprints allowed)
			)
			(placement
				(enabled no)
				(sheetname "")
			)
			(fill
				(thermal_gap 0.5)
				(thermal_bridge_width 0.5)
				(island_removal_mode 0)
			)
			(polygon
				(pts
					(xy 16.891 -81.407) (xy 16.891 -80.899) (xy 16.51 -80.899) (xy 16.51 -81.407)
				)
			)
		)
	)
	(footprint ""
		(layer "B.Cu")
		(at 375.0945 -44.9072 90)
		(property "Reference" "C2T32"
			(at 0 0 90)
			(layer "B.SilkS")
			(hide yes)
			(effects
				(font
					(size 1.27 1.27)
				)
				(justify mirror)
			)
		)
		(property "Value" ""
			(at 0 0 90)
			(layer "B.Fab")
			(effects
				(font
					(size 1.27 1.27)
				)
				(justify mirror)
			)
		)
		(duplicate_pad_numbers_are_jumpers no)
		(fp_poly
			(pts
				(xy -0.3048 -0.1016) (xy -0.3048 0.9906) (xy 0.3048 0.9906) (xy 0.3048 -0.1016)
			)
			(stroke
				(width 0)
				(type default)
			)
			(fill no)
			(layer "B.CrtYd")
		)
		(fp_line
			(start 0.3048 -0.1016)
			(end 0.3048 0.9906)
			(stroke
				(width 0.1)
				(type default)
			)
			(layer "B.Fab")
		)
		(fp_line
			(start -0.3048 -0.1016)
			(end 0.3048 -0.1016)
			(stroke
				(width 0.1)
				(type default)
			)
			(layer "B.Fab")
		)
		(fp_line
			(start 0.3048 0.9906)
			(end -0.3048 0.9906)
			(stroke
				(width 0.1)
				(type default)
			)
			(layer "B.Fab")
		)
		(fp_line
			(start -0.3048 0.9906)
			(end -0.3048 -0.1016)
			(stroke
				(width 0.1)
				(type default)
			)
			(layer "B.Fab")
		)
		(pad "1" smd rect
			(at 0 0 270)
			(size 0.508 0.508)
			(layers "B.Cu" "B.Mask" "B.Paste")
			(net "P0V7_GTL2104_5_VREF")
		)
		(pad "2" smd rect
			(at 0 0.889 270)
			(size 0.508 0.508)
			(layers "B.Cu" "B.Mask" "B.Paste")
			(net "GND")
		)
		(zone
			(layer "B.Cu")
			(hatch none 0.5)
			(connect_pads
				(clearance 0)
			)
			(min_thickness 0.25)
			(keepout
				(tracks allowed)
				(vias not_allowed)
				(pads allowed)
				(copperpour not_allowed)
				(footprints allowed)
			)
			(placement
				(enabled no)
				(sheetname "")
			)
			(fill
				(thermal_gap 0.5)
				(thermal_bridge_width 0.5)
				(island_removal_mode 0)
			)
			(polygon
				(pts
					(xy 375.3485 -45.1612) (xy 375.3485 -44.6532) (xy 375.7295 -44.6532) (xy 375.7295 -45.1612)
				)
			)
		)
		(zone
			(layer "B.Cu")
			(hatch none 0.5)
			(connect_pads
				(clearance 0)
			)
			(min_thickness 0.25)
			(keepout
				(tracks not_allowed)
				(vias allowed)
				(pads allowed)
				(copperpour not_allowed)
				(footprints allowed)
			)
			(placement
				(enabled no)
				(sheetname "")
			)
			(fill
				(thermal_gap 0.5)
				(thermal_bridge_width 0.5)
				(island_removal_mode 0)
			)
			(polygon
				(pts
					(xy 375.7295 -45.1612) (xy 375.7295 -44.6532) (xy 375.3485 -44.6532) (xy 375.3485 -45.1612)
				)
			)
		)
	)
	(footprint ""
		(layer "B.Cu")
		(at 418.846 -23.495 90)
		(property "Reference" "L25W2"
			(at 0 0 90)
			(layer "B.SilkS")
			(hide yes)
			(effects
				(font
					(size 1.27 1.27)
				)
				(justify mirror)
			)
		)
		(property "Value" "*"
			(at -0.0254 -2.8829 90)
			(unlocked yes)
			(layer "B.Fab")
			(hide yes)
			(effects
				(font
					(size 1.27 1.016)
					(thickness 0.1524)
				)
				(justify mirror)
			)
		)
		(property "Device Type" "IND-68NH-15-GP_DISCRET-GC1-INDA"
			(at -0.0254 -4.4069 90)
			(unlocked yes)
			(layer "B.Fab")
			(hide yes)
			(effects
				(font
					(size 1.27 1.016)
					(thickness 0.1524)
				)
				(justify mirror)
			)
		)
		(duplicate_pad_numbers_are_jumpers no)
		(fp_line
			(start -0.254 0)
			(end 0.254 0)
			(stroke
				(width 0.2032)
				(type default)
			)
			(layer "B.SilkS")
		)
		(fp_rect
			(start 0.5842 1.3335)
			(end -0.5842 -1.3335)
			(stroke
				(width 0)
				(type default)
			)
			(fill no)
			(layer "B.CrtYd")
		)
		(fp_rect
			(start 0.5842 1.3335)
			(end -0.5842 -1.3335)
			(stroke
				(width 0)
				(type default)
			)
			(fill no)
			(layer "B.Fab")
		)
		(pad "1" smd custom
			(at 0 -0.762 270)
			(size 0.2159 0.2159)
			(layers "B.Cu" "B.Mask" "B.Paste")
			(net "BMC_VGA_GREEN")
			(options
				(clearance outline)
				(anchor circle)
			)
			(primitives
				(gr_poly
					(pts
						(arc
							(start -0.3302 0.4318)
							(mid -0.402042 0.402042)
							(end -0.4318 0.3302)
						)
						(arc
							(start -0.4318 -0.3302)
							(mid -0.402042 -0.402042)
							(end -0.3302 -0.4318)
						)
						(arc
							(start 0.3302 -0.4318)
							(mid 0.402042 -0.402042)
							(end 0.4318 -0.3302)
						)
						(arc
							(start 0.4318 0.3302)
							(mid 0.402042 0.402042)
							(end 0.3302 0.4318)
						)
					)
					(width 0)
					(fill yes)
				)
			)
		)
		(pad "2" smd custom
			(at 0 0.762 270)
			(size 0.2159 0.2159)
			(layers "B.Cu" "B.Mask" "B.Paste")
			(net "V_IO_G_J")
			(options
				(clearance outline)
				(anchor circle)
			)
			(primitives
				(gr_poly
					(pts
						(arc
							(start -0.3302 0.4318)
							(mid -0.402042 0.402042)
							(end -0.4318 0.3302)
						)
						(arc
							(start -0.4318 -0.3302)
							(mid -0.402042 -0.402042)
							(end -0.3302 -0.4318)
						)
						(arc
							(start 0.3302 -0.4318)
							(mid 0.402042 -0.402042)
							(end 0.4318 -0.3302)
						)
						(arc
							(start 0.4318 0.3302)
							(mid 0.402042 0.402042)
							(end 0.3302 0.4318)
						)
					)
					(width 0)
					(fill yes)
				)
			)
		)
	)
	(footprint ""
		(layer "B.Cu")
		(at 32.832802 -74.553064 90)
		(property "Reference" "C9P4"
			(at 0 0 90)
			(layer "B.SilkS")
			(hide yes)
			(effects
				(font
					(size 1.27 1.27)
				)
				(justify mirror)
			)
		)
		(property "Value" ""
			(at 0 0 90)
			(layer "B.Fab")
			(effects
				(font
					(size 1.27 1.27)
				)
				(justify mirror)
			)
		)
		(duplicate_pad_numbers_are_jumpers no)
		(fp_poly
			(pts
				(xy 0.7239 -0.2159) (xy -0.7239 -0.2159) (xy -0.7239 1.9939) (xy 0.7239 1.9939)
			)
			(stroke
				(width 0)
				(type default)
			)
			(fill no)
			(layer "B.CrtYd")
		)
		(fp_line
			(start 0.7239 -0.2159)
			(end 0.7239 1.9939)
			(stroke
				(width 0.1)
				(type default)
			)
			(layer "B.Fab")
		)
		(fp_line
			(start -0.7239 -0.2159)
			(end 0.7239 -0.2159)
			(stroke
				(width 0.1)
				(type default)
			)
			(layer "B.Fab")
		)
		(fp_line
			(start 0.7239 1.9939)
			(end -0.7239 1.9939)
			(stroke
				(width 0.1)
				(type default)
			)
			(layer "B.Fab")
		)
		(fp_line
			(start -0.7239 1.9939)
			(end -0.7239 -0.2159)
			(stroke
				(width 0.1)
				(type default)
			)
			(layer "B.Fab")
		)
		(pad "1" smd rect
			(at 0 0 270)
			(size 1.27 1.016)
			(layers "B.Cu" "B.Mask" "B.Paste")
			(net "VR_FET_SW_P12V_STBY_PVCCIN_CPU1")
		)
		(pad "2" smd rect
			(at 0 1.778 270)
			(size 1.27 1.016)
			(layers "B.Cu" "B.Mask" "B.Paste")
			(net "GND")
		)
		(zone
			(layer "B.Cu")
			(hatch none 0.5)
			(connect_pads
				(clearance 0)
			)
			(min_thickness 0.25)
			(keepout
				(tracks not_allowed)
				(vias allowed)
				(pads allowed)
				(copperpour not_allowed)
				(footprints allowed)
			)
			(placement
				(enabled no)
				(sheetname "")
			)
			(fill
				(thermal_gap 0.5)
				(thermal_bridge_width 0.5)
				(island_removal_mode 0)
			)
			(polygon
				(pts
					(xy 33.340802 -75.188064) (xy 33.340802 -73.918064) (xy 34.102802 -73.918064) (xy 34.102802 -75.188064)
				)
			)
		)
	)
	(footprint ""
		(layer "B.Cu")
		(at 198.760588 -85.687662 90)
		(property "Reference" "C4C14"
			(at 0 0 90)
			(layer "B.SilkS")
			(hide yes)
			(effects
				(font
					(size 1.27 1.27)
				)
				(justify mirror)
			)
		)
		(property "Value" "*"
			(at -1.1811 -2.8194 90)
			(unlocked yes)
			(layer "B.Fab")
			(hide yes)
			(effects
				(font
					(size 1.27 1.016)
					(thickness 0.1524)
				)
				(justify mirror)
			)
		)
		(property "Device Type" "SC1U10V2KX-4-GP_SMD-BCG6-SC1U1A"
			(at -1.1811 -4.3434 90)
			(unlocked yes)
			(layer "B.Fab")
			(hide yes)
			(effects
				(font
					(size 1.27 1.016)
					(thickness 0.1524)
				)
				(justify mirror)
			)
		)
		(duplicate_pad_numbers_are_jumpers no)
		(fp_rect
			(start 0.4318 0.9525)
			(end -0.4318 -0.9525)
			(stroke
				(width 0)
				(type default)
			)
			(fill no)
			(layer "B.CrtYd")
		)
		(fp_rect
			(start 0.4318 0.9525)
			(end -0.4318 -0.9525)
			(stroke
				(width 0)
				(type default)
			)
			(fill no)
			(layer "B.Fab")
		)
		(pad "1" smd custom
			(at 0 -0.4445 270)
			(size 0.1524 0.1524)
			(layers "B.Cu" "B.Mask" "B.Paste")
			(net "P5V_STBY")
			(options
				(clearance outline)
				(anchor circle)
			)
			(primitives
				(gr_poly
					(pts
						(arc
							(start 0.3048 0.2032)
							(mid 0.275042 0.275042)
							(end 0.2032 0.3048)
						)
						(arc
							(start -0.2032 0.3048)
							(mid -0.275042 0.275042)
							(end -0.3048 0.2032)
						)
						(arc
							(start -0.3048 -0.2032)
							(mid -0.275042 -0.275042)
							(end -0.2032 -0.3048)
						)
						(arc
							(start 0.2032 -0.3048)
							(mid 0.275042 -0.275042)
							(end 0.3048 -0.2032)
						)
					)
					(width 0)
					(fill yes)
				)
			)
		)
		(pad "2" smd custom
			(at 0 0.4445 270)
			(size 0.1524 0.1524)
			(layers "B.Cu" "B.Mask" "B.Paste")
			(net "GND")
			(options
				(clearance outline)
				(anchor circle)
			)
			(primitives
				(gr_poly
					(pts
						(arc
							(start 0.3048 0.2032)
							(mid 0.275042 0.275042)
							(end 0.2032 0.3048)
						)
						(arc
							(start -0.2032 0.3048)
							(mid -0.275042 0.275042)
							(end -0.3048 0.2032)
						)
						(arc
							(start -0.3048 -0.2032)
							(mid -0.275042 -0.275042)
							(end -0.2032 -0.3048)
						)
						(arc
							(start 0.2032 -0.3048)
							(mid 0.275042 -0.275042)
							(end 0.3048 -0.2032)
						)
					)
					(width 0)
					(fill yes)
				)
			)
		)
	)
	(footprint ""
		(layer "B.Cu")
		(at 415.9885 -4.318 -90)
		(property "Reference" "R2P21"
			(at 0 0 90)
			(layer "B.SilkS")
			(hide yes)
			(effects
				(font
					(size 1.27 1.27)
				)
				(justify mirror)
			)
		)
		(property "Value" ""
			(at 0 0 90)
			(layer "B.Fab")
			(effects
				(font
					(size 1.27 1.27)
				)
				(justify mirror)
			)
		)
		(duplicate_pad_numbers_are_jumpers no)
		(fp_poly
			(pts
				(xy 0.2794 -0.1016) (xy -0.2794 -0.1016) (xy -0.2794 0.9906) (xy 0.2794 0.9906)
			)
			(stroke
				(width 0)
				(type default)
			)
			(fill no)
			(layer "B.CrtYd")
		)
		(fp_line
			(start -0.2794 0.9906)
			(end -0.2794 -0.1016)
			(stroke
				(width 0.1)
				(type default)
			)
			(layer "B.Fab")
		)
		(fp_line
			(start 0.2794 0.9906)
			(end -0.2794 0.9906)
			(stroke
				(width 0.1)
				(type default)
			)
			(layer "B.Fab")
		)
		(fp_line
			(start -0.2794 -0.1016)
			(end 0.2794 -0.1016)
			(stroke
				(width 0.1)
				(type default)
			)
			(layer "B.Fab")
		)
		(fp_line
			(start 0.2794 -0.1016)
			(end 0.2794 0.9906)
			(stroke
				(width 0.1)
				(type default)
			)
			(layer "B.Fab")
		)
		(pad "1" smd rect
			(at 0 0 90)
			(size 0.508 0.508)
			(layers "B.Cu" "B.Mask" "B.Paste")
			(net "P3V3_STBY")
		)
		(pad "2" smd rect
			(at 0 0.889 90)
			(size 0.508 0.508)
			(layers "B.Cu" "B.Mask" "B.Paste")
			(net "PWRGD_P5V_R")
		)
		(zone
			(layer "B.Cu")
			(hatch none 0.5)
			(connect_pads
				(clearance 0)
			)
			(min_thickness 0.25)
			(keepout
				(tracks not_allowed)
				(vias allowed)
				(pads allowed)
				(copperpour not_allowed)
				(footprints allowed)
			)
			(placement
				(enabled no)
				(sheetname "")
			)
			(fill
				(thermal_gap 0.5)
				(thermal_bridge_width 0.5)
				(island_removal_mode 0)
			)
			(polygon
				(pts
					(xy 415.3535 -4.064) (xy 415.3535 -4.572) (xy 415.7345 -4.572) (xy 415.7345 -4.064)
				)
			)
		)
		(zone
			(layer "B.Cu")
			(hatch none 0.5)
			(connect_pads
				(clearance 0)
			)
			(min_thickness 0.25)
			(keepout
				(tracks allowed)
				(vias not_allowed)
				(pads allowed)
				(copperpour not_allowed)
				(footprints allowed)
			)
			(placement
				(enabled no)
				(sheetname "")
			)
			(fill
				(thermal_gap 0.5)
				(thermal_bridge_width 0.5)
				(island_removal_mode 0)
			)
			(polygon
				(pts
					(xy 415.7345 -4.064) (xy 415.7345 -4.572) (xy 415.3535 -4.572) (xy 415.3535 -4.064)
				)
			)
		)
	)
	(footprint ""
		(layer "B.Cu")
		(at 373.884952 -43.224958)
		(property "Reference" "R2T26"
			(at 0 0 0)
			(layer "B.SilkS")
			(hide yes)
			(effects
				(font
					(size 1.27 1.27)
				)
				(justify mirror)
			)
		)
		(property "Value" ""
			(at 0 0 0)
			(layer "B.Fab")
			(effects
				(font
					(size 1.27 1.27)
				)
				(justify mirror)
			)
		)
		(duplicate_pad_numbers_are_jumpers no)
		(fp_poly
			(pts
				(xy 0.2794 -0.1016) (xy -0.2794 -0.1016) (xy -0.2794 0.9906) (xy 0.2794 0.9906)
			)
			(stroke
				(width 0)
				(type default)
			)
			(fill no)
			(layer "B.CrtYd")
		)
		(fp_line
			(start -0.2794 -0.1016)
			(end 0.2794 -0.1016)
			(stroke
				(width 0.1)
				(type default)
			)
			(layer "B.Fab")
		)
		(fp_line
			(start -0.2794 0.9906)
			(end -0.2794 -0.1016)
			(stroke
				(width 0.1)
				(type default)
			)
			(layer "B.Fab")
		)
		(fp_line
			(start 0.2794 -0.1016)
			(end 0.2794 0.9906)
			(stroke
				(width 0.1)
				(type default)
			)
			(layer "B.Fab")
		)
		(fp_line
			(start 0.2794 0.9906)
			(end -0.2794 0.9906)
			(stroke
				(width 0.1)
				(type default)
			)
			(layer "B.Fab")
		)
		(pad "1" smd rect
			(at 0 0 180)
			(size 0.508 0.508)
			(layers "B.Cu" "B.Mask" "B.Paste")
			(net "PVCCIO_CPU0")
		)
		(pad "2" smd rect
			(at 0 0.889 180)
			(size 0.508 0.508)
			(layers "B.Cu" "B.Mask" "B.Paste")
			(net "H_CPU_ERR1_GTL_R_N")
		)
		(zone
			(layer "B.Cu")
			(hatch none 0.5)
			(connect_pads
				(clearance 0)
			)
			(min_thickness 0.25)
			(keepout
				(tracks allowed)
				(vias not_allowed)
				(pads allowed)
				(copperpour not_allowed)
				(footprints allowed)
			)
			(placement
				(enabled no)
				(sheetname "")
			)
			(fill
				(thermal_gap 0.5)
				(thermal_bridge_width 0.5)
				(island_removal_mode 0)
			)
			(polygon
				(pts
					(xy 374.138952 -42.970958) (xy 373.630952 -42.970958) (xy 373.630952 -42.589958) (xy 374.138952 -42.589958)
				)
			)
		)
		(zone
			(layer "B.Cu")
			(hatch none 0.5)
			(connect_pads
				(clearance 0)
			)
			(min_thickness 0.25)
			(keepout
				(tracks not_allowed)
				(vias allowed)
				(pads allowed)
				(copperpour not_allowed)
				(footprints allowed)
			)
			(placement
				(enabled no)
				(sheetname "")
			)
			(fill
				(thermal_gap 0.5)
				(thermal_bridge_width 0.5)
				(island_removal_mode 0)
			)
			(polygon
				(pts
					(xy 374.138952 -42.589958) (xy 373.630952 -42.589958) (xy 373.630952 -42.970958) (xy 374.138952 -42.970958)
				)
			)
		)
	)
	(footprint ""
		(layer "B.Cu")
		(at 338.7344 -18.16354 -90)
		(property "Reference" "R3T11"
			(at 0 0 90)
			(layer "B.SilkS")
			(hide yes)
			(effects
				(font
					(size 1.27 1.27)
				)
				(justify mirror)
			)
		)
		(property "Value" ""
			(at 0 0 90)
			(layer "B.Fab")
			(effects
				(font
					(size 1.27 1.27)
				)
				(justify mirror)
			)
		)
		(duplicate_pad_numbers_are_jumpers no)
		(fp_rect
			(start 0.2794 0.9906)
			(end -0.2794 -0.1016)
			(stroke
				(width 0)
				(type default)
			)
			(fill no)
			(layer "B.CrtYd")
		)
		(fp_line
			(start -0.2794 0.9906)
			(end -0.2794 -0.1016)
			(stroke
				(width 0.1)
				(type default)
			)
			(layer "B.Fab")
		)
		(fp_line
			(start 0.2794 0.9906)
			(end -0.2794 0.9906)
			(stroke
				(width 0.1)
				(type default)
			)
			(layer "B.Fab")
		)
		(fp_line
			(start -0.2794 -0.1016)
			(end 0.2794 -0.1016)
			(stroke
				(width 0.1)
				(type default)
			)
			(layer "B.Fab")
		)
		(fp_line
			(start 0.2794 -0.1016)
			(end 0.2794 0.9906)
			(stroke
				(width 0.1)
				(type default)
			)
			(layer "B.Fab")
		)
		(pad "1" smd rect
			(at 0 0 90)
			(size 0.508 0.508)
			(layers "B.Cu" "B.Mask" "B.Paste")
			(net "PVCCIO_CPU0")
		)
		(pad "2" smd rect
			(at 0 0.889 90)
			(size 0.508 0.508)
			(layers "B.Cu" "B.Mask" "B.Paste")
			(net "SVID_CLK1_CPU0_R")
		)
		(zone
			(layer "B.Cu")
			(hatch none 0.5)
			(connect_pads
				(clearance 0)
			)
			(min_thickness 0.25)
			(keepout
				(tracks allowed)
				(vias not_allowed)
				(pads allowed)
				(copperpour not_allowed)
				(footprints allowed)
			)
			(placement
				(enabled no)
				(sheetname "")
			)
			(fill
				(thermal_gap 0.5)
				(thermal_bridge_width 0.5)
				(island_removal_mode 0)
			)
			(polygon
				(pts
					(xy 338.0994 -17.90954) (xy 338.4804 -17.90954) (xy 338.4804 -18.41754) (xy 338.0994 -18.41754)
				)
			)
		)
		(zone
			(layer "B.Cu")
			(hatch none 0.5)
			(connect_pads
				(clearance 0)
			)
			(min_thickness 0.25)
			(keepout
				(tracks not_allowed)
				(vias allowed)
				(pads allowed)
				(copperpour not_allowed)
				(footprints allowed)
			)
			(placement
				(enabled no)
				(sheetname "")
			)
			(fill
				(thermal_gap 0.5)
				(thermal_bridge_width 0.5)
				(island_removal_mode 0)
			)
			(polygon
				(pts
					(xy 338.0994 -17.90954) (xy 338.4804 -17.90954) (xy 338.4804 -18.41754) (xy 338.0994 -18.41754)
				)
			)
		)
	)
	(footprint ""
		(layer "B.Cu")
		(at 489.189014 -140.589 90)
		(property "Reference" "Q1L4"
			(at -2.86131 2.27838 0)
			(unlocked yes)
			(layer "B.SilkS")
			(effects
				(font
					(size 0.7874 0.5842)
					(thickness 0.1524)
				)
				(justify left mirror)
			)
		)
		(property "Value" ""
			(at 0 0 90)
			(layer "B.Fab")
			(effects
				(font
					(size 1.27 1.27)
				)
				(justify mirror)
			)
		)
		(duplicate_pad_numbers_are_jumpers no)
		(fp_circle
			(center 0.848614 -0.6477)
			(end 0.848614 -0.5207)
			(stroke
				(width 0.254)
				(type default)
			)
			(fill no)
			(layer "B.SilkS")
		)
		(fp_poly
			(pts
				(xy -0.21463 -0.450088) (xy -1.56337 -0.450088) (xy -1.56337 1.75006) (xy -0.21463 1.75006)
			)
			(stroke
				(width 0)
				(type default)
			)
			(fill no)
			(layer "B.CrtYd")
		)
		(fp_line
			(start -0.21463 -0.450088)
			(end -1.56337 -0.450088)
			(stroke
				(width 0.1)
				(type default)
			)
			(layer "B.Fab")
		)
		(fp_line
			(start -1.56337 -0.450088)
			(end -1.56337 1.75006)
			(stroke
				(width 0.1)
				(type default)
			)
			(layer "B.Fab")
		)
		(fp_line
			(start -0.21463 1.75006)
			(end -0.21463 -0.450088)
			(stroke
				(width 0.1)
				(type default)
			)
			(layer "B.Fab")
		)
		(fp_line
			(start -1.56337 1.75006)
			(end -0.21463 1.75006)
			(stroke
				(width 0.1)
				(type default)
			)
			(layer "B.Fab")
		)
		(fp_circle
			(center 0.848614 -0.6477)
			(end 0.848614 -0.5207)
			(stroke
				(width 0.254)
				(type default)
			)
			(fill no)
			(layer "B.Fab")
		)
		(pad "1" smd rect
			(at 0 0 270)
			(size 1.016 0.381)
			(layers "B.Cu" "B.Mask" "B.Paste")
			(net "GND")
		)
		(pad "2" smd rect
			(at 0 0.649986 270)
			(size 1.016 0.381)
			(layers "B.Cu" "B.Mask" "B.Paste")
			(net "FM_DB_PRESENT")
		)
		(pad "3" smd rect
			(at 0 1.299972 270)
			(size 1.016 0.381)
			(layers "B.Cu" "B.Mask" "B.Paste")
			(net "TP_FET_Q56_3")
		)
		(pad "4" smd rect
			(at -1.778 1.299972 270)
			(size 1.016 0.381)
			(layers "B.Cu" "B.Mask" "B.Paste")
			(net "TP_FET_Q56_4")
		)
		(pad "5" smd rect
			(at -1.778 0.649986 270)
			(size 1.016 0.381)
			(layers "B.Cu" "B.Mask" "B.Paste")
			(net "TP_FET_Q56_4")
		)
		(pad "6" smd rect
			(at -1.778 0 270)
			(size 1.016 0.381)
			(layers "B.Cu" "B.Mask" "B.Paste")
			(net "FM_POST_CARD_PRES_BMC_N")
		)
	)
	(footprint ""
		(layer "B.Cu")
		(at 477.634554 -2.513838 90)
		(property "Reference" "R9G11"
			(at 0 0 90)
			(layer "B.SilkS")
			(hide yes)
			(effects
				(font
					(size 1.27 1.27)
				)
				(justify mirror)
			)
		)
		(property "Value" ""
			(at 0 0 90)
			(layer "B.Fab")
			(effects
				(font
					(size 1.27 1.27)
				)
				(justify mirror)
			)
		)
		(duplicate_pad_numbers_are_jumpers no)
		(fp_poly
			(pts
				(xy 0.2794 -0.1016) (xy -0.2794 -0.1016) (xy -0.2794 0.9906) (xy 0.2794 0.9906)
			)
			(stroke
				(width 0)
				(type default)
			)
			(fill no)
			(layer "B.CrtYd")
		)
		(fp_line
			(start 0.2794 -0.1016)
			(end 0.2794 0.9906)
			(stroke
				(width 0.1)
				(type default)
			)
			(layer "B.Fab")
		)
		(fp_line
			(start -0.2794 -0.1016)
			(end 0.2794 -0.1016)
			(stroke
				(width 0.1)
				(type default)
			)
			(layer "B.Fab")
		)
		(fp_line
			(start 0.2794 0.9906)
			(end -0.2794 0.9906)
			(stroke
				(width 0.1)
				(type default)
			)
			(layer "B.Fab")
		)
		(fp_line
			(start -0.2794 0.9906)
			(end -0.2794 -0.1016)
			(stroke
				(width 0.1)
				(type default)
			)
			(layer "B.Fab")
		)
		(pad "1" smd rect
			(at 0 0 270)
			(size 0.508 0.508)
			(layers "B.Cu" "B.Mask" "B.Paste")
			(net "NIC_SER_N_MDI_3_DN")
		)
		(pad "2" smd rect
			(at 0 0.889 270)
			(size 0.508 0.508)
			(layers "B.Cu" "B.Mask" "B.Paste")
			(net "NIC_MDI_SPRV_RJ45_3_R_DN")
		)
		(zone
			(layer "B.Cu")
			(hatch none 0.5)
			(connect_pads
				(clearance 0)
			)
			(min_thickness 0.25)
			(keepout
				(tracks allowed)
				(vias not_allowed)
				(pads allowed)
				(copperpour not_allowed)
				(footprints allowed)
			)
			(placement
				(enabled no)
				(sheetname "")
			)
			(fill
				(thermal_gap 0.5)
				(thermal_bridge_width 0.5)
				(island_removal_mode 0)
			)
			(polygon
				(pts
					(xy 477.888554 -2.767838) (xy 477.888554 -2.259838) (xy 478.269554 -2.259838) (xy 478.269554 -2.767838)
				)
			)
		)
		(zone
			(layer "B.Cu")
			(hatch none 0.5)
			(connect_pads
				(clearance 0)
			)
			(min_thickness 0.25)
			(keepout
				(tracks not_allowed)
				(vias allowed)
				(pads allowed)
				(copperpour not_allowed)
				(footprints allowed)
			)
			(placement
				(enabled no)
				(sheetname "")
			)
			(fill
				(thermal_gap 0.5)
				(thermal_bridge_width 0.5)
				(island_removal_mode 0)
			)
			(polygon
				(pts
					(xy 478.269554 -2.767838) (xy 478.269554 -2.259838) (xy 477.888554 -2.259838) (xy 477.888554 -2.767838)
				)
			)
		)
	)
	(footprint ""
		(layer "B.Cu")
		(at 402.463 -152.527 -90)
		(property "Reference" "R2L26"
			(at 0 0 90)
			(layer "B.SilkS")
			(hide yes)
			(effects
				(font
					(size 1.27 1.27)
				)
				(justify mirror)
			)
		)
		(property "Value" ""
			(at 0 0 90)
			(layer "B.Fab")
			(effects
				(font
					(size 1.27 1.27)
				)
				(justify mirror)
			)
		)
		(duplicate_pad_numbers_are_jumpers no)
		(fp_poly
			(pts
				(xy 0.2794 -0.1016) (xy -0.2794 -0.1016) (xy -0.2794 0.9906) (xy 0.2794 0.9906)
			)
			(stroke
				(width 0)
				(type default)
			)
			(fill no)
			(layer "B.CrtYd")
		)
		(fp_line
			(start -0.2794 0.9906)
			(end -0.2794 -0.1016)
			(stroke
				(width 0.1)
				(type default)
			)
			(layer "B.Fab")
		)
		(fp_line
			(start 0.2794 0.9906)
			(end -0.2794 0.9906)
			(stroke
				(width 0.1)
				(type default)
			)
			(layer "B.Fab")
		)
		(fp_line
			(start -0.2794 -0.1016)
			(end 0.2794 -0.1016)
			(stroke
				(width 0.1)
				(type default)
			)
			(layer "B.Fab")
		)
		(fp_line
			(start 0.2794 -0.1016)
			(end 0.2794 0.9906)
			(stroke
				(width 0.1)
				(type default)
			)
			(layer "B.Fab")
		)
		(pad "1" smd rect
			(at 0 0 90)
			(size 0.508 0.508)
			(layers "B.Cu" "B.Mask" "B.Paste")
			(net "P3V3_STBY")
		)
		(pad "2" smd rect
			(at 0 0.889 90)
			(size 0.508 0.508)
			(layers "B.Cu" "B.Mask" "B.Paste")
			(net "VID_PCH_CORE_PVNN_AUX_VID_0")
		)
		(zone
			(layer "B.Cu")
			(hatch none 0.5)
			(connect_pads
				(clearance 0)
			)
			(min_thickness 0.25)
			(keepout
				(tracks not_allowed)
				(vias allowed)
				(pads allowed)
				(copperpour not_allowed)
				(footprints allowed)
			)
			(placement
				(enabled no)
				(sheetname "")
			)
			(fill
				(thermal_gap 0.5)
				(thermal_bridge_width 0.5)
				(island_removal_mode 0)
			)
			(polygon
				(pts
					(xy 401.828 -152.273) (xy 401.828 -152.781) (xy 402.209 -152.781) (xy 402.209 -152.273)
				)
			)
		)
		(zone
			(layer "B.Cu")
			(hatch none 0.5)
			(connect_pads
				(clearance 0)
			)
			(min_thickness 0.25)
			(keepout
				(tracks allowed)
				(vias not_allowed)
				(pads allowed)
				(copperpour not_allowed)
				(footprints allowed)
			)
			(placement
				(enabled no)
				(sheetname "")
			)
			(fill
				(thermal_gap 0.5)
				(thermal_bridge_width 0.5)
				(island_removal_mode 0)
			)
			(polygon
				(pts
					(xy 402.209 -152.273) (xy 402.209 -152.781) (xy 401.828 -152.781) (xy 401.828 -152.273)
				)
			)
		)
	)
	(footprint ""
		(layer "B.Cu")
		(at 30.9372 -88.7222)
		(property "Reference" "CT15"
			(at 0.8382 -0.84963 0)
			(unlocked yes)
			(layer "B.SilkS")
			(effects
				(font
					(size 0.7874 0.5842)
					(thickness 0.1524)
				)
				(justify left mirror)
			)
		)
		(property "Value" ""
			(at 0 0 0)
			(layer "B.Fab")
			(effects
				(font
					(size 1.27 1.27)
				)
				(justify mirror)
			)
		)
		(duplicate_pad_numbers_are_jumpers no)
		(fp_poly
			(pts
				(xy -0.3048 -0.1016) (xy -0.3048 0.9906) (xy 0.3048 0.9906) (xy 0.3048 -0.1016)
			)
			(stroke
				(width 0)
				(type default)
			)
			(fill no)
			(layer "B.CrtYd")
		)
		(fp_line
			(start -0.3048 -0.1016)
			(end 0.3048 -0.1016)
			(stroke
				(width 0.1)
				(type default)
			)
			(layer "B.Fab")
		)
		(fp_line
			(start -0.3048 0.9906)
			(end -0.3048 -0.1016)
			(stroke
				(width 0.1)
				(type default)
			)
			(layer "B.Fab")
		)
		(fp_line
			(start 0.3048 -0.1016)
			(end 0.3048 0.9906)
			(stroke
				(width 0.1)
				(type default)
			)
			(layer "B.Fab")
		)
		(fp_line
			(start 0.3048 0.9906)
			(end -0.3048 0.9906)
			(stroke
				(width 0.1)
				(type default)
			)
			(layer "B.Fab")
		)
		(pad "1" smd rect
			(at 0 0 180)
			(size 0.508 0.508)
			(layers "B.Cu" "B.Mask" "B.Paste")
			(net "A_TSENSE_PVCCIN_CPU1")
		)
		(pad "2" smd rect
			(at 0 0.889 180)
			(size 0.508 0.508)
			(layers "B.Cu" "B.Mask" "B.Paste")
			(net "GND")
		)
		(zone
			(layer "B.Cu")
			(hatch none 0.5)
			(connect_pads
				(clearance 0)
			)
			(min_thickness 0.25)
			(keepout
				(tracks allowed)
				(vias not_allowed)
				(pads allowed)
				(copperpour not_allowed)
				(footprints allowed)
			)
			(placement
				(enabled no)
				(sheetname "")
			)
			(fill
				(thermal_gap 0.5)
				(thermal_bridge_width 0.5)
				(island_removal_mode 0)
			)
			(polygon
				(pts
					(xy 31.1912 -88.4682) (xy 30.6832 -88.4682) (xy 30.6832 -88.0872) (xy 31.1912 -88.0872)
				)
			)
		)
		(zone
			(layer "B.Cu")
			(hatch none 0.5)
			(connect_pads
				(clearance 0)
			)
			(min_thickness 0.25)
			(keepout
				(tracks not_allowed)
				(vias allowed)
				(pads allowed)
				(copperpour not_allowed)
				(footprints allowed)
			)
			(placement
				(enabled no)
				(sheetname "")
			)
			(fill
				(thermal_gap 0.5)
				(thermal_bridge_width 0.5)
				(island_removal_mode 0)
			)
			(polygon
				(pts
					(xy 31.1912 -88.0872) (xy 30.6832 -88.0872) (xy 30.6832 -88.4682) (xy 31.1912 -88.4682)
				)
			)
		)
	)
	(footprint ""
		(layer "B.Cu")
		(at 272.861532 -145.0086 90)
		(property "Reference" "C5L7"
			(at -1.848866 0.752348 90)
			(unlocked yes)
			(layer "B.SilkS")
			(effects
				(font
					(size 1.27 0.9652)
					(thickness 0.1524)
				)
				(justify mirror)
			)
		)
		(property "Value" ""
			(at 0 0 90)
			(layer "B.Fab")
			(effects
				(font
					(size 1.27 1.27)
				)
				(justify mirror)
			)
		)
		(duplicate_pad_numbers_are_jumpers no)
		(fp_rect
			(start 0.500126 1.598422)
			(end -0.500126 -0.201422)
			(stroke
				(width 0)
				(type default)
			)
			(fill no)
			(layer "B.CrtYd")
		)
		(fp_line
			(start 0.500126 -0.201422)
			(end -0.500126 -0.201422)
			(stroke
				(width 0.1)
				(type default)
			)
			(layer "B.Fab")
		)
		(fp_line
			(start -0.500126 -0.201422)
			(end -0.500126 1.598422)
			(stroke
				(width 0.1)
				(type default)
			)
			(layer "B.Fab")
		)
		(fp_line
			(start 0.500126 1.598422)
			(end 0.500126 -0.201422)
			(stroke
				(width 0.1)
				(type default)
			)
			(layer "B.Fab")
		)
		(fp_line
			(start -0.500126 1.598422)
			(end 0.500126 1.598422)
			(stroke
				(width 0.1)
				(type default)
			)
			(layer "B.Fab")
		)
		(pad "1" smd rect
			(at 0 0)
			(size 0.889 0.9906)
			(layers "B.Cu" "B.Mask" "B.Paste")
			(net "PVDDQ_DEF")
		)
		(pad "2" smd rect
			(at 0 1.397)
			(size 0.889 0.9906)
			(layers "B.Cu" "B.Mask" "B.Paste")
			(net "GND")
		)
		(zone
			(layer "B.Cu")
			(hatch none 0.5)
			(connect_pads
				(clearance 0)
			)
			(min_thickness 0.25)
			(keepout
				(tracks not_allowed)
				(vias allowed)
				(pads allowed)
				(copperpour not_allowed)
				(footprints allowed)
			)
			(placement
				(enabled no)
				(sheetname "")
			)
			(fill
				(thermal_gap 0.5)
				(thermal_bridge_width 0.5)
				(island_removal_mode 0)
			)
			(polygon
				(pts
					(xy 273.814032 -145.5039) (xy 273.306032 -145.5039) (xy 273.306032 -144.5133) (xy 273.814032 -144.5133)
				)
			)
		)
		(zone
			(layer "B.Cu")
			(hatch none 0.5)
			(connect_pads
				(clearance 0)
			)
			(min_thickness 0.25)
			(keepout
				(tracks allowed)
				(vias not_allowed)
				(pads allowed)
				(copperpour not_allowed)
				(footprints allowed)
			)
			(placement
				(enabled no)
				(sheetname "")
			)
			(fill
				(thermal_gap 0.5)
				(thermal_bridge_width 0.5)
				(island_removal_mode 0)
			)
			(polygon
				(pts
					(xy 273.814032 -145.5039) (xy 273.306032 -145.5039) (xy 273.306032 -144.5133) (xy 273.814032 -144.5133)
				)
			)
		)
	)
	(footprint ""
		(layer "B.Cu")
		(at 162.91306 -84.328 90)
		(property "Reference" "R7P2"
			(at 0 0 90)
			(layer "B.SilkS")
			(hide yes)
			(effects
				(font
					(size 1.27 1.27)
				)
				(justify mirror)
			)
		)
		(property "Value" ""
			(at 0 0 90)
			(layer "B.Fab")
			(effects
				(font
					(size 1.27 1.27)
				)
				(justify mirror)
			)
		)
		(duplicate_pad_numbers_are_jumpers no)
		(fp_poly
			(pts
				(xy 0.2794 -0.1016) (xy -0.2794 -0.1016) (xy -0.2794 0.9906) (xy 0.2794 0.9906)
			)
			(stroke
				(width 0)
				(type default)
			)
			(fill no)
			(layer "B.CrtYd")
		)
		(fp_line
			(start 0.2794 -0.1016)
			(end 0.2794 0.9906)
			(stroke
				(width 0.1)
				(type default)
			)
			(layer "B.Fab")
		)
		(fp_line
			(start -0.2794 -0.1016)
			(end 0.2794 -0.1016)
			(stroke
				(width 0.1)
				(type default)
			)
			(layer "B.Fab")
		)
		(fp_line
			(start 0.2794 0.9906)
			(end -0.2794 0.9906)
			(stroke
				(width 0.1)
				(type default)
			)
			(layer "B.Fab")
		)
		(fp_line
			(start -0.2794 0.9906)
			(end -0.2794 -0.1016)
			(stroke
				(width 0.1)
				(type default)
			)
			(layer "B.Fab")
		)
		(pad "1" smd rect
			(at 0 0 270)
			(size 0.508 0.508)
			(layers "B.Cu" "B.Mask" "B.Paste")
			(net "CLK_100M_CPU1_BCLK2_DN")
		)
		(pad "2" smd rect
			(at 0 0.889 270)
			(size 0.508 0.508)
			(layers "B.Cu" "B.Mask" "B.Paste")
			(net "GND")
		)
		(zone
			(layer "B.Cu")
			(hatch none 0.5)
			(connect_pads
				(clearance 0)
			)
			(min_thickness 0.25)
			(keepout
				(tracks allowed)
				(vias not_allowed)
				(pads allowed)
				(copperpour not_allowed)
				(footprints allowed)
			)
			(placement
				(enabled no)
				(sheetname "")
			)
			(fill
				(thermal_gap 0.5)
				(thermal_bridge_width 0.5)
				(island_removal_mode 0)
			)
			(polygon
				(pts
					(xy 163.16706 -84.582) (xy 163.16706 -84.074) (xy 163.54806 -84.074) (xy 163.54806 -84.582)
				)
			)
		)
		(zone
			(layer "B.Cu")
			(hatch none 0.5)
			(connect_pads
				(clearance 0)
			)
			(min_thickness 0.25)
			(keepout
				(tracks not_allowed)
				(vias allowed)
				(pads allowed)
				(copperpour not_allowed)
				(footprints allowed)
			)
			(placement
				(enabled no)
				(sheetname "")
			)
			(fill
				(thermal_gap 0.5)
				(thermal_bridge_width 0.5)
				(island_removal_mode 0)
			)
			(polygon
				(pts
					(xy 163.54806 -84.582) (xy 163.54806 -84.074) (xy 163.16706 -84.074) (xy 163.16706 -84.582)
				)
			)
		)
	)
	(footprint ""
		(layer "B.Cu")
		(at 350.024192 -77.834236)
		(property "Reference" "C3P26"
			(at 0 0 0)
			(layer "B.SilkS")
			(hide yes)
			(effects
				(font
					(size 1.27 1.27)
				)
				(justify mirror)
			)
		)
		(property "Value" ""
			(at 0 0 0)
			(layer "B.Fab")
			(effects
				(font
					(size 1.27 1.27)
				)
				(justify mirror)
			)
		)
		(duplicate_pad_numbers_are_jumpers no)
		(fp_poly
			(pts
				(xy -0.3048 -0.1016) (xy -0.3048 0.9906) (xy 0.3048 0.9906) (xy 0.3048 -0.1016)
			)
			(stroke
				(width 0)
				(type default)
			)
			(fill no)
			(layer "B.CrtYd")
		)
		(fp_line
			(start -0.3048 -0.1016)
			(end 0.3048 -0.1016)
			(stroke
				(width 0.1)
				(type default)
			)
			(layer "B.Fab")
		)
		(fp_line
			(start -0.3048 0.9906)
			(end -0.3048 -0.1016)
			(stroke
				(width 0.1)
				(type default)
			)
			(layer "B.Fab")
		)
		(fp_line
			(start 0.3048 -0.1016)
			(end 0.3048 0.9906)
			(stroke
				(width 0.1)
				(type default)
			)
			(layer "B.Fab")
		)
		(fp_line
			(start 0.3048 0.9906)
			(end -0.3048 0.9906)
			(stroke
				(width 0.1)
				(type default)
			)
			(layer "B.Fab")
		)
		(pad "1" smd rect
			(at 0 0 180)
			(size 0.508 0.508)
			(layers "B.Cu" "B.Mask" "B.Paste")
			(net "P3E_CPU0_PE1_SS_TXP<4>")
		)
		(pad "2" smd rect
			(at 0 0.889 180)
			(size 0.508 0.508)
			(layers "B.Cu" "B.Mask" "B.Paste")
			(net "P3E_CPU0_PE1_SS_C_TXP<4>")
		)
		(zone
			(layer "B.Cu")
			(hatch none 0.5)
			(connect_pads
				(clearance 0)
			)
			(min_thickness 0.25)
			(keepout
				(tracks allowed)
				(vias not_allowed)
				(pads allowed)
				(copperpour not_allowed)
				(footprints allowed)
			)
			(placement
				(enabled no)
				(sheetname "")
			)
			(fill
				(thermal_gap 0.5)
				(thermal_bridge_width 0.5)
				(island_removal_mode 0)
			)
			(polygon
				(pts
					(xy 350.278192 -77.580236) (xy 349.770192 -77.580236) (xy 349.770192 -77.199236) (xy 350.278192 -77.199236)
				)
			)
		)
		(zone
			(layer "B.Cu")
			(hatch none 0.5)
			(connect_pads
				(clearance 0)
			)
			(min_thickness 0.25)
			(keepout
				(tracks not_allowed)
				(vias allowed)
				(pads allowed)
				(copperpour not_allowed)
				(footprints allowed)
			)
			(placement
				(enabled no)
				(sheetname "")
			)
			(fill
				(thermal_gap 0.5)
				(thermal_bridge_width 0.5)
				(island_removal_mode 0)
			)
			(polygon
				(pts
					(xy 350.278192 -77.199236) (xy 349.770192 -77.199236) (xy 349.770192 -77.580236) (xy 350.278192 -77.580236)
				)
			)
		)
	)
	(footprint ""
		(layer "B.Cu")
		(at 442.468 -157.1498)
		(property "Reference" "U25W17"
			(at 0.14986 2.621788 0)
			(unlocked yes)
			(layer "B.SilkS")
			(effects
				(font
					(size 1.27 0.964946)
					(thickness 0.000001)
				)
				(justify left mirror)
			)
		)
		(property "Value" ""
			(at 0 0 0)
			(layer "B.Fab")
			(effects
				(font
					(size 1.27 1.27)
				)
				(justify mirror)
			)
		)
		(duplicate_pad_numbers_are_jumpers no)
		(fp_circle
			(center 0.4699 -0.8382)
			(end 0.5969 -0.8382)
			(stroke
				(width 0.254)
				(type default)
			)
			(fill no)
			(layer "B.SilkS")
		)
		(fp_poly
			(pts
				(xy -0.21463 -0.450088) (xy -1.56337 -0.450088) (xy -1.56337 1.75006) (xy -0.21463 1.75006)
			)
			(stroke
				(width 0)
				(type default)
			)
			(fill no)
			(layer "B.CrtYd")
		)
		(fp_line
			(start -1.56337 -0.450088)
			(end -1.56337 1.75006)
			(stroke
				(width 0.1)
				(type default)
			)
			(layer "B.Fab")
		)
		(fp_line
			(start -1.56337 1.75006)
			(end -0.21463 1.75006)
			(stroke
				(width 0.1)
				(type default)
			)
			(layer "B.Fab")
		)
		(fp_line
			(start -0.21463 -0.450088)
			(end -1.56337 -0.450088)
			(stroke
				(width 0.1)
				(type default)
			)
			(layer "B.Fab")
		)
		(fp_line
			(start -0.21463 1.75006)
			(end -0.21463 -0.450088)
			(stroke
				(width 0.1)
				(type default)
			)
			(layer "B.Fab")
		)
		(fp_circle
			(center 0.4699 -0.8382)
			(end 0.5969 -0.8382)
			(stroke
				(width 0.254)
				(type default)
			)
			(fill no)
			(layer "B.Fab")
		)
		(pad "1" smd rect
			(at 0 0 180)
			(size 1.016 0.381)
			(layers "B.Cu" "B.Mask" "B.Paste")
			(net "JTAG_BMC_TRST_N")
		)
		(pad "2" smd rect
			(at 0 0.649986 180)
			(size 1.016 0.381)
			(layers "B.Cu" "B.Mask" "B.Paste")
			(net "BMC_JTAG_SEL_BUF")
		)
		(pad "3" smd rect
			(at 0 1.299972 180)
			(size 1.016 0.381)
			(layers "B.Cu" "B.Mask" "B.Paste")
			(net "GND")
		)
		(pad "4" smd rect
			(at -1.778 1.299972 180)
			(size 1.016 0.381)
			(layers "B.Cu" "B.Mask" "B.Paste")
			(net "JTAG_BMC_TRST_BUF_N")
		)
		(pad "5" smd rect
			(at -1.778 0 180)
			(size 1.016 0.381)
			(layers "B.Cu" "B.Mask" "B.Paste")
			(net "P3V3_STBY")
		)
	)
	(footprint ""
		(layer "B.Cu")
		(at 372.980966 -72.678036 180)
		(property "Reference" "C3P51"
			(at 0 0 0)
			(layer "B.SilkS")
			(hide yes)
			(effects
				(font
					(size 1.27 1.27)
				)
				(justify mirror)
			)
		)
		(property "Value" ""
			(at 0 0 0)
			(layer "B.Fab")
			(effects
				(font
					(size 1.27 1.27)
				)
				(justify mirror)
			)
		)
		(duplicate_pad_numbers_are_jumpers no)
		(fp_rect
			(start 0.2794 0.9144)
			(end -0.2794 -0.1143)
			(stroke
				(width 0)
				(type default)
			)
			(fill no)
			(layer "B.CrtYd")
		)
		(fp_line
			(start 0.2794 0.9144)
			(end 0.2794 -0.1143)
			(stroke
				(width 0.1)
				(type default)
			)
			(layer "B.Fab")
		)
		(fp_line
			(start 0.2794 -0.1143)
			(end -0.2794 -0.1143)
			(stroke
				(width 0.1)
				(type default)
			)
			(layer "B.Fab")
		)
		(fp_line
			(start -0.2794 0.9144)
			(end 0.2794 0.9144)
			(stroke
				(width 0.1)
				(type default)
			)
			(layer "B.Fab")
		)
		(fp_line
			(start -0.2794 -0.1143)
			(end -0.2794 0.9144)
			(stroke
				(width 0.1)
				(type default)
			)
			(layer "B.Fab")
		)
		(pad "1" smd custom
			(at 0 0 90)
			(size 0.10414 0.10414)
			(layers "B.Cu" "B.Mask" "B.Paste")
			(net "P3V3_STBY")
			(options
				(clearance outline)
				(anchor circle)
			)
			(primitives
				(gr_poly
					(pts
						(xy -0.20828 -0.08636) (xy -0.20828 0.08636) (xy -0.08636 0.20828) (xy 0.086614 0.20828) (xy 0.20828 0.086614)
						(xy 0.20828 -0.08636) (xy 0.08636 -0.20828) (xy -0.08636 -0.20828)
					)
					(width 0)
					(fill yes)
				)
			)
		)
		(pad "2" smd custom
			(at 0 0.8001 90)
			(size 0.10414 0.10414)
			(layers "B.Cu" "B.Mask" "B.Paste")
			(net "GND")
			(options
				(clearance outline)
				(anchor circle)
			)
			(primitives
				(gr_poly
					(pts
						(xy -0.20828 -0.08636) (xy -0.20828 0.08636) (xy -0.08636 0.20828) (xy 0.086614 0.20828) (xy 0.20828 0.086614)
						(xy 0.20828 -0.08636) (xy 0.08636 -0.20828) (xy -0.08636 -0.20828)
					)
					(width 0)
					(fill yes)
				)
			)
		)
		(zone
			(layer "B.Cu")
			(hatch none 0.5)
			(connect_pads
				(clearance 0)
			)
			(min_thickness 0.25)
			(keepout
				(tracks allowed)
				(vias not_allowed)
				(pads allowed)
				(copperpour not_allowed)
				(footprints allowed)
			)
			(placement
				(enabled no)
				(sheetname "")
			)
			(fill
				(thermal_gap 0.5)
				(thermal_bridge_width 0.5)
				(island_removal_mode 0)
			)
			(polygon
				(pts
					(xy 372.893336 -72.887586) (xy 372.893336 -73.268586) (xy 373.068596 -73.268586) (xy 373.06885 -72.887586)
				)
			)
		)
		(zone
			(layer "B.Cu")
			(hatch none 0.5)
			(connect_pads
				(clearance 0)
			)
			(min_thickness 0.25)
			(keepout
				(tracks not_allowed)
				(vias allowed)
				(pads allowed)
				(copperpour not_allowed)
				(footprints allowed)
			)
			(placement
				(enabled no)
				(sheetname "")
			)
			(fill
				(thermal_gap 0.5)
				(thermal_bridge_width 0.5)
				(island_removal_mode 0)
			)
			(polygon
				(pts
					(xy 372.893336 -72.887586) (xy 372.893336 -73.268586) (xy 373.068596 -73.268586) (xy 373.06885 -72.887586)
				)
			)
		)
	)
	(footprint ""
		(layer "B.Cu")
		(at 365.506 -112.395 -90)
		(property "Reference" "C3M45"
			(at 0 0 90)
			(layer "B.SilkS")
			(hide yes)
			(effects
				(font
					(size 1.27 1.27)
				)
				(justify mirror)
			)
		)
		(property "Value" ""
			(at 0 0 90)
			(layer "B.Fab")
			(effects
				(font
					(size 1.27 1.27)
				)
				(justify mirror)
			)
		)
		(duplicate_pad_numbers_are_jumpers no)
		(fp_poly
			(pts
				(xy -0.3048 -0.1016) (xy -0.3048 0.9906) (xy 0.3048 0.9906) (xy 0.3048 -0.1016)
			)
			(stroke
				(width 0)
				(type default)
			)
			(fill no)
			(layer "B.CrtYd")
		)
		(fp_line
			(start -0.3048 0.9906)
			(end -0.3048 -0.1016)
			(stroke
				(width 0.1)
				(type default)
			)
			(layer "B.Fab")
		)
		(fp_line
			(start 0.3048 0.9906)
			(end -0.3048 0.9906)
			(stroke
				(width 0.1)
				(type default)
			)
			(layer "B.Fab")
		)
		(fp_line
			(start -0.3048 -0.1016)
			(end 0.3048 -0.1016)
			(stroke
				(width 0.1)
				(type default)
			)
			(layer "B.Fab")
		)
		(fp_line
			(start 0.3048 -0.1016)
			(end 0.3048 0.9906)
			(stroke
				(width 0.1)
				(type default)
			)
			(layer "B.Fab")
		)
		(pad "1" smd rect
			(at 0 0 90)
			(size 0.508 0.508)
			(layers "B.Cu" "B.Mask" "B.Paste")
			(net "DMI_CPU0_PCH_RX_DN<2>")
		)
		(pad "2" smd rect
			(at 0 0.889 90)
			(size 0.508 0.508)
			(layers "B.Cu" "B.Mask" "B.Paste")
			(net "DMI_CPU0_PCH_RX_C_DN<2>")
		)
		(zone
			(layer "B.Cu")
			(hatch none 0.5)
			(connect_pads
				(clearance 0)
			)
			(min_thickness 0.25)
			(keepout
				(tracks not_allowed)
				(vias allowed)
				(pads allowed)
				(copperpour not_allowed)
				(footprints allowed)
			)
			(placement
				(enabled no)
				(sheetname "")
			)
			(fill
				(thermal_gap 0.5)
				(thermal_bridge_width 0.5)
				(island_removal_mode 0)
			)
			(polygon
				(pts
					(xy 364.871 -112.141) (xy 364.871 -112.649) (xy 365.252 -112.649) (xy 365.252 -112.141)
				)
			)
		)
		(zone
			(layer "B.Cu")
			(hatch none 0.5)
			(connect_pads
				(clearance 0)
			)
			(min_thickness 0.25)
			(keepout
				(tracks allowed)
				(vias not_allowed)
				(pads allowed)
				(copperpour not_allowed)
				(footprints allowed)
			)
			(placement
				(enabled no)
				(sheetname "")
			)
			(fill
				(thermal_gap 0.5)
				(thermal_bridge_width 0.5)
				(island_removal_mode 0)
			)
			(polygon
				(pts
					(xy 365.252 -112.141) (xy 365.252 -112.649) (xy 364.871 -112.649) (xy 364.871 -112.141)
				)
			)
		)
	)
	(footprint ""
		(layer "B.Cu")
		(at 399.2372 -87.4522 180)
		(property "Reference" "R8W6"
			(at 0.8382 -0.67818 180)
			(unlocked yes)
			(layer "B.SilkS")
			(effects
				(font
					(size 0.4064 0.254)
					(thickness 0.1524)
				)
				(justify left mirror)
			)
		)
		(property "Value" ""
			(at 0 0 0)
			(layer "B.Fab")
			(effects
				(font
					(size 1.27 1.27)
				)
				(justify mirror)
			)
		)
		(duplicate_pad_numbers_are_jumpers no)
		(fp_poly
			(pts
				(xy 0.2794 -0.1016) (xy -0.2794 -0.1016) (xy -0.2794 0.9906) (xy 0.2794 0.9906)
			)
			(stroke
				(width 0)
				(type default)
			)
			(fill no)
			(layer "B.CrtYd")
		)
		(fp_line
			(start 0.2794 0.9906)
			(end -0.2794 0.9906)
			(stroke
				(width 0.1)
				(type default)
			)
			(layer "B.Fab")
		)
		(fp_line
			(start 0.2794 -0.1016)
			(end 0.2794 0.9906)
			(stroke
				(width 0.1)
				(type default)
			)
			(layer "B.Fab")
		)
		(fp_line
			(start -0.2794 0.9906)
			(end -0.2794 -0.1016)
			(stroke
				(width 0.1)
				(type default)
			)
			(layer "B.Fab")
		)
		(fp_line
			(start -0.2794 -0.1016)
			(end 0.2794 -0.1016)
			(stroke
				(width 0.1)
				(type default)
			)
			(layer "B.Fab")
		)
		(pad "1" smd rect
			(at 0 0)
			(size 0.508 0.508)
			(layers "B.Cu" "B.Mask" "B.Paste")
			(net "P3V3_STBY")
		)
		(pad "2" smd rect
			(at 0 0.889)
			(size 0.508 0.508)
			(layers "B.Cu" "B.Mask" "B.Paste")
			(net "SMB_VR_STBY_LVC3_SDA_R1")
		)
		(zone
			(layer "B.Cu")
			(hatch none 0.5)
			(connect_pads
				(clearance 0)
			)
			(min_thickness 0.25)
			(keepout
				(tracks not_allowed)
				(vias allowed)
				(pads allowed)
				(copperpour not_allowed)
				(footprints allowed)
			)
			(placement
				(enabled no)
				(sheetname "")
			)
			(fill
				(thermal_gap 0.5)
				(thermal_bridge_width 0.5)
				(island_removal_mode 0)
			)
			(polygon
				(pts
					(xy 398.9832 -88.0872) (xy 399.4912 -88.0872) (xy 399.4912 -87.7062) (xy 398.9832 -87.7062)
				)
			)
		)
		(zone
			(layer "B.Cu")
			(hatch none 0.5)
			(connect_pads
				(clearance 0)
			)
			(min_thickness 0.25)
			(keepout
				(tracks allowed)
				(vias not_allowed)
				(pads allowed)
				(copperpour not_allowed)
				(footprints allowed)
			)
			(placement
				(enabled no)
				(sheetname "")
			)
			(fill
				(thermal_gap 0.5)
				(thermal_bridge_width 0.5)
				(island_removal_mode 0)
			)
			(polygon
				(pts
					(xy 398.9832 -87.7062) (xy 399.4912 -87.7062) (xy 399.4912 -88.0872) (xy 398.9832 -88.0872)
				)
			)
		)
	)
	(footprint ""
		(layer "B.Cu")
		(at 33.689036 -93.818202 90)
		(property "Reference" "C1C3"
			(at 0 0 90)
			(layer "B.SilkS")
			(hide yes)
			(effects
				(font
					(size 1.27 1.27)
				)
				(justify mirror)
			)
		)
		(property "Value" "*"
			(at -1.1811 -2.8194 90)
			(unlocked yes)
			(layer "B.Fab")
			(hide yes)
			(effects
				(font
					(size 1.27 1.016)
					(thickness 0.1524)
				)
				(justify mirror)
			)
		)
		(property "Device Type" "SC1U10V2KX-4-GP_SMD-BCG6-SC1U1A"
			(at -1.1811 -4.3434 90)
			(unlocked yes)
			(layer "B.Fab")
			(hide yes)
			(effects
				(font
					(size 1.27 1.016)
					(thickness 0.1524)
				)
				(justify mirror)
			)
		)
		(duplicate_pad_numbers_are_jumpers no)
		(fp_rect
			(start 0.4318 0.9525)
			(end -0.4318 -0.9525)
			(stroke
				(width 0)
				(type default)
			)
			(fill no)
			(layer "B.CrtYd")
		)
		(fp_rect
			(start 0.4318 0.9525)
			(end -0.4318 -0.9525)
			(stroke
				(width 0)
				(type default)
			)
			(fill no)
			(layer "B.Fab")
		)
		(pad "1" smd custom
			(at 0 -0.4445 270)
			(size 0.1524 0.1524)
			(layers "B.Cu" "B.Mask" "B.Paste")
			(net "P5V_STBY")
			(options
				(clearance outline)
				(anchor circle)
			)
			(primitives
				(gr_poly
					(pts
						(arc
							(start 0.3048 0.2032)
							(mid 0.275042 0.275042)
							(end 0.2032 0.3048)
						)
						(arc
							(start -0.2032 0.3048)
							(mid -0.275042 0.275042)
							(end -0.3048 0.2032)
						)
						(arc
							(start -0.3048 -0.2032)
							(mid -0.275042 -0.275042)
							(end -0.2032 -0.3048)
						)
						(arc
							(start 0.2032 -0.3048)
							(mid 0.275042 -0.275042)
							(end 0.3048 -0.2032)
						)
					)
					(width 0)
					(fill yes)
				)
			)
		)
		(pad "2" smd custom
			(at 0 0.4445 270)
			(size 0.1524 0.1524)
			(layers "B.Cu" "B.Mask" "B.Paste")
			(net "GND")
			(options
				(clearance outline)
				(anchor circle)
			)
			(primitives
				(gr_poly
					(pts
						(arc
							(start 0.3048 0.2032)
							(mid 0.275042 0.275042)
							(end 0.2032 0.3048)
						)
						(arc
							(start -0.2032 0.3048)
							(mid -0.275042 0.275042)
							(end -0.3048 0.2032)
						)
						(arc
							(start -0.3048 -0.2032)
							(mid -0.275042 -0.275042)
							(end -0.2032 -0.3048)
						)
						(arc
							(start 0.2032 -0.3048)
							(mid 0.275042 -0.275042)
							(end 0.3048 -0.2032)
						)
					)
					(width 0)
					(fill yes)
				)
			)
		)
	)
	(footprint ""
		(layer "B.Cu")
		(at 484.124 -147.828 90)
		(property "Reference" "CR1L2"
			(at 0 0 90)
			(layer "B.SilkS")
			(hide yes)
			(effects
				(font
					(size 1.27 1.27)
				)
				(justify mirror)
			)
		)
		(property "Value" ""
			(at 0 0 90)
			(layer "B.Fab")
			(effects
				(font
					(size 1.27 1.27)
				)
				(justify mirror)
			)
		)
		(duplicate_pad_numbers_are_jumpers no)
		(fp_line
			(start 0.9144 0.1016)
			(end 0.9144 2.9464)
			(stroke
				(width 0.1524)
				(type default)
			)
			(layer "B.SilkS")
		)
		(fp_line
			(start 0.8382 0.1016)
			(end 0.9144 0.1016)
			(stroke
				(width 0.1524)
				(type default)
			)
			(layer "B.SilkS")
		)
		(fp_line
			(start -0.8382 0.1016)
			(end -0.9144 0.1016)
			(stroke
				(width 0.1524)
				(type default)
			)
			(layer "B.SilkS")
		)
		(fp_line
			(start -0.9144 0.1016)
			(end -0.9144 2.9464)
			(stroke
				(width 0.1524)
				(type default)
			)
			(layer "B.SilkS")
		)
		(fp_line
			(start 0.9144 2.9464)
			(end 0.8382 2.9464)
			(stroke
				(width 0.1524)
				(type default)
			)
			(layer "B.SilkS")
		)
		(fp_line
			(start -0.9144 2.9464)
			(end -0.8382 2.9464)
			(stroke
				(width 0.1524)
				(type default)
			)
			(layer "B.SilkS")
		)
		(fp_circle
			(center -1.128776 -0.907288)
			(end -1.128776 -0.780288)
			(stroke
				(width 0.254)
				(type default)
			)
			(fill no)
			(layer "B.SilkS")
		)
		(fp_poly
			(pts
				(xy 0 0.1016) (xy -0.5334 0.1016) (xy -0.7366 0.1016) (xy -0.9144 0.1016) (xy -0.9144 2.9464) (xy -0.8382 2.9464)
				(xy -0.762 2.9464) (xy 0.9144 2.9464) (xy 0.9144 2.7686) (xy 0.9144 2.159) (xy 0.9144 0.1016) (xy 0.7366 0.1016)
				(xy 0.5842 0.1016)
			)
			(stroke
				(width 0)
				(type default)
			)
			(fill no)
			(layer "B.CrtYd")
		)
		(fp_line
			(start 0.9144 0.1016)
			(end 0.9144 2.9464)
			(stroke
				(width 0.1)
				(type default)
			)
			(layer "B.Fab")
		)
		(fp_line
			(start -0.9144 0.1016)
			(end 0.9144 0.1016)
			(stroke
				(width 0.1)
				(type default)
			)
			(layer "B.Fab")
		)
		(fp_line
			(start 0.9144 2.9464)
			(end -0.9144 2.9464)
			(stroke
				(width 0.1)
				(type default)
			)
			(layer "B.Fab")
		)
		(fp_line
			(start -0.9144 2.9464)
			(end -0.9144 0.1016)
			(stroke
				(width 0.1)
				(type default)
			)
			(layer "B.Fab")
		)
		(fp_circle
			(center -1.128776 -0.907288)
			(end -1.128776 -0.780288)
			(stroke
				(width 0.254)
				(type default)
			)
			(fill no)
			(layer "B.Fab")
		)
		(pad "1" smd rect
			(at 0 0)
			(size 1.524 0.762)
			(layers "B.Cu" "B.Mask" "B.Paste")
			(net "FM_DB_UART_SEL2_N")
		)
		(pad "2" smd rect
			(at 0 3.048 180)
			(size 1.524 0.762)
			(layers "B.Cu" "B.Mask" "B.Paste")
			(net "FM_DB_UART_SEL1_N")
		)
	)
	(footprint ""
		(layer "B.Cu")
		(at 155.194 -8.128 90)
		(property "Reference" "C7U3"
			(at 0 0 90)
			(layer "B.SilkS")
			(hide yes)
			(effects
				(font
					(size 1.27 1.27)
				)
				(justify mirror)
			)
		)
		(property "Value" ""
			(at 0 0 90)
			(layer "B.Fab")
			(effects
				(font
					(size 1.27 1.27)
				)
				(justify mirror)
			)
		)
		(duplicate_pad_numbers_are_jumpers no)
		(fp_poly
			(pts
				(xy 0.4953 -0.2032) (xy -0.4953 -0.2032) (xy -0.4953 1.6002) (xy 0.4953 1.6002)
			)
			(stroke
				(width 0)
				(type default)
			)
			(fill no)
			(layer "B.CrtYd")
		)
		(fp_line
			(start 0.4953 -0.2032)
			(end -0.4953 -0.2032)
			(stroke
				(width 0.1)
				(type default)
			)
			(layer "B.Fab")
		)
		(fp_line
			(start -0.4953 -0.2032)
			(end -0.4953 1.6002)
			(stroke
				(width 0.1)
				(type default)
			)
			(layer "B.Fab")
		)
		(fp_line
			(start 0.4953 1.6002)
			(end 0.4953 -0.2032)
			(stroke
				(width 0.1)
				(type default)
			)
			(layer "B.Fab")
		)
		(fp_line
			(start -0.4953 1.6002)
			(end 0.4953 1.6002)
			(stroke
				(width 0.1)
				(type default)
			)
			(layer "B.Fab")
		)
		(pad "1" smd rect
			(at 0 0 270)
			(size 0.762 0.889)
			(layers "B.Cu" "B.Mask" "B.Paste")
			(net "PVPP_GHJ")
		)
		(pad "2" smd rect
			(at 0 1.397 270)
			(size 0.762 0.889)
			(layers "B.Cu" "B.Mask" "B.Paste")
			(net "GND")
		)
		(zone
			(layer "B.Cu")
			(hatch none 0.5)
			(connect_pads
				(clearance 0)
			)
			(min_thickness 0.25)
			(keepout
				(tracks not_allowed)
				(vias allowed)
				(pads allowed)
				(copperpour not_allowed)
				(footprints allowed)
			)
			(placement
				(enabled no)
				(sheetname "")
			)
			(fill
				(thermal_gap 0.5)
				(thermal_bridge_width 0.5)
				(island_removal_mode 0)
			)
			(polygon
				(pts
					(xy 155.6385 -8.509) (xy 155.6385 -7.747) (xy 156.1465 -7.747) (xy 156.1465 -8.509)
				)
			)
		)
	)
	(footprint ""
		(layer "B.Cu")
		(at 32.832802 -98.937064 90)
		(property "Reference" "C9N19"
			(at 0 0 90)
			(layer "B.SilkS")
			(hide yes)
			(effects
				(font
					(size 1.27 1.27)
				)
				(justify mirror)
			)
		)
		(property "Value" ""
			(at 0 0 90)
			(layer "B.Fab")
			(effects
				(font
					(size 1.27 1.27)
				)
				(justify mirror)
			)
		)
		(duplicate_pad_numbers_are_jumpers no)
		(fp_poly
			(pts
				(xy 0.7239 -0.2159) (xy -0.7239 -0.2159) (xy -0.7239 1.9939) (xy 0.7239 1.9939)
			)
			(stroke
				(width 0)
				(type default)
			)
			(fill no)
			(layer "B.CrtYd")
		)
		(fp_line
			(start 0.7239 -0.2159)
			(end 0.7239 1.9939)
			(stroke
				(width 0.1)
				(type default)
			)
			(layer "B.Fab")
		)
		(fp_line
			(start -0.7239 -0.2159)
			(end 0.7239 -0.2159)
			(stroke
				(width 0.1)
				(type default)
			)
			(layer "B.Fab")
		)
		(fp_line
			(start 0.7239 1.9939)
			(end -0.7239 1.9939)
			(stroke
				(width 0.1)
				(type default)
			)
			(layer "B.Fab")
		)
		(fp_line
			(start -0.7239 1.9939)
			(end -0.7239 -0.2159)
			(stroke
				(width 0.1)
				(type default)
			)
			(layer "B.Fab")
		)
		(pad "1" smd rect
			(at 0 0 270)
			(size 1.27 1.016)
			(layers "B.Cu" "B.Mask" "B.Paste")
			(net "VR_FET_SW_P12V_STBY_PVCCIN_CPU1")
		)
		(pad "2" smd rect
			(at 0 1.778 270)
			(size 1.27 1.016)
			(layers "B.Cu" "B.Mask" "B.Paste")
			(net "GND")
		)
		(zone
			(layer "B.Cu")
			(hatch none 0.5)
			(connect_pads
				(clearance 0)
			)
			(min_thickness 0.25)
			(keepout
				(tracks not_allowed)
				(vias allowed)
				(pads allowed)
				(copperpour not_allowed)
				(footprints allowed)
			)
			(placement
				(enabled no)
				(sheetname "")
			)
			(fill
				(thermal_gap 0.5)
				(thermal_bridge_width 0.5)
				(island_removal_mode 0)
			)
			(polygon
				(pts
					(xy 33.340802 -99.572064) (xy 33.340802 -98.302064) (xy 34.102802 -98.302064) (xy 34.102802 -99.572064)
				)
			)
		)
	)
	(footprint ""
		(layer "B.Cu")
		(at 417.006024 -141.732)
		(property "Reference" "R2L22"
			(at 0 0 0)
			(layer "B.SilkS")
			(hide yes)
			(effects
				(font
					(size 1.27 1.27)
				)
				(justify mirror)
			)
		)
		(property "Value" ""
			(at 0 0 0)
			(layer "B.Fab")
			(effects
				(font
					(size 1.27 1.27)
				)
				(justify mirror)
			)
		)
		(duplicate_pad_numbers_are_jumpers no)
		(fp_poly
			(pts
				(xy 0.2794 -0.1016) (xy -0.2794 -0.1016) (xy -0.2794 0.9906) (xy 0.2794 0.9906)
			)
			(stroke
				(width 0)
				(type default)
			)
			(fill no)
			(layer "B.CrtYd")
		)
		(fp_line
			(start -0.2794 -0.1016)
			(end 0.2794 -0.1016)
			(stroke
				(width 0.1)
				(type default)
			)
			(layer "B.Fab")
		)
		(fp_line
			(start -0.2794 0.9906)
			(end -0.2794 -0.1016)
			(stroke
				(width 0.1)
				(type default)
			)
			(layer "B.Fab")
		)
		(fp_line
			(start 0.2794 -0.1016)
			(end 0.2794 0.9906)
			(stroke
				(width 0.1)
				(type default)
			)
			(layer "B.Fab")
		)
		(fp_line
			(start 0.2794 0.9906)
			(end -0.2794 0.9906)
			(stroke
				(width 0.1)
				(type default)
			)
			(layer "B.Fab")
		)
		(pad "1" smd rect
			(at 0 0 180)
			(size 0.508 0.508)
			(layers "B.Cu" "B.Mask" "B.Paste")
			(net "PD_SATA1_CONTROLLER_TYPE_R")
		)
		(pad "2" smd rect
			(at 0 0.889 180)
			(size 0.508 0.508)
			(layers "B.Cu" "B.Mask" "B.Paste")
			(net "GND")
		)
		(zone
			(layer "B.Cu")
			(hatch none 0.5)
			(connect_pads
				(clearance 0)
			)
			(min_thickness 0.25)
			(keepout
				(tracks allowed)
				(vias not_allowed)
				(pads allowed)
				(copperpour not_allowed)
				(footprints allowed)
			)
			(placement
				(enabled no)
				(sheetname "")
			)
			(fill
				(thermal_gap 0.5)
				(thermal_bridge_width 0.5)
				(island_removal_mode 0)
			)
			(polygon
				(pts
					(xy 417.260024 -141.478) (xy 416.752024 -141.478) (xy 416.752024 -141.097) (xy 417.260024 -141.097)
				)
			)
		)
		(zone
			(layer "B.Cu")
			(hatch none 0.5)
			(connect_pads
				(clearance 0)
			)
			(min_thickness 0.25)
			(keepout
				(tracks not_allowed)
				(vias allowed)
				(pads allowed)
				(copperpour not_allowed)
				(footprints allowed)
			)
			(placement
				(enabled no)
				(sheetname "")
			)
			(fill
				(thermal_gap 0.5)
				(thermal_bridge_width 0.5)
				(island_removal_mode 0)
			)
			(polygon
				(pts
					(xy 417.260024 -141.097) (xy 416.752024 -141.097) (xy 416.752024 -141.478) (xy 417.260024 -141.478)
				)
			)
		)
	)
	(footprint ""
		(layer "B.Cu")
		(at 3.82524 -11.392916 90)
		(property "Reference" "C9U3"
			(at 0 0 90)
			(layer "B.SilkS")
			(hide yes)
			(effects
				(font
					(size 1.27 1.27)
				)
				(justify mirror)
			)
		)
		(property "Value" ""
			(at 0 0 90)
			(layer "B.Fab")
			(effects
				(font
					(size 1.27 1.27)
				)
				(justify mirror)
			)
		)
		(duplicate_pad_numbers_are_jumpers no)
		(fp_rect
			(start -0.7239 -0.2159)
			(end 0.7239 1.9939)
			(stroke
				(width 0)
				(type default)
			)
			(fill no)
			(layer "B.CrtYd")
		)
		(fp_line
			(start 0.7239 -0.2159)
			(end 0.7239 1.9939)
			(stroke
				(width 0.1)
				(type default)
			)
			(layer "B.Fab")
		)
		(fp_line
			(start -0.7239 -0.2159)
			(end 0.7239 -0.2159)
			(stroke
				(width 0.1)
				(type default)
			)
			(layer "B.Fab")
		)
		(fp_line
			(start 0.7239 1.9939)
			(end -0.7239 1.9939)
			(stroke
				(width 0.1)
				(type default)
			)
			(layer "B.Fab")
		)
		(fp_line
			(start -0.7239 1.9939)
			(end -0.7239 -0.2159)
			(stroke
				(width 0.1)
				(type default)
			)
			(layer "B.Fab")
		)
		(pad "1" smd rect
			(at 0 0 270)
			(size 1.27 1.016)
			(layers "B.Cu" "B.Mask" "B.Paste")
			(net "VR_FET_SW_P12V_STBY_PVDDQ_GHJ")
		)
		(pad "2" smd rect
			(at 0 1.778 270)
			(size 1.27 1.016)
			(layers "B.Cu" "B.Mask" "B.Paste")
			(net "GND")
		)
		(zone
			(layer "B.Cu")
			(hatch none 0.5)
			(connect_pads
				(clearance 0)
			)
			(min_thickness 0.25)
			(keepout
				(tracks not_allowed)
				(vias allowed)
				(pads allowed)
				(copperpour not_allowed)
				(footprints allowed)
			)
			(placement
				(enabled no)
				(sheetname "")
			)
			(fill
				(thermal_gap 0.5)
				(thermal_bridge_width 0.5)
				(island_removal_mode 0)
			)
			(polygon
				(pts
					(xy 4.33324 -10.757916) (xy 5.09524 -10.757916) (xy 5.09524 -12.027916) (xy 4.33324 -12.027916)
				)
			)
		)
	)
	(footprint ""
		(layer "B.Cu")
		(at 166.5097 -1.90246 180)
		(property "Reference" "C6W12"
			(at -1.47828 0.78994 270)
			(unlocked yes)
			(layer "B.SilkS")
			(effects
				(font
					(size 0.4064 0.254)
					(thickness 0.1524)
				)
				(justify mirror)
			)
		)
		(property "Value" ""
			(at 0 0 0)
			(layer "B.Fab")
			(effects
				(font
					(size 1.27 1.27)
				)
				(justify mirror)
			)
		)
		(duplicate_pad_numbers_are_jumpers no)
		(fp_poly
			(pts
				(xy 0.7239 -0.2159) (xy -0.7239 -0.2159) (xy -0.7239 1.9939) (xy 0.7239 1.9939)
			)
			(stroke
				(width 0)
				(type default)
			)
			(fill no)
			(layer "B.CrtYd")
		)
		(fp_line
			(start 0.7239 1.9939)
			(end -0.7239 1.9939)
			(stroke
				(width 0.1)
				(type default)
			)
			(layer "B.Fab")
		)
		(fp_line
			(start 0.7239 -0.2159)
			(end 0.7239 1.9939)
			(stroke
				(width 0.1)
				(type default)
			)
			(layer "B.Fab")
		)
		(fp_line
			(start -0.7239 1.9939)
			(end -0.7239 -0.2159)
			(stroke
				(width 0.1)
				(type default)
			)
			(layer "B.Fab")
		)
		(fp_line
			(start -0.7239 -0.2159)
			(end 0.7239 -0.2159)
			(stroke
				(width 0.1)
				(type default)
			)
			(layer "B.Fab")
		)
		(pad "1" smd rect
			(at 0 0)
			(size 1.27 1.016)
			(layers "B.Cu" "B.Mask" "B.Paste")
			(net "PVTT_GHJ")
		)
		(pad "2" smd rect
			(at 0 1.778)
			(size 1.27 1.016)
			(layers "B.Cu" "B.Mask" "B.Paste")
			(net "GND")
		)
		(zone
			(layer "B.Cu")
			(hatch none 0.5)
			(connect_pads
				(clearance 0)
			)
			(min_thickness 0.25)
			(keepout
				(tracks not_allowed)
				(vias allowed)
				(pads allowed)
				(copperpour not_allowed)
				(footprints allowed)
			)
			(placement
				(enabled no)
				(sheetname "")
			)
			(fill
				(thermal_gap 0.5)
				(thermal_bridge_width 0.5)
				(island_removal_mode 0)
			)
			(polygon
				(pts
					(xy 165.8747 -2.41046) (xy 167.1447 -2.41046) (xy 167.1447 -3.17246) (xy 165.8747 -3.17246)
				)
			)
		)
	)
	(footprint ""
		(layer "B.Cu")
		(at 258.1402 -12.827 -90)
		(property "Reference" "C5G45"
			(at -1.14681 0.76708 0)
			(unlocked yes)
			(layer "B.SilkS")
			(effects
				(font
					(size 0.7874 0.5842)
					(thickness 0.1524)
				)
				(justify mirror)
			)
		)
		(property "Value" ""
			(at 0 0 90)
			(layer "B.Fab")
			(effects
				(font
					(size 1.27 1.27)
				)
				(justify mirror)
			)
		)
		(duplicate_pad_numbers_are_jumpers no)
		(fp_rect
			(start -0.4953 -0.2032)
			(end 0.4953 1.6002)
			(stroke
				(width 0)
				(type default)
			)
			(fill no)
			(layer "B.CrtYd")
		)
		(fp_line
			(start -0.4953 1.6002)
			(end 0.4953 1.6002)
			(stroke
				(width 0.1)
				(type default)
			)
			(layer "B.Fab")
		)
		(fp_line
			(start 0.4953 1.6002)
			(end 0.4953 -0.2032)
			(stroke
				(width 0.1)
				(type default)
			)
			(layer "B.Fab")
		)
		(fp_line
			(start -0.4953 -0.2032)
			(end -0.4953 1.6002)
			(stroke
				(width 0.1)
				(type default)
			)
			(layer "B.Fab")
		)
		(fp_line
			(start 0.4953 -0.2032)
			(end -0.4953 -0.2032)
			(stroke
				(width 0.1)
				(type default)
			)
			(layer "B.Fab")
		)
		(pad "1" smd rect
			(at 0 0 90)
			(size 0.762 0.889)
			(layers "B.Cu" "B.Mask" "B.Paste")
			(net "PVDDQ_ABC")
		)
		(pad "2" smd rect
			(at 0 1.397 90)
			(size 0.762 0.889)
			(layers "B.Cu" "B.Mask" "B.Paste")
			(net "GND")
		)
		(zone
			(layer "B.Cu")
			(hatch none 0.5)
			(connect_pads
				(clearance 0)
			)
			(min_thickness 0.25)
			(keepout
				(tracks not_allowed)
				(vias allowed)
				(pads allowed)
				(copperpour not_allowed)
				(footprints allowed)
			)
			(placement
				(enabled no)
				(sheetname "")
			)
			(fill
				(thermal_gap 0.5)
				(thermal_bridge_width 0.5)
				(island_removal_mode 0)
			)
			(polygon
				(pts
					(xy 257.6957 -13.208) (xy 257.1877 -13.208) (xy 257.1877 -12.446) (xy 257.6957 -12.446)
				)
			)
		)
	)
	(footprint ""
		(layer "B.Cu")
		(at 459.73873 -18.55724)
		(property "Reference" "C2T6"
			(at 0 0 0)
			(layer "B.SilkS")
			(hide yes)
			(effects
				(font
					(size 1.27 1.27)
				)
				(justify mirror)
			)
		)
		(property "Value" ""
			(at 0 0 0)
			(layer "B.Fab")
			(effects
				(font
					(size 1.27 1.27)
				)
				(justify mirror)
			)
		)
		(duplicate_pad_numbers_are_jumpers no)
		(fp_rect
			(start 0.7239 -0.2159)
			(end -0.7239 1.9939)
			(stroke
				(width 0)
				(type default)
			)
			(fill no)
			(layer "B.CrtYd")
		)
		(fp_line
			(start -0.7239 -0.2159)
			(end 0.7239 -0.2159)
			(stroke
				(width 0.1)
				(type default)
			)
			(layer "B.Fab")
		)
		(fp_line
			(start -0.7239 1.9939)
			(end -0.7239 -0.2159)
			(stroke
				(width 0.1)
				(type default)
			)
			(layer "B.Fab")
		)
		(fp_line
			(start 0.7239 -0.2159)
			(end 0.7239 1.9939)
			(stroke
				(width 0.1)
				(type default)
			)
			(layer "B.Fab")
		)
		(fp_line
			(start 0.7239 1.9939)
			(end -0.7239 1.9939)
			(stroke
				(width 0.1)
				(type default)
			)
			(layer "B.Fab")
		)
		(pad "1" smd rect
			(at 0 0 180)
			(size 1.27 1.016)
			(layers "B.Cu" "B.Mask" "B.Paste")
			(net "P3V3_STBY")
		)
		(pad "2" smd rect
			(at 0 1.778 180)
			(size 1.27 1.016)
			(layers "B.Cu" "B.Mask" "B.Paste")
			(net "GND")
		)
		(zone
			(layer "B.Cu")
			(hatch none 0.5)
			(connect_pads
				(clearance 0)
			)
			(min_thickness 0.25)
			(keepout
				(tracks not_allowed)
				(vias allowed)
				(pads allowed)
				(copperpour not_allowed)
				(footprints allowed)
			)
			(placement
				(enabled no)
				(sheetname "")
			)
			(fill
				(thermal_gap 0.5)
				(thermal_bridge_width 0.5)
				(island_removal_mode 0)
			)
			(polygon
				(pts
					(xy 460.37373 -18.04924) (xy 459.10373 -18.04924) (xy 459.10373 -17.28724) (xy 460.37373 -17.28724)
				)
			)
		)
	)
	(footprint ""
		(layer "B.Cu")
		(at 19.177 -69.596 180)
		(property "Reference" "R9P30"
			(at 0 0 0)
			(layer "B.SilkS")
			(hide yes)
			(effects
				(font
					(size 1.27 1.27)
				)
				(justify mirror)
			)
		)
		(property "Value" ""
			(at 0 0 0)
			(layer "B.Fab")
			(effects
				(font
					(size 1.27 1.27)
				)
				(justify mirror)
			)
		)
		(duplicate_pad_numbers_are_jumpers no)
		(fp_rect
			(start -0.4953 -0.2032)
			(end 0.4953 1.6002)
			(stroke
				(width 0)
				(type default)
			)
			(fill no)
			(layer "B.CrtYd")
		)
		(fp_line
			(start 0.4953 1.6002)
			(end 0.4953 -0.2032)
			(stroke
				(width 0.1)
				(type default)
			)
			(layer "B.Fab")
		)
		(fp_line
			(start 0.4953 -0.2032)
			(end -0.4953 -0.2032)
			(stroke
				(width 0.1)
				(type default)
			)
			(layer "B.Fab")
		)
		(fp_line
			(start -0.4953 1.6002)
			(end 0.4953 1.6002)
			(stroke
				(width 0.1)
				(type default)
			)
			(layer "B.Fab")
		)
		(fp_line
			(start -0.4953 -0.2032)
			(end -0.4953 1.6002)
			(stroke
				(width 0.1)
				(type default)
			)
			(layer "B.Fab")
		)
		(pad "1" smd rect
			(at 0 0)
			(size 0.762 0.889)
			(layers "B.Cu" "B.Mask" "B.Paste")
			(net "P12V_PSU")
		)
		(pad "2" smd rect
			(at 0 1.397)
			(size 0.762 0.889)
			(layers "B.Cu" "B.Mask" "B.Paste")
			(net "P12V_HSC_VCC")
		)
		(zone
			(layer "B.Cu")
			(hatch none 0.5)
			(connect_pads
				(clearance 0)
			)
			(min_thickness 0.25)
			(keepout
				(tracks not_allowed)
				(vias allowed)
				(pads allowed)
				(copperpour not_allowed)
				(footprints allowed)
			)
			(placement
				(enabled no)
				(sheetname "")
			)
			(fill
				(thermal_gap 0.5)
				(thermal_bridge_width 0.5)
				(island_removal_mode 0)
			)
			(polygon
				(pts
					(xy 19.558 -70.0405) (xy 19.558 -70.5485) (xy 18.796 -70.5485) (xy 18.796 -70.0405)
				)
			)
		)
		(zone
			(layer "B.Cu")
			(hatch none 0.5)
			(connect_pads
				(clearance 0)
			)
			(min_thickness 0.25)
			(keepout
				(tracks allowed)
				(vias not_allowed)
				(pads allowed)
				(copperpour not_allowed)
				(footprints allowed)
			)
			(placement
				(enabled no)
				(sheetname "")
			)
			(fill
				(thermal_gap 0.5)
				(thermal_bridge_width 0.5)
				(island_removal_mode 0)
			)
			(polygon
				(pts
					(xy 19.558 -70.0405) (xy 19.558 -70.5485) (xy 18.796 -70.5485) (xy 18.796 -70.0405)
				)
			)
		)
	)
	(footprint ""
		(layer "B.Cu")
		(at 385.463034 -26.506932 90)
		(property "Reference" "C2T14"
			(at 0 0 90)
			(layer "B.SilkS")
			(hide yes)
			(effects
				(font
					(size 1.27 1.27)
				)
				(justify mirror)
			)
		)
		(property "Value" ""
			(at 0 0 90)
			(layer "B.Fab")
			(effects
				(font
					(size 1.27 1.27)
				)
				(justify mirror)
			)
		)
		(duplicate_pad_numbers_are_jumpers no)
		(fp_poly
			(pts
				(xy -0.3048 -0.1016) (xy -0.3048 0.9906) (xy 0.3048 0.9906) (xy 0.3048 -0.1016)
			)
			(stroke
				(width 0)
				(type default)
			)
			(fill no)
			(layer "B.CrtYd")
		)
		(fp_line
			(start 0.3048 -0.1016)
			(end 0.3048 0.9906)
			(stroke
				(width 0.1)
				(type default)
			)
			(layer "B.Fab")
		)
		(fp_line
			(start -0.3048 -0.1016)
			(end 0.3048 -0.1016)
			(stroke
				(width 0.1)
				(type default)
			)
			(layer "B.Fab")
		)
		(fp_line
			(start 0.3048 0.9906)
			(end -0.3048 0.9906)
			(stroke
				(width 0.1)
				(type default)
			)
			(layer "B.Fab")
		)
		(fp_line
			(start -0.3048 0.9906)
			(end -0.3048 -0.1016)
			(stroke
				(width 0.1)
				(type default)
			)
			(layer "B.Fab")
		)
		(pad "1" smd rect
			(at 0 0 270)
			(size 0.508 0.508)
			(layers "B.Cu" "B.Mask" "B.Paste")
			(net "P3E_PCH_M2_TX_C_DN<2>")
		)
		(pad "2" smd rect
			(at 0 0.889 270)
			(size 0.508 0.508)
			(layers "B.Cu" "B.Mask" "B.Paste")
			(net "P3E_PCH_M2_TX_DN<2>")
		)
		(zone
			(layer "B.Cu")
			(hatch none 0.5)
			(connect_pads
				(clearance 0)
			)
			(min_thickness 0.25)
			(keepout
				(tracks allowed)
				(vias not_allowed)
				(pads allowed)
				(copperpour not_allowed)
				(footprints allowed)
			)
			(placement
				(enabled no)
				(sheetname "")
			)
			(fill
				(thermal_gap 0.5)
				(thermal_bridge_width 0.5)
				(island_removal_mode 0)
			)
			(polygon
				(pts
					(xy 385.717034 -26.760932) (xy 385.717034 -26.252932) (xy 386.098034 -26.252932) (xy 386.098034 -26.760932)
				)
			)
		)
		(zone
			(layer "B.Cu")
			(hatch none 0.5)
			(connect_pads
				(clearance 0)
			)
			(min_thickness 0.25)
			(keepout
				(tracks not_allowed)
				(vias allowed)
				(pads allowed)
				(copperpour not_allowed)
				(footprints allowed)
			)
			(placement
				(enabled no)
				(sheetname "")
			)
			(fill
				(thermal_gap 0.5)
				(thermal_bridge_width 0.5)
				(island_removal_mode 0)
			)
			(polygon
				(pts
					(xy 386.098034 -26.760932) (xy 386.098034 -26.252932) (xy 385.717034 -26.252932) (xy 385.717034 -26.760932)
				)
			)
		)
	)
	(footprint ""
		(layer "B.Cu")
		(at 252.1585 -17.7546 -90)
		(property "Reference" "C5T10"
			(at -1.848866 0.752348 270)
			(unlocked yes)
			(layer "B.SilkS")
			(effects
				(font
					(size 1.27 0.9652)
					(thickness 0.1524)
				)
				(justify mirror)
			)
		)
		(property "Value" ""
			(at 0 0 90)
			(layer "B.Fab")
			(effects
				(font
					(size 1.27 1.27)
				)
				(justify mirror)
			)
		)
		(duplicate_pad_numbers_are_jumpers no)
		(fp_rect
			(start 0.500126 1.598422)
			(end -0.500126 -0.201422)
			(stroke
				(width 0)
				(type default)
			)
			(fill no)
			(layer "B.CrtYd")
		)
		(fp_line
			(start -0.500126 1.598422)
			(end 0.500126 1.598422)
			(stroke
				(width 0.1)
				(type default)
			)
			(layer "B.Fab")
		)
		(fp_line
			(start 0.500126 1.598422)
			(end 0.500126 -0.201422)
			(stroke
				(width 0.1)
				(type default)
			)
			(layer "B.Fab")
		)
		(fp_line
			(start -0.500126 -0.201422)
			(end -0.500126 1.598422)
			(stroke
				(width 0.1)
				(type default)
			)
			(layer "B.Fab")
		)
		(fp_line
			(start 0.500126 -0.201422)
			(end -0.500126 -0.201422)
			(stroke
				(width 0.1)
				(type default)
			)
			(layer "B.Fab")
		)
		(pad "1" smd rect
			(at 0 0 180)
			(size 0.889 0.9906)
			(layers "B.Cu" "B.Mask" "B.Paste")
			(net "PVDDQ_ABC")
		)
		(pad "2" smd rect
			(at 0 1.397 180)
			(size 0.889 0.9906)
			(layers "B.Cu" "B.Mask" "B.Paste")
			(net "GND")
		)
		(zone
			(layer "B.Cu")
			(hatch none 0.5)
			(connect_pads
				(clearance 0)
			)
			(min_thickness 0.25)
			(keepout
				(tracks not_allowed)
				(vias allowed)
				(pads allowed)
				(copperpour not_allowed)
				(footprints allowed)
			)
			(placement
				(enabled no)
				(sheetname "")
			)
			(fill
				(thermal_gap 0.5)
				(thermal_bridge_width 0.5)
				(island_removal_mode 0)
			)
			(polygon
				(pts
					(xy 251.206 -17.2593) (xy 251.714 -17.2593) (xy 251.714 -18.2499) (xy 251.206 -18.2499)
				)
			)
		)
		(zone
			(layer "B.Cu")
			(hatch none 0.5)
			(connect_pads
				(clearance 0)
			)
			(min_thickness 0.25)
			(keepout
				(tracks allowed)
				(vias not_allowed)
				(pads allowed)
				(copperpour not_allowed)
				(footprints allowed)
			)
			(placement
				(enabled no)
				(sheetname "")
			)
			(fill
				(thermal_gap 0.5)
				(thermal_bridge_width 0.5)
				(island_removal_mode 0)
			)
			(polygon
				(pts
					(xy 251.206 -17.2593) (xy 251.714 -17.2593) (xy 251.714 -18.2499) (xy 251.206 -18.2499)
				)
			)
		)
	)
	(footprint ""
		(layer "B.Cu")
		(at 391.56894 -152.00122 -90)
		(property "Reference" "R2L10"
			(at 0 0 90)
			(layer "B.SilkS")
			(hide yes)
			(effects
				(font
					(size 1.27 1.27)
				)
				(justify mirror)
			)
		)
		(property "Value" ""
			(at 0 0 90)
			(layer "B.Fab")
			(effects
				(font
					(size 1.27 1.27)
				)
				(justify mirror)
			)
		)
		(duplicate_pad_numbers_are_jumpers no)
		(fp_poly
			(pts
				(xy 0.2794 -0.1016) (xy -0.2794 -0.1016) (xy -0.2794 0.9906) (xy 0.2794 0.9906)
			)
			(stroke
				(width 0)
				(type default)
			)
			(fill no)
			(layer "B.CrtYd")
		)
		(fp_line
			(start -0.2794 0.9906)
			(end -0.2794 -0.1016)
			(stroke
				(width 0.1)
				(type default)
			)
			(layer "B.Fab")
		)
		(fp_line
			(start 0.2794 0.9906)
			(end -0.2794 0.9906)
			(stroke
				(width 0.1)
				(type default)
			)
			(layer "B.Fab")
		)
		(fp_line
			(start -0.2794 -0.1016)
			(end 0.2794 -0.1016)
			(stroke
				(width 0.1)
				(type default)
			)
			(layer "B.Fab")
		)
		(fp_line
			(start 0.2794 -0.1016)
			(end 0.2794 0.9906)
			(stroke
				(width 0.1)
				(type default)
			)
			(layer "B.Fab")
		)
		(pad "1" smd rect
			(at 0 0 90)
			(size 0.508 0.508)
			(layers "B.Cu" "B.Mask" "B.Paste")
			(net "VR_PVNN_PCH_VINSEN")
		)
		(pad "2" smd rect
			(at 0 0.889 90)
			(size 0.508 0.508)
			(layers "B.Cu" "B.Mask" "B.Paste")
			(net "GND")
		)
		(zone
			(layer "B.Cu")
			(hatch none 0.5)
			(connect_pads
				(clearance 0)
			)
			(min_thickness 0.25)
			(keepout
				(tracks not_allowed)
				(vias allowed)
				(pads allowed)
				(copperpour not_allowed)
				(footprints allowed)
			)
			(placement
				(enabled no)
				(sheetname "")
			)
			(fill
				(thermal_gap 0.5)
				(thermal_bridge_width 0.5)
				(island_removal_mode 0)
			)
			(polygon
				(pts
					(xy 390.93394 -151.74722) (xy 390.93394 -152.25522) (xy 391.31494 -152.25522) (xy 391.31494 -151.74722)
				)
			)
		)
		(zone
			(layer "B.Cu")
			(hatch none 0.5)
			(connect_pads
				(clearance 0)
			)
			(min_thickness 0.25)
			(keepout
				(tracks allowed)
				(vias not_allowed)
				(pads allowed)
				(copperpour not_allowed)
				(footprints allowed)
			)
			(placement
				(enabled no)
				(sheetname "")
			)
			(fill
				(thermal_gap 0.5)
				(thermal_bridge_width 0.5)
				(island_removal_mode 0)
			)
			(polygon
				(pts
					(xy 391.31494 -151.74722) (xy 391.31494 -152.25522) (xy 390.93394 -152.25522) (xy 390.93394 -151.74722)
				)
			)
		)
	)
	(footprint ""
		(layer "B.Cu")
		(at 382.176274 -153.328624)
		(property "Reference" "C3L29"
			(at 0 0 0)
			(layer "B.SilkS")
			(hide yes)
			(effects
				(font
					(size 1.27 1.27)
				)
				(justify mirror)
			)
		)
		(property "Value" "*"
			(at -1.1811 -2.8194 0)
			(unlocked yes)
			(layer "B.Fab")
			(hide yes)
			(effects
				(font
					(size 1.27 1.016)
					(thickness 0.1524)
				)
				(justify mirror)
			)
		)
		(property "Device Type" "SC1U10V2KX-4-GP_SMD-BCG6-SC1U1A"
			(at -1.1811 -4.3434 0)
			(unlocked yes)
			(layer "B.Fab")
			(hide yes)
			(effects
				(font
					(size 1.27 1.016)
					(thickness 0.1524)
				)
				(justify mirror)
			)
		)
		(duplicate_pad_numbers_are_jumpers no)
		(fp_rect
			(start 0.4318 0.9525)
			(end -0.4318 -0.9525)
			(stroke
				(width 0)
				(type default)
			)
			(fill no)
			(layer "B.CrtYd")
		)
		(fp_rect
			(start 0.4318 0.9525)
			(end -0.4318 -0.9525)
			(stroke
				(width 0)
				(type default)
			)
			(fill no)
			(layer "B.Fab")
		)
		(pad "1" smd custom
			(at 0 -0.4445 180)
			(size 0.1524 0.1524)
			(layers "B.Cu" "B.Mask" "B.Paste")
			(net "P5V_STBY")
			(options
				(clearance outline)
				(anchor circle)
			)
			(primitives
				(gr_poly
					(pts
						(arc
							(start 0.3048 0.2032)
							(mid 0.275042 0.275042)
							(end 0.2032 0.3048)
						)
						(arc
							(start -0.2032 0.3048)
							(mid -0.275042 0.275042)
							(end -0.3048 0.2032)
						)
						(arc
							(start -0.3048 -0.2032)
							(mid -0.275042 -0.275042)
							(end -0.2032 -0.3048)
						)
						(arc
							(start 0.2032 -0.3048)
							(mid 0.275042 -0.275042)
							(end 0.3048 -0.2032)
						)
					)
					(width 0)
					(fill yes)
				)
			)
		)
		(pad "2" smd custom
			(at 0 0.4445 180)
			(size 0.1524 0.1524)
			(layers "B.Cu" "B.Mask" "B.Paste")
			(net "GND")
			(options
				(clearance outline)
				(anchor circle)
			)
			(primitives
				(gr_poly
					(pts
						(arc
							(start 0.3048 0.2032)
							(mid 0.275042 0.275042)
							(end 0.2032 0.3048)
						)
						(arc
							(start -0.2032 0.3048)
							(mid -0.275042 0.275042)
							(end -0.3048 0.2032)
						)
						(arc
							(start -0.3048 -0.2032)
							(mid -0.275042 -0.275042)
							(end -0.2032 -0.3048)
						)
						(arc
							(start 0.2032 -0.3048)
							(mid 0.275042 -0.275042)
							(end 0.3048 -0.2032)
						)
					)
					(width 0)
					(fill yes)
				)
			)
		)
	)
	(footprint ""
		(layer "B.Cu")
		(at -0.889 -132.334)
		(property "Reference" "R9M9"
			(at 0 0 0)
			(layer "B.SilkS")
			(hide yes)
			(effects
				(font
					(size 1.27 1.27)
				)
				(justify mirror)
			)
		)
		(property "Value" ""
			(at 0 0 0)
			(layer "B.Fab")
			(effects
				(font
					(size 1.27 1.27)
				)
				(justify mirror)
			)
		)
		(duplicate_pad_numbers_are_jumpers no)
		(fp_poly
			(pts
				(xy 0.2794 -0.1016) (xy -0.2794 -0.1016) (xy -0.2794 0.9906) (xy 0.2794 0.9906)
			)
			(stroke
				(width 0)
				(type default)
			)
			(fill no)
			(layer "B.CrtYd")
		)
		(fp_line
			(start -0.2794 -0.1016)
			(end 0.2794 -0.1016)
			(stroke
				(width 0.1)
				(type default)
			)
			(layer "B.Fab")
		)
		(fp_line
			(start -0.2794 0.9906)
			(end -0.2794 -0.1016)
			(stroke
				(width 0.1)
				(type default)
			)
			(layer "B.Fab")
		)
		(fp_line
			(start 0.2794 -0.1016)
			(end 0.2794 0.9906)
			(stroke
				(width 0.1)
				(type default)
			)
			(layer "B.Fab")
		)
		(fp_line
			(start 0.2794 0.9906)
			(end -0.2794 0.9906)
			(stroke
				(width 0.1)
				(type default)
			)
			(layer "B.Fab")
		)
		(pad "1" smd rect
			(at 0 0 180)
			(size 0.508 0.508)
			(layers "B.Cu" "B.Mask" "B.Paste")
			(net "FM_PVDDQ_KLM_EN")
		)
		(pad "2" smd rect
			(at 0 0.889 180)
			(size 0.508 0.508)
			(layers "B.Cu" "B.Mask" "B.Paste")
			(net "VR_PVDDQ_KLM_VREN")
		)
		(zone
			(layer "B.Cu")
			(hatch none 0.5)
			(connect_pads
				(clearance 0)
			)
			(min_thickness 0.25)
			(keepout
				(tracks allowed)
				(vias not_allowed)
				(pads allowed)
				(copperpour not_allowed)
				(footprints allowed)
			)
			(placement
				(enabled no)
				(sheetname "")
			)
			(fill
				(thermal_gap 0.5)
				(thermal_bridge_width 0.5)
				(island_removal_mode 0)
			)
			(polygon
				(pts
					(xy -0.635 -132.08) (xy -1.143 -132.08) (xy -1.143 -131.699) (xy -0.635 -131.699)
				)
			)
		)
		(zone
			(layer "B.Cu")
			(hatch none 0.5)
			(connect_pads
				(clearance 0)
			)
			(min_thickness 0.25)
			(keepout
				(tracks not_allowed)
				(vias allowed)
				(pads allowed)
				(copperpour not_allowed)
				(footprints allowed)
			)
			(placement
				(enabled no)
				(sheetname "")
			)
			(fill
				(thermal_gap 0.5)
				(thermal_bridge_width 0.5)
				(island_removal_mode 0)
			)
			(polygon
				(pts
					(xy -0.635 -131.699) (xy -1.143 -131.699) (xy -1.143 -132.08) (xy -0.635 -132.08)
				)
			)
		)
	)
	(footprint ""
		(layer "B.Cu")
		(at 276.606 -26.868374 90)
		(property "Reference" "C4T4"
			(at 0 0 90)
			(layer "B.SilkS")
			(hide yes)
			(effects
				(font
					(size 1.27 1.27)
				)
				(justify mirror)
			)
		)
		(property "Value" ""
			(at 0 0 90)
			(layer "B.Fab")
			(effects
				(font
					(size 1.27 1.27)
				)
				(justify mirror)
			)
		)
		(duplicate_pad_numbers_are_jumpers no)
		(fp_rect
			(start 0.7239 1.9939)
			(end -0.7239 -0.2159)
			(stroke
				(width 0)
				(type default)
			)
			(fill no)
			(layer "B.CrtYd")
		)
		(fp_line
			(start 0.7239 -0.2159)
			(end 0.7239 1.9939)
			(stroke
				(width 0.1)
				(type default)
			)
			(layer "B.Fab")
		)
		(fp_line
			(start -0.7239 -0.2159)
			(end 0.7239 -0.2159)
			(stroke
				(width 0.1)
				(type default)
			)
			(layer "B.Fab")
		)
		(fp_line
			(start 0.7239 1.9939)
			(end -0.7239 1.9939)
			(stroke
				(width 0.1)
				(type default)
			)
			(layer "B.Fab")
		)
		(fp_line
			(start -0.7239 1.9939)
			(end -0.7239 -0.2159)
			(stroke
				(width 0.1)
				(type default)
			)
			(layer "B.Fab")
		)
		(pad "1" smd rect
			(at 0 0 270)
			(size 1.27 1.016)
			(layers "B.Cu" "B.Mask" "B.Paste")
			(net "PVDDQ_ABC")
		)
		(pad "2" smd rect
			(at 0 1.778 270)
			(size 1.27 1.016)
			(layers "B.Cu" "B.Mask" "B.Paste")
			(net "GND")
		)
		(zone
			(layer "B.Cu")
			(hatch none 0.5)
			(connect_pads
				(clearance 0)
			)
			(min_thickness 0.25)
			(keepout
				(tracks not_allowed)
				(vias allowed)
				(pads allowed)
				(copperpour not_allowed)
				(footprints allowed)
			)
			(placement
				(enabled no)
				(sheetname "")
			)
			(fill
				(thermal_gap 0.5)
				(thermal_bridge_width 0.5)
				(island_removal_mode 0)
			)
			(polygon
				(pts
					(xy 277.876 -27.503374) (xy 277.114 -27.503374) (xy 277.114 -26.233374) (xy 277.876 -26.233374)
				)
			)
		)
	)
	(footprint ""
		(layer "B.Cu")
		(at 462.801208 -145.415254)
		(property "Reference" "R1L23"
			(at 0 0 0)
			(layer "B.SilkS")
			(hide yes)
			(effects
				(font
					(size 1.27 1.27)
				)
				(justify mirror)
			)
		)
		(property "Value" ""
			(at 0 0 0)
			(layer "B.Fab")
			(effects
				(font
					(size 1.27 1.27)
				)
				(justify mirror)
			)
		)
		(duplicate_pad_numbers_are_jumpers no)
		(fp_poly
			(pts
				(xy 0.2794 -0.1016) (xy -0.2794 -0.1016) (xy -0.2794 0.9906) (xy 0.2794 0.9906)
			)
			(stroke
				(width 0)
				(type default)
			)
			(fill no)
			(layer "B.CrtYd")
		)
		(fp_line
			(start -0.2794 -0.1016)
			(end 0.2794 -0.1016)
			(stroke
				(width 0.1)
				(type default)
			)
			(layer "B.Fab")
		)
		(fp_line
			(start -0.2794 0.9906)
			(end -0.2794 -0.1016)
			(stroke
				(width 0.1)
				(type default)
			)
			(layer "B.Fab")
		)
		(fp_line
			(start 0.2794 -0.1016)
			(end 0.2794 0.9906)
			(stroke
				(width 0.1)
				(type default)
			)
			(layer "B.Fab")
		)
		(fp_line
			(start 0.2794 0.9906)
			(end -0.2794 0.9906)
			(stroke
				(width 0.1)
				(type default)
			)
			(layer "B.Fab")
		)
		(pad "1" smd rect
			(at 0 0 180)
			(size 0.508 0.508)
			(layers "B.Cu" "B.Mask" "B.Paste")
			(net "XDP_PWRGD_RST_N")
		)
		(pad "2" smd rect
			(at 0 0.889 180)
			(size 0.508 0.508)
			(layers "B.Cu" "B.Mask" "B.Paste")
			(net "P3V3_STBY")
		)
		(zone
			(layer "B.Cu")
			(hatch none 0.5)
			(connect_pads
				(clearance 0)
			)
			(min_thickness 0.25)
			(keepout
				(tracks allowed)
				(vias not_allowed)
				(pads allowed)
				(copperpour not_allowed)
				(footprints allowed)
			)
			(placement
				(enabled no)
				(sheetname "")
			)
			(fill
				(thermal_gap 0.5)
				(thermal_bridge_width 0.5)
				(island_removal_mode 0)
			)
			(polygon
				(pts
					(xy 463.055208 -145.161254) (xy 462.547208 -145.161254) (xy 462.547208 -144.780254) (xy 463.055208 -144.780254)
				)
			)
		)
		(zone
			(layer "B.Cu")
			(hatch none 0.5)
			(connect_pads
				(clearance 0)
			)
			(min_thickness 0.25)
			(keepout
				(tracks not_allowed)
				(vias allowed)
				(pads allowed)
				(copperpour not_allowed)
				(footprints allowed)
			)
			(placement
				(enabled no)
				(sheetname "")
			)
			(fill
				(thermal_gap 0.5)
				(thermal_bridge_width 0.5)
				(island_removal_mode 0)
			)
			(polygon
				(pts
					(xy 463.055208 -144.780254) (xy 462.547208 -144.780254) (xy 462.547208 -145.161254) (xy 463.055208 -145.161254)
				)
			)
		)
	)
	(footprint ""
		(layer "B.Cu")
		(at 333.291688 -124.887482 90)
		(property "Reference" "C4M6"
			(at -0.15367 10.5918 0)
			(unlocked yes)
			(layer "B.SilkS")
			(effects
				(font
					(size 0.7874 0.5842)
					(thickness 0.1524)
				)
				(justify mirror)
			)
		)
		(property "Value" ""
			(at 0 0 90)
			(layer "B.Fab")
			(effects
				(font
					(size 1.27 1.27)
				)
				(justify mirror)
			)
		)
		(duplicate_pad_numbers_are_jumpers no)
		(fp_line
			(start 2.563114 -1.616456)
			(end 2.563114 1.633728)
			(stroke
				(width 0.1524)
				(type default)
			)
			(layer "B.SilkS")
		)
		(fp_line
			(start 1.6002 -1.616456)
			(end 2.563114 -1.616456)
			(stroke
				(width 0.1524)
				(type default)
			)
			(layer "B.SilkS")
		)
		(fp_line
			(start -1.6002 -1.616456)
			(end -2.504948 -1.616456)
			(stroke
				(width 0.1524)
				(type default)
			)
			(layer "B.SilkS")
		)
		(fp_line
			(start -2.504948 -1.616456)
			(end -2.504948 1.633728)
			(stroke
				(width 0.1524)
				(type default)
			)
			(layer "B.SilkS")
		)
		(fp_line
			(start 2.563114 1.633728)
			(end 1.6002 1.633728)
			(stroke
				(width 0.1524)
				(type default)
			)
			(layer "B.SilkS")
		)
		(fp_line
			(start -2.504948 1.633728)
			(end -1.6002 1.633728)
			(stroke
				(width 0.1524)
				(type default)
			)
			(layer "B.SilkS")
		)
		(fp_line
			(start 2.286 7.366)
			(end 2.286 1.632712)
			(stroke
				(width 0.1524)
				(type default)
			)
			(layer "B.SilkS")
		)
		(fp_line
			(start 2.286 7.366)
			(end 1.60147 7.366)
			(stroke
				(width 0.1524)
				(type default)
			)
			(layer "B.SilkS")
		)
		(fp_line
			(start -2.286 7.366)
			(end -2.286 1.63195)
			(stroke
				(width 0.1524)
				(type default)
			)
			(layer "B.SilkS")
		)
		(fp_line
			(start -2.286 7.366)
			(end -1.600708 7.366)
			(stroke
				(width 0.1524)
				(type default)
			)
			(layer "B.SilkS")
		)
		(fp_rect
			(start 2.286 7.366)
			(end -2.286 -0.254)
			(stroke
				(width 0)
				(type default)
			)
			(fill no)
			(layer "B.CrtYd")
		)
		(fp_line
			(start 2.286 -0.254)
			(end -2.286 -0.254)
			(stroke
				(width 0.1)
				(type default)
			)
			(layer "B.Fab")
		)
		(fp_line
			(start -2.286 -0.254)
			(end -2.286 7.366)
			(stroke
				(width 0.1)
				(type default)
			)
			(layer "B.Fab")
		)
		(fp_line
			(start 2.286 7.366)
			(end 2.286 -0.254)
			(stroke
				(width 0.1)
				(type default)
			)
			(layer "B.Fab")
		)
		(fp_line
			(start -2.286 7.366)
			(end 2.286 7.366)
			(stroke
				(width 0.1)
				(type default)
			)
			(layer "B.Fab")
		)
		(pad "1" smd rect
			(at 0 0 270)
			(size 2.54 3.048)
			(layers "B.Cu" "B.Mask" "B.Paste")
			(net "P12V_STBY")
		)
		(pad "2" smd rect
			(at 0 7.112 270)
			(size 2.54 3.048)
			(layers "B.Cu" "B.Mask" "B.Paste")
			(net "GND")
		)
	)
	(footprint ""
		(layer "B.Cu")
		(at 389.33755 -114.25555 180)
		(property "Reference" "C2M19"
			(at 0 0 0)
			(layer "B.SilkS")
			(hide yes)
			(effects
				(font
					(size 1.27 1.27)
				)
				(justify mirror)
			)
		)
		(property "Value" ""
			(at 0 0 0)
			(layer "B.Fab")
			(effects
				(font
					(size 1.27 1.27)
				)
				(justify mirror)
			)
		)
		(duplicate_pad_numbers_are_jumpers no)
		(fp_rect
			(start 0.2794 0.9144)
			(end -0.2794 -0.1143)
			(stroke
				(width 0)
				(type default)
			)
			(fill no)
			(layer "B.CrtYd")
		)
		(fp_line
			(start 0.2794 0.9144)
			(end 0.2794 -0.1143)
			(stroke
				(width 0.1)
				(type default)
			)
			(layer "B.Fab")
		)
		(fp_line
			(start 0.2794 -0.1143)
			(end -0.2794 -0.1143)
			(stroke
				(width 0.1)
				(type default)
			)
			(layer "B.Fab")
		)
		(fp_line
			(start -0.2794 0.9144)
			(end 0.2794 0.9144)
			(stroke
				(width 0.1)
				(type default)
			)
			(layer "B.Fab")
		)
		(fp_line
			(start -0.2794 -0.1143)
			(end -0.2794 0.9144)
			(stroke
				(width 0.1)
				(type default)
			)
			(layer "B.Fab")
		)
		(pad "1" smd custom
			(at 0 0 90)
			(size 0.10414 0.10414)
			(layers "B.Cu" "B.Mask" "B.Paste")
			(net "P1V05_PCH_STBY")
			(options
				(clearance outline)
				(anchor circle)
			)
			(primitives
				(gr_poly
					(pts
						(xy -0.20828 -0.08636) (xy -0.20828 0.08636) (xy -0.08636 0.20828) (xy 0.086614 0.20828) (xy 0.20828 0.086614)
						(xy 0.20828 -0.08636) (xy 0.08636 -0.20828) (xy -0.08636 -0.20828)
					)
					(width 0)
					(fill yes)
				)
			)
		)
		(pad "2" smd custom
			(at 0 0.8001 90)
			(size 0.10414 0.10414)
			(layers "B.Cu" "B.Mask" "B.Paste")
			(net "GND")
			(options
				(clearance outline)
				(anchor circle)
			)
			(primitives
				(gr_poly
					(pts
						(xy -0.20828 -0.08636) (xy -0.20828 0.08636) (xy -0.08636 0.20828) (xy 0.086614 0.20828) (xy 0.20828 0.086614)
						(xy 0.20828 -0.08636) (xy 0.08636 -0.20828) (xy -0.08636 -0.20828)
					)
					(width 0)
					(fill yes)
				)
			)
		)
		(zone
			(layer "B.Cu")
			(hatch none 0.5)
			(connect_pads
				(clearance 0)
			)
			(min_thickness 0.25)
			(keepout
				(tracks allowed)
				(vias not_allowed)
				(pads allowed)
				(copperpour not_allowed)
				(footprints allowed)
			)
			(placement
				(enabled no)
				(sheetname "")
			)
			(fill
				(thermal_gap 0.5)
				(thermal_bridge_width 0.5)
				(island_removal_mode 0)
			)
			(polygon
				(pts
					(xy 389.24992 -114.4651) (xy 389.24992 -114.8461) (xy 389.42518 -114.8461) (xy 389.425434 -114.4651)
				)
			)
		)
		(zone
			(layer "B.Cu")
			(hatch none 0.5)
			(connect_pads
				(clearance 0)
			)
			(min_thickness 0.25)
			(keepout
				(tracks not_allowed)
				(vias allowed)
				(pads allowed)
				(copperpour not_allowed)
				(footprints allowed)
			)
			(placement
				(enabled no)
				(sheetname "")
			)
			(fill
				(thermal_gap 0.5)
				(thermal_bridge_width 0.5)
				(island_removal_mode 0)
			)
			(polygon
				(pts
					(xy 389.24992 -114.4651) (xy 389.24992 -114.8461) (xy 389.42518 -114.8461) (xy 389.425434 -114.4651)
				)
			)
		)
	)
	(footprint ""
		(layer "B.Cu")
		(at 490.5375 -155.3337 -90)
		(property "Reference" "R1L12"
			(at 0 0 90)
			(layer "B.SilkS")
			(hide yes)
			(effects
				(font
					(size 1.27 1.27)
				)
				(justify mirror)
			)
		)
		(property "Value" ""
			(at 0 0 90)
			(layer "B.Fab")
			(effects
				(font
					(size 1.27 1.27)
				)
				(justify mirror)
			)
		)
		(duplicate_pad_numbers_are_jumpers no)
		(fp_poly
			(pts
				(xy 0.2794 -0.1016) (xy -0.2794 -0.1016) (xy -0.2794 0.9906) (xy 0.2794 0.9906)
			)
			(stroke
				(width 0)
				(type default)
			)
			(fill no)
			(layer "B.CrtYd")
		)
		(fp_line
			(start -0.2794 0.9906)
			(end -0.2794 -0.1016)
			(stroke
				(width 0.1)
				(type default)
			)
			(layer "B.Fab")
		)
		(fp_line
			(start 0.2794 0.9906)
			(end -0.2794 0.9906)
			(stroke
				(width 0.1)
				(type default)
			)
			(layer "B.Fab")
		)
		(fp_line
			(start -0.2794 -0.1016)
			(end 0.2794 -0.1016)
			(stroke
				(width 0.1)
				(type default)
			)
			(layer "B.Fab")
		)
		(fp_line
			(start 0.2794 -0.1016)
			(end 0.2794 0.9906)
			(stroke
				(width 0.1)
				(type default)
			)
			(layer "B.Fab")
		)
		(pad "1" smd rect
			(at 0 0 90)
			(size 0.508 0.508)
			(layers "B.Cu" "B.Mask" "B.Paste")
			(net "PWRGD_P3V3")
		)
		(pad "2" smd rect
			(at 0 0.889 90)
			(size 0.508 0.508)
			(layers "B.Cu" "B.Mask" "B.Paste")
			(net "PWRGD_P3V3_R")
		)
		(zone
			(layer "B.Cu")
			(hatch none 0.5)
			(connect_pads
				(clearance 0)
			)
			(min_thickness 0.25)
			(keepout
				(tracks not_allowed)
				(vias allowed)
				(pads allowed)
				(copperpour not_allowed)
				(footprints allowed)
			)
			(placement
				(enabled no)
				(sheetname "")
			)
			(fill
				(thermal_gap 0.5)
				(thermal_bridge_width 0.5)
				(island_removal_mode 0)
			)
			(polygon
				(pts
					(xy 489.9025 -155.0797) (xy 489.9025 -155.5877) (xy 490.2835 -155.5877) (xy 490.2835 -155.0797)
				)
			)
		)
		(zone
			(layer "B.Cu")
			(hatch none 0.5)
			(connect_pads
				(clearance 0)
			)
			(min_thickness 0.25)
			(keepout
				(tracks allowed)
				(vias not_allowed)
				(pads allowed)
				(copperpour not_allowed)
				(footprints allowed)
			)
			(placement
				(enabled no)
				(sheetname "")
			)
			(fill
				(thermal_gap 0.5)
				(thermal_bridge_width 0.5)
				(island_removal_mode 0)
			)
			(polygon
				(pts
					(xy 490.2835 -155.0797) (xy 490.2835 -155.5877) (xy 489.9025 -155.5877) (xy 489.9025 -155.0797)
				)
			)
		)
	)
	(footprint ""
		(layer "B.Cu")
		(at 245.7069 -12.954 -90)
		(property "Reference" "C5G41"
			(at -1.14681 0.76708 0)
			(unlocked yes)
			(layer "B.SilkS")
			(effects
				(font
					(size 0.7874 0.5842)
					(thickness 0.1524)
				)
				(justify mirror)
			)
		)
		(property "Value" ""
			(at 0 0 90)
			(layer "B.Fab")
			(effects
				(font
					(size 1.27 1.27)
				)
				(justify mirror)
			)
		)
		(duplicate_pad_numbers_are_jumpers no)
		(fp_rect
			(start 0.4953 1.6002)
			(end -0.4953 -0.2032)
			(stroke
				(width 0)
				(type default)
			)
			(fill no)
			(layer "B.CrtYd")
		)
		(fp_line
			(start -0.4953 1.6002)
			(end 0.4953 1.6002)
			(stroke
				(width 0.1)
				(type default)
			)
			(layer "B.Fab")
		)
		(fp_line
			(start 0.4953 1.6002)
			(end 0.4953 -0.2032)
			(stroke
				(width 0.1)
				(type default)
			)
			(layer "B.Fab")
		)
		(fp_line
			(start -0.4953 -0.2032)
			(end -0.4953 1.6002)
			(stroke
				(width 0.1)
				(type default)
			)
			(layer "B.Fab")
		)
		(fp_line
			(start 0.4953 -0.2032)
			(end -0.4953 -0.2032)
			(stroke
				(width 0.1)
				(type default)
			)
			(layer "B.Fab")
		)
		(pad "1" smd rect
			(at 0 0 90)
			(size 0.762 0.889)
			(layers "B.Cu" "B.Mask" "B.Paste")
			(net "PVDDQ_ABC")
		)
		(pad "2" smd rect
			(at 0 1.397 90)
			(size 0.762 0.889)
			(layers "B.Cu" "B.Mask" "B.Paste")
			(net "GND")
		)
		(zone
			(layer "B.Cu")
			(hatch none 0.5)
			(connect_pads
				(clearance 0)
			)
			(min_thickness 0.25)
			(keepout
				(tracks not_allowed)
				(vias allowed)
				(pads allowed)
				(copperpour not_allowed)
				(footprints allowed)
			)
			(placement
				(enabled no)
				(sheetname "")
			)
			(fill
				(thermal_gap 0.5)
				(thermal_bridge_width 0.5)
				(island_removal_mode 0)
			)
			(polygon
				(pts
					(xy 244.7544 -12.573) (xy 245.2624 -12.573) (xy 245.2624 -13.335) (xy 244.7544 -13.335)
				)
			)
		)
	)
	(footprint ""
		(layer "B.Cu")
		(at 488.22991 -60.818014 90)
		(property "Reference" "R30W3"
			(at 0.8382 -0.67818 90)
			(unlocked yes)
			(layer "B.SilkS")
			(effects
				(font
					(size 0.4064 0.254)
					(thickness 0.1524)
				)
				(justify left mirror)
			)
		)
		(property "Value" ""
			(at 0 0 90)
			(layer "B.Fab")
			(effects
				(font
					(size 1.27 1.27)
				)
				(justify mirror)
			)
		)
		(duplicate_pad_numbers_are_jumpers no)
		(fp_poly
			(pts
				(xy 0.2794 -0.1016) (xy -0.2794 -0.1016) (xy -0.2794 0.9906) (xy 0.2794 0.9906)
			)
			(stroke
				(width 0)
				(type default)
			)
			(fill no)
			(layer "B.CrtYd")
		)
		(fp_line
			(start 0.2794 -0.1016)
			(end 0.2794 0.9906)
			(stroke
				(width 0.1)
				(type default)
			)
			(layer "B.Fab")
		)
		(fp_line
			(start -0.2794 -0.1016)
			(end 0.2794 -0.1016)
			(stroke
				(width 0.1)
				(type default)
			)
			(layer "B.Fab")
		)
		(fp_line
			(start 0.2794 0.9906)
			(end -0.2794 0.9906)
			(stroke
				(width 0.1)
				(type default)
			)
			(layer "B.Fab")
		)
		(fp_line
			(start -0.2794 0.9906)
			(end -0.2794 -0.1016)
			(stroke
				(width 0.1)
				(type default)
			)
			(layer "B.Fab")
		)
		(pad "1" smd rect
			(at 0 0 270)
			(size 0.508 0.508)
			(layers "B.Cu" "B.Mask" "B.Paste")
			(net "USB3_P01_C_TXN")
		)
		(pad "2" smd rect
			(at 0 0.889 270)
			(size 0.508 0.508)
			(layers "B.Cu" "B.Mask" "B.Paste")
			(net "USB3_P01_FB_TXN")
		)
		(zone
			(layer "B.Cu")
			(hatch none 0.5)
			(connect_pads
				(clearance 0)
			)
			(min_thickness 0.25)
			(keepout
				(tracks allowed)
				(vias not_allowed)
				(pads allowed)
				(copperpour not_allowed)
				(footprints allowed)
			)
			(placement
				(enabled no)
				(sheetname "")
			)
			(fill
				(thermal_gap 0.5)
				(thermal_bridge_width 0.5)
				(island_removal_mode 0)
			)
			(polygon
				(pts
					(xy 488.48391 -61.072014) (xy 488.48391 -60.564014) (xy 488.86491 -60.564014) (xy 488.86491 -61.072014)
				)
			)
		)
		(zone
			(layer "B.Cu")
			(hatch none 0.5)
			(connect_pads
				(clearance 0)
			)
			(min_thickness 0.25)
			(keepout
				(tracks not_allowed)
				(vias allowed)
				(pads allowed)
				(copperpour not_allowed)
				(footprints allowed)
			)
			(placement
				(enabled no)
				(sheetname "")
			)
			(fill
				(thermal_gap 0.5)
				(thermal_bridge_width 0.5)
				(island_removal_mode 0)
			)
			(polygon
				(pts
					(xy 488.86491 -61.072014) (xy 488.86491 -60.564014) (xy 488.48391 -60.564014) (xy 488.48391 -61.072014)
				)
			)
		)
	)
	(footprint ""
		(layer "B.Cu")
		(at 282.259024 -72.679814 -90)
		(property "Reference" "R4P10"
			(at 0 0 90)
			(layer "B.SilkS")
			(hide yes)
			(effects
				(font
					(size 1.27 1.27)
				)
				(justify mirror)
			)
		)
		(property "Value" ""
			(at 0 0 90)
			(layer "B.Fab")
			(effects
				(font
					(size 1.27 1.27)
				)
				(justify mirror)
			)
		)
		(duplicate_pad_numbers_are_jumpers no)
		(fp_rect
			(start 0.2794 0.9906)
			(end -0.2794 -0.1016)
			(stroke
				(width 0)
				(type default)
			)
			(fill no)
			(layer "B.CrtYd")
		)
		(fp_line
			(start -0.2794 0.9906)
			(end -0.2794 -0.1016)
			(stroke
				(width 0.1)
				(type default)
			)
			(layer "B.Fab")
		)
		(fp_line
			(start 0.2794 0.9906)
			(end -0.2794 0.9906)
			(stroke
				(width 0.1)
				(type default)
			)
			(layer "B.Fab")
		)
		(fp_line
			(start -0.2794 -0.1016)
			(end 0.2794 -0.1016)
			(stroke
				(width 0.1)
				(type default)
			)
			(layer "B.Fab")
		)
		(fp_line
			(start 0.2794 -0.1016)
			(end 0.2794 0.9906)
			(stroke
				(width 0.1)
				(type default)
			)
			(layer "B.Fab")
		)
		(pad "1" smd rect
			(at 0 0 90)
			(size 0.508 0.508)
			(layers "B.Cu" "B.Mask" "B.Paste")
			(net "A_CPU0_ABC_RCOMP1")
		)
		(pad "2" smd rect
			(at 0 0.889 90)
			(size 0.508 0.508)
			(layers "B.Cu" "B.Mask" "B.Paste")
			(net "GND")
		)
		(zone
			(layer "B.Cu")
			(hatch none 0.5)
			(connect_pads
				(clearance 0)
			)
			(min_thickness 0.25)
			(keepout
				(tracks allowed)
				(vias not_allowed)
				(pads allowed)
				(copperpour not_allowed)
				(footprints allowed)
			)
			(placement
				(enabled no)
				(sheetname "")
			)
			(fill
				(thermal_gap 0.5)
				(thermal_bridge_width 0.5)
				(island_removal_mode 0)
			)
			(polygon
				(pts
					(xy 281.624024 -72.425814) (xy 282.005024 -72.425814) (xy 282.005024 -72.933814) (xy 281.624024 -72.933814)
				)
			)
		)
		(zone
			(layer "B.Cu")
			(hatch none 0.5)
			(connect_pads
				(clearance 0)
			)
			(min_thickness 0.25)
			(keepout
				(tracks not_allowed)
				(vias allowed)
				(pads allowed)
				(copperpour not_allowed)
				(footprints allowed)
			)
			(placement
				(enabled no)
				(sheetname "")
			)
			(fill
				(thermal_gap 0.5)
				(thermal_bridge_width 0.5)
				(island_removal_mode 0)
			)
			(polygon
				(pts
					(xy 281.624024 -72.425814) (xy 282.005024 -72.425814) (xy 282.005024 -72.933814) (xy 281.624024 -72.933814)
				)
			)
		)
	)
	(footprint ""
		(layer "B.Cu")
		(at 278.703024 -77.810614)
		(property "Reference" "C4P5"
			(at 0 0 0)
			(layer "B.SilkS")
			(hide yes)
			(effects
				(font
					(size 1.27 1.27)
				)
				(justify mirror)
			)
		)
		(property "Value" ""
			(at 0 0 0)
			(layer "B.Fab")
			(effects
				(font
					(size 1.27 1.27)
				)
				(justify mirror)
			)
		)
		(duplicate_pad_numbers_are_jumpers no)
		(fp_poly
			(pts
				(xy 0.7239 -0.2159) (xy -0.7239 -0.2159) (xy -0.7239 1.9939) (xy 0.7239 1.9939)
			)
			(stroke
				(width 0)
				(type default)
			)
			(fill no)
			(layer "B.CrtYd")
		)
		(fp_line
			(start -0.7239 -0.2159)
			(end 0.7239 -0.2159)
			(stroke
				(width 0.1)
				(type default)
			)
			(layer "B.Fab")
		)
		(fp_line
			(start -0.7239 1.9939)
			(end -0.7239 -0.2159)
			(stroke
				(width 0.1)
				(type default)
			)
			(layer "B.Fab")
		)
		(fp_line
			(start 0.7239 -0.2159)
			(end 0.7239 1.9939)
			(stroke
				(width 0.1)
				(type default)
			)
			(layer "B.Fab")
		)
		(fp_line
			(start 0.7239 1.9939)
			(end -0.7239 1.9939)
			(stroke
				(width 0.1)
				(type default)
			)
			(layer "B.Fab")
		)
		(pad "1" smd rect
			(at 0 0 180)
			(size 1.27 1.016)
			(layers "B.Cu" "B.Mask" "B.Paste")
			(net "PVCCMCP_CPU0")
		)
		(pad "2" smd rect
			(at 0 1.778 180)
			(size 1.27 1.016)
			(layers "B.Cu" "B.Mask" "B.Paste")
			(net "GND")
		)
		(zone
			(layer "B.Cu")
			(hatch none 0.5)
			(connect_pads
				(clearance 0)
			)
			(min_thickness 0.25)
			(keepout
				(tracks not_allowed)
				(vias allowed)
				(pads allowed)
				(copperpour not_allowed)
				(footprints allowed)
			)
			(placement
				(enabled no)
				(sheetname "")
			)
			(fill
				(thermal_gap 0.5)
				(thermal_bridge_width 0.5)
				(island_removal_mode 0)
			)
			(polygon
				(pts
					(xy 279.338024 -77.302614) (xy 278.068024 -77.302614) (xy 278.068024 -76.540614) (xy 279.338024 -76.540614)
				)
			)
		)
	)
	(footprint ""
		(layer "B.Cu")
		(at 169.770552 -22.654006 -90)
		(property "Reference" "R6T4"
			(at 0 0 90)
			(layer "B.SilkS")
			(hide yes)
			(effects
				(font
					(size 1.27 1.27)
				)
				(justify mirror)
			)
		)
		(property "Value" ""
			(at 0 0 90)
			(layer "B.Fab")
			(effects
				(font
					(size 1.27 1.27)
				)
				(justify mirror)
			)
		)
		(duplicate_pad_numbers_are_jumpers no)
		(fp_poly
			(pts
				(xy 0.2794 -0.1016) (xy -0.2794 -0.1016) (xy -0.2794 0.9906) (xy 0.2794 0.9906)
			)
			(stroke
				(width 0)
				(type default)
			)
			(fill no)
			(layer "B.CrtYd")
		)
		(fp_line
			(start -0.2794 0.9906)
			(end -0.2794 -0.1016)
			(stroke
				(width 0.1)
				(type default)
			)
			(layer "B.Fab")
		)
		(fp_line
			(start 0.2794 0.9906)
			(end -0.2794 0.9906)
			(stroke
				(width 0.1)
				(type default)
			)
			(layer "B.Fab")
		)
		(fp_line
			(start -0.2794 -0.1016)
			(end 0.2794 -0.1016)
			(stroke
				(width 0.1)
				(type default)
			)
			(layer "B.Fab")
		)
		(fp_line
			(start 0.2794 -0.1016)
			(end 0.2794 0.9906)
			(stroke
				(width 0.1)
				(type default)
			)
			(layer "B.Fab")
		)
		(pad "1" smd rect
			(at 0 0 90)
			(size 0.508 0.508)
			(layers "B.Cu" "B.Mask" "B.Paste")
			(net "SMB_DDR_GHJ_SDA_G_R")
		)
		(pad "2" smd rect
			(at 0 0.889 90)
			(size 0.508 0.508)
			(layers "B.Cu" "B.Mask" "B.Paste")
			(net "SMB_DDR_GHJ_SDA_G")
		)
		(zone
			(layer "B.Cu")
			(hatch none 0.5)
			(connect_pads
				(clearance 0)
			)
			(min_thickness 0.25)
			(keepout
				(tracks not_allowed)
				(vias allowed)
				(pads allowed)
				(copperpour not_allowed)
				(footprints allowed)
			)
			(placement
				(enabled no)
				(sheetname "")
			)
			(fill
				(thermal_gap 0.5)
				(thermal_bridge_width 0.5)
				(island_removal_mode 0)
			)
			(polygon
				(pts
					(xy 169.135552 -22.400006) (xy 169.135552 -22.908006) (xy 169.516552 -22.908006) (xy 169.516552 -22.400006)
				)
			)
		)
		(zone
			(layer "B.Cu")
			(hatch none 0.5)
			(connect_pads
				(clearance 0)
			)
			(min_thickness 0.25)
			(keepout
				(tracks allowed)
				(vias not_allowed)
				(pads allowed)
				(copperpour not_allowed)
				(footprints allowed)
			)
			(placement
				(enabled no)
				(sheetname "")
			)
			(fill
				(thermal_gap 0.5)
				(thermal_bridge_width 0.5)
				(island_removal_mode 0)
			)
			(polygon
				(pts
					(xy 169.516552 -22.400006) (xy 169.516552 -22.908006) (xy 169.135552 -22.908006) (xy 169.135552 -22.400006)
				)
			)
		)
	)
	(footprint ""
		(layer "B.Cu")
		(at 111.000032 -3.3528 90)
		(property "Reference" "C5G92"
			(at -1.14681 0.76708 180)
			(unlocked yes)
			(layer "B.SilkS")
			(effects
				(font
					(size 0.7874 0.5842)
					(thickness 0.1524)
				)
				(justify mirror)
			)
		)
		(property "Value" ""
			(at 0 0 90)
			(layer "B.Fab")
			(effects
				(font
					(size 1.27 1.27)
				)
				(justify mirror)
			)
		)
		(duplicate_pad_numbers_are_jumpers no)
		(fp_rect
			(start -0.4953 -0.2032)
			(end 0.4953 1.6002)
			(stroke
				(width 0)
				(type default)
			)
			(fill no)
			(layer "B.CrtYd")
		)
		(fp_line
			(start 0.4953 -0.2032)
			(end -0.4953 -0.2032)
			(stroke
				(width 0.1)
				(type default)
			)
			(layer "B.Fab")
		)
		(fp_line
			(start -0.4953 -0.2032)
			(end -0.4953 1.6002)
			(stroke
				(width 0.1)
				(type default)
			)
			(layer "B.Fab")
		)
		(fp_line
			(start 0.4953 1.6002)
			(end 0.4953 -0.2032)
			(stroke
				(width 0.1)
				(type default)
			)
			(layer "B.Fab")
		)
		(fp_line
			(start -0.4953 1.6002)
			(end 0.4953 1.6002)
			(stroke
				(width 0.1)
				(type default)
			)
			(layer "B.Fab")
		)
		(pad "1" smd rect
			(at 0 0 270)
			(size 0.762 0.889)
			(layers "B.Cu" "B.Mask" "B.Paste")
			(net "PVDDQ_GHJ")
		)
		(pad "2" smd rect
			(at 0 1.397 270)
			(size 0.762 0.889)
			(layers "B.Cu" "B.Mask" "B.Paste")
			(net "GND")
		)
		(zone
			(layer "B.Cu")
			(hatch none 0.5)
			(connect_pads
				(clearance 0)
			)
			(min_thickness 0.25)
			(keepout
				(tracks not_allowed)
				(vias allowed)
				(pads allowed)
				(copperpour not_allowed)
				(footprints allowed)
			)
			(placement
				(enabled no)
				(sheetname "")
			)
			(fill
				(thermal_gap 0.5)
				(thermal_bridge_width 0.5)
				(island_removal_mode 0)
			)
			(polygon
				(pts
					(xy 111.444532 -2.9718) (xy 111.952532 -2.9718) (xy 111.952532 -3.7338) (xy 111.444532 -3.7338)
				)
			)
		)
	)
	(footprint ""
		(layer "B.Cu")
		(at 441.119006 -43.54195 180)
		(property "Reference" "R25W50"
			(at 0 0 0)
			(layer "B.SilkS")
			(hide yes)
			(effects
				(font
					(size 1.27 1.27)
				)
				(justify mirror)
			)
		)
		(property "Value" "*"
			(at -0.064008 -4.108196 180)
			(unlocked yes)
			(layer "B.Fab")
			(hide yes)
			(effects
				(font
					(size 1.27 1.016)
					(thickness 0.1524)
				)
				(justify mirror)
			)
		)
		(property "Device Type" "120R2F-GP_RCL_GP-120R2F-GP,64.A"
			(at -0.064008 -5.632196 180)
			(unlocked yes)
			(layer "B.Fab")
			(hide yes)
			(effects
				(font
					(size 1.27 1.016)
					(thickness 0.1524)
				)
				(justify mirror)
			)
		)
		(duplicate_pad_numbers_are_jumpers no)
		(fp_line
			(start 0.508 -0.9398)
			(end 0.508 0.9398)
			(stroke
				(width 0.1524)
				(type default)
			)
			(layer "B.SilkS")
		)
		(fp_line
			(start -0.508 -0.9398)
			(end 0.508 -0.9398)
			(stroke
				(width 0.1524)
				(type default)
			)
			(layer "B.SilkS")
		)
		(fp_rect
			(start 0.508 0.9398)
			(end -0.508 -0.9398)
			(stroke
				(width 0)
				(type default)
			)
			(fill no)
			(layer "B.CrtYd")
		)
		(fp_rect
			(start 0.508 0.9398)
			(end -0.508 -0.9398)
			(stroke
				(width 0)
				(type default)
			)
			(fill no)
			(layer "B.Fab")
		)
		(pad "1" smd custom
			(at 0 -0.4445)
			(size 0.1397 0.1397)
			(layers "B.Cu" "B.Mask" "B.Paste")
			(net "BMC_M_A12")
			(options
				(clearance outline)
				(anchor circle)
			)
			(primitives
				(gr_poly
					(pts
						(arc
							(start -0.1778 0.2794)
							(mid -0.249642 0.249642)
							(end -0.2794 0.1778)
						)
						(arc
							(start -0.2794 -0.1778)
							(mid -0.249642 -0.249642)
							(end -0.1778 -0.2794)
						)
						(arc
							(start 0.1778 -0.2794)
							(mid 0.249642 -0.249642)
							(end 0.2794 -0.1778)
						)
						(arc
							(start 0.2794 0.1778)
							(mid 0.249642 0.249642)
							(end 0.1778 0.2794)
						)
					)
					(width 0)
					(fill yes)
				)
			)
		)
		(pad "2" smd custom
			(at 0 0.4445)
			(size 0.1397 0.1397)
			(layers "B.Cu" "B.Mask" "B.Paste")
			(net "P1V2_AUX_BMC")
			(options
				(clearance outline)
				(anchor circle)
			)
			(primitives
				(gr_poly
					(pts
						(arc
							(start -0.1778 0.2794)
							(mid -0.249642 0.249642)
							(end -0.2794 0.1778)
						)
						(arc
							(start -0.2794 -0.1778)
							(mid -0.249642 -0.249642)
							(end -0.1778 -0.2794)
						)
						(arc
							(start 0.1778 -0.2794)
							(mid 0.249642 -0.249642)
							(end 0.2794 -0.1778)
						)
						(arc
							(start 0.2794 0.1778)
							(mid 0.249642 0.249642)
							(end 0.1778 0.2794)
						)
					)
					(width 0)
					(fill yes)
				)
			)
		)
	)
	(footprint ""
		(layer "B.Cu")
		(at 407.9113 -8.763 90)
		(property "Reference" "R8D40"
			(at 0 0 90)
			(layer "B.SilkS")
			(hide yes)
			(effects
				(font
					(size 1.27 1.27)
				)
				(justify mirror)
			)
		)
		(property "Value" ""
			(at 0 0 90)
			(layer "B.Fab")
			(effects
				(font
					(size 1.27 1.27)
				)
				(justify mirror)
			)
		)
		(duplicate_pad_numbers_are_jumpers no)
		(fp_poly
			(pts
				(xy 0.2794 -0.1016) (xy -0.2794 -0.1016) (xy -0.2794 0.9906) (xy 0.2794 0.9906)
			)
			(stroke
				(width 0)
				(type default)
			)
			(fill no)
			(layer "B.CrtYd")
		)
		(fp_line
			(start 0.2794 -0.1016)
			(end 0.2794 0.9906)
			(stroke
				(width 0.1)
				(type default)
			)
			(layer "B.Fab")
		)
		(fp_line
			(start -0.2794 -0.1016)
			(end 0.2794 -0.1016)
			(stroke
				(width 0.1)
				(type default)
			)
			(layer "B.Fab")
		)
		(fp_line
			(start 0.2794 0.9906)
			(end -0.2794 0.9906)
			(stroke
				(width 0.1)
				(type default)
			)
			(layer "B.Fab")
		)
		(fp_line
			(start -0.2794 0.9906)
			(end -0.2794 -0.1016)
			(stroke
				(width 0.1)
				(type default)
			)
			(layer "B.Fab")
		)
		(pad "1" smd rect
			(at 0 0 270)
			(size 0.508 0.508)
			(layers "B.Cu" "B.Mask" "B.Paste")
			(net "A_PG_P12V_MAIN")
		)
		(pad "2" smd rect
			(at 0 0.889 270)
			(size 0.508 0.508)
			(layers "B.Cu" "B.Mask" "B.Paste")
			(net "GND")
		)
		(zone
			(layer "B.Cu")
			(hatch none 0.5)
			(connect_pads
				(clearance 0)
			)
			(min_thickness 0.25)
			(keepout
				(tracks allowed)
				(vias not_allowed)
				(pads allowed)
				(copperpour not_allowed)
				(footprints allowed)
			)
			(placement
				(enabled no)
				(sheetname "")
			)
			(fill
				(thermal_gap 0.5)
				(thermal_bridge_width 0.5)
				(island_removal_mode 0)
			)
			(polygon
				(pts
					(xy 408.1653 -9.017) (xy 408.1653 -8.509) (xy 408.5463 -8.509) (xy 408.5463 -9.017)
				)
			)
		)
		(zone
			(layer "B.Cu")
			(hatch none 0.5)
			(connect_pads
				(clearance 0)
			)
			(min_thickness 0.25)
			(keepout
				(tracks not_allowed)
				(vias allowed)
				(pads allowed)
				(copperpour not_allowed)
				(footprints allowed)
			)
			(placement
				(enabled no)
				(sheetname "")
			)
			(fill
				(thermal_gap 0.5)
				(thermal_bridge_width 0.5)
				(island_removal_mode 0)
			)
			(polygon
				(pts
					(xy 408.5463 -9.017) (xy 408.5463 -8.509) (xy 408.1653 -8.509) (xy 408.1653 -9.017)
				)
			)
		)
	)
	(footprint ""
		(layer "B.Cu")
		(at 411.861 -146.431 -90)
		(property "Reference" "C2L26"
			(at 0 0 90)
			(layer "B.SilkS")
			(hide yes)
			(effects
				(font
					(size 1.27 1.27)
				)
				(justify mirror)
			)
		)
		(property "Value" ""
			(at 0 0 90)
			(layer "B.Fab")
			(effects
				(font
					(size 1.27 1.27)
				)
				(justify mirror)
			)
		)
		(duplicate_pad_numbers_are_jumpers no)
		(fp_poly
			(pts
				(xy -0.3048 -0.1016) (xy -0.3048 0.9906) (xy 0.3048 0.9906) (xy 0.3048 -0.1016)
			)
			(stroke
				(width 0)
				(type default)
			)
			(fill no)
			(layer "B.CrtYd")
		)
		(fp_line
			(start -0.3048 0.9906)
			(end -0.3048 -0.1016)
			(stroke
				(width 0.1)
				(type default)
			)
			(layer "B.Fab")
		)
		(fp_line
			(start 0.3048 0.9906)
			(end -0.3048 0.9906)
			(stroke
				(width 0.1)
				(type default)
			)
			(layer "B.Fab")
		)
		(fp_line
			(start -0.3048 -0.1016)
			(end 0.3048 -0.1016)
			(stroke
				(width 0.1)
				(type default)
			)
			(layer "B.Fab")
		)
		(fp_line
			(start 0.3048 -0.1016)
			(end 0.3048 0.9906)
			(stroke
				(width 0.1)
				(type default)
			)
			(layer "B.Fab")
		)
		(pad "1" smd rect
			(at 0 0 90)
			(size 0.508 0.508)
			(layers "B.Cu" "B.Mask" "B.Paste")
			(net "SATA6G_P5_TX_C_DN")
		)
		(pad "2" smd rect
			(at 0 0.889 90)
			(size 0.508 0.508)
			(layers "B.Cu" "B.Mask" "B.Paste")
			(net "SATA6G_PCH_PCIE_UP_SATA_TXN<5>")
		)
		(zone
			(layer "B.Cu")
			(hatch none 0.5)
			(connect_pads
				(clearance 0)
			)
			(min_thickness 0.25)
			(keepout
				(tracks not_allowed)
				(vias allowed)
				(pads allowed)
				(copperpour not_allowed)
				(footprints allowed)
			)
			(placement
				(enabled no)
				(sheetname "")
			)
			(fill
				(thermal_gap 0.5)
				(thermal_bridge_width 0.5)
				(island_removal_mode 0)
			)
			(polygon
				(pts
					(xy 411.226 -146.177) (xy 411.226 -146.685) (xy 411.607 -146.685) (xy 411.607 -146.177)
				)
			)
		)
		(zone
			(layer "B.Cu")
			(hatch none 0.5)
			(connect_pads
				(clearance 0)
			)
			(min_thickness 0.25)
			(keepout
				(tracks allowed)
				(vias not_allowed)
				(pads allowed)
				(copperpour not_allowed)
				(footprints allowed)
			)
			(placement
				(enabled no)
				(sheetname "")
			)
			(fill
				(thermal_gap 0.5)
				(thermal_bridge_width 0.5)
				(island_removal_mode 0)
			)
			(polygon
				(pts
					(xy 411.607 -146.177) (xy 411.607 -146.685) (xy 411.226 -146.685) (xy 411.226 -146.177)
				)
			)
		)
	)
	(footprint ""
		(layer "B.Cu")
		(at 197.848728 -81.191862 90)
		(property "Reference" "C6P15"
			(at 0 0 90)
			(layer "B.SilkS")
			(hide yes)
			(effects
				(font
					(size 1.27 1.27)
				)
				(justify mirror)
			)
		)
		(property "Value" ""
			(at 0 0 90)
			(layer "B.Fab")
			(effects
				(font
					(size 1.27 1.27)
				)
				(justify mirror)
			)
		)
		(duplicate_pad_numbers_are_jumpers no)
		(fp_rect
			(start -0.7239 -0.2159)
			(end 0.7239 1.9939)
			(stroke
				(width 0)
				(type default)
			)
			(fill no)
			(layer "B.CrtYd")
		)
		(fp_line
			(start 0.7239 -0.2159)
			(end 0.7239 1.9939)
			(stroke
				(width 0.1)
				(type default)
			)
			(layer "B.Fab")
		)
		(fp_line
			(start -0.7239 -0.2159)
			(end 0.7239 -0.2159)
			(stroke
				(width 0.1)
				(type default)
			)
			(layer "B.Fab")
		)
		(fp_line
			(start 0.7239 1.9939)
			(end -0.7239 1.9939)
			(stroke
				(width 0.1)
				(type default)
			)
			(layer "B.Fab")
		)
		(fp_line
			(start -0.7239 1.9939)
			(end -0.7239 -0.2159)
			(stroke
				(width 0.1)
				(type default)
			)
			(layer "B.Fab")
		)
		(pad "1" smd rect
			(at 0 0 270)
			(size 1.27 1.016)
			(layers "B.Cu" "B.Mask" "B.Paste")
			(net "VR_FET_SW_P12V_STBY_PVCCIN_CPU0")
		)
		(pad "2" smd rect
			(at 0 1.778 270)
			(size 1.27 1.016)
			(layers "B.Cu" "B.Mask" "B.Paste")
			(net "GND")
		)
		(zone
			(layer "B.Cu")
			(hatch none 0.5)
			(connect_pads
				(clearance 0)
			)
			(min_thickness 0.25)
			(keepout
				(tracks not_allowed)
				(vias allowed)
				(pads allowed)
				(copperpour not_allowed)
				(footprints allowed)
			)
			(placement
				(enabled no)
				(sheetname "")
			)
			(fill
				(thermal_gap 0.5)
				(thermal_bridge_width 0.5)
				(island_removal_mode 0)
			)
			(polygon
				(pts
					(xy 198.356728 -80.556862) (xy 199.118728 -80.556862) (xy 199.118728 -81.826862) (xy 198.356728 -81.826862)
				)
			)
		)
	)
	(footprint ""
		(layer "B.Cu")
		(at 452.278242 -29.786326)
		(property "Reference" "C8D1"
			(at 0 0 0)
			(layer "B.SilkS")
			(hide yes)
			(effects
				(font
					(size 1.27 1.27)
				)
				(justify mirror)
			)
		)
		(property "Value" ""
			(at 0 0 0)
			(layer "B.Fab")
			(effects
				(font
					(size 1.27 1.27)
				)
				(justify mirror)
			)
		)
		(duplicate_pad_numbers_are_jumpers no)
		(fp_poly
			(pts
				(xy -0.3048 -0.1016) (xy -0.3048 0.9906) (xy 0.3048 0.9906) (xy 0.3048 -0.1016)
			)
			(stroke
				(width 0)
				(type default)
			)
			(fill no)
			(layer "B.CrtYd")
		)
		(fp_line
			(start -0.3048 -0.1016)
			(end 0.3048 -0.1016)
			(stroke
				(width 0.1)
				(type default)
			)
			(layer "B.Fab")
		)
		(fp_line
			(start -0.3048 0.9906)
			(end -0.3048 -0.1016)
			(stroke
				(width 0.1)
				(type default)
			)
			(layer "B.Fab")
		)
		(fp_line
			(start 0.3048 -0.1016)
			(end 0.3048 0.9906)
			(stroke
				(width 0.1)
				(type default)
			)
			(layer "B.Fab")
		)
		(fp_line
			(start 0.3048 0.9906)
			(end -0.3048 0.9906)
			(stroke
				(width 0.1)
				(type default)
			)
			(layer "B.Fab")
		)
		(pad "1" smd rect
			(at 0 0 180)
			(size 0.508 0.508)
			(layers "B.Cu" "B.Mask" "B.Paste")
			(net "P3V3_STBY")
		)
		(pad "2" smd rect
			(at 0 0.889 180)
			(size 0.508 0.508)
			(layers "B.Cu" "B.Mask" "B.Paste")
			(net "GND")
		)
		(zone
			(layer "B.Cu")
			(hatch none 0.5)
			(connect_pads
				(clearance 0)
			)
			(min_thickness 0.25)
			(keepout
				(tracks allowed)
				(vias not_allowed)
				(pads allowed)
				(copperpour not_allowed)
				(footprints allowed)
			)
			(placement
				(enabled no)
				(sheetname "")
			)
			(fill
				(thermal_gap 0.5)
				(thermal_bridge_width 0.5)
				(island_removal_mode 0)
			)
			(polygon
				(pts
					(xy 452.532242 -29.532326) (xy 452.024242 -29.532326) (xy 452.024242 -29.151326) (xy 452.532242 -29.151326)
				)
			)
		)
		(zone
			(layer "B.Cu")
			(hatch none 0.5)
			(connect_pads
				(clearance 0)
			)
			(min_thickness 0.25)
			(keepout
				(tracks not_allowed)
				(vias allowed)
				(pads allowed)
				(copperpour not_allowed)
				(footprints allowed)
			)
			(placement
				(enabled no)
				(sheetname "")
			)
			(fill
				(thermal_gap 0.5)
				(thermal_bridge_width 0.5)
				(island_removal_mode 0)
			)
			(polygon
				(pts
					(xy 452.532242 -29.151326) (xy 452.024242 -29.151326) (xy 452.024242 -29.532326) (xy 452.532242 -29.532326)
				)
			)
		)
	)
	(footprint ""
		(layer "B.Cu")
		(at 103.073454 -79.60614 180)
		(property "Reference" "C8P10"
			(at 0 0 0)
			(layer "B.SilkS")
			(hide yes)
			(effects
				(font
					(size 1.27 1.27)
				)
				(justify mirror)
			)
		)
		(property "Value" ""
			(at 0 0 0)
			(layer "B.Fab")
			(effects
				(font
					(size 1.27 1.27)
				)
				(justify mirror)
			)
		)
		(duplicate_pad_numbers_are_jumpers no)
		(fp_poly
			(pts
				(xy 0.7239 -0.2159) (xy -0.7239 -0.2159) (xy -0.7239 1.9939) (xy 0.7239 1.9939)
			)
			(stroke
				(width 0)
				(type default)
			)
			(fill no)
			(layer "B.CrtYd")
		)
		(fp_line
			(start 0.7239 1.9939)
			(end -0.7239 1.9939)
			(stroke
				(width 0.1)
				(type default)
			)
			(layer "B.Fab")
		)
		(fp_line
			(start 0.7239 -0.2159)
			(end 0.7239 1.9939)
			(stroke
				(width 0.1)
				(type default)
			)
			(layer "B.Fab")
		)
		(fp_line
			(start -0.7239 1.9939)
			(end -0.7239 -0.2159)
			(stroke
				(width 0.1)
				(type default)
			)
			(layer "B.Fab")
		)
		(fp_line
			(start -0.7239 -0.2159)
			(end 0.7239 -0.2159)
			(stroke
				(width 0.1)
				(type default)
			)
			(layer "B.Fab")
		)
		(pad "1" smd rect
			(at 0 0)
			(size 1.27 1.016)
			(layers "B.Cu" "B.Mask" "B.Paste")
			(net "PVCCIN_CPU1")
		)
		(pad "2" smd rect
			(at 0 1.778)
			(size 1.27 1.016)
			(layers "B.Cu" "B.Mask" "B.Paste")
			(net "GND")
		)
		(zone
			(layer "B.Cu")
			(hatch none 0.5)
			(connect_pads
				(clearance 0)
			)
			(min_thickness 0.25)
			(keepout
				(tracks not_allowed)
				(vias allowed)
				(pads allowed)
				(copperpour not_allowed)
				(footprints allowed)
			)
			(placement
				(enabled no)
				(sheetname "")
			)
			(fill
				(thermal_gap 0.5)
				(thermal_bridge_width 0.5)
				(island_removal_mode 0)
			)
			(polygon
				(pts
					(xy 102.438454 -80.11414) (xy 103.708454 -80.11414) (xy 103.708454 -80.87614) (xy 102.438454 -80.87614)
				)
			)
		)
	)
	(footprint ""
		(layer "B.Cu")
		(at 323.8627 -32.93618 -90)
		(property "Reference" "R4T3"
			(at 0 0 90)
			(layer "B.SilkS")
			(hide yes)
			(effects
				(font
					(size 1.27 1.27)
				)
				(justify mirror)
			)
		)
		(property "Value" ""
			(at 0 0 90)
			(layer "B.Fab")
			(effects
				(font
					(size 1.27 1.27)
				)
				(justify mirror)
			)
		)
		(duplicate_pad_numbers_are_jumpers no)
		(fp_poly
			(pts
				(xy 0.2794 -0.1016) (xy -0.2794 -0.1016) (xy -0.2794 0.9906) (xy 0.2794 0.9906)
			)
			(stroke
				(width 0)
				(type default)
			)
			(fill no)
			(layer "B.CrtYd")
		)
		(fp_line
			(start -0.2794 0.9906)
			(end -0.2794 -0.1016)
			(stroke
				(width 0.1)
				(type default)
			)
			(layer "B.Fab")
		)
		(fp_line
			(start 0.2794 0.9906)
			(end -0.2794 0.9906)
			(stroke
				(width 0.1)
				(type default)
			)
			(layer "B.Fab")
		)
		(fp_line
			(start -0.2794 -0.1016)
			(end 0.2794 -0.1016)
			(stroke
				(width 0.1)
				(type default)
			)
			(layer "B.Fab")
		)
		(fp_line
			(start 0.2794 -0.1016)
			(end 0.2794 0.9906)
			(stroke
				(width 0.1)
				(type default)
			)
			(layer "B.Fab")
		)
		(pad "1" smd rect
			(at 0 0 90)
			(size 0.508 0.508)
			(layers "B.Cu" "B.Mask" "B.Paste")
			(net "SMB_DDR_ABC_SCL_G_R")
		)
		(pad "2" smd rect
			(at 0 0.889 90)
			(size 0.508 0.508)
			(layers "B.Cu" "B.Mask" "B.Paste")
			(net "SMB_DDR_ABC_SCL_G")
		)
		(zone
			(layer "B.Cu")
			(hatch none 0.5)
			(connect_pads
				(clearance 0)
			)
			(min_thickness 0.25)
			(keepout
				(tracks not_allowed)
				(vias allowed)
				(pads allowed)
				(copperpour not_allowed)
				(footprints allowed)
			)
			(placement
				(enabled no)
				(sheetname "")
			)
			(fill
				(thermal_gap 0.5)
				(thermal_bridge_width 0.5)
				(island_removal_mode 0)
			)
			(polygon
				(pts
					(xy 323.2277 -32.68218) (xy 323.2277 -33.19018) (xy 323.6087 -33.19018) (xy 323.6087 -32.68218)
				)
			)
		)
		(zone
			(layer "B.Cu")
			(hatch none 0.5)
			(connect_pads
				(clearance 0)
			)
			(min_thickness 0.25)
			(keepout
				(tracks allowed)
				(vias not_allowed)
				(pads allowed)
				(copperpour not_allowed)
				(footprints allowed)
			)
			(placement
				(enabled no)
				(sheetname "")
			)
			(fill
				(thermal_gap 0.5)
				(thermal_bridge_width 0.5)
				(island_removal_mode 0)
			)
			(polygon
				(pts
					(xy 323.6087 -32.68218) (xy 323.6087 -33.19018) (xy 323.2277 -33.19018) (xy 323.2277 -32.68218)
				)
			)
		)
	)
	(footprint ""
		(layer "B.Cu")
		(at 406.908 -23.0505)
		(property "Reference" "R25W111"
			(at 0.8382 -0.67818 0)
			(unlocked yes)
			(layer "B.SilkS")
			(effects
				(font
					(size 0.4064 0.254)
					(thickness 0.1524)
				)
				(justify left mirror)
			)
		)
		(property "Value" ""
			(at 0 0 0)
			(layer "B.Fab")
			(effects
				(font
					(size 1.27 1.27)
				)
				(justify mirror)
			)
		)
		(duplicate_pad_numbers_are_jumpers no)
		(fp_poly
			(pts
				(xy 0.2794 -0.1016) (xy -0.2794 -0.1016) (xy -0.2794 0.9906) (xy 0.2794 0.9906)
			)
			(stroke
				(width 0)
				(type default)
			)
			(fill no)
			(layer "B.CrtYd")
		)
		(fp_line
			(start -0.2794 -0.1016)
			(end 0.2794 -0.1016)
			(stroke
				(width 0.1)
				(type default)
			)
			(layer "B.Fab")
		)
		(fp_line
			(start -0.2794 0.9906)
			(end -0.2794 -0.1016)
			(stroke
				(width 0.1)
				(type default)
			)
			(layer "B.Fab")
		)
		(fp_line
			(start 0.2794 -0.1016)
			(end 0.2794 0.9906)
			(stroke
				(width 0.1)
				(type default)
			)
			(layer "B.Fab")
		)
		(fp_line
			(start 0.2794 0.9906)
			(end -0.2794 0.9906)
			(stroke
				(width 0.1)
				(type default)
			)
			(layer "B.Fab")
		)
		(pad "1" smd rect
			(at 0 0 180)
			(size 0.508 0.508)
			(layers "B.Cu" "B.Mask" "B.Paste")
			(net "P3V3_STBY")
		)
		(pad "2" smd rect
			(at 0 0.889 180)
			(size 0.508 0.508)
			(layers "B.Cu" "B.Mask" "B.Paste")
			(net "RMII_BMC_PCH_SPRNGVLLE_TXEN")
		)
		(zone
			(layer "B.Cu")
			(hatch none 0.5)
			(connect_pads
				(clearance 0)
			)
			(min_thickness 0.25)
			(keepout
				(tracks allowed)
				(vias not_allowed)
				(pads allowed)
				(copperpour not_allowed)
				(footprints allowed)
			)
			(placement
				(enabled no)
				(sheetname "")
			)
			(fill
				(thermal_gap 0.5)
				(thermal_bridge_width 0.5)
				(island_removal_mode 0)
			)
			(polygon
				(pts
					(xy 407.162 -22.7965) (xy 406.654 -22.7965) (xy 406.654 -22.4155) (xy 407.162 -22.4155)
				)
			)
		)
		(zone
			(layer "B.Cu")
			(hatch none 0.5)
			(connect_pads
				(clearance 0)
			)
			(min_thickness 0.25)
			(keepout
				(tracks not_allowed)
				(vias allowed)
				(pads allowed)
				(copperpour not_allowed)
				(footprints allowed)
			)
			(placement
				(enabled no)
				(sheetname "")
			)
			(fill
				(thermal_gap 0.5)
				(thermal_bridge_width 0.5)
				(island_removal_mode 0)
			)
			(polygon
				(pts
					(xy 407.162 -22.4155) (xy 406.654 -22.4155) (xy 406.654 -22.7965) (xy 407.162 -22.7965)
				)
			)
		)
	)
	(footprint ""
		(layer "B.Cu")
		(at 482.4857 -148.93671)
		(property "Reference" "R6W49"
			(at 0.8382 -0.67818 0)
			(unlocked yes)
			(layer "B.SilkS")
			(effects
				(font
					(size 0.4064 0.254)
					(thickness 0.1524)
				)
				(justify left mirror)
			)
		)
		(property "Value" ""
			(at 0 0 0)
			(layer "B.Fab")
			(effects
				(font
					(size 1.27 1.27)
				)
				(justify mirror)
			)
		)
		(duplicate_pad_numbers_are_jumpers no)
		(fp_poly
			(pts
				(xy 0.2794 -0.1016) (xy -0.2794 -0.1016) (xy -0.2794 0.9906) (xy 0.2794 0.9906)
			)
			(stroke
				(width 0)
				(type default)
			)
			(fill no)
			(layer "B.CrtYd")
		)
		(fp_line
			(start -0.2794 -0.1016)
			(end 0.2794 -0.1016)
			(stroke
				(width 0.1)
				(type default)
			)
			(layer "B.Fab")
		)
		(fp_line
			(start -0.2794 0.9906)
			(end -0.2794 -0.1016)
			(stroke
				(width 0.1)
				(type default)
			)
			(layer "B.Fab")
		)
		(fp_line
			(start 0.2794 -0.1016)
			(end 0.2794 0.9906)
			(stroke
				(width 0.1)
				(type default)
			)
			(layer "B.Fab")
		)
		(fp_line
			(start 0.2794 0.9906)
			(end -0.2794 0.9906)
			(stroke
				(width 0.1)
				(type default)
			)
			(layer "B.Fab")
		)
		(pad "1" smd rect
			(at 0 0 180)
			(size 0.508 0.508)
			(layers "B.Cu" "B.Mask" "B.Paste")
			(net "FM_UART_SWITCH_N")
		)
		(pad "2" smd rect
			(at 0 0.889 180)
			(size 0.508 0.508)
			(layers "B.Cu" "B.Mask" "B.Paste")
			(net "FM_UART_SEL_N")
		)
		(zone
			(layer "B.Cu")
			(hatch none 0.5)
			(connect_pads
				(clearance 0)
			)
			(min_thickness 0.25)
			(keepout
				(tracks allowed)
				(vias not_allowed)
				(pads allowed)
				(copperpour not_allowed)
				(footprints allowed)
			)
			(placement
				(enabled no)
				(sheetname "")
			)
			(fill
				(thermal_gap 0.5)
				(thermal_bridge_width 0.5)
				(island_removal_mode 0)
			)
			(polygon
				(pts
					(xy 482.7397 -148.68271) (xy 482.2317 -148.68271) (xy 482.2317 -148.30171) (xy 482.7397 -148.30171)
				)
			)
		)
		(zone
			(layer "B.Cu")
			(hatch none 0.5)
			(connect_pads
				(clearance 0)
			)
			(min_thickness 0.25)
			(keepout
				(tracks not_allowed)
				(vias allowed)
				(pads allowed)
				(copperpour not_allowed)
				(footprints allowed)
			)
			(placement
				(enabled no)
				(sheetname "")
			)
			(fill
				(thermal_gap 0.5)
				(thermal_bridge_width 0.5)
				(island_removal_mode 0)
			)
			(polygon
				(pts
					(xy 482.7397 -148.30171) (xy 482.2317 -148.30171) (xy 482.2317 -148.68271) (xy 482.7397 -148.68271)
				)
			)
		)
	)
	(footprint ""
		(layer "B.Cu")
		(at 399.891758 -116.317014 180)
		(property "Reference" "R7W20"
			(at 0.8382 -0.67818 180)
			(unlocked yes)
			(layer "B.SilkS")
			(effects
				(font
					(size 0.4064 0.254)
					(thickness 0.1524)
				)
				(justify left mirror)
			)
		)
		(property "Value" ""
			(at 0 0 0)
			(layer "B.Fab")
			(effects
				(font
					(size 1.27 1.27)
				)
				(justify mirror)
			)
		)
		(duplicate_pad_numbers_are_jumpers no)
		(fp_poly
			(pts
				(xy 0.2794 -0.1016) (xy -0.2794 -0.1016) (xy -0.2794 0.9906) (xy 0.2794 0.9906)
			)
			(stroke
				(width 0)
				(type default)
			)
			(fill no)
			(layer "B.CrtYd")
		)
		(fp_line
			(start 0.2794 0.9906)
			(end -0.2794 0.9906)
			(stroke
				(width 0.1)
				(type default)
			)
			(layer "B.Fab")
		)
		(fp_line
			(start 0.2794 -0.1016)
			(end 0.2794 0.9906)
			(stroke
				(width 0.1)
				(type default)
			)
			(layer "B.Fab")
		)
		(fp_line
			(start -0.2794 0.9906)
			(end -0.2794 -0.1016)
			(stroke
				(width 0.1)
				(type default)
			)
			(layer "B.Fab")
		)
		(fp_line
			(start -0.2794 -0.1016)
			(end 0.2794 -0.1016)
			(stroke
				(width 0.1)
				(type default)
			)
			(layer "B.Fab")
		)
		(pad "1" smd rect
			(at 0 0)
			(size 0.508 0.508)
			(layers "B.Cu" "B.Mask" "B.Paste")
			(net "P3V3_STBY")
		)
		(pad "2" smd rect
			(at 0 0.889)
			(size 0.508 0.508)
			(layers "B.Cu" "B.Mask" "B.Paste")
			(net "FM_POST_CARD_PRES_BMC_R1_N")
		)
		(zone
			(layer "B.Cu")
			(hatch none 0.5)
			(connect_pads
				(clearance 0)
			)
			(min_thickness 0.25)
			(keepout
				(tracks not_allowed)
				(vias allowed)
				(pads allowed)
				(copperpour not_allowed)
				(footprints allowed)
			)
			(placement
				(enabled no)
				(sheetname "")
			)
			(fill
				(thermal_gap 0.5)
				(thermal_bridge_width 0.5)
				(island_removal_mode 0)
			)
			(polygon
				(pts
					(xy 399.637758 -116.952014) (xy 400.145758 -116.952014) (xy 400.145758 -116.571014) (xy 399.637758 -116.571014)
				)
			)
		)
		(zone
			(layer "B.Cu")
			(hatch none 0.5)
			(connect_pads
				(clearance 0)
			)
			(min_thickness 0.25)
			(keepout
				(tracks allowed)
				(vias not_allowed)
				(pads allowed)
				(copperpour not_allowed)
				(footprints allowed)
			)
			(placement
				(enabled no)
				(sheetname "")
			)
			(fill
				(thermal_gap 0.5)
				(thermal_bridge_width 0.5)
				(island_removal_mode 0)
			)
			(polygon
				(pts
					(xy 399.637758 -116.571014) (xy 400.145758 -116.571014) (xy 400.145758 -116.952014) (xy 399.637758 -116.952014)
				)
			)
		)
	)
	(footprint ""
		(layer "B.Cu")
		(at 404.43658 -141.783816 -90)
		(property "Reference" "C2L45"
			(at 0 0 90)
			(layer "B.SilkS")
			(hide yes)
			(effects
				(font
					(size 1.27 1.27)
				)
				(justify mirror)
			)
		)
		(property "Value" ""
			(at 0 0 90)
			(layer "B.Fab")
			(effects
				(font
					(size 1.27 1.27)
				)
				(justify mirror)
			)
		)
		(duplicate_pad_numbers_are_jumpers no)
		(fp_poly
			(pts
				(xy 0.7239 -0.2159) (xy -0.7239 -0.2159) (xy -0.7239 1.9939) (xy 0.7239 1.9939)
			)
			(stroke
				(width 0)
				(type default)
			)
			(fill no)
			(layer "B.CrtYd")
		)
		(fp_line
			(start -0.7239 1.9939)
			(end -0.7239 -0.2159)
			(stroke
				(width 0.1)
				(type default)
			)
			(layer "B.Fab")
		)
		(fp_line
			(start 0.7239 1.9939)
			(end -0.7239 1.9939)
			(stroke
				(width 0.1)
				(type default)
			)
			(layer "B.Fab")
		)
		(fp_line
			(start -0.7239 -0.2159)
			(end 0.7239 -0.2159)
			(stroke
				(width 0.1)
				(type default)
			)
			(layer "B.Fab")
		)
		(fp_line
			(start 0.7239 -0.2159)
			(end 0.7239 1.9939)
			(stroke
				(width 0.1)
				(type default)
			)
			(layer "B.Fab")
		)
		(pad "1" smd rect
			(at 0 0 90)
			(size 1.27 1.016)
			(layers "B.Cu" "B.Mask" "B.Paste")
			(net "P1V8_PCH_STBY")
		)
		(pad "2" smd rect
			(at 0 1.778 90)
			(size 1.27 1.016)
			(layers "B.Cu" "B.Mask" "B.Paste")
			(net "GND")
		)
		(zone
			(layer "B.Cu")
			(hatch none 0.5)
			(connect_pads
				(clearance 0)
			)
			(min_thickness 0.25)
			(keepout
				(tracks not_allowed)
				(vias allowed)
				(pads allowed)
				(copperpour not_allowed)
				(footprints allowed)
			)
			(placement
				(enabled no)
				(sheetname "")
			)
			(fill
				(thermal_gap 0.5)
				(thermal_bridge_width 0.5)
				(island_removal_mode 0)
			)
			(polygon
				(pts
					(xy 403.92858 -141.148816) (xy 403.92858 -142.418816) (xy 403.16658 -142.418816) (xy 403.16658 -141.148816)
				)
			)
		)
	)
	(footprint ""
		(layer "B.Cu")
		(at 401.32 -102.8319)
		(property "Reference" "C2N14"
			(at 0 0 0)
			(layer "B.SilkS")
			(hide yes)
			(effects
				(font
					(size 1.27 1.27)
				)
				(justify mirror)
			)
		)
		(property "Value" ""
			(at 0 0 0)
			(layer "B.Fab")
			(effects
				(font
					(size 1.27 1.27)
				)
				(justify mirror)
			)
		)
		(duplicate_pad_numbers_are_jumpers no)
		(fp_poly
			(pts
				(xy 0.4953 -0.2032) (xy -0.4953 -0.2032) (xy -0.4953 1.6002) (xy 0.4953 1.6002)
			)
			(stroke
				(width 0)
				(type default)
			)
			(fill no)
			(layer "B.CrtYd")
		)
		(fp_line
			(start -0.4953 -0.2032)
			(end -0.4953 1.6002)
			(stroke
				(width 0.1)
				(type default)
			)
			(layer "B.Fab")
		)
		(fp_line
			(start -0.4953 1.6002)
			(end 0.4953 1.6002)
			(stroke
				(width 0.1)
				(type default)
			)
			(layer "B.Fab")
		)
		(fp_line
			(start 0.4953 -0.2032)
			(end -0.4953 -0.2032)
			(stroke
				(width 0.1)
				(type default)
			)
			(layer "B.Fab")
		)
		(fp_line
			(start 0.4953 1.6002)
			(end 0.4953 -0.2032)
			(stroke
				(width 0.1)
				(type default)
			)
			(layer "B.Fab")
		)
		(pad "1" smd rect
			(at 0 0 180)
			(size 0.762 0.889)
			(layers "B.Cu" "B.Mask" "B.Paste")
			(net "P3V3_STBY")
		)
		(pad "2" smd rect
			(at 0 1.397 180)
			(size 0.762 0.889)
			(layers "B.Cu" "B.Mask" "B.Paste")
			(net "GND")
		)
		(zone
			(layer "B.Cu")
			(hatch none 0.5)
			(connect_pads
				(clearance 0)
			)
			(min_thickness 0.25)
			(keepout
				(tracks not_allowed)
				(vias allowed)
				(pads allowed)
				(copperpour not_allowed)
				(footprints allowed)
			)
			(placement
				(enabled no)
				(sheetname "")
			)
			(fill
				(thermal_gap 0.5)
				(thermal_bridge_width 0.5)
				(island_removal_mode 0)
			)
			(polygon
				(pts
					(xy 401.701 -102.3874) (xy 400.939 -102.3874) (xy 400.939 -101.8794) (xy 401.701 -101.8794)
				)
			)
		)
	)
	(footprint ""
		(layer "B.Cu")
		(at 338.934806 -61.257434)
		(property "Reference" "C2U7"
			(at 0 0 0)
			(layer "B.SilkS")
			(hide yes)
			(effects
				(font
					(size 1.27 1.27)
				)
				(justify mirror)
			)
		)
		(property "Value" ""
			(at 0 0 0)
			(layer "B.Fab")
			(effects
				(font
					(size 1.27 1.27)
				)
				(justify mirror)
			)
		)
		(duplicate_pad_numbers_are_jumpers no)
		(fp_poly
			(pts
				(xy -0.3048 -0.1016) (xy -0.3048 0.9906) (xy 0.3048 0.9906) (xy 0.3048 -0.1016)
			)
			(stroke
				(width 0)
				(type default)
			)
			(fill no)
			(layer "B.CrtYd")
		)
		(fp_line
			(start -0.3048 -0.1016)
			(end 0.3048 -0.1016)
			(stroke
				(width 0.1)
				(type default)
			)
			(layer "B.Fab")
		)
		(fp_line
			(start -0.3048 0.9906)
			(end -0.3048 -0.1016)
			(stroke
				(width 0.1)
				(type default)
			)
			(layer "B.Fab")
		)
		(fp_line
			(start 0.3048 -0.1016)
			(end 0.3048 0.9906)
			(stroke
				(width 0.1)
				(type default)
			)
			(layer "B.Fab")
		)
		(fp_line
			(start 0.3048 0.9906)
			(end -0.3048 0.9906)
			(stroke
				(width 0.1)
				(type default)
			)
			(layer "B.Fab")
		)
		(pad "1" smd rect
			(at 0 0 180)
			(size 0.508 0.508)
			(layers "B.Cu" "B.Mask" "B.Paste")
			(net "P3E_CPU0_PE1_PCH_RXP<2>")
		)
		(pad "2" smd rect
			(at 0 0.889 180)
			(size 0.508 0.508)
			(layers "B.Cu" "B.Mask" "B.Paste")
			(net "P3E_CPU0_PE1_SS_RXP<2>")
		)
		(zone
			(layer "B.Cu")
			(hatch none 0.5)
			(connect_pads
				(clearance 0)
			)
			(min_thickness 0.25)
			(keepout
				(tracks allowed)
				(vias not_allowed)
				(pads allowed)
				(copperpour not_allowed)
				(footprints allowed)
			)
			(placement
				(enabled no)
				(sheetname "")
			)
			(fill
				(thermal_gap 0.5)
				(thermal_bridge_width 0.5)
				(island_removal_mode 0)
			)
			(polygon
				(pts
					(xy 339.188806 -61.003434) (xy 338.680806 -61.003434) (xy 338.680806 -60.622434) (xy 339.188806 -60.622434)
				)
			)
		)
		(zone
			(layer "B.Cu")
			(hatch none 0.5)
			(connect_pads
				(clearance 0)
			)
			(min_thickness 0.25)
			(keepout
				(tracks not_allowed)
				(vias allowed)
				(pads allowed)
				(copperpour not_allowed)
				(footprints allowed)
			)
			(placement
				(enabled no)
				(sheetname "")
			)
			(fill
				(thermal_gap 0.5)
				(thermal_bridge_width 0.5)
				(island_removal_mode 0)
			)
			(polygon
				(pts
					(xy 339.188806 -60.622434) (xy 338.680806 -60.622434) (xy 338.680806 -61.003434) (xy 339.188806 -61.003434)
				)
			)
		)
	)
	(footprint ""
		(layer "B.Cu")
		(at 404.5585 -97.155 -90)
		(property "Reference" "R2N16"
			(at 0 0 90)
			(layer "B.SilkS")
			(hide yes)
			(effects
				(font
					(size 1.27 1.27)
				)
				(justify mirror)
			)
		)
		(property "Value" ""
			(at 0 0 90)
			(layer "B.Fab")
			(effects
				(font
					(size 1.27 1.27)
				)
				(justify mirror)
			)
		)
		(duplicate_pad_numbers_are_jumpers no)
		(fp_poly
			(pts
				(xy 0.2794 -0.1016) (xy -0.2794 -0.1016) (xy -0.2794 0.9906) (xy 0.2794 0.9906)
			)
			(stroke
				(width 0)
				(type default)
			)
			(fill no)
			(layer "B.CrtYd")
		)
		(fp_line
			(start -0.2794 0.9906)
			(end -0.2794 -0.1016)
			(stroke
				(width 0.1)
				(type default)
			)
			(layer "B.Fab")
		)
		(fp_line
			(start 0.2794 0.9906)
			(end -0.2794 0.9906)
			(stroke
				(width 0.1)
				(type default)
			)
			(layer "B.Fab")
		)
		(fp_line
			(start -0.2794 -0.1016)
			(end 0.2794 -0.1016)
			(stroke
				(width 0.1)
				(type default)
			)
			(layer "B.Fab")
		)
		(fp_line
			(start 0.2794 -0.1016)
			(end 0.2794 0.9906)
			(stroke
				(width 0.1)
				(type default)
			)
			(layer "B.Fab")
		)
		(pad "1" smd rect
			(at 0 0 90)
			(size 0.508 0.508)
			(layers "B.Cu" "B.Mask" "B.Paste")
			(net "P3V3_STBY")
		)
		(pad "2" smd rect
			(at 0 0.889 90)
			(size 0.508 0.508)
			(layers "B.Cu" "B.Mask" "B.Paste")
			(net "PU_IRQ_VRALERT_N")
		)
		(zone
			(layer "B.Cu")
			(hatch none 0.5)
			(connect_pads
				(clearance 0)
			)
			(min_thickness 0.25)
			(keepout
				(tracks not_allowed)
				(vias allowed)
				(pads allowed)
				(copperpour not_allowed)
				(footprints allowed)
			)
			(placement
				(enabled no)
				(sheetname "")
			)
			(fill
				(thermal_gap 0.5)
				(thermal_bridge_width 0.5)
				(island_removal_mode 0)
			)
			(polygon
				(pts
					(xy 403.9235 -96.901) (xy 403.9235 -97.409) (xy 404.3045 -97.409) (xy 404.3045 -96.901)
				)
			)
		)
		(zone
			(layer "B.Cu")
			(hatch none 0.5)
			(connect_pads
				(clearance 0)
			)
			(min_thickness 0.25)
			(keepout
				(tracks allowed)
				(vias not_allowed)
				(pads allowed)
				(copperpour not_allowed)
				(footprints allowed)
			)
			(placement
				(enabled no)
				(sheetname "")
			)
			(fill
				(thermal_gap 0.5)
				(thermal_bridge_width 0.5)
				(island_removal_mode 0)
			)
			(polygon
				(pts
					(xy 404.3045 -96.901) (xy 404.3045 -97.409) (xy 403.9235 -97.409) (xy 403.9235 -96.901)
				)
			)
		)
	)
	(footprint ""
		(layer "B.Cu")
		(at 27.912568 -134.874 180)
		(property "Reference" "R9M2"
			(at 0 0 0)
			(layer "B.SilkS")
			(hide yes)
			(effects
				(font
					(size 1.27 1.27)
				)
				(justify mirror)
			)
		)
		(property "Value" ""
			(at 0 0 0)
			(layer "B.Fab")
			(effects
				(font
					(size 1.27 1.27)
				)
				(justify mirror)
			)
		)
		(duplicate_pad_numbers_are_jumpers no)
		(fp_poly
			(pts
				(xy 0.2794 -0.1016) (xy -0.2794 -0.1016) (xy -0.2794 0.9906) (xy 0.2794 0.9906)
			)
			(stroke
				(width 0)
				(type default)
			)
			(fill no)
			(layer "B.CrtYd")
		)
		(fp_line
			(start 0.2794 0.9906)
			(end -0.2794 0.9906)
			(stroke
				(width 0.1)
				(type default)
			)
			(layer "B.Fab")
		)
		(fp_line
			(start 0.2794 -0.1016)
			(end 0.2794 0.9906)
			(stroke
				(width 0.1)
				(type default)
			)
			(layer "B.Fab")
		)
		(fp_line
			(start -0.2794 0.9906)
			(end -0.2794 -0.1016)
			(stroke
				(width 0.1)
				(type default)
			)
			(layer "B.Fab")
		)
		(fp_line
			(start -0.2794 -0.1016)
			(end 0.2794 -0.1016)
			(stroke
				(width 0.1)
				(type default)
			)
			(layer "B.Fab")
		)
		(pad "1" smd rect
			(at 0 0)
			(size 0.508 0.508)
			(layers "B.Cu" "B.Mask" "B.Paste")
			(net "M_K_CPU_VREF")
		)
		(pad "2" smd rect
			(at 0 0.889)
			(size 0.508 0.508)
			(layers "B.Cu" "B.Mask" "B.Paste")
			(net "M_K_VREF")
		)
		(zone
			(layer "B.Cu")
			(hatch none 0.5)
			(connect_pads
				(clearance 0)
			)
			(min_thickness 0.25)
			(keepout
				(tracks not_allowed)
				(vias allowed)
				(pads allowed)
				(copperpour not_allowed)
				(footprints allowed)
			)
			(placement
				(enabled no)
				(sheetname "")
			)
			(fill
				(thermal_gap 0.5)
				(thermal_bridge_width 0.5)
				(island_removal_mode 0)
			)
			(polygon
				(pts
					(xy 27.658568 -135.509) (xy 28.166568 -135.509) (xy 28.166568 -135.128) (xy 27.658568 -135.128)
				)
			)
		)
		(zone
			(layer "B.Cu")
			(hatch none 0.5)
			(connect_pads
				(clearance 0)
			)
			(min_thickness 0.25)
			(keepout
				(tracks allowed)
				(vias not_allowed)
				(pads allowed)
				(copperpour not_allowed)
				(footprints allowed)
			)
			(placement
				(enabled no)
				(sheetname "")
			)
			(fill
				(thermal_gap 0.5)
				(thermal_bridge_width 0.5)
				(island_removal_mode 0)
			)
			(polygon
				(pts
					(xy 27.658568 -135.128) (xy 28.166568 -135.128) (xy 28.166568 -135.509) (xy 27.658568 -135.509)
				)
			)
		)
	)
	(footprint ""
		(layer "B.Cu")
		(at 343.063068 -77.694536)
		(property "Reference" "C3P16"
			(at 0 0 0)
			(layer "B.SilkS")
			(hide yes)
			(effects
				(font
					(size 1.27 1.27)
				)
				(justify mirror)
			)
		)
		(property "Value" ""
			(at 0 0 0)
			(layer "B.Fab")
			(effects
				(font
					(size 1.27 1.27)
				)
				(justify mirror)
			)
		)
		(duplicate_pad_numbers_are_jumpers no)
		(fp_poly
			(pts
				(xy -0.3048 -0.1016) (xy -0.3048 0.9906) (xy 0.3048 0.9906) (xy 0.3048 -0.1016)
			)
			(stroke
				(width 0)
				(type default)
			)
			(fill no)
			(layer "B.CrtYd")
		)
		(fp_line
			(start -0.3048 -0.1016)
			(end 0.3048 -0.1016)
			(stroke
				(width 0.1)
				(type default)
			)
			(layer "B.Fab")
		)
		(fp_line
			(start -0.3048 0.9906)
			(end -0.3048 -0.1016)
			(stroke
				(width 0.1)
				(type default)
			)
			(layer "B.Fab")
		)
		(fp_line
			(start 0.3048 -0.1016)
			(end 0.3048 0.9906)
			(stroke
				(width 0.1)
				(type default)
			)
			(layer "B.Fab")
		)
		(fp_line
			(start 0.3048 0.9906)
			(end -0.3048 0.9906)
			(stroke
				(width 0.1)
				(type default)
			)
			(layer "B.Fab")
		)
		(pad "1" smd rect
			(at 0 0 180)
			(size 0.508 0.508)
			(layers "B.Cu" "B.Mask" "B.Paste")
			(net "P3E_CPU0_PE1_SS_TXN<1>")
		)
		(pad "2" smd rect
			(at 0 0.889 180)
			(size 0.508 0.508)
			(layers "B.Cu" "B.Mask" "B.Paste")
			(net "P3E_CPU0_PE1_SS_C_TXN<1>")
		)
		(zone
			(layer "B.Cu")
			(hatch none 0.5)
			(connect_pads
				(clearance 0)
			)
			(min_thickness 0.25)
			(keepout
				(tracks allowed)
				(vias not_allowed)
				(pads allowed)
				(copperpour not_allowed)
				(footprints allowed)
			)
			(placement
				(enabled no)
				(sheetname "")
			)
			(fill
				(thermal_gap 0.5)
				(thermal_bridge_width 0.5)
				(island_removal_mode 0)
			)
			(polygon
				(pts
					(xy 343.317068 -77.440536) (xy 342.809068 -77.440536) (xy 342.809068 -77.059536) (xy 343.317068 -77.059536)
				)
			)
		)
		(zone
			(layer "B.Cu")
			(hatch none 0.5)
			(connect_pads
				(clearance 0)
			)
			(min_thickness 0.25)
			(keepout
				(tracks not_allowed)
				(vias allowed)
				(pads allowed)
				(copperpour not_allowed)
				(footprints allowed)
			)
			(placement
				(enabled no)
				(sheetname "")
			)
			(fill
				(thermal_gap 0.5)
				(thermal_bridge_width 0.5)
				(island_removal_mode 0)
			)
			(polygon
				(pts
					(xy 343.317068 -77.059536) (xy 342.809068 -77.059536) (xy 342.809068 -77.440536) (xy 343.317068 -77.440536)
				)
			)
		)
	)
	(footprint ""
		(layer "B.Cu")
		(at 476.936816 -145.470372 180)
		(property "Reference" "R6W9"
			(at 0.8382 -0.67818 180)
			(unlocked yes)
			(layer "B.SilkS")
			(effects
				(font
					(size 0.4064 0.254)
					(thickness 0.1524)
				)
				(justify left mirror)
			)
		)
		(property "Value" ""
			(at 0 0 0)
			(layer "B.Fab")
			(effects
				(font
					(size 1.27 1.27)
				)
				(justify mirror)
			)
		)
		(duplicate_pad_numbers_are_jumpers no)
		(fp_poly
			(pts
				(xy 0.2794 -0.1016) (xy -0.2794 -0.1016) (xy -0.2794 0.9906) (xy 0.2794 0.9906)
			)
			(stroke
				(width 0)
				(type default)
			)
			(fill no)
			(layer "B.CrtYd")
		)
		(fp_line
			(start 0.2794 0.9906)
			(end -0.2794 0.9906)
			(stroke
				(width 0.1)
				(type default)
			)
			(layer "B.Fab")
		)
		(fp_line
			(start 0.2794 -0.1016)
			(end 0.2794 0.9906)
			(stroke
				(width 0.1)
				(type default)
			)
			(layer "B.Fab")
		)
		(fp_line
			(start -0.2794 0.9906)
			(end -0.2794 -0.1016)
			(stroke
				(width 0.1)
				(type default)
			)
			(layer "B.Fab")
		)
		(fp_line
			(start -0.2794 -0.1016)
			(end 0.2794 -0.1016)
			(stroke
				(width 0.1)
				(type default)
			)
			(layer "B.Fab")
		)
		(pad "1" smd rect
			(at 0 0)
			(size 0.508 0.508)
			(layers "B.Cu" "B.Mask" "B.Paste")
			(net "PCA9555_A0")
		)
		(pad "2" smd rect
			(at 0 0.889)
			(size 0.508 0.508)
			(layers "B.Cu" "B.Mask" "B.Paste")
			(net "GND")
		)
		(zone
			(layer "B.Cu")
			(hatch none 0.5)
			(connect_pads
				(clearance 0)
			)
			(min_thickness 0.25)
			(keepout
				(tracks not_allowed)
				(vias allowed)
				(pads allowed)
				(copperpour not_allowed)
				(footprints allowed)
			)
			(placement
				(enabled no)
				(sheetname "")
			)
			(fill
				(thermal_gap 0.5)
				(thermal_bridge_width 0.5)
				(island_removal_mode 0)
			)
			(polygon
				(pts
					(xy 476.682816 -146.105372) (xy 477.190816 -146.105372) (xy 477.190816 -145.724372) (xy 476.682816 -145.724372)
				)
			)
		)
		(zone
			(layer "B.Cu")
			(hatch none 0.5)
			(connect_pads
				(clearance 0)
			)
			(min_thickness 0.25)
			(keepout
				(tracks allowed)
				(vias not_allowed)
				(pads allowed)
				(copperpour not_allowed)
				(footprints allowed)
			)
			(placement
				(enabled no)
				(sheetname "")
			)
			(fill
				(thermal_gap 0.5)
				(thermal_bridge_width 0.5)
				(island_removal_mode 0)
			)
			(polygon
				(pts
					(xy 476.682816 -145.724372) (xy 477.190816 -145.724372) (xy 477.190816 -146.105372) (xy 476.682816 -146.105372)
				)
			)
		)
	)
	(footprint ""
		(layer "B.Cu")
		(at 369.443 -110.998 -90)
		(property "Reference" "C3N8"
			(at 0 0 90)
			(layer "B.SilkS")
			(hide yes)
			(effects
				(font
					(size 1.27 1.27)
				)
				(justify mirror)
			)
		)
		(property "Value" ""
			(at 0 0 90)
			(layer "B.Fab")
			(effects
				(font
					(size 1.27 1.27)
				)
				(justify mirror)
			)
		)
		(duplicate_pad_numbers_are_jumpers no)
		(fp_poly
			(pts
				(xy -0.3048 -0.1016) (xy -0.3048 0.9906) (xy 0.3048 0.9906) (xy 0.3048 -0.1016)
			)
			(stroke
				(width 0)
				(type default)
			)
			(fill no)
			(layer "B.CrtYd")
		)
		(fp_line
			(start -0.3048 0.9906)
			(end -0.3048 -0.1016)
			(stroke
				(width 0.1)
				(type default)
			)
			(layer "B.Fab")
		)
		(fp_line
			(start 0.3048 0.9906)
			(end -0.3048 0.9906)
			(stroke
				(width 0.1)
				(type default)
			)
			(layer "B.Fab")
		)
		(fp_line
			(start -0.3048 -0.1016)
			(end 0.3048 -0.1016)
			(stroke
				(width 0.1)
				(type default)
			)
			(layer "B.Fab")
		)
		(fp_line
			(start 0.3048 -0.1016)
			(end 0.3048 0.9906)
			(stroke
				(width 0.1)
				(type default)
			)
			(layer "B.Fab")
		)
		(pad "1" smd rect
			(at 0 0 90)
			(size 0.508 0.508)
			(layers "B.Cu" "B.Mask" "B.Paste")
			(net "DMI_CPU0_PCH_RX_DP<3>")
		)
		(pad "2" smd rect
			(at 0 0.889 90)
			(size 0.508 0.508)
			(layers "B.Cu" "B.Mask" "B.Paste")
			(net "DMI_CPU0_PCH_RX_C_DP<3>")
		)
		(zone
			(layer "B.Cu")
			(hatch none 0.5)
			(connect_pads
				(clearance 0)
			)
			(min_thickness 0.25)
			(keepout
				(tracks not_allowed)
				(vias allowed)
				(pads allowed)
				(copperpour not_allowed)
				(footprints allowed)
			)
			(placement
				(enabled no)
				(sheetname "")
			)
			(fill
				(thermal_gap 0.5)
				(thermal_bridge_width 0.5)
				(island_removal_mode 0)
			)
			(polygon
				(pts
					(xy 368.808 -110.744) (xy 368.808 -111.252) (xy 369.189 -111.252) (xy 369.189 -110.744)
				)
			)
		)
		(zone
			(layer "B.Cu")
			(hatch none 0.5)
			(connect_pads
				(clearance 0)
			)
			(min_thickness 0.25)
			(keepout
				(tracks allowed)
				(vias not_allowed)
				(pads allowed)
				(copperpour not_allowed)
				(footprints allowed)
			)
			(placement
				(enabled no)
				(sheetname "")
			)
			(fill
				(thermal_gap 0.5)
				(thermal_bridge_width 0.5)
				(island_removal_mode 0)
			)
			(polygon
				(pts
					(xy 369.189 -110.744) (xy 369.189 -111.252) (xy 368.808 -111.252) (xy 368.808 -110.744)
				)
			)
		)
	)
	(footprint ""
		(layer "B.Cu")
		(at 401.25777 -126.389384 90)
		(property "Reference" "C2M24"
			(at 0 0 90)
			(layer "B.SilkS")
			(hide yes)
			(effects
				(font
					(size 1.27 1.27)
				)
				(justify mirror)
			)
		)
		(property "Value" ""
			(at 0 0 90)
			(layer "B.Fab")
			(effects
				(font
					(size 1.27 1.27)
				)
				(justify mirror)
			)
		)
		(duplicate_pad_numbers_are_jumpers no)
		(fp_poly
			(pts
				(xy -0.3048 -0.1016) (xy -0.3048 0.9906) (xy 0.3048 0.9906) (xy 0.3048 -0.1016)
			)
			(stroke
				(width 0)
				(type default)
			)
			(fill no)
			(layer "B.CrtYd")
		)
		(fp_line
			(start 0.3048 -0.1016)
			(end 0.3048 0.9906)
			(stroke
				(width 0.1)
				(type default)
			)
			(layer "B.Fab")
		)
		(fp_line
			(start -0.3048 -0.1016)
			(end 0.3048 -0.1016)
			(stroke
				(width 0.1)
				(type default)
			)
			(layer "B.Fab")
		)
		(fp_line
			(start 0.3048 0.9906)
			(end -0.3048 0.9906)
			(stroke
				(width 0.1)
				(type default)
			)
			(layer "B.Fab")
		)
		(fp_line
			(start -0.3048 0.9906)
			(end -0.3048 -0.1016)
			(stroke
				(width 0.1)
				(type default)
			)
			(layer "B.Fab")
		)
		(pad "1" smd rect
			(at 0 0 270)
			(size 0.508 0.508)
			(layers "B.Cu" "B.Mask" "B.Paste")
			(net "PE_PCH_SPRV_TX_DN")
		)
		(pad "2" smd rect
			(at 0 0.889 270)
			(size 0.508 0.508)
			(layers "B.Cu" "B.Mask" "B.Paste")
			(net "PE_PCH_SPRV_TX_C_DN")
		)
		(zone
			(layer "B.Cu")
			(hatch none 0.5)
			(connect_pads
				(clearance 0)
			)
			(min_thickness 0.25)
			(keepout
				(tracks allowed)
				(vias not_allowed)
				(pads allowed)
				(copperpour not_allowed)
				(footprints allowed)
			)
			(placement
				(enabled no)
				(sheetname "")
			)
			(fill
				(thermal_gap 0.5)
				(thermal_bridge_width 0.5)
				(island_removal_mode 0)
			)
			(polygon
				(pts
					(xy 401.51177 -126.643384) (xy 401.51177 -126.135384) (xy 401.89277 -126.135384) (xy 401.89277 -126.643384)
				)
			)
		)
		(zone
			(layer "B.Cu")
			(hatch none 0.5)
			(connect_pads
				(clearance 0)
			)
			(min_thickness 0.25)
			(keepout
				(tracks not_allowed)
				(vias allowed)
				(pads allowed)
				(copperpour not_allowed)
				(footprints allowed)
			)
			(placement
				(enabled no)
				(sheetname "")
			)
			(fill
				(thermal_gap 0.5)
				(thermal_bridge_width 0.5)
				(island_removal_mode 0)
			)
			(polygon
				(pts
					(xy 401.89277 -126.643384) (xy 401.89277 -126.135384) (xy 401.51177 -126.135384) (xy 401.51177 -126.643384)
				)
			)
		)
	)
	(footprint ""
		(layer "B.Cu")
		(at 418.719 -34.3535)
		(property "Reference" "C25W55"
			(at 0.8382 -0.67818 0)
			(unlocked yes)
			(layer "B.SilkS")
			(effects
				(font
					(size 0.4064 0.254)
					(thickness 0.1524)
				)
				(justify left mirror)
			)
		)
		(property "Value" ""
			(at 0 0 0)
			(layer "B.Fab")
			(effects
				(font
					(size 1.27 1.27)
				)
				(justify mirror)
			)
		)
		(duplicate_pad_numbers_are_jumpers no)
		(fp_poly
			(pts
				(xy -0.3048 -0.1016) (xy -0.3048 0.9906) (xy 0.3048 0.9906) (xy 0.3048 -0.1016)
			)
			(stroke
				(width 0)
				(type default)
			)
			(fill no)
			(layer "B.CrtYd")
		)
		(fp_line
			(start -0.3048 -0.1016)
			(end 0.3048 -0.1016)
			(stroke
				(width 0.1)
				(type default)
			)
			(layer "B.Fab")
		)
		(fp_line
			(start -0.3048 0.9906)
			(end -0.3048 -0.1016)
			(stroke
				(width 0.1)
				(type default)
			)
			(layer "B.Fab")
		)
		(fp_line
			(start 0.3048 -0.1016)
			(end 0.3048 0.9906)
			(stroke
				(width 0.1)
				(type default)
			)
			(layer "B.Fab")
		)
		(fp_line
			(start 0.3048 0.9906)
			(end -0.3048 0.9906)
			(stroke
				(width 0.1)
				(type default)
			)
			(layer "B.Fab")
		)
		(pad "1" smd rect
			(at 0 0 180)
			(size 0.508 0.508)
			(layers "B.Cu" "B.Mask" "B.Paste")
			(net "P1V2_AUX_BMC")
		)
		(pad "2" smd rect
			(at 0 0.889 180)
			(size 0.508 0.508)
			(layers "B.Cu" "B.Mask" "B.Paste")
			(net "GND")
		)
		(zone
			(layer "B.Cu")
			(hatch none 0.5)
			(connect_pads
				(clearance 0)
			)
			(min_thickness 0.25)
			(keepout
				(tracks allowed)
				(vias not_allowed)
				(pads allowed)
				(copperpour not_allowed)
				(footprints allowed)
			)
			(placement
				(enabled no)
				(sheetname "")
			)
			(fill
				(thermal_gap 0.5)
				(thermal_bridge_width 0.5)
				(island_removal_mode 0)
			)
			(polygon
				(pts
					(xy 418.973 -34.0995) (xy 418.465 -34.0995) (xy 418.465 -33.7185) (xy 418.973 -33.7185)
				)
			)
		)
		(zone
			(layer "B.Cu")
			(hatch none 0.5)
			(connect_pads
				(clearance 0)
			)
			(min_thickness 0.25)
			(keepout
				(tracks not_allowed)
				(vias allowed)
				(pads allowed)
				(copperpour not_allowed)
				(footprints allowed)
			)
			(placement
				(enabled no)
				(sheetname "")
			)
			(fill
				(thermal_gap 0.5)
				(thermal_bridge_width 0.5)
				(island_removal_mode 0)
			)
			(polygon
				(pts
					(xy 418.973 -33.7185) (xy 418.465 -33.7185) (xy 418.465 -34.0995) (xy 418.973 -34.0995)
				)
			)
		)
	)
	(footprint ""
		(layer "B.Cu")
		(at 368.709956 -122.560842 -90)
		(property "Reference" "C3M33"
			(at 0 0 90)
			(layer "B.SilkS")
			(hide yes)
			(effects
				(font
					(size 1.27 1.27)
				)
				(justify mirror)
			)
		)
		(property "Value" ""
			(at 0 0 90)
			(layer "B.Fab")
			(effects
				(font
					(size 1.27 1.27)
				)
				(justify mirror)
			)
		)
		(duplicate_pad_numbers_are_jumpers no)
		(fp_poly
			(pts
				(xy -0.3048 -0.1016) (xy -0.3048 0.9906) (xy 0.3048 0.9906) (xy 0.3048 -0.1016)
			)
			(stroke
				(width 0)
				(type default)
			)
			(fill no)
			(layer "B.CrtYd")
		)
		(fp_line
			(start -0.3048 0.9906)
			(end -0.3048 -0.1016)
			(stroke
				(width 0.1)
				(type default)
			)
			(layer "B.Fab")
		)
		(fp_line
			(start 0.3048 0.9906)
			(end -0.3048 0.9906)
			(stroke
				(width 0.1)
				(type default)
			)
			(layer "B.Fab")
		)
		(fp_line
			(start -0.3048 -0.1016)
			(end 0.3048 -0.1016)
			(stroke
				(width 0.1)
				(type default)
			)
			(layer "B.Fab")
		)
		(fp_line
			(start 0.3048 -0.1016)
			(end 0.3048 0.9906)
			(stroke
				(width 0.1)
				(type default)
			)
			(layer "B.Fab")
		)
		(pad "1" smd rect
			(at 0 0 90)
			(size 0.508 0.508)
			(layers "B.Cu" "B.Mask" "B.Paste")
			(net "P3E_CPU0_PE1_PCH_R_RXN<8>")
		)
		(pad "2" smd rect
			(at 0 0.889 90)
			(size 0.508 0.508)
			(layers "B.Cu" "B.Mask" "B.Paste")
			(net "P3E_CPU0_PE1_PCH_RXN<8>")
		)
		(zone
			(layer "B.Cu")
			(hatch none 0.5)
			(connect_pads
				(clearance 0)
			)
			(min_thickness 0.25)
			(keepout
				(tracks not_allowed)
				(vias allowed)
				(pads allowed)
				(copperpour not_allowed)
				(footprints allowed)
			)
			(placement
				(enabled no)
				(sheetname "")
			)
			(fill
				(thermal_gap 0.5)
				(thermal_bridge_width 0.5)
				(island_removal_mode 0)
			)
			(polygon
				(pts
					(xy 368.074956 -122.306842) (xy 368.074956 -122.814842) (xy 368.455956 -122.814842) (xy 368.455956 -122.306842)
				)
			)
		)
		(zone
			(layer "B.Cu")
			(hatch none 0.5)
			(connect_pads
				(clearance 0)
			)
			(min_thickness 0.25)
			(keepout
				(tracks allowed)
				(vias not_allowed)
				(pads allowed)
				(copperpour not_allowed)
				(footprints allowed)
			)
			(placement
				(enabled no)
				(sheetname "")
			)
			(fill
				(thermal_gap 0.5)
				(thermal_bridge_width 0.5)
				(island_removal_mode 0)
			)
			(polygon
				(pts
					(xy 368.455956 -122.306842) (xy 368.455956 -122.814842) (xy 368.074956 -122.814842) (xy 368.074956 -122.306842)
				)
			)
		)
	)
	(footprint ""
		(layer "B.Cu")
		(at 194.437 -145.3642)
		(property "Reference" "R6L12"
			(at 0 0 0)
			(layer "B.SilkS")
			(hide yes)
			(effects
				(font
					(size 1.27 1.27)
				)
				(justify mirror)
			)
		)
		(property "Value" ""
			(at 0 0 0)
			(layer "B.Fab")
			(effects
				(font
					(size 1.27 1.27)
				)
				(justify mirror)
			)
		)
		(duplicate_pad_numbers_are_jumpers no)
		(fp_poly
			(pts
				(xy 0.2794 -0.1016) (xy -0.2794 -0.1016) (xy -0.2794 0.9906) (xy 0.2794 0.9906)
			)
			(stroke
				(width 0)
				(type default)
			)
			(fill no)
			(layer "B.CrtYd")
		)
		(fp_line
			(start -0.2794 -0.1016)
			(end 0.2794 -0.1016)
			(stroke
				(width 0.1)
				(type default)
			)
			(layer "B.Fab")
		)
		(fp_line
			(start -0.2794 0.9906)
			(end -0.2794 -0.1016)
			(stroke
				(width 0.1)
				(type default)
			)
			(layer "B.Fab")
		)
		(fp_line
			(start 0.2794 -0.1016)
			(end 0.2794 0.9906)
			(stroke
				(width 0.1)
				(type default)
			)
			(layer "B.Fab")
		)
		(fp_line
			(start 0.2794 0.9906)
			(end -0.2794 0.9906)
			(stroke
				(width 0.1)
				(type default)
			)
			(layer "B.Fab")
		)
		(pad "1" smd rect
			(at 0 0 180)
			(size 0.508 0.508)
			(layers "B.Cu" "B.Mask" "B.Paste")
			(net "M_E_VREF")
		)
		(pad "2" smd rect
			(at 0 0.889 180)
			(size 0.508 0.508)
			(layers "B.Cu" "B.Mask" "B.Paste")
			(net "GND")
		)
		(zone
			(layer "B.Cu")
			(hatch none 0.5)
			(connect_pads
				(clearance 0)
			)
			(min_thickness 0.25)
			(keepout
				(tracks allowed)
				(vias not_allowed)
				(pads allowed)
				(copperpour not_allowed)
				(footprints allowed)
			)
			(placement
				(enabled no)
				(sheetname "")
			)
			(fill
				(thermal_gap 0.5)
				(thermal_bridge_width 0.5)
				(island_removal_mode 0)
			)
			(polygon
				(pts
					(xy 194.691 -145.1102) (xy 194.183 -145.1102) (xy 194.183 -144.7292) (xy 194.691 -144.7292)
				)
			)
		)
		(zone
			(layer "B.Cu")
			(hatch none 0.5)
			(connect_pads
				(clearance 0)
			)
			(min_thickness 0.25)
			(keepout
				(tracks not_allowed)
				(vias allowed)
				(pads allowed)
				(copperpour not_allowed)
				(footprints allowed)
			)
			(placement
				(enabled no)
				(sheetname "")
			)
			(fill
				(thermal_gap 0.5)
				(thermal_bridge_width 0.5)
				(island_removal_mode 0)
			)
			(polygon
				(pts
					(xy 194.691 -144.7292) (xy 194.183 -144.7292) (xy 194.183 -145.1102) (xy 194.691 -145.1102)
				)
			)
		)
	)
	(footprint ""
		(layer "B.Cu")
		(at 341.666068 -77.694536 180)
		(property "Reference" "C3P15"
			(at 0 0 0)
			(layer "B.SilkS")
			(hide yes)
			(effects
				(font
					(size 1.27 1.27)
				)
				(justify mirror)
			)
		)
		(property "Value" ""
			(at 0 0 0)
			(layer "B.Fab")
			(effects
				(font
					(size 1.27 1.27)
				)
				(justify mirror)
			)
		)
		(duplicate_pad_numbers_are_jumpers no)
		(fp_poly
			(pts
				(xy -0.3048 -0.1016) (xy -0.3048 0.9906) (xy 0.3048 0.9906) (xy 0.3048 -0.1016)
			)
			(stroke
				(width 0)
				(type default)
			)
			(fill no)
			(layer "B.CrtYd")
		)
		(fp_line
			(start 0.3048 0.9906)
			(end -0.3048 0.9906)
			(stroke
				(width 0.1)
				(type default)
			)
			(layer "B.Fab")
		)
		(fp_line
			(start 0.3048 -0.1016)
			(end 0.3048 0.9906)
			(stroke
				(width 0.1)
				(type default)
			)
			(layer "B.Fab")
		)
		(fp_line
			(start -0.3048 0.9906)
			(end -0.3048 -0.1016)
			(stroke
				(width 0.1)
				(type default)
			)
			(layer "B.Fab")
		)
		(fp_line
			(start -0.3048 -0.1016)
			(end 0.3048 -0.1016)
			(stroke
				(width 0.1)
				(type default)
			)
			(layer "B.Fab")
		)
		(pad "1" smd rect
			(at 0 0)
			(size 0.508 0.508)
			(layers "B.Cu" "B.Mask" "B.Paste")
			(net "P3E_CPU0_PE1_SS_TXP<1>")
		)
		(pad "2" smd rect
			(at 0 0.889)
			(size 0.508 0.508)
			(layers "B.Cu" "B.Mask" "B.Paste")
			(net "P3E_CPU0_PE1_PCH_TXP<1>")
		)
		(zone
			(layer "B.Cu")
			(hatch none 0.5)
			(connect_pads
				(clearance 0)
			)
			(min_thickness 0.25)
			(keepout
				(tracks not_allowed)
				(vias allowed)
				(pads allowed)
				(copperpour not_allowed)
				(footprints allowed)
			)
			(placement
				(enabled no)
				(sheetname "")
			)
			(fill
				(thermal_gap 0.5)
				(thermal_bridge_width 0.5)
				(island_removal_mode 0)
			)
			(polygon
				(pts
					(xy 341.412068 -78.329536) (xy 341.920068 -78.329536) (xy 341.920068 -77.948536) (xy 341.412068 -77.948536)
				)
			)
		)
		(zone
			(layer "B.Cu")
			(hatch none 0.5)
			(connect_pads
				(clearance 0)
			)
			(min_thickness 0.25)
			(keepout
				(tracks allowed)
				(vias not_allowed)
				(pads allowed)
				(copperpour not_allowed)
				(footprints allowed)
			)
			(placement
				(enabled no)
				(sheetname "")
			)
			(fill
				(thermal_gap 0.5)
				(thermal_bridge_width 0.5)
				(island_removal_mode 0)
			)
			(polygon
				(pts
					(xy 341.412068 -77.948536) (xy 341.920068 -77.948536) (xy 341.920068 -78.329536) (xy 341.412068 -78.329536)
				)
			)
		)
	)
	(footprint ""
		(layer "B.Cu")
		(at 379.3998 -46.2026 180)
		(property "Reference" "C7E4"
			(at 0 0 0)
			(layer "B.SilkS")
			(hide yes)
			(effects
				(font
					(size 1.27 1.27)
				)
				(justify mirror)
			)
		)
		(property "Value" ""
			(at 0 0 0)
			(layer "B.Fab")
			(effects
				(font
					(size 1.27 1.27)
				)
				(justify mirror)
			)
		)
		(duplicate_pad_numbers_are_jumpers no)
		(fp_poly
			(pts
				(xy -0.3048 -0.1016) (xy -0.3048 0.9906) (xy 0.3048 0.9906) (xy 0.3048 -0.1016)
			)
			(stroke
				(width 0)
				(type default)
			)
			(fill no)
			(layer "B.CrtYd")
		)
		(fp_line
			(start 0.3048 0.9906)
			(end -0.3048 0.9906)
			(stroke
				(width 0.1)
				(type default)
			)
			(layer "B.Fab")
		)
		(fp_line
			(start 0.3048 -0.1016)
			(end 0.3048 0.9906)
			(stroke
				(width 0.1)
				(type default)
			)
			(layer "B.Fab")
		)
		(fp_line
			(start -0.3048 0.9906)
			(end -0.3048 -0.1016)
			(stroke
				(width 0.1)
				(type default)
			)
			(layer "B.Fab")
		)
		(fp_line
			(start -0.3048 -0.1016)
			(end 0.3048 -0.1016)
			(stroke
				(width 0.1)
				(type default)
			)
			(layer "B.Fab")
		)
		(pad "1" smd rect
			(at 0 0)
			(size 0.508 0.508)
			(layers "B.Cu" "B.Mask" "B.Paste")
			(net "P3V3_STBY")
		)
		(pad "2" smd rect
			(at 0 0.889)
			(size 0.508 0.508)
			(layers "B.Cu" "B.Mask" "B.Paste")
			(net "GND")
		)
		(zone
			(layer "B.Cu")
			(hatch none 0.5)
			(connect_pads
				(clearance 0)
			)
			(min_thickness 0.25)
			(keepout
				(tracks not_allowed)
				(vias allowed)
				(pads allowed)
				(copperpour not_allowed)
				(footprints allowed)
			)
			(placement
				(enabled no)
				(sheetname "")
			)
			(fill
				(thermal_gap 0.5)
				(thermal_bridge_width 0.5)
				(island_removal_mode 0)
			)
			(polygon
				(pts
					(xy 379.1458 -46.8376) (xy 379.6538 -46.8376) (xy 379.6538 -46.4566) (xy 379.1458 -46.4566)
				)
			)
		)
		(zone
			(layer "B.Cu")
			(hatch none 0.5)
			(connect_pads
				(clearance 0)
			)
			(min_thickness 0.25)
			(keepout
				(tracks allowed)
				(vias not_allowed)
				(pads allowed)
				(copperpour not_allowed)
				(footprints allowed)
			)
			(placement
				(enabled no)
				(sheetname "")
			)
			(fill
				(thermal_gap 0.5)
				(thermal_bridge_width 0.5)
				(island_removal_mode 0)
			)
			(polygon
				(pts
					(xy 379.1458 -46.4566) (xy 379.6538 -46.4566) (xy 379.6538 -46.8376) (xy 379.1458 -46.8376)
				)
			)
		)
	)
	(footprint ""
		(layer "B.Cu")
		(at 390.93775 -114.25555 180)
		(property "Reference" "C2M18"
			(at 0 0 0)
			(layer "B.SilkS")
			(hide yes)
			(effects
				(font
					(size 1.27 1.27)
				)
				(justify mirror)
			)
		)
		(property "Value" ""
			(at 0 0 0)
			(layer "B.Fab")
			(effects
				(font
					(size 1.27 1.27)
				)
				(justify mirror)
			)
		)
		(duplicate_pad_numbers_are_jumpers no)
		(fp_rect
			(start 0.2794 0.9144)
			(end -0.2794 -0.1143)
			(stroke
				(width 0)
				(type default)
			)
			(fill no)
			(layer "B.CrtYd")
		)
		(fp_line
			(start 0.2794 0.9144)
			(end 0.2794 -0.1143)
			(stroke
				(width 0.1)
				(type default)
			)
			(layer "B.Fab")
		)
		(fp_line
			(start 0.2794 -0.1143)
			(end -0.2794 -0.1143)
			(stroke
				(width 0.1)
				(type default)
			)
			(layer "B.Fab")
		)
		(fp_line
			(start -0.2794 0.9144)
			(end 0.2794 0.9144)
			(stroke
				(width 0.1)
				(type default)
			)
			(layer "B.Fab")
		)
		(fp_line
			(start -0.2794 -0.1143)
			(end -0.2794 0.9144)
			(stroke
				(width 0.1)
				(type default)
			)
			(layer "B.Fab")
		)
		(pad "1" smd custom
			(at 0 0 90)
			(size 0.10414 0.10414)
			(layers "B.Cu" "B.Mask" "B.Paste")
			(net "P1V05_PCH_STBY")
			(options
				(clearance outline)
				(anchor circle)
			)
			(primitives
				(gr_poly
					(pts
						(xy -0.20828 -0.08636) (xy -0.20828 0.08636) (xy -0.08636 0.20828) (xy 0.086614 0.20828) (xy 0.20828 0.086614)
						(xy 0.20828 -0.08636) (xy 0.08636 -0.20828) (xy -0.08636 -0.20828)
					)
					(width 0)
					(fill yes)
				)
			)
		)
		(pad "2" smd custom
			(at 0 0.8001 90)
			(size 0.10414 0.10414)
			(layers "B.Cu" "B.Mask" "B.Paste")
			(net "GND")
			(options
				(clearance outline)
				(anchor circle)
			)
			(primitives
				(gr_poly
					(pts
						(xy -0.20828 -0.08636) (xy -0.20828 0.08636) (xy -0.08636 0.20828) (xy 0.086614 0.20828) (xy 0.20828 0.086614)
						(xy 0.20828 -0.08636) (xy 0.08636 -0.20828) (xy -0.08636 -0.20828)
					)
					(width 0)
					(fill yes)
				)
			)
		)
		(zone
			(layer "B.Cu")
			(hatch none 0.5)
			(connect_pads
				(clearance 0)
			)
			(min_thickness 0.25)
			(keepout
				(tracks not_allowed)
				(vias allowed)
				(pads allowed)
				(copperpour not_allowed)
				(footprints allowed)
			)
			(placement
				(enabled no)
				(sheetname "")
			)
			(fill
				(thermal_gap 0.5)
				(thermal_bridge_width 0.5)
				(island_removal_mode 0)
			)
			(polygon
				(pts
					(xy 390.85012 -114.4651) (xy 390.85012 -114.8461) (xy 391.02538 -114.8461) (xy 391.025634 -114.4651)
				)
			)
		)
		(zone
			(layer "B.Cu")
			(hatch none 0.5)
			(connect_pads
				(clearance 0)
			)
			(min_thickness 0.25)
			(keepout
				(tracks allowed)
				(vias not_allowed)
				(pads allowed)
				(copperpour not_allowed)
				(footprints allowed)
			)
			(placement
				(enabled no)
				(sheetname "")
			)
			(fill
				(thermal_gap 0.5)
				(thermal_bridge_width 0.5)
				(island_removal_mode 0)
			)
			(polygon
				(pts
					(xy 390.85012 -114.4651) (xy 390.85012 -114.8461) (xy 391.02538 -114.8461) (xy 391.025634 -114.4651)
				)
			)
		)
	)
	(footprint ""
		(layer "B.Cu")
		(at 276.000464 -140.208 90)
		(property "Reference" "C5G76"
			(at -1.14681 0.76708 180)
			(unlocked yes)
			(layer "B.SilkS")
			(effects
				(font
					(size 0.7874 0.5842)
					(thickness 0.1524)
				)
				(justify mirror)
			)
		)
		(property "Value" ""
			(at 0 0 90)
			(layer "B.Fab")
			(effects
				(font
					(size 1.27 1.27)
				)
				(justify mirror)
			)
		)
		(duplicate_pad_numbers_are_jumpers no)
		(fp_rect
			(start -0.4953 -0.2032)
			(end 0.4953 1.6002)
			(stroke
				(width 0)
				(type default)
			)
			(fill no)
			(layer "B.CrtYd")
		)
		(fp_line
			(start 0.4953 -0.2032)
			(end -0.4953 -0.2032)
			(stroke
				(width 0.1)
				(type default)
			)
			(layer "B.Fab")
		)
		(fp_line
			(start -0.4953 -0.2032)
			(end -0.4953 1.6002)
			(stroke
				(width 0.1)
				(type default)
			)
			(layer "B.Fab")
		)
		(fp_line
			(start 0.4953 1.6002)
			(end 0.4953 -0.2032)
			(stroke
				(width 0.1)
				(type default)
			)
			(layer "B.Fab")
		)
		(fp_line
			(start -0.4953 1.6002)
			(end 0.4953 1.6002)
			(stroke
				(width 0.1)
				(type default)
			)
			(layer "B.Fab")
		)
		(pad "1" smd rect
			(at 0 0 270)
			(size 0.762 0.889)
			(layers "B.Cu" "B.Mask" "B.Paste")
			(net "PVDDQ_DEF")
		)
		(pad "2" smd rect
			(at 0 1.397 270)
			(size 0.762 0.889)
			(layers "B.Cu" "B.Mask" "B.Paste")
			(net "GND")
		)
		(zone
			(layer "B.Cu")
			(hatch none 0.5)
			(connect_pads
				(clearance 0)
			)
			(min_thickness 0.25)
			(keepout
				(tracks not_allowed)
				(vias allowed)
				(pads allowed)
				(copperpour not_allowed)
				(footprints allowed)
			)
			(placement
				(enabled no)
				(sheetname "")
			)
			(fill
				(thermal_gap 0.5)
				(thermal_bridge_width 0.5)
				(island_removal_mode 0)
			)
			(polygon
				(pts
					(xy 276.444964 -139.827) (xy 276.952964 -139.827) (xy 276.952964 -140.589) (xy 276.444964 -140.589)
				)
			)
		)
	)
	(footprint ""
		(layer "B.Cu")
		(at 101.104192 -68.184014 180)
		(property "Reference" "C8P31"
			(at 0 0 0)
			(layer "B.SilkS")
			(hide yes)
			(effects
				(font
					(size 1.27 1.27)
				)
				(justify mirror)
			)
		)
		(property "Value" ""
			(at 0 0 0)
			(layer "B.Fab")
			(effects
				(font
					(size 1.27 1.27)
				)
				(justify mirror)
			)
		)
		(duplicate_pad_numbers_are_jumpers no)
		(fp_poly
			(pts
				(xy 0.7239 -0.2159) (xy -0.7239 -0.2159) (xy -0.7239 1.9939) (xy 0.7239 1.9939)
			)
			(stroke
				(width 0)
				(type default)
			)
			(fill no)
			(layer "B.CrtYd")
		)
		(fp_line
			(start 0.7239 1.9939)
			(end -0.7239 1.9939)
			(stroke
				(width 0.1)
				(type default)
			)
			(layer "B.Fab")
		)
		(fp_line
			(start 0.7239 -0.2159)
			(end 0.7239 1.9939)
			(stroke
				(width 0.1)
				(type default)
			)
			(layer "B.Fab")
		)
		(fp_line
			(start -0.7239 1.9939)
			(end -0.7239 -0.2159)
			(stroke
				(width 0.1)
				(type default)
			)
			(layer "B.Fab")
		)
		(fp_line
			(start -0.7239 -0.2159)
			(end 0.7239 -0.2159)
			(stroke
				(width 0.1)
				(type default)
			)
			(layer "B.Fab")
		)
		(pad "1" smd rect
			(at 0 0)
			(size 1.27 1.016)
			(layers "B.Cu" "B.Mask" "B.Paste")
			(net "PVDDQ_GHJ")
		)
		(pad "2" smd rect
			(at 0 1.778)
			(size 1.27 1.016)
			(layers "B.Cu" "B.Mask" "B.Paste")
			(net "GND")
		)
		(zone
			(layer "B.Cu")
			(hatch none 0.5)
			(connect_pads
				(clearance 0)
			)
			(min_thickness 0.25)
			(keepout
				(tracks not_allowed)
				(vias allowed)
				(pads allowed)
				(copperpour not_allowed)
				(footprints allowed)
			)
			(placement
				(enabled no)
				(sheetname "")
			)
			(fill
				(thermal_gap 0.5)
				(thermal_bridge_width 0.5)
				(island_removal_mode 0)
			)
			(polygon
				(pts
					(xy 100.469192 -68.692014) (xy 101.739192 -68.692014) (xy 101.739192 -69.454014) (xy 100.469192 -69.454014)
				)
			)
		)
	)
	(footprint ""
		(layer "B.Cu")
		(at 406.654 -27.178 90)
		(property "Reference" "R25W59"
			(at 0.8382 -0.67818 90)
			(unlocked yes)
			(layer "B.SilkS")
			(effects
				(font
					(size 0.4064 0.254)
					(thickness 0.1524)
				)
				(justify left mirror)
			)
		)
		(property "Value" ""
			(at 0 0 90)
			(layer "B.Fab")
			(effects
				(font
					(size 1.27 1.27)
				)
				(justify mirror)
			)
		)
		(duplicate_pad_numbers_are_jumpers no)
		(fp_poly
			(pts
				(xy 0.2794 -0.1016) (xy -0.2794 -0.1016) (xy -0.2794 0.9906) (xy 0.2794 0.9906)
			)
			(stroke
				(width 0)
				(type default)
			)
			(fill no)
			(layer "B.CrtYd")
		)
		(fp_line
			(start 0.2794 -0.1016)
			(end 0.2794 0.9906)
			(stroke
				(width 0.1)
				(type default)
			)
			(layer "B.Fab")
		)
		(fp_line
			(start -0.2794 -0.1016)
			(end 0.2794 -0.1016)
			(stroke
				(width 0.1)
				(type default)
			)
			(layer "B.Fab")
		)
		(fp_line
			(start 0.2794 0.9906)
			(end -0.2794 0.9906)
			(stroke
				(width 0.1)
				(type default)
			)
			(layer "B.Fab")
		)
		(fp_line
			(start -0.2794 0.9906)
			(end -0.2794 -0.1016)
			(stroke
				(width 0.1)
				(type default)
			)
			(layer "B.Fab")
		)
		(pad "1" smd rect
			(at 0 0 270)
			(size 0.508 0.508)
			(layers "B.Cu" "B.Mask" "B.Paste")
			(net "P3V3_STBY")
		)
		(pad "2" smd rect
			(at 0 0.889 270)
			(size 0.508 0.508)
			(layers "B.Cu" "B.Mask" "B.Paste")
			(net "VCCBAT_TW12")
		)
		(zone
			(layer "B.Cu")
			(hatch none 0.5)
			(connect_pads
				(clearance 0)
			)
			(min_thickness 0.25)
			(keepout
				(tracks allowed)
				(vias not_allowed)
				(pads allowed)
				(copperpour not_allowed)
				(footprints allowed)
			)
			(placement
				(enabled no)
				(sheetname "")
			)
			(fill
				(thermal_gap 0.5)
				(thermal_bridge_width 0.5)
				(island_removal_mode 0)
			)
			(polygon
				(pts
					(xy 406.908 -27.432) (xy 406.908 -26.924) (xy 407.289 -26.924) (xy 407.289 -27.432)
				)
			)
		)
		(zone
			(layer "B.Cu")
			(hatch none 0.5)
			(connect_pads
				(clearance 0)
			)
			(min_thickness 0.25)
			(keepout
				(tracks not_allowed)
				(vias allowed)
				(pads allowed)
				(copperpour not_allowed)
				(footprints allowed)
			)
			(placement
				(enabled no)
				(sheetname "")
			)
			(fill
				(thermal_gap 0.5)
				(thermal_bridge_width 0.5)
				(island_removal_mode 0)
			)
			(polygon
				(pts
					(xy 407.289 -27.432) (xy 407.289 -26.924) (xy 406.908 -26.924) (xy 406.908 -27.432)
				)
			)
		)
	)
	(footprint ""
		(layer "B.Cu")
		(at 17.526 -73.406 180)
		(property "Reference" "C9P17"
			(at 0 0 0)
			(layer "B.SilkS")
			(hide yes)
			(effects
				(font
					(size 1.27 1.27)
				)
				(justify mirror)
			)
		)
		(property "Value" ""
			(at 0 0 0)
			(layer "B.Fab")
			(effects
				(font
					(size 1.27 1.27)
				)
				(justify mirror)
			)
		)
		(duplicate_pad_numbers_are_jumpers no)
		(fp_rect
			(start -0.3048 0.9906)
			(end 0.3048 -0.1016)
			(stroke
				(width 0)
				(type default)
			)
			(fill no)
			(layer "B.CrtYd")
		)
		(fp_line
			(start 0.3048 0.9906)
			(end -0.3048 0.9906)
			(stroke
				(width 0.1)
				(type default)
			)
			(layer "B.Fab")
		)
		(fp_line
			(start 0.3048 -0.1016)
			(end 0.3048 0.9906)
			(stroke
				(width 0.1)
				(type default)
			)
			(layer "B.Fab")
		)
		(fp_line
			(start -0.3048 0.9906)
			(end -0.3048 -0.1016)
			(stroke
				(width 0.1)
				(type default)
			)
			(layer "B.Fab")
		)
		(fp_line
			(start -0.3048 -0.1016)
			(end 0.3048 -0.1016)
			(stroke
				(width 0.1)
				(type default)
			)
			(layer "B.Fab")
		)
		(pad "1" smd rect
			(at 0 0)
			(size 0.508 0.508)
			(layers "B.Cu" "B.Mask" "B.Paste")
			(net "A_HSC_MON")
		)
		(pad "2" smd rect
			(at 0 0.889)
			(size 0.508 0.508)
			(layers "B.Cu" "B.Mask" "B.Paste")
			(net "AGND_HSC")
		)
		(zone
			(layer "B.Cu")
			(hatch none 0.5)
			(connect_pads
				(clearance 0)
			)
			(min_thickness 0.25)
			(keepout
				(tracks not_allowed)
				(vias allowed)
				(pads allowed)
				(copperpour not_allowed)
				(footprints allowed)
			)
			(placement
				(enabled no)
				(sheetname "")
			)
			(fill
				(thermal_gap 0.5)
				(thermal_bridge_width 0.5)
				(island_removal_mode 0)
			)
			(polygon
				(pts
					(xy 17.78 -74.041) (xy 17.272 -74.041) (xy 17.272 -73.66) (xy 17.78 -73.66)
				)
			)
		)
		(zone
			(layer "B.Cu")
			(hatch none 0.5)
			(connect_pads
				(clearance 0)
			)
			(min_thickness 0.25)
			(keepout
				(tracks allowed)
				(vias not_allowed)
				(pads allowed)
				(copperpour not_allowed)
				(footprints allowed)
			)
			(placement
				(enabled no)
				(sheetname "")
			)
			(fill
				(thermal_gap 0.5)
				(thermal_bridge_width 0.5)
				(island_removal_mode 0)
			)
			(polygon
				(pts
					(xy 17.78 -74.041) (xy 17.272 -74.041) (xy 17.272 -73.66) (xy 17.78 -73.66)
				)
			)
		)
	)
	(footprint ""
		(layer "B.Cu")
		(at 476.25 -147.193 -90)
		(property "Reference" "R6W16"
			(at 0.8382 -0.67818 270)
			(unlocked yes)
			(layer "B.SilkS")
			(effects
				(font
					(size 0.4064 0.254)
					(thickness 0.1524)
				)
				(justify left mirror)
			)
		)
		(property "Value" ""
			(at 0 0 90)
			(layer "B.Fab")
			(effects
				(font
					(size 1.27 1.27)
				)
				(justify mirror)
			)
		)
		(duplicate_pad_numbers_are_jumpers no)
		(fp_poly
			(pts
				(xy 0.2794 -0.1016) (xy -0.2794 -0.1016) (xy -0.2794 0.9906) (xy 0.2794 0.9906)
			)
			(stroke
				(width 0)
				(type default)
			)
			(fill no)
			(layer "B.CrtYd")
		)
		(fp_line
			(start -0.2794 0.9906)
			(end -0.2794 -0.1016)
			(stroke
				(width 0.1)
				(type default)
			)
			(layer "B.Fab")
		)
		(fp_line
			(start 0.2794 0.9906)
			(end -0.2794 0.9906)
			(stroke
				(width 0.1)
				(type default)
			)
			(layer "B.Fab")
		)
		(fp_line
			(start -0.2794 -0.1016)
			(end 0.2794 -0.1016)
			(stroke
				(width 0.1)
				(type default)
			)
			(layer "B.Fab")
		)
		(fp_line
			(start 0.2794 -0.1016)
			(end 0.2794 0.9906)
			(stroke
				(width 0.1)
				(type default)
			)
			(layer "B.Fab")
		)
		(pad "1" smd rect
			(at 0 0 90)
			(size 0.508 0.508)
			(layers "B.Cu" "B.Mask" "B.Paste")
			(net "P3V3_STBY")
		)
		(pad "2" smd rect
			(at 0 0.889 90)
			(size 0.508 0.508)
			(layers "B.Cu" "B.Mask" "B.Paste")
			(net "FM_SOL_UART_CH_SEL")
		)
		(zone
			(layer "B.Cu")
			(hatch none 0.5)
			(connect_pads
				(clearance 0)
			)
			(min_thickness 0.25)
			(keepout
				(tracks not_allowed)
				(vias allowed)
				(pads allowed)
				(copperpour not_allowed)
				(footprints allowed)
			)
			(placement
				(enabled no)
				(sheetname "")
			)
			(fill
				(thermal_gap 0.5)
				(thermal_bridge_width 0.5)
				(island_removal_mode 0)
			)
			(polygon
				(pts
					(xy 475.615 -146.939) (xy 475.615 -147.447) (xy 475.996 -147.447) (xy 475.996 -146.939)
				)
			)
		)
		(zone
			(layer "B.Cu")
			(hatch none 0.5)
			(connect_pads
				(clearance 0)
			)
			(min_thickness 0.25)
			(keepout
				(tracks allowed)
				(vias not_allowed)
				(pads allowed)
				(copperpour not_allowed)
				(footprints allowed)
			)
			(placement
				(enabled no)
				(sheetname "")
			)
			(fill
				(thermal_gap 0.5)
				(thermal_bridge_width 0.5)
				(island_removal_mode 0)
			)
			(polygon
				(pts
					(xy 475.996 -146.939) (xy 475.996 -147.447) (xy 475.615 -147.447) (xy 475.615 -146.939)
				)
			)
		)
	)
	(footprint ""
		(layer "B.Cu")
		(at 104.394254 -85.06714)
		(property "Reference" "C8P4"
			(at 0 0 0)
			(layer "B.SilkS")
			(hide yes)
			(effects
				(font
					(size 1.27 1.27)
				)
				(justify mirror)
			)
		)
		(property "Value" ""
			(at 0 0 0)
			(layer "B.Fab")
			(effects
				(font
					(size 1.27 1.27)
				)
				(justify mirror)
			)
		)
		(duplicate_pad_numbers_are_jumpers no)
		(fp_poly
			(pts
				(xy 0.7239 -0.2159) (xy -0.7239 -0.2159) (xy -0.7239 1.9939) (xy 0.7239 1.9939)
			)
			(stroke
				(width 0)
				(type default)
			)
			(fill no)
			(layer "B.CrtYd")
		)
		(fp_line
			(start -0.7239 -0.2159)
			(end 0.7239 -0.2159)
			(stroke
				(width 0.1)
				(type default)
			)
			(layer "B.Fab")
		)
		(fp_line
			(start -0.7239 1.9939)
			(end -0.7239 -0.2159)
			(stroke
				(width 0.1)
				(type default)
			)
			(layer "B.Fab")
		)
		(fp_line
			(start 0.7239 -0.2159)
			(end 0.7239 1.9939)
			(stroke
				(width 0.1)
				(type default)
			)
			(layer "B.Fab")
		)
		(fp_line
			(start 0.7239 1.9939)
			(end -0.7239 1.9939)
			(stroke
				(width 0.1)
				(type default)
			)
			(layer "B.Fab")
		)
		(pad "1" smd rect
			(at 0 0 180)
			(size 1.27 1.016)
			(layers "B.Cu" "B.Mask" "B.Paste")
			(net "PVDDQ_KLM")
		)
		(pad "2" smd rect
			(at 0 1.778 180)
			(size 1.27 1.016)
			(layers "B.Cu" "B.Mask" "B.Paste")
			(net "GND")
		)
		(zone
			(layer "B.Cu")
			(hatch none 0.5)
			(connect_pads
				(clearance 0)
			)
			(min_thickness 0.25)
			(keepout
				(tracks not_allowed)
				(vias allowed)
				(pads allowed)
				(copperpour not_allowed)
				(footprints allowed)
			)
			(placement
				(enabled no)
				(sheetname "")
			)
			(fill
				(thermal_gap 0.5)
				(thermal_bridge_width 0.5)
				(island_removal_mode 0)
			)
			(polygon
				(pts
					(xy 105.029254 -84.55914) (xy 103.759254 -84.55914) (xy 103.759254 -83.79714) (xy 105.029254 -83.79714)
				)
			)
		)
	)
	(footprint ""
		(layer "B.Cu")
		(at 387.604 -16.383 90)
		(property "Reference" "R32W9"
			(at 0.8382 -0.67818 90)
			(unlocked yes)
			(layer "B.SilkS")
			(effects
				(font
					(size 0.4064 0.254)
					(thickness 0.1524)
				)
				(justify left mirror)
			)
		)
		(property "Value" ""
			(at 0 0 90)
			(layer "B.Fab")
			(effects
				(font
					(size 1.27 1.27)
				)
				(justify mirror)
			)
		)
		(duplicate_pad_numbers_are_jumpers no)
		(fp_poly
			(pts
				(xy 0.2794 -0.1016) (xy -0.2794 -0.1016) (xy -0.2794 0.9906) (xy 0.2794 0.9906)
			)
			(stroke
				(width 0)
				(type default)
			)
			(fill no)
			(layer "B.CrtYd")
		)
		(fp_line
			(start 0.2794 -0.1016)
			(end 0.2794 0.9906)
			(stroke
				(width 0.1)
				(type default)
			)
			(layer "B.Fab")
		)
		(fp_line
			(start -0.2794 -0.1016)
			(end 0.2794 -0.1016)
			(stroke
				(width 0.1)
				(type default)
			)
			(layer "B.Fab")
		)
		(fp_line
			(start 0.2794 0.9906)
			(end -0.2794 0.9906)
			(stroke
				(width 0.1)
				(type default)
			)
			(layer "B.Fab")
		)
		(fp_line
			(start -0.2794 0.9906)
			(end -0.2794 -0.1016)
			(stroke
				(width 0.1)
				(type default)
			)
			(layer "B.Fab")
		)
		(pad "1" smd rect
			(at 0 0 270)
			(size 0.508 0.508)
			(layers "B.Cu" "B.Mask" "B.Paste")
			(net "PD_SMB_M2_EN")
		)
		(pad "2" smd rect
			(at 0 0.889 270)
			(size 0.508 0.508)
			(layers "B.Cu" "B.Mask" "B.Paste")
			(net "GND")
		)
		(zone
			(layer "B.Cu")
			(hatch none 0.5)
			(connect_pads
				(clearance 0)
			)
			(min_thickness 0.25)
			(keepout
				(tracks allowed)
				(vias not_allowed)
				(pads allowed)
				(copperpour not_allowed)
				(footprints allowed)
			)
			(placement
				(enabled no)
				(sheetname "")
			)
			(fill
				(thermal_gap 0.5)
				(thermal_bridge_width 0.5)
				(island_removal_mode 0)
			)
			(polygon
				(pts
					(xy 387.858 -16.637) (xy 387.858 -16.129) (xy 388.239 -16.129) (xy 388.239 -16.637)
				)
			)
		)
		(zone
			(layer "B.Cu")
			(hatch none 0.5)
			(connect_pads
				(clearance 0)
			)
			(min_thickness 0.25)
			(keepout
				(tracks not_allowed)
				(vias allowed)
				(pads allowed)
				(copperpour not_allowed)
				(footprints allowed)
			)
			(placement
				(enabled no)
				(sheetname "")
			)
			(fill
				(thermal_gap 0.5)
				(thermal_bridge_width 0.5)
				(island_removal_mode 0)
			)
			(polygon
				(pts
					(xy 388.239 -16.637) (xy 388.239 -16.129) (xy 387.858 -16.129) (xy 387.858 -16.637)
				)
			)
		)
	)
	(footprint ""
		(layer "B.Cu")
		(at 369.145058 -77.096112 90)
		(property "Reference" "C3P48"
			(at 0 0 90)
			(layer "B.SilkS")
			(hide yes)
			(effects
				(font
					(size 1.27 1.27)
				)
				(justify mirror)
			)
		)
		(property "Value" ""
			(at 0 0 90)
			(layer "B.Fab")
			(effects
				(font
					(size 1.27 1.27)
				)
				(justify mirror)
			)
		)
		(duplicate_pad_numbers_are_jumpers no)
		(fp_rect
			(start 0.2794 0.9144)
			(end -0.2794 -0.1143)
			(stroke
				(width 0)
				(type default)
			)
			(fill no)
			(layer "B.CrtYd")
		)
		(fp_line
			(start 0.2794 -0.1143)
			(end -0.2794 -0.1143)
			(stroke
				(width 0.1)
				(type default)
			)
			(layer "B.Fab")
		)
		(fp_line
			(start -0.2794 -0.1143)
			(end -0.2794 0.9144)
			(stroke
				(width 0.1)
				(type default)
			)
			(layer "B.Fab")
		)
		(fp_line
			(start 0.2794 0.9144)
			(end 0.2794 -0.1143)
			(stroke
				(width 0.1)
				(type default)
			)
			(layer "B.Fab")
		)
		(fp_line
			(start -0.2794 0.9144)
			(end 0.2794 0.9144)
			(stroke
				(width 0.1)
				(type default)
			)
			(layer "B.Fab")
		)
		(pad "1" smd custom
			(at 0 0)
			(size 0.10414 0.10414)
			(layers "B.Cu" "B.Mask" "B.Paste")
			(net "P3V3_STBY")
			(options
				(clearance outline)
				(anchor circle)
			)
			(primitives
				(gr_poly
					(pts
						(xy -0.20828 -0.08636) (xy -0.20828 0.08636) (xy -0.08636 0.20828) (xy 0.086614 0.20828) (xy 0.20828 0.086614)
						(xy 0.20828 -0.08636) (xy 0.08636 -0.20828) (xy -0.08636 -0.20828)
					)
					(width 0)
					(fill yes)
				)
			)
		)
		(pad "2" smd custom
			(at 0 0.8001)
			(size 0.10414 0.10414)
			(layers "B.Cu" "B.Mask" "B.Paste")
			(net "GND")
			(options
				(clearance outline)
				(anchor circle)
			)
			(primitives
				(gr_poly
					(pts
						(xy -0.20828 -0.08636) (xy -0.20828 0.08636) (xy -0.08636 0.20828) (xy 0.086614 0.20828) (xy 0.20828 0.086614)
						(xy 0.20828 -0.08636) (xy 0.08636 -0.20828) (xy -0.08636 -0.20828)
					)
					(width 0)
					(fill yes)
				)
			)
		)
		(zone
			(layer "B.Cu")
			(hatch none 0.5)
			(connect_pads
				(clearance 0)
			)
			(min_thickness 0.25)
			(keepout
				(tracks allowed)
				(vias not_allowed)
				(pads allowed)
				(copperpour not_allowed)
				(footprints allowed)
			)
			(placement
				(enabled no)
				(sheetname "")
			)
			(fill
				(thermal_gap 0.5)
				(thermal_bridge_width 0.5)
				(island_removal_mode 0)
			)
			(polygon
				(pts
					(xy 369.354608 -77.183742) (xy 369.735608 -77.183742) (xy 369.735608 -77.008482) (xy 369.354608 -77.008228)
				)
			)
		)
		(zone
			(layer "B.Cu")
			(hatch none 0.5)
			(connect_pads
				(clearance 0)
			)
			(min_thickness 0.25)
			(keepout
				(tracks not_allowed)
				(vias allowed)
				(pads allowed)
				(copperpour not_allowed)
				(footprints allowed)
			)
			(placement
				(enabled no)
				(sheetname "")
			)
			(fill
				(thermal_gap 0.5)
				(thermal_bridge_width 0.5)
				(island_removal_mode 0)
			)
			(polygon
				(pts
					(xy 369.354608 -77.183742) (xy 369.735608 -77.183742) (xy 369.735608 -77.008482) (xy 369.354608 -77.008228)
				)
			)
		)
	)
	(footprint ""
		(layer "B.Cu")
		(at 155.293568 -135.376412 90)
		(property "Reference" "C7M3"
			(at 0 0 90)
			(layer "B.SilkS")
			(hide yes)
			(effects
				(font
					(size 1.27 1.27)
				)
				(justify mirror)
			)
		)
		(property "Value" ""
			(at 0 0 90)
			(layer "B.Fab")
			(effects
				(font
					(size 1.27 1.27)
				)
				(justify mirror)
			)
		)
		(duplicate_pad_numbers_are_jumpers no)
		(fp_rect
			(start 0.4953 1.6002)
			(end -0.4953 -0.2032)
			(stroke
				(width 0)
				(type default)
			)
			(fill no)
			(layer "B.CrtYd")
		)
		(fp_line
			(start 0.4953 -0.2032)
			(end -0.4953 -0.2032)
			(stroke
				(width 0.1)
				(type default)
			)
			(layer "B.Fab")
		)
		(fp_line
			(start -0.4953 -0.2032)
			(end -0.4953 1.6002)
			(stroke
				(width 0.1)
				(type default)
			)
			(layer "B.Fab")
		)
		(fp_line
			(start 0.4953 1.6002)
			(end 0.4953 -0.2032)
			(stroke
				(width 0.1)
				(type default)
			)
			(layer "B.Fab")
		)
		(fp_line
			(start -0.4953 1.6002)
			(end 0.4953 1.6002)
			(stroke
				(width 0.1)
				(type default)
			)
			(layer "B.Fab")
		)
		(pad "1" smd rect
			(at 0 0 270)
			(size 0.762 0.889)
			(layers "B.Cu" "B.Mask" "B.Paste")
			(net "PVPP_KLM")
		)
		(pad "2" smd rect
			(at 0 1.397 270)
			(size 0.762 0.889)
			(layers "B.Cu" "B.Mask" "B.Paste")
			(net "GND")
		)
		(zone
			(layer "B.Cu")
			(hatch none 0.5)
			(connect_pads
				(clearance 0)
			)
			(min_thickness 0.25)
			(keepout
				(tracks not_allowed)
				(vias allowed)
				(pads allowed)
				(copperpour not_allowed)
				(footprints allowed)
			)
			(placement
				(enabled no)
				(sheetname "")
			)
			(fill
				(thermal_gap 0.5)
				(thermal_bridge_width 0.5)
				(island_removal_mode 0)
			)
			(polygon
				(pts
					(xy 156.246068 -135.757412) (xy 155.738068 -135.757412) (xy 155.738068 -134.995412) (xy 156.246068 -134.995412)
				)
			)
		)
	)
	(footprint ""
		(layer "B.Cu")
		(at 372.4275 -93.091 90)
		(property "Reference" "R3N16"
			(at 0 0 90)
			(layer "B.SilkS")
			(hide yes)
			(effects
				(font
					(size 1.27 1.27)
				)
				(justify mirror)
			)
		)
		(property "Value" ""
			(at 0 0 90)
			(layer "B.Fab")
			(effects
				(font
					(size 1.27 1.27)
				)
				(justify mirror)
			)
		)
		(duplicate_pad_numbers_are_jumpers no)
		(fp_poly
			(pts
				(xy 0.2794 -0.1016) (xy -0.2794 -0.1016) (xy -0.2794 0.9906) (xy 0.2794 0.9906)
			)
			(stroke
				(width 0)
				(type default)
			)
			(fill no)
			(layer "B.CrtYd")
		)
		(fp_line
			(start 0.2794 -0.1016)
			(end 0.2794 0.9906)
			(stroke
				(width 0.1)
				(type default)
			)
			(layer "B.Fab")
		)
		(fp_line
			(start -0.2794 -0.1016)
			(end 0.2794 -0.1016)
			(stroke
				(width 0.1)
				(type default)
			)
			(layer "B.Fab")
		)
		(fp_line
			(start 0.2794 0.9906)
			(end -0.2794 0.9906)
			(stroke
				(width 0.1)
				(type default)
			)
			(layer "B.Fab")
		)
		(fp_line
			(start -0.2794 0.9906)
			(end -0.2794 -0.1016)
			(stroke
				(width 0.1)
				(type default)
			)
			(layer "B.Fab")
		)
		(pad "1" smd rect
			(at 0 0 270)
			(size 0.508 0.508)
			(layers "B.Cu" "B.Mask" "B.Paste")
			(net "P1V05_PCH_STBY")
		)
		(pad "2" smd rect
			(at 0 0.889 270)
			(size 0.508 0.508)
			(layers "B.Cu" "B.Mask" "B.Paste")
			(net "FM_PRSNT_2_5_N")
		)
		(zone
			(layer "B.Cu")
			(hatch none 0.5)
			(connect_pads
				(clearance 0)
			)
			(min_thickness 0.25)
			(keepout
				(tracks allowed)
				(vias not_allowed)
				(pads allowed)
				(copperpour not_allowed)
				(footprints allowed)
			)
			(placement
				(enabled no)
				(sheetname "")
			)
			(fill
				(thermal_gap 0.5)
				(thermal_bridge_width 0.5)
				(island_removal_mode 0)
			)
			(polygon
				(pts
					(xy 372.6815 -93.345) (xy 372.6815 -92.837) (xy 373.0625 -92.837) (xy 373.0625 -93.345)
				)
			)
		)
		(zone
			(layer "B.Cu")
			(hatch none 0.5)
			(connect_pads
				(clearance 0)
			)
			(min_thickness 0.25)
			(keepout
				(tracks not_allowed)
				(vias allowed)
				(pads allowed)
				(copperpour not_allowed)
				(footprints allowed)
			)
			(placement
				(enabled no)
				(sheetname "")
			)
			(fill
				(thermal_gap 0.5)
				(thermal_bridge_width 0.5)
				(island_removal_mode 0)
			)
			(polygon
				(pts
					(xy 373.0625 -93.345) (xy 373.0625 -92.837) (xy 372.6815 -92.837) (xy 372.6815 -93.345)
				)
			)
		)
	)
	(footprint ""
		(layer "B.Cu")
		(at 390.1821 -64.443102 -90)
		(property "Reference" "R2T8"
			(at 0 0 90)
			(layer "B.SilkS")
			(hide yes)
			(effects
				(font
					(size 1.27 1.27)
				)
				(justify mirror)
			)
		)
		(property "Value" ""
			(at 0 0 90)
			(layer "B.Fab")
			(effects
				(font
					(size 1.27 1.27)
				)
				(justify mirror)
			)
		)
		(duplicate_pad_numbers_are_jumpers no)
		(fp_poly
			(pts
				(xy 0.2794 -0.1016) (xy -0.2794 -0.1016) (xy -0.2794 0.9906) (xy 0.2794 0.9906)
			)
			(stroke
				(width 0)
				(type default)
			)
			(fill no)
			(layer "B.CrtYd")
		)
		(fp_line
			(start -0.2794 0.9906)
			(end -0.2794 -0.1016)
			(stroke
				(width 0.1)
				(type default)
			)
			(layer "B.Fab")
		)
		(fp_line
			(start 0.2794 0.9906)
			(end -0.2794 0.9906)
			(stroke
				(width 0.1)
				(type default)
			)
			(layer "B.Fab")
		)
		(fp_line
			(start -0.2794 -0.1016)
			(end 0.2794 -0.1016)
			(stroke
				(width 0.1)
				(type default)
			)
			(layer "B.Fab")
		)
		(fp_line
			(start 0.2794 -0.1016)
			(end 0.2794 0.9906)
			(stroke
				(width 0.1)
				(type default)
			)
			(layer "B.Fab")
		)
		(pad "1" smd rect
			(at 0 0 90)
			(size 0.508 0.508)
			(layers "B.Cu" "B.Mask" "B.Paste")
			(net "P3V3_STBY")
		)
		(pad "2" smd rect
			(at 0 0.889 90)
			(size 0.508 0.508)
			(layers "B.Cu" "B.Mask" "B.Paste")
			(net "SPI_SWITCH_CS0_N")
		)
		(zone
			(layer "B.Cu")
			(hatch none 0.5)
			(connect_pads
				(clearance 0)
			)
			(min_thickness 0.25)
			(keepout
				(tracks not_allowed)
				(vias allowed)
				(pads allowed)
				(copperpour not_allowed)
				(footprints allowed)
			)
			(placement
				(enabled no)
				(sheetname "")
			)
			(fill
				(thermal_gap 0.5)
				(thermal_bridge_width 0.5)
				(island_removal_mode 0)
			)
			(polygon
				(pts
					(xy 389.5471 -64.189102) (xy 389.5471 -64.697102) (xy 389.9281 -64.697102) (xy 389.9281 -64.189102)
				)
			)
		)
		(zone
			(layer "B.Cu")
			(hatch none 0.5)
			(connect_pads
				(clearance 0)
			)
			(min_thickness 0.25)
			(keepout
				(tracks allowed)
				(vias not_allowed)
				(pads allowed)
				(copperpour not_allowed)
				(footprints allowed)
			)
			(placement
				(enabled no)
				(sheetname "")
			)
			(fill
				(thermal_gap 0.5)
				(thermal_bridge_width 0.5)
				(island_removal_mode 0)
			)
			(polygon
				(pts
					(xy 389.9281 -64.189102) (xy 389.9281 -64.697102) (xy 389.5471 -64.697102) (xy 389.5471 -64.189102)
				)
			)
		)
	)
	(footprint ""
		(layer "B.Cu")
		(at 181.5973 -4.4577)
		(property "Reference" "C6U12"
			(at 0 0 0)
			(layer "B.SilkS")
			(hide yes)
			(effects
				(font
					(size 1.27 1.27)
				)
				(justify mirror)
			)
		)
		(property "Value" ""
			(at 0 0 0)
			(layer "B.Fab")
			(effects
				(font
					(size 1.27 1.27)
				)
				(justify mirror)
			)
		)
		(duplicate_pad_numbers_are_jumpers no)
		(fp_poly
			(pts
				(xy 0.4953 -0.2032) (xy -0.4953 -0.2032) (xy -0.4953 1.6002) (xy 0.4953 1.6002)
			)
			(stroke
				(width 0)
				(type default)
			)
			(fill no)
			(layer "B.CrtYd")
		)
		(fp_line
			(start -0.4953 -0.2032)
			(end -0.4953 1.6002)
			(stroke
				(width 0.1)
				(type default)
			)
			(layer "B.Fab")
		)
		(fp_line
			(start -0.4953 1.6002)
			(end 0.4953 1.6002)
			(stroke
				(width 0.1)
				(type default)
			)
			(layer "B.Fab")
		)
		(fp_line
			(start 0.4953 -0.2032)
			(end -0.4953 -0.2032)
			(stroke
				(width 0.1)
				(type default)
			)
			(layer "B.Fab")
		)
		(fp_line
			(start 0.4953 1.6002)
			(end 0.4953 -0.2032)
			(stroke
				(width 0.1)
				(type default)
			)
			(layer "B.Fab")
		)
		(pad "1" smd rect
			(at 0 0 180)
			(size 0.762 0.889)
			(layers "B.Cu" "B.Mask" "B.Paste")
			(net "VSENSE_PVDDQ_ABC_VTT")
		)
		(pad "2" smd rect
			(at 0 1.397 180)
			(size 0.762 0.889)
			(layers "B.Cu" "B.Mask" "B.Paste")
			(net "GND")
		)
		(zone
			(layer "B.Cu")
			(hatch none 0.5)
			(connect_pads
				(clearance 0)
			)
			(min_thickness 0.25)
			(keepout
				(tracks not_allowed)
				(vias allowed)
				(pads allowed)
				(copperpour not_allowed)
				(footprints allowed)
			)
			(placement
				(enabled no)
				(sheetname "")
			)
			(fill
				(thermal_gap 0.5)
				(thermal_bridge_width 0.5)
				(island_removal_mode 0)
			)
			(polygon
				(pts
					(xy 181.9783 -4.0132) (xy 181.2163 -4.0132) (xy 181.2163 -3.5052) (xy 181.9783 -3.5052)
				)
			)
		)
	)
	(footprint ""
		(layer "B.Cu")
		(at 261.9248 -26.543 90)
		(property "Reference" "C5U12"
			(at -1.47828 0.78994 180)
			(unlocked yes)
			(layer "B.SilkS")
			(effects
				(font
					(size 0.4064 0.254)
					(thickness 0.1524)
				)
				(justify mirror)
			)
		)
		(property "Value" ""
			(at 0 0 90)
			(layer "B.Fab")
			(effects
				(font
					(size 1.27 1.27)
				)
				(justify mirror)
			)
		)
		(duplicate_pad_numbers_are_jumpers no)
		(fp_poly
			(pts
				(xy 0.7239 -0.2159) (xy -0.7239 -0.2159) (xy -0.7239 1.9939) (xy 0.7239 1.9939)
			)
			(stroke
				(width 0)
				(type default)
			)
			(fill no)
			(layer "B.CrtYd")
		)
		(fp_line
			(start 0.7239 -0.2159)
			(end 0.7239 1.9939)
			(stroke
				(width 0.1)
				(type default)
			)
			(layer "B.Fab")
		)
		(fp_line
			(start -0.7239 -0.2159)
			(end 0.7239 -0.2159)
			(stroke
				(width 0.1)
				(type default)
			)
			(layer "B.Fab")
		)
		(fp_line
			(start 0.7239 1.9939)
			(end -0.7239 1.9939)
			(stroke
				(width 0.1)
				(type default)
			)
			(layer "B.Fab")
		)
		(fp_line
			(start -0.7239 1.9939)
			(end -0.7239 -0.2159)
			(stroke
				(width 0.1)
				(type default)
			)
			(layer "B.Fab")
		)
		(pad "1" smd rect
			(at 0 0 270)
			(size 1.27 1.016)
			(layers "B.Cu" "B.Mask" "B.Paste")
			(net "PVTT_ABC")
		)
		(pad "2" smd rect
			(at 0 1.778 270)
			(size 1.27 1.016)
			(layers "B.Cu" "B.Mask" "B.Paste")
			(net "GND")
		)
		(zone
			(layer "B.Cu")
			(hatch none 0.5)
			(connect_pads
				(clearance 0)
			)
			(min_thickness 0.25)
			(keepout
				(tracks not_allowed)
				(vias allowed)
				(pads allowed)
				(copperpour not_allowed)
				(footprints allowed)
			)
			(placement
				(enabled no)
				(sheetname "")
			)
			(fill
				(thermal_gap 0.5)
				(thermal_bridge_width 0.5)
				(island_removal_mode 0)
			)
			(polygon
				(pts
					(xy 262.4328 -27.178) (xy 262.4328 -25.908) (xy 263.1948 -25.908) (xy 263.1948 -27.178)
				)
			)
		)
	)
	(footprint ""
		(layer "B.Cu")
		(at 173.863 -81.661 -90)
		(property "Reference" "C6P9"
			(at 0 0 90)
			(layer "B.SilkS")
			(hide yes)
			(effects
				(font
					(size 1.27 1.27)
				)
				(justify mirror)
			)
		)
		(property "Value" ""
			(at 0 0 90)
			(layer "B.Fab")
			(effects
				(font
					(size 1.27 1.27)
				)
				(justify mirror)
			)
		)
		(duplicate_pad_numbers_are_jumpers no)
		(fp_poly
			(pts
				(xy -0.3048 -0.1016) (xy -0.3048 0.9906) (xy 0.3048 0.9906) (xy 0.3048 -0.1016)
			)
			(stroke
				(width 0)
				(type default)
			)
			(fill no)
			(layer "B.CrtYd")
		)
		(fp_line
			(start -0.3048 0.9906)
			(end -0.3048 -0.1016)
			(stroke
				(width 0.1)
				(type default)
			)
			(layer "B.Fab")
		)
		(fp_line
			(start 0.3048 0.9906)
			(end -0.3048 0.9906)
			(stroke
				(width 0.1)
				(type default)
			)
			(layer "B.Fab")
		)
		(fp_line
			(start -0.3048 -0.1016)
			(end 0.3048 -0.1016)
			(stroke
				(width 0.1)
				(type default)
			)
			(layer "B.Fab")
		)
		(fp_line
			(start 0.3048 -0.1016)
			(end 0.3048 0.9906)
			(stroke
				(width 0.1)
				(type default)
			)
			(layer "B.Fab")
		)
		(pad "1" smd rect
			(at 0 0 90)
			(size 0.508 0.508)
			(layers "B.Cu" "B.Mask" "B.Paste")
			(net "P3V3_DB1200")
		)
		(pad "2" smd rect
			(at 0 0.889 90)
			(size 0.508 0.508)
			(layers "B.Cu" "B.Mask" "B.Paste")
			(net "GND")
		)
		(zone
			(layer "B.Cu")
			(hatch none 0.5)
			(connect_pads
				(clearance 0)
			)
			(min_thickness 0.25)
			(keepout
				(tracks not_allowed)
				(vias allowed)
				(pads allowed)
				(copperpour not_allowed)
				(footprints allowed)
			)
			(placement
				(enabled no)
				(sheetname "")
			)
			(fill
				(thermal_gap 0.5)
				(thermal_bridge_width 0.5)
				(island_removal_mode 0)
			)
			(polygon
				(pts
					(xy 173.228 -81.407) (xy 173.228 -81.915) (xy 173.609 -81.915) (xy 173.609 -81.407)
				)
			)
		)
		(zone
			(layer "B.Cu")
			(hatch none 0.5)
			(connect_pads
				(clearance 0)
			)
			(min_thickness 0.25)
			(keepout
				(tracks allowed)
				(vias not_allowed)
				(pads allowed)
				(copperpour not_allowed)
				(footprints allowed)
			)
			(placement
				(enabled no)
				(sheetname "")
			)
			(fill
				(thermal_gap 0.5)
				(thermal_bridge_width 0.5)
				(island_removal_mode 0)
			)
			(polygon
				(pts
					(xy 173.609 -81.407) (xy 173.609 -81.915) (xy 173.228 -81.915) (xy 173.228 -81.407)
				)
			)
		)
	)
	(footprint ""
		(layer "B.Cu")
		(at 110.007654 -73.51014)
		(property "Reference" "C7P14"
			(at 0 0 0)
			(layer "B.SilkS")
			(hide yes)
			(effects
				(font
					(size 1.27 1.27)
				)
				(justify mirror)
			)
		)
		(property "Value" ""
			(at 0 0 0)
			(layer "B.Fab")
			(effects
				(font
					(size 1.27 1.27)
				)
				(justify mirror)
			)
		)
		(duplicate_pad_numbers_are_jumpers no)
		(fp_poly
			(pts
				(xy 0.7239 -0.2159) (xy -0.7239 -0.2159) (xy -0.7239 1.9939) (xy 0.7239 1.9939)
			)
			(stroke
				(width 0)
				(type default)
			)
			(fill no)
			(layer "B.CrtYd")
		)
		(fp_line
			(start -0.7239 -0.2159)
			(end 0.7239 -0.2159)
			(stroke
				(width 0.1)
				(type default)
			)
			(layer "B.Fab")
		)
		(fp_line
			(start -0.7239 1.9939)
			(end -0.7239 -0.2159)
			(stroke
				(width 0.1)
				(type default)
			)
			(layer "B.Fab")
		)
		(fp_line
			(start 0.7239 -0.2159)
			(end 0.7239 1.9939)
			(stroke
				(width 0.1)
				(type default)
			)
			(layer "B.Fab")
		)
		(fp_line
			(start 0.7239 1.9939)
			(end -0.7239 1.9939)
			(stroke
				(width 0.1)
				(type default)
			)
			(layer "B.Fab")
		)
		(pad "1" smd rect
			(at 0 0 180)
			(size 1.27 1.016)
			(layers "B.Cu" "B.Mask" "B.Paste")
			(net "PVCCMCP_CPU1")
		)
		(pad "2" smd rect
			(at 0 1.778 180)
			(size 1.27 1.016)
			(layers "B.Cu" "B.Mask" "B.Paste")
			(net "GND")
		)
		(zone
			(layer "B.Cu")
			(hatch none 0.5)
			(connect_pads
				(clearance 0)
			)
			(min_thickness 0.25)
			(keepout
				(tracks not_allowed)
				(vias allowed)
				(pads allowed)
				(copperpour not_allowed)
				(footprints allowed)
			)
			(placement
				(enabled no)
				(sheetname "")
			)
			(fill
				(thermal_gap 0.5)
				(thermal_bridge_width 0.5)
				(island_removal_mode 0)
			)
			(polygon
				(pts
					(xy 110.642654 -73.00214) (xy 109.372654 -73.00214) (xy 109.372654 -72.24014) (xy 110.642654 -72.24014)
				)
			)
		)
	)
	(footprint ""
		(layer "B.Cu")
		(at 381.127 -82.423 90)
		(property "Reference" "U7W1"
			(at 0 0 90)
			(layer "B.SilkS")
			(hide yes)
			(effects
				(font
					(size 1.27 1.27)
				)
				(justify mirror)
			)
		)
		(property "Value" "*"
			(at 2.3622 -8.3185 90)
			(unlocked yes)
			(layer "B.Fab")
			(hide yes)
			(effects
				(font
					(size 1.27 1.016)
					(thickness 0.1524)
				)
				(justify mirror)
			)
		)
		(property "Device Type" "PI5A3157BC6E-GP_DISCRET-GC2-PIA"
			(at 2.3622 -10.2235 90)
			(unlocked yes)
			(layer "B.Fab")
			(hide yes)
			(effects
				(font
					(size 1.27 1.016)
					(thickness 0.1524)
				)
				(justify mirror)
			)
		)
		(duplicate_pad_numbers_are_jumpers no)
		(fp_line
			(start 1.4478 -1.7018)
			(end 1.4478 1.7018)
			(stroke
				(width 0.1524)
				(type default)
			)
			(layer "B.SilkS")
		)
		(fp_line
			(start -1.4478 -1.7018)
			(end 1.4478 -1.7018)
			(stroke
				(width 0.1524)
				(type default)
			)
			(layer "B.SilkS")
		)
		(fp_line
			(start 1.4478 1.7018)
			(end -1.4478 1.7018)
			(stroke
				(width 0.1524)
				(type default)
			)
			(layer "B.SilkS")
		)
		(fp_line
			(start -1.4478 1.7018)
			(end -1.4478 -1.7018)
			(stroke
				(width 0.1524)
				(type default)
			)
			(layer "B.SilkS")
		)
		(fp_line
			(start 1.5494 1.7907)
			(end 1.5494 0.8255)
			(stroke
				(width 0.3302)
				(type default)
			)
			(layer "B.SilkS")
		)
		(fp_line
			(start 0.5715 1.7907)
			(end 1.5494 1.7907)
			(stroke
				(width 0.3302)
				(type default)
			)
			(layer "B.SilkS")
		)
		(fp_poly
			(pts
				(xy 0.6604 1.7272) (xy 1.016 2.0828) (xy 0.3048 2.0828)
			)
			(stroke
				(width 0)
				(type default)
			)
			(fill yes)
			(layer "B.SilkS")
		)
		(fp_poly
			(pts
				(xy 1.524 -1.778) (xy -1.524 -1.778) (xy -1.524 1.778) (xy 1.524 1.778)
			)
			(stroke
				(width 0)
				(type default)
			)
			(fill no)
			(layer "B.CrtYd")
		)
		(fp_poly
			(pts
				(xy 1.524 -1.778) (xy -1.524 -1.778) (xy -1.524 1.778) (xy 1.524 1.778)
			)
			(stroke
				(width 0)
				(type default)
			)
			(fill no)
			(layer "B.Fab")
		)
		(pad "1" smd rect
			(at 0.65024 0.9398 270)
			(size 0.4064 1.016)
			(layers "B.Cu" "B.Mask" "B.Paste")
			(net "PECI_BMC")
		)
		(pad "2" smd rect
			(at 0 0.9398 270)
			(size 0.4064 1.016)
			(layers "B.Cu" "B.Mask" "B.Paste")
			(net "GND")
		)
		(pad "3" smd rect
			(at -0.65024 0.9398 270)
			(size 0.4064 1.016)
			(layers "B.Cu" "B.Mask" "B.Paste")
			(net "PECI_PCH")
		)
		(pad "4" smd rect
			(at -0.65024 -0.9398 270)
			(size 0.4064 1.016)
			(layers "B.Cu" "B.Mask" "B.Paste")
			(net "PECI_CPU_G")
		)
		(pad "5" smd rect
			(at 0 -0.9398 270)
			(size 0.4064 1.016)
			(layers "B.Cu" "B.Mask" "B.Paste")
			(net "P3V3_STBY")
		)
		(pad "6" smd rect
			(at 0.65024 -0.9398 270)
			(size 0.4064 1.016)
			(layers "B.Cu" "B.Mask" "B.Paste")
			(net "PECI_SEL")
		)
	)
	(footprint ""
		(layer "B.Cu")
		(at 376.344688 -69.895466 180)
		(property "Reference" "C2P6"
			(at 0 0 0)
			(layer "B.SilkS")
			(hide yes)
			(effects
				(font
					(size 1.27 1.27)
				)
				(justify mirror)
			)
		)
		(property "Value" ""
			(at 0 0 0)
			(layer "B.Fab")
			(effects
				(font
					(size 1.27 1.27)
				)
				(justify mirror)
			)
		)
		(duplicate_pad_numbers_are_jumpers no)
		(fp_rect
			(start 0.2794 0.9144)
			(end -0.2794 -0.1143)
			(stroke
				(width 0)
				(type default)
			)
			(fill no)
			(layer "B.CrtYd")
		)
		(fp_line
			(start 0.2794 0.9144)
			(end 0.2794 -0.1143)
			(stroke
				(width 0.1)
				(type default)
			)
			(layer "B.Fab")
		)
		(fp_line
			(start 0.2794 -0.1143)
			(end -0.2794 -0.1143)
			(stroke
				(width 0.1)
				(type default)
			)
			(layer "B.Fab")
		)
		(fp_line
			(start -0.2794 0.9144)
			(end 0.2794 0.9144)
			(stroke
				(width 0.1)
				(type default)
			)
			(layer "B.Fab")
		)
		(fp_line
			(start -0.2794 -0.1143)
			(end -0.2794 0.9144)
			(stroke
				(width 0.1)
				(type default)
			)
			(layer "B.Fab")
		)
		(pad "1" smd custom
			(at 0 0 90)
			(size 0.10414 0.10414)
			(layers "B.Cu" "B.Mask" "B.Paste")
			(net "P3V3_STBY")
			(options
				(clearance outline)
				(anchor circle)
			)
			(primitives
				(gr_poly
					(pts
						(xy -0.20828 -0.08636) (xy -0.20828 0.08636) (xy -0.08636 0.20828) (xy 0.086614 0.20828) (xy 0.20828 0.086614)
						(xy 0.20828 -0.08636) (xy 0.08636 -0.20828) (xy -0.08636 -0.20828)
					)
					(width 0)
					(fill yes)
				)
			)
		)
		(pad "2" smd custom
			(at 0 0.8001 90)
			(size 0.10414 0.10414)
			(layers "B.Cu" "B.Mask" "B.Paste")
			(net "GND")
			(options
				(clearance outline)
				(anchor circle)
			)
			(primitives
				(gr_poly
					(pts
						(xy -0.20828 -0.08636) (xy -0.20828 0.08636) (xy -0.08636 0.20828) (xy 0.086614 0.20828) (xy 0.20828 0.086614)
						(xy 0.20828 -0.08636) (xy 0.08636 -0.20828) (xy -0.08636 -0.20828)
					)
					(width 0)
					(fill yes)
				)
			)
		)
		(zone
			(layer "B.Cu")
			(hatch none 0.5)
			(connect_pads
				(clearance 0)
			)
			(min_thickness 0.25)
			(keepout
				(tracks not_allowed)
				(vias allowed)
				(pads allowed)
				(copperpour not_allowed)
				(footprints allowed)
			)
			(placement
				(enabled no)
				(sheetname "")
			)
			(fill
				(thermal_gap 0.5)
				(thermal_bridge_width 0.5)
				(island_removal_mode 0)
			)
			(polygon
				(pts
					(xy 376.257058 -70.105016) (xy 376.257058 -70.486016) (xy 376.432318 -70.486016) (xy 376.432572 -70.105016)
				)
			)
		)
		(zone
			(layer "B.Cu")
			(hatch none 0.5)
			(connect_pads
				(clearance 0)
			)
			(min_thickness 0.25)
			(keepout
				(tracks allowed)
				(vias not_allowed)
				(pads allowed)
				(copperpour not_allowed)
				(footprints allowed)
			)
			(placement
				(enabled no)
				(sheetname "")
			)
			(fill
				(thermal_gap 0.5)
				(thermal_bridge_width 0.5)
				(island_removal_mode 0)
			)
			(polygon
				(pts
					(xy 376.257058 -70.105016) (xy 376.257058 -70.486016) (xy 376.432318 -70.486016) (xy 376.432572 -70.105016)
				)
			)
		)
	)
	(footprint ""
		(layer "B.Cu")
		(at 80.81518 -125.64745 90)
		(property "Reference" "C8M10"
			(at -1.17602 3.79222 0)
			(unlocked yes)
			(layer "B.SilkS")
			(effects
				(font
					(size 0.7874 0.5842)
					(thickness 0.1524)
				)
				(justify mirror)
			)
		)
		(property "Value" ""
			(at 0 0 90)
			(layer "B.Fab")
			(effects
				(font
					(size 1.27 1.27)
				)
				(justify mirror)
			)
		)
		(duplicate_pad_numbers_are_jumpers no)
		(fp_rect
			(start 0.500126 1.598422)
			(end -0.500126 -0.201422)
			(stroke
				(width 0)
				(type default)
			)
			(fill no)
			(layer "B.CrtYd")
		)
		(fp_line
			(start 0.500126 -0.201422)
			(end -0.500126 -0.201422)
			(stroke
				(width 0.1)
				(type default)
			)
			(layer "B.Fab")
		)
		(fp_line
			(start -0.500126 -0.201422)
			(end -0.500126 1.598422)
			(stroke
				(width 0.1)
				(type default)
			)
			(layer "B.Fab")
		)
		(fp_line
			(start 0.500126 1.598422)
			(end 0.500126 -0.201422)
			(stroke
				(width 0.1)
				(type default)
			)
			(layer "B.Fab")
		)
		(fp_line
			(start -0.500126 1.598422)
			(end 0.500126 1.598422)
			(stroke
				(width 0.1)
				(type default)
			)
			(layer "B.Fab")
		)
		(pad "1" smd rect
			(at 0 0)
			(size 0.889 0.9906)
			(layers "B.Cu" "B.Mask" "B.Paste")
			(net "PVDDQ_KLM")
		)
		(pad "2" smd rect
			(at 0 1.397)
			(size 0.889 0.9906)
			(layers "B.Cu" "B.Mask" "B.Paste")
			(net "GND")
		)
		(zone
			(layer "B.Cu")
			(hatch none 0.5)
			(connect_pads
				(clearance 0)
			)
			(min_thickness 0.25)
			(keepout
				(tracks allowed)
				(vias not_allowed)
				(pads allowed)
				(copperpour not_allowed)
				(footprints allowed)
			)
			(placement
				(enabled no)
				(sheetname "")
			)
			(fill
				(thermal_gap 0.5)
				(thermal_bridge_width 0.5)
				(island_removal_mode 0)
			)
			(polygon
				(pts
					(xy 81.76768 -126.14275) (xy 81.25968 -126.14275) (xy 81.25968 -125.15215) (xy 81.76768 -125.15215)
				)
			)
		)
		(zone
			(layer "B.Cu")
			(hatch none 0.5)
			(connect_pads
				(clearance 0)
			)
			(min_thickness 0.25)
			(keepout
				(tracks not_allowed)
				(vias allowed)
				(pads allowed)
				(copperpour not_allowed)
				(footprints allowed)
			)
			(placement
				(enabled no)
				(sheetname "")
			)
			(fill
				(thermal_gap 0.5)
				(thermal_bridge_width 0.5)
				(island_removal_mode 0)
			)
			(polygon
				(pts
					(xy 81.76768 -126.14275) (xy 81.25968 -126.14275) (xy 81.25968 -125.15215) (xy 81.76768 -125.15215)
				)
			)
		)
	)
	(footprint ""
		(layer "B.Cu")
		(at 478.730564 -120.39473 -90)
		(property "Reference" "R1W1"
			(at 0 0 90)
			(layer "B.SilkS")
			(hide yes)
			(effects
				(font
					(size 1.27 1.27)
				)
				(justify mirror)
			)
		)
		(property "Value" "*"
			(at -0.064008 -4.108196 270)
			(unlocked yes)
			(layer "B.Fab")
			(hide yes)
			(effects
				(font
					(size 1.27 1.016)
					(thickness 0.1524)
				)
				(justify mirror)
			)
		)
		(property "Device Type" "1MR2F-L-GP_SMD-RG1-1MR2F-L-GP,A"
			(at -0.064008 -5.632196 270)
			(unlocked yes)
			(layer "B.Fab")
			(hide yes)
			(effects
				(font
					(size 1.27 1.016)
					(thickness 0.1524)
				)
				(justify mirror)
			)
		)
		(duplicate_pad_numbers_are_jumpers no)
		(fp_line
			(start -0.508 -0.9398)
			(end 0.508 -0.9398)
			(stroke
				(width 0.1524)
				(type default)
			)
			(layer "B.SilkS")
		)
		(fp_line
			(start 0.508 -0.9398)
			(end 0.508 0.9398)
			(stroke
				(width 0.1524)
				(type default)
			)
			(layer "B.SilkS")
		)
		(fp_rect
			(start 0.508 0.9398)
			(end -0.508 -0.9398)
			(stroke
				(width 0)
				(type default)
			)
			(fill no)
			(layer "B.CrtYd")
		)
		(fp_rect
			(start 0.508 0.9398)
			(end -0.508 -0.9398)
			(stroke
				(width 0)
				(type default)
			)
			(fill no)
			(layer "B.Fab")
		)
		(pad "1" smd custom
			(at 0 -0.4445 90)
			(size 0.1397 0.1397)
			(layers "B.Cu" "B.Mask" "B.Paste")
			(net "P3V3_STBY")
			(options
				(clearance outline)
				(anchor circle)
			)
			(primitives
				(gr_poly
					(pts
						(arc
							(start -0.1778 0.2794)
							(mid -0.249642 0.249642)
							(end -0.2794 0.1778)
						)
						(arc
							(start -0.2794 -0.1778)
							(mid -0.249642 -0.249642)
							(end -0.1778 -0.2794)
						)
						(arc
							(start 0.1778 -0.2794)
							(mid 0.249642 -0.249642)
							(end 0.2794 -0.1778)
						)
						(arc
							(start 0.2794 0.1778)
							(mid 0.249642 0.249642)
							(end 0.1778 0.2794)
						)
					)
					(width 0)
					(fill yes)
				)
			)
		)
		(pad "2" smd custom
			(at 0 0.4445 90)
			(size 0.1397 0.1397)
			(layers "B.Cu" "B.Mask" "B.Paste")
			(net "FM_OCP_MEZZA_PRES_N")
			(options
				(clearance outline)
				(anchor circle)
			)
			(primitives
				(gr_poly
					(pts
						(arc
							(start -0.1778 0.2794)
							(mid -0.249642 0.249642)
							(end -0.2794 0.1778)
						)
						(arc
							(start -0.2794 -0.1778)
							(mid -0.249642 -0.249642)
							(end -0.1778 -0.2794)
						)
						(arc
							(start 0.1778 -0.2794)
							(mid 0.249642 -0.249642)
							(end 0.2794 -0.1778)
						)
						(arc
							(start 0.2794 0.1778)
							(mid 0.249642 0.249642)
							(end 0.1778 0.2794)
						)
					)
					(width 0)
					(fill yes)
				)
			)
		)
	)
	(footprint ""
		(layer "B.Cu")
		(at 371.875558 -41.506648 -90)
		(property "Reference" "R2T16"
			(at 0 0 90)
			(layer "B.SilkS")
			(hide yes)
			(effects
				(font
					(size 1.27 1.27)
				)
				(justify mirror)
			)
		)
		(property "Value" ""
			(at 0 0 90)
			(layer "B.Fab")
			(effects
				(font
					(size 1.27 1.27)
				)
				(justify mirror)
			)
		)
		(duplicate_pad_numbers_are_jumpers no)
		(fp_poly
			(pts
				(xy 0.2794 -0.1016) (xy -0.2794 -0.1016) (xy -0.2794 0.9906) (xy 0.2794 0.9906)
			)
			(stroke
				(width 0)
				(type default)
			)
			(fill no)
			(layer "B.CrtYd")
		)
		(fp_line
			(start -0.2794 0.9906)
			(end -0.2794 -0.1016)
			(stroke
				(width 0.1)
				(type default)
			)
			(layer "B.Fab")
		)
		(fp_line
			(start 0.2794 0.9906)
			(end -0.2794 0.9906)
			(stroke
				(width 0.1)
				(type default)
			)
			(layer "B.Fab")
		)
		(fp_line
			(start -0.2794 -0.1016)
			(end 0.2794 -0.1016)
			(stroke
				(width 0.1)
				(type default)
			)
			(layer "B.Fab")
		)
		(fp_line
			(start 0.2794 -0.1016)
			(end 0.2794 0.9906)
			(stroke
				(width 0.1)
				(type default)
			)
			(layer "B.Fab")
		)
		(pad "1" smd rect
			(at 0 0 90)
			(size 0.508 0.508)
			(layers "B.Cu" "B.Mask" "B.Paste")
			(net "H_CPU_ERR0_GTL_R_N")
		)
		(pad "2" smd rect
			(at 0 0.889 90)
			(size 0.508 0.508)
			(layers "B.Cu" "B.Mask" "B.Paste")
			(net "H_CPU_ERR0_GTL_N")
		)
		(zone
			(layer "B.Cu")
			(hatch none 0.5)
			(connect_pads
				(clearance 0)
			)
			(min_thickness 0.25)
			(keepout
				(tracks not_allowed)
				(vias allowed)
				(pads allowed)
				(copperpour not_allowed)
				(footprints allowed)
			)
			(placement
				(enabled no)
				(sheetname "")
			)
			(fill
				(thermal_gap 0.5)
				(thermal_bridge_width 0.5)
				(island_removal_mode 0)
			)
			(polygon
				(pts
					(xy 371.240558 -41.252648) (xy 371.240558 -41.760648) (xy 371.621558 -41.760648) (xy 371.621558 -41.252648)
				)
			)
		)
		(zone
			(layer "B.Cu")
			(hatch none 0.5)
			(connect_pads
				(clearance 0)
			)
			(min_thickness 0.25)
			(keepout
				(tracks allowed)
				(vias not_allowed)
				(pads allowed)
				(copperpour not_allowed)
				(footprints allowed)
			)
			(placement
				(enabled no)
				(sheetname "")
			)
			(fill
				(thermal_gap 0.5)
				(thermal_bridge_width 0.5)
				(island_removal_mode 0)
			)
			(polygon
				(pts
					(xy 371.621558 -41.252648) (xy 371.621558 -41.760648) (xy 371.240558 -41.760648) (xy 371.240558 -41.252648)
				)
			)
		)
	)
	(footprint ""
		(layer "B.Cu")
		(at 272.931128 -156.960824 90)
		(property "Reference" "C5L2"
			(at 0 0 90)
			(layer "B.SilkS")
			(hide yes)
			(effects
				(font
					(size 1.27 1.27)
				)
				(justify mirror)
			)
		)
		(property "Value" ""
			(at 0 0 90)
			(layer "B.Fab")
			(effects
				(font
					(size 1.27 1.27)
				)
				(justify mirror)
			)
		)
		(duplicate_pad_numbers_are_jumpers no)
		(fp_rect
			(start 0.7239 1.9939)
			(end -0.7239 -0.2159)
			(stroke
				(width 0)
				(type default)
			)
			(fill no)
			(layer "B.CrtYd")
		)
		(fp_line
			(start 0.7239 -0.2159)
			(end 0.7239 1.9939)
			(stroke
				(width 0.1)
				(type default)
			)
			(layer "B.Fab")
		)
		(fp_line
			(start -0.7239 -0.2159)
			(end 0.7239 -0.2159)
			(stroke
				(width 0.1)
				(type default)
			)
			(layer "B.Fab")
		)
		(fp_line
			(start 0.7239 1.9939)
			(end -0.7239 1.9939)
			(stroke
				(width 0.1)
				(type default)
			)
			(layer "B.Fab")
		)
		(fp_line
			(start -0.7239 1.9939)
			(end -0.7239 -0.2159)
			(stroke
				(width 0.1)
				(type default)
			)
			(layer "B.Fab")
		)
		(pad "1" smd rect
			(at 0 0 270)
			(size 1.27 1.016)
			(layers "B.Cu" "B.Mask" "B.Paste")
			(net "PVDDQ_DEF")
		)
		(pad "2" smd rect
			(at 0 1.778 270)
			(size 1.27 1.016)
			(layers "B.Cu" "B.Mask" "B.Paste")
			(net "GND")
		)
		(zone
			(layer "B.Cu")
			(hatch none 0.5)
			(connect_pads
				(clearance 0)
			)
			(min_thickness 0.25)
			(keepout
				(tracks not_allowed)
				(vias allowed)
				(pads allowed)
				(copperpour not_allowed)
				(footprints allowed)
			)
			(placement
				(enabled no)
				(sheetname "")
			)
			(fill
				(thermal_gap 0.5)
				(thermal_bridge_width 0.5)
				(island_removal_mode 0)
			)
			(polygon
				(pts
					(xy 274.201128 -157.595824) (xy 273.439128 -157.595824) (xy 273.439128 -156.325824) (xy 274.201128 -156.325824)
				)
			)
		)
	)
	(footprint ""
		(layer "B.Cu")
		(at 23.114 -81.534)
		(property "Reference" "R9P33"
			(at 0 0 0)
			(layer "B.SilkS")
			(hide yes)
			(effects
				(font
					(size 1.27 1.27)
				)
				(justify mirror)
			)
		)
		(property "Value" ""
			(at 0 0 0)
			(layer "B.Fab")
			(effects
				(font
					(size 1.27 1.27)
				)
				(justify mirror)
			)
		)
		(duplicate_pad_numbers_are_jumpers no)
		(fp_poly
			(pts
				(xy 0.2794 -0.1016) (xy -0.2794 -0.1016) (xy -0.2794 0.9906) (xy 0.2794 0.9906)
			)
			(stroke
				(width 0)
				(type default)
			)
			(fill no)
			(layer "B.CrtYd")
		)
		(fp_line
			(start -0.2794 -0.1016)
			(end 0.2794 -0.1016)
			(stroke
				(width 0.1)
				(type default)
			)
			(layer "B.Fab")
		)
		(fp_line
			(start -0.2794 0.9906)
			(end -0.2794 -0.1016)
			(stroke
				(width 0.1)
				(type default)
			)
			(layer "B.Fab")
		)
		(fp_line
			(start 0.2794 -0.1016)
			(end 0.2794 0.9906)
			(stroke
				(width 0.1)
				(type default)
			)
			(layer "B.Fab")
		)
		(fp_line
			(start 0.2794 0.9906)
			(end -0.2794 0.9906)
			(stroke
				(width 0.1)
				(type default)
			)
			(layer "B.Fab")
		)
		(pad "1" smd rect
			(at 0 0 180)
			(size 0.508 0.508)
			(layers "B.Cu" "B.Mask" "B.Paste")
			(net "P12V_STBY")
		)
		(pad "2" smd rect
			(at 0 0.889 180)
			(size 0.508 0.508)
			(layers "B.Cu" "B.Mask" "B.Paste")
			(net "A_HSC_INAP")
		)
		(zone
			(layer "B.Cu")
			(hatch none 0.5)
			(connect_pads
				(clearance 0)
			)
			(min_thickness 0.25)
			(keepout
				(tracks allowed)
				(vias not_allowed)
				(pads allowed)
				(copperpour not_allowed)
				(footprints allowed)
			)
			(placement
				(enabled no)
				(sheetname "")
			)
			(fill
				(thermal_gap 0.5)
				(thermal_bridge_width 0.5)
				(island_removal_mode 0)
			)
			(polygon
				(pts
					(xy 23.368 -81.28) (xy 22.86 -81.28) (xy 22.86 -80.899) (xy 23.368 -80.899)
				)
			)
		)
		(zone
			(layer "B.Cu")
			(hatch none 0.5)
			(connect_pads
				(clearance 0)
			)
			(min_thickness 0.25)
			(keepout
				(tracks not_allowed)
				(vias allowed)
				(pads allowed)
				(copperpour not_allowed)
				(footprints allowed)
			)
			(placement
				(enabled no)
				(sheetname "")
			)
			(fill
				(thermal_gap 0.5)
				(thermal_bridge_width 0.5)
				(island_removal_mode 0)
			)
			(polygon
				(pts
					(xy 23.368 -80.899) (xy 22.86 -80.899) (xy 22.86 -81.28) (xy 23.368 -81.28)
				)
			)
		)
	)
	(footprint ""
		(layer "B.Cu")
		(at 459.6384 -52.457858)
		(property "Reference" "C1R4"
			(at 0 0 0)
			(layer "B.SilkS")
			(hide yes)
			(effects
				(font
					(size 1.27 1.27)
				)
				(justify mirror)
			)
		)
		(property "Value" ""
			(at 0 0 0)
			(layer "B.Fab")
			(effects
				(font
					(size 1.27 1.27)
				)
				(justify mirror)
			)
		)
		(duplicate_pad_numbers_are_jumpers no)
		(fp_poly
			(pts
				(xy -0.3048 -0.1016) (xy -0.3048 0.9906) (xy 0.3048 0.9906) (xy 0.3048 -0.1016)
			)
			(stroke
				(width 0)
				(type default)
			)
			(fill no)
			(layer "B.CrtYd")
		)
		(fp_line
			(start -0.3048 -0.1016)
			(end 0.3048 -0.1016)
			(stroke
				(width 0.1)
				(type default)
			)
			(layer "B.Fab")
		)
		(fp_line
			(start -0.3048 0.9906)
			(end -0.3048 -0.1016)
			(stroke
				(width 0.1)
				(type default)
			)
			(layer "B.Fab")
		)
		(fp_line
			(start 0.3048 -0.1016)
			(end 0.3048 0.9906)
			(stroke
				(width 0.1)
				(type default)
			)
			(layer "B.Fab")
		)
		(fp_line
			(start 0.3048 0.9906)
			(end -0.3048 0.9906)
			(stroke
				(width 0.1)
				(type default)
			)
			(layer "B.Fab")
		)
		(pad "1" smd rect
			(at 0 0 180)
			(size 0.508 0.508)
			(layers "B.Cu" "B.Mask" "B.Paste")
			(net "P3E_CPU0_PE3_OCP_TXP<1>")
		)
		(pad "2" smd rect
			(at 0 0.889 180)
			(size 0.508 0.508)
			(layers "B.Cu" "B.Mask" "B.Paste")
			(net "P3E_OCP_CPU0_PE3_C_TXP<1>")
		)
		(zone
			(layer "B.Cu")
			(hatch none 0.5)
			(connect_pads
				(clearance 0)
			)
			(min_thickness 0.25)
			(keepout
				(tracks allowed)
				(vias not_allowed)
				(pads allowed)
				(copperpour not_allowed)
				(footprints allowed)
			)
			(placement
				(enabled no)
				(sheetname "")
			)
			(fill
				(thermal_gap 0.5)
				(thermal_bridge_width 0.5)
				(island_removal_mode 0)
			)
			(polygon
				(pts
					(xy 459.8924 -52.203858) (xy 459.3844 -52.203858) (xy 459.3844 -51.822858) (xy 459.8924 -51.822858)
				)
			)
		)
		(zone
			(layer "B.Cu")
			(hatch none 0.5)
			(connect_pads
				(clearance 0)
			)
			(min_thickness 0.25)
			(keepout
				(tracks not_allowed)
				(vias allowed)
				(pads allowed)
				(copperpour not_allowed)
				(footprints allowed)
			)
			(placement
				(enabled no)
				(sheetname "")
			)
			(fill
				(thermal_gap 0.5)
				(thermal_bridge_width 0.5)
				(island_removal_mode 0)
			)
			(polygon
				(pts
					(xy 459.8924 -51.822858) (xy 459.3844 -51.822858) (xy 459.3844 -52.203858) (xy 459.8924 -52.203858)
				)
			)
		)
	)
	(footprint ""
		(layer "B.Cu")
		(at 97.270824 -83.74634 90)
		(property "Reference" "C8P5"
			(at 0 0 90)
			(layer "B.SilkS")
			(hide yes)
			(effects
				(font
					(size 1.27 1.27)
				)
				(justify mirror)
			)
		)
		(property "Value" ""
			(at 0 0 90)
			(layer "B.Fab")
			(effects
				(font
					(size 1.27 1.27)
				)
				(justify mirror)
			)
		)
		(duplicate_pad_numbers_are_jumpers no)
		(fp_poly
			(pts
				(xy 0.7239 -0.2159) (xy -0.7239 -0.2159) (xy -0.7239 1.9939) (xy 0.7239 1.9939)
			)
			(stroke
				(width 0)
				(type default)
			)
			(fill no)
			(layer "B.CrtYd")
		)
		(fp_line
			(start 0.7239 -0.2159)
			(end 0.7239 1.9939)
			(stroke
				(width 0.1)
				(type default)
			)
			(layer "B.Fab")
		)
		(fp_line
			(start -0.7239 -0.2159)
			(end 0.7239 -0.2159)
			(stroke
				(width 0.1)
				(type default)
			)
			(layer "B.Fab")
		)
		(fp_line
			(start 0.7239 1.9939)
			(end -0.7239 1.9939)
			(stroke
				(width 0.1)
				(type default)
			)
			(layer "B.Fab")
		)
		(fp_line
			(start -0.7239 1.9939)
			(end -0.7239 -0.2159)
			(stroke
				(width 0.1)
				(type default)
			)
			(layer "B.Fab")
		)
		(pad "1" smd rect
			(at 0 0 270)
			(size 1.27 1.016)
			(layers "B.Cu" "B.Mask" "B.Paste")
			(net "PVSA_CPU1")
		)
		(pad "2" smd rect
			(at 0 1.778 270)
			(size 1.27 1.016)
			(layers "B.Cu" "B.Mask" "B.Paste")
			(net "GND")
		)
		(zone
			(layer "B.Cu")
			(hatch none 0.5)
			(connect_pads
				(clearance 0)
			)
			(min_thickness 0.25)
			(keepout
				(tracks not_allowed)
				(vias allowed)
				(pads allowed)
				(copperpour not_allowed)
				(footprints allowed)
			)
			(placement
				(enabled no)
				(sheetname "")
			)
			(fill
				(thermal_gap 0.5)
				(thermal_bridge_width 0.5)
				(island_removal_mode 0)
			)
			(polygon
				(pts
					(xy 97.778824 -84.38134) (xy 97.778824 -83.11134) (xy 98.540824 -83.11134) (xy 98.540824 -84.38134)
				)
			)
		)
	)
	(footprint ""
		(layer "B.Cu")
		(at 334.01 -3.302 90)
		(property "Reference" "C3U5"
			(at 2.89433 4.572 0)
			(unlocked yes)
			(layer "B.SilkS")
			(effects
				(font
					(size 0.7874 0.5842)
					(thickness 0.1524)
				)
				(justify mirror)
			)
		)
		(property "Value" ""
			(at 0 0 90)
			(layer "B.Fab")
			(effects
				(font
					(size 1.27 1.27)
				)
				(justify mirror)
			)
		)
		(duplicate_pad_numbers_are_jumpers no)
		(fp_line
			(start 2.563114 -1.616456)
			(end 2.563114 1.633728)
			(stroke
				(width 0.1524)
				(type default)
			)
			(layer "B.SilkS")
		)
		(fp_line
			(start 1.6002 -1.616456)
			(end 2.563114 -1.616456)
			(stroke
				(width 0.1524)
				(type default)
			)
			(layer "B.SilkS")
		)
		(fp_line
			(start -1.6002 -1.616456)
			(end -2.504948 -1.616456)
			(stroke
				(width 0.1524)
				(type default)
			)
			(layer "B.SilkS")
		)
		(fp_line
			(start -2.504948 -1.616456)
			(end -2.504948 1.633728)
			(stroke
				(width 0.1524)
				(type default)
			)
			(layer "B.SilkS")
		)
		(fp_line
			(start 2.563114 1.633728)
			(end 1.6002 1.633728)
			(stroke
				(width 0.1524)
				(type default)
			)
			(layer "B.SilkS")
		)
		(fp_line
			(start -2.504948 1.633728)
			(end -1.6002 1.633728)
			(stroke
				(width 0.1524)
				(type default)
			)
			(layer "B.SilkS")
		)
		(fp_line
			(start 2.286 7.366)
			(end 2.286 1.632712)
			(stroke
				(width 0.1524)
				(type default)
			)
			(layer "B.SilkS")
		)
		(fp_line
			(start 2.286 7.366)
			(end 1.60147 7.366)
			(stroke
				(width 0.1524)
				(type default)
			)
			(layer "B.SilkS")
		)
		(fp_line
			(start -2.286 7.366)
			(end -2.286 1.63195)
			(stroke
				(width 0.1524)
				(type default)
			)
			(layer "B.SilkS")
		)
		(fp_line
			(start -2.286 7.366)
			(end -1.600708 7.366)
			(stroke
				(width 0.1524)
				(type default)
			)
			(layer "B.SilkS")
		)
		(fp_rect
			(start -2.286 -0.254)
			(end 2.286 7.366)
			(stroke
				(width 0)
				(type default)
			)
			(fill no)
			(layer "B.CrtYd")
		)
		(fp_line
			(start 2.286 -0.254)
			(end -2.286 -0.254)
			(stroke
				(width 0.1)
				(type default)
			)
			(layer "B.Fab")
		)
		(fp_line
			(start -2.286 -0.254)
			(end -2.286 7.366)
			(stroke
				(width 0.1)
				(type default)
			)
			(layer "B.Fab")
		)
		(fp_line
			(start 2.286 7.366)
			(end 2.286 -0.254)
			(stroke
				(width 0.1)
				(type default)
			)
			(layer "B.Fab")
		)
		(fp_line
			(start -2.286 7.366)
			(end 2.286 7.366)
			(stroke
				(width 0.1)
				(type default)
			)
			(layer "B.Fab")
		)
		(pad "1" smd rect
			(at 0 0 270)
			(size 2.54 3.048)
			(layers "B.Cu" "B.Mask" "B.Paste")
			(net "PVDDQ_ABC")
		)
		(pad "2" smd rect
			(at 0 7.112 270)
			(size 2.54 3.048)
			(layers "B.Cu" "B.Mask" "B.Paste")
			(net "GND")
		)
	)
	(footprint ""
		(layer "B.Cu")
		(at 427.4185 -24.13 90)
		(property "Reference" "R2N13"
			(at 0.8382 -0.67818 90)
			(unlocked yes)
			(layer "B.SilkS")
			(effects
				(font
					(size 0.4064 0.254)
					(thickness 0.1524)
				)
				(justify left mirror)
			)
		)
		(property "Value" ""
			(at 0 0 90)
			(layer "B.Fab")
			(effects
				(font
					(size 1.27 1.27)
				)
				(justify mirror)
			)
		)
		(duplicate_pad_numbers_are_jumpers no)
		(fp_poly
			(pts
				(xy 0.2794 -0.1016) (xy -0.2794 -0.1016) (xy -0.2794 0.9906) (xy 0.2794 0.9906)
			)
			(stroke
				(width 0)
				(type default)
			)
			(fill no)
			(layer "B.CrtYd")
		)
		(fp_line
			(start 0.2794 -0.1016)
			(end 0.2794 0.9906)
			(stroke
				(width 0.1)
				(type default)
			)
			(layer "B.Fab")
		)
		(fp_line
			(start -0.2794 -0.1016)
			(end 0.2794 -0.1016)
			(stroke
				(width 0.1)
				(type default)
			)
			(layer "B.Fab")
		)
		(fp_line
			(start 0.2794 0.9906)
			(end -0.2794 0.9906)
			(stroke
				(width 0.1)
				(type default)
			)
			(layer "B.Fab")
		)
		(fp_line
			(start -0.2794 0.9906)
			(end -0.2794 -0.1016)
			(stroke
				(width 0.1)
				(type default)
			)
			(layer "B.Fab")
		)
		(pad "1" smd rect
			(at 0 0 270)
			(size 0.508 0.508)
			(layers "B.Cu" "B.Mask" "B.Paste")
			(net "FM_BIOS_PREFRB2_GOOD")
		)
		(pad "2" smd rect
			(at 0 0.889 270)
			(size 0.508 0.508)
			(layers "B.Cu" "B.Mask" "B.Paste")
			(net "GND")
		)
		(zone
			(layer "B.Cu")
			(hatch none 0.5)
			(connect_pads
				(clearance 0)
			)
			(min_thickness 0.25)
			(keepout
				(tracks allowed)
				(vias not_allowed)
				(pads allowed)
				(copperpour not_allowed)
				(footprints allowed)
			)
			(placement
				(enabled no)
				(sheetname "")
			)
			(fill
				(thermal_gap 0.5)
				(thermal_bridge_width 0.5)
				(island_removal_mode 0)
			)
			(polygon
				(pts
					(xy 427.6725 -24.384) (xy 427.6725 -23.876) (xy 428.0535 -23.876) (xy 428.0535 -24.384)
				)
			)
		)
		(zone
			(layer "B.Cu")
			(hatch none 0.5)
			(connect_pads
				(clearance 0)
			)
			(min_thickness 0.25)
			(keepout
				(tracks not_allowed)
				(vias allowed)
				(pads allowed)
				(copperpour not_allowed)
				(footprints allowed)
			)
			(placement
				(enabled no)
				(sheetname "")
			)
			(fill
				(thermal_gap 0.5)
				(thermal_bridge_width 0.5)
				(island_removal_mode 0)
			)
			(polygon
				(pts
					(xy 428.0535 -24.384) (xy 428.0535 -23.876) (xy 427.6725 -23.876) (xy 427.6725 -24.384)
				)
			)
		)
	)
	(footprint ""
		(layer "B.Cu")
		(at 349.631 -27.9654 180)
		(property "Reference" "C3T10"
			(at 0 0 0)
			(layer "B.SilkS")
			(hide yes)
			(effects
				(font
					(size 1.27 1.27)
				)
				(justify mirror)
			)
		)
		(property "Value" ""
			(at 0 0 0)
			(layer "B.Fab")
			(effects
				(font
					(size 1.27 1.27)
				)
				(justify mirror)
			)
		)
		(duplicate_pad_numbers_are_jumpers no)
		(fp_poly
			(pts
				(xy -0.3048 -0.1016) (xy -0.3048 0.9906) (xy 0.3048 0.9906) (xy 0.3048 -0.1016)
			)
			(stroke
				(width 0)
				(type default)
			)
			(fill no)
			(layer "B.CrtYd")
		)
		(fp_line
			(start 0.3048 0.9906)
			(end -0.3048 0.9906)
			(stroke
				(width 0.1)
				(type default)
			)
			(layer "B.Fab")
		)
		(fp_line
			(start 0.3048 -0.1016)
			(end 0.3048 0.9906)
			(stroke
				(width 0.1)
				(type default)
			)
			(layer "B.Fab")
		)
		(fp_line
			(start -0.3048 0.9906)
			(end -0.3048 -0.1016)
			(stroke
				(width 0.1)
				(type default)
			)
			(layer "B.Fab")
		)
		(fp_line
			(start -0.3048 -0.1016)
			(end 0.3048 -0.1016)
			(stroke
				(width 0.1)
				(type default)
			)
			(layer "B.Fab")
		)
		(pad "1" smd rect
			(at 0 0)
			(size 0.508 0.508)
			(layers "B.Cu" "B.Mask" "B.Paste")
			(net "VR_FET_SW_P12V_STBY_PVPP_ABC")
		)
		(pad "2" smd rect
			(at 0 0.889)
			(size 0.508 0.508)
			(layers "B.Cu" "B.Mask" "B.Paste")
			(net "GND")
		)
		(zone
			(layer "B.Cu")
			(hatch none 0.5)
			(connect_pads
				(clearance 0)
			)
			(min_thickness 0.25)
			(keepout
				(tracks not_allowed)
				(vias allowed)
				(pads allowed)
				(copperpour not_allowed)
				(footprints allowed)
			)
			(placement
				(enabled no)
				(sheetname "")
			)
			(fill
				(thermal_gap 0.5)
				(thermal_bridge_width 0.5)
				(island_removal_mode 0)
			)
			(polygon
				(pts
					(xy 349.377 -28.6004) (xy 349.885 -28.6004) (xy 349.885 -28.2194) (xy 349.377 -28.2194)
				)
			)
		)
		(zone
			(layer "B.Cu")
			(hatch none 0.5)
			(connect_pads
				(clearance 0)
			)
			(min_thickness 0.25)
			(keepout
				(tracks allowed)
				(vias not_allowed)
				(pads allowed)
				(copperpour not_allowed)
				(footprints allowed)
			)
			(placement
				(enabled no)
				(sheetname "")
			)
			(fill
				(thermal_gap 0.5)
				(thermal_bridge_width 0.5)
				(island_removal_mode 0)
			)
			(polygon
				(pts
					(xy 349.377 -28.2194) (xy 349.885 -28.2194) (xy 349.885 -28.6004) (xy 349.377 -28.6004)
				)
			)
		)
	)
	(footprint ""
		(layer "B.Cu")
		(at 173.736 -87.757)
		(property "Reference" "R6P1"
			(at 0 0 0)
			(layer "B.SilkS")
			(hide yes)
			(effects
				(font
					(size 1.27 1.27)
				)
				(justify mirror)
			)
		)
		(property "Value" ""
			(at 0 0 0)
			(layer "B.Fab")
			(effects
				(font
					(size 1.27 1.27)
				)
				(justify mirror)
			)
		)
		(duplicate_pad_numbers_are_jumpers no)
		(fp_poly
			(pts
				(xy 0.2794 -0.1016) (xy -0.2794 -0.1016) (xy -0.2794 0.9906) (xy 0.2794 0.9906)
			)
			(stroke
				(width 0)
				(type default)
			)
			(fill no)
			(layer "B.CrtYd")
		)
		(fp_line
			(start -0.2794 -0.1016)
			(end 0.2794 -0.1016)
			(stroke
				(width 0.1)
				(type default)
			)
			(layer "B.Fab")
		)
		(fp_line
			(start -0.2794 0.9906)
			(end -0.2794 -0.1016)
			(stroke
				(width 0.1)
				(type default)
			)
			(layer "B.Fab")
		)
		(fp_line
			(start 0.2794 -0.1016)
			(end 0.2794 0.9906)
			(stroke
				(width 0.1)
				(type default)
			)
			(layer "B.Fab")
		)
		(fp_line
			(start 0.2794 0.9906)
			(end -0.2794 0.9906)
			(stroke
				(width 0.1)
				(type default)
			)
			(layer "B.Fab")
		)
		(pad "1" smd rect
			(at 0 0 180)
			(size 0.508 0.508)
			(layers "B.Cu" "B.Mask" "B.Paste")
			(net "CLK_100M_CPU0_RC_REFCLK0_DP")
		)
		(pad "2" smd rect
			(at 0 0.889 180)
			(size 0.508 0.508)
			(layers "B.Cu" "B.Mask" "B.Paste")
			(net "GND")
		)
		(zone
			(layer "B.Cu")
			(hatch none 0.5)
			(connect_pads
				(clearance 0)
			)
			(min_thickness 0.25)
			(keepout
				(tracks allowed)
				(vias not_allowed)
				(pads allowed)
				(copperpour not_allowed)
				(footprints allowed)
			)
			(placement
				(enabled no)
				(sheetname "")
			)
			(fill
				(thermal_gap 0.5)
				(thermal_bridge_width 0.5)
				(island_removal_mode 0)
			)
			(polygon
				(pts
					(xy 173.99 -87.503) (xy 173.482 -87.503) (xy 173.482 -87.122) (xy 173.99 -87.122)
				)
			)
		)
		(zone
			(layer "B.Cu")
			(hatch none 0.5)
			(connect_pads
				(clearance 0)
			)
			(min_thickness 0.25)
			(keepout
				(tracks not_allowed)
				(vias allowed)
				(pads allowed)
				(copperpour not_allowed)
				(footprints allowed)
			)
			(placement
				(enabled no)
				(sheetname "")
			)
			(fill
				(thermal_gap 0.5)
				(thermal_bridge_width 0.5)
				(island_removal_mode 0)
			)
			(polygon
				(pts
					(xy 173.99 -87.122) (xy 173.482 -87.122) (xy 173.482 -87.503) (xy 173.99 -87.503)
				)
			)
		)
	)
	(footprint ""
		(layer "B.Cu")
		(at 480.037902 -55.990998)
		(property "Reference" "R8E23"
			(at 0 0 0)
			(layer "B.SilkS")
			(hide yes)
			(effects
				(font
					(size 1.27 1.27)
				)
				(justify mirror)
			)
		)
		(property "Value" ""
			(at 0 0 0)
			(layer "B.Fab")
			(effects
				(font
					(size 1.27 1.27)
				)
				(justify mirror)
			)
		)
		(duplicate_pad_numbers_are_jumpers no)
		(fp_poly
			(pts
				(xy 0.2794 -0.1016) (xy -0.2794 -0.1016) (xy -0.2794 0.9906) (xy 0.2794 0.9906)
			)
			(stroke
				(width 0)
				(type default)
			)
			(fill no)
			(layer "B.CrtYd")
		)
		(fp_line
			(start -0.2794 -0.1016)
			(end 0.2794 -0.1016)
			(stroke
				(width 0.1)
				(type default)
			)
			(layer "B.Fab")
		)
		(fp_line
			(start -0.2794 0.9906)
			(end -0.2794 -0.1016)
			(stroke
				(width 0.1)
				(type default)
			)
			(layer "B.Fab")
		)
		(fp_line
			(start 0.2794 -0.1016)
			(end 0.2794 0.9906)
			(stroke
				(width 0.1)
				(type default)
			)
			(layer "B.Fab")
		)
		(fp_line
			(start 0.2794 0.9906)
			(end -0.2794 0.9906)
			(stroke
				(width 0.1)
				(type default)
			)
			(layer "B.Fab")
		)
		(pad "1" smd rect
			(at 0 0 180)
			(size 0.508 0.508)
			(layers "B.Cu" "B.Mask" "B.Paste")
			(net "PU_TRI_STATE_EN")
		)
		(pad "2" smd rect
			(at 0 0.889 180)
			(size 0.508 0.508)
			(layers "B.Cu" "B.Mask" "B.Paste")
			(net "P3V3_STBY")
		)
		(zone
			(layer "B.Cu")
			(hatch none 0.5)
			(connect_pads
				(clearance 0)
			)
			(min_thickness 0.25)
			(keepout
				(tracks allowed)
				(vias not_allowed)
				(pads allowed)
				(copperpour not_allowed)
				(footprints allowed)
			)
			(placement
				(enabled no)
				(sheetname "")
			)
			(fill
				(thermal_gap 0.5)
				(thermal_bridge_width 0.5)
				(island_removal_mode 0)
			)
			(polygon
				(pts
					(xy 480.291902 -55.736998) (xy 479.783902 -55.736998) (xy 479.783902 -55.355998) (xy 480.291902 -55.355998)
				)
			)
		)
		(zone
			(layer "B.Cu")
			(hatch none 0.5)
			(connect_pads
				(clearance 0)
			)
			(min_thickness 0.25)
			(keepout
				(tracks not_allowed)
				(vias allowed)
				(pads allowed)
				(copperpour not_allowed)
				(footprints allowed)
			)
			(placement
				(enabled no)
				(sheetname "")
			)
			(fill
				(thermal_gap 0.5)
				(thermal_bridge_width 0.5)
				(island_removal_mode 0)
			)
			(polygon
				(pts
					(xy 480.291902 -55.355998) (xy 479.783902 -55.355998) (xy 479.783902 -55.736998) (xy 480.291902 -55.736998)
				)
			)
		)
	)
	(footprint ""
		(layer "B.Cu")
		(at 17.399 -89.281 -90)
		(property "Reference" "R9N14"
			(at 0 0 90)
			(layer "B.SilkS")
			(hide yes)
			(effects
				(font
					(size 1.27 1.27)
				)
				(justify mirror)
			)
		)
		(property "Value" ""
			(at 0 0 90)
			(layer "B.Fab")
			(effects
				(font
					(size 1.27 1.27)
				)
				(justify mirror)
			)
		)
		(duplicate_pad_numbers_are_jumpers no)
		(fp_poly
			(pts
				(xy 0.2794 -0.1016) (xy -0.2794 -0.1016) (xy -0.2794 0.9906) (xy 0.2794 0.9906)
			)
			(stroke
				(width 0)
				(type default)
			)
			(fill no)
			(layer "B.CrtYd")
		)
		(fp_line
			(start -0.2794 0.9906)
			(end -0.2794 -0.1016)
			(stroke
				(width 0.1)
				(type default)
			)
			(layer "B.Fab")
		)
		(fp_line
			(start 0.2794 0.9906)
			(end -0.2794 0.9906)
			(stroke
				(width 0.1)
				(type default)
			)
			(layer "B.Fab")
		)
		(fp_line
			(start -0.2794 -0.1016)
			(end 0.2794 -0.1016)
			(stroke
				(width 0.1)
				(type default)
			)
			(layer "B.Fab")
		)
		(fp_line
			(start 0.2794 -0.1016)
			(end 0.2794 0.9906)
			(stroke
				(width 0.1)
				(type default)
			)
			(layer "B.Fab")
		)
		(pad "1" smd rect
			(at 0 0 90)
			(size 0.508 0.508)
			(layers "B.Cu" "B.Mask" "B.Paste")
			(net "PVCCIO_CPU1")
		)
		(pad "2" smd rect
			(at 0 0.889 90)
			(size 0.508 0.508)
			(layers "B.Cu" "B.Mask" "B.Paste")
			(net "VR_PVCCIN_CPU1_VREN")
		)
		(zone
			(layer "B.Cu")
			(hatch none 0.5)
			(connect_pads
				(clearance 0)
			)
			(min_thickness 0.25)
			(keepout
				(tracks not_allowed)
				(vias allowed)
				(pads allowed)
				(copperpour not_allowed)
				(footprints allowed)
			)
			(placement
				(enabled no)
				(sheetname "")
			)
			(fill
				(thermal_gap 0.5)
				(thermal_bridge_width 0.5)
				(island_removal_mode 0)
			)
			(polygon
				(pts
					(xy 16.764 -89.027) (xy 16.764 -89.535) (xy 17.145 -89.535) (xy 17.145 -89.027)
				)
			)
		)
		(zone
			(layer "B.Cu")
			(hatch none 0.5)
			(connect_pads
				(clearance 0)
			)
			(min_thickness 0.25)
			(keepout
				(tracks allowed)
				(vias not_allowed)
				(pads allowed)
				(copperpour not_allowed)
				(footprints allowed)
			)
			(placement
				(enabled no)
				(sheetname "")
			)
			(fill
				(thermal_gap 0.5)
				(thermal_bridge_width 0.5)
				(island_removal_mode 0)
			)
			(polygon
				(pts
					(xy 17.145 -89.027) (xy 17.145 -89.535) (xy 16.764 -89.535) (xy 16.764 -89.027)
				)
			)
		)
	)
	(footprint ""
		(layer "B.Cu")
		(at 435.434994 -42.0116 -90)
		(property "Reference" "C25W5"
			(at 0.8382 -0.67818 270)
			(unlocked yes)
			(layer "B.SilkS")
			(effects
				(font
					(size 0.4064 0.254)
					(thickness 0.1524)
				)
				(justify left mirror)
			)
		)
		(property "Value" ""
			(at 0 0 90)
			(layer "B.Fab")
			(effects
				(font
					(size 1.27 1.27)
				)
				(justify mirror)
			)
		)
		(duplicate_pad_numbers_are_jumpers no)
		(fp_poly
			(pts
				(xy -0.3048 -0.1016) (xy -0.3048 0.9906) (xy 0.3048 0.9906) (xy 0.3048 -0.1016)
			)
			(stroke
				(width 0)
				(type default)
			)
			(fill no)
			(layer "B.CrtYd")
		)
		(fp_line
			(start -0.3048 0.9906)
			(end -0.3048 -0.1016)
			(stroke
				(width 0.1)
				(type default)
			)
			(layer "B.Fab")
		)
		(fp_line
			(start 0.3048 0.9906)
			(end -0.3048 0.9906)
			(stroke
				(width 0.1)
				(type default)
			)
			(layer "B.Fab")
		)
		(fp_line
			(start -0.3048 -0.1016)
			(end 0.3048 -0.1016)
			(stroke
				(width 0.1)
				(type default)
			)
			(layer "B.Fab")
		)
		(fp_line
			(start 0.3048 -0.1016)
			(end 0.3048 0.9906)
			(stroke
				(width 0.1)
				(type default)
			)
			(layer "B.Fab")
		)
		(pad "1" smd rect
			(at 0 0 90)
			(size 0.508 0.508)
			(layers "B.Cu" "B.Mask" "B.Paste")
			(net "P1V2_AUX_BMC")
		)
		(pad "2" smd rect
			(at 0 0.889 90)
			(size 0.508 0.508)
			(layers "B.Cu" "B.Mask" "B.Paste")
			(net "GND")
		)
		(zone
			(layer "B.Cu")
			(hatch none 0.5)
			(connect_pads
				(clearance 0)
			)
			(min_thickness 0.25)
			(keepout
				(tracks not_allowed)
				(vias allowed)
				(pads allowed)
				(copperpour not_allowed)
				(footprints allowed)
			)
			(placement
				(enabled no)
				(sheetname "")
			)
			(fill
				(thermal_gap 0.5)
				(thermal_bridge_width 0.5)
				(island_removal_mode 0)
			)
			(polygon
				(pts
					(xy 434.799994 -41.7576) (xy 434.799994 -42.2656) (xy 435.180994 -42.2656) (xy 435.180994 -41.7576)
				)
			)
		)
		(zone
			(layer "B.Cu")
			(hatch none 0.5)
			(connect_pads
				(clearance 0)
			)
			(min_thickness 0.25)
			(keepout
				(tracks allowed)
				(vias not_allowed)
				(pads allowed)
				(copperpour not_allowed)
				(footprints allowed)
			)
			(placement
				(enabled no)
				(sheetname "")
			)
			(fill
				(thermal_gap 0.5)
				(thermal_bridge_width 0.5)
				(island_removal_mode 0)
			)
			(polygon
				(pts
					(xy 435.180994 -41.7576) (xy 435.180994 -42.2656) (xy 434.799994 -42.2656) (xy 434.799994 -41.7576)
				)
			)
		)
	)
	(footprint ""
		(layer "B.Cu")
		(at 13.921232 3.752342 90)
		(property "Reference" "R9U8"
			(at 0 0 90)
			(layer "B.SilkS")
			(hide yes)
			(effects
				(font
					(size 1.27 1.27)
				)
				(justify mirror)
			)
		)
		(property "Value" ""
			(at 0 0 90)
			(layer "B.Fab")
			(effects
				(font
					(size 1.27 1.27)
				)
				(justify mirror)
			)
		)
		(duplicate_pad_numbers_are_jumpers no)
		(fp_poly
			(pts
				(xy 0.2794 -0.1016) (xy -0.2794 -0.1016) (xy -0.2794 0.9906) (xy 0.2794 0.9906)
			)
			(stroke
				(width 0)
				(type default)
			)
			(fill no)
			(layer "B.CrtYd")
		)
		(fp_line
			(start 0.2794 -0.1016)
			(end 0.2794 0.9906)
			(stroke
				(width 0.1)
				(type default)
			)
			(layer "B.Fab")
		)
		(fp_line
			(start -0.2794 -0.1016)
			(end 0.2794 -0.1016)
			(stroke
				(width 0.1)
				(type default)
			)
			(layer "B.Fab")
		)
		(fp_line
			(start 0.2794 0.9906)
			(end -0.2794 0.9906)
			(stroke
				(width 0.1)
				(type default)
			)
			(layer "B.Fab")
		)
		(fp_line
			(start -0.2794 0.9906)
			(end -0.2794 -0.1016)
			(stroke
				(width 0.1)
				(type default)
			)
			(layer "B.Fab")
		)
		(pad "1" smd rect
			(at 0 0 270)
			(size 0.508 0.508)
			(layers "B.Cu" "B.Mask" "B.Paste")
			(net "P3V3_STBY")
		)
		(pad "2" smd rect
			(at 0 0.889 270)
			(size 0.508 0.508)
			(layers "B.Cu" "B.Mask" "B.Paste")
			(net "VR_PVDDQ_GHJ_VREN")
		)
		(zone
			(layer "B.Cu")
			(hatch none 0.5)
			(connect_pads
				(clearance 0)
			)
			(min_thickness 0.25)
			(keepout
				(tracks allowed)
				(vias not_allowed)
				(pads allowed)
				(copperpour not_allowed)
				(footprints allowed)
			)
			(placement
				(enabled no)
				(sheetname "")
			)
			(fill
				(thermal_gap 0.5)
				(thermal_bridge_width 0.5)
				(island_removal_mode 0)
			)
			(polygon
				(pts
					(xy 14.175232 3.498342) (xy 14.175232 4.006342) (xy 14.556232 4.006342) (xy 14.556232 3.498342)
				)
			)
		)
		(zone
			(layer "B.Cu")
			(hatch none 0.5)
			(connect_pads
				(clearance 0)
			)
			(min_thickness 0.25)
			(keepout
				(tracks not_allowed)
				(vias allowed)
				(pads allowed)
				(copperpour not_allowed)
				(footprints allowed)
			)
			(placement
				(enabled no)
				(sheetname "")
			)
			(fill
				(thermal_gap 0.5)
				(thermal_bridge_width 0.5)
				(island_removal_mode 0)
			)
			(polygon
				(pts
					(xy 14.556232 3.498342) (xy 14.556232 4.006342) (xy 14.175232 4.006342) (xy 14.175232 3.498342)
				)
			)
		)
	)
	(footprint ""
		(layer "B.Cu")
		(at 164.084 -67.31)
		(property "Reference" "R6P39"
			(at 0 0 0)
			(layer "B.SilkS")
			(hide yes)
			(effects
				(font
					(size 1.27 1.27)
				)
				(justify mirror)
			)
		)
		(property "Value" ""
			(at 0 0 0)
			(layer "B.Fab")
			(effects
				(font
					(size 1.27 1.27)
				)
				(justify mirror)
			)
		)
		(duplicate_pad_numbers_are_jumpers no)
		(fp_poly
			(pts
				(xy 0.2794 -0.1016) (xy -0.2794 -0.1016) (xy -0.2794 0.9906) (xy 0.2794 0.9906)
			)
			(stroke
				(width 0)
				(type default)
			)
			(fill no)
			(layer "B.CrtYd")
		)
		(fp_line
			(start -0.2794 -0.1016)
			(end 0.2794 -0.1016)
			(stroke
				(width 0.1)
				(type default)
			)
			(layer "B.Fab")
		)
		(fp_line
			(start -0.2794 0.9906)
			(end -0.2794 -0.1016)
			(stroke
				(width 0.1)
				(type default)
			)
			(layer "B.Fab")
		)
		(fp_line
			(start 0.2794 -0.1016)
			(end 0.2794 0.9906)
			(stroke
				(width 0.1)
				(type default)
			)
			(layer "B.Fab")
		)
		(fp_line
			(start 0.2794 0.9906)
			(end -0.2794 0.9906)
			(stroke
				(width 0.1)
				(type default)
			)
			(layer "B.Fab")
		)
		(pad "1" smd rect
			(at 0 0 180)
			(size 0.508 0.508)
			(layers "B.Cu" "B.Mask" "B.Paste")
			(net "P3V3_STBY")
		)
		(pad "2" smd rect
			(at 0 0.889 180)
			(size 0.508 0.508)
			(layers "B.Cu" "B.Mask" "B.Paste")
			(net "FM_CPU1_SKTOCC_LVT3_N")
		)
		(zone
			(layer "B.Cu")
			(hatch none 0.5)
			(connect_pads
				(clearance 0)
			)
			(min_thickness 0.25)
			(keepout
				(tracks allowed)
				(vias not_allowed)
				(pads allowed)
				(copperpour not_allowed)
				(footprints allowed)
			)
			(placement
				(enabled no)
				(sheetname "")
			)
			(fill
				(thermal_gap 0.5)
				(thermal_bridge_width 0.5)
				(island_removal_mode 0)
			)
			(polygon
				(pts
					(xy 164.338 -67.056) (xy 163.83 -67.056) (xy 163.83 -66.675) (xy 164.338 -66.675)
				)
			)
		)
		(zone
			(layer "B.Cu")
			(hatch none 0.5)
			(connect_pads
				(clearance 0)
			)
			(min_thickness 0.25)
			(keepout
				(tracks not_allowed)
				(vias allowed)
				(pads allowed)
				(copperpour not_allowed)
				(footprints allowed)
			)
			(placement
				(enabled no)
				(sheetname "")
			)
			(fill
				(thermal_gap 0.5)
				(thermal_bridge_width 0.5)
				(island_removal_mode 0)
			)
			(polygon
				(pts
					(xy 164.338 -66.675) (xy 163.83 -66.675) (xy 163.83 -67.056) (xy 164.338 -67.056)
				)
			)
		)
	)
	(footprint ""
		(layer "B.Cu")
		(at 61.285628 -165.04158 -90)
		(property "Reference" "T1D3"
			(at 0 0 90)
			(layer "B.SilkS")
			(hide yes)
			(effects
				(font
					(size 1.27 1.27)
				)
				(justify mirror)
			)
		)
		(property "Value" "*"
			(at 3.4036 -4.46405 270)
			(unlocked yes)
			(layer "B.Fab")
			(hide yes)
			(effects
				(font
					(size 0.889 0.889)
					(thickness 0.1524)
				)
				(justify mirror)
			)
		)
		(property "Device Type" "TEST-PAD-12P-1-GP-U_DISCRET-GBA"
			(at 3.4036 -5.98805 270)
			(unlocked yes)
			(layer "B.Fab")
			(hide yes)
			(effects
				(font
					(size 0.889 0.889)
					(thickness 0.1524)
				)
				(justify mirror)
			)
		)
		(duplicate_pad_numbers_are_jumpers no)
		(fp_line
			(start -2.3622 3.4798)
			(end 2.3876 3.4798)
			(stroke
				(width 0.1524)
				(type default)
			)
			(layer "B.SilkS")
		)
		(fp_line
			(start 2.3876 3.4798)
			(end 2.3876 -4.826)
			(stroke
				(width 0.1524)
				(type default)
			)
			(layer "B.SilkS")
		)
		(fp_line
			(start -2.3622 -4.826)
			(end -2.3622 3.4798)
			(stroke
				(width 0.1524)
				(type default)
			)
			(layer "B.SilkS")
		)
		(fp_line
			(start 2.3876 -4.826)
			(end -2.3622 -4.826)
			(stroke
				(width 0.1524)
				(type default)
			)
			(layer "B.SilkS")
		)
		(fp_rect
			(start 2.6416 3.7338)
			(end -2.6162 -5.08)
			(stroke
				(width 0)
				(type default)
			)
			(fill no)
			(layer "B.CrtYd")
		)
		(fp_rect
			(start 2.6416 3.7338)
			(end -2.6162 -5.08)
			(stroke
				(width 0)
				(type default)
			)
			(fill no)
			(layer "B.Fab")
		)
		(pad "1" smd circle
			(at -0.496824 -1.301496 90)
			(size 0.6604 0.6604)
			(layers "B.Cu" "B.Mask" "B.Paste")
			(net "L3_85OHM_5INCH_DP")
		)
		(pad "2" smd circle
			(at 0.503936 -1.301496 90)
			(size 0.6604 0.6604)
			(layers "B.Cu" "B.Mask" "B.Paste")
			(net "L3_85OHM_5INCH_DN")
		)
		(pad "3" smd custom
			(at 0.00889 0.370078 90)
			(size 0.74295 0.74295)
			(layers "B.Cu" "B.Mask" "B.Paste")
			(net "GND")
			(options
				(clearance outline)
				(anchor circle)
			)
			(primitives
				(gr_poly
					(pts
						(xy -2.1209 -1.4859) (xy 2.1209 -1.4859) (xy 2.1209 1.4859) (xy 1.08585 1.4859) (xy 1.08585 0.4699)
						(xy -1.08585 0.4699) (xy -1.08585 1.4859) (xy -2.1209 1.4859)
					)
					(width 0)
					(fill yes)
				)
			)
		)
		(pad "4" thru_hole circle
			(at -1.266444 -3.851656 90)
			(size 1.4478 1.4478)
			(drill 1.0414)
			(layers "*.Cu" "*.Mask")
			(remove_unused_layers no)
			(net "GND")
			(clearance 0.1524)
			(thermal_gap 0.1524)
		)
		(pad "5" thru_hole circle
			(at 1.273556 -3.851656 90)
			(size 1.4478 1.4478)
			(drill 1.0414)
			(layers "*.Cu" "*.Mask")
			(remove_unused_layers no)
			(net "GND")
			(clearance 0.1524)
			(thermal_gap 0.1524)
		)
		(pad "6" thru_hole circle
			(at -1.266444 2.498344 90)
			(size 1.4478 1.4478)
			(drill 1.0414)
			(layers "*.Cu" "*.Mask")
			(remove_unused_layers no)
			(net "GND")
			(clearance 0.1524)
			(thermal_gap 0.1524)
		)
		(pad "7" thru_hole circle
			(at 1.273556 2.498344 90)
			(size 1.4478 1.4478)
			(drill 1.0414)
			(layers "*.Cu" "*.Mask")
			(remove_unused_layers no)
			(net "GND")
			(clearance 0.1524)
			(thermal_gap 0.1524)
		)
		(pad "8" thru_hole circle
			(at -1.27 -0.4572 90)
			(size 0.7112 0.7112)
			(drill 0.4064)
			(layers "*.Cu" "*.Mask")
			(remove_unused_layers no)
			(net "GND")
			(clearance 0.1016)
			(thermal_gap 0.1016)
		)
		(pad "9" thru_hole circle
			(at -1.27 0.762 90)
			(size 0.7112 0.7112)
			(drill 0.4064)
			(layers "*.Cu" "*.Mask")
			(remove_unused_layers no)
			(net "GND")
			(clearance 0.1016)
			(thermal_gap 0.1016)
		)
		(pad "10" thru_hole circle
			(at 0.0254 0.762 90)
			(size 0.7112 0.7112)
			(drill 0.4064)
			(layers "*.Cu" "*.Mask")
			(remove_unused_layers no)
			(net "GND")
			(clearance 0.1016)
			(thermal_gap 0.1016)
		)
		(pad "11" thru_hole circle
			(at 1.27 0.762 90)
			(size 0.7112 0.7112)
			(drill 0.4064)
			(layers "*.Cu" "*.Mask")
			(remove_unused_layers no)
			(net "GND")
			(clearance 0.1016)
			(thermal_gap 0.1016)
		)
		(pad "12" thru_hole circle
			(at 1.27 -0.4572 90)
			(size 0.7112 0.7112)
			(drill 0.4064)
			(layers "*.Cu" "*.Mask")
			(remove_unused_layers no)
			(net "GND")
			(clearance 0.1016)
			(thermal_gap 0.1016)
		)
	)
	(footprint ""
		(layer "B.Cu")
		(at 476.48876 -43.116246 -90)
		(property "Reference" "C9E6"
			(at 0 0 90)
			(layer "B.SilkS")
			(hide yes)
			(effects
				(font
					(size 1.27 1.27)
				)
				(justify mirror)
			)
		)
		(property "Value" "*"
			(at 0.0762 -6.2357 270)
			(unlocked yes)
			(layer "B.Fab")
			(hide yes)
			(effects
				(font
					(size 1.27 1.016)
					(thickness 0.1524)
				)
				(justify mirror)
			)
		)
		(property "Device Type" "SC22U16V5MX-4-GP_SMD-BCG5-SC22A"
			(at 0.0762 -8.2677 270)
			(unlocked yes)
			(layer "B.Fab")
			(hide yes)
			(effects
				(font
					(size 1.27 1.016)
					(thickness 0.1524)
				)
				(justify mirror)
			)
		)
		(duplicate_pad_numbers_are_jumpers no)
		(fp_line
			(start -0.635 0)
			(end 0.635 0)
			(stroke
				(width 0.508)
				(type default)
			)
			(layer "B.SilkS")
		)
		(fp_rect
			(start 0.9652 1.778)
			(end -0.9652 -1.778)
			(stroke
				(width 0)
				(type default)
			)
			(fill no)
			(layer "B.CrtYd")
		)
		(fp_poly
			(pts
				(xy 0.9652 -1.778) (xy -0.9652 -1.778) (xy -0.9652 1.778) (xy 0.9652 1.778)
			)
			(stroke
				(width 0)
				(type default)
			)
			(fill no)
			(layer "B.Fab")
		)
		(pad "1" smd rect
			(at 0 -0.9652 90)
			(size 1.397 1.143)
			(layers "B.Cu" "B.Mask" "B.Paste")
			(net "P1V5_LAN")
		)
		(pad "2" smd rect
			(at 0 0.9652 90)
			(size 1.397 1.143)
			(layers "B.Cu" "B.Mask" "B.Paste")
			(net "GND")
		)
	)
	(footprint ""
		(layer "B.Cu")
		(at 164.973 -55.245 90)
		(property "Reference" "C6R12"
			(at -3.20167 4.191 0)
			(unlocked yes)
			(layer "B.SilkS")
			(effects
				(font
					(size 0.7874 0.5842)
					(thickness 0.1524)
				)
				(justify mirror)
			)
		)
		(property "Value" ""
			(at 0 0 90)
			(layer "B.Fab")
			(effects
				(font
					(size 1.27 1.27)
				)
				(justify mirror)
			)
		)
		(duplicate_pad_numbers_are_jumpers no)
		(fp_line
			(start 2.563114 -1.616456)
			(end 2.563114 1.633728)
			(stroke
				(width 0.1524)
				(type default)
			)
			(layer "B.SilkS")
		)
		(fp_line
			(start 1.6002 -1.616456)
			(end 2.563114 -1.616456)
			(stroke
				(width 0.1524)
				(type default)
			)
			(layer "B.SilkS")
		)
		(fp_line
			(start -1.6002 -1.616456)
			(end -2.504948 -1.616456)
			(stroke
				(width 0.1524)
				(type default)
			)
			(layer "B.SilkS")
		)
		(fp_line
			(start -2.504948 -1.616456)
			(end -2.504948 1.633728)
			(stroke
				(width 0.1524)
				(type default)
			)
			(layer "B.SilkS")
		)
		(fp_line
			(start 2.563114 1.633728)
			(end 1.6002 1.633728)
			(stroke
				(width 0.1524)
				(type default)
			)
			(layer "B.SilkS")
		)
		(fp_line
			(start -2.504948 1.633728)
			(end -1.6002 1.633728)
			(stroke
				(width 0.1524)
				(type default)
			)
			(layer "B.SilkS")
		)
		(fp_line
			(start 2.286 7.366)
			(end 2.286 1.632712)
			(stroke
				(width 0.1524)
				(type default)
			)
			(layer "B.SilkS")
		)
		(fp_line
			(start 2.286 7.366)
			(end 1.60147 7.366)
			(stroke
				(width 0.1524)
				(type default)
			)
			(layer "B.SilkS")
		)
		(fp_line
			(start -2.286 7.366)
			(end -2.286 1.63195)
			(stroke
				(width 0.1524)
				(type default)
			)
			(layer "B.SilkS")
		)
		(fp_line
			(start -2.286 7.366)
			(end -1.600708 7.366)
			(stroke
				(width 0.1524)
				(type default)
			)
			(layer "B.SilkS")
		)
		(fp_rect
			(start 2.286 7.366)
			(end -2.286 -0.254)
			(stroke
				(width 0)
				(type default)
			)
			(fill no)
			(layer "B.CrtYd")
		)
		(fp_line
			(start 2.286 -0.254)
			(end -2.286 -0.254)
			(stroke
				(width 0.1)
				(type default)
			)
			(layer "B.Fab")
		)
		(fp_line
			(start -2.286 -0.254)
			(end -2.286 7.366)
			(stroke
				(width 0.1)
				(type default)
			)
			(layer "B.Fab")
		)
		(fp_line
			(start 2.286 7.366)
			(end 2.286 -0.254)
			(stroke
				(width 0.1)
				(type default)
			)
			(layer "B.Fab")
		)
		(fp_line
			(start -2.286 7.366)
			(end 2.286 7.366)
			(stroke
				(width 0.1)
				(type default)
			)
			(layer "B.Fab")
		)
		(pad "1" smd rect
			(at 0 0 270)
			(size 2.54 3.048)
			(layers "B.Cu" "B.Mask" "B.Paste")
			(net "PVCCIO_CPU1")
		)
		(pad "2" smd rect
			(at 0 7.112 270)
			(size 2.54 3.048)
			(layers "B.Cu" "B.Mask" "B.Paste")
			(net "GND")
		)
	)
	(footprint ""
		(layer "B.Cu")
		(at 293.87292 -67.16268)
		(property "Reference" "R4P19"
			(at 0 0 0)
			(layer "B.SilkS")
			(hide yes)
			(effects
				(font
					(size 1.27 1.27)
				)
				(justify mirror)
			)
		)
		(property "Value" ""
			(at 0 0 0)
			(layer "B.Fab")
			(effects
				(font
					(size 1.27 1.27)
				)
				(justify mirror)
			)
		)
		(duplicate_pad_numbers_are_jumpers no)
		(fp_poly
			(pts
				(xy 0.2794 -0.1016) (xy -0.2794 -0.1016) (xy -0.2794 0.9906) (xy 0.2794 0.9906)
			)
			(stroke
				(width 0)
				(type default)
			)
			(fill no)
			(layer "B.CrtYd")
		)
		(fp_line
			(start -0.2794 -0.1016)
			(end 0.2794 -0.1016)
			(stroke
				(width 0.1)
				(type default)
			)
			(layer "B.Fab")
		)
		(fp_line
			(start -0.2794 0.9906)
			(end -0.2794 -0.1016)
			(stroke
				(width 0.1)
				(type default)
			)
			(layer "B.Fab")
		)
		(fp_line
			(start 0.2794 -0.1016)
			(end 0.2794 0.9906)
			(stroke
				(width 0.1)
				(type default)
			)
			(layer "B.Fab")
		)
		(fp_line
			(start 0.2794 0.9906)
			(end -0.2794 0.9906)
			(stroke
				(width 0.1)
				(type default)
			)
			(layer "B.Fab")
		)
		(pad "1" smd rect
			(at 0 0 180)
			(size 0.508 0.508)
			(layers "B.Cu" "B.Mask" "B.Paste")
			(net "H_PMSYNC_CLK_24M_CPU0")
		)
		(pad "2" smd rect
			(at 0 0.889 180)
			(size 0.508 0.508)
			(layers "B.Cu" "B.Mask" "B.Paste")
			(net "H_PMSYNC_CLK_24M")
		)
		(zone
			(layer "B.Cu")
			(hatch none 0.5)
			(connect_pads
				(clearance 0)
			)
			(min_thickness 0.25)
			(keepout
				(tracks allowed)
				(vias not_allowed)
				(pads allowed)
				(copperpour not_allowed)
				(footprints allowed)
			)
			(placement
				(enabled no)
				(sheetname "")
			)
			(fill
				(thermal_gap 0.5)
				(thermal_bridge_width 0.5)
				(island_removal_mode 0)
			)
			(polygon
				(pts
					(xy 294.12692 -66.90868) (xy 293.61892 -66.90868) (xy 293.61892 -66.52768) (xy 294.12692 -66.52768)
				)
			)
		)
		(zone
			(layer "B.Cu")
			(hatch none 0.5)
			(connect_pads
				(clearance 0)
			)
			(min_thickness 0.25)
			(keepout
				(tracks not_allowed)
				(vias allowed)
				(pads allowed)
				(copperpour not_allowed)
				(footprints allowed)
			)
			(placement
				(enabled no)
				(sheetname "")
			)
			(fill
				(thermal_gap 0.5)
				(thermal_bridge_width 0.5)
				(island_removal_mode 0)
			)
			(polygon
				(pts
					(xy 294.12692 -66.52768) (xy 293.61892 -66.52768) (xy 293.61892 -66.90868) (xy 294.12692 -66.90868)
				)
			)
		)
	)
	(footprint ""
		(layer "B.Cu")
		(at 456.787758 -32.062674)
		(property "Reference" "R9E14"
			(at 0 0 0)
			(layer "B.SilkS")
			(hide yes)
			(effects
				(font
					(size 1.27 1.27)
				)
				(justify mirror)
			)
		)
		(property "Value" ""
			(at 0 0 0)
			(layer "B.Fab")
			(effects
				(font
					(size 1.27 1.27)
				)
				(justify mirror)
			)
		)
		(duplicate_pad_numbers_are_jumpers no)
		(fp_poly
			(pts
				(xy 0.2794 -0.1016) (xy -0.2794 -0.1016) (xy -0.2794 0.9906) (xy 0.2794 0.9906)
			)
			(stroke
				(width 0)
				(type default)
			)
			(fill no)
			(layer "B.CrtYd")
		)
		(fp_line
			(start -0.2794 -0.1016)
			(end 0.2794 -0.1016)
			(stroke
				(width 0.1)
				(type default)
			)
			(layer "B.Fab")
		)
		(fp_line
			(start -0.2794 0.9906)
			(end -0.2794 -0.1016)
			(stroke
				(width 0.1)
				(type default)
			)
			(layer "B.Fab")
		)
		(fp_line
			(start 0.2794 -0.1016)
			(end 0.2794 0.9906)
			(stroke
				(width 0.1)
				(type default)
			)
			(layer "B.Fab")
		)
		(fp_line
			(start 0.2794 0.9906)
			(end -0.2794 0.9906)
			(stroke
				(width 0.1)
				(type default)
			)
			(layer "B.Fab")
		)
		(pad "1" smd rect
			(at 0 0 180)
			(size 0.508 0.508)
			(layers "B.Cu" "B.Mask" "B.Paste")
			(net "FM_TPM_PRES_RST_N")
		)
		(pad "2" smd rect
			(at 0 0.889 180)
			(size 0.508 0.508)
			(layers "B.Cu" "B.Mask" "B.Paste")
			(net "FM_BMC_ENABLE_N")
		)
		(zone
			(layer "B.Cu")
			(hatch none 0.5)
			(connect_pads
				(clearance 0)
			)
			(min_thickness 0.25)
			(keepout
				(tracks allowed)
				(vias not_allowed)
				(pads allowed)
				(copperpour not_allowed)
				(footprints allowed)
			)
			(placement
				(enabled no)
				(sheetname "")
			)
			(fill
				(thermal_gap 0.5)
				(thermal_bridge_width 0.5)
				(island_removal_mode 0)
			)
			(polygon
				(pts
					(xy 457.041758 -31.808674) (xy 456.533758 -31.808674) (xy 456.533758 -31.427674) (xy 457.041758 -31.427674)
				)
			)
		)
		(zone
			(layer "B.Cu")
			(hatch none 0.5)
			(connect_pads
				(clearance 0)
			)
			(min_thickness 0.25)
			(keepout
				(tracks not_allowed)
				(vias allowed)
				(pads allowed)
				(copperpour not_allowed)
				(footprints allowed)
			)
			(placement
				(enabled no)
				(sheetname "")
			)
			(fill
				(thermal_gap 0.5)
				(thermal_bridge_width 0.5)
				(island_removal_mode 0)
			)
			(polygon
				(pts
					(xy 457.041758 -31.427674) (xy 456.533758 -31.427674) (xy 456.533758 -31.808674) (xy 457.041758 -31.808674)
				)
			)
		)
	)
	(footprint ""
		(layer "B.Cu")
		(at 351.8662 -87.503 -90)
		(property "Reference" "R3P12"
			(at 0 0 90)
			(layer "B.SilkS")
			(hide yes)
			(effects
				(font
					(size 1.27 1.27)
				)
				(justify mirror)
			)
		)
		(property "Value" ""
			(at 0 0 90)
			(layer "B.Fab")
			(effects
				(font
					(size 1.27 1.27)
				)
				(justify mirror)
			)
		)
		(duplicate_pad_numbers_are_jumpers no)
		(fp_poly
			(pts
				(xy 0.2794 -0.1016) (xy -0.2794 -0.1016) (xy -0.2794 0.9906) (xy 0.2794 0.9906)
			)
			(stroke
				(width 0)
				(type default)
			)
			(fill no)
			(layer "B.CrtYd")
		)
		(fp_line
			(start -0.2794 0.9906)
			(end -0.2794 -0.1016)
			(stroke
				(width 0.1)
				(type default)
			)
			(layer "B.Fab")
		)
		(fp_line
			(start 0.2794 0.9906)
			(end -0.2794 0.9906)
			(stroke
				(width 0.1)
				(type default)
			)
			(layer "B.Fab")
		)
		(fp_line
			(start -0.2794 -0.1016)
			(end 0.2794 -0.1016)
			(stroke
				(width 0.1)
				(type default)
			)
			(layer "B.Fab")
		)
		(fp_line
			(start 0.2794 -0.1016)
			(end 0.2794 0.9906)
			(stroke
				(width 0.1)
				(type default)
			)
			(layer "B.Fab")
		)
		(pad "1" smd rect
			(at 0 0 90)
			(size 0.508 0.508)
			(layers "B.Cu" "B.Mask" "B.Paste")
			(net "VR_FET_SW_P12V_STBY_PVCCIO_CPU0")
		)
		(pad "2" smd rect
			(at 0 0.889 90)
			(size 0.508 0.508)
			(layers "B.Cu" "B.Mask" "B.Paste")
			(net "VR_PVCCIO_CPU0_VINSEN")
		)
		(zone
			(layer "B.Cu")
			(hatch none 0.5)
			(connect_pads
				(clearance 0)
			)
			(min_thickness 0.25)
			(keepout
				(tracks not_allowed)
				(vias allowed)
				(pads allowed)
				(copperpour not_allowed)
				(footprints allowed)
			)
			(placement
				(enabled no)
				(sheetname "")
			)
			(fill
				(thermal_gap 0.5)
				(thermal_bridge_width 0.5)
				(island_removal_mode 0)
			)
			(polygon
				(pts
					(xy 351.2312 -87.249) (xy 351.2312 -87.757) (xy 351.6122 -87.757) (xy 351.6122 -87.249)
				)
			)
		)
		(zone
			(layer "B.Cu")
			(hatch none 0.5)
			(connect_pads
				(clearance 0)
			)
			(min_thickness 0.25)
			(keepout
				(tracks allowed)
				(vias not_allowed)
				(pads allowed)
				(copperpour not_allowed)
				(footprints allowed)
			)
			(placement
				(enabled no)
				(sheetname "")
			)
			(fill
				(thermal_gap 0.5)
				(thermal_bridge_width 0.5)
				(island_removal_mode 0)
			)
			(polygon
				(pts
					(xy 351.6122 -87.249) (xy 351.6122 -87.757) (xy 351.2312 -87.757) (xy 351.2312 -87.249)
				)
			)
		)
	)
	(footprint ""
		(layer "B.Cu")
		(at 483.19436 -28.547314)
		(property "Reference" "C2T22"
			(at 0 0 0)
			(layer "B.SilkS")
			(hide yes)
			(effects
				(font
					(size 1.27 1.27)
				)
				(justify mirror)
			)
		)
		(property "Value" ""
			(at 0 0 0)
			(layer "B.Fab")
			(effects
				(font
					(size 1.27 1.27)
				)
				(justify mirror)
			)
		)
		(duplicate_pad_numbers_are_jumpers no)
		(fp_poly
			(pts
				(xy 0.7239 -0.2159) (xy -0.7239 -0.2159) (xy -0.7239 1.9939) (xy 0.7239 1.9939)
			)
			(stroke
				(width 0)
				(type default)
			)
			(fill no)
			(layer "B.CrtYd")
		)
		(fp_line
			(start -0.7239 -0.2159)
			(end 0.7239 -0.2159)
			(stroke
				(width 0.1)
				(type default)
			)
			(layer "B.Fab")
		)
		(fp_line
			(start -0.7239 1.9939)
			(end -0.7239 -0.2159)
			(stroke
				(width 0.1)
				(type default)
			)
			(layer "B.Fab")
		)
		(fp_line
			(start 0.7239 -0.2159)
			(end 0.7239 1.9939)
			(stroke
				(width 0.1)
				(type default)
			)
			(layer "B.Fab")
		)
		(fp_line
			(start 0.7239 1.9939)
			(end -0.7239 1.9939)
			(stroke
				(width 0.1)
				(type default)
			)
			(layer "B.Fab")
		)
		(pad "1" smd rect
			(at 0 0 180)
			(size 1.27 1.016)
			(layers "B.Cu" "B.Mask" "B.Paste")
			(net "P3V3_STBY_MNG")
		)
		(pad "2" smd rect
			(at 0 1.778 180)
			(size 1.27 1.016)
			(layers "B.Cu" "B.Mask" "B.Paste")
			(net "GND")
		)
		(zone
			(layer "B.Cu")
			(hatch none 0.5)
			(connect_pads
				(clearance 0)
			)
			(min_thickness 0.25)
			(keepout
				(tracks not_allowed)
				(vias allowed)
				(pads allowed)
				(copperpour not_allowed)
				(footprints allowed)
			)
			(placement
				(enabled no)
				(sheetname "")
			)
			(fill
				(thermal_gap 0.5)
				(thermal_bridge_width 0.5)
				(island_removal_mode 0)
			)
			(polygon
				(pts
					(xy 483.82936 -28.039314) (xy 482.55936 -28.039314) (xy 482.55936 -27.277314) (xy 483.82936 -27.277314)
				)
			)
		)
	)
	(footprint ""
		(layer "B.Cu")
		(at 414.5534 -142.0368 -90)
		(property "Reference" "C2L37"
			(at 0 0 90)
			(layer "B.SilkS")
			(hide yes)
			(effects
				(font
					(size 1.27 1.27)
				)
				(justify mirror)
			)
		)
		(property "Value" ""
			(at 0 0 90)
			(layer "B.Fab")
			(effects
				(font
					(size 1.27 1.27)
				)
				(justify mirror)
			)
		)
		(duplicate_pad_numbers_are_jumpers no)
		(fp_poly
			(pts
				(xy -0.3048 -0.1016) (xy -0.3048 0.9906) (xy 0.3048 0.9906) (xy 0.3048 -0.1016)
			)
			(stroke
				(width 0)
				(type default)
			)
			(fill no)
			(layer "B.CrtYd")
		)
		(fp_line
			(start -0.3048 0.9906)
			(end -0.3048 -0.1016)
			(stroke
				(width 0.1)
				(type default)
			)
			(layer "B.Fab")
		)
		(fp_line
			(start 0.3048 0.9906)
			(end -0.3048 0.9906)
			(stroke
				(width 0.1)
				(type default)
			)
			(layer "B.Fab")
		)
		(fp_line
			(start -0.3048 -0.1016)
			(end 0.3048 -0.1016)
			(stroke
				(width 0.1)
				(type default)
			)
			(layer "B.Fab")
		)
		(fp_line
			(start 0.3048 -0.1016)
			(end 0.3048 0.9906)
			(stroke
				(width 0.1)
				(type default)
			)
			(layer "B.Fab")
		)
		(pad "1" smd rect
			(at 0 0 90)
			(size 0.508 0.508)
			(layers "B.Cu" "B.Mask" "B.Paste")
			(net "SATA6G_P4_TX_C_DN")
		)
		(pad "2" smd rect
			(at 0 0.889 90)
			(size 0.508 0.508)
			(layers "B.Cu" "B.Mask" "B.Paste")
			(net "SATA6G_PCH_PCIE_UP_SATA_TXN<4>")
		)
		(zone
			(layer "B.Cu")
			(hatch none 0.5)
			(connect_pads
				(clearance 0)
			)
			(min_thickness 0.25)
			(keepout
				(tracks not_allowed)
				(vias allowed)
				(pads allowed)
				(copperpour not_allowed)
				(footprints allowed)
			)
			(placement
				(enabled no)
				(sheetname "")
			)
			(fill
				(thermal_gap 0.5)
				(thermal_bridge_width 0.5)
				(island_removal_mode 0)
			)
			(polygon
				(pts
					(xy 413.9184 -141.7828) (xy 413.9184 -142.2908) (xy 414.2994 -142.2908) (xy 414.2994 -141.7828)
				)
			)
		)
		(zone
			(layer "B.Cu")
			(hatch none 0.5)
			(connect_pads
				(clearance 0)
			)
			(min_thickness 0.25)
			(keepout
				(tracks allowed)
				(vias not_allowed)
				(pads allowed)
				(copperpour not_allowed)
				(footprints allowed)
			)
			(placement
				(enabled no)
				(sheetname "")
			)
			(fill
				(thermal_gap 0.5)
				(thermal_bridge_width 0.5)
				(island_removal_mode 0)
			)
			(polygon
				(pts
					(xy 414.2994 -141.7828) (xy 414.2994 -142.2908) (xy 413.9184 -142.2908) (xy 413.9184 -141.7828)
				)
			)
		)
	)
	(footprint ""
		(layer "B.Cu")
		(at 362.270294 -44.020486)
		(property "Reference" "R2T66"
			(at 0 0 0)
			(layer "B.SilkS")
			(hide yes)
			(effects
				(font
					(size 1.27 1.27)
				)
				(justify mirror)
			)
		)
		(property "Value" ""
			(at 0 0 0)
			(layer "B.Fab")
			(effects
				(font
					(size 1.27 1.27)
				)
				(justify mirror)
			)
		)
		(duplicate_pad_numbers_are_jumpers no)
		(fp_poly
			(pts
				(xy 0.2794 -0.1016) (xy -0.2794 -0.1016) (xy -0.2794 0.9906) (xy 0.2794 0.9906)
			)
			(stroke
				(width 0)
				(type default)
			)
			(fill no)
			(layer "B.CrtYd")
		)
		(fp_line
			(start -0.2794 -0.1016)
			(end 0.2794 -0.1016)
			(stroke
				(width 0.1)
				(type default)
			)
			(layer "B.Fab")
		)
		(fp_line
			(start -0.2794 0.9906)
			(end -0.2794 -0.1016)
			(stroke
				(width 0.1)
				(type default)
			)
			(layer "B.Fab")
		)
		(fp_line
			(start 0.2794 -0.1016)
			(end 0.2794 0.9906)
			(stroke
				(width 0.1)
				(type default)
			)
			(layer "B.Fab")
		)
		(fp_line
			(start 0.2794 0.9906)
			(end -0.2794 0.9906)
			(stroke
				(width 0.1)
				(type default)
			)
			(layer "B.Fab")
		)
		(pad "1" smd rect
			(at 0 0 180)
			(size 0.508 0.508)
			(layers "B.Cu" "B.Mask" "B.Paste")
			(net "FM_CPU_ERR1_LVT3_R_N")
		)
		(pad "2" smd rect
			(at 0 0.889 180)
			(size 0.508 0.508)
			(layers "B.Cu" "B.Mask" "B.Paste")
			(net "FM_CPU_ERR1_LVT3_K_N")
		)
		(zone
			(layer "B.Cu")
			(hatch none 0.5)
			(connect_pads
				(clearance 0)
			)
			(min_thickness 0.25)
			(keepout
				(tracks allowed)
				(vias not_allowed)
				(pads allowed)
				(copperpour not_allowed)
				(footprints allowed)
			)
			(placement
				(enabled no)
				(sheetname "")
			)
			(fill
				(thermal_gap 0.5)
				(thermal_bridge_width 0.5)
				(island_removal_mode 0)
			)
			(polygon
				(pts
					(xy 362.524294 -43.766486) (xy 362.016294 -43.766486) (xy 362.016294 -43.385486) (xy 362.524294 -43.385486)
				)
			)
		)
		(zone
			(layer "B.Cu")
			(hatch none 0.5)
			(connect_pads
				(clearance 0)
			)
			(min_thickness 0.25)
			(keepout
				(tracks not_allowed)
				(vias allowed)
				(pads allowed)
				(copperpour not_allowed)
				(footprints allowed)
			)
			(placement
				(enabled no)
				(sheetname "")
			)
			(fill
				(thermal_gap 0.5)
				(thermal_bridge_width 0.5)
				(island_removal_mode 0)
			)
			(polygon
				(pts
					(xy 362.524294 -43.385486) (xy 362.016294 -43.385486) (xy 362.016294 -43.766486) (xy 362.524294 -43.766486)
				)
			)
		)
	)
	(footprint ""
		(layer "B.Cu")
		(at 262.206486 -77.82814)
		(property "Reference" "C5P25"
			(at 0 0 0)
			(layer "B.SilkS")
			(hide yes)
			(effects
				(font
					(size 1.27 1.27)
				)
				(justify mirror)
			)
		)
		(property "Value" ""
			(at 0 0 0)
			(layer "B.Fab")
			(effects
				(font
					(size 1.27 1.27)
				)
				(justify mirror)
			)
		)
		(duplicate_pad_numbers_are_jumpers no)
		(fp_poly
			(pts
				(xy 0.7239 -0.2159) (xy -0.7239 -0.2159) (xy -0.7239 1.9939) (xy 0.7239 1.9939)
			)
			(stroke
				(width 0)
				(type default)
			)
			(fill no)
			(layer "B.CrtYd")
		)
		(fp_line
			(start -0.7239 -0.2159)
			(end 0.7239 -0.2159)
			(stroke
				(width 0.1)
				(type default)
			)
			(layer "B.Fab")
		)
		(fp_line
			(start -0.7239 1.9939)
			(end -0.7239 -0.2159)
			(stroke
				(width 0.1)
				(type default)
			)
			(layer "B.Fab")
		)
		(fp_line
			(start 0.7239 -0.2159)
			(end 0.7239 1.9939)
			(stroke
				(width 0.1)
				(type default)
			)
			(layer "B.Fab")
		)
		(fp_line
			(start 0.7239 1.9939)
			(end -0.7239 1.9939)
			(stroke
				(width 0.1)
				(type default)
			)
			(layer "B.Fab")
		)
		(pad "1" smd rect
			(at 0 0 180)
			(size 1.27 1.016)
			(layers "B.Cu" "B.Mask" "B.Paste")
			(net "PVCCIN_CPU0")
		)
		(pad "2" smd rect
			(at 0 1.778 180)
			(size 1.27 1.016)
			(layers "B.Cu" "B.Mask" "B.Paste")
			(net "GND")
		)
		(zone
			(layer "B.Cu")
			(hatch none 0.5)
			(connect_pads
				(clearance 0)
			)
			(min_thickness 0.25)
			(keepout
				(tracks not_allowed)
				(vias allowed)
				(pads allowed)
				(copperpour not_allowed)
				(footprints allowed)
			)
			(placement
				(enabled no)
				(sheetname "")
			)
			(fill
				(thermal_gap 0.5)
				(thermal_bridge_width 0.5)
				(island_removal_mode 0)
			)
			(polygon
				(pts
					(xy 262.841486 -77.32014) (xy 261.571486 -77.32014) (xy 261.571486 -76.55814) (xy 262.841486 -76.55814)
				)
			)
		)
	)
	(footprint ""
		(layer "B.Cu")
		(at 87.158068 -140.208 -90)
		(property "Reference" "C5G112"
			(at -1.14681 0.76708 0)
			(unlocked yes)
			(layer "B.SilkS")
			(effects
				(font
					(size 0.7874 0.5842)
					(thickness 0.1524)
				)
				(justify mirror)
			)
		)
		(property "Value" ""
			(at 0 0 90)
			(layer "B.Fab")
			(effects
				(font
					(size 1.27 1.27)
				)
				(justify mirror)
			)
		)
		(duplicate_pad_numbers_are_jumpers no)
		(fp_rect
			(start 0.4953 1.6002)
			(end -0.4953 -0.2032)
			(stroke
				(width 0)
				(type default)
			)
			(fill no)
			(layer "B.CrtYd")
		)
		(fp_line
			(start -0.4953 1.6002)
			(end 0.4953 1.6002)
			(stroke
				(width 0.1)
				(type default)
			)
			(layer "B.Fab")
		)
		(fp_line
			(start 0.4953 1.6002)
			(end 0.4953 -0.2032)
			(stroke
				(width 0.1)
				(type default)
			)
			(layer "B.Fab")
		)
		(fp_line
			(start -0.4953 -0.2032)
			(end -0.4953 1.6002)
			(stroke
				(width 0.1)
				(type default)
			)
			(layer "B.Fab")
		)
		(fp_line
			(start 0.4953 -0.2032)
			(end -0.4953 -0.2032)
			(stroke
				(width 0.1)
				(type default)
			)
			(layer "B.Fab")
		)
		(pad "1" smd rect
			(at 0 0 90)
			(size 0.762 0.889)
			(layers "B.Cu" "B.Mask" "B.Paste")
			(net "PVDDQ_KLM")
		)
		(pad "2" smd rect
			(at 0 1.397 90)
			(size 0.762 0.889)
			(layers "B.Cu" "B.Mask" "B.Paste")
			(net "GND")
		)
		(zone
			(layer "B.Cu")
			(hatch none 0.5)
			(connect_pads
				(clearance 0)
			)
			(min_thickness 0.25)
			(keepout
				(tracks not_allowed)
				(vias allowed)
				(pads allowed)
				(copperpour not_allowed)
				(footprints allowed)
			)
			(placement
				(enabled no)
				(sheetname "")
			)
			(fill
				(thermal_gap 0.5)
				(thermal_bridge_width 0.5)
				(island_removal_mode 0)
			)
			(polygon
				(pts
					(xy 86.205568 -139.827) (xy 86.713568 -139.827) (xy 86.713568 -140.589) (xy 86.205568 -140.589)
				)
			)
		)
	)
	(footprint ""
		(layer "B.Cu")
		(at 227.584 -91.821 90)
		(property "Reference" "R5N3"
			(at 0 0 90)
			(layer "B.SilkS")
			(hide yes)
			(effects
				(font
					(size 1.27 1.27)
				)
				(justify mirror)
			)
		)
		(property "Value" ""
			(at 0 0 90)
			(layer "B.Fab")
			(effects
				(font
					(size 1.27 1.27)
				)
				(justify mirror)
			)
		)
		(duplicate_pad_numbers_are_jumpers no)
		(fp_poly
			(pts
				(xy 0.2794 -0.1016) (xy -0.2794 -0.1016) (xy -0.2794 0.9906) (xy 0.2794 0.9906)
			)
			(stroke
				(width 0)
				(type default)
			)
			(fill no)
			(layer "B.CrtYd")
		)
		(fp_line
			(start 0.2794 -0.1016)
			(end 0.2794 0.9906)
			(stroke
				(width 0.1)
				(type default)
			)
			(layer "B.Fab")
		)
		(fp_line
			(start -0.2794 -0.1016)
			(end 0.2794 -0.1016)
			(stroke
				(width 0.1)
				(type default)
			)
			(layer "B.Fab")
		)
		(fp_line
			(start 0.2794 0.9906)
			(end -0.2794 0.9906)
			(stroke
				(width 0.1)
				(type default)
			)
			(layer "B.Fab")
		)
		(fp_line
			(start -0.2794 0.9906)
			(end -0.2794 -0.1016)
			(stroke
				(width 0.1)
				(type default)
			)
			(layer "B.Fab")
		)
		(pad "1" smd rect
			(at 0 0 270)
			(size 0.508 0.508)
			(layers "B.Cu" "B.Mask" "B.Paste")
			(net "P3V3_STBY")
		)
		(pad "2" smd rect
			(at 0 0.889 270)
			(size 0.508 0.508)
			(layers "B.Cu" "B.Mask" "B.Paste")
			(net "FM_CPU0_PKGID2")
		)
		(zone
			(layer "B.Cu")
			(hatch none 0.5)
			(connect_pads
				(clearance 0)
			)
			(min_thickness 0.25)
			(keepout
				(tracks allowed)
				(vias not_allowed)
				(pads allowed)
				(copperpour not_allowed)
				(footprints allowed)
			)
			(placement
				(enabled no)
				(sheetname "")
			)
			(fill
				(thermal_gap 0.5)
				(thermal_bridge_width 0.5)
				(island_removal_mode 0)
			)
			(polygon
				(pts
					(xy 227.838 -92.075) (xy 227.838 -91.567) (xy 228.219 -91.567) (xy 228.219 -92.075)
				)
			)
		)
		(zone
			(layer "B.Cu")
			(hatch none 0.5)
			(connect_pads
				(clearance 0)
			)
			(min_thickness 0.25)
			(keepout
				(tracks not_allowed)
				(vias allowed)
				(pads allowed)
				(copperpour not_allowed)
				(footprints allowed)
			)
			(placement
				(enabled no)
				(sheetname "")
			)
			(fill
				(thermal_gap 0.5)
				(thermal_bridge_width 0.5)
				(island_removal_mode 0)
			)
			(polygon
				(pts
					(xy 228.219 -92.075) (xy 228.219 -91.567) (xy 227.838 -91.567) (xy 227.838 -92.075)
				)
			)
		)
	)
	(footprint ""
		(layer "B.Cu")
		(at 194.564 -155.448)
		(property "Reference" "R6L1"
			(at 0 0 0)
			(layer "B.SilkS")
			(hide yes)
			(effects
				(font
					(size 1.27 1.27)
				)
				(justify mirror)
			)
		)
		(property "Value" ""
			(at 0 0 0)
			(layer "B.Fab")
			(effects
				(font
					(size 1.27 1.27)
				)
				(justify mirror)
			)
		)
		(duplicate_pad_numbers_are_jumpers no)
		(fp_poly
			(pts
				(xy 0.2794 -0.1016) (xy -0.2794 -0.1016) (xy -0.2794 0.9906) (xy 0.2794 0.9906)
			)
			(stroke
				(width 0)
				(type default)
			)
			(fill no)
			(layer "B.CrtYd")
		)
		(fp_line
			(start -0.2794 -0.1016)
			(end 0.2794 -0.1016)
			(stroke
				(width 0.1)
				(type default)
			)
			(layer "B.Fab")
		)
		(fp_line
			(start -0.2794 0.9906)
			(end -0.2794 -0.1016)
			(stroke
				(width 0.1)
				(type default)
			)
			(layer "B.Fab")
		)
		(fp_line
			(start 0.2794 -0.1016)
			(end 0.2794 0.9906)
			(stroke
				(width 0.1)
				(type default)
			)
			(layer "B.Fab")
		)
		(fp_line
			(start 0.2794 0.9906)
			(end -0.2794 0.9906)
			(stroke
				(width 0.1)
				(type default)
			)
			(layer "B.Fab")
		)
		(pad "1" smd rect
			(at 0 0 180)
			(size 0.508 0.508)
			(layers "B.Cu" "B.Mask" "B.Paste")
			(net "M_F_VREF")
		)
		(pad "2" smd rect
			(at 0 0.889 180)
			(size 0.508 0.508)
			(layers "B.Cu" "B.Mask" "B.Paste")
			(net "GND")
		)
		(zone
			(layer "B.Cu")
			(hatch none 0.5)
			(connect_pads
				(clearance 0)
			)
			(min_thickness 0.25)
			(keepout
				(tracks allowed)
				(vias not_allowed)
				(pads allowed)
				(copperpour not_allowed)
				(footprints allowed)
			)
			(placement
				(enabled no)
				(sheetname "")
			)
			(fill
				(thermal_gap 0.5)
				(thermal_bridge_width 0.5)
				(island_removal_mode 0)
			)
			(polygon
				(pts
					(xy 194.818 -155.194) (xy 194.31 -155.194) (xy 194.31 -154.813) (xy 194.818 -154.813)
				)
			)
		)
		(zone
			(layer "B.Cu")
			(hatch none 0.5)
			(connect_pads
				(clearance 0)
			)
			(min_thickness 0.25)
			(keepout
				(tracks not_allowed)
				(vias allowed)
				(pads allowed)
				(copperpour not_allowed)
				(footprints allowed)
			)
			(placement
				(enabled no)
				(sheetname "")
			)
			(fill
				(thermal_gap 0.5)
				(thermal_bridge_width 0.5)
				(island_removal_mode 0)
			)
			(polygon
				(pts
					(xy 194.818 -154.813) (xy 194.31 -154.813) (xy 194.31 -155.194) (xy 194.818 -155.194)
				)
			)
		)
	)
	(footprint ""
		(layer "B.Cu")
		(at 341.728806 -60.368434)
		(property "Reference" "R2U20"
			(at 0 0 0)
			(layer "B.SilkS")
			(hide yes)
			(effects
				(font
					(size 1.27 1.27)
				)
				(justify mirror)
			)
		)
		(property "Value" ""
			(at 0 0 0)
			(layer "B.Fab")
			(effects
				(font
					(size 1.27 1.27)
				)
				(justify mirror)
			)
		)
		(duplicate_pad_numbers_are_jumpers no)
		(fp_poly
			(pts
				(xy 0.2794 -0.1016) (xy -0.2794 -0.1016) (xy -0.2794 0.9906) (xy 0.2794 0.9906)
			)
			(stroke
				(width 0)
				(type default)
			)
			(fill no)
			(layer "B.CrtYd")
		)
		(fp_line
			(start -0.2794 -0.1016)
			(end 0.2794 -0.1016)
			(stroke
				(width 0.1)
				(type default)
			)
			(layer "B.Fab")
		)
		(fp_line
			(start -0.2794 0.9906)
			(end -0.2794 -0.1016)
			(stroke
				(width 0.1)
				(type default)
			)
			(layer "B.Fab")
		)
		(fp_line
			(start 0.2794 -0.1016)
			(end 0.2794 0.9906)
			(stroke
				(width 0.1)
				(type default)
			)
			(layer "B.Fab")
		)
		(fp_line
			(start 0.2794 0.9906)
			(end -0.2794 0.9906)
			(stroke
				(width 0.1)
				(type default)
			)
			(layer "B.Fab")
		)
		(pad "1" smd rect
			(at 0 0 180)
			(size 0.508 0.508)
			(layers "B.Cu" "B.Mask" "B.Paste")
			(net "P3E_CPU0_PE1_SS_RXP<3>")
		)
		(pad "2" smd rect
			(at 0 0.889 180)
			(size 0.508 0.508)
			(layers "B.Cu" "B.Mask" "B.Paste")
			(net "P3E_CPU0_PE1_SS_R_RXP<3>")
		)
		(zone
			(layer "B.Cu")
			(hatch none 0.5)
			(connect_pads
				(clearance 0)
			)
			(min_thickness 0.25)
			(keepout
				(tracks allowed)
				(vias not_allowed)
				(pads allowed)
				(copperpour not_allowed)
				(footprints allowed)
			)
			(placement
				(enabled no)
				(sheetname "")
			)
			(fill
				(thermal_gap 0.5)
				(thermal_bridge_width 0.5)
				(island_removal_mode 0)
			)
			(polygon
				(pts
					(xy 341.982806 -60.114434) (xy 341.474806 -60.114434) (xy 341.474806 -59.733434) (xy 341.982806 -59.733434)
				)
			)
		)
		(zone
			(layer "B.Cu")
			(hatch none 0.5)
			(connect_pads
				(clearance 0)
			)
			(min_thickness 0.25)
			(keepout
				(tracks not_allowed)
				(vias allowed)
				(pads allowed)
				(copperpour not_allowed)
				(footprints allowed)
			)
			(placement
				(enabled no)
				(sheetname "")
			)
			(fill
				(thermal_gap 0.5)
				(thermal_bridge_width 0.5)
				(island_removal_mode 0)
			)
			(polygon
				(pts
					(xy 341.982806 -59.733434) (xy 341.474806 -59.733434) (xy 341.474806 -60.114434) (xy 341.982806 -60.114434)
				)
			)
		)
	)
	(footprint ""
		(layer "B.Cu")
		(at 350.022414 -125.227842 -90)
		(property "Reference" "C3M12"
			(at 0 0 90)
			(layer "B.SilkS")
			(hide yes)
			(effects
				(font
					(size 1.27 1.27)
				)
				(justify mirror)
			)
		)
		(property "Value" ""
			(at 0 0 90)
			(layer "B.Fab")
			(effects
				(font
					(size 1.27 1.27)
				)
				(justify mirror)
			)
		)
		(duplicate_pad_numbers_are_jumpers no)
		(fp_poly
			(pts
				(xy -0.3048 -0.1016) (xy -0.3048 0.9906) (xy 0.3048 0.9906) (xy 0.3048 -0.1016)
			)
			(stroke
				(width 0)
				(type default)
			)
			(fill no)
			(layer "B.CrtYd")
		)
		(fp_line
			(start -0.3048 0.9906)
			(end -0.3048 -0.1016)
			(stroke
				(width 0.1)
				(type default)
			)
			(layer "B.Fab")
		)
		(fp_line
			(start 0.3048 0.9906)
			(end -0.3048 0.9906)
			(stroke
				(width 0.1)
				(type default)
			)
			(layer "B.Fab")
		)
		(fp_line
			(start -0.3048 -0.1016)
			(end 0.3048 -0.1016)
			(stroke
				(width 0.1)
				(type default)
			)
			(layer "B.Fab")
		)
		(fp_line
			(start 0.3048 -0.1016)
			(end 0.3048 0.9906)
			(stroke
				(width 0.1)
				(type default)
			)
			(layer "B.Fab")
		)
		(pad "1" smd rect
			(at 0 0 90)
			(size 0.508 0.508)
			(layers "B.Cu" "B.Mask" "B.Paste")
			(net "P3E_CPU0_PE1_PCH_R_RXN<14>")
		)
		(pad "2" smd rect
			(at 0 0.889 90)
			(size 0.508 0.508)
			(layers "B.Cu" "B.Mask" "B.Paste")
			(net "P3E_CPU0_PE1_PCH_RXN<14>")
		)
		(zone
			(layer "B.Cu")
			(hatch none 0.5)
			(connect_pads
				(clearance 0)
			)
			(min_thickness 0.25)
			(keepout
				(tracks not_allowed)
				(vias allowed)
				(pads allowed)
				(copperpour not_allowed)
				(footprints allowed)
			)
			(placement
				(enabled no)
				(sheetname "")
			)
			(fill
				(thermal_gap 0.5)
				(thermal_bridge_width 0.5)
				(island_removal_mode 0)
			)
			(polygon
				(pts
					(xy 349.387414 -124.973842) (xy 349.387414 -125.481842) (xy 349.768414 -125.481842) (xy 349.768414 -124.973842)
				)
			)
		)
		(zone
			(layer "B.Cu")
			(hatch none 0.5)
			(connect_pads
				(clearance 0)
			)
			(min_thickness 0.25)
			(keepout
				(tracks allowed)
				(vias not_allowed)
				(pads allowed)
				(copperpour not_allowed)
				(footprints allowed)
			)
			(placement
				(enabled no)
				(sheetname "")
			)
			(fill
				(thermal_gap 0.5)
				(thermal_bridge_width 0.5)
				(island_removal_mode 0)
			)
			(polygon
				(pts
					(xy 349.768414 -124.973842) (xy 349.768414 -125.481842) (xy 349.387414 -125.481842) (xy 349.387414 -124.973842)
				)
			)
		)
	)
	(footprint ""
		(layer "B.Cu")
		(at 474.938344 -5.70992 90)
		(property "Reference" "R2U39"
			(at 0 0 90)
			(layer "B.SilkS")
			(hide yes)
			(effects
				(font
					(size 1.27 1.27)
				)
				(justify mirror)
			)
		)
		(property "Value" ""
			(at 0 0 90)
			(layer "B.Fab")
			(effects
				(font
					(size 1.27 1.27)
				)
				(justify mirror)
			)
		)
		(duplicate_pad_numbers_are_jumpers no)
		(fp_poly
			(pts
				(xy 0.2794 -0.1016) (xy -0.2794 -0.1016) (xy -0.2794 0.9906) (xy 0.2794 0.9906)
			)
			(stroke
				(width 0)
				(type default)
			)
			(fill no)
			(layer "B.CrtYd")
		)
		(fp_line
			(start 0.2794 -0.1016)
			(end 0.2794 0.9906)
			(stroke
				(width 0.1)
				(type default)
			)
			(layer "B.Fab")
		)
		(fp_line
			(start -0.2794 -0.1016)
			(end 0.2794 -0.1016)
			(stroke
				(width 0.1)
				(type default)
			)
			(layer "B.Fab")
		)
		(fp_line
			(start 0.2794 0.9906)
			(end -0.2794 0.9906)
			(stroke
				(width 0.1)
				(type default)
			)
			(layer "B.Fab")
		)
		(fp_line
			(start -0.2794 0.9906)
			(end -0.2794 -0.1016)
			(stroke
				(width 0.1)
				(type default)
			)
			(layer "B.Fab")
		)
		(pad "1" smd rect
			(at 0 0 270)
			(size 0.508 0.508)
			(layers "B.Cu" "B.Mask" "B.Paste")
			(net "P3V3_STBY")
		)
		(pad "2" smd rect
			(at 0 0.889 270)
			(size 0.508 0.508)
			(layers "B.Cu" "B.Mask" "B.Paste")
			(net "SMB_SENSOR_STBY_LVC3_SDA")
		)
		(zone
			(layer "B.Cu")
			(hatch none 0.5)
			(connect_pads
				(clearance 0)
			)
			(min_thickness 0.25)
			(keepout
				(tracks allowed)
				(vias not_allowed)
				(pads allowed)
				(copperpour not_allowed)
				(footprints allowed)
			)
			(placement
				(enabled no)
				(sheetname "")
			)
			(fill
				(thermal_gap 0.5)
				(thermal_bridge_width 0.5)
				(island_removal_mode 0)
			)
			(polygon
				(pts
					(xy 475.192344 -5.96392) (xy 475.192344 -5.45592) (xy 475.573344 -5.45592) (xy 475.573344 -5.96392)
				)
			)
		)
		(zone
			(layer "B.Cu")
			(hatch none 0.5)
			(connect_pads
				(clearance 0)
			)
			(min_thickness 0.25)
			(keepout
				(tracks not_allowed)
				(vias allowed)
				(pads allowed)
				(copperpour not_allowed)
				(footprints allowed)
			)
			(placement
				(enabled no)
				(sheetname "")
			)
			(fill
				(thermal_gap 0.5)
				(thermal_bridge_width 0.5)
				(island_removal_mode 0)
			)
			(polygon
				(pts
					(xy 475.573344 -5.96392) (xy 475.573344 -5.45592) (xy 475.192344 -5.45592) (xy 475.192344 -5.96392)
				)
			)
		)
	)
	(footprint ""
		(layer "B.Cu")
		(at 421.513 -146.939 -90)
		(property "Reference" "C2L23"
			(at 0 0 90)
			(layer "B.SilkS")
			(hide yes)
			(effects
				(font
					(size 1.27 1.27)
				)
				(justify mirror)
			)
		)
		(property "Value" ""
			(at 0 0 90)
			(layer "B.Fab")
			(effects
				(font
					(size 1.27 1.27)
				)
				(justify mirror)
			)
		)
		(duplicate_pad_numbers_are_jumpers no)
		(fp_poly
			(pts
				(xy -0.3048 -0.1016) (xy -0.3048 0.9906) (xy 0.3048 0.9906) (xy 0.3048 -0.1016)
			)
			(stroke
				(width 0)
				(type default)
			)
			(fill no)
			(layer "B.CrtYd")
		)
		(fp_line
			(start -0.3048 0.9906)
			(end -0.3048 -0.1016)
			(stroke
				(width 0.1)
				(type default)
			)
			(layer "B.Fab")
		)
		(fp_line
			(start 0.3048 0.9906)
			(end -0.3048 0.9906)
			(stroke
				(width 0.1)
				(type default)
			)
			(layer "B.Fab")
		)
		(fp_line
			(start -0.3048 -0.1016)
			(end 0.3048 -0.1016)
			(stroke
				(width 0.1)
				(type default)
			)
			(layer "B.Fab")
		)
		(fp_line
			(start 0.3048 -0.1016)
			(end 0.3048 0.9906)
			(stroke
				(width 0.1)
				(type default)
			)
			(layer "B.Fab")
		)
		(pad "1" smd rect
			(at 0 0 90)
			(size 0.508 0.508)
			(layers "B.Cu" "B.Mask" "B.Paste")
			(net "SATA6G_P3_TX_C_DP")
		)
		(pad "2" smd rect
			(at 0 0.889 90)
			(size 0.508 0.508)
			(layers "B.Cu" "B.Mask" "B.Paste")
			(net "SATA6G_PCH_PCIE_UP_SATA_TXP<3>")
		)
		(zone
			(layer "B.Cu")
			(hatch none 0.5)
			(connect_pads
				(clearance 0)
			)
			(min_thickness 0.25)
			(keepout
				(tracks not_allowed)
				(vias allowed)
				(pads allowed)
				(copperpour not_allowed)
				(footprints allowed)
			)
			(placement
				(enabled no)
				(sheetname "")
			)
			(fill
				(thermal_gap 0.5)
				(thermal_bridge_width 0.5)
				(island_removal_mode 0)
			)
			(polygon
				(pts
					(xy 420.878 -146.685) (xy 420.878 -147.193) (xy 421.259 -147.193) (xy 421.259 -146.685)
				)
			)
		)
		(zone
			(layer "B.Cu")
			(hatch none 0.5)
			(connect_pads
				(clearance 0)
			)
			(min_thickness 0.25)
			(keepout
				(tracks allowed)
				(vias not_allowed)
				(pads allowed)
				(copperpour not_allowed)
				(footprints allowed)
			)
			(placement
				(enabled no)
				(sheetname "")
			)
			(fill
				(thermal_gap 0.5)
				(thermal_bridge_width 0.5)
				(island_removal_mode 0)
			)
			(polygon
				(pts
					(xy 421.259 -146.685) (xy 421.259 -147.193) (xy 420.878 -147.193) (xy 420.878 -146.685)
				)
			)
		)
	)
	(footprint ""
		(layer "B.Cu")
		(at 168.402 -128.905 90)
		(property "Reference" "U6M1"
			(at 0.14986 2.838958 90)
			(unlocked yes)
			(layer "B.SilkS")
			(effects
				(font
					(size 0.7874 0.5842)
					(thickness 0.1524)
				)
				(justify left mirror)
			)
		)
		(property "Value" ""
			(at 0 0 90)
			(layer "B.Fab")
			(effects
				(font
					(size 1.27 1.27)
				)
				(justify mirror)
			)
		)
		(duplicate_pad_numbers_are_jumpers no)
		(fp_circle
			(center 0.931418 -0.008382)
			(end 0.931418 0.118618)
			(stroke
				(width 0.254)
				(type default)
			)
			(fill no)
			(layer "B.SilkS")
		)
		(fp_poly
			(pts
				(xy -0.21463 -0.450088) (xy -1.56337 -0.450088) (xy -1.56337 1.75006) (xy -0.21463 1.75006)
			)
			(stroke
				(width 0)
				(type default)
			)
			(fill no)
			(layer "B.CrtYd")
		)
		(fp_line
			(start -0.21463 -0.450088)
			(end -1.56337 -0.450088)
			(stroke
				(width 0.1)
				(type default)
			)
			(layer "B.Fab")
		)
		(fp_line
			(start -1.56337 -0.450088)
			(end -1.56337 1.75006)
			(stroke
				(width 0.1)
				(type default)
			)
			(layer "B.Fab")
		)
		(fp_line
			(start -0.21463 1.75006)
			(end -0.21463 -0.450088)
			(stroke
				(width 0.1)
				(type default)
			)
			(layer "B.Fab")
		)
		(fp_line
			(start -1.56337 1.75006)
			(end -0.21463 1.75006)
			(stroke
				(width 0.1)
				(type default)
			)
			(layer "B.Fab")
		)
		(fp_circle
			(center 0.4699 -0.8382)
			(end 0.4699 -0.7112)
			(stroke
				(width 0.254)
				(type default)
			)
			(fill no)
			(layer "B.Fab")
		)
		(pad "1" smd rect
			(at 0 0 270)
			(size 1.016 0.381)
			(layers "B.Cu" "B.Mask" "B.Paste")
			(net "FM_CPU1_PKGID1")
		)
		(pad "2" smd rect
			(at 0 0.649986 270)
			(size 1.016 0.381)
			(layers "B.Cu" "B.Mask" "B.Paste")
			(net "P1V8_MCP_CPU1")
		)
		(pad "3" smd rect
			(at 0 1.299972 270)
			(size 1.016 0.381)
			(layers "B.Cu" "B.Mask" "B.Paste")
			(net "GND")
		)
		(pad "4" smd rect
			(at -1.778 1.299972 270)
			(size 1.016 0.381)
			(layers "B.Cu" "B.Mask" "B.Paste")
			(net "JTAG_MCP_CPU1_TDI_R")
		)
		(pad "5" smd rect
			(at -1.778 0 270)
			(size 1.016 0.381)
			(layers "B.Cu" "B.Mask" "B.Paste")
			(net "P3V3_STBY")
		)
	)
	(footprint ""
		(layer "B.Cu")
		(at 385.7625 -60.198 -90)
		(property "Reference" "R2R12"
			(at 0 0 90)
			(layer "B.SilkS")
			(hide yes)
			(effects
				(font
					(size 1.27 1.27)
				)
				(justify mirror)
			)
		)
		(property "Value" ""
			(at 0 0 90)
			(layer "B.Fab")
			(effects
				(font
					(size 1.27 1.27)
				)
				(justify mirror)
			)
		)
		(duplicate_pad_numbers_are_jumpers no)
		(fp_poly
			(pts
				(xy 0.2794 -0.1016) (xy -0.2794 -0.1016) (xy -0.2794 0.9906) (xy 0.2794 0.9906)
			)
			(stroke
				(width 0)
				(type default)
			)
			(fill no)
			(layer "B.CrtYd")
		)
		(fp_line
			(start -0.2794 0.9906)
			(end -0.2794 -0.1016)
			(stroke
				(width 0.1)
				(type default)
			)
			(layer "B.Fab")
		)
		(fp_line
			(start 0.2794 0.9906)
			(end -0.2794 0.9906)
			(stroke
				(width 0.1)
				(type default)
			)
			(layer "B.Fab")
		)
		(fp_line
			(start -0.2794 -0.1016)
			(end 0.2794 -0.1016)
			(stroke
				(width 0.1)
				(type default)
			)
			(layer "B.Fab")
		)
		(fp_line
			(start 0.2794 -0.1016)
			(end 0.2794 0.9906)
			(stroke
				(width 0.1)
				(type default)
			)
			(layer "B.Fab")
		)
		(pad "1" smd rect
			(at 0 0 90)
			(size 0.508 0.508)
			(layers "B.Cu" "B.Mask" "B.Paste")
			(net "SPI_PCH_IO2")
		)
		(pad "2" smd rect
			(at 0 0.889 90)
			(size 0.508 0.508)
			(layers "B.Cu" "B.Mask" "B.Paste")
			(net "SPI_PCH_IO2_R1")
		)
		(zone
			(layer "B.Cu")
			(hatch none 0.5)
			(connect_pads
				(clearance 0)
			)
			(min_thickness 0.25)
			(keepout
				(tracks not_allowed)
				(vias allowed)
				(pads allowed)
				(copperpour not_allowed)
				(footprints allowed)
			)
			(placement
				(enabled no)
				(sheetname "")
			)
			(fill
				(thermal_gap 0.5)
				(thermal_bridge_width 0.5)
				(island_removal_mode 0)
			)
			(polygon
				(pts
					(xy 385.1275 -59.944) (xy 385.1275 -60.452) (xy 385.5085 -60.452) (xy 385.5085 -59.944)
				)
			)
		)
		(zone
			(layer "B.Cu")
			(hatch none 0.5)
			(connect_pads
				(clearance 0)
			)
			(min_thickness 0.25)
			(keepout
				(tracks allowed)
				(vias not_allowed)
				(pads allowed)
				(copperpour not_allowed)
				(footprints allowed)
			)
			(placement
				(enabled no)
				(sheetname "")
			)
			(fill
				(thermal_gap 0.5)
				(thermal_bridge_width 0.5)
				(island_removal_mode 0)
			)
			(polygon
				(pts
					(xy 385.5085 -59.944) (xy 385.5085 -60.452) (xy 385.1275 -60.452) (xy 385.1275 -59.944)
				)
			)
		)
	)
	(footprint ""
		(layer "B.Cu")
		(at 353.64801 -143.629888 90)
		(property "Reference" "C7W10"
			(at 0 0 90)
			(layer "B.SilkS")
			(hide yes)
			(effects
				(font
					(size 1.27 1.27)
				)
				(justify mirror)
			)
		)
		(property "Value" "*"
			(at 0.0762 -6.2357 90)
			(unlocked yes)
			(layer "B.Fab")
			(hide yes)
			(effects
				(font
					(size 1.27 1.016)
					(thickness 0.1524)
				)
				(justify mirror)
			)
		)
		(property "Device Type" "SC22U16V5MX-4-GP_SMD-BCG5-SC22A"
			(at 0.0762 -8.2677 90)
			(unlocked yes)
			(layer "B.Fab")
			(hide yes)
			(effects
				(font
					(size 1.27 1.016)
					(thickness 0.1524)
				)
				(justify mirror)
			)
		)
		(duplicate_pad_numbers_are_jumpers no)
		(fp_line
			(start -0.635 0)
			(end 0.635 0)
			(stroke
				(width 0.508)
				(type default)
			)
			(layer "B.SilkS")
		)
		(fp_rect
			(start 0.9652 1.778)
			(end -0.9652 -1.778)
			(stroke
				(width 0)
				(type default)
			)
			(fill no)
			(layer "B.CrtYd")
		)
		(fp_poly
			(pts
				(xy 0.9652 -1.778) (xy -0.9652 -1.778) (xy -0.9652 1.778) (xy 0.9652 1.778)
			)
			(stroke
				(width 0)
				(type default)
			)
			(fill no)
			(layer "B.Fab")
		)
		(pad "1" smd rect
			(at 0 -0.9652 270)
			(size 1.397 1.143)
			(layers "B.Cu" "B.Mask" "B.Paste")
			(net "VR_FET_SW_P12V_STBY_PVDDQ_DEF")
		)
		(pad "2" smd rect
			(at 0 0.9652 270)
			(size 1.397 1.143)
			(layers "B.Cu" "B.Mask" "B.Paste")
			(net "GND")
		)
	)
	(footprint ""
		(layer "B.Cu")
		(at 108.559854 -79.60614 180)
		(property "Reference" "C7P7"
			(at 0 0 0)
			(layer "B.SilkS")
			(hide yes)
			(effects
				(font
					(size 1.27 1.27)
				)
				(justify mirror)
			)
		)
		(property "Value" ""
			(at 0 0 0)
			(layer "B.Fab")
			(effects
				(font
					(size 1.27 1.27)
				)
				(justify mirror)
			)
		)
		(duplicate_pad_numbers_are_jumpers no)
		(fp_poly
			(pts
				(xy 0.7239 -0.2159) (xy -0.7239 -0.2159) (xy -0.7239 1.9939) (xy 0.7239 1.9939)
			)
			(stroke
				(width 0)
				(type default)
			)
			(fill no)
			(layer "B.CrtYd")
		)
		(fp_line
			(start 0.7239 1.9939)
			(end -0.7239 1.9939)
			(stroke
				(width 0.1)
				(type default)
			)
			(layer "B.Fab")
		)
		(fp_line
			(start 0.7239 -0.2159)
			(end 0.7239 1.9939)
			(stroke
				(width 0.1)
				(type default)
			)
			(layer "B.Fab")
		)
		(fp_line
			(start -0.7239 1.9939)
			(end -0.7239 -0.2159)
			(stroke
				(width 0.1)
				(type default)
			)
			(layer "B.Fab")
		)
		(fp_line
			(start -0.7239 -0.2159)
			(end 0.7239 -0.2159)
			(stroke
				(width 0.1)
				(type default)
			)
			(layer "B.Fab")
		)
		(pad "1" smd rect
			(at 0 0)
			(size 1.27 1.016)
			(layers "B.Cu" "B.Mask" "B.Paste")
			(net "PVCCMCP_CPU1")
		)
		(pad "2" smd rect
			(at 0 1.778)
			(size 1.27 1.016)
			(layers "B.Cu" "B.Mask" "B.Paste")
			(net "GND")
		)
		(zone
			(layer "B.Cu")
			(hatch none 0.5)
			(connect_pads
				(clearance 0)
			)
			(min_thickness 0.25)
			(keepout
				(tracks not_allowed)
				(vias allowed)
				(pads allowed)
				(copperpour not_allowed)
				(footprints allowed)
			)
			(placement
				(enabled no)
				(sheetname "")
			)
			(fill
				(thermal_gap 0.5)
				(thermal_bridge_width 0.5)
				(island_removal_mode 0)
			)
			(polygon
				(pts
					(xy 107.924854 -80.11414) (xy 109.194854 -80.11414) (xy 109.194854 -80.87614) (xy 107.924854 -80.87614)
				)
			)
		)
	)
	(footprint ""
		(layer "B.Cu")
		(at 3.893312 -18.586196 90)
		(property "Reference" "C9T6"
			(at 0 0 90)
			(layer "B.SilkS")
			(hide yes)
			(effects
				(font
					(size 1.27 1.27)
				)
				(justify mirror)
			)
		)
		(property "Value" ""
			(at 0 0 90)
			(layer "B.Fab")
			(effects
				(font
					(size 1.27 1.27)
				)
				(justify mirror)
			)
		)
		(duplicate_pad_numbers_are_jumpers no)
		(fp_rect
			(start -0.7239 -0.2159)
			(end 0.7239 1.9939)
			(stroke
				(width 0)
				(type default)
			)
			(fill no)
			(layer "B.CrtYd")
		)
		(fp_line
			(start 0.7239 -0.2159)
			(end 0.7239 1.9939)
			(stroke
				(width 0.1)
				(type default)
			)
			(layer "B.Fab")
		)
		(fp_line
			(start -0.7239 -0.2159)
			(end 0.7239 -0.2159)
			(stroke
				(width 0.1)
				(type default)
			)
			(layer "B.Fab")
		)
		(fp_line
			(start 0.7239 1.9939)
			(end -0.7239 1.9939)
			(stroke
				(width 0.1)
				(type default)
			)
			(layer "B.Fab")
		)
		(fp_line
			(start -0.7239 1.9939)
			(end -0.7239 -0.2159)
			(stroke
				(width 0.1)
				(type default)
			)
			(layer "B.Fab")
		)
		(pad "1" smd rect
			(at 0 0 270)
			(size 1.27 1.016)
			(layers "B.Cu" "B.Mask" "B.Paste")
			(net "VR_FET_SW_P12V_STBY_PVDDQ_GHJ")
		)
		(pad "2" smd rect
			(at 0 1.778 270)
			(size 1.27 1.016)
			(layers "B.Cu" "B.Mask" "B.Paste")
			(net "GND")
		)
		(zone
			(layer "B.Cu")
			(hatch none 0.5)
			(connect_pads
				(clearance 0)
			)
			(min_thickness 0.25)
			(keepout
				(tracks not_allowed)
				(vias allowed)
				(pads allowed)
				(copperpour not_allowed)
				(footprints allowed)
			)
			(placement
				(enabled no)
				(sheetname "")
			)
			(fill
				(thermal_gap 0.5)
				(thermal_bridge_width 0.5)
				(island_removal_mode 0)
			)
			(polygon
				(pts
					(xy 4.401312 -17.951196) (xy 5.163312 -17.951196) (xy 5.163312 -19.221196) (xy 4.401312 -19.221196)
				)
			)
		)
	)
	(footprint ""
		(layer "B.Cu")
		(at 418.870638 -37.5285 -90)
		(property "Reference" "C25W51"
			(at 0.8382 -0.67818 270)
			(unlocked yes)
			(layer "B.SilkS")
			(effects
				(font
					(size 0.4064 0.254)
					(thickness 0.1524)
				)
				(justify left mirror)
			)
		)
		(property "Value" ""
			(at 0 0 90)
			(layer "B.Fab")
			(effects
				(font
					(size 1.27 1.27)
				)
				(justify mirror)
			)
		)
		(duplicate_pad_numbers_are_jumpers no)
		(fp_poly
			(pts
				(xy -0.3048 -0.1016) (xy -0.3048 0.9906) (xy 0.3048 0.9906) (xy 0.3048 -0.1016)
			)
			(stroke
				(width 0)
				(type default)
			)
			(fill no)
			(layer "B.CrtYd")
		)
		(fp_line
			(start -0.3048 0.9906)
			(end -0.3048 -0.1016)
			(stroke
				(width 0.1)
				(type default)
			)
			(layer "B.Fab")
		)
		(fp_line
			(start 0.3048 0.9906)
			(end -0.3048 0.9906)
			(stroke
				(width 0.1)
				(type default)
			)
			(layer "B.Fab")
		)
		(fp_line
			(start -0.3048 -0.1016)
			(end 0.3048 -0.1016)
			(stroke
				(width 0.1)
				(type default)
			)
			(layer "B.Fab")
		)
		(fp_line
			(start 0.3048 -0.1016)
			(end 0.3048 0.9906)
			(stroke
				(width 0.1)
				(type default)
			)
			(layer "B.Fab")
		)
		(pad "1" smd rect
			(at 0 0 90)
			(size 0.508 0.508)
			(layers "B.Cu" "B.Mask" "B.Paste")
			(net "P1V2_AUX_BMC")
		)
		(pad "2" smd rect
			(at 0 0.889 90)
			(size 0.508 0.508)
			(layers "B.Cu" "B.Mask" "B.Paste")
			(net "GND")
		)
		(zone
			(layer "B.Cu")
			(hatch none 0.5)
			(connect_pads
				(clearance 0)
			)
			(min_thickness 0.25)
			(keepout
				(tracks not_allowed)
				(vias allowed)
				(pads allowed)
				(copperpour not_allowed)
				(footprints allowed)
			)
			(placement
				(enabled no)
				(sheetname "")
			)
			(fill
				(thermal_gap 0.5)
				(thermal_bridge_width 0.5)
				(island_removal_mode 0)
			)
			(polygon
				(pts
					(xy 418.235638 -37.2745) (xy 418.235638 -37.7825) (xy 418.616638 -37.7825) (xy 418.616638 -37.2745)
				)
			)
		)
		(zone
			(layer "B.Cu")
			(hatch none 0.5)
			(connect_pads
				(clearance 0)
			)
			(min_thickness 0.25)
			(keepout
				(tracks allowed)
				(vias not_allowed)
				(pads allowed)
				(copperpour not_allowed)
				(footprints allowed)
			)
			(placement
				(enabled no)
				(sheetname "")
			)
			(fill
				(thermal_gap 0.5)
				(thermal_bridge_width 0.5)
				(island_removal_mode 0)
			)
			(polygon
				(pts
					(xy 418.616638 -37.2745) (xy 418.616638 -37.7825) (xy 418.235638 -37.7825) (xy 418.235638 -37.2745)
				)
			)
		)
	)
	(footprint ""
		(layer "B.Cu")
		(at 409.917646 -22.996652 -90)
		(property "Reference" "C25W50"
			(at -0.97536 0.76708 0)
			(unlocked yes)
			(layer "B.SilkS")
			(effects
				(font
					(size 0.4064 0.254)
					(thickness 0.1524)
				)
				(justify mirror)
			)
		)
		(property "Value" ""
			(at 0 0 90)
			(layer "B.Fab")
			(effects
				(font
					(size 1.27 1.27)
				)
				(justify mirror)
			)
		)
		(duplicate_pad_numbers_are_jumpers no)
		(fp_poly
			(pts
				(xy 0.4953 -0.2032) (xy -0.4953 -0.2032) (xy -0.4953 1.6002) (xy 0.4953 1.6002)
			)
			(stroke
				(width 0)
				(type default)
			)
			(fill no)
			(layer "B.CrtYd")
		)
		(fp_line
			(start -0.4953 1.6002)
			(end 0.4953 1.6002)
			(stroke
				(width 0.1)
				(type default)
			)
			(layer "B.Fab")
		)
		(fp_line
			(start 0.4953 1.6002)
			(end 0.4953 -0.2032)
			(stroke
				(width 0.1)
				(type default)
			)
			(layer "B.Fab")
		)
		(fp_line
			(start -0.4953 -0.2032)
			(end -0.4953 1.6002)
			(stroke
				(width 0.1)
				(type default)
			)
			(layer "B.Fab")
		)
		(fp_line
			(start 0.4953 -0.2032)
			(end -0.4953 -0.2032)
			(stroke
				(width 0.1)
				(type default)
			)
			(layer "B.Fab")
		)
		(pad "1" smd rect
			(at 0 0 90)
			(size 0.762 0.889)
			(layers "B.Cu" "B.Mask" "B.Paste")
			(net "P3V3_STBY")
		)
		(pad "2" smd rect
			(at 0 1.397 90)
			(size 0.762 0.889)
			(layers "B.Cu" "B.Mask" "B.Paste")
			(net "GND")
		)
		(zone
			(layer "B.Cu")
			(hatch none 0.5)
			(connect_pads
				(clearance 0)
			)
			(min_thickness 0.25)
			(keepout
				(tracks not_allowed)
				(vias allowed)
				(pads allowed)
				(copperpour not_allowed)
				(footprints allowed)
			)
			(placement
				(enabled no)
				(sheetname "")
			)
			(fill
				(thermal_gap 0.5)
				(thermal_bridge_width 0.5)
				(island_removal_mode 0)
			)
			(polygon
				(pts
					(xy 409.473146 -22.615652) (xy 409.473146 -23.377652) (xy 408.965146 -23.377652) (xy 408.965146 -22.615652)
				)
			)
		)
	)
	(footprint ""
		(layer "B.Cu")
		(at 160.76422 -123.9647)
		(property "Reference" "R7M1"
			(at 0 0 0)
			(layer "B.SilkS")
			(hide yes)
			(effects
				(font
					(size 1.27 1.27)
				)
				(justify mirror)
			)
		)
		(property "Value" ""
			(at 0 0 0)
			(layer "B.Fab")
			(effects
				(font
					(size 1.27 1.27)
				)
				(justify mirror)
			)
		)
		(duplicate_pad_numbers_are_jumpers no)
		(fp_poly
			(pts
				(xy 0.2794 -0.1016) (xy -0.2794 -0.1016) (xy -0.2794 0.9906) (xy 0.2794 0.9906)
			)
			(stroke
				(width 0)
				(type default)
			)
			(fill no)
			(layer "B.CrtYd")
		)
		(fp_line
			(start -0.2794 -0.1016)
			(end 0.2794 -0.1016)
			(stroke
				(width 0.1)
				(type default)
			)
			(layer "B.Fab")
		)
		(fp_line
			(start -0.2794 0.9906)
			(end -0.2794 -0.1016)
			(stroke
				(width 0.1)
				(type default)
			)
			(layer "B.Fab")
		)
		(fp_line
			(start 0.2794 -0.1016)
			(end 0.2794 0.9906)
			(stroke
				(width 0.1)
				(type default)
			)
			(layer "B.Fab")
		)
		(fp_line
			(start 0.2794 0.9906)
			(end -0.2794 0.9906)
			(stroke
				(width 0.1)
				(type default)
			)
			(layer "B.Fab")
		)
		(pad "1" smd rect
			(at 0 0 180)
			(size 0.508 0.508)
			(layers "B.Cu" "B.Mask" "B.Paste")
			(net "PVPP_KLM")
		)
		(pad "2" smd rect
			(at 0 0.889 180)
			(size 0.508 0.508)
			(layers "B.Cu" "B.Mask" "B.Paste")
			(net "SMB_DDR_KLM_VPP_SCL_R")
		)
		(zone
			(layer "B.Cu")
			(hatch none 0.5)
			(connect_pads
				(clearance 0)
			)
			(min_thickness 0.25)
			(keepout
				(tracks allowed)
				(vias not_allowed)
				(pads allowed)
				(copperpour not_allowed)
				(footprints allowed)
			)
			(placement
				(enabled no)
				(sheetname "")
			)
			(fill
				(thermal_gap 0.5)
				(thermal_bridge_width 0.5)
				(island_removal_mode 0)
			)
			(polygon
				(pts
					(xy 161.01822 -123.7107) (xy 160.51022 -123.7107) (xy 160.51022 -123.3297) (xy 161.01822 -123.3297)
				)
			)
		)
		(zone
			(layer "B.Cu")
			(hatch none 0.5)
			(connect_pads
				(clearance 0)
			)
			(min_thickness 0.25)
			(keepout
				(tracks not_allowed)
				(vias allowed)
				(pads allowed)
				(copperpour not_allowed)
				(footprints allowed)
			)
			(placement
				(enabled no)
				(sheetname "")
			)
			(fill
				(thermal_gap 0.5)
				(thermal_bridge_width 0.5)
				(island_removal_mode 0)
			)
			(polygon
				(pts
					(xy 161.01822 -123.3297) (xy 160.51022 -123.3297) (xy 160.51022 -123.7107) (xy 161.01822 -123.7107)
				)
			)
		)
	)
	(footprint ""
		(layer "B.Cu")
		(at 390.635744 -24.981916 -90)
		(property "Reference" "C2T16"
			(at 0 0 90)
			(layer "B.SilkS")
			(hide yes)
			(effects
				(font
					(size 1.27 1.27)
				)
				(justify mirror)
			)
		)
		(property "Value" ""
			(at 0 0 90)
			(layer "B.Fab")
			(effects
				(font
					(size 1.27 1.27)
				)
				(justify mirror)
			)
		)
		(duplicate_pad_numbers_are_jumpers no)
		(fp_poly
			(pts
				(xy -0.3048 -0.1016) (xy -0.3048 0.9906) (xy 0.3048 0.9906) (xy 0.3048 -0.1016)
			)
			(stroke
				(width 0)
				(type default)
			)
			(fill no)
			(layer "B.CrtYd")
		)
		(fp_line
			(start -0.3048 0.9906)
			(end -0.3048 -0.1016)
			(stroke
				(width 0.1)
				(type default)
			)
			(layer "B.Fab")
		)
		(fp_line
			(start 0.3048 0.9906)
			(end -0.3048 0.9906)
			(stroke
				(width 0.1)
				(type default)
			)
			(layer "B.Fab")
		)
		(fp_line
			(start -0.3048 -0.1016)
			(end 0.3048 -0.1016)
			(stroke
				(width 0.1)
				(type default)
			)
			(layer "B.Fab")
		)
		(fp_line
			(start 0.3048 -0.1016)
			(end 0.3048 0.9906)
			(stroke
				(width 0.1)
				(type default)
			)
			(layer "B.Fab")
		)
		(pad "1" smd rect
			(at 0 0 90)
			(size 0.508 0.508)
			(layers "B.Cu" "B.Mask" "B.Paste")
			(net "P3V3")
		)
		(pad "2" smd rect
			(at 0 0.889 90)
			(size 0.508 0.508)
			(layers "B.Cu" "B.Mask" "B.Paste")
			(net "GND")
		)
		(zone
			(layer "B.Cu")
			(hatch none 0.5)
			(connect_pads
				(clearance 0)
			)
			(min_thickness 0.25)
			(keepout
				(tracks not_allowed)
				(vias allowed)
				(pads allowed)
				(copperpour not_allowed)
				(footprints allowed)
			)
			(placement
				(enabled no)
				(sheetname "")
			)
			(fill
				(thermal_gap 0.5)
				(thermal_bridge_width 0.5)
				(island_removal_mode 0)
			)
			(polygon
				(pts
					(xy 390.000744 -24.727916) (xy 390.000744 -25.235916) (xy 390.381744 -25.235916) (xy 390.381744 -24.727916)
				)
			)
		)
		(zone
			(layer "B.Cu")
			(hatch none 0.5)
			(connect_pads
				(clearance 0)
			)
			(min_thickness 0.25)
			(keepout
				(tracks allowed)
				(vias not_allowed)
				(pads allowed)
				(copperpour not_allowed)
				(footprints allowed)
			)
			(placement
				(enabled no)
				(sheetname "")
			)
			(fill
				(thermal_gap 0.5)
				(thermal_bridge_width 0.5)
				(island_removal_mode 0)
			)
			(polygon
				(pts
					(xy 390.381744 -24.727916) (xy 390.381744 -25.235916) (xy 390.000744 -25.235916) (xy 390.000744 -24.727916)
				)
			)
		)
	)
	(footprint ""
		(layer "B.Cu")
		(at 354.301806 -61.257434)
		(property "Reference" "C2U18"
			(at 0 0 0)
			(layer "B.SilkS")
			(hide yes)
			(effects
				(font
					(size 1.27 1.27)
				)
				(justify mirror)
			)
		)
		(property "Value" ""
			(at 0 0 0)
			(layer "B.Fab")
			(effects
				(font
					(size 1.27 1.27)
				)
				(justify mirror)
			)
		)
		(duplicate_pad_numbers_are_jumpers no)
		(fp_poly
			(pts
				(xy -0.3048 -0.1016) (xy -0.3048 0.9906) (xy 0.3048 0.9906) (xy 0.3048 -0.1016)
			)
			(stroke
				(width 0)
				(type default)
			)
			(fill no)
			(layer "B.CrtYd")
		)
		(fp_line
			(start -0.3048 -0.1016)
			(end 0.3048 -0.1016)
			(stroke
				(width 0.1)
				(type default)
			)
			(layer "B.Fab")
		)
		(fp_line
			(start -0.3048 0.9906)
			(end -0.3048 -0.1016)
			(stroke
				(width 0.1)
				(type default)
			)
			(layer "B.Fab")
		)
		(fp_line
			(start 0.3048 -0.1016)
			(end 0.3048 0.9906)
			(stroke
				(width 0.1)
				(type default)
			)
			(layer "B.Fab")
		)
		(fp_line
			(start 0.3048 0.9906)
			(end -0.3048 0.9906)
			(stroke
				(width 0.1)
				(type default)
			)
			(layer "B.Fab")
		)
		(pad "1" smd rect
			(at 0 0 180)
			(size 0.508 0.508)
			(layers "B.Cu" "B.Mask" "B.Paste")
			(net "P3E_CPU0_PE1_PCH_RXN<7>")
		)
		(pad "2" smd rect
			(at 0 0.889 180)
			(size 0.508 0.508)
			(layers "B.Cu" "B.Mask" "B.Paste")
			(net "P3E_CPU0_PE1_SS_RXN<7>")
		)
		(zone
			(layer "B.Cu")
			(hatch none 0.5)
			(connect_pads
				(clearance 0)
			)
			(min_thickness 0.25)
			(keepout
				(tracks allowed)
				(vias not_allowed)
				(pads allowed)
				(copperpour not_allowed)
				(footprints allowed)
			)
			(placement
				(enabled no)
				(sheetname "")
			)
			(fill
				(thermal_gap 0.5)
				(thermal_bridge_width 0.5)
				(island_removal_mode 0)
			)
			(polygon
				(pts
					(xy 354.555806 -61.003434) (xy 354.047806 -61.003434) (xy 354.047806 -60.622434) (xy 354.555806 -60.622434)
				)
			)
		)
		(zone
			(layer "B.Cu")
			(hatch none 0.5)
			(connect_pads
				(clearance 0)
			)
			(min_thickness 0.25)
			(keepout
				(tracks not_allowed)
				(vias allowed)
				(pads allowed)
				(copperpour not_allowed)
				(footprints allowed)
			)
			(placement
				(enabled no)
				(sheetname "")
			)
			(fill
				(thermal_gap 0.5)
				(thermal_bridge_width 0.5)
				(island_removal_mode 0)
			)
			(polygon
				(pts
					(xy 354.555806 -60.622434) (xy 354.047806 -60.622434) (xy 354.047806 -61.003434) (xy 354.555806 -61.003434)
				)
			)
		)
	)
	(footprint ""
		(layer "B.Cu")
		(at 10.2108 -124.9172)
		(property "Reference" "Q12W4"
			(at 0 0 0)
			(layer "B.SilkS")
			(hide yes)
			(effects
				(font
					(size 1.27 1.27)
				)
				(justify mirror)
			)
		)
		(property "Value" "*"
			(at 4.572 -7.6835 0)
			(unlocked yes)
			(layer "B.Fab")
			(hide yes)
			(effects
				(font
					(size 1.27 1.016)
					(thickness 0.1524)
				)
				(justify mirror)
			)
		)
		(property "Device Type" "BSL308C-H6327-GP_DISCRET-GB1-BA"
			(at 4.572 -9.2075 0)
			(unlocked yes)
			(layer "B.Fab")
			(hide yes)
			(effects
				(font
					(size 1.27 1.016)
					(thickness 0.1524)
				)
				(justify mirror)
			)
		)
		(duplicate_pad_numbers_are_jumpers no)
		(fp_line
			(start -1.102868 -0.081534)
			(end -1.102868 0.081534)
			(stroke
				(width 0.1524)
				(type default)
			)
			(layer "B.SilkS")
		)
		(fp_line
			(start -1.102868 0.081534)
			(end 1.8796 0.081534)
			(stroke
				(width 0.1524)
				(type default)
			)
			(layer "B.SilkS")
		)
		(fp_line
			(start 1.524 0)
			(end 1.8796 0.081534)
			(stroke
				(width 0.1524)
				(type default)
			)
			(layer "B.SilkS")
		)
		(fp_line
			(start 1.7018 0.3048)
			(end 1.7018 1.8796)
			(stroke
				(width 0.508)
				(type default)
			)
			(layer "B.SilkS")
		)
		(fp_line
			(start 1.8796 -0.081534)
			(end -1.102868 -0.081534)
			(stroke
				(width 0.1524)
				(type default)
			)
			(layer "B.SilkS")
		)
		(fp_line
			(start 1.8796 -0.081534)
			(end 1.524 0)
			(stroke
				(width 0.1524)
				(type default)
			)
			(layer "B.SilkS")
		)
		(fp_line
			(start 1.8796 0.081534)
			(end 1.8796 -0.081534)
			(stroke
				(width 0.1524)
				(type default)
			)
			(layer "B.SilkS")
		)
		(fp_poly
			(pts
				(xy 1.179068 0.081534) (xy 1.179068 -0.081534) (xy -1.102868 -0.081534) (xy -1.102868 0.081534)
			)
			(stroke
				(width 0)
				(type default)
			)
			(fill yes)
			(layer "B.SilkS")
		)
		(fp_rect
			(start 1.4478 1.2446)
			(end -1.4478 -1.2446)
			(stroke
				(width 0)
				(type default)
			)
			(fill no)
			(layer "B.CrtYd")
		)
		(fp_poly
			(pts
				(xy 1.4478 -1.23952) (xy 1.9558 -1.23952) (xy 1.9558 2.1336) (xy -1.9558 2.1336) (xy -1.9558 -2.1336)
				(xy 1.9558 -2.1336) (xy 1.9558 -1.2446) (xy -1.4478 -1.2446) (xy -1.4478 1.2446) (xy 1.4478 1.2446)
			)
			(stroke
				(width 0)
				(type default)
			)
			(fill no)
			(layer "B.CrtYd")
		)
		(fp_rect
			(start 1.9558 2.1336)
			(end -1.9558 -2.1336)
			(stroke
				(width 0)
				(type default)
			)
			(fill no)
			(layer "B.Fab")
		)
		(pad "1" smd rect
			(at 0.950468 0.995934 180)
			(size 0.4572 1.27)
			(layers "B.Cu" "B.Mask" "B.Paste")
			(net "PWRGD_PVDDQ_KLM")
		)
		(pad "2" smd rect
			(at 0 0.995934 180)
			(size 0.4572 1.27)
			(layers "B.Cu" "B.Mask" "B.Paste")
			(net "P12V_NVDIMM_KLM")
		)
		(pad "3" smd rect
			(at -0.950468 0.995934 180)
			(size 0.4572 1.27)
			(layers "B.Cu" "B.Mask" "B.Paste")
			(net "PWRGD_PVDDQ_KLM_N")
		)
		(pad "4" smd rect
			(at -0.950468 -0.995934 180)
			(size 0.4572 1.27)
			(layers "B.Cu" "B.Mask" "B.Paste")
			(net "P12V_NVDIMM_KLM_D")
		)
		(pad "5" smd rect
			(at 0 -0.995934 180)
			(size 0.4572 1.27)
			(layers "B.Cu" "B.Mask" "B.Paste")
			(net "GND")
		)
		(pad "6" smd rect
			(at 0.950468 -0.995934 180)
			(size 0.4572 1.27)
			(layers "B.Cu" "B.Mask" "B.Paste")
			(net "PWRGD_PVDDQ_KLM_N")
		)
	)
	(footprint ""
		(layer "B.Cu")
		(at 374.744742 -73.095104)
		(property "Reference" "C2P5"
			(at 0 0 0)
			(layer "B.SilkS")
			(hide yes)
			(effects
				(font
					(size 1.27 1.27)
				)
				(justify mirror)
			)
		)
		(property "Value" ""
			(at 0 0 0)
			(layer "B.Fab")
			(effects
				(font
					(size 1.27 1.27)
				)
				(justify mirror)
			)
		)
		(duplicate_pad_numbers_are_jumpers no)
		(fp_rect
			(start 0.2794 0.9144)
			(end -0.2794 -0.1143)
			(stroke
				(width 0)
				(type default)
			)
			(fill no)
			(layer "B.CrtYd")
		)
		(fp_line
			(start -0.2794 -0.1143)
			(end -0.2794 0.9144)
			(stroke
				(width 0.1)
				(type default)
			)
			(layer "B.Fab")
		)
		(fp_line
			(start -0.2794 0.9144)
			(end 0.2794 0.9144)
			(stroke
				(width 0.1)
				(type default)
			)
			(layer "B.Fab")
		)
		(fp_line
			(start 0.2794 -0.1143)
			(end -0.2794 -0.1143)
			(stroke
				(width 0.1)
				(type default)
			)
			(layer "B.Fab")
		)
		(fp_line
			(start 0.2794 0.9144)
			(end 0.2794 -0.1143)
			(stroke
				(width 0.1)
				(type default)
			)
			(layer "B.Fab")
		)
		(pad "1" smd custom
			(at 0 0 270)
			(size 0.10414 0.10414)
			(layers "B.Cu" "B.Mask" "B.Paste")
			(net "P3V3_STBY")
			(options
				(clearance outline)
				(anchor circle)
			)
			(primitives
				(gr_poly
					(pts
						(xy -0.20828 -0.08636) (xy -0.20828 0.08636) (xy -0.08636 0.20828) (xy 0.086614 0.20828) (xy 0.20828 0.086614)
						(xy 0.20828 -0.08636) (xy 0.08636 -0.20828) (xy -0.08636 -0.20828)
					)
					(width 0)
					(fill yes)
				)
			)
		)
		(pad "2" smd custom
			(at 0 0.8001 270)
			(size 0.10414 0.10414)
			(layers "B.Cu" "B.Mask" "B.Paste")
			(net "GND")
			(options
				(clearance outline)
				(anchor circle)
			)
			(primitives
				(gr_poly
					(pts
						(xy -0.20828 -0.08636) (xy -0.20828 0.08636) (xy -0.08636 0.20828) (xy 0.086614 0.20828) (xy 0.20828 0.086614)
						(xy 0.20828 -0.08636) (xy 0.08636 -0.20828) (xy -0.08636 -0.20828)
					)
					(width 0)
					(fill yes)
				)
			)
		)
		(zone
			(layer "B.Cu")
			(hatch none 0.5)
			(connect_pads
				(clearance 0)
			)
			(min_thickness 0.25)
			(keepout
				(tracks not_allowed)
				(vias allowed)
				(pads allowed)
				(copperpour not_allowed)
				(footprints allowed)
			)
			(placement
				(enabled no)
				(sheetname "")
			)
			(fill
				(thermal_gap 0.5)
				(thermal_bridge_width 0.5)
				(island_removal_mode 0)
			)
			(polygon
				(pts
					(xy 374.832372 -72.885554) (xy 374.832372 -72.504554) (xy 374.657112 -72.504554) (xy 374.656858 -72.885554)
				)
			)
		)
		(zone
			(layer "B.Cu")
			(hatch none 0.5)
			(connect_pads
				(clearance 0)
			)
			(min_thickness 0.25)
			(keepout
				(tracks allowed)
				(vias not_allowed)
				(pads allowed)
				(copperpour not_allowed)
				(footprints allowed)
			)
			(placement
				(enabled no)
				(sheetname "")
			)
			(fill
				(thermal_gap 0.5)
				(thermal_bridge_width 0.5)
				(island_removal_mode 0)
			)
			(polygon
				(pts
					(xy 374.832372 -72.885554) (xy 374.832372 -72.504554) (xy 374.657112 -72.504554) (xy 374.656858 -72.885554)
				)
			)
		)
	)
	(footprint ""
		(layer "B.Cu")
		(at 390.7155 -38.62451 -90)
		(property "Reference" "C2T4"
			(at 0 0 90)
			(layer "B.SilkS")
			(hide yes)
			(effects
				(font
					(size 1.27 1.27)
				)
				(justify mirror)
			)
		)
		(property "Value" ""
			(at 0 0 90)
			(layer "B.Fab")
			(effects
				(font
					(size 1.27 1.27)
				)
				(justify mirror)
			)
		)
		(duplicate_pad_numbers_are_jumpers no)
		(fp_poly
			(pts
				(xy -0.3048 -0.1016) (xy -0.3048 0.9906) (xy 0.3048 0.9906) (xy 0.3048 -0.1016)
			)
			(stroke
				(width 0)
				(type default)
			)
			(fill no)
			(layer "B.CrtYd")
		)
		(fp_line
			(start -0.3048 0.9906)
			(end -0.3048 -0.1016)
			(stroke
				(width 0.1)
				(type default)
			)
			(layer "B.Fab")
		)
		(fp_line
			(start 0.3048 0.9906)
			(end -0.3048 0.9906)
			(stroke
				(width 0.1)
				(type default)
			)
			(layer "B.Fab")
		)
		(fp_line
			(start -0.3048 -0.1016)
			(end 0.3048 -0.1016)
			(stroke
				(width 0.1)
				(type default)
			)
			(layer "B.Fab")
		)
		(fp_line
			(start 0.3048 -0.1016)
			(end 0.3048 0.9906)
			(stroke
				(width 0.1)
				(type default)
			)
			(layer "B.Fab")
		)
		(pad "1" smd rect
			(at 0 0 90)
			(size 0.508 0.508)
			(layers "B.Cu" "B.Mask" "B.Paste")
			(net "P3V3")
		)
		(pad "2" smd rect
			(at 0 0.889 90)
			(size 0.508 0.508)
			(layers "B.Cu" "B.Mask" "B.Paste")
			(net "GND")
		)
		(zone
			(layer "B.Cu")
			(hatch none 0.5)
			(connect_pads
				(clearance 0)
			)
			(min_thickness 0.25)
			(keepout
				(tracks not_allowed)
				(vias allowed)
				(pads allowed)
				(copperpour not_allowed)
				(footprints allowed)
			)
			(placement
				(enabled no)
				(sheetname "")
			)
			(fill
				(thermal_gap 0.5)
				(thermal_bridge_width 0.5)
				(island_removal_mode 0)
			)
			(polygon
				(pts
					(xy 390.0805 -38.37051) (xy 390.0805 -38.87851) (xy 390.4615 -38.87851) (xy 390.4615 -38.37051)
				)
			)
		)
		(zone
			(layer "B.Cu")
			(hatch none 0.5)
			(connect_pads
				(clearance 0)
			)
			(min_thickness 0.25)
			(keepout
				(tracks allowed)
				(vias not_allowed)
				(pads allowed)
				(copperpour not_allowed)
				(footprints allowed)
			)
			(placement
				(enabled no)
				(sheetname "")
			)
			(fill
				(thermal_gap 0.5)
				(thermal_bridge_width 0.5)
				(island_removal_mode 0)
			)
			(polygon
				(pts
					(xy 390.4615 -38.37051) (xy 390.4615 -38.87851) (xy 390.0805 -38.87851) (xy 390.0805 -38.37051)
				)
			)
		)
	)
	(footprint ""
		(layer "B.Cu")
		(at 161.78022 -123.0757 180)
		(property "Reference" "R7M4"
			(at 0 0 0)
			(layer "B.SilkS")
			(hide yes)
			(effects
				(font
					(size 1.27 1.27)
				)
				(justify mirror)
			)
		)
		(property "Value" ""
			(at 0 0 0)
			(layer "B.Fab")
			(effects
				(font
					(size 1.27 1.27)
				)
				(justify mirror)
			)
		)
		(duplicate_pad_numbers_are_jumpers no)
		(fp_poly
			(pts
				(xy 0.2794 -0.1016) (xy -0.2794 -0.1016) (xy -0.2794 0.9906) (xy 0.2794 0.9906)
			)
			(stroke
				(width 0)
				(type default)
			)
			(fill no)
			(layer "B.CrtYd")
		)
		(fp_line
			(start 0.2794 0.9906)
			(end -0.2794 0.9906)
			(stroke
				(width 0.1)
				(type default)
			)
			(layer "B.Fab")
		)
		(fp_line
			(start 0.2794 -0.1016)
			(end 0.2794 0.9906)
			(stroke
				(width 0.1)
				(type default)
			)
			(layer "B.Fab")
		)
		(fp_line
			(start -0.2794 0.9906)
			(end -0.2794 -0.1016)
			(stroke
				(width 0.1)
				(type default)
			)
			(layer "B.Fab")
		)
		(fp_line
			(start -0.2794 -0.1016)
			(end 0.2794 -0.1016)
			(stroke
				(width 0.1)
				(type default)
			)
			(layer "B.Fab")
		)
		(pad "1" smd rect
			(at 0 0)
			(size 0.508 0.508)
			(layers "B.Cu" "B.Mask" "B.Paste")
			(net "SMB_DDR_KLM_VPP_SCL_R")
		)
		(pad "2" smd rect
			(at 0 0.889)
			(size 0.508 0.508)
			(layers "B.Cu" "B.Mask" "B.Paste")
			(net "SMB_DDR_KLM_VPP_SCL")
		)
		(zone
			(layer "B.Cu")
			(hatch none 0.5)
			(connect_pads
				(clearance 0)
			)
			(min_thickness 0.25)
			(keepout
				(tracks not_allowed)
				(vias allowed)
				(pads allowed)
				(copperpour not_allowed)
				(footprints allowed)
			)
			(placement
				(enabled no)
				(sheetname "")
			)
			(fill
				(thermal_gap 0.5)
				(thermal_bridge_width 0.5)
				(island_removal_mode 0)
			)
			(polygon
				(pts
					(xy 161.52622 -123.7107) (xy 162.03422 -123.7107) (xy 162.03422 -123.3297) (xy 161.52622 -123.3297)
				)
			)
		)
		(zone
			(layer "B.Cu")
			(hatch none 0.5)
			(connect_pads
				(clearance 0)
			)
			(min_thickness 0.25)
			(keepout
				(tracks allowed)
				(vias not_allowed)
				(pads allowed)
				(copperpour not_allowed)
				(footprints allowed)
			)
			(placement
				(enabled no)
				(sheetname "")
			)
			(fill
				(thermal_gap 0.5)
				(thermal_bridge_width 0.5)
				(island_removal_mode 0)
			)
			(polygon
				(pts
					(xy 161.52622 -123.3297) (xy 162.03422 -123.3297) (xy 162.03422 -123.7107) (xy 161.52622 -123.7107)
				)
			)
		)
	)
	(footprint ""
		(layer "B.Cu")
		(at 451.7898 -5.5118 90)
		(property "Reference" "R6W2"
			(at 0.8382 -0.67818 90)
			(unlocked yes)
			(layer "B.SilkS")
			(effects
				(font
					(size 0.4064 0.254)
					(thickness 0.1524)
				)
				(justify left mirror)
			)
		)
		(property "Value" ""
			(at 0 0 90)
			(layer "B.Fab")
			(effects
				(font
					(size 1.27 1.27)
				)
				(justify mirror)
			)
		)
		(duplicate_pad_numbers_are_jumpers no)
		(fp_poly
			(pts
				(xy 0.2794 -0.1016) (xy -0.2794 -0.1016) (xy -0.2794 0.9906) (xy 0.2794 0.9906)
			)
			(stroke
				(width 0)
				(type default)
			)
			(fill no)
			(layer "B.CrtYd")
		)
		(fp_line
			(start 0.2794 -0.1016)
			(end 0.2794 0.9906)
			(stroke
				(width 0.1)
				(type default)
			)
			(layer "B.Fab")
		)
		(fp_line
			(start -0.2794 -0.1016)
			(end 0.2794 -0.1016)
			(stroke
				(width 0.1)
				(type default)
			)
			(layer "B.Fab")
		)
		(fp_line
			(start 0.2794 0.9906)
			(end -0.2794 0.9906)
			(stroke
				(width 0.1)
				(type default)
			)
			(layer "B.Fab")
		)
		(fp_line
			(start -0.2794 0.9906)
			(end -0.2794 -0.1016)
			(stroke
				(width 0.1)
				(type default)
			)
			(layer "B.Fab")
		)
		(pad "1" smd rect
			(at 0 0 270)
			(size 0.508 0.508)
			(layers "B.Cu" "B.Mask" "B.Paste")
			(net "PD_UV_HIGH_SET")
		)
		(pad "2" smd rect
			(at 0 0.889 270)
			(size 0.508 0.508)
			(layers "B.Cu" "B.Mask" "B.Paste")
			(net "GND")
		)
		(zone
			(layer "B.Cu")
			(hatch none 0.5)
			(connect_pads
				(clearance 0)
			)
			(min_thickness 0.25)
			(keepout
				(tracks allowed)
				(vias not_allowed)
				(pads allowed)
				(copperpour not_allowed)
				(footprints allowed)
			)
			(placement
				(enabled no)
				(sheetname "")
			)
			(fill
				(thermal_gap 0.5)
				(thermal_bridge_width 0.5)
				(island_removal_mode 0)
			)
			(polygon
				(pts
					(xy 452.0438 -5.7658) (xy 452.0438 -5.2578) (xy 452.4248 -5.2578) (xy 452.4248 -5.7658)
				)
			)
		)
		(zone
			(layer "B.Cu")
			(hatch none 0.5)
			(connect_pads
				(clearance 0)
			)
			(min_thickness 0.25)
			(keepout
				(tracks not_allowed)
				(vias allowed)
				(pads allowed)
				(copperpour not_allowed)
				(footprints allowed)
			)
			(placement
				(enabled no)
				(sheetname "")
			)
			(fill
				(thermal_gap 0.5)
				(thermal_bridge_width 0.5)
				(island_removal_mode 0)
			)
			(polygon
				(pts
					(xy 452.4248 -5.7658) (xy 452.4248 -5.2578) (xy 452.0438 -5.2578) (xy 452.0438 -5.7658)
				)
			)
		)
	)
	(footprint ""
		(layer "B.Cu")
		(at 282.2448 -77.2414 -90)
		(property "Reference" "R4P4"
			(at 0 0 90)
			(layer "B.SilkS")
			(hide yes)
			(effects
				(font
					(size 1.27 1.27)
				)
				(justify mirror)
			)
		)
		(property "Value" ""
			(at 0 0 90)
			(layer "B.Fab")
			(effects
				(font
					(size 1.27 1.27)
				)
				(justify mirror)
			)
		)
		(duplicate_pad_numbers_are_jumpers no)
		(fp_rect
			(start 0.2794 0.9906)
			(end -0.2794 -0.1016)
			(stroke
				(width 0)
				(type default)
			)
			(fill no)
			(layer "B.CrtYd")
		)
		(fp_line
			(start -0.2794 0.9906)
			(end -0.2794 -0.1016)
			(stroke
				(width 0.1)
				(type default)
			)
			(layer "B.Fab")
		)
		(fp_line
			(start 0.2794 0.9906)
			(end -0.2794 0.9906)
			(stroke
				(width 0.1)
				(type default)
			)
			(layer "B.Fab")
		)
		(fp_line
			(start -0.2794 -0.1016)
			(end 0.2794 -0.1016)
			(stroke
				(width 0.1)
				(type default)
			)
			(layer "B.Fab")
		)
		(fp_line
			(start 0.2794 -0.1016)
			(end 0.2794 0.9906)
			(stroke
				(width 0.1)
				(type default)
			)
			(layer "B.Fab")
		)
		(pad "1" smd rect
			(at 0 0 90)
			(size 0.508 0.508)
			(layers "B.Cu" "B.Mask" "B.Paste")
			(net "A_CPU0_UPI2_RBIAS")
		)
		(pad "2" smd rect
			(at 0 0.889 90)
			(size 0.508 0.508)
			(layers "B.Cu" "B.Mask" "B.Paste")
			(net "GND")
		)
		(zone
			(layer "B.Cu")
			(hatch none 0.5)
			(connect_pads
				(clearance 0)
			)
			(min_thickness 0.25)
			(keepout
				(tracks not_allowed)
				(vias allowed)
				(pads allowed)
				(copperpour not_allowed)
				(footprints allowed)
			)
			(placement
				(enabled no)
				(sheetname "")
			)
			(fill
				(thermal_gap 0.5)
				(thermal_bridge_width 0.5)
				(island_removal_mode 0)
			)
			(polygon
				(pts
					(xy 281.6098 -76.9874) (xy 281.9908 -76.9874) (xy 281.9908 -77.4954) (xy 281.6098 -77.4954)
				)
			)
		)
		(zone
			(layer "B.Cu")
			(hatch none 0.5)
			(connect_pads
				(clearance 0)
			)
			(min_thickness 0.25)
			(keepout
				(tracks allowed)
				(vias not_allowed)
				(pads allowed)
				(copperpour not_allowed)
				(footprints allowed)
			)
			(placement
				(enabled no)
				(sheetname "")
			)
			(fill
				(thermal_gap 0.5)
				(thermal_bridge_width 0.5)
				(island_removal_mode 0)
			)
			(polygon
				(pts
					(xy 281.6098 -76.9874) (xy 281.9908 -76.9874) (xy 281.9908 -77.4954) (xy 281.6098 -77.4954)
				)
			)
		)
	)
	(footprint ""
		(layer "B.Cu")
		(at 369.443 -112.395 -90)
		(property "Reference" "C3M44"
			(at 0 0 90)
			(layer "B.SilkS")
			(hide yes)
			(effects
				(font
					(size 1.27 1.27)
				)
				(justify mirror)
			)
		)
		(property "Value" ""
			(at 0 0 90)
			(layer "B.Fab")
			(effects
				(font
					(size 1.27 1.27)
				)
				(justify mirror)
			)
		)
		(duplicate_pad_numbers_are_jumpers no)
		(fp_poly
			(pts
				(xy -0.3048 -0.1016) (xy -0.3048 0.9906) (xy 0.3048 0.9906) (xy 0.3048 -0.1016)
			)
			(stroke
				(width 0)
				(type default)
			)
			(fill no)
			(layer "B.CrtYd")
		)
		(fp_line
			(start -0.3048 0.9906)
			(end -0.3048 -0.1016)
			(stroke
				(width 0.1)
				(type default)
			)
			(layer "B.Fab")
		)
		(fp_line
			(start 0.3048 0.9906)
			(end -0.3048 0.9906)
			(stroke
				(width 0.1)
				(type default)
			)
			(layer "B.Fab")
		)
		(fp_line
			(start -0.3048 -0.1016)
			(end 0.3048 -0.1016)
			(stroke
				(width 0.1)
				(type default)
			)
			(layer "B.Fab")
		)
		(fp_line
			(start 0.3048 -0.1016)
			(end 0.3048 0.9906)
			(stroke
				(width 0.1)
				(type default)
			)
			(layer "B.Fab")
		)
		(pad "1" smd rect
			(at 0 0 90)
			(size 0.508 0.508)
			(layers "B.Cu" "B.Mask" "B.Paste")
			(net "DMI_CPU0_PCH_RX_DN<0>")
		)
		(pad "2" smd rect
			(at 0 0.889 90)
			(size 0.508 0.508)
			(layers "B.Cu" "B.Mask" "B.Paste")
			(net "DMI_CPU0_PCH_RX_C_DN<0>")
		)
		(zone
			(layer "B.Cu")
			(hatch none 0.5)
			(connect_pads
				(clearance 0)
			)
			(min_thickness 0.25)
			(keepout
				(tracks not_allowed)
				(vias allowed)
				(pads allowed)
				(copperpour not_allowed)
				(footprints allowed)
			)
			(placement
				(enabled no)
				(sheetname "")
			)
			(fill
				(thermal_gap 0.5)
				(thermal_bridge_width 0.5)
				(island_removal_mode 0)
			)
			(polygon
				(pts
					(xy 368.808 -112.141) (xy 368.808 -112.649) (xy 369.189 -112.649) (xy 369.189 -112.141)
				)
			)
		)
		(zone
			(layer "B.Cu")
			(hatch none 0.5)
			(connect_pads
				(clearance 0)
			)
			(min_thickness 0.25)
			(keepout
				(tracks allowed)
				(vias not_allowed)
				(pads allowed)
				(copperpour not_allowed)
				(footprints allowed)
			)
			(placement
				(enabled no)
				(sheetname "")
			)
			(fill
				(thermal_gap 0.5)
				(thermal_bridge_width 0.5)
				(island_removal_mode 0)
			)
			(polygon
				(pts
					(xy 369.189 -112.141) (xy 369.189 -112.649) (xy 368.808 -112.649) (xy 368.808 -112.141)
				)
			)
		)
	)
	(footprint ""
		(layer "B.Cu")
		(at -2.33426 -121.47296 180)
		(property "Reference" "R9M13"
			(at 0 0 0)
			(layer "B.SilkS")
			(hide yes)
			(effects
				(font
					(size 1.27 1.27)
				)
				(justify mirror)
			)
		)
		(property "Value" ""
			(at 0 0 0)
			(layer "B.Fab")
			(effects
				(font
					(size 1.27 1.27)
				)
				(justify mirror)
			)
		)
		(duplicate_pad_numbers_are_jumpers no)
		(fp_rect
			(start 0.2794 -0.1016)
			(end -0.2794 0.9906)
			(stroke
				(width 0)
				(type default)
			)
			(fill no)
			(layer "B.CrtYd")
		)
		(fp_line
			(start 0.2794 0.9906)
			(end -0.2794 0.9906)
			(stroke
				(width 0.1)
				(type default)
			)
			(layer "B.Fab")
		)
		(fp_line
			(start 0.2794 -0.1016)
			(end 0.2794 0.9906)
			(stroke
				(width 0.1)
				(type default)
			)
			(layer "B.Fab")
		)
		(fp_line
			(start -0.2794 0.9906)
			(end -0.2794 -0.1016)
			(stroke
				(width 0.1)
				(type default)
			)
			(layer "B.Fab")
		)
		(fp_line
			(start -0.2794 -0.1016)
			(end 0.2794 -0.1016)
			(stroke
				(width 0.1)
				(type default)
			)
			(layer "B.Fab")
		)
		(pad "1" smd rect
			(at 0 0)
			(size 0.508 0.508)
			(layers "B.Cu" "B.Mask" "B.Paste")
			(net "SMB_PEHPCPU1_STBY_LVC3_R_SDA")
		)
		(pad "2" smd rect
			(at 0 0.889)
			(size 0.508 0.508)
			(layers "B.Cu" "B.Mask" "B.Paste")
			(net "SMB_PEHPCPU1_STBY_LVC3_SDA")
		)
		(zone
			(layer "B.Cu")
			(hatch none 0.5)
			(connect_pads
				(clearance 0)
			)
			(min_thickness 0.25)
			(keepout
				(tracks not_allowed)
				(vias allowed)
				(pads allowed)
				(copperpour not_allowed)
				(footprints allowed)
			)
			(placement
				(enabled no)
				(sheetname "")
			)
			(fill
				(thermal_gap 0.5)
				(thermal_bridge_width 0.5)
				(island_removal_mode 0)
			)
			(polygon
				(pts
					(xy -2.58826 -121.72696) (xy -2.08026 -121.72696) (xy -2.08026 -122.10796) (xy -2.58826 -122.10796)
				)
			)
		)
		(zone
			(layer "B.Cu")
			(hatch none 0.5)
			(connect_pads
				(clearance 0)
			)
			(min_thickness 0.25)
			(keepout
				(tracks allowed)
				(vias not_allowed)
				(pads allowed)
				(copperpour not_allowed)
				(footprints allowed)
			)
			(placement
				(enabled no)
				(sheetname "")
			)
			(fill
				(thermal_gap 0.5)
				(thermal_bridge_width 0.5)
				(island_removal_mode 0)
			)
			(polygon
				(pts
					(xy -2.58826 -121.72696) (xy -2.08026 -121.72696) (xy -2.08026 -122.10796) (xy -2.58826 -122.10796)
				)
			)
		)
	)
	(footprint ""
		(layer "B.Cu")
		(at 16.82242 -108.83392 90)
		(property "Reference" "C9N1"
			(at 0 0 90)
			(layer "B.SilkS")
			(hide yes)
			(effects
				(font
					(size 1.27 1.27)
				)
				(justify mirror)
			)
		)
		(property "Value" ""
			(at 0 0 90)
			(layer "B.Fab")
			(effects
				(font
					(size 1.27 1.27)
				)
				(justify mirror)
			)
		)
		(duplicate_pad_numbers_are_jumpers no)
		(fp_poly
			(pts
				(xy -0.3048 -0.1016) (xy -0.3048 0.9906) (xy 0.3048 0.9906) (xy 0.3048 -0.1016)
			)
			(stroke
				(width 0)
				(type default)
			)
			(fill no)
			(layer "B.CrtYd")
		)
		(fp_line
			(start 0.3048 -0.1016)
			(end 0.3048 0.9906)
			(stroke
				(width 0.1)
				(type default)
			)
			(layer "B.Fab")
		)
		(fp_line
			(start -0.3048 -0.1016)
			(end 0.3048 -0.1016)
			(stroke
				(width 0.1)
				(type default)
			)
			(layer "B.Fab")
		)
		(fp_line
			(start 0.3048 0.9906)
			(end -0.3048 0.9906)
			(stroke
				(width 0.1)
				(type default)
			)
			(layer "B.Fab")
		)
		(fp_line
			(start -0.3048 0.9906)
			(end -0.3048 -0.1016)
			(stroke
				(width 0.1)
				(type default)
			)
			(layer "B.Fab")
		)
		(pad "1" smd rect
			(at 0 0 270)
			(size 0.508 0.508)
			(layers "B.Cu" "B.Mask" "B.Paste")
			(net "P3E_CPU1_PE3_MP_C_TXP<10>")
		)
		(pad "2" smd rect
			(at 0 0.889 270)
			(size 0.508 0.508)
			(layers "B.Cu" "B.Mask" "B.Paste")
			(net "P3E_CPU1_PE3_MP_TXP<10>")
		)
		(zone
			(layer "B.Cu")
			(hatch none 0.5)
			(connect_pads
				(clearance 0)
			)
			(min_thickness 0.25)
			(keepout
				(tracks allowed)
				(vias not_allowed)
				(pads allowed)
				(copperpour not_allowed)
				(footprints allowed)
			)
			(placement
				(enabled no)
				(sheetname "")
			)
			(fill
				(thermal_gap 0.5)
				(thermal_bridge_width 0.5)
				(island_removal_mode 0)
			)
			(polygon
				(pts
					(xy 17.07642 -109.08792) (xy 17.07642 -108.57992) (xy 17.45742 -108.57992) (xy 17.45742 -109.08792)
				)
			)
		)
		(zone
			(layer "B.Cu")
			(hatch none 0.5)
			(connect_pads
				(clearance 0)
			)
			(min_thickness 0.25)
			(keepout
				(tracks not_allowed)
				(vias allowed)
				(pads allowed)
				(copperpour not_allowed)
				(footprints allowed)
			)
			(placement
				(enabled no)
				(sheetname "")
			)
			(fill
				(thermal_gap 0.5)
				(thermal_bridge_width 0.5)
				(island_removal_mode 0)
			)
			(polygon
				(pts
					(xy 17.45742 -109.08792) (xy 17.45742 -108.57992) (xy 17.07642 -108.57992) (xy 17.07642 -109.08792)
				)
			)
		)
	)
	(footprint ""
		(layer "B.Cu")
		(at 456.025758 -31.173674 180)
		(property "Reference" "R8D22"
			(at 0 0 0)
			(layer "B.SilkS")
			(hide yes)
			(effects
				(font
					(size 1.27 1.27)
				)
				(justify mirror)
			)
		)
		(property "Value" ""
			(at 0 0 0)
			(layer "B.Fab")
			(effects
				(font
					(size 1.27 1.27)
				)
				(justify mirror)
			)
		)
		(duplicate_pad_numbers_are_jumpers no)
		(fp_poly
			(pts
				(xy 0.2794 -0.1016) (xy -0.2794 -0.1016) (xy -0.2794 0.9906) (xy 0.2794 0.9906)
			)
			(stroke
				(width 0)
				(type default)
			)
			(fill no)
			(layer "B.CrtYd")
		)
		(fp_line
			(start 0.2794 0.9906)
			(end -0.2794 0.9906)
			(stroke
				(width 0.1)
				(type default)
			)
			(layer "B.Fab")
		)
		(fp_line
			(start 0.2794 -0.1016)
			(end 0.2794 0.9906)
			(stroke
				(width 0.1)
				(type default)
			)
			(layer "B.Fab")
		)
		(fp_line
			(start -0.2794 0.9906)
			(end -0.2794 -0.1016)
			(stroke
				(width 0.1)
				(type default)
			)
			(layer "B.Fab")
		)
		(fp_line
			(start -0.2794 -0.1016)
			(end 0.2794 -0.1016)
			(stroke
				(width 0.1)
				(type default)
			)
			(layer "B.Fab")
		)
		(pad "1" smd rect
			(at 0 0)
			(size 0.508 0.508)
			(layers "B.Cu" "B.Mask" "B.Paste")
			(net "RST_BMC_SRST_R2_N")
		)
		(pad "2" smd rect
			(at 0 0.889)
			(size 0.508 0.508)
			(layers "B.Cu" "B.Mask" "B.Paste")
			(net "FM_TPM_PRES_RST_N")
		)
		(zone
			(layer "B.Cu")
			(hatch none 0.5)
			(connect_pads
				(clearance 0)
			)
			(min_thickness 0.25)
			(keepout
				(tracks not_allowed)
				(vias allowed)
				(pads allowed)
				(copperpour not_allowed)
				(footprints allowed)
			)
			(placement
				(enabled no)
				(sheetname "")
			)
			(fill
				(thermal_gap 0.5)
				(thermal_bridge_width 0.5)
				(island_removal_mode 0)
			)
			(polygon
				(pts
					(xy 455.771758 -31.808674) (xy 456.279758 -31.808674) (xy 456.279758 -31.427674) (xy 455.771758 -31.427674)
				)
			)
		)
		(zone
			(layer "B.Cu")
			(hatch none 0.5)
			(connect_pads
				(clearance 0)
			)
			(min_thickness 0.25)
			(keepout
				(tracks allowed)
				(vias not_allowed)
				(pads allowed)
				(copperpour not_allowed)
				(footprints allowed)
			)
			(placement
				(enabled no)
				(sheetname "")
			)
			(fill
				(thermal_gap 0.5)
				(thermal_bridge_width 0.5)
				(island_removal_mode 0)
			)
			(polygon
				(pts
					(xy 455.771758 -31.427674) (xy 456.279758 -31.427674) (xy 456.279758 -31.808674) (xy 455.771758 -31.808674)
				)
			)
		)
	)
	(footprint ""
		(layer "B.Cu")
		(at 382.905 -133.604 90)
		(property "Reference" "C3M27"
			(at 0 0 90)
			(layer "B.SilkS")
			(hide yes)
			(effects
				(font
					(size 1.27 1.27)
				)
				(justify mirror)
			)
		)
		(property "Value" ""
			(at 0 0 90)
			(layer "B.Fab")
			(effects
				(font
					(size 1.27 1.27)
				)
				(justify mirror)
			)
		)
		(duplicate_pad_numbers_are_jumpers no)
		(fp_poly
			(pts
				(xy -0.3048 -0.1016) (xy -0.3048 0.9906) (xy 0.3048 0.9906) (xy 0.3048 -0.1016)
			)
			(stroke
				(width 0)
				(type default)
			)
			(fill no)
			(layer "B.CrtYd")
		)
		(fp_line
			(start 0.3048 -0.1016)
			(end 0.3048 0.9906)
			(stroke
				(width 0.1)
				(type default)
			)
			(layer "B.Fab")
		)
		(fp_line
			(start -0.3048 -0.1016)
			(end 0.3048 -0.1016)
			(stroke
				(width 0.1)
				(type default)
			)
			(layer "B.Fab")
		)
		(fp_line
			(start 0.3048 0.9906)
			(end -0.3048 0.9906)
			(stroke
				(width 0.1)
				(type default)
			)
			(layer "B.Fab")
		)
		(fp_line
			(start -0.3048 0.9906)
			(end -0.3048 -0.1016)
			(stroke
				(width 0.1)
				(type default)
			)
			(layer "B.Fab")
		)
		(pad "1" smd rect
			(at 0 0 270)
			(size 0.508 0.508)
			(layers "B.Cu" "B.Mask" "B.Paste")
			(net "P1V05_PCH_STBY_VCCA_XTAL")
		)
		(pad "2" smd rect
			(at 0 0.889 270)
			(size 0.508 0.508)
			(layers "B.Cu" "B.Mask" "B.Paste")
			(net "GND")
		)
		(zone
			(layer "B.Cu")
			(hatch none 0.5)
			(connect_pads
				(clearance 0)
			)
			(min_thickness 0.25)
			(keepout
				(tracks allowed)
				(vias not_allowed)
				(pads allowed)
				(copperpour not_allowed)
				(footprints allowed)
			)
			(placement
				(enabled no)
				(sheetname "")
			)
			(fill
				(thermal_gap 0.5)
				(thermal_bridge_width 0.5)
				(island_removal_mode 0)
			)
			(polygon
				(pts
					(xy 383.159 -133.858) (xy 383.159 -133.35) (xy 383.54 -133.35) (xy 383.54 -133.858)
				)
			)
		)
		(zone
			(layer "B.Cu")
			(hatch none 0.5)
			(connect_pads
				(clearance 0)
			)
			(min_thickness 0.25)
			(keepout
				(tracks not_allowed)
				(vias allowed)
				(pads allowed)
				(copperpour not_allowed)
				(footprints allowed)
			)
			(placement
				(enabled no)
				(sheetname "")
			)
			(fill
				(thermal_gap 0.5)
				(thermal_bridge_width 0.5)
				(island_removal_mode 0)
			)
			(polygon
				(pts
					(xy 383.54 -133.858) (xy 383.54 -133.35) (xy 383.159 -133.35) (xy 383.159 -133.858)
				)
			)
		)
	)
	(footprint ""
		(layer "B.Cu")
		(at 14.445488 -80.7847)
		(property "Reference" "Q1W5"
			(at 0.229362 -1.2065 0)
			(unlocked yes)
			(layer "B.SilkS")
			(effects
				(font
					(size 0.4064 0.254)
					(thickness 0.1524)
				)
				(justify left mirror)
			)
		)
		(property "Value" ""
			(at 0 0 0)
			(layer "B.Fab")
			(effects
				(font
					(size 1.27 1.27)
				)
				(justify mirror)
			)
		)
		(duplicate_pad_numbers_are_jumpers no)
		(fp_line
			(start -1.778 -0.5715)
			(end -1.778 0.3175)
			(stroke
				(width 0.1524)
				(type default)
			)
			(layer "B.SilkS")
		)
		(fp_line
			(start -1.778 2.4765)
			(end -1.778 1.5875)
			(stroke
				(width 0.1524)
				(type default)
			)
			(layer "B.SilkS")
		)
		(fp_line
			(start -0.9525 -0.5715)
			(end -1.778 -0.5715)
			(stroke
				(width 0.1524)
				(type default)
			)
			(layer "B.SilkS")
		)
		(fp_line
			(start -0.9525 2.4765)
			(end -1.778 2.4765)
			(stroke
				(width 0.1524)
				(type default)
			)
			(layer "B.SilkS")
		)
		(fp_line
			(start -0.381 0.635)
			(end -0.381 1.27)
			(stroke
				(width 0.1524)
				(type default)
			)
			(layer "B.SilkS")
		)
		(fp_circle
			(center 0.9525 -0.9271)
			(end 1.0795 -0.9271)
			(stroke
				(width 0.254)
				(type default)
			)
			(fill no)
			(layer "B.SilkS")
		)
		(fp_poly
			(pts
				(xy -1.778 2.4765) (xy -0.381 2.4765) (xy -0.381 -0.5715) (xy -1.778 -0.5715)
			)
			(stroke
				(width 0)
				(type default)
			)
			(fill no)
			(layer "B.CrtYd")
		)
		(fp_line
			(start -1.778 -0.5715)
			(end -0.381 -0.5715)
			(stroke
				(width 0.1)
				(type default)
			)
			(layer "B.Fab")
		)
		(fp_line
			(start -1.778 2.4765)
			(end -1.778 -0.5715)
			(stroke
				(width 0.1)
				(type default)
			)
			(layer "B.Fab")
		)
		(fp_line
			(start -0.381 -0.5715)
			(end -0.381 2.4765)
			(stroke
				(width 0.1)
				(type default)
			)
			(layer "B.Fab")
		)
		(fp_line
			(start -0.381 2.4765)
			(end -1.778 2.4765)
			(stroke
				(width 0.1)
				(type default)
			)
			(layer "B.Fab")
		)
		(fp_circle
			(center 0.9525 -0.9271)
			(end 1.0795 -0.9271)
			(stroke
				(width 0.254)
				(type default)
			)
			(fill no)
			(layer "B.Fab")
		)
		(pad "1" smd rect
			(at 0 0 180)
			(size 1.143 0.508)
			(layers "B.Cu" "B.Mask" "B.Paste")
			(net "A_HSC_HIGH_EN")
		)
		(pad "2" smd rect
			(at 0 1.905 180)
			(size 1.143 0.508)
			(layers "B.Cu" "B.Mask" "B.Paste")
			(net "GND")
		)
		(pad "3" smd rect
			(at -2.159 0.9525 180)
			(size 1.143 0.508)
			(layers "B.Cu" "B.Mask" "B.Paste")
			(net "A_HSC_LOW_GATE")
		)
	)
	(footprint ""
		(layer "B.Cu")
		(at 334.264 -45.974 180)
		(property "Reference" "C3R4"
			(at -3.14833 3.429 270)
			(unlocked yes)
			(layer "B.SilkS")
			(effects
				(font
					(size 0.7874 0.5842)
					(thickness 0.1524)
				)
				(justify mirror)
			)
		)
		(property "Value" ""
			(at 0 0 0)
			(layer "B.Fab")
			(effects
				(font
					(size 1.27 1.27)
				)
				(justify mirror)
			)
		)
		(duplicate_pad_numbers_are_jumpers no)
		(fp_line
			(start 2.563114 1.633728)
			(end 1.6002 1.633728)
			(stroke
				(width 0.1524)
				(type default)
			)
			(layer "B.SilkS")
		)
		(fp_line
			(start 2.563114 -1.616456)
			(end 2.563114 1.633728)
			(stroke
				(width 0.1524)
				(type default)
			)
			(layer "B.SilkS")
		)
		(fp_line
			(start 2.286 7.366)
			(end 2.286 1.632712)
			(stroke
				(width 0.1524)
				(type default)
			)
			(layer "B.SilkS")
		)
		(fp_line
			(start 2.286 7.366)
			(end 1.60147 7.366)
			(stroke
				(width 0.1524)
				(type default)
			)
			(layer "B.SilkS")
		)
		(fp_line
			(start 1.6002 -1.616456)
			(end 2.563114 -1.616456)
			(stroke
				(width 0.1524)
				(type default)
			)
			(layer "B.SilkS")
		)
		(fp_line
			(start -1.6002 -1.616456)
			(end -2.504948 -1.616456)
			(stroke
				(width 0.1524)
				(type default)
			)
			(layer "B.SilkS")
		)
		(fp_line
			(start -2.286 7.366)
			(end -1.600708 7.366)
			(stroke
				(width 0.1524)
				(type default)
			)
			(layer "B.SilkS")
		)
		(fp_line
			(start -2.286 7.366)
			(end -2.286 1.63195)
			(stroke
				(width 0.1524)
				(type default)
			)
			(layer "B.SilkS")
		)
		(fp_line
			(start -2.504948 1.633728)
			(end -1.6002 1.633728)
			(stroke
				(width 0.1524)
				(type default)
			)
			(layer "B.SilkS")
		)
		(fp_line
			(start -2.504948 -1.616456)
			(end -2.504948 1.633728)
			(stroke
				(width 0.1524)
				(type default)
			)
			(layer "B.SilkS")
		)
		(fp_rect
			(start 2.286 7.366)
			(end -2.286 -0.254)
			(stroke
				(width 0)
				(type default)
			)
			(fill no)
			(layer "B.CrtYd")
		)
		(fp_line
			(start 2.286 7.366)
			(end 2.286 -0.254)
			(stroke
				(width 0.1)
				(type default)
			)
			(layer "B.Fab")
		)
		(fp_line
			(start 2.286 -0.254)
			(end -2.286 -0.254)
			(stroke
				(width 0.1)
				(type default)
			)
			(layer "B.Fab")
		)
		(fp_line
			(start -2.286 7.366)
			(end 2.286 7.366)
			(stroke
				(width 0.1)
				(type default)
			)
			(layer "B.Fab")
		)
		(fp_line
			(start -2.286 -0.254)
			(end -2.286 7.366)
			(stroke
				(width 0.1)
				(type default)
			)
			(layer "B.Fab")
		)
		(pad "1" smd rect
			(at 0 0)
			(size 2.54 3.048)
			(layers "B.Cu" "B.Mask" "B.Paste")
			(net "PVCCMCP_CPU0")
		)
		(pad "2" smd rect
			(at 0 7.112)
			(size 2.54 3.048)
			(layers "B.Cu" "B.Mask" "B.Paste")
			(net "GND")
		)
	)
	(footprint ""
		(layer "B.Cu")
		(at 437.515 -52.3875)
		(property "Reference" "C2R17"
			(at 0 0 0)
			(layer "B.SilkS")
			(hide yes)
			(effects
				(font
					(size 1.27 1.27)
				)
				(justify mirror)
			)
		)
		(property "Value" ""
			(at 0 0 0)
			(layer "B.Fab")
			(effects
				(font
					(size 1.27 1.27)
				)
				(justify mirror)
			)
		)
		(duplicate_pad_numbers_are_jumpers no)
		(fp_poly
			(pts
				(xy -0.3048 -0.1016) (xy -0.3048 0.9906) (xy 0.3048 0.9906) (xy 0.3048 -0.1016)
			)
			(stroke
				(width 0)
				(type default)
			)
			(fill no)
			(layer "B.CrtYd")
		)
		(fp_line
			(start -0.3048 -0.1016)
			(end 0.3048 -0.1016)
			(stroke
				(width 0.1)
				(type default)
			)
			(layer "B.Fab")
		)
		(fp_line
			(start -0.3048 0.9906)
			(end -0.3048 -0.1016)
			(stroke
				(width 0.1)
				(type default)
			)
			(layer "B.Fab")
		)
		(fp_line
			(start 0.3048 -0.1016)
			(end 0.3048 0.9906)
			(stroke
				(width 0.1)
				(type default)
			)
			(layer "B.Fab")
		)
		(fp_line
			(start 0.3048 0.9906)
			(end -0.3048 0.9906)
			(stroke
				(width 0.1)
				(type default)
			)
			(layer "B.Fab")
		)
		(pad "1" smd rect
			(at 0 0 180)
			(size 0.508 0.508)
			(layers "B.Cu" "B.Mask" "B.Paste")
			(net "P12V_STBY")
		)
		(pad "2" smd rect
			(at 0 0.889 180)
			(size 0.508 0.508)
			(layers "B.Cu" "B.Mask" "B.Paste")
			(net "GND")
		)
		(zone
			(layer "B.Cu")
			(hatch none 0.5)
			(connect_pads
				(clearance 0)
			)
			(min_thickness 0.25)
			(keepout
				(tracks allowed)
				(vias not_allowed)
				(pads allowed)
				(copperpour not_allowed)
				(footprints allowed)
			)
			(placement
				(enabled no)
				(sheetname "")
			)
			(fill
				(thermal_gap 0.5)
				(thermal_bridge_width 0.5)
				(island_removal_mode 0)
			)
			(polygon
				(pts
					(xy 437.769 -52.1335) (xy 437.261 -52.1335) (xy 437.261 -51.7525) (xy 437.769 -51.7525)
				)
			)
		)
		(zone
			(layer "B.Cu")
			(hatch none 0.5)
			(connect_pads
				(clearance 0)
			)
			(min_thickness 0.25)
			(keepout
				(tracks not_allowed)
				(vias allowed)
				(pads allowed)
				(copperpour not_allowed)
				(footprints allowed)
			)
			(placement
				(enabled no)
				(sheetname "")
			)
			(fill
				(thermal_gap 0.5)
				(thermal_bridge_width 0.5)
				(island_removal_mode 0)
			)
			(polygon
				(pts
					(xy 437.769 -51.7525) (xy 437.261 -51.7525) (xy 437.261 -52.1335) (xy 437.769 -52.1335)
				)
			)
		)
	)
	(footprint ""
		(layer "B.Cu")
		(at 164.973 -84.709 90)
		(property "Reference" "C6P5"
			(at 0 0 90)
			(layer "B.SilkS")
			(hide yes)
			(effects
				(font
					(size 1.27 1.27)
				)
				(justify mirror)
			)
		)
		(property "Value" ""
			(at 0 0 90)
			(layer "B.Fab")
			(effects
				(font
					(size 1.27 1.27)
				)
				(justify mirror)
			)
		)
		(duplicate_pad_numbers_are_jumpers no)
		(fp_poly
			(pts
				(xy -0.3048 -0.1016) (xy -0.3048 0.9906) (xy 0.3048 0.9906) (xy 0.3048 -0.1016)
			)
			(stroke
				(width 0)
				(type default)
			)
			(fill no)
			(layer "B.CrtYd")
		)
		(fp_line
			(start 0.3048 -0.1016)
			(end 0.3048 0.9906)
			(stroke
				(width 0.1)
				(type default)
			)
			(layer "B.Fab")
		)
		(fp_line
			(start -0.3048 -0.1016)
			(end 0.3048 -0.1016)
			(stroke
				(width 0.1)
				(type default)
			)
			(layer "B.Fab")
		)
		(fp_line
			(start 0.3048 0.9906)
			(end -0.3048 0.9906)
			(stroke
				(width 0.1)
				(type default)
			)
			(layer "B.Fab")
		)
		(fp_line
			(start -0.3048 0.9906)
			(end -0.3048 -0.1016)
			(stroke
				(width 0.1)
				(type default)
			)
			(layer "B.Fab")
		)
		(pad "1" smd rect
			(at 0 0 270)
			(size 0.508 0.508)
			(layers "B.Cu" "B.Mask" "B.Paste")
			(net "P3V3_DB1200")
		)
		(pad "2" smd rect
			(at 0 0.889 270)
			(size 0.508 0.508)
			(layers "B.Cu" "B.Mask" "B.Paste")
			(net "GND")
		)
		(zone
			(layer "B.Cu")
			(hatch none 0.5)
			(connect_pads
				(clearance 0)
			)
			(min_thickness 0.25)
			(keepout
				(tracks allowed)
				(vias not_allowed)
				(pads allowed)
				(copperpour not_allowed)
				(footprints allowed)
			)
			(placement
				(enabled no)
				(sheetname "")
			)
			(fill
				(thermal_gap 0.5)
				(thermal_bridge_width 0.5)
				(island_removal_mode 0)
			)
			(polygon
				(pts
					(xy 165.227 -84.963) (xy 165.227 -84.455) (xy 165.608 -84.455) (xy 165.608 -84.963)
				)
			)
		)
		(zone
			(layer "B.Cu")
			(hatch none 0.5)
			(connect_pads
				(clearance 0)
			)
			(min_thickness 0.25)
			(keepout
				(tracks not_allowed)
				(vias allowed)
				(pads allowed)
				(copperpour not_allowed)
				(footprints allowed)
			)
			(placement
				(enabled no)
				(sheetname "")
			)
			(fill
				(thermal_gap 0.5)
				(thermal_bridge_width 0.5)
				(island_removal_mode 0)
			)
			(polygon
				(pts
					(xy 165.608 -84.963) (xy 165.608 -84.455) (xy 165.227 -84.455) (xy 165.227 -84.963)
				)
			)
		)
	)
	(footprint ""
		(layer "B.Cu")
		(at 448.55638 -34.7345 90)
		(property "Reference" "R25W48"
			(at 0 0 90)
			(layer "B.SilkS")
			(hide yes)
			(effects
				(font
					(size 1.27 1.27)
				)
				(justify mirror)
			)
		)
		(property "Value" "*"
			(at -0.064008 -4.108196 90)
			(unlocked yes)
			(layer "B.Fab")
			(hide yes)
			(effects
				(font
					(size 1.27 1.016)
					(thickness 0.1524)
				)
				(justify mirror)
			)
		)
		(property "Device Type" "120R2F-GP_RCL_GP-120R2F-GP,64.A"
			(at -0.064008 -5.632196 90)
			(unlocked yes)
			(layer "B.Fab")
			(hide yes)
			(effects
				(font
					(size 1.27 1.016)
					(thickness 0.1524)
				)
				(justify mirror)
			)
		)
		(duplicate_pad_numbers_are_jumpers no)
		(fp_line
			(start 0.508 -0.9398)
			(end 0.508 0.9398)
			(stroke
				(width 0.1524)
				(type default)
			)
			(layer "B.SilkS")
		)
		(fp_line
			(start -0.508 -0.9398)
			(end 0.508 -0.9398)
			(stroke
				(width 0.1524)
				(type default)
			)
			(layer "B.SilkS")
		)
		(fp_rect
			(start 0.508 0.9398)
			(end -0.508 -0.9398)
			(stroke
				(width 0)
				(type default)
			)
			(fill no)
			(layer "B.CrtYd")
		)
		(fp_rect
			(start 0.508 0.9398)
			(end -0.508 -0.9398)
			(stroke
				(width 0)
				(type default)
			)
			(fill no)
			(layer "B.Fab")
		)
		(pad "1" smd custom
			(at 0 -0.4445 270)
			(size 0.1397 0.1397)
			(layers "B.Cu" "B.Mask" "B.Paste")
			(net "BMC_M_A10")
			(options
				(clearance outline)
				(anchor circle)
			)
			(primitives
				(gr_poly
					(pts
						(arc
							(start -0.1778 0.2794)
							(mid -0.249642 0.249642)
							(end -0.2794 0.1778)
						)
						(arc
							(start -0.2794 -0.1778)
							(mid -0.249642 -0.249642)
							(end -0.1778 -0.2794)
						)
						(arc
							(start 0.1778 -0.2794)
							(mid 0.249642 -0.249642)
							(end 0.2794 -0.1778)
						)
						(arc
							(start 0.2794 0.1778)
							(mid 0.249642 0.249642)
							(end 0.1778 0.2794)
						)
					)
					(width 0)
					(fill yes)
				)
			)
		)
		(pad "2" smd custom
			(at 0 0.4445 270)
			(size 0.1397 0.1397)
			(layers "B.Cu" "B.Mask" "B.Paste")
			(net "P1V2_AUX_BMC")
			(options
				(clearance outline)
				(anchor circle)
			)
			(primitives
				(gr_poly
					(pts
						(arc
							(start -0.1778 0.2794)
							(mid -0.249642 0.249642)
							(end -0.2794 0.1778)
						)
						(arc
							(start -0.2794 -0.1778)
							(mid -0.249642 -0.249642)
							(end -0.1778 -0.2794)
						)
						(arc
							(start 0.1778 -0.2794)
							(mid 0.249642 -0.249642)
							(end 0.2794 -0.1778)
						)
						(arc
							(start 0.2794 0.1778)
							(mid 0.249642 0.249642)
							(end 0.1778 0.2794)
						)
					)
					(width 0)
					(fill yes)
				)
			)
		)
	)
	(footprint ""
		(layer "B.Cu")
		(at 280.354024 -77.366114)
		(property "Reference" "C4P6"
			(at 0 0 0)
			(layer "B.SilkS")
			(hide yes)
			(effects
				(font
					(size 1.27 1.27)
				)
				(justify mirror)
			)
		)
		(property "Value" ""
			(at 0 0 0)
			(layer "B.Fab")
			(effects
				(font
					(size 1.27 1.27)
				)
				(justify mirror)
			)
		)
		(duplicate_pad_numbers_are_jumpers no)
		(fp_poly
			(pts
				(xy 0.4953 -0.2032) (xy -0.4953 -0.2032) (xy -0.4953 1.6002) (xy 0.4953 1.6002)
			)
			(stroke
				(width 0)
				(type default)
			)
			(fill no)
			(layer "B.CrtYd")
		)
		(fp_line
			(start -0.4953 -0.2032)
			(end -0.4953 1.6002)
			(stroke
				(width 0.1)
				(type default)
			)
			(layer "B.Fab")
		)
		(fp_line
			(start -0.4953 1.6002)
			(end 0.4953 1.6002)
			(stroke
				(width 0.1)
				(type default)
			)
			(layer "B.Fab")
		)
		(fp_line
			(start 0.4953 -0.2032)
			(end -0.4953 -0.2032)
			(stroke
				(width 0.1)
				(type default)
			)
			(layer "B.Fab")
		)
		(fp_line
			(start 0.4953 1.6002)
			(end 0.4953 -0.2032)
			(stroke
				(width 0.1)
				(type default)
			)
			(layer "B.Fab")
		)
		(pad "1" smd rect
			(at 0 0 180)
			(size 0.762 0.889)
			(layers "B.Cu" "B.Mask" "B.Paste")
			(net "PVCCIO_CPU0")
		)
		(pad "2" smd rect
			(at 0 1.397 180)
			(size 0.762 0.889)
			(layers "B.Cu" "B.Mask" "B.Paste")
			(net "GND")
		)
		(zone
			(layer "B.Cu")
			(hatch none 0.5)
			(connect_pads
				(clearance 0)
			)
			(min_thickness 0.25)
			(keepout
				(tracks not_allowed)
				(vias allowed)
				(pads allowed)
				(copperpour not_allowed)
				(footprints allowed)
			)
			(placement
				(enabled no)
				(sheetname "")
			)
			(fill
				(thermal_gap 0.5)
				(thermal_bridge_width 0.5)
				(island_removal_mode 0)
			)
			(polygon
				(pts
					(xy 280.735024 -76.921614) (xy 279.973024 -76.921614) (xy 279.973024 -76.413614) (xy 280.735024 -76.413614)
				)
			)
		)
	)
	(footprint ""
		(layer "B.Cu")
		(at 429.7172 -23.4188)
		(property "Reference" "R1U18"
			(at 0 0 0)
			(layer "B.SilkS")
			(hide yes)
			(effects
				(font
					(size 1.27 1.27)
				)
				(justify mirror)
			)
		)
		(property "Value" ""
			(at 0 0 0)
			(layer "B.Fab")
			(effects
				(font
					(size 1.27 1.27)
				)
				(justify mirror)
			)
		)
		(duplicate_pad_numbers_are_jumpers no)
		(fp_poly
			(pts
				(xy 0.2794 -0.1016) (xy -0.2794 -0.1016) (xy -0.2794 0.9906) (xy 0.2794 0.9906)
			)
			(stroke
				(width 0)
				(type default)
			)
			(fill no)
			(layer "B.CrtYd")
		)
		(fp_line
			(start -0.2794 -0.1016)
			(end 0.2794 -0.1016)
			(stroke
				(width 0.1)
				(type default)
			)
			(layer "B.Fab")
		)
		(fp_line
			(start -0.2794 0.9906)
			(end -0.2794 -0.1016)
			(stroke
				(width 0.1)
				(type default)
			)
			(layer "B.Fab")
		)
		(fp_line
			(start 0.2794 -0.1016)
			(end 0.2794 0.9906)
			(stroke
				(width 0.1)
				(type default)
			)
			(layer "B.Fab")
		)
		(fp_line
			(start 0.2794 0.9906)
			(end -0.2794 0.9906)
			(stroke
				(width 0.1)
				(type default)
			)
			(layer "B.Fab")
		)
		(pad "1" smd rect
			(at 0 0 180)
			(size 0.508 0.508)
			(layers "B.Cu" "B.Mask" "B.Paste")
			(net "FM_BOARD_SKU_ID0")
		)
		(pad "2" smd rect
			(at 0 0.889 180)
			(size 0.508 0.508)
			(layers "B.Cu" "B.Mask" "B.Paste")
			(net "GND")
		)
		(zone
			(layer "B.Cu")
			(hatch none 0.5)
			(connect_pads
				(clearance 0)
			)
			(min_thickness 0.25)
			(keepout
				(tracks allowed)
				(vias not_allowed)
				(pads allowed)
				(copperpour not_allowed)
				(footprints allowed)
			)
			(placement
				(enabled no)
				(sheetname "")
			)
			(fill
				(thermal_gap 0.5)
				(thermal_bridge_width 0.5)
				(island_removal_mode 0)
			)
			(polygon
				(pts
					(xy 429.9712 -23.1648) (xy 429.4632 -23.1648) (xy 429.4632 -22.7838) (xy 429.9712 -22.7838)
				)
			)
		)
		(zone
			(layer "B.Cu")
			(hatch none 0.5)
			(connect_pads
				(clearance 0)
			)
			(min_thickness 0.25)
			(keepout
				(tracks not_allowed)
				(vias allowed)
				(pads allowed)
				(copperpour not_allowed)
				(footprints allowed)
			)
			(placement
				(enabled no)
				(sheetname "")
			)
			(fill
				(thermal_gap 0.5)
				(thermal_bridge_width 0.5)
				(island_removal_mode 0)
			)
			(polygon
				(pts
					(xy 429.9712 -22.7838) (xy 429.4632 -22.7838) (xy 429.4632 -23.1648) (xy 429.9712 -23.1648)
				)
			)
		)
	)
	(footprint ""
		(layer "B.Cu")
		(at 29.699458 -142.477236 90)
		(property "Reference" "J9L2"
			(at 2.403348 38.118542 0)
			(unlocked yes)
			(layer "B.SilkS")
			(effects
				(font
					(size 0.7874 0.5842)
					(thickness 0.1524)
				)
				(justify left mirror)
			)
		)
		(property "Value" ""
			(at 0 0 90)
			(layer "B.Fab")
			(effects
				(font
					(size 1.27 1.27)
				)
				(justify mirror)
			)
		)
		(duplicate_pad_numbers_are_jumpers no)
		(fp_line
			(start 0.94996 -7.675118)
			(end -5.5499 -7.675118)
			(stroke
				(width 0.1524)
				(type default)
			)
			(layer "B.SilkS")
		)
		(fp_line
			(start -5.5499 -7.675118)
			(end -5.5499 -1.480058)
			(stroke
				(width 0.1524)
				(type default)
			)
			(layer "B.SilkS")
		)
		(fp_line
			(start 0.94996 -1.480058)
			(end 0.94996 -7.675118)
			(stroke
				(width 0.1524)
				(type default)
			)
			(layer "B.SilkS")
		)
		(fp_line
			(start -5.5499 128.130046)
			(end -5.5499 134.325106)
			(stroke
				(width 0.1524)
				(type default)
			)
			(layer "B.SilkS")
		)
		(fp_line
			(start 0.94996 134.325106)
			(end 0.94996 128.130046)
			(stroke
				(width 0.1524)
				(type default)
			)
			(layer "B.SilkS")
		)
		(fp_line
			(start -5.5499 134.325106)
			(end 0.94996 134.325106)
			(stroke
				(width 0.1524)
				(type default)
			)
			(layer "B.SilkS")
		)
		(fp_poly
			(pts
				(xy 3.157474 -4.290822) (xy 3.157474 -3.274822) (xy 1.887474 -3.782822)
			)
			(stroke
				(width 0)
				(type default)
			)
			(fill yes)
			(layer "B.SilkS")
		)
		(fp_poly
			(pts
				(xy 0.94996 -7.675118) (xy 0.94996 134.325106) (xy -5.5499 134.325106) (xy -5.5499 -7.675118)
			)
			(stroke
				(width 0)
				(type default)
			)
			(fill no)
			(layer "B.CrtYd")
		)
		(fp_line
			(start 0.94996 -7.675118)
			(end -5.5499 -7.675118)
			(stroke
				(width 0.1)
				(type default)
			)
			(layer "B.Fab")
		)
		(fp_line
			(start -5.5499 -7.675118)
			(end -5.5499 134.325106)
			(stroke
				(width 0.1)
				(type default)
			)
			(layer "B.Fab")
		)
		(fp_line
			(start 0.94996 134.325106)
			(end 0.94996 -7.675118)
			(stroke
				(width 0.1)
				(type default)
			)
			(layer "B.Fab")
		)
		(fp_line
			(start -5.5499 134.325106)
			(end 0.94996 134.325106)
			(stroke
				(width 0.1)
				(type default)
			)
			(layer "B.Fab")
		)
		(fp_poly
			(pts
				(xy 2.984246 -0.461264) (xy 2.984246 0.554736) (xy 1.714246 0.046736)
			)
			(stroke
				(width 0)
				(type default)
			)
			(fill yes)
			(layer "B.Fab")
		)
		(fp_text user "145"
			(at -6.232652 2.685542 0)
			(unlocked yes)
			(layer "B.SilkS")
			(effects
				(font
					(size 0.7874 0.5842)
					(thickness 0.1524)
				)
				(justify left mirror)
			)
		)
		(fp_text user "77"
			(at 1.133348 66.439542 0)
			(unlocked yes)
			(layer "B.SilkS")
			(effects
				(font
					(size 0.7874 0.5842)
					(thickness 0.1524)
				)
				(justify left mirror)
			)
		)
		(fp_text user "221"
			(at -5.724652 67.201542 0)
			(unlocked yes)
			(layer "B.SilkS")
			(effects
				(font
					(size 0.7874 0.5842)
					(thickness 0.1524)
				)
				(justify left mirror)
			)
		)
		(fp_text user "78"
			(at 1.530858 71.210424 0)
			(unlocked yes)
			(layer "B.SilkS")
			(effects
				(font
					(size 0.7874 0.5842)
					(thickness 0.1524)
				)
				(justify left mirror)
			)
		)
		(fp_text user "222"
			(at -6.105652 72.027542 0)
			(unlocked yes)
			(layer "B.SilkS")
			(effects
				(font
					(size 0.7874 0.5842)
					(thickness 0.1524)
				)
				(justify left mirror)
			)
		)
		(fp_text user "144"
			(at 1.641348 129.939542 0)
			(unlocked yes)
			(layer "B.SilkS")
			(effects
				(font
					(size 0.7874 0.5842)
					(thickness 0.1524)
				)
				(justify left mirror)
			)
		)
		(fp_text user "288"
			(at -10.423652 136.797542 0)
			(unlocked yes)
			(layer "B.SilkS")
			(effects
				(font
					(size 0.7874 0.5842)
					(thickness 0.1524)
				)
				(justify left mirror)
			)
		)
		(fp_text user "145"
			(at -3.411982 -0.843788 90)
			(unlocked yes)
			(layer "B.Fab")
			(effects
				(font
					(size 0.7874 0.5842)
					(thickness 0.1524)
				)
				(justify left mirror)
			)
		)
		(fp_text user "77"
			(at 0.398018 65.831212 90)
			(unlocked yes)
			(layer "B.Fab")
			(effects
				(font
					(size 0.7874 0.5842)
					(thickness 0.1524)
				)
				(justify left mirror)
			)
		)
		(fp_text user "221"
			(at -3.411982 65.831212 90)
			(unlocked yes)
			(layer "B.Fab")
			(effects
				(font
					(size 0.7874 0.5842)
					(thickness 0.1524)
				)
				(justify left mirror)
			)
		)
		(fp_text user "78"
			(at 0.398018 69.641212 90)
			(unlocked yes)
			(layer "B.Fab")
			(effects
				(font
					(size 0.7874 0.5842)
					(thickness 0.1524)
				)
				(justify left mirror)
			)
		)
		(fp_text user "222"
			(at -3.411982 69.641212 90)
			(unlocked yes)
			(layer "B.Fab")
			(effects
				(font
					(size 0.7874 0.5842)
					(thickness 0.1524)
				)
				(justify left mirror)
			)
		)
		(fp_text user "144"
			(at 0.398018 128.061212 90)
			(unlocked yes)
			(layer "B.Fab")
			(effects
				(font
					(size 0.7874 0.5842)
					(thickness 0.1524)
				)
				(justify left mirror)
			)
		)
		(fp_text user "288"
			(at -2.776982 128.061212 90)
			(unlocked yes)
			(layer "B.Fab")
			(effects
				(font
					(size 0.7874 0.5842)
					(thickness 0.1524)
				)
				(justify left mirror)
			)
		)
		(pad "" thru_hole circle
			(at -2.29997 -5.649976 270)
			(size 2.8194 2.8194)
			(drill 2.4384)
			(layers "*.Cu" "*.Mask")
			(remove_unused_layers no)
			(clearance 0.127)
			(thermal_gap 0.127)
		)
		(pad "" thru_hole oval
			(at -2.29997 68.90004 270)
			(size 2.8194 1.5748)
			(drill oval 2.4384 1.1938)
			(layers "*.Cu" "*.Mask")
			(remove_unused_layers no)
			(clearance 0.127)
			(thermal_gap 0.127)
		)
		(pad "" thru_hole circle
			(at -2.29997 132.299964 270)
			(size 2.8194 2.8194)
			(drill 2.4384)
			(layers "*.Cu" "*.Mask")
			(remove_unused_layers no)
			(clearance 0.127)
			(thermal_gap 0.127)
		)
		(pad "1" smd rect
			(at 0 0 270)
			(size 1.8034 0.508)
			(layers "B.Cu" "B.Mask" "B.Paste")
			(net "P12V_NVDIMM_KLM")
		)
		(pad "2" smd rect
			(at 0 0.849884 270)
			(size 1.8034 0.508)
			(layers "B.Cu" "B.Mask" "B.Paste")
			(net "GND")
		)
		(pad "3" smd rect
			(at 0 1.700022 270)
			(size 1.8034 0.508)
			(layers "B.Cu" "B.Mask" "B.Paste")
			(net "M_L_DQ<4>")
		)
		(pad "4" smd rect
			(at 0 2.549906 270)
			(size 1.8034 0.508)
			(layers "B.Cu" "B.Mask" "B.Paste")
			(net "GND")
		)
		(pad "5" smd rect
			(at 0 3.400044 270)
			(size 1.8034 0.508)
			(layers "B.Cu" "B.Mask" "B.Paste")
			(net "M_L_DQ<0>")
		)
		(pad "6" smd rect
			(at 0 4.249928 270)
			(size 1.8034 0.508)
			(layers "B.Cu" "B.Mask" "B.Paste")
			(net "GND")
		)
		(pad "7" smd rect
			(at 0 5.100066 270)
			(size 1.8034 0.508)
			(layers "B.Cu" "B.Mask" "B.Paste")
			(net "M_L_DQS_DP<9>")
		)
		(pad "8" smd rect
			(at 0 5.94995 270)
			(size 1.8034 0.508)
			(layers "B.Cu" "B.Mask" "B.Paste")
			(net "M_L_DQS_DN<9>")
		)
		(pad "9" smd rect
			(at 0 6.800088 270)
			(size 1.8034 0.508)
			(layers "B.Cu" "B.Mask" "B.Paste")
			(net "GND")
		)
		(pad "10" smd rect
			(at 0 7.649972 270)
			(size 1.8034 0.508)
			(layers "B.Cu" "B.Mask" "B.Paste")
			(net "M_L_DQ<6>")
		)
		(pad "11" smd rect
			(at 0 8.50011 270)
			(size 1.8034 0.508)
			(layers "B.Cu" "B.Mask" "B.Paste")
			(net "GND")
		)
		(pad "12" smd rect
			(at 0 9.349994 270)
			(size 1.8034 0.508)
			(layers "B.Cu" "B.Mask" "B.Paste")
			(net "M_L_DQ<2>")
		)
		(pad "13" smd rect
			(at 0 10.199878 270)
			(size 1.8034 0.508)
			(layers "B.Cu" "B.Mask" "B.Paste")
			(net "GND")
		)
		(pad "14" smd rect
			(at 0 11.050016 270)
			(size 1.8034 0.508)
			(layers "B.Cu" "B.Mask" "B.Paste")
			(net "M_L_DQ<12>")
		)
		(pad "15" smd rect
			(at 0 11.8999 270)
			(size 1.8034 0.508)
			(layers "B.Cu" "B.Mask" "B.Paste")
			(net "GND")
		)
		(pad "16" smd rect
			(at 0 12.750038 270)
			(size 1.8034 0.508)
			(layers "B.Cu" "B.Mask" "B.Paste")
			(net "M_L_DQ<8>")
		)
		(pad "17" smd rect
			(at 0 13.599922 270)
			(size 1.8034 0.508)
			(layers "B.Cu" "B.Mask" "B.Paste")
			(net "GND")
		)
		(pad "18" smd rect
			(at 0 14.45006 270)
			(size 1.8034 0.508)
			(layers "B.Cu" "B.Mask" "B.Paste")
			(net "M_L_DQS_DP<10>")
		)
		(pad "19" smd rect
			(at 0 15.299944 270)
			(size 1.8034 0.508)
			(layers "B.Cu" "B.Mask" "B.Paste")
			(net "M_L_DQS_DN<10>")
		)
		(pad "20" smd rect
			(at 0 16.150082 270)
			(size 1.8034 0.508)
			(layers "B.Cu" "B.Mask" "B.Paste")
			(net "GND")
		)
		(pad "21" smd rect
			(at 0 16.999966 270)
			(size 1.8034 0.508)
			(layers "B.Cu" "B.Mask" "B.Paste")
			(net "M_L_DQ<14>")
		)
		(pad "22" smd rect
			(at 0 17.850104 270)
			(size 1.8034 0.508)
			(layers "B.Cu" "B.Mask" "B.Paste")
			(net "GND")
		)
		(pad "23" smd rect
			(at 0 18.699988 270)
			(size 1.8034 0.508)
			(layers "B.Cu" "B.Mask" "B.Paste")
			(net "M_L_DQ<10>")
		)
		(pad "24" smd rect
			(at 0 19.550126 270)
			(size 1.8034 0.508)
			(layers "B.Cu" "B.Mask" "B.Paste")
			(net "GND")
		)
		(pad "25" smd rect
			(at 0 20.40001 270)
			(size 1.8034 0.508)
			(layers "B.Cu" "B.Mask" "B.Paste")
			(net "M_L_DQ<20>")
		)
		(pad "26" smd rect
			(at 0 21.249894 270)
			(size 1.8034 0.508)
			(layers "B.Cu" "B.Mask" "B.Paste")
			(net "GND")
		)
		(pad "27" smd rect
			(at 0 22.100032 270)
			(size 1.8034 0.508)
			(layers "B.Cu" "B.Mask" "B.Paste")
			(net "M_L_DQ<16>")
		)
		(pad "28" smd rect
			(at 0 22.949916 270)
			(size 1.8034 0.508)
			(layers "B.Cu" "B.Mask" "B.Paste")
			(net "GND")
		)
		(pad "29" smd rect
			(at 0 23.800054 270)
			(size 1.8034 0.508)
			(layers "B.Cu" "B.Mask" "B.Paste")
			(net "M_L_DQS_DP<11>")
		)
		(pad "30" smd rect
			(at 0 24.649938 270)
			(size 1.8034 0.508)
			(layers "B.Cu" "B.Mask" "B.Paste")
			(net "M_L_DQS_DN<11>")
		)
		(pad "31" smd rect
			(at 0 25.500076 270)
			(size 1.8034 0.508)
			(layers "B.Cu" "B.Mask" "B.Paste")
			(net "GND")
		)
		(pad "32" smd rect
			(at 0 26.34996 270)
			(size 1.8034 0.508)
			(layers "B.Cu" "B.Mask" "B.Paste")
			(net "M_L_DQ<22>")
		)
		(pad "33" smd rect
			(at 0 27.200098 270)
			(size 1.8034 0.508)
			(layers "B.Cu" "B.Mask" "B.Paste")
			(net "GND")
		)
		(pad "34" smd rect
			(at 0 28.049982 270)
			(size 1.8034 0.508)
			(layers "B.Cu" "B.Mask" "B.Paste")
			(net "M_L_DQ<18>")
		)
		(pad "35" smd rect
			(at 0 28.90012 270)
			(size 1.8034 0.508)
			(layers "B.Cu" "B.Mask" "B.Paste")
			(net "GND")
		)
		(pad "36" smd rect
			(at 0 29.750004 270)
			(size 1.8034 0.508)
			(layers "B.Cu" "B.Mask" "B.Paste")
			(net "M_L_DQ<28>")
		)
		(pad "37" smd rect
			(at 0 30.599888 270)
			(size 1.8034 0.508)
			(layers "B.Cu" "B.Mask" "B.Paste")
			(net "GND")
		)
		(pad "38" smd rect
			(at 0 31.450026 270)
			(size 1.8034 0.508)
			(layers "B.Cu" "B.Mask" "B.Paste")
			(net "M_L_DQ<24>")
		)
		(pad "39" smd rect
			(at 0 32.29991 270)
			(size 1.8034 0.508)
			(layers "B.Cu" "B.Mask" "B.Paste")
			(net "GND")
		)
		(pad "40" smd rect
			(at 0 33.150048 270)
			(size 1.8034 0.508)
			(layers "B.Cu" "B.Mask" "B.Paste")
			(net "M_L_DQS_DP<12>")
		)
		(pad "41" smd rect
			(at 0 33.999932 270)
			(size 1.8034 0.508)
			(layers "B.Cu" "B.Mask" "B.Paste")
			(net "M_L_DQS_DN<12>")
		)
		(pad "42" smd rect
			(at 0 34.85007 270)
			(size 1.8034 0.508)
			(layers "B.Cu" "B.Mask" "B.Paste")
			(net "GND")
		)
		(pad "43" smd rect
			(at 0 35.699954 270)
			(size 1.8034 0.508)
			(layers "B.Cu" "B.Mask" "B.Paste")
			(net "M_L_DQ<30>")
		)
		(pad "44" smd rect
			(at 0 36.550092 270)
			(size 1.8034 0.508)
			(layers "B.Cu" "B.Mask" "B.Paste")
			(net "GND")
		)
		(pad "45" smd rect
			(at 0 37.399976 270)
			(size 1.8034 0.508)
			(layers "B.Cu" "B.Mask" "B.Paste")
			(net "M_L_DQ<26>")
		)
		(pad "46" smd rect
			(at 0 38.250114 270)
			(size 1.8034 0.508)
			(layers "B.Cu" "B.Mask" "B.Paste")
			(net "GND")
		)
		(pad "47" smd rect
			(at 0 39.099998 270)
			(size 1.8034 0.508)
			(layers "B.Cu" "B.Mask" "B.Paste")
			(net "M_L_ECC<4>")
		)
		(pad "48" smd rect
			(at 0 39.949882 270)
			(size 1.8034 0.508)
			(layers "B.Cu" "B.Mask" "B.Paste")
			(net "GND")
		)
		(pad "49" smd rect
			(at 0 40.80002 270)
			(size 1.8034 0.508)
			(layers "B.Cu" "B.Mask" "B.Paste")
			(net "M_L_ECC<0>")
		)
		(pad "50" smd rect
			(at 0 41.649904 270)
			(size 1.8034 0.508)
			(layers "B.Cu" "B.Mask" "B.Paste")
			(net "GND")
		)
		(pad "51" smd rect
			(at 0 42.500042 270)
			(size 1.8034 0.508)
			(layers "B.Cu" "B.Mask" "B.Paste")
			(net "M_L_DQS_DP<17>")
		)
		(pad "52" smd rect
			(at 0 43.349926 270)
			(size 1.8034 0.508)
			(layers "B.Cu" "B.Mask" "B.Paste")
			(net "M_L_DQS_DN<17>")
		)
		(pad "53" smd rect
			(at 0 44.200064 270)
			(size 1.8034 0.508)
			(layers "B.Cu" "B.Mask" "B.Paste")
			(net "GND")
		)
		(pad "54" smd rect
			(at 0 45.049948 270)
			(size 1.8034 0.508)
			(layers "B.Cu" "B.Mask" "B.Paste")
			(net "M_L_ECC<6>")
		)
		(pad "55" smd rect
			(at 0 45.900086 270)
			(size 1.8034 0.508)
			(layers "B.Cu" "B.Mask" "B.Paste")
			(net "GND")
		)
		(pad "56" smd rect
			(at 0 46.74997 270)
			(size 1.8034 0.508)
			(layers "B.Cu" "B.Mask" "B.Paste")
			(net "M_L_ECC<2>")
		)
		(pad "57" smd rect
			(at 0 47.600108 270)
			(size 1.8034 0.508)
			(layers "B.Cu" "B.Mask" "B.Paste")
			(net "GND")
		)
		(pad "58" smd rect
			(at 0 48.449992 270)
			(size 1.8034 0.508)
			(layers "B.Cu" "B.Mask" "B.Paste")
			(net "M_KLM_RST_N")
		)
		(pad "59" smd rect
			(at 0 49.299876 270)
			(size 1.8034 0.508)
			(layers "B.Cu" "B.Mask" "B.Paste")
			(net "PVDDQ_KLM")
		)
		(pad "60" smd rect
			(at 0 50.150014 270)
			(size 1.8034 0.508)
			(layers "B.Cu" "B.Mask" "B.Paste")
			(net "M_L_CKE<2>")
		)
		(pad "61" smd rect
			(at 0 50.999898 270)
			(size 1.8034 0.508)
			(layers "B.Cu" "B.Mask" "B.Paste")
			(net "PVDDQ_KLM")
		)
		(pad "62" smd rect
			(at 0 51.850036 270)
			(size 1.8034 0.508)
			(layers "B.Cu" "B.Mask" "B.Paste")
			(net "M_L_ACT_N")
		)
		(pad "63" smd rect
			(at 0 52.69992 270)
			(size 1.8034 0.508)
			(layers "B.Cu" "B.Mask" "B.Paste")
			(net "M_L_BG<0>")
		)
		(pad "64" smd rect
			(at 0 53.550058 270)
			(size 1.8034 0.508)
			(layers "B.Cu" "B.Mask" "B.Paste")
			(net "PVDDQ_KLM")
		)
		(pad "65" smd rect
			(at 0 54.399942 270)
			(size 1.8034 0.508)
			(layers "B.Cu" "B.Mask" "B.Paste")
			(net "M_L_MA<12>")
		)
		(pad "66" smd rect
			(at 0 55.25008 270)
			(size 1.8034 0.508)
			(layers "B.Cu" "B.Mask" "B.Paste")
			(net "M_L_MA<9>")
		)
		(pad "67" smd rect
			(at 0 56.099964 270)
			(size 1.8034 0.508)
			(layers "B.Cu" "B.Mask" "B.Paste")
			(net "PVDDQ_KLM")
		)
		(pad "68" smd rect
			(at 0 56.950102 270)
			(size 1.8034 0.508)
			(layers "B.Cu" "B.Mask" "B.Paste")
			(net "M_L_MA<8>")
		)
		(pad "69" smd rect
			(at 0 57.799986 270)
			(size 1.8034 0.508)
			(layers "B.Cu" "B.Mask" "B.Paste")
			(net "M_L_MA<6>")
		)
		(pad "70" smd rect
			(at 0 58.650124 270)
			(size 1.8034 0.508)
			(layers "B.Cu" "B.Mask" "B.Paste")
			(net "PVDDQ_KLM")
		)
		(pad "71" smd rect
			(at 0 59.500008 270)
			(size 1.8034 0.508)
			(layers "B.Cu" "B.Mask" "B.Paste")
			(net "M_L_MA<3>")
		)
		(pad "72" smd rect
			(at 0 60.349892 270)
			(size 1.8034 0.508)
			(layers "B.Cu" "B.Mask" "B.Paste")
			(net "M_L_MA<1>")
		)
		(pad "73" smd rect
			(at 0 61.20003 270)
			(size 1.8034 0.508)
			(layers "B.Cu" "B.Mask" "B.Paste")
			(net "PVDDQ_KLM")
		)
		(pad "74" smd rect
			(at 0 62.049914 270)
			(size 1.8034 0.508)
			(layers "B.Cu" "B.Mask" "B.Paste")
			(net "M_L_CLK_DP<2>")
		)
		(pad "75" smd rect
			(at 0 62.900052 270)
			(size 1.8034 0.508)
			(layers "B.Cu" "B.Mask" "B.Paste")
			(net "M_L_CLK_DN<2>")
		)
		(pad "76" smd rect
			(at 0 63.749936 270)
			(size 1.8034 0.508)
			(layers "B.Cu" "B.Mask" "B.Paste")
			(net "PVDDQ_KLM")
		)
		(pad "77" smd rect
			(at 0 64.600074 270)
			(size 1.8034 0.508)
			(layers "B.Cu" "B.Mask" "B.Paste")
			(net "PVTT_KLM")
		)
		(pad "78" smd rect
			(at 0 70.550024 270)
			(size 1.8034 0.508)
			(layers "B.Cu" "B.Mask" "B.Paste")
			(net "FM_DIMM_EVENT_COD_N")
		)
		(pad "79" smd rect
			(at 0 71.399908 270)
			(size 1.8034 0.508)
			(layers "B.Cu" "B.Mask" "B.Paste")
			(net "M_L_MA<0>")
		)
		(pad "80" smd rect
			(at 0 72.250046 270)
			(size 1.8034 0.508)
			(layers "B.Cu" "B.Mask" "B.Paste")
			(net "PVDDQ_KLM")
		)
		(pad "81" smd rect
			(at 0 73.09993 270)
			(size 1.8034 0.508)
			(layers "B.Cu" "B.Mask" "B.Paste")
			(net "M_L_BA<0>")
		)
		(pad "82" smd rect
			(at 0 73.950068 270)
			(size 1.8034 0.508)
			(layers "B.Cu" "B.Mask" "B.Paste")
			(net "M_L_MA<16>")
		)
		(pad "83" smd rect
			(at 0 74.799952 270)
			(size 1.8034 0.508)
			(layers "B.Cu" "B.Mask" "B.Paste")
			(net "PVDDQ_KLM")
		)
		(pad "84" smd rect
			(at 0 75.65009 270)
			(size 1.8034 0.508)
			(layers "B.Cu" "B.Mask" "B.Paste")
			(net "M_L_CS_N<4>")
		)
		(pad "85" smd rect
			(at 0 76.499974 270)
			(size 1.8034 0.508)
			(layers "B.Cu" "B.Mask" "B.Paste")
			(net "PVDDQ_KLM")
		)
		(pad "86" smd rect
			(at 0 77.350112 270)
			(size 1.8034 0.508)
			(layers "B.Cu" "B.Mask" "B.Paste")
			(net "M_L_MA<15>")
		)
		(pad "87" smd rect
			(at 0 78.199996 270)
			(size 1.8034 0.508)
			(layers "B.Cu" "B.Mask" "B.Paste")
			(net "M_L_ODT<2>")
		)
		(pad "88" smd rect
			(at 0 79.04988 270)
			(size 1.8034 0.508)
			(layers "B.Cu" "B.Mask" "B.Paste")
			(net "PVDDQ_KLM")
		)
		(pad "89" smd rect
			(at 0 79.900018 270)
			(size 1.8034 0.508)
			(layers "B.Cu" "B.Mask" "B.Paste")
			(net "M_L_CS_N<5>")
		)
		(pad "90" smd rect
			(at 0 80.749902 270)
			(size 1.8034 0.508)
			(layers "B.Cu" "B.Mask" "B.Paste")
			(net "PVDDQ_KLM")
		)
		(pad "91" smd rect
			(at 0 81.60004 270)
			(size 1.8034 0.508)
			(layers "B.Cu" "B.Mask" "B.Paste")
			(net "M_L_ODT<3>")
		)
		(pad "92" smd rect
			(at 0 82.449924 270)
			(size 1.8034 0.508)
			(layers "B.Cu" "B.Mask" "B.Paste")
			(net "PVDDQ_KLM")
		)
		(pad "93" smd rect
			(at 0 83.300062 270)
			(size 1.8034 0.508)
			(layers "B.Cu" "B.Mask" "B.Paste")
			(net "M_L_CS_N<6>")
		)
		(pad "94" smd rect
			(at 0 84.149946 270)
			(size 1.8034 0.508)
			(layers "B.Cu" "B.Mask" "B.Paste")
			(net "GND")
		)
		(pad "95" smd rect
			(at 0 85.000084 270)
			(size 1.8034 0.508)
			(layers "B.Cu" "B.Mask" "B.Paste")
			(net "M_L_DQ<36>")
		)
		(pad "96" smd rect
			(at 0 85.849968 270)
			(size 1.8034 0.508)
			(layers "B.Cu" "B.Mask" "B.Paste")
			(net "GND")
		)
		(pad "97" smd rect
			(at 0 86.700106 270)
			(size 1.8034 0.508)
			(layers "B.Cu" "B.Mask" "B.Paste")
			(net "M_L_DQ<32>")
		)
		(pad "98" smd rect
			(at 0 87.54999 270)
			(size 1.8034 0.508)
			(layers "B.Cu" "B.Mask" "B.Paste")
			(net "GND")
		)
		(pad "99" smd rect
			(at 0 88.399874 270)
			(size 1.8034 0.508)
			(layers "B.Cu" "B.Mask" "B.Paste")
			(net "M_L_DQS_DP<13>")
		)
		(pad "100" smd rect
			(at 0 89.250012 270)
			(size 1.8034 0.508)
			(layers "B.Cu" "B.Mask" "B.Paste")
			(net "M_L_DQS_DN<13>")
		)
		(pad "101" smd rect
			(at 0 90.099896 270)
			(size 1.8034 0.508)
			(layers "B.Cu" "B.Mask" "B.Paste")
			(net "GND")
		)
		(pad "102" smd rect
			(at 0 90.950034 270)
			(size 1.8034 0.508)
			(layers "B.Cu" "B.Mask" "B.Paste")
			(net "M_L_DQ<38>")
		)
		(pad "103" smd rect
			(at 0 91.799918 270)
			(size 1.8034 0.508)
			(layers "B.Cu" "B.Mask" "B.Paste")
			(net "GND")
		)
		(pad "104" smd rect
			(at 0 92.650056 270)
			(size 1.8034 0.508)
			(layers "B.Cu" "B.Mask" "B.Paste")
			(net "M_L_DQ<34>")
		)
		(pad "105" smd rect
			(at 0 93.49994 270)
			(size 1.8034 0.508)
			(layers "B.Cu" "B.Mask" "B.Paste")
			(net "GND")
		)
		(pad "106" smd rect
			(at 0 94.350078 270)
			(size 1.8034 0.508)
			(layers "B.Cu" "B.Mask" "B.Paste")
			(net "M_L_DQ<44>")
		)
		(pad "107" smd rect
			(at 0 95.199962 270)
			(size 1.8034 0.508)
			(layers "B.Cu" "B.Mask" "B.Paste")
			(net "GND")
		)
		(pad "108" smd rect
			(at 0 96.0501 270)
			(size 1.8034 0.508)
			(layers "B.Cu" "B.Mask" "B.Paste")
			(net "M_L_DQ<40>")
		)
		(pad "109" smd rect
			(at 0 96.899984 270)
			(size 1.8034 0.508)
			(layers "B.Cu" "B.Mask" "B.Paste")
			(net "GND")
		)
		(pad "110" smd rect
			(at 0 97.750122 270)
			(size 1.8034 0.508)
			(layers "B.Cu" "B.Mask" "B.Paste")
			(net "M_L_DQS_DP<14>")
		)
		(pad "111" smd rect
			(at 0 98.600006 270)
			(size 1.8034 0.508)
			(layers "B.Cu" "B.Mask" "B.Paste")
			(net "M_L_DQS_DN<14>")
		)
		(pad "112" smd rect
			(at 0 99.44989 270)
			(size 1.8034 0.508)
			(layers "B.Cu" "B.Mask" "B.Paste")
			(net "GND")
		)
		(pad "113" smd rect
			(at 0 100.300028 270)
			(size 1.8034 0.508)
			(layers "B.Cu" "B.Mask" "B.Paste")
			(net "M_L_DQ<46>")
		)
		(pad "114" smd rect
			(at 0 101.149912 270)
			(size 1.8034 0.508)
			(layers "B.Cu" "B.Mask" "B.Paste")
			(net "GND")
		)
		(pad "115" smd rect
			(at 0 102.00005 270)
			(size 1.8034 0.508)
			(layers "B.Cu" "B.Mask" "B.Paste")
			(net "M_L_DQ<42>")
		)
		(pad "116" smd rect
			(at 0 102.849934 270)
			(size 1.8034 0.508)
			(layers "B.Cu" "B.Mask" "B.Paste")
			(net "GND")
		)
		(pad "117" smd rect
			(at 0 103.700072 270)
			(size 1.8034 0.508)
			(layers "B.Cu" "B.Mask" "B.Paste")
			(net "M_L_DQ<52>")
		)
		(pad "118" smd rect
			(at 0 104.549956 270)
			(size 1.8034 0.508)
			(layers "B.Cu" "B.Mask" "B.Paste")
			(net "GND")
		)
		(pad "119" smd rect
			(at 0 105.400094 270)
			(size 1.8034 0.508)
			(layers "B.Cu" "B.Mask" "B.Paste")
			(net "M_L_DQ<48>")
		)
		(pad "120" smd rect
			(at 0 106.249978 270)
			(size 1.8034 0.508)
			(layers "B.Cu" "B.Mask" "B.Paste")
			(net "GND")
		)
		(pad "121" smd rect
			(at 0 107.100116 270)
			(size 1.8034 0.508)
			(layers "B.Cu" "B.Mask" "B.Paste")
			(net "M_L_DQS_DP<15>")
		)
		(pad "122" smd rect
			(at 0 107.95 270)
			(size 1.8034 0.508)
			(layers "B.Cu" "B.Mask" "B.Paste")
			(net "M_L_DQS_DN<15>")
		)
		(pad "123" smd rect
			(at 0 108.799884 270)
			(size 1.8034 0.508)
			(layers "B.Cu" "B.Mask" "B.Paste")
			(net "GND")
		)
		(pad "124" smd rect
			(at 0 109.650022 270)
			(size 1.8034 0.508)
			(layers "B.Cu" "B.Mask" "B.Paste")
			(net "M_L_DQ<54>")
		)
		(pad "125" smd rect
			(at 0 110.499906 270)
			(size 1.8034 0.508)
			(layers "B.Cu" "B.Mask" "B.Paste")
			(net "GND")
		)
		(pad "126" smd rect
			(at 0 111.350044 270)
			(size 1.8034 0.508)
			(layers "B.Cu" "B.Mask" "B.Paste")
			(net "M_L_DQ<50>")
		)
		(pad "127" smd rect
			(at 0 112.199928 270)
			(size 1.8034 0.508)
			(layers "B.Cu" "B.Mask" "B.Paste")
			(net "GND")
		)
		(pad "128" smd rect
			(at 0 113.050066 270)
			(size 1.8034 0.508)
			(layers "B.Cu" "B.Mask" "B.Paste")
			(net "M_L_DQ<60>")
		)
		(pad "129" smd rect
			(at 0 113.89995 270)
			(size 1.8034 0.508)
			(layers "B.Cu" "B.Mask" "B.Paste")
			(net "GND")
		)
		(pad "130" smd rect
			(at 0 114.750088 270)
			(size 1.8034 0.508)
			(layers "B.Cu" "B.Mask" "B.Paste")
			(net "M_L_DQ<56>")
		)
		(pad "131" smd rect
			(at 0 115.599972 270)
			(size 1.8034 0.508)
			(layers "B.Cu" "B.Mask" "B.Paste")
			(net "GND")
		)
		(pad "132" smd rect
			(at 0 116.45011 270)
			(size 1.8034 0.508)
			(layers "B.Cu" "B.Mask" "B.Paste")
			(net "M_L_DQS_DP<16>")
		)
		(pad "133" smd rect
			(at 0 117.299994 270)
			(size 1.8034 0.508)
			(layers "B.Cu" "B.Mask" "B.Paste")
			(net "M_L_DQS_DN<16>")
		)
		(pad "134" smd rect
			(at 0 118.149878 270)
			(size 1.8034 0.508)
			(layers "B.Cu" "B.Mask" "B.Paste")
			(net "GND")
		)
		(pad "135" smd rect
			(at 0 119.000016 270)
			(size 1.8034 0.508)
			(layers "B.Cu" "B.Mask" "B.Paste")
			(net "M_L_DQ<62>")
		)
		(pad "136" smd rect
			(at 0 119.8499 270)
			(size 1.8034 0.508)
			(layers "B.Cu" "B.Mask" "B.Paste")
			(net "GND")
		)
		(pad "137" smd rect
			(at 0 120.700038 270)
			(size 1.8034 0.508)
			(layers "B.Cu" "B.Mask" "B.Paste")
			(net "M_L_DQ<58>")
		)
		(pad "138" smd rect
			(at 0 121.549922 270)
			(size 1.8034 0.508)
			(layers "B.Cu" "B.Mask" "B.Paste")
			(net "GND")
		)
		(pad "139" smd rect
			(at 0 122.40006 270)
			(size 1.8034 0.508)
			(layers "B.Cu" "B.Mask" "B.Paste")
			(net "PVPP_KLM")
		)
		(pad "140" smd rect
			(at 0 123.249944 270)
			(size 1.8034 0.508)
			(layers "B.Cu" "B.Mask" "B.Paste")
			(net "PVPP_KLM")
		)
		(pad "141" smd rect
			(at 0 124.100082 270)
			(size 1.8034 0.508)
			(layers "B.Cu" "B.Mask" "B.Paste")
			(net "SMB_DDR_KLM_VPP_SCL")
		)
		(pad "142" smd rect
			(at 0 124.949966 270)
			(size 1.8034 0.508)
			(layers "B.Cu" "B.Mask" "B.Paste")
			(net "PVPP_KLM")
		)
		(pad "143" smd rect
			(at 0 125.800104 270)
			(size 1.8034 0.508)
			(layers "B.Cu" "B.Mask" "B.Paste")
			(net "PVPP_KLM")
		)
		(pad "144" smd rect
			(at 0 126.649988 270)
			(size 1.8034 0.508)
			(layers "B.Cu" "B.Mask" "B.Paste")
			(net "TP_CH_L_DIMM0_RFU_2")
		)
		(pad "145" smd rect
			(at -4.59994 0 270)
			(size 1.8034 0.508)
			(layers "B.Cu" "B.Mask" "B.Paste")
			(net "P12V_NVDIMM_KLM")
		)
		(pad "146" smd rect
			(at -4.59994 0.849884 270)
			(size 1.8034 0.508)
			(layers "B.Cu" "B.Mask" "B.Paste")
			(net "M_L_VREF")
		)
		(pad "147" smd rect
			(at -4.59994 1.700022 270)
			(size 1.8034 0.508)
			(layers "B.Cu" "B.Mask" "B.Paste")
			(net "GND")
		)
		(pad "148" smd rect
			(at -4.59994 2.549906 270)
			(size 1.8034 0.508)
			(layers "B.Cu" "B.Mask" "B.Paste")
			(net "M_L_DQ<5>")
		)
		(pad "149" smd rect
			(at -4.59994 3.400044 270)
			(size 1.8034 0.508)
			(layers "B.Cu" "B.Mask" "B.Paste")
			(net "GND")
		)
		(pad "150" smd rect
			(at -4.59994 4.249928 270)
			(size 1.8034 0.508)
			(layers "B.Cu" "B.Mask" "B.Paste")
			(net "M_L_DQ<1>")
		)
		(pad "151" smd rect
			(at -4.59994 5.100066 270)
			(size 1.8034 0.508)
			(layers "B.Cu" "B.Mask" "B.Paste")
			(net "GND")
		)
		(pad "152" smd rect
			(at -4.59994 5.94995 270)
			(size 1.8034 0.508)
			(layers "B.Cu" "B.Mask" "B.Paste")
			(net "M_L_DQS_DN<0>")
		)
		(pad "153" smd rect
			(at -4.59994 6.800088 270)
			(size 1.8034 0.508)
			(layers "B.Cu" "B.Mask" "B.Paste")
			(net "M_L_DQS_DP<0>")
		)
		(pad "154" smd rect
			(at -4.59994 7.649972 270)
			(size 1.8034 0.508)
			(layers "B.Cu" "B.Mask" "B.Paste")
			(net "GND")
		)
		(pad "155" smd rect
			(at -4.59994 8.50011 270)
			(size 1.8034 0.508)
			(layers "B.Cu" "B.Mask" "B.Paste")
			(net "M_L_DQ<7>")
		)
		(pad "156" smd rect
			(at -4.59994 9.349994 270)
			(size 1.8034 0.508)
			(layers "B.Cu" "B.Mask" "B.Paste")
			(net "GND")
		)
		(pad "157" smd rect
			(at -4.59994 10.199878 270)
			(size 1.8034 0.508)
			(layers "B.Cu" "B.Mask" "B.Paste")
			(net "M_L_DQ<3>")
		)
		(pad "158" smd rect
			(at -4.59994 11.050016 270)
			(size 1.8034 0.508)
			(layers "B.Cu" "B.Mask" "B.Paste")
			(net "GND")
		)
		(pad "159" smd rect
			(at -4.59994 11.8999 270)
			(size 1.8034 0.508)
			(layers "B.Cu" "B.Mask" "B.Paste")
			(net "M_L_DQ<13>")
		)
		(pad "160" smd rect
			(at -4.59994 12.750038 270)
			(size 1.8034 0.508)
			(layers "B.Cu" "B.Mask" "B.Paste")
			(net "GND")
		)
		(pad "161" smd rect
			(at -4.59994 13.599922 270)
			(size 1.8034 0.508)
			(layers "B.Cu" "B.Mask" "B.Paste")
			(net "M_L_DQ<9>")
		)
		(pad "162" smd rect
			(at -4.59994 14.45006 270)
			(size 1.8034 0.508)
			(layers "B.Cu" "B.Mask" "B.Paste")
			(net "GND")
		)
		(pad "163" smd rect
			(at -4.59994 15.299944 270)
			(size 1.8034 0.508)
			(layers "B.Cu" "B.Mask" "B.Paste")
			(net "M_L_DQS_DN<1>")
		)
		(pad "164" smd rect
			(at -4.59994 16.150082 270)
			(size 1.8034 0.508)
			(layers "B.Cu" "B.Mask" "B.Paste")
			(net "M_L_DQS_DP<1>")
		)
		(pad "165" smd rect
			(at -4.59994 16.999966 270)
			(size 1.8034 0.508)
			(layers "B.Cu" "B.Mask" "B.Paste")
			(net "GND")
		)
		(pad "166" smd rect
			(at -4.59994 17.850104 270)
			(size 1.8034 0.508)
			(layers "B.Cu" "B.Mask" "B.Paste")
			(net "M_L_DQ<15>")
		)
		(pad "167" smd rect
			(at -4.59994 18.699988 270)
			(size 1.8034 0.508)
			(layers "B.Cu" "B.Mask" "B.Paste")
			(net "GND")
		)
		(pad "168" smd rect
			(at -4.59994 19.550126 270)
			(size 1.8034 0.508)
			(layers "B.Cu" "B.Mask" "B.Paste")
			(net "M_L_DQ<11>")
		)
		(pad "169" smd rect
			(at -4.59994 20.40001 270)
			(size 1.8034 0.508)
			(layers "B.Cu" "B.Mask" "B.Paste")
			(net "GND")
		)
		(pad "170" smd rect
			(at -4.59994 21.249894 270)
			(size 1.8034 0.508)
			(layers "B.Cu" "B.Mask" "B.Paste")
			(net "M_L_DQ<21>")
		)
		(pad "171" smd rect
			(at -4.59994 22.100032 270)
			(size 1.8034 0.508)
			(layers "B.Cu" "B.Mask" "B.Paste")
			(net "GND")
		)
		(pad "172" smd rect
			(at -4.59994 22.949916 270)
			(size 1.8034 0.508)
			(layers "B.Cu" "B.Mask" "B.Paste")
			(net "M_L_DQ<17>")
		)
		(pad "173" smd rect
			(at -4.59994 23.800054 270)
			(size 1.8034 0.508)
			(layers "B.Cu" "B.Mask" "B.Paste")
			(net "GND")
		)
		(pad "174" smd rect
			(at -4.59994 24.649938 270)
			(size 1.8034 0.508)
			(layers "B.Cu" "B.Mask" "B.Paste")
			(net "M_L_DQS_DN<2>")
		)
		(pad "175" smd rect
			(at -4.59994 25.500076 270)
			(size 1.8034 0.508)
			(layers "B.Cu" "B.Mask" "B.Paste")
			(net "M_L_DQS_DP<2>")
		)
		(pad "176" smd rect
			(at -4.59994 26.34996 270)
			(size 1.8034 0.508)
			(layers "B.Cu" "B.Mask" "B.Paste")
			(net "GND")
		)
		(pad "177" smd rect
			(at -4.59994 27.200098 270)
			(size 1.8034 0.508)
			(layers "B.Cu" "B.Mask" "B.Paste")
			(net "M_L_DQ<23>")
		)
		(pad "178" smd rect
			(at -4.59994 28.049982 270)
			(size 1.8034 0.508)
			(layers "B.Cu" "B.Mask" "B.Paste")
			(net "GND")
		)
		(pad "179" smd rect
			(at -4.59994 28.90012 270)
			(size 1.8034 0.508)
			(layers "B.Cu" "B.Mask" "B.Paste")
			(net "M_L_DQ<19>")
		)
		(pad "180" smd rect
			(at -4.59994 29.750004 270)
			(size 1.8034 0.508)
			(layers "B.Cu" "B.Mask" "B.Paste")
			(net "GND")
		)
		(pad "181" smd rect
			(at -4.59994 30.599888 270)
			(size 1.8034 0.508)
			(layers "B.Cu" "B.Mask" "B.Paste")
			(net "M_L_DQ<29>")
		)
		(pad "182" smd rect
			(at -4.59994 31.450026 270)
			(size 1.8034 0.508)
			(layers "B.Cu" "B.Mask" "B.Paste")
			(net "GND")
		)
		(pad "183" smd rect
			(at -4.59994 32.29991 270)
			(size 1.8034 0.508)
			(layers "B.Cu" "B.Mask" "B.Paste")
			(net "M_L_DQ<25>")
		)
		(pad "184" smd rect
			(at -4.59994 33.150048 270)
			(size 1.8034 0.508)
			(layers "B.Cu" "B.Mask" "B.Paste")
			(net "GND")
		)
		(pad "185" smd rect
			(at -4.59994 33.999932 270)
			(size 1.8034 0.508)
			(layers "B.Cu" "B.Mask" "B.Paste")
			(net "M_L_DQS_DN<3>")
		)
		(pad "186" smd rect
			(at -4.59994 34.85007 270)
			(size 1.8034 0.508)
			(layers "B.Cu" "B.Mask" "B.Paste")
			(net "M_L_DQS_DP<3>")
		)
		(pad "187" smd rect
			(at -4.59994 35.699954 270)
			(size 1.8034 0.508)
			(layers "B.Cu" "B.Mask" "B.Paste")
			(net "GND")
		)
		(pad "188" smd rect
			(at -4.59994 36.550092 270)
			(size 1.8034 0.508)
			(layers "B.Cu" "B.Mask" "B.Paste")
			(net "M_L_DQ<31>")
		)
		(pad "189" smd rect
			(at -4.59994 37.399976 270)
			(size 1.8034 0.508)
			(layers "B.Cu" "B.Mask" "B.Paste")
			(net "GND")
		)
		(pad "190" smd rect
			(at -4.59994 38.250114 270)
			(size 1.8034 0.508)
			(layers "B.Cu" "B.Mask" "B.Paste")
			(net "M_L_DQ<27>")
		)
		(pad "191" smd rect
			(at -4.59994 39.099998 270)
			(size 1.8034 0.508)
			(layers "B.Cu" "B.Mask" "B.Paste")
			(net "GND")
		)
		(pad "192" smd rect
			(at -4.59994 39.949882 270)
			(size 1.8034 0.508)
			(layers "B.Cu" "B.Mask" "B.Paste")
			(net "M_L_ECC<5>")
		)
		(pad "193" smd rect
			(at -4.59994 40.80002 270)
			(size 1.8034 0.508)
			(layers "B.Cu" "B.Mask" "B.Paste")
			(net "GND")
		)
		(pad "194" smd rect
			(at -4.59994 41.649904 270)
			(size 1.8034 0.508)
			(layers "B.Cu" "B.Mask" "B.Paste")
			(net "M_L_ECC<1>")
		)
		(pad "195" smd rect
			(at -4.59994 42.500042 270)
			(size 1.8034 0.508)
			(layers "B.Cu" "B.Mask" "B.Paste")
			(net "GND")
		)
		(pad "196" smd rect
			(at -4.59994 43.349926 270)
			(size 1.8034 0.508)
			(layers "B.Cu" "B.Mask" "B.Paste")
			(net "M_L_DQS_DN<8>")
		)
		(pad "197" smd rect
			(at -4.59994 44.200064 270)
			(size 1.8034 0.508)
			(layers "B.Cu" "B.Mask" "B.Paste")
			(net "M_L_DQS_DP<8>")
		)
		(pad "198" smd rect
			(at -4.59994 45.049948 270)
			(size 1.8034 0.508)
			(layers "B.Cu" "B.Mask" "B.Paste")
			(net "GND")
		)
		(pad "199" smd rect
			(at -4.59994 45.900086 270)
			(size 1.8034 0.508)
			(layers "B.Cu" "B.Mask" "B.Paste")
			(net "M_L_ECC<7>")
		)
		(pad "200" smd rect
			(at -4.59994 46.74997 270)
			(size 1.8034 0.508)
			(layers "B.Cu" "B.Mask" "B.Paste")
			(net "GND")
		)
		(pad "201" smd rect
			(at -4.59994 47.600108 270)
			(size 1.8034 0.508)
			(layers "B.Cu" "B.Mask" "B.Paste")
			(net "M_L_ECC<3>")
		)
		(pad "202" smd rect
			(at -4.59994 48.449992 270)
			(size 1.8034 0.508)
			(layers "B.Cu" "B.Mask" "B.Paste")
			(net "GND")
		)
		(pad "203" smd rect
			(at -4.59994 49.299876 270)
			(size 1.8034 0.508)
			(layers "B.Cu" "B.Mask" "B.Paste")
			(net "M_L_CKE<3>")
		)
		(pad "204" smd rect
			(at -4.59994 50.150014 270)
			(size 1.8034 0.508)
			(layers "B.Cu" "B.Mask" "B.Paste")
			(net "PVDDQ_KLM")
		)
		(pad "205" smd rect
			(at -4.59994 50.999898 270)
			(size 1.8034 0.508)
			(layers "B.Cu" "B.Mask" "B.Paste")
			(net "TP_CH_L_DIMM0_RFU_0")
		)
		(pad "206" smd rect
			(at -4.59994 51.850036 270)
			(size 1.8034 0.508)
			(layers "B.Cu" "B.Mask" "B.Paste")
			(net "PVDDQ_KLM")
		)
		(pad "207" smd rect
			(at -4.59994 52.69992 270)
			(size 1.8034 0.508)
			(layers "B.Cu" "B.Mask" "B.Paste")
			(net "M_L_BG<1>")
		)
		(pad "208" smd rect
			(at -4.59994 53.550058 270)
			(size 1.8034 0.508)
			(layers "B.Cu" "B.Mask" "B.Paste")
			(net "M_L_ALERT_N")
		)
		(pad "209" smd rect
			(at -4.59994 54.399942 270)
			(size 1.8034 0.508)
			(layers "B.Cu" "B.Mask" "B.Paste")
			(net "PVDDQ_KLM")
		)
		(pad "210" smd rect
			(at -4.59994 55.25008 270)
			(size 1.8034 0.508)
			(layers "B.Cu" "B.Mask" "B.Paste")
			(net "M_L_MA<11>")
		)
		(pad "211" smd rect
			(at -4.59994 56.099964 270)
			(size 1.8034 0.508)
			(layers "B.Cu" "B.Mask" "B.Paste")
			(net "M_L_MA<7>")
		)
		(pad "212" smd rect
			(at -4.59994 56.950102 270)
			(size 1.8034 0.508)
			(layers "B.Cu" "B.Mask" "B.Paste")
			(net "PVDDQ_KLM")
		)
		(pad "213" smd rect
			(at -4.59994 57.799986 270)
			(size 1.8034 0.508)
			(layers "B.Cu" "B.Mask" "B.Paste")
			(net "M_L_MA<5>")
		)
		(pad "214" smd rect
			(at -4.59994 58.650124 270)
			(size 1.8034 0.508)
			(layers "B.Cu" "B.Mask" "B.Paste")
			(net "M_L_MA<4>")
		)
		(pad "215" smd rect
			(at -4.59994 59.500008 270)
			(size 1.8034 0.508)
			(layers "B.Cu" "B.Mask" "B.Paste")
			(net "PVDDQ_KLM")
		)
		(pad "216" smd rect
			(at -4.59994 60.349892 270)
			(size 1.8034 0.508)
			(layers "B.Cu" "B.Mask" "B.Paste")
			(net "M_L_MA<2>")
		)
		(pad "217" smd rect
			(at -4.59994 61.20003 270)
			(size 1.8034 0.508)
			(layers "B.Cu" "B.Mask" "B.Paste")
			(net "PVDDQ_KLM")
		)
		(pad "218" smd rect
			(at -4.59994 62.049914 270)
			(size 1.8034 0.508)
			(layers "B.Cu" "B.Mask" "B.Paste")
			(net "M_L_CLK_DP<3>")
		)
		(pad "219" smd rect
			(at -4.59994 62.900052 270)
			(size 1.8034 0.508)
			(layers "B.Cu" "B.Mask" "B.Paste")
			(net "M_L_CLK_DN<3>")
		)
		(pad "220" smd rect
			(at -4.59994 63.749936 270)
			(size 1.8034 0.508)
			(layers "B.Cu" "B.Mask" "B.Paste")
			(net "PVDDQ_KLM")
		)
		(pad "221" smd rect
			(at -4.59994 64.600074 270)
			(size 1.8034 0.508)
			(layers "B.Cu" "B.Mask" "B.Paste")
			(net "PVTT_KLM")
		)
		(pad "222" smd rect
			(at -4.59994 70.550024 270)
			(size 1.8034 0.508)
			(layers "B.Cu" "B.Mask" "B.Paste")
			(net "M_L_PAR")
		)
		(pad "223" smd rect
			(at -4.59994 71.399908 270)
			(size 1.8034 0.508)
			(layers "B.Cu" "B.Mask" "B.Paste")
			(net "PVDDQ_KLM")
		)
		(pad "224" smd rect
			(at -4.59994 72.250046 270)
			(size 1.8034 0.508)
			(layers "B.Cu" "B.Mask" "B.Paste")
			(net "M_L_BA<1>")
		)
		(pad "225" smd rect
			(at -4.59994 73.09993 270)
			(size 1.8034 0.508)
			(layers "B.Cu" "B.Mask" "B.Paste")
			(net "M_L_MA<10>")
		)
		(pad "226" smd rect
			(at -4.59994 73.950068 270)
			(size 1.8034 0.508)
			(layers "B.Cu" "B.Mask" "B.Paste")
			(net "PVDDQ_KLM")
		)
		(pad "227" smd rect
			(at -4.59994 74.799952 270)
			(size 1.8034 0.508)
			(layers "B.Cu" "B.Mask" "B.Paste")
			(net "TP_CH_L_DIMM0_RFU_1")
		)
		(pad "228" smd rect
			(at -4.59994 75.65009 270)
			(size 1.8034 0.508)
			(layers "B.Cu" "B.Mask" "B.Paste")
			(net "M_L_MA<14>")
		)
		(pad "229" smd rect
			(at -4.59994 76.499974 270)
			(size 1.8034 0.508)
			(layers "B.Cu" "B.Mask" "B.Paste")
			(net "PVDDQ_KLM")
		)
		(pad "230" smd rect
			(at -4.59994 77.350112 270)
			(size 1.8034 0.508)
			(layers "B.Cu" "B.Mask" "B.Paste")
			(net "FM_ADR_COMPLETE_KLM_N")
		)
		(pad "231" smd rect
			(at -4.59994 78.199996 270)
			(size 1.8034 0.508)
			(layers "B.Cu" "B.Mask" "B.Paste")
			(net "PVDDQ_KLM")
		)
		(pad "232" smd rect
			(at -4.59994 79.04988 270)
			(size 1.8034 0.508)
			(layers "B.Cu" "B.Mask" "B.Paste")
			(net "M_L_MA<13>")
		)
		(pad "233" smd rect
			(at -4.59994 79.900018 270)
			(size 1.8034 0.508)
			(layers "B.Cu" "B.Mask" "B.Paste")
			(net "PVDDQ_KLM")
		)
		(pad "234" smd rect
			(at -4.59994 80.749902 270)
			(size 1.8034 0.508)
			(layers "B.Cu" "B.Mask" "B.Paste")
			(net "M_L_MA<17>")
		)
		(pad "235" smd rect
			(at -4.59994 81.60004 270)
			(size 1.8034 0.508)
			(layers "B.Cu" "B.Mask" "B.Paste")
			(net "M_L_C<2>")
		)
		(pad "236" smd rect
			(at -4.59994 82.449924 270)
			(size 1.8034 0.508)
			(layers "B.Cu" "B.Mask" "B.Paste")
			(net "PVDDQ_KLM")
		)
		(pad "237" smd rect
			(at -4.59994 83.300062 270)
			(size 1.8034 0.508)
			(layers "B.Cu" "B.Mask" "B.Paste")
			(net "M_L_CS_N<7>")
		)
		(pad "238" smd rect
			(at -4.59994 84.149946 270)
			(size 1.8034 0.508)
			(layers "B.Cu" "B.Mask" "B.Paste")
			(net "GND")
		)
		(pad "239" smd rect
			(at -4.59994 85.000084 270)
			(size 1.8034 0.508)
			(layers "B.Cu" "B.Mask" "B.Paste")
			(net "GND")
		)
		(pad "240" smd rect
			(at -4.59994 85.849968 270)
			(size 1.8034 0.508)
			(layers "B.Cu" "B.Mask" "B.Paste")
			(net "M_L_DQ<37>")
		)
		(pad "241" smd rect
			(at -4.59994 86.700106 270)
			(size 1.8034 0.508)
			(layers "B.Cu" "B.Mask" "B.Paste")
			(net "GND")
		)
		(pad "242" smd rect
			(at -4.59994 87.54999 270)
			(size 1.8034 0.508)
			(layers "B.Cu" "B.Mask" "B.Paste")
			(net "M_L_DQ<33>")
		)
		(pad "243" smd rect
			(at -4.59994 88.399874 270)
			(size 1.8034 0.508)
			(layers "B.Cu" "B.Mask" "B.Paste")
			(net "GND")
		)
		(pad "244" smd rect
			(at -4.59994 89.250012 270)
			(size 1.8034 0.508)
			(layers "B.Cu" "B.Mask" "B.Paste")
			(net "M_L_DQS_DN<4>")
		)
		(pad "245" smd rect
			(at -4.59994 90.099896 270)
			(size 1.8034 0.508)
			(layers "B.Cu" "B.Mask" "B.Paste")
			(net "M_L_DQS_DP<4>")
		)
		(pad "246" smd rect
			(at -4.59994 90.950034 270)
			(size 1.8034 0.508)
			(layers "B.Cu" "B.Mask" "B.Paste")
			(net "GND")
		)
		(pad "247" smd rect
			(at -4.59994 91.799918 270)
			(size 1.8034 0.508)
			(layers "B.Cu" "B.Mask" "B.Paste")
			(net "M_L_DQ<39>")
		)
		(pad "248" smd rect
			(at -4.59994 92.650056 270)
			(size 1.8034 0.508)
			(layers "B.Cu" "B.Mask" "B.Paste")
			(net "GND")
		)
		(pad "249" smd rect
			(at -4.59994 93.49994 270)
			(size 1.8034 0.508)
			(layers "B.Cu" "B.Mask" "B.Paste")
			(net "M_L_DQ<35>")
		)
		(pad "250" smd rect
			(at -4.59994 94.350078 270)
			(size 1.8034 0.508)
			(layers "B.Cu" "B.Mask" "B.Paste")
			(net "GND")
		)
		(pad "251" smd rect
			(at -4.59994 95.199962 270)
			(size 1.8034 0.508)
			(layers "B.Cu" "B.Mask" "B.Paste")
			(net "M_L_DQ<45>")
		)
		(pad "252" smd rect
			(at -4.59994 96.0501 270)
			(size 1.8034 0.508)
			(layers "B.Cu" "B.Mask" "B.Paste")
			(net "GND")
		)
		(pad "253" smd rect
			(at -4.59994 96.899984 270)
			(size 1.8034 0.508)
			(layers "B.Cu" "B.Mask" "B.Paste")
			(net "M_L_DQ<41>")
		)
		(pad "254" smd rect
			(at -4.59994 97.750122 270)
			(size 1.8034 0.508)
			(layers "B.Cu" "B.Mask" "B.Paste")
			(net "GND")
		)
		(pad "255" smd rect
			(at -4.59994 98.600006 270)
			(size 1.8034 0.508)
			(layers "B.Cu" "B.Mask" "B.Paste")
			(net "M_L_DQS_DN<5>")
		)
		(pad "256" smd rect
			(at -4.59994 99.44989 270)
			(size 1.8034 0.508)
			(layers "B.Cu" "B.Mask" "B.Paste")
			(net "M_L_DQS_DP<5>")
		)
		(pad "257" smd rect
			(at -4.59994 100.300028 270)
			(size 1.8034 0.508)
			(layers "B.Cu" "B.Mask" "B.Paste")
			(net "GND")
		)
		(pad "258" smd rect
			(at -4.59994 101.149912 270)
			(size 1.8034 0.508)
			(layers "B.Cu" "B.Mask" "B.Paste")
			(net "M_L_DQ<47>")
		)
		(pad "259" smd rect
			(at -4.59994 102.00005 270)
			(size 1.8034 0.508)
			(layers "B.Cu" "B.Mask" "B.Paste")
			(net "GND")
		)
		(pad "260" smd rect
			(at -4.59994 102.849934 270)
			(size 1.8034 0.508)
			(layers "B.Cu" "B.Mask" "B.Paste")
			(net "M_L_DQ<43>")
		)
		(pad "261" smd rect
			(at -4.59994 103.700072 270)
			(size 1.8034 0.508)
			(layers "B.Cu" "B.Mask" "B.Paste")
			(net "GND")
		)
		(pad "262" smd rect
			(at -4.59994 104.549956 270)
			(size 1.8034 0.508)
			(layers "B.Cu" "B.Mask" "B.Paste")
			(net "M_L_DQ<53>")
		)
		(pad "263" smd rect
			(at -4.59994 105.400094 270)
			(size 1.8034 0.508)
			(layers "B.Cu" "B.Mask" "B.Paste")
			(net "GND")
		)
		(pad "264" smd rect
			(at -4.59994 106.249978 270)
			(size 1.8034 0.508)
			(layers "B.Cu" "B.Mask" "B.Paste")
			(net "M_L_DQ<49>")
		)
		(pad "265" smd rect
			(at -4.59994 107.100116 270)
			(size 1.8034 0.508)
			(layers "B.Cu" "B.Mask" "B.Paste")
			(net "GND")
		)
		(pad "266" smd rect
			(at -4.59994 107.95 270)
			(size 1.8034 0.508)
			(layers "B.Cu" "B.Mask" "B.Paste")
			(net "M_L_DQS_DN<6>")
		)
		(pad "267" smd rect
			(at -4.59994 108.799884 270)
			(size 1.8034 0.508)
			(layers "B.Cu" "B.Mask" "B.Paste")
			(net "M_L_DQS_DP<6>")
		)
		(pad "268" smd rect
			(at -4.59994 109.650022 270)
			(size 1.8034 0.508)
			(layers "B.Cu" "B.Mask" "B.Paste")
			(net "GND")
		)
		(pad "269" smd rect
			(at -4.59994 110.499906 270)
			(size 1.8034 0.508)
			(layers "B.Cu" "B.Mask" "B.Paste")
			(net "M_L_DQ<55>")
		)
		(pad "270" smd rect
			(at -4.59994 111.350044 270)
			(size 1.8034 0.508)
			(layers "B.Cu" "B.Mask" "B.Paste")
			(net "GND")
		)
		(pad "271" smd rect
			(at -4.59994 112.199928 270)
			(size 1.8034 0.508)
			(layers "B.Cu" "B.Mask" "B.Paste")
			(net "M_L_DQ<51>")
		)
		(pad "272" smd rect
			(at -4.59994 113.050066 270)
			(size 1.8034 0.508)
			(layers "B.Cu" "B.Mask" "B.Paste")
			(net "GND")
		)
		(pad "273" smd rect
			(at -4.59994 113.89995 270)
			(size 1.8034 0.508)
			(layers "B.Cu" "B.Mask" "B.Paste")
			(net "M_L_DQ<61>")
		)
		(pad "274" smd rect
			(at -4.59994 114.750088 270)
			(size 1.8034 0.508)
			(layers "B.Cu" "B.Mask" "B.Paste")
			(net "GND")
		)
		(pad "275" smd rect
			(at -4.59994 115.599972 270)
			(size 1.8034 0.508)
			(layers "B.Cu" "B.Mask" "B.Paste")
			(net "M_L_DQ<57>")
		)
		(pad "276" smd rect
			(at -4.59994 116.45011 270)
			(size 1.8034 0.508)
			(layers "B.Cu" "B.Mask" "B.Paste")
			(net "GND")
		)
		(pad "277" smd rect
			(at -4.59994 117.299994 270)
			(size 1.8034 0.508)
			(layers "B.Cu" "B.Mask" "B.Paste")
			(net "M_L_DQS_DN<7>")
		)
		(pad "278" smd rect
			(at -4.59994 118.149878 270)
			(size 1.8034 0.508)
			(layers "B.Cu" "B.Mask" "B.Paste")
			(net "M_L_DQS_DP<7>")
		)
		(pad "279" smd rect
			(at -4.59994 119.000016 270)
			(size 1.8034 0.508)
			(layers "B.Cu" "B.Mask" "B.Paste")
			(net "GND")
		)
		(pad "280" smd rect
			(at -4.59994 119.8499 270)
			(size 1.8034 0.508)
			(layers "B.Cu" "B.Mask" "B.Paste")
			(net "M_L_DQ<63>")
		)
		(pad "281" smd rect
			(at -4.59994 120.700038 270)
			(size 1.8034 0.508)
			(layers "B.Cu" "B.Mask" "B.Paste")
			(net "GND")
		)
		(pad "282" smd rect
			(at -4.59994 121.549922 270)
			(size 1.8034 0.508)
			(layers "B.Cu" "B.Mask" "B.Paste")
			(net "M_L_DQ<59>")
		)
		(pad "283" smd rect
			(at -4.59994 122.40006 270)
			(size 1.8034 0.508)
			(layers "B.Cu" "B.Mask" "B.Paste")
			(net "GND")
		)
		(pad "284" smd rect
			(at -4.59994 123.249944 270)
			(size 1.8034 0.508)
			(layers "B.Cu" "B.Mask" "B.Paste")
			(net "PVPP_KLM")
		)
		(pad "285" smd rect
			(at -4.59994 124.100082 270)
			(size 1.8034 0.508)
			(layers "B.Cu" "B.Mask" "B.Paste")
			(net "SMB_DDR_KLM_VPP_SDA")
		)
		(pad "286" smd rect
			(at -4.59994 124.949966 270)
			(size 1.8034 0.508)
			(layers "B.Cu" "B.Mask" "B.Paste")
			(net "PVPP_KLM")
		)
		(pad "287" smd rect
			(at -4.59994 125.800104 270)
			(size 1.8034 0.508)
			(layers "B.Cu" "B.Mask" "B.Paste")
			(net "PVPP_KLM")
		)
		(pad "288" smd rect
			(at -4.59994 126.649988 270)
			(size 1.8034 0.508)
			(layers "B.Cu" "B.Mask" "B.Paste")
			(net "PVPP_KLM")
		)
	)
	(footprint ""
		(layer "B.Cu")
		(at 168.927526 -146.713448 90)
		(property "Reference" "C6L5"
			(at 0 0 90)
			(layer "B.SilkS")
			(hide yes)
			(effects
				(font
					(size 1.27 1.27)
				)
				(justify mirror)
			)
		)
		(property "Value" ""
			(at 0 0 90)
			(layer "B.Fab")
			(effects
				(font
					(size 1.27 1.27)
				)
				(justify mirror)
			)
		)
		(duplicate_pad_numbers_are_jumpers no)
		(fp_rect
			(start 0.4953 1.6002)
			(end -0.4953 -0.2032)
			(stroke
				(width 0)
				(type default)
			)
			(fill no)
			(layer "B.CrtYd")
		)
		(fp_line
			(start 0.4953 -0.2032)
			(end -0.4953 -0.2032)
			(stroke
				(width 0.1)
				(type default)
			)
			(layer "B.Fab")
		)
		(fp_line
			(start -0.4953 -0.2032)
			(end -0.4953 1.6002)
			(stroke
				(width 0.1)
				(type default)
			)
			(layer "B.Fab")
		)
		(fp_line
			(start 0.4953 1.6002)
			(end 0.4953 -0.2032)
			(stroke
				(width 0.1)
				(type default)
			)
			(layer "B.Fab")
		)
		(fp_line
			(start -0.4953 1.6002)
			(end 0.4953 1.6002)
			(stroke
				(width 0.1)
				(type default)
			)
			(layer "B.Fab")
		)
		(pad "1" smd rect
			(at 0 0 270)
			(size 0.762 0.889)
			(layers "B.Cu" "B.Mask" "B.Paste")
			(net "PVDDQ_KLM")
		)
		(pad "2" smd rect
			(at 0 1.397 270)
			(size 0.762 0.889)
			(layers "B.Cu" "B.Mask" "B.Paste")
			(net "GND")
		)
		(zone
			(layer "B.Cu")
			(hatch none 0.5)
			(connect_pads
				(clearance 0)
			)
			(min_thickness 0.25)
			(keepout
				(tracks not_allowed)
				(vias allowed)
				(pads allowed)
				(copperpour not_allowed)
				(footprints allowed)
			)
			(placement
				(enabled no)
				(sheetname "")
			)
			(fill
				(thermal_gap 0.5)
				(thermal_bridge_width 0.5)
				(island_removal_mode 0)
			)
			(polygon
				(pts
					(xy 169.880026 -147.094448) (xy 169.372026 -147.094448) (xy 169.372026 -146.332448) (xy 169.880026 -146.332448)
				)
			)
		)
	)
	(footprint ""
		(layer "B.Cu")
		(at 269.559532 -149.8092 90)
		(property "Reference" "C5G70"
			(at -1.14681 0.76708 180)
			(unlocked yes)
			(layer "B.SilkS")
			(effects
				(font
					(size 0.7874 0.5842)
					(thickness 0.1524)
				)
				(justify mirror)
			)
		)
		(property "Value" ""
			(at 0 0 90)
			(layer "B.Fab")
			(effects
				(font
					(size 1.27 1.27)
				)
				(justify mirror)
			)
		)
		(duplicate_pad_numbers_are_jumpers no)
		(fp_rect
			(start -0.4953 -0.2032)
			(end 0.4953 1.6002)
			(stroke
				(width 0)
				(type default)
			)
			(fill no)
			(layer "B.CrtYd")
		)
		(fp_line
			(start 0.4953 -0.2032)
			(end -0.4953 -0.2032)
			(stroke
				(width 0.1)
				(type default)
			)
			(layer "B.Fab")
		)
		(fp_line
			(start -0.4953 -0.2032)
			(end -0.4953 1.6002)
			(stroke
				(width 0.1)
				(type default)
			)
			(layer "B.Fab")
		)
		(fp_line
			(start 0.4953 1.6002)
			(end 0.4953 -0.2032)
			(stroke
				(width 0.1)
				(type default)
			)
			(layer "B.Fab")
		)
		(fp_line
			(start -0.4953 1.6002)
			(end 0.4953 1.6002)
			(stroke
				(width 0.1)
				(type default)
			)
			(layer "B.Fab")
		)
		(pad "1" smd rect
			(at 0 0 270)
			(size 0.762 0.889)
			(layers "B.Cu" "B.Mask" "B.Paste")
			(net "PVDDQ_DEF")
		)
		(pad "2" smd rect
			(at 0 1.397 270)
			(size 0.762 0.889)
			(layers "B.Cu" "B.Mask" "B.Paste")
			(net "GND")
		)
		(zone
			(layer "B.Cu")
			(hatch none 0.5)
			(connect_pads
				(clearance 0)
			)
			(min_thickness 0.25)
			(keepout
				(tracks not_allowed)
				(vias allowed)
				(pads allowed)
				(copperpour not_allowed)
				(footprints allowed)
			)
			(placement
				(enabled no)
				(sheetname "")
			)
			(fill
				(thermal_gap 0.5)
				(thermal_bridge_width 0.5)
				(island_removal_mode 0)
			)
			(polygon
				(pts
					(xy 270.004032 -149.4282) (xy 270.512032 -149.4282) (xy 270.512032 -150.1902) (xy 270.004032 -150.1902)
				)
			)
		)
	)
	(footprint ""
		(layer "B.Cu")
		(at 269.502128 -156.960824 90)
		(property "Reference" "C5L3"
			(at 0 0 90)
			(layer "B.SilkS")
			(hide yes)
			(effects
				(font
					(size 1.27 1.27)
				)
				(justify mirror)
			)
		)
		(property "Value" ""
			(at 0 0 90)
			(layer "B.Fab")
			(effects
				(font
					(size 1.27 1.27)
				)
				(justify mirror)
			)
		)
		(duplicate_pad_numbers_are_jumpers no)
		(fp_rect
			(start 0.7239 1.9939)
			(end -0.7239 -0.2159)
			(stroke
				(width 0)
				(type default)
			)
			(fill no)
			(layer "B.CrtYd")
		)
		(fp_line
			(start 0.7239 -0.2159)
			(end 0.7239 1.9939)
			(stroke
				(width 0.1)
				(type default)
			)
			(layer "B.Fab")
		)
		(fp_line
			(start -0.7239 -0.2159)
			(end 0.7239 -0.2159)
			(stroke
				(width 0.1)
				(type default)
			)
			(layer "B.Fab")
		)
		(fp_line
			(start 0.7239 1.9939)
			(end -0.7239 1.9939)
			(stroke
				(width 0.1)
				(type default)
			)
			(layer "B.Fab")
		)
		(fp_line
			(start -0.7239 1.9939)
			(end -0.7239 -0.2159)
			(stroke
				(width 0.1)
				(type default)
			)
			(layer "B.Fab")
		)
		(pad "1" smd rect
			(at 0 0 270)
			(size 1.27 1.016)
			(layers "B.Cu" "B.Mask" "B.Paste")
			(net "PVDDQ_DEF")
		)
		(pad "2" smd rect
			(at 0 1.778 270)
			(size 1.27 1.016)
			(layers "B.Cu" "B.Mask" "B.Paste")
			(net "GND")
		)
		(zone
			(layer "B.Cu")
			(hatch none 0.5)
			(connect_pads
				(clearance 0)
			)
			(min_thickness 0.25)
			(keepout
				(tracks not_allowed)
				(vias allowed)
				(pads allowed)
				(copperpour not_allowed)
				(footprints allowed)
			)
			(placement
				(enabled no)
				(sheetname "")
			)
			(fill
				(thermal_gap 0.5)
				(thermal_bridge_width 0.5)
				(island_removal_mode 0)
			)
			(polygon
				(pts
					(xy 270.772128 -157.595824) (xy 270.010128 -157.595824) (xy 270.010128 -156.325824) (xy 270.772128 -156.325824)
				)
			)
		)
	)
	(footprint ""
		(layer "B.Cu")
		(at 465.0232 -130.5052 90)
		(property "Reference" "U1M3"
			(at -5.83819 0.86614 0)
			(unlocked yes)
			(layer "B.SilkS")
			(effects
				(font
					(size 0.7874 0.5842)
					(thickness 0.1524)
				)
				(justify mirror)
			)
		)
		(property "Value" ""
			(at 0 0 90)
			(layer "B.Fab")
			(effects
				(font
					(size 1.27 1.27)
				)
				(justify mirror)
			)
		)
		(duplicate_pad_numbers_are_jumpers no)
		(fp_circle
			(center 1.395222 -0.155448)
			(end 1.395222 -0.028448)
			(stroke
				(width 0.254)
				(type default)
			)
			(fill no)
			(layer "B.SilkS")
		)
		(fp_rect
			(start -0.45847 2.400046)
			(end -2.20853 -0.500126)
			(stroke
				(width 0)
				(type default)
			)
			(fill no)
			(layer "B.CrtYd")
		)
		(fp_line
			(start -0.45847 -0.500126)
			(end -2.20853 -0.500126)
			(stroke
				(width 0.1)
				(type default)
			)
			(layer "B.Fab")
		)
		(fp_line
			(start -2.20853 -0.500126)
			(end -2.20853 2.400046)
			(stroke
				(width 0.1)
				(type default)
			)
			(layer "B.Fab")
		)
		(fp_line
			(start -0.45847 2.400046)
			(end -0.45847 -0.500126)
			(stroke
				(width 0.1)
				(type default)
			)
			(layer "B.Fab")
		)
		(fp_line
			(start -2.20853 2.400046)
			(end -0.45847 2.400046)
			(stroke
				(width 0.1)
				(type default)
			)
			(layer "B.Fab")
		)
		(fp_circle
			(center 1.395222 -0.155448)
			(end 1.395222 -0.028448)
			(stroke
				(width 0.254)
				(type default)
			)
			(fill no)
			(layer "B.Fab")
		)
		(pad "1" smd rect
			(at 0 0 270)
			(size 1.397 0.508)
			(layers "B.Cu" "B.Mask" "B.Paste")
			(net "P5V_USB")
		)
		(pad "2" smd rect
			(at 0 0.94996 270)
			(size 1.397 0.508)
			(layers "B.Cu" "B.Mask" "B.Paste")
			(net "GND")
		)
		(pad "3" smd rect
			(at 0 1.89992 270)
			(size 1.397 0.508)
			(layers "B.Cu" "B.Mask" "B.Paste")
			(net "FM_OC0_USB_N")
		)
		(pad "4" smd rect
			(at -2.667 1.89992 270)
			(size 1.397 0.508)
			(layers "B.Cu" "B.Mask" "B.Paste")
			(net "FM_USB_P0_EN_R_N")
		)
		(pad "5" smd rect
			(at -2.667 0 270)
			(size 1.397 0.508)
			(layers "B.Cu" "B.Mask" "B.Paste")
			(net "P5V_TPS2061")
		)
	)
	(footprint ""
		(layer "B.Cu")
		(at 480.108006 -34.980118 -90)
		(property "Reference" "R2T52"
			(at 0 0 90)
			(layer "B.SilkS")
			(hide yes)
			(effects
				(font
					(size 1.27 1.27)
				)
				(justify mirror)
			)
		)
		(property "Value" ""
			(at 0 0 90)
			(layer "B.Fab")
			(effects
				(font
					(size 1.27 1.27)
				)
				(justify mirror)
			)
		)
		(duplicate_pad_numbers_are_jumpers no)
		(fp_poly
			(pts
				(xy 0.4953 -0.2032) (xy -0.4953 -0.2032) (xy -0.4953 1.6002) (xy 0.4953 1.6002)
			)
			(stroke
				(width 0)
				(type default)
			)
			(fill no)
			(layer "B.CrtYd")
		)
		(fp_line
			(start -0.4953 1.6002)
			(end 0.4953 1.6002)
			(stroke
				(width 0.1)
				(type default)
			)
			(layer "B.Fab")
		)
		(fp_line
			(start 0.4953 1.6002)
			(end 0.4953 -0.2032)
			(stroke
				(width 0.1)
				(type default)
			)
			(layer "B.Fab")
		)
		(fp_line
			(start -0.4953 -0.2032)
			(end -0.4953 1.6002)
			(stroke
				(width 0.1)
				(type default)
			)
			(layer "B.Fab")
		)
		(fp_line
			(start 0.4953 -0.2032)
			(end -0.4953 -0.2032)
			(stroke
				(width 0.1)
				(type default)
			)
			(layer "B.Fab")
		)
		(pad "1" smd rect
			(at 0 0 90)
			(size 0.762 0.889)
			(layers "B.Cu" "B.Mask" "B.Paste")
			(net "P3V3_STBY_MNG")
		)
		(pad "2" smd rect
			(at 0 1.397 90)
			(size 0.762 0.889)
			(layers "B.Cu" "B.Mask" "B.Paste")
			(net "P3V3_STBY_MNG_RMII")
		)
		(zone
			(layer "B.Cu")
			(hatch none 0.5)
			(connect_pads
				(clearance 0)
			)
			(min_thickness 0.25)
			(keepout
				(tracks allowed)
				(vias not_allowed)
				(pads allowed)
				(copperpour not_allowed)
				(footprints allowed)
			)
			(placement
				(enabled no)
				(sheetname "")
			)
			(fill
				(thermal_gap 0.5)
				(thermal_bridge_width 0.5)
				(island_removal_mode 0)
			)
			(polygon
				(pts
					(xy 479.155506 -35.361118) (xy 479.663506 -35.361118) (xy 479.663506 -34.599118) (xy 479.155506 -34.599118)
				)
			)
		)
		(zone
			(layer "B.Cu")
			(hatch none 0.5)
			(connect_pads
				(clearance 0)
			)
			(min_thickness 0.25)
			(keepout
				(tracks not_allowed)
				(vias allowed)
				(pads allowed)
				(copperpour not_allowed)
				(footprints allowed)
			)
			(placement
				(enabled no)
				(sheetname "")
			)
			(fill
				(thermal_gap 0.5)
				(thermal_bridge_width 0.5)
				(island_removal_mode 0)
			)
			(polygon
				(pts
					(xy 479.155506 -34.599118) (xy 479.663506 -34.599118) (xy 479.663506 -35.361118) (xy 479.155506 -35.361118)
				)
			)
		)
	)
	(footprint ""
		(layer "B.Cu")
		(at 374.408446 -88.236806 180)
		(property "Reference" "R3N14"
			(at 0.8382 -0.67818 180)
			(unlocked yes)
			(layer "B.SilkS")
			(effects
				(font
					(size 0.4064 0.254)
					(thickness 0.1524)
				)
				(justify left mirror)
			)
		)
		(property "Value" ""
			(at 0 0 0)
			(layer "B.Fab")
			(effects
				(font
					(size 1.27 1.27)
				)
				(justify mirror)
			)
		)
		(duplicate_pad_numbers_are_jumpers no)
		(fp_poly
			(pts
				(xy 0.2794 -0.1016) (xy -0.2794 -0.1016) (xy -0.2794 0.9906) (xy 0.2794 0.9906)
			)
			(stroke
				(width 0)
				(type default)
			)
			(fill no)
			(layer "B.CrtYd")
		)
		(fp_line
			(start 0.2794 0.9906)
			(end -0.2794 0.9906)
			(stroke
				(width 0.1)
				(type default)
			)
			(layer "B.Fab")
		)
		(fp_line
			(start 0.2794 -0.1016)
			(end 0.2794 0.9906)
			(stroke
				(width 0.1)
				(type default)
			)
			(layer "B.Fab")
		)
		(fp_line
			(start -0.2794 0.9906)
			(end -0.2794 -0.1016)
			(stroke
				(width 0.1)
				(type default)
			)
			(layer "B.Fab")
		)
		(fp_line
			(start -0.2794 -0.1016)
			(end 0.2794 -0.1016)
			(stroke
				(width 0.1)
				(type default)
			)
			(layer "B.Fab")
		)
		(pad "1" smd rect
			(at 0 0)
			(size 0.508 0.508)
			(layers "B.Cu" "B.Mask" "B.Paste")
			(net "H_PM_SYNC_GTL")
		)
		(pad "2" smd rect
			(at 0 0.889)
			(size 0.508 0.508)
			(layers "B.Cu" "B.Mask" "B.Paste")
			(net "GND")
		)
		(zone
			(layer "B.Cu")
			(hatch none 0.5)
			(connect_pads
				(clearance 0)
			)
			(min_thickness 0.25)
			(keepout
				(tracks not_allowed)
				(vias allowed)
				(pads allowed)
				(copperpour not_allowed)
				(footprints allowed)
			)
			(placement
				(enabled no)
				(sheetname "")
			)
			(fill
				(thermal_gap 0.5)
				(thermal_bridge_width 0.5)
				(island_removal_mode 0)
			)
			(polygon
				(pts
					(xy 374.154446 -88.871806) (xy 374.662446 -88.871806) (xy 374.662446 -88.490806) (xy 374.154446 -88.490806)
				)
			)
		)
		(zone
			(layer "B.Cu")
			(hatch none 0.5)
			(connect_pads
				(clearance 0)
			)
			(min_thickness 0.25)
			(keepout
				(tracks allowed)
				(vias not_allowed)
				(pads allowed)
				(copperpour not_allowed)
				(footprints allowed)
			)
			(placement
				(enabled no)
				(sheetname "")
			)
			(fill
				(thermal_gap 0.5)
				(thermal_bridge_width 0.5)
				(island_removal_mode 0)
			)
			(polygon
				(pts
					(xy 374.154446 -88.490806) (xy 374.662446 -88.490806) (xy 374.662446 -88.871806) (xy 374.154446 -88.871806)
				)
			)
		)
	)
	(footprint ""
		(layer "B.Cu")
		(at 308.874414 -164.908992 90)
		(property "Reference" "T1D16"
			(at 0 0 90)
			(layer "B.SilkS")
			(hide yes)
			(effects
				(font
					(size 1.27 1.27)
				)
				(justify mirror)
			)
		)
		(property "Value" "*"
			(at 3.4036 -4.46405 90)
			(unlocked yes)
			(layer "B.Fab")
			(hide yes)
			(effects
				(font
					(size 0.889 0.889)
					(thickness 0.1524)
				)
				(justify mirror)
			)
		)
		(property "Device Type" "TEST-PAD-12P-1-GP-U_DISCRET-GBA"
			(at 3.4036 -5.98805 90)
			(unlocked yes)
			(layer "B.Fab")
			(hide yes)
			(effects
				(font
					(size 0.889 0.889)
					(thickness 0.1524)
				)
				(justify mirror)
			)
		)
		(duplicate_pad_numbers_are_jumpers no)
		(fp_line
			(start 2.3876 -4.826)
			(end -2.3622 -4.826)
			(stroke
				(width 0.1524)
				(type default)
			)
			(layer "B.SilkS")
		)
		(fp_line
			(start -2.3622 -4.826)
			(end -2.3622 3.4798)
			(stroke
				(width 0.1524)
				(type default)
			)
			(layer "B.SilkS")
		)
		(fp_line
			(start 2.3876 3.4798)
			(end 2.3876 -4.826)
			(stroke
				(width 0.1524)
				(type default)
			)
			(layer "B.SilkS")
		)
		(fp_line
			(start -2.3622 3.4798)
			(end 2.3876 3.4798)
			(stroke
				(width 0.1524)
				(type default)
			)
			(layer "B.SilkS")
		)
		(fp_rect
			(start 2.6416 3.7338)
			(end -2.6162 -5.08)
			(stroke
				(width 0)
				(type default)
			)
			(fill no)
			(layer "B.CrtYd")
		)
		(fp_rect
			(start 2.6416 3.7338)
			(end -2.6162 -5.08)
			(stroke
				(width 0)
				(type default)
			)
			(fill no)
			(layer "B.Fab")
		)
		(pad "1" smd circle
			(at -0.496824 -1.301496 270)
			(size 0.6604 0.6604)
			(layers "B.Cu" "B.Mask" "B.Paste")
			(net "L3_85OHM_10INCH_DN")
		)
		(pad "2" smd circle
			(at 0.503936 -1.301496 270)
			(size 0.6604 0.6604)
			(layers "B.Cu" "B.Mask" "B.Paste")
			(net "L3_85OHM_10INCH_DP")
		)
		(pad "3" smd custom
			(at 0.00889 0.370078 270)
			(size 0.74295 0.74295)
			(layers "B.Cu" "B.Mask" "B.Paste")
			(net "GND")
			(options
				(clearance outline)
				(anchor circle)
			)
			(primitives
				(gr_poly
					(pts
						(xy -2.1209 -1.4859) (xy 2.1209 -1.4859) (xy 2.1209 1.4859) (xy 1.08585 1.4859) (xy 1.08585 0.4699)
						(xy -1.08585 0.4699) (xy -1.08585 1.4859) (xy -2.1209 1.4859)
					)
					(width 0)
					(fill yes)
				)
			)
		)
		(pad "4" thru_hole circle
			(at -1.266444 -3.851656 270)
			(size 1.4478 1.4478)
			(drill 1.0414)
			(layers "*.Cu" "*.Mask")
			(remove_unused_layers no)
			(net "GND")
			(clearance 0.1524)
			(thermal_gap 0.1524)
		)
		(pad "5" thru_hole circle
			(at 1.273556 -3.851656 270)
			(size 1.4478 1.4478)
			(drill 1.0414)
			(layers "*.Cu" "*.Mask")
			(remove_unused_layers no)
			(net "GND")
			(clearance 0.1524)
			(thermal_gap 0.1524)
		)
		(pad "6" thru_hole circle
			(at -1.266444 2.498344 270)
			(size 1.4478 1.4478)
			(drill 1.0414)
			(layers "*.Cu" "*.Mask")
			(remove_unused_layers no)
			(net "GND")
			(clearance 0.1524)
			(thermal_gap 0.1524)
		)
		(pad "7" thru_hole circle
			(at 1.273556 2.498344 270)
			(size 1.4478 1.4478)
			(drill 1.0414)
			(layers "*.Cu" "*.Mask")
			(remove_unused_layers no)
			(net "GND")
			(clearance 0.1524)
			(thermal_gap 0.1524)
		)
		(pad "8" thru_hole circle
			(at -1.27 -0.4572 270)
			(size 0.7112 0.7112)
			(drill 0.4064)
			(layers "*.Cu" "*.Mask")
			(remove_unused_layers no)
			(net "GND")
			(clearance 0.1016)
			(thermal_gap 0.1016)
		)
		(pad "9" thru_hole circle
			(at -1.27 0.762 270)
			(size 0.7112 0.7112)
			(drill 0.4064)
			(layers "*.Cu" "*.Mask")
			(remove_unused_layers no)
			(net "GND")
			(clearance 0.1016)
			(thermal_gap 0.1016)
		)
		(pad "10" thru_hole circle
			(at 0.0254 0.762 270)
			(size 0.7112 0.7112)
			(drill 0.4064)
			(layers "*.Cu" "*.Mask")
			(remove_unused_layers no)
			(net "GND")
			(clearance 0.1016)
			(thermal_gap 0.1016)
		)
		(pad "11" thru_hole circle
			(at 1.27 0.762 270)
			(size 0.7112 0.7112)
			(drill 0.4064)
			(layers "*.Cu" "*.Mask")
			(remove_unused_layers no)
			(net "GND")
			(clearance 0.1016)
			(thermal_gap 0.1016)
		)
		(pad "12" thru_hole circle
			(at 1.27 -0.4572 270)
			(size 0.7112 0.7112)
			(drill 0.4064)
			(layers "*.Cu" "*.Mask")
			(remove_unused_layers no)
			(net "GND")
			(clearance 0.1016)
			(thermal_gap 0.1016)
		)
	)
	(footprint ""
		(layer "B.Cu")
		(at 181.5846 -61.03366 180)
		(property "Reference" "C22W18"
			(at 0 0 0)
			(layer "B.SilkS")
			(hide yes)
			(effects
				(font
					(size 1.27 1.27)
				)
				(justify mirror)
			)
		)
		(property "Value" "*"
			(at 0.0762 -6.2357 180)
			(unlocked yes)
			(layer "B.Fab")
			(hide yes)
			(effects
				(font
					(size 1.27 1.016)
					(thickness 0.1524)
				)
				(justify mirror)
			)
		)
		(property "Device Type" "SC22U16V5MX-4-GP_SMD-BCG5-SC22A"
			(at 0.0762 -8.2677 180)
			(unlocked yes)
			(layer "B.Fab")
			(hide yes)
			(effects
				(font
					(size 1.27 1.016)
					(thickness 0.1524)
				)
				(justify mirror)
			)
		)
		(duplicate_pad_numbers_are_jumpers no)
		(fp_line
			(start -0.635 0)
			(end 0.635 0)
			(stroke
				(width 0.508)
				(type default)
			)
			(layer "B.SilkS")
		)
		(fp_rect
			(start 0.9652 1.778)
			(end -0.9652 -1.778)
			(stroke
				(width 0)
				(type default)
			)
			(fill no)
			(layer "B.CrtYd")
		)
		(fp_poly
			(pts
				(xy 0.9652 -1.778) (xy -0.9652 -1.778) (xy -0.9652 1.778) (xy 0.9652 1.778)
			)
			(stroke
				(width 0)
				(type default)
			)
			(fill no)
			(layer "B.Fab")
		)
		(pad "1" smd rect
			(at 0 -0.9652)
			(size 1.397 1.143)
			(layers "B.Cu" "B.Mask" "B.Paste")
			(net "VR_FET_SW_P12V_STBY_PVCCIN_CPU0")
		)
		(pad "2" smd rect
			(at 0 0.9652)
			(size 1.397 1.143)
			(layers "B.Cu" "B.Mask" "B.Paste")
			(net "GND")
		)
	)
	(footprint ""
		(layer "B.Cu")
		(at 384.7084 -137.541)
		(property "Reference" "C3L24"
			(at 0 0 0)
			(layer "B.SilkS")
			(hide yes)
			(effects
				(font
					(size 1.27 1.27)
				)
				(justify mirror)
			)
		)
		(property "Value" ""
			(at 0 0 0)
			(layer "B.Fab")
			(effects
				(font
					(size 1.27 1.27)
				)
				(justify mirror)
			)
		)
		(duplicate_pad_numbers_are_jumpers no)
		(fp_poly
			(pts
				(xy 0.4953 -0.2032) (xy -0.4953 -0.2032) (xy -0.4953 1.6002) (xy 0.4953 1.6002)
			)
			(stroke
				(width 0)
				(type default)
			)
			(fill no)
			(layer "B.CrtYd")
		)
		(fp_line
			(start -0.4953 -0.2032)
			(end -0.4953 1.6002)
			(stroke
				(width 0.1)
				(type default)
			)
			(layer "B.Fab")
		)
		(fp_line
			(start -0.4953 1.6002)
			(end 0.4953 1.6002)
			(stroke
				(width 0.1)
				(type default)
			)
			(layer "B.Fab")
		)
		(fp_line
			(start 0.4953 -0.2032)
			(end -0.4953 -0.2032)
			(stroke
				(width 0.1)
				(type default)
			)
			(layer "B.Fab")
		)
		(fp_line
			(start 0.4953 1.6002)
			(end 0.4953 -0.2032)
			(stroke
				(width 0.1)
				(type default)
			)
			(layer "B.Fab")
		)
		(pad "1" smd rect
			(at 0 0 180)
			(size 0.762 0.889)
			(layers "B.Cu" "B.Mask" "B.Paste")
			(net "PVNN_PCH_STBY")
		)
		(pad "2" smd rect
			(at 0 1.397 180)
			(size 0.762 0.889)
			(layers "B.Cu" "B.Mask" "B.Paste")
			(net "GND")
		)
		(zone
			(layer "B.Cu")
			(hatch none 0.5)
			(connect_pads
				(clearance 0)
			)
			(min_thickness 0.25)
			(keepout
				(tracks not_allowed)
				(vias allowed)
				(pads allowed)
				(copperpour not_allowed)
				(footprints allowed)
			)
			(placement
				(enabled no)
				(sheetname "")
			)
			(fill
				(thermal_gap 0.5)
				(thermal_bridge_width 0.5)
				(island_removal_mode 0)
			)
			(polygon
				(pts
					(xy 385.0894 -137.0965) (xy 384.3274 -137.0965) (xy 384.3274 -136.5885) (xy 385.0894 -136.5885)
				)
			)
		)
	)
	(footprint ""
		(layer "B.Cu")
		(at 266.397232 -145.0086 90)
		(property "Reference" "C5L9"
			(at -1.848866 0.752348 90)
			(unlocked yes)
			(layer "B.SilkS")
			(effects
				(font
					(size 1.27 0.9652)
					(thickness 0.1524)
				)
				(justify mirror)
			)
		)
		(property "Value" ""
			(at 0 0 90)
			(layer "B.Fab")
			(effects
				(font
					(size 1.27 1.27)
				)
				(justify mirror)
			)
		)
		(duplicate_pad_numbers_are_jumpers no)
		(fp_rect
			(start 0.500126 1.598422)
			(end -0.500126 -0.201422)
			(stroke
				(width 0)
				(type default)
			)
			(fill no)
			(layer "B.CrtYd")
		)
		(fp_line
			(start 0.500126 -0.201422)
			(end -0.500126 -0.201422)
			(stroke
				(width 0.1)
				(type default)
			)
			(layer "B.Fab")
		)
		(fp_line
			(start -0.500126 -0.201422)
			(end -0.500126 1.598422)
			(stroke
				(width 0.1)
				(type default)
			)
			(layer "B.Fab")
		)
		(fp_line
			(start 0.500126 1.598422)
			(end 0.500126 -0.201422)
			(stroke
				(width 0.1)
				(type default)
			)
			(layer "B.Fab")
		)
		(fp_line
			(start -0.500126 1.598422)
			(end 0.500126 1.598422)
			(stroke
				(width 0.1)
				(type default)
			)
			(layer "B.Fab")
		)
		(pad "1" smd rect
			(at 0 0)
			(size 0.889 0.9906)
			(layers "B.Cu" "B.Mask" "B.Paste")
			(net "PVDDQ_DEF")
		)
		(pad "2" smd rect
			(at 0 1.397)
			(size 0.889 0.9906)
			(layers "B.Cu" "B.Mask" "B.Paste")
			(net "GND")
		)
		(zone
			(layer "B.Cu")
			(hatch none 0.5)
			(connect_pads
				(clearance 0)
			)
			(min_thickness 0.25)
			(keepout
				(tracks not_allowed)
				(vias allowed)
				(pads allowed)
				(copperpour not_allowed)
				(footprints allowed)
			)
			(placement
				(enabled no)
				(sheetname "")
			)
			(fill
				(thermal_gap 0.5)
				(thermal_bridge_width 0.5)
				(island_removal_mode 0)
			)
			(polygon
				(pts
					(xy 267.349732 -145.5039) (xy 266.841732 -145.5039) (xy 266.841732 -144.5133) (xy 267.349732 -144.5133)
				)
			)
		)
		(zone
			(layer "B.Cu")
			(hatch none 0.5)
			(connect_pads
				(clearance 0)
			)
			(min_thickness 0.25)
			(keepout
				(tracks allowed)
				(vias not_allowed)
				(pads allowed)
				(copperpour not_allowed)
				(footprints allowed)
			)
			(placement
				(enabled no)
				(sheetname "")
			)
			(fill
				(thermal_gap 0.5)
				(thermal_bridge_width 0.5)
				(island_removal_mode 0)
			)
			(polygon
				(pts
					(xy 267.349732 -145.5039) (xy 266.841732 -145.5039) (xy 266.841732 -144.5133) (xy 267.349732 -144.5133)
				)
			)
		)
	)
	(footprint ""
		(layer "B.Cu")
		(at 195.2244 -55.88 90)
		(property "Reference" "CT2"
			(at 0.8382 -0.84963 90)
			(unlocked yes)
			(layer "B.SilkS")
			(effects
				(font
					(size 0.7874 0.5842)
					(thickness 0.1524)
				)
				(justify left mirror)
			)
		)
		(property "Value" ""
			(at 0 0 90)
			(layer "B.Fab")
			(effects
				(font
					(size 1.27 1.27)
				)
				(justify mirror)
			)
		)
		(duplicate_pad_numbers_are_jumpers no)
		(fp_poly
			(pts
				(xy -0.3048 -0.1016) (xy -0.3048 0.9906) (xy 0.3048 0.9906) (xy 0.3048 -0.1016)
			)
			(stroke
				(width 0)
				(type default)
			)
			(fill no)
			(layer "B.CrtYd")
		)
		(fp_line
			(start 0.3048 -0.1016)
			(end 0.3048 0.9906)
			(stroke
				(width 0.1)
				(type default)
			)
			(layer "B.Fab")
		)
		(fp_line
			(start -0.3048 -0.1016)
			(end 0.3048 -0.1016)
			(stroke
				(width 0.1)
				(type default)
			)
			(layer "B.Fab")
		)
		(fp_line
			(start 0.3048 0.9906)
			(end -0.3048 0.9906)
			(stroke
				(width 0.1)
				(type default)
			)
			(layer "B.Fab")
		)
		(fp_line
			(start -0.3048 0.9906)
			(end -0.3048 -0.1016)
			(stroke
				(width 0.1)
				(type default)
			)
			(layer "B.Fab")
		)
		(pad "1" smd rect
			(at 0 0 270)
			(size 0.508 0.508)
			(layers "B.Cu" "B.Mask" "B.Paste")
			(net "A_TSENSE_PVCCIN_CPU0")
		)
		(pad "2" smd rect
			(at 0 0.889 270)
			(size 0.508 0.508)
			(layers "B.Cu" "B.Mask" "B.Paste")
			(net "GND")
		)
		(zone
			(layer "B.Cu")
			(hatch none 0.5)
			(connect_pads
				(clearance 0)
			)
			(min_thickness 0.25)
			(keepout
				(tracks allowed)
				(vias not_allowed)
				(pads allowed)
				(copperpour not_allowed)
				(footprints allowed)
			)
			(placement
				(enabled no)
				(sheetname "")
			)
			(fill
				(thermal_gap 0.5)
				(thermal_bridge_width 0.5)
				(island_removal_mode 0)
			)
			(polygon
				(pts
					(xy 195.4784 -56.134) (xy 195.4784 -55.626) (xy 195.8594 -55.626) (xy 195.8594 -56.134)
				)
			)
		)
		(zone
			(layer "B.Cu")
			(hatch none 0.5)
			(connect_pads
				(clearance 0)
			)
			(min_thickness 0.25)
			(keepout
				(tracks not_allowed)
				(vias allowed)
				(pads allowed)
				(copperpour not_allowed)
				(footprints allowed)
			)
			(placement
				(enabled no)
				(sheetname "")
			)
			(fill
				(thermal_gap 0.5)
				(thermal_bridge_width 0.5)
				(island_removal_mode 0)
			)
			(polygon
				(pts
					(xy 195.8594 -56.134) (xy 195.8594 -55.626) (xy 195.4784 -55.626) (xy 195.4784 -56.134)
				)
			)
		)
	)
	(footprint ""
		(layer "B.Cu")
		(at 374.777 -140.589 180)
		(property "Reference" "C3L21"
			(at -3.10007 3.24612 270)
			(unlocked yes)
			(layer "B.SilkS")
			(effects
				(font
					(size 0.7874 0.5842)
					(thickness 0.1524)
				)
				(justify mirror)
			)
		)
		(property "Value" ""
			(at 0 0 0)
			(layer "B.Fab")
			(effects
				(font
					(size 1.27 1.27)
				)
				(justify mirror)
			)
		)
		(duplicate_pad_numbers_are_jumpers no)
		(fp_line
			(start 2.563114 1.633728)
			(end 1.6002 1.633728)
			(stroke
				(width 0.1524)
				(type default)
			)
			(layer "B.SilkS")
		)
		(fp_line
			(start 2.563114 -1.616456)
			(end 2.563114 1.633728)
			(stroke
				(width 0.1524)
				(type default)
			)
			(layer "B.SilkS")
		)
		(fp_line
			(start 2.286 7.366)
			(end 2.286 1.632712)
			(stroke
				(width 0.1524)
				(type default)
			)
			(layer "B.SilkS")
		)
		(fp_line
			(start 2.286 7.366)
			(end 1.60147 7.366)
			(stroke
				(width 0.1524)
				(type default)
			)
			(layer "B.SilkS")
		)
		(fp_line
			(start 1.6002 -1.616456)
			(end 2.563114 -1.616456)
			(stroke
				(width 0.1524)
				(type default)
			)
			(layer "B.SilkS")
		)
		(fp_line
			(start -1.6002 -1.616456)
			(end -2.504948 -1.616456)
			(stroke
				(width 0.1524)
				(type default)
			)
			(layer "B.SilkS")
		)
		(fp_line
			(start -2.286 7.366)
			(end -1.600708 7.366)
			(stroke
				(width 0.1524)
				(type default)
			)
			(layer "B.SilkS")
		)
		(fp_line
			(start -2.286 7.366)
			(end -2.286 1.63195)
			(stroke
				(width 0.1524)
				(type default)
			)
			(layer "B.SilkS")
		)
		(fp_line
			(start -2.504948 1.633728)
			(end -1.6002 1.633728)
			(stroke
				(width 0.1524)
				(type default)
			)
			(layer "B.SilkS")
		)
		(fp_line
			(start -2.504948 -1.616456)
			(end -2.504948 1.633728)
			(stroke
				(width 0.1524)
				(type default)
			)
			(layer "B.SilkS")
		)
		(fp_rect
			(start 2.286 7.366)
			(end -2.286 -0.254)
			(stroke
				(width 0)
				(type default)
			)
			(fill no)
			(layer "B.CrtYd")
		)
		(fp_line
			(start 2.286 7.366)
			(end 2.286 -0.254)
			(stroke
				(width 0.1)
				(type default)
			)
			(layer "B.Fab")
		)
		(fp_line
			(start 2.286 -0.254)
			(end -2.286 -0.254)
			(stroke
				(width 0.1)
				(type default)
			)
			(layer "B.Fab")
		)
		(fp_line
			(start -2.286 7.366)
			(end 2.286 7.366)
			(stroke
				(width 0.1)
				(type default)
			)
			(layer "B.Fab")
		)
		(fp_line
			(start -2.286 -0.254)
			(end -2.286 7.366)
			(stroke
				(width 0.1)
				(type default)
			)
			(layer "B.Fab")
		)
		(pad "1" smd rect
			(at 0 0)
			(size 2.54 3.048)
			(layers "B.Cu" "B.Mask" "B.Paste")
			(net "PVNN_PCH_STBY")
		)
		(pad "2" smd rect
			(at 0 7.112)
			(size 2.54 3.048)
			(layers "B.Cu" "B.Mask" "B.Paste")
			(net "GND")
		)
	)
	(footprint ""
		(layer "B.Cu")
		(at 26.769568 -144.4752 180)
		(property "Reference" "C9L8"
			(at 0 0 0)
			(layer "B.SilkS")
			(hide yes)
			(effects
				(font
					(size 1.27 1.27)
				)
				(justify mirror)
			)
		)
		(property "Value" ""
			(at 0 0 0)
			(layer "B.Fab")
			(effects
				(font
					(size 1.27 1.27)
				)
				(justify mirror)
			)
		)
		(duplicate_pad_numbers_are_jumpers no)
		(fp_poly
			(pts
				(xy -0.3048 -0.1016) (xy -0.3048 0.9906) (xy 0.3048 0.9906) (xy 0.3048 -0.1016)
			)
			(stroke
				(width 0)
				(type default)
			)
			(fill no)
			(layer "B.CrtYd")
		)
		(fp_line
			(start 0.3048 0.9906)
			(end -0.3048 0.9906)
			(stroke
				(width 0.1)
				(type default)
			)
			(layer "B.Fab")
		)
		(fp_line
			(start 0.3048 -0.1016)
			(end 0.3048 0.9906)
			(stroke
				(width 0.1)
				(type default)
			)
			(layer "B.Fab")
		)
		(fp_line
			(start -0.3048 0.9906)
			(end -0.3048 -0.1016)
			(stroke
				(width 0.1)
				(type default)
			)
			(layer "B.Fab")
		)
		(fp_line
			(start -0.3048 -0.1016)
			(end 0.3048 -0.1016)
			(stroke
				(width 0.1)
				(type default)
			)
			(layer "B.Fab")
		)
		(pad "1" smd rect
			(at 0 0)
			(size 0.508 0.508)
			(layers "B.Cu" "B.Mask" "B.Paste")
			(net "M_L_CPU_VREF")
		)
		(pad "2" smd rect
			(at 0 0.889)
			(size 0.508 0.508)
			(layers "B.Cu" "B.Mask" "B.Paste")
			(net "GND")
		)
		(zone
			(layer "B.Cu")
			(hatch none 0.5)
			(connect_pads
				(clearance 0)
			)
			(min_thickness 0.25)
			(keepout
				(tracks not_allowed)
				(vias allowed)
				(pads allowed)
				(copperpour not_allowed)
				(footprints allowed)
			)
			(placement
				(enabled no)
				(sheetname "")
			)
			(fill
				(thermal_gap 0.5)
				(thermal_bridge_width 0.5)
				(island_removal_mode 0)
			)
			(polygon
				(pts
					(xy 26.515568 -145.1102) (xy 27.023568 -145.1102) (xy 27.023568 -144.7292) (xy 26.515568 -144.7292)
				)
			)
		)
		(zone
			(layer "B.Cu")
			(hatch none 0.5)
			(connect_pads
				(clearance 0)
			)
			(min_thickness 0.25)
			(keepout
				(tracks allowed)
				(vias not_allowed)
				(pads allowed)
				(copperpour not_allowed)
				(footprints allowed)
			)
			(placement
				(enabled no)
				(sheetname "")
			)
			(fill
				(thermal_gap 0.5)
				(thermal_bridge_width 0.5)
				(island_removal_mode 0)
			)
			(polygon
				(pts
					(xy 26.515568 -144.7292) (xy 27.023568 -144.7292) (xy 27.023568 -145.1102) (xy 26.515568 -145.1102)
				)
			)
		)
	)
	(footprint ""
		(layer "B.Cu")
		(at 405.358854 -35.09391 90)
		(property "Reference" "R25W122"
			(at 0.8382 -0.67818 90)
			(unlocked yes)
			(layer "B.SilkS")
			(effects
				(font
					(size 0.4064 0.254)
					(thickness 0.1524)
				)
				(justify left mirror)
			)
		)
		(property "Value" ""
			(at 0 0 90)
			(layer "B.Fab")
			(effects
				(font
					(size 1.27 1.27)
				)
				(justify mirror)
			)
		)
		(duplicate_pad_numbers_are_jumpers no)
		(fp_poly
			(pts
				(xy 0.2794 -0.1016) (xy -0.2794 -0.1016) (xy -0.2794 0.9906) (xy 0.2794 0.9906)
			)
			(stroke
				(width 0)
				(type default)
			)
			(fill no)
			(layer "B.CrtYd")
		)
		(fp_line
			(start 0.2794 -0.1016)
			(end 0.2794 0.9906)
			(stroke
				(width 0.1)
				(type default)
			)
			(layer "B.Fab")
		)
		(fp_line
			(start -0.2794 -0.1016)
			(end 0.2794 -0.1016)
			(stroke
				(width 0.1)
				(type default)
			)
			(layer "B.Fab")
		)
		(fp_line
			(start 0.2794 0.9906)
			(end -0.2794 0.9906)
			(stroke
				(width 0.1)
				(type default)
			)
			(layer "B.Fab")
		)
		(fp_line
			(start -0.2794 0.9906)
			(end -0.2794 -0.1016)
			(stroke
				(width 0.1)
				(type default)
			)
			(layer "B.Fab")
		)
		(pad "1" smd rect
			(at 0 0 270)
			(size 0.508 0.508)
			(layers "B.Cu" "B.Mask" "B.Paste")
			(net "SMB_PEHPCPU0_STBY_LVC3_R_SCL")
		)
		(pad "2" smd rect
			(at 0 0.889 270)
			(size 0.508 0.508)
			(layers "B.Cu" "B.Mask" "B.Paste")
			(net "SMB_PEHPCPU0_STBY_LVC3_R2_SCL")
		)
		(zone
			(layer "B.Cu")
			(hatch none 0.5)
			(connect_pads
				(clearance 0)
			)
			(min_thickness 0.25)
			(keepout
				(tracks allowed)
				(vias not_allowed)
				(pads allowed)
				(copperpour not_allowed)
				(footprints allowed)
			)
			(placement
				(enabled no)
				(sheetname "")
			)
			(fill
				(thermal_gap 0.5)
				(thermal_bridge_width 0.5)
				(island_removal_mode 0)
			)
			(polygon
				(pts
					(xy 405.612854 -35.34791) (xy 405.612854 -34.83991) (xy 405.993854 -34.83991) (xy 405.993854 -35.34791)
				)
			)
		)
		(zone
			(layer "B.Cu")
			(hatch none 0.5)
			(connect_pads
				(clearance 0)
			)
			(min_thickness 0.25)
			(keepout
				(tracks not_allowed)
				(vias allowed)
				(pads allowed)
				(copperpour not_allowed)
				(footprints allowed)
			)
			(placement
				(enabled no)
				(sheetname "")
			)
			(fill
				(thermal_gap 0.5)
				(thermal_bridge_width 0.5)
				(island_removal_mode 0)
			)
			(polygon
				(pts
					(xy 405.993854 -35.34791) (xy 405.993854 -34.83991) (xy 405.612854 -34.83991) (xy 405.612854 -35.34791)
				)
			)
		)
	)
	(footprint ""
		(layer "B.Cu")
		(at 355.736398 -77.915516)
		(property "Reference" "C3P34"
			(at 0 0 0)
			(layer "B.SilkS")
			(hide yes)
			(effects
				(font
					(size 1.27 1.27)
				)
				(justify mirror)
			)
		)
		(property "Value" ""
			(at 0 0 0)
			(layer "B.Fab")
			(effects
				(font
					(size 1.27 1.27)
				)
				(justify mirror)
			)
		)
		(duplicate_pad_numbers_are_jumpers no)
		(fp_poly
			(pts
				(xy -0.3048 -0.1016) (xy -0.3048 0.9906) (xy 0.3048 0.9906) (xy 0.3048 -0.1016)
			)
			(stroke
				(width 0)
				(type default)
			)
			(fill no)
			(layer "B.CrtYd")
		)
		(fp_line
			(start -0.3048 -0.1016)
			(end 0.3048 -0.1016)
			(stroke
				(width 0.1)
				(type default)
			)
			(layer "B.Fab")
		)
		(fp_line
			(start -0.3048 0.9906)
			(end -0.3048 -0.1016)
			(stroke
				(width 0.1)
				(type default)
			)
			(layer "B.Fab")
		)
		(fp_line
			(start 0.3048 -0.1016)
			(end 0.3048 0.9906)
			(stroke
				(width 0.1)
				(type default)
			)
			(layer "B.Fab")
		)
		(fp_line
			(start 0.3048 0.9906)
			(end -0.3048 0.9906)
			(stroke
				(width 0.1)
				(type default)
			)
			(layer "B.Fab")
		)
		(pad "1" smd rect
			(at 0 0 180)
			(size 0.508 0.508)
			(layers "B.Cu" "B.Mask" "B.Paste")
			(net "P3E_CPU0_PE1_SS_TXP<6>")
		)
		(pad "2" smd rect
			(at 0 0.889 180)
			(size 0.508 0.508)
			(layers "B.Cu" "B.Mask" "B.Paste")
			(net "P3E_CPU0_PE1_SS_C_TXP<6>")
		)
		(zone
			(layer "B.Cu")
			(hatch none 0.5)
			(connect_pads
				(clearance 0)
			)
			(min_thickness 0.25)
			(keepout
				(tracks allowed)
				(vias not_allowed)
				(pads allowed)
				(copperpour not_allowed)
				(footprints allowed)
			)
			(placement
				(enabled no)
				(sheetname "")
			)
			(fill
				(thermal_gap 0.5)
				(thermal_bridge_width 0.5)
				(island_removal_mode 0)
			)
			(polygon
				(pts
					(xy 355.990398 -77.661516) (xy 355.482398 -77.661516) (xy 355.482398 -77.280516) (xy 355.990398 -77.280516)
				)
			)
		)
		(zone
			(layer "B.Cu")
			(hatch none 0.5)
			(connect_pads
				(clearance 0)
			)
			(min_thickness 0.25)
			(keepout
				(tracks not_allowed)
				(vias allowed)
				(pads allowed)
				(copperpour not_allowed)
				(footprints allowed)
			)
			(placement
				(enabled no)
				(sheetname "")
			)
			(fill
				(thermal_gap 0.5)
				(thermal_bridge_width 0.5)
				(island_removal_mode 0)
			)
			(polygon
				(pts
					(xy 355.990398 -77.280516) (xy 355.482398 -77.280516) (xy 355.482398 -77.661516) (xy 355.990398 -77.661516)
				)
			)
		)
	)
	(footprint ""
		(layer "B.Cu")
		(at 455.549 -4.2164 90)
		(property "Reference" "R1U49"
			(at 0 0 90)
			(layer "B.SilkS")
			(hide yes)
			(effects
				(font
					(size 1.27 1.27)
				)
				(justify mirror)
			)
		)
		(property "Value" ""
			(at 0 0 90)
			(layer "B.Fab")
			(effects
				(font
					(size 1.27 1.27)
				)
				(justify mirror)
			)
		)
		(duplicate_pad_numbers_are_jumpers no)
		(fp_poly
			(pts
				(xy 0.2794 -0.1016) (xy -0.2794 -0.1016) (xy -0.2794 0.9906) (xy 0.2794 0.9906)
			)
			(stroke
				(width 0)
				(type default)
			)
			(fill no)
			(layer "B.CrtYd")
		)
		(fp_line
			(start 0.2794 -0.1016)
			(end 0.2794 0.9906)
			(stroke
				(width 0.1)
				(type default)
			)
			(layer "B.Fab")
		)
		(fp_line
			(start -0.2794 -0.1016)
			(end 0.2794 -0.1016)
			(stroke
				(width 0.1)
				(type default)
			)
			(layer "B.Fab")
		)
		(fp_line
			(start 0.2794 0.9906)
			(end -0.2794 0.9906)
			(stroke
				(width 0.1)
				(type default)
			)
			(layer "B.Fab")
		)
		(fp_line
			(start -0.2794 0.9906)
			(end -0.2794 -0.1016)
			(stroke
				(width 0.1)
				(type default)
			)
			(layer "B.Fab")
		)
		(pad "1" smd rect
			(at 0 0 270)
			(size 0.508 0.508)
			(layers "B.Cu" "B.Mask" "B.Paste")
			(net "P3V3_STBY")
		)
		(pad "2" smd rect
			(at 0 0.889 270)
			(size 0.508 0.508)
			(layers "B.Cu" "B.Mask" "B.Paste")
			(net "FM_BATTERY_SENSE_EN")
		)
		(zone
			(layer "B.Cu")
			(hatch none 0.5)
			(connect_pads
				(clearance 0)
			)
			(min_thickness 0.25)
			(keepout
				(tracks allowed)
				(vias not_allowed)
				(pads allowed)
				(copperpour not_allowed)
				(footprints allowed)
			)
			(placement
				(enabled no)
				(sheetname "")
			)
			(fill
				(thermal_gap 0.5)
				(thermal_bridge_width 0.5)
				(island_removal_mode 0)
			)
			(polygon
				(pts
					(xy 455.803 -4.4704) (xy 455.803 -3.9624) (xy 456.184 -3.9624) (xy 456.184 -4.4704)
				)
			)
		)
		(zone
			(layer "B.Cu")
			(hatch none 0.5)
			(connect_pads
				(clearance 0)
			)
			(min_thickness 0.25)
			(keepout
				(tracks not_allowed)
				(vias allowed)
				(pads allowed)
				(copperpour not_allowed)
				(footprints allowed)
			)
			(placement
				(enabled no)
				(sheetname "")
			)
			(fill
				(thermal_gap 0.5)
				(thermal_bridge_width 0.5)
				(island_removal_mode 0)
			)
			(polygon
				(pts
					(xy 456.184 -4.4704) (xy 456.184 -3.9624) (xy 455.803 -3.9624) (xy 455.803 -4.4704)
				)
			)
		)
	)
	(footprint ""
		(layer "B.Cu")
		(at 276.0472 -29.337 -90)
		(property "Reference" "SH4U2"
			(at 0 0 90)
			(layer "B.SilkS")
			(hide yes)
			(effects
				(font
					(size 1.27 1.27)
				)
				(justify mirror)
			)
		)
		(property "Value" ""
			(at 0 0 90)
			(layer "B.Fab")
			(effects
				(font
					(size 1.27 1.27)
				)
				(justify mirror)
			)
		)
		(duplicate_pad_numbers_are_jumpers no)
		(fp_poly
			(pts
				(xy 0.1651 -0.0508) (xy 0.1651 0.5842) (xy -0.1651 0.5842) (xy -0.1651 -0.0508)
			)
			(stroke
				(width 0)
				(type default)
			)
			(fill no)
			(layer "B.CrtYd")
		)
		(fp_line
			(start -0.1651 0.5842)
			(end 0.1651 0.5842)
			(stroke
				(width 0.1)
				(type default)
			)
			(layer "B.Fab")
		)
		(fp_line
			(start 0.1651 0.5842)
			(end 0.1651 -0.0508)
			(stroke
				(width 0.1)
				(type default)
			)
			(layer "B.Fab")
		)
		(fp_line
			(start -0.1651 -0.0508)
			(end -0.1651 0.5842)
			(stroke
				(width 0.1)
				(type default)
			)
			(layer "B.Fab")
		)
		(fp_line
			(start 0.1651 -0.0508)
			(end -0.1651 -0.0508)
			(stroke
				(width 0.1)
				(type default)
			)
			(layer "B.Fab")
		)
		(pad "1" smd custom
			(at 0 0 270)
			(size 0.0762 0.0762)
			(layers "B.Cu" "B.Mask" "B.Paste")
			(net "VSENSE_PVDDQ_ABC_P")
			(options
				(clearance outline)
				(anchor circle)
			)
			(primitives
				(gr_poly
					(pts
						(arc
							(start -0.1524 0.10795)
							(mid -0.098518 0.130268)
							(end -0.0762 0.18415)
						)
						(xy -0.0762 0.22225) (xy 0.0762 0.22225)
						(arc
							(start 0.0762 0.18415)
							(mid 0.098518 0.130268)
							(end 0.1524 0.10795)
						)
						(xy 0.1524 -0.22225) (xy -0.1524 -0.22225)
					)
					(width 0)
					(fill yes)
				)
			)
		)
		(pad "2" smd custom
			(at 0 0.5334 90)
			(size 0.0762 0.0762)
			(layers "B.Cu" "B.Mask" "B.Paste")
			(net "PVDDQ_ABC")
			(options
				(clearance outline)
				(anchor circle)
			)
			(primitives
				(gr_poly
					(pts
						(arc
							(start -0.1524 0.10795)
							(mid -0.098518 0.130268)
							(end -0.0762 0.18415)
						)
						(xy -0.0762 0.22225) (xy 0.0762 0.22225)
						(arc
							(start 0.0762 0.18415)
							(mid 0.098518 0.130268)
							(end 0.1524 0.10795)
						)
						(xy 0.1524 -0.22225) (xy -0.1524 -0.22225)
					)
					(width 0)
					(fill yes)
				)
			)
		)
	)
	(footprint ""
		(layer "B.Cu")
		(at 264.416286 -79.60614 180)
		(property "Reference" "C5P16"
			(at 0 0 0)
			(layer "B.SilkS")
			(hide yes)
			(effects
				(font
					(size 1.27 1.27)
				)
				(justify mirror)
			)
		)
		(property "Value" ""
			(at 0 0 0)
			(layer "B.Fab")
			(effects
				(font
					(size 1.27 1.27)
				)
				(justify mirror)
			)
		)
		(duplicate_pad_numbers_are_jumpers no)
		(fp_poly
			(pts
				(xy 0.7239 -0.2159) (xy -0.7239 -0.2159) (xy -0.7239 1.9939) (xy 0.7239 1.9939)
			)
			(stroke
				(width 0)
				(type default)
			)
			(fill no)
			(layer "B.CrtYd")
		)
		(fp_line
			(start 0.7239 1.9939)
			(end -0.7239 1.9939)
			(stroke
				(width 0.1)
				(type default)
			)
			(layer "B.Fab")
		)
		(fp_line
			(start 0.7239 -0.2159)
			(end 0.7239 1.9939)
			(stroke
				(width 0.1)
				(type default)
			)
			(layer "B.Fab")
		)
		(fp_line
			(start -0.7239 1.9939)
			(end -0.7239 -0.2159)
			(stroke
				(width 0.1)
				(type default)
			)
			(layer "B.Fab")
		)
		(fp_line
			(start -0.7239 -0.2159)
			(end 0.7239 -0.2159)
			(stroke
				(width 0.1)
				(type default)
			)
			(layer "B.Fab")
		)
		(pad "1" smd rect
			(at 0 0)
			(size 1.27 1.016)
			(layers "B.Cu" "B.Mask" "B.Paste")
			(net "PVCCIN_CPU0")
		)
		(pad "2" smd rect
			(at 0 1.778)
			(size 1.27 1.016)
			(layers "B.Cu" "B.Mask" "B.Paste")
			(net "GND")
		)
		(zone
			(layer "B.Cu")
			(hatch none 0.5)
			(connect_pads
				(clearance 0)
			)
			(min_thickness 0.25)
			(keepout
				(tracks not_allowed)
				(vias allowed)
				(pads allowed)
				(copperpour not_allowed)
				(footprints allowed)
			)
			(placement
				(enabled no)
				(sheetname "")
			)
			(fill
				(thermal_gap 0.5)
				(thermal_bridge_width 0.5)
				(island_removal_mode 0)
			)
			(polygon
				(pts
					(xy 263.781286 -80.11414) (xy 265.051286 -80.11414) (xy 265.051286 -80.87614) (xy 263.781286 -80.87614)
				)
			)
		)
	)
	(footprint ""
		(layer "B.Cu")
		(at 476.234506 -27.703018 180)
		(property "Reference" "C2T17"
			(at 0 0 0)
			(layer "B.SilkS")
			(hide yes)
			(effects
				(font
					(size 1.27 1.27)
				)
				(justify mirror)
			)
		)
		(property "Value" ""
			(at 0 0 0)
			(layer "B.Fab")
			(effects
				(font
					(size 1.27 1.27)
				)
				(justify mirror)
			)
		)
		(duplicate_pad_numbers_are_jumpers no)
		(fp_poly
			(pts
				(xy -0.3048 -0.1016) (xy -0.3048 0.9906) (xy 0.3048 0.9906) (xy 0.3048 -0.1016)
			)
			(stroke
				(width 0)
				(type default)
			)
			(fill no)
			(layer "B.CrtYd")
		)
		(fp_line
			(start 0.3048 0.9906)
			(end -0.3048 0.9906)
			(stroke
				(width 0.1)
				(type default)
			)
			(layer "B.Fab")
		)
		(fp_line
			(start 0.3048 -0.1016)
			(end 0.3048 0.9906)
			(stroke
				(width 0.1)
				(type default)
			)
			(layer "B.Fab")
		)
		(fp_line
			(start -0.3048 0.9906)
			(end -0.3048 -0.1016)
			(stroke
				(width 0.1)
				(type default)
			)
			(layer "B.Fab")
		)
		(fp_line
			(start -0.3048 -0.1016)
			(end 0.3048 -0.1016)
			(stroke
				(width 0.1)
				(type default)
			)
			(layer "B.Fab")
		)
		(pad "1" smd rect
			(at 0 0)
			(size 0.508 0.508)
			(layers "B.Cu" "B.Mask" "B.Paste")
			(net "P3V3_STBY_MNG")
		)
		(pad "2" smd rect
			(at 0 0.889)
			(size 0.508 0.508)
			(layers "B.Cu" "B.Mask" "B.Paste")
			(net "GND")
		)
		(zone
			(layer "B.Cu")
			(hatch none 0.5)
			(connect_pads
				(clearance 0)
			)
			(min_thickness 0.25)
			(keepout
				(tracks not_allowed)
				(vias allowed)
				(pads allowed)
				(copperpour not_allowed)
				(footprints allowed)
			)
			(placement
				(enabled no)
				(sheetname "")
			)
			(fill
				(thermal_gap 0.5)
				(thermal_bridge_width 0.5)
				(island_removal_mode 0)
			)
			(polygon
				(pts
					(xy 475.980506 -28.338018) (xy 476.488506 -28.338018) (xy 476.488506 -27.957018) (xy 475.980506 -27.957018)
				)
			)
		)
		(zone
			(layer "B.Cu")
			(hatch none 0.5)
			(connect_pads
				(clearance 0)
			)
			(min_thickness 0.25)
			(keepout
				(tracks allowed)
				(vias not_allowed)
				(pads allowed)
				(copperpour not_allowed)
				(footprints allowed)
			)
			(placement
				(enabled no)
				(sheetname "")
			)
			(fill
				(thermal_gap 0.5)
				(thermal_bridge_width 0.5)
				(island_removal_mode 0)
			)
			(polygon
				(pts
					(xy 475.980506 -27.957018) (xy 476.488506 -27.957018) (xy 476.488506 -28.338018) (xy 475.980506 -28.338018)
				)
			)
		)
	)
	(footprint ""
		(layer "B.Cu")
		(at 397.637 -88.2142)
		(property "Reference" "R8D4"
			(at 0 0 0)
			(layer "B.SilkS")
			(hide yes)
			(effects
				(font
					(size 1.27 1.27)
				)
				(justify mirror)
			)
		)
		(property "Value" ""
			(at 0 0 0)
			(layer "B.Fab")
			(effects
				(font
					(size 1.27 1.27)
				)
				(justify mirror)
			)
		)
		(duplicate_pad_numbers_are_jumpers no)
		(fp_poly
			(pts
				(xy 0.2794 -0.1016) (xy -0.2794 -0.1016) (xy -0.2794 0.9906) (xy 0.2794 0.9906)
			)
			(stroke
				(width 0)
				(type default)
			)
			(fill no)
			(layer "B.CrtYd")
		)
		(fp_line
			(start -0.2794 -0.1016)
			(end 0.2794 -0.1016)
			(stroke
				(width 0.1)
				(type default)
			)
			(layer "B.Fab")
		)
		(fp_line
			(start -0.2794 0.9906)
			(end -0.2794 -0.1016)
			(stroke
				(width 0.1)
				(type default)
			)
			(layer "B.Fab")
		)
		(fp_line
			(start 0.2794 -0.1016)
			(end 0.2794 0.9906)
			(stroke
				(width 0.1)
				(type default)
			)
			(layer "B.Fab")
		)
		(fp_line
			(start 0.2794 0.9906)
			(end -0.2794 0.9906)
			(stroke
				(width 0.1)
				(type default)
			)
			(layer "B.Fab")
		)
		(pad "1" smd rect
			(at 0 0 180)
			(size 0.508 0.508)
			(layers "B.Cu" "B.Mask" "B.Paste")
			(net "SMB_VR_STBY_LVC3_SCL_R1")
		)
		(pad "2" smd rect
			(at 0 0.889 180)
			(size 0.508 0.508)
			(layers "B.Cu" "B.Mask" "B.Paste")
			(net "SMB_VR_STBY_LVC3_SCL")
		)
		(zone
			(layer "B.Cu")
			(hatch none 0.5)
			(connect_pads
				(clearance 0)
			)
			(min_thickness 0.25)
			(keepout
				(tracks allowed)
				(vias not_allowed)
				(pads allowed)
				(copperpour not_allowed)
				(footprints allowed)
			)
			(placement
				(enabled no)
				(sheetname "")
			)
			(fill
				(thermal_gap 0.5)
				(thermal_bridge_width 0.5)
				(island_removal_mode 0)
			)
			(polygon
				(pts
					(xy 397.891 -87.9602) (xy 397.383 -87.9602) (xy 397.383 -87.5792) (xy 397.891 -87.5792)
				)
			)
		)
		(zone
			(layer "B.Cu")
			(hatch none 0.5)
			(connect_pads
				(clearance 0)
			)
			(min_thickness 0.25)
			(keepout
				(tracks not_allowed)
				(vias allowed)
				(pads allowed)
				(copperpour not_allowed)
				(footprints allowed)
			)
			(placement
				(enabled no)
				(sheetname "")
			)
			(fill
				(thermal_gap 0.5)
				(thermal_bridge_width 0.5)
				(island_removal_mode 0)
			)
			(polygon
				(pts
					(xy 397.891 -87.5792) (xy 397.383 -87.5792) (xy 397.383 -87.9602) (xy 397.891 -87.9602)
				)
			)
		)
	)
	(footprint ""
		(layer "B.Cu")
		(at 32.832802 -90.809064 90)
		(property "Reference" "C9N26"
			(at 0 0 90)
			(layer "B.SilkS")
			(hide yes)
			(effects
				(font
					(size 1.27 1.27)
				)
				(justify mirror)
			)
		)
		(property "Value" ""
			(at 0 0 90)
			(layer "B.Fab")
			(effects
				(font
					(size 1.27 1.27)
				)
				(justify mirror)
			)
		)
		(duplicate_pad_numbers_are_jumpers no)
		(fp_poly
			(pts
				(xy 0.7239 -0.2159) (xy -0.7239 -0.2159) (xy -0.7239 1.9939) (xy 0.7239 1.9939)
			)
			(stroke
				(width 0)
				(type default)
			)
			(fill no)
			(layer "B.CrtYd")
		)
		(fp_line
			(start 0.7239 -0.2159)
			(end 0.7239 1.9939)
			(stroke
				(width 0.1)
				(type default)
			)
			(layer "B.Fab")
		)
		(fp_line
			(start -0.7239 -0.2159)
			(end 0.7239 -0.2159)
			(stroke
				(width 0.1)
				(type default)
			)
			(layer "B.Fab")
		)
		(fp_line
			(start 0.7239 1.9939)
			(end -0.7239 1.9939)
			(stroke
				(width 0.1)
				(type default)
			)
			(layer "B.Fab")
		)
		(fp_line
			(start -0.7239 1.9939)
			(end -0.7239 -0.2159)
			(stroke
				(width 0.1)
				(type default)
			)
			(layer "B.Fab")
		)
		(pad "1" smd rect
			(at 0 0 270)
			(size 1.27 1.016)
			(layers "B.Cu" "B.Mask" "B.Paste")
			(net "VR_FET_SW_P12V_STBY_PVCCIN_CPU1")
		)
		(pad "2" smd rect
			(at 0 1.778 270)
			(size 1.27 1.016)
			(layers "B.Cu" "B.Mask" "B.Paste")
			(net "GND")
		)
		(zone
			(layer "B.Cu")
			(hatch none 0.5)
			(connect_pads
				(clearance 0)
			)
			(min_thickness 0.25)
			(keepout
				(tracks not_allowed)
				(vias allowed)
				(pads allowed)
				(copperpour not_allowed)
				(footprints allowed)
			)
			(placement
				(enabled no)
				(sheetname "")
			)
			(fill
				(thermal_gap 0.5)
				(thermal_bridge_width 0.5)
				(island_removal_mode 0)
			)
			(polygon
				(pts
					(xy 33.340802 -91.444064) (xy 33.340802 -90.174064) (xy 34.102802 -90.174064) (xy 34.102802 -91.444064)
				)
			)
		)
	)
	(footprint ""
		(layer "B.Cu")
		(at 356.08768 -94.072202 90)
		(property "Reference" "C22W31"
			(at 0 0 90)
			(layer "B.SilkS")
			(hide yes)
			(effects
				(font
					(size 1.27 1.27)
				)
				(justify mirror)
			)
		)
		(property "Value" "*"
			(at 0.0762 -6.2357 90)
			(unlocked yes)
			(layer "B.Fab")
			(hide yes)
			(effects
				(font
					(size 1.27 1.016)
					(thickness 0.1524)
				)
				(justify mirror)
			)
		)
		(property "Device Type" "SC22U16V5MX-4-GP_SMD-BCG5-SC22A"
			(at 0.0762 -8.2677 90)
			(unlocked yes)
			(layer "B.Fab")
			(hide yes)
			(effects
				(font
					(size 1.27 1.016)
					(thickness 0.1524)
				)
				(justify mirror)
			)
		)
		(duplicate_pad_numbers_are_jumpers no)
		(fp_line
			(start -0.635 0)
			(end 0.635 0)
			(stroke
				(width 0.508)
				(type default)
			)
			(layer "B.SilkS")
		)
		(fp_rect
			(start 0.9652 1.778)
			(end -0.9652 -1.778)
			(stroke
				(width 0)
				(type default)
			)
			(fill no)
			(layer "B.CrtYd")
		)
		(fp_poly
			(pts
				(xy 0.9652 -1.778) (xy -0.9652 -1.778) (xy -0.9652 1.778) (xy 0.9652 1.778)
			)
			(stroke
				(width 0)
				(type default)
			)
			(fill no)
			(layer "B.Fab")
		)
		(pad "1" smd rect
			(at 0 -0.9652 270)
			(size 1.397 1.143)
			(layers "B.Cu" "B.Mask" "B.Paste")
			(net "VR_FET_SW_P12V_STBY_PVCCIO_CPU0")
		)
		(pad "2" smd rect
			(at 0 0.9652 270)
			(size 1.397 1.143)
			(layers "B.Cu" "B.Mask" "B.Paste")
			(net "GND")
		)
	)
	(footprint ""
		(layer "B.Cu")
		(at 351.2312 -85.1408 90)
		(property "Reference" "C3P7"
			(at 0 0 90)
			(layer "B.SilkS")
			(hide yes)
			(effects
				(font
					(size 1.27 1.27)
				)
				(justify mirror)
			)
		)
		(property "Value" ""
			(at 0 0 90)
			(layer "B.Fab")
			(effects
				(font
					(size 1.27 1.27)
				)
				(justify mirror)
			)
		)
		(duplicate_pad_numbers_are_jumpers no)
		(fp_poly
			(pts
				(xy -0.3048 -0.1016) (xy -0.3048 0.9906) (xy 0.3048 0.9906) (xy 0.3048 -0.1016)
			)
			(stroke
				(width 0)
				(type default)
			)
			(fill no)
			(layer "B.CrtYd")
		)
		(fp_line
			(start 0.3048 -0.1016)
			(end 0.3048 0.9906)
			(stroke
				(width 0.1)
				(type default)
			)
			(layer "B.Fab")
		)
		(fp_line
			(start -0.3048 -0.1016)
			(end 0.3048 -0.1016)
			(stroke
				(width 0.1)
				(type default)
			)
			(layer "B.Fab")
		)
		(fp_line
			(start 0.3048 0.9906)
			(end -0.3048 0.9906)
			(stroke
				(width 0.1)
				(type default)
			)
			(layer "B.Fab")
		)
		(fp_line
			(start -0.3048 0.9906)
			(end -0.3048 -0.1016)
			(stroke
				(width 0.1)
				(type default)
			)
			(layer "B.Fab")
		)
		(pad "1" smd rect
			(at 0 0 270)
			(size 0.508 0.508)
			(layers "B.Cu" "B.Mask" "B.Paste")
			(net "VR_PVCCIO_CPU0_VDD")
		)
		(pad "2" smd rect
			(at 0 0.889 270)
			(size 0.508 0.508)
			(layers "B.Cu" "B.Mask" "B.Paste")
			(net "GND")
		)
		(zone
			(layer "B.Cu")
			(hatch none 0.5)
			(connect_pads
				(clearance 0)
			)
			(min_thickness 0.25)
			(keepout
				(tracks allowed)
				(vias not_allowed)
				(pads allowed)
				(copperpour not_allowed)
				(footprints allowed)
			)
			(placement
				(enabled no)
				(sheetname "")
			)
			(fill
				(thermal_gap 0.5)
				(thermal_bridge_width 0.5)
				(island_removal_mode 0)
			)
			(polygon
				(pts
					(xy 351.4852 -85.3948) (xy 351.4852 -84.8868) (xy 351.8662 -84.8868) (xy 351.8662 -85.3948)
				)
			)
		)
		(zone
			(layer "B.Cu")
			(hatch none 0.5)
			(connect_pads
				(clearance 0)
			)
			(min_thickness 0.25)
			(keepout
				(tracks not_allowed)
				(vias allowed)
				(pads allowed)
				(copperpour not_allowed)
				(footprints allowed)
			)
			(placement
				(enabled no)
				(sheetname "")
			)
			(fill
				(thermal_gap 0.5)
				(thermal_bridge_width 0.5)
				(island_removal_mode 0)
			)
			(polygon
				(pts
					(xy 351.8662 -85.3948) (xy 351.8662 -84.8868) (xy 351.4852 -84.8868) (xy 351.4852 -85.3948)
				)
			)
		)
	)
	(footprint ""
		(layer "B.Cu")
		(at 197.848728 -92.489782 90)
		(property "Reference" "C6N8"
			(at 0 0 90)
			(layer "B.SilkS")
			(hide yes)
			(effects
				(font
					(size 1.27 1.27)
				)
				(justify mirror)
			)
		)
		(property "Value" ""
			(at 0 0 90)
			(layer "B.Fab")
			(effects
				(font
					(size 1.27 1.27)
				)
				(justify mirror)
			)
		)
		(duplicate_pad_numbers_are_jumpers no)
		(fp_rect
			(start -0.7239 -0.2159)
			(end 0.7239 1.9939)
			(stroke
				(width 0)
				(type default)
			)
			(fill no)
			(layer "B.CrtYd")
		)
		(fp_line
			(start 0.7239 -0.2159)
			(end 0.7239 1.9939)
			(stroke
				(width 0.1)
				(type default)
			)
			(layer "B.Fab")
		)
		(fp_line
			(start -0.7239 -0.2159)
			(end 0.7239 -0.2159)
			(stroke
				(width 0.1)
				(type default)
			)
			(layer "B.Fab")
		)
		(fp_line
			(start 0.7239 1.9939)
			(end -0.7239 1.9939)
			(stroke
				(width 0.1)
				(type default)
			)
			(layer "B.Fab")
		)
		(fp_line
			(start -0.7239 1.9939)
			(end -0.7239 -0.2159)
			(stroke
				(width 0.1)
				(type default)
			)
			(layer "B.Fab")
		)
		(pad "1" smd rect
			(at 0 0 270)
			(size 1.27 1.016)
			(layers "B.Cu" "B.Mask" "B.Paste")
			(net "VR_FET_SW_P12V_STBY_PVCCIN_CPU0")
		)
		(pad "2" smd rect
			(at 0 1.778 270)
			(size 1.27 1.016)
			(layers "B.Cu" "B.Mask" "B.Paste")
			(net "GND")
		)
		(zone
			(layer "B.Cu")
			(hatch none 0.5)
			(connect_pads
				(clearance 0)
			)
			(min_thickness 0.25)
			(keepout
				(tracks not_allowed)
				(vias allowed)
				(pads allowed)
				(copperpour not_allowed)
				(footprints allowed)
			)
			(placement
				(enabled no)
				(sheetname "")
			)
			(fill
				(thermal_gap 0.5)
				(thermal_bridge_width 0.5)
				(island_removal_mode 0)
			)
			(polygon
				(pts
					(xy 198.356728 -91.854782) (xy 199.118728 -91.854782) (xy 199.118728 -93.124782) (xy 198.356728 -93.124782)
				)
			)
		)
	)
	(footprint ""
		(layer "B.Cu")
		(at 245.7196 -27.2034 90)
		(property "Reference" "C5T2"
			(at 0 0 90)
			(layer "B.SilkS")
			(hide yes)
			(effects
				(font
					(size 1.27 1.27)
				)
				(justify mirror)
			)
		)
		(property "Value" ""
			(at 0 0 90)
			(layer "B.Fab")
			(effects
				(font
					(size 1.27 1.27)
				)
				(justify mirror)
			)
		)
		(duplicate_pad_numbers_are_jumpers no)
		(fp_rect
			(start 0.500126 1.598422)
			(end -0.500126 -0.201422)
			(stroke
				(width 0)
				(type default)
			)
			(fill no)
			(layer "B.CrtYd")
		)
		(fp_line
			(start 0.500126 -0.201422)
			(end -0.500126 -0.201422)
			(stroke
				(width 0.1)
				(type default)
			)
			(layer "B.Fab")
		)
		(fp_line
			(start -0.500126 -0.201422)
			(end -0.500126 1.598422)
			(stroke
				(width 0.1)
				(type default)
			)
			(layer "B.Fab")
		)
		(fp_line
			(start 0.500126 1.598422)
			(end 0.500126 -0.201422)
			(stroke
				(width 0.1)
				(type default)
			)
			(layer "B.Fab")
		)
		(fp_line
			(start -0.500126 1.598422)
			(end 0.500126 1.598422)
			(stroke
				(width 0.1)
				(type default)
			)
			(layer "B.Fab")
		)
		(pad "1" smd rect
			(at 0 0)
			(size 0.889 0.9906)
			(layers "B.Cu" "B.Mask" "B.Paste")
			(net "PVDDQ_ABC")
		)
		(pad "2" smd rect
			(at 0 1.397)
			(size 0.889 0.9906)
			(layers "B.Cu" "B.Mask" "B.Paste")
			(net "GND")
		)
		(zone
			(layer "B.Cu")
			(hatch none 0.5)
			(connect_pads
				(clearance 0)
			)
			(min_thickness 0.25)
			(keepout
				(tracks not_allowed)
				(vias allowed)
				(pads allowed)
				(copperpour not_allowed)
				(footprints allowed)
			)
			(placement
				(enabled no)
				(sheetname "")
			)
			(fill
				(thermal_gap 0.5)
				(thermal_bridge_width 0.5)
				(island_removal_mode 0)
			)
			(polygon
				(pts
					(xy 246.6721 -27.6987) (xy 246.1641 -27.6987) (xy 246.1641 -26.7081) (xy 246.6721 -26.7081)
				)
			)
		)
		(zone
			(layer "B.Cu")
			(hatch none 0.5)
			(connect_pads
				(clearance 0)
			)
			(min_thickness 0.25)
			(keepout
				(tracks allowed)
				(vias not_allowed)
				(pads allowed)
				(copperpour not_allowed)
				(footprints allowed)
			)
			(placement
				(enabled no)
				(sheetname "")
			)
			(fill
				(thermal_gap 0.5)
				(thermal_bridge_width 0.5)
				(island_removal_mode 0)
			)
			(polygon
				(pts
					(xy 246.6721 -27.6987) (xy 246.1641 -27.6987) (xy 246.1641 -26.7081) (xy 246.6721 -26.7081)
				)
			)
		)
	)
	(footprint ""
		(layer "B.Cu")
		(at 329.356466 -57.916318)
		(property "Reference" "U4R1"
			(at -2.794 0.87503 0)
			(unlocked yes)
			(layer "B.SilkS")
			(effects
				(font
					(size 0.7874 0.5842)
					(thickness 0.1524)
				)
				(justify left mirror)
			)
		)
		(property "Value" ""
			(at 0 0 0)
			(layer "B.Fab")
			(effects
				(font
					(size 1.27 1.27)
				)
				(justify mirror)
			)
		)
		(duplicate_pad_numbers_are_jumpers no)
		(fp_circle
			(center 0.4699 -0.8382)
			(end 0.5969 -0.8382)
			(stroke
				(width 0.254)
				(type default)
			)
			(fill no)
			(layer "B.SilkS")
		)
		(fp_poly
			(pts
				(xy -0.21463 -0.450088) (xy -1.56337 -0.450088) (xy -1.56337 1.75006) (xy -0.21463 1.75006)
			)
			(stroke
				(width 0)
				(type default)
			)
			(fill no)
			(layer "B.CrtYd")
		)
		(fp_line
			(start -1.56337 -0.450088)
			(end -1.56337 1.75006)
			(stroke
				(width 0.1)
				(type default)
			)
			(layer "B.Fab")
		)
		(fp_line
			(start -1.56337 1.75006)
			(end -0.21463 1.75006)
			(stroke
				(width 0.1)
				(type default)
			)
			(layer "B.Fab")
		)
		(fp_line
			(start -0.21463 -0.450088)
			(end -1.56337 -0.450088)
			(stroke
				(width 0.1)
				(type default)
			)
			(layer "B.Fab")
		)
		(fp_line
			(start -0.21463 1.75006)
			(end -0.21463 -0.450088)
			(stroke
				(width 0.1)
				(type default)
			)
			(layer "B.Fab")
		)
		(fp_circle
			(center 0.4699 -0.8382)
			(end 0.5969 -0.8382)
			(stroke
				(width 0.254)
				(type default)
			)
			(fill no)
			(layer "B.Fab")
		)
		(pad "1" smd rect
			(at 0 0 180)
			(size 1.016 0.381)
			(layers "B.Cu" "B.Mask" "B.Paste")
			(net "FM_CPU0_PKGID1")
		)
		(pad "2" smd rect
			(at 0 0.649986 180)
			(size 1.016 0.381)
			(layers "B.Cu" "B.Mask" "B.Paste")
			(net "P1V8_MCP_CPU0")
		)
		(pad "3" smd rect
			(at 0 1.299972 180)
			(size 1.016 0.381)
			(layers "B.Cu" "B.Mask" "B.Paste")
			(net "GND")
		)
		(pad "4" smd rect
			(at -1.778 1.299972 180)
			(size 1.016 0.381)
			(layers "B.Cu" "B.Mask" "B.Paste")
			(net "JTAG_MCP_CPU0_TDI_R")
		)
		(pad "5" smd rect
			(at -1.778 0 180)
			(size 1.016 0.381)
			(layers "B.Cu" "B.Mask" "B.Paste")
			(net "P3V3_STBY")
		)
	)
	(footprint ""
		(layer "B.Cu")
		(at 180.873654 -150.815548)
		(property "Reference" "C6L4"
			(at 0 0 0)
			(layer "B.SilkS")
			(hide yes)
			(effects
				(font
					(size 1.27 1.27)
				)
				(justify mirror)
			)
		)
		(property "Value" ""
			(at 0 0 0)
			(layer "B.Fab")
			(effects
				(font
					(size 1.27 1.27)
				)
				(justify mirror)
			)
		)
		(duplicate_pad_numbers_are_jumpers no)
		(fp_rect
			(start 0.4953 -0.2032)
			(end -0.4953 1.6002)
			(stroke
				(width 0)
				(type default)
			)
			(fill no)
			(layer "B.CrtYd")
		)
		(fp_line
			(start -0.4953 -0.2032)
			(end -0.4953 1.6002)
			(stroke
				(width 0.1)
				(type default)
			)
			(layer "B.Fab")
		)
		(fp_line
			(start -0.4953 1.6002)
			(end 0.4953 1.6002)
			(stroke
				(width 0.1)
				(type default)
			)
			(layer "B.Fab")
		)
		(fp_line
			(start 0.4953 -0.2032)
			(end -0.4953 -0.2032)
			(stroke
				(width 0.1)
				(type default)
			)
			(layer "B.Fab")
		)
		(fp_line
			(start 0.4953 1.6002)
			(end 0.4953 -0.2032)
			(stroke
				(width 0.1)
				(type default)
			)
			(layer "B.Fab")
		)
		(pad "1" smd rect
			(at 0 0 180)
			(size 0.762 0.889)
			(layers "B.Cu" "B.Mask" "B.Paste")
			(net "PVDDQ_DEF")
		)
		(pad "2" smd rect
			(at 0 1.397 180)
			(size 0.762 0.889)
			(layers "B.Cu" "B.Mask" "B.Paste")
			(net "GND")
		)
		(zone
			(layer "B.Cu")
			(hatch none 0.5)
			(connect_pads
				(clearance 0)
			)
			(min_thickness 0.25)
			(keepout
				(tracks not_allowed)
				(vias allowed)
				(pads allowed)
				(copperpour not_allowed)
				(footprints allowed)
			)
			(placement
				(enabled no)
				(sheetname "")
			)
			(fill
				(thermal_gap 0.5)
				(thermal_bridge_width 0.5)
				(island_removal_mode 0)
			)
			(polygon
				(pts
					(xy 181.254654 -150.371048) (xy 180.492654 -150.371048) (xy 180.492654 -149.863048) (xy 181.254654 -149.863048)
				)
			)
		)
	)
	(footprint ""
		(layer "B.Cu")
		(at 438.604406 -33.101026 90)
		(property "Reference" "R1T28"
			(at 0.8382 -0.67818 90)
			(unlocked yes)
			(layer "B.SilkS")
			(effects
				(font
					(size 0.4064 0.254)
					(thickness 0.1524)
				)
				(justify left mirror)
			)
		)
		(property "Value" ""
			(at 0 0 90)
			(layer "B.Fab")
			(effects
				(font
					(size 1.27 1.27)
				)
				(justify mirror)
			)
		)
		(duplicate_pad_numbers_are_jumpers no)
		(fp_poly
			(pts
				(xy 0.2794 -0.1016) (xy -0.2794 -0.1016) (xy -0.2794 0.9906) (xy 0.2794 0.9906)
			)
			(stroke
				(width 0)
				(type default)
			)
			(fill no)
			(layer "B.CrtYd")
		)
		(fp_line
			(start 0.2794 -0.1016)
			(end 0.2794 0.9906)
			(stroke
				(width 0.1)
				(type default)
			)
			(layer "B.Fab")
		)
		(fp_line
			(start -0.2794 -0.1016)
			(end 0.2794 -0.1016)
			(stroke
				(width 0.1)
				(type default)
			)
			(layer "B.Fab")
		)
		(fp_line
			(start 0.2794 0.9906)
			(end -0.2794 0.9906)
			(stroke
				(width 0.1)
				(type default)
			)
			(layer "B.Fab")
		)
		(fp_line
			(start -0.2794 0.9906)
			(end -0.2794 -0.1016)
			(stroke
				(width 0.1)
				(type default)
			)
			(layer "B.Fab")
		)
		(pad "1" smd rect
			(at 0 0 270)
			(size 0.508 0.508)
			(layers "B.Cu" "B.Mask" "B.Paste")
			(net "BMC_M_CLK_DN")
		)
		(pad "2" smd rect
			(at 0 0.889 270)
			(size 0.508 0.508)
			(layers "B.Cu" "B.Mask" "B.Paste")
			(net "BMC_M_CLK")
		)
		(zone
			(layer "B.Cu")
			(hatch none 0.5)
			(connect_pads
				(clearance 0)
			)
			(min_thickness 0.25)
			(keepout
				(tracks allowed)
				(vias not_allowed)
				(pads allowed)
				(copperpour not_allowed)
				(footprints allowed)
			)
			(placement
				(enabled no)
				(sheetname "")
			)
			(fill
				(thermal_gap 0.5)
				(thermal_bridge_width 0.5)
				(island_removal_mode 0)
			)
			(polygon
				(pts
					(xy 438.858406 -33.355026) (xy 438.858406 -32.847026) (xy 439.239406 -32.847026) (xy 439.239406 -33.355026)
				)
			)
		)
		(zone
			(layer "B.Cu")
			(hatch none 0.5)
			(connect_pads
				(clearance 0)
			)
			(min_thickness 0.25)
			(keepout
				(tracks not_allowed)
				(vias allowed)
				(pads allowed)
				(copperpour not_allowed)
				(footprints allowed)
			)
			(placement
				(enabled no)
				(sheetname "")
			)
			(fill
				(thermal_gap 0.5)
				(thermal_bridge_width 0.5)
				(island_removal_mode 0)
			)
			(polygon
				(pts
					(xy 439.239406 -33.355026) (xy 439.239406 -32.847026) (xy 438.858406 -32.847026) (xy 438.858406 -33.355026)
				)
			)
		)
	)
	(footprint ""
		(layer "B.Cu")
		(at 423.387774 -40.982646 180)
		(property "Reference" "C25W58"
			(at 0.8382 -0.67818 180)
			(unlocked yes)
			(layer "B.SilkS")
			(effects
				(font
					(size 0.4064 0.254)
					(thickness 0.1524)
				)
				(justify left mirror)
			)
		)
		(property "Value" ""
			(at 0 0 0)
			(layer "B.Fab")
			(effects
				(font
					(size 1.27 1.27)
				)
				(justify mirror)
			)
		)
		(duplicate_pad_numbers_are_jumpers no)
		(fp_poly
			(pts
				(xy -0.3048 -0.1016) (xy -0.3048 0.9906) (xy 0.3048 0.9906) (xy 0.3048 -0.1016)
			)
			(stroke
				(width 0)
				(type default)
			)
			(fill no)
			(layer "B.CrtYd")
		)
		(fp_line
			(start 0.3048 0.9906)
			(end -0.3048 0.9906)
			(stroke
				(width 0.1)
				(type default)
			)
			(layer "B.Fab")
		)
		(fp_line
			(start 0.3048 -0.1016)
			(end 0.3048 0.9906)
			(stroke
				(width 0.1)
				(type default)
			)
			(layer "B.Fab")
		)
		(fp_line
			(start -0.3048 0.9906)
			(end -0.3048 -0.1016)
			(stroke
				(width 0.1)
				(type default)
			)
			(layer "B.Fab")
		)
		(fp_line
			(start -0.3048 -0.1016)
			(end 0.3048 -0.1016)
			(stroke
				(width 0.1)
				(type default)
			)
			(layer "B.Fab")
		)
		(pad "1" smd rect
			(at 0 0)
			(size 0.508 0.508)
			(layers "B.Cu" "B.Mask" "B.Paste")
			(net "VCC_PA_3V3")
		)
		(pad "2" smd rect
			(at 0 0.889)
			(size 0.508 0.508)
			(layers "B.Cu" "B.Mask" "B.Paste")
			(net "GND")
		)
		(zone
			(layer "B.Cu")
			(hatch none 0.5)
			(connect_pads
				(clearance 0)
			)
			(min_thickness 0.25)
			(keepout
				(tracks not_allowed)
				(vias allowed)
				(pads allowed)
				(copperpour not_allowed)
				(footprints allowed)
			)
			(placement
				(enabled no)
				(sheetname "")
			)
			(fill
				(thermal_gap 0.5)
				(thermal_bridge_width 0.5)
				(island_removal_mode 0)
			)
			(polygon
				(pts
					(xy 423.133774 -41.617646) (xy 423.641774 -41.617646) (xy 423.641774 -41.236646) (xy 423.133774 -41.236646)
				)
			)
		)
		(zone
			(layer "B.Cu")
			(hatch none 0.5)
			(connect_pads
				(clearance 0)
			)
			(min_thickness 0.25)
			(keepout
				(tracks allowed)
				(vias not_allowed)
				(pads allowed)
				(copperpour not_allowed)
				(footprints allowed)
			)
			(placement
				(enabled no)
				(sheetname "")
			)
			(fill
				(thermal_gap 0.5)
				(thermal_bridge_width 0.5)
				(island_removal_mode 0)
			)
			(polygon
				(pts
					(xy 423.133774 -41.236646) (xy 423.641774 -41.236646) (xy 423.641774 -41.617646) (xy 423.133774 -41.617646)
				)
			)
		)
	)
	(footprint ""
		(layer "B.Cu")
		(at 370.986558 -40.617648 90)
		(property "Reference" "R2T57"
			(at 0 0 90)
			(layer "B.SilkS")
			(hide yes)
			(effects
				(font
					(size 1.27 1.27)
				)
				(justify mirror)
			)
		)
		(property "Value" ""
			(at 0 0 90)
			(layer "B.Fab")
			(effects
				(font
					(size 1.27 1.27)
				)
				(justify mirror)
			)
		)
		(duplicate_pad_numbers_are_jumpers no)
		(fp_poly
			(pts
				(xy 0.2794 -0.1016) (xy -0.2794 -0.1016) (xy -0.2794 0.9906) (xy 0.2794 0.9906)
			)
			(stroke
				(width 0)
				(type default)
			)
			(fill no)
			(layer "B.CrtYd")
		)
		(fp_line
			(start 0.2794 -0.1016)
			(end 0.2794 0.9906)
			(stroke
				(width 0.1)
				(type default)
			)
			(layer "B.Fab")
		)
		(fp_line
			(start -0.2794 -0.1016)
			(end 0.2794 -0.1016)
			(stroke
				(width 0.1)
				(type default)
			)
			(layer "B.Fab")
		)
		(fp_line
			(start 0.2794 0.9906)
			(end -0.2794 0.9906)
			(stroke
				(width 0.1)
				(type default)
			)
			(layer "B.Fab")
		)
		(fp_line
			(start -0.2794 0.9906)
			(end -0.2794 -0.1016)
			(stroke
				(width 0.1)
				(type default)
			)
			(layer "B.Fab")
		)
		(pad "1" smd rect
			(at 0 0 270)
			(size 0.508 0.508)
			(layers "B.Cu" "B.Mask" "B.Paste")
			(net "H_CPU_ERR0_PCH_N")
		)
		(pad "2" smd rect
			(at 0 0.889 270)
			(size 0.508 0.508)
			(layers "B.Cu" "B.Mask" "B.Paste")
			(net "H_CPU_ERR0_GTL_R_N")
		)
		(zone
			(layer "B.Cu")
			(hatch none 0.5)
			(connect_pads
				(clearance 0)
			)
			(min_thickness 0.25)
			(keepout
				(tracks allowed)
				(vias not_allowed)
				(pads allowed)
				(copperpour not_allowed)
				(footprints allowed)
			)
			(placement
				(enabled no)
				(sheetname "")
			)
			(fill
				(thermal_gap 0.5)
				(thermal_bridge_width 0.5)
				(island_removal_mode 0)
			)
			(polygon
				(pts
					(xy 371.240558 -40.871648) (xy 371.240558 -40.363648) (xy 371.621558 -40.363648) (xy 371.621558 -40.871648)
				)
			)
		)
		(zone
			(layer "B.Cu")
			(hatch none 0.5)
			(connect_pads
				(clearance 0)
			)
			(min_thickness 0.25)
			(keepout
				(tracks not_allowed)
				(vias allowed)
				(pads allowed)
				(copperpour not_allowed)
				(footprints allowed)
			)
			(placement
				(enabled no)
				(sheetname "")
			)
			(fill
				(thermal_gap 0.5)
				(thermal_bridge_width 0.5)
				(island_removal_mode 0)
			)
			(polygon
				(pts
					(xy 371.621558 -40.871648) (xy 371.621558 -40.363648) (xy 371.240558 -40.363648) (xy 371.240558 -40.871648)
				)
			)
		)
	)
	(footprint ""
		(layer "B.Cu")
		(at 382.27 -87.3125 180)
		(property "Reference" "R7D6"
			(at 0 0 0)
			(layer "B.SilkS")
			(hide yes)
			(effects
				(font
					(size 1.27 1.27)
				)
				(justify mirror)
			)
		)
		(property "Value" ""
			(at 0 0 0)
			(layer "B.Fab")
			(effects
				(font
					(size 1.27 1.27)
				)
				(justify mirror)
			)
		)
		(duplicate_pad_numbers_are_jumpers no)
		(fp_poly
			(pts
				(xy 0.2794 -0.1016) (xy -0.2794 -0.1016) (xy -0.2794 0.9906) (xy 0.2794 0.9906)
			)
			(stroke
				(width 0)
				(type default)
			)
			(fill no)
			(layer "B.CrtYd")
		)
		(fp_line
			(start 0.2794 0.9906)
			(end -0.2794 0.9906)
			(stroke
				(width 0.1)
				(type default)
			)
			(layer "B.Fab")
		)
		(fp_line
			(start 0.2794 -0.1016)
			(end 0.2794 0.9906)
			(stroke
				(width 0.1)
				(type default)
			)
			(layer "B.Fab")
		)
		(fp_line
			(start -0.2794 0.9906)
			(end -0.2794 -0.1016)
			(stroke
				(width 0.1)
				(type default)
			)
			(layer "B.Fab")
		)
		(fp_line
			(start -0.2794 -0.1016)
			(end 0.2794 -0.1016)
			(stroke
				(width 0.1)
				(type default)
			)
			(layer "B.Fab")
		)
		(pad "1" smd rect
			(at 0 0)
			(size 0.508 0.508)
			(layers "B.Cu" "B.Mask" "B.Paste")
			(net "P3V3_STBY")
		)
		(pad "2" smd rect
			(at 0 0.889)
			(size 0.508 0.508)
			(layers "B.Cu" "B.Mask" "B.Paste")
			(net "FM_BMC_READY_N")
		)
		(zone
			(layer "B.Cu")
			(hatch none 0.5)
			(connect_pads
				(clearance 0)
			)
			(min_thickness 0.25)
			(keepout
				(tracks not_allowed)
				(vias allowed)
				(pads allowed)
				(copperpour not_allowed)
				(footprints allowed)
			)
			(placement
				(enabled no)
				(sheetname "")
			)
			(fill
				(thermal_gap 0.5)
				(thermal_bridge_width 0.5)
				(island_removal_mode 0)
			)
			(polygon
				(pts
					(xy 382.016 -87.9475) (xy 382.524 -87.9475) (xy 382.524 -87.5665) (xy 382.016 -87.5665)
				)
			)
		)
		(zone
			(layer "B.Cu")
			(hatch none 0.5)
			(connect_pads
				(clearance 0)
			)
			(min_thickness 0.25)
			(keepout
				(tracks allowed)
				(vias not_allowed)
				(pads allowed)
				(copperpour not_allowed)
				(footprints allowed)
			)
			(placement
				(enabled no)
				(sheetname "")
			)
			(fill
				(thermal_gap 0.5)
				(thermal_bridge_width 0.5)
				(island_removal_mode 0)
			)
			(polygon
				(pts
					(xy 382.016 -87.5665) (xy 382.524 -87.5665) (xy 382.524 -87.9475) (xy 382.016 -87.9475)
				)
			)
		)
	)
	(footprint ""
		(layer "B.Cu")
		(at 370.967 -152.019 90)
		(property "Reference" "C22W24"
			(at 0 0 90)
			(layer "B.SilkS")
			(hide yes)
			(effects
				(font
					(size 1.27 1.27)
				)
				(justify mirror)
			)
		)
		(property "Value" "*"
			(at 0.0762 -6.2357 90)
			(unlocked yes)
			(layer "B.Fab")
			(hide yes)
			(effects
				(font
					(size 1.27 1.016)
					(thickness 0.1524)
				)
				(justify mirror)
			)
		)
		(property "Device Type" "SC22U16V5MX-4-GP_SMD-BCG5-SC22A"
			(at 0.0762 -8.2677 90)
			(unlocked yes)
			(layer "B.Fab")
			(hide yes)
			(effects
				(font
					(size 1.27 1.016)
					(thickness 0.1524)
				)
				(justify mirror)
			)
		)
		(duplicate_pad_numbers_are_jumpers no)
		(fp_line
			(start -0.635 0)
			(end 0.635 0)
			(stroke
				(width 0.508)
				(type default)
			)
			(layer "B.SilkS")
		)
		(fp_rect
			(start 0.9652 1.778)
			(end -0.9652 -1.778)
			(stroke
				(width 0)
				(type default)
			)
			(fill no)
			(layer "B.CrtYd")
		)
		(fp_poly
			(pts
				(xy 0.9652 -1.778) (xy -0.9652 -1.778) (xy -0.9652 1.778) (xy 0.9652 1.778)
			)
			(stroke
				(width 0)
				(type default)
			)
			(fill no)
			(layer "B.Fab")
		)
		(pad "1" smd rect
			(at 0 -0.9652 270)
			(size 1.397 1.143)
			(layers "B.Cu" "B.Mask" "B.Paste")
			(net "VR_FET_SW_P12V_STBY_PVDDQ_DEF")
		)
		(pad "2" smd rect
			(at 0 0.9652 270)
			(size 1.397 1.143)
			(layers "B.Cu" "B.Mask" "B.Paste")
			(net "GND")
		)
	)
	(footprint ""
		(layer "B.Cu")
		(at 391.18794 -139.66698 180)
		(property "Reference" "C2L25"
			(at -3.10007 3.24612 270)
			(unlocked yes)
			(layer "B.SilkS")
			(effects
				(font
					(size 0.7874 0.5842)
					(thickness 0.1524)
				)
				(justify mirror)
			)
		)
		(property "Value" ""
			(at 0 0 0)
			(layer "B.Fab")
			(effects
				(font
					(size 1.27 1.27)
				)
				(justify mirror)
			)
		)
		(duplicate_pad_numbers_are_jumpers no)
		(fp_line
			(start 2.563114 1.633728)
			(end 1.6002 1.633728)
			(stroke
				(width 0.1524)
				(type default)
			)
			(layer "B.SilkS")
		)
		(fp_line
			(start 2.563114 -1.616456)
			(end 2.563114 1.633728)
			(stroke
				(width 0.1524)
				(type default)
			)
			(layer "B.SilkS")
		)
		(fp_line
			(start 2.286 7.366)
			(end 2.286 1.632712)
			(stroke
				(width 0.1524)
				(type default)
			)
			(layer "B.SilkS")
		)
		(fp_line
			(start 2.286 7.366)
			(end 1.60147 7.366)
			(stroke
				(width 0.1524)
				(type default)
			)
			(layer "B.SilkS")
		)
		(fp_line
			(start 1.6002 -1.616456)
			(end 2.563114 -1.616456)
			(stroke
				(width 0.1524)
				(type default)
			)
			(layer "B.SilkS")
		)
		(fp_line
			(start -1.6002 -1.616456)
			(end -2.504948 -1.616456)
			(stroke
				(width 0.1524)
				(type default)
			)
			(layer "B.SilkS")
		)
		(fp_line
			(start -2.286 7.366)
			(end -1.600708 7.366)
			(stroke
				(width 0.1524)
				(type default)
			)
			(layer "B.SilkS")
		)
		(fp_line
			(start -2.286 7.366)
			(end -2.286 1.63195)
			(stroke
				(width 0.1524)
				(type default)
			)
			(layer "B.SilkS")
		)
		(fp_line
			(start -2.504948 1.633728)
			(end -1.6002 1.633728)
			(stroke
				(width 0.1524)
				(type default)
			)
			(layer "B.SilkS")
		)
		(fp_line
			(start -2.504948 -1.616456)
			(end -2.504948 1.633728)
			(stroke
				(width 0.1524)
				(type default)
			)
			(layer "B.SilkS")
		)
		(fp_rect
			(start 2.286 7.366)
			(end -2.286 -0.254)
			(stroke
				(width 0)
				(type default)
			)
			(fill no)
			(layer "B.CrtYd")
		)
		(fp_line
			(start 2.286 7.366)
			(end 2.286 -0.254)
			(stroke
				(width 0.1)
				(type default)
			)
			(layer "B.Fab")
		)
		(fp_line
			(start 2.286 -0.254)
			(end -2.286 -0.254)
			(stroke
				(width 0.1)
				(type default)
			)
			(layer "B.Fab")
		)
		(fp_line
			(start -2.286 7.366)
			(end 2.286 7.366)
			(stroke
				(width 0.1)
				(type default)
			)
			(layer "B.Fab")
		)
		(fp_line
			(start -2.286 -0.254)
			(end -2.286 7.366)
			(stroke
				(width 0.1)
				(type default)
			)
			(layer "B.Fab")
		)
		(pad "1" smd rect
			(at 0 0)
			(size 2.54 3.048)
			(layers "B.Cu" "B.Mask" "B.Paste")
			(net "P1V05_PCH_STBY")
		)
		(pad "2" smd rect
			(at 0 7.112)
			(size 2.54 3.048)
			(layers "B.Cu" "B.Mask" "B.Paste")
			(net "GND")
		)
	)
	(footprint ""
		(layer "B.Cu")
		(at 162.463988 -71.982076 180)
		(property "Reference" "R7P30"
			(at 0 0 0)
			(layer "B.SilkS")
			(hide yes)
			(effects
				(font
					(size 1.27 1.27)
				)
				(justify mirror)
			)
		)
		(property "Value" ""
			(at 0 0 0)
			(layer "B.Fab")
			(effects
				(font
					(size 1.27 1.27)
				)
				(justify mirror)
			)
		)
		(duplicate_pad_numbers_are_jumpers no)
		(fp_poly
			(pts
				(xy 0.2794 -0.1016) (xy -0.2794 -0.1016) (xy -0.2794 0.9906) (xy 0.2794 0.9906)
			)
			(stroke
				(width 0)
				(type default)
			)
			(fill no)
			(layer "B.CrtYd")
		)
		(fp_line
			(start 0.2794 0.9906)
			(end -0.2794 0.9906)
			(stroke
				(width 0.1)
				(type default)
			)
			(layer "B.Fab")
		)
		(fp_line
			(start 0.2794 -0.1016)
			(end 0.2794 0.9906)
			(stroke
				(width 0.1)
				(type default)
			)
			(layer "B.Fab")
		)
		(fp_line
			(start -0.2794 0.9906)
			(end -0.2794 -0.1016)
			(stroke
				(width 0.1)
				(type default)
			)
			(layer "B.Fab")
		)
		(fp_line
			(start -0.2794 -0.1016)
			(end 0.2794 -0.1016)
			(stroke
				(width 0.1)
				(type default)
			)
			(layer "B.Fab")
		)
		(pad "1" smd rect
			(at 0 0)
			(size 0.508 0.508)
			(layers "B.Cu" "B.Mask" "B.Paste")
			(net "PVCCIO_CPU0")
		)
		(pad "2" smd rect
			(at 0 0.889)
			(size 0.508 0.508)
			(layers "B.Cu" "B.Mask" "B.Paste")
			(net "XDP_CPU_MBP0_N")
		)
		(zone
			(layer "B.Cu")
			(hatch none 0.5)
			(connect_pads
				(clearance 0)
			)
			(min_thickness 0.25)
			(keepout
				(tracks not_allowed)
				(vias allowed)
				(pads allowed)
				(copperpour not_allowed)
				(footprints allowed)
			)
			(placement
				(enabled no)
				(sheetname "")
			)
			(fill
				(thermal_gap 0.5)
				(thermal_bridge_width 0.5)
				(island_removal_mode 0)
			)
			(polygon
				(pts
					(xy 162.209988 -72.617076) (xy 162.717988 -72.617076) (xy 162.717988 -72.236076) (xy 162.209988 -72.236076)
				)
			)
		)
		(zone
			(layer "B.Cu")
			(hatch none 0.5)
			(connect_pads
				(clearance 0)
			)
			(min_thickness 0.25)
			(keepout
				(tracks allowed)
				(vias not_allowed)
				(pads allowed)
				(copperpour not_allowed)
				(footprints allowed)
			)
			(placement
				(enabled no)
				(sheetname "")
			)
			(fill
				(thermal_gap 0.5)
				(thermal_bridge_width 0.5)
				(island_removal_mode 0)
			)
			(polygon
				(pts
					(xy 162.209988 -72.236076) (xy 162.717988 -72.236076) (xy 162.717988 -72.617076) (xy 162.209988 -72.617076)
				)
			)
		)
	)
	(footprint ""
		(layer "B.Cu")
		(at 481.623116 -144.009872 90)
		(property "Reference" "R6W8"
			(at 0.8382 -0.67818 90)
			(unlocked yes)
			(layer "B.SilkS")
			(effects
				(font
					(size 0.4064 0.254)
					(thickness 0.1524)
				)
				(justify left mirror)
			)
		)
		(property "Value" ""
			(at 0 0 90)
			(layer "B.Fab")
			(effects
				(font
					(size 1.27 1.27)
				)
				(justify mirror)
			)
		)
		(duplicate_pad_numbers_are_jumpers no)
		(fp_poly
			(pts
				(xy 0.2794 -0.1016) (xy -0.2794 -0.1016) (xy -0.2794 0.9906) (xy 0.2794 0.9906)
			)
			(stroke
				(width 0)
				(type default)
			)
			(fill no)
			(layer "B.CrtYd")
		)
		(fp_line
			(start 0.2794 -0.1016)
			(end 0.2794 0.9906)
			(stroke
				(width 0.1)
				(type default)
			)
			(layer "B.Fab")
		)
		(fp_line
			(start -0.2794 -0.1016)
			(end 0.2794 -0.1016)
			(stroke
				(width 0.1)
				(type default)
			)
			(layer "B.Fab")
		)
		(fp_line
			(start 0.2794 0.9906)
			(end -0.2794 0.9906)
			(stroke
				(width 0.1)
				(type default)
			)
			(layer "B.Fab")
		)
		(fp_line
			(start -0.2794 0.9906)
			(end -0.2794 -0.1016)
			(stroke
				(width 0.1)
				(type default)
			)
			(layer "B.Fab")
		)
		(pad "1" smd rect
			(at 0 0 270)
			(size 0.508 0.508)
			(layers "B.Cu" "B.Mask" "B.Paste")
			(net "PCA9555_A1")
		)
		(pad "2" smd rect
			(at 0 0.889 270)
			(size 0.508 0.508)
			(layers "B.Cu" "B.Mask" "B.Paste")
			(net "GND")
		)
		(zone
			(layer "B.Cu")
			(hatch none 0.5)
			(connect_pads
				(clearance 0)
			)
			(min_thickness 0.25)
			(keepout
				(tracks allowed)
				(vias not_allowed)
				(pads allowed)
				(copperpour not_allowed)
				(footprints allowed)
			)
			(placement
				(enabled no)
				(sheetname "")
			)
			(fill
				(thermal_gap 0.5)
				(thermal_bridge_width 0.5)
				(island_removal_mode 0)
			)
			(polygon
				(pts
					(xy 481.877116 -144.263872) (xy 481.877116 -143.755872) (xy 482.258116 -143.755872) (xy 482.258116 -144.263872)
				)
			)
		)
		(zone
			(layer "B.Cu")
			(hatch none 0.5)
			(connect_pads
				(clearance 0)
			)
			(min_thickness 0.25)
			(keepout
				(tracks not_allowed)
				(vias allowed)
				(pads allowed)
				(copperpour not_allowed)
				(footprints allowed)
			)
			(placement
				(enabled no)
				(sheetname "")
			)
			(fill
				(thermal_gap 0.5)
				(thermal_bridge_width 0.5)
				(island_removal_mode 0)
			)
			(polygon
				(pts
					(xy 482.258116 -144.263872) (xy 482.258116 -143.755872) (xy 481.877116 -143.755872) (xy 481.877116 -144.263872)
				)
			)
		)
	)
	(footprint ""
		(layer "B.Cu")
		(at 407.416 -103.8225)
		(property "Reference" "C2N23"
			(at 0 0 0)
			(layer "B.SilkS")
			(hide yes)
			(effects
				(font
					(size 1.27 1.27)
				)
				(justify mirror)
			)
		)
		(property "Value" ""
			(at 0 0 0)
			(layer "B.Fab")
			(effects
				(font
					(size 1.27 1.27)
				)
				(justify mirror)
			)
		)
		(duplicate_pad_numbers_are_jumpers no)
		(fp_poly
			(pts
				(xy 0.4953 -0.2032) (xy -0.4953 -0.2032) (xy -0.4953 1.6002) (xy 0.4953 1.6002)
			)
			(stroke
				(width 0)
				(type default)
			)
			(fill no)
			(layer "B.CrtYd")
		)
		(fp_line
			(start -0.4953 -0.2032)
			(end -0.4953 1.6002)
			(stroke
				(width 0.1)
				(type default)
			)
			(layer "B.Fab")
		)
		(fp_line
			(start -0.4953 1.6002)
			(end 0.4953 1.6002)
			(stroke
				(width 0.1)
				(type default)
			)
			(layer "B.Fab")
		)
		(fp_line
			(start 0.4953 -0.2032)
			(end -0.4953 -0.2032)
			(stroke
				(width 0.1)
				(type default)
			)
			(layer "B.Fab")
		)
		(fp_line
			(start 0.4953 1.6002)
			(end 0.4953 -0.2032)
			(stroke
				(width 0.1)
				(type default)
			)
			(layer "B.Fab")
		)
		(pad "1" smd rect
			(at 0 0 180)
			(size 0.762 0.889)
			(layers "B.Cu" "B.Mask" "B.Paste")
			(net "P3V3_STBY")
		)
		(pad "2" smd rect
			(at 0 1.397 180)
			(size 0.762 0.889)
			(layers "B.Cu" "B.Mask" "B.Paste")
			(net "GND")
		)
		(zone
			(layer "B.Cu")
			(hatch none 0.5)
			(connect_pads
				(clearance 0)
			)
			(min_thickness 0.25)
			(keepout
				(tracks not_allowed)
				(vias allowed)
				(pads allowed)
				(copperpour not_allowed)
				(footprints allowed)
			)
			(placement
				(enabled no)
				(sheetname "")
			)
			(fill
				(thermal_gap 0.5)
				(thermal_bridge_width 0.5)
				(island_removal_mode 0)
			)
			(polygon
				(pts
					(xy 407.797 -103.378) (xy 407.035 -103.378) (xy 407.035 -102.87) (xy 407.797 -102.87)
				)
			)
		)
	)
	(footprint ""
		(layer "B.Cu")
		(at 172.847 -126.111)
		(property "Reference" "R6M4"
			(at 0 0 0)
			(layer "B.SilkS")
			(hide yes)
			(effects
				(font
					(size 1.27 1.27)
				)
				(justify mirror)
			)
		)
		(property "Value" ""
			(at 0 0 0)
			(layer "B.Fab")
			(effects
				(font
					(size 1.27 1.27)
				)
				(justify mirror)
			)
		)
		(duplicate_pad_numbers_are_jumpers no)
		(fp_poly
			(pts
				(xy 0.2794 -0.1016) (xy -0.2794 -0.1016) (xy -0.2794 0.9906) (xy 0.2794 0.9906)
			)
			(stroke
				(width 0)
				(type default)
			)
			(fill no)
			(layer "B.CrtYd")
		)
		(fp_line
			(start -0.2794 -0.1016)
			(end 0.2794 -0.1016)
			(stroke
				(width 0.1)
				(type default)
			)
			(layer "B.Fab")
		)
		(fp_line
			(start -0.2794 0.9906)
			(end -0.2794 -0.1016)
			(stroke
				(width 0.1)
				(type default)
			)
			(layer "B.Fab")
		)
		(fp_line
			(start 0.2794 -0.1016)
			(end 0.2794 0.9906)
			(stroke
				(width 0.1)
				(type default)
			)
			(layer "B.Fab")
		)
		(fp_line
			(start 0.2794 0.9906)
			(end -0.2794 0.9906)
			(stroke
				(width 0.1)
				(type default)
			)
			(layer "B.Fab")
		)
		(pad "1" smd rect
			(at 0 0 180)
			(size 0.508 0.508)
			(layers "B.Cu" "B.Mask" "B.Paste")
			(net "P3V3")
		)
		(pad "2" smd rect
			(at 0 0.889 180)
			(size 0.508 0.508)
			(layers "B.Cu" "B.Mask" "B.Paste")
			(net "H_CPU1_MEMKLM_MEMHOT")
		)
		(zone
			(layer "B.Cu")
			(hatch none 0.5)
			(connect_pads
				(clearance 0)
			)
			(min_thickness 0.25)
			(keepout
				(tracks allowed)
				(vias not_allowed)
				(pads allowed)
				(copperpour not_allowed)
				(footprints allowed)
			)
			(placement
				(enabled no)
				(sheetname "")
			)
			(fill
				(thermal_gap 0.5)
				(thermal_bridge_width 0.5)
				(island_removal_mode 0)
			)
			(polygon
				(pts
					(xy 173.101 -125.857) (xy 172.593 -125.857) (xy 172.593 -125.476) (xy 173.101 -125.476)
				)
			)
		)
		(zone
			(layer "B.Cu")
			(hatch none 0.5)
			(connect_pads
				(clearance 0)
			)
			(min_thickness 0.25)
			(keepout
				(tracks not_allowed)
				(vias allowed)
				(pads allowed)
				(copperpour not_allowed)
				(footprints allowed)
			)
			(placement
				(enabled no)
				(sheetname "")
			)
			(fill
				(thermal_gap 0.5)
				(thermal_bridge_width 0.5)
				(island_removal_mode 0)
			)
			(polygon
				(pts
					(xy 173.101 -125.476) (xy 172.593 -125.476) (xy 172.593 -125.857) (xy 173.101 -125.857)
				)
			)
		)
	)
	(footprint ""
		(layer "B.Cu")
		(at -3.0226 -9.017 -90)
		(property "Reference" "C22W1"
			(at 0 0 90)
			(layer "B.SilkS")
			(hide yes)
			(effects
				(font
					(size 1.27 1.27)
				)
				(justify mirror)
			)
		)
		(property "Value" "*"
			(at 0.0762 -6.2357 270)
			(unlocked yes)
			(layer "B.Fab")
			(hide yes)
			(effects
				(font
					(size 1.27 1.016)
					(thickness 0.1524)
				)
				(justify mirror)
			)
		)
		(property "Device Type" "SC22U16V5MX-4-GP_SMD-BCG5-SC22A"
			(at 0.0762 -8.2677 270)
			(unlocked yes)
			(layer "B.Fab")
			(hide yes)
			(effects
				(font
					(size 1.27 1.016)
					(thickness 0.1524)
				)
				(justify mirror)
			)
		)
		(duplicate_pad_numbers_are_jumpers no)
		(fp_line
			(start -0.635 0)
			(end 0.635 0)
			(stroke
				(width 0.508)
				(type default)
			)
			(layer "B.SilkS")
		)
		(fp_rect
			(start 0.9652 1.778)
			(end -0.9652 -1.778)
			(stroke
				(width 0)
				(type default)
			)
			(fill no)
			(layer "B.CrtYd")
		)
		(fp_poly
			(pts
				(xy 0.9652 -1.778) (xy -0.9652 -1.778) (xy -0.9652 1.778) (xy 0.9652 1.778)
			)
			(stroke
				(width 0)
				(type default)
			)
			(fill no)
			(layer "B.Fab")
		)
		(pad "1" smd rect
			(at 0 -0.9652 90)
			(size 1.397 1.143)
			(layers "B.Cu" "B.Mask" "B.Paste")
			(net "VR_FET_SW_P12V_STBY_PVDDQ_GHJ")
		)
		(pad "2" smd rect
			(at 0 0.9652 90)
			(size 1.397 1.143)
			(layers "B.Cu" "B.Mask" "B.Paste")
			(net "GND")
		)
	)
	(footprint ""
		(layer "B.Cu")
		(at 191.897 -154.559 180)
		(property "Reference" "C6L2"
			(at 0 0 0)
			(layer "B.SilkS")
			(hide yes)
			(effects
				(font
					(size 1.27 1.27)
				)
				(justify mirror)
			)
		)
		(property "Value" ""
			(at 0 0 0)
			(layer "B.Fab")
			(effects
				(font
					(size 1.27 1.27)
				)
				(justify mirror)
			)
		)
		(duplicate_pad_numbers_are_jumpers no)
		(fp_poly
			(pts
				(xy -0.3048 -0.1016) (xy -0.3048 0.9906) (xy 0.3048 0.9906) (xy 0.3048 -0.1016)
			)
			(stroke
				(width 0)
				(type default)
			)
			(fill no)
			(layer "B.CrtYd")
		)
		(fp_line
			(start 0.3048 0.9906)
			(end -0.3048 0.9906)
			(stroke
				(width 0.1)
				(type default)
			)
			(layer "B.Fab")
		)
		(fp_line
			(start 0.3048 -0.1016)
			(end 0.3048 0.9906)
			(stroke
				(width 0.1)
				(type default)
			)
			(layer "B.Fab")
		)
		(fp_line
			(start -0.3048 0.9906)
			(end -0.3048 -0.1016)
			(stroke
				(width 0.1)
				(type default)
			)
			(layer "B.Fab")
		)
		(fp_line
			(start -0.3048 -0.1016)
			(end 0.3048 -0.1016)
			(stroke
				(width 0.1)
				(type default)
			)
			(layer "B.Fab")
		)
		(pad "1" smd rect
			(at 0 0)
			(size 0.508 0.508)
			(layers "B.Cu" "B.Mask" "B.Paste")
			(net "M_F_CPU_VREF")
		)
		(pad "2" smd rect
			(at 0 0.889)
			(size 0.508 0.508)
			(layers "B.Cu" "B.Mask" "B.Paste")
			(net "GND")
		)
		(zone
			(layer "B.Cu")
			(hatch none 0.5)
			(connect_pads
				(clearance 0)
			)
			(min_thickness 0.25)
			(keepout
				(tracks not_allowed)
				(vias allowed)
				(pads allowed)
				(copperpour not_allowed)
				(footprints allowed)
			)
			(placement
				(enabled no)
				(sheetname "")
			)
			(fill
				(thermal_gap 0.5)
				(thermal_bridge_width 0.5)
				(island_removal_mode 0)
			)
			(polygon
				(pts
					(xy 191.643 -155.194) (xy 192.151 -155.194) (xy 192.151 -154.813) (xy 191.643 -154.813)
				)
			)
		)
		(zone
			(layer "B.Cu")
			(hatch none 0.5)
			(connect_pads
				(clearance 0)
			)
			(min_thickness 0.25)
			(keepout
				(tracks allowed)
				(vias not_allowed)
				(pads allowed)
				(copperpour not_allowed)
				(footprints allowed)
			)
			(placement
				(enabled no)
				(sheetname "")
			)
			(fill
				(thermal_gap 0.5)
				(thermal_bridge_width 0.5)
				(island_removal_mode 0)
			)
			(polygon
				(pts
					(xy 191.643 -154.813) (xy 192.151 -154.813) (xy 192.151 -155.194) (xy 191.643 -155.194)
				)
			)
		)
	)
	(footprint ""
		(layer "B.Cu")
		(at 392.117326 -113.903252 90)
		(property "Reference" "C2M20"
			(at 0 0 90)
			(layer "B.SilkS")
			(hide yes)
			(effects
				(font
					(size 1.27 1.27)
				)
				(justify mirror)
			)
		)
		(property "Value" ""
			(at 0 0 90)
			(layer "B.Fab")
			(effects
				(font
					(size 1.27 1.27)
				)
				(justify mirror)
			)
		)
		(duplicate_pad_numbers_are_jumpers no)
		(fp_poly
			(pts
				(xy -0.3048 -0.1016) (xy -0.3048 0.9906) (xy 0.3048 0.9906) (xy 0.3048 -0.1016)
			)
			(stroke
				(width 0)
				(type default)
			)
			(fill no)
			(layer "B.CrtYd")
		)
		(fp_line
			(start 0.3048 -0.1016)
			(end 0.3048 0.9906)
			(stroke
				(width 0.1)
				(type default)
			)
			(layer "B.Fab")
		)
		(fp_line
			(start -0.3048 -0.1016)
			(end 0.3048 -0.1016)
			(stroke
				(width 0.1)
				(type default)
			)
			(layer "B.Fab")
		)
		(fp_line
			(start 0.3048 0.9906)
			(end -0.3048 0.9906)
			(stroke
				(width 0.1)
				(type default)
			)
			(layer "B.Fab")
		)
		(fp_line
			(start -0.3048 0.9906)
			(end -0.3048 -0.1016)
			(stroke
				(width 0.1)
				(type default)
			)
			(layer "B.Fab")
		)
		(pad "1" smd rect
			(at 0 0 270)
			(size 0.508 0.508)
			(layers "B.Cu" "B.Mask" "B.Paste")
			(net "P1V05_PCH_STBY")
		)
		(pad "2" smd rect
			(at 0 0.889 270)
			(size 0.508 0.508)
			(layers "B.Cu" "B.Mask" "B.Paste")
			(net "GND")
		)
		(zone
			(layer "B.Cu")
			(hatch none 0.5)
			(connect_pads
				(clearance 0)
			)
			(min_thickness 0.25)
			(keepout
				(tracks allowed)
				(vias not_allowed)
				(pads allowed)
				(copperpour not_allowed)
				(footprints allowed)
			)
			(placement
				(enabled no)
				(sheetname "")
			)
			(fill
				(thermal_gap 0.5)
				(thermal_bridge_width 0.5)
				(island_removal_mode 0)
			)
			(polygon
				(pts
					(xy 392.371326 -114.157252) (xy 392.371326 -113.649252) (xy 392.752326 -113.649252) (xy 392.752326 -114.157252)
				)
			)
		)
		(zone
			(layer "B.Cu")
			(hatch none 0.5)
			(connect_pads
				(clearance 0)
			)
			(min_thickness 0.25)
			(keepout
				(tracks not_allowed)
				(vias allowed)
				(pads allowed)
				(copperpour not_allowed)
				(footprints allowed)
			)
			(placement
				(enabled no)
				(sheetname "")
			)
			(fill
				(thermal_gap 0.5)
				(thermal_bridge_width 0.5)
				(island_removal_mode 0)
			)
			(polygon
				(pts
					(xy 392.752326 -114.157252) (xy 392.752326 -113.649252) (xy 392.371326 -113.649252) (xy 392.371326 -114.157252)
				)
			)
		)
	)
	(footprint ""
		(layer "B.Cu")
		(at 255.38938 -157.57652 90)
		(property "Reference" "SH5L1"
			(at 0 0 90)
			(layer "B.SilkS")
			(hide yes)
			(effects
				(font
					(size 1.27 1.27)
				)
				(justify mirror)
			)
		)
		(property "Value" ""
			(at 0 0 90)
			(layer "B.Fab")
			(effects
				(font
					(size 1.27 1.27)
				)
				(justify mirror)
			)
		)
		(duplicate_pad_numbers_are_jumpers no)
		(fp_poly
			(pts
				(xy 0.1651 -0.0508) (xy 0.1651 0.5842) (xy -0.1651 0.5842) (xy -0.1651 -0.0508)
			)
			(stroke
				(width 0)
				(type default)
			)
			(fill no)
			(layer "B.CrtYd")
		)
		(fp_line
			(start 0.1651 -0.0508)
			(end -0.1651 -0.0508)
			(stroke
				(width 0.1)
				(type default)
			)
			(layer "B.Fab")
		)
		(fp_line
			(start -0.1651 -0.0508)
			(end -0.1651 0.5842)
			(stroke
				(width 0.1)
				(type default)
			)
			(layer "B.Fab")
		)
		(fp_line
			(start 0.1651 0.5842)
			(end 0.1651 -0.0508)
			(stroke
				(width 0.1)
				(type default)
			)
			(layer "B.Fab")
		)
		(fp_line
			(start -0.1651 0.5842)
			(end 0.1651 0.5842)
			(stroke
				(width 0.1)
				(type default)
			)
			(layer "B.Fab")
		)
		(pad "1" smd custom
			(at 0 0 90)
			(size 0.0762 0.0762)
			(layers "B.Cu" "B.Mask" "B.Paste")
			(net "VR_PVTT_DEF_SNS")
			(options
				(clearance outline)
				(anchor circle)
			)
			(primitives
				(gr_poly
					(pts
						(arc
							(start -0.1524 0.10795)
							(mid -0.098518 0.130268)
							(end -0.0762 0.18415)
						)
						(xy -0.0762 0.22225) (xy 0.0762 0.22225)
						(arc
							(start 0.0762 0.18415)
							(mid 0.098518 0.130268)
							(end 0.1524 0.10795)
						)
						(xy 0.1524 -0.22225) (xy -0.1524 -0.22225)
					)
					(width 0)
					(fill yes)
				)
			)
		)
		(pad "2" smd custom
			(at 0 0.5334 270)
			(size 0.0762 0.0762)
			(layers "B.Cu" "B.Mask" "B.Paste")
			(net "PVTT_DEF")
			(options
				(clearance outline)
				(anchor circle)
			)
			(primitives
				(gr_poly
					(pts
						(arc
							(start -0.1524 0.10795)
							(mid -0.098518 0.130268)
							(end -0.0762 0.18415)
						)
						(xy -0.0762 0.22225) (xy 0.0762 0.22225)
						(arc
							(start 0.0762 0.18415)
							(mid 0.098518 0.130268)
							(end 0.1524 0.10795)
						)
						(xy 0.1524 -0.22225) (xy -0.1524 -0.22225)
					)
					(width 0)
					(fill yes)
				)
			)
		)
	)
	(footprint ""
		(layer "B.Cu")
		(at 408.1526 -153.5938 90)
		(property "Reference" "C2L7"
			(at 0 0 90)
			(layer "B.SilkS")
			(hide yes)
			(effects
				(font
					(size 1.27 1.27)
				)
				(justify mirror)
			)
		)
		(property "Value" ""
			(at 0 0 90)
			(layer "B.Fab")
			(effects
				(font
					(size 1.27 1.27)
				)
				(justify mirror)
			)
		)
		(duplicate_pad_numbers_are_jumpers no)
		(fp_poly
			(pts
				(xy -0.3048 -0.1016) (xy -0.3048 0.9906) (xy 0.3048 0.9906) (xy 0.3048 -0.1016)
			)
			(stroke
				(width 0)
				(type default)
			)
			(fill no)
			(layer "B.CrtYd")
		)
		(fp_line
			(start 0.3048 -0.1016)
			(end 0.3048 0.9906)
			(stroke
				(width 0.1)
				(type default)
			)
			(layer "B.Fab")
		)
		(fp_line
			(start -0.3048 -0.1016)
			(end 0.3048 -0.1016)
			(stroke
				(width 0.1)
				(type default)
			)
			(layer "B.Fab")
		)
		(fp_line
			(start 0.3048 0.9906)
			(end -0.3048 0.9906)
			(stroke
				(width 0.1)
				(type default)
			)
			(layer "B.Fab")
		)
		(fp_line
			(start -0.3048 0.9906)
			(end -0.3048 -0.1016)
			(stroke
				(width 0.1)
				(type default)
			)
			(layer "B.Fab")
		)
		(pad "1" smd rect
			(at 0 0 270)
			(size 0.508 0.508)
			(layers "B.Cu" "B.Mask" "B.Paste")
			(net "SATA6G_PCH_PCIE_UP_SATA_RXP<7>")
		)
		(pad "2" smd rect
			(at 0 0.889 270)
			(size 0.508 0.508)
			(layers "B.Cu" "B.Mask" "B.Paste")
			(net "SATA6G_P7_RX_C_DP")
		)
		(zone
			(layer "B.Cu")
			(hatch none 0.5)
			(connect_pads
				(clearance 0)
			)
			(min_thickness 0.25)
			(keepout
				(tracks allowed)
				(vias not_allowed)
				(pads allowed)
				(copperpour not_allowed)
				(footprints allowed)
			)
			(placement
				(enabled no)
				(sheetname "")
			)
			(fill
				(thermal_gap 0.5)
				(thermal_bridge_width 0.5)
				(island_removal_mode 0)
			)
			(polygon
				(pts
					(xy 408.4066 -153.8478) (xy 408.4066 -153.3398) (xy 408.7876 -153.3398) (xy 408.7876 -153.8478)
				)
			)
		)
		(zone
			(layer "B.Cu")
			(hatch none 0.5)
			(connect_pads
				(clearance 0)
			)
			(min_thickness 0.25)
			(keepout
				(tracks not_allowed)
				(vias allowed)
				(pads allowed)
				(copperpour not_allowed)
				(footprints allowed)
			)
			(placement
				(enabled no)
				(sheetname "")
			)
			(fill
				(thermal_gap 0.5)
				(thermal_bridge_width 0.5)
				(island_removal_mode 0)
			)
			(polygon
				(pts
					(xy 408.7876 -153.8478) (xy 408.7876 -153.3398) (xy 408.4066 -153.3398) (xy 408.4066 -153.8478)
				)
			)
		)
	)
	(footprint ""
		(layer "B.Cu")
		(at 348.052136 -141.085062 -90)
		(property "Reference" "C7W13"
			(at 0 0 90)
			(layer "B.SilkS")
			(hide yes)
			(effects
				(font
					(size 1.27 1.27)
				)
				(justify mirror)
			)
		)
		(property "Value" "*"
			(at 0.0762 -6.2357 270)
			(unlocked yes)
			(layer "B.Fab")
			(hide yes)
			(effects
				(font
					(size 1.27 1.016)
					(thickness 0.1524)
				)
				(justify mirror)
			)
		)
		(property "Device Type" "SC22U16V5MX-4-GP_SMD-BCG5-SC22A"
			(at 0.0762 -8.2677 270)
			(unlocked yes)
			(layer "B.Fab")
			(hide yes)
			(effects
				(font
					(size 1.27 1.016)
					(thickness 0.1524)
				)
				(justify mirror)
			)
		)
		(duplicate_pad_numbers_are_jumpers no)
		(fp_line
			(start -0.635 0)
			(end 0.635 0)
			(stroke
				(width 0.508)
				(type default)
			)
			(layer "B.SilkS")
		)
		(fp_rect
			(start 0.9652 1.778)
			(end -0.9652 -1.778)
			(stroke
				(width 0)
				(type default)
			)
			(fill no)
			(layer "B.CrtYd")
		)
		(fp_poly
			(pts
				(xy 0.9652 -1.778) (xy -0.9652 -1.778) (xy -0.9652 1.778) (xy 0.9652 1.778)
			)
			(stroke
				(width 0)
				(type default)
			)
			(fill no)
			(layer "B.Fab")
		)
		(pad "1" smd rect
			(at 0 -0.9652 90)
			(size 1.397 1.143)
			(layers "B.Cu" "B.Mask" "B.Paste")
			(net "VR_FET_SW_P12V_STBY_PVDDQ_DEF")
		)
		(pad "2" smd rect
			(at 0 0.9652 90)
			(size 1.397 1.143)
			(layers "B.Cu" "B.Mask" "B.Paste")
			(net "GND")
		)
	)
	(footprint ""
		(layer "B.Cu")
		(at 369.945158 -77.896212 -90)
		(property "Reference" "C3P44"
			(at 0 0 90)
			(layer "B.SilkS")
			(hide yes)
			(effects
				(font
					(size 1.27 1.27)
				)
				(justify mirror)
			)
		)
		(property "Value" ""
			(at 0 0 90)
			(layer "B.Fab")
			(effects
				(font
					(size 1.27 1.27)
				)
				(justify mirror)
			)
		)
		(duplicate_pad_numbers_are_jumpers no)
		(fp_rect
			(start 0.2794 0.9144)
			(end -0.2794 -0.1143)
			(stroke
				(width 0)
				(type default)
			)
			(fill no)
			(layer "B.CrtYd")
		)
		(fp_line
			(start -0.2794 0.9144)
			(end 0.2794 0.9144)
			(stroke
				(width 0.1)
				(type default)
			)
			(layer "B.Fab")
		)
		(fp_line
			(start 0.2794 0.9144)
			(end 0.2794 -0.1143)
			(stroke
				(width 0.1)
				(type default)
			)
			(layer "B.Fab")
		)
		(fp_line
			(start -0.2794 -0.1143)
			(end -0.2794 0.9144)
			(stroke
				(width 0.1)
				(type default)
			)
			(layer "B.Fab")
		)
		(fp_line
			(start 0.2794 -0.1143)
			(end -0.2794 -0.1143)
			(stroke
				(width 0.1)
				(type default)
			)
			(layer "B.Fab")
		)
		(pad "1" smd custom
			(at 0 0 180)
			(size 0.10414 0.10414)
			(layers "B.Cu" "B.Mask" "B.Paste")
			(net "P3V3_STBY")
			(options
				(clearance outline)
				(anchor circle)
			)
			(primitives
				(gr_poly
					(pts
						(xy -0.20828 -0.08636) (xy -0.20828 0.08636) (xy -0.08636 0.20828) (xy 0.086614 0.20828) (xy 0.20828 0.086614)
						(xy 0.20828 -0.08636) (xy 0.08636 -0.20828) (xy -0.08636 -0.20828)
					)
					(width 0)
					(fill yes)
				)
			)
		)
		(pad "2" smd custom
			(at 0 0.8001 180)
			(size 0.10414 0.10414)
			(layers "B.Cu" "B.Mask" "B.Paste")
			(net "GND")
			(options
				(clearance outline)
				(anchor circle)
			)
			(primitives
				(gr_poly
					(pts
						(xy -0.20828 -0.08636) (xy -0.20828 0.08636) (xy -0.08636 0.20828) (xy 0.086614 0.20828) (xy 0.20828 0.086614)
						(xy 0.20828 -0.08636) (xy 0.08636 -0.20828) (xy -0.08636 -0.20828)
					)
					(width 0)
					(fill yes)
				)
			)
		)
		(zone
			(layer "B.Cu")
			(hatch none 0.5)
			(connect_pads
				(clearance 0)
			)
			(min_thickness 0.25)
			(keepout
				(tracks allowed)
				(vias not_allowed)
				(pads allowed)
				(copperpour not_allowed)
				(footprints allowed)
			)
			(placement
				(enabled no)
				(sheetname "")
			)
			(fill
				(thermal_gap 0.5)
				(thermal_bridge_width 0.5)
				(island_removal_mode 0)
			)
			(polygon
				(pts
					(xy 369.735608 -77.808582) (xy 369.354608 -77.808582) (xy 369.354608 -77.983842) (xy 369.735608 -77.984096)
				)
			)
		)
		(zone
			(layer "B.Cu")
			(hatch none 0.5)
			(connect_pads
				(clearance 0)
			)
			(min_thickness 0.25)
			(keepout
				(tracks not_allowed)
				(vias allowed)
				(pads allowed)
				(copperpour not_allowed)
				(footprints allowed)
			)
			(placement
				(enabled no)
				(sheetname "")
			)
			(fill
				(thermal_gap 0.5)
				(thermal_bridge_width 0.5)
				(island_removal_mode 0)
			)
			(polygon
				(pts
					(xy 369.735608 -77.808582) (xy 369.354608 -77.808582) (xy 369.354608 -77.983842) (xy 369.735608 -77.984096)
				)
			)
		)
	)
	(footprint ""
		(layer "B.Cu")
		(at 385.33705 -111.85525 180)
		(property "Reference" "C3N1"
			(at 0 0 0)
			(layer "B.SilkS")
			(hide yes)
			(effects
				(font
					(size 1.27 1.27)
				)
				(justify mirror)
			)
		)
		(property "Value" ""
			(at 0 0 0)
			(layer "B.Fab")
			(effects
				(font
					(size 1.27 1.27)
				)
				(justify mirror)
			)
		)
		(duplicate_pad_numbers_are_jumpers no)
		(fp_rect
			(start 0.2794 0.9144)
			(end -0.2794 -0.1143)
			(stroke
				(width 0)
				(type default)
			)
			(fill no)
			(layer "B.CrtYd")
		)
		(fp_line
			(start 0.2794 0.9144)
			(end 0.2794 -0.1143)
			(stroke
				(width 0.1)
				(type default)
			)
			(layer "B.Fab")
		)
		(fp_line
			(start 0.2794 -0.1143)
			(end -0.2794 -0.1143)
			(stroke
				(width 0.1)
				(type default)
			)
			(layer "B.Fab")
		)
		(fp_line
			(start -0.2794 0.9144)
			(end 0.2794 0.9144)
			(stroke
				(width 0.1)
				(type default)
			)
			(layer "B.Fab")
		)
		(fp_line
			(start -0.2794 -0.1143)
			(end -0.2794 0.9144)
			(stroke
				(width 0.1)
				(type default)
			)
			(layer "B.Fab")
		)
		(pad "1" smd custom
			(at 0 0 90)
			(size 0.10414 0.10414)
			(layers "B.Cu" "B.Mask" "B.Paste")
			(net "PVNN_PCH_STBY")
			(options
				(clearance outline)
				(anchor circle)
			)
			(primitives
				(gr_poly
					(pts
						(xy -0.20828 -0.08636) (xy -0.20828 0.08636) (xy -0.08636 0.20828) (xy 0.086614 0.20828) (xy 0.20828 0.086614)
						(xy 0.20828 -0.08636) (xy 0.08636 -0.20828) (xy -0.08636 -0.20828)
					)
					(width 0)
					(fill yes)
				)
			)
		)
		(pad "2" smd custom
			(at 0 0.8001 90)
			(size 0.10414 0.10414)
			(layers "B.Cu" "B.Mask" "B.Paste")
			(net "GND")
			(options
				(clearance outline)
				(anchor circle)
			)
			(primitives
				(gr_poly
					(pts
						(xy -0.20828 -0.08636) (xy -0.20828 0.08636) (xy -0.08636 0.20828) (xy 0.086614 0.20828) (xy 0.20828 0.086614)
						(xy 0.20828 -0.08636) (xy 0.08636 -0.20828) (xy -0.08636 -0.20828)
					)
					(width 0)
					(fill yes)
				)
			)
		)
		(zone
			(layer "B.Cu")
			(hatch none 0.5)
			(connect_pads
				(clearance 0)
			)
			(min_thickness 0.25)
			(keepout
				(tracks allowed)
				(vias not_allowed)
				(pads allowed)
				(copperpour not_allowed)
				(footprints allowed)
			)
			(placement
				(enabled no)
				(sheetname "")
			)
			(fill
				(thermal_gap 0.5)
				(thermal_bridge_width 0.5)
				(island_removal_mode 0)
			)
			(polygon
				(pts
					(xy 385.24942 -112.0648) (xy 385.24942 -112.4458) (xy 385.42468 -112.4458) (xy 385.424934 -112.0648)
				)
			)
		)
		(zone
			(layer "B.Cu")
			(hatch none 0.5)
			(connect_pads
				(clearance 0)
			)
			(min_thickness 0.25)
			(keepout
				(tracks not_allowed)
				(vias allowed)
				(pads allowed)
				(copperpour not_allowed)
				(footprints allowed)
			)
			(placement
				(enabled no)
				(sheetname "")
			)
			(fill
				(thermal_gap 0.5)
				(thermal_bridge_width 0.5)
				(island_removal_mode 0)
			)
			(polygon
				(pts
					(xy 385.24942 -112.0648) (xy 385.24942 -112.4458) (xy 385.42468 -112.4458) (xy 385.424934 -112.0648)
				)
			)
		)
	)
	(footprint ""
		(layer "B.Cu")
		(at 370.745512 -72.294242)
		(property "Reference" "C2R2"
			(at 0 0 0)
			(layer "B.SilkS")
			(hide yes)
			(effects
				(font
					(size 1.27 1.27)
				)
				(justify mirror)
			)
		)
		(property "Value" ""
			(at 0 0 0)
			(layer "B.Fab")
			(effects
				(font
					(size 1.27 1.27)
				)
				(justify mirror)
			)
		)
		(duplicate_pad_numbers_are_jumpers no)
		(fp_rect
			(start 0.2794 0.9144)
			(end -0.2794 -0.1143)
			(stroke
				(width 0)
				(type default)
			)
			(fill no)
			(layer "B.CrtYd")
		)
		(fp_line
			(start -0.2794 -0.1143)
			(end -0.2794 0.9144)
			(stroke
				(width 0.1)
				(type default)
			)
			(layer "B.Fab")
		)
		(fp_line
			(start -0.2794 0.9144)
			(end 0.2794 0.9144)
			(stroke
				(width 0.1)
				(type default)
			)
			(layer "B.Fab")
		)
		(fp_line
			(start 0.2794 -0.1143)
			(end -0.2794 -0.1143)
			(stroke
				(width 0.1)
				(type default)
			)
			(layer "B.Fab")
		)
		(fp_line
			(start 0.2794 0.9144)
			(end 0.2794 -0.1143)
			(stroke
				(width 0.1)
				(type default)
			)
			(layer "B.Fab")
		)
		(pad "1" smd custom
			(at 0 0 270)
			(size 0.10414 0.10414)
			(layers "B.Cu" "B.Mask" "B.Paste")
			(net "P3V3_STBY")
			(options
				(clearance outline)
				(anchor circle)
			)
			(primitives
				(gr_poly
					(pts
						(xy -0.20828 -0.08636) (xy -0.20828 0.08636) (xy -0.08636 0.20828) (xy 0.086614 0.20828) (xy 0.20828 0.086614)
						(xy 0.20828 -0.08636) (xy 0.08636 -0.20828) (xy -0.08636 -0.20828)
					)
					(width 0)
					(fill yes)
				)
			)
		)
		(pad "2" smd custom
			(at 0 0.8001 270)
			(size 0.10414 0.10414)
			(layers "B.Cu" "B.Mask" "B.Paste")
			(net "GND")
			(options
				(clearance outline)
				(anchor circle)
			)
			(primitives
				(gr_poly
					(pts
						(xy -0.20828 -0.08636) (xy -0.20828 0.08636) (xy -0.08636 0.20828) (xy 0.086614 0.20828) (xy 0.20828 0.086614)
						(xy 0.20828 -0.08636) (xy 0.08636 -0.20828) (xy -0.08636 -0.20828)
					)
					(width 0)
					(fill yes)
				)
			)
		)
		(zone
			(layer "B.Cu")
			(hatch none 0.5)
			(connect_pads
				(clearance 0)
			)
			(min_thickness 0.25)
			(keepout
				(tracks not_allowed)
				(vias allowed)
				(pads allowed)
				(copperpour not_allowed)
				(footprints allowed)
			)
			(placement
				(enabled no)
				(sheetname "")
			)
			(fill
				(thermal_gap 0.5)
				(thermal_bridge_width 0.5)
				(island_removal_mode 0)
			)
			(polygon
				(pts
					(xy 370.833142 -72.084692) (xy 370.833142 -71.703692) (xy 370.657882 -71.703692) (xy 370.657628 -72.084692)
				)
			)
		)
		(zone
			(layer "B.Cu")
			(hatch none 0.5)
			(connect_pads
				(clearance 0)
			)
			(min_thickness 0.25)
			(keepout
				(tracks allowed)
				(vias not_allowed)
				(pads allowed)
				(copperpour not_allowed)
				(footprints allowed)
			)
			(placement
				(enabled no)
				(sheetname "")
			)
			(fill
				(thermal_gap 0.5)
				(thermal_bridge_width 0.5)
				(island_removal_mode 0)
			)
			(polygon
				(pts
					(xy 370.833142 -72.084692) (xy 370.833142 -71.703692) (xy 370.657882 -71.703692) (xy 370.657628 -72.084692)
				)
			)
		)
	)
	(footprint ""
		(layer "B.Cu")
		(at 432.0032 -23.4188)
		(property "Reference" "R1U17"
			(at 0 0 0)
			(layer "B.SilkS")
			(hide yes)
			(effects
				(font
					(size 1.27 1.27)
				)
				(justify mirror)
			)
		)
		(property "Value" ""
			(at 0 0 0)
			(layer "B.Fab")
			(effects
				(font
					(size 1.27 1.27)
				)
				(justify mirror)
			)
		)
		(duplicate_pad_numbers_are_jumpers no)
		(fp_poly
			(pts
				(xy 0.2794 -0.1016) (xy -0.2794 -0.1016) (xy -0.2794 0.9906) (xy 0.2794 0.9906)
			)
			(stroke
				(width 0)
				(type default)
			)
			(fill no)
			(layer "B.CrtYd")
		)
		(fp_line
			(start -0.2794 -0.1016)
			(end 0.2794 -0.1016)
			(stroke
				(width 0.1)
				(type default)
			)
			(layer "B.Fab")
		)
		(fp_line
			(start -0.2794 0.9906)
			(end -0.2794 -0.1016)
			(stroke
				(width 0.1)
				(type default)
			)
			(layer "B.Fab")
		)
		(fp_line
			(start 0.2794 -0.1016)
			(end 0.2794 0.9906)
			(stroke
				(width 0.1)
				(type default)
			)
			(layer "B.Fab")
		)
		(fp_line
			(start 0.2794 0.9906)
			(end -0.2794 0.9906)
			(stroke
				(width 0.1)
				(type default)
			)
			(layer "B.Fab")
		)
		(pad "1" smd rect
			(at 0 0 180)
			(size 0.508 0.508)
			(layers "B.Cu" "B.Mask" "B.Paste")
			(net "FM_BOARD_SKU_ID2")
		)
		(pad "2" smd rect
			(at 0 0.889 180)
			(size 0.508 0.508)
			(layers "B.Cu" "B.Mask" "B.Paste")
			(net "GND")
		)
		(zone
			(layer "B.Cu")
			(hatch none 0.5)
			(connect_pads
				(clearance 0)
			)
			(min_thickness 0.25)
			(keepout
				(tracks allowed)
				(vias not_allowed)
				(pads allowed)
				(copperpour not_allowed)
				(footprints allowed)
			)
			(placement
				(enabled no)
				(sheetname "")
			)
			(fill
				(thermal_gap 0.5)
				(thermal_bridge_width 0.5)
				(island_removal_mode 0)
			)
			(polygon
				(pts
					(xy 432.2572 -23.1648) (xy 431.7492 -23.1648) (xy 431.7492 -22.7838) (xy 432.2572 -22.7838)
				)
			)
		)
		(zone
			(layer "B.Cu")
			(hatch none 0.5)
			(connect_pads
				(clearance 0)
			)
			(min_thickness 0.25)
			(keepout
				(tracks not_allowed)
				(vias allowed)
				(pads allowed)
				(copperpour not_allowed)
				(footprints allowed)
			)
			(placement
				(enabled no)
				(sheetname "")
			)
			(fill
				(thermal_gap 0.5)
				(thermal_bridge_width 0.5)
				(island_removal_mode 0)
			)
			(polygon
				(pts
					(xy 432.2572 -22.7838) (xy 431.7492 -22.7838) (xy 431.7492 -23.1648) (xy 432.2572 -23.1648)
				)
			)
		)
	)
	(footprint ""
		(layer "B.Cu")
		(at 363.87024 -138.41857 90)
		(property "Reference" "R3L11"
			(at 0 0 90)
			(layer "B.SilkS")
			(hide yes)
			(effects
				(font
					(size 1.27 1.27)
				)
				(justify mirror)
			)
		)
		(property "Value" ""
			(at 0 0 90)
			(layer "B.Fab")
			(effects
				(font
					(size 1.27 1.27)
				)
				(justify mirror)
			)
		)
		(duplicate_pad_numbers_are_jumpers no)
		(fp_rect
			(start -0.2794 -0.1016)
			(end 0.2794 0.9906)
			(stroke
				(width 0)
				(type default)
			)
			(fill no)
			(layer "B.CrtYd")
		)
		(fp_line
			(start 0.2794 -0.1016)
			(end 0.2794 0.9906)
			(stroke
				(width 0.1)
				(type default)
			)
			(layer "B.Fab")
		)
		(fp_line
			(start -0.2794 -0.1016)
			(end 0.2794 -0.1016)
			(stroke
				(width 0.1)
				(type default)
			)
			(layer "B.Fab")
		)
		(fp_line
			(start 0.2794 0.9906)
			(end -0.2794 0.9906)
			(stroke
				(width 0.1)
				(type default)
			)
			(layer "B.Fab")
		)
		(fp_line
			(start -0.2794 0.9906)
			(end -0.2794 -0.1016)
			(stroke
				(width 0.1)
				(type default)
			)
			(layer "B.Fab")
		)
		(pad "1" smd rect
			(at 0 0 270)
			(size 0.508 0.508)
			(layers "B.Cu" "B.Mask" "B.Paste")
			(net "PVCCIO_CPU0")
		)
		(pad "2" smd rect
			(at 0 0.889 270)
			(size 0.508 0.508)
			(layers "B.Cu" "B.Mask" "B.Paste")
			(net "SVID_DIO1_CPU0_R")
		)
		(zone
			(layer "B.Cu")
			(hatch none 0.5)
			(connect_pads
				(clearance 0)
			)
			(min_thickness 0.25)
			(keepout
				(tracks not_allowed)
				(vias allowed)
				(pads allowed)
				(copperpour not_allowed)
				(footprints allowed)
			)
			(placement
				(enabled no)
				(sheetname "")
			)
			(fill
				(thermal_gap 0.5)
				(thermal_bridge_width 0.5)
				(island_removal_mode 0)
			)
			(polygon
				(pts
					(xy 364.12424 -138.16457) (xy 364.50524 -138.16457) (xy 364.50524 -138.67257) (xy 364.12424 -138.67257)
				)
			)
		)
		(zone
			(layer "B.Cu")
			(hatch none 0.5)
			(connect_pads
				(clearance 0)
			)
			(min_thickness 0.25)
			(keepout
				(tracks allowed)
				(vias not_allowed)
				(pads allowed)
				(copperpour not_allowed)
				(footprints allowed)
			)
			(placement
				(enabled no)
				(sheetname "")
			)
			(fill
				(thermal_gap 0.5)
				(thermal_bridge_width 0.5)
				(island_removal_mode 0)
			)
			(polygon
				(pts
					(xy 364.12424 -138.16457) (xy 364.50524 -138.16457) (xy 364.50524 -138.67257) (xy 364.12424 -138.67257)
				)
			)
		)
	)
	(footprint ""
		(layer "B.Cu")
		(at 479.95205 4.714748 180)
		(property "Reference" "C9F22"
			(at 0 0 0)
			(layer "B.SilkS")
			(hide yes)
			(effects
				(font
					(size 1.27 1.27)
				)
				(justify mirror)
			)
		)
		(property "Value" ""
			(at 0 0 0)
			(layer "B.Fab")
			(effects
				(font
					(size 1.27 1.27)
				)
				(justify mirror)
			)
		)
		(duplicate_pad_numbers_are_jumpers no)
		(fp_poly
			(pts
				(xy -0.3048 -0.1016) (xy -0.3048 0.9906) (xy 0.3048 0.9906) (xy 0.3048 -0.1016)
			)
			(stroke
				(width 0)
				(type default)
			)
			(fill no)
			(layer "B.CrtYd")
		)
		(fp_line
			(start 0.3048 0.9906)
			(end -0.3048 0.9906)
			(stroke
				(width 0.1)
				(type default)
			)
			(layer "B.Fab")
		)
		(fp_line
			(start 0.3048 -0.1016)
			(end 0.3048 0.9906)
			(stroke
				(width 0.1)
				(type default)
			)
			(layer "B.Fab")
		)
		(fp_line
			(start -0.3048 0.9906)
			(end -0.3048 -0.1016)
			(stroke
				(width 0.1)
				(type default)
			)
			(layer "B.Fab")
		)
		(fp_line
			(start -0.3048 -0.1016)
			(end 0.3048 -0.1016)
			(stroke
				(width 0.1)
				(type default)
			)
			(layer "B.Fab")
		)
		(pad "1" smd rect
			(at 0 0)
			(size 0.508 0.508)
			(layers "B.Cu" "B.Mask" "B.Paste")
			(net "LED_LAN_1_N")
		)
		(pad "2" smd rect
			(at 0 0.889)
			(size 0.508 0.508)
			(layers "B.Cu" "B.Mask" "B.Paste")
			(net "GND")
		)
		(zone
			(layer "B.Cu")
			(hatch none 0.5)
			(connect_pads
				(clearance 0)
			)
			(min_thickness 0.25)
			(keepout
				(tracks not_allowed)
				(vias allowed)
				(pads allowed)
				(copperpour not_allowed)
				(footprints allowed)
			)
			(placement
				(enabled no)
				(sheetname "")
			)
			(fill
				(thermal_gap 0.5)
				(thermal_bridge_width 0.5)
				(island_removal_mode 0)
			)
			(polygon
				(pts
					(xy 479.69805 4.079748) (xy 480.20605 4.079748) (xy 480.20605 4.460748) (xy 479.69805 4.460748)
				)
			)
		)
		(zone
			(layer "B.Cu")
			(hatch none 0.5)
			(connect_pads
				(clearance 0)
			)
			(min_thickness 0.25)
			(keepout
				(tracks allowed)
				(vias not_allowed)
				(pads allowed)
				(copperpour not_allowed)
				(footprints allowed)
			)
			(placement
				(enabled no)
				(sheetname "")
			)
			(fill
				(thermal_gap 0.5)
				(thermal_bridge_width 0.5)
				(island_removal_mode 0)
			)
			(polygon
				(pts
					(xy 479.69805 4.460748) (xy 480.20605 4.460748) (xy 480.20605 4.079748) (xy 479.69805 4.079748)
				)
			)
		)
	)
	(footprint ""
		(layer "B.Cu")
		(at 347.469206 1.043178 -90)
		(property "Reference" "C3U6"
			(at 0 0 90)
			(layer "B.SilkS")
			(hide yes)
			(effects
				(font
					(size 1.27 1.27)
				)
				(justify mirror)
			)
		)
		(property "Value" ""
			(at 0 0 90)
			(layer "B.Fab")
			(effects
				(font
					(size 1.27 1.27)
				)
				(justify mirror)
			)
		)
		(duplicate_pad_numbers_are_jumpers no)
		(fp_rect
			(start 0.7239 1.9939)
			(end -0.7239 -0.2159)
			(stroke
				(width 0)
				(type default)
			)
			(fill no)
			(layer "B.CrtYd")
		)
		(fp_line
			(start -0.7239 1.9939)
			(end -0.7239 -0.2159)
			(stroke
				(width 0.1)
				(type default)
			)
			(layer "B.Fab")
		)
		(fp_line
			(start 0.7239 1.9939)
			(end -0.7239 1.9939)
			(stroke
				(width 0.1)
				(type default)
			)
			(layer "B.Fab")
		)
		(fp_line
			(start -0.7239 -0.2159)
			(end 0.7239 -0.2159)
			(stroke
				(width 0.1)
				(type default)
			)
			(layer "B.Fab")
		)
		(fp_line
			(start 0.7239 -0.2159)
			(end 0.7239 1.9939)
			(stroke
				(width 0.1)
				(type default)
			)
			(layer "B.Fab")
		)
		(pad "1" smd rect
			(at 0 0 90)
			(size 1.27 1.016)
			(layers "B.Cu" "B.Mask" "B.Paste")
			(net "VR_FET_SW_P12V_STBY_PVDDQ_ABC")
		)
		(pad "2" smd rect
			(at 0 1.778 90)
			(size 1.27 1.016)
			(layers "B.Cu" "B.Mask" "B.Paste")
			(net "GND")
		)
		(zone
			(layer "B.Cu")
			(hatch none 0.5)
			(connect_pads
				(clearance 0)
			)
			(min_thickness 0.25)
			(keepout
				(tracks not_allowed)
				(vias allowed)
				(pads allowed)
				(copperpour not_allowed)
				(footprints allowed)
			)
			(placement
				(enabled no)
				(sheetname "")
			)
			(fill
				(thermal_gap 0.5)
				(thermal_bridge_width 0.5)
				(island_removal_mode 0)
			)
			(polygon
				(pts
					(xy 346.199206 1.678178) (xy 346.961206 1.678178) (xy 346.961206 0.408178) (xy 346.199206 0.408178)
				)
			)
		)
	)
	(footprint ""
		(layer "B.Cu")
		(at 479.9838 -42.5958 90)
		(property "Reference" "C1R24"
			(at 0 0 90)
			(layer "B.SilkS")
			(hide yes)
			(effects
				(font
					(size 1.27 1.27)
				)
				(justify mirror)
			)
		)
		(property "Value" ""
			(at 0 0 90)
			(layer "B.Fab")
			(effects
				(font
					(size 1.27 1.27)
				)
				(justify mirror)
			)
		)
		(duplicate_pad_numbers_are_jumpers no)
		(fp_poly
			(pts
				(xy -0.3048 -0.1016) (xy -0.3048 0.9906) (xy 0.3048 0.9906) (xy 0.3048 -0.1016)
			)
			(stroke
				(width 0)
				(type default)
			)
			(fill no)
			(layer "B.CrtYd")
		)
		(fp_line
			(start 0.3048 -0.1016)
			(end 0.3048 0.9906)
			(stroke
				(width 0.1)
				(type default)
			)
			(layer "B.Fab")
		)
		(fp_line
			(start -0.3048 -0.1016)
			(end 0.3048 -0.1016)
			(stroke
				(width 0.1)
				(type default)
			)
			(layer "B.Fab")
		)
		(fp_line
			(start 0.3048 0.9906)
			(end -0.3048 0.9906)
			(stroke
				(width 0.1)
				(type default)
			)
			(layer "B.Fab")
		)
		(fp_line
			(start -0.3048 0.9906)
			(end -0.3048 -0.1016)
			(stroke
				(width 0.1)
				(type default)
			)
			(layer "B.Fab")
		)
		(pad "1" smd rect
			(at 0 0 270)
			(size 0.508 0.508)
			(layers "B.Cu" "B.Mask" "B.Paste")
			(net "P0V9_LAN")
		)
		(pad "2" smd rect
			(at 0 0.889 270)
			(size 0.508 0.508)
			(layers "B.Cu" "B.Mask" "B.Paste")
			(net "GND")
		)
		(zone
			(layer "B.Cu")
			(hatch none 0.5)
			(connect_pads
				(clearance 0)
			)
			(min_thickness 0.25)
			(keepout
				(tracks allowed)
				(vias not_allowed)
				(pads allowed)
				(copperpour not_allowed)
				(footprints allowed)
			)
			(placement
				(enabled no)
				(sheetname "")
			)
			(fill
				(thermal_gap 0.5)
				(thermal_bridge_width 0.5)
				(island_removal_mode 0)
			)
			(polygon
				(pts
					(xy 480.2378 -42.8498) (xy 480.2378 -42.3418) (xy 480.6188 -42.3418) (xy 480.6188 -42.8498)
				)
			)
		)
		(zone
			(layer "B.Cu")
			(hatch none 0.5)
			(connect_pads
				(clearance 0)
			)
			(min_thickness 0.25)
			(keepout
				(tracks not_allowed)
				(vias allowed)
				(pads allowed)
				(copperpour not_allowed)
				(footprints allowed)
			)
			(placement
				(enabled no)
				(sheetname "")
			)
			(fill
				(thermal_gap 0.5)
				(thermal_bridge_width 0.5)
				(island_removal_mode 0)
			)
			(polygon
				(pts
					(xy 480.6188 -42.8498) (xy 480.6188 -42.3418) (xy 480.2378 -42.3418) (xy 480.2378 -42.8498)
				)
			)
		)
	)
	(footprint ""
		(layer "B.Cu")
		(at 466.5472 -123.444 -90)
		(property "Reference" "R1W10"
			(at -1.47828 0.78994 0)
			(unlocked yes)
			(layer "B.SilkS")
			(effects
				(font
					(size 0.4064 0.254)
					(thickness 0.1524)
				)
				(justify mirror)
			)
		)
		(property "Value" ""
			(at 0 0 90)
			(layer "B.Fab")
			(effects
				(font
					(size 1.27 1.27)
				)
				(justify mirror)
			)
		)
		(duplicate_pad_numbers_are_jumpers no)
		(fp_poly
			(pts
				(xy 0.7239 -0.2159) (xy -0.7239 -0.2159) (xy -0.7239 1.9939) (xy 0.7239 1.9939)
			)
			(stroke
				(width 0)
				(type default)
			)
			(fill no)
			(layer "B.CrtYd")
		)
		(fp_line
			(start -0.7239 1.9939)
			(end -0.7239 -0.2159)
			(stroke
				(width 0.1)
				(type default)
			)
			(layer "B.Fab")
		)
		(fp_line
			(start 0.7239 1.9939)
			(end -0.7239 1.9939)
			(stroke
				(width 0.1)
				(type default)
			)
			(layer "B.Fab")
		)
		(fp_line
			(start -0.7239 -0.2159)
			(end 0.7239 -0.2159)
			(stroke
				(width 0.1)
				(type default)
			)
			(layer "B.Fab")
		)
		(fp_line
			(start 0.7239 -0.2159)
			(end 0.7239 1.9939)
			(stroke
				(width 0.1)
				(type default)
			)
			(layer "B.Fab")
		)
		(pad "1" smd rect
			(at 0 0 90)
			(size 1.27 1.016)
			(layers "B.Cu" "B.Mask" "B.Paste")
			(net "P5V_STBY")
		)
		(pad "2" smd rect
			(at 0 1.778 90)
			(size 1.27 1.016)
			(layers "B.Cu" "B.Mask" "B.Paste")
			(net "P5V_TPS2061")
		)
		(zone
			(layer "B.Cu")
			(hatch none 0.5)
			(connect_pads
				(clearance 0)
			)
			(min_thickness 0.25)
			(keepout
				(tracks not_allowed)
				(vias allowed)
				(pads allowed)
				(copperpour not_allowed)
				(footprints allowed)
			)
			(placement
				(enabled no)
				(sheetname "")
			)
			(fill
				(thermal_gap 0.5)
				(thermal_bridge_width 0.5)
				(island_removal_mode 0)
			)
			(polygon
				(pts
					(xy 466.0392 -124.079) (xy 465.2772 -124.079) (xy 465.2772 -123.9901) (xy 465.2772 -122.809) (xy 466.0392 -122.809)
				)
			)
		)
	)
	(footprint ""
		(layer "B.Cu")
		(at 489.417614 -47.930054 90)
		(property "Reference" "R25W134"
			(at 0.8382 -0.67818 90)
			(unlocked yes)
			(layer "B.SilkS")
			(effects
				(font
					(size 0.4064 0.254)
					(thickness 0.1524)
				)
				(justify left mirror)
			)
		)
		(property "Value" ""
			(at 0 0 90)
			(layer "B.Fab")
			(effects
				(font
					(size 1.27 1.27)
				)
				(justify mirror)
			)
		)
		(duplicate_pad_numbers_are_jumpers no)
		(fp_poly
			(pts
				(xy 0.2794 -0.1016) (xy -0.2794 -0.1016) (xy -0.2794 0.9906) (xy 0.2794 0.9906)
			)
			(stroke
				(width 0)
				(type default)
			)
			(fill no)
			(layer "B.CrtYd")
		)
		(fp_line
			(start 0.2794 -0.1016)
			(end 0.2794 0.9906)
			(stroke
				(width 0.1)
				(type default)
			)
			(layer "B.Fab")
		)
		(fp_line
			(start -0.2794 -0.1016)
			(end 0.2794 -0.1016)
			(stroke
				(width 0.1)
				(type default)
			)
			(layer "B.Fab")
		)
		(fp_line
			(start 0.2794 0.9906)
			(end -0.2794 0.9906)
			(stroke
				(width 0.1)
				(type default)
			)
			(layer "B.Fab")
		)
		(fp_line
			(start -0.2794 0.9906)
			(end -0.2794 -0.1016)
			(stroke
				(width 0.1)
				(type default)
			)
			(layer "B.Fab")
		)
		(pad "1" smd rect
			(at 0 0 270)
			(size 0.508 0.508)
			(layers "B.Cu" "B.Mask" "B.Paste")
			(net "P3V3")
		)
		(pad "2" smd rect
			(at 0 0.889 270)
			(size 0.508 0.508)
			(layers "B.Cu" "B.Mask" "B.Paste")
			(net "Q25W2_GATE")
		)
		(zone
			(layer "B.Cu")
			(hatch none 0.5)
			(connect_pads
				(clearance 0)
			)
			(min_thickness 0.25)
			(keepout
				(tracks allowed)
				(vias not_allowed)
				(pads allowed)
				(copperpour not_allowed)
				(footprints allowed)
			)
			(placement
				(enabled no)
				(sheetname "")
			)
			(fill
				(thermal_gap 0.5)
				(thermal_bridge_width 0.5)
				(island_removal_mode 0)
			)
			(polygon
				(pts
					(xy 489.671614 -48.184054) (xy 489.671614 -47.676054) (xy 490.052614 -47.676054) (xy 490.052614 -48.184054)
				)
			)
		)
		(zone
			(layer "B.Cu")
			(hatch none 0.5)
			(connect_pads
				(clearance 0)
			)
			(min_thickness 0.25)
			(keepout
				(tracks not_allowed)
				(vias allowed)
				(pads allowed)
				(copperpour not_allowed)
				(footprints allowed)
			)
			(placement
				(enabled no)
				(sheetname "")
			)
			(fill
				(thermal_gap 0.5)
				(thermal_bridge_width 0.5)
				(island_removal_mode 0)
			)
			(polygon
				(pts
					(xy 490.052614 -48.184054) (xy 490.052614 -47.676054) (xy 489.671614 -47.676054) (xy 489.671614 -48.184054)
				)
			)
		)
	)
	(footprint ""
		(layer "B.Cu")
		(at 281.3812 -74.803 90)
		(property "Reference" "R4P7"
			(at 0 0 90)
			(layer "B.SilkS")
			(hide yes)
			(effects
				(font
					(size 1.27 1.27)
				)
				(justify mirror)
			)
		)
		(property "Value" ""
			(at 0 0 90)
			(layer "B.Fab")
			(effects
				(font
					(size 1.27 1.27)
				)
				(justify mirror)
			)
		)
		(duplicate_pad_numbers_are_jumpers no)
		(fp_rect
			(start -0.2794 -0.1016)
			(end 0.2794 0.9906)
			(stroke
				(width 0)
				(type default)
			)
			(fill no)
			(layer "B.CrtYd")
		)
		(fp_line
			(start 0.2794 -0.1016)
			(end 0.2794 0.9906)
			(stroke
				(width 0.1)
				(type default)
			)
			(layer "B.Fab")
		)
		(fp_line
			(start -0.2794 -0.1016)
			(end 0.2794 -0.1016)
			(stroke
				(width 0.1)
				(type default)
			)
			(layer "B.Fab")
		)
		(fp_line
			(start 0.2794 0.9906)
			(end -0.2794 0.9906)
			(stroke
				(width 0.1)
				(type default)
			)
			(layer "B.Fab")
		)
		(fp_line
			(start -0.2794 0.9906)
			(end -0.2794 -0.1016)
			(stroke
				(width 0.1)
				(type default)
			)
			(layer "B.Fab")
		)
		(pad "1" smd rect
			(at 0 0 270)
			(size 0.508 0.508)
			(layers "B.Cu" "B.Mask" "B.Paste")
			(net "GND")
		)
		(pad "2" smd rect
			(at 0 0.889 270)
			(size 0.508 0.508)
			(layers "B.Cu" "B.Mask" "B.Paste")
			(net "PD_CPU0_KSFC_DIS")
		)
		(zone
			(layer "B.Cu")
			(hatch none 0.5)
			(connect_pads
				(clearance 0)
			)
			(min_thickness 0.25)
			(keepout
				(tracks allowed)
				(vias not_allowed)
				(pads allowed)
				(copperpour not_allowed)
				(footprints allowed)
			)
			(placement
				(enabled no)
				(sheetname "")
			)
			(fill
				(thermal_gap 0.5)
				(thermal_bridge_width 0.5)
				(island_removal_mode 0)
			)
			(polygon
				(pts
					(xy 281.6352 -74.549) (xy 282.0162 -74.549) (xy 282.0162 -75.057) (xy 281.6352 -75.057)
				)
			)
		)
		(zone
			(layer "B.Cu")
			(hatch none 0.5)
			(connect_pads
				(clearance 0)
			)
			(min_thickness 0.25)
			(keepout
				(tracks not_allowed)
				(vias allowed)
				(pads allowed)
				(copperpour not_allowed)
				(footprints allowed)
			)
			(placement
				(enabled no)
				(sheetname "")
			)
			(fill
				(thermal_gap 0.5)
				(thermal_bridge_width 0.5)
				(island_removal_mode 0)
			)
			(polygon
				(pts
					(xy 281.6352 -74.549) (xy 282.0162 -74.549) (xy 282.0162 -75.057) (xy 281.6352 -75.057)
				)
			)
		)
	)
	(footprint ""
		(layer "B.Cu")
		(at 27.023568 -134.874 180)
		(property "Reference" "C9M2"
			(at 0 0 0)
			(layer "B.SilkS")
			(hide yes)
			(effects
				(font
					(size 1.27 1.27)
				)
				(justify mirror)
			)
		)
		(property "Value" ""
			(at 0 0 0)
			(layer "B.Fab")
			(effects
				(font
					(size 1.27 1.27)
				)
				(justify mirror)
			)
		)
		(duplicate_pad_numbers_are_jumpers no)
		(fp_poly
			(pts
				(xy -0.3048 -0.1016) (xy -0.3048 0.9906) (xy 0.3048 0.9906) (xy 0.3048 -0.1016)
			)
			(stroke
				(width 0)
				(type default)
			)
			(fill no)
			(layer "B.CrtYd")
		)
		(fp_line
			(start 0.3048 0.9906)
			(end -0.3048 0.9906)
			(stroke
				(width 0.1)
				(type default)
			)
			(layer "B.Fab")
		)
		(fp_line
			(start 0.3048 -0.1016)
			(end 0.3048 0.9906)
			(stroke
				(width 0.1)
				(type default)
			)
			(layer "B.Fab")
		)
		(fp_line
			(start -0.3048 0.9906)
			(end -0.3048 -0.1016)
			(stroke
				(width 0.1)
				(type default)
			)
			(layer "B.Fab")
		)
		(fp_line
			(start -0.3048 -0.1016)
			(end 0.3048 -0.1016)
			(stroke
				(width 0.1)
				(type default)
			)
			(layer "B.Fab")
		)
		(pad "1" smd rect
			(at 0 0)
			(size 0.508 0.508)
			(layers "B.Cu" "B.Mask" "B.Paste")
			(net "M_K_CPU_VREF")
		)
		(pad "2" smd rect
			(at 0 0.889)
			(size 0.508 0.508)
			(layers "B.Cu" "B.Mask" "B.Paste")
			(net "GND")
		)
		(zone
			(layer "B.Cu")
			(hatch none 0.5)
			(connect_pads
				(clearance 0)
			)
			(min_thickness 0.25)
			(keepout
				(tracks not_allowed)
				(vias allowed)
				(pads allowed)
				(copperpour not_allowed)
				(footprints allowed)
			)
			(placement
				(enabled no)
				(sheetname "")
			)
			(fill
				(thermal_gap 0.5)
				(thermal_bridge_width 0.5)
				(island_removal_mode 0)
			)
			(polygon
				(pts
					(xy 26.769568 -135.509) (xy 27.277568 -135.509) (xy 27.277568 -135.128) (xy 26.769568 -135.128)
				)
			)
		)
		(zone
			(layer "B.Cu")
			(hatch none 0.5)
			(connect_pads
				(clearance 0)
			)
			(min_thickness 0.25)
			(keepout
				(tracks allowed)
				(vias not_allowed)
				(pads allowed)
				(copperpour not_allowed)
				(footprints allowed)
			)
			(placement
				(enabled no)
				(sheetname "")
			)
			(fill
				(thermal_gap 0.5)
				(thermal_bridge_width 0.5)
				(island_removal_mode 0)
			)
			(polygon
				(pts
					(xy 26.769568 -135.128) (xy 27.277568 -135.128) (xy 27.277568 -135.509) (xy 26.769568 -135.509)
				)
			)
		)
	)
	(footprint ""
		(layer "B.Cu")
		(at 385.90474 -83.22056 90)
		(property "Reference" "C14W1"
			(at 0.8382 -0.67818 90)
			(unlocked yes)
			(layer "B.SilkS")
			(effects
				(font
					(size 0.4064 0.254)
					(thickness 0.1524)
				)
				(justify left mirror)
			)
		)
		(property "Value" ""
			(at 0 0 90)
			(layer "B.Fab")
			(effects
				(font
					(size 1.27 1.27)
				)
				(justify mirror)
			)
		)
		(duplicate_pad_numbers_are_jumpers no)
		(fp_poly
			(pts
				(xy -0.3048 -0.1016) (xy -0.3048 0.9906) (xy 0.3048 0.9906) (xy 0.3048 -0.1016)
			)
			(stroke
				(width 0)
				(type default)
			)
			(fill no)
			(layer "B.CrtYd")
		)
		(fp_line
			(start 0.3048 -0.1016)
			(end 0.3048 0.9906)
			(stroke
				(width 0.1)
				(type default)
			)
			(layer "B.Fab")
		)
		(fp_line
			(start -0.3048 -0.1016)
			(end 0.3048 -0.1016)
			(stroke
				(width 0.1)
				(type default)
			)
			(layer "B.Fab")
		)
		(fp_line
			(start 0.3048 0.9906)
			(end -0.3048 0.9906)
			(stroke
				(width 0.1)
				(type default)
			)
			(layer "B.Fab")
		)
		(fp_line
			(start -0.3048 0.9906)
			(end -0.3048 -0.1016)
			(stroke
				(width 0.1)
				(type default)
			)
			(layer "B.Fab")
		)
		(pad "1" smd rect
			(at 0 0 270)
			(size 0.508 0.508)
			(layers "B.Cu" "B.Mask" "B.Paste")
			(net "P3V3")
		)
		(pad "2" smd rect
			(at 0 0.889 270)
			(size 0.508 0.508)
			(layers "B.Cu" "B.Mask" "B.Paste")
			(net "GND")
		)
		(zone
			(layer "B.Cu")
			(hatch none 0.5)
			(connect_pads
				(clearance 0)
			)
			(min_thickness 0.25)
			(keepout
				(tracks allowed)
				(vias not_allowed)
				(pads allowed)
				(copperpour not_allowed)
				(footprints allowed)
			)
			(placement
				(enabled no)
				(sheetname "")
			)
			(fill
				(thermal_gap 0.5)
				(thermal_bridge_width 0.5)
				(island_removal_mode 0)
			)
			(polygon
				(pts
					(xy 386.15874 -83.47456) (xy 386.15874 -82.96656) (xy 386.53974 -82.96656) (xy 386.53974 -83.47456)
				)
			)
		)
		(zone
			(layer "B.Cu")
			(hatch none 0.5)
			(connect_pads
				(clearance 0)
			)
			(min_thickness 0.25)
			(keepout
				(tracks not_allowed)
				(vias allowed)
				(pads allowed)
				(copperpour not_allowed)
				(footprints allowed)
			)
			(placement
				(enabled no)
				(sheetname "")
			)
			(fill
				(thermal_gap 0.5)
				(thermal_bridge_width 0.5)
				(island_removal_mode 0)
			)
			(polygon
				(pts
					(xy 386.53974 -83.47456) (xy 386.53974 -82.96656) (xy 386.15874 -82.96656) (xy 386.15874 -83.47456)
				)
			)
		)
	)
	(footprint ""
		(layer "B.Cu")
		(at 401.193 -107.1245 180)
		(property "Reference" "R8C6"
			(at 0 0 0)
			(layer "B.SilkS")
			(hide yes)
			(effects
				(font
					(size 1.27 1.27)
				)
				(justify mirror)
			)
		)
		(property "Value" ""
			(at 0 0 0)
			(layer "B.Fab")
			(effects
				(font
					(size 1.27 1.27)
				)
				(justify mirror)
			)
		)
		(duplicate_pad_numbers_are_jumpers no)
		(fp_poly
			(pts
				(xy 0.2794 -0.1016) (xy -0.2794 -0.1016) (xy -0.2794 0.9906) (xy 0.2794 0.9906)
			)
			(stroke
				(width 0)
				(type default)
			)
			(fill no)
			(layer "B.CrtYd")
		)
		(fp_line
			(start 0.2794 0.9906)
			(end -0.2794 0.9906)
			(stroke
				(width 0.1)
				(type default)
			)
			(layer "B.Fab")
		)
		(fp_line
			(start 0.2794 -0.1016)
			(end 0.2794 0.9906)
			(stroke
				(width 0.1)
				(type default)
			)
			(layer "B.Fab")
		)
		(fp_line
			(start -0.2794 0.9906)
			(end -0.2794 -0.1016)
			(stroke
				(width 0.1)
				(type default)
			)
			(layer "B.Fab")
		)
		(fp_line
			(start -0.2794 -0.1016)
			(end 0.2794 -0.1016)
			(stroke
				(width 0.1)
				(type default)
			)
			(layer "B.Fab")
		)
		(pad "1" smd rect
			(at 0 0)
			(size 0.508 0.508)
			(layers "B.Cu" "B.Mask" "B.Paste")
			(net "P3V3_STBY")
		)
		(pad "2" smd rect
			(at 0 0.889)
			(size 0.508 0.508)
			(layers "B.Cu" "B.Mask" "B.Paste")
			(net "FM_BIOS_POST_CMPLT_N")
		)
		(zone
			(layer "B.Cu")
			(hatch none 0.5)
			(connect_pads
				(clearance 0)
			)
			(min_thickness 0.25)
			(keepout
				(tracks not_allowed)
				(vias allowed)
				(pads allowed)
				(copperpour not_allowed)
				(footprints allowed)
			)
			(placement
				(enabled no)
				(sheetname "")
			)
			(fill
				(thermal_gap 0.5)
				(thermal_bridge_width 0.5)
				(island_removal_mode 0)
			)
			(polygon
				(pts
					(xy 400.939 -107.7595) (xy 401.447 -107.7595) (xy 401.447 -107.3785) (xy 400.939 -107.3785)
				)
			)
		)
		(zone
			(layer "B.Cu")
			(hatch none 0.5)
			(connect_pads
				(clearance 0)
			)
			(min_thickness 0.25)
			(keepout
				(tracks allowed)
				(vias not_allowed)
				(pads allowed)
				(copperpour not_allowed)
				(footprints allowed)
			)
			(placement
				(enabled no)
				(sheetname "")
			)
			(fill
				(thermal_gap 0.5)
				(thermal_bridge_width 0.5)
				(island_removal_mode 0)
			)
			(polygon
				(pts
					(xy 400.939 -107.3785) (xy 401.447 -107.3785) (xy 401.447 -107.7595) (xy 400.939 -107.7595)
				)
			)
		)
	)
	(footprint ""
		(layer "B.Cu")
		(at 398.272 -27.432 180)
		(property "Reference" "R2T34"
			(at 0 0 0)
			(layer "B.SilkS")
			(hide yes)
			(effects
				(font
					(size 1.27 1.27)
				)
				(justify mirror)
			)
		)
		(property "Value" ""
			(at 0 0 0)
			(layer "B.Fab")
			(effects
				(font
					(size 1.27 1.27)
				)
				(justify mirror)
			)
		)
		(duplicate_pad_numbers_are_jumpers no)
		(fp_poly
			(pts
				(xy 0.2794 -0.1016) (xy -0.2794 -0.1016) (xy -0.2794 0.9906) (xy 0.2794 0.9906)
			)
			(stroke
				(width 0)
				(type default)
			)
			(fill no)
			(layer "B.CrtYd")
		)
		(fp_line
			(start 0.2794 0.9906)
			(end -0.2794 0.9906)
			(stroke
				(width 0.1)
				(type default)
			)
			(layer "B.Fab")
		)
		(fp_line
			(start 0.2794 -0.1016)
			(end 0.2794 0.9906)
			(stroke
				(width 0.1)
				(type default)
			)
			(layer "B.Fab")
		)
		(fp_line
			(start -0.2794 0.9906)
			(end -0.2794 -0.1016)
			(stroke
				(width 0.1)
				(type default)
			)
			(layer "B.Fab")
		)
		(fp_line
			(start -0.2794 -0.1016)
			(end 0.2794 -0.1016)
			(stroke
				(width 0.1)
				(type default)
			)
			(layer "B.Fab")
		)
		(pad "1" smd rect
			(at 0 0)
			(size 0.508 0.508)
			(layers "B.Cu" "B.Mask" "B.Paste")
			(net "P3V3_STBY")
		)
		(pad "2" smd rect
			(at 0 0.889)
			(size 0.508 0.508)
			(layers "B.Cu" "B.Mask" "B.Paste")
			(net "FM_BMC_PWRBTN_OUT_N")
		)
		(zone
			(layer "B.Cu")
			(hatch none 0.5)
			(connect_pads
				(clearance 0)
			)
			(min_thickness 0.25)
			(keepout
				(tracks not_allowed)
				(vias allowed)
				(pads allowed)
				(copperpour not_allowed)
				(footprints allowed)
			)
			(placement
				(enabled no)
				(sheetname "")
			)
			(fill
				(thermal_gap 0.5)
				(thermal_bridge_width 0.5)
				(island_removal_mode 0)
			)
			(polygon
				(pts
					(xy 398.018 -28.067) (xy 398.526 -28.067) (xy 398.526 -27.686) (xy 398.018 -27.686)
				)
			)
		)
		(zone
			(layer "B.Cu")
			(hatch none 0.5)
			(connect_pads
				(clearance 0)
			)
			(min_thickness 0.25)
			(keepout
				(tracks allowed)
				(vias not_allowed)
				(pads allowed)
				(copperpour not_allowed)
				(footprints allowed)
			)
			(placement
				(enabled no)
				(sheetname "")
			)
			(fill
				(thermal_gap 0.5)
				(thermal_bridge_width 0.5)
				(island_removal_mode 0)
			)
			(polygon
				(pts
					(xy 398.018 -27.686) (xy 398.526 -27.686) (xy 398.526 -28.067) (xy 398.018 -28.067)
				)
			)
		)
	)
	(footprint ""
		(layer "B.Cu")
		(at 370.745258 -75.494642 180)
		(property "Reference" "C3P43"
			(at 0 0 0)
			(layer "B.SilkS")
			(hide yes)
			(effects
				(font
					(size 1.27 1.27)
				)
				(justify mirror)
			)
		)
		(property "Value" ""
			(at 0 0 0)
			(layer "B.Fab")
			(effects
				(font
					(size 1.27 1.27)
				)
				(justify mirror)
			)
		)
		(duplicate_pad_numbers_are_jumpers no)
		(fp_rect
			(start 0.2794 0.9144)
			(end -0.2794 -0.1143)
			(stroke
				(width 0)
				(type default)
			)
			(fill no)
			(layer "B.CrtYd")
		)
		(fp_line
			(start 0.2794 0.9144)
			(end 0.2794 -0.1143)
			(stroke
				(width 0.1)
				(type default)
			)
			(layer "B.Fab")
		)
		(fp_line
			(start 0.2794 -0.1143)
			(end -0.2794 -0.1143)
			(stroke
				(width 0.1)
				(type default)
			)
			(layer "B.Fab")
		)
		(fp_line
			(start -0.2794 0.9144)
			(end 0.2794 0.9144)
			(stroke
				(width 0.1)
				(type default)
			)
			(layer "B.Fab")
		)
		(fp_line
			(start -0.2794 -0.1143)
			(end -0.2794 0.9144)
			(stroke
				(width 0.1)
				(type default)
			)
			(layer "B.Fab")
		)
		(pad "1" smd custom
			(at 0 0 90)
			(size 0.10414 0.10414)
			(layers "B.Cu" "B.Mask" "B.Paste")
			(net "P3V3_STBY")
			(options
				(clearance outline)
				(anchor circle)
			)
			(primitives
				(gr_poly
					(pts
						(xy -0.20828 -0.08636) (xy -0.20828 0.08636) (xy -0.08636 0.20828) (xy 0.086614 0.20828) (xy 0.20828 0.086614)
						(xy 0.20828 -0.08636) (xy 0.08636 -0.20828) (xy -0.08636 -0.20828)
					)
					(width 0)
					(fill yes)
				)
			)
		)
		(pad "2" smd custom
			(at 0 0.8001 90)
			(size 0.10414 0.10414)
			(layers "B.Cu" "B.Mask" "B.Paste")
			(net "GND")
			(options
				(clearance outline)
				(anchor circle)
			)
			(primitives
				(gr_poly
					(pts
						(xy -0.20828 -0.08636) (xy -0.20828 0.08636) (xy -0.08636 0.20828) (xy 0.086614 0.20828) (xy 0.20828 0.086614)
						(xy 0.20828 -0.08636) (xy 0.08636 -0.20828) (xy -0.08636 -0.20828)
					)
					(width 0)
					(fill yes)
				)
			)
		)
		(zone
			(layer "B.Cu")
			(hatch none 0.5)
			(connect_pads
				(clearance 0)
			)
			(min_thickness 0.25)
			(keepout
				(tracks not_allowed)
				(vias allowed)
				(pads allowed)
				(copperpour not_allowed)
				(footprints allowed)
			)
			(placement
				(enabled no)
				(sheetname "")
			)
			(fill
				(thermal_gap 0.5)
				(thermal_bridge_width 0.5)
				(island_removal_mode 0)
			)
			(polygon
				(pts
					(xy 370.657628 -75.704192) (xy 370.657628 -76.085192) (xy 370.832888 -76.085192) (xy 370.833142 -75.704192)
				)
			)
		)
		(zone
			(layer "B.Cu")
			(hatch none 0.5)
			(connect_pads
				(clearance 0)
			)
			(min_thickness 0.25)
			(keepout
				(tracks allowed)
				(vias not_allowed)
				(pads allowed)
				(copperpour not_allowed)
				(footprints allowed)
			)
			(placement
				(enabled no)
				(sheetname "")
			)
			(fill
				(thermal_gap 0.5)
				(thermal_bridge_width 0.5)
				(island_removal_mode 0)
			)
			(polygon
				(pts
					(xy 370.657628 -75.704192) (xy 370.657628 -76.085192) (xy 370.832888 -76.085192) (xy 370.833142 -75.704192)
				)
			)
		)
	)
	(footprint ""
		(layer "B.Cu")
		(at 350.110806 -60.368434)
		(property "Reference" "R2U26"
			(at 0 0 0)
			(layer "B.SilkS")
			(hide yes)
			(effects
				(font
					(size 1.27 1.27)
				)
				(justify mirror)
			)
		)
		(property "Value" ""
			(at 0 0 0)
			(layer "B.Fab")
			(effects
				(font
					(size 1.27 1.27)
				)
				(justify mirror)
			)
		)
		(duplicate_pad_numbers_are_jumpers no)
		(fp_poly
			(pts
				(xy 0.2794 -0.1016) (xy -0.2794 -0.1016) (xy -0.2794 0.9906) (xy 0.2794 0.9906)
			)
			(stroke
				(width 0)
				(type default)
			)
			(fill no)
			(layer "B.CrtYd")
		)
		(fp_line
			(start -0.2794 -0.1016)
			(end 0.2794 -0.1016)
			(stroke
				(width 0.1)
				(type default)
			)
			(layer "B.Fab")
		)
		(fp_line
			(start -0.2794 0.9906)
			(end -0.2794 -0.1016)
			(stroke
				(width 0.1)
				(type default)
			)
			(layer "B.Fab")
		)
		(fp_line
			(start 0.2794 -0.1016)
			(end 0.2794 0.9906)
			(stroke
				(width 0.1)
				(type default)
			)
			(layer "B.Fab")
		)
		(fp_line
			(start 0.2794 0.9906)
			(end -0.2794 0.9906)
			(stroke
				(width 0.1)
				(type default)
			)
			(layer "B.Fab")
		)
		(pad "1" smd rect
			(at 0 0 180)
			(size 0.508 0.508)
			(layers "B.Cu" "B.Mask" "B.Paste")
			(net "P3E_CPU0_PE1_SS_RXP<6>")
		)
		(pad "2" smd rect
			(at 0 0.889 180)
			(size 0.508 0.508)
			(layers "B.Cu" "B.Mask" "B.Paste")
			(net "P3E_CPU0_PE1_SS_R_RXP<6>")
		)
		(zone
			(layer "B.Cu")
			(hatch none 0.5)
			(connect_pads
				(clearance 0)
			)
			(min_thickness 0.25)
			(keepout
				(tracks allowed)
				(vias not_allowed)
				(pads allowed)
				(copperpour not_allowed)
				(footprints allowed)
			)
			(placement
				(enabled no)
				(sheetname "")
			)
			(fill
				(thermal_gap 0.5)
				(thermal_bridge_width 0.5)
				(island_removal_mode 0)
			)
			(polygon
				(pts
					(xy 350.364806 -60.114434) (xy 349.856806 -60.114434) (xy 349.856806 -59.733434) (xy 350.364806 -59.733434)
				)
			)
		)
		(zone
			(layer "B.Cu")
			(hatch none 0.5)
			(connect_pads
				(clearance 0)
			)
			(min_thickness 0.25)
			(keepout
				(tracks not_allowed)
				(vias allowed)
				(pads allowed)
				(copperpour not_allowed)
				(footprints allowed)
			)
			(placement
				(enabled no)
				(sheetname "")
			)
			(fill
				(thermal_gap 0.5)
				(thermal_bridge_width 0.5)
				(island_removal_mode 0)
			)
			(polygon
				(pts
					(xy 350.364806 -59.733434) (xy 349.856806 -59.733434) (xy 349.856806 -60.114434) (xy 350.364806 -60.114434)
				)
			)
		)
	)
	(footprint ""
		(layer "B.Cu")
		(at 343.125806 -61.257434)
		(property "Reference" "C2U10"
			(at 0 0 0)
			(layer "B.SilkS")
			(hide yes)
			(effects
				(font
					(size 1.27 1.27)
				)
				(justify mirror)
			)
		)
		(property "Value" ""
			(at 0 0 0)
			(layer "B.Fab")
			(effects
				(font
					(size 1.27 1.27)
				)
				(justify mirror)
			)
		)
		(duplicate_pad_numbers_are_jumpers no)
		(fp_poly
			(pts
				(xy -0.3048 -0.1016) (xy -0.3048 0.9906) (xy 0.3048 0.9906) (xy 0.3048 -0.1016)
			)
			(stroke
				(width 0)
				(type default)
			)
			(fill no)
			(layer "B.CrtYd")
		)
		(fp_line
			(start -0.3048 -0.1016)
			(end 0.3048 -0.1016)
			(stroke
				(width 0.1)
				(type default)
			)
			(layer "B.Fab")
		)
		(fp_line
			(start -0.3048 0.9906)
			(end -0.3048 -0.1016)
			(stroke
				(width 0.1)
				(type default)
			)
			(layer "B.Fab")
		)
		(fp_line
			(start 0.3048 -0.1016)
			(end 0.3048 0.9906)
			(stroke
				(width 0.1)
				(type default)
			)
			(layer "B.Fab")
		)
		(fp_line
			(start 0.3048 0.9906)
			(end -0.3048 0.9906)
			(stroke
				(width 0.1)
				(type default)
			)
			(layer "B.Fab")
		)
		(pad "1" smd rect
			(at 0 0 180)
			(size 0.508 0.508)
			(layers "B.Cu" "B.Mask" "B.Paste")
			(net "P3E_CPU0_PE1_PCH_RXN<3>")
		)
		(pad "2" smd rect
			(at 0 0.889 180)
			(size 0.508 0.508)
			(layers "B.Cu" "B.Mask" "B.Paste")
			(net "P3E_CPU0_PE1_SS_RXN<3>")
		)
		(zone
			(layer "B.Cu")
			(hatch none 0.5)
			(connect_pads
				(clearance 0)
			)
			(min_thickness 0.25)
			(keepout
				(tracks allowed)
				(vias not_allowed)
				(pads allowed)
				(copperpour not_allowed)
				(footprints allowed)
			)
			(placement
				(enabled no)
				(sheetname "")
			)
			(fill
				(thermal_gap 0.5)
				(thermal_bridge_width 0.5)
				(island_removal_mode 0)
			)
			(polygon
				(pts
					(xy 343.379806 -61.003434) (xy 342.871806 -61.003434) (xy 342.871806 -60.622434) (xy 343.379806 -60.622434)
				)
			)
		)
		(zone
			(layer "B.Cu")
			(hatch none 0.5)
			(connect_pads
				(clearance 0)
			)
			(min_thickness 0.25)
			(keepout
				(tracks not_allowed)
				(vias allowed)
				(pads allowed)
				(copperpour not_allowed)
				(footprints allowed)
			)
			(placement
				(enabled no)
				(sheetname "")
			)
			(fill
				(thermal_gap 0.5)
				(thermal_bridge_width 0.5)
				(island_removal_mode 0)
			)
			(polygon
				(pts
					(xy 343.379806 -60.622434) (xy 342.871806 -60.622434) (xy 342.871806 -61.003434) (xy 343.379806 -61.003434)
				)
			)
		)
	)
	(footprint ""
		(layer "B.Cu")
		(at 392.835384 -113.080038)
		(property "Reference" "R2M6"
			(at 0 0 0)
			(layer "B.SilkS")
			(hide yes)
			(effects
				(font
					(size 1.27 1.27)
				)
				(justify mirror)
			)
		)
		(property "Value" ""
			(at 0 0 0)
			(layer "B.Fab")
			(effects
				(font
					(size 1.27 1.27)
				)
				(justify mirror)
			)
		)
		(duplicate_pad_numbers_are_jumpers no)
		(fp_poly
			(pts
				(xy 0.2794 -0.1016) (xy -0.2794 -0.1016) (xy -0.2794 0.9906) (xy 0.2794 0.9906)
			)
			(stroke
				(width 0)
				(type default)
			)
			(fill no)
			(layer "B.CrtYd")
		)
		(fp_line
			(start -0.2794 -0.1016)
			(end 0.2794 -0.1016)
			(stroke
				(width 0.1)
				(type default)
			)
			(layer "B.Fab")
		)
		(fp_line
			(start -0.2794 0.9906)
			(end -0.2794 -0.1016)
			(stroke
				(width 0.1)
				(type default)
			)
			(layer "B.Fab")
		)
		(fp_line
			(start 0.2794 -0.1016)
			(end 0.2794 0.9906)
			(stroke
				(width 0.1)
				(type default)
			)
			(layer "B.Fab")
		)
		(fp_line
			(start 0.2794 0.9906)
			(end -0.2794 0.9906)
			(stroke
				(width 0.1)
				(type default)
			)
			(layer "B.Fab")
		)
		(pad "1" smd rect
			(at 0 0 180)
			(size 0.508 0.508)
			(layers "B.Cu" "B.Mask" "B.Paste")
			(net "A_KR1_RBIAS")
		)
		(pad "2" smd rect
			(at 0 0.889 180)
			(size 0.508 0.508)
			(layers "B.Cu" "B.Mask" "B.Paste")
			(net "P1V05_PCH_STBY_KR_PLL")
		)
		(zone
			(layer "B.Cu")
			(hatch none 0.5)
			(connect_pads
				(clearance 0)
			)
			(min_thickness 0.25)
			(keepout
				(tracks allowed)
				(vias not_allowed)
				(pads allowed)
				(copperpour not_allowed)
				(footprints allowed)
			)
			(placement
				(enabled no)
				(sheetname "")
			)
			(fill
				(thermal_gap 0.5)
				(thermal_bridge_width 0.5)
				(island_removal_mode 0)
			)
			(polygon
				(pts
					(xy 393.089384 -112.826038) (xy 392.581384 -112.826038) (xy 392.581384 -112.445038) (xy 393.089384 -112.445038)
				)
			)
		)
		(zone
			(layer "B.Cu")
			(hatch none 0.5)
			(connect_pads
				(clearance 0)
			)
			(min_thickness 0.25)
			(keepout
				(tracks not_allowed)
				(vias allowed)
				(pads allowed)
				(copperpour not_allowed)
				(footprints allowed)
			)
			(placement
				(enabled no)
				(sheetname "")
			)
			(fill
				(thermal_gap 0.5)
				(thermal_bridge_width 0.5)
				(island_removal_mode 0)
			)
			(polygon
				(pts
					(xy 393.089384 -112.445038) (xy 392.581384 -112.445038) (xy 392.581384 -112.826038) (xy 393.089384 -112.826038)
				)
			)
		)
	)
	(footprint ""
		(layer "B.Cu")
		(at 172.8724 -12.1412)
		(property "Reference" "C6U6"
			(at 0 0 0)
			(layer "B.SilkS")
			(hide yes)
			(effects
				(font
					(size 1.27 1.27)
				)
				(justify mirror)
			)
		)
		(property "Value" ""
			(at 0 0 0)
			(layer "B.Fab")
			(effects
				(font
					(size 1.27 1.27)
				)
				(justify mirror)
			)
		)
		(duplicate_pad_numbers_are_jumpers no)
		(fp_rect
			(start 0.4953 1.6002)
			(end -0.4953 -0.2032)
			(stroke
				(width 0)
				(type default)
			)
			(fill no)
			(layer "B.CrtYd")
		)
		(fp_line
			(start -0.4953 -0.2032)
			(end -0.4953 1.6002)
			(stroke
				(width 0.1)
				(type default)
			)
			(layer "B.Fab")
		)
		(fp_line
			(start -0.4953 1.6002)
			(end 0.4953 1.6002)
			(stroke
				(width 0.1)
				(type default)
			)
			(layer "B.Fab")
		)
		(fp_line
			(start 0.4953 -0.2032)
			(end -0.4953 -0.2032)
			(stroke
				(width 0.1)
				(type default)
			)
			(layer "B.Fab")
		)
		(fp_line
			(start 0.4953 1.6002)
			(end 0.4953 -0.2032)
			(stroke
				(width 0.1)
				(type default)
			)
			(layer "B.Fab")
		)
		(pad "1" smd rect
			(at 0 0 180)
			(size 0.762 0.889)
			(layers "B.Cu" "B.Mask" "B.Paste")
			(net "VR_VB_PVPP_GHJ")
		)
		(pad "2" smd rect
			(at 0 1.397 180)
			(size 0.762 0.889)
			(layers "B.Cu" "B.Mask" "B.Paste")
			(net "AGND_PVPP_GHJ")
		)
		(zone
			(layer "B.Cu")
			(hatch none 0.5)
			(connect_pads
				(clearance 0)
			)
			(min_thickness 0.25)
			(keepout
				(tracks not_allowed)
				(vias allowed)
				(pads allowed)
				(copperpour not_allowed)
				(footprints allowed)
			)
			(placement
				(enabled no)
				(sheetname "")
			)
			(fill
				(thermal_gap 0.5)
				(thermal_bridge_width 0.5)
				(island_removal_mode 0)
			)
			(polygon
				(pts
					(xy 173.2534 -11.1887) (xy 173.2534 -11.6967) (xy 172.4914 -11.6967) (xy 172.4914 -11.1887)
				)
			)
		)
	)
	(footprint ""
		(layer "B.Cu")
		(at 106.762296 -156.910024 -90)
		(property "Reference" "C8L1"
			(at 0 0 90)
			(layer "B.SilkS")
			(hide yes)
			(effects
				(font
					(size 1.27 1.27)
				)
				(justify mirror)
			)
		)
		(property "Value" ""
			(at 0 0 90)
			(layer "B.Fab")
			(effects
				(font
					(size 1.27 1.27)
				)
				(justify mirror)
			)
		)
		(duplicate_pad_numbers_are_jumpers no)
		(fp_poly
			(pts
				(xy 0.7239 -0.2159) (xy -0.7239 -0.2159) (xy -0.7239 1.9939) (xy 0.7239 1.9939)
			)
			(stroke
				(width 0)
				(type default)
			)
			(fill no)
			(layer "B.CrtYd")
		)
		(fp_line
			(start -0.7239 1.9939)
			(end -0.7239 -0.2159)
			(stroke
				(width 0.1)
				(type default)
			)
			(layer "B.Fab")
		)
		(fp_line
			(start 0.7239 1.9939)
			(end -0.7239 1.9939)
			(stroke
				(width 0.1)
				(type default)
			)
			(layer "B.Fab")
		)
		(fp_line
			(start -0.7239 -0.2159)
			(end 0.7239 -0.2159)
			(stroke
				(width 0.1)
				(type default)
			)
			(layer "B.Fab")
		)
		(fp_line
			(start 0.7239 -0.2159)
			(end 0.7239 1.9939)
			(stroke
				(width 0.1)
				(type default)
			)
			(layer "B.Fab")
		)
		(pad "1" smd rect
			(at 0 0 90)
			(size 1.27 1.016)
			(layers "B.Cu" "B.Mask" "B.Paste")
			(net "PVDDQ_KLM")
		)
		(pad "2" smd rect
			(at 0 1.778 90)
			(size 1.27 1.016)
			(layers "B.Cu" "B.Mask" "B.Paste")
			(net "GND")
		)
		(zone
			(layer "B.Cu")
			(hatch none 0.5)
			(connect_pads
				(clearance 0)
			)
			(min_thickness 0.25)
			(keepout
				(tracks not_allowed)
				(vias allowed)
				(pads allowed)
				(copperpour not_allowed)
				(footprints allowed)
			)
			(placement
				(enabled no)
				(sheetname "")
			)
			(fill
				(thermal_gap 0.5)
				(thermal_bridge_width 0.5)
				(island_removal_mode 0)
			)
			(polygon
				(pts
					(xy 106.254296 -156.275024) (xy 106.254296 -157.545024) (xy 105.492296 -157.545024) (xy 105.492296 -156.275024)
				)
			)
		)
	)
	(footprint ""
		(layer "B.Cu")
		(at 113.44148 -124.655834 90)
		(property "Reference" "C7M5"
			(at -1.71831 0.57658 0)
			(unlocked yes)
			(layer "B.SilkS")
			(effects
				(font
					(size 0.7874 0.5842)
					(thickness 0.1524)
				)
				(justify mirror)
			)
		)
		(property "Value" ""
			(at 0 0 90)
			(layer "B.Fab")
			(effects
				(font
					(size 1.27 1.27)
				)
				(justify mirror)
			)
		)
		(duplicate_pad_numbers_are_jumpers no)
		(fp_rect
			(start 0.500126 1.598422)
			(end -0.500126 -0.201422)
			(stroke
				(width 0)
				(type default)
			)
			(fill no)
			(layer "B.CrtYd")
		)
		(fp_line
			(start 0.500126 -0.201422)
			(end -0.500126 -0.201422)
			(stroke
				(width 0.1)
				(type default)
			)
			(layer "B.Fab")
		)
		(fp_line
			(start -0.500126 -0.201422)
			(end -0.500126 1.598422)
			(stroke
				(width 0.1)
				(type default)
			)
			(layer "B.Fab")
		)
		(fp_line
			(start 0.500126 1.598422)
			(end 0.500126 -0.201422)
			(stroke
				(width 0.1)
				(type default)
			)
			(layer "B.Fab")
		)
		(fp_line
			(start -0.500126 1.598422)
			(end 0.500126 1.598422)
			(stroke
				(width 0.1)
				(type default)
			)
			(layer "B.Fab")
		)
		(pad "1" smd rect
			(at 0 0)
			(size 0.889 0.9906)
			(layers "B.Cu" "B.Mask" "B.Paste")
			(net "PVDDQ_KLM")
		)
		(pad "2" smd rect
			(at 0 1.397)
			(size 0.889 0.9906)
			(layers "B.Cu" "B.Mask" "B.Paste")
			(net "GND")
		)
		(zone
			(layer "B.Cu")
			(hatch none 0.5)
			(connect_pads
				(clearance 0)
			)
			(min_thickness 0.25)
			(keepout
				(tracks allowed)
				(vias not_allowed)
				(pads allowed)
				(copperpour not_allowed)
				(footprints allowed)
			)
			(placement
				(enabled no)
				(sheetname "")
			)
			(fill
				(thermal_gap 0.5)
				(thermal_bridge_width 0.5)
				(island_removal_mode 0)
			)
			(polygon
				(pts
					(xy 114.39398 -125.151134) (xy 113.88598 -125.151134) (xy 113.88598 -124.160534) (xy 114.39398 -124.160534)
				)
			)
		)
		(zone
			(layer "B.Cu")
			(hatch none 0.5)
			(connect_pads
				(clearance 0)
			)
			(min_thickness 0.25)
			(keepout
				(tracks not_allowed)
				(vias allowed)
				(pads allowed)
				(copperpour not_allowed)
				(footprints allowed)
			)
			(placement
				(enabled no)
				(sheetname "")
			)
			(fill
				(thermal_gap 0.5)
				(thermal_bridge_width 0.5)
				(island_removal_mode 0)
			)
			(polygon
				(pts
					(xy 114.39398 -125.151134) (xy 113.88598 -125.151134) (xy 113.88598 -124.160534) (xy 114.39398 -124.160534)
				)
			)
		)
	)
	(footprint ""
		(layer "B.Cu")
		(at 468.341202 -36.435792 -90)
		(property "Reference" "C1T15"
			(at 0 0 90)
			(layer "B.SilkS")
			(hide yes)
			(effects
				(font
					(size 1.27 1.27)
				)
				(justify mirror)
			)
		)
		(property "Value" ""
			(at 0 0 90)
			(layer "B.Fab")
			(effects
				(font
					(size 1.27 1.27)
				)
				(justify mirror)
			)
		)
		(duplicate_pad_numbers_are_jumpers no)
		(fp_poly
			(pts
				(xy 0.4953 -0.2032) (xy -0.4953 -0.2032) (xy -0.4953 1.6002) (xy 0.4953 1.6002)
			)
			(stroke
				(width 0)
				(type default)
			)
			(fill no)
			(layer "B.CrtYd")
		)
		(fp_line
			(start -0.4953 1.6002)
			(end 0.4953 1.6002)
			(stroke
				(width 0.1)
				(type default)
			)
			(layer "B.Fab")
		)
		(fp_line
			(start 0.4953 1.6002)
			(end 0.4953 -0.2032)
			(stroke
				(width 0.1)
				(type default)
			)
			(layer "B.Fab")
		)
		(fp_line
			(start -0.4953 -0.2032)
			(end -0.4953 1.6002)
			(stroke
				(width 0.1)
				(type default)
			)
			(layer "B.Fab")
		)
		(fp_line
			(start 0.4953 -0.2032)
			(end -0.4953 -0.2032)
			(stroke
				(width 0.1)
				(type default)
			)
			(layer "B.Fab")
		)
		(pad "1" smd rect
			(at 0 0 90)
			(size 0.762 0.889)
			(layers "B.Cu" "B.Mask" "B.Paste")
			(net "P1V2_AUX_BMC")
		)
		(pad "2" smd rect
			(at 0 1.397 90)
			(size 0.762 0.889)
			(layers "B.Cu" "B.Mask" "B.Paste")
			(net "GND")
		)
		(zone
			(layer "B.Cu")
			(hatch none 0.5)
			(connect_pads
				(clearance 0)
			)
			(min_thickness 0.25)
			(keepout
				(tracks not_allowed)
				(vias allowed)
				(pads allowed)
				(copperpour not_allowed)
				(footprints allowed)
			)
			(placement
				(enabled no)
				(sheetname "")
			)
			(fill
				(thermal_gap 0.5)
				(thermal_bridge_width 0.5)
				(island_removal_mode 0)
			)
			(polygon
				(pts
					(xy 467.896702 -36.054792) (xy 467.896702 -36.816792) (xy 467.388702 -36.816792) (xy 467.388702 -36.054792)
				)
			)
		)
	)
	(footprint ""
		(layer "B.Cu")
		(at 378.587 -49.276 90)
		(property "Reference" "R3T2"
			(at 0 0 90)
			(layer "B.SilkS")
			(hide yes)
			(effects
				(font
					(size 1.27 1.27)
				)
				(justify mirror)
			)
		)
		(property "Value" ""
			(at 0 0 90)
			(layer "B.Fab")
			(effects
				(font
					(size 1.27 1.27)
				)
				(justify mirror)
			)
		)
		(duplicate_pad_numbers_are_jumpers no)
		(fp_poly
			(pts
				(xy 0.2794 -0.1016) (xy -0.2794 -0.1016) (xy -0.2794 0.9906) (xy 0.2794 0.9906)
			)
			(stroke
				(width 0)
				(type default)
			)
			(fill no)
			(layer "B.CrtYd")
		)
		(fp_line
			(start 0.2794 -0.1016)
			(end 0.2794 0.9906)
			(stroke
				(width 0.1)
				(type default)
			)
			(layer "B.Fab")
		)
		(fp_line
			(start -0.2794 -0.1016)
			(end 0.2794 -0.1016)
			(stroke
				(width 0.1)
				(type default)
			)
			(layer "B.Fab")
		)
		(fp_line
			(start 0.2794 0.9906)
			(end -0.2794 0.9906)
			(stroke
				(width 0.1)
				(type default)
			)
			(layer "B.Fab")
		)
		(fp_line
			(start -0.2794 0.9906)
			(end -0.2794 -0.1016)
			(stroke
				(width 0.1)
				(type default)
			)
			(layer "B.Fab")
		)
		(pad "1" smd rect
			(at 0 0 270)
			(size 0.508 0.508)
			(layers "B.Cu" "B.Mask" "B.Paste")
			(net "SPI_SWITCH_MISO")
		)
		(pad "2" smd rect
			(at 0 0.889 270)
			(size 0.508 0.508)
			(layers "B.Cu" "B.Mask" "B.Paste")
			(net "SPI_MISO_R1")
		)
		(zone
			(layer "B.Cu")
			(hatch none 0.5)
			(connect_pads
				(clearance 0)
			)
			(min_thickness 0.25)
			(keepout
				(tracks allowed)
				(vias not_allowed)
				(pads allowed)
				(copperpour not_allowed)
				(footprints allowed)
			)
			(placement
				(enabled no)
				(sheetname "")
			)
			(fill
				(thermal_gap 0.5)
				(thermal_bridge_width 0.5)
				(island_removal_mode 0)
			)
			(polygon
				(pts
					(xy 378.841 -49.53) (xy 378.841 -49.022) (xy 379.222 -49.022) (xy 379.222 -49.53)
				)
			)
		)
		(zone
			(layer "B.Cu")
			(hatch none 0.5)
			(connect_pads
				(clearance 0)
			)
			(min_thickness 0.25)
			(keepout
				(tracks not_allowed)
				(vias allowed)
				(pads allowed)
				(copperpour not_allowed)
				(footprints allowed)
			)
			(placement
				(enabled no)
				(sheetname "")
			)
			(fill
				(thermal_gap 0.5)
				(thermal_bridge_width 0.5)
				(island_removal_mode 0)
			)
			(polygon
				(pts
					(xy 379.222 -49.53) (xy 379.222 -49.022) (xy 378.841 -49.022) (xy 378.841 -49.53)
				)
			)
		)
	)
	(footprint ""
		(layer "B.Cu")
		(at 412.3055 -34.925 90)
		(property "Reference" "C25W23"
			(at 0.8382 -0.67818 90)
			(unlocked yes)
			(layer "B.SilkS")
			(effects
				(font
					(size 0.4064 0.254)
					(thickness 0.1524)
				)
				(justify left mirror)
			)
		)
		(property "Value" ""
			(at 0 0 90)
			(layer "B.Fab")
			(effects
				(font
					(size 1.27 1.27)
				)
				(justify mirror)
			)
		)
		(duplicate_pad_numbers_are_jumpers no)
		(fp_poly
			(pts
				(xy -0.3048 -0.1016) (xy -0.3048 0.9906) (xy 0.3048 0.9906) (xy 0.3048 -0.1016)
			)
			(stroke
				(width 0)
				(type default)
			)
			(fill no)
			(layer "B.CrtYd")
		)
		(fp_line
			(start 0.3048 -0.1016)
			(end 0.3048 0.9906)
			(stroke
				(width 0.1)
				(type default)
			)
			(layer "B.Fab")
		)
		(fp_line
			(start -0.3048 -0.1016)
			(end 0.3048 -0.1016)
			(stroke
				(width 0.1)
				(type default)
			)
			(layer "B.Fab")
		)
		(fp_line
			(start 0.3048 0.9906)
			(end -0.3048 0.9906)
			(stroke
				(width 0.1)
				(type default)
			)
			(layer "B.Fab")
		)
		(fp_line
			(start -0.3048 0.9906)
			(end -0.3048 -0.1016)
			(stroke
				(width 0.1)
				(type default)
			)
			(layer "B.Fab")
		)
		(pad "1" smd rect
			(at 0 0 270)
			(size 0.508 0.508)
			(layers "B.Cu" "B.Mask" "B.Paste")
			(net "P1V15_AUX_BMC")
		)
		(pad "2" smd rect
			(at 0 0.889 270)
			(size 0.508 0.508)
			(layers "B.Cu" "B.Mask" "B.Paste")
			(net "GND")
		)
		(zone
			(layer "B.Cu")
			(hatch none 0.5)
			(connect_pads
				(clearance 0)
			)
			(min_thickness 0.25)
			(keepout
				(tracks allowed)
				(vias not_allowed)
				(pads allowed)
				(copperpour not_allowed)
				(footprints allowed)
			)
			(placement
				(enabled no)
				(sheetname "")
			)
			(fill
				(thermal_gap 0.5)
				(thermal_bridge_width 0.5)
				(island_removal_mode 0)
			)
			(polygon
				(pts
					(xy 412.5595 -35.179) (xy 412.5595 -34.671) (xy 412.9405 -34.671) (xy 412.9405 -35.179)
				)
			)
		)
		(zone
			(layer "B.Cu")
			(hatch none 0.5)
			(connect_pads
				(clearance 0)
			)
			(min_thickness 0.25)
			(keepout
				(tracks not_allowed)
				(vias allowed)
				(pads allowed)
				(copperpour not_allowed)
				(footprints allowed)
			)
			(placement
				(enabled no)
				(sheetname "")
			)
			(fill
				(thermal_gap 0.5)
				(thermal_bridge_width 0.5)
				(island_removal_mode 0)
			)
			(polygon
				(pts
					(xy 412.9405 -35.179) (xy 412.9405 -34.671) (xy 412.5595 -34.671) (xy 412.5595 -35.179)
				)
			)
		)
	)
	(footprint ""
		(layer "B.Cu")
		(at 368.189256 -92.100654 90)
		(property "Reference" "R7W21"
			(at 0.8382 -0.67818 90)
			(unlocked yes)
			(layer "B.SilkS")
			(effects
				(font
					(size 0.4064 0.254)
					(thickness 0.1524)
				)
				(justify left mirror)
			)
		)
		(property "Value" ""
			(at 0 0 90)
			(layer "B.Fab")
			(effects
				(font
					(size 1.27 1.27)
				)
				(justify mirror)
			)
		)
		(duplicate_pad_numbers_are_jumpers no)
		(fp_poly
			(pts
				(xy 0.2794 -0.1016) (xy -0.2794 -0.1016) (xy -0.2794 0.9906) (xy 0.2794 0.9906)
			)
			(stroke
				(width 0)
				(type default)
			)
			(fill no)
			(layer "B.CrtYd")
		)
		(fp_line
			(start 0.2794 -0.1016)
			(end 0.2794 0.9906)
			(stroke
				(width 0.1)
				(type default)
			)
			(layer "B.Fab")
		)
		(fp_line
			(start -0.2794 -0.1016)
			(end 0.2794 -0.1016)
			(stroke
				(width 0.1)
				(type default)
			)
			(layer "B.Fab")
		)
		(fp_line
			(start 0.2794 0.9906)
			(end -0.2794 0.9906)
			(stroke
				(width 0.1)
				(type default)
			)
			(layer "B.Fab")
		)
		(fp_line
			(start -0.2794 0.9906)
			(end -0.2794 -0.1016)
			(stroke
				(width 0.1)
				(type default)
			)
			(layer "B.Fab")
		)
		(pad "1" smd rect
			(at 0 0 270)
			(size 0.508 0.508)
			(layers "B.Cu" "B.Mask" "B.Paste")
			(net "P3V3_STBY")
		)
		(pad "2" smd rect
			(at 0 0.889 270)
			(size 0.508 0.508)
			(layers "B.Cu" "B.Mask" "B.Paste")
			(net "RST_BMC_SRST_R_N")
		)
		(zone
			(layer "B.Cu")
			(hatch none 0.5)
			(connect_pads
				(clearance 0)
			)
			(min_thickness 0.25)
			(keepout
				(tracks allowed)
				(vias not_allowed)
				(pads allowed)
				(copperpour not_allowed)
				(footprints allowed)
			)
			(placement
				(enabled no)
				(sheetname "")
			)
			(fill
				(thermal_gap 0.5)
				(thermal_bridge_width 0.5)
				(island_removal_mode 0)
			)
			(polygon
				(pts
					(xy 368.443256 -92.354654) (xy 368.443256 -91.846654) (xy 368.824256 -91.846654) (xy 368.824256 -92.354654)
				)
			)
		)
		(zone
			(layer "B.Cu")
			(hatch none 0.5)
			(connect_pads
				(clearance 0)
			)
			(min_thickness 0.25)
			(keepout
				(tracks not_allowed)
				(vias allowed)
				(pads allowed)
				(copperpour not_allowed)
				(footprints allowed)
			)
			(placement
				(enabled no)
				(sheetname "")
			)
			(fill
				(thermal_gap 0.5)
				(thermal_bridge_width 0.5)
				(island_removal_mode 0)
			)
			(polygon
				(pts
					(xy 368.824256 -92.354654) (xy 368.824256 -91.846654) (xy 368.443256 -91.846654) (xy 368.443256 -92.354654)
				)
			)
		)
	)
	(footprint ""
		(layer "B.Cu")
		(at 349.4024 -109.474 -90)
		(property "Reference" "C3N14"
			(at 3.58267 0.4064 0)
			(unlocked yes)
			(layer "B.SilkS")
			(effects
				(font
					(size 0.7874 0.5842)
					(thickness 0.1524)
				)
				(justify mirror)
			)
		)
		(property "Value" ""
			(at 0 0 90)
			(layer "B.Fab")
			(effects
				(font
					(size 1.27 1.27)
				)
				(justify mirror)
			)
		)
		(duplicate_pad_numbers_are_jumpers no)
		(fp_line
			(start -2.286 7.366)
			(end -1.600708 7.366)
			(stroke
				(width 0.1524)
				(type default)
			)
			(layer "B.SilkS")
		)
		(fp_line
			(start -2.286 7.366)
			(end -2.286 1.63195)
			(stroke
				(width 0.1524)
				(type default)
			)
			(layer "B.SilkS")
		)
		(fp_line
			(start 2.286 7.366)
			(end 1.60147 7.366)
			(stroke
				(width 0.1524)
				(type default)
			)
			(layer "B.SilkS")
		)
		(fp_line
			(start 2.286 7.366)
			(end 2.286 1.632712)
			(stroke
				(width 0.1524)
				(type default)
			)
			(layer "B.SilkS")
		)
		(fp_line
			(start -2.504948 1.633728)
			(end -1.6002 1.633728)
			(stroke
				(width 0.1524)
				(type default)
			)
			(layer "B.SilkS")
		)
		(fp_line
			(start 2.563114 1.633728)
			(end 1.6002 1.633728)
			(stroke
				(width 0.1524)
				(type default)
			)
			(layer "B.SilkS")
		)
		(fp_line
			(start -2.504948 -1.616456)
			(end -2.504948 1.633728)
			(stroke
				(width 0.1524)
				(type default)
			)
			(layer "B.SilkS")
		)
		(fp_line
			(start -1.6002 -1.616456)
			(end -2.504948 -1.616456)
			(stroke
				(width 0.1524)
				(type default)
			)
			(layer "B.SilkS")
		)
		(fp_line
			(start 1.6002 -1.616456)
			(end 2.563114 -1.616456)
			(stroke
				(width 0.1524)
				(type default)
			)
			(layer "B.SilkS")
		)
		(fp_line
			(start 2.563114 -1.616456)
			(end 2.563114 1.633728)
			(stroke
				(width 0.1524)
				(type default)
			)
			(layer "B.SilkS")
		)
		(fp_rect
			(start 2.286 7.366)
			(end -2.286 -0.254)
			(stroke
				(width 0)
				(type default)
			)
			(fill no)
			(layer "B.CrtYd")
		)
		(fp_line
			(start -2.286 7.366)
			(end 2.286 7.366)
			(stroke
				(width 0.1)
				(type default)
			)
			(layer "B.Fab")
		)
		(fp_line
			(start 2.286 7.366)
			(end 2.286 -0.254)
			(stroke
				(width 0.1)
				(type default)
			)
			(layer "B.Fab")
		)
		(fp_line
			(start -2.286 -0.254)
			(end -2.286 7.366)
			(stroke
				(width 0.1)
				(type default)
			)
			(layer "B.Fab")
		)
		(fp_line
			(start 2.286 -0.254)
			(end -2.286 -0.254)
			(stroke
				(width 0.1)
				(type default)
			)
			(layer "B.Fab")
		)
		(pad "1" smd rect
			(at 0 0 90)
			(size 2.54 3.048)
			(layers "B.Cu" "B.Mask" "B.Paste")
			(net "PVCCIOMCP_CPU0")
		)
		(pad "2" smd rect
			(at 0 7.112 90)
			(size 2.54 3.048)
			(layers "B.Cu" "B.Mask" "B.Paste")
			(net "GND")
		)
	)
	(footprint ""
		(layer "B.Cu")
		(at 411.791658 -11.877802 -90)
		(property "Reference" "R2R9"
			(at 0 0 90)
			(layer "B.SilkS")
			(hide yes)
			(effects
				(font
					(size 1.27 1.27)
				)
				(justify mirror)
			)
		)
		(property "Value" ""
			(at 0 0 90)
			(layer "B.Fab")
			(effects
				(font
					(size 1.27 1.27)
				)
				(justify mirror)
			)
		)
		(duplicate_pad_numbers_are_jumpers no)
		(fp_poly
			(pts
				(xy 0.2794 -0.1016) (xy -0.2794 -0.1016) (xy -0.2794 0.9906) (xy 0.2794 0.9906)
			)
			(stroke
				(width 0)
				(type default)
			)
			(fill no)
			(layer "B.CrtYd")
		)
		(fp_line
			(start -0.2794 0.9906)
			(end -0.2794 -0.1016)
			(stroke
				(width 0.1)
				(type default)
			)
			(layer "B.Fab")
		)
		(fp_line
			(start 0.2794 0.9906)
			(end -0.2794 0.9906)
			(stroke
				(width 0.1)
				(type default)
			)
			(layer "B.Fab")
		)
		(fp_line
			(start -0.2794 -0.1016)
			(end 0.2794 -0.1016)
			(stroke
				(width 0.1)
				(type default)
			)
			(layer "B.Fab")
		)
		(fp_line
			(start 0.2794 -0.1016)
			(end 0.2794 0.9906)
			(stroke
				(width 0.1)
				(type default)
			)
			(layer "B.Fab")
		)
		(pad "1" smd rect
			(at 0 0 90)
			(size 0.508 0.508)
			(layers "B.Cu" "B.Mask" "B.Paste")
			(net "FP_NMI_BTN_OUT_R_N")
		)
		(pad "2" smd rect
			(at 0 0.889 90)
			(size 0.508 0.508)
			(layers "B.Cu" "B.Mask" "B.Paste")
			(net "FP_NMI_BTN_OUT_N")
		)
		(zone
			(layer "B.Cu")
			(hatch none 0.5)
			(connect_pads
				(clearance 0)
			)
			(min_thickness 0.25)
			(keepout
				(tracks not_allowed)
				(vias allowed)
				(pads allowed)
				(copperpour not_allowed)
				(footprints allowed)
			)
			(placement
				(enabled no)
				(sheetname "")
			)
			(fill
				(thermal_gap 0.5)
				(thermal_bridge_width 0.5)
				(island_removal_mode 0)
			)
			(polygon
				(pts
					(xy 411.156658 -11.623802) (xy 411.156658 -12.131802) (xy 411.537658 -12.131802) (xy 411.537658 -11.623802)
				)
			)
		)
		(zone
			(layer "B.Cu")
			(hatch none 0.5)
			(connect_pads
				(clearance 0)
			)
			(min_thickness 0.25)
			(keepout
				(tracks allowed)
				(vias not_allowed)
				(pads allowed)
				(copperpour not_allowed)
				(footprints allowed)
			)
			(placement
				(enabled no)
				(sheetname "")
			)
			(fill
				(thermal_gap 0.5)
				(thermal_bridge_width 0.5)
				(island_removal_mode 0)
			)
			(polygon
				(pts
					(xy 411.537658 -11.623802) (xy 411.537658 -12.131802) (xy 411.156658 -12.131802) (xy 411.156658 -11.623802)
				)
			)
		)
	)
	(footprint ""
		(layer "B.Cu")
		(at 265.864086 -77.82814)
		(property "Reference" "C5P23"
			(at 0 0 0)
			(layer "B.SilkS")
			(hide yes)
			(effects
				(font
					(size 1.27 1.27)
				)
				(justify mirror)
			)
		)
		(property "Value" ""
			(at 0 0 0)
			(layer "B.Fab")
			(effects
				(font
					(size 1.27 1.27)
				)
				(justify mirror)
			)
		)
		(duplicate_pad_numbers_are_jumpers no)
		(fp_poly
			(pts
				(xy 0.7239 -0.2159) (xy -0.7239 -0.2159) (xy -0.7239 1.9939) (xy 0.7239 1.9939)
			)
			(stroke
				(width 0)
				(type default)
			)
			(fill no)
			(layer "B.CrtYd")
		)
		(fp_line
			(start -0.7239 -0.2159)
			(end 0.7239 -0.2159)
			(stroke
				(width 0.1)
				(type default)
			)
			(layer "B.Fab")
		)
		(fp_line
			(start -0.7239 1.9939)
			(end -0.7239 -0.2159)
			(stroke
				(width 0.1)
				(type default)
			)
			(layer "B.Fab")
		)
		(fp_line
			(start 0.7239 -0.2159)
			(end 0.7239 1.9939)
			(stroke
				(width 0.1)
				(type default)
			)
			(layer "B.Fab")
		)
		(fp_line
			(start 0.7239 1.9939)
			(end -0.7239 1.9939)
			(stroke
				(width 0.1)
				(type default)
			)
			(layer "B.Fab")
		)
		(pad "1" smd rect
			(at 0 0 180)
			(size 1.27 1.016)
			(layers "B.Cu" "B.Mask" "B.Paste")
			(net "PVCCIN_CPU0")
		)
		(pad "2" smd rect
			(at 0 1.778 180)
			(size 1.27 1.016)
			(layers "B.Cu" "B.Mask" "B.Paste")
			(net "GND")
		)
		(zone
			(layer "B.Cu")
			(hatch none 0.5)
			(connect_pads
				(clearance 0)
			)
			(min_thickness 0.25)
			(keepout
				(tracks not_allowed)
				(vias allowed)
				(pads allowed)
				(copperpour not_allowed)
				(footprints allowed)
			)
			(placement
				(enabled no)
				(sheetname "")
			)
			(fill
				(thermal_gap 0.5)
				(thermal_bridge_width 0.5)
				(island_removal_mode 0)
			)
			(polygon
				(pts
					(xy 266.499086 -77.32014) (xy 265.229086 -77.32014) (xy 265.229086 -76.55814) (xy 266.499086 -76.55814)
				)
			)
		)
	)
	(footprint ""
		(layer "B.Cu")
		(at 318.543432 -135.382 -90)
		(property "Reference" "C4M4"
			(at 0 0 90)
			(layer "B.SilkS")
			(hide yes)
			(effects
				(font
					(size 1.27 1.27)
				)
				(justify mirror)
			)
		)
		(property "Value" ""
			(at 0 0 90)
			(layer "B.Fab")
			(effects
				(font
					(size 1.27 1.27)
				)
				(justify mirror)
			)
		)
		(duplicate_pad_numbers_are_jumpers no)
		(fp_poly
			(pts
				(xy 0.4953 -0.2032) (xy -0.4953 -0.2032) (xy -0.4953 1.6002) (xy 0.4953 1.6002)
			)
			(stroke
				(width 0)
				(type default)
			)
			(fill no)
			(layer "B.CrtYd")
		)
		(fp_line
			(start -0.4953 1.6002)
			(end 0.4953 1.6002)
			(stroke
				(width 0.1)
				(type default)
			)
			(layer "B.Fab")
		)
		(fp_line
			(start 0.4953 1.6002)
			(end 0.4953 -0.2032)
			(stroke
				(width 0.1)
				(type default)
			)
			(layer "B.Fab")
		)
		(fp_line
			(start -0.4953 -0.2032)
			(end -0.4953 1.6002)
			(stroke
				(width 0.1)
				(type default)
			)
			(layer "B.Fab")
		)
		(fp_line
			(start 0.4953 -0.2032)
			(end -0.4953 -0.2032)
			(stroke
				(width 0.1)
				(type default)
			)
			(layer "B.Fab")
		)
		(pad "1" smd rect
			(at 0 0 90)
			(size 0.762 0.889)
			(layers "B.Cu" "B.Mask" "B.Paste")
			(net "PVPP_DEF")
		)
		(pad "2" smd rect
			(at 0 1.397 90)
			(size 0.762 0.889)
			(layers "B.Cu" "B.Mask" "B.Paste")
			(net "GND")
		)
		(zone
			(layer "B.Cu")
			(hatch none 0.5)
			(connect_pads
				(clearance 0)
			)
			(min_thickness 0.25)
			(keepout
				(tracks not_allowed)
				(vias allowed)
				(pads allowed)
				(copperpour not_allowed)
				(footprints allowed)
			)
			(placement
				(enabled no)
				(sheetname "")
			)
			(fill
				(thermal_gap 0.5)
				(thermal_bridge_width 0.5)
				(island_removal_mode 0)
			)
			(polygon
				(pts
					(xy 318.098932 -135.001) (xy 318.098932 -135.763) (xy 317.590932 -135.763) (xy 317.590932 -135.001)
				)
			)
		)
	)
	(footprint ""
		(layer "B.Cu")
		(at 195.5546 -135.3312 90)
		(property "Reference" "C6M1"
			(at 0 0 90)
			(layer "B.SilkS")
			(hide yes)
			(effects
				(font
					(size 1.27 1.27)
				)
				(justify mirror)
			)
		)
		(property "Value" ""
			(at 0 0 90)
			(layer "B.Fab")
			(effects
				(font
					(size 1.27 1.27)
				)
				(justify mirror)
			)
		)
		(duplicate_pad_numbers_are_jumpers no)
		(fp_poly
			(pts
				(xy -0.3048 -0.1016) (xy -0.3048 0.9906) (xy 0.3048 0.9906) (xy 0.3048 -0.1016)
			)
			(stroke
				(width 0)
				(type default)
			)
			(fill no)
			(layer "B.CrtYd")
		)
		(fp_line
			(start 0.3048 -0.1016)
			(end 0.3048 0.9906)
			(stroke
				(width 0.1)
				(type default)
			)
			(layer "B.Fab")
		)
		(fp_line
			(start -0.3048 -0.1016)
			(end 0.3048 -0.1016)
			(stroke
				(width 0.1)
				(type default)
			)
			(layer "B.Fab")
		)
		(fp_line
			(start 0.3048 0.9906)
			(end -0.3048 0.9906)
			(stroke
				(width 0.1)
				(type default)
			)
			(layer "B.Fab")
		)
		(fp_line
			(start -0.3048 0.9906)
			(end -0.3048 -0.1016)
			(stroke
				(width 0.1)
				(type default)
			)
			(layer "B.Fab")
		)
		(pad "1" smd rect
			(at 0 0 270)
			(size 0.508 0.508)
			(layers "B.Cu" "B.Mask" "B.Paste")
			(net "M_D_VREF")
		)
		(pad "2" smd rect
			(at 0 0.889 270)
			(size 0.508 0.508)
			(layers "B.Cu" "B.Mask" "B.Paste")
			(net "GND")
		)
		(zone
			(layer "B.Cu")
			(hatch none 0.5)
			(connect_pads
				(clearance 0)
			)
			(min_thickness 0.25)
			(keepout
				(tracks allowed)
				(vias not_allowed)
				(pads allowed)
				(copperpour not_allowed)
				(footprints allowed)
			)
			(placement
				(enabled no)
				(sheetname "")
			)
			(fill
				(thermal_gap 0.5)
				(thermal_bridge_width 0.5)
				(island_removal_mode 0)
			)
			(polygon
				(pts
					(xy 195.8086 -135.5852) (xy 195.8086 -135.0772) (xy 196.1896 -135.0772) (xy 196.1896 -135.5852)
				)
			)
		)
		(zone
			(layer "B.Cu")
			(hatch none 0.5)
			(connect_pads
				(clearance 0)
			)
			(min_thickness 0.25)
			(keepout
				(tracks not_allowed)
				(vias allowed)
				(pads allowed)
				(copperpour not_allowed)
				(footprints allowed)
			)
			(placement
				(enabled no)
				(sheetname "")
			)
			(fill
				(thermal_gap 0.5)
				(thermal_bridge_width 0.5)
				(island_removal_mode 0)
			)
			(polygon
				(pts
					(xy 196.1896 -135.5852) (xy 196.1896 -135.0772) (xy 195.8086 -135.0772) (xy 195.8086 -135.5852)
				)
			)
		)
	)
	(footprint ""
		(layer "B.Cu")
		(at 434.132482 -147.504658 -90)
		(property "Reference" "R2L21"
			(at 0 0 90)
			(layer "B.SilkS")
			(hide yes)
			(effects
				(font
					(size 1.27 1.27)
				)
				(justify mirror)
			)
		)
		(property "Value" ""
			(at 0 0 90)
			(layer "B.Fab")
			(effects
				(font
					(size 1.27 1.27)
				)
				(justify mirror)
			)
		)
		(duplicate_pad_numbers_are_jumpers no)
		(fp_poly
			(pts
				(xy 0.2794 -0.1016) (xy -0.2794 -0.1016) (xy -0.2794 0.9906) (xy 0.2794 0.9906)
			)
			(stroke
				(width 0)
				(type default)
			)
			(fill no)
			(layer "B.CrtYd")
		)
		(fp_line
			(start -0.2794 0.9906)
			(end -0.2794 -0.1016)
			(stroke
				(width 0.1)
				(type default)
			)
			(layer "B.Fab")
		)
		(fp_line
			(start 0.2794 0.9906)
			(end -0.2794 0.9906)
			(stroke
				(width 0.1)
				(type default)
			)
			(layer "B.Fab")
		)
		(fp_line
			(start -0.2794 -0.1016)
			(end 0.2794 -0.1016)
			(stroke
				(width 0.1)
				(type default)
			)
			(layer "B.Fab")
		)
		(fp_line
			(start 0.2794 -0.1016)
			(end 0.2794 0.9906)
			(stroke
				(width 0.1)
				(type default)
			)
			(layer "B.Fab")
		)
		(pad "1" smd rect
			(at 0 0 90)
			(size 0.508 0.508)
			(layers "B.Cu" "B.Mask" "B.Paste")
			(net "P3V3")
		)
		(pad "2" smd rect
			(at 0 0.889 90)
			(size 0.508 0.508)
			(layers "B.Cu" "B.Mask" "B.Paste")
			(net "PU_DATAIN1_SATA_0_R")
		)
		(zone
			(layer "B.Cu")
			(hatch none 0.5)
			(connect_pads
				(clearance 0)
			)
			(min_thickness 0.25)
			(keepout
				(tracks not_allowed)
				(vias allowed)
				(pads allowed)
				(copperpour not_allowed)
				(footprints allowed)
			)
			(placement
				(enabled no)
				(sheetname "")
			)
			(fill
				(thermal_gap 0.5)
				(thermal_bridge_width 0.5)
				(island_removal_mode 0)
			)
			(polygon
				(pts
					(xy 433.497482 -147.250658) (xy 433.497482 -147.758658) (xy 433.878482 -147.758658) (xy 433.878482 -147.250658)
				)
			)
		)
		(zone
			(layer "B.Cu")
			(hatch none 0.5)
			(connect_pads
				(clearance 0)
			)
			(min_thickness 0.25)
			(keepout
				(tracks allowed)
				(vias not_allowed)
				(pads allowed)
				(copperpour not_allowed)
				(footprints allowed)
			)
			(placement
				(enabled no)
				(sheetname "")
			)
			(fill
				(thermal_gap 0.5)
				(thermal_bridge_width 0.5)
				(island_removal_mode 0)
			)
			(polygon
				(pts
					(xy 433.878482 -147.250658) (xy 433.878482 -147.758658) (xy 433.497482 -147.758658) (xy 433.497482 -147.250658)
				)
			)
		)
	)
	(footprint ""
		(layer "B.Cu")
		(at 314.760102 -29.511752 90)
		(property "Reference" "Q8W1"
			(at 0 -1.2065 90)
			(unlocked yes)
			(layer "B.SilkS")
			(effects
				(font
					(size 1.27 0.9652)
					(thickness 0.1524)
				)
				(justify left mirror)
			)
		)
		(property "Value" ""
			(at 0 0 90)
			(layer "B.Fab")
			(effects
				(font
					(size 1.27 1.27)
				)
				(justify mirror)
			)
		)
		(duplicate_pad_numbers_are_jumpers no)
		(fp_circle
			(center 0.603758 -0.604266)
			(end 0.603758 -0.477266)
			(stroke
				(width 0.254)
				(type default)
			)
			(fill no)
			(layer "B.SilkS")
		)
		(fp_poly
			(pts
				(xy -0.21463 -0.450088) (xy -1.56337 -0.450088) (xy -1.56337 1.75006) (xy -0.21463 1.75006)
			)
			(stroke
				(width 0)
				(type default)
			)
			(fill no)
			(layer "B.CrtYd")
		)
		(fp_line
			(start -0.21463 -0.450088)
			(end -1.56337 -0.450088)
			(stroke
				(width 0.1)
				(type default)
			)
			(layer "B.Fab")
		)
		(fp_line
			(start -1.56337 -0.450088)
			(end -1.56337 1.75006)
			(stroke
				(width 0.1)
				(type default)
			)
			(layer "B.Fab")
		)
		(fp_line
			(start -0.21463 1.75006)
			(end -0.21463 -0.450088)
			(stroke
				(width 0.1)
				(type default)
			)
			(layer "B.Fab")
		)
		(fp_line
			(start -1.56337 1.75006)
			(end -0.21463 1.75006)
			(stroke
				(width 0.1)
				(type default)
			)
			(layer "B.Fab")
		)
		(fp_circle
			(center 0.848614 -0.6477)
			(end 0.848614 -0.5207)
			(stroke
				(width 0.254)
				(type default)
			)
			(fill no)
			(layer "B.Fab")
		)
		(pad "1" smd rect
			(at 0 0 270)
			(size 1.016 0.381)
			(layers "B.Cu" "B.Mask" "B.Paste")
			(net "GND")
		)
		(pad "2" smd rect
			(at 0 0.649986 270)
			(size 1.016 0.381)
			(layers "B.Cu" "B.Mask" "B.Paste")
			(net "IRQ_DIMM_SAVE_LVT3_CPU1")
		)
		(pad "3" smd rect
			(at 0 1.299972 270)
			(size 1.016 0.381)
			(layers "B.Cu" "B.Mask" "B.Paste")
			(net "IRQ_DIMM_SAVE_LVT3_CPU1")
		)
		(pad "4" smd rect
			(at -1.778 1.299972 270)
			(size 1.016 0.381)
			(layers "B.Cu" "B.Mask" "B.Paste")
			(net "GND")
		)
		(pad "5" smd rect
			(at -1.778 0.649986 270)
			(size 1.016 0.381)
			(layers "B.Cu" "B.Mask" "B.Paste")
			(net "IRQ_DIMM_SAVE_CPU1_R_N")
		)
		(pad "6" smd rect
			(at -1.778 0 270)
			(size 1.016 0.381)
			(layers "B.Cu" "B.Mask" "B.Paste")
			(net "IRQ_DIMM_SAVE_LVT3_N")
		)
	)
	(footprint ""
		(layer "B.Cu")
		(at 353.6315 -74.549 -90)
		(property "Reference" "R3P35"
			(at 0 0 90)
			(layer "B.SilkS")
			(hide yes)
			(effects
				(font
					(size 1.27 1.27)
				)
				(justify mirror)
			)
		)
		(property "Value" ""
			(at 0 0 90)
			(layer "B.Fab")
			(effects
				(font
					(size 1.27 1.27)
				)
				(justify mirror)
			)
		)
		(duplicate_pad_numbers_are_jumpers no)
		(fp_poly
			(pts
				(xy 0.2794 -0.1016) (xy -0.2794 -0.1016) (xy -0.2794 0.9906) (xy 0.2794 0.9906)
			)
			(stroke
				(width 0)
				(type default)
			)
			(fill no)
			(layer "B.CrtYd")
		)
		(fp_line
			(start -0.2794 0.9906)
			(end -0.2794 -0.1016)
			(stroke
				(width 0.1)
				(type default)
			)
			(layer "B.Fab")
		)
		(fp_line
			(start 0.2794 0.9906)
			(end -0.2794 0.9906)
			(stroke
				(width 0.1)
				(type default)
			)
			(layer "B.Fab")
		)
		(fp_line
			(start -0.2794 -0.1016)
			(end 0.2794 -0.1016)
			(stroke
				(width 0.1)
				(type default)
			)
			(layer "B.Fab")
		)
		(fp_line
			(start 0.2794 -0.1016)
			(end 0.2794 0.9906)
			(stroke
				(width 0.1)
				(type default)
			)
			(layer "B.Fab")
		)
		(pad "1" smd rect
			(at 0 0 90)
			(size 0.508 0.508)
			(layers "B.Cu" "B.Mask" "B.Paste")
			(net "RST_CPU1_LVC3_R1_N")
		)
		(pad "2" smd rect
			(at 0 0.889 90)
			(size 0.508 0.508)
			(layers "B.Cu" "B.Mask" "B.Paste")
			(net "RST_CPU1_LVC3_N")
		)
		(zone
			(layer "B.Cu")
			(hatch none 0.5)
			(connect_pads
				(clearance 0)
			)
			(min_thickness 0.25)
			(keepout
				(tracks not_allowed)
				(vias allowed)
				(pads allowed)
				(copperpour not_allowed)
				(footprints allowed)
			)
			(placement
				(enabled no)
				(sheetname "")
			)
			(fill
				(thermal_gap 0.5)
				(thermal_bridge_width 0.5)
				(island_removal_mode 0)
			)
			(polygon
				(pts
					(xy 352.9965 -74.295) (xy 352.9965 -74.803) (xy 353.3775 -74.803) (xy 353.3775 -74.295)
				)
			)
		)
		(zone
			(layer "B.Cu")
			(hatch none 0.5)
			(connect_pads
				(clearance 0)
			)
			(min_thickness 0.25)
			(keepout
				(tracks allowed)
				(vias not_allowed)
				(pads allowed)
				(copperpour not_allowed)
				(footprints allowed)
			)
			(placement
				(enabled no)
				(sheetname "")
			)
			(fill
				(thermal_gap 0.5)
				(thermal_bridge_width 0.5)
				(island_removal_mode 0)
			)
			(polygon
				(pts
					(xy 353.3775 -74.295) (xy 353.3775 -74.803) (xy 352.9965 -74.803) (xy 352.9965 -74.295)
				)
			)
		)
	)
	(footprint ""
		(layer "B.Cu")
		(at 449.199 -131.318 -90)
		(property "Reference" "R1M20"
			(at 0 0 90)
			(layer "B.SilkS")
			(hide yes)
			(effects
				(font
					(size 1.27 1.27)
				)
				(justify mirror)
			)
		)
		(property "Value" ""
			(at 0 0 90)
			(layer "B.Fab")
			(effects
				(font
					(size 1.27 1.27)
				)
				(justify mirror)
			)
		)
		(duplicate_pad_numbers_are_jumpers no)
		(fp_poly
			(pts
				(xy 0.2794 -0.1016) (xy -0.2794 -0.1016) (xy -0.2794 0.9906) (xy 0.2794 0.9906)
			)
			(stroke
				(width 0)
				(type default)
			)
			(fill no)
			(layer "B.CrtYd")
		)
		(fp_line
			(start -0.2794 0.9906)
			(end -0.2794 -0.1016)
			(stroke
				(width 0.1)
				(type default)
			)
			(layer "B.Fab")
		)
		(fp_line
			(start 0.2794 0.9906)
			(end -0.2794 0.9906)
			(stroke
				(width 0.1)
				(type default)
			)
			(layer "B.Fab")
		)
		(fp_line
			(start -0.2794 -0.1016)
			(end 0.2794 -0.1016)
			(stroke
				(width 0.1)
				(type default)
			)
			(layer "B.Fab")
		)
		(fp_line
			(start 0.2794 -0.1016)
			(end 0.2794 0.9906)
			(stroke
				(width 0.1)
				(type default)
			)
			(layer "B.Fab")
		)
		(pad "1" smd rect
			(at 0 0 90)
			(size 0.508 0.508)
			(layers "B.Cu" "B.Mask" "B.Paste")
			(net "P1V8_MCP_CPU0")
		)
		(pad "2" smd rect
			(at 0 0.889 90)
			(size 0.508 0.508)
			(layers "B.Cu" "B.Mask" "B.Paste")
			(net "JTAG_MCP_MUX_TDI")
		)
		(zone
			(layer "B.Cu")
			(hatch none 0.5)
			(connect_pads
				(clearance 0)
			)
			(min_thickness 0.25)
			(keepout
				(tracks not_allowed)
				(vias allowed)
				(pads allowed)
				(copperpour not_allowed)
				(footprints allowed)
			)
			(placement
				(enabled no)
				(sheetname "")
			)
			(fill
				(thermal_gap 0.5)
				(thermal_bridge_width 0.5)
				(island_removal_mode 0)
			)
			(polygon
				(pts
					(xy 448.564 -131.064) (xy 448.564 -131.572) (xy 448.945 -131.572) (xy 448.945 -131.064)
				)
			)
		)
		(zone
			(layer "B.Cu")
			(hatch none 0.5)
			(connect_pads
				(clearance 0)
			)
			(min_thickness 0.25)
			(keepout
				(tracks allowed)
				(vias not_allowed)
				(pads allowed)
				(copperpour not_allowed)
				(footprints allowed)
			)
			(placement
				(enabled no)
				(sheetname "")
			)
			(fill
				(thermal_gap 0.5)
				(thermal_bridge_width 0.5)
				(island_removal_mode 0)
			)
			(polygon
				(pts
					(xy 448.945 -131.064) (xy 448.945 -131.572) (xy 448.564 -131.572) (xy 448.564 -131.064)
				)
			)
		)
	)
	(footprint ""
		(layer "B.Cu")
		(at 357.378 -33.782)
		(property "Reference" "C3T6"
			(at 3.27533 3.048 270)
			(unlocked yes)
			(layer "B.SilkS")
			(effects
				(font
					(size 0.7874 0.5842)
					(thickness 0.1524)
				)
				(justify mirror)
			)
		)
		(property "Value" ""
			(at 0 0 0)
			(layer "B.Fab")
			(effects
				(font
					(size 1.27 1.27)
				)
				(justify mirror)
			)
		)
		(duplicate_pad_numbers_are_jumpers no)
		(fp_line
			(start -2.504948 -1.616456)
			(end -2.504948 1.633728)
			(stroke
				(width 0.1524)
				(type default)
			)
			(layer "B.SilkS")
		)
		(fp_line
			(start -2.504948 1.633728)
			(end -1.6002 1.633728)
			(stroke
				(width 0.1524)
				(type default)
			)
			(layer "B.SilkS")
		)
		(fp_line
			(start -2.286 7.366)
			(end -2.286 1.63195)
			(stroke
				(width 0.1524)
				(type default)
			)
			(layer "B.SilkS")
		)
		(fp_line
			(start -2.286 7.366)
			(end -1.600708 7.366)
			(stroke
				(width 0.1524)
				(type default)
			)
			(layer "B.SilkS")
		)
		(fp_line
			(start -1.6002 -1.616456)
			(end -2.504948 -1.616456)
			(stroke
				(width 0.1524)
				(type default)
			)
			(layer "B.SilkS")
		)
		(fp_line
			(start 1.6002 -1.616456)
			(end 2.563114 -1.616456)
			(stroke
				(width 0.1524)
				(type default)
			)
			(layer "B.SilkS")
		)
		(fp_line
			(start 2.286 7.366)
			(end 1.60147 7.366)
			(stroke
				(width 0.1524)
				(type default)
			)
			(layer "B.SilkS")
		)
		(fp_line
			(start 2.286 7.366)
			(end 2.286 1.632712)
			(stroke
				(width 0.1524)
				(type default)
			)
			(layer "B.SilkS")
		)
		(fp_line
			(start 2.563114 -1.616456)
			(end 2.563114 1.633728)
			(stroke
				(width 0.1524)
				(type default)
			)
			(layer "B.SilkS")
		)
		(fp_line
			(start 2.563114 1.633728)
			(end 1.6002 1.633728)
			(stroke
				(width 0.1524)
				(type default)
			)
			(layer "B.SilkS")
		)
		(fp_rect
			(start 2.286 7.366)
			(end -2.286 -0.254)
			(stroke
				(width 0)
				(type default)
			)
			(fill no)
			(layer "B.CrtYd")
		)
		(fp_line
			(start -2.286 -0.254)
			(end -2.286 7.366)
			(stroke
				(width 0.1)
				(type default)
			)
			(layer "B.Fab")
		)
		(fp_line
			(start -2.286 7.366)
			(end 2.286 7.366)
			(stroke
				(width 0.1)
				(type default)
			)
			(layer "B.Fab")
		)
		(fp_line
			(start 2.286 -0.254)
			(end -2.286 -0.254)
			(stroke
				(width 0.1)
				(type default)
			)
			(layer "B.Fab")
		)
		(fp_line
			(start 2.286 7.366)
			(end 2.286 -0.254)
			(stroke
				(width 0.1)
				(type default)
			)
			(layer "B.Fab")
		)
		(pad "1" smd rect
			(at 0 0 180)
			(size 2.54 3.048)
			(layers "B.Cu" "B.Mask" "B.Paste")
			(net "P12V_STBY")
		)
		(pad "2" smd rect
			(at 0 7.112 180)
			(size 2.54 3.048)
			(layers "B.Cu" "B.Mask" "B.Paste")
			(net "GND")
		)
	)
	(footprint ""
		(layer "B.Cu")
		(at 459.359 -153.924 90)
		(property "Reference" "C1L1"
			(at 0 0 90)
			(layer "B.SilkS")
			(hide yes)
			(effects
				(font
					(size 1.27 1.27)
				)
				(justify mirror)
			)
		)
		(property "Value" ""
			(at 0 0 90)
			(layer "B.Fab")
			(effects
				(font
					(size 1.27 1.27)
				)
				(justify mirror)
			)
		)
		(duplicate_pad_numbers_are_jumpers no)
		(fp_poly
			(pts
				(xy -0.3048 -0.1016) (xy -0.3048 0.9906) (xy 0.3048 0.9906) (xy 0.3048 -0.1016)
			)
			(stroke
				(width 0)
				(type default)
			)
			(fill no)
			(layer "B.CrtYd")
		)
		(fp_line
			(start 0.3048 -0.1016)
			(end 0.3048 0.9906)
			(stroke
				(width 0.1)
				(type default)
			)
			(layer "B.Fab")
		)
		(fp_line
			(start -0.3048 -0.1016)
			(end 0.3048 -0.1016)
			(stroke
				(width 0.1)
				(type default)
			)
			(layer "B.Fab")
		)
		(fp_line
			(start 0.3048 0.9906)
			(end -0.3048 0.9906)
			(stroke
				(width 0.1)
				(type default)
			)
			(layer "B.Fab")
		)
		(fp_line
			(start -0.3048 0.9906)
			(end -0.3048 -0.1016)
			(stroke
				(width 0.1)
				(type default)
			)
			(layer "B.Fab")
		)
		(pad "1" smd rect
			(at 0 0 270)
			(size 0.508 0.508)
			(layers "B.Cu" "B.Mask" "B.Paste")
			(net "P3V3_STBY")
		)
		(pad "2" smd rect
			(at 0 0.889 270)
			(size 0.508 0.508)
			(layers "B.Cu" "B.Mask" "B.Paste")
			(net "GND")
		)
		(zone
			(layer "B.Cu")
			(hatch none 0.5)
			(connect_pads
				(clearance 0)
			)
			(min_thickness 0.25)
			(keepout
				(tracks allowed)
				(vias not_allowed)
				(pads allowed)
				(copperpour not_allowed)
				(footprints allowed)
			)
			(placement
				(enabled no)
				(sheetname "")
			)
			(fill
				(thermal_gap 0.5)
				(thermal_bridge_width 0.5)
				(island_removal_mode 0)
			)
			(polygon
				(pts
					(xy 459.613 -154.178) (xy 459.613 -153.67) (xy 459.994 -153.67) (xy 459.994 -154.178)
				)
			)
		)
		(zone
			(layer "B.Cu")
			(hatch none 0.5)
			(connect_pads
				(clearance 0)
			)
			(min_thickness 0.25)
			(keepout
				(tracks not_allowed)
				(vias allowed)
				(pads allowed)
				(copperpour not_allowed)
				(footprints allowed)
			)
			(placement
				(enabled no)
				(sheetname "")
			)
			(fill
				(thermal_gap 0.5)
				(thermal_bridge_width 0.5)
				(island_removal_mode 0)
			)
			(polygon
				(pts
					(xy 459.994 -154.178) (xy 459.994 -153.67) (xy 459.613 -153.67) (xy 459.613 -154.178)
				)
			)
		)
	)
	(footprint ""
		(layer "B.Cu")
		(at 401.20316 -54.25186)
		(property "Reference" "C3T5"
			(at 0 0 0)
			(layer "B.SilkS")
			(hide yes)
			(effects
				(font
					(size 1.27 1.27)
				)
				(justify mirror)
			)
		)
		(property "Value" ""
			(at 0 0 0)
			(layer "B.Fab")
			(effects
				(font
					(size 1.27 1.27)
				)
				(justify mirror)
			)
		)
		(duplicate_pad_numbers_are_jumpers no)
		(fp_poly
			(pts
				(xy -0.3048 -0.1016) (xy -0.3048 0.9906) (xy 0.3048 0.9906) (xy 0.3048 -0.1016)
			)
			(stroke
				(width 0)
				(type default)
			)
			(fill no)
			(layer "B.CrtYd")
		)
		(fp_line
			(start -0.3048 -0.1016)
			(end 0.3048 -0.1016)
			(stroke
				(width 0.1)
				(type default)
			)
			(layer "B.Fab")
		)
		(fp_line
			(start -0.3048 0.9906)
			(end -0.3048 -0.1016)
			(stroke
				(width 0.1)
				(type default)
			)
			(layer "B.Fab")
		)
		(fp_line
			(start 0.3048 -0.1016)
			(end 0.3048 0.9906)
			(stroke
				(width 0.1)
				(type default)
			)
			(layer "B.Fab")
		)
		(fp_line
			(start 0.3048 0.9906)
			(end -0.3048 0.9906)
			(stroke
				(width 0.1)
				(type default)
			)
			(layer "B.Fab")
		)
		(pad "1" smd rect
			(at 0 0 180)
			(size 0.508 0.508)
			(layers "B.Cu" "B.Mask" "B.Paste")
			(net "P3V3_STBY")
		)
		(pad "2" smd rect
			(at 0 0.889 180)
			(size 0.508 0.508)
			(layers "B.Cu" "B.Mask" "B.Paste")
			(net "GND")
		)
		(zone
			(layer "B.Cu")
			(hatch none 0.5)
			(connect_pads
				(clearance 0)
			)
			(min_thickness 0.25)
			(keepout
				(tracks allowed)
				(vias not_allowed)
				(pads allowed)
				(copperpour not_allowed)
				(footprints allowed)
			)
			(placement
				(enabled no)
				(sheetname "")
			)
			(fill
				(thermal_gap 0.5)
				(thermal_bridge_width 0.5)
				(island_removal_mode 0)
			)
			(polygon
				(pts
					(xy 401.45716 -53.99786) (xy 400.94916 -53.99786) (xy 400.94916 -53.61686) (xy 401.45716 -53.61686)
				)
			)
		)
		(zone
			(layer "B.Cu")
			(hatch none 0.5)
			(connect_pads
				(clearance 0)
			)
			(min_thickness 0.25)
			(keepout
				(tracks not_allowed)
				(vias allowed)
				(pads allowed)
				(copperpour not_allowed)
				(footprints allowed)
			)
			(placement
				(enabled no)
				(sheetname "")
			)
			(fill
				(thermal_gap 0.5)
				(thermal_bridge_width 0.5)
				(island_removal_mode 0)
			)
			(polygon
				(pts
					(xy 401.45716 -53.61686) (xy 400.94916 -53.61686) (xy 400.94916 -53.99786) (xy 401.45716 -53.99786)
				)
			)
		)
	)
	(footprint ""
		(layer "B.Cu")
		(at 427.795944 -11.947906 -90)
		(property "Reference" "R1U46"
			(at 0 0 90)
			(layer "B.SilkS")
			(hide yes)
			(effects
				(font
					(size 1.27 1.27)
				)
				(justify mirror)
			)
		)
		(property "Value" ""
			(at 0 0 90)
			(layer "B.Fab")
			(effects
				(font
					(size 1.27 1.27)
				)
				(justify mirror)
			)
		)
		(duplicate_pad_numbers_are_jumpers no)
		(fp_poly
			(pts
				(xy 0.2794 -0.1016) (xy -0.2794 -0.1016) (xy -0.2794 0.9906) (xy 0.2794 0.9906)
			)
			(stroke
				(width 0)
				(type default)
			)
			(fill no)
			(layer "B.CrtYd")
		)
		(fp_line
			(start -0.2794 0.9906)
			(end -0.2794 -0.1016)
			(stroke
				(width 0.1)
				(type default)
			)
			(layer "B.Fab")
		)
		(fp_line
			(start 0.2794 0.9906)
			(end -0.2794 0.9906)
			(stroke
				(width 0.1)
				(type default)
			)
			(layer "B.Fab")
		)
		(fp_line
			(start -0.2794 -0.1016)
			(end 0.2794 -0.1016)
			(stroke
				(width 0.1)
				(type default)
			)
			(layer "B.Fab")
		)
		(fp_line
			(start 0.2794 -0.1016)
			(end 0.2794 0.9906)
			(stroke
				(width 0.1)
				(type default)
			)
			(layer "B.Fab")
		)
		(pad "1" smd rect
			(at 0 0 90)
			(size 0.508 0.508)
			(layers "B.Cu" "B.Mask" "B.Paste")
			(net "H_CPU0_MEMABC_MEMHOT_LVT3_K_N")
		)
		(pad "2" smd rect
			(at 0 0.889 90)
			(size 0.508 0.508)
			(layers "B.Cu" "B.Mask" "B.Paste")
			(net "H_CPU0_MEMABC_MEMHOT_LVT3_N")
		)
		(zone
			(layer "B.Cu")
			(hatch none 0.5)
			(connect_pads
				(clearance 0)
			)
			(min_thickness 0.25)
			(keepout
				(tracks not_allowed)
				(vias allowed)
				(pads allowed)
				(copperpour not_allowed)
				(footprints allowed)
			)
			(placement
				(enabled no)
				(sheetname "")
			)
			(fill
				(thermal_gap 0.5)
				(thermal_bridge_width 0.5)
				(island_removal_mode 0)
			)
			(polygon
				(pts
					(xy 427.160944 -11.693906) (xy 427.160944 -12.201906) (xy 427.541944 -12.201906) (xy 427.541944 -11.693906)
				)
			)
		)
		(zone
			(layer "B.Cu")
			(hatch none 0.5)
			(connect_pads
				(clearance 0)
			)
			(min_thickness 0.25)
			(keepout
				(tracks allowed)
				(vias not_allowed)
				(pads allowed)
				(copperpour not_allowed)
				(footprints allowed)
			)
			(placement
				(enabled no)
				(sheetname "")
			)
			(fill
				(thermal_gap 0.5)
				(thermal_bridge_width 0.5)
				(island_removal_mode 0)
			)
			(polygon
				(pts
					(xy 427.541944 -11.693906) (xy 427.541944 -12.201906) (xy 427.160944 -12.201906) (xy 427.160944 -11.693906)
				)
			)
		)
	)
	(footprint ""
		(layer "B.Cu")
		(at 311.15 -123.8504)
		(property "Reference" ""
			(at 0 0 0)
			(layer "B.SilkS")
			(hide yes)
			(effects
				(font
					(size 1.27 1.27)
				)
				(justify mirror)
			)
		)
		(property "Value" ""
			(at 0 0 0)
			(layer "B.Fab")
			(effects
				(font
					(size 1.27 1.27)
				)
				(justify mirror)
			)
		)
		(duplicate_pad_numbers_are_jumpers no)
		(fp_poly
			(pts
				(arc
					(start 2.032 0)
					(mid -2.032 0)
					(end 2.032 0)
				)
			)
			(stroke
				(width 0)
				(type default)
			)
			(fill no)
			(layer "B.CrtYd")
		)
		(pad "1" smd circle
			(at 0 0 180)
			(size 1.016 1.016)
			(layers "B.Cu" "B.Mask" "B.Paste")
			(net "Net_397")
		)
		(zone
			(layers "F.Cu" "B.Cu" "In1.Cu" "In2.Cu" "In3.Cu" "In4.Cu" "In5.Cu" "In6.Cu"
				"In7.Cu" "In8.Cu" "In9.Cu" "In10.Cu" "In11.Cu" "In12.Cu"
			)
			(hatch none 0.5)
			(connect_pads
				(clearance 0)
			)
			(min_thickness 0.25)
			(keepout
				(tracks allowed)
				(vias not_allowed)
				(pads allowed)
				(copperpour not_allowed)
				(footprints allowed)
			)
			(placement
				(enabled no)
				(sheetname "")
			)
			(fill
				(thermal_gap 0.5)
				(thermal_bridge_width 0.5)
				(island_removal_mode 0)
			)
			(polygon
				(pts
					(arc
						(start 312.674 -123.8504)
						(mid 309.626 -123.8504)
						(end 312.674 -123.8504)
					)
				)
			)
		)
		(zone
			(layer "B.Cu")
			(hatch none 0.5)
			(connect_pads
				(clearance 0)
			)
			(min_thickness 0.25)
			(keepout
				(tracks not_allowed)
				(vias allowed)
				(pads allowed)
				(copperpour not_allowed)
				(footprints allowed)
			)
			(placement
				(enabled no)
				(sheetname "")
			)
			(fill
				(thermal_gap 0.5)
				(thermal_bridge_width 0.5)
				(island_removal_mode 0)
			)
			(polygon
				(pts
					(arc
						(start 312.674 -123.8504)
						(mid 309.626 -123.8504)
						(end 312.674 -123.8504)
					)
				)
			)
		)
	)
	(footprint ""
		(layer "B.Cu")
		(at 489.65739 -148.082 90)
		(property "Reference" "R1L11"
			(at 0 0 90)
			(layer "B.SilkS")
			(hide yes)
			(effects
				(font
					(size 1.27 1.27)
				)
				(justify mirror)
			)
		)
		(property "Value" ""
			(at 0 0 90)
			(layer "B.Fab")
			(effects
				(font
					(size 1.27 1.27)
				)
				(justify mirror)
			)
		)
		(duplicate_pad_numbers_are_jumpers no)
		(fp_poly
			(pts
				(xy 0.2794 -0.1016) (xy -0.2794 -0.1016) (xy -0.2794 0.9906) (xy 0.2794 0.9906)
			)
			(stroke
				(width 0)
				(type default)
			)
			(fill no)
			(layer "B.CrtYd")
		)
		(fp_line
			(start 0.2794 -0.1016)
			(end 0.2794 0.9906)
			(stroke
				(width 0.1)
				(type default)
			)
			(layer "B.Fab")
		)
		(fp_line
			(start -0.2794 -0.1016)
			(end 0.2794 -0.1016)
			(stroke
				(width 0.1)
				(type default)
			)
			(layer "B.Fab")
		)
		(fp_line
			(start 0.2794 0.9906)
			(end -0.2794 0.9906)
			(stroke
				(width 0.1)
				(type default)
			)
			(layer "B.Fab")
		)
		(fp_line
			(start -0.2794 0.9906)
			(end -0.2794 -0.1016)
			(stroke
				(width 0.1)
				(type default)
			)
			(layer "B.Fab")
		)
		(pad "1" smd rect
			(at 0 0 270)
			(size 0.508 0.508)
			(layers "B.Cu" "B.Mask" "B.Paste")
			(net "LED_POSTCODE_7")
		)
		(pad "2" smd rect
			(at 0 0.889 270)
			(size 0.508 0.508)
			(layers "B.Cu" "B.Mask" "B.Paste")
			(net "LED_POSTCODE_7_R")
		)
		(zone
			(layer "B.Cu")
			(hatch none 0.5)
			(connect_pads
				(clearance 0)
			)
			(min_thickness 0.25)
			(keepout
				(tracks allowed)
				(vias not_allowed)
				(pads allowed)
				(copperpour not_allowed)
				(footprints allowed)
			)
			(placement
				(enabled no)
				(sheetname "")
			)
			(fill
				(thermal_gap 0.5)
				(thermal_bridge_width 0.5)
				(island_removal_mode 0)
			)
			(polygon
				(pts
					(xy 489.91139 -148.336) (xy 489.91139 -147.828) (xy 490.29239 -147.828) (xy 490.29239 -148.336)
				)
			)
		)
		(zone
			(layer "B.Cu")
			(hatch none 0.5)
			(connect_pads
				(clearance 0)
			)
			(min_thickness 0.25)
			(keepout
				(tracks not_allowed)
				(vias allowed)
				(pads allowed)
				(copperpour not_allowed)
				(footprints allowed)
			)
			(placement
				(enabled no)
				(sheetname "")
			)
			(fill
				(thermal_gap 0.5)
				(thermal_bridge_width 0.5)
				(island_removal_mode 0)
			)
			(polygon
				(pts
					(xy 490.29239 -148.336) (xy 490.29239 -147.828) (xy 489.91139 -147.828) (xy 489.91139 -148.336)
				)
			)
		)
	)
	(footprint ""
		(layer "B.Cu")
		(at 459.753208 -136.144254 90)
		(property "Reference" "U1L5"
			(at 2.894076 -0.394208 0)
			(unlocked yes)
			(layer "B.SilkS")
			(effects
				(font
					(size 0.7874 0.5842)
					(thickness 0.1524)
				)
				(justify left mirror)
			)
		)
		(property "Value" ""
			(at 0 0 90)
			(layer "B.Fab")
			(effects
				(font
					(size 1.27 1.27)
				)
				(justify mirror)
			)
		)
		(duplicate_pad_numbers_are_jumpers no)
		(fp_circle
			(center 1.17856 -2.466086)
			(end 1.17856 -2.339086)
			(stroke
				(width 0.254)
				(type default)
			)
			(fill no)
			(layer "B.SilkS")
		)
		(fp_rect
			(start 0.9144 0.9144)
			(end -0.9144 -0.9144)
			(stroke
				(width 0)
				(type default)
			)
			(fill yes)
			(layer "B.Paste")
		)
		(fp_rect
			(start 1.82499 1.82499)
			(end -1.82499 -1.82499)
			(stroke
				(width 0)
				(type default)
			)
			(fill no)
			(layer "B.CrtYd")
		)
		(fp_line
			(start 1.82499 -1.82499)
			(end -1.82499 -1.82499)
			(stroke
				(width 0.1)
				(type default)
			)
			(layer "B.Fab")
		)
		(fp_line
			(start -1.82499 -1.82499)
			(end -1.82499 1.82499)
			(stroke
				(width 0.1)
				(type default)
			)
			(layer "B.Fab")
		)
		(fp_line
			(start 1.82499 1.82499)
			(end 1.82499 -1.82499)
			(stroke
				(width 0.1)
				(type default)
			)
			(layer "B.Fab")
		)
		(fp_line
			(start -1.82499 1.82499)
			(end 1.82499 1.82499)
			(stroke
				(width 0.1)
				(type default)
			)
			(layer "B.Fab")
		)
		(fp_circle
			(center 1.17856 -2.466086)
			(end 1.17856 -2.339086)
			(stroke
				(width 0.254)
				(type default)
			)
			(fill no)
			(layer "B.Fab")
		)
		(pad "1" smd custom
			(at 0.750062 -1.549908 270)
			(size 0.0762 0.0762)
			(layers "B.Cu" "B.Mask" "B.Paste")
			(net "PWRGD_PVCCIN_CPU0")
			(options
				(clearance outline)
				(anchor circle)
			)
			(primitives
				(gr_poly
					(pts
						(xy 0.1524 0.381)
						(arc
							(start 0.1524 -0.2286)
							(mid 0 -0.381)
							(end -0.1524 -0.2286)
						)
						(xy -0.1524 0.381)
					)
					(width 0)
					(fill yes)
				)
			)
		)
		(pad "2" smd custom
			(at 1.549908 -0.999998 270)
			(size 0.0762 0.0762)
			(layers "B.Cu" "B.Mask" "B.Paste")
			(net "XDP_OBSFN_B1_MBP7_N")
			(options
				(clearance outline)
				(anchor circle)
			)
			(primitives
				(gr_poly
					(pts
						(xy -0.381 0.1524)
						(arc
							(start 0.2286 0.1524)
							(mid 0.381 0)
							(end 0.2286 -0.1524)
						)
						(xy -0.381 -0.1524)
					)
					(width 0)
					(fill yes)
				)
			)
		)
		(pad "3" smd custom
			(at 1.549908 -0.500126 270)
			(size 0.0762 0.0762)
			(layers "B.Cu" "B.Mask" "B.Paste")
			(net "XDP_CPU_OBSFN_B1_MBP7_N")
			(options
				(clearance outline)
				(anchor circle)
			)
			(primitives
				(gr_poly
					(pts
						(xy -0.381 0.1524)
						(arc
							(start 0.2286 0.1524)
							(mid 0.381 0)
							(end 0.2286 -0.1524)
						)
						(xy -0.381 -0.1524)
					)
					(width 0)
					(fill yes)
				)
			)
		)
		(pad "4" smd custom
			(at 1.549908 0 270)
			(size 0.0762 0.0762)
			(layers "B.Cu" "B.Mask" "B.Paste")
			(net "PWRGD_PVCCIN_CPU0")
			(options
				(clearance outline)
				(anchor circle)
			)
			(primitives
				(gr_poly
					(pts
						(xy -0.381 0.1524)
						(arc
							(start 0.2286 0.1524)
							(mid 0.381 0)
							(end 0.2286 -0.1524)
						)
						(xy -0.381 -0.1524)
					)
					(width 0)
					(fill yes)
				)
			)
		)
		(pad "5" smd custom
			(at 1.549908 0.500126 270)
			(size 0.0762 0.0762)
			(layers "B.Cu" "B.Mask" "B.Paste")
			(net "XDP_OBSFN_B0_MBP6_N")
			(options
				(clearance outline)
				(anchor circle)
			)
			(primitives
				(gr_poly
					(pts
						(xy -0.381 0.1524)
						(arc
							(start 0.2286 0.1524)
							(mid 0.381 0)
							(end 0.2286 -0.1524)
						)
						(xy -0.381 -0.1524)
					)
					(width 0)
					(fill yes)
				)
			)
		)
		(pad "6" smd custom
			(at 1.549908 0.999998 270)
			(size 0.0762 0.0762)
			(layers "B.Cu" "B.Mask" "B.Paste")
			(net "XDP_CPU_OBSFN_B0_MBP6_N")
			(options
				(clearance outline)
				(anchor circle)
			)
			(primitives
				(gr_poly
					(pts
						(xy -0.381 0.1524)
						(arc
							(start 0.2286 0.1524)
							(mid 0.381 0)
							(end 0.2286 -0.1524)
						)
						(xy -0.381 -0.1524)
					)
					(width 0)
					(fill yes)
				)
			)
		)
		(pad "7" smd custom
			(at 0.750062 1.549908 270)
			(size 0.0762 0.0762)
			(layers "B.Cu" "B.Mask" "B.Paste")
			(net "GND")
			(options
				(clearance outline)
				(anchor circle)
			)
			(primitives
				(gr_poly
					(pts
						(xy -0.1524 -0.381)
						(arc
							(start -0.1524 0.2286)
							(mid 0 0.381)
							(end 0.1524 0.2286)
						)
						(xy 0.1524 -0.381)
					)
					(width 0)
					(fill yes)
				)
			)
		)
		(pad "8" smd custom
			(at -0.769874 1.549908 270)
			(size 0.0762 0.0762)
			(layers "B.Cu" "B.Mask" "B.Paste")
			(net "XDP_CPU_PRDY_N")
			(options
				(clearance outline)
				(anchor circle)
			)
			(primitives
				(gr_poly
					(pts
						(xy -0.1524 -0.381)
						(arc
							(start -0.1524 0.2286)
							(mid 0 0.381)
							(end 0.1524 0.2286)
						)
						(xy 0.1524 -0.381)
					)
					(width 0)
					(fill yes)
				)
			)
		)
		(pad "9" smd custom
			(at -1.549908 0.999998 270)
			(size 0.0762 0.0762)
			(layers "B.Cu" "B.Mask" "B.Paste")
			(net "XDP_PRDY_N")
			(options
				(clearance outline)
				(anchor circle)
			)
			(primitives
				(gr_poly
					(pts
						(xy 0.381 -0.1524)
						(arc
							(start -0.2286 -0.1524)
							(mid -0.381 0)
							(end -0.2286 0.1524)
						)
						(xy 0.381 0.1524)
					)
					(width 0)
					(fill yes)
				)
			)
		)
		(pad "10" smd custom
			(at -1.549908 0.500126 270)
			(size 0.0762 0.0762)
			(layers "B.Cu" "B.Mask" "B.Paste")
			(net "PWRGD_PVCCIN_CPU0")
			(options
				(clearance outline)
				(anchor circle)
			)
			(primitives
				(gr_poly
					(pts
						(xy 0.381 -0.1524)
						(arc
							(start -0.2286 -0.1524)
							(mid -0.381 0)
							(end -0.2286 0.1524)
						)
						(xy 0.381 0.1524)
					)
					(width 0)
					(fill yes)
				)
			)
		)
		(pad "11" smd custom
			(at -1.549908 0 270)
			(size 0.0762 0.0762)
			(layers "B.Cu" "B.Mask" "B.Paste")
			(net "XDP_CPU_PREQ_N")
			(options
				(clearance outline)
				(anchor circle)
			)
			(primitives
				(gr_poly
					(pts
						(xy 0.381 -0.1524)
						(arc
							(start -0.2286 -0.1524)
							(mid -0.381 0)
							(end -0.2286 0.1524)
						)
						(xy 0.381 0.1524)
					)
					(width 0)
					(fill yes)
				)
			)
		)
		(pad "12" smd custom
			(at -1.549908 -0.500126 270)
			(size 0.0762 0.0762)
			(layers "B.Cu" "B.Mask" "B.Paste")
			(net "XDP_PREQ_N")
			(options
				(clearance outline)
				(anchor circle)
			)
			(primitives
				(gr_poly
					(pts
						(xy 0.381 -0.1524)
						(arc
							(start -0.2286 -0.1524)
							(mid -0.381 0)
							(end -0.2286 0.1524)
						)
						(xy 0.381 0.1524)
					)
					(width 0)
					(fill yes)
				)
			)
		)
		(pad "13" smd custom
			(at -1.549908 -0.999998 270)
			(size 0.0762 0.0762)
			(layers "B.Cu" "B.Mask" "B.Paste")
			(net "PWRGD_PVCCIN_CPU0")
			(options
				(clearance outline)
				(anchor circle)
			)
			(primitives
				(gr_poly
					(pts
						(xy 0.381 -0.1524)
						(arc
							(start -0.2286 -0.1524)
							(mid -0.381 0)
							(end -0.2286 0.1524)
						)
						(xy 0.381 0.1524)
					)
					(width 0)
					(fill yes)
				)
			)
		)
		(pad "14" smd custom
			(at -0.750062 -1.549908 270)
			(size 0.0762 0.0762)
			(layers "B.Cu" "B.Mask" "B.Paste")
			(net "P3V3_STBY")
			(options
				(clearance outline)
				(anchor circle)
			)
			(primitives
				(gr_poly
					(pts
						(xy 0.1524 0.381)
						(arc
							(start 0.1524 -0.2286)
							(mid 0 -0.381)
							(end -0.1524 -0.2286)
						)
						(xy -0.1524 0.381)
					)
					(width 0)
					(fill yes)
				)
			)
		)
		(pad "15" smd rect
			(at 0 0 270)
			(size 1.8288 1.8288)
			(layers "B.Cu" "B.Mask" "B.Paste")
			(net "GND")
		)
	)
	(footprint ""
		(layer "B.Cu")
		(at 377.75642 -67.2211)
		(property "Reference" "R1W26"
			(at 0.8382 -0.67818 0)
			(unlocked yes)
			(layer "B.SilkS")
			(effects
				(font
					(size 0.4064 0.254)
					(thickness 0.1524)
				)
				(justify left mirror)
			)
		)
		(property "Value" ""
			(at 0 0 0)
			(layer "B.Fab")
			(effects
				(font
					(size 1.27 1.27)
				)
				(justify mirror)
			)
		)
		(duplicate_pad_numbers_are_jumpers no)
		(fp_poly
			(pts
				(xy 0.2794 -0.1016) (xy -0.2794 -0.1016) (xy -0.2794 0.9906) (xy 0.2794 0.9906)
			)
			(stroke
				(width 0)
				(type default)
			)
			(fill no)
			(layer "B.CrtYd")
		)
		(fp_line
			(start -0.2794 -0.1016)
			(end 0.2794 -0.1016)
			(stroke
				(width 0.1)
				(type default)
			)
			(layer "B.Fab")
		)
		(fp_line
			(start -0.2794 0.9906)
			(end -0.2794 -0.1016)
			(stroke
				(width 0.1)
				(type default)
			)
			(layer "B.Fab")
		)
		(fp_line
			(start 0.2794 -0.1016)
			(end 0.2794 0.9906)
			(stroke
				(width 0.1)
				(type default)
			)
			(layer "B.Fab")
		)
		(fp_line
			(start 0.2794 0.9906)
			(end -0.2794 0.9906)
			(stroke
				(width 0.1)
				(type default)
			)
			(layer "B.Fab")
		)
		(pad "1" smd rect
			(at 0 0 180)
			(size 0.508 0.508)
			(layers "B.Cu" "B.Mask" "B.Paste")
			(net "RST_RSMRST_R_N")
		)
		(pad "2" smd rect
			(at 0 0.889 180)
			(size 0.508 0.508)
			(layers "B.Cu" "B.Mask" "B.Paste")
			(net "GND")
		)
		(zone
			(layer "B.Cu")
			(hatch none 0.5)
			(connect_pads
				(clearance 0)
			)
			(min_thickness 0.25)
			(keepout
				(tracks allowed)
				(vias not_allowed)
				(pads allowed)
				(copperpour not_allowed)
				(footprints allowed)
			)
			(placement
				(enabled no)
				(sheetname "")
			)
			(fill
				(thermal_gap 0.5)
				(thermal_bridge_width 0.5)
				(island_removal_mode 0)
			)
			(polygon
				(pts
					(xy 378.01042 -66.9671) (xy 377.50242 -66.9671) (xy 377.50242 -66.5861) (xy 378.01042 -66.5861)
				)
			)
		)
		(zone
			(layer "B.Cu")
			(hatch none 0.5)
			(connect_pads
				(clearance 0)
			)
			(min_thickness 0.25)
			(keepout
				(tracks not_allowed)
				(vias allowed)
				(pads allowed)
				(copperpour not_allowed)
				(footprints allowed)
			)
			(placement
				(enabled no)
				(sheetname "")
			)
			(fill
				(thermal_gap 0.5)
				(thermal_bridge_width 0.5)
				(island_removal_mode 0)
			)
			(polygon
				(pts
					(xy 378.01042 -66.5861) (xy 377.50242 -66.5861) (xy 377.50242 -66.9671) (xy 378.01042 -66.9671)
				)
			)
		)
	)
	(footprint ""
		(layer "B.Cu")
		(at 367.925604 -151.694388)
		(property "Reference" "C7W12"
			(at 0 0 0)
			(layer "B.SilkS")
			(hide yes)
			(effects
				(font
					(size 1.27 1.27)
				)
				(justify mirror)
			)
		)
		(property "Value" "*"
			(at 0.0762 -6.2357 0)
			(unlocked yes)
			(layer "B.Fab")
			(hide yes)
			(effects
				(font
					(size 1.27 1.016)
					(thickness 0.1524)
				)
				(justify mirror)
			)
		)
		(property "Device Type" "SC22U16V5MX-4-GP_SMD-BCG5-SC22A"
			(at 0.0762 -8.2677 0)
			(unlocked yes)
			(layer "B.Fab")
			(hide yes)
			(effects
				(font
					(size 1.27 1.016)
					(thickness 0.1524)
				)
				(justify mirror)
			)
		)
		(duplicate_pad_numbers_are_jumpers no)
		(fp_line
			(start -0.635 0)
			(end 0.635 0)
			(stroke
				(width 0.508)
				(type default)
			)
			(layer "B.SilkS")
		)
		(fp_rect
			(start 0.9652 1.778)
			(end -0.9652 -1.778)
			(stroke
				(width 0)
				(type default)
			)
			(fill no)
			(layer "B.CrtYd")
		)
		(fp_poly
			(pts
				(xy 0.9652 -1.778) (xy -0.9652 -1.778) (xy -0.9652 1.778) (xy 0.9652 1.778)
			)
			(stroke
				(width 0)
				(type default)
			)
			(fill no)
			(layer "B.Fab")
		)
		(pad "1" smd rect
			(at 0 -0.9652 180)
			(size 1.397 1.143)
			(layers "B.Cu" "B.Mask" "B.Paste")
			(net "VR_FET_SW_P12V_STBY_PVDDQ_DEF")
		)
		(pad "2" smd rect
			(at 0 0.9652 180)
			(size 1.397 1.143)
			(layers "B.Cu" "B.Mask" "B.Paste")
			(net "GND")
		)
	)
	(footprint ""
		(layer "B.Cu")
		(at 479.9838 -43.4086 90)
		(property "Reference" "C1R21"
			(at 0 0 90)
			(layer "B.SilkS")
			(hide yes)
			(effects
				(font
					(size 1.27 1.27)
				)
				(justify mirror)
			)
		)
		(property "Value" ""
			(at 0 0 90)
			(layer "B.Fab")
			(effects
				(font
					(size 1.27 1.27)
				)
				(justify mirror)
			)
		)
		(duplicate_pad_numbers_are_jumpers no)
		(fp_poly
			(pts
				(xy -0.3048 -0.1016) (xy -0.3048 0.9906) (xy 0.3048 0.9906) (xy 0.3048 -0.1016)
			)
			(stroke
				(width 0)
				(type default)
			)
			(fill no)
			(layer "B.CrtYd")
		)
		(fp_line
			(start 0.3048 -0.1016)
			(end 0.3048 0.9906)
			(stroke
				(width 0.1)
				(type default)
			)
			(layer "B.Fab")
		)
		(fp_line
			(start -0.3048 -0.1016)
			(end 0.3048 -0.1016)
			(stroke
				(width 0.1)
				(type default)
			)
			(layer "B.Fab")
		)
		(fp_line
			(start 0.3048 0.9906)
			(end -0.3048 0.9906)
			(stroke
				(width 0.1)
				(type default)
			)
			(layer "B.Fab")
		)
		(fp_line
			(start -0.3048 0.9906)
			(end -0.3048 -0.1016)
			(stroke
				(width 0.1)
				(type default)
			)
			(layer "B.Fab")
		)
		(pad "1" smd rect
			(at 0 0 270)
			(size 0.508 0.508)
			(layers "B.Cu" "B.Mask" "B.Paste")
			(net "P3V3_STBY")
		)
		(pad "2" smd rect
			(at 0 0.889 270)
			(size 0.508 0.508)
			(layers "B.Cu" "B.Mask" "B.Paste")
			(net "GND")
		)
		(zone
			(layer "B.Cu")
			(hatch none 0.5)
			(connect_pads
				(clearance 0)
			)
			(min_thickness 0.25)
			(keepout
				(tracks allowed)
				(vias not_allowed)
				(pads allowed)
				(copperpour not_allowed)
				(footprints allowed)
			)
			(placement
				(enabled no)
				(sheetname "")
			)
			(fill
				(thermal_gap 0.5)
				(thermal_bridge_width 0.5)
				(island_removal_mode 0)
			)
			(polygon
				(pts
					(xy 480.2378 -43.6626) (xy 480.2378 -43.1546) (xy 480.6188 -43.1546) (xy 480.6188 -43.6626)
				)
			)
		)
		(zone
			(layer "B.Cu")
			(hatch none 0.5)
			(connect_pads
				(clearance 0)
			)
			(min_thickness 0.25)
			(keepout
				(tracks not_allowed)
				(vias allowed)
				(pads allowed)
				(copperpour not_allowed)
				(footprints allowed)
			)
			(placement
				(enabled no)
				(sheetname "")
			)
			(fill
				(thermal_gap 0.5)
				(thermal_bridge_width 0.5)
				(island_removal_mode 0)
			)
			(polygon
				(pts
					(xy 480.6188 -43.6626) (xy 480.6188 -43.1546) (xy 480.2378 -43.1546) (xy 480.2378 -43.6626)
				)
			)
		)
	)
	(footprint ""
		(layer "B.Cu")
		(at 464.3755 -126.492 -90)
		(property "Reference" "C1M38"
			(at 0 0 90)
			(layer "B.SilkS")
			(hide yes)
			(effects
				(font
					(size 1.27 1.27)
				)
				(justify mirror)
			)
		)
		(property "Value" ""
			(at 0 0 90)
			(layer "B.Fab")
			(effects
				(font
					(size 1.27 1.27)
				)
				(justify mirror)
			)
		)
		(duplicate_pad_numbers_are_jumpers no)
		(fp_rect
			(start -0.3048 -0.1016)
			(end 0.3048 0.9906)
			(stroke
				(width 0)
				(type default)
			)
			(fill no)
			(layer "B.CrtYd")
		)
		(fp_line
			(start -0.3048 0.9906)
			(end -0.3048 -0.1016)
			(stroke
				(width 0.1)
				(type default)
			)
			(layer "B.Fab")
		)
		(fp_line
			(start 0.3048 0.9906)
			(end -0.3048 0.9906)
			(stroke
				(width 0.1)
				(type default)
			)
			(layer "B.Fab")
		)
		(fp_line
			(start -0.3048 -0.1016)
			(end 0.3048 -0.1016)
			(stroke
				(width 0.1)
				(type default)
			)
			(layer "B.Fab")
		)
		(fp_line
			(start 0.3048 -0.1016)
			(end 0.3048 0.9906)
			(stroke
				(width 0.1)
				(type default)
			)
			(layer "B.Fab")
		)
		(pad "1" smd rect
			(at 0 0 90)
			(size 0.508 0.508)
			(layers "B.Cu" "B.Mask" "B.Paste")
			(net "P5V_TPS2061")
		)
		(pad "2" smd rect
			(at 0 0.889 90)
			(size 0.508 0.508)
			(layers "B.Cu" "B.Mask" "B.Paste")
			(net "GND")
		)
		(zone
			(layer "B.Cu")
			(hatch none 0.5)
			(connect_pads
				(clearance 0)
			)
			(min_thickness 0.25)
			(keepout
				(tracks allowed)
				(vias not_allowed)
				(pads allowed)
				(copperpour not_allowed)
				(footprints allowed)
			)
			(placement
				(enabled no)
				(sheetname "")
			)
			(fill
				(thermal_gap 0.5)
				(thermal_bridge_width 0.5)
				(island_removal_mode 0)
			)
			(polygon
				(pts
					(xy 464.1215 -126.746) (xy 463.7405 -126.746) (xy 463.7405 -126.238) (xy 464.1215 -126.238)
				)
			)
		)
		(zone
			(layer "B.Cu")
			(hatch none 0.5)
			(connect_pads
				(clearance 0)
			)
			(min_thickness 0.25)
			(keepout
				(tracks not_allowed)
				(vias allowed)
				(pads allowed)
				(copperpour not_allowed)
				(footprints allowed)
			)
			(placement
				(enabled no)
				(sheetname "")
			)
			(fill
				(thermal_gap 0.5)
				(thermal_bridge_width 0.5)
				(island_removal_mode 0)
			)
			(polygon
				(pts
					(xy 464.1215 -126.746) (xy 463.7405 -126.746) (xy 463.7405 -126.238) (xy 464.1215 -126.238)
				)
			)
		)
	)
	(footprint ""
		(layer "B.Cu")
		(at 499.2878 -145.9738 180)
		(property "Reference" "R1L21"
			(at 0 0 0)
			(layer "B.SilkS")
			(hide yes)
			(effects
				(font
					(size 1.27 1.27)
				)
				(justify mirror)
			)
		)
		(property "Value" ""
			(at 0 0 0)
			(layer "B.Fab")
			(effects
				(font
					(size 1.27 1.27)
				)
				(justify mirror)
			)
		)
		(duplicate_pad_numbers_are_jumpers no)
		(fp_poly
			(pts
				(xy 0.2794 -0.1016) (xy -0.2794 -0.1016) (xy -0.2794 0.9906) (xy 0.2794 0.9906)
			)
			(stroke
				(width 0)
				(type default)
			)
			(fill no)
			(layer "B.CrtYd")
		)
		(fp_line
			(start 0.2794 0.9906)
			(end -0.2794 0.9906)
			(stroke
				(width 0.1)
				(type default)
			)
			(layer "B.Fab")
		)
		(fp_line
			(start 0.2794 -0.1016)
			(end 0.2794 0.9906)
			(stroke
				(width 0.1)
				(type default)
			)
			(layer "B.Fab")
		)
		(fp_line
			(start -0.2794 0.9906)
			(end -0.2794 -0.1016)
			(stroke
				(width 0.1)
				(type default)
			)
			(layer "B.Fab")
		)
		(fp_line
			(start -0.2794 -0.1016)
			(end 0.2794 -0.1016)
			(stroke
				(width 0.1)
				(type default)
			)
			(layer "B.Fab")
		)
		(pad "1" smd rect
			(at 0 0)
			(size 0.508 0.508)
			(layers "B.Cu" "B.Mask" "B.Paste")
			(net "P3V3")
		)
		(pad "2" smd rect
			(at 0 0.889)
			(size 0.508 0.508)
			(layers "B.Cu" "B.Mask" "B.Paste")
			(net "FP_LED_HDD_ACTIVITY_AND_R_N")
		)
		(zone
			(layer "B.Cu")
			(hatch none 0.5)
			(connect_pads
				(clearance 0)
			)
			(min_thickness 0.25)
			(keepout
				(tracks not_allowed)
				(vias allowed)
				(pads allowed)
				(copperpour not_allowed)
				(footprints allowed)
			)
			(placement
				(enabled no)
				(sheetname "")
			)
			(fill
				(thermal_gap 0.5)
				(thermal_bridge_width 0.5)
				(island_removal_mode 0)
			)
			(polygon
				(pts
					(xy 499.0338 -146.6088) (xy 499.5418 -146.6088) (xy 499.5418 -146.2278) (xy 499.0338 -146.2278)
				)
			)
		)
		(zone
			(layer "B.Cu")
			(hatch none 0.5)
			(connect_pads
				(clearance 0)
			)
			(min_thickness 0.25)
			(keepout
				(tracks allowed)
				(vias not_allowed)
				(pads allowed)
				(copperpour not_allowed)
				(footprints allowed)
			)
			(placement
				(enabled no)
				(sheetname "")
			)
			(fill
				(thermal_gap 0.5)
				(thermal_bridge_width 0.5)
				(island_removal_mode 0)
			)
			(polygon
				(pts
					(xy 499.0338 -146.2278) (xy 499.5418 -146.2278) (xy 499.5418 -146.6088) (xy 499.0338 -146.6088)
				)
			)
		)
	)
	(footprint ""
		(layer "B.Cu")
		(at 450.7484 -9.6012 -90)
		(property "Reference" "CR2U1"
			(at 1.93167 -1.016 0)
			(unlocked yes)
			(layer "B.SilkS")
			(effects
				(font
					(size 0.7874 0.5842)
					(thickness 0.1524)
				)
				(justify left mirror)
			)
		)
		(property "Value" ""
			(at 0 0 90)
			(layer "B.Fab")
			(effects
				(font
					(size 1.27 1.27)
				)
				(justify mirror)
			)
		)
		(duplicate_pad_numbers_are_jumpers no)
		(fp_line
			(start -1.8415 2.5273)
			(end -0.9652 2.5273)
			(stroke
				(width 0.1524)
				(type default)
			)
			(layer "B.SilkS")
		)
		(fp_line
			(start -1.8415 1.8542)
			(end -1.8415 2.5273)
			(stroke
				(width 0.1524)
				(type default)
			)
			(layer "B.SilkS")
		)
		(fp_line
			(start -1.8415 -0.4953)
			(end -1.8415 0.1778)
			(stroke
				(width 0.1524)
				(type default)
			)
			(layer "B.SilkS")
		)
		(fp_line
			(start -0.9652 -0.4953)
			(end -1.8415 -0.4953)
			(stroke
				(width 0.1524)
				(type default)
			)
			(layer "B.SilkS")
		)
		(fp_circle
			(center 0.988568 -1.098296)
			(end 0.988568 -1.225296)
			(stroke
				(width 0.254)
				(type default)
			)
			(fill no)
			(layer "B.SilkS")
		)
		(fp_poly
			(pts
				(xy -1.8415 2.5273) (xy -0.4445 2.5273) (xy -0.4445 -0.4953) (xy -1.8415 -0.4953)
			)
			(stroke
				(width 0)
				(type default)
			)
			(fill no)
			(layer "B.CrtYd")
		)
		(fp_rect
			(start -1.8415 2.5273)
			(end -0.4445 -0.4953)
			(stroke
				(width 0)
				(type default)
			)
			(fill no)
			(layer "B.Fab")
		)
		(fp_circle
			(center 0.988568 -1.098296)
			(end 0.988568 -1.225296)
			(stroke
				(width 0.254)
				(type default)
			)
			(fill no)
			(layer "B.Fab")
		)
		(pad "1" smd rect
			(at 0 0 90)
			(size 1.27 1.016)
			(layers "B.Cu" "B.Mask" "B.Paste")
			(net "P3V3_STBY")
		)
		(pad "2" smd rect
			(at 0 2.032 90)
			(size 1.27 1.016)
			(layers "B.Cu" "B.Mask" "B.Paste")
			(net "A_P3V_BAT_R")
		)
		(pad "3" smd rect
			(at -2.286 1.016 90)
			(size 1.27 1.016)
			(layers "B.Cu" "B.Mask" "B.Paste")
			(net "P3V3_RTC_STBY")
		)
	)
	(footprint ""
		(layer "B.Cu")
		(at 471.3605 -137.795 -90)
		(property "Reference" "R1L31"
			(at 0 0 90)
			(layer "B.SilkS")
			(hide yes)
			(effects
				(font
					(size 1.27 1.27)
				)
				(justify mirror)
			)
		)
		(property "Value" ""
			(at 0 0 90)
			(layer "B.Fab")
			(effects
				(font
					(size 1.27 1.27)
				)
				(justify mirror)
			)
		)
		(duplicate_pad_numbers_are_jumpers no)
		(fp_poly
			(pts
				(xy 0.2794 -0.1016) (xy -0.2794 -0.1016) (xy -0.2794 0.9906) (xy 0.2794 0.9906)
			)
			(stroke
				(width 0)
				(type default)
			)
			(fill no)
			(layer "B.CrtYd")
		)
		(fp_line
			(start -0.2794 0.9906)
			(end -0.2794 -0.1016)
			(stroke
				(width 0.1)
				(type default)
			)
			(layer "B.Fab")
		)
		(fp_line
			(start 0.2794 0.9906)
			(end -0.2794 0.9906)
			(stroke
				(width 0.1)
				(type default)
			)
			(layer "B.Fab")
		)
		(fp_line
			(start -0.2794 -0.1016)
			(end 0.2794 -0.1016)
			(stroke
				(width 0.1)
				(type default)
			)
			(layer "B.Fab")
		)
		(fp_line
			(start 0.2794 -0.1016)
			(end 0.2794 0.9906)
			(stroke
				(width 0.1)
				(type default)
			)
			(layer "B.Fab")
		)
		(pad "1" smd rect
			(at 0 0 90)
			(size 0.508 0.508)
			(layers "B.Cu" "B.Mask" "B.Paste")
			(net "FP_PWR_BTN_R_N")
		)
		(pad "2" smd rect
			(at 0 0.889 90)
			(size 0.508 0.508)
			(layers "B.Cu" "B.Mask" "B.Paste")
			(net "FP_PWR_BTN_R1_N")
		)
		(zone
			(layer "B.Cu")
			(hatch none 0.5)
			(connect_pads
				(clearance 0)
			)
			(min_thickness 0.25)
			(keepout
				(tracks not_allowed)
				(vias allowed)
				(pads allowed)
				(copperpour not_allowed)
				(footprints allowed)
			)
			(placement
				(enabled no)
				(sheetname "")
			)
			(fill
				(thermal_gap 0.5)
				(thermal_bridge_width 0.5)
				(island_removal_mode 0)
			)
			(polygon
				(pts
					(xy 470.7255 -137.541) (xy 470.7255 -138.049) (xy 471.1065 -138.049) (xy 471.1065 -137.541)
				)
			)
		)
		(zone
			(layer "B.Cu")
			(hatch none 0.5)
			(connect_pads
				(clearance 0)
			)
			(min_thickness 0.25)
			(keepout
				(tracks allowed)
				(vias not_allowed)
				(pads allowed)
				(copperpour not_allowed)
				(footprints allowed)
			)
			(placement
				(enabled no)
				(sheetname "")
			)
			(fill
				(thermal_gap 0.5)
				(thermal_bridge_width 0.5)
				(island_removal_mode 0)
			)
			(polygon
				(pts
					(xy 471.1065 -137.541) (xy 471.1065 -138.049) (xy 470.7255 -138.049) (xy 470.7255 -137.541)
				)
			)
		)
	)
	(footprint ""
		(layer "B.Cu")
		(at 45.212 -83.947 -90)
		(property "Reference" "C9P5"
			(at 0.78867 -3.556 0)
			(unlocked yes)
			(layer "B.SilkS")
			(effects
				(font
					(size 0.7874 0.5842)
					(thickness 0.1524)
				)
				(justify mirror)
			)
		)
		(property "Value" ""
			(at 0 0 90)
			(layer "B.Fab")
			(effects
				(font
					(size 1.27 1.27)
				)
				(justify mirror)
			)
		)
		(duplicate_pad_numbers_are_jumpers no)
		(fp_line
			(start -2.286 7.366)
			(end -1.600708 7.366)
			(stroke
				(width 0.1524)
				(type default)
			)
			(layer "B.SilkS")
		)
		(fp_line
			(start -2.286 7.366)
			(end -2.286 1.63195)
			(stroke
				(width 0.1524)
				(type default)
			)
			(layer "B.SilkS")
		)
		(fp_line
			(start 2.286 7.366)
			(end 1.60147 7.366)
			(stroke
				(width 0.1524)
				(type default)
			)
			(layer "B.SilkS")
		)
		(fp_line
			(start 2.286 7.366)
			(end 2.286 1.632712)
			(stroke
				(width 0.1524)
				(type default)
			)
			(layer "B.SilkS")
		)
		(fp_line
			(start -2.504948 1.633728)
			(end -1.6002 1.633728)
			(stroke
				(width 0.1524)
				(type default)
			)
			(layer "B.SilkS")
		)
		(fp_line
			(start 2.563114 1.633728)
			(end 1.6002 1.633728)
			(stroke
				(width 0.1524)
				(type default)
			)
			(layer "B.SilkS")
		)
		(fp_line
			(start -2.504948 -1.616456)
			(end -2.504948 1.633728)
			(stroke
				(width 0.1524)
				(type default)
			)
			(layer "B.SilkS")
		)
		(fp_line
			(start -1.6002 -1.616456)
			(end -2.504948 -1.616456)
			(stroke
				(width 0.1524)
				(type default)
			)
			(layer "B.SilkS")
		)
		(fp_line
			(start 1.6002 -1.616456)
			(end 2.563114 -1.616456)
			(stroke
				(width 0.1524)
				(type default)
			)
			(layer "B.SilkS")
		)
		(fp_line
			(start 2.563114 -1.616456)
			(end 2.563114 1.633728)
			(stroke
				(width 0.1524)
				(type default)
			)
			(layer "B.SilkS")
		)
		(fp_rect
			(start 2.286 7.366)
			(end -2.286 -0.254)
			(stroke
				(width 0)
				(type default)
			)
			(fill no)
			(layer "B.CrtYd")
		)
		(fp_line
			(start -2.286 7.366)
			(end 2.286 7.366)
			(stroke
				(width 0.1)
				(type default)
			)
			(layer "B.Fab")
		)
		(fp_line
			(start 2.286 7.366)
			(end 2.286 -0.254)
			(stroke
				(width 0.1)
				(type default)
			)
			(layer "B.Fab")
		)
		(fp_line
			(start -2.286 -0.254)
			(end -2.286 7.366)
			(stroke
				(width 0.1)
				(type default)
			)
			(layer "B.Fab")
		)
		(fp_line
			(start 2.286 -0.254)
			(end -2.286 -0.254)
			(stroke
				(width 0.1)
				(type default)
			)
			(layer "B.Fab")
		)
		(pad "1" smd rect
			(at 0 0 90)
			(size 2.54 3.048)
			(layers "B.Cu" "B.Mask" "B.Paste")
			(net "PVCCIN_CPU1")
		)
		(pad "2" smd rect
			(at 0 7.112 90)
			(size 2.54 3.048)
			(layers "B.Cu" "B.Mask" "B.Paste")
			(net "GND")
		)
	)
	(footprint ""
		(layer "B.Cu")
		(at 179.199794 -69.230494 -90)
		(property "Reference" "R6P32"
			(at 0 0 90)
			(layer "B.SilkS")
			(hide yes)
			(effects
				(font
					(size 1.27 1.27)
				)
				(justify mirror)
			)
		)
		(property "Value" ""
			(at 0 0 90)
			(layer "B.Fab")
			(effects
				(font
					(size 1.27 1.27)
				)
				(justify mirror)
			)
		)
		(duplicate_pad_numbers_are_jumpers no)
		(fp_rect
			(start 0.2794 0.9906)
			(end -0.2794 -0.1016)
			(stroke
				(width 0)
				(type default)
			)
			(fill no)
			(layer "B.CrtYd")
		)
		(fp_line
			(start -0.2794 0.9906)
			(end -0.2794 -0.1016)
			(stroke
				(width 0.1)
				(type default)
			)
			(layer "B.Fab")
		)
		(fp_line
			(start 0.2794 0.9906)
			(end -0.2794 0.9906)
			(stroke
				(width 0.1)
				(type default)
			)
			(layer "B.Fab")
		)
		(fp_line
			(start -0.2794 -0.1016)
			(end 0.2794 -0.1016)
			(stroke
				(width 0.1)
				(type default)
			)
			(layer "B.Fab")
		)
		(fp_line
			(start 0.2794 -0.1016)
			(end 0.2794 0.9906)
			(stroke
				(width 0.1)
				(type default)
			)
			(layer "B.Fab")
		)
		(pad "1" smd rect
			(at 0 0 90)
			(size 0.508 0.508)
			(layers "B.Cu" "B.Mask" "B.Paste")
			(net "P3V3_STBY")
		)
		(pad "2" smd rect
			(at 0 0.889 90)
			(size 0.508 0.508)
			(layers "B.Cu" "B.Mask" "B.Paste")
			(net "SMB_VR_STBY_LVC3_SDA")
		)
		(zone
			(layer "B.Cu")
			(hatch none 0.5)
			(connect_pads
				(clearance 0)
			)
			(min_thickness 0.25)
			(keepout
				(tracks not_allowed)
				(vias allowed)
				(pads allowed)
				(copperpour not_allowed)
				(footprints allowed)
			)
			(placement
				(enabled no)
				(sheetname "")
			)
			(fill
				(thermal_gap 0.5)
				(thermal_bridge_width 0.5)
				(island_removal_mode 0)
			)
			(polygon
				(pts
					(xy 178.564794 -68.976494) (xy 178.945794 -68.976494) (xy 178.945794 -69.484494) (xy 178.564794 -69.484494)
				)
			)
		)
		(zone
			(layer "B.Cu")
			(hatch none 0.5)
			(connect_pads
				(clearance 0)
			)
			(min_thickness 0.25)
			(keepout
				(tracks allowed)
				(vias not_allowed)
				(pads allowed)
				(copperpour not_allowed)
				(footprints allowed)
			)
			(placement
				(enabled no)
				(sheetname "")
			)
			(fill
				(thermal_gap 0.5)
				(thermal_bridge_width 0.5)
				(island_removal_mode 0)
			)
			(polygon
				(pts
					(xy 178.564794 -68.976494) (xy 178.945794 -68.976494) (xy 178.945794 -69.484494) (xy 178.564794 -69.484494)
				)
			)
		)
	)
	(footprint ""
		(layer "B.Cu")
		(at 442.849 -116.49202)
		(property "Reference" "C2M15"
			(at 0 0 0)
			(layer "B.SilkS")
			(hide yes)
			(effects
				(font
					(size 1.27 1.27)
				)
				(justify mirror)
			)
		)
		(property "Value" ""
			(at 0 0 0)
			(layer "B.Fab")
			(effects
				(font
					(size 1.27 1.27)
				)
				(justify mirror)
			)
		)
		(duplicate_pad_numbers_are_jumpers no)
		(fp_rect
			(start -0.3048 0.9906)
			(end 0.3048 -0.1016)
			(stroke
				(width 0)
				(type default)
			)
			(fill no)
			(layer "B.CrtYd")
		)
		(fp_line
			(start -0.3048 -0.1016)
			(end 0.3048 -0.1016)
			(stroke
				(width 0.1)
				(type default)
			)
			(layer "B.Fab")
		)
		(fp_line
			(start -0.3048 0.9906)
			(end -0.3048 -0.1016)
			(stroke
				(width 0.1)
				(type default)
			)
			(layer "B.Fab")
		)
		(fp_line
			(start 0.3048 -0.1016)
			(end 0.3048 0.9906)
			(stroke
				(width 0.1)
				(type default)
			)
			(layer "B.Fab")
		)
		(fp_line
			(start 0.3048 0.9906)
			(end -0.3048 0.9906)
			(stroke
				(width 0.1)
				(type default)
			)
			(layer "B.Fab")
		)
		(pad "1" smd rect
			(at 0 0 180)
			(size 0.508 0.508)
			(layers "B.Cu" "B.Mask" "B.Paste")
			(net "P3E_CPU0_PE3_OCP_TXN<8>")
		)
		(pad "2" smd rect
			(at 0 0.889 180)
			(size 0.508 0.508)
			(layers "B.Cu" "B.Mask" "B.Paste")
			(net "P3E_OCP_CPU0_PE3_C_TXN<8>")
		)
		(zone
			(layer "B.Cu")
			(hatch none 0.5)
			(connect_pads
				(clearance 0)
			)
			(min_thickness 0.25)
			(keepout
				(tracks not_allowed)
				(vias allowed)
				(pads allowed)
				(copperpour not_allowed)
				(footprints allowed)
			)
			(placement
				(enabled no)
				(sheetname "")
			)
			(fill
				(thermal_gap 0.5)
				(thermal_bridge_width 0.5)
				(island_removal_mode 0)
			)
			(polygon
				(pts
					(xy 442.595 -115.85702) (xy 443.103 -115.85702) (xy 443.103 -116.23802) (xy 442.595 -116.23802)
				)
			)
		)
		(zone
			(layer "B.Cu")
			(hatch none 0.5)
			(connect_pads
				(clearance 0)
			)
			(min_thickness 0.25)
			(keepout
				(tracks allowed)
				(vias not_allowed)
				(pads allowed)
				(copperpour not_allowed)
				(footprints allowed)
			)
			(placement
				(enabled no)
				(sheetname "")
			)
			(fill
				(thermal_gap 0.5)
				(thermal_bridge_width 0.5)
				(island_removal_mode 0)
			)
			(polygon
				(pts
					(xy 442.595 -115.85702) (xy 443.103 -115.85702) (xy 443.103 -116.23802) (xy 442.595 -116.23802)
				)
			)
		)
	)
	(footprint ""
		(layer "B.Cu")
		(at 411.861 -6.5405)
		(property "Reference" "R2P18"
			(at 0 0 0)
			(layer "B.SilkS")
			(hide yes)
			(effects
				(font
					(size 1.27 1.27)
				)
				(justify mirror)
			)
		)
		(property "Value" ""
			(at 0 0 0)
			(layer "B.Fab")
			(effects
				(font
					(size 1.27 1.27)
				)
				(justify mirror)
			)
		)
		(duplicate_pad_numbers_are_jumpers no)
		(fp_poly
			(pts
				(xy 0.2794 -0.1016) (xy -0.2794 -0.1016) (xy -0.2794 0.9906) (xy 0.2794 0.9906)
			)
			(stroke
				(width 0)
				(type default)
			)
			(fill no)
			(layer "B.CrtYd")
		)
		(fp_line
			(start -0.2794 -0.1016)
			(end 0.2794 -0.1016)
			(stroke
				(width 0.1)
				(type default)
			)
			(layer "B.Fab")
		)
		(fp_line
			(start -0.2794 0.9906)
			(end -0.2794 -0.1016)
			(stroke
				(width 0.1)
				(type default)
			)
			(layer "B.Fab")
		)
		(fp_line
			(start 0.2794 -0.1016)
			(end 0.2794 0.9906)
			(stroke
				(width 0.1)
				(type default)
			)
			(layer "B.Fab")
		)
		(fp_line
			(start 0.2794 0.9906)
			(end -0.2794 0.9906)
			(stroke
				(width 0.1)
				(type default)
			)
			(layer "B.Fab")
		)
		(pad "1" smd rect
			(at 0 0 180)
			(size 0.508 0.508)
			(layers "B.Cu" "B.Mask" "B.Paste")
			(net "P3V3_STBY")
		)
		(pad "2" smd rect
			(at 0 0.889 180)
			(size 0.508 0.508)
			(layers "B.Cu" "B.Mask" "B.Paste")
			(net "PWRGD_P5V_N")
		)
		(zone
			(layer "B.Cu")
			(hatch none 0.5)
			(connect_pads
				(clearance 0)
			)
			(min_thickness 0.25)
			(keepout
				(tracks allowed)
				(vias not_allowed)
				(pads allowed)
				(copperpour not_allowed)
				(footprints allowed)
			)
			(placement
				(enabled no)
				(sheetname "")
			)
			(fill
				(thermal_gap 0.5)
				(thermal_bridge_width 0.5)
				(island_removal_mode 0)
			)
			(polygon
				(pts
					(xy 412.115 -6.2865) (xy 411.607 -6.2865) (xy 411.607 -5.9055) (xy 412.115 -5.9055)
				)
			)
		)
		(zone
			(layer "B.Cu")
			(hatch none 0.5)
			(connect_pads
				(clearance 0)
			)
			(min_thickness 0.25)
			(keepout
				(tracks not_allowed)
				(vias allowed)
				(pads allowed)
				(copperpour not_allowed)
				(footprints allowed)
			)
			(placement
				(enabled no)
				(sheetname "")
			)
			(fill
				(thermal_gap 0.5)
				(thermal_bridge_width 0.5)
				(island_removal_mode 0)
			)
			(polygon
				(pts
					(xy 412.115 -5.9055) (xy 411.607 -5.9055) (xy 411.607 -6.2865) (xy 412.115 -6.2865)
				)
			)
		)
	)
	(footprint ""
		(layer "B.Cu")
		(at 372.351046 -75.4888)
		(property "Reference" "C3P47"
			(at 0 0 0)
			(layer "B.SilkS")
			(hide yes)
			(effects
				(font
					(size 1.27 1.27)
				)
				(justify mirror)
			)
		)
		(property "Value" ""
			(at 0 0 0)
			(layer "B.Fab")
			(effects
				(font
					(size 1.27 1.27)
				)
				(justify mirror)
			)
		)
		(duplicate_pad_numbers_are_jumpers no)
		(fp_rect
			(start 0.2794 0.9144)
			(end -0.2794 -0.1143)
			(stroke
				(width 0)
				(type default)
			)
			(fill no)
			(layer "B.CrtYd")
		)
		(fp_line
			(start -0.2794 -0.1143)
			(end -0.2794 0.9144)
			(stroke
				(width 0.1)
				(type default)
			)
			(layer "B.Fab")
		)
		(fp_line
			(start -0.2794 0.9144)
			(end 0.2794 0.9144)
			(stroke
				(width 0.1)
				(type default)
			)
			(layer "B.Fab")
		)
		(fp_line
			(start 0.2794 -0.1143)
			(end -0.2794 -0.1143)
			(stroke
				(width 0.1)
				(type default)
			)
			(layer "B.Fab")
		)
		(fp_line
			(start 0.2794 0.9144)
			(end 0.2794 -0.1143)
			(stroke
				(width 0.1)
				(type default)
			)
			(layer "B.Fab")
		)
		(pad "1" smd custom
			(at 0 0 270)
			(size 0.10414 0.10414)
			(layers "B.Cu" "B.Mask" "B.Paste")
			(net "P3V3_STBY")
			(options
				(clearance outline)
				(anchor circle)
			)
			(primitives
				(gr_poly
					(pts
						(xy -0.20828 -0.08636) (xy -0.20828 0.08636) (xy -0.08636 0.20828) (xy 0.086614 0.20828) (xy 0.20828 0.086614)
						(xy 0.20828 -0.08636) (xy 0.08636 -0.20828) (xy -0.08636 -0.20828)
					)
					(width 0)
					(fill yes)
				)
			)
		)
		(pad "2" smd custom
			(at 0 0.8001 270)
			(size 0.10414 0.10414)
			(layers "B.Cu" "B.Mask" "B.Paste")
			(net "GND")
			(options
				(clearance outline)
				(anchor circle)
			)
			(primitives
				(gr_poly
					(pts
						(xy -0.20828 -0.08636) (xy -0.20828 0.08636) (xy -0.08636 0.20828) (xy 0.086614 0.20828) (xy 0.20828 0.086614)
						(xy 0.20828 -0.08636) (xy 0.08636 -0.20828) (xy -0.08636 -0.20828)
					)
					(width 0)
					(fill yes)
				)
			)
		)
		(zone
			(layer "B.Cu")
			(hatch none 0.5)
			(connect_pads
				(clearance 0)
			)
			(min_thickness 0.25)
			(keepout
				(tracks not_allowed)
				(vias allowed)
				(pads allowed)
				(copperpour not_allowed)
				(footprints allowed)
			)
			(placement
				(enabled no)
				(sheetname "")
			)
			(fill
				(thermal_gap 0.5)
				(thermal_bridge_width 0.5)
				(island_removal_mode 0)
			)
			(polygon
				(pts
					(xy 372.438676 -75.27925) (xy 372.438676 -74.89825) (xy 372.263416 -74.89825) (xy 372.263162 -75.27925)
				)
			)
		)
		(zone
			(layer "B.Cu")
			(hatch none 0.5)
			(connect_pads
				(clearance 0)
			)
			(min_thickness 0.25)
			(keepout
				(tracks allowed)
				(vias not_allowed)
				(pads allowed)
				(copperpour not_allowed)
				(footprints allowed)
			)
			(placement
				(enabled no)
				(sheetname "")
			)
			(fill
				(thermal_gap 0.5)
				(thermal_bridge_width 0.5)
				(island_removal_mode 0)
			)
			(polygon
				(pts
					(xy 372.438676 -75.27925) (xy 372.438676 -74.89825) (xy 372.263416 -74.89825) (xy 372.263162 -75.27925)
				)
			)
		)
	)
	(footprint ""
		(layer "B.Cu")
		(at 396.674086 -30.627574 180)
		(property "Reference" "R2T28"
			(at 0 0 0)
			(layer "B.SilkS")
			(hide yes)
			(effects
				(font
					(size 1.27 1.27)
				)
				(justify mirror)
			)
		)
		(property "Value" ""
			(at 0 0 0)
			(layer "B.Fab")
			(effects
				(font
					(size 1.27 1.27)
				)
				(justify mirror)
			)
		)
		(duplicate_pad_numbers_are_jumpers no)
		(fp_poly
			(pts
				(xy 0.2794 -0.1016) (xy -0.2794 -0.1016) (xy -0.2794 0.9906) (xy 0.2794 0.9906)
			)
			(stroke
				(width 0)
				(type default)
			)
			(fill no)
			(layer "B.CrtYd")
		)
		(fp_line
			(start 0.2794 0.9906)
			(end -0.2794 0.9906)
			(stroke
				(width 0.1)
				(type default)
			)
			(layer "B.Fab")
		)
		(fp_line
			(start 0.2794 -0.1016)
			(end 0.2794 0.9906)
			(stroke
				(width 0.1)
				(type default)
			)
			(layer "B.Fab")
		)
		(fp_line
			(start -0.2794 0.9906)
			(end -0.2794 -0.1016)
			(stroke
				(width 0.1)
				(type default)
			)
			(layer "B.Fab")
		)
		(fp_line
			(start -0.2794 -0.1016)
			(end 0.2794 -0.1016)
			(stroke
				(width 0.1)
				(type default)
			)
			(layer "B.Fab")
		)
		(pad "1" smd rect
			(at 0 0)
			(size 0.508 0.508)
			(layers "B.Cu" "B.Mask" "B.Paste")
			(net "FM_PCH_PWRBTN_R_N")
		)
		(pad "2" smd rect
			(at 0 0.889)
			(size 0.508 0.508)
			(layers "B.Cu" "B.Mask" "B.Paste")
			(net "FM_PCH_PWRBTN_N")
		)
		(zone
			(layer "B.Cu")
			(hatch none 0.5)
			(connect_pads
				(clearance 0)
			)
			(min_thickness 0.25)
			(keepout
				(tracks not_allowed)
				(vias allowed)
				(pads allowed)
				(copperpour not_allowed)
				(footprints allowed)
			)
			(placement
				(enabled no)
				(sheetname "")
			)
			(fill
				(thermal_gap 0.5)
				(thermal_bridge_width 0.5)
				(island_removal_mode 0)
			)
			(polygon
				(pts
					(xy 396.420086 -31.262574) (xy 396.928086 -31.262574) (xy 396.928086 -30.881574) (xy 396.420086 -30.881574)
				)
			)
		)
		(zone
			(layer "B.Cu")
			(hatch none 0.5)
			(connect_pads
				(clearance 0)
			)
			(min_thickness 0.25)
			(keepout
				(tracks allowed)
				(vias not_allowed)
				(pads allowed)
				(copperpour not_allowed)
				(footprints allowed)
			)
			(placement
				(enabled no)
				(sheetname "")
			)
			(fill
				(thermal_gap 0.5)
				(thermal_bridge_width 0.5)
				(island_removal_mode 0)
			)
			(polygon
				(pts
					(xy 396.420086 -30.881574) (xy 396.928086 -30.881574) (xy 396.928086 -31.262574) (xy 396.420086 -31.262574)
				)
			)
		)
	)
	(footprint ""
		(layer "B.Cu")
		(at 331.8002 -135.4074 90)
		(property "Reference" "C4M1"
			(at -3.36423 1.43002 0)
			(unlocked yes)
			(layer "B.SilkS")
			(effects
				(font
					(size 0.7874 0.5842)
					(thickness 0.1524)
				)
				(justify left mirror)
			)
		)
		(property "Value" ""
			(at 0 0 90)
			(layer "B.Fab")
			(effects
				(font
					(size 1.27 1.27)
				)
				(justify mirror)
			)
		)
		(duplicate_pad_numbers_are_jumpers no)
		(fp_line
			(start 2.032 -1.524)
			(end 2.032 1.524)
			(stroke
				(width 0.1524)
				(type default)
			)
			(layer "B.SilkS")
		)
		(fp_line
			(start 1.7272 -1.524)
			(end 2.032 -1.524)
			(stroke
				(width 0.1524)
				(type default)
			)
			(layer "B.SilkS")
		)
		(fp_line
			(start -1.7272 -1.524)
			(end -2.032 -1.524)
			(stroke
				(width 0.1524)
				(type default)
			)
			(layer "B.SilkS")
		)
		(fp_line
			(start -2.032 -1.524)
			(end -2.032 1.524)
			(stroke
				(width 0.1524)
				(type default)
			)
			(layer "B.SilkS")
		)
		(fp_line
			(start 2.2987 -0.2413)
			(end 2.2987 7.3533)
			(stroke
				(width 0.1524)
				(type default)
			)
			(layer "B.SilkS")
		)
		(fp_line
			(start 2.032 -0.2413)
			(end 2.2987 -0.2413)
			(stroke
				(width 0.1524)
				(type default)
			)
			(layer "B.SilkS")
		)
		(fp_line
			(start -2.2987 -0.2413)
			(end -2.032 -0.2413)
			(stroke
				(width 0.1524)
				(type default)
			)
			(layer "B.SilkS")
		)
		(fp_line
			(start 2.032 1.524)
			(end 1.7272 1.524)
			(stroke
				(width 0.1524)
				(type default)
			)
			(layer "B.SilkS")
		)
		(fp_line
			(start -2.032 1.524)
			(end -1.7272 1.524)
			(stroke
				(width 0.1524)
				(type default)
			)
			(layer "B.SilkS")
		)
		(fp_line
			(start 2.2987 7.3533)
			(end 1.7272 7.3533)
			(stroke
				(width 0.1524)
				(type default)
			)
			(layer "B.SilkS")
		)
		(fp_line
			(start -1.7272 7.3533)
			(end -2.2987 7.3533)
			(stroke
				(width 0.1524)
				(type default)
			)
			(layer "B.SilkS")
		)
		(fp_line
			(start -2.2987 7.3533)
			(end -2.2987 -0.2413)
			(stroke
				(width 0.1524)
				(type default)
			)
			(layer "B.SilkS")
		)
		(fp_poly
			(pts
				(xy 2.2987 -0.2413) (xy -2.2987 -0.2413) (xy -2.2987 7.3533) (xy 2.2987 7.3533)
			)
			(stroke
				(width 0)
				(type default)
			)
			(fill no)
			(layer "B.CrtYd")
		)
		(fp_line
			(start 2.2987 -0.2413)
			(end -2.2987 -0.2413)
			(stroke
				(width 0.1)
				(type default)
			)
			(layer "B.Fab")
		)
		(fp_line
			(start -2.2987 -0.2413)
			(end -2.2987 7.3533)
			(stroke
				(width 0.1)
				(type default)
			)
			(layer "B.Fab")
		)
		(fp_line
			(start 2.2987 7.3533)
			(end 2.2987 -0.2413)
			(stroke
				(width 0.1)
				(type default)
			)
			(layer "B.Fab")
		)
		(fp_line
			(start -2.2987 7.3533)
			(end 2.2987 7.3533)
			(stroke
				(width 0.1)
				(type default)
			)
			(layer "B.Fab")
		)
		(pad "1" smd rect
			(at 0 0 270)
			(size 2.54 3.048)
			(layers "B.Cu" "B.Mask" "B.Paste")
			(net "PVPP_DEF")
		)
		(pad "2" smd rect
			(at 0 7.112 270)
			(size 2.54 3.048)
			(layers "B.Cu" "B.Mask" "B.Paste")
			(net "GND")
		)
	)
	(footprint ""
		(layer "B.Cu")
		(at 93.548454 -73.51014)
		(property "Reference" "C8P29"
			(at 0 0 0)
			(layer "B.SilkS")
			(hide yes)
			(effects
				(font
					(size 1.27 1.27)
				)
				(justify mirror)
			)
		)
		(property "Value" ""
			(at 0 0 0)
			(layer "B.Fab")
			(effects
				(font
					(size 1.27 1.27)
				)
				(justify mirror)
			)
		)
		(duplicate_pad_numbers_are_jumpers no)
		(fp_poly
			(pts
				(xy 0.7239 -0.2159) (xy -0.7239 -0.2159) (xy -0.7239 1.9939) (xy 0.7239 1.9939)
			)
			(stroke
				(width 0)
				(type default)
			)
			(fill no)
			(layer "B.CrtYd")
		)
		(fp_line
			(start -0.7239 -0.2159)
			(end 0.7239 -0.2159)
			(stroke
				(width 0.1)
				(type default)
			)
			(layer "B.Fab")
		)
		(fp_line
			(start -0.7239 1.9939)
			(end -0.7239 -0.2159)
			(stroke
				(width 0.1)
				(type default)
			)
			(layer "B.Fab")
		)
		(fp_line
			(start 0.7239 -0.2159)
			(end 0.7239 1.9939)
			(stroke
				(width 0.1)
				(type default)
			)
			(layer "B.Fab")
		)
		(fp_line
			(start 0.7239 1.9939)
			(end -0.7239 1.9939)
			(stroke
				(width 0.1)
				(type default)
			)
			(layer "B.Fab")
		)
		(pad "1" smd rect
			(at 0 0 180)
			(size 1.27 1.016)
			(layers "B.Cu" "B.Mask" "B.Paste")
			(net "PVCCIN_CPU1")
		)
		(pad "2" smd rect
			(at 0 1.778 180)
			(size 1.27 1.016)
			(layers "B.Cu" "B.Mask" "B.Paste")
			(net "GND")
		)
		(zone
			(layer "B.Cu")
			(hatch none 0.5)
			(connect_pads
				(clearance 0)
			)
			(min_thickness 0.25)
			(keepout
				(tracks not_allowed)
				(vias allowed)
				(pads allowed)
				(copperpour not_allowed)
				(footprints allowed)
			)
			(placement
				(enabled no)
				(sheetname "")
			)
			(fill
				(thermal_gap 0.5)
				(thermal_bridge_width 0.5)
				(island_removal_mode 0)
			)
			(polygon
				(pts
					(xy 94.183454 -73.00214) (xy 92.913454 -73.00214) (xy 92.913454 -72.24014) (xy 94.183454 -72.24014)
				)
			)
		)
	)
	(footprint ""
		(layer "B.Cu")
		(at 195.1736 -80.2386 90)
		(property "Reference" "CT42"
			(at 0.8382 -0.84963 90)
			(unlocked yes)
			(layer "B.SilkS")
			(effects
				(font
					(size 0.7874 0.5842)
					(thickness 0.1524)
				)
				(justify left mirror)
			)
		)
		(property "Value" ""
			(at 0 0 90)
			(layer "B.Fab")
			(effects
				(font
					(size 1.27 1.27)
				)
				(justify mirror)
			)
		)
		(duplicate_pad_numbers_are_jumpers no)
		(fp_poly
			(pts
				(xy -0.3048 -0.1016) (xy -0.3048 0.9906) (xy 0.3048 0.9906) (xy 0.3048 -0.1016)
			)
			(stroke
				(width 0)
				(type default)
			)
			(fill no)
			(layer "B.CrtYd")
		)
		(fp_line
			(start 0.3048 -0.1016)
			(end 0.3048 0.9906)
			(stroke
				(width 0.1)
				(type default)
			)
			(layer "B.Fab")
		)
		(fp_line
			(start -0.3048 -0.1016)
			(end 0.3048 -0.1016)
			(stroke
				(width 0.1)
				(type default)
			)
			(layer "B.Fab")
		)
		(fp_line
			(start 0.3048 0.9906)
			(end -0.3048 0.9906)
			(stroke
				(width 0.1)
				(type default)
			)
			(layer "B.Fab")
		)
		(fp_line
			(start -0.3048 0.9906)
			(end -0.3048 -0.1016)
			(stroke
				(width 0.1)
				(type default)
			)
			(layer "B.Fab")
		)
		(pad "1" smd rect
			(at 0 0 270)
			(size 0.508 0.508)
			(layers "B.Cu" "B.Mask" "B.Paste")
			(net "A_TSENSE_PVCCIN_CPU0")
		)
		(pad "2" smd rect
			(at 0 0.889 270)
			(size 0.508 0.508)
			(layers "B.Cu" "B.Mask" "B.Paste")
			(net "GND")
		)
		(zone
			(layer "B.Cu")
			(hatch none 0.5)
			(connect_pads
				(clearance 0)
			)
			(min_thickness 0.25)
			(keepout
				(tracks allowed)
				(vias not_allowed)
				(pads allowed)
				(copperpour not_allowed)
				(footprints allowed)
			)
			(placement
				(enabled no)
				(sheetname "")
			)
			(fill
				(thermal_gap 0.5)
				(thermal_bridge_width 0.5)
				(island_removal_mode 0)
			)
			(polygon
				(pts
					(xy 195.4276 -80.4926) (xy 195.4276 -79.9846) (xy 195.8086 -79.9846) (xy 195.8086 -80.4926)
				)
			)
		)
		(zone
			(layer "B.Cu")
			(hatch none 0.5)
			(connect_pads
				(clearance 0)
			)
			(min_thickness 0.25)
			(keepout
				(tracks not_allowed)
				(vias allowed)
				(pads allowed)
				(copperpour not_allowed)
				(footprints allowed)
			)
			(placement
				(enabled no)
				(sheetname "")
			)
			(fill
				(thermal_gap 0.5)
				(thermal_bridge_width 0.5)
				(island_removal_mode 0)
			)
			(polygon
				(pts
					(xy 195.8086 -80.4926) (xy 195.8086 -79.9846) (xy 195.4276 -79.9846) (xy 195.4276 -80.4926)
				)
			)
		)
	)
	(footprint ""
		(layer "B.Cu")
		(at 262.587486 -79.60614 180)
		(property "Reference" "C5P17"
			(at 0 0 0)
			(layer "B.SilkS")
			(hide yes)
			(effects
				(font
					(size 1.27 1.27)
				)
				(justify mirror)
			)
		)
		(property "Value" ""
			(at 0 0 0)
			(layer "B.Fab")
			(effects
				(font
					(size 1.27 1.27)
				)
				(justify mirror)
			)
		)
		(duplicate_pad_numbers_are_jumpers no)
		(fp_poly
			(pts
				(xy 0.7239 -0.2159) (xy -0.7239 -0.2159) (xy -0.7239 1.9939) (xy 0.7239 1.9939)
			)
			(stroke
				(width 0)
				(type default)
			)
			(fill no)
			(layer "B.CrtYd")
		)
		(fp_line
			(start 0.7239 1.9939)
			(end -0.7239 1.9939)
			(stroke
				(width 0.1)
				(type default)
			)
			(layer "B.Fab")
		)
		(fp_line
			(start 0.7239 -0.2159)
			(end 0.7239 1.9939)
			(stroke
				(width 0.1)
				(type default)
			)
			(layer "B.Fab")
		)
		(fp_line
			(start -0.7239 1.9939)
			(end -0.7239 -0.2159)
			(stroke
				(width 0.1)
				(type default)
			)
			(layer "B.Fab")
		)
		(fp_line
			(start -0.7239 -0.2159)
			(end 0.7239 -0.2159)
			(stroke
				(width 0.1)
				(type default)
			)
			(layer "B.Fab")
		)
		(pad "1" smd rect
			(at 0 0)
			(size 1.27 1.016)
			(layers "B.Cu" "B.Mask" "B.Paste")
			(net "PVCCIN_CPU0")
		)
		(pad "2" smd rect
			(at 0 1.778)
			(size 1.27 1.016)
			(layers "B.Cu" "B.Mask" "B.Paste")
			(net "GND")
		)
		(zone
			(layer "B.Cu")
			(hatch none 0.5)
			(connect_pads
				(clearance 0)
			)
			(min_thickness 0.25)
			(keepout
				(tracks not_allowed)
				(vias allowed)
				(pads allowed)
				(copperpour not_allowed)
				(footprints allowed)
			)
			(placement
				(enabled no)
				(sheetname "")
			)
			(fill
				(thermal_gap 0.5)
				(thermal_bridge_width 0.5)
				(island_removal_mode 0)
			)
			(polygon
				(pts
					(xy 261.952486 -80.11414) (xy 263.222486 -80.11414) (xy 263.222486 -80.87614) (xy 261.952486 -80.87614)
				)
			)
		)
	)
	(footprint ""
		(layer "B.Cu")
		(at 493.719104 -43.056048 180)
		(property "Reference" "C25W81"
			(at 0.8382 -0.67818 180)
			(unlocked yes)
			(layer "B.SilkS")
			(effects
				(font
					(size 0.4064 0.254)
					(thickness 0.1524)
				)
				(justify left mirror)
			)
		)
		(property "Value" ""
			(at 0 0 0)
			(layer "B.Fab")
			(effects
				(font
					(size 1.27 1.27)
				)
				(justify mirror)
			)
		)
		(duplicate_pad_numbers_are_jumpers no)
		(fp_poly
			(pts
				(xy -0.3048 -0.1016) (xy -0.3048 0.9906) (xy 0.3048 0.9906) (xy 0.3048 -0.1016)
			)
			(stroke
				(width 0)
				(type default)
			)
			(fill no)
			(layer "B.CrtYd")
		)
		(fp_line
			(start 0.3048 0.9906)
			(end -0.3048 0.9906)
			(stroke
				(width 0.1)
				(type default)
			)
			(layer "B.Fab")
		)
		(fp_line
			(start 0.3048 -0.1016)
			(end 0.3048 0.9906)
			(stroke
				(width 0.1)
				(type default)
			)
			(layer "B.Fab")
		)
		(fp_line
			(start -0.3048 0.9906)
			(end -0.3048 -0.1016)
			(stroke
				(width 0.1)
				(type default)
			)
			(layer "B.Fab")
		)
		(fp_line
			(start -0.3048 -0.1016)
			(end 0.3048 -0.1016)
			(stroke
				(width 0.1)
				(type default)
			)
			(layer "B.Fab")
		)
		(pad "1" smd rect
			(at 0 0)
			(size 0.508 0.508)
			(layers "B.Cu" "B.Mask" "B.Paste")
			(net "V_IO_HSYNC_J")
		)
		(pad "2" smd rect
			(at 0 0.889)
			(size 0.508 0.508)
			(layers "B.Cu" "B.Mask" "B.Paste")
			(net "GND")
		)
		(zone
			(layer "B.Cu")
			(hatch none 0.5)
			(connect_pads
				(clearance 0)
			)
			(min_thickness 0.25)
			(keepout
				(tracks not_allowed)
				(vias allowed)
				(pads allowed)
				(copperpour not_allowed)
				(footprints allowed)
			)
			(placement
				(enabled no)
				(sheetname "")
			)
			(fill
				(thermal_gap 0.5)
				(thermal_bridge_width 0.5)
				(island_removal_mode 0)
			)
			(polygon
				(pts
					(xy 493.465104 -43.691048) (xy 493.973104 -43.691048) (xy 493.973104 -43.310048) (xy 493.465104 -43.310048)
				)
			)
		)
		(zone
			(layer "B.Cu")
			(hatch none 0.5)
			(connect_pads
				(clearance 0)
			)
			(min_thickness 0.25)
			(keepout
				(tracks allowed)
				(vias not_allowed)
				(pads allowed)
				(copperpour not_allowed)
				(footprints allowed)
			)
			(placement
				(enabled no)
				(sheetname "")
			)
			(fill
				(thermal_gap 0.5)
				(thermal_bridge_width 0.5)
				(island_removal_mode 0)
			)
			(polygon
				(pts
					(xy 493.465104 -43.310048) (xy 493.973104 -43.310048) (xy 493.973104 -43.691048) (xy 493.465104 -43.691048)
				)
			)
		)
	)
	(footprint ""
		(layer "B.Cu")
		(at 499.618 -131.6228 -90)
		(property "Reference" "C1M28"
			(at 0 0 90)
			(layer "B.SilkS")
			(hide yes)
			(effects
				(font
					(size 1.27 1.27)
				)
				(justify mirror)
			)
		)
		(property "Value" ""
			(at 0 0 90)
			(layer "B.Fab")
			(effects
				(font
					(size 1.27 1.27)
				)
				(justify mirror)
			)
		)
		(duplicate_pad_numbers_are_jumpers no)
		(fp_poly
			(pts
				(xy -0.3048 -0.1016) (xy -0.3048 0.9906) (xy 0.3048 0.9906) (xy 0.3048 -0.1016)
			)
			(stroke
				(width 0)
				(type default)
			)
			(fill no)
			(layer "B.CrtYd")
		)
		(fp_line
			(start -0.3048 0.9906)
			(end -0.3048 -0.1016)
			(stroke
				(width 0.1)
				(type default)
			)
			(layer "B.Fab")
		)
		(fp_line
			(start 0.3048 0.9906)
			(end -0.3048 0.9906)
			(stroke
				(width 0.1)
				(type default)
			)
			(layer "B.Fab")
		)
		(fp_line
			(start -0.3048 -0.1016)
			(end 0.3048 -0.1016)
			(stroke
				(width 0.1)
				(type default)
			)
			(layer "B.Fab")
		)
		(fp_line
			(start 0.3048 -0.1016)
			(end 0.3048 0.9906)
			(stroke
				(width 0.1)
				(type default)
			)
			(layer "B.Fab")
		)
		(pad "1" smd rect
			(at 0 0 90)
			(size 0.508 0.508)
			(layers "B.Cu" "B.Mask" "B.Paste")
			(net "P3V3_STBY")
		)
		(pad "2" smd rect
			(at 0 0.889 90)
			(size 0.508 0.508)
			(layers "B.Cu" "B.Mask" "B.Paste")
			(net "GND")
		)
		(zone
			(layer "B.Cu")
			(hatch none 0.5)
			(connect_pads
				(clearance 0)
			)
			(min_thickness 0.25)
			(keepout
				(tracks not_allowed)
				(vias allowed)
				(pads allowed)
				(copperpour not_allowed)
				(footprints allowed)
			)
			(placement
				(enabled no)
				(sheetname "")
			)
			(fill
				(thermal_gap 0.5)
				(thermal_bridge_width 0.5)
				(island_removal_mode 0)
			)
			(polygon
				(pts
					(xy 498.983 -131.3688) (xy 498.983 -131.8768) (xy 499.364 -131.8768) (xy 499.364 -131.3688)
				)
			)
		)
		(zone
			(layer "B.Cu")
			(hatch none 0.5)
			(connect_pads
				(clearance 0)
			)
			(min_thickness 0.25)
			(keepout
				(tracks allowed)
				(vias not_allowed)
				(pads allowed)
				(copperpour not_allowed)
				(footprints allowed)
			)
			(placement
				(enabled no)
				(sheetname "")
			)
			(fill
				(thermal_gap 0.5)
				(thermal_bridge_width 0.5)
				(island_removal_mode 0)
			)
			(polygon
				(pts
					(xy 499.364 -131.3688) (xy 499.364 -131.8768) (xy 498.983 -131.8768) (xy 498.983 -131.3688)
				)
			)
		)
	)
	(footprint ""
		(layer "B.Cu")
		(at 422.91 -5.0165 180)
		(property "Reference" "C3P46"
			(at 0 0 0)
			(layer "B.SilkS")
			(hide yes)
			(effects
				(font
					(size 1.27 1.27)
				)
				(justify mirror)
			)
		)
		(property "Value" ""
			(at 0 0 0)
			(layer "B.Fab")
			(effects
				(font
					(size 1.27 1.27)
				)
				(justify mirror)
			)
		)
		(duplicate_pad_numbers_are_jumpers no)
		(fp_rect
			(start -0.3048 0.9906)
			(end 0.3048 -0.1016)
			(stroke
				(width 0)
				(type default)
			)
			(fill no)
			(layer "B.CrtYd")
		)
		(fp_line
			(start 0.3048 0.9906)
			(end -0.3048 0.9906)
			(stroke
				(width 0.1)
				(type default)
			)
			(layer "B.Fab")
		)
		(fp_line
			(start 0.3048 -0.1016)
			(end 0.3048 0.9906)
			(stroke
				(width 0.1)
				(type default)
			)
			(layer "B.Fab")
		)
		(fp_line
			(start -0.3048 0.9906)
			(end -0.3048 -0.1016)
			(stroke
				(width 0.1)
				(type default)
			)
			(layer "B.Fab")
		)
		(fp_line
			(start -0.3048 -0.1016)
			(end 0.3048 -0.1016)
			(stroke
				(width 0.1)
				(type default)
			)
			(layer "B.Fab")
		)
		(pad "1" smd rect
			(at 0 0)
			(size 0.508 0.508)
			(layers "B.Cu" "B.Mask" "B.Paste")
			(net "P3V3_STBY")
		)
		(pad "2" smd rect
			(at 0 0.889)
			(size 0.508 0.508)
			(layers "B.Cu" "B.Mask" "B.Paste")
			(net "GND")
		)
		(zone
			(layer "B.Cu")
			(hatch none 0.5)
			(connect_pads
				(clearance 0)
			)
			(min_thickness 0.25)
			(keepout
				(tracks not_allowed)
				(vias allowed)
				(pads allowed)
				(copperpour not_allowed)
				(footprints allowed)
			)
			(placement
				(enabled no)
				(sheetname "")
			)
			(fill
				(thermal_gap 0.5)
				(thermal_bridge_width 0.5)
				(island_removal_mode 0)
			)
			(polygon
				(pts
					(xy 423.164 -5.6515) (xy 422.656 -5.6515) (xy 422.656 -5.2705) (xy 423.164 -5.2705)
				)
			)
		)
		(zone
			(layer "B.Cu")
			(hatch none 0.5)
			(connect_pads
				(clearance 0)
			)
			(min_thickness 0.25)
			(keepout
				(tracks allowed)
				(vias not_allowed)
				(pads allowed)
				(copperpour not_allowed)
				(footprints allowed)
			)
			(placement
				(enabled no)
				(sheetname "")
			)
			(fill
				(thermal_gap 0.5)
				(thermal_bridge_width 0.5)
				(island_removal_mode 0)
			)
			(polygon
				(pts
					(xy 423.164 -5.6515) (xy 422.656 -5.6515) (xy 422.656 -5.2705) (xy 423.164 -5.2705)
				)
			)
		)
	)
	(footprint ""
		(layer "B.Cu")
		(at 376.936 -66.04 180)
		(property "Reference" "R2R1"
			(at 0 0 0)
			(layer "B.SilkS")
			(hide yes)
			(effects
				(font
					(size 1.27 1.27)
				)
				(justify mirror)
			)
		)
		(property "Value" ""
			(at 0 0 0)
			(layer "B.Fab")
			(effects
				(font
					(size 1.27 1.27)
				)
				(justify mirror)
			)
		)
		(duplicate_pad_numbers_are_jumpers no)
		(fp_poly
			(pts
				(xy 0.2794 -0.1016) (xy -0.2794 -0.1016) (xy -0.2794 0.9906) (xy 0.2794 0.9906)
			)
			(stroke
				(width 0)
				(type default)
			)
			(fill no)
			(layer "B.CrtYd")
		)
		(fp_line
			(start 0.2794 0.9906)
			(end -0.2794 0.9906)
			(stroke
				(width 0.1)
				(type default)
			)
			(layer "B.Fab")
		)
		(fp_line
			(start 0.2794 -0.1016)
			(end 0.2794 0.9906)
			(stroke
				(width 0.1)
				(type default)
			)
			(layer "B.Fab")
		)
		(fp_line
			(start -0.2794 0.9906)
			(end -0.2794 -0.1016)
			(stroke
				(width 0.1)
				(type default)
			)
			(layer "B.Fab")
		)
		(fp_line
			(start -0.2794 -0.1016)
			(end 0.2794 -0.1016)
			(stroke
				(width 0.1)
				(type default)
			)
			(layer "B.Fab")
		)
		(pad "1" smd rect
			(at 0 0)
			(size 0.508 0.508)
			(layers "B.Cu" "B.Mask" "B.Paste")
			(net "P3V3_STBY")
		)
		(pad "2" smd rect
			(at 0 0.889)
			(size 0.508 0.508)
			(layers "B.Cu" "B.Mask" "B.Paste")
			(net "PU_RST_PERST_BIT0")
		)
		(zone
			(layer "B.Cu")
			(hatch none 0.5)
			(connect_pads
				(clearance 0)
			)
			(min_thickness 0.25)
			(keepout
				(tracks not_allowed)
				(vias allowed)
				(pads allowed)
				(copperpour not_allowed)
				(footprints allowed)
			)
			(placement
				(enabled no)
				(sheetname "")
			)
			(fill
				(thermal_gap 0.5)
				(thermal_bridge_width 0.5)
				(island_removal_mode 0)
			)
			(polygon
				(pts
					(xy 376.682 -66.675) (xy 377.19 -66.675) (xy 377.19 -66.294) (xy 376.682 -66.294)
				)
			)
		)
		(zone
			(layer "B.Cu")
			(hatch none 0.5)
			(connect_pads
				(clearance 0)
			)
			(min_thickness 0.25)
			(keepout
				(tracks allowed)
				(vias not_allowed)
				(pads allowed)
				(copperpour not_allowed)
				(footprints allowed)
			)
			(placement
				(enabled no)
				(sheetname "")
			)
			(fill
				(thermal_gap 0.5)
				(thermal_bridge_width 0.5)
				(island_removal_mode 0)
			)
			(polygon
				(pts
					(xy 376.682 -66.294) (xy 377.19 -66.294) (xy 377.19 -66.675) (xy 376.682 -66.675)
				)
			)
		)
	)
	(footprint ""
		(layer "B.Cu")
		(at 262.271256 -83.74634 90)
		(property "Reference" "C5P7"
			(at 0 0 90)
			(layer "B.SilkS")
			(hide yes)
			(effects
				(font
					(size 1.27 1.27)
				)
				(justify mirror)
			)
		)
		(property "Value" ""
			(at 0 0 90)
			(layer "B.Fab")
			(effects
				(font
					(size 1.27 1.27)
				)
				(justify mirror)
			)
		)
		(duplicate_pad_numbers_are_jumpers no)
		(fp_poly
			(pts
				(xy 0.7239 -0.2159) (xy -0.7239 -0.2159) (xy -0.7239 1.9939) (xy 0.7239 1.9939)
			)
			(stroke
				(width 0)
				(type default)
			)
			(fill no)
			(layer "B.CrtYd")
		)
		(fp_line
			(start 0.7239 -0.2159)
			(end 0.7239 1.9939)
			(stroke
				(width 0.1)
				(type default)
			)
			(layer "B.Fab")
		)
		(fp_line
			(start -0.7239 -0.2159)
			(end 0.7239 -0.2159)
			(stroke
				(width 0.1)
				(type default)
			)
			(layer "B.Fab")
		)
		(fp_line
			(start 0.7239 1.9939)
			(end -0.7239 1.9939)
			(stroke
				(width 0.1)
				(type default)
			)
			(layer "B.Fab")
		)
		(fp_line
			(start -0.7239 1.9939)
			(end -0.7239 -0.2159)
			(stroke
				(width 0.1)
				(type default)
			)
			(layer "B.Fab")
		)
		(pad "1" smd rect
			(at 0 0 270)
			(size 1.27 1.016)
			(layers "B.Cu" "B.Mask" "B.Paste")
			(net "PVSA_CPU0")
		)
		(pad "2" smd rect
			(at 0 1.778 270)
			(size 1.27 1.016)
			(layers "B.Cu" "B.Mask" "B.Paste")
			(net "GND")
		)
		(zone
			(layer "B.Cu")
			(hatch none 0.5)
			(connect_pads
				(clearance 0)
			)
			(min_thickness 0.25)
			(keepout
				(tracks not_allowed)
				(vias allowed)
				(pads allowed)
				(copperpour not_allowed)
				(footprints allowed)
			)
			(placement
				(enabled no)
				(sheetname "")
			)
			(fill
				(thermal_gap 0.5)
				(thermal_bridge_width 0.5)
				(island_removal_mode 0)
			)
			(polygon
				(pts
					(xy 262.779256 -84.38134) (xy 262.779256 -83.11134) (xy 263.541256 -83.11134) (xy 263.541256 -84.38134)
				)
			)
		)
	)
	(footprint ""
		(layer "B.Cu")
		(at 433.243482 -148.520658 90)
		(property "Reference" "R2L18"
			(at 0 0 90)
			(layer "B.SilkS")
			(hide yes)
			(effects
				(font
					(size 1.27 1.27)
				)
				(justify mirror)
			)
		)
		(property "Value" ""
			(at 0 0 90)
			(layer "B.Fab")
			(effects
				(font
					(size 1.27 1.27)
				)
				(justify mirror)
			)
		)
		(duplicate_pad_numbers_are_jumpers no)
		(fp_poly
			(pts
				(xy 0.2794 -0.1016) (xy -0.2794 -0.1016) (xy -0.2794 0.9906) (xy 0.2794 0.9906)
			)
			(stroke
				(width 0)
				(type default)
			)
			(fill no)
			(layer "B.CrtYd")
		)
		(fp_line
			(start 0.2794 -0.1016)
			(end 0.2794 0.9906)
			(stroke
				(width 0.1)
				(type default)
			)
			(layer "B.Fab")
		)
		(fp_line
			(start -0.2794 -0.1016)
			(end 0.2794 -0.1016)
			(stroke
				(width 0.1)
				(type default)
			)
			(layer "B.Fab")
		)
		(fp_line
			(start 0.2794 0.9906)
			(end -0.2794 0.9906)
			(stroke
				(width 0.1)
				(type default)
			)
			(layer "B.Fab")
		)
		(fp_line
			(start -0.2794 0.9906)
			(end -0.2794 -0.1016)
			(stroke
				(width 0.1)
				(type default)
			)
			(layer "B.Fab")
		)
		(pad "1" smd rect
			(at 0 0 270)
			(size 0.508 0.508)
			(layers "B.Cu" "B.Mask" "B.Paste")
			(net "PD_SATA0_CONTROLLER_TYPE_R")
		)
		(pad "2" smd rect
			(at 0 0.889 270)
			(size 0.508 0.508)
			(layers "B.Cu" "B.Mask" "B.Paste")
			(net "GND")
		)
		(zone
			(layer "B.Cu")
			(hatch none 0.5)
			(connect_pads
				(clearance 0)
			)
			(min_thickness 0.25)
			(keepout
				(tracks allowed)
				(vias not_allowed)
				(pads allowed)
				(copperpour not_allowed)
				(footprints allowed)
			)
			(placement
				(enabled no)
				(sheetname "")
			)
			(fill
				(thermal_gap 0.5)
				(thermal_bridge_width 0.5)
				(island_removal_mode 0)
			)
			(polygon
				(pts
					(xy 433.497482 -148.774658) (xy 433.497482 -148.266658) (xy 433.878482 -148.266658) (xy 433.878482 -148.774658)
				)
			)
		)
		(zone
			(layer "B.Cu")
			(hatch none 0.5)
			(connect_pads
				(clearance 0)
			)
			(min_thickness 0.25)
			(keepout
				(tracks not_allowed)
				(vias allowed)
				(pads allowed)
				(copperpour not_allowed)
				(footprints allowed)
			)
			(placement
				(enabled no)
				(sheetname "")
			)
			(fill
				(thermal_gap 0.5)
				(thermal_bridge_width 0.5)
				(island_removal_mode 0)
			)
			(polygon
				(pts
					(xy 433.878482 -148.774658) (xy 433.878482 -148.266658) (xy 433.497482 -148.266658) (xy 433.497482 -148.774658)
				)
			)
		)
	)
	(footprint ""
		(layer "B.Cu")
		(at 258.548886 -73.51014)
		(property "Reference" "C5P37"
			(at 0 0 0)
			(layer "B.SilkS")
			(hide yes)
			(effects
				(font
					(size 1.27 1.27)
				)
				(justify mirror)
			)
		)
		(property "Value" ""
			(at 0 0 0)
			(layer "B.Fab")
			(effects
				(font
					(size 1.27 1.27)
				)
				(justify mirror)
			)
		)
		(duplicate_pad_numbers_are_jumpers no)
		(fp_poly
			(pts
				(xy 0.7239 -0.2159) (xy -0.7239 -0.2159) (xy -0.7239 1.9939) (xy 0.7239 1.9939)
			)
			(stroke
				(width 0)
				(type default)
			)
			(fill no)
			(layer "B.CrtYd")
		)
		(fp_line
			(start -0.7239 -0.2159)
			(end 0.7239 -0.2159)
			(stroke
				(width 0.1)
				(type default)
			)
			(layer "B.Fab")
		)
		(fp_line
			(start -0.7239 1.9939)
			(end -0.7239 -0.2159)
			(stroke
				(width 0.1)
				(type default)
			)
			(layer "B.Fab")
		)
		(fp_line
			(start 0.7239 -0.2159)
			(end 0.7239 1.9939)
			(stroke
				(width 0.1)
				(type default)
			)
			(layer "B.Fab")
		)
		(fp_line
			(start 0.7239 1.9939)
			(end -0.7239 1.9939)
			(stroke
				(width 0.1)
				(type default)
			)
			(layer "B.Fab")
		)
		(pad "1" smd rect
			(at 0 0 180)
			(size 1.27 1.016)
			(layers "B.Cu" "B.Mask" "B.Paste")
			(net "PVCCIN_CPU0")
		)
		(pad "2" smd rect
			(at 0 1.778 180)
			(size 1.27 1.016)
			(layers "B.Cu" "B.Mask" "B.Paste")
			(net "GND")
		)
		(zone
			(layer "B.Cu")
			(hatch none 0.5)
			(connect_pads
				(clearance 0)
			)
			(min_thickness 0.25)
			(keepout
				(tracks not_allowed)
				(vias allowed)
				(pads allowed)
				(copperpour not_allowed)
				(footprints allowed)
			)
			(placement
				(enabled no)
				(sheetname "")
			)
			(fill
				(thermal_gap 0.5)
				(thermal_bridge_width 0.5)
				(island_removal_mode 0)
			)
			(polygon
				(pts
					(xy 259.183886 -73.00214) (xy 257.913886 -73.00214) (xy 257.913886 -72.24014) (xy 259.183886 -72.24014)
				)
			)
		)
	)
	(footprint ""
		(layer "B.Cu")
		(at 395.7828 -27.92476 90)
		(property "Reference" "U8F3"
			(at 0 0 90)
			(layer "B.SilkS")
			(hide yes)
			(effects
				(font
					(size 1.27 1.27)
				)
				(justify mirror)
			)
		)
		(property "Value" "*"
			(at 2.3622 -8.3185 90)
			(unlocked yes)
			(layer "B.Fab")
			(hide yes)
			(effects
				(font
					(size 1.27 1.016)
					(thickness 0.1524)
				)
				(justify mirror)
			)
		)
		(property "Device Type" "SN74LVC2G07DCKR-GP_DISCRET-G4-A"
			(at 2.3622 -10.2235 90)
			(unlocked yes)
			(layer "B.Fab")
			(hide yes)
			(effects
				(font
					(size 1.27 1.016)
					(thickness 0.1524)
				)
				(justify mirror)
			)
		)
		(duplicate_pad_numbers_are_jumpers no)
		(fp_line
			(start 1.4478 -1.7018)
			(end 1.4478 1.7018)
			(stroke
				(width 0.1524)
				(type default)
			)
			(layer "B.SilkS")
		)
		(fp_line
			(start -1.4478 -1.7018)
			(end 1.4478 -1.7018)
			(stroke
				(width 0.1524)
				(type default)
			)
			(layer "B.SilkS")
		)
		(fp_line
			(start 1.4478 1.7018)
			(end -1.4478 1.7018)
			(stroke
				(width 0.1524)
				(type default)
			)
			(layer "B.SilkS")
		)
		(fp_line
			(start -1.4478 1.7018)
			(end -1.4478 -1.7018)
			(stroke
				(width 0.1524)
				(type default)
			)
			(layer "B.SilkS")
		)
		(fp_line
			(start 1.5494 1.7907)
			(end 1.5494 0.8255)
			(stroke
				(width 0.635)
				(type default)
			)
			(layer "B.SilkS")
		)
		(fp_line
			(start 0.5715 1.7907)
			(end 1.5494 1.7907)
			(stroke
				(width 0.635)
				(type default)
			)
			(layer "B.SilkS")
		)
		(fp_poly
			(pts
				(xy 1.81864 2.02184) (xy 2.17424 1.66624) (xy 2.39268 1.4478) (xy 2.41808 1.4224) (xy 2.42824 1.4224)
				(xy 2.42824 1.4478) (xy 2.42824 2.6162) (xy 2.413 2.6162) (xy 2.17424 2.37744)
			)
			(stroke
				(width 0)
				(type default)
			)
			(fill yes)
			(layer "B.SilkS")
		)
		(fp_poly
			(pts
				(xy 1.524 -1.778) (xy -1.524 -1.778) (xy -1.524 1.778) (xy 1.524 1.778)
			)
			(stroke
				(width 0)
				(type default)
			)
			(fill no)
			(layer "B.CrtYd")
		)
		(fp_poly
			(pts
				(xy 1.524 -1.778) (xy -1.524 -1.778) (xy -1.524 1.778) (xy 1.524 1.778)
			)
			(stroke
				(width 0)
				(type default)
			)
			(fill no)
			(layer "B.Fab")
		)
		(pad "1" smd rect
			(at 0.65024 0.9398 270)
			(size 0.4064 1.016)
			(layers "B.Cu" "B.Mask" "B.Paste")
			(net "RST_BMC_SYSRST_BTN_OUT_N")
		)
		(pad "2" smd rect
			(at 0 0.9398 270)
			(size 0.4064 1.016)
			(layers "B.Cu" "B.Mask" "B.Paste")
			(net "GND")
		)
		(pad "3" smd rect
			(at -0.65024 0.9398 270)
			(size 0.4064 1.016)
			(layers "B.Cu" "B.Mask" "B.Paste")
			(net "FM_BMC_PWRBTN_OUT_N")
		)
		(pad "4" smd rect
			(at -0.65024 -0.9398 270)
			(size 0.4064 1.016)
			(layers "B.Cu" "B.Mask" "B.Paste")
			(net "FM_PCH_PWRBTN_R_N")
		)
		(pad "5" smd rect
			(at 0 -0.9398 270)
			(size 0.4064 1.016)
			(layers "B.Cu" "B.Mask" "B.Paste")
			(net "P3V3_STBY")
		)
		(pad "6" smd rect
			(at 0.65024 -0.9398 270)
			(size 0.4064 1.016)
			(layers "B.Cu" "B.Mask" "B.Paste")
			(net "RST_BMC_SYSRST_BTN_OUT_B_R_N")
		)
	)
	(footprint ""
		(layer "B.Cu")
		(at 282.259024 -71.867014 -90)
		(property "Reference" "R4P11"
			(at 0 0 90)
			(layer "B.SilkS")
			(hide yes)
			(effects
				(font
					(size 1.27 1.27)
				)
				(justify mirror)
			)
		)
		(property "Value" ""
			(at 0 0 90)
			(layer "B.Fab")
			(effects
				(font
					(size 1.27 1.27)
				)
				(justify mirror)
			)
		)
		(duplicate_pad_numbers_are_jumpers no)
		(fp_rect
			(start 0.2794 0.9906)
			(end -0.2794 -0.1016)
			(stroke
				(width 0)
				(type default)
			)
			(fill no)
			(layer "B.CrtYd")
		)
		(fp_line
			(start -0.2794 0.9906)
			(end -0.2794 -0.1016)
			(stroke
				(width 0.1)
				(type default)
			)
			(layer "B.Fab")
		)
		(fp_line
			(start 0.2794 0.9906)
			(end -0.2794 0.9906)
			(stroke
				(width 0.1)
				(type default)
			)
			(layer "B.Fab")
		)
		(fp_line
			(start -0.2794 -0.1016)
			(end 0.2794 -0.1016)
			(stroke
				(width 0.1)
				(type default)
			)
			(layer "B.Fab")
		)
		(fp_line
			(start 0.2794 -0.1016)
			(end 0.2794 0.9906)
			(stroke
				(width 0.1)
				(type default)
			)
			(layer "B.Fab")
		)
		(pad "1" smd rect
			(at 0 0 90)
			(size 0.508 0.508)
			(layers "B.Cu" "B.Mask" "B.Paste")
			(net "A_CPU0_ABC_RCOMP2")
		)
		(pad "2" smd rect
			(at 0 0.889 90)
			(size 0.508 0.508)
			(layers "B.Cu" "B.Mask" "B.Paste")
			(net "GND")
		)
		(zone
			(layer "B.Cu")
			(hatch none 0.5)
			(connect_pads
				(clearance 0)
			)
			(min_thickness 0.25)
			(keepout
				(tracks allowed)
				(vias not_allowed)
				(pads allowed)
				(copperpour not_allowed)
				(footprints allowed)
			)
			(placement
				(enabled no)
				(sheetname "")
			)
			(fill
				(thermal_gap 0.5)
				(thermal_bridge_width 0.5)
				(island_removal_mode 0)
			)
			(polygon
				(pts
					(xy 281.624024 -71.613014) (xy 282.005024 -71.613014) (xy 282.005024 -72.121014) (xy 281.624024 -72.121014)
				)
			)
		)
		(zone
			(layer "B.Cu")
			(hatch none 0.5)
			(connect_pads
				(clearance 0)
			)
			(min_thickness 0.25)
			(keepout
				(tracks not_allowed)
				(vias allowed)
				(pads allowed)
				(copperpour not_allowed)
				(footprints allowed)
			)
			(placement
				(enabled no)
				(sheetname "")
			)
			(fill
				(thermal_gap 0.5)
				(thermal_bridge_width 0.5)
				(island_removal_mode 0)
			)
			(polygon
				(pts
					(xy 281.624024 -71.613014) (xy 282.005024 -71.613014) (xy 282.005024 -72.121014) (xy 281.624024 -72.121014)
				)
			)
		)
	)
	(footprint ""
		(layer "B.Cu")
		(at 416.883596 -32.327342 180)
		(property "Reference" "C25W27"
			(at 0.8382 -0.67818 180)
			(unlocked yes)
			(layer "B.SilkS")
			(effects
				(font
					(size 0.4064 0.254)
					(thickness 0.1524)
				)
				(justify left mirror)
			)
		)
		(property "Value" ""
			(at 0 0 0)
			(layer "B.Fab")
			(effects
				(font
					(size 1.27 1.27)
				)
				(justify mirror)
			)
		)
		(duplicate_pad_numbers_are_jumpers no)
		(fp_poly
			(pts
				(xy -0.3048 -0.1016) (xy -0.3048 0.9906) (xy 0.3048 0.9906) (xy 0.3048 -0.1016)
			)
			(stroke
				(width 0)
				(type default)
			)
			(fill no)
			(layer "B.CrtYd")
		)
		(fp_line
			(start 0.3048 0.9906)
			(end -0.3048 0.9906)
			(stroke
				(width 0.1)
				(type default)
			)
			(layer "B.Fab")
		)
		(fp_line
			(start 0.3048 -0.1016)
			(end 0.3048 0.9906)
			(stroke
				(width 0.1)
				(type default)
			)
			(layer "B.Fab")
		)
		(fp_line
			(start -0.3048 0.9906)
			(end -0.3048 -0.1016)
			(stroke
				(width 0.1)
				(type default)
			)
			(layer "B.Fab")
		)
		(fp_line
			(start -0.3048 -0.1016)
			(end 0.3048 -0.1016)
			(stroke
				(width 0.1)
				(type default)
			)
			(layer "B.Fab")
		)
		(pad "1" smd rect
			(at 0 0)
			(size 0.508 0.508)
			(layers "B.Cu" "B.Mask" "B.Paste")
			(net "P1V15_AUX_BMC")
		)
		(pad "2" smd rect
			(at 0 0.889)
			(size 0.508 0.508)
			(layers "B.Cu" "B.Mask" "B.Paste")
			(net "GND")
		)
		(zone
			(layer "B.Cu")
			(hatch none 0.5)
			(connect_pads
				(clearance 0)
			)
			(min_thickness 0.25)
			(keepout
				(tracks not_allowed)
				(vias allowed)
				(pads allowed)
				(copperpour not_allowed)
				(footprints allowed)
			)
			(placement
				(enabled no)
				(sheetname "")
			)
			(fill
				(thermal_gap 0.5)
				(thermal_bridge_width 0.5)
				(island_removal_mode 0)
			)
			(polygon
				(pts
					(xy 416.629596 -32.962342) (xy 417.137596 -32.962342) (xy 417.137596 -32.581342) (xy 416.629596 -32.581342)
				)
			)
		)
		(zone
			(layer "B.Cu")
			(hatch none 0.5)
			(connect_pads
				(clearance 0)
			)
			(min_thickness 0.25)
			(keepout
				(tracks allowed)
				(vias not_allowed)
				(pads allowed)
				(copperpour not_allowed)
				(footprints allowed)
			)
			(placement
				(enabled no)
				(sheetname "")
			)
			(fill
				(thermal_gap 0.5)
				(thermal_bridge_width 0.5)
				(island_removal_mode 0)
			)
			(polygon
				(pts
					(xy 416.629596 -32.581342) (xy 417.137596 -32.581342) (xy 417.137596 -32.962342) (xy 416.629596 -32.962342)
				)
			)
		)
	)
	(footprint ""
		(layer "B.Cu")
		(at 168.61028 -148.7424 -90)
		(property "Reference" "R6L5"
			(at 0 0 90)
			(layer "B.SilkS")
			(hide yes)
			(effects
				(font
					(size 1.27 1.27)
				)
				(justify mirror)
			)
		)
		(property "Value" ""
			(at 0 0 90)
			(layer "B.Fab")
			(effects
				(font
					(size 1.27 1.27)
				)
				(justify mirror)
			)
		)
		(duplicate_pad_numbers_are_jumpers no)
		(fp_rect
			(start -0.2794 -0.1016)
			(end 0.2794 0.9906)
			(stroke
				(width 0)
				(type default)
			)
			(fill no)
			(layer "B.CrtYd")
		)
		(fp_line
			(start -0.2794 0.9906)
			(end -0.2794 -0.1016)
			(stroke
				(width 0.1)
				(type default)
			)
			(layer "B.Fab")
		)
		(fp_line
			(start 0.2794 0.9906)
			(end -0.2794 0.9906)
			(stroke
				(width 0.1)
				(type default)
			)
			(layer "B.Fab")
		)
		(fp_line
			(start -0.2794 -0.1016)
			(end 0.2794 -0.1016)
			(stroke
				(width 0.1)
				(type default)
			)
			(layer "B.Fab")
		)
		(fp_line
			(start 0.2794 -0.1016)
			(end 0.2794 0.9906)
			(stroke
				(width 0.1)
				(type default)
			)
			(layer "B.Fab")
		)
		(pad "1" smd rect
			(at 0 0 90)
			(size 0.508 0.508)
			(layers "B.Cu" "B.Mask" "B.Paste")
			(net "P3V3")
		)
		(pad "2" smd rect
			(at 0 0.889 90)
			(size 0.508 0.508)
			(layers "B.Cu" "B.Mask" "B.Paste")
			(net "FM_PVTT_KLM_EN_R")
		)
		(zone
			(layer "B.Cu")
			(hatch none 0.5)
			(connect_pads
				(clearance 0)
			)
			(min_thickness 0.25)
			(keepout
				(tracks not_allowed)
				(vias allowed)
				(pads allowed)
				(copperpour not_allowed)
				(footprints allowed)
			)
			(placement
				(enabled no)
				(sheetname "")
			)
			(fill
				(thermal_gap 0.5)
				(thermal_bridge_width 0.5)
				(island_removal_mode 0)
			)
			(polygon
				(pts
					(xy 168.35628 -148.9964) (xy 167.97528 -148.9964) (xy 167.97528 -148.4884) (xy 168.35628 -148.4884)
				)
			)
		)
		(zone
			(layer "B.Cu")
			(hatch none 0.5)
			(connect_pads
				(clearance 0)
			)
			(min_thickness 0.25)
			(keepout
				(tracks allowed)
				(vias not_allowed)
				(pads allowed)
				(copperpour not_allowed)
				(footprints allowed)
			)
			(placement
				(enabled no)
				(sheetname "")
			)
			(fill
				(thermal_gap 0.5)
				(thermal_bridge_width 0.5)
				(island_removal_mode 0)
			)
			(polygon
				(pts
					(xy 168.35628 -148.9964) (xy 167.97528 -148.9964) (xy 167.97528 -148.4884) (xy 168.35628 -148.4884)
				)
			)
		)
	)
	(footprint ""
		(layer "B.Cu")
		(at 418.719 -35.1155 180)
		(property "Reference" "C25W53"
			(at 0.8382 -0.67818 180)
			(unlocked yes)
			(layer "B.SilkS")
			(effects
				(font
					(size 0.4064 0.254)
					(thickness 0.1524)
				)
				(justify left mirror)
			)
		)
		(property "Value" ""
			(at 0 0 0)
			(layer "B.Fab")
			(effects
				(font
					(size 1.27 1.27)
				)
				(justify mirror)
			)
		)
		(duplicate_pad_numbers_are_jumpers no)
		(fp_poly
			(pts
				(xy -0.3048 -0.1016) (xy -0.3048 0.9906) (xy 0.3048 0.9906) (xy 0.3048 -0.1016)
			)
			(stroke
				(width 0)
				(type default)
			)
			(fill no)
			(layer "B.CrtYd")
		)
		(fp_line
			(start 0.3048 0.9906)
			(end -0.3048 0.9906)
			(stroke
				(width 0.1)
				(type default)
			)
			(layer "B.Fab")
		)
		(fp_line
			(start 0.3048 -0.1016)
			(end 0.3048 0.9906)
			(stroke
				(width 0.1)
				(type default)
			)
			(layer "B.Fab")
		)
		(fp_line
			(start -0.3048 0.9906)
			(end -0.3048 -0.1016)
			(stroke
				(width 0.1)
				(type default)
			)
			(layer "B.Fab")
		)
		(fp_line
			(start -0.3048 -0.1016)
			(end 0.3048 -0.1016)
			(stroke
				(width 0.1)
				(type default)
			)
			(layer "B.Fab")
		)
		(pad "1" smd rect
			(at 0 0)
			(size 0.508 0.508)
			(layers "B.Cu" "B.Mask" "B.Paste")
			(net "P1V2_AUX_BMC")
		)
		(pad "2" smd rect
			(at 0 0.889)
			(size 0.508 0.508)
			(layers "B.Cu" "B.Mask" "B.Paste")
			(net "GND")
		)
		(zone
			(layer "B.Cu")
			(hatch none 0.5)
			(connect_pads
				(clearance 0)
			)
			(min_thickness 0.25)
			(keepout
				(tracks not_allowed)
				(vias allowed)
				(pads allowed)
				(copperpour not_allowed)
				(footprints allowed)
			)
			(placement
				(enabled no)
				(sheetname "")
			)
			(fill
				(thermal_gap 0.5)
				(thermal_bridge_width 0.5)
				(island_removal_mode 0)
			)
			(polygon
				(pts
					(xy 418.465 -35.7505) (xy 418.973 -35.7505) (xy 418.973 -35.3695) (xy 418.465 -35.3695)
				)
			)
		)
		(zone
			(layer "B.Cu")
			(hatch none 0.5)
			(connect_pads
				(clearance 0)
			)
			(min_thickness 0.25)
			(keepout
				(tracks allowed)
				(vias not_allowed)
				(pads allowed)
				(copperpour not_allowed)
				(footprints allowed)
			)
			(placement
				(enabled no)
				(sheetname "")
			)
			(fill
				(thermal_gap 0.5)
				(thermal_bridge_width 0.5)
				(island_removal_mode 0)
			)
			(polygon
				(pts
					(xy 418.465 -35.3695) (xy 418.973 -35.3695) (xy 418.973 -35.7505) (xy 418.465 -35.7505)
				)
			)
		)
	)
	(footprint ""
		(layer "B.Cu")
		(at 409.884118 -87.526114 180)
		(property "Reference" "Q7E2"
			(at 1.20777 1.88214 90)
			(unlocked yes)
			(layer "B.SilkS")
			(effects
				(font
					(size 0.7874 0.5842)
					(thickness 0.1524)
				)
				(justify left mirror)
			)
		)
		(property "Value" ""
			(at 0 0 0)
			(layer "B.Fab")
			(effects
				(font
					(size 1.27 1.27)
				)
				(justify mirror)
			)
		)
		(duplicate_pad_numbers_are_jumpers no)
		(fp_circle
			(center 0.508 -0.7874)
			(end 0.381 -0.7874)
			(stroke
				(width 0.254)
				(type default)
			)
			(fill no)
			(layer "B.SilkS")
		)
		(fp_poly
			(pts
				(xy -0.2159 1.7526) (xy -1.5621 1.7526) (xy -1.5621 -0.4572) (xy -0.2159 -0.4572)
			)
			(stroke
				(width 0)
				(type default)
			)
			(fill no)
			(layer "B.CrtYd")
		)
		(fp_line
			(start -0.2159 1.75514)
			(end -1.5621 1.75514)
			(stroke
				(width 0.1)
				(type default)
			)
			(layer "B.Fab")
		)
		(fp_line
			(start -0.2159 -0.45466)
			(end -0.2159 1.75514)
			(stroke
				(width 0.1)
				(type default)
			)
			(layer "B.Fab")
		)
		(fp_line
			(start -1.5621 1.75514)
			(end -1.5621 -0.45466)
			(stroke
				(width 0.1)
				(type default)
			)
			(layer "B.Fab")
		)
		(fp_line
			(start -1.5621 -0.45466)
			(end -0.2159 -0.45466)
			(stroke
				(width 0.1)
				(type default)
			)
			(layer "B.Fab")
		)
		(fp_circle
			(center 0.508 -0.7874)
			(end 0.381 -0.7874)
			(stroke
				(width 0.254)
				(type default)
			)
			(fill no)
			(layer "B.Fab")
		)
		(pad "1" smd rect
			(at 0 0)
			(size 1.016 0.381)
			(layers "B.Cu" "B.Mask" "B.Paste")
			(net "GND")
		)
		(pad "2" smd rect
			(at 0 0.65024)
			(size 1.016 0.381)
			(layers "B.Cu" "B.Mask" "B.Paste")
			(net "IRQ_PVDDQ_GHJ_VRHOT_LVT3_N")
		)
		(pad "3" smd rect
			(at 0 1.30048)
			(size 1.016 0.381)
			(layers "B.Cu" "B.Mask" "B.Paste")
			(net "H_CPU1_MEMGHJ_MEMHOT_G_N")
		)
		(pad "4" smd rect
			(at -1.778 1.30048)
			(size 1.016 0.381)
			(layers "B.Cu" "B.Mask" "B.Paste")
			(net "GND")
		)
		(pad "5" smd rect
			(at -1.778 0.65024)
			(size 1.016 0.381)
			(layers "B.Cu" "B.Mask" "B.Paste")
			(net "H_CPU1_MEMGHJ_MEMHOT")
		)
		(pad "6" smd rect
			(at -1.778 0)
			(size 1.016 0.381)
			(layers "B.Cu" "B.Mask" "B.Paste")
			(net "H_CPU1_MEMGHJ_MEMHOT")
		)
		(zone
			(layer "B.Cu")
			(hatch none 0.5)
			(connect_pads
				(clearance 0)
			)
			(min_thickness 0.25)
			(keepout
				(tracks allowed)
				(vias not_allowed)
				(pads allowed)
				(copperpour not_allowed)
				(footprints allowed)
			)
			(placement
				(enabled no)
				(sheetname "")
			)
			(fill
				(thermal_gap 0.5)
				(thermal_bridge_width 0.5)
				(island_removal_mode 0)
			)
			(polygon
				(pts
					(xy 409.376118 -87.335614) (xy 410.392118 -87.335614) (xy 410.392118 -89.024714) (xy 409.376118 -89.024714)
				)
			)
		)
		(zone
			(layer "B.Cu")
			(hatch none 0.5)
			(connect_pads
				(clearance 0)
			)
			(min_thickness 0.25)
			(keepout
				(tracks allowed)
				(vias not_allowed)
				(pads allowed)
				(copperpour not_allowed)
				(footprints allowed)
			)
			(placement
				(enabled no)
				(sheetname "")
			)
			(fill
				(thermal_gap 0.5)
				(thermal_bridge_width 0.5)
				(island_removal_mode 0)
			)
			(polygon
				(pts
					(xy 411.154118 -87.335614) (xy 412.170118 -87.335614) (xy 412.170118 -89.024714) (xy 411.154118 -89.024714)
				)
			)
		)
	)
	(footprint ""
		(layer "B.Cu")
		(at 438.604406 -32.100774 90)
		(property "Reference" "R1T40"
			(at 0.8382 -0.67818 90)
			(unlocked yes)
			(layer "B.SilkS")
			(effects
				(font
					(size 0.4064 0.254)
					(thickness 0.1524)
				)
				(justify left mirror)
			)
		)
		(property "Value" ""
			(at 0 0 90)
			(layer "B.Fab")
			(effects
				(font
					(size 1.27 1.27)
				)
				(justify mirror)
			)
		)
		(duplicate_pad_numbers_are_jumpers no)
		(fp_poly
			(pts
				(xy 0.2794 -0.1016) (xy -0.2794 -0.1016) (xy -0.2794 0.9906) (xy 0.2794 0.9906)
			)
			(stroke
				(width 0)
				(type default)
			)
			(fill no)
			(layer "B.CrtYd")
		)
		(fp_line
			(start 0.2794 -0.1016)
			(end 0.2794 0.9906)
			(stroke
				(width 0.1)
				(type default)
			)
			(layer "B.Fab")
		)
		(fp_line
			(start -0.2794 -0.1016)
			(end 0.2794 -0.1016)
			(stroke
				(width 0.1)
				(type default)
			)
			(layer "B.Fab")
		)
		(fp_line
			(start 0.2794 0.9906)
			(end -0.2794 0.9906)
			(stroke
				(width 0.1)
				(type default)
			)
			(layer "B.Fab")
		)
		(fp_line
			(start -0.2794 0.9906)
			(end -0.2794 -0.1016)
			(stroke
				(width 0.1)
				(type default)
			)
			(layer "B.Fab")
		)
		(pad "1" smd rect
			(at 0 0 270)
			(size 0.508 0.508)
			(layers "B.Cu" "B.Mask" "B.Paste")
			(net "BMC_M_CLK_DP")
		)
		(pad "2" smd rect
			(at 0 0.889 270)
			(size 0.508 0.508)
			(layers "B.Cu" "B.Mask" "B.Paste")
			(net "BMC_M_CLK")
		)
		(zone
			(layer "B.Cu")
			(hatch none 0.5)
			(connect_pads
				(clearance 0)
			)
			(min_thickness 0.25)
			(keepout
				(tracks allowed)
				(vias not_allowed)
				(pads allowed)
				(copperpour not_allowed)
				(footprints allowed)
			)
			(placement
				(enabled no)
				(sheetname "")
			)
			(fill
				(thermal_gap 0.5)
				(thermal_bridge_width 0.5)
				(island_removal_mode 0)
			)
			(polygon
				(pts
					(xy 438.858406 -32.354774) (xy 438.858406 -31.846774) (xy 439.239406 -31.846774) (xy 439.239406 -32.354774)
				)
			)
		)
		(zone
			(layer "B.Cu")
			(hatch none 0.5)
			(connect_pads
				(clearance 0)
			)
			(min_thickness 0.25)
			(keepout
				(tracks not_allowed)
				(vias allowed)
				(pads allowed)
				(copperpour not_allowed)
				(footprints allowed)
			)
			(placement
				(enabled no)
				(sheetname "")
			)
			(fill
				(thermal_gap 0.5)
				(thermal_bridge_width 0.5)
				(island_removal_mode 0)
			)
			(polygon
				(pts
					(xy 439.239406 -32.354774) (xy 439.239406 -31.846774) (xy 438.858406 -31.846774) (xy 438.858406 -32.354774)
				)
			)
		)
	)
	(footprint ""
		(layer "B.Cu")
		(at 45.212 -67.945 -90)
		(property "Reference" "C9P23"
			(at 0.53467 -3.937 0)
			(unlocked yes)
			(layer "B.SilkS")
			(effects
				(font
					(size 0.7874 0.5842)
					(thickness 0.1524)
				)
				(justify mirror)
			)
		)
		(property "Value" ""
			(at 0 0 90)
			(layer "B.Fab")
			(effects
				(font
					(size 1.27 1.27)
				)
				(justify mirror)
			)
		)
		(duplicate_pad_numbers_are_jumpers no)
		(fp_line
			(start -2.286 7.366)
			(end -1.600708 7.366)
			(stroke
				(width 0.1524)
				(type default)
			)
			(layer "B.SilkS")
		)
		(fp_line
			(start -2.286 7.366)
			(end -2.286 1.63195)
			(stroke
				(width 0.1524)
				(type default)
			)
			(layer "B.SilkS")
		)
		(fp_line
			(start 2.286 7.366)
			(end 1.60147 7.366)
			(stroke
				(width 0.1524)
				(type default)
			)
			(layer "B.SilkS")
		)
		(fp_line
			(start 2.286 7.366)
			(end 2.286 1.632712)
			(stroke
				(width 0.1524)
				(type default)
			)
			(layer "B.SilkS")
		)
		(fp_line
			(start -2.504948 1.633728)
			(end -1.6002 1.633728)
			(stroke
				(width 0.1524)
				(type default)
			)
			(layer "B.SilkS")
		)
		(fp_line
			(start 2.563114 1.633728)
			(end 1.6002 1.633728)
			(stroke
				(width 0.1524)
				(type default)
			)
			(layer "B.SilkS")
		)
		(fp_line
			(start -2.504948 -1.616456)
			(end -2.504948 1.633728)
			(stroke
				(width 0.1524)
				(type default)
			)
			(layer "B.SilkS")
		)
		(fp_line
			(start -1.6002 -1.616456)
			(end -2.504948 -1.616456)
			(stroke
				(width 0.1524)
				(type default)
			)
			(layer "B.SilkS")
		)
		(fp_line
			(start 1.6002 -1.616456)
			(end 2.563114 -1.616456)
			(stroke
				(width 0.1524)
				(type default)
			)
			(layer "B.SilkS")
		)
		(fp_line
			(start 2.563114 -1.616456)
			(end 2.563114 1.633728)
			(stroke
				(width 0.1524)
				(type default)
			)
			(layer "B.SilkS")
		)
		(fp_rect
			(start 2.286 7.366)
			(end -2.286 -0.254)
			(stroke
				(width 0)
				(type default)
			)
			(fill no)
			(layer "B.CrtYd")
		)
		(fp_line
			(start -2.286 7.366)
			(end 2.286 7.366)
			(stroke
				(width 0.1)
				(type default)
			)
			(layer "B.Fab")
		)
		(fp_line
			(start 2.286 7.366)
			(end 2.286 -0.254)
			(stroke
				(width 0.1)
				(type default)
			)
			(layer "B.Fab")
		)
		(fp_line
			(start -2.286 -0.254)
			(end -2.286 7.366)
			(stroke
				(width 0.1)
				(type default)
			)
			(layer "B.Fab")
		)
		(fp_line
			(start 2.286 -0.254)
			(end -2.286 -0.254)
			(stroke
				(width 0.1)
				(type default)
			)
			(layer "B.Fab")
		)
		(pad "1" smd rect
			(at 0 0 90)
			(size 2.54 3.048)
			(layers "B.Cu" "B.Mask" "B.Paste")
			(net "PVCCIN_CPU1")
		)
		(pad "2" smd rect
			(at 0 7.112 90)
			(size 2.54 3.048)
			(layers "B.Cu" "B.Mask" "B.Paste")
			(net "GND")
		)
	)
	(footprint ""
		(layer "B.Cu")
		(at 390.635744 -22.543516 -90)
		(property "Reference" "C2T26"
			(at 0 0 90)
			(layer "B.SilkS")
			(hide yes)
			(effects
				(font
					(size 1.27 1.27)
				)
				(justify mirror)
			)
		)
		(property "Value" ""
			(at 0 0 90)
			(layer "B.Fab")
			(effects
				(font
					(size 1.27 1.27)
				)
				(justify mirror)
			)
		)
		(duplicate_pad_numbers_are_jumpers no)
		(fp_poly
			(pts
				(xy -0.3048 -0.1016) (xy -0.3048 0.9906) (xy 0.3048 0.9906) (xy 0.3048 -0.1016)
			)
			(stroke
				(width 0)
				(type default)
			)
			(fill no)
			(layer "B.CrtYd")
		)
		(fp_line
			(start -0.3048 0.9906)
			(end -0.3048 -0.1016)
			(stroke
				(width 0.1)
				(type default)
			)
			(layer "B.Fab")
		)
		(fp_line
			(start 0.3048 0.9906)
			(end -0.3048 0.9906)
			(stroke
				(width 0.1)
				(type default)
			)
			(layer "B.Fab")
		)
		(fp_line
			(start -0.3048 -0.1016)
			(end 0.3048 -0.1016)
			(stroke
				(width 0.1)
				(type default)
			)
			(layer "B.Fab")
		)
		(fp_line
			(start 0.3048 -0.1016)
			(end 0.3048 0.9906)
			(stroke
				(width 0.1)
				(type default)
			)
			(layer "B.Fab")
		)
		(pad "1" smd rect
			(at 0 0 90)
			(size 0.508 0.508)
			(layers "B.Cu" "B.Mask" "B.Paste")
			(net "P3V3")
		)
		(pad "2" smd rect
			(at 0 0.889 90)
			(size 0.508 0.508)
			(layers "B.Cu" "B.Mask" "B.Paste")
			(net "GND")
		)
		(zone
			(layer "B.Cu")
			(hatch none 0.5)
			(connect_pads
				(clearance 0)
			)
			(min_thickness 0.25)
			(keepout
				(tracks not_allowed)
				(vias allowed)
				(pads allowed)
				(copperpour not_allowed)
				(footprints allowed)
			)
			(placement
				(enabled no)
				(sheetname "")
			)
			(fill
				(thermal_gap 0.5)
				(thermal_bridge_width 0.5)
				(island_removal_mode 0)
			)
			(polygon
				(pts
					(xy 390.000744 -22.289516) (xy 390.000744 -22.797516) (xy 390.381744 -22.797516) (xy 390.381744 -22.289516)
				)
			)
		)
		(zone
			(layer "B.Cu")
			(hatch none 0.5)
			(connect_pads
				(clearance 0)
			)
			(min_thickness 0.25)
			(keepout
				(tracks allowed)
				(vias not_allowed)
				(pads allowed)
				(copperpour not_allowed)
				(footprints allowed)
			)
			(placement
				(enabled no)
				(sheetname "")
			)
			(fill
				(thermal_gap 0.5)
				(thermal_bridge_width 0.5)
				(island_removal_mode 0)
			)
			(polygon
				(pts
					(xy 390.381744 -22.289516) (xy 390.381744 -22.797516) (xy 390.000744 -22.797516) (xy 390.000744 -22.289516)
				)
			)
		)
	)
	(footprint ""
		(layer "B.Cu")
		(at 352.8949 -72.8218 -90)
		(property "Reference" "R7D40"
			(at 0 0 90)
			(layer "B.SilkS")
			(hide yes)
			(effects
				(font
					(size 1.27 1.27)
				)
				(justify mirror)
			)
		)
		(property "Value" ""
			(at 0 0 90)
			(layer "B.Fab")
			(effects
				(font
					(size 1.27 1.27)
				)
				(justify mirror)
			)
		)
		(duplicate_pad_numbers_are_jumpers no)
		(fp_poly
			(pts
				(xy 0.2794 -0.1016) (xy -0.2794 -0.1016) (xy -0.2794 0.9906) (xy 0.2794 0.9906)
			)
			(stroke
				(width 0)
				(type default)
			)
			(fill no)
			(layer "B.CrtYd")
		)
		(fp_line
			(start -0.2794 0.9906)
			(end -0.2794 -0.1016)
			(stroke
				(width 0.1)
				(type default)
			)
			(layer "B.Fab")
		)
		(fp_line
			(start 0.2794 0.9906)
			(end -0.2794 0.9906)
			(stroke
				(width 0.1)
				(type default)
			)
			(layer "B.Fab")
		)
		(fp_line
			(start -0.2794 -0.1016)
			(end 0.2794 -0.1016)
			(stroke
				(width 0.1)
				(type default)
			)
			(layer "B.Fab")
		)
		(fp_line
			(start 0.2794 -0.1016)
			(end 0.2794 0.9906)
			(stroke
				(width 0.1)
				(type default)
			)
			(layer "B.Fab")
		)
		(pad "1" smd rect
			(at 0 0 90)
			(size 0.508 0.508)
			(layers "B.Cu" "B.Mask" "B.Paste")
			(net "FM_CPU0_VRM_OSC_EN")
		)
		(pad "2" smd rect
			(at 0 0.889 90)
			(size 0.508 0.508)
			(layers "B.Cu" "B.Mask" "B.Paste")
			(net "FM_CPU0_STL_BRD_OSC_EN")
		)
		(zone
			(layer "B.Cu")
			(hatch none 0.5)
			(connect_pads
				(clearance 0)
			)
			(min_thickness 0.25)
			(keepout
				(tracks not_allowed)
				(vias allowed)
				(pads allowed)
				(copperpour not_allowed)
				(footprints allowed)
			)
			(placement
				(enabled no)
				(sheetname "")
			)
			(fill
				(thermal_gap 0.5)
				(thermal_bridge_width 0.5)
				(island_removal_mode 0)
			)
			(polygon
				(pts
					(xy 352.2599 -72.5678) (xy 352.2599 -73.0758) (xy 352.6409 -73.0758) (xy 352.6409 -72.5678)
				)
			)
		)
		(zone
			(layer "B.Cu")
			(hatch none 0.5)
			(connect_pads
				(clearance 0)
			)
			(min_thickness 0.25)
			(keepout
				(tracks allowed)
				(vias not_allowed)
				(pads allowed)
				(copperpour not_allowed)
				(footprints allowed)
			)
			(placement
				(enabled no)
				(sheetname "")
			)
			(fill
				(thermal_gap 0.5)
				(thermal_bridge_width 0.5)
				(island_removal_mode 0)
			)
			(polygon
				(pts
					(xy 352.6409 -72.5678) (xy 352.6409 -73.0758) (xy 352.2599 -73.0758) (xy 352.2599 -72.5678)
				)
			)
		)
	)
	(footprint ""
		(layer "B.Cu")
		(at 497.743226 -34.715704 90)
		(property "Reference" "R9F66"
			(at 0 0 90)
			(layer "B.SilkS")
			(hide yes)
			(effects
				(font
					(size 1.27 1.27)
				)
				(justify mirror)
			)
		)
		(property "Value" ""
			(at 0 0 90)
			(layer "B.Fab")
			(effects
				(font
					(size 1.27 1.27)
				)
				(justify mirror)
			)
		)
		(duplicate_pad_numbers_are_jumpers no)
		(fp_poly
			(pts
				(xy 0.2794 -0.1016) (xy -0.2794 -0.1016) (xy -0.2794 0.9906) (xy 0.2794 0.9906)
			)
			(stroke
				(width 0)
				(type default)
			)
			(fill no)
			(layer "B.CrtYd")
		)
		(fp_line
			(start 0.2794 -0.1016)
			(end 0.2794 0.9906)
			(stroke
				(width 0.1)
				(type default)
			)
			(layer "B.Fab")
		)
		(fp_line
			(start -0.2794 -0.1016)
			(end 0.2794 -0.1016)
			(stroke
				(width 0.1)
				(type default)
			)
			(layer "B.Fab")
		)
		(fp_line
			(start 0.2794 0.9906)
			(end -0.2794 0.9906)
			(stroke
				(width 0.1)
				(type default)
			)
			(layer "B.Fab")
		)
		(fp_line
			(start -0.2794 0.9906)
			(end -0.2794 -0.1016)
			(stroke
				(width 0.1)
				(type default)
			)
			(layer "B.Fab")
		)
		(pad "1" smd rect
			(at 0 0 270)
			(size 0.508 0.508)
			(layers "B.Cu" "B.Mask" "B.Paste")
			(net "SP2_BMC_CM_UART_TX")
		)
		(pad "2" smd rect
			(at 0 0.889 270)
			(size 0.508 0.508)
			(layers "B.Cu" "B.Mask" "B.Paste")
			(net "SP2_BMC_CM_UART_TX_R")
		)
		(zone
			(layer "B.Cu")
			(hatch none 0.5)
			(connect_pads
				(clearance 0)
			)
			(min_thickness 0.25)
			(keepout
				(tracks allowed)
				(vias not_allowed)
				(pads allowed)
				(copperpour not_allowed)
				(footprints allowed)
			)
			(placement
				(enabled no)
				(sheetname "")
			)
			(fill
				(thermal_gap 0.5)
				(thermal_bridge_width 0.5)
				(island_removal_mode 0)
			)
			(polygon
				(pts
					(xy 497.997226 -34.969704) (xy 497.997226 -34.461704) (xy 498.378226 -34.461704) (xy 498.378226 -34.969704)
				)
			)
		)
		(zone
			(layer "B.Cu")
			(hatch none 0.5)
			(connect_pads
				(clearance 0)
			)
			(min_thickness 0.25)
			(keepout
				(tracks not_allowed)
				(vias allowed)
				(pads allowed)
				(copperpour not_allowed)
				(footprints allowed)
			)
			(placement
				(enabled no)
				(sheetname "")
			)
			(fill
				(thermal_gap 0.5)
				(thermal_bridge_width 0.5)
				(island_removal_mode 0)
			)
			(polygon
				(pts
					(xy 498.378226 -34.969704) (xy 498.378226 -34.461704) (xy 497.997226 -34.461704) (xy 497.997226 -34.969704)
				)
			)
		)
	)
	(footprint ""
		(layer "B.Cu")
		(at 316.3443 -164.9095 -90)
		(property "Reference" "T1D17"
			(at 0 0 90)
			(layer "B.SilkS")
			(hide yes)
			(effects
				(font
					(size 1.27 1.27)
				)
				(justify mirror)
			)
		)
		(property "Value" "*"
			(at 3.4036 -4.46405 270)
			(unlocked yes)
			(layer "B.Fab")
			(hide yes)
			(effects
				(font
					(size 0.889 0.889)
					(thickness 0.1524)
				)
				(justify mirror)
			)
		)
		(property "Device Type" "TEST-PAD-12P-1-GP-U_DISCRET-GBA"
			(at 3.4036 -5.98805 270)
			(unlocked yes)
			(layer "B.Fab")
			(hide yes)
			(effects
				(font
					(size 0.889 0.889)
					(thickness 0.1524)
				)
				(justify mirror)
			)
		)
		(duplicate_pad_numbers_are_jumpers no)
		(fp_line
			(start -2.3622 3.4798)
			(end 2.3876 3.4798)
			(stroke
				(width 0.1524)
				(type default)
			)
			(layer "B.SilkS")
		)
		(fp_line
			(start 2.3876 3.4798)
			(end 2.3876 -4.826)
			(stroke
				(width 0.1524)
				(type default)
			)
			(layer "B.SilkS")
		)
		(fp_line
			(start -2.3622 -4.826)
			(end -2.3622 3.4798)
			(stroke
				(width 0.1524)
				(type default)
			)
			(layer "B.SilkS")
		)
		(fp_line
			(start 2.3876 -4.826)
			(end -2.3622 -4.826)
			(stroke
				(width 0.1524)
				(type default)
			)
			(layer "B.SilkS")
		)
		(fp_rect
			(start 2.6416 3.7338)
			(end -2.6162 -5.08)
			(stroke
				(width 0)
				(type default)
			)
			(fill no)
			(layer "B.CrtYd")
		)
		(fp_rect
			(start 2.6416 3.7338)
			(end -2.6162 -5.08)
			(stroke
				(width 0)
				(type default)
			)
			(fill no)
			(layer "B.Fab")
		)
		(pad "1" smd circle
			(at -0.496824 -1.301496 90)
			(size 0.6604 0.6604)
			(layers "B.Cu" "B.Mask" "B.Paste")
			(net "L5_85OHM_10INCH_DP")
		)
		(pad "2" smd circle
			(at 0.503936 -1.301496 90)
			(size 0.6604 0.6604)
			(layers "B.Cu" "B.Mask" "B.Paste")
			(net "L5_85OHM_10INCH_DN")
		)
		(pad "3" smd custom
			(at 0.00889 0.370078 90)
			(size 0.74295 0.74295)
			(layers "B.Cu" "B.Mask" "B.Paste")
			(net "GND")
			(options
				(clearance outline)
				(anchor circle)
			)
			(primitives
				(gr_poly
					(pts
						(xy -2.1209 -1.4859) (xy 2.1209 -1.4859) (xy 2.1209 1.4859) (xy 1.08585 1.4859) (xy 1.08585 0.4699)
						(xy -1.08585 0.4699) (xy -1.08585 1.4859) (xy -2.1209 1.4859)
					)
					(width 0)
					(fill yes)
				)
			)
		)
		(pad "4" thru_hole circle
			(at -1.266444 -3.851656 90)
			(size 1.4478 1.4478)
			(drill 1.0414)
			(layers "*.Cu" "*.Mask")
			(remove_unused_layers no)
			(net "GND")
			(clearance 0.1524)
			(thermal_gap 0.1524)
		)
		(pad "5" thru_hole circle
			(at 1.273556 -3.851656 90)
			(size 1.4478 1.4478)
			(drill 1.0414)
			(layers "*.Cu" "*.Mask")
			(remove_unused_layers no)
			(net "GND")
			(clearance 0.1524)
			(thermal_gap 0.1524)
		)
		(pad "6" thru_hole circle
			(at -1.266444 2.498344 90)
			(size 1.4478 1.4478)
			(drill 1.0414)
			(layers "*.Cu" "*.Mask")
			(remove_unused_layers no)
			(net "GND")
			(clearance 0.1524)
			(thermal_gap 0.1524)
		)
		(pad "7" thru_hole circle
			(at 1.273556 2.498344 90)
			(size 1.4478 1.4478)
			(drill 1.0414)
			(layers "*.Cu" "*.Mask")
			(remove_unused_layers no)
			(net "GND")
			(clearance 0.1524)
			(thermal_gap 0.1524)
		)
		(pad "8" thru_hole circle
			(at -1.27 -0.4572 90)
			(size 0.7112 0.7112)
			(drill 0.4064)
			(layers "*.Cu" "*.Mask")
			(remove_unused_layers no)
			(net "GND")
			(clearance 0.1016)
			(thermal_gap 0.1016)
		)
		(pad "9" thru_hole circle
			(at -1.27 0.762 90)
			(size 0.7112 0.7112)
			(drill 0.4064)
			(layers "*.Cu" "*.Mask")
			(remove_unused_layers no)
			(net "GND")
			(clearance 0.1016)
			(thermal_gap 0.1016)
		)
		(pad "10" thru_hole circle
			(at 0.0254 0.762 90)
			(size 0.7112 0.7112)
			(drill 0.4064)
			(layers "*.Cu" "*.Mask")
			(remove_unused_layers no)
			(net "GND")
			(clearance 0.1016)
			(thermal_gap 0.1016)
		)
		(pad "11" thru_hole circle
			(at 1.27 0.762 90)
			(size 0.7112 0.7112)
			(drill 0.4064)
			(layers "*.Cu" "*.Mask")
			(remove_unused_layers no)
			(net "GND")
			(clearance 0.1016)
			(thermal_gap 0.1016)
		)
		(pad "12" thru_hole circle
			(at 1.27 -0.4572 90)
			(size 0.7112 0.7112)
			(drill 0.4064)
			(layers "*.Cu" "*.Mask")
			(remove_unused_layers no)
			(net "GND")
			(clearance 0.1016)
			(thermal_gap 0.1016)
		)
	)
	(footprint ""
		(layer "B.Cu")
		(at 370.1669 -104.8766 90)
		(property "Reference" "C3N27"
			(at 0 0 90)
			(layer "B.SilkS")
			(hide yes)
			(effects
				(font
					(size 1.27 1.27)
				)
				(justify mirror)
			)
		)
		(property "Value" ""
			(at 0 0 90)
			(layer "B.Fab")
			(effects
				(font
					(size 1.27 1.27)
				)
				(justify mirror)
			)
		)
		(duplicate_pad_numbers_are_jumpers no)
		(fp_poly
			(pts
				(xy 0.4953 -0.2032) (xy -0.4953 -0.2032) (xy -0.4953 1.6002) (xy 0.4953 1.6002)
			)
			(stroke
				(width 0)
				(type default)
			)
			(fill no)
			(layer "B.CrtYd")
		)
		(fp_line
			(start 0.4953 -0.2032)
			(end -0.4953 -0.2032)
			(stroke
				(width 0.1)
				(type default)
			)
			(layer "B.Fab")
		)
		(fp_line
			(start -0.4953 -0.2032)
			(end -0.4953 1.6002)
			(stroke
				(width 0.1)
				(type default)
			)
			(layer "B.Fab")
		)
		(fp_line
			(start 0.4953 1.6002)
			(end 0.4953 -0.2032)
			(stroke
				(width 0.1)
				(type default)
			)
			(layer "B.Fab")
		)
		(fp_line
			(start -0.4953 1.6002)
			(end 0.4953 1.6002)
			(stroke
				(width 0.1)
				(type default)
			)
			(layer "B.Fab")
		)
		(pad "1" smd rect
			(at 0 0 270)
			(size 0.762 0.889)
			(layers "B.Cu" "B.Mask" "B.Paste")
			(net "PVNN_PCH_STBY")
		)
		(pad "2" smd rect
			(at 0 1.397 270)
			(size 0.762 0.889)
			(layers "B.Cu" "B.Mask" "B.Paste")
			(net "GND")
		)
		(zone
			(layer "B.Cu")
			(hatch none 0.5)
			(connect_pads
				(clearance 0)
			)
			(min_thickness 0.25)
			(keepout
				(tracks not_allowed)
				(vias allowed)
				(pads allowed)
				(copperpour not_allowed)
				(footprints allowed)
			)
			(placement
				(enabled no)
				(sheetname "")
			)
			(fill
				(thermal_gap 0.5)
				(thermal_bridge_width 0.5)
				(island_removal_mode 0)
			)
			(polygon
				(pts
					(xy 370.6114 -105.2576) (xy 370.6114 -104.4956) (xy 371.1194 -104.4956) (xy 371.1194 -105.2576)
				)
			)
		)
	)
	(footprint ""
		(layer "B.Cu")
		(at 446.9892 -17.3482 90)
		(property "Reference" "R3W7"
			(at 0.8382 -0.67818 90)
			(unlocked yes)
			(layer "B.SilkS")
			(effects
				(font
					(size 0.4064 0.254)
					(thickness 0.1524)
				)
				(justify left mirror)
			)
		)
		(property "Value" ""
			(at 0 0 90)
			(layer "B.Fab")
			(effects
				(font
					(size 1.27 1.27)
				)
				(justify mirror)
			)
		)
		(duplicate_pad_numbers_are_jumpers no)
		(fp_poly
			(pts
				(xy 0.2794 -0.1016) (xy -0.2794 -0.1016) (xy -0.2794 0.9906) (xy 0.2794 0.9906)
			)
			(stroke
				(width 0)
				(type default)
			)
			(fill no)
			(layer "B.CrtYd")
		)
		(fp_line
			(start 0.2794 -0.1016)
			(end 0.2794 0.9906)
			(stroke
				(width 0.1)
				(type default)
			)
			(layer "B.Fab")
		)
		(fp_line
			(start -0.2794 -0.1016)
			(end 0.2794 -0.1016)
			(stroke
				(width 0.1)
				(type default)
			)
			(layer "B.Fab")
		)
		(fp_line
			(start 0.2794 0.9906)
			(end -0.2794 0.9906)
			(stroke
				(width 0.1)
				(type default)
			)
			(layer "B.Fab")
		)
		(fp_line
			(start -0.2794 0.9906)
			(end -0.2794 -0.1016)
			(stroke
				(width 0.1)
				(type default)
			)
			(layer "B.Fab")
		)
		(pad "1" smd rect
			(at 0 0 270)
			(size 0.508 0.508)
			(layers "B.Cu" "B.Mask" "B.Paste")
			(net "P3V3_STBY")
		)
		(pad "2" smd rect
			(at 0 0.889 270)
			(size 0.508 0.508)
			(layers "B.Cu" "B.Mask" "B.Paste")
			(net "VREF_2V2")
		)
		(zone
			(layer "B.Cu")
			(hatch none 0.5)
			(connect_pads
				(clearance 0)
			)
			(min_thickness 0.25)
			(keepout
				(tracks allowed)
				(vias not_allowed)
				(pads allowed)
				(copperpour not_allowed)
				(footprints allowed)
			)
			(placement
				(enabled no)
				(sheetname "")
			)
			(fill
				(thermal_gap 0.5)
				(thermal_bridge_width 0.5)
				(island_removal_mode 0)
			)
			(polygon
				(pts
					(xy 447.2432 -17.6022) (xy 447.2432 -17.0942) (xy 447.6242 -17.0942) (xy 447.6242 -17.6022)
				)
			)
		)
		(zone
			(layer "B.Cu")
			(hatch none 0.5)
			(connect_pads
				(clearance 0)
			)
			(min_thickness 0.25)
			(keepout
				(tracks not_allowed)
				(vias allowed)
				(pads allowed)
				(copperpour not_allowed)
				(footprints allowed)
			)
			(placement
				(enabled no)
				(sheetname "")
			)
			(fill
				(thermal_gap 0.5)
				(thermal_bridge_width 0.5)
				(island_removal_mode 0)
			)
			(polygon
				(pts
					(xy 447.6242 -17.6022) (xy 447.6242 -17.0942) (xy 447.2432 -17.0942) (xy 447.2432 -17.6022)
				)
			)
		)
	)
	(footprint ""
		(layer "B.Cu")
		(at 411.324552 -29.55036 90)
		(property "Reference" "C25W68"
			(at 0.8382 -0.67818 90)
			(unlocked yes)
			(layer "B.SilkS")
			(effects
				(font
					(size 0.4064 0.254)
					(thickness 0.1524)
				)
				(justify left mirror)
			)
		)
		(property "Value" ""
			(at 0 0 90)
			(layer "B.Fab")
			(effects
				(font
					(size 1.27 1.27)
				)
				(justify mirror)
			)
		)
		(duplicate_pad_numbers_are_jumpers no)
		(fp_poly
			(pts
				(xy -0.3048 -0.1016) (xy -0.3048 0.9906) (xy 0.3048 0.9906) (xy 0.3048 -0.1016)
			)
			(stroke
				(width 0)
				(type default)
			)
			(fill no)
			(layer "B.CrtYd")
		)
		(fp_line
			(start 0.3048 -0.1016)
			(end 0.3048 0.9906)
			(stroke
				(width 0.1)
				(type default)
			)
			(layer "B.Fab")
		)
		(fp_line
			(start -0.3048 -0.1016)
			(end 0.3048 -0.1016)
			(stroke
				(width 0.1)
				(type default)
			)
			(layer "B.Fab")
		)
		(fp_line
			(start 0.3048 0.9906)
			(end -0.3048 0.9906)
			(stroke
				(width 0.1)
				(type default)
			)
			(layer "B.Fab")
		)
		(fp_line
			(start -0.3048 0.9906)
			(end -0.3048 -0.1016)
			(stroke
				(width 0.1)
				(type default)
			)
			(layer "B.Fab")
		)
		(pad "1" smd rect
			(at 0 0 270)
			(size 0.508 0.508)
			(layers "B.Cu" "B.Mask" "B.Paste")
			(net "VCC_VA_3V3")
		)
		(pad "2" smd rect
			(at 0 0.889 270)
			(size 0.508 0.508)
			(layers "B.Cu" "B.Mask" "B.Paste")
			(net "GND")
		)
		(zone
			(layer "B.Cu")
			(hatch none 0.5)
			(connect_pads
				(clearance 0)
			)
			(min_thickness 0.25)
			(keepout
				(tracks allowed)
				(vias not_allowed)
				(pads allowed)
				(copperpour not_allowed)
				(footprints allowed)
			)
			(placement
				(enabled no)
				(sheetname "")
			)
			(fill
				(thermal_gap 0.5)
				(thermal_bridge_width 0.5)
				(island_removal_mode 0)
			)
			(polygon
				(pts
					(xy 411.578552 -29.80436) (xy 411.578552 -29.29636) (xy 411.959552 -29.29636) (xy 411.959552 -29.80436)
				)
			)
		)
		(zone
			(layer "B.Cu")
			(hatch none 0.5)
			(connect_pads
				(clearance 0)
			)
			(min_thickness 0.25)
			(keepout
				(tracks not_allowed)
				(vias allowed)
				(pads allowed)
				(copperpour not_allowed)
				(footprints allowed)
			)
			(placement
				(enabled no)
				(sheetname "")
			)
			(fill
				(thermal_gap 0.5)
				(thermal_bridge_width 0.5)
				(island_removal_mode 0)
			)
			(polygon
				(pts
					(xy 411.959552 -29.80436) (xy 411.959552 -29.29636) (xy 411.578552 -29.29636) (xy 411.578552 -29.80436)
				)
			)
		)
	)
	(footprint ""
		(layer "B.Cu")
		(at 390.93775 -113.45545)
		(property "Reference" "C2M21"
			(at 0 0 0)
			(layer "B.SilkS")
			(hide yes)
			(effects
				(font
					(size 1.27 1.27)
				)
				(justify mirror)
			)
		)
		(property "Value" ""
			(at 0 0 0)
			(layer "B.Fab")
			(effects
				(font
					(size 1.27 1.27)
				)
				(justify mirror)
			)
		)
		(duplicate_pad_numbers_are_jumpers no)
		(fp_rect
			(start 0.2794 0.9144)
			(end -0.2794 -0.1143)
			(stroke
				(width 0)
				(type default)
			)
			(fill no)
			(layer "B.CrtYd")
		)
		(fp_line
			(start -0.2794 -0.1143)
			(end -0.2794 0.9144)
			(stroke
				(width 0.1)
				(type default)
			)
			(layer "B.Fab")
		)
		(fp_line
			(start -0.2794 0.9144)
			(end 0.2794 0.9144)
			(stroke
				(width 0.1)
				(type default)
			)
			(layer "B.Fab")
		)
		(fp_line
			(start 0.2794 -0.1143)
			(end -0.2794 -0.1143)
			(stroke
				(width 0.1)
				(type default)
			)
			(layer "B.Fab")
		)
		(fp_line
			(start 0.2794 0.9144)
			(end 0.2794 -0.1143)
			(stroke
				(width 0.1)
				(type default)
			)
			(layer "B.Fab")
		)
		(pad "1" smd custom
			(at 0 0 270)
			(size 0.10414 0.10414)
			(layers "B.Cu" "B.Mask" "B.Paste")
			(net "P1V05_PCH_STBY")
			(options
				(clearance outline)
				(anchor circle)
			)
			(primitives
				(gr_poly
					(pts
						(xy -0.20828 -0.08636) (xy -0.20828 0.08636) (xy -0.08636 0.20828) (xy 0.086614 0.20828) (xy 0.20828 0.086614)
						(xy 0.20828 -0.08636) (xy 0.08636 -0.20828) (xy -0.08636 -0.20828)
					)
					(width 0)
					(fill yes)
				)
			)
		)
		(pad "2" smd custom
			(at 0 0.8001 270)
			(size 0.10414 0.10414)
			(layers "B.Cu" "B.Mask" "B.Paste")
			(net "GND")
			(options
				(clearance outline)
				(anchor circle)
			)
			(primitives
				(gr_poly
					(pts
						(xy -0.20828 -0.08636) (xy -0.20828 0.08636) (xy -0.08636 0.20828) (xy 0.086614 0.20828) (xy 0.20828 0.086614)
						(xy 0.20828 -0.08636) (xy 0.08636 -0.20828) (xy -0.08636 -0.20828)
					)
					(width 0)
					(fill yes)
				)
			)
		)
		(zone
			(layer "B.Cu")
			(hatch none 0.5)
			(connect_pads
				(clearance 0)
			)
			(min_thickness 0.25)
			(keepout
				(tracks not_allowed)
				(vias allowed)
				(pads allowed)
				(copperpour not_allowed)
				(footprints allowed)
			)
			(placement
				(enabled no)
				(sheetname "")
			)
			(fill
				(thermal_gap 0.5)
				(thermal_bridge_width 0.5)
				(island_removal_mode 0)
			)
			(polygon
				(pts
					(xy 391.02538 -113.2459) (xy 391.02538 -112.8649) (xy 390.85012 -112.8649) (xy 390.849866 -113.2459)
				)
			)
		)
		(zone
			(layer "B.Cu")
			(hatch none 0.5)
			(connect_pads
				(clearance 0)
			)
			(min_thickness 0.25)
			(keepout
				(tracks allowed)
				(vias not_allowed)
				(pads allowed)
				(copperpour not_allowed)
				(footprints allowed)
			)
			(placement
				(enabled no)
				(sheetname "")
			)
			(fill
				(thermal_gap 0.5)
				(thermal_bridge_width 0.5)
				(island_removal_mode 0)
			)
			(polygon
				(pts
					(xy 391.02538 -113.2459) (xy 391.02538 -112.8649) (xy 390.85012 -112.8649) (xy 390.849866 -113.2459)
				)
			)
		)
	)
	(footprint ""
		(layer "B.Cu")
		(at 402.043646 -24.838152)
		(property "Reference" "R1U44"
			(at 0 0 0)
			(layer "B.SilkS")
			(hide yes)
			(effects
				(font
					(size 1.27 1.27)
				)
				(justify mirror)
			)
		)
		(property "Value" "*"
			(at -0.064008 -4.108196 0)
			(unlocked yes)
			(layer "B.Fab")
			(hide yes)
			(effects
				(font
					(size 1.27 1.016)
					(thickness 0.1524)
				)
				(justify mirror)
			)
		)
		(property "Device Type" "1K82R2F-1-GP_SMD-RG-1K82R2F-1-A"
			(at -0.064008 -5.632196 0)
			(unlocked yes)
			(layer "B.Fab")
			(hide yes)
			(effects
				(font
					(size 1.27 1.016)
					(thickness 0.1524)
				)
				(justify mirror)
			)
		)
		(duplicate_pad_numbers_are_jumpers no)
		(fp_line
			(start -0.508 -0.9398)
			(end 0.508 -0.9398)
			(stroke
				(width 0.1524)
				(type default)
			)
			(layer "B.SilkS")
		)
		(fp_line
			(start 0.508 -0.9398)
			(end 0.508 0.9398)
			(stroke
				(width 0.1524)
				(type default)
			)
			(layer "B.SilkS")
		)
		(fp_rect
			(start 0.508 0.9398)
			(end -0.508 -0.9398)
			(stroke
				(width 0)
				(type default)
			)
			(fill no)
			(layer "B.CrtYd")
		)
		(fp_rect
			(start 0.508 0.9398)
			(end -0.508 -0.9398)
			(stroke
				(width 0)
				(type default)
			)
			(fill no)
			(layer "B.Fab")
		)
		(pad "1" smd custom
			(at 0 -0.4445 180)
			(size 0.1397 0.1397)
			(layers "B.Cu" "B.Mask" "B.Paste")
			(net "A_P5V_STBY_SCALED")
			(options
				(clearance outline)
				(anchor circle)
			)
			(primitives
				(gr_poly
					(pts
						(arc
							(start -0.1778 0.2794)
							(mid -0.249642 0.249642)
							(end -0.2794 0.1778)
						)
						(arc
							(start -0.2794 -0.1778)
							(mid -0.249642 -0.249642)
							(end -0.1778 -0.2794)
						)
						(arc
							(start 0.1778 -0.2794)
							(mid 0.249642 -0.249642)
							(end 0.2794 -0.1778)
						)
						(arc
							(start 0.2794 0.1778)
							(mid 0.249642 0.249642)
							(end 0.1778 0.2794)
						)
					)
					(width 0)
					(fill yes)
				)
			)
		)
		(pad "2" smd custom
			(at 0 0.4445 180)
			(size 0.1397 0.1397)
			(layers "B.Cu" "B.Mask" "B.Paste")
			(net "GND")
			(options
				(clearance outline)
				(anchor circle)
			)
			(primitives
				(gr_poly
					(pts
						(arc
							(start -0.1778 0.2794)
							(mid -0.249642 0.249642)
							(end -0.2794 0.1778)
						)
						(arc
							(start -0.2794 -0.1778)
							(mid -0.249642 -0.249642)
							(end -0.1778 -0.2794)
						)
						(arc
							(start 0.1778 -0.2794)
							(mid 0.249642 -0.249642)
							(end 0.2794 -0.1778)
						)
						(arc
							(start 0.2794 0.1778)
							(mid 0.249642 0.249642)
							(end 0.1778 0.2794)
						)
					)
					(width 0)
					(fill yes)
				)
			)
		)
	)
	(footprint ""
		(layer "B.Cu")
		(at 448.19189 -28.8036 -90)
		(property "Reference" "C25W10"
			(at 0.8382 -0.67818 270)
			(unlocked yes)
			(layer "B.SilkS")
			(effects
				(font
					(size 0.4064 0.254)
					(thickness 0.1524)
				)
				(justify left mirror)
			)
		)
		(property "Value" ""
			(at 0 0 90)
			(layer "B.Fab")
			(effects
				(font
					(size 1.27 1.27)
				)
				(justify mirror)
			)
		)
		(duplicate_pad_numbers_are_jumpers no)
		(fp_poly
			(pts
				(xy -0.3048 -0.1016) (xy -0.3048 0.9906) (xy 0.3048 0.9906) (xy 0.3048 -0.1016)
			)
			(stroke
				(width 0)
				(type default)
			)
			(fill no)
			(layer "B.CrtYd")
		)
		(fp_line
			(start -0.3048 0.9906)
			(end -0.3048 -0.1016)
			(stroke
				(width 0.1)
				(type default)
			)
			(layer "B.Fab")
		)
		(fp_line
			(start 0.3048 0.9906)
			(end -0.3048 0.9906)
			(stroke
				(width 0.1)
				(type default)
			)
			(layer "B.Fab")
		)
		(fp_line
			(start -0.3048 -0.1016)
			(end 0.3048 -0.1016)
			(stroke
				(width 0.1)
				(type default)
			)
			(layer "B.Fab")
		)
		(fp_line
			(start 0.3048 -0.1016)
			(end 0.3048 0.9906)
			(stroke
				(width 0.1)
				(type default)
			)
			(layer "B.Fab")
		)
		(pad "1" smd rect
			(at 0 0 90)
			(size 0.508 0.508)
			(layers "B.Cu" "B.Mask" "B.Paste")
			(net "P1V2_AUX_BMC")
		)
		(pad "2" smd rect
			(at 0 0.889 90)
			(size 0.508 0.508)
			(layers "B.Cu" "B.Mask" "B.Paste")
			(net "BMC_M_VREFCA")
		)
		(zone
			(layer "B.Cu")
			(hatch none 0.5)
			(connect_pads
				(clearance 0)
			)
			(min_thickness 0.25)
			(keepout
				(tracks not_allowed)
				(vias allowed)
				(pads allowed)
				(copperpour not_allowed)
				(footprints allowed)
			)
			(placement
				(enabled no)
				(sheetname "")
			)
			(fill
				(thermal_gap 0.5)
				(thermal_bridge_width 0.5)
				(island_removal_mode 0)
			)
			(polygon
				(pts
					(xy 447.55689 -28.5496) (xy 447.55689 -29.0576) (xy 447.93789 -29.0576) (xy 447.93789 -28.5496)
				)
			)
		)
		(zone
			(layer "B.Cu")
			(hatch none 0.5)
			(connect_pads
				(clearance 0)
			)
			(min_thickness 0.25)
			(keepout
				(tracks allowed)
				(vias not_allowed)
				(pads allowed)
				(copperpour not_allowed)
				(footprints allowed)
			)
			(placement
				(enabled no)
				(sheetname "")
			)
			(fill
				(thermal_gap 0.5)
				(thermal_bridge_width 0.5)
				(island_removal_mode 0)
			)
			(polygon
				(pts
					(xy 447.93789 -28.5496) (xy 447.93789 -29.0576) (xy 447.55689 -29.0576) (xy 447.55689 -28.5496)
				)
			)
		)
	)
	(footprint ""
		(layer "B.Cu")
		(at 408.1907 -14.7828 -90)
		(property "Reference" "R2R10"
			(at 0 0 90)
			(layer "B.SilkS")
			(hide yes)
			(effects
				(font
					(size 1.27 1.27)
				)
				(justify mirror)
			)
		)
		(property "Value" ""
			(at 0 0 90)
			(layer "B.Fab")
			(effects
				(font
					(size 1.27 1.27)
				)
				(justify mirror)
			)
		)
		(duplicate_pad_numbers_are_jumpers no)
		(fp_poly
			(pts
				(xy 0.2794 -0.1016) (xy -0.2794 -0.1016) (xy -0.2794 0.9906) (xy 0.2794 0.9906)
			)
			(stroke
				(width 0)
				(type default)
			)
			(fill no)
			(layer "B.CrtYd")
		)
		(fp_line
			(start -0.2794 0.9906)
			(end -0.2794 -0.1016)
			(stroke
				(width 0.1)
				(type default)
			)
			(layer "B.Fab")
		)
		(fp_line
			(start 0.2794 0.9906)
			(end -0.2794 0.9906)
			(stroke
				(width 0.1)
				(type default)
			)
			(layer "B.Fab")
		)
		(fp_line
			(start -0.2794 -0.1016)
			(end 0.2794 -0.1016)
			(stroke
				(width 0.1)
				(type default)
			)
			(layer "B.Fab")
		)
		(fp_line
			(start 0.2794 -0.1016)
			(end 0.2794 0.9906)
			(stroke
				(width 0.1)
				(type default)
			)
			(layer "B.Fab")
		)
		(pad "1" smd rect
			(at 0 0 90)
			(size 0.508 0.508)
			(layers "B.Cu" "B.Mask" "B.Paste")
			(net "FP_NMI_BTN_R_N")
		)
		(pad "2" smd rect
			(at 0 0.889 90)
			(size 0.508 0.508)
			(layers "B.Cu" "B.Mask" "B.Paste")
			(net "FP_NMI_BTN_N")
		)
		(zone
			(layer "B.Cu")
			(hatch none 0.5)
			(connect_pads
				(clearance 0)
			)
			(min_thickness 0.25)
			(keepout
				(tracks not_allowed)
				(vias allowed)
				(pads allowed)
				(copperpour not_allowed)
				(footprints allowed)
			)
			(placement
				(enabled no)
				(sheetname "")
			)
			(fill
				(thermal_gap 0.5)
				(thermal_bridge_width 0.5)
				(island_removal_mode 0)
			)
			(polygon
				(pts
					(xy 407.5557 -14.5288) (xy 407.5557 -15.0368) (xy 407.9367 -15.0368) (xy 407.9367 -14.5288)
				)
			)
		)
		(zone
			(layer "B.Cu")
			(hatch none 0.5)
			(connect_pads
				(clearance 0)
			)
			(min_thickness 0.25)
			(keepout
				(tracks allowed)
				(vias not_allowed)
				(pads allowed)
				(copperpour not_allowed)
				(footprints allowed)
			)
			(placement
				(enabled no)
				(sheetname "")
			)
			(fill
				(thermal_gap 0.5)
				(thermal_bridge_width 0.5)
				(island_removal_mode 0)
			)
			(polygon
				(pts
					(xy 407.9367 -14.5288) (xy 407.9367 -15.0368) (xy 407.5557 -15.0368) (xy 407.5557 -14.5288)
				)
			)
		)
	)
	(footprint ""
		(layer "B.Cu")
		(at 483.785164 -17.036542 90)
		(property "Reference" "R9G2"
			(at 0 0 90)
			(layer "B.SilkS")
			(hide yes)
			(effects
				(font
					(size 1.27 1.27)
				)
				(justify mirror)
			)
		)
		(property "Value" ""
			(at 0 0 90)
			(layer "B.Fab")
			(effects
				(font
					(size 1.27 1.27)
				)
				(justify mirror)
			)
		)
		(duplicate_pad_numbers_are_jumpers no)
		(fp_poly
			(pts
				(xy 0.2794 -0.1016) (xy -0.2794 -0.1016) (xy -0.2794 0.9906) (xy 0.2794 0.9906)
			)
			(stroke
				(width 0)
				(type default)
			)
			(fill no)
			(layer "B.CrtYd")
		)
		(fp_line
			(start 0.2794 -0.1016)
			(end 0.2794 0.9906)
			(stroke
				(width 0.1)
				(type default)
			)
			(layer "B.Fab")
		)
		(fp_line
			(start -0.2794 -0.1016)
			(end 0.2794 -0.1016)
			(stroke
				(width 0.1)
				(type default)
			)
			(layer "B.Fab")
		)
		(fp_line
			(start 0.2794 0.9906)
			(end -0.2794 0.9906)
			(stroke
				(width 0.1)
				(type default)
			)
			(layer "B.Fab")
		)
		(fp_line
			(start -0.2794 0.9906)
			(end -0.2794 -0.1016)
			(stroke
				(width 0.1)
				(type default)
			)
			(layer "B.Fab")
		)
		(pad "1" smd rect
			(at 0 0 270)
			(size 0.508 0.508)
			(layers "B.Cu" "B.Mask" "B.Paste")
			(net "LED_LAN_2_R_N")
		)
		(pad "2" smd rect
			(at 0 0.889 270)
			(size 0.508 0.508)
			(layers "B.Cu" "B.Mask" "B.Paste")
			(net "LED_LAN_2_N")
		)
		(zone
			(layer "B.Cu")
			(hatch none 0.5)
			(connect_pads
				(clearance 0)
			)
			(min_thickness 0.25)
			(keepout
				(tracks allowed)
				(vias not_allowed)
				(pads allowed)
				(copperpour not_allowed)
				(footprints allowed)
			)
			(placement
				(enabled no)
				(sheetname "")
			)
			(fill
				(thermal_gap 0.5)
				(thermal_bridge_width 0.5)
				(island_removal_mode 0)
			)
			(polygon
				(pts
					(xy 484.039164 -17.290542) (xy 484.039164 -16.782542) (xy 484.420164 -16.782542) (xy 484.420164 -17.290542)
				)
			)
		)
		(zone
			(layer "B.Cu")
			(hatch none 0.5)
			(connect_pads
				(clearance 0)
			)
			(min_thickness 0.25)
			(keepout
				(tracks not_allowed)
				(vias allowed)
				(pads allowed)
				(copperpour not_allowed)
				(footprints allowed)
			)
			(placement
				(enabled no)
				(sheetname "")
			)
			(fill
				(thermal_gap 0.5)
				(thermal_bridge_width 0.5)
				(island_removal_mode 0)
			)
			(polygon
				(pts
					(xy 484.420164 -17.290542) (xy 484.420164 -16.782542) (xy 484.039164 -16.782542) (xy 484.039164 -17.290542)
				)
			)
		)
	)
	(footprint ""
		(layer "B.Cu")
		(at 330.4794 -11.7094)
		(property "Reference" "R4U2"
			(at 0 0 0)
			(layer "B.SilkS")
			(hide yes)
			(effects
				(font
					(size 1.27 1.27)
				)
				(justify mirror)
			)
		)
		(property "Value" ""
			(at 0 0 0)
			(layer "B.Fab")
			(effects
				(font
					(size 1.27 1.27)
				)
				(justify mirror)
			)
		)
		(duplicate_pad_numbers_are_jumpers no)
		(fp_poly
			(pts
				(xy 0.2794 -0.1016) (xy -0.2794 -0.1016) (xy -0.2794 0.9906) (xy 0.2794 0.9906)
			)
			(stroke
				(width 0)
				(type default)
			)
			(fill no)
			(layer "B.CrtYd")
		)
		(fp_line
			(start -0.2794 -0.1016)
			(end 0.2794 -0.1016)
			(stroke
				(width 0.1)
				(type default)
			)
			(layer "B.Fab")
		)
		(fp_line
			(start -0.2794 0.9906)
			(end -0.2794 -0.1016)
			(stroke
				(width 0.1)
				(type default)
			)
			(layer "B.Fab")
		)
		(fp_line
			(start 0.2794 -0.1016)
			(end 0.2794 0.9906)
			(stroke
				(width 0.1)
				(type default)
			)
			(layer "B.Fab")
		)
		(fp_line
			(start 0.2794 0.9906)
			(end -0.2794 0.9906)
			(stroke
				(width 0.1)
				(type default)
			)
			(layer "B.Fab")
		)
		(pad "1" smd rect
			(at 0 0 180)
			(size 0.508 0.508)
			(layers "B.Cu" "B.Mask" "B.Paste")
			(net "PVPP_ABC")
		)
		(pad "2" smd rect
			(at 0 0.889 180)
			(size 0.508 0.508)
			(layers "B.Cu" "B.Mask" "B.Paste")
			(net "FM_DIMM_EVENT_COD_N")
		)
		(zone
			(layer "B.Cu")
			(hatch none 0.5)
			(connect_pads
				(clearance 0)
			)
			(min_thickness 0.25)
			(keepout
				(tracks allowed)
				(vias not_allowed)
				(pads allowed)
				(copperpour not_allowed)
				(footprints allowed)
			)
			(placement
				(enabled no)
				(sheetname "")
			)
			(fill
				(thermal_gap 0.5)
				(thermal_bridge_width 0.5)
				(island_removal_mode 0)
			)
			(polygon
				(pts
					(xy 330.7334 -11.4554) (xy 330.2254 -11.4554) (xy 330.2254 -11.0744) (xy 330.7334 -11.0744)
				)
			)
		)
		(zone
			(layer "B.Cu")
			(hatch none 0.5)
			(connect_pads
				(clearance 0)
			)
			(min_thickness 0.25)
			(keepout
				(tracks not_allowed)
				(vias allowed)
				(pads allowed)
				(copperpour not_allowed)
				(footprints allowed)
			)
			(placement
				(enabled no)
				(sheetname "")
			)
			(fill
				(thermal_gap 0.5)
				(thermal_bridge_width 0.5)
				(island_removal_mode 0)
			)
			(polygon
				(pts
					(xy 330.7334 -11.0744) (xy 330.2254 -11.0744) (xy 330.2254 -11.4554) (xy 330.7334 -11.4554)
				)
			)
		)
	)
	(footprint ""
		(layer "B.Cu")
		(at 347.79204 -149.168104 -90)
		(property "Reference" "C7A26"
			(at 0 0 90)
			(layer "B.SilkS")
			(hide yes)
			(effects
				(font
					(size 1.27 1.27)
				)
				(justify mirror)
			)
		)
		(property "Value" "*"
			(at -1.1811 -2.8194 270)
			(unlocked yes)
			(layer "B.Fab")
			(hide yes)
			(effects
				(font
					(size 1.27 1.016)
					(thickness 0.1524)
				)
				(justify mirror)
			)
		)
		(property "Device Type" "SC1U10V2KX-4-GP_SMD-BCG6-SC1U1A"
			(at -1.1811 -4.3434 270)
			(unlocked yes)
			(layer "B.Fab")
			(hide yes)
			(effects
				(font
					(size 1.27 1.016)
					(thickness 0.1524)
				)
				(justify mirror)
			)
		)
		(duplicate_pad_numbers_are_jumpers no)
		(fp_rect
			(start 0.4318 0.9525)
			(end -0.4318 -0.9525)
			(stroke
				(width 0)
				(type default)
			)
			(fill no)
			(layer "B.CrtYd")
		)
		(fp_rect
			(start 0.4318 0.9525)
			(end -0.4318 -0.9525)
			(stroke
				(width 0)
				(type default)
			)
			(fill no)
			(layer "B.Fab")
		)
		(pad "1" smd custom
			(at 0 -0.4445 90)
			(size 0.1524 0.1524)
			(layers "B.Cu" "B.Mask" "B.Paste")
			(net "P5V_STBY")
			(options
				(clearance outline)
				(anchor circle)
			)
			(primitives
				(gr_poly
					(pts
						(arc
							(start 0.3048 0.2032)
							(mid 0.275042 0.275042)
							(end 0.2032 0.3048)
						)
						(arc
							(start -0.2032 0.3048)
							(mid -0.275042 0.275042)
							(end -0.3048 0.2032)
						)
						(arc
							(start -0.3048 -0.2032)
							(mid -0.275042 -0.275042)
							(end -0.2032 -0.3048)
						)
						(arc
							(start 0.2032 -0.3048)
							(mid 0.275042 -0.275042)
							(end 0.3048 -0.2032)
						)
					)
					(width 0)
					(fill yes)
				)
			)
		)
		(pad "2" smd custom
			(at 0 0.4445 90)
			(size 0.1524 0.1524)
			(layers "B.Cu" "B.Mask" "B.Paste")
			(net "GND")
			(options
				(clearance outline)
				(anchor circle)
			)
			(primitives
				(gr_poly
					(pts
						(arc
							(start 0.3048 0.2032)
							(mid 0.275042 0.275042)
							(end 0.2032 0.3048)
						)
						(arc
							(start -0.2032 0.3048)
							(mid -0.275042 0.275042)
							(end -0.3048 0.2032)
						)
						(arc
							(start -0.3048 -0.2032)
							(mid -0.275042 -0.275042)
							(end -0.2032 -0.3048)
						)
						(arc
							(start 0.2032 -0.3048)
							(mid 0.275042 -0.275042)
							(end 0.3048 -0.2032)
						)
					)
					(width 0)
					(fill yes)
				)
			)
		)
	)
	(footprint ""
		(layer "B.Cu")
		(at 468.63 -46.6725 180)
		(property "Reference" "R9E12"
			(at 0 0 0)
			(layer "B.SilkS")
			(hide yes)
			(effects
				(font
					(size 1.27 1.27)
				)
				(justify mirror)
			)
		)
		(property "Value" ""
			(at 0 0 0)
			(layer "B.Fab")
			(effects
				(font
					(size 1.27 1.27)
				)
				(justify mirror)
			)
		)
		(duplicate_pad_numbers_are_jumpers no)
		(fp_poly
			(pts
				(xy 0.2794 -0.1016) (xy -0.2794 -0.1016) (xy -0.2794 0.9906) (xy 0.2794 0.9906)
			)
			(stroke
				(width 0)
				(type default)
			)
			(fill no)
			(layer "B.CrtYd")
		)
		(fp_line
			(start 0.2794 0.9906)
			(end -0.2794 0.9906)
			(stroke
				(width 0.1)
				(type default)
			)
			(layer "B.Fab")
		)
		(fp_line
			(start 0.2794 -0.1016)
			(end 0.2794 0.9906)
			(stroke
				(width 0.1)
				(type default)
			)
			(layer "B.Fab")
		)
		(fp_line
			(start -0.2794 0.9906)
			(end -0.2794 -0.1016)
			(stroke
				(width 0.1)
				(type default)
			)
			(layer "B.Fab")
		)
		(fp_line
			(start -0.2794 -0.1016)
			(end 0.2794 -0.1016)
			(stroke
				(width 0.1)
				(type default)
			)
			(layer "B.Fab")
		)
		(pad "1" smd rect
			(at 0 0)
			(size 0.508 0.508)
			(layers "B.Cu" "B.Mask" "B.Paste")
			(net "RST_PCIE_CPU_DEV3_R_N")
		)
		(pad "2" smd rect
			(at 0 0.889)
			(size 0.508 0.508)
			(layers "B.Cu" "B.Mask" "B.Paste")
			(net "RST_PCIE_CPU_DEV3_N")
		)
		(zone
			(layer "B.Cu")
			(hatch none 0.5)
			(connect_pads
				(clearance 0)
			)
			(min_thickness 0.25)
			(keepout
				(tracks not_allowed)
				(vias allowed)
				(pads allowed)
				(copperpour not_allowed)
				(footprints allowed)
			)
			(placement
				(enabled no)
				(sheetname "")
			)
			(fill
				(thermal_gap 0.5)
				(thermal_bridge_width 0.5)
				(island_removal_mode 0)
			)
			(polygon
				(pts
					(xy 468.376 -47.3075) (xy 468.884 -47.3075) (xy 468.884 -46.9265) (xy 468.376 -46.9265)
				)
			)
		)
		(zone
			(layer "B.Cu")
			(hatch none 0.5)
			(connect_pads
				(clearance 0)
			)
			(min_thickness 0.25)
			(keepout
				(tracks allowed)
				(vias not_allowed)
				(pads allowed)
				(copperpour not_allowed)
				(footprints allowed)
			)
			(placement
				(enabled no)
				(sheetname "")
			)
			(fill
				(thermal_gap 0.5)
				(thermal_bridge_width 0.5)
				(island_removal_mode 0)
			)
			(polygon
				(pts
					(xy 468.376 -46.9265) (xy 468.884 -46.9265) (xy 468.884 -47.3075) (xy 468.376 -47.3075)
				)
			)
		)
	)
	(footprint ""
		(layer "B.Cu")
		(at -1.44526 -119.46636 180)
		(property "Reference" "R9M16"
			(at 0 0 0)
			(layer "B.SilkS")
			(hide yes)
			(effects
				(font
					(size 1.27 1.27)
				)
				(justify mirror)
			)
		)
		(property "Value" ""
			(at 0 0 0)
			(layer "B.Fab")
			(effects
				(font
					(size 1.27 1.27)
				)
				(justify mirror)
			)
		)
		(duplicate_pad_numbers_are_jumpers no)
		(fp_rect
			(start 0.2794 -0.1016)
			(end -0.2794 0.9906)
			(stroke
				(width 0)
				(type default)
			)
			(fill no)
			(layer "B.CrtYd")
		)
		(fp_line
			(start 0.2794 0.9906)
			(end -0.2794 0.9906)
			(stroke
				(width 0.1)
				(type default)
			)
			(layer "B.Fab")
		)
		(fp_line
			(start 0.2794 -0.1016)
			(end 0.2794 0.9906)
			(stroke
				(width 0.1)
				(type default)
			)
			(layer "B.Fab")
		)
		(fp_line
			(start -0.2794 0.9906)
			(end -0.2794 -0.1016)
			(stroke
				(width 0.1)
				(type default)
			)
			(layer "B.Fab")
		)
		(fp_line
			(start -0.2794 -0.1016)
			(end 0.2794 -0.1016)
			(stroke
				(width 0.1)
				(type default)
			)
			(layer "B.Fab")
		)
		(pad "1" smd rect
			(at 0 0)
			(size 0.508 0.508)
			(layers "B.Cu" "B.Mask" "B.Paste")
			(net "P3V3_STBY")
		)
		(pad "2" smd rect
			(at 0 0.889)
			(size 0.508 0.508)
			(layers "B.Cu" "B.Mask" "B.Paste")
			(net "SMB_PEHPCPU1_STBY_LVC3_R_SDA")
		)
		(zone
			(layer "B.Cu")
			(hatch none 0.5)
			(connect_pads
				(clearance 0)
			)
			(min_thickness 0.25)
			(keepout
				(tracks allowed)
				(vias not_allowed)
				(pads allowed)
				(copperpour not_allowed)
				(footprints allowed)
			)
			(placement
				(enabled no)
				(sheetname "")
			)
			(fill
				(thermal_gap 0.5)
				(thermal_bridge_width 0.5)
				(island_removal_mode 0)
			)
			(polygon
				(pts
					(xy -1.69926 -119.72036) (xy -1.19126 -119.72036) (xy -1.19126 -120.10136) (xy -1.69926 -120.10136)
				)
			)
		)
		(zone
			(layer "B.Cu")
			(hatch none 0.5)
			(connect_pads
				(clearance 0)
			)
			(min_thickness 0.25)
			(keepout
				(tracks not_allowed)
				(vias allowed)
				(pads allowed)
				(copperpour not_allowed)
				(footprints allowed)
			)
			(placement
				(enabled no)
				(sheetname "")
			)
			(fill
				(thermal_gap 0.5)
				(thermal_bridge_width 0.5)
				(island_removal_mode 0)
			)
			(polygon
				(pts
					(xy -1.69926 -119.72036) (xy -1.19126 -119.72036) (xy -1.19126 -120.10136) (xy -1.69926 -120.10136)
				)
			)
		)
	)
	(footprint ""
		(layer "B.Cu")
		(at 484.9749 -49.8602 90)
		(property "Reference" "R1R1"
			(at 0 0 90)
			(layer "B.SilkS")
			(hide yes)
			(effects
				(font
					(size 1.27 1.27)
				)
				(justify mirror)
			)
		)
		(property "Value" ""
			(at 0 0 90)
			(layer "B.Fab")
			(effects
				(font
					(size 1.27 1.27)
				)
				(justify mirror)
			)
		)
		(duplicate_pad_numbers_are_jumpers no)
		(fp_poly
			(pts
				(xy 0.2794 -0.1016) (xy -0.2794 -0.1016) (xy -0.2794 0.9906) (xy 0.2794 0.9906)
			)
			(stroke
				(width 0)
				(type default)
			)
			(fill no)
			(layer "B.CrtYd")
		)
		(fp_line
			(start 0.2794 -0.1016)
			(end 0.2794 0.9906)
			(stroke
				(width 0.1)
				(type default)
			)
			(layer "B.Fab")
		)
		(fp_line
			(start -0.2794 -0.1016)
			(end 0.2794 -0.1016)
			(stroke
				(width 0.1)
				(type default)
			)
			(layer "B.Fab")
		)
		(fp_line
			(start 0.2794 0.9906)
			(end -0.2794 0.9906)
			(stroke
				(width 0.1)
				(type default)
			)
			(layer "B.Fab")
		)
		(fp_line
			(start -0.2794 0.9906)
			(end -0.2794 -0.1016)
			(stroke
				(width 0.1)
				(type default)
			)
			(layer "B.Fab")
		)
		(pad "1" smd rect
			(at 0 0 270)
			(size 0.508 0.508)
			(layers "B.Cu" "B.Mask" "B.Paste")
			(net "RST_PLTRST_N")
		)
		(pad "2" smd rect
			(at 0 0.889 270)
			(size 0.508 0.508)
			(layers "B.Cu" "B.Mask" "B.Paste")
			(net "RST_PLTRST_SPRV_R_N")
		)
		(zone
			(layer "B.Cu")
			(hatch none 0.5)
			(connect_pads
				(clearance 0)
			)
			(min_thickness 0.25)
			(keepout
				(tracks allowed)
				(vias not_allowed)
				(pads allowed)
				(copperpour not_allowed)
				(footprints allowed)
			)
			(placement
				(enabled no)
				(sheetname "")
			)
			(fill
				(thermal_gap 0.5)
				(thermal_bridge_width 0.5)
				(island_removal_mode 0)
			)
			(polygon
				(pts
					(xy 485.2289 -50.1142) (xy 485.2289 -49.6062) (xy 485.6099 -49.6062) (xy 485.6099 -50.1142)
				)
			)
		)
		(zone
			(layer "B.Cu")
			(hatch none 0.5)
			(connect_pads
				(clearance 0)
			)
			(min_thickness 0.25)
			(keepout
				(tracks not_allowed)
				(vias allowed)
				(pads allowed)
				(copperpour not_allowed)
				(footprints allowed)
			)
			(placement
				(enabled no)
				(sheetname "")
			)
			(fill
				(thermal_gap 0.5)
				(thermal_bridge_width 0.5)
				(island_removal_mode 0)
			)
			(polygon
				(pts
					(xy 485.6099 -50.1142) (xy 485.6099 -49.6062) (xy 485.2289 -49.6062) (xy 485.2289 -50.1142)
				)
			)
		)
	)
	(footprint ""
		(layer "B.Cu")
		(at 448.55638 -35.8775 90)
		(property "Reference" "R25W32"
			(at 0 0 90)
			(layer "B.SilkS")
			(hide yes)
			(effects
				(font
					(size 1.27 1.27)
				)
				(justify mirror)
			)
		)
		(property "Value" "*"
			(at -0.064008 -4.108196 90)
			(unlocked yes)
			(layer "B.Fab")
			(hide yes)
			(effects
				(font
					(size 1.27 1.016)
					(thickness 0.1524)
				)
				(justify mirror)
			)
		)
		(property "Device Type" "120R2F-GP_RCL_GP-120R2F-GP,64.A"
			(at -0.064008 -5.632196 90)
			(unlocked yes)
			(layer "B.Fab")
			(hide yes)
			(effects
				(font
					(size 1.27 1.016)
					(thickness 0.1524)
				)
				(justify mirror)
			)
		)
		(duplicate_pad_numbers_are_jumpers no)
		(fp_line
			(start 0.508 -0.9398)
			(end 0.508 0.9398)
			(stroke
				(width 0.1524)
				(type default)
			)
			(layer "B.SilkS")
		)
		(fp_line
			(start -0.508 -0.9398)
			(end 0.508 -0.9398)
			(stroke
				(width 0.1524)
				(type default)
			)
			(layer "B.SilkS")
		)
		(fp_rect
			(start 0.508 0.9398)
			(end -0.508 -0.9398)
			(stroke
				(width 0)
				(type default)
			)
			(fill no)
			(layer "B.CrtYd")
		)
		(fp_rect
			(start 0.508 0.9398)
			(end -0.508 -0.9398)
			(stroke
				(width 0)
				(type default)
			)
			(fill no)
			(layer "B.Fab")
		)
		(pad "1" smd custom
			(at 0 -0.4445 270)
			(size 0.1397 0.1397)
			(layers "B.Cu" "B.Mask" "B.Paste")
			(net "BMC_M_RAS_N")
			(options
				(clearance outline)
				(anchor circle)
			)
			(primitives
				(gr_poly
					(pts
						(arc
							(start -0.1778 0.2794)
							(mid -0.249642 0.249642)
							(end -0.2794 0.1778)
						)
						(arc
							(start -0.2794 -0.1778)
							(mid -0.249642 -0.249642)
							(end -0.1778 -0.2794)
						)
						(arc
							(start 0.1778 -0.2794)
							(mid 0.249642 -0.249642)
							(end 0.2794 -0.1778)
						)
						(arc
							(start 0.2794 0.1778)
							(mid 0.249642 0.249642)
							(end 0.1778 0.2794)
						)
					)
					(width 0)
					(fill yes)
				)
			)
		)
		(pad "2" smd custom
			(at 0 0.4445 270)
			(size 0.1397 0.1397)
			(layers "B.Cu" "B.Mask" "B.Paste")
			(net "P1V2_AUX_BMC")
			(options
				(clearance outline)
				(anchor circle)
			)
			(primitives
				(gr_poly
					(pts
						(arc
							(start -0.1778 0.2794)
							(mid -0.249642 0.249642)
							(end -0.2794 0.1778)
						)
						(arc
							(start -0.2794 -0.1778)
							(mid -0.249642 -0.249642)
							(end -0.1778 -0.2794)
						)
						(arc
							(start 0.1778 -0.2794)
							(mid 0.249642 -0.249642)
							(end 0.2794 -0.1778)
						)
						(arc
							(start 0.2794 0.1778)
							(mid 0.249642 0.249642)
							(end 0.1778 0.2794)
						)
					)
					(width 0)
					(fill yes)
				)
			)
		)
	)
	(footprint ""
		(layer "B.Cu")
		(at 359.1052 -4.2418 180)
		(property "Reference" "R8W11"
			(at 0.8382 -0.67818 180)
			(unlocked yes)
			(layer "B.SilkS")
			(effects
				(font
					(size 0.4064 0.254)
					(thickness 0.1524)
				)
				(justify left mirror)
			)
		)
		(property "Value" ""
			(at 0 0 0)
			(layer "B.Fab")
			(effects
				(font
					(size 1.27 1.27)
				)
				(justify mirror)
			)
		)
		(duplicate_pad_numbers_are_jumpers no)
		(fp_poly
			(pts
				(xy 0.2794 -0.1016) (xy -0.2794 -0.1016) (xy -0.2794 0.9906) (xy 0.2794 0.9906)
			)
			(stroke
				(width 0)
				(type default)
			)
			(fill no)
			(layer "B.CrtYd")
		)
		(fp_line
			(start 0.2794 0.9906)
			(end -0.2794 0.9906)
			(stroke
				(width 0.1)
				(type default)
			)
			(layer "B.Fab")
		)
		(fp_line
			(start 0.2794 -0.1016)
			(end 0.2794 0.9906)
			(stroke
				(width 0.1)
				(type default)
			)
			(layer "B.Fab")
		)
		(fp_line
			(start -0.2794 0.9906)
			(end -0.2794 -0.1016)
			(stroke
				(width 0.1)
				(type default)
			)
			(layer "B.Fab")
		)
		(fp_line
			(start -0.2794 -0.1016)
			(end 0.2794 -0.1016)
			(stroke
				(width 0.1)
				(type default)
			)
			(layer "B.Fab")
		)
		(pad "1" smd rect
			(at 0 0)
			(size 0.508 0.508)
			(layers "B.Cu" "B.Mask" "B.Paste")
			(net "JTAG_RISER_TCK")
		)
		(pad "2" smd rect
			(at 0 0.889)
			(size 0.508 0.508)
			(layers "B.Cu" "B.Mask" "B.Paste")
			(net "JTAG_PLD_TCK_MUX")
		)
		(zone
			(layer "B.Cu")
			(hatch none 0.5)
			(connect_pads
				(clearance 0)
			)
			(min_thickness 0.25)
			(keepout
				(tracks not_allowed)
				(vias allowed)
				(pads allowed)
				(copperpour not_allowed)
				(footprints allowed)
			)
			(placement
				(enabled no)
				(sheetname "")
			)
			(fill
				(thermal_gap 0.5)
				(thermal_bridge_width 0.5)
				(island_removal_mode 0)
			)
			(polygon
				(pts
					(xy 358.8512 -4.8768) (xy 359.3592 -4.8768) (xy 359.3592 -4.4958) (xy 358.8512 -4.4958)
				)
			)
		)
		(zone
			(layer "B.Cu")
			(hatch none 0.5)
			(connect_pads
				(clearance 0)
			)
			(min_thickness 0.25)
			(keepout
				(tracks allowed)
				(vias not_allowed)
				(pads allowed)
				(copperpour not_allowed)
				(footprints allowed)
			)
			(placement
				(enabled no)
				(sheetname "")
			)
			(fill
				(thermal_gap 0.5)
				(thermal_bridge_width 0.5)
				(island_removal_mode 0)
			)
			(polygon
				(pts
					(xy 358.8512 -4.4958) (xy 359.3592 -4.4958) (xy 359.3592 -4.8768) (xy 358.8512 -4.8768)
				)
			)
		)
	)
	(footprint ""
		(layer "B.Cu")
		(at 29.563568 -155.448)
		(property "Reference" "R9L1"
			(at 0 0 0)
			(layer "B.SilkS")
			(hide yes)
			(effects
				(font
					(size 1.27 1.27)
				)
				(justify mirror)
			)
		)
		(property "Value" ""
			(at 0 0 0)
			(layer "B.Fab")
			(effects
				(font
					(size 1.27 1.27)
				)
				(justify mirror)
			)
		)
		(duplicate_pad_numbers_are_jumpers no)
		(fp_poly
			(pts
				(xy 0.2794 -0.1016) (xy -0.2794 -0.1016) (xy -0.2794 0.9906) (xy 0.2794 0.9906)
			)
			(stroke
				(width 0)
				(type default)
			)
			(fill no)
			(layer "B.CrtYd")
		)
		(fp_line
			(start -0.2794 -0.1016)
			(end 0.2794 -0.1016)
			(stroke
				(width 0.1)
				(type default)
			)
			(layer "B.Fab")
		)
		(fp_line
			(start -0.2794 0.9906)
			(end -0.2794 -0.1016)
			(stroke
				(width 0.1)
				(type default)
			)
			(layer "B.Fab")
		)
		(fp_line
			(start 0.2794 -0.1016)
			(end 0.2794 0.9906)
			(stroke
				(width 0.1)
				(type default)
			)
			(layer "B.Fab")
		)
		(fp_line
			(start 0.2794 0.9906)
			(end -0.2794 0.9906)
			(stroke
				(width 0.1)
				(type default)
			)
			(layer "B.Fab")
		)
		(pad "1" smd rect
			(at 0 0 180)
			(size 0.508 0.508)
			(layers "B.Cu" "B.Mask" "B.Paste")
			(net "M_M_VREF")
		)
		(pad "2" smd rect
			(at 0 0.889 180)
			(size 0.508 0.508)
			(layers "B.Cu" "B.Mask" "B.Paste")
			(net "GND")
		)
		(zone
			(layer "B.Cu")
			(hatch none 0.5)
			(connect_pads
				(clearance 0)
			)
			(min_thickness 0.25)
			(keepout
				(tracks allowed)
				(vias not_allowed)
				(pads allowed)
				(copperpour not_allowed)
				(footprints allowed)
			)
			(placement
				(enabled no)
				(sheetname "")
			)
			(fill
				(thermal_gap 0.5)
				(thermal_bridge_width 0.5)
				(island_removal_mode 0)
			)
			(polygon
				(pts
					(xy 29.817568 -155.194) (xy 29.309568 -155.194) (xy 29.309568 -154.813) (xy 29.817568 -154.813)
				)
			)
		)
		(zone
			(layer "B.Cu")
			(hatch none 0.5)
			(connect_pads
				(clearance 0)
			)
			(min_thickness 0.25)
			(keepout
				(tracks not_allowed)
				(vias allowed)
				(pads allowed)
				(copperpour not_allowed)
				(footprints allowed)
			)
			(placement
				(enabled no)
				(sheetname "")
			)
			(fill
				(thermal_gap 0.5)
				(thermal_bridge_width 0.5)
				(island_removal_mode 0)
			)
			(polygon
				(pts
					(xy 29.817568 -154.813) (xy 29.309568 -154.813) (xy 29.309568 -155.194) (xy 29.817568 -155.194)
				)
			)
		)
	)
	(footprint ""
		(layer "B.Cu")
		(at 402.336 -87.3125 180)
		(property "Reference" "R8D44"
			(at 0.8382 -0.67818 180)
			(unlocked yes)
			(layer "B.SilkS")
			(effects
				(font
					(size 0.4064 0.254)
					(thickness 0.1524)
				)
				(justify left mirror)
			)
		)
		(property "Value" ""
			(at 0 0 0)
			(layer "B.Fab")
			(effects
				(font
					(size 1.27 1.27)
				)
				(justify mirror)
			)
		)
		(duplicate_pad_numbers_are_jumpers no)
		(fp_poly
			(pts
				(xy 0.2794 -0.1016) (xy -0.2794 -0.1016) (xy -0.2794 0.9906) (xy 0.2794 0.9906)
			)
			(stroke
				(width 0)
				(type default)
			)
			(fill no)
			(layer "B.CrtYd")
		)
		(fp_line
			(start 0.2794 0.9906)
			(end -0.2794 0.9906)
			(stroke
				(width 0.1)
				(type default)
			)
			(layer "B.Fab")
		)
		(fp_line
			(start 0.2794 -0.1016)
			(end 0.2794 0.9906)
			(stroke
				(width 0.1)
				(type default)
			)
			(layer "B.Fab")
		)
		(fp_line
			(start -0.2794 0.9906)
			(end -0.2794 -0.1016)
			(stroke
				(width 0.1)
				(type default)
			)
			(layer "B.Fab")
		)
		(fp_line
			(start -0.2794 -0.1016)
			(end 0.2794 -0.1016)
			(stroke
				(width 0.1)
				(type default)
			)
			(layer "B.Fab")
		)
		(pad "1" smd rect
			(at 0 0)
			(size 0.508 0.508)
			(layers "B.Cu" "B.Mask" "B.Paste")
			(net "P3V3_STBY")
		)
		(pad "2" smd rect
			(at 0 0.889)
			(size 0.508 0.508)
			(layers "B.Cu" "B.Mask" "B.Paste")
			(net "FM_CPU0_RC_EN")
		)
		(zone
			(layer "B.Cu")
			(hatch none 0.5)
			(connect_pads
				(clearance 0)
			)
			(min_thickness 0.25)
			(keepout
				(tracks not_allowed)
				(vias allowed)
				(pads allowed)
				(copperpour not_allowed)
				(footprints allowed)
			)
			(placement
				(enabled no)
				(sheetname "")
			)
			(fill
				(thermal_gap 0.5)
				(thermal_bridge_width 0.5)
				(island_removal_mode 0)
			)
			(polygon
				(pts
					(xy 402.082 -87.9475) (xy 402.59 -87.9475) (xy 402.59 -87.5665) (xy 402.082 -87.5665)
				)
			)
		)
		(zone
			(layer "B.Cu")
			(hatch none 0.5)
			(connect_pads
				(clearance 0)
			)
			(min_thickness 0.25)
			(keepout
				(tracks allowed)
				(vias not_allowed)
				(pads allowed)
				(copperpour not_allowed)
				(footprints allowed)
			)
			(placement
				(enabled no)
				(sheetname "")
			)
			(fill
				(thermal_gap 0.5)
				(thermal_bridge_width 0.5)
				(island_removal_mode 0)
			)
			(polygon
				(pts
					(xy 402.082 -87.5665) (xy 402.59 -87.5665) (xy 402.59 -87.9475) (xy 402.082 -87.9475)
				)
			)
		)
	)
	(footprint ""
		(layer "B.Cu")
		(at 348.488 -104.267 180)
		(property "Reference" "C22W30"
			(at 0 0 0)
			(layer "B.SilkS")
			(hide yes)
			(effects
				(font
					(size 1.27 1.27)
				)
				(justify mirror)
			)
		)
		(property "Value" "*"
			(at 0.0762 -6.2357 180)
			(unlocked yes)
			(layer "B.Fab")
			(hide yes)
			(effects
				(font
					(size 1.27 1.016)
					(thickness 0.1524)
				)
				(justify mirror)
			)
		)
		(property "Device Type" "SC22U16V5MX-4-GP_SMD-BCG5-SC22A"
			(at 0.0762 -8.2677 180)
			(unlocked yes)
			(layer "B.Fab")
			(hide yes)
			(effects
				(font
					(size 1.27 1.016)
					(thickness 0.1524)
				)
				(justify mirror)
			)
		)
		(duplicate_pad_numbers_are_jumpers no)
		(fp_line
			(start -0.635 0)
			(end 0.635 0)
			(stroke
				(width 0.508)
				(type default)
			)
			(layer "B.SilkS")
		)
		(fp_rect
			(start 0.9652 1.778)
			(end -0.9652 -1.778)
			(stroke
				(width 0)
				(type default)
			)
			(fill no)
			(layer "B.CrtYd")
		)
		(fp_poly
			(pts
				(xy 0.9652 -1.778) (xy -0.9652 -1.778) (xy -0.9652 1.778) (xy 0.9652 1.778)
			)
			(stroke
				(width 0)
				(type default)
			)
			(fill no)
			(layer "B.Fab")
		)
		(pad "1" smd rect
			(at 0 -0.9652)
			(size 1.397 1.143)
			(layers "B.Cu" "B.Mask" "B.Paste")
			(net "VR_FET_SW_P12V_STBY_PVCCIO_CPU0")
		)
		(pad "2" smd rect
			(at 0 0.9652)
			(size 1.397 1.143)
			(layers "B.Cu" "B.Mask" "B.Paste")
			(net "GND")
		)
	)
	(footprint ""
		(layer "B.Cu")
		(at 436.547006 -43.54195 180)
		(property "Reference" "R25W43"
			(at 0 0 0)
			(layer "B.SilkS")
			(hide yes)
			(effects
				(font
					(size 1.27 1.27)
				)
				(justify mirror)
			)
		)
		(property "Value" "*"
			(at -0.064008 -4.108196 180)
			(unlocked yes)
			(layer "B.Fab")
			(hide yes)
			(effects
				(font
					(size 1.27 1.016)
					(thickness 0.1524)
				)
				(justify mirror)
			)
		)
		(property "Device Type" "120R2F-GP_RCL_GP-120R2F-GP,64.A"
			(at -0.064008 -5.632196 180)
			(unlocked yes)
			(layer "B.Fab")
			(hide yes)
			(effects
				(font
					(size 1.27 1.016)
					(thickness 0.1524)
				)
				(justify mirror)
			)
		)
		(duplicate_pad_numbers_are_jumpers no)
		(fp_line
			(start 0.508 -0.9398)
			(end 0.508 0.9398)
			(stroke
				(width 0.1524)
				(type default)
			)
			(layer "B.SilkS")
		)
		(fp_line
			(start -0.508 -0.9398)
			(end 0.508 -0.9398)
			(stroke
				(width 0.1524)
				(type default)
			)
			(layer "B.SilkS")
		)
		(fp_rect
			(start 0.508 0.9398)
			(end -0.508 -0.9398)
			(stroke
				(width 0)
				(type default)
			)
			(fill no)
			(layer "B.CrtYd")
		)
		(fp_rect
			(start 0.508 0.9398)
			(end -0.508 -0.9398)
			(stroke
				(width 0)
				(type default)
			)
			(fill no)
			(layer "B.Fab")
		)
		(pad "1" smd custom
			(at 0 -0.4445)
			(size 0.1397 0.1397)
			(layers "B.Cu" "B.Mask" "B.Paste")
			(net "BMC_M_A5")
			(options
				(clearance outline)
				(anchor circle)
			)
			(primitives
				(gr_poly
					(pts
						(arc
							(start -0.1778 0.2794)
							(mid -0.249642 0.249642)
							(end -0.2794 0.1778)
						)
						(arc
							(start -0.2794 -0.1778)
							(mid -0.249642 -0.249642)
							(end -0.1778 -0.2794)
						)
						(arc
							(start 0.1778 -0.2794)
							(mid 0.249642 -0.249642)
							(end 0.2794 -0.1778)
						)
						(arc
							(start 0.2794 0.1778)
							(mid 0.249642 0.249642)
							(end 0.1778 0.2794)
						)
					)
					(width 0)
					(fill yes)
				)
			)
		)
		(pad "2" smd custom
			(at 0 0.4445)
			(size 0.1397 0.1397)
			(layers "B.Cu" "B.Mask" "B.Paste")
			(net "P1V2_AUX_BMC")
			(options
				(clearance outline)
				(anchor circle)
			)
			(primitives
				(gr_poly
					(pts
						(arc
							(start -0.1778 0.2794)
							(mid -0.249642 0.249642)
							(end -0.2794 0.1778)
						)
						(arc
							(start -0.2794 -0.1778)
							(mid -0.249642 -0.249642)
							(end -0.1778 -0.2794)
						)
						(arc
							(start 0.1778 -0.2794)
							(mid 0.249642 -0.249642)
							(end 0.2794 -0.1778)
						)
						(arc
							(start 0.2794 0.1778)
							(mid 0.249642 0.249642)
							(end 0.1778 0.2794)
						)
					)
					(width 0)
					(fill yes)
				)
			)
		)
	)
	(footprint ""
		(layer "B.Cu")
		(at 495.01552 -133.6675 90)
		(property "Reference" "U1M2"
			(at -3.14198 -1.37541 270)
			(unlocked yes)
			(layer "B.SilkS")
			(effects
				(font
					(size 0.7874 0.5842)
					(thickness 0.1524)
				)
				(justify left mirror)
			)
		)
		(property "Value" ""
			(at 0 0 90)
			(layer "B.Fab")
			(effects
				(font
					(size 1.27 1.27)
				)
				(justify mirror)
			)
		)
		(duplicate_pad_numbers_are_jumpers no)
		(fp_circle
			(center 0.595884 -0.655574)
			(end 0.595884 -0.528574)
			(stroke
				(width 0.254)
				(type default)
			)
			(fill no)
			(layer "B.SilkS")
		)
		(fp_poly
			(pts
				(xy -0.21463 -0.450088) (xy -1.56337 -0.450088) (xy -1.56337 1.75006) (xy -0.21463 1.75006)
			)
			(stroke
				(width 0)
				(type default)
			)
			(fill no)
			(layer "B.CrtYd")
		)
		(fp_line
			(start -0.21463 -0.450088)
			(end -1.56337 -0.450088)
			(stroke
				(width 0.1)
				(type default)
			)
			(layer "B.Fab")
		)
		(fp_line
			(start -1.56337 -0.450088)
			(end -1.56337 1.75006)
			(stroke
				(width 0.1)
				(type default)
			)
			(layer "B.Fab")
		)
		(fp_line
			(start -0.21463 1.75006)
			(end -0.21463 -0.450088)
			(stroke
				(width 0.1)
				(type default)
			)
			(layer "B.Fab")
		)
		(fp_line
			(start -1.56337 1.75006)
			(end -0.21463 1.75006)
			(stroke
				(width 0.1)
				(type default)
			)
			(layer "B.Fab")
		)
		(fp_circle
			(center 0.848614 -0.6477)
			(end 0.848614 -0.5207)
			(stroke
				(width 0.254)
				(type default)
			)
			(fill no)
			(layer "B.Fab")
		)
		(pad "1" smd rect
			(at 0 0 270)
			(size 1.016 0.381)
			(layers "B.Cu" "B.Mask" "B.Paste")
			(net "JTAG_MCP_CPU0_TDO")
		)
		(pad "2" smd rect
			(at 0 0.649986 270)
			(size 1.016 0.381)
			(layers "B.Cu" "B.Mask" "B.Paste")
			(net "GND")
		)
		(pad "3" smd rect
			(at 0 1.299972 270)
			(size 1.016 0.381)
			(layers "B.Cu" "B.Mask" "B.Paste")
			(net "JTAG_MCP_CPU1_TDO")
		)
		(pad "4" smd rect
			(at -1.778 1.299972 270)
			(size 1.016 0.381)
			(layers "B.Cu" "B.Mask" "B.Paste")
			(net "JTAG_MCP_MUX_TDO")
		)
		(pad "5" smd rect
			(at -1.778 0.649986 270)
			(size 1.016 0.381)
			(layers "B.Cu" "B.Mask" "B.Paste")
			(net "P3V3_STBY")
		)
		(pad "6" smd rect
			(at -1.778 0 270)
			(size 1.016 0.381)
			(layers "B.Cu" "B.Mask" "B.Paste")
			(net "FM_CPU1_CD_PRES_N")
		)
	)
	(footprint ""
		(layer "B.Cu")
		(at 100.672392 -85.075014)
		(property "Reference" "C8P2"
			(at 0 0 0)
			(layer "B.SilkS")
			(hide yes)
			(effects
				(font
					(size 1.27 1.27)
				)
				(justify mirror)
			)
		)
		(property "Value" ""
			(at 0 0 0)
			(layer "B.Fab")
			(effects
				(font
					(size 1.27 1.27)
				)
				(justify mirror)
			)
		)
		(duplicate_pad_numbers_are_jumpers no)
		(fp_poly
			(pts
				(xy 0.7239 -0.2159) (xy -0.7239 -0.2159) (xy -0.7239 1.9939) (xy 0.7239 1.9939)
			)
			(stroke
				(width 0)
				(type default)
			)
			(fill no)
			(layer "B.CrtYd")
		)
		(fp_line
			(start -0.7239 -0.2159)
			(end 0.7239 -0.2159)
			(stroke
				(width 0.1)
				(type default)
			)
			(layer "B.Fab")
		)
		(fp_line
			(start -0.7239 1.9939)
			(end -0.7239 -0.2159)
			(stroke
				(width 0.1)
				(type default)
			)
			(layer "B.Fab")
		)
		(fp_line
			(start 0.7239 -0.2159)
			(end 0.7239 1.9939)
			(stroke
				(width 0.1)
				(type default)
			)
			(layer "B.Fab")
		)
		(fp_line
			(start 0.7239 1.9939)
			(end -0.7239 1.9939)
			(stroke
				(width 0.1)
				(type default)
			)
			(layer "B.Fab")
		)
		(pad "1" smd rect
			(at 0 0 180)
			(size 1.27 1.016)
			(layers "B.Cu" "B.Mask" "B.Paste")
			(net "PVDDQ_KLM")
		)
		(pad "2" smd rect
			(at 0 1.778 180)
			(size 1.27 1.016)
			(layers "B.Cu" "B.Mask" "B.Paste")
			(net "GND")
		)
		(zone
			(layer "B.Cu")
			(hatch none 0.5)
			(connect_pads
				(clearance 0)
			)
			(min_thickness 0.25)
			(keepout
				(tracks not_allowed)
				(vias allowed)
				(pads allowed)
				(copperpour not_allowed)
				(footprints allowed)
			)
			(placement
				(enabled no)
				(sheetname "")
			)
			(fill
				(thermal_gap 0.5)
				(thermal_bridge_width 0.5)
				(island_removal_mode 0)
			)
			(polygon
				(pts
					(xy 101.307392 -84.567014) (xy 100.037392 -84.567014) (xy 100.037392 -83.805014) (xy 101.307392 -83.805014)
				)
			)
		)
	)
	(footprint ""
		(layer "B.Cu")
		(at 195.453 1.524 90)
		(property "Reference" "C6U17"
			(at 0 0 90)
			(layer "B.SilkS")
			(hide yes)
			(effects
				(font
					(size 1.27 1.27)
				)
				(justify mirror)
			)
		)
		(property "Value" ""
			(at 0 0 90)
			(layer "B.Fab")
			(effects
				(font
					(size 1.27 1.27)
				)
				(justify mirror)
			)
		)
		(duplicate_pad_numbers_are_jumpers no)
		(fp_poly
			(pts
				(xy -0.3048 -0.1016) (xy -0.3048 0.9906) (xy 0.3048 0.9906) (xy 0.3048 -0.1016)
			)
			(stroke
				(width 0)
				(type default)
			)
			(fill no)
			(layer "B.CrtYd")
		)
		(fp_line
			(start 0.3048 -0.1016)
			(end 0.3048 0.9906)
			(stroke
				(width 0.1)
				(type default)
			)
			(layer "B.Fab")
		)
		(fp_line
			(start -0.3048 -0.1016)
			(end 0.3048 -0.1016)
			(stroke
				(width 0.1)
				(type default)
			)
			(layer "B.Fab")
		)
		(fp_line
			(start 0.3048 0.9906)
			(end -0.3048 0.9906)
			(stroke
				(width 0.1)
				(type default)
			)
			(layer "B.Fab")
		)
		(fp_line
			(start -0.3048 0.9906)
			(end -0.3048 -0.1016)
			(stroke
				(width 0.1)
				(type default)
			)
			(layer "B.Fab")
		)
		(pad "1" smd rect
			(at 0 0 270)
			(size 0.508 0.508)
			(layers "B.Cu" "B.Mask" "B.Paste")
			(net "M_C_VREF")
		)
		(pad "2" smd rect
			(at 0 0.889 270)
			(size 0.508 0.508)
			(layers "B.Cu" "B.Mask" "B.Paste")
			(net "GND")
		)
		(zone
			(layer "B.Cu")
			(hatch none 0.5)
			(connect_pads
				(clearance 0)
			)
			(min_thickness 0.25)
			(keepout
				(tracks allowed)
				(vias not_allowed)
				(pads allowed)
				(copperpour not_allowed)
				(footprints allowed)
			)
			(placement
				(enabled no)
				(sheetname "")
			)
			(fill
				(thermal_gap 0.5)
				(thermal_bridge_width 0.5)
				(island_removal_mode 0)
			)
			(polygon
				(pts
					(xy 195.707 1.27) (xy 195.707 1.778) (xy 196.088 1.778) (xy 196.088 1.27)
				)
			)
		)
		(zone
			(layer "B.Cu")
			(hatch none 0.5)
			(connect_pads
				(clearance 0)
			)
			(min_thickness 0.25)
			(keepout
				(tracks not_allowed)
				(vias allowed)
				(pads allowed)
				(copperpour not_allowed)
				(footprints allowed)
			)
			(placement
				(enabled no)
				(sheetname "")
			)
			(fill
				(thermal_gap 0.5)
				(thermal_bridge_width 0.5)
				(island_removal_mode 0)
			)
			(polygon
				(pts
					(xy 196.088 1.27) (xy 196.088 1.778) (xy 195.707 1.778) (xy 195.707 1.27)
				)
			)
		)
	)
	(footprint ""
		(layer "B.Cu")
		(at 470.027 -62.484 -90)
		(property "Reference" "R1R16"
			(at 0 0 90)
			(layer "B.SilkS")
			(hide yes)
			(effects
				(font
					(size 1.27 1.27)
				)
				(justify mirror)
			)
		)
		(property "Value" ""
			(at 0 0 90)
			(layer "B.Fab")
			(effects
				(font
					(size 1.27 1.27)
				)
				(justify mirror)
			)
		)
		(duplicate_pad_numbers_are_jumpers no)
		(fp_poly
			(pts
				(xy 0.2794 -0.1016) (xy -0.2794 -0.1016) (xy -0.2794 0.9906) (xy 0.2794 0.9906)
			)
			(stroke
				(width 0)
				(type default)
			)
			(fill no)
			(layer "B.CrtYd")
		)
		(fp_line
			(start -0.2794 0.9906)
			(end -0.2794 -0.1016)
			(stroke
				(width 0.1)
				(type default)
			)
			(layer "B.Fab")
		)
		(fp_line
			(start 0.2794 0.9906)
			(end -0.2794 0.9906)
			(stroke
				(width 0.1)
				(type default)
			)
			(layer "B.Fab")
		)
		(fp_line
			(start -0.2794 -0.1016)
			(end 0.2794 -0.1016)
			(stroke
				(width 0.1)
				(type default)
			)
			(layer "B.Fab")
		)
		(fp_line
			(start 0.2794 -0.1016)
			(end 0.2794 0.9906)
			(stroke
				(width 0.1)
				(type default)
			)
			(layer "B.Fab")
		)
		(pad "1" smd rect
			(at 0 0 90)
			(size 0.508 0.508)
			(layers "B.Cu" "B.Mask" "B.Paste")
			(net "P3V3_STBY")
		)
		(pad "2" smd rect
			(at 0 0.889 90)
			(size 0.508 0.508)
			(layers "B.Cu" "B.Mask" "B.Paste")
			(net "SMB_PCH_MEZZ_LOM2_SCL")
		)
		(zone
			(layer "B.Cu")
			(hatch none 0.5)
			(connect_pads
				(clearance 0)
			)
			(min_thickness 0.25)
			(keepout
				(tracks not_allowed)
				(vias allowed)
				(pads allowed)
				(copperpour not_allowed)
				(footprints allowed)
			)
			(placement
				(enabled no)
				(sheetname "")
			)
			(fill
				(thermal_gap 0.5)
				(thermal_bridge_width 0.5)
				(island_removal_mode 0)
			)
			(polygon
				(pts
					(xy 469.392 -62.23) (xy 469.392 -62.738) (xy 469.773 -62.738) (xy 469.773 -62.23)
				)
			)
		)
		(zone
			(layer "B.Cu")
			(hatch none 0.5)
			(connect_pads
				(clearance 0)
			)
			(min_thickness 0.25)
			(keepout
				(tracks allowed)
				(vias not_allowed)
				(pads allowed)
				(copperpour not_allowed)
				(footprints allowed)
			)
			(placement
				(enabled no)
				(sheetname "")
			)
			(fill
				(thermal_gap 0.5)
				(thermal_bridge_width 0.5)
				(island_removal_mode 0)
			)
			(polygon
				(pts
					(xy 469.773 -62.23) (xy 469.773 -62.738) (xy 469.392 -62.738) (xy 469.392 -62.23)
				)
			)
		)
	)
	(footprint ""
		(layer "B.Cu")
		(at 419.887146 -48.160432 90)
		(property "Reference" "R1T3"
			(at 0 0 90)
			(layer "B.SilkS")
			(hide yes)
			(effects
				(font
					(size 1.27 1.27)
				)
				(justify mirror)
			)
		)
		(property "Value" ""
			(at 0 0 90)
			(layer "B.Fab")
			(effects
				(font
					(size 1.27 1.27)
				)
				(justify mirror)
			)
		)
		(duplicate_pad_numbers_are_jumpers no)
		(fp_poly
			(pts
				(xy 0.2794 -0.1016) (xy -0.2794 -0.1016) (xy -0.2794 0.9906) (xy 0.2794 0.9906)
			)
			(stroke
				(width 0)
				(type default)
			)
			(fill no)
			(layer "B.CrtYd")
		)
		(fp_line
			(start 0.2794 -0.1016)
			(end 0.2794 0.9906)
			(stroke
				(width 0.1)
				(type default)
			)
			(layer "B.Fab")
		)
		(fp_line
			(start -0.2794 -0.1016)
			(end 0.2794 -0.1016)
			(stroke
				(width 0.1)
				(type default)
			)
			(layer "B.Fab")
		)
		(fp_line
			(start 0.2794 0.9906)
			(end -0.2794 0.9906)
			(stroke
				(width 0.1)
				(type default)
			)
			(layer "B.Fab")
		)
		(fp_line
			(start -0.2794 0.9906)
			(end -0.2794 -0.1016)
			(stroke
				(width 0.1)
				(type default)
			)
			(layer "B.Fab")
		)
		(pad "1" smd rect
			(at 0 0 270)
			(size 0.508 0.508)
			(layers "B.Cu" "B.Mask" "B.Paste")
			(net "P3V3_STBY")
		)
		(pad "2" smd rect
			(at 0 0.889 270)
			(size 0.508 0.508)
			(layers "B.Cu" "B.Mask" "B.Paste")
			(net "SMB_SLOTX24_STBY_LVC3_SDA_R")
		)
		(zone
			(layer "B.Cu")
			(hatch none 0.5)
			(connect_pads
				(clearance 0)
			)
			(min_thickness 0.25)
			(keepout
				(tracks allowed)
				(vias not_allowed)
				(pads allowed)
				(copperpour not_allowed)
				(footprints allowed)
			)
			(placement
				(enabled no)
				(sheetname "")
			)
			(fill
				(thermal_gap 0.5)
				(thermal_bridge_width 0.5)
				(island_removal_mode 0)
			)
			(polygon
				(pts
					(xy 420.141146 -48.414432) (xy 420.141146 -47.906432) (xy 420.522146 -47.906432) (xy 420.522146 -48.414432)
				)
			)
		)
		(zone
			(layer "B.Cu")
			(hatch none 0.5)
			(connect_pads
				(clearance 0)
			)
			(min_thickness 0.25)
			(keepout
				(tracks not_allowed)
				(vias allowed)
				(pads allowed)
				(copperpour not_allowed)
				(footprints allowed)
			)
			(placement
				(enabled no)
				(sheetname "")
			)
			(fill
				(thermal_gap 0.5)
				(thermal_bridge_width 0.5)
				(island_removal_mode 0)
			)
			(polygon
				(pts
					(xy 420.522146 -48.414432) (xy 420.522146 -47.906432) (xy 420.141146 -47.906432) (xy 420.141146 -48.414432)
				)
			)
		)
	)
	(footprint ""
		(layer "B.Cu")
		(at 266.104624 -68.184014 180)
		(property "Reference" "C5P39"
			(at 0 0 0)
			(layer "B.SilkS")
			(hide yes)
			(effects
				(font
					(size 1.27 1.27)
				)
				(justify mirror)
			)
		)
		(property "Value" ""
			(at 0 0 0)
			(layer "B.Fab")
			(effects
				(font
					(size 1.27 1.27)
				)
				(justify mirror)
			)
		)
		(duplicate_pad_numbers_are_jumpers no)
		(fp_poly
			(pts
				(xy 0.7239 -0.2159) (xy -0.7239 -0.2159) (xy -0.7239 1.9939) (xy 0.7239 1.9939)
			)
			(stroke
				(width 0)
				(type default)
			)
			(fill no)
			(layer "B.CrtYd")
		)
		(fp_line
			(start 0.7239 1.9939)
			(end -0.7239 1.9939)
			(stroke
				(width 0.1)
				(type default)
			)
			(layer "B.Fab")
		)
		(fp_line
			(start 0.7239 -0.2159)
			(end 0.7239 1.9939)
			(stroke
				(width 0.1)
				(type default)
			)
			(layer "B.Fab")
		)
		(fp_line
			(start -0.7239 1.9939)
			(end -0.7239 -0.2159)
			(stroke
				(width 0.1)
				(type default)
			)
			(layer "B.Fab")
		)
		(fp_line
			(start -0.7239 -0.2159)
			(end 0.7239 -0.2159)
			(stroke
				(width 0.1)
				(type default)
			)
			(layer "B.Fab")
		)
		(pad "1" smd rect
			(at 0 0)
			(size 1.27 1.016)
			(layers "B.Cu" "B.Mask" "B.Paste")
			(net "PVDDQ_ABC")
		)
		(pad "2" smd rect
			(at 0 1.778)
			(size 1.27 1.016)
			(layers "B.Cu" "B.Mask" "B.Paste")
			(net "GND")
		)
		(zone
			(layer "B.Cu")
			(hatch none 0.5)
			(connect_pads
				(clearance 0)
			)
			(min_thickness 0.25)
			(keepout
				(tracks not_allowed)
				(vias allowed)
				(pads allowed)
				(copperpour not_allowed)
				(footprints allowed)
			)
			(placement
				(enabled no)
				(sheetname "")
			)
			(fill
				(thermal_gap 0.5)
				(thermal_bridge_width 0.5)
				(island_removal_mode 0)
			)
			(polygon
				(pts
					(xy 265.469624 -68.692014) (xy 266.739624 -68.692014) (xy 266.739624 -69.454014) (xy 265.469624 -69.454014)
				)
			)
		)
	)
	(footprint ""
		(layer "B.Cu")
		(at 402.3995 -42.926 -90)
		(property "Reference" "R25W70"
			(at 0.8382 -0.67818 270)
			(unlocked yes)
			(layer "B.SilkS")
			(effects
				(font
					(size 0.4064 0.254)
					(thickness 0.1524)
				)
				(justify left mirror)
			)
		)
		(property "Value" ""
			(at 0 0 90)
			(layer "B.Fab")
			(effects
				(font
					(size 1.27 1.27)
				)
				(justify mirror)
			)
		)
		(duplicate_pad_numbers_are_jumpers no)
		(fp_poly
			(pts
				(xy 0.2794 -0.1016) (xy -0.2794 -0.1016) (xy -0.2794 0.9906) (xy 0.2794 0.9906)
			)
			(stroke
				(width 0)
				(type default)
			)
			(fill no)
			(layer "B.CrtYd")
		)
		(fp_line
			(start -0.2794 0.9906)
			(end -0.2794 -0.1016)
			(stroke
				(width 0.1)
				(type default)
			)
			(layer "B.Fab")
		)
		(fp_line
			(start 0.2794 0.9906)
			(end -0.2794 0.9906)
			(stroke
				(width 0.1)
				(type default)
			)
			(layer "B.Fab")
		)
		(fp_line
			(start -0.2794 -0.1016)
			(end 0.2794 -0.1016)
			(stroke
				(width 0.1)
				(type default)
			)
			(layer "B.Fab")
		)
		(fp_line
			(start 0.2794 -0.1016)
			(end 0.2794 0.9906)
			(stroke
				(width 0.1)
				(type default)
			)
			(layer "B.Fab")
		)
		(pad "1" smd rect
			(at 0 0 90)
			(size 0.508 0.508)
			(layers "B.Cu" "B.Mask" "B.Paste")
			(net "FM_CPU0_FIVR_FAULT_LVT3_R_N")
		)
		(pad "2" smd rect
			(at 0 0.889 90)
			(size 0.508 0.508)
			(layers "B.Cu" "B.Mask" "B.Paste")
			(net "FM_CPU0_FIVR_FAULT_LVT3_N")
		)
		(zone
			(layer "B.Cu")
			(hatch none 0.5)
			(connect_pads
				(clearance 0)
			)
			(min_thickness 0.25)
			(keepout
				(tracks not_allowed)
				(vias allowed)
				(pads allowed)
				(copperpour not_allowed)
				(footprints allowed)
			)
			(placement
				(enabled no)
				(sheetname "")
			)
			(fill
				(thermal_gap 0.5)
				(thermal_bridge_width 0.5)
				(island_removal_mode 0)
			)
			(polygon
				(pts
					(xy 401.7645 -42.672) (xy 401.7645 -43.18) (xy 402.1455 -43.18) (xy 402.1455 -42.672)
				)
			)
		)
		(zone
			(layer "B.Cu")
			(hatch none 0.5)
			(connect_pads
				(clearance 0)
			)
			(min_thickness 0.25)
			(keepout
				(tracks allowed)
				(vias not_allowed)
				(pads allowed)
				(copperpour not_allowed)
				(footprints allowed)
			)
			(placement
				(enabled no)
				(sheetname "")
			)
			(fill
				(thermal_gap 0.5)
				(thermal_bridge_width 0.5)
				(island_removal_mode 0)
			)
			(polygon
				(pts
					(xy 402.1455 -42.672) (xy 402.1455 -43.18) (xy 401.7645 -43.18) (xy 401.7645 -42.672)
				)
			)
		)
	)
	(footprint ""
		(layer "B.Cu")
		(at 485.0892 -128.2065 180)
		(property "Reference" "R1U20"
			(at 0 0 0)
			(layer "B.SilkS")
			(hide yes)
			(effects
				(font
					(size 1.27 1.27)
				)
				(justify mirror)
			)
		)
		(property "Value" ""
			(at 0 0 0)
			(layer "B.Fab")
			(effects
				(font
					(size 1.27 1.27)
				)
				(justify mirror)
			)
		)
		(duplicate_pad_numbers_are_jumpers no)
		(fp_poly
			(pts
				(xy 0.2794 -0.1016) (xy -0.2794 -0.1016) (xy -0.2794 0.9906) (xy 0.2794 0.9906)
			)
			(stroke
				(width 0)
				(type default)
			)
			(fill no)
			(layer "B.CrtYd")
		)
		(fp_line
			(start 0.2794 0.9906)
			(end -0.2794 0.9906)
			(stroke
				(width 0.1)
				(type default)
			)
			(layer "B.Fab")
		)
		(fp_line
			(start 0.2794 -0.1016)
			(end 0.2794 0.9906)
			(stroke
				(width 0.1)
				(type default)
			)
			(layer "B.Fab")
		)
		(fp_line
			(start -0.2794 0.9906)
			(end -0.2794 -0.1016)
			(stroke
				(width 0.1)
				(type default)
			)
			(layer "B.Fab")
		)
		(fp_line
			(start -0.2794 -0.1016)
			(end 0.2794 -0.1016)
			(stroke
				(width 0.1)
				(type default)
			)
			(layer "B.Fab")
		)
		(pad "1" smd rect
			(at 0 0)
			(size 0.508 0.508)
			(layers "B.Cu" "B.Mask" "B.Paste")
			(net "SMB_SMLINK0_STBY_LVC3_SDA")
		)
		(pad "2" smd rect
			(at 0 0.889)
			(size 0.508 0.508)
			(layers "B.Cu" "B.Mask" "B.Paste")
			(net "SMB_SPRINGVILLE_STBY_LVC3_SDA")
		)
		(zone
			(layer "B.Cu")
			(hatch none 0.5)
			(connect_pads
				(clearance 0)
			)
			(min_thickness 0.25)
			(keepout
				(tracks not_allowed)
				(vias allowed)
				(pads allowed)
				(copperpour not_allowed)
				(footprints allowed)
			)
			(placement
				(enabled no)
				(sheetname "")
			)
			(fill
				(thermal_gap 0.5)
				(thermal_bridge_width 0.5)
				(island_removal_mode 0)
			)
			(polygon
				(pts
					(xy 484.8352 -128.8415) (xy 485.3432 -128.8415) (xy 485.3432 -128.4605) (xy 484.8352 -128.4605)
				)
			)
		)
		(zone
			(layer "B.Cu")
			(hatch none 0.5)
			(connect_pads
				(clearance 0)
			)
			(min_thickness 0.25)
			(keepout
				(tracks allowed)
				(vias not_allowed)
				(pads allowed)
				(copperpour not_allowed)
				(footprints allowed)
			)
			(placement
				(enabled no)
				(sheetname "")
			)
			(fill
				(thermal_gap 0.5)
				(thermal_bridge_width 0.5)
				(island_removal_mode 0)
			)
			(polygon
				(pts
					(xy 484.8352 -128.4605) (xy 485.3432 -128.4605) (xy 485.3432 -128.8415) (xy 484.8352 -128.8415)
				)
			)
		)
	)
	(footprint ""
		(layer "B.Cu")
		(at 488.181396 -44.48556 -90)
		(property "Reference" "C1R18"
			(at 0 0 90)
			(layer "B.SilkS")
			(hide yes)
			(effects
				(font
					(size 1.27 1.27)
				)
				(justify mirror)
			)
		)
		(property "Value" ""
			(at 0 0 90)
			(layer "B.Fab")
			(effects
				(font
					(size 1.27 1.27)
				)
				(justify mirror)
			)
		)
		(duplicate_pad_numbers_are_jumpers no)
		(fp_poly
			(pts
				(xy -0.3048 -0.1016) (xy -0.3048 0.9906) (xy 0.3048 0.9906) (xy 0.3048 -0.1016)
			)
			(stroke
				(width 0)
				(type default)
			)
			(fill no)
			(layer "B.CrtYd")
		)
		(fp_line
			(start -0.3048 0.9906)
			(end -0.3048 -0.1016)
			(stroke
				(width 0.1)
				(type default)
			)
			(layer "B.Fab")
		)
		(fp_line
			(start 0.3048 0.9906)
			(end -0.3048 0.9906)
			(stroke
				(width 0.1)
				(type default)
			)
			(layer "B.Fab")
		)
		(fp_line
			(start -0.3048 -0.1016)
			(end 0.3048 -0.1016)
			(stroke
				(width 0.1)
				(type default)
			)
			(layer "B.Fab")
		)
		(fp_line
			(start 0.3048 -0.1016)
			(end 0.3048 0.9906)
			(stroke
				(width 0.1)
				(type default)
			)
			(layer "B.Fab")
		)
		(pad "1" smd rect
			(at 0 0 90)
			(size 0.508 0.508)
			(layers "B.Cu" "B.Mask" "B.Paste")
			(net "P0V9_LAN")
		)
		(pad "2" smd rect
			(at 0 0.889 90)
			(size 0.508 0.508)
			(layers "B.Cu" "B.Mask" "B.Paste")
			(net "GND")
		)
		(zone
			(layer "B.Cu")
			(hatch none 0.5)
			(connect_pads
				(clearance 0)
			)
			(min_thickness 0.25)
			(keepout
				(tracks not_allowed)
				(vias allowed)
				(pads allowed)
				(copperpour not_allowed)
				(footprints allowed)
			)
			(placement
				(enabled no)
				(sheetname "")
			)
			(fill
				(thermal_gap 0.5)
				(thermal_bridge_width 0.5)
				(island_removal_mode 0)
			)
			(polygon
				(pts
					(xy 487.546396 -44.23156) (xy 487.546396 -44.73956) (xy 487.927396 -44.73956) (xy 487.927396 -44.23156)
				)
			)
		)
		(zone
			(layer "B.Cu")
			(hatch none 0.5)
			(connect_pads
				(clearance 0)
			)
			(min_thickness 0.25)
			(keepout
				(tracks allowed)
				(vias not_allowed)
				(pads allowed)
				(copperpour not_allowed)
				(footprints allowed)
			)
			(placement
				(enabled no)
				(sheetname "")
			)
			(fill
				(thermal_gap 0.5)
				(thermal_bridge_width 0.5)
				(island_removal_mode 0)
			)
			(polygon
				(pts
					(xy 487.927396 -44.23156) (xy 487.927396 -44.73956) (xy 487.546396 -44.73956) (xy 487.546396 -44.23156)
				)
			)
		)
	)
	(footprint ""
		(layer "B.Cu")
		(at 449.172838 -155.848812 90)
		(property "Reference" "C25W100"
			(at 0.8382 -0.67818 90)
			(unlocked yes)
			(layer "B.SilkS")
			(effects
				(font
					(size 0.4064 0.254)
					(thickness 0.1524)
				)
				(justify left mirror)
			)
		)
		(property "Value" ""
			(at 0 0 90)
			(layer "B.Fab")
			(effects
				(font
					(size 1.27 1.27)
				)
				(justify mirror)
			)
		)
		(duplicate_pad_numbers_are_jumpers no)
		(fp_poly
			(pts
				(xy -0.3048 -0.1016) (xy -0.3048 0.9906) (xy 0.3048 0.9906) (xy 0.3048 -0.1016)
			)
			(stroke
				(width 0)
				(type default)
			)
			(fill no)
			(layer "B.CrtYd")
		)
		(fp_line
			(start 0.3048 -0.1016)
			(end 0.3048 0.9906)
			(stroke
				(width 0.1)
				(type default)
			)
			(layer "B.Fab")
		)
		(fp_line
			(start -0.3048 -0.1016)
			(end 0.3048 -0.1016)
			(stroke
				(width 0.1)
				(type default)
			)
			(layer "B.Fab")
		)
		(fp_line
			(start 0.3048 0.9906)
			(end -0.3048 0.9906)
			(stroke
				(width 0.1)
				(type default)
			)
			(layer "B.Fab")
		)
		(fp_line
			(start -0.3048 0.9906)
			(end -0.3048 -0.1016)
			(stroke
				(width 0.1)
				(type default)
			)
			(layer "B.Fab")
		)
		(pad "1" smd rect
			(at 0 0 270)
			(size 0.508 0.508)
			(layers "B.Cu" "B.Mask" "B.Paste")
			(net "P3V3_STBY")
		)
		(pad "2" smd rect
			(at 0 0.889 270)
			(size 0.508 0.508)
			(layers "B.Cu" "B.Mask" "B.Paste")
			(net "GND")
		)
		(zone
			(layer "B.Cu")
			(hatch none 0.5)
			(connect_pads
				(clearance 0)
			)
			(min_thickness 0.25)
			(keepout
				(tracks allowed)
				(vias not_allowed)
				(pads allowed)
				(copperpour not_allowed)
				(footprints allowed)
			)
			(placement
				(enabled no)
				(sheetname "")
			)
			(fill
				(thermal_gap 0.5)
				(thermal_bridge_width 0.5)
				(island_removal_mode 0)
			)
			(polygon
				(pts
					(xy 449.426838 -156.102812) (xy 449.426838 -155.594812) (xy 449.807838 -155.594812) (xy 449.807838 -156.102812)
				)
			)
		)
		(zone
			(layer "B.Cu")
			(hatch none 0.5)
			(connect_pads
				(clearance 0)
			)
			(min_thickness 0.25)
			(keepout
				(tracks not_allowed)
				(vias allowed)
				(pads allowed)
				(copperpour not_allowed)
				(footprints allowed)
			)
			(placement
				(enabled no)
				(sheetname "")
			)
			(fill
				(thermal_gap 0.5)
				(thermal_bridge_width 0.5)
				(island_removal_mode 0)
			)
			(polygon
				(pts
					(xy 449.807838 -156.102812) (xy 449.807838 -155.594812) (xy 449.426838 -155.594812) (xy 449.426838 -156.102812)
				)
			)
		)
	)
	(footprint ""
		(layer "B.Cu")
		(at 375.1072 -57.785 180)
		(property "Reference" "R3W10"
			(at 0.8382 -0.67818 180)
			(unlocked yes)
			(layer "B.SilkS")
			(effects
				(font
					(size 0.4064 0.254)
					(thickness 0.1524)
				)
				(justify left mirror)
			)
		)
		(property "Value" ""
			(at 0 0 0)
			(layer "B.Fab")
			(effects
				(font
					(size 1.27 1.27)
				)
				(justify mirror)
			)
		)
		(duplicate_pad_numbers_are_jumpers no)
		(fp_poly
			(pts
				(xy 0.2794 -0.1016) (xy -0.2794 -0.1016) (xy -0.2794 0.9906) (xy 0.2794 0.9906)
			)
			(stroke
				(width 0)
				(type default)
			)
			(fill no)
			(layer "B.CrtYd")
		)
		(fp_line
			(start 0.2794 0.9906)
			(end -0.2794 0.9906)
			(stroke
				(width 0.1)
				(type default)
			)
			(layer "B.Fab")
		)
		(fp_line
			(start 0.2794 -0.1016)
			(end 0.2794 0.9906)
			(stroke
				(width 0.1)
				(type default)
			)
			(layer "B.Fab")
		)
		(fp_line
			(start -0.2794 0.9906)
			(end -0.2794 -0.1016)
			(stroke
				(width 0.1)
				(type default)
			)
			(layer "B.Fab")
		)
		(fp_line
			(start -0.2794 -0.1016)
			(end 0.2794 -0.1016)
			(stroke
				(width 0.1)
				(type default)
			)
			(layer "B.Fab")
		)
		(pad "1" smd rect
			(at 0 0)
			(size 0.508 0.508)
			(layers "B.Cu" "B.Mask" "B.Paste")
			(net "PVCCIO_CPU0")
		)
		(pad "2" smd rect
			(at 0 0.889)
			(size 0.508 0.508)
			(layers "B.Cu" "B.Mask" "B.Paste")
			(net "P0V7_GTL2104_VREF_1")
		)
		(zone
			(layer "B.Cu")
			(hatch none 0.5)
			(connect_pads
				(clearance 0)
			)
			(min_thickness 0.25)
			(keepout
				(tracks not_allowed)
				(vias allowed)
				(pads allowed)
				(copperpour not_allowed)
				(footprints allowed)
			)
			(placement
				(enabled no)
				(sheetname "")
			)
			(fill
				(thermal_gap 0.5)
				(thermal_bridge_width 0.5)
				(island_removal_mode 0)
			)
			(polygon
				(pts
					(xy 374.8532 -58.42) (xy 375.3612 -58.42) (xy 375.3612 -58.039) (xy 374.8532 -58.039)
				)
			)
		)
		(zone
			(layer "B.Cu")
			(hatch none 0.5)
			(connect_pads
				(clearance 0)
			)
			(min_thickness 0.25)
			(keepout
				(tracks allowed)
				(vias not_allowed)
				(pads allowed)
				(copperpour not_allowed)
				(footprints allowed)
			)
			(placement
				(enabled no)
				(sheetname "")
			)
			(fill
				(thermal_gap 0.5)
				(thermal_bridge_width 0.5)
				(island_removal_mode 0)
			)
			(polygon
				(pts
					(xy 374.8532 -58.039) (xy 375.3612 -58.039) (xy 375.3612 -58.42) (xy 374.8532 -58.42)
				)
			)
		)
	)
	(footprint ""
		(layer "B.Cu")
		(at 500.1514 -140.8684)
		(property "Reference" "R6W38"
			(at 0.8382 -0.67818 0)
			(unlocked yes)
			(layer "B.SilkS")
			(effects
				(font
					(size 0.4064 0.254)
					(thickness 0.1524)
				)
				(justify left mirror)
			)
		)
		(property "Value" ""
			(at 0 0 0)
			(layer "B.Fab")
			(effects
				(font
					(size 1.27 1.27)
				)
				(justify mirror)
			)
		)
		(duplicate_pad_numbers_are_jumpers no)
		(fp_poly
			(pts
				(xy 0.2794 -0.1016) (xy -0.2794 -0.1016) (xy -0.2794 0.9906) (xy 0.2794 0.9906)
			)
			(stroke
				(width 0)
				(type default)
			)
			(fill no)
			(layer "B.CrtYd")
		)
		(fp_line
			(start -0.2794 -0.1016)
			(end 0.2794 -0.1016)
			(stroke
				(width 0.1)
				(type default)
			)
			(layer "B.Fab")
		)
		(fp_line
			(start -0.2794 0.9906)
			(end -0.2794 -0.1016)
			(stroke
				(width 0.1)
				(type default)
			)
			(layer "B.Fab")
		)
		(fp_line
			(start 0.2794 -0.1016)
			(end 0.2794 0.9906)
			(stroke
				(width 0.1)
				(type default)
			)
			(layer "B.Fab")
		)
		(fp_line
			(start 0.2794 0.9906)
			(end -0.2794 0.9906)
			(stroke
				(width 0.1)
				(type default)
			)
			(layer "B.Fab")
		)
		(pad "1" smd rect
			(at 0 0 180)
			(size 0.508 0.508)
			(layers "B.Cu" "B.Mask" "B.Paste")
			(net "DEBUG_CARD2_PRSNT")
		)
		(pad "2" smd rect
			(at 0 0.889 180)
			(size 0.508 0.508)
			(layers "B.Cu" "B.Mask" "B.Paste")
			(net "GND")
		)
		(zone
			(layer "B.Cu")
			(hatch none 0.5)
			(connect_pads
				(clearance 0)
			)
			(min_thickness 0.25)
			(keepout
				(tracks allowed)
				(vias not_allowed)
				(pads allowed)
				(copperpour not_allowed)
				(footprints allowed)
			)
			(placement
				(enabled no)
				(sheetname "")
			)
			(fill
				(thermal_gap 0.5)
				(thermal_bridge_width 0.5)
				(island_removal_mode 0)
			)
			(polygon
				(pts
					(xy 500.4054 -140.6144) (xy 499.8974 -140.6144) (xy 499.8974 -140.2334) (xy 500.4054 -140.2334)
				)
			)
		)
		(zone
			(layer "B.Cu")
			(hatch none 0.5)
			(connect_pads
				(clearance 0)
			)
			(min_thickness 0.25)
			(keepout
				(tracks not_allowed)
				(vias allowed)
				(pads allowed)
				(copperpour not_allowed)
				(footprints allowed)
			)
			(placement
				(enabled no)
				(sheetname "")
			)
			(fill
				(thermal_gap 0.5)
				(thermal_bridge_width 0.5)
				(island_removal_mode 0)
			)
			(polygon
				(pts
					(xy 500.4054 -140.2334) (xy 499.8974 -140.2334) (xy 499.8974 -140.6144) (xy 500.4054 -140.6144)
				)
			)
		)
	)
	(footprint ""
		(layer "B.Cu")
		(at 409.23845 -122.216418)
		(property "Reference" "C2M8"
			(at 0 0 0)
			(layer "B.SilkS")
			(hide yes)
			(effects
				(font
					(size 1.27 1.27)
				)
				(justify mirror)
			)
		)
		(property "Value" ""
			(at 0 0 0)
			(layer "B.Fab")
			(effects
				(font
					(size 1.27 1.27)
				)
				(justify mirror)
			)
		)
		(duplicate_pad_numbers_are_jumpers no)
		(fp_poly
			(pts
				(xy -0.3048 -0.1016) (xy -0.3048 0.9906) (xy 0.3048 0.9906) (xy 0.3048 -0.1016)
			)
			(stroke
				(width 0)
				(type default)
			)
			(fill no)
			(layer "B.CrtYd")
		)
		(fp_line
			(start -0.3048 -0.1016)
			(end 0.3048 -0.1016)
			(stroke
				(width 0.1)
				(type default)
			)
			(layer "B.Fab")
		)
		(fp_line
			(start -0.3048 0.9906)
			(end -0.3048 -0.1016)
			(stroke
				(width 0.1)
				(type default)
			)
			(layer "B.Fab")
		)
		(fp_line
			(start 0.3048 -0.1016)
			(end 0.3048 0.9906)
			(stroke
				(width 0.1)
				(type default)
			)
			(layer "B.Fab")
		)
		(fp_line
			(start 0.3048 0.9906)
			(end -0.3048 0.9906)
			(stroke
				(width 0.1)
				(type default)
			)
			(layer "B.Fab")
		)
		(pad "1" smd rect
			(at 0 0 180)
			(size 0.508 0.508)
			(layers "B.Cu" "B.Mask" "B.Paste")
			(net "P1V05_PCH_STBY")
		)
		(pad "2" smd rect
			(at 0 0.889 180)
			(size 0.508 0.508)
			(layers "B.Cu" "B.Mask" "B.Paste")
			(net "GND")
		)
		(zone
			(layer "B.Cu")
			(hatch none 0.5)
			(connect_pads
				(clearance 0)
			)
			(min_thickness 0.25)
			(keepout
				(tracks allowed)
				(vias not_allowed)
				(pads allowed)
				(copperpour not_allowed)
				(footprints allowed)
			)
			(placement
				(enabled no)
				(sheetname "")
			)
			(fill
				(thermal_gap 0.5)
				(thermal_bridge_width 0.5)
				(island_removal_mode 0)
			)
			(polygon
				(pts
					(xy 409.49245 -121.962418) (xy 408.98445 -121.962418) (xy 408.98445 -121.581418) (xy 409.49245 -121.581418)
				)
			)
		)
		(zone
			(layer "B.Cu")
			(hatch none 0.5)
			(connect_pads
				(clearance 0)
			)
			(min_thickness 0.25)
			(keepout
				(tracks not_allowed)
				(vias allowed)
				(pads allowed)
				(copperpour not_allowed)
				(footprints allowed)
			)
			(placement
				(enabled no)
				(sheetname "")
			)
			(fill
				(thermal_gap 0.5)
				(thermal_bridge_width 0.5)
				(island_removal_mode 0)
			)
			(polygon
				(pts
					(xy 409.49245 -121.581418) (xy 408.98445 -121.581418) (xy 408.98445 -121.962418) (xy 409.49245 -121.962418)
				)
			)
		)
	)
	(footprint ""
		(layer "B.Cu")
		(at 470.027 -59.436 -90)
		(property "Reference" "R1W44"
			(at 0.8382 -0.67818 270)
			(unlocked yes)
			(layer "B.SilkS")
			(effects
				(font
					(size 0.4064 0.254)
					(thickness 0.1524)
				)
				(justify left mirror)
			)
		)
		(property "Value" ""
			(at 0 0 90)
			(layer "B.Fab")
			(effects
				(font
					(size 1.27 1.27)
				)
				(justify mirror)
			)
		)
		(duplicate_pad_numbers_are_jumpers no)
		(fp_poly
			(pts
				(xy 0.2794 -0.1016) (xy -0.2794 -0.1016) (xy -0.2794 0.9906) (xy 0.2794 0.9906)
			)
			(stroke
				(width 0)
				(type default)
			)
			(fill no)
			(layer "B.CrtYd")
		)
		(fp_line
			(start -0.2794 0.9906)
			(end -0.2794 -0.1016)
			(stroke
				(width 0.1)
				(type default)
			)
			(layer "B.Fab")
		)
		(fp_line
			(start 0.2794 0.9906)
			(end -0.2794 0.9906)
			(stroke
				(width 0.1)
				(type default)
			)
			(layer "B.Fab")
		)
		(fp_line
			(start -0.2794 -0.1016)
			(end 0.2794 -0.1016)
			(stroke
				(width 0.1)
				(type default)
			)
			(layer "B.Fab")
		)
		(fp_line
			(start 0.2794 -0.1016)
			(end 0.2794 0.9906)
			(stroke
				(width 0.1)
				(type default)
			)
			(layer "B.Fab")
		)
		(pad "1" smd rect
			(at 0 0 90)
			(size 0.508 0.508)
			(layers "B.Cu" "B.Mask" "B.Paste")
			(net "P3V3_STBY")
		)
		(pad "2" smd rect
			(at 0 0.889 90)
			(size 0.508 0.508)
			(layers "B.Cu" "B.Mask" "B.Paste")
			(net "FM_GBE2_LVC3_MOD_ABS")
		)
		(zone
			(layer "B.Cu")
			(hatch none 0.5)
			(connect_pads
				(clearance 0)
			)
			(min_thickness 0.25)
			(keepout
				(tracks not_allowed)
				(vias allowed)
				(pads allowed)
				(copperpour not_allowed)
				(footprints allowed)
			)
			(placement
				(enabled no)
				(sheetname "")
			)
			(fill
				(thermal_gap 0.5)
				(thermal_bridge_width 0.5)
				(island_removal_mode 0)
			)
			(polygon
				(pts
					(xy 469.392 -59.182) (xy 469.392 -59.69) (xy 469.773 -59.69) (xy 469.773 -59.182)
				)
			)
		)
		(zone
			(layer "B.Cu")
			(hatch none 0.5)
			(connect_pads
				(clearance 0)
			)
			(min_thickness 0.25)
			(keepout
				(tracks allowed)
				(vias not_allowed)
				(pads allowed)
				(copperpour not_allowed)
				(footprints allowed)
			)
			(placement
				(enabled no)
				(sheetname "")
			)
			(fill
				(thermal_gap 0.5)
				(thermal_bridge_width 0.5)
				(island_removal_mode 0)
			)
			(polygon
				(pts
					(xy 469.773 -59.182) (xy 469.773 -59.69) (xy 469.392 -59.69) (xy 469.392 -59.182)
				)
			)
		)
	)
	(footprint ""
		(layer "B.Cu")
		(at 120.65 -31.115)
		(property "Reference" ""
			(at 0 0 0)
			(layer "B.SilkS")
			(hide yes)
			(effects
				(font
					(size 1.27 1.27)
				)
				(justify mirror)
			)
		)
		(property "Value" ""
			(at 0 0 0)
			(layer "B.Fab")
			(effects
				(font
					(size 1.27 1.27)
				)
				(justify mirror)
			)
		)
		(duplicate_pad_numbers_are_jumpers no)
		(fp_poly
			(pts
				(arc
					(start 2.032 0)
					(mid -2.032 0)
					(end 2.032 0)
				)
			)
			(stroke
				(width 0)
				(type default)
			)
			(fill no)
			(layer "B.CrtYd")
		)
		(pad "1" smd circle
			(at 0 0 180)
			(size 1.016 1.016)
			(layers "B.Cu" "B.Mask" "B.Paste")
			(net "Net_388")
		)
		(zone
			(layers "F.Cu" "B.Cu" "In1.Cu" "In2.Cu" "In3.Cu" "In4.Cu" "In5.Cu" "In6.Cu"
				"In7.Cu" "In8.Cu" "In9.Cu" "In10.Cu" "In11.Cu" "In12.Cu"
			)
			(hatch none 0.5)
			(connect_pads
				(clearance 0)
			)
			(min_thickness 0.25)
			(keepout
				(tracks allowed)
				(vias not_allowed)
				(pads allowed)
				(copperpour not_allowed)
				(footprints allowed)
			)
			(placement
				(enabled no)
				(sheetname "")
			)
			(fill
				(thermal_gap 0.5)
				(thermal_bridge_width 0.5)
				(island_removal_mode 0)
			)
			(polygon
				(pts
					(arc
						(start 122.174 -31.115)
						(mid 119.126 -31.115)
						(end 122.174 -31.115)
					)
				)
			)
		)
		(zone
			(layer "B.Cu")
			(hatch none 0.5)
			(connect_pads
				(clearance 0)
			)
			(min_thickness 0.25)
			(keepout
				(tracks not_allowed)
				(vias allowed)
				(pads allowed)
				(copperpour not_allowed)
				(footprints allowed)
			)
			(placement
				(enabled no)
				(sheetname "")
			)
			(fill
				(thermal_gap 0.5)
				(thermal_bridge_width 0.5)
				(island_removal_mode 0)
			)
			(polygon
				(pts
					(arc
						(start 122.174 -31.115)
						(mid 119.126 -31.115)
						(end 122.174 -31.115)
					)
				)
			)
		)
	)
	(footprint ""
		(layer "B.Cu")
		(at 227.584 -90.297 90)
		(property "Reference" "R5N5"
			(at 0 0 90)
			(layer "B.SilkS")
			(hide yes)
			(effects
				(font
					(size 1.27 1.27)
				)
				(justify mirror)
			)
		)
		(property "Value" ""
			(at 0 0 90)
			(layer "B.Fab")
			(effects
				(font
					(size 1.27 1.27)
				)
				(justify mirror)
			)
		)
		(duplicate_pad_numbers_are_jumpers no)
		(fp_poly
			(pts
				(xy 0.2794 -0.1016) (xy -0.2794 -0.1016) (xy -0.2794 0.9906) (xy 0.2794 0.9906)
			)
			(stroke
				(width 0)
				(type default)
			)
			(fill no)
			(layer "B.CrtYd")
		)
		(fp_line
			(start 0.2794 -0.1016)
			(end 0.2794 0.9906)
			(stroke
				(width 0.1)
				(type default)
			)
			(layer "B.Fab")
		)
		(fp_line
			(start -0.2794 -0.1016)
			(end 0.2794 -0.1016)
			(stroke
				(width 0.1)
				(type default)
			)
			(layer "B.Fab")
		)
		(fp_line
			(start 0.2794 0.9906)
			(end -0.2794 0.9906)
			(stroke
				(width 0.1)
				(type default)
			)
			(layer "B.Fab")
		)
		(fp_line
			(start -0.2794 0.9906)
			(end -0.2794 -0.1016)
			(stroke
				(width 0.1)
				(type default)
			)
			(layer "B.Fab")
		)
		(pad "1" smd rect
			(at 0 0 270)
			(size 0.508 0.508)
			(layers "B.Cu" "B.Mask" "B.Paste")
			(net "P3V3_STBY")
		)
		(pad "2" smd rect
			(at 0 0.889 270)
			(size 0.508 0.508)
			(layers "B.Cu" "B.Mask" "B.Paste")
			(net "FM_CPU0_PKGID1")
		)
		(zone
			(layer "B.Cu")
			(hatch none 0.5)
			(connect_pads
				(clearance 0)
			)
			(min_thickness 0.25)
			(keepout
				(tracks allowed)
				(vias not_allowed)
				(pads allowed)
				(copperpour not_allowed)
				(footprints allowed)
			)
			(placement
				(enabled no)
				(sheetname "")
			)
			(fill
				(thermal_gap 0.5)
				(thermal_bridge_width 0.5)
				(island_removal_mode 0)
			)
			(polygon
				(pts
					(xy 227.838 -90.551) (xy 227.838 -90.043) (xy 228.219 -90.043) (xy 228.219 -90.551)
				)
			)
		)
		(zone
			(layer "B.Cu")
			(hatch none 0.5)
			(connect_pads
				(clearance 0)
			)
			(min_thickness 0.25)
			(keepout
				(tracks not_allowed)
				(vias allowed)
				(pads allowed)
				(copperpour not_allowed)
				(footprints allowed)
			)
			(placement
				(enabled no)
				(sheetname "")
			)
			(fill
				(thermal_gap 0.5)
				(thermal_bridge_width 0.5)
				(island_removal_mode 0)
			)
			(polygon
				(pts
					(xy 228.219 -90.551) (xy 228.219 -90.043) (xy 227.838 -90.043) (xy 227.838 -90.551)
				)
			)
		)
	)
	(footprint ""
		(layer "B.Cu")
		(at 256.853436 -157.016958 90)
		(property "Reference" "C5L4"
			(at -1.47828 0.78994 180)
			(unlocked yes)
			(layer "B.SilkS")
			(effects
				(font
					(size 0.4064 0.254)
					(thickness 0.1524)
				)
				(justify mirror)
			)
		)
		(property "Value" ""
			(at 0 0 90)
			(layer "B.Fab")
			(effects
				(font
					(size 1.27 1.27)
				)
				(justify mirror)
			)
		)
		(duplicate_pad_numbers_are_jumpers no)
		(fp_poly
			(pts
				(xy 0.7239 -0.2159) (xy -0.7239 -0.2159) (xy -0.7239 1.9939) (xy 0.7239 1.9939)
			)
			(stroke
				(width 0)
				(type default)
			)
			(fill no)
			(layer "B.CrtYd")
		)
		(fp_line
			(start 0.7239 -0.2159)
			(end 0.7239 1.9939)
			(stroke
				(width 0.1)
				(type default)
			)
			(layer "B.Fab")
		)
		(fp_line
			(start -0.7239 -0.2159)
			(end 0.7239 -0.2159)
			(stroke
				(width 0.1)
				(type default)
			)
			(layer "B.Fab")
		)
		(fp_line
			(start 0.7239 1.9939)
			(end -0.7239 1.9939)
			(stroke
				(width 0.1)
				(type default)
			)
			(layer "B.Fab")
		)
		(fp_line
			(start -0.7239 1.9939)
			(end -0.7239 -0.2159)
			(stroke
				(width 0.1)
				(type default)
			)
			(layer "B.Fab")
		)
		(pad "1" smd rect
			(at 0 0 270)
			(size 1.27 1.016)
			(layers "B.Cu" "B.Mask" "B.Paste")
			(net "PVTT_DEF")
		)
		(pad "2" smd rect
			(at 0 1.778 270)
			(size 1.27 1.016)
			(layers "B.Cu" "B.Mask" "B.Paste")
			(net "GND")
		)
		(zone
			(layer "B.Cu")
			(hatch none 0.5)
			(connect_pads
				(clearance 0)
			)
			(min_thickness 0.25)
			(keepout
				(tracks not_allowed)
				(vias allowed)
				(pads allowed)
				(copperpour not_allowed)
				(footprints allowed)
			)
			(placement
				(enabled no)
				(sheetname "")
			)
			(fill
				(thermal_gap 0.5)
				(thermal_bridge_width 0.5)
				(island_removal_mode 0)
			)
			(polygon
				(pts
					(xy 257.361436 -157.651958) (xy 257.361436 -156.381958) (xy 258.123436 -156.381958) (xy 258.123436 -157.651958)
				)
			)
		)
	)
	(footprint ""
		(layer "B.Cu")
		(at 361.782614 -125.558042 -90)
		(property "Reference" "R781"
			(at 0.8382 -0.67818 270)
			(unlocked yes)
			(layer "B.SilkS")
			(effects
				(font
					(size 0.4064 0.254)
					(thickness 0.1524)
				)
				(justify left mirror)
			)
		)
		(property "Value" ""
			(at 0 0 90)
			(layer "B.Fab")
			(effects
				(font
					(size 1.27 1.27)
				)
				(justify mirror)
			)
		)
		(duplicate_pad_numbers_are_jumpers no)
		(fp_poly
			(pts
				(xy 0.2794 -0.1016) (xy -0.2794 -0.1016) (xy -0.2794 0.9906) (xy 0.2794 0.9906)
			)
			(stroke
				(width 0)
				(type default)
			)
			(fill no)
			(layer "B.CrtYd")
		)
		(fp_line
			(start -0.2794 0.9906)
			(end -0.2794 -0.1016)
			(stroke
				(width 0.1)
				(type default)
			)
			(layer "B.Fab")
		)
		(fp_line
			(start 0.2794 0.9906)
			(end -0.2794 0.9906)
			(stroke
				(width 0.1)
				(type default)
			)
			(layer "B.Fab")
		)
		(fp_line
			(start -0.2794 -0.1016)
			(end 0.2794 -0.1016)
			(stroke
				(width 0.1)
				(type default)
			)
			(layer "B.Fab")
		)
		(fp_line
			(start 0.2794 -0.1016)
			(end 0.2794 0.9906)
			(stroke
				(width 0.1)
				(type default)
			)
			(layer "B.Fab")
		)
		(pad "1" smd rect
			(at 0 0 90)
			(size 0.508 0.508)
			(layers "B.Cu" "B.Mask" "B.Paste")
			(net "P3E_CPU0_PE1_PCH_RXP<10>")
		)
		(pad "2" smd rect
			(at 0 0.889 90)
			(size 0.508 0.508)
			(layers "B.Cu" "B.Mask" "B.Paste")
			(net "P3E_CPU0_PE1_PCH_CON_RXP<10>")
		)
		(zone
			(layer "B.Cu")
			(hatch none 0.5)
			(connect_pads
				(clearance 0)
			)
			(min_thickness 0.25)
			(keepout
				(tracks not_allowed)
				(vias allowed)
				(pads allowed)
				(copperpour not_allowed)
				(footprints allowed)
			)
			(placement
				(enabled no)
				(sheetname "")
			)
			(fill
				(thermal_gap 0.5)
				(thermal_bridge_width 0.5)
				(island_removal_mode 0)
			)
			(polygon
				(pts
					(xy 361.147614 -125.304042) (xy 361.147614 -125.812042) (xy 361.528614 -125.812042) (xy 361.528614 -125.304042)
				)
			)
		)
		(zone
			(layer "B.Cu")
			(hatch none 0.5)
			(connect_pads
				(clearance 0)
			)
			(min_thickness 0.25)
			(keepout
				(tracks allowed)
				(vias not_allowed)
				(pads allowed)
				(copperpour not_allowed)
				(footprints allowed)
			)
			(placement
				(enabled no)
				(sheetname "")
			)
			(fill
				(thermal_gap 0.5)
				(thermal_bridge_width 0.5)
				(island_removal_mode 0)
			)
			(polygon
				(pts
					(xy 361.528614 -125.304042) (xy 361.528614 -125.812042) (xy 361.147614 -125.812042) (xy 361.147614 -125.304042)
				)
			)
		)
	)
	(footprint ""
		(layer "B.Cu")
		(at 197.848728 -74.506582 90)
		(property "Reference" "C6P19"
			(at 0 0 90)
			(layer "B.SilkS")
			(hide yes)
			(effects
				(font
					(size 1.27 1.27)
				)
				(justify mirror)
			)
		)
		(property "Value" ""
			(at 0 0 90)
			(layer "B.Fab")
			(effects
				(font
					(size 1.27 1.27)
				)
				(justify mirror)
			)
		)
		(duplicate_pad_numbers_are_jumpers no)
		(fp_rect
			(start 0.7239 1.9939)
			(end -0.7239 -0.2159)
			(stroke
				(width 0)
				(type default)
			)
			(fill no)
			(layer "B.CrtYd")
		)
		(fp_line
			(start 0.7239 -0.2159)
			(end 0.7239 1.9939)
			(stroke
				(width 0.1)
				(type default)
			)
			(layer "B.Fab")
		)
		(fp_line
			(start -0.7239 -0.2159)
			(end 0.7239 -0.2159)
			(stroke
				(width 0.1)
				(type default)
			)
			(layer "B.Fab")
		)
		(fp_line
			(start 0.7239 1.9939)
			(end -0.7239 1.9939)
			(stroke
				(width 0.1)
				(type default)
			)
			(layer "B.Fab")
		)
		(fp_line
			(start -0.7239 1.9939)
			(end -0.7239 -0.2159)
			(stroke
				(width 0.1)
				(type default)
			)
			(layer "B.Fab")
		)
		(pad "1" smd rect
			(at 0 0 270)
			(size 1.27 1.016)
			(layers "B.Cu" "B.Mask" "B.Paste")
			(net "VR_FET_SW_P12V_STBY_PVCCIN_CPU0")
		)
		(pad "2" smd rect
			(at 0 1.778 270)
			(size 1.27 1.016)
			(layers "B.Cu" "B.Mask" "B.Paste")
			(net "GND")
		)
		(zone
			(layer "B.Cu")
			(hatch none 0.5)
			(connect_pads
				(clearance 0)
			)
			(min_thickness 0.25)
			(keepout
				(tracks not_allowed)
				(vias allowed)
				(pads allowed)
				(copperpour not_allowed)
				(footprints allowed)
			)
			(placement
				(enabled no)
				(sheetname "")
			)
			(fill
				(thermal_gap 0.5)
				(thermal_bridge_width 0.5)
				(island_removal_mode 0)
			)
			(polygon
				(pts
					(xy 199.118728 -75.141582) (xy 198.356728 -75.141582) (xy 198.356728 -73.871582) (xy 199.118728 -73.871582)
				)
			)
		)
	)
	(footprint ""
		(layer "B.Cu")
		(at 489.189014 -153.924 90)
		(property "Reference" "U1L2"
			(at -2.633726 2.058416 270)
			(unlocked yes)
			(layer "B.SilkS")
			(effects
				(font
					(size 0.7874 0.5842)
					(thickness 0.1524)
				)
				(justify left mirror)
			)
		)
		(property "Value" ""
			(at 0 0 90)
			(layer "B.Fab")
			(effects
				(font
					(size 1.27 1.27)
				)
				(justify mirror)
			)
		)
		(duplicate_pad_numbers_are_jumpers no)
		(fp_circle
			(center 0.4699 -0.8382)
			(end 0.4699 -0.7112)
			(stroke
				(width 0.254)
				(type default)
			)
			(fill no)
			(layer "B.SilkS")
		)
		(fp_poly
			(pts
				(xy -0.21463 -0.450088) (xy -1.56337 -0.450088) (xy -1.56337 1.75006) (xy -0.21463 1.75006)
			)
			(stroke
				(width 0)
				(type default)
			)
			(fill no)
			(layer "B.CrtYd")
		)
		(fp_line
			(start -0.21463 -0.450088)
			(end -1.56337 -0.450088)
			(stroke
				(width 0.1)
				(type default)
			)
			(layer "B.Fab")
		)
		(fp_line
			(start -1.56337 -0.450088)
			(end -1.56337 1.75006)
			(stroke
				(width 0.1)
				(type default)
			)
			(layer "B.Fab")
		)
		(fp_line
			(start -0.21463 1.75006)
			(end -0.21463 -0.450088)
			(stroke
				(width 0.1)
				(type default)
			)
			(layer "B.Fab")
		)
		(fp_line
			(start -1.56337 1.75006)
			(end -0.21463 1.75006)
			(stroke
				(width 0.1)
				(type default)
			)
			(layer "B.Fab")
		)
		(fp_circle
			(center 0.4699 -0.8382)
			(end 0.4699 -0.7112)
			(stroke
				(width 0.254)
				(type default)
			)
			(fill no)
			(layer "B.Fab")
		)
		(pad "1" smd rect
			(at 0 0 270)
			(size 1.016 0.381)
			(layers "B.Cu" "B.Mask" "B.Paste")
			(net "PWRGD_P3V3_R")
		)
		(pad "2" smd rect
			(at 0 0.649986 270)
			(size 1.016 0.381)
			(layers "B.Cu" "B.Mask" "B.Paste")
			(net "FP_PWR_ID_LED_N")
		)
		(pad "3" smd rect
			(at 0 1.299972 270)
			(size 1.016 0.381)
			(layers "B.Cu" "B.Mask" "B.Paste")
			(net "GND")
		)
		(pad "4" smd rect
			(at -1.778 1.299972 270)
			(size 1.016 0.381)
			(layers "B.Cu" "B.Mask" "B.Paste")
			(net "FP_ID_LED_P5V_STBY_N")
		)
		(pad "5" smd rect
			(at -1.778 0 270)
			(size 1.016 0.381)
			(layers "B.Cu" "B.Mask" "B.Paste")
			(net "P5V_STBY")
		)
	)
	(footprint ""
		(layer "B.Cu")
		(at 80.731868 -140.208 -90)
		(property "Reference" "C5G114"
			(at -1.14681 0.76708 0)
			(unlocked yes)
			(layer "B.SilkS")
			(effects
				(font
					(size 0.7874 0.5842)
					(thickness 0.1524)
				)
				(justify mirror)
			)
		)
		(property "Value" ""
			(at 0 0 90)
			(layer "B.Fab")
			(effects
				(font
					(size 1.27 1.27)
				)
				(justify mirror)
			)
		)
		(duplicate_pad_numbers_are_jumpers no)
		(fp_rect
			(start 0.4953 1.6002)
			(end -0.4953 -0.2032)
			(stroke
				(width 0)
				(type default)
			)
			(fill no)
			(layer "B.CrtYd")
		)
		(fp_line
			(start -0.4953 1.6002)
			(end 0.4953 1.6002)
			(stroke
				(width 0.1)
				(type default)
			)
			(layer "B.Fab")
		)
		(fp_line
			(start 0.4953 1.6002)
			(end 0.4953 -0.2032)
			(stroke
				(width 0.1)
				(type default)
			)
			(layer "B.Fab")
		)
		(fp_line
			(start -0.4953 -0.2032)
			(end -0.4953 1.6002)
			(stroke
				(width 0.1)
				(type default)
			)
			(layer "B.Fab")
		)
		(fp_line
			(start 0.4953 -0.2032)
			(end -0.4953 -0.2032)
			(stroke
				(width 0.1)
				(type default)
			)
			(layer "B.Fab")
		)
		(pad "1" smd rect
			(at 0 0 90)
			(size 0.762 0.889)
			(layers "B.Cu" "B.Mask" "B.Paste")
			(net "PVDDQ_KLM")
		)
		(pad "2" smd rect
			(at 0 1.397 90)
			(size 0.762 0.889)
			(layers "B.Cu" "B.Mask" "B.Paste")
			(net "GND")
		)
		(zone
			(layer "B.Cu")
			(hatch none 0.5)
			(connect_pads
				(clearance 0)
			)
			(min_thickness 0.25)
			(keepout
				(tracks not_allowed)
				(vias allowed)
				(pads allowed)
				(copperpour not_allowed)
				(footprints allowed)
			)
			(placement
				(enabled no)
				(sheetname "")
			)
			(fill
				(thermal_gap 0.5)
				(thermal_bridge_width 0.5)
				(island_removal_mode 0)
			)
			(polygon
				(pts
					(xy 79.779368 -139.827) (xy 80.287368 -139.827) (xy 80.287368 -140.589) (xy 79.779368 -140.589)
				)
			)
		)
	)
	(footprint ""
		(layer "B.Cu")
		(at 422.2242 -83.1342 -90)
		(property "Reference" "R2P11"
			(at 0 0 90)
			(layer "B.SilkS")
			(hide yes)
			(effects
				(font
					(size 1.27 1.27)
				)
				(justify mirror)
			)
		)
		(property "Value" ""
			(at 0 0 90)
			(layer "B.Fab")
			(effects
				(font
					(size 1.27 1.27)
				)
				(justify mirror)
			)
		)
		(duplicate_pad_numbers_are_jumpers no)
		(fp_poly
			(pts
				(xy 0.2794 -0.1016) (xy -0.2794 -0.1016) (xy -0.2794 0.9906) (xy 0.2794 0.9906)
			)
			(stroke
				(width 0)
				(type default)
			)
			(fill no)
			(layer "B.CrtYd")
		)
		(fp_line
			(start -0.2794 0.9906)
			(end -0.2794 -0.1016)
			(stroke
				(width 0.1)
				(type default)
			)
			(layer "B.Fab")
		)
		(fp_line
			(start 0.2794 0.9906)
			(end -0.2794 0.9906)
			(stroke
				(width 0.1)
				(type default)
			)
			(layer "B.Fab")
		)
		(fp_line
			(start -0.2794 -0.1016)
			(end 0.2794 -0.1016)
			(stroke
				(width 0.1)
				(type default)
			)
			(layer "B.Fab")
		)
		(fp_line
			(start 0.2794 -0.1016)
			(end 0.2794 0.9906)
			(stroke
				(width 0.1)
				(type default)
			)
			(layer "B.Fab")
		)
		(pad "1" smd rect
			(at 0 0 90)
			(size 0.508 0.508)
			(layers "B.Cu" "B.Mask" "B.Paste")
			(net "FM_PMBUS_ALERT_BUF_EN_N")
		)
		(pad "2" smd rect
			(at 0 0.889 90)
			(size 0.508 0.508)
			(layers "B.Cu" "B.Mask" "B.Paste")
			(net "GND")
		)
		(zone
			(layer "B.Cu")
			(hatch none 0.5)
			(connect_pads
				(clearance 0)
			)
			(min_thickness 0.25)
			(keepout
				(tracks not_allowed)
				(vias allowed)
				(pads allowed)
				(copperpour not_allowed)
				(footprints allowed)
			)
			(placement
				(enabled no)
				(sheetname "")
			)
			(fill
				(thermal_gap 0.5)
				(thermal_bridge_width 0.5)
				(island_removal_mode 0)
			)
			(polygon
				(pts
					(xy 421.5892 -82.8802) (xy 421.5892 -83.3882) (xy 421.9702 -83.3882) (xy 421.9702 -82.8802)
				)
			)
		)
		(zone
			(layer "B.Cu")
			(hatch none 0.5)
			(connect_pads
				(clearance 0)
			)
			(min_thickness 0.25)
			(keepout
				(tracks allowed)
				(vias not_allowed)
				(pads allowed)
				(copperpour not_allowed)
				(footprints allowed)
			)
			(placement
				(enabled no)
				(sheetname "")
			)
			(fill
				(thermal_gap 0.5)
				(thermal_bridge_width 0.5)
				(island_removal_mode 0)
			)
			(polygon
				(pts
					(xy 421.9702 -82.8802) (xy 421.9702 -83.3882) (xy 421.5892 -83.3882) (xy 421.5892 -82.8802)
				)
			)
		)
	)
	(footprint ""
		(layer "B.Cu")
		(at 352.425 -108.4834)
		(property "Reference" "C3N40"
			(at 0 0 0)
			(layer "B.SilkS")
			(hide yes)
			(effects
				(font
					(size 1.27 1.27)
				)
				(justify mirror)
			)
		)
		(property "Value" ""
			(at 0 0 0)
			(layer "B.Fab")
			(effects
				(font
					(size 1.27 1.27)
				)
				(justify mirror)
			)
		)
		(duplicate_pad_numbers_are_jumpers no)
		(fp_poly
			(pts
				(xy -0.3048 -0.1016) (xy -0.3048 0.9906) (xy 0.3048 0.9906) (xy 0.3048 -0.1016)
			)
			(stroke
				(width 0)
				(type default)
			)
			(fill no)
			(layer "B.CrtYd")
		)
		(fp_line
			(start -0.3048 -0.1016)
			(end 0.3048 -0.1016)
			(stroke
				(width 0.1)
				(type default)
			)
			(layer "B.Fab")
		)
		(fp_line
			(start -0.3048 0.9906)
			(end -0.3048 -0.1016)
			(stroke
				(width 0.1)
				(type default)
			)
			(layer "B.Fab")
		)
		(fp_line
			(start 0.3048 -0.1016)
			(end 0.3048 0.9906)
			(stroke
				(width 0.1)
				(type default)
			)
			(layer "B.Fab")
		)
		(fp_line
			(start 0.3048 0.9906)
			(end -0.3048 0.9906)
			(stroke
				(width 0.1)
				(type default)
			)
			(layer "B.Fab")
		)
		(pad "1" smd rect
			(at 0 0 180)
			(size 0.508 0.508)
			(layers "B.Cu" "B.Mask" "B.Paste")
			(net "PVCCIOMCP_CPU0")
		)
		(pad "2" smd rect
			(at 0 0.889 180)
			(size 0.508 0.508)
			(layers "B.Cu" "B.Mask" "B.Paste")
			(net "GND")
		)
		(zone
			(layer "B.Cu")
			(hatch none 0.5)
			(connect_pads
				(clearance 0)
			)
			(min_thickness 0.25)
			(keepout
				(tracks allowed)
				(vias not_allowed)
				(pads allowed)
				(copperpour not_allowed)
				(footprints allowed)
			)
			(placement
				(enabled no)
				(sheetname "")
			)
			(fill
				(thermal_gap 0.5)
				(thermal_bridge_width 0.5)
				(island_removal_mode 0)
			)
			(polygon
				(pts
					(xy 352.679 -108.2294) (xy 352.171 -108.2294) (xy 352.171 -107.8484) (xy 352.679 -107.8484)
				)
			)
		)
		(zone
			(layer "B.Cu")
			(hatch none 0.5)
			(connect_pads
				(clearance 0)
			)
			(min_thickness 0.25)
			(keepout
				(tracks not_allowed)
				(vias allowed)
				(pads allowed)
				(copperpour not_allowed)
				(footprints allowed)
			)
			(placement
				(enabled no)
				(sheetname "")
			)
			(fill
				(thermal_gap 0.5)
				(thermal_bridge_width 0.5)
				(island_removal_mode 0)
			)
			(polygon
				(pts
					(xy 352.679 -107.8484) (xy 352.171 -107.8484) (xy 352.171 -108.2294) (xy 352.679 -108.2294)
				)
			)
		)
	)
	(footprint ""
		(layer "B.Cu")
		(at 470.027 -57.15 -90)
		(property "Reference" "R1R21"
			(at 0 0 90)
			(layer "B.SilkS")
			(hide yes)
			(effects
				(font
					(size 1.27 1.27)
				)
				(justify mirror)
			)
		)
		(property "Value" ""
			(at 0 0 90)
			(layer "B.Fab")
			(effects
				(font
					(size 1.27 1.27)
				)
				(justify mirror)
			)
		)
		(duplicate_pad_numbers_are_jumpers no)
		(fp_poly
			(pts
				(xy 0.2794 -0.1016) (xy -0.2794 -0.1016) (xy -0.2794 0.9906) (xy 0.2794 0.9906)
			)
			(stroke
				(width 0)
				(type default)
			)
			(fill no)
			(layer "B.CrtYd")
		)
		(fp_line
			(start -0.2794 0.9906)
			(end -0.2794 -0.1016)
			(stroke
				(width 0.1)
				(type default)
			)
			(layer "B.Fab")
		)
		(fp_line
			(start 0.2794 0.9906)
			(end -0.2794 0.9906)
			(stroke
				(width 0.1)
				(type default)
			)
			(layer "B.Fab")
		)
		(fp_line
			(start -0.2794 -0.1016)
			(end 0.2794 -0.1016)
			(stroke
				(width 0.1)
				(type default)
			)
			(layer "B.Fab")
		)
		(fp_line
			(start 0.2794 -0.1016)
			(end 0.2794 0.9906)
			(stroke
				(width 0.1)
				(type default)
			)
			(layer "B.Fab")
		)
		(pad "1" smd rect
			(at 0 0 90)
			(size 0.508 0.508)
			(layers "B.Cu" "B.Mask" "B.Paste")
			(net "P3V3_STBY")
		)
		(pad "2" smd rect
			(at 0 0.889 90)
			(size 0.508 0.508)
			(layers "B.Cu" "B.Mask" "B.Paste")
			(net "SMB_PCH_MEZZ_LOM1_SDA")
		)
		(zone
			(layer "B.Cu")
			(hatch none 0.5)
			(connect_pads
				(clearance 0)
			)
			(min_thickness 0.25)
			(keepout
				(tracks not_allowed)
				(vias allowed)
				(pads allowed)
				(copperpour not_allowed)
				(footprints allowed)
			)
			(placement
				(enabled no)
				(sheetname "")
			)
			(fill
				(thermal_gap 0.5)
				(thermal_bridge_width 0.5)
				(island_removal_mode 0)
			)
			(polygon
				(pts
					(xy 469.392 -56.896) (xy 469.392 -57.404) (xy 469.773 -57.404) (xy 469.773 -56.896)
				)
			)
		)
		(zone
			(layer "B.Cu")
			(hatch none 0.5)
			(connect_pads
				(clearance 0)
			)
			(min_thickness 0.25)
			(keepout
				(tracks allowed)
				(vias not_allowed)
				(pads allowed)
				(copperpour not_allowed)
				(footprints allowed)
			)
			(placement
				(enabled no)
				(sheetname "")
			)
			(fill
				(thermal_gap 0.5)
				(thermal_bridge_width 0.5)
				(island_removal_mode 0)
			)
			(polygon
				(pts
					(xy 469.773 -56.896) (xy 469.773 -57.404) (xy 469.392 -57.404) (xy 469.392 -56.896)
				)
			)
		)
	)
	(footprint ""
		(layer "B.Cu")
		(at 156.539692 -164.904674 -90)
		(property "Reference" "T1D23"
			(at 0 0 90)
			(layer "B.SilkS")
			(hide yes)
			(effects
				(font
					(size 1.27 1.27)
				)
				(justify mirror)
			)
		)
		(property "Value" "*"
			(at 3.4036 -4.46405 270)
			(unlocked yes)
			(layer "B.Fab")
			(hide yes)
			(effects
				(font
					(size 0.889 0.889)
					(thickness 0.1524)
				)
				(justify mirror)
			)
		)
		(property "Device Type" "TEST-PAD-12P-1-GP-U_DISCRET-GBA"
			(at 3.4036 -5.98805 270)
			(unlocked yes)
			(layer "B.Fab")
			(hide yes)
			(effects
				(font
					(size 0.889 0.889)
					(thickness 0.1524)
				)
				(justify mirror)
			)
		)
		(duplicate_pad_numbers_are_jumpers no)
		(fp_line
			(start -2.3622 3.4798)
			(end 2.3876 3.4798)
			(stroke
				(width 0.1524)
				(type default)
			)
			(layer "B.SilkS")
		)
		(fp_line
			(start 2.3876 3.4798)
			(end 2.3876 -4.826)
			(stroke
				(width 0.1524)
				(type default)
			)
			(layer "B.SilkS")
		)
		(fp_line
			(start -2.3622 -4.826)
			(end -2.3622 3.4798)
			(stroke
				(width 0.1524)
				(type default)
			)
			(layer "B.SilkS")
		)
		(fp_line
			(start 2.3876 -4.826)
			(end -2.3622 -4.826)
			(stroke
				(width 0.1524)
				(type default)
			)
			(layer "B.SilkS")
		)
		(fp_rect
			(start 2.6416 3.7338)
			(end -2.6162 -5.08)
			(stroke
				(width 0)
				(type default)
			)
			(fill no)
			(layer "B.CrtYd")
		)
		(fp_rect
			(start 2.6416 3.7338)
			(end -2.6162 -5.08)
			(stroke
				(width 0)
				(type default)
			)
			(fill no)
			(layer "B.Fab")
		)
		(pad "1" smd circle
			(at -0.496824 -1.301496 90)
			(size 0.6604 0.6604)
			(layers "B.Cu" "B.Mask" "B.Paste")
			(net "L14_85OHM_10INCH_DP")
		)
		(pad "2" smd circle
			(at 0.503936 -1.301496 90)
			(size 0.6604 0.6604)
			(layers "B.Cu" "B.Mask" "B.Paste")
			(net "L14_85OHM_10INCH_DN")
		)
		(pad "3" smd custom
			(at 0.00889 0.370078 90)
			(size 0.74295 0.74295)
			(layers "B.Cu" "B.Mask" "B.Paste")
			(net "GND")
			(options
				(clearance outline)
				(anchor circle)
			)
			(primitives
				(gr_poly
					(pts
						(xy -2.1209 -1.4859) (xy 2.1209 -1.4859) (xy 2.1209 1.4859) (xy 1.08585 1.4859) (xy 1.08585 0.4699)
						(xy -1.08585 0.4699) (xy -1.08585 1.4859) (xy -2.1209 1.4859)
					)
					(width 0)
					(fill yes)
				)
			)
		)
		(pad "4" thru_hole circle
			(at -1.266444 -3.851656 90)
			(size 1.4478 1.4478)
			(drill 1.0414)
			(layers "*.Cu" "*.Mask")
			(remove_unused_layers no)
			(net "GND")
			(clearance 0.1524)
			(thermal_gap 0.1524)
		)
		(pad "5" thru_hole circle
			(at 1.273556 -3.851656 90)
			(size 1.4478 1.4478)
			(drill 1.0414)
			(layers "*.Cu" "*.Mask")
			(remove_unused_layers no)
			(net "GND")
			(clearance 0.1524)
			(thermal_gap 0.1524)
		)
		(pad "6" thru_hole circle
			(at -1.266444 2.498344 90)
			(size 1.4478 1.4478)
			(drill 1.0414)
			(layers "*.Cu" "*.Mask")
			(remove_unused_layers no)
			(net "GND")
			(clearance 0.1524)
			(thermal_gap 0.1524)
		)
		(pad "7" thru_hole circle
			(at 1.273556 2.498344 90)
			(size 1.4478 1.4478)
			(drill 1.0414)
			(layers "*.Cu" "*.Mask")
			(remove_unused_layers no)
			(net "GND")
			(clearance 0.1524)
			(thermal_gap 0.1524)
		)
		(pad "8" thru_hole circle
			(at -1.27 -0.4572 90)
			(size 0.7112 0.7112)
			(drill 0.4064)
			(layers "*.Cu" "*.Mask")
			(remove_unused_layers no)
			(net "GND")
			(clearance 0.1016)
			(thermal_gap 0.1016)
		)
		(pad "9" thru_hole circle
			(at -1.27 0.762 90)
			(size 0.7112 0.7112)
			(drill 0.4064)
			(layers "*.Cu" "*.Mask")
			(remove_unused_layers no)
			(net "GND")
			(clearance 0.1016)
			(thermal_gap 0.1016)
		)
		(pad "10" thru_hole circle
			(at 0.0254 0.762 90)
			(size 0.7112 0.7112)
			(drill 0.4064)
			(layers "*.Cu" "*.Mask")
			(remove_unused_layers no)
			(net "GND")
			(clearance 0.1016)
			(thermal_gap 0.1016)
		)
		(pad "11" thru_hole circle
			(at 1.27 0.762 90)
			(size 0.7112 0.7112)
			(drill 0.4064)
			(layers "*.Cu" "*.Mask")
			(remove_unused_layers no)
			(net "GND")
			(clearance 0.1016)
			(thermal_gap 0.1016)
		)
		(pad "12" thru_hole circle
			(at 1.27 -0.4572 90)
			(size 0.7112 0.7112)
			(drill 0.4064)
			(layers "*.Cu" "*.Mask")
			(remove_unused_layers no)
			(net "GND")
			(clearance 0.1016)
			(thermal_gap 0.1016)
		)
	)
	(footprint ""
		(layer "B.Cu")
		(at 394.175234 -150.95474 -90)
		(property "Reference" "R2L14"
			(at 0 0 90)
			(layer "B.SilkS")
			(hide yes)
			(effects
				(font
					(size 1.27 1.27)
				)
				(justify mirror)
			)
		)
		(property "Value" ""
			(at 0 0 90)
			(layer "B.Fab")
			(effects
				(font
					(size 1.27 1.27)
				)
				(justify mirror)
			)
		)
		(duplicate_pad_numbers_are_jumpers no)
		(fp_poly
			(pts
				(xy 0.2794 -0.1016) (xy -0.2794 -0.1016) (xy -0.2794 0.9906) (xy 0.2794 0.9906)
			)
			(stroke
				(width 0)
				(type default)
			)
			(fill no)
			(layer "B.CrtYd")
		)
		(fp_line
			(start -0.2794 0.9906)
			(end -0.2794 -0.1016)
			(stroke
				(width 0.1)
				(type default)
			)
			(layer "B.Fab")
		)
		(fp_line
			(start 0.2794 0.9906)
			(end -0.2794 0.9906)
			(stroke
				(width 0.1)
				(type default)
			)
			(layer "B.Fab")
		)
		(fp_line
			(start -0.2794 -0.1016)
			(end 0.2794 -0.1016)
			(stroke
				(width 0.1)
				(type default)
			)
			(layer "B.Fab")
		)
		(fp_line
			(start 0.2794 -0.1016)
			(end 0.2794 0.9906)
			(stroke
				(width 0.1)
				(type default)
			)
			(layer "B.Fab")
		)
		(pad "1" smd rect
			(at 0 0 90)
			(size 0.508 0.508)
			(layers "B.Cu" "B.Mask" "B.Paste")
			(net "P3V3_STBY")
		)
		(pad "2" smd rect
			(at 0 0.889 90)
			(size 0.508 0.508)
			(layers "B.Cu" "B.Mask" "B.Paste")
			(net "VR_PVNN_PCH_VDD")
		)
		(zone
			(layer "B.Cu")
			(hatch none 0.5)
			(connect_pads
				(clearance 0)
			)
			(min_thickness 0.25)
			(keepout
				(tracks not_allowed)
				(vias allowed)
				(pads allowed)
				(copperpour not_allowed)
				(footprints allowed)
			)
			(placement
				(enabled no)
				(sheetname "")
			)
			(fill
				(thermal_gap 0.5)
				(thermal_bridge_width 0.5)
				(island_removal_mode 0)
			)
			(polygon
				(pts
					(xy 393.540234 -150.70074) (xy 393.540234 -151.20874) (xy 393.921234 -151.20874) (xy 393.921234 -150.70074)
				)
			)
		)
		(zone
			(layer "B.Cu")
			(hatch none 0.5)
			(connect_pads
				(clearance 0)
			)
			(min_thickness 0.25)
			(keepout
				(tracks allowed)
				(vias not_allowed)
				(pads allowed)
				(copperpour not_allowed)
				(footprints allowed)
			)
			(placement
				(enabled no)
				(sheetname "")
			)
			(fill
				(thermal_gap 0.5)
				(thermal_bridge_width 0.5)
				(island_removal_mode 0)
			)
			(polygon
				(pts
					(xy 393.921234 -150.70074) (xy 393.921234 -151.20874) (xy 393.540234 -151.20874) (xy 393.540234 -150.70074)
				)
			)
		)
	)
	(footprint ""
		(layer "B.Cu")
		(at 362.270294 -46.433486 180)
		(property "Reference" "R7D41"
			(at 0 0 0)
			(layer "B.SilkS")
			(hide yes)
			(effects
				(font
					(size 1.27 1.27)
				)
				(justify mirror)
			)
		)
		(property "Value" ""
			(at 0 0 0)
			(layer "B.Fab")
			(effects
				(font
					(size 1.27 1.27)
				)
				(justify mirror)
			)
		)
		(duplicate_pad_numbers_are_jumpers no)
		(fp_poly
			(pts
				(xy 0.2794 -0.1016) (xy -0.2794 -0.1016) (xy -0.2794 0.9906) (xy 0.2794 0.9906)
			)
			(stroke
				(width 0)
				(type default)
			)
			(fill no)
			(layer "B.CrtYd")
		)
		(fp_line
			(start 0.2794 0.9906)
			(end -0.2794 0.9906)
			(stroke
				(width 0.1)
				(type default)
			)
			(layer "B.Fab")
		)
		(fp_line
			(start 0.2794 -0.1016)
			(end 0.2794 0.9906)
			(stroke
				(width 0.1)
				(type default)
			)
			(layer "B.Fab")
		)
		(fp_line
			(start -0.2794 0.9906)
			(end -0.2794 -0.1016)
			(stroke
				(width 0.1)
				(type default)
			)
			(layer "B.Fab")
		)
		(fp_line
			(start -0.2794 -0.1016)
			(end 0.2794 -0.1016)
			(stroke
				(width 0.1)
				(type default)
			)
			(layer "B.Fab")
		)
		(pad "1" smd rect
			(at 0 0)
			(size 0.508 0.508)
			(layers "B.Cu" "B.Mask" "B.Paste")
			(net "FM_CPU1_PROCHOT_LVT3_R_N")
		)
		(pad "2" smd rect
			(at 0 0.889)
			(size 0.508 0.508)
			(layers "B.Cu" "B.Mask" "B.Paste")
			(net "FM_CPU1_PROCHOT_LVT3_K_N")
		)
		(zone
			(layer "B.Cu")
			(hatch none 0.5)
			(connect_pads
				(clearance 0)
			)
			(min_thickness 0.25)
			(keepout
				(tracks not_allowed)
				(vias allowed)
				(pads allowed)
				(copperpour not_allowed)
				(footprints allowed)
			)
			(placement
				(enabled no)
				(sheetname "")
			)
			(fill
				(thermal_gap 0.5)
				(thermal_bridge_width 0.5)
				(island_removal_mode 0)
			)
			(polygon
				(pts
					(xy 362.016294 -47.068486) (xy 362.524294 -47.068486) (xy 362.524294 -46.687486) (xy 362.016294 -46.687486)
				)
			)
		)
		(zone
			(layer "B.Cu")
			(hatch none 0.5)
			(connect_pads
				(clearance 0)
			)
			(min_thickness 0.25)
			(keepout
				(tracks allowed)
				(vias not_allowed)
				(pads allowed)
				(copperpour not_allowed)
				(footprints allowed)
			)
			(placement
				(enabled no)
				(sheetname "")
			)
			(fill
				(thermal_gap 0.5)
				(thermal_bridge_width 0.5)
				(island_removal_mode 0)
			)
			(polygon
				(pts
					(xy 362.016294 -46.687486) (xy 362.524294 -46.687486) (xy 362.524294 -47.068486) (xy 362.016294 -47.068486)
				)
			)
		)
	)
	(footprint ""
		(layer "B.Cu")
		(at 361.188 -23.241)
		(property "Reference" "C3T15"
			(at -3.20167 3.81 270)
			(unlocked yes)
			(layer "B.SilkS")
			(effects
				(font
					(size 0.7874 0.5842)
					(thickness 0.1524)
				)
				(justify mirror)
			)
		)
		(property "Value" ""
			(at 0 0 0)
			(layer "B.Fab")
			(effects
				(font
					(size 1.27 1.27)
				)
				(justify mirror)
			)
		)
		(duplicate_pad_numbers_are_jumpers no)
		(fp_line
			(start -2.504948 -1.616456)
			(end -2.504948 1.633728)
			(stroke
				(width 0.1524)
				(type default)
			)
			(layer "B.SilkS")
		)
		(fp_line
			(start -2.504948 1.633728)
			(end -1.6002 1.633728)
			(stroke
				(width 0.1524)
				(type default)
			)
			(layer "B.SilkS")
		)
		(fp_line
			(start -2.286 7.366)
			(end -2.286 1.63195)
			(stroke
				(width 0.1524)
				(type default)
			)
			(layer "B.SilkS")
		)
		(fp_line
			(start -2.286 7.366)
			(end -1.600708 7.366)
			(stroke
				(width 0.1524)
				(type default)
			)
			(layer "B.SilkS")
		)
		(fp_line
			(start -1.6002 -1.616456)
			(end -2.504948 -1.616456)
			(stroke
				(width 0.1524)
				(type default)
			)
			(layer "B.SilkS")
		)
		(fp_line
			(start 1.6002 -1.616456)
			(end 2.563114 -1.616456)
			(stroke
				(width 0.1524)
				(type default)
			)
			(layer "B.SilkS")
		)
		(fp_line
			(start 2.286 7.366)
			(end 1.60147 7.366)
			(stroke
				(width 0.1524)
				(type default)
			)
			(layer "B.SilkS")
		)
		(fp_line
			(start 2.286 7.366)
			(end 2.286 1.632712)
			(stroke
				(width 0.1524)
				(type default)
			)
			(layer "B.SilkS")
		)
		(fp_line
			(start 2.563114 -1.616456)
			(end 2.563114 1.633728)
			(stroke
				(width 0.1524)
				(type default)
			)
			(layer "B.SilkS")
		)
		(fp_line
			(start 2.563114 1.633728)
			(end 1.6002 1.633728)
			(stroke
				(width 0.1524)
				(type default)
			)
			(layer "B.SilkS")
		)
		(fp_rect
			(start 2.286 7.366)
			(end -2.286 -0.254)
			(stroke
				(width 0)
				(type default)
			)
			(fill no)
			(layer "B.CrtYd")
		)
		(fp_line
			(start -2.286 -0.254)
			(end -2.286 7.366)
			(stroke
				(width 0.1)
				(type default)
			)
			(layer "B.Fab")
		)
		(fp_line
			(start -2.286 7.366)
			(end 2.286 7.366)
			(stroke
				(width 0.1)
				(type default)
			)
			(layer "B.Fab")
		)
		(fp_line
			(start 2.286 -0.254)
			(end -2.286 -0.254)
			(stroke
				(width 0.1)
				(type default)
			)
			(layer "B.Fab")
		)
		(fp_line
			(start 2.286 7.366)
			(end 2.286 -0.254)
			(stroke
				(width 0.1)
				(type default)
			)
			(layer "B.Fab")
		)
		(pad "1" smd rect
			(at 0 0 180)
			(size 2.54 3.048)
			(layers "B.Cu" "B.Mask" "B.Paste")
			(net "P12V_STBY")
		)
		(pad "2" smd rect
			(at 0 7.112 180)
			(size 2.54 3.048)
			(layers "B.Cu" "B.Mask" "B.Paste")
			(net "GND")
		)
	)
	(footprint ""
		(layer "B.Cu")
		(at 18.0086 -139.1666 -90)
		(property "Reference" "C9L12"
			(at -2.03073 9.6266 0)
			(unlocked yes)
			(layer "B.SilkS")
			(effects
				(font
					(size 0.7874 0.5842)
					(thickness 0.1524)
				)
				(justify mirror)
			)
		)
		(property "Value" ""
			(at 0 0 90)
			(layer "B.Fab")
			(effects
				(font
					(size 1.27 1.27)
				)
				(justify mirror)
			)
		)
		(duplicate_pad_numbers_are_jumpers no)
		(fp_line
			(start -2.286 7.366)
			(end -1.600708 7.366)
			(stroke
				(width 0.1524)
				(type default)
			)
			(layer "B.SilkS")
		)
		(fp_line
			(start -2.286 7.366)
			(end -2.286 1.63195)
			(stroke
				(width 0.1524)
				(type default)
			)
			(layer "B.SilkS")
		)
		(fp_line
			(start 2.286 7.366)
			(end 1.60147 7.366)
			(stroke
				(width 0.1524)
				(type default)
			)
			(layer "B.SilkS")
		)
		(fp_line
			(start 2.286 7.366)
			(end 2.286 1.632712)
			(stroke
				(width 0.1524)
				(type default)
			)
			(layer "B.SilkS")
		)
		(fp_line
			(start -2.504948 1.633728)
			(end -1.6002 1.633728)
			(stroke
				(width 0.1524)
				(type default)
			)
			(layer "B.SilkS")
		)
		(fp_line
			(start 2.563114 1.633728)
			(end 1.6002 1.633728)
			(stroke
				(width 0.1524)
				(type default)
			)
			(layer "B.SilkS")
		)
		(fp_line
			(start -2.504948 -1.616456)
			(end -2.504948 1.633728)
			(stroke
				(width 0.1524)
				(type default)
			)
			(layer "B.SilkS")
		)
		(fp_line
			(start -1.6002 -1.616456)
			(end -2.504948 -1.616456)
			(stroke
				(width 0.1524)
				(type default)
			)
			(layer "B.SilkS")
		)
		(fp_line
			(start 1.6002 -1.616456)
			(end 2.563114 -1.616456)
			(stroke
				(width 0.1524)
				(type default)
			)
			(layer "B.SilkS")
		)
		(fp_line
			(start 2.563114 -1.616456)
			(end 2.563114 1.633728)
			(stroke
				(width 0.1524)
				(type default)
			)
			(layer "B.SilkS")
		)
		(fp_rect
			(start 2.286 -0.254)
			(end -2.286 7.366)
			(stroke
				(width 0)
				(type default)
			)
			(fill no)
			(layer "B.CrtYd")
		)
		(fp_line
			(start -2.286 7.366)
			(end 2.286 7.366)
			(stroke
				(width 0.1)
				(type default)
			)
			(layer "B.Fab")
		)
		(fp_line
			(start 2.286 7.366)
			(end 2.286 -0.254)
			(stroke
				(width 0.1)
				(type default)
			)
			(layer "B.Fab")
		)
		(fp_line
			(start -2.286 -0.254)
			(end -2.286 7.366)
			(stroke
				(width 0.1)
				(type default)
			)
			(layer "B.Fab")
		)
		(fp_line
			(start 2.286 -0.254)
			(end -2.286 -0.254)
			(stroke
				(width 0.1)
				(type default)
			)
			(layer "B.Fab")
		)
		(pad "1" smd rect
			(at 0 0 90)
			(size 2.54 3.048)
			(layers "B.Cu" "B.Mask" "B.Paste")
			(net "PVDDQ_KLM")
		)
		(pad "2" smd rect
			(at 0 7.112 90)
			(size 2.54 3.048)
			(layers "B.Cu" "B.Mask" "B.Paste")
			(net "GND")
		)
	)
	(footprint ""
		(layer "B.Cu")
		(at 323.8627 -28.36418 -90)
		(property "Reference" "R4T7"
			(at 0 0 90)
			(layer "B.SilkS")
			(hide yes)
			(effects
				(font
					(size 1.27 1.27)
				)
				(justify mirror)
			)
		)
		(property "Value" ""
			(at 0 0 90)
			(layer "B.Fab")
			(effects
				(font
					(size 1.27 1.27)
				)
				(justify mirror)
			)
		)
		(duplicate_pad_numbers_are_jumpers no)
		(fp_poly
			(pts
				(xy 0.2794 -0.1016) (xy -0.2794 -0.1016) (xy -0.2794 0.9906) (xy 0.2794 0.9906)
			)
			(stroke
				(width 0)
				(type default)
			)
			(fill no)
			(layer "B.CrtYd")
		)
		(fp_line
			(start -0.2794 0.9906)
			(end -0.2794 -0.1016)
			(stroke
				(width 0.1)
				(type default)
			)
			(layer "B.Fab")
		)
		(fp_line
			(start 0.2794 0.9906)
			(end -0.2794 0.9906)
			(stroke
				(width 0.1)
				(type default)
			)
			(layer "B.Fab")
		)
		(fp_line
			(start -0.2794 -0.1016)
			(end 0.2794 -0.1016)
			(stroke
				(width 0.1)
				(type default)
			)
			(layer "B.Fab")
		)
		(fp_line
			(start 0.2794 -0.1016)
			(end 0.2794 0.9906)
			(stroke
				(width 0.1)
				(type default)
			)
			(layer "B.Fab")
		)
		(pad "1" smd rect
			(at 0 0 90)
			(size 0.508 0.508)
			(layers "B.Cu" "B.Mask" "B.Paste")
			(net "PVPP_ABC")
		)
		(pad "2" smd rect
			(at 0 0.889 90)
			(size 0.508 0.508)
			(layers "B.Cu" "B.Mask" "B.Paste")
			(net "SMB_DDR_ABC_VPP_SCL_R")
		)
		(zone
			(layer "B.Cu")
			(hatch none 0.5)
			(connect_pads
				(clearance 0)
			)
			(min_thickness 0.25)
			(keepout
				(tracks not_allowed)
				(vias allowed)
				(pads allowed)
				(copperpour not_allowed)
				(footprints allowed)
			)
			(placement
				(enabled no)
				(sheetname "")
			)
			(fill
				(thermal_gap 0.5)
				(thermal_bridge_width 0.5)
				(island_removal_mode 0)
			)
			(polygon
				(pts
					(xy 323.2277 -28.11018) (xy 323.2277 -28.61818) (xy 323.6087 -28.61818) (xy 323.6087 -28.11018)
				)
			)
		)
		(zone
			(layer "B.Cu")
			(hatch none 0.5)
			(connect_pads
				(clearance 0)
			)
			(min_thickness 0.25)
			(keepout
				(tracks allowed)
				(vias not_allowed)
				(pads allowed)
				(copperpour not_allowed)
				(footprints allowed)
			)
			(placement
				(enabled no)
				(sheetname "")
			)
			(fill
				(thermal_gap 0.5)
				(thermal_bridge_width 0.5)
				(island_removal_mode 0)
			)
			(polygon
				(pts
					(xy 323.6087 -28.11018) (xy 323.6087 -28.61818) (xy 323.2277 -28.61818) (xy 323.2277 -28.11018)
				)
			)
		)
	)
	(footprint ""
		(layer "B.Cu")
		(at 430.0855 -13.716 -90)
		(property "Reference" "R9G33"
			(at 0 0 90)
			(layer "B.SilkS")
			(hide yes)
			(effects
				(font
					(size 1.27 1.27)
				)
				(justify mirror)
			)
		)
		(property "Value" ""
			(at 0 0 90)
			(layer "B.Fab")
			(effects
				(font
					(size 1.27 1.27)
				)
				(justify mirror)
			)
		)
		(duplicate_pad_numbers_are_jumpers no)
		(fp_poly
			(pts
				(xy 0.2794 -0.1016) (xy -0.2794 -0.1016) (xy -0.2794 0.9906) (xy 0.2794 0.9906)
			)
			(stroke
				(width 0)
				(type default)
			)
			(fill no)
			(layer "B.CrtYd")
		)
		(fp_line
			(start -0.2794 0.9906)
			(end -0.2794 -0.1016)
			(stroke
				(width 0.1)
				(type default)
			)
			(layer "B.Fab")
		)
		(fp_line
			(start 0.2794 0.9906)
			(end -0.2794 0.9906)
			(stroke
				(width 0.1)
				(type default)
			)
			(layer "B.Fab")
		)
		(fp_line
			(start -0.2794 -0.1016)
			(end 0.2794 -0.1016)
			(stroke
				(width 0.1)
				(type default)
			)
			(layer "B.Fab")
		)
		(fp_line
			(start 0.2794 -0.1016)
			(end 0.2794 0.9906)
			(stroke
				(width 0.1)
				(type default)
			)
			(layer "B.Fab")
		)
		(pad "1" smd rect
			(at 0 0 90)
			(size 0.508 0.508)
			(layers "B.Cu" "B.Mask" "B.Paste")
			(net "H_CPU0_DEF_MEMHOT_LVT3_R_N")
		)
		(pad "2" smd rect
			(at 0 0.889 90)
			(size 0.508 0.508)
			(layers "B.Cu" "B.Mask" "B.Paste")
			(net "H_CPU0_MEMDEF_MEMHOT_LVT3_K_N")
		)
		(zone
			(layer "B.Cu")
			(hatch none 0.5)
			(connect_pads
				(clearance 0)
			)
			(min_thickness 0.25)
			(keepout
				(tracks not_allowed)
				(vias allowed)
				(pads allowed)
				(copperpour not_allowed)
				(footprints allowed)
			)
			(placement
				(enabled no)
				(sheetname "")
			)
			(fill
				(thermal_gap 0.5)
				(thermal_bridge_width 0.5)
				(island_removal_mode 0)
			)
			(polygon
				(pts
					(xy 429.4505 -13.462) (xy 429.4505 -13.97) (xy 429.8315 -13.97) (xy 429.8315 -13.462)
				)
			)
		)
		(zone
			(layer "B.Cu")
			(hatch none 0.5)
			(connect_pads
				(clearance 0)
			)
			(min_thickness 0.25)
			(keepout
				(tracks allowed)
				(vias not_allowed)
				(pads allowed)
				(copperpour not_allowed)
				(footprints allowed)
			)
			(placement
				(enabled no)
				(sheetname "")
			)
			(fill
				(thermal_gap 0.5)
				(thermal_bridge_width 0.5)
				(island_removal_mode 0)
			)
			(polygon
				(pts
					(xy 429.8315 -13.462) (xy 429.8315 -13.97) (xy 429.4505 -13.97) (xy 429.4505 -13.462)
				)
			)
		)
	)
	(footprint ""
		(layer "B.Cu")
		(at 320.194432 -17.78 90)
		(property "Reference" "C4T5"
			(at 0 0 90)
			(layer "B.SilkS")
			(hide yes)
			(effects
				(font
					(size 1.27 1.27)
				)
				(justify mirror)
			)
		)
		(property "Value" ""
			(at 0 0 90)
			(layer "B.Fab")
			(effects
				(font
					(size 1.27 1.27)
				)
				(justify mirror)
			)
		)
		(duplicate_pad_numbers_are_jumpers no)
		(fp_poly
			(pts
				(xy 0.4953 -0.2032) (xy -0.4953 -0.2032) (xy -0.4953 1.6002) (xy 0.4953 1.6002)
			)
			(stroke
				(width 0)
				(type default)
			)
			(fill no)
			(layer "B.CrtYd")
		)
		(fp_line
			(start 0.4953 -0.2032)
			(end -0.4953 -0.2032)
			(stroke
				(width 0.1)
				(type default)
			)
			(layer "B.Fab")
		)
		(fp_line
			(start -0.4953 -0.2032)
			(end -0.4953 1.6002)
			(stroke
				(width 0.1)
				(type default)
			)
			(layer "B.Fab")
		)
		(fp_line
			(start 0.4953 1.6002)
			(end 0.4953 -0.2032)
			(stroke
				(width 0.1)
				(type default)
			)
			(layer "B.Fab")
		)
		(fp_line
			(start -0.4953 1.6002)
			(end 0.4953 1.6002)
			(stroke
				(width 0.1)
				(type default)
			)
			(layer "B.Fab")
		)
		(pad "1" smd rect
			(at 0 0 270)
			(size 0.762 0.889)
			(layers "B.Cu" "B.Mask" "B.Paste")
			(net "PVPP_ABC")
		)
		(pad "2" smd rect
			(at 0 1.397 270)
			(size 0.762 0.889)
			(layers "B.Cu" "B.Mask" "B.Paste")
			(net "GND")
		)
		(zone
			(layer "B.Cu")
			(hatch none 0.5)
			(connect_pads
				(clearance 0)
			)
			(min_thickness 0.25)
			(keepout
				(tracks not_allowed)
				(vias allowed)
				(pads allowed)
				(copperpour not_allowed)
				(footprints allowed)
			)
			(placement
				(enabled no)
				(sheetname "")
			)
			(fill
				(thermal_gap 0.5)
				(thermal_bridge_width 0.5)
				(island_removal_mode 0)
			)
			(polygon
				(pts
					(xy 320.638932 -18.161) (xy 320.638932 -17.399) (xy 321.146932 -17.399) (xy 321.146932 -18.161)
				)
			)
		)
	)
	(footprint ""
		(layer "B.Cu")
		(at 394.2207 -19.812 90)
		(property "Reference" "R32W4"
			(at 0.8382 -0.67818 90)
			(unlocked yes)
			(layer "B.SilkS")
			(effects
				(font
					(size 0.4064 0.254)
					(thickness 0.1524)
				)
				(justify left mirror)
			)
		)
		(property "Value" ""
			(at 0 0 90)
			(layer "B.Fab")
			(effects
				(font
					(size 1.27 1.27)
				)
				(justify mirror)
			)
		)
		(duplicate_pad_numbers_are_jumpers no)
		(fp_poly
			(pts
				(xy 0.2794 -0.1016) (xy -0.2794 -0.1016) (xy -0.2794 0.9906) (xy 0.2794 0.9906)
			)
			(stroke
				(width 0)
				(type default)
			)
			(fill no)
			(layer "B.CrtYd")
		)
		(fp_line
			(start 0.2794 -0.1016)
			(end 0.2794 0.9906)
			(stroke
				(width 0.1)
				(type default)
			)
			(layer "B.Fab")
		)
		(fp_line
			(start -0.2794 -0.1016)
			(end 0.2794 -0.1016)
			(stroke
				(width 0.1)
				(type default)
			)
			(layer "B.Fab")
		)
		(fp_line
			(start 0.2794 0.9906)
			(end -0.2794 0.9906)
			(stroke
				(width 0.1)
				(type default)
			)
			(layer "B.Fab")
		)
		(fp_line
			(start -0.2794 0.9906)
			(end -0.2794 -0.1016)
			(stroke
				(width 0.1)
				(type default)
			)
			(layer "B.Fab")
		)
		(pad "1" smd rect
			(at 0 0 270)
			(size 0.508 0.508)
			(layers "B.Cu" "B.Mask" "B.Paste")
			(net "P1V8_M2")
		)
		(pad "2" smd rect
			(at 0 0.889 270)
			(size 0.508 0.508)
			(layers "B.Cu" "B.Mask" "B.Paste")
			(net "GND")
		)
		(zone
			(layer "B.Cu")
			(hatch none 0.5)
			(connect_pads
				(clearance 0)
			)
			(min_thickness 0.25)
			(keepout
				(tracks allowed)
				(vias not_allowed)
				(pads allowed)
				(copperpour not_allowed)
				(footprints allowed)
			)
			(placement
				(enabled no)
				(sheetname "")
			)
			(fill
				(thermal_gap 0.5)
				(thermal_bridge_width 0.5)
				(island_removal_mode 0)
			)
			(polygon
				(pts
					(xy 394.4747 -20.066) (xy 394.4747 -19.558) (xy 394.8557 -19.558) (xy 394.8557 -20.066)
				)
			)
		)
		(zone
			(layer "B.Cu")
			(hatch none 0.5)
			(connect_pads
				(clearance 0)
			)
			(min_thickness 0.25)
			(keepout
				(tracks not_allowed)
				(vias allowed)
				(pads allowed)
				(copperpour not_allowed)
				(footprints allowed)
			)
			(placement
				(enabled no)
				(sheetname "")
			)
			(fill
				(thermal_gap 0.5)
				(thermal_bridge_width 0.5)
				(island_removal_mode 0)
			)
			(polygon
				(pts
					(xy 394.8557 -20.066) (xy 394.8557 -19.558) (xy 394.4747 -19.558) (xy 394.4747 -20.066)
				)
			)
		)
	)
	(footprint ""
		(layer "B.Cu")
		(at 409.3845 -24.384 -90)
		(property "Reference" "C25W60"
			(at 0.8382 -0.67818 270)
			(unlocked yes)
			(layer "B.SilkS")
			(effects
				(font
					(size 0.4064 0.254)
					(thickness 0.1524)
				)
				(justify left mirror)
			)
		)
		(property "Value" ""
			(at 0 0 90)
			(layer "B.Fab")
			(effects
				(font
					(size 1.27 1.27)
				)
				(justify mirror)
			)
		)
		(duplicate_pad_numbers_are_jumpers no)
		(fp_poly
			(pts
				(xy -0.3048 -0.1016) (xy -0.3048 0.9906) (xy 0.3048 0.9906) (xy 0.3048 -0.1016)
			)
			(stroke
				(width 0)
				(type default)
			)
			(fill no)
			(layer "B.CrtYd")
		)
		(fp_line
			(start -0.3048 0.9906)
			(end -0.3048 -0.1016)
			(stroke
				(width 0.1)
				(type default)
			)
			(layer "B.Fab")
		)
		(fp_line
			(start 0.3048 0.9906)
			(end -0.3048 0.9906)
			(stroke
				(width 0.1)
				(type default)
			)
			(layer "B.Fab")
		)
		(fp_line
			(start -0.3048 -0.1016)
			(end 0.3048 -0.1016)
			(stroke
				(width 0.1)
				(type default)
			)
			(layer "B.Fab")
		)
		(fp_line
			(start 0.3048 -0.1016)
			(end 0.3048 0.9906)
			(stroke
				(width 0.1)
				(type default)
			)
			(layer "B.Fab")
		)
		(pad "1" smd rect
			(at 0 0 90)
			(size 0.508 0.508)
			(layers "B.Cu" "B.Mask" "B.Paste")
			(net "P3V3_STBY")
		)
		(pad "2" smd rect
			(at 0 0.889 90)
			(size 0.508 0.508)
			(layers "B.Cu" "B.Mask" "B.Paste")
			(net "GND")
		)
		(zone
			(layer "B.Cu")
			(hatch none 0.5)
			(connect_pads
				(clearance 0)
			)
			(min_thickness 0.25)
			(keepout
				(tracks not_allowed)
				(vias allowed)
				(pads allowed)
				(copperpour not_allowed)
				(footprints allowed)
			)
			(placement
				(enabled no)
				(sheetname "")
			)
			(fill
				(thermal_gap 0.5)
				(thermal_bridge_width 0.5)
				(island_removal_mode 0)
			)
			(polygon
				(pts
					(xy 408.7495 -24.13) (xy 408.7495 -24.638) (xy 409.1305 -24.638) (xy 409.1305 -24.13)
				)
			)
		)
		(zone
			(layer "B.Cu")
			(hatch none 0.5)
			(connect_pads
				(clearance 0)
			)
			(min_thickness 0.25)
			(keepout
				(tracks allowed)
				(vias not_allowed)
				(pads allowed)
				(copperpour not_allowed)
				(footprints allowed)
			)
			(placement
				(enabled no)
				(sheetname "")
			)
			(fill
				(thermal_gap 0.5)
				(thermal_bridge_width 0.5)
				(island_removal_mode 0)
			)
			(polygon
				(pts
					(xy 409.1305 -24.13) (xy 409.1305 -24.638) (xy 408.7495 -24.638) (xy 408.7495 -24.13)
				)
			)
		)
	)
	(footprint ""
		(layer "B.Cu")
		(at 452.35241 -3.852672 90)
		(property "Reference" "R1U63"
			(at 0 0 90)
			(layer "B.SilkS")
			(hide yes)
			(effects
				(font
					(size 1.27 1.27)
				)
				(justify mirror)
			)
		)
		(property "Value" ""
			(at 0 0 90)
			(layer "B.Fab")
			(effects
				(font
					(size 1.27 1.27)
				)
				(justify mirror)
			)
		)
		(duplicate_pad_numbers_are_jumpers no)
		(fp_poly
			(pts
				(xy 0.2794 -0.1016) (xy -0.2794 -0.1016) (xy -0.2794 0.9906) (xy 0.2794 0.9906)
			)
			(stroke
				(width 0)
				(type default)
			)
			(fill no)
			(layer "B.CrtYd")
		)
		(fp_line
			(start 0.2794 -0.1016)
			(end 0.2794 0.9906)
			(stroke
				(width 0.1)
				(type default)
			)
			(layer "B.Fab")
		)
		(fp_line
			(start -0.2794 -0.1016)
			(end 0.2794 -0.1016)
			(stroke
				(width 0.1)
				(type default)
			)
			(layer "B.Fab")
		)
		(fp_line
			(start 0.2794 0.9906)
			(end -0.2794 0.9906)
			(stroke
				(width 0.1)
				(type default)
			)
			(layer "B.Fab")
		)
		(fp_line
			(start -0.2794 0.9906)
			(end -0.2794 -0.1016)
			(stroke
				(width 0.1)
				(type default)
			)
			(layer "B.Fab")
		)
		(pad "1" smd rect
			(at 0 0 270)
			(size 0.508 0.508)
			(layers "B.Cu" "B.Mask" "B.Paste")
			(net "PD_RST_RTCRST_N")
		)
		(pad "2" smd rect
			(at 0 0.889 270)
			(size 0.508 0.508)
			(layers "B.Cu" "B.Mask" "B.Paste")
			(net "GND")
		)
		(zone
			(layer "B.Cu")
			(hatch none 0.5)
			(connect_pads
				(clearance 0)
			)
			(min_thickness 0.25)
			(keepout
				(tracks allowed)
				(vias not_allowed)
				(pads allowed)
				(copperpour not_allowed)
				(footprints allowed)
			)
			(placement
				(enabled no)
				(sheetname "")
			)
			(fill
				(thermal_gap 0.5)
				(thermal_bridge_width 0.5)
				(island_removal_mode 0)
			)
			(polygon
				(pts
					(xy 452.60641 -4.106672) (xy 452.60641 -3.598672) (xy 452.98741 -3.598672) (xy 452.98741 -4.106672)
				)
			)
		)
		(zone
			(layer "B.Cu")
			(hatch none 0.5)
			(connect_pads
				(clearance 0)
			)
			(min_thickness 0.25)
			(keepout
				(tracks not_allowed)
				(vias allowed)
				(pads allowed)
				(copperpour not_allowed)
				(footprints allowed)
			)
			(placement
				(enabled no)
				(sheetname "")
			)
			(fill
				(thermal_gap 0.5)
				(thermal_bridge_width 0.5)
				(island_removal_mode 0)
			)
			(polygon
				(pts
					(xy 452.98741 -4.106672) (xy 452.98741 -3.598672) (xy 452.60641 -3.598672) (xy 452.60641 -4.106672)
				)
			)
		)
	)
	(footprint ""
		(layer "B.Cu")
		(at 444.1317 -36.738052 180)
		(property "Reference" "R25W119"
			(at 0.8382 -0.67818 180)
			(unlocked yes)
			(layer "B.SilkS")
			(effects
				(font
					(size 0.4064 0.254)
					(thickness 0.1524)
				)
				(justify left mirror)
			)
		)
		(property "Value" ""
			(at 0 0 0)
			(layer "B.Fab")
			(effects
				(font
					(size 1.27 1.27)
				)
				(justify mirror)
			)
		)
		(duplicate_pad_numbers_are_jumpers no)
		(fp_poly
			(pts
				(xy 0.2794 -0.1016) (xy -0.2794 -0.1016) (xy -0.2794 0.9906) (xy 0.2794 0.9906)
			)
			(stroke
				(width 0)
				(type default)
			)
			(fill no)
			(layer "B.CrtYd")
		)
		(fp_line
			(start 0.2794 0.9906)
			(end -0.2794 0.9906)
			(stroke
				(width 0.1)
				(type default)
			)
			(layer "B.Fab")
		)
		(fp_line
			(start 0.2794 -0.1016)
			(end 0.2794 0.9906)
			(stroke
				(width 0.1)
				(type default)
			)
			(layer "B.Fab")
		)
		(fp_line
			(start -0.2794 0.9906)
			(end -0.2794 -0.1016)
			(stroke
				(width 0.1)
				(type default)
			)
			(layer "B.Fab")
		)
		(fp_line
			(start -0.2794 -0.1016)
			(end 0.2794 -0.1016)
			(stroke
				(width 0.1)
				(type default)
			)
			(layer "B.Fab")
		)
		(pad "1" smd rect
			(at 0 0)
			(size 0.508 0.508)
			(layers "B.Cu" "B.Mask" "B.Paste")
			(net "P1V2_AUX_BMC")
		)
		(pad "2" smd rect
			(at 0 0.889)
			(size 0.508 0.508)
			(layers "B.Cu" "B.Mask" "B.Paste")
			(net "BMC_M_PAR")
		)
		(zone
			(layer "B.Cu")
			(hatch none 0.5)
			(connect_pads
				(clearance 0)
			)
			(min_thickness 0.25)
			(keepout
				(tracks not_allowed)
				(vias allowed)
				(pads allowed)
				(copperpour not_allowed)
				(footprints allowed)
			)
			(placement
				(enabled no)
				(sheetname "")
			)
			(fill
				(thermal_gap 0.5)
				(thermal_bridge_width 0.5)
				(island_removal_mode 0)
			)
			(polygon
				(pts
					(xy 443.8777 -37.373052) (xy 444.3857 -37.373052) (xy 444.3857 -36.992052) (xy 443.8777 -36.992052)
				)
			)
		)
		(zone
			(layer "B.Cu")
			(hatch none 0.5)
			(connect_pads
				(clearance 0)
			)
			(min_thickness 0.25)
			(keepout
				(tracks allowed)
				(vias not_allowed)
				(pads allowed)
				(copperpour not_allowed)
				(footprints allowed)
			)
			(placement
				(enabled no)
				(sheetname "")
			)
			(fill
				(thermal_gap 0.5)
				(thermal_bridge_width 0.5)
				(island_removal_mode 0)
			)
			(polygon
				(pts
					(xy 443.8777 -36.992052) (xy 444.3857 -36.992052) (xy 444.3857 -37.373052) (xy 443.8777 -37.373052)
				)
			)
		)
	)
	(footprint ""
		(layer "B.Cu")
		(at 452.5772 -149.0345 180)
		(property "Reference" "R25W183"
			(at 0 0 0)
			(layer "B.SilkS")
			(hide yes)
			(effects
				(font
					(size 1.27 1.27)
				)
				(justify mirror)
			)
		)
		(property "Value" "*"
			(at -0.064008 -4.108196 180)
			(unlocked yes)
			(layer "B.Fab")
			(hide yes)
			(effects
				(font
					(size 1.27 1.016)
					(thickness 0.1524)
				)
				(justify mirror)
			)
		)
		(property "Device Type" "374R2F-1-GP_SMD-RG-374R2F-1-GPA"
			(at -0.064008 -5.632196 180)
			(unlocked yes)
			(layer "B.Fab")
			(hide yes)
			(effects
				(font
					(size 1.27 1.016)
					(thickness 0.1524)
				)
				(justify mirror)
			)
		)
		(duplicate_pad_numbers_are_jumpers no)
		(fp_line
			(start 0.508 -0.9398)
			(end 0.508 0.9398)
			(stroke
				(width 0.1524)
				(type default)
			)
			(layer "B.SilkS")
		)
		(fp_line
			(start -0.508 -0.9398)
			(end 0.508 -0.9398)
			(stroke
				(width 0.1524)
				(type default)
			)
			(layer "B.SilkS")
		)
		(fp_rect
			(start 0.508 0.9398)
			(end -0.508 -0.9398)
			(stroke
				(width 0)
				(type default)
			)
			(fill no)
			(layer "B.CrtYd")
		)
		(fp_rect
			(start 0.508 0.9398)
			(end -0.508 -0.9398)
			(stroke
				(width 0)
				(type default)
			)
			(fill no)
			(layer "B.Fab")
		)
		(pad "1" smd custom
			(at 0 -0.4445)
			(size 0.1397 0.1397)
			(layers "B.Cu" "B.Mask" "B.Paste")
			(net "P3V3_STBY")
			(options
				(clearance outline)
				(anchor circle)
			)
			(primitives
				(gr_poly
					(pts
						(arc
							(start -0.1778 0.2794)
							(mid -0.249642 0.249642)
							(end -0.2794 0.1778)
						)
						(arc
							(start -0.2794 -0.1778)
							(mid -0.249642 -0.249642)
							(end -0.1778 -0.2794)
						)
						(arc
							(start 0.1778 -0.2794)
							(mid 0.249642 -0.249642)
							(end 0.2794 -0.1778)
						)
						(arc
							(start 0.2794 0.1778)
							(mid 0.249642 0.249642)
							(end 0.1778 0.2794)
						)
					)
					(width 0)
					(fill yes)
				)
			)
		)
		(pad "2" smd custom
			(at 0 0.4445)
			(size 0.1397 0.1397)
			(layers "B.Cu" "B.Mask" "B.Paste")
			(net "P0V7_GTL2014_VREF_6")
			(options
				(clearance outline)
				(anchor circle)
			)
			(primitives
				(gr_poly
					(pts
						(arc
							(start -0.1778 0.2794)
							(mid -0.249642 0.249642)
							(end -0.2794 0.1778)
						)
						(arc
							(start -0.2794 -0.1778)
							(mid -0.249642 -0.249642)
							(end -0.1778 -0.2794)
						)
						(arc
							(start 0.1778 -0.2794)
							(mid 0.249642 -0.249642)
							(end 0.2794 -0.1778)
						)
						(arc
							(start 0.2794 0.1778)
							(mid 0.249642 0.249642)
							(end 0.1778 0.2794)
						)
					)
					(width 0)
					(fill yes)
				)
			)
		)
	)
	(footprint ""
		(layer "B.Cu")
		(at 385.318 -87.1601 180)
		(property "Reference" "R3P61"
			(at 0 0 0)
			(layer "B.SilkS")
			(hide yes)
			(effects
				(font
					(size 1.27 1.27)
				)
				(justify mirror)
			)
		)
		(property "Value" ""
			(at 0 0 0)
			(layer "B.Fab")
			(effects
				(font
					(size 1.27 1.27)
				)
				(justify mirror)
			)
		)
		(duplicate_pad_numbers_are_jumpers no)
		(fp_poly
			(pts
				(xy 0.2794 -0.1016) (xy -0.2794 -0.1016) (xy -0.2794 0.9906) (xy 0.2794 0.9906)
			)
			(stroke
				(width 0)
				(type default)
			)
			(fill no)
			(layer "B.CrtYd")
		)
		(fp_line
			(start 0.2794 0.9906)
			(end -0.2794 0.9906)
			(stroke
				(width 0.1)
				(type default)
			)
			(layer "B.Fab")
		)
		(fp_line
			(start 0.2794 -0.1016)
			(end 0.2794 0.9906)
			(stroke
				(width 0.1)
				(type default)
			)
			(layer "B.Fab")
		)
		(fp_line
			(start -0.2794 0.9906)
			(end -0.2794 -0.1016)
			(stroke
				(width 0.1)
				(type default)
			)
			(layer "B.Fab")
		)
		(fp_line
			(start -0.2794 -0.1016)
			(end 0.2794 -0.1016)
			(stroke
				(width 0.1)
				(type default)
			)
			(layer "B.Fab")
		)
		(pad "1" smd rect
			(at 0 0)
			(size 0.508 0.508)
			(layers "B.Cu" "B.Mask" "B.Paste")
			(net "P3V3_STBY")
		)
		(pad "2" smd rect
			(at 0 0.889)
			(size 0.508 0.508)
			(layers "B.Cu" "B.Mask" "B.Paste")
			(net "FM_MB_SLOT_ID2")
		)
		(zone
			(layer "B.Cu")
			(hatch none 0.5)
			(connect_pads
				(clearance 0)
			)
			(min_thickness 0.25)
			(keepout
				(tracks not_allowed)
				(vias allowed)
				(pads allowed)
				(copperpour not_allowed)
				(footprints allowed)
			)
			(placement
				(enabled no)
				(sheetname "")
			)
			(fill
				(thermal_gap 0.5)
				(thermal_bridge_width 0.5)
				(island_removal_mode 0)
			)
			(polygon
				(pts
					(xy 385.064 -87.7951) (xy 385.572 -87.7951) (xy 385.572 -87.4141) (xy 385.064 -87.4141)
				)
			)
		)
		(zone
			(layer "B.Cu")
			(hatch none 0.5)
			(connect_pads
				(clearance 0)
			)
			(min_thickness 0.25)
			(keepout
				(tracks allowed)
				(vias not_allowed)
				(pads allowed)
				(copperpour not_allowed)
				(footprints allowed)
			)
			(placement
				(enabled no)
				(sheetname "")
			)
			(fill
				(thermal_gap 0.5)
				(thermal_bridge_width 0.5)
				(island_removal_mode 0)
			)
			(polygon
				(pts
					(xy 385.064 -87.4141) (xy 385.572 -87.4141) (xy 385.572 -87.7951) (xy 385.064 -87.7951)
				)
			)
		)
	)
	(footprint ""
		(layer "B.Cu")
		(at 428.3075 -22.606 -90)
		(property "Reference" "R25W130"
			(at 0.8382 -0.67818 270)
			(unlocked yes)
			(layer "B.SilkS")
			(effects
				(font
					(size 0.4064 0.254)
					(thickness 0.1524)
				)
				(justify left mirror)
			)
		)
		(property "Value" ""
			(at 0 0 90)
			(layer "B.Fab")
			(effects
				(font
					(size 1.27 1.27)
				)
				(justify mirror)
			)
		)
		(duplicate_pad_numbers_are_jumpers no)
		(fp_poly
			(pts
				(xy 0.2794 -0.1016) (xy -0.2794 -0.1016) (xy -0.2794 0.9906) (xy 0.2794 0.9906)
			)
			(stroke
				(width 0)
				(type default)
			)
			(fill no)
			(layer "B.CrtYd")
		)
		(fp_line
			(start -0.2794 0.9906)
			(end -0.2794 -0.1016)
			(stroke
				(width 0.1)
				(type default)
			)
			(layer "B.Fab")
		)
		(fp_line
			(start 0.2794 0.9906)
			(end -0.2794 0.9906)
			(stroke
				(width 0.1)
				(type default)
			)
			(layer "B.Fab")
		)
		(fp_line
			(start -0.2794 -0.1016)
			(end 0.2794 -0.1016)
			(stroke
				(width 0.1)
				(type default)
			)
			(layer "B.Fab")
		)
		(fp_line
			(start 0.2794 -0.1016)
			(end 0.2794 0.9906)
			(stroke
				(width 0.1)
				(type default)
			)
			(layer "B.Fab")
		)
		(pad "1" smd rect
			(at 0 0 90)
			(size 0.508 0.508)
			(layers "B.Cu" "B.Mask" "B.Paste")
			(net "P3V3")
		)
		(pad "2" smd rect
			(at 0 0.889 90)
			(size 0.508 0.508)
			(layers "B.Cu" "B.Mask" "B.Paste")
			(net "I2C_BMC_VGA_DDC_SDA")
		)
		(zone
			(layer "B.Cu")
			(hatch none 0.5)
			(connect_pads
				(clearance 0)
			)
			(min_thickness 0.25)
			(keepout
				(tracks not_allowed)
				(vias allowed)
				(pads allowed)
				(copperpour not_allowed)
				(footprints allowed)
			)
			(placement
				(enabled no)
				(sheetname "")
			)
			(fill
				(thermal_gap 0.5)
				(thermal_bridge_width 0.5)
				(island_removal_mode 0)
			)
			(polygon
				(pts
					(xy 427.6725 -22.352) (xy 427.6725 -22.86) (xy 428.0535 -22.86) (xy 428.0535 -22.352)
				)
			)
		)
		(zone
			(layer "B.Cu")
			(hatch none 0.5)
			(connect_pads
				(clearance 0)
			)
			(min_thickness 0.25)
			(keepout
				(tracks allowed)
				(vias not_allowed)
				(pads allowed)
				(copperpour not_allowed)
				(footprints allowed)
			)
			(placement
				(enabled no)
				(sheetname "")
			)
			(fill
				(thermal_gap 0.5)
				(thermal_bridge_width 0.5)
				(island_removal_mode 0)
			)
			(polygon
				(pts
					(xy 428.0535 -22.352) (xy 428.0535 -22.86) (xy 427.6725 -22.86) (xy 427.6725 -22.352)
				)
			)
		)
	)
	(footprint ""
		(layer "B.Cu")
		(at 471.424 -116.84 180)
		(property "Reference" "R1M17"
			(at 0 0 0)
			(layer "B.SilkS")
			(hide yes)
			(effects
				(font
					(size 1.27 1.27)
				)
				(justify mirror)
			)
		)
		(property "Value" ""
			(at 0 0 0)
			(layer "B.Fab")
			(effects
				(font
					(size 1.27 1.27)
				)
				(justify mirror)
			)
		)
		(duplicate_pad_numbers_are_jumpers no)
		(fp_poly
			(pts
				(xy 0.2794 -0.1016) (xy -0.2794 -0.1016) (xy -0.2794 0.9906) (xy 0.2794 0.9906)
			)
			(stroke
				(width 0)
				(type default)
			)
			(fill no)
			(layer "B.CrtYd")
		)
		(fp_line
			(start 0.2794 0.9906)
			(end -0.2794 0.9906)
			(stroke
				(width 0.1)
				(type default)
			)
			(layer "B.Fab")
		)
		(fp_line
			(start 0.2794 -0.1016)
			(end 0.2794 0.9906)
			(stroke
				(width 0.1)
				(type default)
			)
			(layer "B.Fab")
		)
		(fp_line
			(start -0.2794 0.9906)
			(end -0.2794 -0.1016)
			(stroke
				(width 0.1)
				(type default)
			)
			(layer "B.Fab")
		)
		(fp_line
			(start -0.2794 -0.1016)
			(end 0.2794 -0.1016)
			(stroke
				(width 0.1)
				(type default)
			)
			(layer "B.Fab")
		)
		(pad "1" smd rect
			(at 0 0)
			(size 0.508 0.508)
			(layers "B.Cu" "B.Mask" "B.Paste")
			(net "RMII_BMC_OCP_RXD0")
		)
		(pad "2" smd rect
			(at 0 0.889)
			(size 0.508 0.508)
			(layers "B.Cu" "B.Mask" "B.Paste")
			(net "RMII_BMC_OCP_RXD0_R")
		)
		(zone
			(layer "B.Cu")
			(hatch none 0.5)
			(connect_pads
				(clearance 0)
			)
			(min_thickness 0.25)
			(keepout
				(tracks not_allowed)
				(vias allowed)
				(pads allowed)
				(copperpour not_allowed)
				(footprints allowed)
			)
			(placement
				(enabled no)
				(sheetname "")
			)
			(fill
				(thermal_gap 0.5)
				(thermal_bridge_width 0.5)
				(island_removal_mode 0)
			)
			(polygon
				(pts
					(xy 471.17 -117.475) (xy 471.678 -117.475) (xy 471.678 -117.094) (xy 471.17 -117.094)
				)
			)
		)
		(zone
			(layer "B.Cu")
			(hatch none 0.5)
			(connect_pads
				(clearance 0)
			)
			(min_thickness 0.25)
			(keepout
				(tracks allowed)
				(vias not_allowed)
				(pads allowed)
				(copperpour not_allowed)
				(footprints allowed)
			)
			(placement
				(enabled no)
				(sheetname "")
			)
			(fill
				(thermal_gap 0.5)
				(thermal_bridge_width 0.5)
				(island_removal_mode 0)
			)
			(polygon
				(pts
					(xy 471.17 -117.094) (xy 471.678 -117.094) (xy 471.678 -117.475) (xy 471.17 -117.475)
				)
			)
		)
	)
	(footprint ""
		(layer "B.Cu")
		(at 416.179 -22.987 180)
		(property "Reference" "C25W73"
			(at 0.8382 -0.67818 180)
			(unlocked yes)
			(layer "B.SilkS")
			(effects
				(font
					(size 0.4064 0.254)
					(thickness 0.1524)
				)
				(justify left mirror)
			)
		)
		(property "Value" ""
			(at 0 0 0)
			(layer "B.Fab")
			(effects
				(font
					(size 1.27 1.27)
				)
				(justify mirror)
			)
		)
		(duplicate_pad_numbers_are_jumpers no)
		(fp_poly
			(pts
				(xy -0.3048 -0.1016) (xy -0.3048 0.9906) (xy 0.3048 0.9906) (xy 0.3048 -0.1016)
			)
			(stroke
				(width 0)
				(type default)
			)
			(fill no)
			(layer "B.CrtYd")
		)
		(fp_line
			(start 0.3048 0.9906)
			(end -0.3048 0.9906)
			(stroke
				(width 0.1)
				(type default)
			)
			(layer "B.Fab")
		)
		(fp_line
			(start 0.3048 -0.1016)
			(end 0.3048 0.9906)
			(stroke
				(width 0.1)
				(type default)
			)
			(layer "B.Fab")
		)
		(fp_line
			(start -0.3048 0.9906)
			(end -0.3048 -0.1016)
			(stroke
				(width 0.1)
				(type default)
			)
			(layer "B.Fab")
		)
		(fp_line
			(start -0.3048 -0.1016)
			(end 0.3048 -0.1016)
			(stroke
				(width 0.1)
				(type default)
			)
			(layer "B.Fab")
		)
		(pad "1" smd rect
			(at 0 0)
			(size 0.508 0.508)
			(layers "B.Cu" "B.Mask" "B.Paste")
			(net "BMC_VGA_GREEN")
		)
		(pad "2" smd rect
			(at 0 0.889)
			(size 0.508 0.508)
			(layers "B.Cu" "B.Mask" "B.Paste")
			(net "GND")
		)
		(zone
			(layer "B.Cu")
			(hatch none 0.5)
			(connect_pads
				(clearance 0)
			)
			(min_thickness 0.25)
			(keepout
				(tracks not_allowed)
				(vias allowed)
				(pads allowed)
				(copperpour not_allowed)
				(footprints allowed)
			)
			(placement
				(enabled no)
				(sheetname "")
			)
			(fill
				(thermal_gap 0.5)
				(thermal_bridge_width 0.5)
				(island_removal_mode 0)
			)
			(polygon
				(pts
					(xy 415.925 -23.622) (xy 416.433 -23.622) (xy 416.433 -23.241) (xy 415.925 -23.241)
				)
			)
		)
		(zone
			(layer "B.Cu")
			(hatch none 0.5)
			(connect_pads
				(clearance 0)
			)
			(min_thickness 0.25)
			(keepout
				(tracks allowed)
				(vias not_allowed)
				(pads allowed)
				(copperpour not_allowed)
				(footprints allowed)
			)
			(placement
				(enabled no)
				(sheetname "")
			)
			(fill
				(thermal_gap 0.5)
				(thermal_bridge_width 0.5)
				(island_removal_mode 0)
			)
			(polygon
				(pts
					(xy 415.925 -23.241) (xy 416.433 -23.241) (xy 416.433 -23.622) (xy 415.925 -23.622)
				)
			)
		)
	)
	(footprint ""
		(layer "B.Cu")
		(at 407.3652 -13.0683 180)
		(property "Reference" "R8F24"
			(at 0 0 0)
			(layer "B.SilkS")
			(hide yes)
			(effects
				(font
					(size 1.27 1.27)
				)
				(justify mirror)
			)
		)
		(property "Value" ""
			(at 0 0 0)
			(layer "B.Fab")
			(effects
				(font
					(size 1.27 1.27)
				)
				(justify mirror)
			)
		)
		(duplicate_pad_numbers_are_jumpers no)
		(fp_poly
			(pts
				(xy 0.2794 -0.1016) (xy -0.2794 -0.1016) (xy -0.2794 0.9906) (xy 0.2794 0.9906)
			)
			(stroke
				(width 0)
				(type default)
			)
			(fill no)
			(layer "B.CrtYd")
		)
		(fp_line
			(start 0.2794 0.9906)
			(end -0.2794 0.9906)
			(stroke
				(width 0.1)
				(type default)
			)
			(layer "B.Fab")
		)
		(fp_line
			(start 0.2794 -0.1016)
			(end 0.2794 0.9906)
			(stroke
				(width 0.1)
				(type default)
			)
			(layer "B.Fab")
		)
		(fp_line
			(start -0.2794 0.9906)
			(end -0.2794 -0.1016)
			(stroke
				(width 0.1)
				(type default)
			)
			(layer "B.Fab")
		)
		(fp_line
			(start -0.2794 -0.1016)
			(end 0.2794 -0.1016)
			(stroke
				(width 0.1)
				(type default)
			)
			(layer "B.Fab")
		)
		(pad "1" smd rect
			(at 0 0)
			(size 0.508 0.508)
			(layers "B.Cu" "B.Mask" "B.Paste")
			(net "P3V3_STBY")
		)
		(pad "2" smd rect
			(at 0 0.889)
			(size 0.508 0.508)
			(layers "B.Cu" "B.Mask" "B.Paste")
			(net "FP_NMI_BTN_N")
		)
		(zone
			(layer "B.Cu")
			(hatch none 0.5)
			(connect_pads
				(clearance 0)
			)
			(min_thickness 0.25)
			(keepout
				(tracks not_allowed)
				(vias allowed)
				(pads allowed)
				(copperpour not_allowed)
				(footprints allowed)
			)
			(placement
				(enabled no)
				(sheetname "")
			)
			(fill
				(thermal_gap 0.5)
				(thermal_bridge_width 0.5)
				(island_removal_mode 0)
			)
			(polygon
				(pts
					(xy 407.1112 -13.7033) (xy 407.6192 -13.7033) (xy 407.6192 -13.3223) (xy 407.1112 -13.3223)
				)
			)
		)
		(zone
			(layer "B.Cu")
			(hatch none 0.5)
			(connect_pads
				(clearance 0)
			)
			(min_thickness 0.25)
			(keepout
				(tracks allowed)
				(vias not_allowed)
				(pads allowed)
				(copperpour not_allowed)
				(footprints allowed)
			)
			(placement
				(enabled no)
				(sheetname "")
			)
			(fill
				(thermal_gap 0.5)
				(thermal_bridge_width 0.5)
				(island_removal_mode 0)
			)
			(polygon
				(pts
					(xy 407.1112 -13.3223) (xy 407.6192 -13.3223) (xy 407.6192 -13.7033) (xy 407.1112 -13.7033)
				)
			)
		)
	)
	(footprint ""
		(layer "B.Cu")
		(at 197.239128 -70.787006 90)
		(property "Reference" "R6P19"
			(at 0 0 90)
			(layer "B.SilkS")
			(hide yes)
			(effects
				(font
					(size 1.27 1.27)
				)
				(justify mirror)
			)
		)
		(property "Value" ""
			(at 0 0 90)
			(layer "B.Fab")
			(effects
				(font
					(size 1.27 1.27)
				)
				(justify mirror)
			)
		)
		(duplicate_pad_numbers_are_jumpers no)
		(fp_rect
			(start 0.2794 -0.1016)
			(end -0.2794 0.9906)
			(stroke
				(width 0)
				(type default)
			)
			(fill no)
			(layer "B.CrtYd")
		)
		(fp_line
			(start 0.2794 -0.1016)
			(end 0.2794 0.9906)
			(stroke
				(width 0.1)
				(type default)
			)
			(layer "B.Fab")
		)
		(fp_line
			(start -0.2794 -0.1016)
			(end 0.2794 -0.1016)
			(stroke
				(width 0.1)
				(type default)
			)
			(layer "B.Fab")
		)
		(fp_line
			(start 0.2794 0.9906)
			(end -0.2794 0.9906)
			(stroke
				(width 0.1)
				(type default)
			)
			(layer "B.Fab")
		)
		(fp_line
			(start -0.2794 0.9906)
			(end -0.2794 -0.1016)
			(stroke
				(width 0.1)
				(type default)
			)
			(layer "B.Fab")
		)
		(pad "1" smd rect
			(at 0 0 270)
			(size 0.508 0.508)
			(layers "B.Cu" "B.Mask" "B.Paste")
			(net "VR_PVCCIN_CPU0_PH3_VCIN")
		)
		(pad "2" smd rect
			(at 0 0.889 270)
			(size 0.508 0.508)
			(layers "B.Cu" "B.Mask" "B.Paste")
			(net "P5V_STBY")
		)
		(zone
			(layer "B.Cu")
			(hatch none 0.5)
			(connect_pads
				(clearance 0)
			)
			(min_thickness 0.25)
			(keepout
				(tracks not_allowed)
				(vias allowed)
				(pads allowed)
				(copperpour not_allowed)
				(footprints allowed)
			)
			(placement
				(enabled no)
				(sheetname "")
			)
			(fill
				(thermal_gap 0.5)
				(thermal_bridge_width 0.5)
				(island_removal_mode 0)
			)
			(polygon
				(pts
					(xy 197.493128 -71.041006) (xy 197.493128 -70.533006) (xy 197.874128 -70.533006) (xy 197.874128 -71.041006)
				)
			)
		)
		(zone
			(layer "B.Cu")
			(hatch none 0.5)
			(connect_pads
				(clearance 0)
			)
			(min_thickness 0.25)
			(keepout
				(tracks allowed)
				(vias not_allowed)
				(pads allowed)
				(copperpour not_allowed)
				(footprints allowed)
			)
			(placement
				(enabled no)
				(sheetname "")
			)
			(fill
				(thermal_gap 0.5)
				(thermal_bridge_width 0.5)
				(island_removal_mode 0)
			)
			(polygon
				(pts
					(xy 197.493128 -71.041006) (xy 197.493128 -70.533006) (xy 197.874128 -70.533006) (xy 197.874128 -71.041006)
				)
			)
		)
	)
	(footprint ""
		(layer "B.Cu")
		(at 382.473708 -104.314244 -90)
		(property "Reference" "R3N2"
			(at 0 0 90)
			(layer "B.SilkS")
			(hide yes)
			(effects
				(font
					(size 1.27 1.27)
				)
				(justify mirror)
			)
		)
		(property "Value" ""
			(at 0 0 90)
			(layer "B.Fab")
			(effects
				(font
					(size 1.27 1.27)
				)
				(justify mirror)
			)
		)
		(duplicate_pad_numbers_are_jumpers no)
		(fp_poly
			(pts
				(xy 0.2794 -0.1016) (xy -0.2794 -0.1016) (xy -0.2794 0.9906) (xy 0.2794 0.9906)
			)
			(stroke
				(width 0)
				(type default)
			)
			(fill no)
			(layer "B.CrtYd")
		)
		(fp_line
			(start -0.2794 0.9906)
			(end -0.2794 -0.1016)
			(stroke
				(width 0.1)
				(type default)
			)
			(layer "B.Fab")
		)
		(fp_line
			(start 0.2794 0.9906)
			(end -0.2794 0.9906)
			(stroke
				(width 0.1)
				(type default)
			)
			(layer "B.Fab")
		)
		(fp_line
			(start -0.2794 -0.1016)
			(end 0.2794 -0.1016)
			(stroke
				(width 0.1)
				(type default)
			)
			(layer "B.Fab")
		)
		(fp_line
			(start 0.2794 -0.1016)
			(end 0.2794 0.9906)
			(stroke
				(width 0.1)
				(type default)
			)
			(layer "B.Fab")
		)
		(pad "1" smd rect
			(at 0 0 90)
			(size 0.508 0.508)
			(layers "B.Cu" "B.Mask" "B.Paste")
			(net "P3V3_STBY")
		)
		(pad "2" smd rect
			(at 0 0.889 90)
			(size 0.508 0.508)
			(layers "B.Cu" "B.Mask" "B.Paste")
			(net "FM_FLASH_DESC_OVERRIDE")
		)
		(zone
			(layer "B.Cu")
			(hatch none 0.5)
			(connect_pads
				(clearance 0)
			)
			(min_thickness 0.25)
			(keepout
				(tracks not_allowed)
				(vias allowed)
				(pads allowed)
				(copperpour not_allowed)
				(footprints allowed)
			)
			(placement
				(enabled no)
				(sheetname "")
			)
			(fill
				(thermal_gap 0.5)
				(thermal_bridge_width 0.5)
				(island_removal_mode 0)
			)
			(polygon
				(pts
					(xy 381.838708 -104.060244) (xy 381.838708 -104.568244) (xy 382.219708 -104.568244) (xy 382.219708 -104.060244)
				)
			)
		)
		(zone
			(layer "B.Cu")
			(hatch none 0.5)
			(connect_pads
				(clearance 0)
			)
			(min_thickness 0.25)
			(keepout
				(tracks allowed)
				(vias not_allowed)
				(pads allowed)
				(copperpour not_allowed)
				(footprints allowed)
			)
			(placement
				(enabled no)
				(sheetname "")
			)
			(fill
				(thermal_gap 0.5)
				(thermal_bridge_width 0.5)
				(island_removal_mode 0)
			)
			(polygon
				(pts
					(xy 382.219708 -104.060244) (xy 382.219708 -104.568244) (xy 381.838708 -104.568244) (xy 381.838708 -104.060244)
				)
			)
		)
	)
	(footprint ""
		(layer "B.Cu")
		(at 386.08 -48.006 90)
		(property "Reference" "R3T12"
			(at 0 0 90)
			(layer "B.SilkS")
			(hide yes)
			(effects
				(font
					(size 1.27 1.27)
				)
				(justify mirror)
			)
		)
		(property "Value" ""
			(at 0 0 90)
			(layer "B.Fab")
			(effects
				(font
					(size 1.27 1.27)
				)
				(justify mirror)
			)
		)
		(duplicate_pad_numbers_are_jumpers no)
		(fp_poly
			(pts
				(xy 0.2794 -0.1016) (xy -0.2794 -0.1016) (xy -0.2794 0.9906) (xy 0.2794 0.9906)
			)
			(stroke
				(width 0)
				(type default)
			)
			(fill no)
			(layer "B.CrtYd")
		)
		(fp_line
			(start 0.2794 -0.1016)
			(end 0.2794 0.9906)
			(stroke
				(width 0.1)
				(type default)
			)
			(layer "B.Fab")
		)
		(fp_line
			(start -0.2794 -0.1016)
			(end 0.2794 -0.1016)
			(stroke
				(width 0.1)
				(type default)
			)
			(layer "B.Fab")
		)
		(fp_line
			(start 0.2794 0.9906)
			(end -0.2794 0.9906)
			(stroke
				(width 0.1)
				(type default)
			)
			(layer "B.Fab")
		)
		(fp_line
			(start -0.2794 0.9906)
			(end -0.2794 -0.1016)
			(stroke
				(width 0.1)
				(type default)
			)
			(layer "B.Fab")
		)
		(pad "1" smd rect
			(at 0 0 270)
			(size 0.508 0.508)
			(layers "B.Cu" "B.Mask" "B.Paste")
			(net "P3V3_STBY")
		)
		(pad "2" smd rect
			(at 0 0.889 270)
			(size 0.508 0.508)
			(layers "B.Cu" "B.Mask" "B.Paste")
			(net "PU_BIOS_SPI_WP1_N")
		)
		(zone
			(layer "B.Cu")
			(hatch none 0.5)
			(connect_pads
				(clearance 0)
			)
			(min_thickness 0.25)
			(keepout
				(tracks allowed)
				(vias not_allowed)
				(pads allowed)
				(copperpour not_allowed)
				(footprints allowed)
			)
			(placement
				(enabled no)
				(sheetname "")
			)
			(fill
				(thermal_gap 0.5)
				(thermal_bridge_width 0.5)
				(island_removal_mode 0)
			)
			(polygon
				(pts
					(xy 386.334 -48.26) (xy 386.334 -47.752) (xy 386.715 -47.752) (xy 386.715 -48.26)
				)
			)
		)
		(zone
			(layer "B.Cu")
			(hatch none 0.5)
			(connect_pads
				(clearance 0)
			)
			(min_thickness 0.25)
			(keepout
				(tracks not_allowed)
				(vias allowed)
				(pads allowed)
				(copperpour not_allowed)
				(footprints allowed)
			)
			(placement
				(enabled no)
				(sheetname "")
			)
			(fill
				(thermal_gap 0.5)
				(thermal_bridge_width 0.5)
				(island_removal_mode 0)
			)
			(polygon
				(pts
					(xy 386.715 -48.26) (xy 386.715 -47.752) (xy 386.334 -47.752) (xy 386.334 -48.26)
				)
			)
		)
	)
	(footprint ""
		(layer "B.Cu")
		(at 449.96735 -52.407058)
		(property "Reference" "C1R10"
			(at 0 0 0)
			(layer "B.SilkS")
			(hide yes)
			(effects
				(font
					(size 1.27 1.27)
				)
				(justify mirror)
			)
		)
		(property "Value" ""
			(at 0 0 0)
			(layer "B.Fab")
			(effects
				(font
					(size 1.27 1.27)
				)
				(justify mirror)
			)
		)
		(duplicate_pad_numbers_are_jumpers no)
		(fp_poly
			(pts
				(xy -0.3048 -0.1016) (xy -0.3048 0.9906) (xy 0.3048 0.9906) (xy 0.3048 -0.1016)
			)
			(stroke
				(width 0)
				(type default)
			)
			(fill no)
			(layer "B.CrtYd")
		)
		(fp_line
			(start -0.3048 -0.1016)
			(end 0.3048 -0.1016)
			(stroke
				(width 0.1)
				(type default)
			)
			(layer "B.Fab")
		)
		(fp_line
			(start -0.3048 0.9906)
			(end -0.3048 -0.1016)
			(stroke
				(width 0.1)
				(type default)
			)
			(layer "B.Fab")
		)
		(fp_line
			(start 0.3048 -0.1016)
			(end 0.3048 0.9906)
			(stroke
				(width 0.1)
				(type default)
			)
			(layer "B.Fab")
		)
		(fp_line
			(start 0.3048 0.9906)
			(end -0.3048 0.9906)
			(stroke
				(width 0.1)
				(type default)
			)
			(layer "B.Fab")
		)
		(pad "1" smd rect
			(at 0 0 180)
			(size 0.508 0.508)
			(layers "B.Cu" "B.Mask" "B.Paste")
			(net "P3E_CPU0_PE3_OCP_TXP<4>")
		)
		(pad "2" smd rect
			(at 0 0.889 180)
			(size 0.508 0.508)
			(layers "B.Cu" "B.Mask" "B.Paste")
			(net "P3E_OCP_CPU0_PE3_C_TXP<4>")
		)
		(zone
			(layer "B.Cu")
			(hatch none 0.5)
			(connect_pads
				(clearance 0)
			)
			(min_thickness 0.25)
			(keepout
				(tracks allowed)
				(vias not_allowed)
				(pads allowed)
				(copperpour not_allowed)
				(footprints allowed)
			)
			(placement
				(enabled no)
				(sheetname "")
			)
			(fill
				(thermal_gap 0.5)
				(thermal_bridge_width 0.5)
				(island_removal_mode 0)
			)
			(polygon
				(pts
					(xy 450.22135 -52.153058) (xy 449.71335 -52.153058) (xy 449.71335 -51.772058) (xy 450.22135 -51.772058)
				)
			)
		)
		(zone
			(layer "B.Cu")
			(hatch none 0.5)
			(connect_pads
				(clearance 0)
			)
			(min_thickness 0.25)
			(keepout
				(tracks not_allowed)
				(vias allowed)
				(pads allowed)
				(copperpour not_allowed)
				(footprints allowed)
			)
			(placement
				(enabled no)
				(sheetname "")
			)
			(fill
				(thermal_gap 0.5)
				(thermal_bridge_width 0.5)
				(island_removal_mode 0)
			)
			(polygon
				(pts
					(xy 450.22135 -51.772058) (xy 449.71335 -51.772058) (xy 449.71335 -52.153058) (xy 450.22135 -52.153058)
				)
			)
		)
	)
	(footprint ""
		(layer "B.Cu")
		(at 45.611796 -95.596202 -90)
		(property "Reference" "C9N20"
			(at 0.626872 -3.791204 0)
			(unlocked yes)
			(layer "B.SilkS")
			(effects
				(font
					(size 0.7874 0.5842)
					(thickness 0.1524)
				)
				(justify mirror)
			)
		)
		(property "Value" ""
			(at 0 0 90)
			(layer "B.Fab")
			(effects
				(font
					(size 1.27 1.27)
				)
				(justify mirror)
			)
		)
		(duplicate_pad_numbers_are_jumpers no)
		(fp_line
			(start -2.286 7.366)
			(end -1.600708 7.366)
			(stroke
				(width 0.1524)
				(type default)
			)
			(layer "B.SilkS")
		)
		(fp_line
			(start -2.286 7.366)
			(end -2.286 1.63195)
			(stroke
				(width 0.1524)
				(type default)
			)
			(layer "B.SilkS")
		)
		(fp_line
			(start 2.286 7.366)
			(end 1.60147 7.366)
			(stroke
				(width 0.1524)
				(type default)
			)
			(layer "B.SilkS")
		)
		(fp_line
			(start 2.286 7.366)
			(end 2.286 1.632712)
			(stroke
				(width 0.1524)
				(type default)
			)
			(layer "B.SilkS")
		)
		(fp_line
			(start -2.504948 1.633728)
			(end -1.6002 1.633728)
			(stroke
				(width 0.1524)
				(type default)
			)
			(layer "B.SilkS")
		)
		(fp_line
			(start 2.563114 1.633728)
			(end 1.6002 1.633728)
			(stroke
				(width 0.1524)
				(type default)
			)
			(layer "B.SilkS")
		)
		(fp_line
			(start -2.504948 -1.616456)
			(end -2.504948 1.633728)
			(stroke
				(width 0.1524)
				(type default)
			)
			(layer "B.SilkS")
		)
		(fp_line
			(start -1.6002 -1.616456)
			(end -2.504948 -1.616456)
			(stroke
				(width 0.1524)
				(type default)
			)
			(layer "B.SilkS")
		)
		(fp_line
			(start 1.6002 -1.616456)
			(end 2.563114 -1.616456)
			(stroke
				(width 0.1524)
				(type default)
			)
			(layer "B.SilkS")
		)
		(fp_line
			(start 2.563114 -1.616456)
			(end 2.563114 1.633728)
			(stroke
				(width 0.1524)
				(type default)
			)
			(layer "B.SilkS")
		)
		(fp_rect
			(start 2.286 7.366)
			(end -2.286 -0.254)
			(stroke
				(width 0)
				(type default)
			)
			(fill no)
			(layer "B.CrtYd")
		)
		(fp_line
			(start -2.286 7.366)
			(end 2.286 7.366)
			(stroke
				(width 0.1)
				(type default)
			)
			(layer "B.Fab")
		)
		(fp_line
			(start 2.286 7.366)
			(end 2.286 -0.254)
			(stroke
				(width 0.1)
				(type default)
			)
			(layer "B.Fab")
		)
		(fp_line
			(start -2.286 -0.254)
			(end -2.286 7.366)
			(stroke
				(width 0.1)
				(type default)
			)
			(layer "B.Fab")
		)
		(fp_line
			(start 2.286 -0.254)
			(end -2.286 -0.254)
			(stroke
				(width 0.1)
				(type default)
			)
			(layer "B.Fab")
		)
		(pad "1" smd rect
			(at 0 0 90)
			(size 2.54 3.048)
			(layers "B.Cu" "B.Mask" "B.Paste")
			(net "PVSA_CPU1")
		)
		(pad "2" smd rect
			(at 0 7.112 90)
			(size 2.54 3.048)
			(layers "B.Cu" "B.Mask" "B.Paste")
			(net "GND")
		)
	)
	(footprint ""
		(layer "B.Cu")
		(at 13.360654 -122.704098 180)
		(property "Reference" "C10W2"
			(at 0.8382 -0.67818 180)
			(unlocked yes)
			(layer "B.SilkS")
			(effects
				(font
					(size 0.4064 0.254)
					(thickness 0.1524)
				)
				(justify left mirror)
			)
		)
		(property "Value" ""
			(at 0 0 0)
			(layer "B.Fab")
			(effects
				(font
					(size 1.27 1.27)
				)
				(justify mirror)
			)
		)
		(duplicate_pad_numbers_are_jumpers no)
		(fp_poly
			(pts
				(xy -0.3048 -0.1016) (xy -0.3048 0.9906) (xy 0.3048 0.9906) (xy 0.3048 -0.1016)
			)
			(stroke
				(width 0)
				(type default)
			)
			(fill no)
			(layer "B.CrtYd")
		)
		(fp_line
			(start 0.3048 0.9906)
			(end -0.3048 0.9906)
			(stroke
				(width 0.1)
				(type default)
			)
			(layer "B.Fab")
		)
		(fp_line
			(start 0.3048 -0.1016)
			(end 0.3048 0.9906)
			(stroke
				(width 0.1)
				(type default)
			)
			(layer "B.Fab")
		)
		(fp_line
			(start -0.3048 0.9906)
			(end -0.3048 -0.1016)
			(stroke
				(width 0.1)
				(type default)
			)
			(layer "B.Fab")
		)
		(fp_line
			(start -0.3048 -0.1016)
			(end 0.3048 -0.1016)
			(stroke
				(width 0.1)
				(type default)
			)
			(layer "B.Fab")
		)
		(pad "1" smd rect
			(at 0 0)
			(size 0.508 0.508)
			(layers "B.Cu" "B.Mask" "B.Paste")
			(net "P12V_PUMP")
		)
		(pad "2" smd rect
			(at 0 0.889)
			(size 0.508 0.508)
			(layers "B.Cu" "B.Mask" "B.Paste")
			(net "GND")
		)
		(zone
			(layer "B.Cu")
			(hatch none 0.5)
			(connect_pads
				(clearance 0)
			)
			(min_thickness 0.25)
			(keepout
				(tracks not_allowed)
				(vias allowed)
				(pads allowed)
				(copperpour not_allowed)
				(footprints allowed)
			)
			(placement
				(enabled no)
				(sheetname "")
			)
			(fill
				(thermal_gap 0.5)
				(thermal_bridge_width 0.5)
				(island_removal_mode 0)
			)
			(polygon
				(pts
					(xy 13.106654 -123.339098) (xy 13.614654 -123.339098) (xy 13.614654 -122.958098) (xy 13.106654 -122.958098)
				)
			)
		)
		(zone
			(layer "B.Cu")
			(hatch none 0.5)
			(connect_pads
				(clearance 0)
			)
			(min_thickness 0.25)
			(keepout
				(tracks allowed)
				(vias not_allowed)
				(pads allowed)
				(copperpour not_allowed)
				(footprints allowed)
			)
			(placement
				(enabled no)
				(sheetname "")
			)
			(fill
				(thermal_gap 0.5)
				(thermal_bridge_width 0.5)
				(island_removal_mode 0)
			)
			(polygon
				(pts
					(xy 13.106654 -122.958098) (xy 13.614654 -122.958098) (xy 13.614654 -123.339098) (xy 13.106654 -123.339098)
				)
			)
		)
	)
	(footprint ""
		(layer "B.Cu")
		(at 485.25938 -60.822332 90)
		(property "Reference" "C30W1"
			(at 0.8382 -0.67818 90)
			(unlocked yes)
			(layer "B.SilkS")
			(effects
				(font
					(size 0.4064 0.254)
					(thickness 0.1524)
				)
				(justify left mirror)
			)
		)
		(property "Value" ""
			(at 0 0 90)
			(layer "B.Fab")
			(effects
				(font
					(size 1.27 1.27)
				)
				(justify mirror)
			)
		)
		(duplicate_pad_numbers_are_jumpers no)
		(fp_poly
			(pts
				(xy -0.3048 -0.1016) (xy -0.3048 0.9906) (xy 0.3048 0.9906) (xy 0.3048 -0.1016)
			)
			(stroke
				(width 0)
				(type default)
			)
			(fill no)
			(layer "B.CrtYd")
		)
		(fp_line
			(start 0.3048 -0.1016)
			(end 0.3048 0.9906)
			(stroke
				(width 0.1)
				(type default)
			)
			(layer "B.Fab")
		)
		(fp_line
			(start -0.3048 -0.1016)
			(end 0.3048 -0.1016)
			(stroke
				(width 0.1)
				(type default)
			)
			(layer "B.Fab")
		)
		(fp_line
			(start 0.3048 0.9906)
			(end -0.3048 0.9906)
			(stroke
				(width 0.1)
				(type default)
			)
			(layer "B.Fab")
		)
		(fp_line
			(start -0.3048 0.9906)
			(end -0.3048 -0.1016)
			(stroke
				(width 0.1)
				(type default)
			)
			(layer "B.Fab")
		)
		(pad "1" smd rect
			(at 0 0 270)
			(size 0.508 0.508)
			(layers "B.Cu" "B.Mask" "B.Paste")
			(net "USB3_P01_TXN")
		)
		(pad "2" smd rect
			(at 0 0.889 270)
			(size 0.508 0.508)
			(layers "B.Cu" "B.Mask" "B.Paste")
			(net "USB3_P01_C_TXN")
		)
		(zone
			(layer "B.Cu")
			(hatch none 0.5)
			(connect_pads
				(clearance 0)
			)
			(min_thickness 0.25)
			(keepout
				(tracks allowed)
				(vias not_allowed)
				(pads allowed)
				(copperpour not_allowed)
				(footprints allowed)
			)
			(placement
				(enabled no)
				(sheetname "")
			)
			(fill
				(thermal_gap 0.5)
				(thermal_bridge_width 0.5)
				(island_removal_mode 0)
			)
			(polygon
				(pts
					(xy 485.51338 -61.076332) (xy 485.51338 -60.568332) (xy 485.89438 -60.568332) (xy 485.89438 -61.076332)
				)
			)
		)
		(zone
			(layer "B.Cu")
			(hatch none 0.5)
			(connect_pads
				(clearance 0)
			)
			(min_thickness 0.25)
			(keepout
				(tracks not_allowed)
				(vias allowed)
				(pads allowed)
				(copperpour not_allowed)
				(footprints allowed)
			)
			(placement
				(enabled no)
				(sheetname "")
			)
			(fill
				(thermal_gap 0.5)
				(thermal_bridge_width 0.5)
				(island_removal_mode 0)
			)
			(polygon
				(pts
					(xy 485.89438 -61.076332) (xy 485.89438 -60.568332) (xy 485.51338 -60.568332) (xy 485.51338 -61.076332)
				)
			)
		)
	)
	(footprint ""
		(layer "B.Cu")
		(at 362.715556 -121.392442 -90)
		(property "Reference" "C3M25"
			(at 0 0 90)
			(layer "B.SilkS")
			(hide yes)
			(effects
				(font
					(size 1.27 1.27)
				)
				(justify mirror)
			)
		)
		(property "Value" ""
			(at 0 0 90)
			(layer "B.Fab")
			(effects
				(font
					(size 1.27 1.27)
				)
				(justify mirror)
			)
		)
		(duplicate_pad_numbers_are_jumpers no)
		(fp_poly
			(pts
				(xy -0.3048 -0.1016) (xy -0.3048 0.9906) (xy 0.3048 0.9906) (xy 0.3048 -0.1016)
			)
			(stroke
				(width 0)
				(type default)
			)
			(fill no)
			(layer "B.CrtYd")
		)
		(fp_line
			(start -0.3048 0.9906)
			(end -0.3048 -0.1016)
			(stroke
				(width 0.1)
				(type default)
			)
			(layer "B.Fab")
		)
		(fp_line
			(start 0.3048 0.9906)
			(end -0.3048 0.9906)
			(stroke
				(width 0.1)
				(type default)
			)
			(layer "B.Fab")
		)
		(fp_line
			(start -0.3048 -0.1016)
			(end 0.3048 -0.1016)
			(stroke
				(width 0.1)
				(type default)
			)
			(layer "B.Fab")
		)
		(fp_line
			(start 0.3048 -0.1016)
			(end 0.3048 0.9906)
			(stroke
				(width 0.1)
				(type default)
			)
			(layer "B.Fab")
		)
		(pad "1" smd rect
			(at 0 0 90)
			(size 0.508 0.508)
			(layers "B.Cu" "B.Mask" "B.Paste")
			(net "P3E_CPU0_PE1_PCH_R_RXP<11>")
		)
		(pad "2" smd rect
			(at 0 0.889 90)
			(size 0.508 0.508)
			(layers "B.Cu" "B.Mask" "B.Paste")
			(net "P3E_CPU0_PE1_PCH_RXP<11>")
		)
		(zone
			(layer "B.Cu")
			(hatch none 0.5)
			(connect_pads
				(clearance 0)
			)
			(min_thickness 0.25)
			(keepout
				(tracks not_allowed)
				(vias allowed)
				(pads allowed)
				(copperpour not_allowed)
				(footprints allowed)
			)
			(placement
				(enabled no)
				(sheetname "")
			)
			(fill
				(thermal_gap 0.5)
				(thermal_bridge_width 0.5)
				(island_removal_mode 0)
			)
			(polygon
				(pts
					(xy 362.080556 -121.138442) (xy 362.080556 -121.646442) (xy 362.461556 -121.646442) (xy 362.461556 -121.138442)
				)
			)
		)
		(zone
			(layer "B.Cu")
			(hatch none 0.5)
			(connect_pads
				(clearance 0)
			)
			(min_thickness 0.25)
			(keepout
				(tracks allowed)
				(vias not_allowed)
				(pads allowed)
				(copperpour not_allowed)
				(footprints allowed)
			)
			(placement
				(enabled no)
				(sheetname "")
			)
			(fill
				(thermal_gap 0.5)
				(thermal_bridge_width 0.5)
				(island_removal_mode 0)
			)
			(polygon
				(pts
					(xy 362.461556 -121.138442) (xy 362.461556 -121.646442) (xy 362.080556 -121.646442) (xy 362.080556 -121.138442)
				)
			)
		)
	)
	(footprint ""
		(layer "B.Cu")
		(at 149.065234 -164.916866 90)
		(property "Reference" "T1D6"
			(at 0 0 90)
			(layer "B.SilkS")
			(hide yes)
			(effects
				(font
					(size 1.27 1.27)
				)
				(justify mirror)
			)
		)
		(property "Value" "*"
			(at 3.4036 -4.46405 90)
			(unlocked yes)
			(layer "B.Fab")
			(hide yes)
			(effects
				(font
					(size 0.889 0.889)
					(thickness 0.1524)
				)
				(justify mirror)
			)
		)
		(property "Device Type" "TEST-PAD-12P-1-GP-U_DISCRET-GBA"
			(at 3.4036 -5.98805 90)
			(unlocked yes)
			(layer "B.Fab")
			(hide yes)
			(effects
				(font
					(size 0.889 0.889)
					(thickness 0.1524)
				)
				(justify mirror)
			)
		)
		(duplicate_pad_numbers_are_jumpers no)
		(fp_line
			(start 2.3876 -4.826)
			(end -2.3622 -4.826)
			(stroke
				(width 0.1524)
				(type default)
			)
			(layer "B.SilkS")
		)
		(fp_line
			(start -2.3622 -4.826)
			(end -2.3622 3.4798)
			(stroke
				(width 0.1524)
				(type default)
			)
			(layer "B.SilkS")
		)
		(fp_line
			(start 2.3876 3.4798)
			(end 2.3876 -4.826)
			(stroke
				(width 0.1524)
				(type default)
			)
			(layer "B.SilkS")
		)
		(fp_line
			(start -2.3622 3.4798)
			(end 2.3876 3.4798)
			(stroke
				(width 0.1524)
				(type default)
			)
			(layer "B.SilkS")
		)
		(fp_rect
			(start 2.6416 3.7338)
			(end -2.6162 -5.08)
			(stroke
				(width 0)
				(type default)
			)
			(fill no)
			(layer "B.CrtYd")
		)
		(fp_rect
			(start 2.6416 3.7338)
			(end -2.6162 -5.08)
			(stroke
				(width 0)
				(type default)
			)
			(fill no)
			(layer "B.Fab")
		)
		(pad "1" smd circle
			(at -0.496824 -1.301496 270)
			(size 0.6604 0.6604)
			(layers "B.Cu" "B.Mask" "B.Paste")
			(net "L5_85OHM_5INCH_DN")
		)
		(pad "2" smd circle
			(at 0.503936 -1.301496 270)
			(size 0.6604 0.6604)
			(layers "B.Cu" "B.Mask" "B.Paste")
			(net "L5_85OHM_5INCH_DP")
		)
		(pad "3" smd custom
			(at 0.00889 0.370078 270)
			(size 0.74295 0.74295)
			(layers "B.Cu" "B.Mask" "B.Paste")
			(net "GND")
			(options
				(clearance outline)
				(anchor circle)
			)
			(primitives
				(gr_poly
					(pts
						(xy -2.1209 -1.4859) (xy 2.1209 -1.4859) (xy 2.1209 1.4859) (xy 1.08585 1.4859) (xy 1.08585 0.4699)
						(xy -1.08585 0.4699) (xy -1.08585 1.4859) (xy -2.1209 1.4859)
					)
					(width 0)
					(fill yes)
				)
			)
		)
		(pad "4" thru_hole circle
			(at -1.266444 -3.851656 270)
			(size 1.4478 1.4478)
			(drill 1.0414)
			(layers "*.Cu" "*.Mask")
			(remove_unused_layers no)
			(net "GND")
			(clearance 0.1524)
			(thermal_gap 0.1524)
		)
		(pad "5" thru_hole circle
			(at 1.273556 -3.851656 270)
			(size 1.4478 1.4478)
			(drill 1.0414)
			(layers "*.Cu" "*.Mask")
			(remove_unused_layers no)
			(net "GND")
			(clearance 0.1524)
			(thermal_gap 0.1524)
		)
		(pad "6" thru_hole circle
			(at -1.266444 2.498344 270)
			(size 1.4478 1.4478)
			(drill 1.0414)
			(layers "*.Cu" "*.Mask")
			(remove_unused_layers no)
			(net "GND")
			(clearance 0.1524)
			(thermal_gap 0.1524)
		)
		(pad "7" thru_hole circle
			(at 1.273556 2.498344 270)
			(size 1.4478 1.4478)
			(drill 1.0414)
			(layers "*.Cu" "*.Mask")
			(remove_unused_layers no)
			(net "GND")
			(clearance 0.1524)
			(thermal_gap 0.1524)
		)
		(pad "8" thru_hole circle
			(at -1.27 -0.4572 270)
			(size 0.7112 0.7112)
			(drill 0.4064)
			(layers "*.Cu" "*.Mask")
			(remove_unused_layers no)
			(net "GND")
			(clearance 0.1016)
			(thermal_gap 0.1016)
		)
		(pad "9" thru_hole circle
			(at -1.27 0.762 270)
			(size 0.7112 0.7112)
			(drill 0.4064)
			(layers "*.Cu" "*.Mask")
			(remove_unused_layers no)
			(net "GND")
			(clearance 0.1016)
			(thermal_gap 0.1016)
		)
		(pad "10" thru_hole circle
			(at 0.0254 0.762 270)
			(size 0.7112 0.7112)
			(drill 0.4064)
			(layers "*.Cu" "*.Mask")
			(remove_unused_layers no)
			(net "GND")
			(clearance 0.1016)
			(thermal_gap 0.1016)
		)
		(pad "11" thru_hole circle
			(at 1.27 0.762 270)
			(size 0.7112 0.7112)
			(drill 0.4064)
			(layers "*.Cu" "*.Mask")
			(remove_unused_layers no)
			(net "GND")
			(clearance 0.1016)
			(thermal_gap 0.1016)
		)
		(pad "12" thru_hole circle
			(at 1.27 -0.4572 270)
			(size 0.7112 0.7112)
			(drill 0.4064)
			(layers "*.Cu" "*.Mask")
			(remove_unused_layers no)
			(net "GND")
			(clearance 0.1016)
			(thermal_gap 0.1016)
		)
	)
	(footprint ""
		(layer "B.Cu")
		(at 24.765 -77.978)
		(property "Reference" "R9P19"
			(at 0 0 0)
			(layer "B.SilkS")
			(hide yes)
			(effects
				(font
					(size 1.27 1.27)
				)
				(justify mirror)
			)
		)
		(property "Value" ""
			(at 0 0 0)
			(layer "B.Fab")
			(effects
				(font
					(size 1.27 1.27)
				)
				(justify mirror)
			)
		)
		(duplicate_pad_numbers_are_jumpers no)
		(fp_poly
			(pts
				(xy 0.2794 -0.1016) (xy -0.2794 -0.1016) (xy -0.2794 0.9906) (xy 0.2794 0.9906)
			)
			(stroke
				(width 0)
				(type default)
			)
			(fill no)
			(layer "B.CrtYd")
		)
		(fp_line
			(start -0.2794 -0.1016)
			(end 0.2794 -0.1016)
			(stroke
				(width 0.1)
				(type default)
			)
			(layer "B.Fab")
		)
		(fp_line
			(start -0.2794 0.9906)
			(end -0.2794 -0.1016)
			(stroke
				(width 0.1)
				(type default)
			)
			(layer "B.Fab")
		)
		(fp_line
			(start 0.2794 -0.1016)
			(end 0.2794 0.9906)
			(stroke
				(width 0.1)
				(type default)
			)
			(layer "B.Fab")
		)
		(fp_line
			(start 0.2794 0.9906)
			(end -0.2794 0.9906)
			(stroke
				(width 0.1)
				(type default)
			)
			(layer "B.Fab")
		)
		(pad "1" smd rect
			(at 0 0 180)
			(size 0.508 0.508)
			(layers "B.Cu" "B.Mask" "B.Paste")
			(net "A_HSC_TIMER_R")
		)
		(pad "2" smd rect
			(at 0 0.889 180)
			(size 0.508 0.508)
			(layers "B.Cu" "B.Mask" "B.Paste")
			(net "AGND_HSC")
		)
		(zone
			(layer "B.Cu")
			(hatch none 0.5)
			(connect_pads
				(clearance 0)
			)
			(min_thickness 0.25)
			(keepout
				(tracks allowed)
				(vias not_allowed)
				(pads allowed)
				(copperpour not_allowed)
				(footprints allowed)
			)
			(placement
				(enabled no)
				(sheetname "")
			)
			(fill
				(thermal_gap 0.5)
				(thermal_bridge_width 0.5)
				(island_removal_mode 0)
			)
			(polygon
				(pts
					(xy 25.019 -77.724) (xy 24.511 -77.724) (xy 24.511 -77.343) (xy 25.019 -77.343)
				)
			)
		)
		(zone
			(layer "B.Cu")
			(hatch none 0.5)
			(connect_pads
				(clearance 0)
			)
			(min_thickness 0.25)
			(keepout
				(tracks not_allowed)
				(vias allowed)
				(pads allowed)
				(copperpour not_allowed)
				(footprints allowed)
			)
			(placement
				(enabled no)
				(sheetname "")
			)
			(fill
				(thermal_gap 0.5)
				(thermal_bridge_width 0.5)
				(island_removal_mode 0)
			)
			(polygon
				(pts
					(xy 25.019 -77.343) (xy 24.511 -77.343) (xy 24.511 -77.724) (xy 25.019 -77.724)
				)
			)
		)
	)
	(footprint ""
		(layer "B.Cu")
		(at 85.547708 -125.99162 -90)
		(property "Reference" "SH7L2"
			(at 0 0 90)
			(layer "B.SilkS")
			(hide yes)
			(effects
				(font
					(size 1.27 1.27)
				)
				(justify mirror)
			)
		)
		(property "Value" ""
			(at 0 0 90)
			(layer "B.Fab")
			(effects
				(font
					(size 1.27 1.27)
				)
				(justify mirror)
			)
		)
		(duplicate_pad_numbers_are_jumpers no)
		(fp_poly
			(pts
				(xy 0.1651 -0.0508) (xy 0.1651 0.5842) (xy -0.1651 0.5842) (xy -0.1651 -0.0508)
			)
			(stroke
				(width 0)
				(type default)
			)
			(fill no)
			(layer "B.CrtYd")
		)
		(fp_line
			(start -0.1651 0.5842)
			(end 0.1651 0.5842)
			(stroke
				(width 0.1)
				(type default)
			)
			(layer "B.Fab")
		)
		(fp_line
			(start 0.1651 0.5842)
			(end 0.1651 -0.0508)
			(stroke
				(width 0.1)
				(type default)
			)
			(layer "B.Fab")
		)
		(fp_line
			(start -0.1651 -0.0508)
			(end -0.1651 0.5842)
			(stroke
				(width 0.1)
				(type default)
			)
			(layer "B.Fab")
		)
		(fp_line
			(start 0.1651 -0.0508)
			(end -0.1651 -0.0508)
			(stroke
				(width 0.1)
				(type default)
			)
			(layer "B.Fab")
		)
		(pad "1" smd custom
			(at 0 0 270)
			(size 0.0762 0.0762)
			(layers "B.Cu" "B.Mask" "B.Paste")
			(net "VSENSE_PVDDQ_KLM_P")
			(options
				(clearance outline)
				(anchor circle)
			)
			(primitives
				(gr_poly
					(pts
						(arc
							(start -0.1524 0.10795)
							(mid -0.098518 0.130268)
							(end -0.0762 0.18415)
						)
						(xy -0.0762 0.22225) (xy 0.0762 0.22225)
						(arc
							(start 0.0762 0.18415)
							(mid 0.098518 0.130268)
							(end 0.1524 0.10795)
						)
						(xy 0.1524 -0.22225) (xy -0.1524 -0.22225)
					)
					(width 0)
					(fill yes)
				)
			)
		)
		(pad "2" smd custom
			(at 0 0.5334 90)
			(size 0.0762 0.0762)
			(layers "B.Cu" "B.Mask" "B.Paste")
			(net "PVDDQ_KLM")
			(options
				(clearance outline)
				(anchor circle)
			)
			(primitives
				(gr_poly
					(pts
						(arc
							(start -0.1524 0.10795)
							(mid -0.098518 0.130268)
							(end -0.0762 0.18415)
						)
						(xy -0.0762 0.22225) (xy 0.0762 0.22225)
						(arc
							(start 0.0762 0.18415)
							(mid 0.098518 0.130268)
							(end 0.1524 0.10795)
						)
						(xy 0.1524 -0.22225) (xy -0.1524 -0.22225)
					)
					(width 0)
					(fill yes)
				)
			)
		)
	)
	(footprint ""
		(layer "B.Cu")
		(at 445.72555 -29.6164)
		(property "Reference" "R1T29"
			(at 0 0 0)
			(layer "B.SilkS")
			(hide yes)
			(effects
				(font
					(size 1.27 1.27)
				)
				(justify mirror)
			)
		)
		(property "Value" ""
			(at 0 0 0)
			(layer "B.Fab")
			(effects
				(font
					(size 1.27 1.27)
				)
				(justify mirror)
			)
		)
		(duplicate_pad_numbers_are_jumpers no)
		(fp_poly
			(pts
				(xy 0.2794 -0.1016) (xy -0.2794 -0.1016) (xy -0.2794 0.9906) (xy 0.2794 0.9906)
			)
			(stroke
				(width 0)
				(type default)
			)
			(fill no)
			(layer "B.CrtYd")
		)
		(fp_line
			(start -0.2794 -0.1016)
			(end 0.2794 -0.1016)
			(stroke
				(width 0.1)
				(type default)
			)
			(layer "B.Fab")
		)
		(fp_line
			(start -0.2794 0.9906)
			(end -0.2794 -0.1016)
			(stroke
				(width 0.1)
				(type default)
			)
			(layer "B.Fab")
		)
		(fp_line
			(start 0.2794 -0.1016)
			(end 0.2794 0.9906)
			(stroke
				(width 0.1)
				(type default)
			)
			(layer "B.Fab")
		)
		(fp_line
			(start 0.2794 0.9906)
			(end -0.2794 0.9906)
			(stroke
				(width 0.1)
				(type default)
			)
			(layer "B.Fab")
		)
		(pad "1" smd rect
			(at 0 0 180)
			(size 0.508 0.508)
			(layers "B.Cu" "B.Mask" "B.Paste")
			(net "BMC_M_VREFCA")
		)
		(pad "2" smd rect
			(at 0 0.889 180)
			(size 0.508 0.508)
			(layers "B.Cu" "B.Mask" "B.Paste")
			(net "GND")
		)
		(zone
			(layer "B.Cu")
			(hatch none 0.5)
			(connect_pads
				(clearance 0)
			)
			(min_thickness 0.25)
			(keepout
				(tracks allowed)
				(vias not_allowed)
				(pads allowed)
				(copperpour not_allowed)
				(footprints allowed)
			)
			(placement
				(enabled no)
				(sheetname "")
			)
			(fill
				(thermal_gap 0.5)
				(thermal_bridge_width 0.5)
				(island_removal_mode 0)
			)
			(polygon
				(pts
					(xy 445.97955 -29.3624) (xy 445.47155 -29.3624) (xy 445.47155 -28.9814) (xy 445.97955 -28.9814)
				)
			)
		)
		(zone
			(layer "B.Cu")
			(hatch none 0.5)
			(connect_pads
				(clearance 0)
			)
			(min_thickness 0.25)
			(keepout
				(tracks not_allowed)
				(vias allowed)
				(pads allowed)
				(copperpour not_allowed)
				(footprints allowed)
			)
			(placement
				(enabled no)
				(sheetname "")
			)
			(fill
				(thermal_gap 0.5)
				(thermal_bridge_width 0.5)
				(island_removal_mode 0)
			)
			(polygon
				(pts
					(xy 445.97955 -28.9814) (xy 445.47155 -28.9814) (xy 445.47155 -29.3624) (xy 445.97955 -29.3624)
				)
			)
		)
	)
	(footprint ""
		(layer "B.Cu")
		(at 366.268 -40.5892 180)
		(property "Reference" "C8F5"
			(at 0 0 0)
			(layer "B.SilkS")
			(hide yes)
			(effects
				(font
					(size 1.27 1.27)
				)
				(justify mirror)
			)
		)
		(property "Value" ""
			(at 0 0 0)
			(layer "B.Fab")
			(effects
				(font
					(size 1.27 1.27)
				)
				(justify mirror)
			)
		)
		(duplicate_pad_numbers_are_jumpers no)
		(fp_poly
			(pts
				(xy -0.3048 -0.1016) (xy -0.3048 0.9906) (xy 0.3048 0.9906) (xy 0.3048 -0.1016)
			)
			(stroke
				(width 0)
				(type default)
			)
			(fill no)
			(layer "B.CrtYd")
		)
		(fp_line
			(start 0.3048 0.9906)
			(end -0.3048 0.9906)
			(stroke
				(width 0.1)
				(type default)
			)
			(layer "B.Fab")
		)
		(fp_line
			(start 0.3048 -0.1016)
			(end 0.3048 0.9906)
			(stroke
				(width 0.1)
				(type default)
			)
			(layer "B.Fab")
		)
		(fp_line
			(start -0.3048 0.9906)
			(end -0.3048 -0.1016)
			(stroke
				(width 0.1)
				(type default)
			)
			(layer "B.Fab")
		)
		(fp_line
			(start -0.3048 -0.1016)
			(end 0.3048 -0.1016)
			(stroke
				(width 0.1)
				(type default)
			)
			(layer "B.Fab")
		)
		(pad "1" smd rect
			(at 0 0)
			(size 0.508 0.508)
			(layers "B.Cu" "B.Mask" "B.Paste")
			(net "P3V3_STBY")
		)
		(pad "2" smd rect
			(at 0 0.889)
			(size 0.508 0.508)
			(layers "B.Cu" "B.Mask" "B.Paste")
			(net "GND")
		)
		(zone
			(layer "B.Cu")
			(hatch none 0.5)
			(connect_pads
				(clearance 0)
			)
			(min_thickness 0.25)
			(keepout
				(tracks not_allowed)
				(vias allowed)
				(pads allowed)
				(copperpour not_allowed)
				(footprints allowed)
			)
			(placement
				(enabled no)
				(sheetname "")
			)
			(fill
				(thermal_gap 0.5)
				(thermal_bridge_width 0.5)
				(island_removal_mode 0)
			)
			(polygon
				(pts
					(xy 366.014 -41.2242) (xy 366.522 -41.2242) (xy 366.522 -40.8432) (xy 366.014 -40.8432)
				)
			)
		)
		(zone
			(layer "B.Cu")
			(hatch none 0.5)
			(connect_pads
				(clearance 0)
			)
			(min_thickness 0.25)
			(keepout
				(tracks allowed)
				(vias not_allowed)
				(pads allowed)
				(copperpour not_allowed)
				(footprints allowed)
			)
			(placement
				(enabled no)
				(sheetname "")
			)
			(fill
				(thermal_gap 0.5)
				(thermal_bridge_width 0.5)
				(island_removal_mode 0)
			)
			(polygon
				(pts
					(xy 366.014 -40.8432) (xy 366.522 -40.8432) (xy 366.522 -41.2242) (xy 366.014 -41.2242)
				)
			)
		)
	)
	(footprint ""
		(layer "B.Cu")
		(at 444.548006 -43.54195 180)
		(property "Reference" "R25W44"
			(at 0 0 0)
			(layer "B.SilkS")
			(hide yes)
			(effects
				(font
					(size 1.27 1.27)
				)
				(justify mirror)
			)
		)
		(property "Value" "*"
			(at -0.064008 -4.108196 180)
			(unlocked yes)
			(layer "B.Fab")
			(hide yes)
			(effects
				(font
					(size 1.27 1.016)
					(thickness 0.1524)
				)
				(justify mirror)
			)
		)
		(property "Device Type" "120R2F-GP_RCL_GP-120R2F-GP,64.A"
			(at -0.064008 -5.632196 180)
			(unlocked yes)
			(layer "B.Fab")
			(hide yes)
			(effects
				(font
					(size 1.27 1.016)
					(thickness 0.1524)
				)
				(justify mirror)
			)
		)
		(duplicate_pad_numbers_are_jumpers no)
		(fp_line
			(start 0.508 -0.9398)
			(end 0.508 0.9398)
			(stroke
				(width 0.1524)
				(type default)
			)
			(layer "B.SilkS")
		)
		(fp_line
			(start -0.508 -0.9398)
			(end 0.508 -0.9398)
			(stroke
				(width 0.1524)
				(type default)
			)
			(layer "B.SilkS")
		)
		(fp_rect
			(start 0.508 0.9398)
			(end -0.508 -0.9398)
			(stroke
				(width 0)
				(type default)
			)
			(fill no)
			(layer "B.CrtYd")
		)
		(fp_rect
			(start 0.508 0.9398)
			(end -0.508 -0.9398)
			(stroke
				(width 0)
				(type default)
			)
			(fill no)
			(layer "B.Fab")
		)
		(pad "1" smd custom
			(at 0 -0.4445)
			(size 0.1397 0.1397)
			(layers "B.Cu" "B.Mask" "B.Paste")
			(net "BMC_M_A6")
			(options
				(clearance outline)
				(anchor circle)
			)
			(primitives
				(gr_poly
					(pts
						(arc
							(start -0.1778 0.2794)
							(mid -0.249642 0.249642)
							(end -0.2794 0.1778)
						)
						(arc
							(start -0.2794 -0.1778)
							(mid -0.249642 -0.249642)
							(end -0.1778 -0.2794)
						)
						(arc
							(start 0.1778 -0.2794)
							(mid 0.249642 -0.249642)
							(end 0.2794 -0.1778)
						)
						(arc
							(start 0.2794 0.1778)
							(mid 0.249642 0.249642)
							(end 0.1778 0.2794)
						)
					)
					(width 0)
					(fill yes)
				)
			)
		)
		(pad "2" smd custom
			(at 0 0.4445)
			(size 0.1397 0.1397)
			(layers "B.Cu" "B.Mask" "B.Paste")
			(net "P1V2_AUX_BMC")
			(options
				(clearance outline)
				(anchor circle)
			)
			(primitives
				(gr_poly
					(pts
						(arc
							(start -0.1778 0.2794)
							(mid -0.249642 0.249642)
							(end -0.2794 0.1778)
						)
						(arc
							(start -0.2794 -0.1778)
							(mid -0.249642 -0.249642)
							(end -0.1778 -0.2794)
						)
						(arc
							(start 0.1778 -0.2794)
							(mid 0.249642 -0.249642)
							(end 0.2794 -0.1778)
						)
						(arc
							(start 0.2794 0.1778)
							(mid 0.249642 0.249642)
							(end 0.1778 0.2794)
						)
					)
					(width 0)
					(fill yes)
				)
			)
		)
	)
	(footprint ""
		(layer "B.Cu")
		(at 461.899 -146.304 90)
		(property "Reference" "C1L5"
			(at 0 0 90)
			(layer "B.SilkS")
			(hide yes)
			(effects
				(font
					(size 1.27 1.27)
				)
				(justify mirror)
			)
		)
		(property "Value" ""
			(at 0 0 90)
			(layer "B.Fab")
			(effects
				(font
					(size 1.27 1.27)
				)
				(justify mirror)
			)
		)
		(duplicate_pad_numbers_are_jumpers no)
		(fp_poly
			(pts
				(xy -0.3048 -0.1016) (xy -0.3048 0.9906) (xy 0.3048 0.9906) (xy 0.3048 -0.1016)
			)
			(stroke
				(width 0)
				(type default)
			)
			(fill no)
			(layer "B.CrtYd")
		)
		(fp_line
			(start 0.3048 -0.1016)
			(end 0.3048 0.9906)
			(stroke
				(width 0.1)
				(type default)
			)
			(layer "B.Fab")
		)
		(fp_line
			(start -0.3048 -0.1016)
			(end 0.3048 -0.1016)
			(stroke
				(width 0.1)
				(type default)
			)
			(layer "B.Fab")
		)
		(fp_line
			(start 0.3048 0.9906)
			(end -0.3048 0.9906)
			(stroke
				(width 0.1)
				(type default)
			)
			(layer "B.Fab")
		)
		(fp_line
			(start -0.3048 0.9906)
			(end -0.3048 -0.1016)
			(stroke
				(width 0.1)
				(type default)
			)
			(layer "B.Fab")
		)
		(pad "1" smd rect
			(at 0 0 270)
			(size 0.508 0.508)
			(layers "B.Cu" "B.Mask" "B.Paste")
			(net "P1V05_PCH_STBY")
		)
		(pad "2" smd rect
			(at 0 0.889 270)
			(size 0.508 0.508)
			(layers "B.Cu" "B.Mask" "B.Paste")
			(net "GND")
		)
		(zone
			(layer "B.Cu")
			(hatch none 0.5)
			(connect_pads
				(clearance 0)
			)
			(min_thickness 0.25)
			(keepout
				(tracks allowed)
				(vias not_allowed)
				(pads allowed)
				(copperpour not_allowed)
				(footprints allowed)
			)
			(placement
				(enabled no)
				(sheetname "")
			)
			(fill
				(thermal_gap 0.5)
				(thermal_bridge_width 0.5)
				(island_removal_mode 0)
			)
			(polygon
				(pts
					(xy 462.153 -146.558) (xy 462.153 -146.05) (xy 462.534 -146.05) (xy 462.534 -146.558)
				)
			)
		)
		(zone
			(layer "B.Cu")
			(hatch none 0.5)
			(connect_pads
				(clearance 0)
			)
			(min_thickness 0.25)
			(keepout
				(tracks not_allowed)
				(vias allowed)
				(pads allowed)
				(copperpour not_allowed)
				(footprints allowed)
			)
			(placement
				(enabled no)
				(sheetname "")
			)
			(fill
				(thermal_gap 0.5)
				(thermal_bridge_width 0.5)
				(island_removal_mode 0)
			)
			(polygon
				(pts
					(xy 462.534 -146.558) (xy 462.534 -146.05) (xy 462.153 -146.05) (xy 462.153 -146.558)
				)
			)
		)
	)
	(footprint ""
		(layer "B.Cu")
		(at 488.22864 -60.024772 90)
		(property "Reference" "R30W4"
			(at 0.8382 -0.67818 90)
			(unlocked yes)
			(layer "B.SilkS")
			(effects
				(font
					(size 0.4064 0.254)
					(thickness 0.1524)
				)
				(justify left mirror)
			)
		)
		(property "Value" ""
			(at 0 0 90)
			(layer "B.Fab")
			(effects
				(font
					(size 1.27 1.27)
				)
				(justify mirror)
			)
		)
		(duplicate_pad_numbers_are_jumpers no)
		(fp_poly
			(pts
				(xy 0.2794 -0.1016) (xy -0.2794 -0.1016) (xy -0.2794 0.9906) (xy 0.2794 0.9906)
			)
			(stroke
				(width 0)
				(type default)
			)
			(fill no)
			(layer "B.CrtYd")
		)
		(fp_line
			(start 0.2794 -0.1016)
			(end 0.2794 0.9906)
			(stroke
				(width 0.1)
				(type default)
			)
			(layer "B.Fab")
		)
		(fp_line
			(start -0.2794 -0.1016)
			(end 0.2794 -0.1016)
			(stroke
				(width 0.1)
				(type default)
			)
			(layer "B.Fab")
		)
		(fp_line
			(start 0.2794 0.9906)
			(end -0.2794 0.9906)
			(stroke
				(width 0.1)
				(type default)
			)
			(layer "B.Fab")
		)
		(fp_line
			(start -0.2794 0.9906)
			(end -0.2794 -0.1016)
			(stroke
				(width 0.1)
				(type default)
			)
			(layer "B.Fab")
		)
		(pad "1" smd rect
			(at 0 0 270)
			(size 0.508 0.508)
			(layers "B.Cu" "B.Mask" "B.Paste")
			(net "USB3_P01_C_TXP")
		)
		(pad "2" smd rect
			(at 0 0.889 270)
			(size 0.508 0.508)
			(layers "B.Cu" "B.Mask" "B.Paste")
			(net "USB3_P01_FB_TXP")
		)
		(zone
			(layer "B.Cu")
			(hatch none 0.5)
			(connect_pads
				(clearance 0)
			)
			(min_thickness 0.25)
			(keepout
				(tracks allowed)
				(vias not_allowed)
				(pads allowed)
				(copperpour not_allowed)
				(footprints allowed)
			)
			(placement
				(enabled no)
				(sheetname "")
			)
			(fill
				(thermal_gap 0.5)
				(thermal_bridge_width 0.5)
				(island_removal_mode 0)
			)
			(polygon
				(pts
					(xy 488.48264 -60.278772) (xy 488.48264 -59.770772) (xy 488.86364 -59.770772) (xy 488.86364 -60.278772)
				)
			)
		)
		(zone
			(layer "B.Cu")
			(hatch none 0.5)
			(connect_pads
				(clearance 0)
			)
			(min_thickness 0.25)
			(keepout
				(tracks not_allowed)
				(vias allowed)
				(pads allowed)
				(copperpour not_allowed)
				(footprints allowed)
			)
			(placement
				(enabled no)
				(sheetname "")
			)
			(fill
				(thermal_gap 0.5)
				(thermal_bridge_width 0.5)
				(island_removal_mode 0)
			)
			(polygon
				(pts
					(xy 488.86364 -60.278772) (xy 488.86364 -59.770772) (xy 488.48264 -59.770772) (xy 488.48264 -60.278772)
				)
			)
		)
	)
	(footprint ""
		(layer "B.Cu")
		(at 461.7466 -126.7714)
		(property "Reference" "C1M36"
			(at 0 0 0)
			(layer "B.SilkS")
			(hide yes)
			(effects
				(font
					(size 1.27 1.27)
				)
				(justify mirror)
			)
		)
		(property "Value" ""
			(at 0 0 0)
			(layer "B.Fab")
			(effects
				(font
					(size 1.27 1.27)
				)
				(justify mirror)
			)
		)
		(duplicate_pad_numbers_are_jumpers no)
		(fp_poly
			(pts
				(xy -0.3048 -0.1016) (xy -0.3048 0.9906) (xy 0.3048 0.9906) (xy 0.3048 -0.1016)
			)
			(stroke
				(width 0)
				(type default)
			)
			(fill no)
			(layer "B.CrtYd")
		)
		(fp_line
			(start -0.3048 -0.1016)
			(end 0.3048 -0.1016)
			(stroke
				(width 0.1)
				(type default)
			)
			(layer "B.Fab")
		)
		(fp_line
			(start -0.3048 0.9906)
			(end -0.3048 -0.1016)
			(stroke
				(width 0.1)
				(type default)
			)
			(layer "B.Fab")
		)
		(fp_line
			(start 0.3048 -0.1016)
			(end 0.3048 0.9906)
			(stroke
				(width 0.1)
				(type default)
			)
			(layer "B.Fab")
		)
		(fp_line
			(start 0.3048 0.9906)
			(end -0.3048 0.9906)
			(stroke
				(width 0.1)
				(type default)
			)
			(layer "B.Fab")
		)
		(pad "1" smd rect
			(at 0 0 180)
			(size 0.508 0.508)
			(layers "B.Cu" "B.Mask" "B.Paste")
			(net "P3V3_STBY")
		)
		(pad "2" smd rect
			(at 0 0.889 180)
			(size 0.508 0.508)
			(layers "B.Cu" "B.Mask" "B.Paste")
			(net "GND")
		)
		(zone
			(layer "B.Cu")
			(hatch none 0.5)
			(connect_pads
				(clearance 0)
			)
			(min_thickness 0.25)
			(keepout
				(tracks allowed)
				(vias not_allowed)
				(pads allowed)
				(copperpour not_allowed)
				(footprints allowed)
			)
			(placement
				(enabled no)
				(sheetname "")
			)
			(fill
				(thermal_gap 0.5)
				(thermal_bridge_width 0.5)
				(island_removal_mode 0)
			)
			(polygon
				(pts
					(xy 462.0006 -126.5174) (xy 461.4926 -126.5174) (xy 461.4926 -126.1364) (xy 462.0006 -126.1364)
				)
			)
		)
		(zone
			(layer "B.Cu")
			(hatch none 0.5)
			(connect_pads
				(clearance 0)
			)
			(min_thickness 0.25)
			(keepout
				(tracks not_allowed)
				(vias allowed)
				(pads allowed)
				(copperpour not_allowed)
				(footprints allowed)
			)
			(placement
				(enabled no)
				(sheetname "")
			)
			(fill
				(thermal_gap 0.5)
				(thermal_bridge_width 0.5)
				(island_removal_mode 0)
			)
			(polygon
				(pts
					(xy 462.0006 -126.1364) (xy 461.4926 -126.1364) (xy 461.4926 -126.5174) (xy 462.0006 -126.5174)
				)
			)
		)
	)
	(footprint ""
		(layer "B.Cu")
		(at 474.801946 -128.020572 -90)
		(property "Reference" "R1W33"
			(at 0.8382 -0.67818 270)
			(unlocked yes)
			(layer "B.SilkS")
			(effects
				(font
					(size 0.4064 0.254)
					(thickness 0.1524)
				)
				(justify left mirror)
			)
		)
		(property "Value" ""
			(at 0 0 90)
			(layer "B.Fab")
			(effects
				(font
					(size 1.27 1.27)
				)
				(justify mirror)
			)
		)
		(duplicate_pad_numbers_are_jumpers no)
		(fp_poly
			(pts
				(xy 0.2794 -0.1016) (xy -0.2794 -0.1016) (xy -0.2794 0.9906) (xy 0.2794 0.9906)
			)
			(stroke
				(width 0)
				(type default)
			)
			(fill no)
			(layer "B.CrtYd")
		)
		(fp_line
			(start -0.2794 0.9906)
			(end -0.2794 -0.1016)
			(stroke
				(width 0.1)
				(type default)
			)
			(layer "B.Fab")
		)
		(fp_line
			(start 0.2794 0.9906)
			(end -0.2794 0.9906)
			(stroke
				(width 0.1)
				(type default)
			)
			(layer "B.Fab")
		)
		(fp_line
			(start -0.2794 -0.1016)
			(end 0.2794 -0.1016)
			(stroke
				(width 0.1)
				(type default)
			)
			(layer "B.Fab")
		)
		(fp_line
			(start 0.2794 -0.1016)
			(end 0.2794 0.9906)
			(stroke
				(width 0.1)
				(type default)
			)
			(layer "B.Fab")
		)
		(pad "1" smd rect
			(at 0 0 90)
			(size 0.508 0.508)
			(layers "B.Cu" "B.Mask" "B.Paste")
			(net "SMB_DEBUG_STBY_LVC3_SCL_R1")
		)
		(pad "2" smd rect
			(at 0 0.889 90)
			(size 0.508 0.508)
			(layers "B.Cu" "B.Mask" "B.Paste")
			(net "SMB_DEBUG_STBY_LVC3_SCL")
		)
		(zone
			(layer "B.Cu")
			(hatch none 0.5)
			(connect_pads
				(clearance 0)
			)
			(min_thickness 0.25)
			(keepout
				(tracks not_allowed)
				(vias allowed)
				(pads allowed)
				(copperpour not_allowed)
				(footprints allowed)
			)
			(placement
				(enabled no)
				(sheetname "")
			)
			(fill
				(thermal_gap 0.5)
				(thermal_bridge_width 0.5)
				(island_removal_mode 0)
			)
			(polygon
				(pts
					(xy 474.166946 -127.766572) (xy 474.166946 -128.274572) (xy 474.547946 -128.274572) (xy 474.547946 -127.766572)
				)
			)
		)
		(zone
			(layer "B.Cu")
			(hatch none 0.5)
			(connect_pads
				(clearance 0)
			)
			(min_thickness 0.25)
			(keepout
				(tracks allowed)
				(vias not_allowed)
				(pads allowed)
				(copperpour not_allowed)
				(footprints allowed)
			)
			(placement
				(enabled no)
				(sheetname "")
			)
			(fill
				(thermal_gap 0.5)
				(thermal_bridge_width 0.5)
				(island_removal_mode 0)
			)
			(polygon
				(pts
					(xy 474.547946 -127.766572) (xy 474.547946 -128.274572) (xy 474.166946 -128.274572) (xy 474.166946 -127.766572)
				)
			)
		)
	)
	(footprint ""
		(layer "B.Cu")
		(at 338.328 -11.938 90)
		(property "Reference" "R3U4"
			(at 0 0 90)
			(layer "B.SilkS")
			(hide yes)
			(effects
				(font
					(size 1.27 1.27)
				)
				(justify mirror)
			)
		)
		(property "Value" ""
			(at 0 0 90)
			(layer "B.Fab")
			(effects
				(font
					(size 1.27 1.27)
				)
				(justify mirror)
			)
		)
		(duplicate_pad_numbers_are_jumpers no)
		(fp_rect
			(start 0.4953 1.6002)
			(end -0.4953 -0.2032)
			(stroke
				(width 0)
				(type default)
			)
			(fill no)
			(layer "B.CrtYd")
		)
		(fp_line
			(start 0.4953 -0.2032)
			(end -0.4953 -0.2032)
			(stroke
				(width 0.1)
				(type default)
			)
			(layer "B.Fab")
		)
		(fp_line
			(start -0.4953 -0.2032)
			(end -0.4953 1.6002)
			(stroke
				(width 0.1)
				(type default)
			)
			(layer "B.Fab")
		)
		(fp_line
			(start 0.4953 1.6002)
			(end 0.4953 -0.2032)
			(stroke
				(width 0.1)
				(type default)
			)
			(layer "B.Fab")
		)
		(fp_line
			(start -0.4953 1.6002)
			(end 0.4953 1.6002)
			(stroke
				(width 0.1)
				(type default)
			)
			(layer "B.Fab")
		)
		(pad "1" smd rect
			(at 0 0 270)
			(size 0.762 0.889)
			(layers "B.Cu" "B.Mask" "B.Paste")
			(net "PVDDQ_ABC")
		)
		(pad "2" smd rect
			(at 0 1.397 270)
			(size 0.762 0.889)
			(layers "B.Cu" "B.Mask" "B.Paste")
			(net "GND")
		)
		(zone
			(layer "B.Cu")
			(hatch none 0.5)
			(connect_pads
				(clearance 0)
			)
			(min_thickness 0.25)
			(keepout
				(tracks not_allowed)
				(vias allowed)
				(pads allowed)
				(copperpour not_allowed)
				(footprints allowed)
			)
			(placement
				(enabled no)
				(sheetname "")
			)
			(fill
				(thermal_gap 0.5)
				(thermal_bridge_width 0.5)
				(island_removal_mode 0)
			)
			(polygon
				(pts
					(xy 339.2805 -12.319) (xy 338.7725 -12.319) (xy 338.7725 -11.557) (xy 339.2805 -11.557)
				)
			)
		)
		(zone
			(layer "B.Cu")
			(hatch none 0.5)
			(connect_pads
				(clearance 0)
			)
			(min_thickness 0.25)
			(keepout
				(tracks allowed)
				(vias not_allowed)
				(pads allowed)
				(copperpour not_allowed)
				(footprints allowed)
			)
			(placement
				(enabled no)
				(sheetname "")
			)
			(fill
				(thermal_gap 0.5)
				(thermal_bridge_width 0.5)
				(island_removal_mode 0)
			)
			(polygon
				(pts
					(xy 339.2805 -12.319) (xy 338.7725 -12.319) (xy 338.7725 -11.557) (xy 339.2805 -11.557)
				)
			)
		)
	)
	(footprint ""
		(layer "B.Cu")
		(at 9.7536 -41.6814 -90)
		(property "Reference" "R9R9"
			(at 0 0 90)
			(layer "B.SilkS")
			(hide yes)
			(effects
				(font
					(size 1.27 1.27)
				)
				(justify mirror)
			)
		)
		(property "Value" ""
			(at 0 0 90)
			(layer "B.Fab")
			(effects
				(font
					(size 1.27 1.27)
				)
				(justify mirror)
			)
		)
		(duplicate_pad_numbers_are_jumpers no)
		(fp_poly
			(pts
				(xy 0.2794 -0.1016) (xy -0.2794 -0.1016) (xy -0.2794 0.9906) (xy 0.2794 0.9906)
			)
			(stroke
				(width 0)
				(type default)
			)
			(fill no)
			(layer "B.CrtYd")
		)
		(fp_line
			(start -0.2794 0.9906)
			(end -0.2794 -0.1016)
			(stroke
				(width 0.1)
				(type default)
			)
			(layer "B.Fab")
		)
		(fp_line
			(start 0.2794 0.9906)
			(end -0.2794 0.9906)
			(stroke
				(width 0.1)
				(type default)
			)
			(layer "B.Fab")
		)
		(fp_line
			(start -0.2794 -0.1016)
			(end 0.2794 -0.1016)
			(stroke
				(width 0.1)
				(type default)
			)
			(layer "B.Fab")
		)
		(fp_line
			(start 0.2794 -0.1016)
			(end 0.2794 0.9906)
			(stroke
				(width 0.1)
				(type default)
			)
			(layer "B.Fab")
		)
		(pad "1" smd rect
			(at 0 0 90)
			(size 0.508 0.508)
			(layers "B.Cu" "B.Mask" "B.Paste")
			(net "FAN_TACH3")
		)
		(pad "2" smd rect
			(at 0 0.889 90)
			(size 0.508 0.508)
			(layers "B.Cu" "B.Mask" "B.Paste")
			(net "FAN_TACH3_R")
		)
		(zone
			(layer "B.Cu")
			(hatch none 0.5)
			(connect_pads
				(clearance 0)
			)
			(min_thickness 0.25)
			(keepout
				(tracks not_allowed)
				(vias allowed)
				(pads allowed)
				(copperpour not_allowed)
				(footprints allowed)
			)
			(placement
				(enabled no)
				(sheetname "")
			)
			(fill
				(thermal_gap 0.5)
				(thermal_bridge_width 0.5)
				(island_removal_mode 0)
			)
			(polygon
				(pts
					(xy 9.1186 -41.4274) (xy 9.1186 -41.9354) (xy 9.4996 -41.9354) (xy 9.4996 -41.4274)
				)
			)
		)
		(zone
			(layer "B.Cu")
			(hatch none 0.5)
			(connect_pads
				(clearance 0)
			)
			(min_thickness 0.25)
			(keepout
				(tracks allowed)
				(vias not_allowed)
				(pads allowed)
				(copperpour not_allowed)
				(footprints allowed)
			)
			(placement
				(enabled no)
				(sheetname "")
			)
			(fill
				(thermal_gap 0.5)
				(thermal_bridge_width 0.5)
				(island_removal_mode 0)
			)
			(polygon
				(pts
					(xy 9.4996 -41.4274) (xy 9.4996 -41.9354) (xy 9.1186 -41.9354) (xy 9.1186 -41.4274)
				)
			)
		)
	)
	(footprint ""
		(layer "B.Cu")
		(at 346.821506 -2.152904 -90)
		(property "Reference" "C7G42"
			(at 0 0 90)
			(layer "B.SilkS")
			(hide yes)
			(effects
				(font
					(size 1.27 1.27)
				)
				(justify mirror)
			)
		)
		(property "Value" "*"
			(at -1.1811 -2.8194 270)
			(unlocked yes)
			(layer "B.Fab")
			(hide yes)
			(effects
				(font
					(size 1.27 1.016)
					(thickness 0.1524)
				)
				(justify mirror)
			)
		)
		(property "Device Type" "SC1U10V2KX-4-GP_SMD-BCG6-SC1U1A"
			(at -1.1811 -4.3434 270)
			(unlocked yes)
			(layer "B.Fab")
			(hide yes)
			(effects
				(font
					(size 1.27 1.016)
					(thickness 0.1524)
				)
				(justify mirror)
			)
		)
		(duplicate_pad_numbers_are_jumpers no)
		(fp_rect
			(start 0.4318 0.9525)
			(end -0.4318 -0.9525)
			(stroke
				(width 0)
				(type default)
			)
			(fill no)
			(layer "B.CrtYd")
		)
		(fp_rect
			(start 0.4318 0.9525)
			(end -0.4318 -0.9525)
			(stroke
				(width 0)
				(type default)
			)
			(fill no)
			(layer "B.Fab")
		)
		(pad "1" smd custom
			(at 0 -0.4445 90)
			(size 0.1524 0.1524)
			(layers "B.Cu" "B.Mask" "B.Paste")
			(net "P5V_STBY")
			(options
				(clearance outline)
				(anchor circle)
			)
			(primitives
				(gr_poly
					(pts
						(arc
							(start 0.3048 0.2032)
							(mid 0.275042 0.275042)
							(end 0.2032 0.3048)
						)
						(arc
							(start -0.2032 0.3048)
							(mid -0.275042 0.275042)
							(end -0.3048 0.2032)
						)
						(arc
							(start -0.3048 -0.2032)
							(mid -0.275042 -0.275042)
							(end -0.2032 -0.3048)
						)
						(arc
							(start 0.2032 -0.3048)
							(mid 0.275042 -0.275042)
							(end 0.3048 -0.2032)
						)
					)
					(width 0)
					(fill yes)
				)
			)
		)
		(pad "2" smd custom
			(at 0 0.4445 90)
			(size 0.1524 0.1524)
			(layers "B.Cu" "B.Mask" "B.Paste")
			(net "GND")
			(options
				(clearance outline)
				(anchor circle)
			)
			(primitives
				(gr_poly
					(pts
						(arc
							(start 0.3048 0.2032)
							(mid 0.275042 0.275042)
							(end 0.2032 0.3048)
						)
						(arc
							(start -0.2032 0.3048)
							(mid -0.275042 0.275042)
							(end -0.3048 0.2032)
						)
						(arc
							(start -0.3048 -0.2032)
							(mid -0.275042 -0.275042)
							(end -0.2032 -0.3048)
						)
						(arc
							(start 0.2032 -0.3048)
							(mid 0.275042 -0.275042)
							(end 0.3048 -0.2032)
						)
					)
					(width 0)
					(fill yes)
				)
			)
		)
	)
	(footprint ""
		(layer "B.Cu")
		(at 183.3626 -136.4234 180)
		(property "Reference" "C6L10"
			(at 0 0 0)
			(layer "B.SilkS")
			(hide yes)
			(effects
				(font
					(size 1.27 1.27)
				)
				(justify mirror)
			)
		)
		(property "Value" ""
			(at 0 0 0)
			(layer "B.Fab")
			(effects
				(font
					(size 1.27 1.27)
				)
				(justify mirror)
			)
		)
		(duplicate_pad_numbers_are_jumpers no)
		(fp_poly
			(pts
				(xy 0.7239 -0.2159) (xy -0.7239 -0.2159) (xy -0.7239 1.9939) (xy 0.7239 1.9939)
			)
			(stroke
				(width 0)
				(type default)
			)
			(fill no)
			(layer "B.CrtYd")
		)
		(fp_line
			(start 0.7239 1.9939)
			(end -0.7239 1.9939)
			(stroke
				(width 0.1)
				(type default)
			)
			(layer "B.Fab")
		)
		(fp_line
			(start 0.7239 -0.2159)
			(end 0.7239 1.9939)
			(stroke
				(width 0.1)
				(type default)
			)
			(layer "B.Fab")
		)
		(fp_line
			(start -0.7239 1.9939)
			(end -0.7239 -0.2159)
			(stroke
				(width 0.1)
				(type default)
			)
			(layer "B.Fab")
		)
		(fp_line
			(start -0.7239 -0.2159)
			(end 0.7239 -0.2159)
			(stroke
				(width 0.1)
				(type default)
			)
			(layer "B.Fab")
		)
		(pad "1" smd rect
			(at 0 0)
			(size 1.27 1.016)
			(layers "B.Cu" "B.Mask" "B.Paste")
			(net "VR_FET_SW_P12V_STBY_PVPP_KLM")
		)
		(pad "2" smd rect
			(at 0 1.778)
			(size 1.27 1.016)
			(layers "B.Cu" "B.Mask" "B.Paste")
			(net "GND")
		)
		(zone
			(layer "B.Cu")
			(hatch none 0.5)
			(connect_pads
				(clearance 0)
			)
			(min_thickness 0.25)
			(keepout
				(tracks not_allowed)
				(vias allowed)
				(pads allowed)
				(copperpour not_allowed)
				(footprints allowed)
			)
			(placement
				(enabled no)
				(sheetname "")
			)
			(fill
				(thermal_gap 0.5)
				(thermal_bridge_width 0.5)
				(island_removal_mode 0)
			)
			(polygon
				(pts
					(xy 182.7276 -136.9314) (xy 183.9976 -136.9314) (xy 183.9976 -137.6934) (xy 182.7276 -137.6934)
				)
			)
		)
	)
	(footprint ""
		(layer "B.Cu")
		(at 354.543614 -123.780042 -90)
		(property "Reference" "C3M4"
			(at 0 0 90)
			(layer "B.SilkS")
			(hide yes)
			(effects
				(font
					(size 1.27 1.27)
				)
				(justify mirror)
			)
		)
		(property "Value" ""
			(at 0 0 90)
			(layer "B.Fab")
			(effects
				(font
					(size 1.27 1.27)
				)
				(justify mirror)
			)
		)
		(duplicate_pad_numbers_are_jumpers no)
		(fp_poly
			(pts
				(xy -0.3048 -0.1016) (xy -0.3048 0.9906) (xy 0.3048 0.9906) (xy 0.3048 -0.1016)
			)
			(stroke
				(width 0)
				(type default)
			)
			(fill no)
			(layer "B.CrtYd")
		)
		(fp_line
			(start -0.3048 0.9906)
			(end -0.3048 -0.1016)
			(stroke
				(width 0.1)
				(type default)
			)
			(layer "B.Fab")
		)
		(fp_line
			(start 0.3048 0.9906)
			(end -0.3048 0.9906)
			(stroke
				(width 0.1)
				(type default)
			)
			(layer "B.Fab")
		)
		(fp_line
			(start -0.3048 -0.1016)
			(end 0.3048 -0.1016)
			(stroke
				(width 0.1)
				(type default)
			)
			(layer "B.Fab")
		)
		(fp_line
			(start 0.3048 -0.1016)
			(end 0.3048 0.9906)
			(stroke
				(width 0.1)
				(type default)
			)
			(layer "B.Fab")
		)
		(pad "1" smd rect
			(at 0 0 90)
			(size 0.508 0.508)
			(layers "B.Cu" "B.Mask" "B.Paste")
			(net "P3E_CPU0_PE1_PCH_R_RXN<12>")
		)
		(pad "2" smd rect
			(at 0 0.889 90)
			(size 0.508 0.508)
			(layers "B.Cu" "B.Mask" "B.Paste")
			(net "P3E_CPU0_PE1_PCH_RXN<12>")
		)
		(zone
			(layer "B.Cu")
			(hatch none 0.5)
			(connect_pads
				(clearance 0)
			)
			(min_thickness 0.25)
			(keepout
				(tracks not_allowed)
				(vias allowed)
				(pads allowed)
				(copperpour not_allowed)
				(footprints allowed)
			)
			(placement
				(enabled no)
				(sheetname "")
			)
			(fill
				(thermal_gap 0.5)
				(thermal_bridge_width 0.5)
				(island_removal_mode 0)
			)
			(polygon
				(pts
					(xy 353.908614 -123.526042) (xy 353.908614 -124.034042) (xy 354.289614 -124.034042) (xy 354.289614 -123.526042)
				)
			)
		)
		(zone
			(layer "B.Cu")
			(hatch none 0.5)
			(connect_pads
				(clearance 0)
			)
			(min_thickness 0.25)
			(keepout
				(tracks allowed)
				(vias not_allowed)
				(pads allowed)
				(copperpour not_allowed)
				(footprints allowed)
			)
			(placement
				(enabled no)
				(sheetname "")
			)
			(fill
				(thermal_gap 0.5)
				(thermal_bridge_width 0.5)
				(island_removal_mode 0)
			)
			(polygon
				(pts
					(xy 354.289614 -123.526042) (xy 354.289614 -124.034042) (xy 353.908614 -124.034042) (xy 353.908614 -123.526042)
				)
			)
		)
	)
	(footprint ""
		(layer "B.Cu")
		(at 273.179286 -73.51014)
		(property "Reference" "C5P29"
			(at 0 0 0)
			(layer "B.SilkS")
			(hide yes)
			(effects
				(font
					(size 1.27 1.27)
				)
				(justify mirror)
			)
		)
		(property "Value" ""
			(at 0 0 0)
			(layer "B.Fab")
			(effects
				(font
					(size 1.27 1.27)
				)
				(justify mirror)
			)
		)
		(duplicate_pad_numbers_are_jumpers no)
		(fp_poly
			(pts
				(xy 0.7239 -0.2159) (xy -0.7239 -0.2159) (xy -0.7239 1.9939) (xy 0.7239 1.9939)
			)
			(stroke
				(width 0)
				(type default)
			)
			(fill no)
			(layer "B.CrtYd")
		)
		(fp_line
			(start -0.7239 -0.2159)
			(end 0.7239 -0.2159)
			(stroke
				(width 0.1)
				(type default)
			)
			(layer "B.Fab")
		)
		(fp_line
			(start -0.7239 1.9939)
			(end -0.7239 -0.2159)
			(stroke
				(width 0.1)
				(type default)
			)
			(layer "B.Fab")
		)
		(fp_line
			(start 0.7239 -0.2159)
			(end 0.7239 1.9939)
			(stroke
				(width 0.1)
				(type default)
			)
			(layer "B.Fab")
		)
		(fp_line
			(start 0.7239 1.9939)
			(end -0.7239 1.9939)
			(stroke
				(width 0.1)
				(type default)
			)
			(layer "B.Fab")
		)
		(pad "1" smd rect
			(at 0 0 180)
			(size 1.27 1.016)
			(layers "B.Cu" "B.Mask" "B.Paste")
			(net "PVCCMCP_CPU0")
		)
		(pad "2" smd rect
			(at 0 1.778 180)
			(size 1.27 1.016)
			(layers "B.Cu" "B.Mask" "B.Paste")
			(net "GND")
		)
		(zone
			(layer "B.Cu")
			(hatch none 0.5)
			(connect_pads
				(clearance 0)
			)
			(min_thickness 0.25)
			(keepout
				(tracks not_allowed)
				(vias allowed)
				(pads allowed)
				(copperpour not_allowed)
				(footprints allowed)
			)
			(placement
				(enabled no)
				(sheetname "")
			)
			(fill
				(thermal_gap 0.5)
				(thermal_bridge_width 0.5)
				(island_removal_mode 0)
			)
			(polygon
				(pts
					(xy 273.814286 -73.00214) (xy 272.544286 -73.00214) (xy 272.544286 -72.24014) (xy 273.814286 -72.24014)
				)
			)
		)
	)
	(footprint ""
		(layer "B.Cu")
		(at 373.126 -75.5015)
		(property "Reference" "C3R2"
			(at 0 0 0)
			(layer "B.SilkS")
			(hide yes)
			(effects
				(font
					(size 1.27 1.27)
				)
				(justify mirror)
			)
		)
		(property "Value" ""
			(at 0 0 0)
			(layer "B.Fab")
			(effects
				(font
					(size 1.27 1.27)
				)
				(justify mirror)
			)
		)
		(duplicate_pad_numbers_are_jumpers no)
		(fp_rect
			(start 0.2794 0.9144)
			(end -0.2794 -0.1143)
			(stroke
				(width 0)
				(type default)
			)
			(fill no)
			(layer "B.CrtYd")
		)
		(fp_line
			(start -0.2794 -0.1143)
			(end -0.2794 0.9144)
			(stroke
				(width 0.1)
				(type default)
			)
			(layer "B.Fab")
		)
		(fp_line
			(start -0.2794 0.9144)
			(end 0.2794 0.9144)
			(stroke
				(width 0.1)
				(type default)
			)
			(layer "B.Fab")
		)
		(fp_line
			(start 0.2794 -0.1143)
			(end -0.2794 -0.1143)
			(stroke
				(width 0.1)
				(type default)
			)
			(layer "B.Fab")
		)
		(fp_line
			(start 0.2794 0.9144)
			(end 0.2794 -0.1143)
			(stroke
				(width 0.1)
				(type default)
			)
			(layer "B.Fab")
		)
		(pad "1" smd custom
			(at 0 0 270)
			(size 0.10414 0.10414)
			(layers "B.Cu" "B.Mask" "B.Paste")
			(net "P3V3_STBY")
			(options
				(clearance outline)
				(anchor circle)
			)
			(primitives
				(gr_poly
					(pts
						(xy -0.20828 -0.08636) (xy -0.20828 0.08636) (xy -0.08636 0.20828) (xy 0.086614 0.20828) (xy 0.20828 0.086614)
						(xy 0.20828 -0.08636) (xy 0.08636 -0.20828) (xy -0.08636 -0.20828)
					)
					(width 0)
					(fill yes)
				)
			)
		)
		(pad "2" smd custom
			(at 0 0.8001 270)
			(size 0.10414 0.10414)
			(layers "B.Cu" "B.Mask" "B.Paste")
			(net "GND")
			(options
				(clearance outline)
				(anchor circle)
			)
			(primitives
				(gr_poly
					(pts
						(xy -0.20828 -0.08636) (xy -0.20828 0.08636) (xy -0.08636 0.20828) (xy 0.086614 0.20828) (xy 0.20828 0.086614)
						(xy 0.20828 -0.08636) (xy 0.08636 -0.20828) (xy -0.08636 -0.20828)
					)
					(width 0)
					(fill yes)
				)
			)
		)
		(zone
			(layer "B.Cu")
			(hatch none 0.5)
			(connect_pads
				(clearance 0)
			)
			(min_thickness 0.25)
			(keepout
				(tracks not_allowed)
				(vias allowed)
				(pads allowed)
				(copperpour not_allowed)
				(footprints allowed)
			)
			(placement
				(enabled no)
				(sheetname "")
			)
			(fill
				(thermal_gap 0.5)
				(thermal_bridge_width 0.5)
				(island_removal_mode 0)
			)
			(polygon
				(pts
					(xy 373.21363 -75.29195) (xy 373.21363 -74.91095) (xy 373.03837 -74.91095) (xy 373.038116 -75.29195)
				)
			)
		)
		(zone
			(layer "B.Cu")
			(hatch none 0.5)
			(connect_pads
				(clearance 0)
			)
			(min_thickness 0.25)
			(keepout
				(tracks allowed)
				(vias not_allowed)
				(pads allowed)
				(copperpour not_allowed)
				(footprints allowed)
			)
			(placement
				(enabled no)
				(sheetname "")
			)
			(fill
				(thermal_gap 0.5)
				(thermal_bridge_width 0.5)
				(island_removal_mode 0)
			)
			(polygon
				(pts
					(xy 373.21363 -75.29195) (xy 373.21363 -74.91095) (xy 373.03837 -74.91095) (xy 373.038116 -75.29195)
				)
			)
		)
	)
	(footprint ""
		(layer "B.Cu")
		(at 32.832802 -97.286064 90)
		(property "Reference" "C9N13"
			(at 0 0 90)
			(layer "B.SilkS")
			(hide yes)
			(effects
				(font
					(size 1.27 1.27)
				)
				(justify mirror)
			)
		)
		(property "Value" ""
			(at 0 0 90)
			(layer "B.Fab")
			(effects
				(font
					(size 1.27 1.27)
				)
				(justify mirror)
			)
		)
		(duplicate_pad_numbers_are_jumpers no)
		(fp_poly
			(pts
				(xy 0.7239 -0.2159) (xy -0.7239 -0.2159) (xy -0.7239 1.9939) (xy 0.7239 1.9939)
			)
			(stroke
				(width 0)
				(type default)
			)
			(fill no)
			(layer "B.CrtYd")
		)
		(fp_line
			(start 0.7239 -0.2159)
			(end 0.7239 1.9939)
			(stroke
				(width 0.1)
				(type default)
			)
			(layer "B.Fab")
		)
		(fp_line
			(start -0.7239 -0.2159)
			(end 0.7239 -0.2159)
			(stroke
				(width 0.1)
				(type default)
			)
			(layer "B.Fab")
		)
		(fp_line
			(start 0.7239 1.9939)
			(end -0.7239 1.9939)
			(stroke
				(width 0.1)
				(type default)
			)
			(layer "B.Fab")
		)
		(fp_line
			(start -0.7239 1.9939)
			(end -0.7239 -0.2159)
			(stroke
				(width 0.1)
				(type default)
			)
			(layer "B.Fab")
		)
		(pad "1" smd rect
			(at 0 0 270)
			(size 1.27 1.016)
			(layers "B.Cu" "B.Mask" "B.Paste")
			(net "VR_FET_SW_P12V_STBY_PVCCIN_CPU1")
		)
		(pad "2" smd rect
			(at 0 1.778 270)
			(size 1.27 1.016)
			(layers "B.Cu" "B.Mask" "B.Paste")
			(net "GND")
		)
		(zone
			(layer "B.Cu")
			(hatch none 0.5)
			(connect_pads
				(clearance 0)
			)
			(min_thickness 0.25)
			(keepout
				(tracks not_allowed)
				(vias allowed)
				(pads allowed)
				(copperpour not_allowed)
				(footprints allowed)
			)
			(placement
				(enabled no)
				(sheetname "")
			)
			(fill
				(thermal_gap 0.5)
				(thermal_bridge_width 0.5)
				(island_removal_mode 0)
			)
			(polygon
				(pts
					(xy 33.340802 -97.921064) (xy 33.340802 -96.651064) (xy 34.102802 -96.651064) (xy 34.102802 -97.921064)
				)
			)
		)
	)
	(footprint ""
		(layer "B.Cu")
		(at 481.623116 -143.247872 90)
		(property "Reference" "R6W7"
			(at 0.8382 -0.67818 90)
			(unlocked yes)
			(layer "B.SilkS")
			(effects
				(font
					(size 0.4064 0.254)
					(thickness 0.1524)
				)
				(justify left mirror)
			)
		)
		(property "Value" ""
			(at 0 0 90)
			(layer "B.Fab")
			(effects
				(font
					(size 1.27 1.27)
				)
				(justify mirror)
			)
		)
		(duplicate_pad_numbers_are_jumpers no)
		(fp_poly
			(pts
				(xy 0.2794 -0.1016) (xy -0.2794 -0.1016) (xy -0.2794 0.9906) (xy 0.2794 0.9906)
			)
			(stroke
				(width 0)
				(type default)
			)
			(fill no)
			(layer "B.CrtYd")
		)
		(fp_line
			(start 0.2794 -0.1016)
			(end 0.2794 0.9906)
			(stroke
				(width 0.1)
				(type default)
			)
			(layer "B.Fab")
		)
		(fp_line
			(start -0.2794 -0.1016)
			(end 0.2794 -0.1016)
			(stroke
				(width 0.1)
				(type default)
			)
			(layer "B.Fab")
		)
		(fp_line
			(start 0.2794 0.9906)
			(end -0.2794 0.9906)
			(stroke
				(width 0.1)
				(type default)
			)
			(layer "B.Fab")
		)
		(fp_line
			(start -0.2794 0.9906)
			(end -0.2794 -0.1016)
			(stroke
				(width 0.1)
				(type default)
			)
			(layer "B.Fab")
		)
		(pad "1" smd rect
			(at 0 0 270)
			(size 0.508 0.508)
			(layers "B.Cu" "B.Mask" "B.Paste")
			(net "PCA9555_A2")
		)
		(pad "2" smd rect
			(at 0 0.889 270)
			(size 0.508 0.508)
			(layers "B.Cu" "B.Mask" "B.Paste")
			(net "GND")
		)
		(zone
			(layer "B.Cu")
			(hatch none 0.5)
			(connect_pads
				(clearance 0)
			)
			(min_thickness 0.25)
			(keepout
				(tracks allowed)
				(vias not_allowed)
				(pads allowed)
				(copperpour not_allowed)
				(footprints allowed)
			)
			(placement
				(enabled no)
				(sheetname "")
			)
			(fill
				(thermal_gap 0.5)
				(thermal_bridge_width 0.5)
				(island_removal_mode 0)
			)
			(polygon
				(pts
					(xy 481.877116 -143.501872) (xy 481.877116 -142.993872) (xy 482.258116 -142.993872) (xy 482.258116 -143.501872)
				)
			)
		)
		(zone
			(layer "B.Cu")
			(hatch none 0.5)
			(connect_pads
				(clearance 0)
			)
			(min_thickness 0.25)
			(keepout
				(tracks not_allowed)
				(vias allowed)
				(pads allowed)
				(copperpour not_allowed)
				(footprints allowed)
			)
			(placement
				(enabled no)
				(sheetname "")
			)
			(fill
				(thermal_gap 0.5)
				(thermal_bridge_width 0.5)
				(island_removal_mode 0)
			)
			(polygon
				(pts
					(xy 482.258116 -143.501872) (xy 482.258116 -142.993872) (xy 481.877116 -142.993872) (xy 481.877116 -143.501872)
				)
			)
		)
	)
	(footprint ""
		(layer "B.Cu")
		(at 275.008086 -73.51014)
		(property "Reference" "C5P28"
			(at 0 0 0)
			(layer "B.SilkS")
			(hide yes)
			(effects
				(font
					(size 1.27 1.27)
				)
				(justify mirror)
			)
		)
		(property "Value" ""
			(at 0 0 0)
			(layer "B.Fab")
			(effects
				(font
					(size 1.27 1.27)
				)
				(justify mirror)
			)
		)
		(duplicate_pad_numbers_are_jumpers no)
		(fp_poly
			(pts
				(xy 0.7239 -0.2159) (xy -0.7239 -0.2159) (xy -0.7239 1.9939) (xy 0.7239 1.9939)
			)
			(stroke
				(width 0)
				(type default)
			)
			(fill no)
			(layer "B.CrtYd")
		)
		(fp_line
			(start -0.7239 -0.2159)
			(end 0.7239 -0.2159)
			(stroke
				(width 0.1)
				(type default)
			)
			(layer "B.Fab")
		)
		(fp_line
			(start -0.7239 1.9939)
			(end -0.7239 -0.2159)
			(stroke
				(width 0.1)
				(type default)
			)
			(layer "B.Fab")
		)
		(fp_line
			(start 0.7239 -0.2159)
			(end 0.7239 1.9939)
			(stroke
				(width 0.1)
				(type default)
			)
			(layer "B.Fab")
		)
		(fp_line
			(start 0.7239 1.9939)
			(end -0.7239 1.9939)
			(stroke
				(width 0.1)
				(type default)
			)
			(layer "B.Fab")
		)
		(pad "1" smd rect
			(at 0 0 180)
			(size 1.27 1.016)
			(layers "B.Cu" "B.Mask" "B.Paste")
			(net "PVCCMCP_CPU0")
		)
		(pad "2" smd rect
			(at 0 1.778 180)
			(size 1.27 1.016)
			(layers "B.Cu" "B.Mask" "B.Paste")
			(net "GND")
		)
		(zone
			(layer "B.Cu")
			(hatch none 0.5)
			(connect_pads
				(clearance 0)
			)
			(min_thickness 0.25)
			(keepout
				(tracks not_allowed)
				(vias allowed)
				(pads allowed)
				(copperpour not_allowed)
				(footprints allowed)
			)
			(placement
				(enabled no)
				(sheetname "")
			)
			(fill
				(thermal_gap 0.5)
				(thermal_bridge_width 0.5)
				(island_removal_mode 0)
			)
			(polygon
				(pts
					(xy 275.643086 -73.00214) (xy 274.373086 -73.00214) (xy 274.373086 -72.24014) (xy 275.643086 -72.24014)
				)
			)
		)
	)
	(footprint ""
		(layer "B.Cu")
		(at 13.11402 -97.99828 90)
		(property "Reference" "C9N17"
			(at 0 0 90)
			(layer "B.SilkS")
			(hide yes)
			(effects
				(font
					(size 1.27 1.27)
				)
				(justify mirror)
			)
		)
		(property "Value" ""
			(at 0 0 90)
			(layer "B.Fab")
			(effects
				(font
					(size 1.27 1.27)
				)
				(justify mirror)
			)
		)
		(duplicate_pad_numbers_are_jumpers no)
		(fp_poly
			(pts
				(xy -0.3048 -0.1016) (xy -0.3048 0.9906) (xy 0.3048 0.9906) (xy 0.3048 -0.1016)
			)
			(stroke
				(width 0)
				(type default)
			)
			(fill no)
			(layer "B.CrtYd")
		)
		(fp_line
			(start 0.3048 -0.1016)
			(end 0.3048 0.9906)
			(stroke
				(width 0.1)
				(type default)
			)
			(layer "B.Fab")
		)
		(fp_line
			(start -0.3048 -0.1016)
			(end 0.3048 -0.1016)
			(stroke
				(width 0.1)
				(type default)
			)
			(layer "B.Fab")
		)
		(fp_line
			(start 0.3048 0.9906)
			(end -0.3048 0.9906)
			(stroke
				(width 0.1)
				(type default)
			)
			(layer "B.Fab")
		)
		(fp_line
			(start -0.3048 0.9906)
			(end -0.3048 -0.1016)
			(stroke
				(width 0.1)
				(type default)
			)
			(layer "B.Fab")
		)
		(pad "1" smd rect
			(at 0 0 270)
			(size 0.508 0.508)
			(layers "B.Cu" "B.Mask" "B.Paste")
			(net "P3E_CPU1_PE3_MP_C_TXP<8>")
		)
		(pad "2" smd rect
			(at 0 0.889 270)
			(size 0.508 0.508)
			(layers "B.Cu" "B.Mask" "B.Paste")
			(net "P3E_CPU1_PE3_MP_TXP<8>")
		)
		(zone
			(layer "B.Cu")
			(hatch none 0.5)
			(connect_pads
				(clearance 0)
			)
			(min_thickness 0.25)
			(keepout
				(tracks allowed)
				(vias not_allowed)
				(pads allowed)
				(copperpour not_allowed)
				(footprints allowed)
			)
			(placement
				(enabled no)
				(sheetname "")
			)
			(fill
				(thermal_gap 0.5)
				(thermal_bridge_width 0.5)
				(island_removal_mode 0)
			)
			(polygon
				(pts
					(xy 13.36802 -98.25228) (xy 13.36802 -97.74428) (xy 13.74902 -97.74428) (xy 13.74902 -98.25228)
				)
			)
		)
		(zone
			(layer "B.Cu")
			(hatch none 0.5)
			(connect_pads
				(clearance 0)
			)
			(min_thickness 0.25)
			(keepout
				(tracks not_allowed)
				(vias allowed)
				(pads allowed)
				(copperpour not_allowed)
				(footprints allowed)
			)
			(placement
				(enabled no)
				(sheetname "")
			)
			(fill
				(thermal_gap 0.5)
				(thermal_bridge_width 0.5)
				(island_removal_mode 0)
			)
			(polygon
				(pts
					(xy 13.74902 -98.25228) (xy 13.74902 -97.74428) (xy 13.36802 -97.74428) (xy 13.36802 -98.25228)
				)
			)
		)
	)
	(footprint ""
		(layer "B.Cu")
		(at 439.976006 -41.648126 180)
		(property "Reference" "R25W15"
			(at 0 0 0)
			(layer "B.SilkS")
			(hide yes)
			(effects
				(font
					(size 1.27 1.27)
				)
				(justify mirror)
			)
		)
		(property "Value" "*"
			(at -0.064008 -4.108196 180)
			(unlocked yes)
			(layer "B.Fab")
			(hide yes)
			(effects
				(font
					(size 1.27 1.016)
					(thickness 0.1524)
				)
				(justify mirror)
			)
		)
		(property "Device Type" "120R2F-GP_RCL_GP-120R2F-GP,64.A"
			(at -0.064008 -5.632196 180)
			(unlocked yes)
			(layer "B.Fab")
			(hide yes)
			(effects
				(font
					(size 1.27 1.016)
					(thickness 0.1524)
				)
				(justify mirror)
			)
		)
		(duplicate_pad_numbers_are_jumpers no)
		(fp_line
			(start 0.508 -0.9398)
			(end 0.508 0.9398)
			(stroke
				(width 0.1524)
				(type default)
			)
			(layer "B.SilkS")
		)
		(fp_line
			(start -0.508 -0.9398)
			(end 0.508 -0.9398)
			(stroke
				(width 0.1524)
				(type default)
			)
			(layer "B.SilkS")
		)
		(fp_rect
			(start 0.508 0.9398)
			(end -0.508 -0.9398)
			(stroke
				(width 0)
				(type default)
			)
			(fill no)
			(layer "B.CrtYd")
		)
		(fp_rect
			(start 0.508 0.9398)
			(end -0.508 -0.9398)
			(stroke
				(width 0)
				(type default)
			)
			(fill no)
			(layer "B.Fab")
		)
		(pad "1" smd custom
			(at 0 -0.4445)
			(size 0.1397 0.1397)
			(layers "B.Cu" "B.Mask" "B.Paste")
			(net "GND")
			(options
				(clearance outline)
				(anchor circle)
			)
			(primitives
				(gr_poly
					(pts
						(arc
							(start -0.1778 0.2794)
							(mid -0.249642 0.249642)
							(end -0.2794 0.1778)
						)
						(arc
							(start -0.2794 -0.1778)
							(mid -0.249642 -0.249642)
							(end -0.1778 -0.2794)
						)
						(arc
							(start 0.1778 -0.2794)
							(mid 0.249642 -0.249642)
							(end 0.2794 -0.1778)
						)
						(arc
							(start 0.2794 0.1778)
							(mid 0.249642 0.249642)
							(end 0.1778 0.2794)
						)
					)
					(width 0)
					(fill yes)
				)
			)
		)
		(pad "2" smd custom
			(at 0 0.4445)
			(size 0.1397 0.1397)
			(layers "B.Cu" "B.Mask" "B.Paste")
			(net "BMC_M_A3")
			(options
				(clearance outline)
				(anchor circle)
			)
			(primitives
				(gr_poly
					(pts
						(arc
							(start -0.1778 0.2794)
							(mid -0.249642 0.249642)
							(end -0.2794 0.1778)
						)
						(arc
							(start -0.2794 -0.1778)
							(mid -0.249642 -0.249642)
							(end -0.1778 -0.2794)
						)
						(arc
							(start 0.1778 -0.2794)
							(mid 0.249642 -0.249642)
							(end 0.2794 -0.1778)
						)
						(arc
							(start 0.2794 0.1778)
							(mid 0.249642 0.249642)
							(end 0.1778 0.2794)
						)
					)
					(width 0)
					(fill yes)
				)
			)
		)
	)
	(footprint ""
		(layer "B.Cu")
		(at 346.814902 -133.133846 180)
		(property "Reference" "C3M15"
			(at 0 0 0)
			(layer "B.SilkS")
			(hide yes)
			(effects
				(font
					(size 1.27 1.27)
				)
				(justify mirror)
			)
		)
		(property "Value" ""
			(at 0 0 0)
			(layer "B.Fab")
			(effects
				(font
					(size 1.27 1.27)
				)
				(justify mirror)
			)
		)
		(duplicate_pad_numbers_are_jumpers no)
		(fp_poly
			(pts
				(xy 0.7239 -0.2159) (xy -0.7239 -0.2159) (xy -0.7239 1.9939) (xy 0.7239 1.9939)
			)
			(stroke
				(width 0)
				(type default)
			)
			(fill no)
			(layer "B.CrtYd")
		)
		(fp_line
			(start 0.7239 1.9939)
			(end -0.7239 1.9939)
			(stroke
				(width 0.1)
				(type default)
			)
			(layer "B.Fab")
		)
		(fp_line
			(start 0.7239 -0.2159)
			(end 0.7239 1.9939)
			(stroke
				(width 0.1)
				(type default)
			)
			(layer "B.Fab")
		)
		(fp_line
			(start -0.7239 1.9939)
			(end -0.7239 -0.2159)
			(stroke
				(width 0.1)
				(type default)
			)
			(layer "B.Fab")
		)
		(fp_line
			(start -0.7239 -0.2159)
			(end 0.7239 -0.2159)
			(stroke
				(width 0.1)
				(type default)
			)
			(layer "B.Fab")
		)
		(pad "1" smd rect
			(at 0 0)
			(size 1.27 1.016)
			(layers "B.Cu" "B.Mask" "B.Paste")
			(net "VR_FET_SW_P12V_STBY_PVPP_DEF")
		)
		(pad "2" smd rect
			(at 0 1.778)
			(size 1.27 1.016)
			(layers "B.Cu" "B.Mask" "B.Paste")
			(net "GND")
		)
		(zone
			(layer "B.Cu")
			(hatch none 0.5)
			(connect_pads
				(clearance 0)
			)
			(min_thickness 0.25)
			(keepout
				(tracks not_allowed)
				(vias allowed)
				(pads allowed)
				(copperpour not_allowed)
				(footprints allowed)
			)
			(placement
				(enabled no)
				(sheetname "")
			)
			(fill
				(thermal_gap 0.5)
				(thermal_bridge_width 0.5)
				(island_removal_mode 0)
			)
			(polygon
				(pts
					(xy 346.179902 -133.641846) (xy 347.449902 -133.641846) (xy 347.449902 -134.403846) (xy 346.179902 -134.403846)
				)
			)
		)
	)
	(footprint ""
		(layer "B.Cu")
		(at 108.178854 -73.51014)
		(property "Reference" "C7P15"
			(at 0 0 0)
			(layer "B.SilkS")
			(hide yes)
			(effects
				(font
					(size 1.27 1.27)
				)
				(justify mirror)
			)
		)
		(property "Value" ""
			(at 0 0 0)
			(layer "B.Fab")
			(effects
				(font
					(size 1.27 1.27)
				)
				(justify mirror)
			)
		)
		(duplicate_pad_numbers_are_jumpers no)
		(fp_poly
			(pts
				(xy 0.7239 -0.2159) (xy -0.7239 -0.2159) (xy -0.7239 1.9939) (xy 0.7239 1.9939)
			)
			(stroke
				(width 0)
				(type default)
			)
			(fill no)
			(layer "B.CrtYd")
		)
		(fp_line
			(start -0.7239 -0.2159)
			(end 0.7239 -0.2159)
			(stroke
				(width 0.1)
				(type default)
			)
			(layer "B.Fab")
		)
		(fp_line
			(start -0.7239 1.9939)
			(end -0.7239 -0.2159)
			(stroke
				(width 0.1)
				(type default)
			)
			(layer "B.Fab")
		)
		(fp_line
			(start 0.7239 -0.2159)
			(end 0.7239 1.9939)
			(stroke
				(width 0.1)
				(type default)
			)
			(layer "B.Fab")
		)
		(fp_line
			(start 0.7239 1.9939)
			(end -0.7239 1.9939)
			(stroke
				(width 0.1)
				(type default)
			)
			(layer "B.Fab")
		)
		(pad "1" smd rect
			(at 0 0 180)
			(size 1.27 1.016)
			(layers "B.Cu" "B.Mask" "B.Paste")
			(net "PVCCMCP_CPU1")
		)
		(pad "2" smd rect
			(at 0 1.778 180)
			(size 1.27 1.016)
			(layers "B.Cu" "B.Mask" "B.Paste")
			(net "GND")
		)
		(zone
			(layer "B.Cu")
			(hatch none 0.5)
			(connect_pads
				(clearance 0)
			)
			(min_thickness 0.25)
			(keepout
				(tracks not_allowed)
				(vias allowed)
				(pads allowed)
				(copperpour not_allowed)
				(footprints allowed)
			)
			(placement
				(enabled no)
				(sheetname "")
			)
			(fill
				(thermal_gap 0.5)
				(thermal_bridge_width 0.5)
				(island_removal_mode 0)
			)
			(polygon
				(pts
					(xy 108.813854 -73.00214) (xy 107.543854 -73.00214) (xy 107.543854 -72.24014) (xy 108.813854 -72.24014)
				)
			)
		)
	)
	(footprint ""
		(layer "B.Cu")
		(at 428.8409 -17.272 -90)
		(property "Reference" "R1U16"
			(at 0 0 90)
			(layer "B.SilkS")
			(hide yes)
			(effects
				(font
					(size 1.27 1.27)
				)
				(justify mirror)
			)
		)
		(property "Value" ""
			(at 0 0 90)
			(layer "B.Fab")
			(effects
				(font
					(size 1.27 1.27)
				)
				(justify mirror)
			)
		)
		(duplicate_pad_numbers_are_jumpers no)
		(fp_poly
			(pts
				(xy 0.2794 -0.1016) (xy -0.2794 -0.1016) (xy -0.2794 0.9906) (xy 0.2794 0.9906)
			)
			(stroke
				(width 0)
				(type default)
			)
			(fill no)
			(layer "B.CrtYd")
		)
		(fp_line
			(start -0.2794 0.9906)
			(end -0.2794 -0.1016)
			(stroke
				(width 0.1)
				(type default)
			)
			(layer "B.Fab")
		)
		(fp_line
			(start 0.2794 0.9906)
			(end -0.2794 0.9906)
			(stroke
				(width 0.1)
				(type default)
			)
			(layer "B.Fab")
		)
		(fp_line
			(start -0.2794 -0.1016)
			(end 0.2794 -0.1016)
			(stroke
				(width 0.1)
				(type default)
			)
			(layer "B.Fab")
		)
		(fp_line
			(start 0.2794 -0.1016)
			(end 0.2794 0.9906)
			(stroke
				(width 0.1)
				(type default)
			)
			(layer "B.Fab")
		)
		(pad "1" smd rect
			(at 0 0 90)
			(size 0.508 0.508)
			(layers "B.Cu" "B.Mask" "B.Paste")
			(net "FM_BOARD_SKU_ID1")
		)
		(pad "2" smd rect
			(at 0 0.889 90)
			(size 0.508 0.508)
			(layers "B.Cu" "B.Mask" "B.Paste")
			(net "GND")
		)
		(zone
			(layer "B.Cu")
			(hatch none 0.5)
			(connect_pads
				(clearance 0)
			)
			(min_thickness 0.25)
			(keepout
				(tracks not_allowed)
				(vias allowed)
				(pads allowed)
				(copperpour not_allowed)
				(footprints allowed)
			)
			(placement
				(enabled no)
				(sheetname "")
			)
			(fill
				(thermal_gap 0.5)
				(thermal_bridge_width 0.5)
				(island_removal_mode 0)
			)
			(polygon
				(pts
					(xy 428.2059 -17.018) (xy 428.2059 -17.526) (xy 428.5869 -17.526) (xy 428.5869 -17.018)
				)
			)
		)
		(zone
			(layer "B.Cu")
			(hatch none 0.5)
			(connect_pads
				(clearance 0)
			)
			(min_thickness 0.25)
			(keepout
				(tracks allowed)
				(vias not_allowed)
				(pads allowed)
				(copperpour not_allowed)
				(footprints allowed)
			)
			(placement
				(enabled no)
				(sheetname "")
			)
			(fill
				(thermal_gap 0.5)
				(thermal_bridge_width 0.5)
				(island_removal_mode 0)
			)
			(polygon
				(pts
					(xy 428.5869 -17.018) (xy 428.5869 -17.526) (xy 428.2059 -17.526) (xy 428.2059 -17.018)
				)
			)
		)
	)
	(footprint ""
		(layer "B.Cu")
		(at 438.404 -52.3875)
		(property "Reference" "C2R16"
			(at 0 0 0)
			(layer "B.SilkS")
			(hide yes)
			(effects
				(font
					(size 1.27 1.27)
				)
				(justify mirror)
			)
		)
		(property "Value" ""
			(at 0 0 0)
			(layer "B.Fab")
			(effects
				(font
					(size 1.27 1.27)
				)
				(justify mirror)
			)
		)
		(duplicate_pad_numbers_are_jumpers no)
		(fp_poly
			(pts
				(xy -0.3048 -0.1016) (xy -0.3048 0.9906) (xy 0.3048 0.9906) (xy 0.3048 -0.1016)
			)
			(stroke
				(width 0)
				(type default)
			)
			(fill no)
			(layer "B.CrtYd")
		)
		(fp_line
			(start -0.3048 -0.1016)
			(end 0.3048 -0.1016)
			(stroke
				(width 0.1)
				(type default)
			)
			(layer "B.Fab")
		)
		(fp_line
			(start -0.3048 0.9906)
			(end -0.3048 -0.1016)
			(stroke
				(width 0.1)
				(type default)
			)
			(layer "B.Fab")
		)
		(fp_line
			(start 0.3048 -0.1016)
			(end 0.3048 0.9906)
			(stroke
				(width 0.1)
				(type default)
			)
			(layer "B.Fab")
		)
		(fp_line
			(start 0.3048 0.9906)
			(end -0.3048 0.9906)
			(stroke
				(width 0.1)
				(type default)
			)
			(layer "B.Fab")
		)
		(pad "1" smd rect
			(at 0 0 180)
			(size 0.508 0.508)
			(layers "B.Cu" "B.Mask" "B.Paste")
			(net "P12V_STBY")
		)
		(pad "2" smd rect
			(at 0 0.889 180)
			(size 0.508 0.508)
			(layers "B.Cu" "B.Mask" "B.Paste")
			(net "GND")
		)
		(zone
			(layer "B.Cu")
			(hatch none 0.5)
			(connect_pads
				(clearance 0)
			)
			(min_thickness 0.25)
			(keepout
				(tracks allowed)
				(vias not_allowed)
				(pads allowed)
				(copperpour not_allowed)
				(footprints allowed)
			)
			(placement
				(enabled no)
				(sheetname "")
			)
			(fill
				(thermal_gap 0.5)
				(thermal_bridge_width 0.5)
				(island_removal_mode 0)
			)
			(polygon
				(pts
					(xy 438.658 -52.1335) (xy 438.15 -52.1335) (xy 438.15 -51.7525) (xy 438.658 -51.7525)
				)
			)
		)
		(zone
			(layer "B.Cu")
			(hatch none 0.5)
			(connect_pads
				(clearance 0)
			)
			(min_thickness 0.25)
			(keepout
				(tracks not_allowed)
				(vias allowed)
				(pads allowed)
				(copperpour not_allowed)
				(footprints allowed)
			)
			(placement
				(enabled no)
				(sheetname "")
			)
			(fill
				(thermal_gap 0.5)
				(thermal_bridge_width 0.5)
				(island_removal_mode 0)
			)
			(polygon
				(pts
					(xy 438.658 -51.7525) (xy 438.15 -51.7525) (xy 438.15 -52.1335) (xy 438.658 -52.1335)
				)
			)
		)
	)
	(footprint ""
		(layer "B.Cu")
		(at 7.2898 -122.936)
		(property "Reference" "EU9M1"
			(at 4.5212 -0.35433 0)
			(unlocked yes)
			(layer "B.SilkS")
			(effects
				(font
					(size 0.7874 0.5842)
					(thickness 0.1524)
				)
				(justify left mirror)
			)
		)
		(property "Value" ""
			(at 0 0 0)
			(layer "B.Fab")
			(effects
				(font
					(size 1.27 1.27)
				)
				(justify mirror)
			)
		)
		(duplicate_pad_numbers_are_jumpers no)
		(fp_circle
			(center 0.702056 -0.595376)
			(end 0.829056 -0.595376)
			(stroke
				(width 0.254)
				(type default)
			)
			(fill no)
			(layer "B.SilkS")
		)
		(fp_rect
			(start -1.4732 1.549908)
			(end -0.5842 -0.050292)
			(stroke
				(width 0)
				(type default)
			)
			(fill yes)
			(layer "B.Paste")
		)
		(fp_rect
			(start -2.078736 1.799844)
			(end 0.021336 -0.300228)
			(stroke
				(width 0)
				(type default)
			)
			(fill no)
			(layer "B.CrtYd")
		)
		(fp_line
			(start -2.078736 -0.300228)
			(end -2.078736 1.799844)
			(stroke
				(width 0.1)
				(type default)
			)
			(layer "B.Fab")
		)
		(fp_line
			(start -2.078736 1.799844)
			(end 0.021336 1.799844)
			(stroke
				(width 0.1)
				(type default)
			)
			(layer "B.Fab")
		)
		(fp_line
			(start 0.021336 -0.300228)
			(end -2.078736 -0.300228)
			(stroke
				(width 0.1)
				(type default)
			)
			(layer "B.Fab")
		)
		(fp_line
			(start 0.021336 1.799844)
			(end 0.021336 -0.300228)
			(stroke
				(width 0.1)
				(type default)
			)
			(layer "B.Fab")
		)
		(fp_circle
			(center 0.702056 -0.595376)
			(end 0.829056 -0.595376)
			(stroke
				(width 0.254)
				(type default)
			)
			(fill no)
			(layer "B.Fab")
		)
		(pad "1" smd rect
			(at 0 0 180)
			(size 0.6604 0.3048)
			(layers "B.Cu" "B.Mask" "B.Paste")
			(net "P5V_STBY")
		)
		(pad "2" smd rect
			(at 0 0.499872 180)
			(size 0.6604 0.3048)
			(layers "B.Cu" "B.Mask" "B.Paste")
			(net "FM_ENABLE_FAN_POWER")
		)
		(pad "3" smd rect
			(at 0 0.999744 180)
			(size 0.6604 0.3048)
			(layers "B.Cu" "B.Mask" "B.Paste")
			(net "P5V_STBY")
		)
		(pad "4" smd rect
			(at 0 1.499616 180)
			(size 0.6604 0.3048)
			(layers "B.Cu" "B.Mask" "B.Paste")
			(net "GND")
		)
		(pad "5" smd rect
			(at -2.0574 1.499616 180)
			(size 0.6604 0.3048)
			(layers "B.Cu" "B.Mask" "B.Paste")
			(net "P12V_STBY")
		)
		(pad "6" smd rect
			(at -2.0574 0.999744 180)
			(size 0.6604 0.3048)
			(layers "B.Cu" "B.Mask" "B.Paste")
			(net "P12V_FAN")
		)
		(pad "7" smd rect
			(at -2.0574 0.499872 180)
			(size 0.6604 0.3048)
			(layers "B.Cu" "B.Mask" "B.Paste")
			(net "P12V_FAN_SWITCH_G")
		)
		(pad "8" smd rect
			(at -2.0574 0 180)
			(size 0.6604 0.3048)
			(layers "B.Cu" "B.Mask" "B.Paste")
			(net "TP_SLG55021_P12V_FAN_8")
		)
		(pad "9" smd rect
			(at -1.0287 0.749808 180)
			(size 0.889 1.6002)
			(layers "B.Cu" "B.Mask" "B.Paste")
			(net "GND")
		)
	)
	(footprint ""
		(layer "B.Cu")
		(at 24.692356 -31.679896 -90)
		(property "Reference" "R9T3"
			(at 0 0 90)
			(layer "B.SilkS")
			(hide yes)
			(effects
				(font
					(size 1.27 1.27)
				)
				(justify mirror)
			)
		)
		(property "Value" ""
			(at 0 0 90)
			(layer "B.Fab")
			(effects
				(font
					(size 1.27 1.27)
				)
				(justify mirror)
			)
		)
		(duplicate_pad_numbers_are_jumpers no)
		(fp_rect
			(start -0.2794 -0.1016)
			(end 0.2794 0.9906)
			(stroke
				(width 0)
				(type default)
			)
			(fill no)
			(layer "B.CrtYd")
		)
		(fp_line
			(start -0.2794 0.9906)
			(end -0.2794 -0.1016)
			(stroke
				(width 0.1)
				(type default)
			)
			(layer "B.Fab")
		)
		(fp_line
			(start 0.2794 0.9906)
			(end -0.2794 0.9906)
			(stroke
				(width 0.1)
				(type default)
			)
			(layer "B.Fab")
		)
		(fp_line
			(start -0.2794 -0.1016)
			(end 0.2794 -0.1016)
			(stroke
				(width 0.1)
				(type default)
			)
			(layer "B.Fab")
		)
		(fp_line
			(start 0.2794 -0.1016)
			(end 0.2794 0.9906)
			(stroke
				(width 0.1)
				(type default)
			)
			(layer "B.Fab")
		)
		(pad "1" smd rect
			(at 0 0 90)
			(size 0.508 0.508)
			(layers "B.Cu" "B.Mask" "B.Paste")
			(net "FM_P12V_HOTSWAP0_EN")
		)
		(pad "2" smd rect
			(at 0 0.889 90)
			(size 0.508 0.508)
			(layers "B.Cu" "B.Mask" "B.Paste")
			(net "GND")
		)
		(zone
			(layer "B.Cu")
			(hatch none 0.5)
			(connect_pads
				(clearance 0)
			)
			(min_thickness 0.25)
			(keepout
				(tracks allowed)
				(vias not_allowed)
				(pads allowed)
				(copperpour not_allowed)
				(footprints allowed)
			)
			(placement
				(enabled no)
				(sheetname "")
			)
			(fill
				(thermal_gap 0.5)
				(thermal_bridge_width 0.5)
				(island_removal_mode 0)
			)
			(polygon
				(pts
					(xy 24.438356 -31.933896) (xy 24.057356 -31.933896) (xy 24.057356 -31.425896) (xy 24.438356 -31.425896)
				)
			)
		)
		(zone
			(layer "B.Cu")
			(hatch none 0.5)
			(connect_pads
				(clearance 0)
			)
			(min_thickness 0.25)
			(keepout
				(tracks not_allowed)
				(vias allowed)
				(pads allowed)
				(copperpour not_allowed)
				(footprints allowed)
			)
			(placement
				(enabled no)
				(sheetname "")
			)
			(fill
				(thermal_gap 0.5)
				(thermal_bridge_width 0.5)
				(island_removal_mode 0)
			)
			(polygon
				(pts
					(xy 24.438356 -31.933896) (xy 24.057356 -31.933896) (xy 24.057356 -31.425896) (xy 24.438356 -31.425896)
				)
			)
		)
	)
	(footprint ""
		(layer "B.Cu")
		(at 108.051854 -85.06714)
		(property "Reference" "C7P2"
			(at 0 0 0)
			(layer "B.SilkS")
			(hide yes)
			(effects
				(font
					(size 1.27 1.27)
				)
				(justify mirror)
			)
		)
		(property "Value" ""
			(at 0 0 0)
			(layer "B.Fab")
			(effects
				(font
					(size 1.27 1.27)
				)
				(justify mirror)
			)
		)
		(duplicate_pad_numbers_are_jumpers no)
		(fp_poly
			(pts
				(xy 0.7239 -0.2159) (xy -0.7239 -0.2159) (xy -0.7239 1.9939) (xy 0.7239 1.9939)
			)
			(stroke
				(width 0)
				(type default)
			)
			(fill no)
			(layer "B.CrtYd")
		)
		(fp_line
			(start -0.7239 -0.2159)
			(end 0.7239 -0.2159)
			(stroke
				(width 0.1)
				(type default)
			)
			(layer "B.Fab")
		)
		(fp_line
			(start -0.7239 1.9939)
			(end -0.7239 -0.2159)
			(stroke
				(width 0.1)
				(type default)
			)
			(layer "B.Fab")
		)
		(fp_line
			(start 0.7239 -0.2159)
			(end 0.7239 1.9939)
			(stroke
				(width 0.1)
				(type default)
			)
			(layer "B.Fab")
		)
		(fp_line
			(start 0.7239 1.9939)
			(end -0.7239 1.9939)
			(stroke
				(width 0.1)
				(type default)
			)
			(layer "B.Fab")
		)
		(pad "1" smd rect
			(at 0 0 180)
			(size 1.27 1.016)
			(layers "B.Cu" "B.Mask" "B.Paste")
			(net "PVDDQ_KLM")
		)
		(pad "2" smd rect
			(at 0 1.778 180)
			(size 1.27 1.016)
			(layers "B.Cu" "B.Mask" "B.Paste")
			(net "GND")
		)
		(zone
			(layer "B.Cu")
			(hatch none 0.5)
			(connect_pads
				(clearance 0)
			)
			(min_thickness 0.25)
			(keepout
				(tracks not_allowed)
				(vias allowed)
				(pads allowed)
				(copperpour not_allowed)
				(footprints allowed)
			)
			(placement
				(enabled no)
				(sheetname "")
			)
			(fill
				(thermal_gap 0.5)
				(thermal_bridge_width 0.5)
				(island_removal_mode 0)
			)
			(polygon
				(pts
					(xy 108.686854 -84.55914) (xy 107.416854 -84.55914) (xy 107.416854 -83.79714) (xy 108.686854 -83.79714)
				)
			)
		)
	)
	(footprint ""
		(layer "B.Cu")
		(at 151.511 -122.809 -90)
		(property "Reference" "C7M6"
			(at -3.10007 3.24612 0)
			(unlocked yes)
			(layer "B.SilkS")
			(effects
				(font
					(size 0.7874 0.5842)
					(thickness 0.1524)
				)
				(justify mirror)
			)
		)
		(property "Value" ""
			(at 0 0 90)
			(layer "B.Fab")
			(effects
				(font
					(size 1.27 1.27)
				)
				(justify mirror)
			)
		)
		(duplicate_pad_numbers_are_jumpers no)
		(fp_line
			(start -2.286 7.366)
			(end -1.600708 7.366)
			(stroke
				(width 0.1524)
				(type default)
			)
			(layer "B.SilkS")
		)
		(fp_line
			(start -2.286 7.366)
			(end -2.286 1.63195)
			(stroke
				(width 0.1524)
				(type default)
			)
			(layer "B.SilkS")
		)
		(fp_line
			(start 2.286 7.366)
			(end 1.60147 7.366)
			(stroke
				(width 0.1524)
				(type default)
			)
			(layer "B.SilkS")
		)
		(fp_line
			(start 2.286 7.366)
			(end 2.286 1.632712)
			(stroke
				(width 0.1524)
				(type default)
			)
			(layer "B.SilkS")
		)
		(fp_line
			(start -2.504948 1.633728)
			(end -1.6002 1.633728)
			(stroke
				(width 0.1524)
				(type default)
			)
			(layer "B.SilkS")
		)
		(fp_line
			(start 2.563114 1.633728)
			(end 1.6002 1.633728)
			(stroke
				(width 0.1524)
				(type default)
			)
			(layer "B.SilkS")
		)
		(fp_line
			(start -2.504948 -1.616456)
			(end -2.504948 1.633728)
			(stroke
				(width 0.1524)
				(type default)
			)
			(layer "B.SilkS")
		)
		(fp_line
			(start -1.6002 -1.616456)
			(end -2.504948 -1.616456)
			(stroke
				(width 0.1524)
				(type default)
			)
			(layer "B.SilkS")
		)
		(fp_line
			(start 1.6002 -1.616456)
			(end 2.563114 -1.616456)
			(stroke
				(width 0.1524)
				(type default)
			)
			(layer "B.SilkS")
		)
		(fp_line
			(start 2.563114 -1.616456)
			(end 2.563114 1.633728)
			(stroke
				(width 0.1524)
				(type default)
			)
			(layer "B.SilkS")
		)
		(fp_rect
			(start 2.286 7.366)
			(end -2.286 -0.254)
			(stroke
				(width 0)
				(type default)
			)
			(fill no)
			(layer "B.CrtYd")
		)
		(fp_line
			(start -2.286 7.366)
			(end 2.286 7.366)
			(stroke
				(width 0.1)
				(type default)
			)
			(layer "B.Fab")
		)
		(fp_line
			(start 2.286 7.366)
			(end 2.286 -0.254)
			(stroke
				(width 0.1)
				(type default)
			)
			(layer "B.Fab")
		)
		(fp_line
			(start -2.286 -0.254)
			(end -2.286 7.366)
			(stroke
				(width 0.1)
				(type default)
			)
			(layer "B.Fab")
		)
		(fp_line
			(start 2.286 -0.254)
			(end -2.286 -0.254)
			(stroke
				(width 0.1)
				(type default)
			)
			(layer "B.Fab")
		)
		(pad "1" smd rect
			(at 0 0 90)
			(size 2.54 3.048)
			(layers "B.Cu" "B.Mask" "B.Paste")
			(net "P12V_STBY")
		)
		(pad "2" smd rect
			(at 0 7.112 90)
			(size 2.54 3.048)
			(layers "B.Cu" "B.Mask" "B.Paste")
			(net "GND")
		)
	)
	(footprint ""
		(layer "B.Cu")
		(at 227.584 -92.583 90)
		(property "Reference" "R5N2"
			(at 0 0 90)
			(layer "B.SilkS")
			(hide yes)
			(effects
				(font
					(size 1.27 1.27)
				)
				(justify mirror)
			)
		)
		(property "Value" ""
			(at 0 0 90)
			(layer "B.Fab")
			(effects
				(font
					(size 1.27 1.27)
				)
				(justify mirror)
			)
		)
		(duplicate_pad_numbers_are_jumpers no)
		(fp_poly
			(pts
				(xy 0.2794 -0.1016) (xy -0.2794 -0.1016) (xy -0.2794 0.9906) (xy 0.2794 0.9906)
			)
			(stroke
				(width 0)
				(type default)
			)
			(fill no)
			(layer "B.CrtYd")
		)
		(fp_line
			(start 0.2794 -0.1016)
			(end 0.2794 0.9906)
			(stroke
				(width 0.1)
				(type default)
			)
			(layer "B.Fab")
		)
		(fp_line
			(start -0.2794 -0.1016)
			(end 0.2794 -0.1016)
			(stroke
				(width 0.1)
				(type default)
			)
			(layer "B.Fab")
		)
		(fp_line
			(start 0.2794 0.9906)
			(end -0.2794 0.9906)
			(stroke
				(width 0.1)
				(type default)
			)
			(layer "B.Fab")
		)
		(fp_line
			(start -0.2794 0.9906)
			(end -0.2794 -0.1016)
			(stroke
				(width 0.1)
				(type default)
			)
			(layer "B.Fab")
		)
		(pad "1" smd rect
			(at 0 0 270)
			(size 0.508 0.508)
			(layers "B.Cu" "B.Mask" "B.Paste")
			(net "P3V3_STBY")
		)
		(pad "2" smd rect
			(at 0 0.889 270)
			(size 0.508 0.508)
			(layers "B.Cu" "B.Mask" "B.Paste")
			(net "FM_CPU0_PROC_ID1")
		)
		(zone
			(layer "B.Cu")
			(hatch none 0.5)
			(connect_pads
				(clearance 0)
			)
			(min_thickness 0.25)
			(keepout
				(tracks allowed)
				(vias not_allowed)
				(pads allowed)
				(copperpour not_allowed)
				(footprints allowed)
			)
			(placement
				(enabled no)
				(sheetname "")
			)
			(fill
				(thermal_gap 0.5)
				(thermal_bridge_width 0.5)
				(island_removal_mode 0)
			)
			(polygon
				(pts
					(xy 227.838 -92.837) (xy 227.838 -92.329) (xy 228.219 -92.329) (xy 228.219 -92.837)
				)
			)
		)
		(zone
			(layer "B.Cu")
			(hatch none 0.5)
			(connect_pads
				(clearance 0)
			)
			(min_thickness 0.25)
			(keepout
				(tracks not_allowed)
				(vias allowed)
				(pads allowed)
				(copperpour not_allowed)
				(footprints allowed)
			)
			(placement
				(enabled no)
				(sheetname "")
			)
			(fill
				(thermal_gap 0.5)
				(thermal_bridge_width 0.5)
				(island_removal_mode 0)
			)
			(polygon
				(pts
					(xy 228.219 -92.837) (xy 228.219 -92.329) (xy 227.838 -92.329) (xy 227.838 -92.837)
				)
			)
		)
	)
	(footprint ""
		(layer "B.Cu")
		(at 197.848728 -66.327782 90)
		(property "Reference" "C6P24"
			(at 0 0 90)
			(layer "B.SilkS")
			(hide yes)
			(effects
				(font
					(size 1.27 1.27)
				)
				(justify mirror)
			)
		)
		(property "Value" ""
			(at 0 0 90)
			(layer "B.Fab")
			(effects
				(font
					(size 1.27 1.27)
				)
				(justify mirror)
			)
		)
		(duplicate_pad_numbers_are_jumpers no)
		(fp_rect
			(start 0.7239 1.9939)
			(end -0.7239 -0.2159)
			(stroke
				(width 0)
				(type default)
			)
			(fill no)
			(layer "B.CrtYd")
		)
		(fp_line
			(start 0.7239 -0.2159)
			(end 0.7239 1.9939)
			(stroke
				(width 0.1)
				(type default)
			)
			(layer "B.Fab")
		)
		(fp_line
			(start -0.7239 -0.2159)
			(end 0.7239 -0.2159)
			(stroke
				(width 0.1)
				(type default)
			)
			(layer "B.Fab")
		)
		(fp_line
			(start 0.7239 1.9939)
			(end -0.7239 1.9939)
			(stroke
				(width 0.1)
				(type default)
			)
			(layer "B.Fab")
		)
		(fp_line
			(start -0.7239 1.9939)
			(end -0.7239 -0.2159)
			(stroke
				(width 0.1)
				(type default)
			)
			(layer "B.Fab")
		)
		(pad "1" smd rect
			(at 0 0 270)
			(size 1.27 1.016)
			(layers "B.Cu" "B.Mask" "B.Paste")
			(net "VR_FET_SW_P12V_STBY_PVCCIN_CPU0")
		)
		(pad "2" smd rect
			(at 0 1.778 270)
			(size 1.27 1.016)
			(layers "B.Cu" "B.Mask" "B.Paste")
			(net "GND")
		)
		(zone
			(layer "B.Cu")
			(hatch none 0.5)
			(connect_pads
				(clearance 0)
			)
			(min_thickness 0.25)
			(keepout
				(tracks not_allowed)
				(vias allowed)
				(pads allowed)
				(copperpour not_allowed)
				(footprints allowed)
			)
			(placement
				(enabled no)
				(sheetname "")
			)
			(fill
				(thermal_gap 0.5)
				(thermal_bridge_width 0.5)
				(island_removal_mode 0)
			)
			(polygon
				(pts
					(xy 199.118728 -66.962782) (xy 198.356728 -66.962782) (xy 198.356728 -65.692782) (xy 199.118728 -65.692782)
				)
			)
		)
	)
	(footprint ""
		(layer "B.Cu")
		(at 388.366 -129.99974 180)
		(property "Reference" "R3M8"
			(at 0 0 0)
			(layer "B.SilkS")
			(hide yes)
			(effects
				(font
					(size 1.27 1.27)
				)
				(justify mirror)
			)
		)
		(property "Value" ""
			(at 0 0 0)
			(layer "B.Fab")
			(effects
				(font
					(size 1.27 1.27)
				)
				(justify mirror)
			)
		)
		(duplicate_pad_numbers_are_jumpers no)
		(fp_poly
			(pts
				(xy 0.2794 -0.1016) (xy -0.2794 -0.1016) (xy -0.2794 0.9906) (xy 0.2794 0.9906)
			)
			(stroke
				(width 0)
				(type default)
			)
			(fill no)
			(layer "B.CrtYd")
		)
		(fp_line
			(start 0.2794 0.9906)
			(end -0.2794 0.9906)
			(stroke
				(width 0.1)
				(type default)
			)
			(layer "B.Fab")
		)
		(fp_line
			(start 0.2794 -0.1016)
			(end 0.2794 0.9906)
			(stroke
				(width 0.1)
				(type default)
			)
			(layer "B.Fab")
		)
		(fp_line
			(start -0.2794 0.9906)
			(end -0.2794 -0.1016)
			(stroke
				(width 0.1)
				(type default)
			)
			(layer "B.Fab")
		)
		(fp_line
			(start -0.2794 -0.1016)
			(end 0.2794 -0.1016)
			(stroke
				(width 0.1)
				(type default)
			)
			(layer "B.Fab")
		)
		(pad "1" smd rect
			(at 0 0)
			(size 0.508 0.508)
			(layers "B.Cu" "B.Mask" "B.Paste")
			(net "P2E_SSB_BMC_RX_C_DP")
		)
		(pad "2" smd rect
			(at 0 0.889)
			(size 0.508 0.508)
			(layers "B.Cu" "B.Mask" "B.Paste")
			(net "GND")
		)
		(zone
			(layer "B.Cu")
			(hatch none 0.5)
			(connect_pads
				(clearance 0)
			)
			(min_thickness 0.25)
			(keepout
				(tracks not_allowed)
				(vias allowed)
				(pads allowed)
				(copperpour not_allowed)
				(footprints allowed)
			)
			(placement
				(enabled no)
				(sheetname "")
			)
			(fill
				(thermal_gap 0.5)
				(thermal_bridge_width 0.5)
				(island_removal_mode 0)
			)
			(polygon
				(pts
					(xy 388.112 -130.63474) (xy 388.62 -130.63474) (xy 388.62 -130.25374) (xy 388.112 -130.25374)
				)
			)
		)
		(zone
			(layer "B.Cu")
			(hatch none 0.5)
			(connect_pads
				(clearance 0)
			)
			(min_thickness 0.25)
			(keepout
				(tracks allowed)
				(vias not_allowed)
				(pads allowed)
				(copperpour not_allowed)
				(footprints allowed)
			)
			(placement
				(enabled no)
				(sheetname "")
			)
			(fill
				(thermal_gap 0.5)
				(thermal_bridge_width 0.5)
				(island_removal_mode 0)
			)
			(polygon
				(pts
					(xy 388.112 -130.25374) (xy 388.62 -130.25374) (xy 388.62 -130.63474) (xy 388.112 -130.63474)
				)
			)
		)
	)
	(footprint ""
		(layer "B.Cu")
		(at 320.294 -154.813 90)
		(property "Reference" "C4L1"
			(at 0 0 90)
			(layer "B.SilkS")
			(hide yes)
			(effects
				(font
					(size 1.27 1.27)
				)
				(justify mirror)
			)
		)
		(property "Value" ""
			(at 0 0 90)
			(layer "B.Fab")
			(effects
				(font
					(size 1.27 1.27)
				)
				(justify mirror)
			)
		)
		(duplicate_pad_numbers_are_jumpers no)
		(fp_poly
			(pts
				(xy 0.4953 -0.2032) (xy -0.4953 -0.2032) (xy -0.4953 1.6002) (xy 0.4953 1.6002)
			)
			(stroke
				(width 0)
				(type default)
			)
			(fill no)
			(layer "B.CrtYd")
		)
		(fp_line
			(start 0.4953 -0.2032)
			(end -0.4953 -0.2032)
			(stroke
				(width 0.1)
				(type default)
			)
			(layer "B.Fab")
		)
		(fp_line
			(start -0.4953 -0.2032)
			(end -0.4953 1.6002)
			(stroke
				(width 0.1)
				(type default)
			)
			(layer "B.Fab")
		)
		(fp_line
			(start 0.4953 1.6002)
			(end 0.4953 -0.2032)
			(stroke
				(width 0.1)
				(type default)
			)
			(layer "B.Fab")
		)
		(fp_line
			(start -0.4953 1.6002)
			(end 0.4953 1.6002)
			(stroke
				(width 0.1)
				(type default)
			)
			(layer "B.Fab")
		)
		(pad "1" smd rect
			(at 0 0 270)
			(size 0.762 0.889)
			(layers "B.Cu" "B.Mask" "B.Paste")
			(net "PVPP_DEF")
		)
		(pad "2" smd rect
			(at 0 1.397 270)
			(size 0.762 0.889)
			(layers "B.Cu" "B.Mask" "B.Paste")
			(net "GND")
		)
		(zone
			(layer "B.Cu")
			(hatch none 0.5)
			(connect_pads
				(clearance 0)
			)
			(min_thickness 0.25)
			(keepout
				(tracks not_allowed)
				(vias allowed)
				(pads allowed)
				(copperpour not_allowed)
				(footprints allowed)
			)
			(placement
				(enabled no)
				(sheetname "")
			)
			(fill
				(thermal_gap 0.5)
				(thermal_bridge_width 0.5)
				(island_removal_mode 0)
			)
			(polygon
				(pts
					(xy 320.7385 -155.194) (xy 320.7385 -154.432) (xy 321.2465 -154.432) (xy 321.2465 -155.194)
				)
			)
		)
	)
	(footprint ""
		(layer "B.Cu")
		(at 446.912238 -52.407058)
		(property "Reference" "C2R14"
			(at 0 0 0)
			(layer "B.SilkS")
			(hide yes)
			(effects
				(font
					(size 1.27 1.27)
				)
				(justify mirror)
			)
		)
		(property "Value" ""
			(at 0 0 0)
			(layer "B.Fab")
			(effects
				(font
					(size 1.27 1.27)
				)
				(justify mirror)
			)
		)
		(duplicate_pad_numbers_are_jumpers no)
		(fp_poly
			(pts
				(xy -0.3048 -0.1016) (xy -0.3048 0.9906) (xy 0.3048 0.9906) (xy 0.3048 -0.1016)
			)
			(stroke
				(width 0)
				(type default)
			)
			(fill no)
			(layer "B.CrtYd")
		)
		(fp_line
			(start -0.3048 -0.1016)
			(end 0.3048 -0.1016)
			(stroke
				(width 0.1)
				(type default)
			)
			(layer "B.Fab")
		)
		(fp_line
			(start -0.3048 0.9906)
			(end -0.3048 -0.1016)
			(stroke
				(width 0.1)
				(type default)
			)
			(layer "B.Fab")
		)
		(fp_line
			(start 0.3048 -0.1016)
			(end 0.3048 0.9906)
			(stroke
				(width 0.1)
				(type default)
			)
			(layer "B.Fab")
		)
		(fp_line
			(start 0.3048 0.9906)
			(end -0.3048 0.9906)
			(stroke
				(width 0.1)
				(type default)
			)
			(layer "B.Fab")
		)
		(pad "1" smd rect
			(at 0 0 180)
			(size 0.508 0.508)
			(layers "B.Cu" "B.Mask" "B.Paste")
			(net "P3E_CPU0_PE3_OCP_TXP<5>")
		)
		(pad "2" smd rect
			(at 0 0.889 180)
			(size 0.508 0.508)
			(layers "B.Cu" "B.Mask" "B.Paste")
			(net "P3E_OCP_CPU0_PE3_C_TXP<5>")
		)
		(zone
			(layer "B.Cu")
			(hatch none 0.5)
			(connect_pads
				(clearance 0)
			)
			(min_thickness 0.25)
			(keepout
				(tracks allowed)
				(vias not_allowed)
				(pads allowed)
				(copperpour not_allowed)
				(footprints allowed)
			)
			(placement
				(enabled no)
				(sheetname "")
			)
			(fill
				(thermal_gap 0.5)
				(thermal_bridge_width 0.5)
				(island_removal_mode 0)
			)
			(polygon
				(pts
					(xy 447.166238 -52.153058) (xy 446.658238 -52.153058) (xy 446.658238 -51.772058) (xy 447.166238 -51.772058)
				)
			)
		)
		(zone
			(layer "B.Cu")
			(hatch none 0.5)
			(connect_pads
				(clearance 0)
			)
			(min_thickness 0.25)
			(keepout
				(tracks not_allowed)
				(vias allowed)
				(pads allowed)
				(copperpour not_allowed)
				(footprints allowed)
			)
			(placement
				(enabled no)
				(sheetname "")
			)
			(fill
				(thermal_gap 0.5)
				(thermal_bridge_width 0.5)
				(island_removal_mode 0)
			)
			(polygon
				(pts
					(xy 447.166238 -51.772058) (xy 446.658238 -51.772058) (xy 446.658238 -52.153058) (xy 447.166238 -52.153058)
				)
			)
		)
	)
	(footprint ""
		(layer "B.Cu")
		(at 482.65969 -58.831988 -90)
		(property "Reference" "R8E26"
			(at 0 0 90)
			(layer "B.SilkS")
			(hide yes)
			(effects
				(font
					(size 1.27 1.27)
				)
				(justify mirror)
			)
		)
		(property "Value" ""
			(at 0 0 90)
			(layer "B.Fab")
			(effects
				(font
					(size 1.27 1.27)
				)
				(justify mirror)
			)
		)
		(duplicate_pad_numbers_are_jumpers no)
		(fp_poly
			(pts
				(xy 0.2794 -0.1016) (xy -0.2794 -0.1016) (xy -0.2794 0.9906) (xy 0.2794 0.9906)
			)
			(stroke
				(width 0)
				(type default)
			)
			(fill no)
			(layer "B.CrtYd")
		)
		(fp_line
			(start -0.2794 0.9906)
			(end -0.2794 -0.1016)
			(stroke
				(width 0.1)
				(type default)
			)
			(layer "B.Fab")
		)
		(fp_line
			(start 0.2794 0.9906)
			(end -0.2794 0.9906)
			(stroke
				(width 0.1)
				(type default)
			)
			(layer "B.Fab")
		)
		(fp_line
			(start -0.2794 -0.1016)
			(end 0.2794 -0.1016)
			(stroke
				(width 0.1)
				(type default)
			)
			(layer "B.Fab")
		)
		(fp_line
			(start 0.2794 -0.1016)
			(end 0.2794 0.9906)
			(stroke
				(width 0.1)
				(type default)
			)
			(layer "B.Fab")
		)
		(pad "1" smd rect
			(at 0 0 90)
			(size 0.508 0.508)
			(layers "B.Cu" "B.Mask" "B.Paste")
			(net "FM_PE_OCP_WAKE_N")
		)
		(pad "2" smd rect
			(at 0 0.889 90)
			(size 0.508 0.508)
			(layers "B.Cu" "B.Mask" "B.Paste")
			(net "FM_ALL_WAKE_N")
		)
		(zone
			(layer "B.Cu")
			(hatch none 0.5)
			(connect_pads
				(clearance 0)
			)
			(min_thickness 0.25)
			(keepout
				(tracks not_allowed)
				(vias allowed)
				(pads allowed)
				(copperpour not_allowed)
				(footprints allowed)
			)
			(placement
				(enabled no)
				(sheetname "")
			)
			(fill
				(thermal_gap 0.5)
				(thermal_bridge_width 0.5)
				(island_removal_mode 0)
			)
			(polygon
				(pts
					(xy 482.02469 -58.577988) (xy 482.02469 -59.085988) (xy 482.40569 -59.085988) (xy 482.40569 -58.577988)
				)
			)
		)
		(zone
			(layer "B.Cu")
			(hatch none 0.5)
			(connect_pads
				(clearance 0)
			)
			(min_thickness 0.25)
			(keepout
				(tracks allowed)
				(vias not_allowed)
				(pads allowed)
				(copperpour not_allowed)
				(footprints allowed)
			)
			(placement
				(enabled no)
				(sheetname "")
			)
			(fill
				(thermal_gap 0.5)
				(thermal_bridge_width 0.5)
				(island_removal_mode 0)
			)
			(polygon
				(pts
					(xy 482.40569 -58.577988) (xy 482.40569 -59.085988) (xy 482.02469 -59.085988) (xy 482.02469 -58.577988)
				)
			)
		)
	)
	(footprint ""
		(layer "B.Cu")
		(at 446.292478 -152.855168)
		(property "Reference" "R25W179"
			(at 0.8382 -0.67818 0)
			(unlocked yes)
			(layer "B.SilkS")
			(effects
				(font
					(size 0.4064 0.254)
					(thickness 0.1524)
				)
				(justify left mirror)
			)
		)
		(property "Value" ""
			(at 0 0 0)
			(layer "B.Fab")
			(effects
				(font
					(size 1.27 1.27)
				)
				(justify mirror)
			)
		)
		(duplicate_pad_numbers_are_jumpers no)
		(fp_poly
			(pts
				(xy 0.2794 -0.1016) (xy -0.2794 -0.1016) (xy -0.2794 0.9906) (xy 0.2794 0.9906)
			)
			(stroke
				(width 0)
				(type default)
			)
			(fill no)
			(layer "B.CrtYd")
		)
		(fp_line
			(start -0.2794 -0.1016)
			(end 0.2794 -0.1016)
			(stroke
				(width 0.1)
				(type default)
			)
			(layer "B.Fab")
		)
		(fp_line
			(start -0.2794 0.9906)
			(end -0.2794 -0.1016)
			(stroke
				(width 0.1)
				(type default)
			)
			(layer "B.Fab")
		)
		(fp_line
			(start 0.2794 -0.1016)
			(end 0.2794 0.9906)
			(stroke
				(width 0.1)
				(type default)
			)
			(layer "B.Fab")
		)
		(fp_line
			(start 0.2794 0.9906)
			(end -0.2794 0.9906)
			(stroke
				(width 0.1)
				(type default)
			)
			(layer "B.Fab")
		)
		(pad "1" smd rect
			(at 0 0 180)
			(size 0.508 0.508)
			(layers "B.Cu" "B.Mask" "B.Paste")
			(net "P3V3_STBY")
		)
		(pad "2" smd rect
			(at 0 0.889 180)
			(size 0.508 0.508)
			(layers "B.Cu" "B.Mask" "B.Paste")
			(net "XDP_PRESENT_N")
		)
		(zone
			(layer "B.Cu")
			(hatch none 0.5)
			(connect_pads
				(clearance 0)
			)
			(min_thickness 0.25)
			(keepout
				(tracks allowed)
				(vias not_allowed)
				(pads allowed)
				(copperpour not_allowed)
				(footprints allowed)
			)
			(placement
				(enabled no)
				(sheetname "")
			)
			(fill
				(thermal_gap 0.5)
				(thermal_bridge_width 0.5)
				(island_removal_mode 0)
			)
			(polygon
				(pts
					(xy 446.546478 -152.601168) (xy 446.038478 -152.601168) (xy 446.038478 -152.220168) (xy 446.546478 -152.220168)
				)
			)
		)
		(zone
			(layer "B.Cu")
			(hatch none 0.5)
			(connect_pads
				(clearance 0)
			)
			(min_thickness 0.25)
			(keepout
				(tracks not_allowed)
				(vias allowed)
				(pads allowed)
				(copperpour not_allowed)
				(footprints allowed)
			)
			(placement
				(enabled no)
				(sheetname "")
			)
			(fill
				(thermal_gap 0.5)
				(thermal_bridge_width 0.5)
				(island_removal_mode 0)
			)
			(polygon
				(pts
					(xy 446.546478 -152.220168) (xy 446.038478 -152.220168) (xy 446.038478 -152.601168) (xy 446.546478 -152.601168)
				)
			)
		)
	)
	(footprint ""
		(layer "B.Cu")
		(at -2.20726 -117.89156)
		(property "Reference" "R9M18"
			(at 0 0 0)
			(layer "B.SilkS")
			(hide yes)
			(effects
				(font
					(size 1.27 1.27)
				)
				(justify mirror)
			)
		)
		(property "Value" ""
			(at 0 0 0)
			(layer "B.Fab")
			(effects
				(font
					(size 1.27 1.27)
				)
				(justify mirror)
			)
		)
		(duplicate_pad_numbers_are_jumpers no)
		(fp_rect
			(start -0.2794 0.9906)
			(end 0.2794 -0.1016)
			(stroke
				(width 0)
				(type default)
			)
			(fill no)
			(layer "B.CrtYd")
		)
		(fp_line
			(start -0.2794 -0.1016)
			(end 0.2794 -0.1016)
			(stroke
				(width 0.1)
				(type default)
			)
			(layer "B.Fab")
		)
		(fp_line
			(start -0.2794 0.9906)
			(end -0.2794 -0.1016)
			(stroke
				(width 0.1)
				(type default)
			)
			(layer "B.Fab")
		)
		(fp_line
			(start 0.2794 -0.1016)
			(end 0.2794 0.9906)
			(stroke
				(width 0.1)
				(type default)
			)
			(layer "B.Fab")
		)
		(fp_line
			(start 0.2794 0.9906)
			(end -0.2794 0.9906)
			(stroke
				(width 0.1)
				(type default)
			)
			(layer "B.Fab")
		)
		(pad "1" smd rect
			(at 0 0 180)
			(size 0.508 0.508)
			(layers "B.Cu" "B.Mask" "B.Paste")
			(net "PVCCIO_CPU1")
		)
		(pad "2" smd rect
			(at 0 0.889 180)
			(size 0.508 0.508)
			(layers "B.Cu" "B.Mask" "B.Paste")
			(net "SMB_CPU1_PE_HP_GTL_R_SDA")
		)
		(zone
			(layer "B.Cu")
			(hatch none 0.5)
			(connect_pads
				(clearance 0)
			)
			(min_thickness 0.25)
			(keepout
				(tracks not_allowed)
				(vias allowed)
				(pads allowed)
				(copperpour not_allowed)
				(footprints allowed)
			)
			(placement
				(enabled no)
				(sheetname "")
			)
			(fill
				(thermal_gap 0.5)
				(thermal_bridge_width 0.5)
				(island_removal_mode 0)
			)
			(polygon
				(pts
					(xy -2.46126 -117.25656) (xy -1.95326 -117.25656) (xy -1.95326 -117.63756) (xy -2.46126 -117.63756)
				)
			)
		)
		(zone
			(layer "B.Cu")
			(hatch none 0.5)
			(connect_pads
				(clearance 0)
			)
			(min_thickness 0.25)
			(keepout
				(tracks allowed)
				(vias not_allowed)
				(pads allowed)
				(copperpour not_allowed)
				(footprints allowed)
			)
			(placement
				(enabled no)
				(sheetname "")
			)
			(fill
				(thermal_gap 0.5)
				(thermal_bridge_width 0.5)
				(island_removal_mode 0)
			)
			(polygon
				(pts
					(xy -2.46126 -117.25656) (xy -1.95326 -117.25656) (xy -1.95326 -117.63756) (xy -2.46126 -117.63756)
				)
			)
		)
	)
	(footprint ""
		(layer "B.Cu")
		(at 186.69 -99.695)
		(property "Reference" ""
			(at 0 0 0)
			(layer "B.SilkS")
			(hide yes)
			(effects
				(font
					(size 1.27 1.27)
				)
				(justify mirror)
			)
		)
		(property "Value" ""
			(at 0 0 0)
			(layer "B.Fab")
			(effects
				(font
					(size 1.27 1.27)
				)
				(justify mirror)
			)
		)
		(duplicate_pad_numbers_are_jumpers no)
		(fp_poly
			(pts
				(arc
					(start 2.032 0)
					(mid -2.032 0)
					(end 2.032 0)
				)
			)
			(stroke
				(width 0)
				(type default)
			)
			(fill no)
			(layer "B.CrtYd")
		)
		(pad "1" smd circle
			(at 0 0 180)
			(size 1.016 1.016)
			(layers "B.Cu" "B.Mask" "B.Paste")
			(net "Net_392")
		)
		(zone
			(layers "F.Cu" "B.Cu" "In1.Cu" "In2.Cu" "In3.Cu" "In4.Cu" "In5.Cu" "In6.Cu"
				"In7.Cu" "In8.Cu" "In9.Cu" "In10.Cu" "In11.Cu" "In12.Cu"
			)
			(hatch none 0.5)
			(connect_pads
				(clearance 0)
			)
			(min_thickness 0.25)
			(keepout
				(tracks allowed)
				(vias not_allowed)
				(pads allowed)
				(copperpour not_allowed)
				(footprints allowed)
			)
			(placement
				(enabled no)
				(sheetname "")
			)
			(fill
				(thermal_gap 0.5)
				(thermal_bridge_width 0.5)
				(island_removal_mode 0)
			)
			(polygon
				(pts
					(arc
						(start 188.214 -99.695)
						(mid 185.166 -99.695)
						(end 188.214 -99.695)
					)
				)
			)
		)
		(zone
			(layer "B.Cu")
			(hatch none 0.5)
			(connect_pads
				(clearance 0)
			)
			(min_thickness 0.25)
			(keepout
				(tracks not_allowed)
				(vias allowed)
				(pads allowed)
				(copperpour not_allowed)
				(footprints allowed)
			)
			(placement
				(enabled no)
				(sheetname "")
			)
			(fill
				(thermal_gap 0.5)
				(thermal_bridge_width 0.5)
				(island_removal_mode 0)
			)
			(polygon
				(pts
					(arc
						(start 188.214 -99.695)
						(mid 185.166 -99.695)
						(end 188.214 -99.695)
					)
				)
			)
		)
	)
	(footprint ""
		(layer "B.Cu")
		(at 310.307228 -28.944824)
		(property "Reference" "R8D31"
			(at 0 0 0)
			(layer "B.SilkS")
			(hide yes)
			(effects
				(font
					(size 1.27 1.27)
				)
				(justify mirror)
			)
		)
		(property "Value" ""
			(at 0 0 0)
			(layer "B.Fab")
			(effects
				(font
					(size 1.27 1.27)
				)
				(justify mirror)
			)
		)
		(duplicate_pad_numbers_are_jumpers no)
		(fp_poly
			(pts
				(xy 0.2794 -0.1016) (xy -0.2794 -0.1016) (xy -0.2794 0.9906) (xy 0.2794 0.9906)
			)
			(stroke
				(width 0)
				(type default)
			)
			(fill no)
			(layer "B.CrtYd")
		)
		(fp_line
			(start -0.2794 -0.1016)
			(end 0.2794 -0.1016)
			(stroke
				(width 0.1)
				(type default)
			)
			(layer "B.Fab")
		)
		(fp_line
			(start -0.2794 0.9906)
			(end -0.2794 -0.1016)
			(stroke
				(width 0.1)
				(type default)
			)
			(layer "B.Fab")
		)
		(fp_line
			(start 0.2794 -0.1016)
			(end 0.2794 0.9906)
			(stroke
				(width 0.1)
				(type default)
			)
			(layer "B.Fab")
		)
		(fp_line
			(start 0.2794 0.9906)
			(end -0.2794 0.9906)
			(stroke
				(width 0.1)
				(type default)
			)
			(layer "B.Fab")
		)
		(pad "1" smd rect
			(at 0 0 180)
			(size 0.508 0.508)
			(layers "B.Cu" "B.Mask" "B.Paste")
			(net "P3V3_STBY")
		)
		(pad "2" smd rect
			(at 0 0.889 180)
			(size 0.508 0.508)
			(layers "B.Cu" "B.Mask" "B.Paste")
			(net "IRQ_DIMM_SAVE_LVT3_N")
		)
		(zone
			(layer "B.Cu")
			(hatch none 0.5)
			(connect_pads
				(clearance 0)
			)
			(min_thickness 0.25)
			(keepout
				(tracks allowed)
				(vias not_allowed)
				(pads allowed)
				(copperpour not_allowed)
				(footprints allowed)
			)
			(placement
				(enabled no)
				(sheetname "")
			)
			(fill
				(thermal_gap 0.5)
				(thermal_bridge_width 0.5)
				(island_removal_mode 0)
			)
			(polygon
				(pts
					(xy 310.561228 -28.690824) (xy 310.053228 -28.690824) (xy 310.053228 -28.309824) (xy 310.561228 -28.309824)
				)
			)
		)
		(zone
			(layer "B.Cu")
			(hatch none 0.5)
			(connect_pads
				(clearance 0)
			)
			(min_thickness 0.25)
			(keepout
				(tracks not_allowed)
				(vias allowed)
				(pads allowed)
				(copperpour not_allowed)
				(footprints allowed)
			)
			(placement
				(enabled no)
				(sheetname "")
			)
			(fill
				(thermal_gap 0.5)
				(thermal_bridge_width 0.5)
				(island_removal_mode 0)
			)
			(polygon
				(pts
					(xy 310.561228 -28.309824) (xy 310.053228 -28.309824) (xy 310.053228 -28.690824) (xy 310.561228 -28.690824)
				)
			)
		)
	)
	(footprint ""
		(layer "B.Cu")
		(at 13.11402 -99.57308 90)
		(property "Reference" "C9N16"
			(at 0 0 90)
			(layer "B.SilkS")
			(hide yes)
			(effects
				(font
					(size 1.27 1.27)
				)
				(justify mirror)
			)
		)
		(property "Value" ""
			(at 0 0 90)
			(layer "B.Fab")
			(effects
				(font
					(size 1.27 1.27)
				)
				(justify mirror)
			)
		)
		(duplicate_pad_numbers_are_jumpers no)
		(fp_poly
			(pts
				(xy -0.3048 -0.1016) (xy -0.3048 0.9906) (xy 0.3048 0.9906) (xy 0.3048 -0.1016)
			)
			(stroke
				(width 0)
				(type default)
			)
			(fill no)
			(layer "B.CrtYd")
		)
		(fp_line
			(start 0.3048 -0.1016)
			(end 0.3048 0.9906)
			(stroke
				(width 0.1)
				(type default)
			)
			(layer "B.Fab")
		)
		(fp_line
			(start -0.3048 -0.1016)
			(end 0.3048 -0.1016)
			(stroke
				(width 0.1)
				(type default)
			)
			(layer "B.Fab")
		)
		(fp_line
			(start 0.3048 0.9906)
			(end -0.3048 0.9906)
			(stroke
				(width 0.1)
				(type default)
			)
			(layer "B.Fab")
		)
		(fp_line
			(start -0.3048 0.9906)
			(end -0.3048 -0.1016)
			(stroke
				(width 0.1)
				(type default)
			)
			(layer "B.Fab")
		)
		(pad "1" smd rect
			(at 0 0 270)
			(size 0.508 0.508)
			(layers "B.Cu" "B.Mask" "B.Paste")
			(net "P3E_CPU1_PE3_MP_C_TXN<12>")
		)
		(pad "2" smd rect
			(at 0 0.889 270)
			(size 0.508 0.508)
			(layers "B.Cu" "B.Mask" "B.Paste")
			(net "P3E_CPU1_PE3_MP_TXN<12>")
		)
		(zone
			(layer "B.Cu")
			(hatch none 0.5)
			(connect_pads
				(clearance 0)
			)
			(min_thickness 0.25)
			(keepout
				(tracks allowed)
				(vias not_allowed)
				(pads allowed)
				(copperpour not_allowed)
				(footprints allowed)
			)
			(placement
				(enabled no)
				(sheetname "")
			)
			(fill
				(thermal_gap 0.5)
				(thermal_bridge_width 0.5)
				(island_removal_mode 0)
			)
			(polygon
				(pts
					(xy 13.36802 -99.82708) (xy 13.36802 -99.31908) (xy 13.74902 -99.31908) (xy 13.74902 -99.82708)
				)
			)
		)
		(zone
			(layer "B.Cu")
			(hatch none 0.5)
			(connect_pads
				(clearance 0)
			)
			(min_thickness 0.25)
			(keepout
				(tracks not_allowed)
				(vias allowed)
				(pads allowed)
				(copperpour not_allowed)
				(footprints allowed)
			)
			(placement
				(enabled no)
				(sheetname "")
			)
			(fill
				(thermal_gap 0.5)
				(thermal_bridge_width 0.5)
				(island_removal_mode 0)
			)
			(polygon
				(pts
					(xy 13.74902 -99.82708) (xy 13.74902 -99.31908) (xy 13.36802 -99.31908) (xy 13.36802 -99.82708)
				)
			)
		)
	)
	(footprint ""
		(layer "B.Cu")
		(at 374.231916 -37.063426 180)
		(property "Reference" "Q7E5"
			(at -2.94005 3.6957 90)
			(unlocked yes)
			(layer "B.SilkS")
			(effects
				(font
					(size 0.7874 0.5842)
					(thickness 0.1524)
				)
				(justify left mirror)
			)
		)
		(property "Value" ""
			(at 0 0 0)
			(layer "B.Fab")
			(effects
				(font
					(size 1.27 1.27)
				)
				(justify mirror)
			)
		)
		(duplicate_pad_numbers_are_jumpers no)
		(fp_circle
			(center 0.784352 -0.400558)
			(end 0.657352 -0.400558)
			(stroke
				(width 0.254)
				(type default)
			)
			(fill no)
			(layer "B.SilkS")
		)
		(fp_poly
			(pts
				(xy -0.2159 1.7526) (xy -1.5621 1.7526) (xy -1.5621 -0.4572) (xy -0.2159 -0.4572)
			)
			(stroke
				(width 0)
				(type default)
			)
			(fill no)
			(layer "B.CrtYd")
		)
		(fp_line
			(start -0.2159 1.75514)
			(end -1.5621 1.75514)
			(stroke
				(width 0.1)
				(type default)
			)
			(layer "B.Fab")
		)
		(fp_line
			(start -0.2159 -0.45466)
			(end -0.2159 1.75514)
			(stroke
				(width 0.1)
				(type default)
			)
			(layer "B.Fab")
		)
		(fp_line
			(start -1.5621 1.75514)
			(end -1.5621 -0.45466)
			(stroke
				(width 0.1)
				(type default)
			)
			(layer "B.Fab")
		)
		(fp_line
			(start -1.5621 -0.45466)
			(end -0.2159 -0.45466)
			(stroke
				(width 0.1)
				(type default)
			)
			(layer "B.Fab")
		)
		(fp_circle
			(center 0.508 -0.7874)
			(end 0.381 -0.7874)
			(stroke
				(width 0.254)
				(type default)
			)
			(fill no)
			(layer "B.Fab")
		)
		(pad "1" smd rect
			(at 0 0)
			(size 1.016 0.381)
			(layers "B.Cu" "B.Mask" "B.Paste")
			(net "GND")
		)
		(pad "2" smd rect
			(at 0 0.65024)
			(size 1.016 0.381)
			(layers "B.Cu" "B.Mask" "B.Paste")
			(net "IRQ_CPU0_PROCHOT_G_N")
		)
		(pad "3" smd rect
			(at 0 1.30048)
			(size 1.016 0.381)
			(layers "B.Cu" "B.Mask" "B.Paste")
			(net "H_CPU0_PROCHOT_G_N")
		)
		(pad "4" smd rect
			(at -1.778 1.30048)
			(size 1.016 0.381)
			(layers "B.Cu" "B.Mask" "B.Paste")
			(net "GND")
		)
		(pad "5" smd rect
			(at -1.778 0.65024)
			(size 1.016 0.381)
			(layers "B.Cu" "B.Mask" "B.Paste")
			(net "IRQ_CPU0_VRHOT")
		)
		(pad "6" smd rect
			(at -1.778 0)
			(size 1.016 0.381)
			(layers "B.Cu" "B.Mask" "B.Paste")
			(net "IRQ_CPU0_VRHOT")
		)
		(zone
			(layer "B.Cu")
			(hatch none 0.5)
			(connect_pads
				(clearance 0)
			)
			(min_thickness 0.25)
			(keepout
				(tracks allowed)
				(vias not_allowed)
				(pads allowed)
				(copperpour not_allowed)
				(footprints allowed)
			)
			(placement
				(enabled no)
				(sheetname "")
			)
			(fill
				(thermal_gap 0.5)
				(thermal_bridge_width 0.5)
				(island_removal_mode 0)
			)
			(polygon
				(pts
					(xy 373.723916 -36.872926) (xy 374.739916 -36.872926) (xy 374.739916 -38.562026) (xy 373.723916 -38.562026)
				)
			)
		)
		(zone
			(layer "B.Cu")
			(hatch none 0.5)
			(connect_pads
				(clearance 0)
			)
			(min_thickness 0.25)
			(keepout
				(tracks allowed)
				(vias not_allowed)
				(pads allowed)
				(copperpour not_allowed)
				(footprints allowed)
			)
			(placement
				(enabled no)
				(sheetname "")
			)
			(fill
				(thermal_gap 0.5)
				(thermal_bridge_width 0.5)
				(island_removal_mode 0)
			)
			(polygon
				(pts
					(xy 375.501916 -36.872926) (xy 376.517916 -36.872926) (xy 376.517916 -38.562026) (xy 375.501916 -38.562026)
				)
			)
		)
	)
	(footprint ""
		(layer "B.Cu")
		(at 468.181944 -11.42492)
		(property "Reference" "R2U32"
			(at 0 0 0)
			(layer "B.SilkS")
			(hide yes)
			(effects
				(font
					(size 1.27 1.27)
				)
				(justify mirror)
			)
		)
		(property "Value" ""
			(at 0 0 0)
			(layer "B.Fab")
			(effects
				(font
					(size 1.27 1.27)
				)
				(justify mirror)
			)
		)
		(duplicate_pad_numbers_are_jumpers no)
		(fp_poly
			(pts
				(xy 0.2794 -0.1016) (xy -0.2794 -0.1016) (xy -0.2794 0.9906) (xy 0.2794 0.9906)
			)
			(stroke
				(width 0)
				(type default)
			)
			(fill no)
			(layer "B.CrtYd")
		)
		(fp_line
			(start -0.2794 -0.1016)
			(end 0.2794 -0.1016)
			(stroke
				(width 0.1)
				(type default)
			)
			(layer "B.Fab")
		)
		(fp_line
			(start -0.2794 0.9906)
			(end -0.2794 -0.1016)
			(stroke
				(width 0.1)
				(type default)
			)
			(layer "B.Fab")
		)
		(fp_line
			(start 0.2794 -0.1016)
			(end 0.2794 0.9906)
			(stroke
				(width 0.1)
				(type default)
			)
			(layer "B.Fab")
		)
		(fp_line
			(start 0.2794 0.9906)
			(end -0.2794 0.9906)
			(stroke
				(width 0.1)
				(type default)
			)
			(layer "B.Fab")
		)
		(pad "1" smd rect
			(at 0 0 180)
			(size 0.508 0.508)
			(layers "B.Cu" "B.Mask" "B.Paste")
			(net "SMB_SLOTX24_BMC_STBY_LVC3_SCL")
		)
		(pad "2" smd rect
			(at 0 0.889 180)
			(size 0.508 0.508)
			(layers "B.Cu" "B.Mask" "B.Paste")
			(net "SMB_SLOTX24_STBY_LVC3_SCL_R2")
		)
		(zone
			(layer "B.Cu")
			(hatch none 0.5)
			(connect_pads
				(clearance 0)
			)
			(min_thickness 0.25)
			(keepout
				(tracks allowed)
				(vias not_allowed)
				(pads allowed)
				(copperpour not_allowed)
				(footprints allowed)
			)
			(placement
				(enabled no)
				(sheetname "")
			)
			(fill
				(thermal_gap 0.5)
				(thermal_bridge_width 0.5)
				(island_removal_mode 0)
			)
			(polygon
				(pts
					(xy 468.435944 -11.17092) (xy 467.927944 -11.17092) (xy 467.927944 -10.78992) (xy 468.435944 -10.78992)
				)
			)
		)
		(zone
			(layer "B.Cu")
			(hatch none 0.5)
			(connect_pads
				(clearance 0)
			)
			(min_thickness 0.25)
			(keepout
				(tracks not_allowed)
				(vias allowed)
				(pads allowed)
				(copperpour not_allowed)
				(footprints allowed)
			)
			(placement
				(enabled no)
				(sheetname "")
			)
			(fill
				(thermal_gap 0.5)
				(thermal_bridge_width 0.5)
				(island_removal_mode 0)
			)
			(polygon
				(pts
					(xy 468.435944 -10.78992) (xy 467.927944 -10.78992) (xy 467.927944 -11.17092) (xy 468.435944 -11.17092)
				)
			)
		)
	)
	(footprint ""
		(layer "B.Cu")
		(at 365.379 -40.5892 180)
		(property "Reference" "C8F4"
			(at 0 0 0)
			(layer "B.SilkS")
			(hide yes)
			(effects
				(font
					(size 1.27 1.27)
				)
				(justify mirror)
			)
		)
		(property "Value" ""
			(at 0 0 0)
			(layer "B.Fab")
			(effects
				(font
					(size 1.27 1.27)
				)
				(justify mirror)
			)
		)
		(duplicate_pad_numbers_are_jumpers no)
		(fp_poly
			(pts
				(xy -0.3048 -0.1016) (xy -0.3048 0.9906) (xy 0.3048 0.9906) (xy 0.3048 -0.1016)
			)
			(stroke
				(width 0)
				(type default)
			)
			(fill no)
			(layer "B.CrtYd")
		)
		(fp_line
			(start 0.3048 0.9906)
			(end -0.3048 0.9906)
			(stroke
				(width 0.1)
				(type default)
			)
			(layer "B.Fab")
		)
		(fp_line
			(start 0.3048 -0.1016)
			(end 0.3048 0.9906)
			(stroke
				(width 0.1)
				(type default)
			)
			(layer "B.Fab")
		)
		(fp_line
			(start -0.3048 0.9906)
			(end -0.3048 -0.1016)
			(stroke
				(width 0.1)
				(type default)
			)
			(layer "B.Fab")
		)
		(fp_line
			(start -0.3048 -0.1016)
			(end 0.3048 -0.1016)
			(stroke
				(width 0.1)
				(type default)
			)
			(layer "B.Fab")
		)
		(pad "1" smd rect
			(at 0 0)
			(size 0.508 0.508)
			(layers "B.Cu" "B.Mask" "B.Paste")
			(net "P3V3_STBY")
		)
		(pad "2" smd rect
			(at 0 0.889)
			(size 0.508 0.508)
			(layers "B.Cu" "B.Mask" "B.Paste")
			(net "GND")
		)
		(zone
			(layer "B.Cu")
			(hatch none 0.5)
			(connect_pads
				(clearance 0)
			)
			(min_thickness 0.25)
			(keepout
				(tracks not_allowed)
				(vias allowed)
				(pads allowed)
				(copperpour not_allowed)
				(footprints allowed)
			)
			(placement
				(enabled no)
				(sheetname "")
			)
			(fill
				(thermal_gap 0.5)
				(thermal_bridge_width 0.5)
				(island_removal_mode 0)
			)
			(polygon
				(pts
					(xy 365.125 -41.2242) (xy 365.633 -41.2242) (xy 365.633 -40.8432) (xy 365.125 -40.8432)
				)
			)
		)
		(zone
			(layer "B.Cu")
			(hatch none 0.5)
			(connect_pads
				(clearance 0)
			)
			(min_thickness 0.25)
			(keepout
				(tracks allowed)
				(vias not_allowed)
				(pads allowed)
				(copperpour not_allowed)
				(footprints allowed)
			)
			(placement
				(enabled no)
				(sheetname "")
			)
			(fill
				(thermal_gap 0.5)
				(thermal_bridge_width 0.5)
				(island_removal_mode 0)
			)
			(polygon
				(pts
					(xy 365.125 -40.8432) (xy 365.633 -40.8432) (xy 365.633 -41.2242) (xy 365.125 -41.2242)
				)
			)
		)
	)
	(footprint ""
		(layer "B.Cu")
		(at 210.612228 -95.596202 -90)
		(property "Reference" "C6N4"
			(at -3.401568 -4.525772 0)
			(unlocked yes)
			(layer "B.SilkS")
			(effects
				(font
					(size 0.7874 0.5842)
					(thickness 0.1524)
				)
				(justify mirror)
			)
		)
		(property "Value" ""
			(at 0 0 90)
			(layer "B.Fab")
			(effects
				(font
					(size 1.27 1.27)
				)
				(justify mirror)
			)
		)
		(duplicate_pad_numbers_are_jumpers no)
		(fp_line
			(start -2.286 7.366)
			(end -1.600708 7.366)
			(stroke
				(width 0.1524)
				(type default)
			)
			(layer "B.SilkS")
		)
		(fp_line
			(start -2.286 7.366)
			(end -2.286 1.63195)
			(stroke
				(width 0.1524)
				(type default)
			)
			(layer "B.SilkS")
		)
		(fp_line
			(start 2.286 7.366)
			(end 1.60147 7.366)
			(stroke
				(width 0.1524)
				(type default)
			)
			(layer "B.SilkS")
		)
		(fp_line
			(start 2.286 7.366)
			(end 2.286 1.632712)
			(stroke
				(width 0.1524)
				(type default)
			)
			(layer "B.SilkS")
		)
		(fp_line
			(start -2.504948 1.633728)
			(end -1.6002 1.633728)
			(stroke
				(width 0.1524)
				(type default)
			)
			(layer "B.SilkS")
		)
		(fp_line
			(start 2.563114 1.633728)
			(end 1.6002 1.633728)
			(stroke
				(width 0.1524)
				(type default)
			)
			(layer "B.SilkS")
		)
		(fp_line
			(start -2.504948 -1.616456)
			(end -2.504948 1.633728)
			(stroke
				(width 0.1524)
				(type default)
			)
			(layer "B.SilkS")
		)
		(fp_line
			(start -1.6002 -1.616456)
			(end -2.504948 -1.616456)
			(stroke
				(width 0.1524)
				(type default)
			)
			(layer "B.SilkS")
		)
		(fp_line
			(start 1.6002 -1.616456)
			(end 2.563114 -1.616456)
			(stroke
				(width 0.1524)
				(type default)
			)
			(layer "B.SilkS")
		)
		(fp_line
			(start 2.563114 -1.616456)
			(end 2.563114 1.633728)
			(stroke
				(width 0.1524)
				(type default)
			)
			(layer "B.SilkS")
		)
		(fp_rect
			(start 2.286 7.366)
			(end -2.286 -0.254)
			(stroke
				(width 0)
				(type default)
			)
			(fill no)
			(layer "B.CrtYd")
		)
		(fp_line
			(start -2.286 7.366)
			(end 2.286 7.366)
			(stroke
				(width 0.1)
				(type default)
			)
			(layer "B.Fab")
		)
		(fp_line
			(start 2.286 7.366)
			(end 2.286 -0.254)
			(stroke
				(width 0.1)
				(type default)
			)
			(layer "B.Fab")
		)
		(fp_line
			(start -2.286 -0.254)
			(end -2.286 7.366)
			(stroke
				(width 0.1)
				(type default)
			)
			(layer "B.Fab")
		)
		(fp_line
			(start 2.286 -0.254)
			(end -2.286 -0.254)
			(stroke
				(width 0.1)
				(type default)
			)
			(layer "B.Fab")
		)
		(pad "1" smd rect
			(at 0 0 90)
			(size 2.54 3.048)
			(layers "B.Cu" "B.Mask" "B.Paste")
			(net "PVSA_CPU0")
		)
		(pad "2" smd rect
			(at 0 7.112 90)
			(size 2.54 3.048)
			(layers "B.Cu" "B.Mask" "B.Paste")
			(net "GND")
		)
	)
	(footprint ""
		(layer "B.Cu")
		(at 245.14302 -87.46236 -90)
		(property "Reference" "R5P2"
			(at 0 0 90)
			(layer "B.SilkS")
			(hide yes)
			(effects
				(font
					(size 1.27 1.27)
				)
				(justify mirror)
			)
		)
		(property "Value" ""
			(at 0 0 90)
			(layer "B.Fab")
			(effects
				(font
					(size 1.27 1.27)
				)
				(justify mirror)
			)
		)
		(duplicate_pad_numbers_are_jumpers no)
		(fp_poly
			(pts
				(xy 0.2794 -0.1016) (xy -0.2794 -0.1016) (xy -0.2794 0.9906) (xy 0.2794 0.9906)
			)
			(stroke
				(width 0)
				(type default)
			)
			(fill no)
			(layer "B.CrtYd")
		)
		(fp_line
			(start -0.2794 0.9906)
			(end -0.2794 -0.1016)
			(stroke
				(width 0.1)
				(type default)
			)
			(layer "B.Fab")
		)
		(fp_line
			(start 0.2794 0.9906)
			(end -0.2794 0.9906)
			(stroke
				(width 0.1)
				(type default)
			)
			(layer "B.Fab")
		)
		(fp_line
			(start -0.2794 -0.1016)
			(end 0.2794 -0.1016)
			(stroke
				(width 0.1)
				(type default)
			)
			(layer "B.Fab")
		)
		(fp_line
			(start 0.2794 -0.1016)
			(end 0.2794 0.9906)
			(stroke
				(width 0.1)
				(type default)
			)
			(layer "B.Fab")
		)
		(pad "1" smd rect
			(at 0 0 90)
			(size 0.508 0.508)
			(layers "B.Cu" "B.Mask" "B.Paste")
			(net "PD_CPU0_TEST14")
		)
		(pad "2" smd rect
			(at 0 0.889 90)
			(size 0.508 0.508)
			(layers "B.Cu" "B.Mask" "B.Paste")
			(net "GND")
		)
		(zone
			(layer "B.Cu")
			(hatch none 0.5)
			(connect_pads
				(clearance 0)
			)
			(min_thickness 0.25)
			(keepout
				(tracks not_allowed)
				(vias allowed)
				(pads allowed)
				(copperpour not_allowed)
				(footprints allowed)
			)
			(placement
				(enabled no)
				(sheetname "")
			)
			(fill
				(thermal_gap 0.5)
				(thermal_bridge_width 0.5)
				(island_removal_mode 0)
			)
			(polygon
				(pts
					(xy 244.50802 -87.20836) (xy 244.50802 -87.71636) (xy 244.88902 -87.71636) (xy 244.88902 -87.20836)
				)
			)
		)
		(zone
			(layer "B.Cu")
			(hatch none 0.5)
			(connect_pads
				(clearance 0)
			)
			(min_thickness 0.25)
			(keepout
				(tracks allowed)
				(vias not_allowed)
				(pads allowed)
				(copperpour not_allowed)
				(footprints allowed)
			)
			(placement
				(enabled no)
				(sheetname "")
			)
			(fill
				(thermal_gap 0.5)
				(thermal_bridge_width 0.5)
				(island_removal_mode 0)
			)
			(polygon
				(pts
					(xy 244.88902 -87.20836) (xy 244.88902 -87.71636) (xy 244.50802 -87.71636) (xy 244.50802 -87.20836)
				)
			)
		)
	)
	(footprint ""
		(layer "B.Cu")
		(at 401.066 -104.0765 180)
		(property "Reference" "R6W25"
			(at 0.8382 -0.67818 180)
			(unlocked yes)
			(layer "B.SilkS")
			(effects
				(font
					(size 0.4064 0.254)
					(thickness 0.1524)
				)
				(justify left mirror)
			)
		)
		(property "Value" ""
			(at 0 0 0)
			(layer "B.Fab")
			(effects
				(font
					(size 1.27 1.27)
				)
				(justify mirror)
			)
		)
		(duplicate_pad_numbers_are_jumpers no)
		(fp_poly
			(pts
				(xy 0.2794 -0.1016) (xy -0.2794 -0.1016) (xy -0.2794 0.9906) (xy 0.2794 0.9906)
			)
			(stroke
				(width 0)
				(type default)
			)
			(fill no)
			(layer "B.CrtYd")
		)
		(fp_line
			(start 0.2794 0.9906)
			(end -0.2794 0.9906)
			(stroke
				(width 0.1)
				(type default)
			)
			(layer "B.Fab")
		)
		(fp_line
			(start 0.2794 -0.1016)
			(end 0.2794 0.9906)
			(stroke
				(width 0.1)
				(type default)
			)
			(layer "B.Fab")
		)
		(fp_line
			(start -0.2794 0.9906)
			(end -0.2794 -0.1016)
			(stroke
				(width 0.1)
				(type default)
			)
			(layer "B.Fab")
		)
		(fp_line
			(start -0.2794 -0.1016)
			(end 0.2794 -0.1016)
			(stroke
				(width 0.1)
				(type default)
			)
			(layer "B.Fab")
		)
		(pad "1" smd rect
			(at 0 0)
			(size 0.508 0.508)
			(layers "B.Cu" "B.Mask" "B.Paste")
			(net "P3V3_STBY")
		)
		(pad "2" smd rect
			(at 0 0.889)
			(size 0.508 0.508)
			(layers "B.Cu" "B.Mask" "B.Paste")
			(net "SMB_PMBUS_BMC_STBY_LVC3_SCL_R1")
		)
		(zone
			(layer "B.Cu")
			(hatch none 0.5)
			(connect_pads
				(clearance 0)
			)
			(min_thickness 0.25)
			(keepout
				(tracks not_allowed)
				(vias allowed)
				(pads allowed)
				(copperpour not_allowed)
				(footprints allowed)
			)
			(placement
				(enabled no)
				(sheetname "")
			)
			(fill
				(thermal_gap 0.5)
				(thermal_bridge_width 0.5)
				(island_removal_mode 0)
			)
			(polygon
				(pts
					(xy 400.812 -104.7115) (xy 401.32 -104.7115) (xy 401.32 -104.3305) (xy 400.812 -104.3305)
				)
			)
		)
		(zone
			(layer "B.Cu")
			(hatch none 0.5)
			(connect_pads
				(clearance 0)
			)
			(min_thickness 0.25)
			(keepout
				(tracks allowed)
				(vias not_allowed)
				(pads allowed)
				(copperpour not_allowed)
				(footprints allowed)
			)
			(placement
				(enabled no)
				(sheetname "")
			)
			(fill
				(thermal_gap 0.5)
				(thermal_bridge_width 0.5)
				(island_removal_mode 0)
			)
			(polygon
				(pts
					(xy 400.812 -104.3305) (xy 401.32 -104.3305) (xy 401.32 -104.7115) (xy 400.812 -104.7115)
				)
			)
		)
	)
	(footprint ""
		(layer "B.Cu")
		(at 266.397232 -17.7546 90)
		(property "Reference" "C5T8"
			(at -1.848866 0.752348 90)
			(unlocked yes)
			(layer "B.SilkS")
			(effects
				(font
					(size 1.27 0.9652)
					(thickness 0.1524)
				)
				(justify mirror)
			)
		)
		(property "Value" ""
			(at 0 0 90)
			(layer "B.Fab")
			(effects
				(font
					(size 1.27 1.27)
				)
				(justify mirror)
			)
		)
		(duplicate_pad_numbers_are_jumpers no)
		(fp_rect
			(start 0.500126 1.598422)
			(end -0.500126 -0.201422)
			(stroke
				(width 0)
				(type default)
			)
			(fill no)
			(layer "B.CrtYd")
		)
		(fp_line
			(start 0.500126 -0.201422)
			(end -0.500126 -0.201422)
			(stroke
				(width 0.1)
				(type default)
			)
			(layer "B.Fab")
		)
		(fp_line
			(start -0.500126 -0.201422)
			(end -0.500126 1.598422)
			(stroke
				(width 0.1)
				(type default)
			)
			(layer "B.Fab")
		)
		(fp_line
			(start 0.500126 1.598422)
			(end 0.500126 -0.201422)
			(stroke
				(width 0.1)
				(type default)
			)
			(layer "B.Fab")
		)
		(fp_line
			(start -0.500126 1.598422)
			(end 0.500126 1.598422)
			(stroke
				(width 0.1)
				(type default)
			)
			(layer "B.Fab")
		)
		(pad "1" smd rect
			(at 0 0)
			(size 0.889 0.9906)
			(layers "B.Cu" "B.Mask" "B.Paste")
			(net "PVDDQ_ABC")
		)
		(pad "2" smd rect
			(at 0 1.397)
			(size 0.889 0.9906)
			(layers "B.Cu" "B.Mask" "B.Paste")
			(net "GND")
		)
		(zone
			(layer "B.Cu")
			(hatch none 0.5)
			(connect_pads
				(clearance 0)
			)
			(min_thickness 0.25)
			(keepout
				(tracks allowed)
				(vias not_allowed)
				(pads allowed)
				(copperpour not_allowed)
				(footprints allowed)
			)
			(placement
				(enabled no)
				(sheetname "")
			)
			(fill
				(thermal_gap 0.5)
				(thermal_bridge_width 0.5)
				(island_removal_mode 0)
			)
			(polygon
				(pts
					(xy 267.349732 -18.2499) (xy 266.841732 -18.2499) (xy 266.841732 -17.2593) (xy 267.349732 -17.2593)
				)
			)
		)
		(zone
			(layer "B.Cu")
			(hatch none 0.5)
			(connect_pads
				(clearance 0)
			)
			(min_thickness 0.25)
			(keepout
				(tracks not_allowed)
				(vias allowed)
				(pads allowed)
				(copperpour not_allowed)
				(footprints allowed)
			)
			(placement
				(enabled no)
				(sheetname "")
			)
			(fill
				(thermal_gap 0.5)
				(thermal_bridge_width 0.5)
				(island_removal_mode 0)
			)
			(polygon
				(pts
					(xy 267.349732 -18.2499) (xy 266.841732 -18.2499) (xy 266.841732 -17.2593) (xy 267.349732 -17.2593)
				)
			)
		)
	)
	(footprint ""
		(layer "B.Cu")
		(at 269.559532 -3.3528 90)
		(property "Reference" "C5G57"
			(at -1.14681 0.76708 180)
			(unlocked yes)
			(layer "B.SilkS")
			(effects
				(font
					(size 0.7874 0.5842)
					(thickness 0.1524)
				)
				(justify mirror)
			)
		)
		(property "Value" ""
			(at 0 0 90)
			(layer "B.Fab")
			(effects
				(font
					(size 1.27 1.27)
				)
				(justify mirror)
			)
		)
		(duplicate_pad_numbers_are_jumpers no)
		(fp_rect
			(start -0.4953 -0.2032)
			(end 0.4953 1.6002)
			(stroke
				(width 0)
				(type default)
			)
			(fill no)
			(layer "B.CrtYd")
		)
		(fp_line
			(start 0.4953 -0.2032)
			(end -0.4953 -0.2032)
			(stroke
				(width 0.1)
				(type default)
			)
			(layer "B.Fab")
		)
		(fp_line
			(start -0.4953 -0.2032)
			(end -0.4953 1.6002)
			(stroke
				(width 0.1)
				(type default)
			)
			(layer "B.Fab")
		)
		(fp_line
			(start 0.4953 1.6002)
			(end 0.4953 -0.2032)
			(stroke
				(width 0.1)
				(type default)
			)
			(layer "B.Fab")
		)
		(fp_line
			(start -0.4953 1.6002)
			(end 0.4953 1.6002)
			(stroke
				(width 0.1)
				(type default)
			)
			(layer "B.Fab")
		)
		(pad "1" smd rect
			(at 0 0 270)
			(size 0.762 0.889)
			(layers "B.Cu" "B.Mask" "B.Paste")
			(net "PVDDQ_ABC")
		)
		(pad "2" smd rect
			(at 0 1.397 270)
			(size 0.762 0.889)
			(layers "B.Cu" "B.Mask" "B.Paste")
			(net "GND")
		)
		(zone
			(layer "B.Cu")
			(hatch none 0.5)
			(connect_pads
				(clearance 0)
			)
			(min_thickness 0.25)
			(keepout
				(tracks not_allowed)
				(vias allowed)
				(pads allowed)
				(copperpour not_allowed)
				(footprints allowed)
			)
			(placement
				(enabled no)
				(sheetname "")
			)
			(fill
				(thermal_gap 0.5)
				(thermal_bridge_width 0.5)
				(island_removal_mode 0)
			)
			(polygon
				(pts
					(xy 270.004032 -2.9718) (xy 270.512032 -2.9718) (xy 270.512032 -3.7338) (xy 270.004032 -3.7338)
				)
			)
		)
	)
	(footprint ""
		(layer "B.Cu")
		(at 390.5758 -154.278838 180)
		(property "Reference" "C4W4"
			(at 0.8382 -0.67818 180)
			(unlocked yes)
			(layer "B.SilkS")
			(effects
				(font
					(size 0.4064 0.254)
					(thickness 0.1524)
				)
				(justify left mirror)
			)
		)
		(property "Value" ""
			(at 0 0 0)
			(layer "B.Fab")
			(effects
				(font
					(size 1.27 1.27)
				)
				(justify mirror)
			)
		)
		(duplicate_pad_numbers_are_jumpers no)
		(fp_poly
			(pts
				(xy -0.3048 -0.1016) (xy -0.3048 0.9906) (xy 0.3048 0.9906) (xy 0.3048 -0.1016)
			)
			(stroke
				(width 0)
				(type default)
			)
			(fill no)
			(layer "B.CrtYd")
		)
		(fp_line
			(start 0.3048 0.9906)
			(end -0.3048 0.9906)
			(stroke
				(width 0.1)
				(type default)
			)
			(layer "B.Fab")
		)
		(fp_line
			(start 0.3048 -0.1016)
			(end 0.3048 0.9906)
			(stroke
				(width 0.1)
				(type default)
			)
			(layer "B.Fab")
		)
		(fp_line
			(start -0.3048 0.9906)
			(end -0.3048 -0.1016)
			(stroke
				(width 0.1)
				(type default)
			)
			(layer "B.Fab")
		)
		(fp_line
			(start -0.3048 -0.1016)
			(end 0.3048 -0.1016)
			(stroke
				(width 0.1)
				(type default)
			)
			(layer "B.Fab")
		)
		(pad "1" smd rect
			(at 0 0)
			(size 0.508 0.508)
			(layers "B.Cu" "B.Mask" "B.Paste")
			(net "A_TSENSE_P1V05_PCH_STBY_TMON")
		)
		(pad "2" smd rect
			(at 0 0.889)
			(size 0.508 0.508)
			(layers "B.Cu" "B.Mask" "B.Paste")
			(net "GND")
		)
		(zone
			(layer "B.Cu")
			(hatch none 0.5)
			(connect_pads
				(clearance 0)
			)
			(min_thickness 0.25)
			(keepout
				(tracks not_allowed)
				(vias allowed)
				(pads allowed)
				(copperpour not_allowed)
				(footprints allowed)
			)
			(placement
				(enabled no)
				(sheetname "")
			)
			(fill
				(thermal_gap 0.5)
				(thermal_bridge_width 0.5)
				(island_removal_mode 0)
			)
			(polygon
				(pts
					(xy 390.3218 -154.913838) (xy 390.8298 -154.913838) (xy 390.8298 -154.532838) (xy 390.3218 -154.532838)
				)
			)
		)
		(zone
			(layer "B.Cu")
			(hatch none 0.5)
			(connect_pads
				(clearance 0)
			)
			(min_thickness 0.25)
			(keepout
				(tracks allowed)
				(vias not_allowed)
				(pads allowed)
				(copperpour not_allowed)
				(footprints allowed)
			)
			(placement
				(enabled no)
				(sheetname "")
			)
			(fill
				(thermal_gap 0.5)
				(thermal_bridge_width 0.5)
				(island_removal_mode 0)
			)
			(polygon
				(pts
					(xy 390.3218 -154.532838) (xy 390.8298 -154.532838) (xy 390.8298 -154.913838) (xy 390.3218 -154.913838)
				)
			)
		)
	)
	(footprint ""
		(layer "B.Cu")
		(at 442.722 -14.6812 -90)
		(property "Reference" "R1W35"
			(at 0.8382 -0.67818 270)
			(unlocked yes)
			(layer "B.SilkS")
			(effects
				(font
					(size 0.4064 0.254)
					(thickness 0.1524)
				)
				(justify left mirror)
			)
		)
		(property "Value" ""
			(at 0 0 90)
			(layer "B.Fab")
			(effects
				(font
					(size 1.27 1.27)
				)
				(justify mirror)
			)
		)
		(duplicate_pad_numbers_are_jumpers no)
		(fp_poly
			(pts
				(xy 0.2794 -0.1016) (xy -0.2794 -0.1016) (xy -0.2794 0.9906) (xy 0.2794 0.9906)
			)
			(stroke
				(width 0)
				(type default)
			)
			(fill no)
			(layer "B.CrtYd")
		)
		(fp_line
			(start -0.2794 0.9906)
			(end -0.2794 -0.1016)
			(stroke
				(width 0.1)
				(type default)
			)
			(layer "B.Fab")
		)
		(fp_line
			(start 0.2794 0.9906)
			(end -0.2794 0.9906)
			(stroke
				(width 0.1)
				(type default)
			)
			(layer "B.Fab")
		)
		(fp_line
			(start -0.2794 -0.1016)
			(end 0.2794 -0.1016)
			(stroke
				(width 0.1)
				(type default)
			)
			(layer "B.Fab")
		)
		(fp_line
			(start 0.2794 -0.1016)
			(end 0.2794 0.9906)
			(stroke
				(width 0.1)
				(type default)
			)
			(layer "B.Fab")
		)
		(pad "1" smd rect
			(at 0 0 90)
			(size 0.508 0.508)
			(layers "B.Cu" "B.Mask" "B.Paste")
			(net "PVCCIO_CPU0")
		)
		(pad "2" smd rect
			(at 0 0.889 90)
			(size 0.508 0.508)
			(layers "B.Cu" "B.Mask" "B.Paste")
			(net "P0V7_GTL2014_2")
		)
		(zone
			(layer "B.Cu")
			(hatch none 0.5)
			(connect_pads
				(clearance 0)
			)
			(min_thickness 0.25)
			(keepout
				(tracks not_allowed)
				(vias allowed)
				(pads allowed)
				(copperpour not_allowed)
				(footprints allowed)
			)
			(placement
				(enabled no)
				(sheetname "")
			)
			(fill
				(thermal_gap 0.5)
				(thermal_bridge_width 0.5)
				(island_removal_mode 0)
			)
			(polygon
				(pts
					(xy 442.087 -14.4272) (xy 442.087 -14.9352) (xy 442.468 -14.9352) (xy 442.468 -14.4272)
				)
			)
		)
		(zone
			(layer "B.Cu")
			(hatch none 0.5)
			(connect_pads
				(clearance 0)
			)
			(min_thickness 0.25)
			(keepout
				(tracks allowed)
				(vias not_allowed)
				(pads allowed)
				(copperpour not_allowed)
				(footprints allowed)
			)
			(placement
				(enabled no)
				(sheetname "")
			)
			(fill
				(thermal_gap 0.5)
				(thermal_bridge_width 0.5)
				(island_removal_mode 0)
			)
			(polygon
				(pts
					(xy 442.468 -14.4272) (xy 442.468 -14.9352) (xy 442.087 -14.9352) (xy 442.087 -14.4272)
				)
			)
		)
	)
	(footprint ""
		(layer "B.Cu")
		(at 450.8627 -145.21053 -90)
		(property "Reference" "FB25W5"
			(at 0 0 90)
			(layer "B.SilkS")
			(hide yes)
			(effects
				(font
					(size 1.27 1.27)
				)
				(justify mirror)
			)
		)
		(property "Value" "*"
			(at 0.0127 -7.01675 270)
			(unlocked yes)
			(layer "B.Fab")
			(hide yes)
			(effects
				(font
					(size 0.889 0.889)
					(thickness 0.1524)
				)
				(justify mirror)
			)
		)
		(property "Device Type" "BLM15AG121SN-1GP_DISCRET-G-BLMA"
			(at 0.0127 -8.54075 270)
			(unlocked yes)
			(layer "B.Fab")
			(hide yes)
			(effects
				(font
					(size 0.889 0.889)
					(thickness 0.1524)
				)
				(justify mirror)
			)
		)
		(duplicate_pad_numbers_are_jumpers no)
		(fp_line
			(start 0.508 0.9398)
			(end 0.508 0.8636)
			(stroke
				(width 0.1524)
				(type default)
			)
			(layer "B.SilkS")
		)
		(fp_line
			(start -0.508 -0.9398)
			(end 0.508 -0.9398)
			(stroke
				(width 0.1524)
				(type default)
			)
			(layer "B.SilkS")
		)
		(fp_line
			(start 0.508 -0.9398)
			(end 0.508 0.9398)
			(stroke
				(width 0.1524)
				(type default)
			)
			(layer "B.SilkS")
		)
		(fp_rect
			(start 0.508 0.9398)
			(end -0.508 -0.9398)
			(stroke
				(width 0)
				(type default)
			)
			(fill no)
			(layer "B.CrtYd")
		)
		(fp_rect
			(start 0.508 0.9398)
			(end -0.508 -0.9398)
			(stroke
				(width 0)
				(type default)
			)
			(fill no)
			(layer "B.Fab")
		)
		(pad "1" smd custom
			(at 0 -0.4445 90)
			(size 0.1397 0.1397)
			(layers "B.Cu" "B.Mask" "B.Paste")
			(net "XDP_TMS_R")
			(options
				(clearance outline)
				(anchor circle)
			)
			(primitives
				(gr_poly
					(pts
						(arc
							(start -0.1778 0.2794)
							(mid -0.249642 0.249642)
							(end -0.2794 0.1778)
						)
						(arc
							(start -0.2794 -0.1778)
							(mid -0.249642 -0.249642)
							(end -0.1778 -0.2794)
						)
						(arc
							(start 0.1778 -0.2794)
							(mid 0.249642 -0.249642)
							(end 0.2794 -0.1778)
						)
						(arc
							(start 0.2794 0.1778)
							(mid 0.249642 0.249642)
							(end 0.1778 0.2794)
						)
					)
					(width 0)
					(fill yes)
				)
			)
		)
		(pad "2" smd custom
			(at 0 0.4445 90)
			(size 0.1397 0.1397)
			(layers "B.Cu" "B.Mask" "B.Paste")
			(net "XDP_TMS")
			(options
				(clearance outline)
				(anchor circle)
			)
			(primitives
				(gr_poly
					(pts
						(arc
							(start -0.1778 0.2794)
							(mid -0.249642 0.249642)
							(end -0.2794 0.1778)
						)
						(arc
							(start -0.2794 -0.1778)
							(mid -0.249642 -0.249642)
							(end -0.1778 -0.2794)
						)
						(arc
							(start 0.1778 -0.2794)
							(mid 0.249642 -0.249642)
							(end 0.2794 -0.1778)
						)
						(arc
							(start 0.2794 0.1778)
							(mid 0.249642 0.249642)
							(end 0.1778 0.2794)
						)
					)
					(width 0)
					(fill yes)
				)
			)
		)
	)
	(footprint ""
		(layer "B.Cu")
		(at 63.2968 -91.1352 90)
		(property "Reference" "R8N3"
			(at 0 0 90)
			(layer "B.SilkS")
			(hide yes)
			(effects
				(font
					(size 1.27 1.27)
				)
				(justify mirror)
			)
		)
		(property "Value" ""
			(at 0 0 90)
			(layer "B.Fab")
			(effects
				(font
					(size 1.27 1.27)
				)
				(justify mirror)
			)
		)
		(duplicate_pad_numbers_are_jumpers no)
		(fp_poly
			(pts
				(xy 0.2794 -0.1016) (xy -0.2794 -0.1016) (xy -0.2794 0.9906) (xy 0.2794 0.9906)
			)
			(stroke
				(width 0)
				(type default)
			)
			(fill no)
			(layer "B.CrtYd")
		)
		(fp_line
			(start 0.2794 -0.1016)
			(end 0.2794 0.9906)
			(stroke
				(width 0.1)
				(type default)
			)
			(layer "B.Fab")
		)
		(fp_line
			(start -0.2794 -0.1016)
			(end 0.2794 -0.1016)
			(stroke
				(width 0.1)
				(type default)
			)
			(layer "B.Fab")
		)
		(fp_line
			(start 0.2794 0.9906)
			(end -0.2794 0.9906)
			(stroke
				(width 0.1)
				(type default)
			)
			(layer "B.Fab")
		)
		(fp_line
			(start -0.2794 0.9906)
			(end -0.2794 -0.1016)
			(stroke
				(width 0.1)
				(type default)
			)
			(layer "B.Fab")
		)
		(pad "1" smd rect
			(at 0 0 270)
			(size 0.508 0.508)
			(layers "B.Cu" "B.Mask" "B.Paste")
			(net "P3V3_STBY")
		)
		(pad "2" smd rect
			(at 0 0.889 270)
			(size 0.508 0.508)
			(layers "B.Cu" "B.Mask" "B.Paste")
			(net "FM_CPU1_PKGID2")
		)
		(zone
			(layer "B.Cu")
			(hatch none 0.5)
			(connect_pads
				(clearance 0)
			)
			(min_thickness 0.25)
			(keepout
				(tracks allowed)
				(vias not_allowed)
				(pads allowed)
				(copperpour not_allowed)
				(footprints allowed)
			)
			(placement
				(enabled no)
				(sheetname "")
			)
			(fill
				(thermal_gap 0.5)
				(thermal_bridge_width 0.5)
				(island_removal_mode 0)
			)
			(polygon
				(pts
					(xy 63.5508 -91.3892) (xy 63.5508 -90.8812) (xy 63.9318 -90.8812) (xy 63.9318 -91.3892)
				)
			)
		)
		(zone
			(layer "B.Cu")
			(hatch none 0.5)
			(connect_pads
				(clearance 0)
			)
			(min_thickness 0.25)
			(keepout
				(tracks not_allowed)
				(vias allowed)
				(pads allowed)
				(copperpour not_allowed)
				(footprints allowed)
			)
			(placement
				(enabled no)
				(sheetname "")
			)
			(fill
				(thermal_gap 0.5)
				(thermal_bridge_width 0.5)
				(island_removal_mode 0)
			)
			(polygon
				(pts
					(xy 63.9318 -91.3892) (xy 63.9318 -90.8812) (xy 63.5508 -90.8812) (xy 63.5508 -91.3892)
				)
			)
		)
	)
	(footprint ""
		(layer "B.Cu")
		(at 86.436708 -125.99162 90)
		(property "Reference" "R7L2"
			(at 0 0 90)
			(layer "B.SilkS")
			(hide yes)
			(effects
				(font
					(size 1.27 1.27)
				)
				(justify mirror)
			)
		)
		(property "Value" ""
			(at 0 0 90)
			(layer "B.Fab")
			(effects
				(font
					(size 1.27 1.27)
				)
				(justify mirror)
			)
		)
		(duplicate_pad_numbers_are_jumpers no)
		(fp_poly
			(pts
				(xy 0.2794 -0.1016) (xy -0.2794 -0.1016) (xy -0.2794 0.9906) (xy 0.2794 0.9906)
			)
			(stroke
				(width 0)
				(type default)
			)
			(fill no)
			(layer "B.CrtYd")
		)
		(fp_line
			(start 0.2794 -0.1016)
			(end 0.2794 0.9906)
			(stroke
				(width 0.1)
				(type default)
			)
			(layer "B.Fab")
		)
		(fp_line
			(start -0.2794 -0.1016)
			(end 0.2794 -0.1016)
			(stroke
				(width 0.1)
				(type default)
			)
			(layer "B.Fab")
		)
		(fp_line
			(start 0.2794 0.9906)
			(end -0.2794 0.9906)
			(stroke
				(width 0.1)
				(type default)
			)
			(layer "B.Fab")
		)
		(fp_line
			(start -0.2794 0.9906)
			(end -0.2794 -0.1016)
			(stroke
				(width 0.1)
				(type default)
			)
			(layer "B.Fab")
		)
		(pad "1" smd rect
			(at 0 0 270)
			(size 0.508 0.508)
			(layers "B.Cu" "B.Mask" "B.Paste")
			(net "VSENSE_PVDDQ_KLM_P")
		)
		(pad "2" smd rect
			(at 0 0.889 270)
			(size 0.508 0.508)
			(layers "B.Cu" "B.Mask" "B.Paste")
			(net "VSENSE_PVDDQ_KLM_N")
		)
		(zone
			(layer "B.Cu")
			(hatch none 0.5)
			(connect_pads
				(clearance 0)
			)
			(min_thickness 0.25)
			(keepout
				(tracks allowed)
				(vias not_allowed)
				(pads allowed)
				(copperpour not_allowed)
				(footprints allowed)
			)
			(placement
				(enabled no)
				(sheetname "")
			)
			(fill
				(thermal_gap 0.5)
				(thermal_bridge_width 0.5)
				(island_removal_mode 0)
			)
			(polygon
				(pts
					(xy 86.690708 -126.24562) (xy 86.690708 -125.73762) (xy 87.071708 -125.73762) (xy 87.071708 -126.24562)
				)
			)
		)
		(zone
			(layer "B.Cu")
			(hatch none 0.5)
			(connect_pads
				(clearance 0)
			)
			(min_thickness 0.25)
			(keepout
				(tracks not_allowed)
				(vias allowed)
				(pads allowed)
				(copperpour not_allowed)
				(footprints allowed)
			)
			(placement
				(enabled no)
				(sheetname "")
			)
			(fill
				(thermal_gap 0.5)
				(thermal_bridge_width 0.5)
				(island_removal_mode 0)
			)
			(polygon
				(pts
					(xy 87.071708 -126.24562) (xy 87.071708 -125.73762) (xy 86.690708 -125.73762) (xy 86.690708 -126.24562)
				)
			)
		)
	)
	(footprint ""
		(layer "B.Cu")
		(at 395.478 -29.845 -90)
		(property "Reference" "R2T22"
			(at 0 0 90)
			(layer "B.SilkS")
			(hide yes)
			(effects
				(font
					(size 1.27 1.27)
				)
				(justify mirror)
			)
		)
		(property "Value" ""
			(at 0 0 90)
			(layer "B.Fab")
			(effects
				(font
					(size 1.27 1.27)
				)
				(justify mirror)
			)
		)
		(duplicate_pad_numbers_are_jumpers no)
		(fp_poly
			(pts
				(xy 0.2794 -0.1016) (xy -0.2794 -0.1016) (xy -0.2794 0.9906) (xy 0.2794 0.9906)
			)
			(stroke
				(width 0)
				(type default)
			)
			(fill no)
			(layer "B.CrtYd")
		)
		(fp_line
			(start -0.2794 0.9906)
			(end -0.2794 -0.1016)
			(stroke
				(width 0.1)
				(type default)
			)
			(layer "B.Fab")
		)
		(fp_line
			(start 0.2794 0.9906)
			(end -0.2794 0.9906)
			(stroke
				(width 0.1)
				(type default)
			)
			(layer "B.Fab")
		)
		(fp_line
			(start -0.2794 -0.1016)
			(end 0.2794 -0.1016)
			(stroke
				(width 0.1)
				(type default)
			)
			(layer "B.Fab")
		)
		(fp_line
			(start 0.2794 -0.1016)
			(end 0.2794 0.9906)
			(stroke
				(width 0.1)
				(type default)
			)
			(layer "B.Fab")
		)
		(pad "1" smd rect
			(at 0 0 90)
			(size 0.508 0.508)
			(layers "B.Cu" "B.Mask" "B.Paste")
			(net "P3V3_STBY")
		)
		(pad "2" smd rect
			(at 0 0.889 90)
			(size 0.508 0.508)
			(layers "B.Cu" "B.Mask" "B.Paste")
			(net "RST_BMC_SYSRST_BTN_OUT_B_R_N")
		)
	)
	(footprint ""
		(layer "B.Cu")
		(at 295.8846 -68.154804)
		(property "Reference" "R4P18"
			(at 0 0 0)
			(layer "B.SilkS")
			(hide yes)
			(effects
				(font
					(size 1.27 1.27)
				)
				(justify mirror)
			)
		)
		(property "Value" ""
			(at 0 0 0)
			(layer "B.Fab")
			(effects
				(font
					(size 1.27 1.27)
				)
				(justify mirror)
			)
		)
		(duplicate_pad_numbers_are_jumpers no)
		(fp_poly
			(pts
				(xy 0.2794 -0.1016) (xy -0.2794 -0.1016) (xy -0.2794 0.9906) (xy 0.2794 0.9906)
			)
			(stroke
				(width 0)
				(type default)
			)
			(fill no)
			(layer "B.CrtYd")
		)
		(fp_line
			(start -0.2794 -0.1016)
			(end 0.2794 -0.1016)
			(stroke
				(width 0.1)
				(type default)
			)
			(layer "B.Fab")
		)
		(fp_line
			(start -0.2794 0.9906)
			(end -0.2794 -0.1016)
			(stroke
				(width 0.1)
				(type default)
			)
			(layer "B.Fab")
		)
		(fp_line
			(start 0.2794 -0.1016)
			(end 0.2794 0.9906)
			(stroke
				(width 0.1)
				(type default)
			)
			(layer "B.Fab")
		)
		(fp_line
			(start 0.2794 0.9906)
			(end -0.2794 0.9906)
			(stroke
				(width 0.1)
				(type default)
			)
			(layer "B.Fab")
		)
		(pad "1" smd rect
			(at 0 0 180)
			(size 0.508 0.508)
			(layers "B.Cu" "B.Mask" "B.Paste")
			(net "H_PM_SYNC_GTL_R1")
		)
		(pad "2" smd rect
			(at 0 0.889 180)
			(size 0.508 0.508)
			(layers "B.Cu" "B.Mask" "B.Paste")
			(net "H_PM_SYNC_GTL")
		)
		(zone
			(layer "B.Cu")
			(hatch none 0.5)
			(connect_pads
				(clearance 0)
			)
			(min_thickness 0.25)
			(keepout
				(tracks allowed)
				(vias not_allowed)
				(pads allowed)
				(copperpour not_allowed)
				(footprints allowed)
			)
			(placement
				(enabled no)
				(sheetname "")
			)
			(fill
				(thermal_gap 0.5)
				(thermal_bridge_width 0.5)
				(island_removal_mode 0)
			)
			(polygon
				(pts
					(xy 296.1386 -67.900804) (xy 295.6306 -67.900804) (xy 295.6306 -67.519804) (xy 296.1386 -67.519804)
				)
			)
		)
		(zone
			(layer "B.Cu")
			(hatch none 0.5)
			(connect_pads
				(clearance 0)
			)
			(min_thickness 0.25)
			(keepout
				(tracks not_allowed)
				(vias allowed)
				(pads allowed)
				(copperpour not_allowed)
				(footprints allowed)
			)
			(placement
				(enabled no)
				(sheetname "")
			)
			(fill
				(thermal_gap 0.5)
				(thermal_bridge_width 0.5)
				(island_removal_mode 0)
			)
			(polygon
				(pts
					(xy 296.1386 -67.519804) (xy 295.6306 -67.519804) (xy 295.6306 -67.900804) (xy 296.1386 -67.900804)
				)
			)
		)
	)
	(footprint ""
		(layer "B.Cu")
		(at 479.9711 -39.5224 90)
		(property "Reference" "C1R19"
			(at 0 0 90)
			(layer "B.SilkS")
			(hide yes)
			(effects
				(font
					(size 1.27 1.27)
				)
				(justify mirror)
			)
		)
		(property "Value" ""
			(at 0 0 90)
			(layer "B.Fab")
			(effects
				(font
					(size 1.27 1.27)
				)
				(justify mirror)
			)
		)
		(duplicate_pad_numbers_are_jumpers no)
		(fp_poly
			(pts
				(xy -0.3048 -0.1016) (xy -0.3048 0.9906) (xy 0.3048 0.9906) (xy 0.3048 -0.1016)
			)
			(stroke
				(width 0)
				(type default)
			)
			(fill no)
			(layer "B.CrtYd")
		)
		(fp_line
			(start 0.3048 -0.1016)
			(end 0.3048 0.9906)
			(stroke
				(width 0.1)
				(type default)
			)
			(layer "B.Fab")
		)
		(fp_line
			(start -0.3048 -0.1016)
			(end 0.3048 -0.1016)
			(stroke
				(width 0.1)
				(type default)
			)
			(layer "B.Fab")
		)
		(fp_line
			(start 0.3048 0.9906)
			(end -0.3048 0.9906)
			(stroke
				(width 0.1)
				(type default)
			)
			(layer "B.Fab")
		)
		(fp_line
			(start -0.3048 0.9906)
			(end -0.3048 -0.1016)
			(stroke
				(width 0.1)
				(type default)
			)
			(layer "B.Fab")
		)
		(pad "1" smd rect
			(at 0 0 270)
			(size 0.508 0.508)
			(layers "B.Cu" "B.Mask" "B.Paste")
			(net "P1V5_LAN")
		)
		(pad "2" smd rect
			(at 0 0.889 270)
			(size 0.508 0.508)
			(layers "B.Cu" "B.Mask" "B.Paste")
			(net "GND")
		)
		(zone
			(layer "B.Cu")
			(hatch none 0.5)
			(connect_pads
				(clearance 0)
			)
			(min_thickness 0.25)
			(keepout
				(tracks allowed)
				(vias not_allowed)
				(pads allowed)
				(copperpour not_allowed)
				(footprints allowed)
			)
			(placement
				(enabled no)
				(sheetname "")
			)
			(fill
				(thermal_gap 0.5)
				(thermal_bridge_width 0.5)
				(island_removal_mode 0)
			)
			(polygon
				(pts
					(xy 480.2251 -39.7764) (xy 480.2251 -39.2684) (xy 480.6061 -39.2684) (xy 480.6061 -39.7764)
				)
			)
		)
		(zone
			(layer "B.Cu")
			(hatch none 0.5)
			(connect_pads
				(clearance 0)
			)
			(min_thickness 0.25)
			(keepout
				(tracks not_allowed)
				(vias allowed)
				(pads allowed)
				(copperpour not_allowed)
				(footprints allowed)
			)
			(placement
				(enabled no)
				(sheetname "")
			)
			(fill
				(thermal_gap 0.5)
				(thermal_bridge_width 0.5)
				(island_removal_mode 0)
			)
			(polygon
				(pts
					(xy 480.6061 -39.7764) (xy 480.6061 -39.2684) (xy 480.2251 -39.2684) (xy 480.2251 -39.7764)
				)
			)
		)
	)
	(footprint ""
		(layer "B.Cu")
		(at 260.377686 -77.82814)
		(property "Reference" "C5P26"
			(at 0 0 0)
			(layer "B.SilkS")
			(hide yes)
			(effects
				(font
					(size 1.27 1.27)
				)
				(justify mirror)
			)
		)
		(property "Value" ""
			(at 0 0 0)
			(layer "B.Fab")
			(effects
				(font
					(size 1.27 1.27)
				)
				(justify mirror)
			)
		)
		(duplicate_pad_numbers_are_jumpers no)
		(fp_poly
			(pts
				(xy 0.7239 -0.2159) (xy -0.7239 -0.2159) (xy -0.7239 1.9939) (xy 0.7239 1.9939)
			)
			(stroke
				(width 0)
				(type default)
			)
			(fill no)
			(layer "B.CrtYd")
		)
		(fp_line
			(start -0.7239 -0.2159)
			(end 0.7239 -0.2159)
			(stroke
				(width 0.1)
				(type default)
			)
			(layer "B.Fab")
		)
		(fp_line
			(start -0.7239 1.9939)
			(end -0.7239 -0.2159)
			(stroke
				(width 0.1)
				(type default)
			)
			(layer "B.Fab")
		)
		(fp_line
			(start 0.7239 -0.2159)
			(end 0.7239 1.9939)
			(stroke
				(width 0.1)
				(type default)
			)
			(layer "B.Fab")
		)
		(fp_line
			(start 0.7239 1.9939)
			(end -0.7239 1.9939)
			(stroke
				(width 0.1)
				(type default)
			)
			(layer "B.Fab")
		)
		(pad "1" smd rect
			(at 0 0 180)
			(size 1.27 1.016)
			(layers "B.Cu" "B.Mask" "B.Paste")
			(net "PVCCIN_CPU0")
		)
		(pad "2" smd rect
			(at 0 1.778 180)
			(size 1.27 1.016)
			(layers "B.Cu" "B.Mask" "B.Paste")
			(net "GND")
		)
		(zone
			(layer "B.Cu")
			(hatch none 0.5)
			(connect_pads
				(clearance 0)
			)
			(min_thickness 0.25)
			(keepout
				(tracks not_allowed)
				(vias allowed)
				(pads allowed)
				(copperpour not_allowed)
				(footprints allowed)
			)
			(placement
				(enabled no)
				(sheetname "")
			)
			(fill
				(thermal_gap 0.5)
				(thermal_bridge_width 0.5)
				(island_removal_mode 0)
			)
			(polygon
				(pts
					(xy 261.012686 -77.32014) (xy 259.742686 -77.32014) (xy 259.742686 -76.55814) (xy 261.012686 -76.55814)
				)
			)
		)
	)
	(footprint ""
		(layer "B.Cu")
		(at 248.8565 -140.208 -90)
		(property "Reference" "C5G65"
			(at -1.14681 0.76708 0)
			(unlocked yes)
			(layer "B.SilkS")
			(effects
				(font
					(size 0.7874 0.5842)
					(thickness 0.1524)
				)
				(justify mirror)
			)
		)
		(property "Value" ""
			(at 0 0 90)
			(layer "B.Fab")
			(effects
				(font
					(size 1.27 1.27)
				)
				(justify mirror)
			)
		)
		(duplicate_pad_numbers_are_jumpers no)
		(fp_rect
			(start 0.4953 1.6002)
			(end -0.4953 -0.2032)
			(stroke
				(width 0)
				(type default)
			)
			(fill no)
			(layer "B.CrtYd")
		)
		(fp_line
			(start -0.4953 1.6002)
			(end 0.4953 1.6002)
			(stroke
				(width 0.1)
				(type default)
			)
			(layer "B.Fab")
		)
		(fp_line
			(start 0.4953 1.6002)
			(end 0.4953 -0.2032)
			(stroke
				(width 0.1)
				(type default)
			)
			(layer "B.Fab")
		)
		(fp_line
			(start -0.4953 -0.2032)
			(end -0.4953 1.6002)
			(stroke
				(width 0.1)
				(type default)
			)
			(layer "B.Fab")
		)
		(fp_line
			(start 0.4953 -0.2032)
			(end -0.4953 -0.2032)
			(stroke
				(width 0.1)
				(type default)
			)
			(layer "B.Fab")
		)
		(pad "1" smd rect
			(at 0 0 90)
			(size 0.762 0.889)
			(layers "B.Cu" "B.Mask" "B.Paste")
			(net "PVDDQ_DEF")
		)
		(pad "2" smd rect
			(at 0 1.397 90)
			(size 0.762 0.889)
			(layers "B.Cu" "B.Mask" "B.Paste")
			(net "GND")
		)
		(zone
			(layer "B.Cu")
			(hatch none 0.5)
			(connect_pads
				(clearance 0)
			)
			(min_thickness 0.25)
			(keepout
				(tracks not_allowed)
				(vias allowed)
				(pads allowed)
				(copperpour not_allowed)
				(footprints allowed)
			)
			(placement
				(enabled no)
				(sheetname "")
			)
			(fill
				(thermal_gap 0.5)
				(thermal_bridge_width 0.5)
				(island_removal_mode 0)
			)
			(polygon
				(pts
					(xy 247.904 -139.827) (xy 248.412 -139.827) (xy 248.412 -140.589) (xy 247.904 -140.589)
				)
			)
		)
	)
	(footprint ""
		(layer "B.Cu")
		(at 477.84766 -27.70632 180)
		(property "Reference" "R2T25"
			(at 0 0 0)
			(layer "B.SilkS")
			(hide yes)
			(effects
				(font
					(size 1.27 1.27)
				)
				(justify mirror)
			)
		)
		(property "Value" ""
			(at 0 0 0)
			(layer "B.Fab")
			(effects
				(font
					(size 1.27 1.27)
				)
				(justify mirror)
			)
		)
		(duplicate_pad_numbers_are_jumpers no)
		(fp_poly
			(pts
				(xy 0.2794 -0.1016) (xy -0.2794 -0.1016) (xy -0.2794 0.9906) (xy 0.2794 0.9906)
			)
			(stroke
				(width 0)
				(type default)
			)
			(fill no)
			(layer "B.CrtYd")
		)
		(fp_line
			(start 0.2794 0.9906)
			(end -0.2794 0.9906)
			(stroke
				(width 0.1)
				(type default)
			)
			(layer "B.Fab")
		)
		(fp_line
			(start 0.2794 -0.1016)
			(end 0.2794 0.9906)
			(stroke
				(width 0.1)
				(type default)
			)
			(layer "B.Fab")
		)
		(fp_line
			(start -0.2794 0.9906)
			(end -0.2794 -0.1016)
			(stroke
				(width 0.1)
				(type default)
			)
			(layer "B.Fab")
		)
		(fp_line
			(start -0.2794 -0.1016)
			(end 0.2794 -0.1016)
			(stroke
				(width 0.1)
				(type default)
			)
			(layer "B.Fab")
		)
		(pad "1" smd rect
			(at 0 0)
			(size 0.508 0.508)
			(layers "B.Cu" "B.Mask" "B.Paste")
			(net "PD_CKMNG_OE")
		)
		(pad "2" smd rect
			(at 0 0.889)
			(size 0.508 0.508)
			(layers "B.Cu" "B.Mask" "B.Paste")
			(net "GND")
		)
		(zone
			(layer "B.Cu")
			(hatch none 0.5)
			(connect_pads
				(clearance 0)
			)
			(min_thickness 0.25)
			(keepout
				(tracks not_allowed)
				(vias allowed)
				(pads allowed)
				(copperpour not_allowed)
				(footprints allowed)
			)
			(placement
				(enabled no)
				(sheetname "")
			)
			(fill
				(thermal_gap 0.5)
				(thermal_bridge_width 0.5)
				(island_removal_mode 0)
			)
			(polygon
				(pts
					(xy 477.59366 -28.34132) (xy 478.10166 -28.34132) (xy 478.10166 -27.96032) (xy 477.59366 -27.96032)
				)
			)
		)
		(zone
			(layer "B.Cu")
			(hatch none 0.5)
			(connect_pads
				(clearance 0)
			)
			(min_thickness 0.25)
			(keepout
				(tracks allowed)
				(vias not_allowed)
				(pads allowed)
				(copperpour not_allowed)
				(footprints allowed)
			)
			(placement
				(enabled no)
				(sheetname "")
			)
			(fill
				(thermal_gap 0.5)
				(thermal_bridge_width 0.5)
				(island_removal_mode 0)
			)
			(polygon
				(pts
					(xy 477.59366 -27.96032) (xy 478.10166 -27.96032) (xy 478.10166 -28.34132) (xy 477.59366 -28.34132)
				)
			)
		)
	)
	(footprint ""
		(layer "B.Cu")
		(at 414.743646 -35.658552)
		(property "Reference" "C25W30"
			(at -0.97536 0.76708 90)
			(unlocked yes)
			(layer "B.SilkS")
			(effects
				(font
					(size 0.4064 0.254)
					(thickness 0.1524)
				)
				(justify mirror)
			)
		)
		(property "Value" ""
			(at 0 0 0)
			(layer "B.Fab")
			(effects
				(font
					(size 1.27 1.27)
				)
				(justify mirror)
			)
		)
		(duplicate_pad_numbers_are_jumpers no)
		(fp_poly
			(pts
				(xy 0.4953 -0.2032) (xy -0.4953 -0.2032) (xy -0.4953 1.6002) (xy 0.4953 1.6002)
			)
			(stroke
				(width 0)
				(type default)
			)
			(fill no)
			(layer "B.CrtYd")
		)
		(fp_line
			(start -0.4953 -0.2032)
			(end -0.4953 1.6002)
			(stroke
				(width 0.1)
				(type default)
			)
			(layer "B.Fab")
		)
		(fp_line
			(start -0.4953 1.6002)
			(end 0.4953 1.6002)
			(stroke
				(width 0.1)
				(type default)
			)
			(layer "B.Fab")
		)
		(fp_line
			(start 0.4953 -0.2032)
			(end -0.4953 -0.2032)
			(stroke
				(width 0.1)
				(type default)
			)
			(layer "B.Fab")
		)
		(fp_line
			(start 0.4953 1.6002)
			(end 0.4953 -0.2032)
			(stroke
				(width 0.1)
				(type default)
			)
			(layer "B.Fab")
		)
		(pad "1" smd rect
			(at 0 0 180)
			(size 0.762 0.889)
			(layers "B.Cu" "B.Mask" "B.Paste")
			(net "P1V15_AUX_BMC")
		)
		(pad "2" smd rect
			(at 0 1.397 180)
			(size 0.762 0.889)
			(layers "B.Cu" "B.Mask" "B.Paste")
			(net "GND")
		)
		(zone
			(layer "B.Cu")
			(hatch none 0.5)
			(connect_pads
				(clearance 0)
			)
			(min_thickness 0.25)
			(keepout
				(tracks not_allowed)
				(vias allowed)
				(pads allowed)
				(copperpour not_allowed)
				(footprints allowed)
			)
			(placement
				(enabled no)
				(sheetname "")
			)
			(fill
				(thermal_gap 0.5)
				(thermal_bridge_width 0.5)
				(island_removal_mode 0)
			)
			(polygon
				(pts
					(xy 415.124646 -35.214052) (xy 414.362646 -35.214052) (xy 414.362646 -34.706052) (xy 415.124646 -34.706052)
				)
			)
		)
	)
	(footprint ""
		(layer "B.Cu")
		(at 496.05438 -128.15062)
		(property "Reference" "C1M3"
			(at 0 0 0)
			(layer "B.SilkS")
			(hide yes)
			(effects
				(font
					(size 1.27 1.27)
				)
				(justify mirror)
			)
		)
		(property "Value" ""
			(at 0 0 0)
			(layer "B.Fab")
			(effects
				(font
					(size 1.27 1.27)
				)
				(justify mirror)
			)
		)
		(duplicate_pad_numbers_are_jumpers no)
		(fp_poly
			(pts
				(xy -0.3048 -0.1016) (xy -0.3048 0.9906) (xy 0.3048 0.9906) (xy 0.3048 -0.1016)
			)
			(stroke
				(width 0)
				(type default)
			)
			(fill no)
			(layer "B.CrtYd")
		)
		(fp_line
			(start -0.3048 -0.1016)
			(end 0.3048 -0.1016)
			(stroke
				(width 0.1)
				(type default)
			)
			(layer "B.Fab")
		)
		(fp_line
			(start -0.3048 0.9906)
			(end -0.3048 -0.1016)
			(stroke
				(width 0.1)
				(type default)
			)
			(layer "B.Fab")
		)
		(fp_line
			(start 0.3048 -0.1016)
			(end 0.3048 0.9906)
			(stroke
				(width 0.1)
				(type default)
			)
			(layer "B.Fab")
		)
		(fp_line
			(start 0.3048 0.9906)
			(end -0.3048 0.9906)
			(stroke
				(width 0.1)
				(type default)
			)
			(layer "B.Fab")
		)
		(pad "1" smd rect
			(at 0 0 180)
			(size 0.508 0.508)
			(layers "B.Cu" "B.Mask" "B.Paste")
			(net "P3V3")
		)
		(pad "2" smd rect
			(at 0 0.889 180)
			(size 0.508 0.508)
			(layers "B.Cu" "B.Mask" "B.Paste")
			(net "GND")
		)
		(zone
			(layer "B.Cu")
			(hatch none 0.5)
			(connect_pads
				(clearance 0)
			)
			(min_thickness 0.25)
			(keepout
				(tracks allowed)
				(vias not_allowed)
				(pads allowed)
				(copperpour not_allowed)
				(footprints allowed)
			)
			(placement
				(enabled no)
				(sheetname "")
			)
			(fill
				(thermal_gap 0.5)
				(thermal_bridge_width 0.5)
				(island_removal_mode 0)
			)
			(polygon
				(pts
					(xy 496.30838 -127.89662) (xy 495.80038 -127.89662) (xy 495.80038 -127.51562) (xy 496.30838 -127.51562)
				)
			)
		)
		(zone
			(layer "B.Cu")
			(hatch none 0.5)
			(connect_pads
				(clearance 0)
			)
			(min_thickness 0.25)
			(keepout
				(tracks not_allowed)
				(vias allowed)
				(pads allowed)
				(copperpour not_allowed)
				(footprints allowed)
			)
			(placement
				(enabled no)
				(sheetname "")
			)
			(fill
				(thermal_gap 0.5)
				(thermal_bridge_width 0.5)
				(island_removal_mode 0)
			)
			(polygon
				(pts
					(xy 496.30838 -127.51562) (xy 495.80038 -127.51562) (xy 495.80038 -127.89662) (xy 496.30838 -127.89662)
				)
			)
		)
	)
	(footprint ""
		(layer "B.Cu")
		(at 471.6653 -124.079 180)
		(property "Reference" "L1M2"
			(at -0.127 -1.07188 180)
			(unlocked yes)
			(layer "B.SilkS")
			(effects
				(font
					(size 0.4064 0.254)
					(thickness 0.1524)
				)
				(justify left mirror)
			)
		)
		(property "Value" ""
			(at 0 0 0)
			(layer "B.Fab")
			(effects
				(font
					(size 1.27 1.27)
				)
				(justify mirror)
			)
		)
		(duplicate_pad_numbers_are_jumpers no)
		(fp_rect
			(start 0.08382 1.09982)
			(end -2.11582 -0.29972)
			(stroke
				(width 0)
				(type default)
			)
			(fill no)
			(layer "B.CrtYd")
		)
		(fp_line
			(start 0.08382 1.09982)
			(end 0.08382 -0.29972)
			(stroke
				(width 0.1)
				(type default)
			)
			(layer "B.Fab")
		)
		(fp_line
			(start 0.08382 -0.29972)
			(end -2.11582 -0.29972)
			(stroke
				(width 0.1)
				(type default)
			)
			(layer "B.Fab")
		)
		(fp_line
			(start -2.11582 1.09982)
			(end 0.08382 1.09982)
			(stroke
				(width 0.1)
				(type default)
			)
			(layer "B.Fab")
		)
		(fp_line
			(start -2.11582 -0.29972)
			(end -2.11582 1.09982)
			(stroke
				(width 0.1)
				(type default)
			)
			(layer "B.Fab")
		)
		(pad "1" smd rect
			(at 0 0)
			(size 1.27 0.508)
			(layers "B.Cu" "B.Mask" "B.Paste")
			(net "USB2_P01_DN")
		)
		(pad "2" smd rect
			(at 0 0.8001)
			(size 1.27 0.508)
			(layers "B.Cu" "B.Mask" "B.Paste")
			(net "USB2_P01_DP")
		)
		(pad "3" smd rect
			(at -2.032 0.8001)
			(size 1.27 0.508)
			(layers "B.Cu" "B.Mask" "B.Paste")
			(net "USB2_P01_ESD_DP")
		)
		(pad "4" smd rect
			(at -2.032 0)
			(size 1.27 0.508)
			(layers "B.Cu" "B.Mask" "B.Paste")
			(net "USB2_P01_ESD_DN")
		)
		(zone
			(layer "B.Cu")
			(hatch none 0.5)
			(connect_pads
				(clearance 0)
			)
			(min_thickness 0.25)
			(keepout
				(tracks not_allowed)
				(vias allowed)
				(pads allowed)
				(copperpour not_allowed)
				(footprints allowed)
			)
			(placement
				(enabled no)
				(sheetname "")
			)
			(fill
				(thermal_gap 0.5)
				(thermal_bridge_width 0.5)
				(island_removal_mode 0)
			)
			(polygon
				(pts
					(xy 471.0303 -124.6251) (xy 471.0303 -124.333) (xy 472.3003 -124.333) (xy 472.3003 -124.6251)
				)
			)
		)
		(zone
			(layer "B.Cu")
			(hatch none 0.5)
			(connect_pads
				(clearance 0)
			)
			(min_thickness 0.25)
			(keepout
				(tracks not_allowed)
				(vias allowed)
				(pads allowed)
				(copperpour not_allowed)
				(footprints allowed)
			)
			(placement
				(enabled no)
				(sheetname "")
			)
			(fill
				(thermal_gap 0.5)
				(thermal_bridge_width 0.5)
				(island_removal_mode 0)
			)
			(polygon
				(pts
					(xy 472.3003 -125.1331) (xy 473.0623 -125.1331) (xy 473.0623 -123.825) (xy 472.3003 -123.825)
				)
			)
		)
		(zone
			(layer "B.Cu")
			(hatch none 0.5)
			(connect_pads
				(clearance 0)
			)
			(min_thickness 0.25)
			(keepout
				(tracks allowed)
				(vias not_allowed)
				(pads allowed)
				(copperpour not_allowed)
				(footprints allowed)
			)
			(placement
				(enabled no)
				(sheetname "")
			)
			(fill
				(thermal_gap 0.5)
				(thermal_bridge_width 0.5)
				(island_removal_mode 0)
			)
			(polygon
				(pts
					(xy 472.3003 -123.825) (xy 472.3003 -125.1331) (xy 473.0623 -125.1331) (xy 473.0623 -123.825)
				)
			)
		)
		(zone
			(layer "B.Cu")
			(hatch none 0.5)
			(connect_pads
				(clearance 0)
			)
			(min_thickness 0.25)
			(keepout
				(tracks not_allowed)
				(vias allowed)
				(pads allowed)
				(copperpour not_allowed)
				(footprints allowed)
			)
			(placement
				(enabled no)
				(sheetname "")
			)
			(fill
				(thermal_gap 0.5)
				(thermal_bridge_width 0.5)
				(island_removal_mode 0)
			)
			(polygon
				(pts
					(xy 473.0623 -124.6251) (xy 473.0623 -124.333) (xy 474.3323 -124.333) (xy 474.3323 -124.6251)
				)
			)
		)
	)
	(footprint ""
		(layer "B.Cu")
		(at 377.589288 -110.817914)
		(property "Reference" "R3N1"
			(at 0 0 0)
			(layer "B.SilkS")
			(hide yes)
			(effects
				(font
					(size 1.27 1.27)
				)
				(justify mirror)
			)
		)
		(property "Value" ""
			(at 0 0 0)
			(layer "B.Fab")
			(effects
				(font
					(size 1.27 1.27)
				)
				(justify mirror)
			)
		)
		(duplicate_pad_numbers_are_jumpers no)
		(fp_poly
			(pts
				(xy 0.2794 -0.1016) (xy -0.2794 -0.1016) (xy -0.2794 0.9906) (xy 0.2794 0.9906)
			)
			(stroke
				(width 0)
				(type default)
			)
			(fill no)
			(layer "B.CrtYd")
		)
		(fp_line
			(start -0.2794 -0.1016)
			(end 0.2794 -0.1016)
			(stroke
				(width 0.1)
				(type default)
			)
			(layer "B.Fab")
		)
		(fp_line
			(start -0.2794 0.9906)
			(end -0.2794 -0.1016)
			(stroke
				(width 0.1)
				(type default)
			)
			(layer "B.Fab")
		)
		(fp_line
			(start 0.2794 -0.1016)
			(end 0.2794 0.9906)
			(stroke
				(width 0.1)
				(type default)
			)
			(layer "B.Fab")
		)
		(fp_line
			(start 0.2794 0.9906)
			(end -0.2794 0.9906)
			(stroke
				(width 0.1)
				(type default)
			)
			(layer "B.Fab")
		)
		(pad "1" smd rect
			(at 0 0 180)
			(size 0.508 0.508)
			(layers "B.Cu" "B.Mask" "B.Paste")
			(net "A_PCH_XCLK_BIASREF")
		)
		(pad "2" smd rect
			(at 0 0.889 180)
			(size 0.508 0.508)
			(layers "B.Cu" "B.Mask" "B.Paste")
			(net "GND")
		)
		(zone
			(layer "B.Cu")
			(hatch none 0.5)
			(connect_pads
				(clearance 0)
			)
			(min_thickness 0.25)
			(keepout
				(tracks allowed)
				(vias not_allowed)
				(pads allowed)
				(copperpour not_allowed)
				(footprints allowed)
			)
			(placement
				(enabled no)
				(sheetname "")
			)
			(fill
				(thermal_gap 0.5)
				(thermal_bridge_width 0.5)
				(island_removal_mode 0)
			)
			(polygon
				(pts
					(xy 377.843288 -110.563914) (xy 377.335288 -110.563914) (xy 377.335288 -110.182914) (xy 377.843288 -110.182914)
				)
			)
		)
		(zone
			(layer "B.Cu")
			(hatch none 0.5)
			(connect_pads
				(clearance 0)
			)
			(min_thickness 0.25)
			(keepout
				(tracks not_allowed)
				(vias allowed)
				(pads allowed)
				(copperpour not_allowed)
				(footprints allowed)
			)
			(placement
				(enabled no)
				(sheetname "")
			)
			(fill
				(thermal_gap 0.5)
				(thermal_bridge_width 0.5)
				(island_removal_mode 0)
			)
			(polygon
				(pts
					(xy 377.843288 -110.182914) (xy 377.335288 -110.182914) (xy 377.335288 -110.563914) (xy 377.843288 -110.563914)
				)
			)
		)
	)
	(footprint ""
		(layer "B.Cu")
		(at 409.702 2.722372)
		(property "Reference" "R2U42"
			(at 0 0 0)
			(layer "B.SilkS")
			(hide yes)
			(effects
				(font
					(size 1.27 1.27)
				)
				(justify mirror)
			)
		)
		(property "Value" ""
			(at 0 0 0)
			(layer "B.Fab")
			(effects
				(font
					(size 1.27 1.27)
				)
				(justify mirror)
			)
		)
		(duplicate_pad_numbers_are_jumpers no)
		(fp_poly
			(pts
				(xy 0.2794 -0.1016) (xy -0.2794 -0.1016) (xy -0.2794 0.9906) (xy 0.2794 0.9906)
			)
			(stroke
				(width 0)
				(type default)
			)
			(fill no)
			(layer "B.CrtYd")
		)
		(fp_line
			(start -0.2794 -0.1016)
			(end 0.2794 -0.1016)
			(stroke
				(width 0.1)
				(type default)
			)
			(layer "B.Fab")
		)
		(fp_line
			(start -0.2794 0.9906)
			(end -0.2794 -0.1016)
			(stroke
				(width 0.1)
				(type default)
			)
			(layer "B.Fab")
		)
		(fp_line
			(start 0.2794 -0.1016)
			(end 0.2794 0.9906)
			(stroke
				(width 0.1)
				(type default)
			)
			(layer "B.Fab")
		)
		(fp_line
			(start 0.2794 0.9906)
			(end -0.2794 0.9906)
			(stroke
				(width 0.1)
				(type default)
			)
			(layer "B.Fab")
		)
		(pad "1" smd rect
			(at 0 0 180)
			(size 0.508 0.508)
			(layers "B.Cu" "B.Mask" "B.Paste")
			(net "FAN_PWM_OUT_SYS0_BUF")
		)
		(pad "2" smd rect
			(at 0 0.889 180)
			(size 0.508 0.508)
			(layers "B.Cu" "B.Mask" "B.Paste")
			(net "FAN_PWM_OUT_SYS0_R")
		)
		(zone
			(layer "B.Cu")
			(hatch none 0.5)
			(connect_pads
				(clearance 0)
			)
			(min_thickness 0.25)
			(keepout
				(tracks allowed)
				(vias not_allowed)
				(pads allowed)
				(copperpour not_allowed)
				(footprints allowed)
			)
			(placement
				(enabled no)
				(sheetname "")
			)
			(fill
				(thermal_gap 0.5)
				(thermal_bridge_width 0.5)
				(island_removal_mode 0)
			)
			(polygon
				(pts
					(xy 409.956 2.976372) (xy 409.448 2.976372) (xy 409.448 3.357372) (xy 409.956 3.357372)
				)
			)
		)
		(zone
			(layer "B.Cu")
			(hatch none 0.5)
			(connect_pads
				(clearance 0)
			)
			(min_thickness 0.25)
			(keepout
				(tracks not_allowed)
				(vias allowed)
				(pads allowed)
				(copperpour not_allowed)
				(footprints allowed)
			)
			(placement
				(enabled no)
				(sheetname "")
			)
			(fill
				(thermal_gap 0.5)
				(thermal_bridge_width 0.5)
				(island_removal_mode 0)
			)
			(polygon
				(pts
					(xy 409.956 3.357372) (xy 409.448 3.357372) (xy 409.448 2.976372) (xy 409.956 2.976372)
				)
			)
		)
	)
	(footprint ""
		(layer "B.Cu")
		(at 357.133398 -77.915516 180)
		(property "Reference" "C3P37"
			(at 0 0 0)
			(layer "B.SilkS")
			(hide yes)
			(effects
				(font
					(size 1.27 1.27)
				)
				(justify mirror)
			)
		)
		(property "Value" ""
			(at 0 0 0)
			(layer "B.Fab")
			(effects
				(font
					(size 1.27 1.27)
				)
				(justify mirror)
			)
		)
		(duplicate_pad_numbers_are_jumpers no)
		(fp_poly
			(pts
				(xy -0.3048 -0.1016) (xy -0.3048 0.9906) (xy 0.3048 0.9906) (xy 0.3048 -0.1016)
			)
			(stroke
				(width 0)
				(type default)
			)
			(fill no)
			(layer "B.CrtYd")
		)
		(fp_line
			(start 0.3048 0.9906)
			(end -0.3048 0.9906)
			(stroke
				(width 0.1)
				(type default)
			)
			(layer "B.Fab")
		)
		(fp_line
			(start 0.3048 -0.1016)
			(end 0.3048 0.9906)
			(stroke
				(width 0.1)
				(type default)
			)
			(layer "B.Fab")
		)
		(fp_line
			(start -0.3048 0.9906)
			(end -0.3048 -0.1016)
			(stroke
				(width 0.1)
				(type default)
			)
			(layer "B.Fab")
		)
		(fp_line
			(start -0.3048 -0.1016)
			(end 0.3048 -0.1016)
			(stroke
				(width 0.1)
				(type default)
			)
			(layer "B.Fab")
		)
		(pad "1" smd rect
			(at 0 0)
			(size 0.508 0.508)
			(layers "B.Cu" "B.Mask" "B.Paste")
			(net "P3E_CPU0_PE1_SS_TXN<6>")
		)
		(pad "2" smd rect
			(at 0 0.889)
			(size 0.508 0.508)
			(layers "B.Cu" "B.Mask" "B.Paste")
			(net "P3E_CPU0_PE1_PCH_TXN<6>")
		)
		(zone
			(layer "B.Cu")
			(hatch none 0.5)
			(connect_pads
				(clearance 0)
			)
			(min_thickness 0.25)
			(keepout
				(tracks not_allowed)
				(vias allowed)
				(pads allowed)
				(copperpour not_allowed)
				(footprints allowed)
			)
			(placement
				(enabled no)
				(sheetname "")
			)
			(fill
				(thermal_gap 0.5)
				(thermal_bridge_width 0.5)
				(island_removal_mode 0)
			)
			(polygon
				(pts
					(xy 356.879398 -78.550516) (xy 357.387398 -78.550516) (xy 357.387398 -78.169516) (xy 356.879398 -78.169516)
				)
			)
		)
		(zone
			(layer "B.Cu")
			(hatch none 0.5)
			(connect_pads
				(clearance 0)
			)
			(min_thickness 0.25)
			(keepout
				(tracks allowed)
				(vias not_allowed)
				(pads allowed)
				(copperpour not_allowed)
				(footprints allowed)
			)
			(placement
				(enabled no)
				(sheetname "")
			)
			(fill
				(thermal_gap 0.5)
				(thermal_bridge_width 0.5)
				(island_removal_mode 0)
			)
			(polygon
				(pts
					(xy 356.879398 -78.169516) (xy 357.387398 -78.169516) (xy 357.387398 -78.550516) (xy 356.879398 -78.550516)
				)
			)
		)
	)
	(footprint ""
		(layer "B.Cu")
		(at 352.8949 -73.5838 -90)
		(property "Reference" "R8D43"
			(at 0 0 90)
			(layer "B.SilkS")
			(hide yes)
			(effects
				(font
					(size 1.27 1.27)
				)
				(justify mirror)
			)
		)
		(property "Value" ""
			(at 0 0 90)
			(layer "B.Fab")
			(effects
				(font
					(size 1.27 1.27)
				)
				(justify mirror)
			)
		)
		(duplicate_pad_numbers_are_jumpers no)
		(fp_poly
			(pts
				(xy 0.2794 -0.1016) (xy -0.2794 -0.1016) (xy -0.2794 0.9906) (xy 0.2794 0.9906)
			)
			(stroke
				(width 0)
				(type default)
			)
			(fill no)
			(layer "B.CrtYd")
		)
		(fp_line
			(start -0.2794 0.9906)
			(end -0.2794 -0.1016)
			(stroke
				(width 0.1)
				(type default)
			)
			(layer "B.Fab")
		)
		(fp_line
			(start 0.2794 0.9906)
			(end -0.2794 0.9906)
			(stroke
				(width 0.1)
				(type default)
			)
			(layer "B.Fab")
		)
		(fp_line
			(start -0.2794 -0.1016)
			(end 0.2794 -0.1016)
			(stroke
				(width 0.1)
				(type default)
			)
			(layer "B.Fab")
		)
		(fp_line
			(start 0.2794 -0.1016)
			(end 0.2794 0.9906)
			(stroke
				(width 0.1)
				(type default)
			)
			(layer "B.Fab")
		)
		(pad "1" smd rect
			(at 0 0 90)
			(size 0.508 0.508)
			(layers "B.Cu" "B.Mask" "B.Paste")
			(net "FM_156M_CPU0_BRD_OSC_EN")
		)
		(pad "2" smd rect
			(at 0 0.889 90)
			(size 0.508 0.508)
			(layers "B.Cu" "B.Mask" "B.Paste")
			(net "FM_CPU0_STL_BRD_OSC_EN")
		)
		(zone
			(layer "B.Cu")
			(hatch none 0.5)
			(connect_pads
				(clearance 0)
			)
			(min_thickness 0.25)
			(keepout
				(tracks not_allowed)
				(vias allowed)
				(pads allowed)
				(copperpour not_allowed)
				(footprints allowed)
			)
			(placement
				(enabled no)
				(sheetname "")
			)
			(fill
				(thermal_gap 0.5)
				(thermal_bridge_width 0.5)
				(island_removal_mode 0)
			)
			(polygon
				(pts
					(xy 352.2599 -73.3298) (xy 352.2599 -73.8378) (xy 352.6409 -73.8378) (xy 352.6409 -73.3298)
				)
			)
		)
		(zone
			(layer "B.Cu")
			(hatch none 0.5)
			(connect_pads
				(clearance 0)
			)
			(min_thickness 0.25)
			(keepout
				(tracks allowed)
				(vias not_allowed)
				(pads allowed)
				(copperpour not_allowed)
				(footprints allowed)
			)
			(placement
				(enabled no)
				(sheetname "")
			)
			(fill
				(thermal_gap 0.5)
				(thermal_bridge_width 0.5)
				(island_removal_mode 0)
			)
			(polygon
				(pts
					(xy 352.6409 -73.3298) (xy 352.6409 -73.8378) (xy 352.2599 -73.8378) (xy 352.2599 -73.3298)
				)
			)
		)
	)
	(footprint ""
		(layer "B.Cu")
		(at 411.1625 -27.813 90)
		(property "Reference" "C25W66"
			(at 0.8382 -0.67818 90)
			(unlocked yes)
			(layer "B.SilkS")
			(effects
				(font
					(size 0.4064 0.254)
					(thickness 0.1524)
				)
				(justify left mirror)
			)
		)
		(property "Value" ""
			(at 0 0 90)
			(layer "B.Fab")
			(effects
				(font
					(size 1.27 1.27)
				)
				(justify mirror)
			)
		)
		(duplicate_pad_numbers_are_jumpers no)
		(fp_poly
			(pts
				(xy -0.3048 -0.1016) (xy -0.3048 0.9906) (xy 0.3048 0.9906) (xy 0.3048 -0.1016)
			)
			(stroke
				(width 0)
				(type default)
			)
			(fill no)
			(layer "B.CrtYd")
		)
		(fp_line
			(start 0.3048 -0.1016)
			(end 0.3048 0.9906)
			(stroke
				(width 0.1)
				(type default)
			)
			(layer "B.Fab")
		)
		(fp_line
			(start -0.3048 -0.1016)
			(end 0.3048 -0.1016)
			(stroke
				(width 0.1)
				(type default)
			)
			(layer "B.Fab")
		)
		(fp_line
			(start 0.3048 0.9906)
			(end -0.3048 0.9906)
			(stroke
				(width 0.1)
				(type default)
			)
			(layer "B.Fab")
		)
		(fp_line
			(start -0.3048 0.9906)
			(end -0.3048 -0.1016)
			(stroke
				(width 0.1)
				(type default)
			)
			(layer "B.Fab")
		)
		(pad "1" smd rect
			(at 0 0 270)
			(size 0.508 0.508)
			(layers "B.Cu" "B.Mask" "B.Paste")
			(net "VCC_VA_3V3")
		)
		(pad "2" smd rect
			(at 0 0.889 270)
			(size 0.508 0.508)
			(layers "B.Cu" "B.Mask" "B.Paste")
			(net "GND")
		)
		(zone
			(layer "B.Cu")
			(hatch none 0.5)
			(connect_pads
				(clearance 0)
			)
			(min_thickness 0.25)
			(keepout
				(tracks allowed)
				(vias not_allowed)
				(pads allowed)
				(copperpour not_allowed)
				(footprints allowed)
			)
			(placement
				(enabled no)
				(sheetname "")
			)
			(fill
				(thermal_gap 0.5)
				(thermal_bridge_width 0.5)
				(island_removal_mode 0)
			)
			(polygon
				(pts
					(xy 411.4165 -28.067) (xy 411.4165 -27.559) (xy 411.7975 -27.559) (xy 411.7975 -28.067)
				)
			)
		)
		(zone
			(layer "B.Cu")
			(hatch none 0.5)
			(connect_pads
				(clearance 0)
			)
			(min_thickness 0.25)
			(keepout
				(tracks not_allowed)
				(vias allowed)
				(pads allowed)
				(copperpour not_allowed)
				(footprints allowed)
			)
			(placement
				(enabled no)
				(sheetname "")
			)
			(fill
				(thermal_gap 0.5)
				(thermal_bridge_width 0.5)
				(island_removal_mode 0)
			)
			(polygon
				(pts
					(xy 411.7975 -28.067) (xy 411.7975 -27.559) (xy 411.4165 -27.559) (xy 411.4165 -28.067)
				)
			)
		)
	)
	(footprint ""
		(layer "B.Cu")
		(at 314.0964 -31.718758)
		(property "Reference" "WR8D30"
			(at 0.8382 -0.67818 0)
			(unlocked yes)
			(layer "B.SilkS")
			(effects
				(font
					(size 0.4064 0.254)
					(thickness 0.1524)
				)
				(justify left mirror)
			)
		)
		(property "Value" ""
			(at 0 0 0)
			(layer "B.Fab")
			(effects
				(font
					(size 1.27 1.27)
				)
				(justify mirror)
			)
		)
		(duplicate_pad_numbers_are_jumpers no)
		(fp_poly
			(pts
				(xy 0.2794 -0.1016) (xy -0.2794 -0.1016) (xy -0.2794 0.9906) (xy 0.2794 0.9906)
			)
			(stroke
				(width 0)
				(type default)
			)
			(fill no)
			(layer "B.CrtYd")
		)
		(fp_line
			(start -0.2794 -0.1016)
			(end 0.2794 -0.1016)
			(stroke
				(width 0.1)
				(type default)
			)
			(layer "B.Fab")
		)
		(fp_line
			(start -0.2794 0.9906)
			(end -0.2794 -0.1016)
			(stroke
				(width 0.1)
				(type default)
			)
			(layer "B.Fab")
		)
		(fp_line
			(start 0.2794 -0.1016)
			(end 0.2794 0.9906)
			(stroke
				(width 0.1)
				(type default)
			)
			(layer "B.Fab")
		)
		(fp_line
			(start 0.2794 0.9906)
			(end -0.2794 0.9906)
			(stroke
				(width 0.1)
				(type default)
			)
			(layer "B.Fab")
		)
		(pad "1" smd rect
			(at 0 0 180)
			(size 0.508 0.508)
			(layers "B.Cu" "B.Mask" "B.Paste")
			(net "FM_ADR_COMPLETE_CPU1_N")
		)
		(pad "2" smd rect
			(at 0 0.889 180)
			(size 0.508 0.508)
			(layers "B.Cu" "B.Mask" "B.Paste")
			(net "IRQ_DIMM_SAVE_CPU1_R_N")
		)
		(zone
			(layer "B.Cu")
			(hatch none 0.5)
			(connect_pads
				(clearance 0)
			)
			(min_thickness 0.25)
			(keepout
				(tracks allowed)
				(vias not_allowed)
				(pads allowed)
				(copperpour not_allowed)
				(footprints allowed)
			)
			(placement
				(enabled no)
				(sheetname "")
			)
			(fill
				(thermal_gap 0.5)
				(thermal_bridge_width 0.5)
				(island_removal_mode 0)
			)
			(polygon
				(pts
					(xy 314.3504 -31.464758) (xy 313.8424 -31.464758) (xy 313.8424 -31.083758) (xy 314.3504 -31.083758)
				)
			)
		)
		(zone
			(layer "B.Cu")
			(hatch none 0.5)
			(connect_pads
				(clearance 0)
			)
			(min_thickness 0.25)
			(keepout
				(tracks not_allowed)
				(vias allowed)
				(pads allowed)
				(copperpour not_allowed)
				(footprints allowed)
			)
			(placement
				(enabled no)
				(sheetname "")
			)
			(fill
				(thermal_gap 0.5)
				(thermal_bridge_width 0.5)
				(island_removal_mode 0)
			)
			(polygon
				(pts
					(xy 314.3504 -31.083758) (xy 313.8424 -31.083758) (xy 313.8424 -31.464758) (xy 314.3504 -31.464758)
				)
			)
		)
	)
	(footprint ""
		(layer "B.Cu")
		(at 396.875 -87.3252 180)
		(property "Reference" "R8W7"
			(at 0.8382 -0.67818 180)
			(unlocked yes)
			(layer "B.SilkS")
			(effects
				(font
					(size 0.4064 0.254)
					(thickness 0.1524)
				)
				(justify left mirror)
			)
		)
		(property "Value" ""
			(at 0 0 0)
			(layer "B.Fab")
			(effects
				(font
					(size 1.27 1.27)
				)
				(justify mirror)
			)
		)
		(duplicate_pad_numbers_are_jumpers no)
		(fp_poly
			(pts
				(xy 0.2794 -0.1016) (xy -0.2794 -0.1016) (xy -0.2794 0.9906) (xy 0.2794 0.9906)
			)
			(stroke
				(width 0)
				(type default)
			)
			(fill no)
			(layer "B.CrtYd")
		)
		(fp_line
			(start 0.2794 0.9906)
			(end -0.2794 0.9906)
			(stroke
				(width 0.1)
				(type default)
			)
			(layer "B.Fab")
		)
		(fp_line
			(start 0.2794 -0.1016)
			(end 0.2794 0.9906)
			(stroke
				(width 0.1)
				(type default)
			)
			(layer "B.Fab")
		)
		(fp_line
			(start -0.2794 0.9906)
			(end -0.2794 -0.1016)
			(stroke
				(width 0.1)
				(type default)
			)
			(layer "B.Fab")
		)
		(fp_line
			(start -0.2794 -0.1016)
			(end 0.2794 -0.1016)
			(stroke
				(width 0.1)
				(type default)
			)
			(layer "B.Fab")
		)
		(pad "1" smd rect
			(at 0 0)
			(size 0.508 0.508)
			(layers "B.Cu" "B.Mask" "B.Paste")
			(net "P3V3_STBY")
		)
		(pad "2" smd rect
			(at 0 0.889)
			(size 0.508 0.508)
			(layers "B.Cu" "B.Mask" "B.Paste")
			(net "SMB_VR_STBY_LVC3_SCL_R1")
		)
		(zone
			(layer "B.Cu")
			(hatch none 0.5)
			(connect_pads
				(clearance 0)
			)
			(min_thickness 0.25)
			(keepout
				(tracks not_allowed)
				(vias allowed)
				(pads allowed)
				(copperpour not_allowed)
				(footprints allowed)
			)
			(placement
				(enabled no)
				(sheetname "")
			)
			(fill
				(thermal_gap 0.5)
				(thermal_bridge_width 0.5)
				(island_removal_mode 0)
			)
			(polygon
				(pts
					(xy 396.621 -87.9602) (xy 397.129 -87.9602) (xy 397.129 -87.5792) (xy 396.621 -87.5792)
				)
			)
		)
		(zone
			(layer "B.Cu")
			(hatch none 0.5)
			(connect_pads
				(clearance 0)
			)
			(min_thickness 0.25)
			(keepout
				(tracks allowed)
				(vias not_allowed)
				(pads allowed)
				(copperpour not_allowed)
				(footprints allowed)
			)
			(placement
				(enabled no)
				(sheetname "")
			)
			(fill
				(thermal_gap 0.5)
				(thermal_bridge_width 0.5)
				(island_removal_mode 0)
			)
			(polygon
				(pts
					(xy 396.621 -87.5792) (xy 397.129 -87.5792) (xy 397.129 -87.9602) (xy 396.621 -87.9602)
				)
			)
		)
	)
	(footprint ""
		(layer "B.Cu")
		(at 447.928238 -52.407058)
		(property "Reference" "C2R13"
			(at 0 0 0)
			(layer "B.SilkS")
			(hide yes)
			(effects
				(font
					(size 1.27 1.27)
				)
				(justify mirror)
			)
		)
		(property "Value" ""
			(at 0 0 0)
			(layer "B.Fab")
			(effects
				(font
					(size 1.27 1.27)
				)
				(justify mirror)
			)
		)
		(duplicate_pad_numbers_are_jumpers no)
		(fp_poly
			(pts
				(xy -0.3048 -0.1016) (xy -0.3048 0.9906) (xy 0.3048 0.9906) (xy 0.3048 -0.1016)
			)
			(stroke
				(width 0)
				(type default)
			)
			(fill no)
			(layer "B.CrtYd")
		)
		(fp_line
			(start -0.3048 -0.1016)
			(end 0.3048 -0.1016)
			(stroke
				(width 0.1)
				(type default)
			)
			(layer "B.Fab")
		)
		(fp_line
			(start -0.3048 0.9906)
			(end -0.3048 -0.1016)
			(stroke
				(width 0.1)
				(type default)
			)
			(layer "B.Fab")
		)
		(fp_line
			(start 0.3048 -0.1016)
			(end 0.3048 0.9906)
			(stroke
				(width 0.1)
				(type default)
			)
			(layer "B.Fab")
		)
		(fp_line
			(start 0.3048 0.9906)
			(end -0.3048 0.9906)
			(stroke
				(width 0.1)
				(type default)
			)
			(layer "B.Fab")
		)
		(pad "1" smd rect
			(at 0 0 180)
			(size 0.508 0.508)
			(layers "B.Cu" "B.Mask" "B.Paste")
			(net "P3E_CPU0_PE3_OCP_TXN<5>")
		)
		(pad "2" smd rect
			(at 0 0.889 180)
			(size 0.508 0.508)
			(layers "B.Cu" "B.Mask" "B.Paste")
			(net "P3E_OCP_CPU0_PE3_C_TXN<5>")
		)
		(zone
			(layer "B.Cu")
			(hatch none 0.5)
			(connect_pads
				(clearance 0)
			)
			(min_thickness 0.25)
			(keepout
				(tracks allowed)
				(vias not_allowed)
				(pads allowed)
				(copperpour not_allowed)
				(footprints allowed)
			)
			(placement
				(enabled no)
				(sheetname "")
			)
			(fill
				(thermal_gap 0.5)
				(thermal_bridge_width 0.5)
				(island_removal_mode 0)
			)
			(polygon
				(pts
					(xy 448.182238 -52.153058) (xy 447.674238 -52.153058) (xy 447.674238 -51.772058) (xy 448.182238 -51.772058)
				)
			)
		)
		(zone
			(layer "B.Cu")
			(hatch none 0.5)
			(connect_pads
				(clearance 0)
			)
			(min_thickness 0.25)
			(keepout
				(tracks not_allowed)
				(vias allowed)
				(pads allowed)
				(copperpour not_allowed)
				(footprints allowed)
			)
			(placement
				(enabled no)
				(sheetname "")
			)
			(fill
				(thermal_gap 0.5)
				(thermal_bridge_width 0.5)
				(island_removal_mode 0)
			)
			(polygon
				(pts
					(xy 448.182238 -51.772058) (xy 447.674238 -51.772058) (xy 447.674238 -52.153058) (xy 448.182238 -52.153058)
				)
			)
		)
	)
	(footprint ""
		(layer "B.Cu")
		(at 29.699458 -5.621782 90)
		(property "Reference" "J9U2"
			(at 2.098548 38.118542 0)
			(unlocked yes)
			(layer "B.SilkS")
			(effects
				(font
					(size 0.7874 0.5842)
					(thickness 0.1524)
				)
				(justify left mirror)
			)
		)
		(property "Value" ""
			(at 0 0 90)
			(layer "B.Fab")
			(effects
				(font
					(size 1.27 1.27)
				)
				(justify mirror)
			)
		)
		(duplicate_pad_numbers_are_jumpers no)
		(fp_line
			(start 0.94996 -7.675118)
			(end -5.5499 -7.675118)
			(stroke
				(width 0.1524)
				(type default)
			)
			(layer "B.SilkS")
		)
		(fp_line
			(start -5.5499 -7.675118)
			(end -5.5499 -1.480058)
			(stroke
				(width 0.1524)
				(type default)
			)
			(layer "B.SilkS")
		)
		(fp_line
			(start 0.94996 -1.480058)
			(end 0.94996 -7.675118)
			(stroke
				(width 0.1524)
				(type default)
			)
			(layer "B.SilkS")
		)
		(fp_line
			(start -5.5499 128.130046)
			(end -5.5499 134.325106)
			(stroke
				(width 0.1524)
				(type default)
			)
			(layer "B.SilkS")
		)
		(fp_line
			(start 0.94996 134.325106)
			(end 0.94996 128.130046)
			(stroke
				(width 0.1524)
				(type default)
			)
			(layer "B.SilkS")
		)
		(fp_line
			(start -5.5499 134.325106)
			(end 0.94996 134.325106)
			(stroke
				(width 0.1524)
				(type default)
			)
			(layer "B.SilkS")
		)
		(fp_poly
			(pts
				(xy 2.877566 -0.592582) (xy 2.877566 0.423418) (xy 1.607566 -0.084582)
			)
			(stroke
				(width 0)
				(type default)
			)
			(fill yes)
			(layer "B.SilkS")
		)
		(fp_poly
			(pts
				(xy 0.94996 -7.675118) (xy 0.94996 134.325106) (xy -5.5499 134.325106) (xy -5.5499 -7.675118)
			)
			(stroke
				(width 0)
				(type default)
			)
			(fill no)
			(layer "B.CrtYd")
		)
		(fp_line
			(start 0.94996 -7.675118)
			(end -5.5499 -7.675118)
			(stroke
				(width 0.1)
				(type default)
			)
			(layer "B.Fab")
		)
		(fp_line
			(start -5.5499 -7.675118)
			(end -5.5499 134.325106)
			(stroke
				(width 0.1)
				(type default)
			)
			(layer "B.Fab")
		)
		(fp_line
			(start 0.94996 134.325106)
			(end 0.94996 -7.675118)
			(stroke
				(width 0.1)
				(type default)
			)
			(layer "B.Fab")
		)
		(fp_line
			(start -5.5499 134.325106)
			(end 0.94996 134.325106)
			(stroke
				(width 0.1)
				(type default)
			)
			(layer "B.Fab")
		)
		(fp_poly
			(pts
				(xy 2.984246 -0.461264) (xy 2.984246 0.554736) (xy 1.714246 0.046736)
			)
			(stroke
				(width 0)
				(type default)
			)
			(fill yes)
			(layer "B.Fab")
		)
		(fp_text user "145"
			(at -6.174232 0.582676 0)
			(unlocked yes)
			(layer "B.SilkS")
			(effects
				(font
					(size 0.7874 0.5842)
					(thickness 0.1524)
				)
				(justify left mirror)
			)
		)
		(fp_text user "77"
			(at 1.082548 66.312542 0)
			(unlocked yes)
			(layer "B.SilkS")
			(effects
				(font
					(size 0.7874 0.5842)
					(thickness 0.1524)
				)
				(justify left mirror)
			)
		)
		(fp_text user "221"
			(at -6.029452 66.820542 0)
			(unlocked yes)
			(layer "B.SilkS")
			(effects
				(font
					(size 0.7874 0.5842)
					(thickness 0.1524)
				)
				(justify left mirror)
			)
		)
		(fp_text user "78"
			(at 1.590548 71.265542 0)
			(unlocked yes)
			(layer "B.SilkS")
			(effects
				(font
					(size 0.7874 0.5842)
					(thickness 0.1524)
				)
				(justify left mirror)
			)
		)
		(fp_text user "222"
			(at -6.283452 71.900542 0)
			(unlocked yes)
			(layer "B.SilkS")
			(effects
				(font
					(size 0.7874 0.5842)
					(thickness 0.1524)
				)
				(justify left mirror)
			)
		)
		(fp_text user "288"
			(at -6.283452 129.558542 0)
			(unlocked yes)
			(layer "B.SilkS")
			(effects
				(font
					(size 0.7874 0.5842)
					(thickness 0.1524)
				)
				(justify left mirror)
			)
		)
		(fp_text user "144"
			(at 1.717548 129.812542 0)
			(unlocked yes)
			(layer "B.SilkS")
			(effects
				(font
					(size 0.7874 0.5842)
					(thickness 0.1524)
				)
				(justify left mirror)
			)
		)
		(fp_text user "145"
			(at -3.081782 -1.478788 90)
			(unlocked yes)
			(layer "B.Fab")
			(effects
				(font
					(size 0.7874 0.5842)
					(thickness 0.1524)
				)
				(justify left mirror)
			)
		)
		(fp_text user "77"
			(at 0.728218 65.831212 90)
			(unlocked yes)
			(layer "B.Fab")
			(effects
				(font
					(size 0.7874 0.5842)
					(thickness 0.1524)
				)
				(justify left mirror)
			)
		)
		(fp_text user "221"
			(at -3.081782 65.831212 90)
			(unlocked yes)
			(layer "B.Fab")
			(effects
				(font
					(size 0.7874 0.5842)
					(thickness 0.1524)
				)
				(justify left mirror)
			)
		)
		(fp_text user "78"
			(at 0.728218 69.006212 90)
			(unlocked yes)
			(layer "B.Fab")
			(effects
				(font
					(size 0.7874 0.5842)
					(thickness 0.1524)
				)
				(justify left mirror)
			)
		)
		(fp_text user "222"
			(at -3.716782 69.006212 90)
			(unlocked yes)
			(layer "B.Fab")
			(effects
				(font
					(size 0.7874 0.5842)
					(thickness 0.1524)
				)
				(justify left mirror)
			)
		)
		(fp_text user "144"
			(at 0.728218 128.061212 90)
			(unlocked yes)
			(layer "B.Fab")
			(effects
				(font
					(size 0.7874 0.5842)
					(thickness 0.1524)
				)
				(justify left mirror)
			)
		)
		(fp_text user "288"
			(at -3.081782 128.061212 90)
			(unlocked yes)
			(layer "B.Fab")
			(effects
				(font
					(size 0.7874 0.5842)
					(thickness 0.1524)
				)
				(justify left mirror)
			)
		)
		(pad "" thru_hole circle
			(at -2.29997 -5.649976 270)
			(size 2.8194 2.8194)
			(drill 2.4384)
			(layers "*.Cu" "*.Mask")
			(remove_unused_layers no)
			(clearance 0.127)
			(thermal_gap 0.127)
		)
		(pad "" thru_hole oval
			(at -2.29997 68.90004 270)
			(size 2.8194 1.5748)
			(drill oval 2.4384 1.1938)
			(layers "*.Cu" "*.Mask")
			(remove_unused_layers no)
			(clearance 0.127)
			(thermal_gap 0.127)
		)
		(pad "" thru_hole circle
			(at -2.29997 132.299964 270)
			(size 2.8194 2.8194)
			(drill 2.4384)
			(layers "*.Cu" "*.Mask")
			(remove_unused_layers no)
			(clearance 0.127)
			(thermal_gap 0.127)
		)
		(pad "1" smd rect
			(at 0 0 270)
			(size 1.8034 0.508)
			(layers "B.Cu" "B.Mask" "B.Paste")
			(net "P12V_NVDIMM_GHJ")
		)
		(pad "2" smd rect
			(at 0 0.849884 270)
			(size 1.8034 0.508)
			(layers "B.Cu" "B.Mask" "B.Paste")
			(net "GND")
		)
		(pad "3" smd rect
			(at 0 1.700022 270)
			(size 1.8034 0.508)
			(layers "B.Cu" "B.Mask" "B.Paste")
			(net "M_J_DQ<4>")
		)
		(pad "4" smd rect
			(at 0 2.549906 270)
			(size 1.8034 0.508)
			(layers "B.Cu" "B.Mask" "B.Paste")
			(net "GND")
		)
		(pad "5" smd rect
			(at 0 3.400044 270)
			(size 1.8034 0.508)
			(layers "B.Cu" "B.Mask" "B.Paste")
			(net "M_J_DQ<0>")
		)
		(pad "6" smd rect
			(at 0 4.249928 270)
			(size 1.8034 0.508)
			(layers "B.Cu" "B.Mask" "B.Paste")
			(net "GND")
		)
		(pad "7" smd rect
			(at 0 5.100066 270)
			(size 1.8034 0.508)
			(layers "B.Cu" "B.Mask" "B.Paste")
			(net "M_J_DQS_DP<9>")
		)
		(pad "8" smd rect
			(at 0 5.94995 270)
			(size 1.8034 0.508)
			(layers "B.Cu" "B.Mask" "B.Paste")
			(net "M_J_DQS_DN<9>")
		)
		(pad "9" smd rect
			(at 0 6.800088 270)
			(size 1.8034 0.508)
			(layers "B.Cu" "B.Mask" "B.Paste")
			(net "GND")
		)
		(pad "10" smd rect
			(at 0 7.649972 270)
			(size 1.8034 0.508)
			(layers "B.Cu" "B.Mask" "B.Paste")
			(net "M_J_DQ<6>")
		)
		(pad "11" smd rect
			(at 0 8.50011 270)
			(size 1.8034 0.508)
			(layers "B.Cu" "B.Mask" "B.Paste")
			(net "GND")
		)
		(pad "12" smd rect
			(at 0 9.349994 270)
			(size 1.8034 0.508)
			(layers "B.Cu" "B.Mask" "B.Paste")
			(net "M_J_DQ<2>")
		)
		(pad "13" smd rect
			(at 0 10.199878 270)
			(size 1.8034 0.508)
			(layers "B.Cu" "B.Mask" "B.Paste")
			(net "GND")
		)
		(pad "14" smd rect
			(at 0 11.050016 270)
			(size 1.8034 0.508)
			(layers "B.Cu" "B.Mask" "B.Paste")
			(net "M_J_DQ<12>")
		)
		(pad "15" smd rect
			(at 0 11.8999 270)
			(size 1.8034 0.508)
			(layers "B.Cu" "B.Mask" "B.Paste")
			(net "GND")
		)
		(pad "16" smd rect
			(at 0 12.750038 270)
			(size 1.8034 0.508)
			(layers "B.Cu" "B.Mask" "B.Paste")
			(net "M_J_DQ<8>")
		)
		(pad "17" smd rect
			(at 0 13.599922 270)
			(size 1.8034 0.508)
			(layers "B.Cu" "B.Mask" "B.Paste")
			(net "GND")
		)
		(pad "18" smd rect
			(at 0 14.45006 270)
			(size 1.8034 0.508)
			(layers "B.Cu" "B.Mask" "B.Paste")
			(net "M_J_DQS_DP<10>")
		)
		(pad "19" smd rect
			(at 0 15.299944 270)
			(size 1.8034 0.508)
			(layers "B.Cu" "B.Mask" "B.Paste")
			(net "M_J_DQS_DN<10>")
		)
		(pad "20" smd rect
			(at 0 16.150082 270)
			(size 1.8034 0.508)
			(layers "B.Cu" "B.Mask" "B.Paste")
			(net "GND")
		)
		(pad "21" smd rect
			(at 0 16.999966 270)
			(size 1.8034 0.508)
			(layers "B.Cu" "B.Mask" "B.Paste")
			(net "M_J_DQ<14>")
		)
		(pad "22" smd rect
			(at 0 17.850104 270)
			(size 1.8034 0.508)
			(layers "B.Cu" "B.Mask" "B.Paste")
			(net "GND")
		)
		(pad "23" smd rect
			(at 0 18.699988 270)
			(size 1.8034 0.508)
			(layers "B.Cu" "B.Mask" "B.Paste")
			(net "M_J_DQ<10>")
		)
		(pad "24" smd rect
			(at 0 19.550126 270)
			(size 1.8034 0.508)
			(layers "B.Cu" "B.Mask" "B.Paste")
			(net "GND")
		)
		(pad "25" smd rect
			(at 0 20.40001 270)
			(size 1.8034 0.508)
			(layers "B.Cu" "B.Mask" "B.Paste")
			(net "M_J_DQ<20>")
		)
		(pad "26" smd rect
			(at 0 21.249894 270)
			(size 1.8034 0.508)
			(layers "B.Cu" "B.Mask" "B.Paste")
			(net "GND")
		)
		(pad "27" smd rect
			(at 0 22.100032 270)
			(size 1.8034 0.508)
			(layers "B.Cu" "B.Mask" "B.Paste")
			(net "M_J_DQ<16>")
		)
		(pad "28" smd rect
			(at 0 22.949916 270)
			(size 1.8034 0.508)
			(layers "B.Cu" "B.Mask" "B.Paste")
			(net "GND")
		)
		(pad "29" smd rect
			(at 0 23.800054 270)
			(size 1.8034 0.508)
			(layers "B.Cu" "B.Mask" "B.Paste")
			(net "M_J_DQS_DP<11>")
		)
		(pad "30" smd rect
			(at 0 24.649938 270)
			(size 1.8034 0.508)
			(layers "B.Cu" "B.Mask" "B.Paste")
			(net "M_J_DQS_DN<11>")
		)
		(pad "31" smd rect
			(at 0 25.500076 270)
			(size 1.8034 0.508)
			(layers "B.Cu" "B.Mask" "B.Paste")
			(net "GND")
		)
		(pad "32" smd rect
			(at 0 26.34996 270)
			(size 1.8034 0.508)
			(layers "B.Cu" "B.Mask" "B.Paste")
			(net "M_J_DQ<22>")
		)
		(pad "33" smd rect
			(at 0 27.200098 270)
			(size 1.8034 0.508)
			(layers "B.Cu" "B.Mask" "B.Paste")
			(net "GND")
		)
		(pad "34" smd rect
			(at 0 28.049982 270)
			(size 1.8034 0.508)
			(layers "B.Cu" "B.Mask" "B.Paste")
			(net "M_J_DQ<18>")
		)
		(pad "35" smd rect
			(at 0 28.90012 270)
			(size 1.8034 0.508)
			(layers "B.Cu" "B.Mask" "B.Paste")
			(net "GND")
		)
		(pad "36" smd rect
			(at 0 29.750004 270)
			(size 1.8034 0.508)
			(layers "B.Cu" "B.Mask" "B.Paste")
			(net "M_J_DQ<28>")
		)
		(pad "37" smd rect
			(at 0 30.599888 270)
			(size 1.8034 0.508)
			(layers "B.Cu" "B.Mask" "B.Paste")
			(net "GND")
		)
		(pad "38" smd rect
			(at 0 31.450026 270)
			(size 1.8034 0.508)
			(layers "B.Cu" "B.Mask" "B.Paste")
			(net "M_J_DQ<24>")
		)
		(pad "39" smd rect
			(at 0 32.29991 270)
			(size 1.8034 0.508)
			(layers "B.Cu" "B.Mask" "B.Paste")
			(net "GND")
		)
		(pad "40" smd rect
			(at 0 33.150048 270)
			(size 1.8034 0.508)
			(layers "B.Cu" "B.Mask" "B.Paste")
			(net "M_J_DQS_DP<12>")
		)
		(pad "41" smd rect
			(at 0 33.999932 270)
			(size 1.8034 0.508)
			(layers "B.Cu" "B.Mask" "B.Paste")
			(net "M_J_DQS_DN<12>")
		)
		(pad "42" smd rect
			(at 0 34.85007 270)
			(size 1.8034 0.508)
			(layers "B.Cu" "B.Mask" "B.Paste")
			(net "GND")
		)
		(pad "43" smd rect
			(at 0 35.699954 270)
			(size 1.8034 0.508)
			(layers "B.Cu" "B.Mask" "B.Paste")
			(net "M_J_DQ<30>")
		)
		(pad "44" smd rect
			(at 0 36.550092 270)
			(size 1.8034 0.508)
			(layers "B.Cu" "B.Mask" "B.Paste")
			(net "GND")
		)
		(pad "45" smd rect
			(at 0 37.399976 270)
			(size 1.8034 0.508)
			(layers "B.Cu" "B.Mask" "B.Paste")
			(net "M_J_DQ<26>")
		)
		(pad "46" smd rect
			(at 0 38.250114 270)
			(size 1.8034 0.508)
			(layers "B.Cu" "B.Mask" "B.Paste")
			(net "GND")
		)
		(pad "47" smd rect
			(at 0 39.099998 270)
			(size 1.8034 0.508)
			(layers "B.Cu" "B.Mask" "B.Paste")
			(net "M_J_ECC<4>")
		)
		(pad "48" smd rect
			(at 0 39.949882 270)
			(size 1.8034 0.508)
			(layers "B.Cu" "B.Mask" "B.Paste")
			(net "GND")
		)
		(pad "49" smd rect
			(at 0 40.80002 270)
			(size 1.8034 0.508)
			(layers "B.Cu" "B.Mask" "B.Paste")
			(net "M_J_ECC<0>")
		)
		(pad "50" smd rect
			(at 0 41.649904 270)
			(size 1.8034 0.508)
			(layers "B.Cu" "B.Mask" "B.Paste")
			(net "GND")
		)
		(pad "51" smd rect
			(at 0 42.500042 270)
			(size 1.8034 0.508)
			(layers "B.Cu" "B.Mask" "B.Paste")
			(net "M_J_DQS_DP<17>")
		)
		(pad "52" smd rect
			(at 0 43.349926 270)
			(size 1.8034 0.508)
			(layers "B.Cu" "B.Mask" "B.Paste")
			(net "M_J_DQS_DN<17>")
		)
		(pad "53" smd rect
			(at 0 44.200064 270)
			(size 1.8034 0.508)
			(layers "B.Cu" "B.Mask" "B.Paste")
			(net "GND")
		)
		(pad "54" smd rect
			(at 0 45.049948 270)
			(size 1.8034 0.508)
			(layers "B.Cu" "B.Mask" "B.Paste")
			(net "M_J_ECC<6>")
		)
		(pad "55" smd rect
			(at 0 45.900086 270)
			(size 1.8034 0.508)
			(layers "B.Cu" "B.Mask" "B.Paste")
			(net "GND")
		)
		(pad "56" smd rect
			(at 0 46.74997 270)
			(size 1.8034 0.508)
			(layers "B.Cu" "B.Mask" "B.Paste")
			(net "M_J_ECC<2>")
		)
		(pad "57" smd rect
			(at 0 47.600108 270)
			(size 1.8034 0.508)
			(layers "B.Cu" "B.Mask" "B.Paste")
			(net "GND")
		)
		(pad "58" smd rect
			(at 0 48.449992 270)
			(size 1.8034 0.508)
			(layers "B.Cu" "B.Mask" "B.Paste")
			(net "M_GHJ_RST_N")
		)
		(pad "59" smd rect
			(at 0 49.299876 270)
			(size 1.8034 0.508)
			(layers "B.Cu" "B.Mask" "B.Paste")
			(net "PVDDQ_GHJ")
		)
		(pad "60" smd rect
			(at 0 50.150014 270)
			(size 1.8034 0.508)
			(layers "B.Cu" "B.Mask" "B.Paste")
			(net "M_J_CKE<2>")
		)
		(pad "61" smd rect
			(at 0 50.999898 270)
			(size 1.8034 0.508)
			(layers "B.Cu" "B.Mask" "B.Paste")
			(net "PVDDQ_GHJ")
		)
		(pad "62" smd rect
			(at 0 51.850036 270)
			(size 1.8034 0.508)
			(layers "B.Cu" "B.Mask" "B.Paste")
			(net "M_J_ACT_N")
		)
		(pad "63" smd rect
			(at 0 52.69992 270)
			(size 1.8034 0.508)
			(layers "B.Cu" "B.Mask" "B.Paste")
			(net "M_J_BG<0>")
		)
		(pad "64" smd rect
			(at 0 53.550058 270)
			(size 1.8034 0.508)
			(layers "B.Cu" "B.Mask" "B.Paste")
			(net "PVDDQ_GHJ")
		)
		(pad "65" smd rect
			(at 0 54.399942 270)
			(size 1.8034 0.508)
			(layers "B.Cu" "B.Mask" "B.Paste")
			(net "M_J_MA<12>")
		)
		(pad "66" smd rect
			(at 0 55.25008 270)
			(size 1.8034 0.508)
			(layers "B.Cu" "B.Mask" "B.Paste")
			(net "M_J_MA<9>")
		)
		(pad "67" smd rect
			(at 0 56.099964 270)
			(size 1.8034 0.508)
			(layers "B.Cu" "B.Mask" "B.Paste")
			(net "PVDDQ_GHJ")
		)
		(pad "68" smd rect
			(at 0 56.950102 270)
			(size 1.8034 0.508)
			(layers "B.Cu" "B.Mask" "B.Paste")
			(net "M_J_MA<8>")
		)
		(pad "69" smd rect
			(at 0 57.799986 270)
			(size 1.8034 0.508)
			(layers "B.Cu" "B.Mask" "B.Paste")
			(net "M_J_MA<6>")
		)
		(pad "70" smd rect
			(at 0 58.650124 270)
			(size 1.8034 0.508)
			(layers "B.Cu" "B.Mask" "B.Paste")
			(net "PVDDQ_GHJ")
		)
		(pad "71" smd rect
			(at 0 59.500008 270)
			(size 1.8034 0.508)
			(layers "B.Cu" "B.Mask" "B.Paste")
			(net "M_J_MA<3>")
		)
		(pad "72" smd rect
			(at 0 60.349892 270)
			(size 1.8034 0.508)
			(layers "B.Cu" "B.Mask" "B.Paste")
			(net "M_J_MA<1>")
		)
		(pad "73" smd rect
			(at 0 61.20003 270)
			(size 1.8034 0.508)
			(layers "B.Cu" "B.Mask" "B.Paste")
			(net "PVDDQ_GHJ")
		)
		(pad "74" smd rect
			(at 0 62.049914 270)
			(size 1.8034 0.508)
			(layers "B.Cu" "B.Mask" "B.Paste")
			(net "M_J_CLK_DP<2>")
		)
		(pad "75" smd rect
			(at 0 62.900052 270)
			(size 1.8034 0.508)
			(layers "B.Cu" "B.Mask" "B.Paste")
			(net "M_J_CLK_DN<2>")
		)
		(pad "76" smd rect
			(at 0 63.749936 270)
			(size 1.8034 0.508)
			(layers "B.Cu" "B.Mask" "B.Paste")
			(net "PVDDQ_GHJ")
		)
		(pad "77" smd rect
			(at 0 64.600074 270)
			(size 1.8034 0.508)
			(layers "B.Cu" "B.Mask" "B.Paste")
			(net "PVTT_GHJ")
		)
		(pad "78" smd rect
			(at 0 70.550024 270)
			(size 1.8034 0.508)
			(layers "B.Cu" "B.Mask" "B.Paste")
			(net "FM_DIMM_EVENT_COD_N")
		)
		(pad "79" smd rect
			(at 0 71.399908 270)
			(size 1.8034 0.508)
			(layers "B.Cu" "B.Mask" "B.Paste")
			(net "M_J_MA<0>")
		)
		(pad "80" smd rect
			(at 0 72.250046 270)
			(size 1.8034 0.508)
			(layers "B.Cu" "B.Mask" "B.Paste")
			(net "PVDDQ_GHJ")
		)
		(pad "81" smd rect
			(at 0 73.09993 270)
			(size 1.8034 0.508)
			(layers "B.Cu" "B.Mask" "B.Paste")
			(net "M_J_BA<0>")
		)
		(pad "82" smd rect
			(at 0 73.950068 270)
			(size 1.8034 0.508)
			(layers "B.Cu" "B.Mask" "B.Paste")
			(net "M_J_MA<16>")
		)
		(pad "83" smd rect
			(at 0 74.799952 270)
			(size 1.8034 0.508)
			(layers "B.Cu" "B.Mask" "B.Paste")
			(net "PVDDQ_GHJ")
		)
		(pad "84" smd rect
			(at 0 75.65009 270)
			(size 1.8034 0.508)
			(layers "B.Cu" "B.Mask" "B.Paste")
			(net "M_J_CS_N<4>")
		)
		(pad "85" smd rect
			(at 0 76.499974 270)
			(size 1.8034 0.508)
			(layers "B.Cu" "B.Mask" "B.Paste")
			(net "PVDDQ_GHJ")
		)
		(pad "86" smd rect
			(at 0 77.350112 270)
			(size 1.8034 0.508)
			(layers "B.Cu" "B.Mask" "B.Paste")
			(net "M_J_MA<15>")
		)
		(pad "87" smd rect
			(at 0 78.199996 270)
			(size 1.8034 0.508)
			(layers "B.Cu" "B.Mask" "B.Paste")
			(net "M_J_ODT<2>")
		)
		(pad "88" smd rect
			(at 0 79.04988 270)
			(size 1.8034 0.508)
			(layers "B.Cu" "B.Mask" "B.Paste")
			(net "PVDDQ_GHJ")
		)
		(pad "89" smd rect
			(at 0 79.900018 270)
			(size 1.8034 0.508)
			(layers "B.Cu" "B.Mask" "B.Paste")
			(net "M_J_CS_N<5>")
		)
		(pad "90" smd rect
			(at 0 80.749902 270)
			(size 1.8034 0.508)
			(layers "B.Cu" "B.Mask" "B.Paste")
			(net "PVDDQ_GHJ")
		)
		(pad "91" smd rect
			(at 0 81.60004 270)
			(size 1.8034 0.508)
			(layers "B.Cu" "B.Mask" "B.Paste")
			(net "M_J_ODT<3>")
		)
		(pad "92" smd rect
			(at 0 82.449924 270)
			(size 1.8034 0.508)
			(layers "B.Cu" "B.Mask" "B.Paste")
			(net "PVDDQ_GHJ")
		)
		(pad "93" smd rect
			(at 0 83.300062 270)
			(size 1.8034 0.508)
			(layers "B.Cu" "B.Mask" "B.Paste")
			(net "M_J_CS_N<6>")
		)
		(pad "94" smd rect
			(at 0 84.149946 270)
			(size 1.8034 0.508)
			(layers "B.Cu" "B.Mask" "B.Paste")
			(net "GND")
		)
		(pad "95" smd rect
			(at 0 85.000084 270)
			(size 1.8034 0.508)
			(layers "B.Cu" "B.Mask" "B.Paste")
			(net "M_J_DQ<36>")
		)
		(pad "96" smd rect
			(at 0 85.849968 270)
			(size 1.8034 0.508)
			(layers "B.Cu" "B.Mask" "B.Paste")
			(net "GND")
		)
		(pad "97" smd rect
			(at 0 86.700106 270)
			(size 1.8034 0.508)
			(layers "B.Cu" "B.Mask" "B.Paste")
			(net "M_J_DQ<32>")
		)
		(pad "98" smd rect
			(at 0 87.54999 270)
			(size 1.8034 0.508)
			(layers "B.Cu" "B.Mask" "B.Paste")
			(net "GND")
		)
		(pad "99" smd rect
			(at 0 88.399874 270)
			(size 1.8034 0.508)
			(layers "B.Cu" "B.Mask" "B.Paste")
			(net "M_J_DQS_DP<13>")
		)
		(pad "100" smd rect
			(at 0 89.250012 270)
			(size 1.8034 0.508)
			(layers "B.Cu" "B.Mask" "B.Paste")
			(net "M_J_DQS_DN<13>")
		)
		(pad "101" smd rect
			(at 0 90.099896 270)
			(size 1.8034 0.508)
			(layers "B.Cu" "B.Mask" "B.Paste")
			(net "GND")
		)
		(pad "102" smd rect
			(at 0 90.950034 270)
			(size 1.8034 0.508)
			(layers "B.Cu" "B.Mask" "B.Paste")
			(net "M_J_DQ<38>")
		)
		(pad "103" smd rect
			(at 0 91.799918 270)
			(size 1.8034 0.508)
			(layers "B.Cu" "B.Mask" "B.Paste")
			(net "GND")
		)
		(pad "104" smd rect
			(at 0 92.650056 270)
			(size 1.8034 0.508)
			(layers "B.Cu" "B.Mask" "B.Paste")
			(net "M_J_DQ<34>")
		)
		(pad "105" smd rect
			(at 0 93.49994 270)
			(size 1.8034 0.508)
			(layers "B.Cu" "B.Mask" "B.Paste")
			(net "GND")
		)
		(pad "106" smd rect
			(at 0 94.350078 270)
			(size 1.8034 0.508)
			(layers "B.Cu" "B.Mask" "B.Paste")
			(net "M_J_DQ<44>")
		)
		(pad "107" smd rect
			(at 0 95.199962 270)
			(size 1.8034 0.508)
			(layers "B.Cu" "B.Mask" "B.Paste")
			(net "GND")
		)
		(pad "108" smd rect
			(at 0 96.0501 270)
			(size 1.8034 0.508)
			(layers "B.Cu" "B.Mask" "B.Paste")
			(net "M_J_DQ<40>")
		)
		(pad "109" smd rect
			(at 0 96.899984 270)
			(size 1.8034 0.508)
			(layers "B.Cu" "B.Mask" "B.Paste")
			(net "GND")
		)
		(pad "110" smd rect
			(at 0 97.750122 270)
			(size 1.8034 0.508)
			(layers "B.Cu" "B.Mask" "B.Paste")
			(net "M_J_DQS_DP<14>")
		)
		(pad "111" smd rect
			(at 0 98.600006 270)
			(size 1.8034 0.508)
			(layers "B.Cu" "B.Mask" "B.Paste")
			(net "M_J_DQS_DN<14>")
		)
		(pad "112" smd rect
			(at 0 99.44989 270)
			(size 1.8034 0.508)
			(layers "B.Cu" "B.Mask" "B.Paste")
			(net "GND")
		)
		(pad "113" smd rect
			(at 0 100.300028 270)
			(size 1.8034 0.508)
			(layers "B.Cu" "B.Mask" "B.Paste")
			(net "M_J_DQ<46>")
		)
		(pad "114" smd rect
			(at 0 101.149912 270)
			(size 1.8034 0.508)
			(layers "B.Cu" "B.Mask" "B.Paste")
			(net "GND")
		)
		(pad "115" smd rect
			(at 0 102.00005 270)
			(size 1.8034 0.508)
			(layers "B.Cu" "B.Mask" "B.Paste")
			(net "M_J_DQ<42>")
		)
		(pad "116" smd rect
			(at 0 102.849934 270)
			(size 1.8034 0.508)
			(layers "B.Cu" "B.Mask" "B.Paste")
			(net "GND")
		)
		(pad "117" smd rect
			(at 0 103.700072 270)
			(size 1.8034 0.508)
			(layers "B.Cu" "B.Mask" "B.Paste")
			(net "M_J_DQ<52>")
		)
		(pad "118" smd rect
			(at 0 104.549956 270)
			(size 1.8034 0.508)
			(layers "B.Cu" "B.Mask" "B.Paste")
			(net "GND")
		)
		(pad "119" smd rect
			(at 0 105.400094 270)
			(size 1.8034 0.508)
			(layers "B.Cu" "B.Mask" "B.Paste")
			(net "M_J_DQ<48>")
		)
		(pad "120" smd rect
			(at 0 106.249978 270)
			(size 1.8034 0.508)
			(layers "B.Cu" "B.Mask" "B.Paste")
			(net "GND")
		)
		(pad "121" smd rect
			(at 0 107.100116 270)
			(size 1.8034 0.508)
			(layers "B.Cu" "B.Mask" "B.Paste")
			(net "M_J_DQS_DP<15>")
		)
		(pad "122" smd rect
			(at 0 107.95 270)
			(size 1.8034 0.508)
			(layers "B.Cu" "B.Mask" "B.Paste")
			(net "M_J_DQS_DN<15>")
		)
		(pad "123" smd rect
			(at 0 108.799884 270)
			(size 1.8034 0.508)
			(layers "B.Cu" "B.Mask" "B.Paste")
			(net "GND")
		)
		(pad "124" smd rect
			(at 0 109.650022 270)
			(size 1.8034 0.508)
			(layers "B.Cu" "B.Mask" "B.Paste")
			(net "M_J_DQ<54>")
		)
		(pad "125" smd rect
			(at 0 110.499906 270)
			(size 1.8034 0.508)
			(layers "B.Cu" "B.Mask" "B.Paste")
			(net "GND")
		)
		(pad "126" smd rect
			(at 0 111.350044 270)
			(size 1.8034 0.508)
			(layers "B.Cu" "B.Mask" "B.Paste")
			(net "M_J_DQ<50>")
		)
		(pad "127" smd rect
			(at 0 112.199928 270)
			(size 1.8034 0.508)
			(layers "B.Cu" "B.Mask" "B.Paste")
			(net "GND")
		)
		(pad "128" smd rect
			(at 0 113.050066 270)
			(size 1.8034 0.508)
			(layers "B.Cu" "B.Mask" "B.Paste")
			(net "M_J_DQ<60>")
		)
		(pad "129" smd rect
			(at 0 113.89995 270)
			(size 1.8034 0.508)
			(layers "B.Cu" "B.Mask" "B.Paste")
			(net "GND")
		)
		(pad "130" smd rect
			(at 0 114.750088 270)
			(size 1.8034 0.508)
			(layers "B.Cu" "B.Mask" "B.Paste")
			(net "M_J_DQ<56>")
		)
		(pad "131" smd rect
			(at 0 115.599972 270)
			(size 1.8034 0.508)
			(layers "B.Cu" "B.Mask" "B.Paste")
			(net "GND")
		)
		(pad "132" smd rect
			(at 0 116.45011 270)
			(size 1.8034 0.508)
			(layers "B.Cu" "B.Mask" "B.Paste")
			(net "M_J_DQS_DP<16>")
		)
		(pad "133" smd rect
			(at 0 117.299994 270)
			(size 1.8034 0.508)
			(layers "B.Cu" "B.Mask" "B.Paste")
			(net "M_J_DQS_DN<16>")
		)
		(pad "134" smd rect
			(at 0 118.149878 270)
			(size 1.8034 0.508)
			(layers "B.Cu" "B.Mask" "B.Paste")
			(net "GND")
		)
		(pad "135" smd rect
			(at 0 119.000016 270)
			(size 1.8034 0.508)
			(layers "B.Cu" "B.Mask" "B.Paste")
			(net "M_J_DQ<62>")
		)
		(pad "136" smd rect
			(at 0 119.8499 270)
			(size 1.8034 0.508)
			(layers "B.Cu" "B.Mask" "B.Paste")
			(net "GND")
		)
		(pad "137" smd rect
			(at 0 120.700038 270)
			(size 1.8034 0.508)
			(layers "B.Cu" "B.Mask" "B.Paste")
			(net "M_J_DQ<58>")
		)
		(pad "138" smd rect
			(at 0 121.549922 270)
			(size 1.8034 0.508)
			(layers "B.Cu" "B.Mask" "B.Paste")
			(net "GND")
		)
		(pad "139" smd rect
			(at 0 122.40006 270)
			(size 1.8034 0.508)
			(layers "B.Cu" "B.Mask" "B.Paste")
			(net "PVPP_GHJ")
		)
		(pad "140" smd rect
			(at 0 123.249944 270)
			(size 1.8034 0.508)
			(layers "B.Cu" "B.Mask" "B.Paste")
			(net "GND")
		)
		(pad "141" smd rect
			(at 0 124.100082 270)
			(size 1.8034 0.508)
			(layers "B.Cu" "B.Mask" "B.Paste")
			(net "SMB_DDR_GHJ_VPP_SCL")
		)
		(pad "142" smd rect
			(at 0 124.949966 270)
			(size 1.8034 0.508)
			(layers "B.Cu" "B.Mask" "B.Paste")
			(net "PVPP_GHJ")
		)
		(pad "143" smd rect
			(at 0 125.800104 270)
			(size 1.8034 0.508)
			(layers "B.Cu" "B.Mask" "B.Paste")
			(net "PVPP_GHJ")
		)
		(pad "144" smd rect
			(at 0 126.649988 270)
			(size 1.8034 0.508)
			(layers "B.Cu" "B.Mask" "B.Paste")
			(net "TP_CH_J_DIMM_J1_RFU_2")
		)
		(pad "145" smd rect
			(at -4.59994 0 270)
			(size 1.8034 0.508)
			(layers "B.Cu" "B.Mask" "B.Paste")
			(net "P12V_NVDIMM_GHJ")
		)
		(pad "146" smd rect
			(at -4.59994 0.849884 270)
			(size 1.8034 0.508)
			(layers "B.Cu" "B.Mask" "B.Paste")
			(net "M_J_VREF")
		)
		(pad "147" smd rect
			(at -4.59994 1.700022 270)
			(size 1.8034 0.508)
			(layers "B.Cu" "B.Mask" "B.Paste")
			(net "GND")
		)
		(pad "148" smd rect
			(at -4.59994 2.549906 270)
			(size 1.8034 0.508)
			(layers "B.Cu" "B.Mask" "B.Paste")
			(net "M_J_DQ<5>")
		)
		(pad "149" smd rect
			(at -4.59994 3.400044 270)
			(size 1.8034 0.508)
			(layers "B.Cu" "B.Mask" "B.Paste")
			(net "GND")
		)
		(pad "150" smd rect
			(at -4.59994 4.249928 270)
			(size 1.8034 0.508)
			(layers "B.Cu" "B.Mask" "B.Paste")
			(net "M_J_DQ<1>")
		)
		(pad "151" smd rect
			(at -4.59994 5.100066 270)
			(size 1.8034 0.508)
			(layers "B.Cu" "B.Mask" "B.Paste")
			(net "GND")
		)
		(pad "152" smd rect
			(at -4.59994 5.94995 270)
			(size 1.8034 0.508)
			(layers "B.Cu" "B.Mask" "B.Paste")
			(net "M_J_DQS_DN<0>")
		)
		(pad "153" smd rect
			(at -4.59994 6.800088 270)
			(size 1.8034 0.508)
			(layers "B.Cu" "B.Mask" "B.Paste")
			(net "M_J_DQS_DP<0>")
		)
		(pad "154" smd rect
			(at -4.59994 7.649972 270)
			(size 1.8034 0.508)
			(layers "B.Cu" "B.Mask" "B.Paste")
			(net "GND")
		)
		(pad "155" smd rect
			(at -4.59994 8.50011 270)
			(size 1.8034 0.508)
			(layers "B.Cu" "B.Mask" "B.Paste")
			(net "M_J_DQ<7>")
		)
		(pad "156" smd rect
			(at -4.59994 9.349994 270)
			(size 1.8034 0.508)
			(layers "B.Cu" "B.Mask" "B.Paste")
			(net "GND")
		)
		(pad "157" smd rect
			(at -4.59994 10.199878 270)
			(size 1.8034 0.508)
			(layers "B.Cu" "B.Mask" "B.Paste")
			(net "M_J_DQ<3>")
		)
		(pad "158" smd rect
			(at -4.59994 11.050016 270)
			(size 1.8034 0.508)
			(layers "B.Cu" "B.Mask" "B.Paste")
			(net "GND")
		)
		(pad "159" smd rect
			(at -4.59994 11.8999 270)
			(size 1.8034 0.508)
			(layers "B.Cu" "B.Mask" "B.Paste")
			(net "M_J_DQ<13>")
		)
		(pad "160" smd rect
			(at -4.59994 12.750038 270)
			(size 1.8034 0.508)
			(layers "B.Cu" "B.Mask" "B.Paste")
			(net "GND")
		)
		(pad "161" smd rect
			(at -4.59994 13.599922 270)
			(size 1.8034 0.508)
			(layers "B.Cu" "B.Mask" "B.Paste")
			(net "M_J_DQ<9>")
		)
		(pad "162" smd rect
			(at -4.59994 14.45006 270)
			(size 1.8034 0.508)
			(layers "B.Cu" "B.Mask" "B.Paste")
			(net "GND")
		)
		(pad "163" smd rect
			(at -4.59994 15.299944 270)
			(size 1.8034 0.508)
			(layers "B.Cu" "B.Mask" "B.Paste")
			(net "M_J_DQS_DN<1>")
		)
		(pad "164" smd rect
			(at -4.59994 16.150082 270)
			(size 1.8034 0.508)
			(layers "B.Cu" "B.Mask" "B.Paste")
			(net "M_J_DQS_DP<1>")
		)
		(pad "165" smd rect
			(at -4.59994 16.999966 270)
			(size 1.8034 0.508)
			(layers "B.Cu" "B.Mask" "B.Paste")
			(net "GND")
		)
		(pad "166" smd rect
			(at -4.59994 17.850104 270)
			(size 1.8034 0.508)
			(layers "B.Cu" "B.Mask" "B.Paste")
			(net "M_J_DQ<15>")
		)
		(pad "167" smd rect
			(at -4.59994 18.699988 270)
			(size 1.8034 0.508)
			(layers "B.Cu" "B.Mask" "B.Paste")
			(net "GND")
		)
		(pad "168" smd rect
			(at -4.59994 19.550126 270)
			(size 1.8034 0.508)
			(layers "B.Cu" "B.Mask" "B.Paste")
			(net "M_J_DQ<11>")
		)
		(pad "169" smd rect
			(at -4.59994 20.40001 270)
			(size 1.8034 0.508)
			(layers "B.Cu" "B.Mask" "B.Paste")
			(net "GND")
		)
		(pad "170" smd rect
			(at -4.59994 21.249894 270)
			(size 1.8034 0.508)
			(layers "B.Cu" "B.Mask" "B.Paste")
			(net "M_J_DQ<21>")
		)
		(pad "171" smd rect
			(at -4.59994 22.100032 270)
			(size 1.8034 0.508)
			(layers "B.Cu" "B.Mask" "B.Paste")
			(net "GND")
		)
		(pad "172" smd rect
			(at -4.59994 22.949916 270)
			(size 1.8034 0.508)
			(layers "B.Cu" "B.Mask" "B.Paste")
			(net "M_J_DQ<17>")
		)
		(pad "173" smd rect
			(at -4.59994 23.800054 270)
			(size 1.8034 0.508)
			(layers "B.Cu" "B.Mask" "B.Paste")
			(net "GND")
		)
		(pad "174" smd rect
			(at -4.59994 24.649938 270)
			(size 1.8034 0.508)
			(layers "B.Cu" "B.Mask" "B.Paste")
			(net "M_J_DQS_DN<2>")
		)
		(pad "175" smd rect
			(at -4.59994 25.500076 270)
			(size 1.8034 0.508)
			(layers "B.Cu" "B.Mask" "B.Paste")
			(net "M_J_DQS_DP<2>")
		)
		(pad "176" smd rect
			(at -4.59994 26.34996 270)
			(size 1.8034 0.508)
			(layers "B.Cu" "B.Mask" "B.Paste")
			(net "GND")
		)
		(pad "177" smd rect
			(at -4.59994 27.200098 270)
			(size 1.8034 0.508)
			(layers "B.Cu" "B.Mask" "B.Paste")
			(net "M_J_DQ<23>")
		)
		(pad "178" smd rect
			(at -4.59994 28.049982 270)
			(size 1.8034 0.508)
			(layers "B.Cu" "B.Mask" "B.Paste")
			(net "GND")
		)
		(pad "179" smd rect
			(at -4.59994 28.90012 270)
			(size 1.8034 0.508)
			(layers "B.Cu" "B.Mask" "B.Paste")
			(net "M_J_DQ<19>")
		)
		(pad "180" smd rect
			(at -4.59994 29.750004 270)
			(size 1.8034 0.508)
			(layers "B.Cu" "B.Mask" "B.Paste")
			(net "GND")
		)
		(pad "181" smd rect
			(at -4.59994 30.599888 270)
			(size 1.8034 0.508)
			(layers "B.Cu" "B.Mask" "B.Paste")
			(net "M_J_DQ<29>")
		)
		(pad "182" smd rect
			(at -4.59994 31.450026 270)
			(size 1.8034 0.508)
			(layers "B.Cu" "B.Mask" "B.Paste")
			(net "GND")
		)
		(pad "183" smd rect
			(at -4.59994 32.29991 270)
			(size 1.8034 0.508)
			(layers "B.Cu" "B.Mask" "B.Paste")
			(net "M_J_DQ<25>")
		)
		(pad "184" smd rect
			(at -4.59994 33.150048 270)
			(size 1.8034 0.508)
			(layers "B.Cu" "B.Mask" "B.Paste")
			(net "GND")
		)
		(pad "185" smd rect
			(at -4.59994 33.999932 270)
			(size 1.8034 0.508)
			(layers "B.Cu" "B.Mask" "B.Paste")
			(net "M_J_DQS_DN<3>")
		)
		(pad "186" smd rect
			(at -4.59994 34.85007 270)
			(size 1.8034 0.508)
			(layers "B.Cu" "B.Mask" "B.Paste")
			(net "M_J_DQS_DP<3>")
		)
		(pad "187" smd rect
			(at -4.59994 35.699954 270)
			(size 1.8034 0.508)
			(layers "B.Cu" "B.Mask" "B.Paste")
			(net "GND")
		)
		(pad "188" smd rect
			(at -4.59994 36.550092 270)
			(size 1.8034 0.508)
			(layers "B.Cu" "B.Mask" "B.Paste")
			(net "M_J_DQ<31>")
		)
		(pad "189" smd rect
			(at -4.59994 37.399976 270)
			(size 1.8034 0.508)
			(layers "B.Cu" "B.Mask" "B.Paste")
			(net "GND")
		)
		(pad "190" smd rect
			(at -4.59994 38.250114 270)
			(size 1.8034 0.508)
			(layers "B.Cu" "B.Mask" "B.Paste")
			(net "M_J_DQ<27>")
		)
		(pad "191" smd rect
			(at -4.59994 39.099998 270)
			(size 1.8034 0.508)
			(layers "B.Cu" "B.Mask" "B.Paste")
			(net "GND")
		)
		(pad "192" smd rect
			(at -4.59994 39.949882 270)
			(size 1.8034 0.508)
			(layers "B.Cu" "B.Mask" "B.Paste")
			(net "M_J_ECC<5>")
		)
		(pad "193" smd rect
			(at -4.59994 40.80002 270)
			(size 1.8034 0.508)
			(layers "B.Cu" "B.Mask" "B.Paste")
			(net "GND")
		)
		(pad "194" smd rect
			(at -4.59994 41.649904 270)
			(size 1.8034 0.508)
			(layers "B.Cu" "B.Mask" "B.Paste")
			(net "M_J_ECC<1>")
		)
		(pad "195" smd rect
			(at -4.59994 42.500042 270)
			(size 1.8034 0.508)
			(layers "B.Cu" "B.Mask" "B.Paste")
			(net "GND")
		)
		(pad "196" smd rect
			(at -4.59994 43.349926 270)
			(size 1.8034 0.508)
			(layers "B.Cu" "B.Mask" "B.Paste")
			(net "M_J_DQS_DN<8>")
		)
		(pad "197" smd rect
			(at -4.59994 44.200064 270)
			(size 1.8034 0.508)
			(layers "B.Cu" "B.Mask" "B.Paste")
			(net "M_J_DQS_DP<8>")
		)
		(pad "198" smd rect
			(at -4.59994 45.049948 270)
			(size 1.8034 0.508)
			(layers "B.Cu" "B.Mask" "B.Paste")
			(net "GND")
		)
		(pad "199" smd rect
			(at -4.59994 45.900086 270)
			(size 1.8034 0.508)
			(layers "B.Cu" "B.Mask" "B.Paste")
			(net "M_J_ECC<7>")
		)
		(pad "200" smd rect
			(at -4.59994 46.74997 270)
			(size 1.8034 0.508)
			(layers "B.Cu" "B.Mask" "B.Paste")
			(net "GND")
		)
		(pad "201" smd rect
			(at -4.59994 47.600108 270)
			(size 1.8034 0.508)
			(layers "B.Cu" "B.Mask" "B.Paste")
			(net "M_J_ECC<3>")
		)
		(pad "202" smd rect
			(at -4.59994 48.449992 270)
			(size 1.8034 0.508)
			(layers "B.Cu" "B.Mask" "B.Paste")
			(net "GND")
		)
		(pad "203" smd rect
			(at -4.59994 49.299876 270)
			(size 1.8034 0.508)
			(layers "B.Cu" "B.Mask" "B.Paste")
			(net "M_J_CKE<3>")
		)
		(pad "204" smd rect
			(at -4.59994 50.150014 270)
			(size 1.8034 0.508)
			(layers "B.Cu" "B.Mask" "B.Paste")
			(net "PVDDQ_GHJ")
		)
		(pad "205" smd rect
			(at -4.59994 50.999898 270)
			(size 1.8034 0.508)
			(layers "B.Cu" "B.Mask" "B.Paste")
			(net "TP_CH_J_DIMM_J1_RFU_0")
		)
		(pad "206" smd rect
			(at -4.59994 51.850036 270)
			(size 1.8034 0.508)
			(layers "B.Cu" "B.Mask" "B.Paste")
			(net "PVDDQ_GHJ")
		)
		(pad "207" smd rect
			(at -4.59994 52.69992 270)
			(size 1.8034 0.508)
			(layers "B.Cu" "B.Mask" "B.Paste")
			(net "M_J_BG<1>")
		)
		(pad "208" smd rect
			(at -4.59994 53.550058 270)
			(size 1.8034 0.508)
			(layers "B.Cu" "B.Mask" "B.Paste")
			(net "M_J_ALERT_N")
		)
		(pad "209" smd rect
			(at -4.59994 54.399942 270)
			(size 1.8034 0.508)
			(layers "B.Cu" "B.Mask" "B.Paste")
			(net "PVDDQ_GHJ")
		)
		(pad "210" smd rect
			(at -4.59994 55.25008 270)
			(size 1.8034 0.508)
			(layers "B.Cu" "B.Mask" "B.Paste")
			(net "M_J_MA<11>")
		)
		(pad "211" smd rect
			(at -4.59994 56.099964 270)
			(size 1.8034 0.508)
			(layers "B.Cu" "B.Mask" "B.Paste")
			(net "M_J_MA<7>")
		)
		(pad "212" smd rect
			(at -4.59994 56.950102 270)
			(size 1.8034 0.508)
			(layers "B.Cu" "B.Mask" "B.Paste")
			(net "PVDDQ_GHJ")
		)
		(pad "213" smd rect
			(at -4.59994 57.799986 270)
			(size 1.8034 0.508)
			(layers "B.Cu" "B.Mask" "B.Paste")
			(net "M_J_MA<5>")
		)
		(pad "214" smd rect
			(at -4.59994 58.650124 270)
			(size 1.8034 0.508)
			(layers "B.Cu" "B.Mask" "B.Paste")
			(net "M_J_MA<4>")
		)
		(pad "215" smd rect
			(at -4.59994 59.500008 270)
			(size 1.8034 0.508)
			(layers "B.Cu" "B.Mask" "B.Paste")
			(net "PVDDQ_GHJ")
		)
		(pad "216" smd rect
			(at -4.59994 60.349892 270)
			(size 1.8034 0.508)
			(layers "B.Cu" "B.Mask" "B.Paste")
			(net "M_J_MA<2>")
		)
		(pad "217" smd rect
			(at -4.59994 61.20003 270)
			(size 1.8034 0.508)
			(layers "B.Cu" "B.Mask" "B.Paste")
			(net "PVDDQ_GHJ")
		)
		(pad "218" smd rect
			(at -4.59994 62.049914 270)
			(size 1.8034 0.508)
			(layers "B.Cu" "B.Mask" "B.Paste")
			(net "M_J_CLK_DP<3>")
		)
		(pad "219" smd rect
			(at -4.59994 62.900052 270)
			(size 1.8034 0.508)
			(layers "B.Cu" "B.Mask" "B.Paste")
			(net "M_J_CLK_DN<3>")
		)
		(pad "220" smd rect
			(at -4.59994 63.749936 270)
			(size 1.8034 0.508)
			(layers "B.Cu" "B.Mask" "B.Paste")
			(net "PVDDQ_GHJ")
		)
		(pad "221" smd rect
			(at -4.59994 64.600074 270)
			(size 1.8034 0.508)
			(layers "B.Cu" "B.Mask" "B.Paste")
			(net "PVTT_GHJ")
		)
		(pad "222" smd rect
			(at -4.59994 70.550024 270)
			(size 1.8034 0.508)
			(layers "B.Cu" "B.Mask" "B.Paste")
			(net "M_J_PAR")
		)
		(pad "223" smd rect
			(at -4.59994 71.399908 270)
			(size 1.8034 0.508)
			(layers "B.Cu" "B.Mask" "B.Paste")
			(net "PVDDQ_GHJ")
		)
		(pad "224" smd rect
			(at -4.59994 72.250046 270)
			(size 1.8034 0.508)
			(layers "B.Cu" "B.Mask" "B.Paste")
			(net "M_J_BA<1>")
		)
		(pad "225" smd rect
			(at -4.59994 73.09993 270)
			(size 1.8034 0.508)
			(layers "B.Cu" "B.Mask" "B.Paste")
			(net "M_J_MA<10>")
		)
		(pad "226" smd rect
			(at -4.59994 73.950068 270)
			(size 1.8034 0.508)
			(layers "B.Cu" "B.Mask" "B.Paste")
			(net "PVDDQ_GHJ")
		)
		(pad "227" smd rect
			(at -4.59994 74.799952 270)
			(size 1.8034 0.508)
			(layers "B.Cu" "B.Mask" "B.Paste")
			(net "TP_CH_J_DIMM_J1_RFU_1")
		)
		(pad "228" smd rect
			(at -4.59994 75.65009 270)
			(size 1.8034 0.508)
			(layers "B.Cu" "B.Mask" "B.Paste")
			(net "M_J_MA<14>")
		)
		(pad "229" smd rect
			(at -4.59994 76.499974 270)
			(size 1.8034 0.508)
			(layers "B.Cu" "B.Mask" "B.Paste")
			(net "PVDDQ_GHJ")
		)
		(pad "230" smd rect
			(at -4.59994 77.350112 270)
			(size 1.8034 0.508)
			(layers "B.Cu" "B.Mask" "B.Paste")
			(net "FM_ADR_COMPLETE_GHJ_N")
		)
		(pad "231" smd rect
			(at -4.59994 78.199996 270)
			(size 1.8034 0.508)
			(layers "B.Cu" "B.Mask" "B.Paste")
			(net "PVDDQ_GHJ")
		)
		(pad "232" smd rect
			(at -4.59994 79.04988 270)
			(size 1.8034 0.508)
			(layers "B.Cu" "B.Mask" "B.Paste")
			(net "M_J_MA<13>")
		)
		(pad "233" smd rect
			(at -4.59994 79.900018 270)
			(size 1.8034 0.508)
			(layers "B.Cu" "B.Mask" "B.Paste")
			(net "PVDDQ_GHJ")
		)
		(pad "234" smd rect
			(at -4.59994 80.749902 270)
			(size 1.8034 0.508)
			(layers "B.Cu" "B.Mask" "B.Paste")
			(net "M_J_MA<17>")
		)
		(pad "235" smd rect
			(at -4.59994 81.60004 270)
			(size 1.8034 0.508)
			(layers "B.Cu" "B.Mask" "B.Paste")
			(net "M_J_C<2>")
		)
		(pad "236" smd rect
			(at -4.59994 82.449924 270)
			(size 1.8034 0.508)
			(layers "B.Cu" "B.Mask" "B.Paste")
			(net "PVDDQ_GHJ")
		)
		(pad "237" smd rect
			(at -4.59994 83.300062 270)
			(size 1.8034 0.508)
			(layers "B.Cu" "B.Mask" "B.Paste")
			(net "M_J_CS_N<7>")
		)
		(pad "238" smd rect
			(at -4.59994 84.149946 270)
			(size 1.8034 0.508)
			(layers "B.Cu" "B.Mask" "B.Paste")
			(net "PVPP_GHJ")
		)
		(pad "239" smd rect
			(at -4.59994 85.000084 270)
			(size 1.8034 0.508)
			(layers "B.Cu" "B.Mask" "B.Paste")
			(net "GND")
		)
		(pad "240" smd rect
			(at -4.59994 85.849968 270)
			(size 1.8034 0.508)
			(layers "B.Cu" "B.Mask" "B.Paste")
			(net "M_J_DQ<37>")
		)
		(pad "241" smd rect
			(at -4.59994 86.700106 270)
			(size 1.8034 0.508)
			(layers "B.Cu" "B.Mask" "B.Paste")
			(net "GND")
		)
		(pad "242" smd rect
			(at -4.59994 87.54999 270)
			(size 1.8034 0.508)
			(layers "B.Cu" "B.Mask" "B.Paste")
			(net "M_J_DQ<33>")
		)
		(pad "243" smd rect
			(at -4.59994 88.399874 270)
			(size 1.8034 0.508)
			(layers "B.Cu" "B.Mask" "B.Paste")
			(net "GND")
		)
		(pad "244" smd rect
			(at -4.59994 89.250012 270)
			(size 1.8034 0.508)
			(layers "B.Cu" "B.Mask" "B.Paste")
			(net "M_J_DQS_DN<4>")
		)
		(pad "245" smd rect
			(at -4.59994 90.099896 270)
			(size 1.8034 0.508)
			(layers "B.Cu" "B.Mask" "B.Paste")
			(net "M_J_DQS_DP<4>")
		)
		(pad "246" smd rect
			(at -4.59994 90.950034 270)
			(size 1.8034 0.508)
			(layers "B.Cu" "B.Mask" "B.Paste")
			(net "GND")
		)
		(pad "247" smd rect
			(at -4.59994 91.799918 270)
			(size 1.8034 0.508)
			(layers "B.Cu" "B.Mask" "B.Paste")
			(net "M_J_DQ<39>")
		)
		(pad "248" smd rect
			(at -4.59994 92.650056 270)
			(size 1.8034 0.508)
			(layers "B.Cu" "B.Mask" "B.Paste")
			(net "GND")
		)
		(pad "249" smd rect
			(at -4.59994 93.49994 270)
			(size 1.8034 0.508)
			(layers "B.Cu" "B.Mask" "B.Paste")
			(net "M_J_DQ<35>")
		)
		(pad "250" smd rect
			(at -4.59994 94.350078 270)
			(size 1.8034 0.508)
			(layers "B.Cu" "B.Mask" "B.Paste")
			(net "GND")
		)
		(pad "251" smd rect
			(at -4.59994 95.199962 270)
			(size 1.8034 0.508)
			(layers "B.Cu" "B.Mask" "B.Paste")
			(net "M_J_DQ<45>")
		)
		(pad "252" smd rect
			(at -4.59994 96.0501 270)
			(size 1.8034 0.508)
			(layers "B.Cu" "B.Mask" "B.Paste")
			(net "GND")
		)
		(pad "253" smd rect
			(at -4.59994 96.899984 270)
			(size 1.8034 0.508)
			(layers "B.Cu" "B.Mask" "B.Paste")
			(net "M_J_DQ<41>")
		)
		(pad "254" smd rect
			(at -4.59994 97.750122 270)
			(size 1.8034 0.508)
			(layers "B.Cu" "B.Mask" "B.Paste")
			(net "GND")
		)
		(pad "255" smd rect
			(at -4.59994 98.600006 270)
			(size 1.8034 0.508)
			(layers "B.Cu" "B.Mask" "B.Paste")
			(net "M_J_DQS_DN<5>")
		)
		(pad "256" smd rect
			(at -4.59994 99.44989 270)
			(size 1.8034 0.508)
			(layers "B.Cu" "B.Mask" "B.Paste")
			(net "M_J_DQS_DP<5>")
		)
		(pad "257" smd rect
			(at -4.59994 100.300028 270)
			(size 1.8034 0.508)
			(layers "B.Cu" "B.Mask" "B.Paste")
			(net "GND")
		)
		(pad "258" smd rect
			(at -4.59994 101.149912 270)
			(size 1.8034 0.508)
			(layers "B.Cu" "B.Mask" "B.Paste")
			(net "M_J_DQ<47>")
		)
		(pad "259" smd rect
			(at -4.59994 102.00005 270)
			(size 1.8034 0.508)
			(layers "B.Cu" "B.Mask" "B.Paste")
			(net "GND")
		)
		(pad "260" smd rect
			(at -4.59994 102.849934 270)
			(size 1.8034 0.508)
			(layers "B.Cu" "B.Mask" "B.Paste")
			(net "M_J_DQ<43>")
		)
		(pad "261" smd rect
			(at -4.59994 103.700072 270)
			(size 1.8034 0.508)
			(layers "B.Cu" "B.Mask" "B.Paste")
			(net "GND")
		)
		(pad "262" smd rect
			(at -4.59994 104.549956 270)
			(size 1.8034 0.508)
			(layers "B.Cu" "B.Mask" "B.Paste")
			(net "M_J_DQ<53>")
		)
		(pad "263" smd rect
			(at -4.59994 105.400094 270)
			(size 1.8034 0.508)
			(layers "B.Cu" "B.Mask" "B.Paste")
			(net "GND")
		)
		(pad "264" smd rect
			(at -4.59994 106.249978 270)
			(size 1.8034 0.508)
			(layers "B.Cu" "B.Mask" "B.Paste")
			(net "M_J_DQ<49>")
		)
		(pad "265" smd rect
			(at -4.59994 107.100116 270)
			(size 1.8034 0.508)
			(layers "B.Cu" "B.Mask" "B.Paste")
			(net "GND")
		)
		(pad "266" smd rect
			(at -4.59994 107.95 270)
			(size 1.8034 0.508)
			(layers "B.Cu" "B.Mask" "B.Paste")
			(net "M_J_DQS_DN<6>")
		)
		(pad "267" smd rect
			(at -4.59994 108.799884 270)
			(size 1.8034 0.508)
			(layers "B.Cu" "B.Mask" "B.Paste")
			(net "M_J_DQS_DP<6>")
		)
		(pad "268" smd rect
			(at -4.59994 109.650022 270)
			(size 1.8034 0.508)
			(layers "B.Cu" "B.Mask" "B.Paste")
			(net "GND")
		)
		(pad "269" smd rect
			(at -4.59994 110.499906 270)
			(size 1.8034 0.508)
			(layers "B.Cu" "B.Mask" "B.Paste")
			(net "M_J_DQ<55>")
		)
		(pad "270" smd rect
			(at -4.59994 111.350044 270)
			(size 1.8034 0.508)
			(layers "B.Cu" "B.Mask" "B.Paste")
			(net "GND")
		)
		(pad "271" smd rect
			(at -4.59994 112.199928 270)
			(size 1.8034 0.508)
			(layers "B.Cu" "B.Mask" "B.Paste")
			(net "M_J_DQ<51>")
		)
		(pad "272" smd rect
			(at -4.59994 113.050066 270)
			(size 1.8034 0.508)
			(layers "B.Cu" "B.Mask" "B.Paste")
			(net "GND")
		)
		(pad "273" smd rect
			(at -4.59994 113.89995 270)
			(size 1.8034 0.508)
			(layers "B.Cu" "B.Mask" "B.Paste")
			(net "M_J_DQ<61>")
		)
		(pad "274" smd rect
			(at -4.59994 114.750088 270)
			(size 1.8034 0.508)
			(layers "B.Cu" "B.Mask" "B.Paste")
			(net "GND")
		)
		(pad "275" smd rect
			(at -4.59994 115.599972 270)
			(size 1.8034 0.508)
			(layers "B.Cu" "B.Mask" "B.Paste")
			(net "M_J_DQ<57>")
		)
		(pad "276" smd rect
			(at -4.59994 116.45011 270)
			(size 1.8034 0.508)
			(layers "B.Cu" "B.Mask" "B.Paste")
			(net "GND")
		)
		(pad "277" smd rect
			(at -4.59994 117.299994 270)
			(size 1.8034 0.508)
			(layers "B.Cu" "B.Mask" "B.Paste")
			(net "M_J_DQS_DN<7>")
		)
		(pad "278" smd rect
			(at -4.59994 118.149878 270)
			(size 1.8034 0.508)
			(layers "B.Cu" "B.Mask" "B.Paste")
			(net "M_J_DQS_DP<7>")
		)
		(pad "279" smd rect
			(at -4.59994 119.000016 270)
			(size 1.8034 0.508)
			(layers "B.Cu" "B.Mask" "B.Paste")
			(net "GND")
		)
		(pad "280" smd rect
			(at -4.59994 119.8499 270)
			(size 1.8034 0.508)
			(layers "B.Cu" "B.Mask" "B.Paste")
			(net "M_J_DQ<63>")
		)
		(pad "281" smd rect
			(at -4.59994 120.700038 270)
			(size 1.8034 0.508)
			(layers "B.Cu" "B.Mask" "B.Paste")
			(net "GND")
		)
		(pad "282" smd rect
			(at -4.59994 121.549922 270)
			(size 1.8034 0.508)
			(layers "B.Cu" "B.Mask" "B.Paste")
			(net "M_J_DQ<59>")
		)
		(pad "283" smd rect
			(at -4.59994 122.40006 270)
			(size 1.8034 0.508)
			(layers "B.Cu" "B.Mask" "B.Paste")
			(net "GND")
		)
		(pad "284" smd rect
			(at -4.59994 123.249944 270)
			(size 1.8034 0.508)
			(layers "B.Cu" "B.Mask" "B.Paste")
			(net "PVPP_GHJ")
		)
		(pad "285" smd rect
			(at -4.59994 124.100082 270)
			(size 1.8034 0.508)
			(layers "B.Cu" "B.Mask" "B.Paste")
			(net "SMB_DDR_GHJ_VPP_SDA")
		)
		(pad "286" smd rect
			(at -4.59994 124.949966 270)
			(size 1.8034 0.508)
			(layers "B.Cu" "B.Mask" "B.Paste")
			(net "PVPP_GHJ")
		)
		(pad "287" smd rect
			(at -4.59994 125.800104 270)
			(size 1.8034 0.508)
			(layers "B.Cu" "B.Mask" "B.Paste")
			(net "PVPP_GHJ")
		)
		(pad "288" smd rect
			(at -4.59994 126.649988 270)
			(size 1.8034 0.508)
			(layers "B.Cu" "B.Mask" "B.Paste")
			(net "PVPP_GHJ")
		)
	)
	(footprint ""
		(layer "B.Cu")
		(at 498.602 -137.287 90)
		(property "Reference" "R1L44"
			(at 0 0 90)
			(layer "B.SilkS")
			(hide yes)
			(effects
				(font
					(size 1.27 1.27)
				)
				(justify mirror)
			)
		)
		(property "Value" ""
			(at 0 0 90)
			(layer "B.Fab")
			(effects
				(font
					(size 1.27 1.27)
				)
				(justify mirror)
			)
		)
		(duplicate_pad_numbers_are_jumpers no)
		(fp_poly
			(pts
				(xy 0.2794 -0.1016) (xy -0.2794 -0.1016) (xy -0.2794 0.9906) (xy 0.2794 0.9906)
			)
			(stroke
				(width 0)
				(type default)
			)
			(fill no)
			(layer "B.CrtYd")
		)
		(fp_line
			(start 0.2794 -0.1016)
			(end 0.2794 0.9906)
			(stroke
				(width 0.1)
				(type default)
			)
			(layer "B.Fab")
		)
		(fp_line
			(start -0.2794 -0.1016)
			(end 0.2794 -0.1016)
			(stroke
				(width 0.1)
				(type default)
			)
			(layer "B.Fab")
		)
		(fp_line
			(start 0.2794 0.9906)
			(end -0.2794 0.9906)
			(stroke
				(width 0.1)
				(type default)
			)
			(layer "B.Fab")
		)
		(fp_line
			(start -0.2794 0.9906)
			(end -0.2794 -0.1016)
			(stroke
				(width 0.1)
				(type default)
			)
			(layer "B.Fab")
		)
		(pad "1" smd rect
			(at 0 0 270)
			(size 0.508 0.508)
			(layers "B.Cu" "B.Mask" "B.Paste")
			(net "FM_UARTSW_MSB_R_N")
		)
		(pad "2" smd rect
			(at 0 0.889 270)
			(size 0.508 0.508)
			(layers "B.Cu" "B.Mask" "B.Paste")
			(net "P3V3_STBY")
		)
		(zone
			(layer "B.Cu")
			(hatch none 0.5)
			(connect_pads
				(clearance 0)
			)
			(min_thickness 0.25)
			(keepout
				(tracks allowed)
				(vias not_allowed)
				(pads allowed)
				(copperpour not_allowed)
				(footprints allowed)
			)
			(placement
				(enabled no)
				(sheetname "")
			)
			(fill
				(thermal_gap 0.5)
				(thermal_bridge_width 0.5)
				(island_removal_mode 0)
			)
			(polygon
				(pts
					(xy 498.856 -137.541) (xy 498.856 -137.033) (xy 499.237 -137.033) (xy 499.237 -137.541)
				)
			)
		)
		(zone
			(layer "B.Cu")
			(hatch none 0.5)
			(connect_pads
				(clearance 0)
			)
			(min_thickness 0.25)
			(keepout
				(tracks not_allowed)
				(vias allowed)
				(pads allowed)
				(copperpour not_allowed)
				(footprints allowed)
			)
			(placement
				(enabled no)
				(sheetname "")
			)
			(fill
				(thermal_gap 0.5)
				(thermal_bridge_width 0.5)
				(island_removal_mode 0)
			)
			(polygon
				(pts
					(xy 499.237 -137.541) (xy 499.237 -137.033) (xy 498.856 -137.033) (xy 498.856 -137.541)
				)
			)
		)
	)
	(footprint ""
		(layer "B.Cu")
		(at 155.064968 -154.782012 90)
		(property "Reference" "C7L2"
			(at 0 0 90)
			(layer "B.SilkS")
			(hide yes)
			(effects
				(font
					(size 1.27 1.27)
				)
				(justify mirror)
			)
		)
		(property "Value" ""
			(at 0 0 90)
			(layer "B.Fab")
			(effects
				(font
					(size 1.27 1.27)
				)
				(justify mirror)
			)
		)
		(duplicate_pad_numbers_are_jumpers no)
		(fp_rect
			(start 0.4953 1.6002)
			(end -0.4953 -0.2032)
			(stroke
				(width 0)
				(type default)
			)
			(fill no)
			(layer "B.CrtYd")
		)
		(fp_line
			(start 0.4953 -0.2032)
			(end -0.4953 -0.2032)
			(stroke
				(width 0.1)
				(type default)
			)
			(layer "B.Fab")
		)
		(fp_line
			(start -0.4953 -0.2032)
			(end -0.4953 1.6002)
			(stroke
				(width 0.1)
				(type default)
			)
			(layer "B.Fab")
		)
		(fp_line
			(start 0.4953 1.6002)
			(end 0.4953 -0.2032)
			(stroke
				(width 0.1)
				(type default)
			)
			(layer "B.Fab")
		)
		(fp_line
			(start -0.4953 1.6002)
			(end 0.4953 1.6002)
			(stroke
				(width 0.1)
				(type default)
			)
			(layer "B.Fab")
		)
		(pad "1" smd rect
			(at 0 0 270)
			(size 0.762 0.889)
			(layers "B.Cu" "B.Mask" "B.Paste")
			(net "PVPP_KLM")
		)
		(pad "2" smd rect
			(at 0 1.397 270)
			(size 0.762 0.889)
			(layers "B.Cu" "B.Mask" "B.Paste")
			(net "GND")
		)
		(zone
			(layer "B.Cu")
			(hatch none 0.5)
			(connect_pads
				(clearance 0)
			)
			(min_thickness 0.25)
			(keepout
				(tracks not_allowed)
				(vias allowed)
				(pads allowed)
				(copperpour not_allowed)
				(footprints allowed)
			)
			(placement
				(enabled no)
				(sheetname "")
			)
			(fill
				(thermal_gap 0.5)
				(thermal_bridge_width 0.5)
				(island_removal_mode 0)
			)
			(polygon
				(pts
					(xy 156.017468 -155.163012) (xy 155.509468 -155.163012) (xy 155.509468 -154.401012) (xy 156.017468 -154.401012)
				)
			)
		)
	)
	(footprint ""
		(layer "B.Cu")
		(at 338.76996 -77.694536 180)
		(property "Reference" "C3P11"
			(at 0 0 0)
			(layer "B.SilkS")
			(hide yes)
			(effects
				(font
					(size 1.27 1.27)
				)
				(justify mirror)
			)
		)
		(property "Value" ""
			(at 0 0 0)
			(layer "B.Fab")
			(effects
				(font
					(size 1.27 1.27)
				)
				(justify mirror)
			)
		)
		(duplicate_pad_numbers_are_jumpers no)
		(fp_poly
			(pts
				(xy -0.3048 -0.1016) (xy -0.3048 0.9906) (xy 0.3048 0.9906) (xy 0.3048 -0.1016)
			)
			(stroke
				(width 0)
				(type default)
			)
			(fill no)
			(layer "B.CrtYd")
		)
		(fp_line
			(start 0.3048 0.9906)
			(end -0.3048 0.9906)
			(stroke
				(width 0.1)
				(type default)
			)
			(layer "B.Fab")
		)
		(fp_line
			(start 0.3048 -0.1016)
			(end 0.3048 0.9906)
			(stroke
				(width 0.1)
				(type default)
			)
			(layer "B.Fab")
		)
		(fp_line
			(start -0.3048 0.9906)
			(end -0.3048 -0.1016)
			(stroke
				(width 0.1)
				(type default)
			)
			(layer "B.Fab")
		)
		(fp_line
			(start -0.3048 -0.1016)
			(end 0.3048 -0.1016)
			(stroke
				(width 0.1)
				(type default)
			)
			(layer "B.Fab")
		)
		(pad "1" smd rect
			(at 0 0)
			(size 0.508 0.508)
			(layers "B.Cu" "B.Mask" "B.Paste")
			(net "P3E_CPU0_PE1_SS_TXP<0>")
		)
		(pad "2" smd rect
			(at 0 0.889)
			(size 0.508 0.508)
			(layers "B.Cu" "B.Mask" "B.Paste")
			(net "P3E_CPU0_PE1_PCH_TXP<0>")
		)
		(zone
			(layer "B.Cu")
			(hatch none 0.5)
			(connect_pads
				(clearance 0)
			)
			(min_thickness 0.25)
			(keepout
				(tracks not_allowed)
				(vias allowed)
				(pads allowed)
				(copperpour not_allowed)
				(footprints allowed)
			)
			(placement
				(enabled no)
				(sheetname "")
			)
			(fill
				(thermal_gap 0.5)
				(thermal_bridge_width 0.5)
				(island_removal_mode 0)
			)
			(polygon
				(pts
					(xy 338.51596 -78.329536) (xy 339.02396 -78.329536) (xy 339.02396 -77.948536) (xy 338.51596 -77.948536)
				)
			)
		)
		(zone
			(layer "B.Cu")
			(hatch none 0.5)
			(connect_pads
				(clearance 0)
			)
			(min_thickness 0.25)
			(keepout
				(tracks allowed)
				(vias not_allowed)
				(pads allowed)
				(copperpour not_allowed)
				(footprints allowed)
			)
			(placement
				(enabled no)
				(sheetname "")
			)
			(fill
				(thermal_gap 0.5)
				(thermal_bridge_width 0.5)
				(island_removal_mode 0)
			)
			(polygon
				(pts
					(xy 338.51596 -77.948536) (xy 339.02396 -77.948536) (xy 339.02396 -78.329536) (xy 338.51596 -78.329536)
				)
			)
		)
	)
	(footprint ""
		(layer "B.Cu")
		(at 264.1346 -124.6886 -90)
		(property "Reference" "SH4L1"
			(at 0 0 90)
			(layer "B.SilkS")
			(hide yes)
			(effects
				(font
					(size 1.27 1.27)
				)
				(justify mirror)
			)
		)
		(property "Value" ""
			(at 0 0 90)
			(layer "B.Fab")
			(effects
				(font
					(size 1.27 1.27)
				)
				(justify mirror)
			)
		)
		(duplicate_pad_numbers_are_jumpers no)
		(fp_poly
			(pts
				(xy 0.1651 -0.0508) (xy 0.1651 0.5842) (xy -0.1651 0.5842) (xy -0.1651 -0.0508)
			)
			(stroke
				(width 0)
				(type default)
			)
			(fill no)
			(layer "B.CrtYd")
		)
		(fp_line
			(start -0.1651 0.5842)
			(end 0.1651 0.5842)
			(stroke
				(width 0.1)
				(type default)
			)
			(layer "B.Fab")
		)
		(fp_line
			(start 0.1651 0.5842)
			(end 0.1651 -0.0508)
			(stroke
				(width 0.1)
				(type default)
			)
			(layer "B.Fab")
		)
		(fp_line
			(start -0.1651 -0.0508)
			(end -0.1651 0.5842)
			(stroke
				(width 0.1)
				(type default)
			)
			(layer "B.Fab")
		)
		(fp_line
			(start 0.1651 -0.0508)
			(end -0.1651 -0.0508)
			(stroke
				(width 0.1)
				(type default)
			)
			(layer "B.Fab")
		)
		(pad "1" smd custom
			(at 0 0 270)
			(size 0.0762 0.0762)
			(layers "B.Cu" "B.Mask" "B.Paste")
			(net "VSENSE_PVDDQ_DEF_N")
			(options
				(clearance outline)
				(anchor circle)
			)
			(primitives
				(gr_poly
					(pts
						(arc
							(start -0.1524 0.10795)
							(mid -0.098518 0.130268)
							(end -0.0762 0.18415)
						)
						(xy -0.0762 0.22225) (xy 0.0762 0.22225)
						(arc
							(start 0.0762 0.18415)
							(mid 0.098518 0.130268)
							(end 0.1524 0.10795)
						)
						(xy 0.1524 -0.22225) (xy -0.1524 -0.22225)
					)
					(width 0)
					(fill yes)
				)
			)
		)
		(pad "2" smd custom
			(at 0 0.5334 90)
			(size 0.0762 0.0762)
			(layers "B.Cu" "B.Mask" "B.Paste")
			(net "GND")
			(options
				(clearance outline)
				(anchor circle)
			)
			(primitives
				(gr_poly
					(pts
						(arc
							(start -0.1524 0.10795)
							(mid -0.098518 0.130268)
							(end -0.0762 0.18415)
						)
						(xy -0.0762 0.22225) (xy 0.0762 0.22225)
						(arc
							(start 0.0762 0.18415)
							(mid 0.098518 0.130268)
							(end 0.1524 0.10795)
						)
						(xy 0.1524 -0.22225) (xy -0.1524 -0.22225)
					)
					(width 0)
					(fill yes)
				)
			)
		)
	)
	(footprint ""
		(layer "B.Cu")
		(at 455.676 -116.49202)
		(property "Reference" "C1M13"
			(at 0 0 0)
			(layer "B.SilkS")
			(hide yes)
			(effects
				(font
					(size 1.27 1.27)
				)
				(justify mirror)
			)
		)
		(property "Value" ""
			(at 0 0 0)
			(layer "B.Fab")
			(effects
				(font
					(size 1.27 1.27)
				)
				(justify mirror)
			)
		)
		(duplicate_pad_numbers_are_jumpers no)
		(fp_rect
			(start -0.3048 0.9906)
			(end 0.3048 -0.1016)
			(stroke
				(width 0)
				(type default)
			)
			(fill no)
			(layer "B.CrtYd")
		)
		(fp_line
			(start -0.3048 -0.1016)
			(end 0.3048 -0.1016)
			(stroke
				(width 0.1)
				(type default)
			)
			(layer "B.Fab")
		)
		(fp_line
			(start -0.3048 0.9906)
			(end -0.3048 -0.1016)
			(stroke
				(width 0.1)
				(type default)
			)
			(layer "B.Fab")
		)
		(fp_line
			(start 0.3048 -0.1016)
			(end 0.3048 0.9906)
			(stroke
				(width 0.1)
				(type default)
			)
			(layer "B.Fab")
		)
		(fp_line
			(start 0.3048 0.9906)
			(end -0.3048 0.9906)
			(stroke
				(width 0.1)
				(type default)
			)
			(layer "B.Fab")
		)
		(pad "1" smd rect
			(at 0 0 180)
			(size 0.508 0.508)
			(layers "B.Cu" "B.Mask" "B.Paste")
			(net "P3E_CPU0_PE3_OCP_TXN<12>")
		)
		(pad "2" smd rect
			(at 0 0.889 180)
			(size 0.508 0.508)
			(layers "B.Cu" "B.Mask" "B.Paste")
			(net "P3E_OCP_CPU0_PE3_C_TXN<12>")
		)
		(zone
			(layer "B.Cu")
			(hatch none 0.5)
			(connect_pads
				(clearance 0)
			)
			(min_thickness 0.25)
			(keepout
				(tracks allowed)
				(vias not_allowed)
				(pads allowed)
				(copperpour not_allowed)
				(footprints allowed)
			)
			(placement
				(enabled no)
				(sheetname "")
			)
			(fill
				(thermal_gap 0.5)
				(thermal_bridge_width 0.5)
				(island_removal_mode 0)
			)
			(polygon
				(pts
					(xy 455.422 -115.85702) (xy 455.93 -115.85702) (xy 455.93 -116.23802) (xy 455.422 -116.23802)
				)
			)
		)
		(zone
			(layer "B.Cu")
			(hatch none 0.5)
			(connect_pads
				(clearance 0)
			)
			(min_thickness 0.25)
			(keepout
				(tracks not_allowed)
				(vias allowed)
				(pads allowed)
				(copperpour not_allowed)
				(footprints allowed)
			)
			(placement
				(enabled no)
				(sheetname "")
			)
			(fill
				(thermal_gap 0.5)
				(thermal_bridge_width 0.5)
				(island_removal_mode 0)
			)
			(polygon
				(pts
					(xy 455.422 -115.85702) (xy 455.93 -115.85702) (xy 455.93 -116.23802) (xy 455.422 -116.23802)
				)
			)
		)
	)
	(footprint ""
		(layer "B.Cu")
		(at 427.9519 -18.034 90)
		(property "Reference" "R1U22"
			(at 0 0 90)
			(layer "B.SilkS")
			(hide yes)
			(effects
				(font
					(size 1.27 1.27)
				)
				(justify mirror)
			)
		)
		(property "Value" ""
			(at 0 0 90)
			(layer "B.Fab")
			(effects
				(font
					(size 1.27 1.27)
				)
				(justify mirror)
			)
		)
		(duplicate_pad_numbers_are_jumpers no)
		(fp_poly
			(pts
				(xy 0.2794 -0.1016) (xy -0.2794 -0.1016) (xy -0.2794 0.9906) (xy 0.2794 0.9906)
			)
			(stroke
				(width 0)
				(type default)
			)
			(fill no)
			(layer "B.CrtYd")
		)
		(fp_line
			(start 0.2794 -0.1016)
			(end 0.2794 0.9906)
			(stroke
				(width 0.1)
				(type default)
			)
			(layer "B.Fab")
		)
		(fp_line
			(start -0.2794 -0.1016)
			(end 0.2794 -0.1016)
			(stroke
				(width 0.1)
				(type default)
			)
			(layer "B.Fab")
		)
		(fp_line
			(start 0.2794 0.9906)
			(end -0.2794 0.9906)
			(stroke
				(width 0.1)
				(type default)
			)
			(layer "B.Fab")
		)
		(fp_line
			(start -0.2794 0.9906)
			(end -0.2794 -0.1016)
			(stroke
				(width 0.1)
				(type default)
			)
			(layer "B.Fab")
		)
		(pad "1" smd rect
			(at 0 0 270)
			(size 0.508 0.508)
			(layers "B.Cu" "B.Mask" "B.Paste")
			(net "P3V3_STBY")
		)
		(pad "2" smd rect
			(at 0 0.889 270)
			(size 0.508 0.508)
			(layers "B.Cu" "B.Mask" "B.Paste")
			(net "FM_BOARD_SKU_ID1")
		)
		(zone
			(layer "B.Cu")
			(hatch none 0.5)
			(connect_pads
				(clearance 0)
			)
			(min_thickness 0.25)
			(keepout
				(tracks allowed)
				(vias not_allowed)
				(pads allowed)
				(copperpour not_allowed)
				(footprints allowed)
			)
			(placement
				(enabled no)
				(sheetname "")
			)
			(fill
				(thermal_gap 0.5)
				(thermal_bridge_width 0.5)
				(island_removal_mode 0)
			)
			(polygon
				(pts
					(xy 428.2059 -18.288) (xy 428.2059 -17.78) (xy 428.5869 -17.78) (xy 428.5869 -18.288)
				)
			)
		)
		(zone
			(layer "B.Cu")
			(hatch none 0.5)
			(connect_pads
				(clearance 0)
			)
			(min_thickness 0.25)
			(keepout
				(tracks not_allowed)
				(vias allowed)
				(pads allowed)
				(copperpour not_allowed)
				(footprints allowed)
			)
			(placement
				(enabled no)
				(sheetname "")
			)
			(fill
				(thermal_gap 0.5)
				(thermal_bridge_width 0.5)
				(island_removal_mode 0)
			)
			(polygon
				(pts
					(xy 428.5869 -18.288) (xy 428.5869 -17.78) (xy 428.2059 -17.78) (xy 428.2059 -18.288)
				)
			)
		)
	)
	(footprint ""
		(layer "B.Cu")
		(at 265.864086 -73.51014)
		(property "Reference" "C5P33"
			(at 0 0 0)
			(layer "B.SilkS")
			(hide yes)
			(effects
				(font
					(size 1.27 1.27)
				)
				(justify mirror)
			)
		)
		(property "Value" ""
			(at 0 0 0)
			(layer "B.Fab")
			(effects
				(font
					(size 1.27 1.27)
				)
				(justify mirror)
			)
		)
		(duplicate_pad_numbers_are_jumpers no)
		(fp_poly
			(pts
				(xy 0.7239 -0.2159) (xy -0.7239 -0.2159) (xy -0.7239 1.9939) (xy 0.7239 1.9939)
			)
			(stroke
				(width 0)
				(type default)
			)
			(fill no)
			(layer "B.CrtYd")
		)
		(fp_line
			(start -0.7239 -0.2159)
			(end 0.7239 -0.2159)
			(stroke
				(width 0.1)
				(type default)
			)
			(layer "B.Fab")
		)
		(fp_line
			(start -0.7239 1.9939)
			(end -0.7239 -0.2159)
			(stroke
				(width 0.1)
				(type default)
			)
			(layer "B.Fab")
		)
		(fp_line
			(start 0.7239 -0.2159)
			(end 0.7239 1.9939)
			(stroke
				(width 0.1)
				(type default)
			)
			(layer "B.Fab")
		)
		(fp_line
			(start 0.7239 1.9939)
			(end -0.7239 1.9939)
			(stroke
				(width 0.1)
				(type default)
			)
			(layer "B.Fab")
		)
		(pad "1" smd rect
			(at 0 0 180)
			(size 1.27 1.016)
			(layers "B.Cu" "B.Mask" "B.Paste")
			(net "PVCCIN_CPU0")
		)
		(pad "2" smd rect
			(at 0 1.778 180)
			(size 1.27 1.016)
			(layers "B.Cu" "B.Mask" "B.Paste")
			(net "GND")
		)
		(zone
			(layer "B.Cu")
			(hatch none 0.5)
			(connect_pads
				(clearance 0)
			)
			(min_thickness 0.25)
			(keepout
				(tracks not_allowed)
				(vias allowed)
				(pads allowed)
				(copperpour not_allowed)
				(footprints allowed)
			)
			(placement
				(enabled no)
				(sheetname "")
			)
			(fill
				(thermal_gap 0.5)
				(thermal_bridge_width 0.5)
				(island_removal_mode 0)
			)
			(polygon
				(pts
					(xy 266.499086 -73.00214) (xy 265.229086 -73.00214) (xy 265.229086 -72.24014) (xy 266.499086 -72.24014)
				)
			)
		)
	)
	(footprint ""
		(layer "B.Cu")
		(at 3.8227 -9.564116 90)
		(property "Reference" "C9U4"
			(at 0 0 90)
			(layer "B.SilkS")
			(hide yes)
			(effects
				(font
					(size 1.27 1.27)
				)
				(justify mirror)
			)
		)
		(property "Value" ""
			(at 0 0 90)
			(layer "B.Fab")
			(effects
				(font
					(size 1.27 1.27)
				)
				(justify mirror)
			)
		)
		(duplicate_pad_numbers_are_jumpers no)
		(fp_rect
			(start -0.7239 -0.2159)
			(end 0.7239 1.9939)
			(stroke
				(width 0)
				(type default)
			)
			(fill no)
			(layer "B.CrtYd")
		)
		(fp_line
			(start 0.7239 -0.2159)
			(end 0.7239 1.9939)
			(stroke
				(width 0.1)
				(type default)
			)
			(layer "B.Fab")
		)
		(fp_line
			(start -0.7239 -0.2159)
			(end 0.7239 -0.2159)
			(stroke
				(width 0.1)
				(type default)
			)
			(layer "B.Fab")
		)
		(fp_line
			(start 0.7239 1.9939)
			(end -0.7239 1.9939)
			(stroke
				(width 0.1)
				(type default)
			)
			(layer "B.Fab")
		)
		(fp_line
			(start -0.7239 1.9939)
			(end -0.7239 -0.2159)
			(stroke
				(width 0.1)
				(type default)
			)
			(layer "B.Fab")
		)
		(pad "1" smd rect
			(at 0 0 270)
			(size 1.27 1.016)
			(layers "B.Cu" "B.Mask" "B.Paste")
			(net "VR_FET_SW_P12V_STBY_PVDDQ_GHJ")
		)
		(pad "2" smd rect
			(at 0 1.778 270)
			(size 1.27 1.016)
			(layers "B.Cu" "B.Mask" "B.Paste")
			(net "GND")
		)
		(zone
			(layer "B.Cu")
			(hatch none 0.5)
			(connect_pads
				(clearance 0)
			)
			(min_thickness 0.25)
			(keepout
				(tracks not_allowed)
				(vias allowed)
				(pads allowed)
				(copperpour not_allowed)
				(footprints allowed)
			)
			(placement
				(enabled no)
				(sheetname "")
			)
			(fill
				(thermal_gap 0.5)
				(thermal_bridge_width 0.5)
				(island_removal_mode 0)
			)
			(polygon
				(pts
					(xy 4.3307 -8.929116) (xy 5.0927 -8.929116) (xy 5.0927 -10.199116) (xy 4.3307 -10.199116)
				)
			)
		)
	)
	(footprint ""
		(layer "B.Cu")
		(at 338.934806 -60.368434)
		(property "Reference" "R2U18"
			(at 0 0 0)
			(layer "B.SilkS")
			(hide yes)
			(effects
				(font
					(size 1.27 1.27)
				)
				(justify mirror)
			)
		)
		(property "Value" ""
			(at 0 0 0)
			(layer "B.Fab")
			(effects
				(font
					(size 1.27 1.27)
				)
				(justify mirror)
			)
		)
		(duplicate_pad_numbers_are_jumpers no)
		(fp_poly
			(pts
				(xy 0.2794 -0.1016) (xy -0.2794 -0.1016) (xy -0.2794 0.9906) (xy 0.2794 0.9906)
			)
			(stroke
				(width 0)
				(type default)
			)
			(fill no)
			(layer "B.CrtYd")
		)
		(fp_line
			(start -0.2794 -0.1016)
			(end 0.2794 -0.1016)
			(stroke
				(width 0.1)
				(type default)
			)
			(layer "B.Fab")
		)
		(fp_line
			(start -0.2794 0.9906)
			(end -0.2794 -0.1016)
			(stroke
				(width 0.1)
				(type default)
			)
			(layer "B.Fab")
		)
		(fp_line
			(start 0.2794 -0.1016)
			(end 0.2794 0.9906)
			(stroke
				(width 0.1)
				(type default)
			)
			(layer "B.Fab")
		)
		(fp_line
			(start 0.2794 0.9906)
			(end -0.2794 0.9906)
			(stroke
				(width 0.1)
				(type default)
			)
			(layer "B.Fab")
		)
		(pad "1" smd rect
			(at 0 0 180)
			(size 0.508 0.508)
			(layers "B.Cu" "B.Mask" "B.Paste")
			(net "P3E_CPU0_PE1_SS_RXP<2>")
		)
		(pad "2" smd rect
			(at 0 0.889 180)
			(size 0.508 0.508)
			(layers "B.Cu" "B.Mask" "B.Paste")
			(net "P3E_CPU0_PE1_SS_R_RXP<2>")
		)
		(zone
			(layer "B.Cu")
			(hatch none 0.5)
			(connect_pads
				(clearance 0)
			)
			(min_thickness 0.25)
			(keepout
				(tracks allowed)
				(vias not_allowed)
				(pads allowed)
				(copperpour not_allowed)
				(footprints allowed)
			)
			(placement
				(enabled no)
				(sheetname "")
			)
			(fill
				(thermal_gap 0.5)
				(thermal_bridge_width 0.5)
				(island_removal_mode 0)
			)
			(polygon
				(pts
					(xy 339.188806 -60.114434) (xy 338.680806 -60.114434) (xy 338.680806 -59.733434) (xy 339.188806 -59.733434)
				)
			)
		)
		(zone
			(layer "B.Cu")
			(hatch none 0.5)
			(connect_pads
				(clearance 0)
			)
			(min_thickness 0.25)
			(keepout
				(tracks not_allowed)
				(vias allowed)
				(pads allowed)
				(copperpour not_allowed)
				(footprints allowed)
			)
			(placement
				(enabled no)
				(sheetname "")
			)
			(fill
				(thermal_gap 0.5)
				(thermal_bridge_width 0.5)
				(island_removal_mode 0)
			)
			(polygon
				(pts
					(xy 339.188806 -59.733434) (xy 338.680806 -59.733434) (xy 338.680806 -60.114434) (xy 339.188806 -60.114434)
				)
			)
		)
	)
	(footprint ""
		(layer "B.Cu")
		(at 383.73685 -106.25455)
		(property "Reference" "C3N19"
			(at 0 0 0)
			(layer "B.SilkS")
			(hide yes)
			(effects
				(font
					(size 1.27 1.27)
				)
				(justify mirror)
			)
		)
		(property "Value" ""
			(at 0 0 0)
			(layer "B.Fab")
			(effects
				(font
					(size 1.27 1.27)
				)
				(justify mirror)
			)
		)
		(duplicate_pad_numbers_are_jumpers no)
		(fp_rect
			(start 0.2794 0.9144)
			(end -0.2794 -0.1143)
			(stroke
				(width 0)
				(type default)
			)
			(fill no)
			(layer "B.CrtYd")
		)
		(fp_line
			(start -0.2794 -0.1143)
			(end -0.2794 0.9144)
			(stroke
				(width 0.1)
				(type default)
			)
			(layer "B.Fab")
		)
		(fp_line
			(start -0.2794 0.9144)
			(end 0.2794 0.9144)
			(stroke
				(width 0.1)
				(type default)
			)
			(layer "B.Fab")
		)
		(fp_line
			(start 0.2794 -0.1143)
			(end -0.2794 -0.1143)
			(stroke
				(width 0.1)
				(type default)
			)
			(layer "B.Fab")
		)
		(fp_line
			(start 0.2794 0.9144)
			(end 0.2794 -0.1143)
			(stroke
				(width 0.1)
				(type default)
			)
			(layer "B.Fab")
		)
		(pad "1" smd custom
			(at 0 0 270)
			(size 0.10414 0.10414)
			(layers "B.Cu" "B.Mask" "B.Paste")
			(net "PVNN_PCH_STBY")
			(options
				(clearance outline)
				(anchor circle)
			)
			(primitives
				(gr_poly
					(pts
						(xy -0.20828 -0.08636) (xy -0.20828 0.08636) (xy -0.08636 0.20828) (xy 0.086614 0.20828) (xy 0.20828 0.086614)
						(xy 0.20828 -0.08636) (xy 0.08636 -0.20828) (xy -0.08636 -0.20828)
					)
					(width 0)
					(fill yes)
				)
			)
		)
		(pad "2" smd custom
			(at 0 0.8001 270)
			(size 0.10414 0.10414)
			(layers "B.Cu" "B.Mask" "B.Paste")
			(net "GND")
			(options
				(clearance outline)
				(anchor circle)
			)
			(primitives
				(gr_poly
					(pts
						(xy -0.20828 -0.08636) (xy -0.20828 0.08636) (xy -0.08636 0.20828) (xy 0.086614 0.20828) (xy 0.20828 0.086614)
						(xy 0.20828 -0.08636) (xy 0.08636 -0.20828) (xy -0.08636 -0.20828)
					)
					(width 0)
					(fill yes)
				)
			)
		)
		(zone
			(layer "B.Cu")
			(hatch none 0.5)
			(connect_pads
				(clearance 0)
			)
			(min_thickness 0.25)
			(keepout
				(tracks allowed)
				(vias not_allowed)
				(pads allowed)
				(copperpour not_allowed)
				(footprints allowed)
			)
			(placement
				(enabled no)
				(sheetname "")
			)
			(fill
				(thermal_gap 0.5)
				(thermal_bridge_width 0.5)
				(island_removal_mode 0)
			)
			(polygon
				(pts
					(xy 383.82448 -106.045) (xy 383.82448 -105.664) (xy 383.64922 -105.664) (xy 383.648966 -106.045)
				)
			)
		)
		(zone
			(layer "B.Cu")
			(hatch none 0.5)
			(connect_pads
				(clearance 0)
			)
			(min_thickness 0.25)
			(keepout
				(tracks not_allowed)
				(vias allowed)
				(pads allowed)
				(copperpour not_allowed)
				(footprints allowed)
			)
			(placement
				(enabled no)
				(sheetname "")
			)
			(fill
				(thermal_gap 0.5)
				(thermal_bridge_width 0.5)
				(island_removal_mode 0)
			)
			(polygon
				(pts
					(xy 383.82448 -106.045) (xy 383.82448 -105.664) (xy 383.64922 -105.664) (xy 383.648966 -106.045)
				)
			)
		)
	)
	(footprint ""
		(layer "B.Cu")
		(at 326.3519 -124.1298 -90)
		(property "Reference" "C7E1"
			(at 0 0 90)
			(layer "B.SilkS")
			(hide yes)
			(effects
				(font
					(size 1.27 1.27)
				)
				(justify mirror)
			)
		)
		(property "Value" ""
			(at 0 0 90)
			(layer "B.Fab")
			(effects
				(font
					(size 1.27 1.27)
				)
				(justify mirror)
			)
		)
		(duplicate_pad_numbers_are_jumpers no)
		(fp_poly
			(pts
				(xy -0.3048 -0.1016) (xy -0.3048 0.9906) (xy 0.3048 0.9906) (xy 0.3048 -0.1016)
			)
			(stroke
				(width 0)
				(type default)
			)
			(fill no)
			(layer "B.CrtYd")
		)
		(fp_line
			(start -0.3048 0.9906)
			(end -0.3048 -0.1016)
			(stroke
				(width 0.1)
				(type default)
			)
			(layer "B.Fab")
		)
		(fp_line
			(start 0.3048 0.9906)
			(end -0.3048 0.9906)
			(stroke
				(width 0.1)
				(type default)
			)
			(layer "B.Fab")
		)
		(fp_line
			(start -0.3048 -0.1016)
			(end 0.3048 -0.1016)
			(stroke
				(width 0.1)
				(type default)
			)
			(layer "B.Fab")
		)
		(fp_line
			(start 0.3048 -0.1016)
			(end 0.3048 0.9906)
			(stroke
				(width 0.1)
				(type default)
			)
			(layer "B.Fab")
		)
		(pad "1" smd rect
			(at 0 0 90)
			(size 0.508 0.508)
			(layers "B.Cu" "B.Mask" "B.Paste")
			(net "PVCCIO_CPU0")
		)
		(pad "2" smd rect
			(at 0 0.889 90)
			(size 0.508 0.508)
			(layers "B.Cu" "B.Mask" "B.Paste")
			(net "GND")
		)
		(zone
			(layer "B.Cu")
			(hatch none 0.5)
			(connect_pads
				(clearance 0)
			)
			(min_thickness 0.25)
			(keepout
				(tracks not_allowed)
				(vias allowed)
				(pads allowed)
				(copperpour not_allowed)
				(footprints allowed)
			)
			(placement
				(enabled no)
				(sheetname "")
			)
			(fill
				(thermal_gap 0.5)
				(thermal_bridge_width 0.5)
				(island_removal_mode 0)
			)
			(polygon
				(pts
					(xy 325.7169 -123.8758) (xy 325.7169 -124.3838) (xy 326.0979 -124.3838) (xy 326.0979 -123.8758)
				)
			)
		)
		(zone
			(layer "B.Cu")
			(hatch none 0.5)
			(connect_pads
				(clearance 0)
			)
			(min_thickness 0.25)
			(keepout
				(tracks allowed)
				(vias not_allowed)
				(pads allowed)
				(copperpour not_allowed)
				(footprints allowed)
			)
			(placement
				(enabled no)
				(sheetname "")
			)
			(fill
				(thermal_gap 0.5)
				(thermal_bridge_width 0.5)
				(island_removal_mode 0)
			)
			(polygon
				(pts
					(xy 326.0979 -123.8758) (xy 326.0979 -124.3838) (xy 325.7169 -124.3838) (xy 325.7169 -123.8758)
				)
			)
		)
	)
	(footprint ""
		(layer "B.Cu")
		(at 388.366 -87.3125 180)
		(property "Reference" "R8D11"
			(at 0.8382 -0.67818 180)
			(unlocked yes)
			(layer "B.SilkS")
			(effects
				(font
					(size 0.4064 0.254)
					(thickness 0.1524)
				)
				(justify left mirror)
			)
		)
		(property "Value" ""
			(at 0 0 0)
			(layer "B.Fab")
			(effects
				(font
					(size 1.27 1.27)
				)
				(justify mirror)
			)
		)
		(duplicate_pad_numbers_are_jumpers no)
		(fp_poly
			(pts
				(xy 0.2794 -0.1016) (xy -0.2794 -0.1016) (xy -0.2794 0.9906) (xy 0.2794 0.9906)
			)
			(stroke
				(width 0)
				(type default)
			)
			(fill no)
			(layer "B.CrtYd")
		)
		(fp_line
			(start 0.2794 0.9906)
			(end -0.2794 0.9906)
			(stroke
				(width 0.1)
				(type default)
			)
			(layer "B.Fab")
		)
		(fp_line
			(start 0.2794 -0.1016)
			(end 0.2794 0.9906)
			(stroke
				(width 0.1)
				(type default)
			)
			(layer "B.Fab")
		)
		(fp_line
			(start -0.2794 0.9906)
			(end -0.2794 -0.1016)
			(stroke
				(width 0.1)
				(type default)
			)
			(layer "B.Fab")
		)
		(fp_line
			(start -0.2794 -0.1016)
			(end 0.2794 -0.1016)
			(stroke
				(width 0.1)
				(type default)
			)
			(layer "B.Fab")
		)
		(pad "1" smd rect
			(at 0 0)
			(size 0.508 0.508)
			(layers "B.Cu" "B.Mask" "B.Paste")
			(net "RMII_PCH_SPRNGVLLE_ARB_OUT")
		)
		(pad "2" smd rect
			(at 0 0.889)
			(size 0.508 0.508)
			(layers "B.Cu" "B.Mask" "B.Paste")
			(net "RMII_PCH_SPRNGVLLE_ARB_OUT_R")
		)
		(zone
			(layer "B.Cu")
			(hatch none 0.5)
			(connect_pads
				(clearance 0)
			)
			(min_thickness 0.25)
			(keepout
				(tracks not_allowed)
				(vias allowed)
				(pads allowed)
				(copperpour not_allowed)
				(footprints allowed)
			)
			(placement
				(enabled no)
				(sheetname "")
			)
			(fill
				(thermal_gap 0.5)
				(thermal_bridge_width 0.5)
				(island_removal_mode 0)
			)
			(polygon
				(pts
					(xy 388.112 -87.9475) (xy 388.62 -87.9475) (xy 388.62 -87.5665) (xy 388.112 -87.5665)
				)
			)
		)
		(zone
			(layer "B.Cu")
			(hatch none 0.5)
			(connect_pads
				(clearance 0)
			)
			(min_thickness 0.25)
			(keepout
				(tracks allowed)
				(vias not_allowed)
				(pads allowed)
				(copperpour not_allowed)
				(footprints allowed)
			)
			(placement
				(enabled no)
				(sheetname "")
			)
			(fill
				(thermal_gap 0.5)
				(thermal_bridge_width 0.5)
				(island_removal_mode 0)
			)
			(polygon
				(pts
					(xy 388.112 -87.5665) (xy 388.62 -87.5665) (xy 388.62 -87.9475) (xy 388.112 -87.9475)
				)
			)
		)
	)
	(footprint ""
		(layer "B.Cu")
		(at 495.28476 -124.0663 180)
		(property "Reference" "R1M11"
			(at 0 0 0)
			(layer "B.SilkS")
			(hide yes)
			(effects
				(font
					(size 1.27 1.27)
				)
				(justify mirror)
			)
		)
		(property "Value" ""
			(at 0 0 0)
			(layer "B.Fab")
			(effects
				(font
					(size 1.27 1.27)
				)
				(justify mirror)
			)
		)
		(duplicate_pad_numbers_are_jumpers no)
		(fp_poly
			(pts
				(xy 0.2794 -0.1016) (xy -0.2794 -0.1016) (xy -0.2794 0.9906) (xy 0.2794 0.9906)
			)
			(stroke
				(width 0)
				(type default)
			)
			(fill no)
			(layer "B.CrtYd")
		)
		(fp_line
			(start 0.2794 0.9906)
			(end -0.2794 0.9906)
			(stroke
				(width 0.1)
				(type default)
			)
			(layer "B.Fab")
		)
		(fp_line
			(start 0.2794 -0.1016)
			(end 0.2794 0.9906)
			(stroke
				(width 0.1)
				(type default)
			)
			(layer "B.Fab")
		)
		(fp_line
			(start -0.2794 0.9906)
			(end -0.2794 -0.1016)
			(stroke
				(width 0.1)
				(type default)
			)
			(layer "B.Fab")
		)
		(fp_line
			(start -0.2794 -0.1016)
			(end 0.2794 -0.1016)
			(stroke
				(width 0.1)
				(type default)
			)
			(layer "B.Fab")
		)
		(pad "1" smd rect
			(at 0 0)
			(size 0.508 0.508)
			(layers "B.Cu" "B.Mask" "B.Paste")
			(net "P3V3")
		)
		(pad "2" smd rect
			(at 0 0.889)
			(size 0.508 0.508)
			(layers "B.Cu" "B.Mask" "B.Paste")
			(net "LED_SATA_ACT_R_N")
		)
		(zone
			(layer "B.Cu")
			(hatch none 0.5)
			(connect_pads
				(clearance 0)
			)
			(min_thickness 0.25)
			(keepout
				(tracks not_allowed)
				(vias allowed)
				(pads allowed)
				(copperpour not_allowed)
				(footprints allowed)
			)
			(placement
				(enabled no)
				(sheetname "")
			)
			(fill
				(thermal_gap 0.5)
				(thermal_bridge_width 0.5)
				(island_removal_mode 0)
			)
			(polygon
				(pts
					(xy 495.03076 -124.7013) (xy 495.53876 -124.7013) (xy 495.53876 -124.3203) (xy 495.03076 -124.3203)
				)
			)
		)
		(zone
			(layer "B.Cu")
			(hatch none 0.5)
			(connect_pads
				(clearance 0)
			)
			(min_thickness 0.25)
			(keepout
				(tracks allowed)
				(vias not_allowed)
				(pads allowed)
				(copperpour not_allowed)
				(footprints allowed)
			)
			(placement
				(enabled no)
				(sheetname "")
			)
			(fill
				(thermal_gap 0.5)
				(thermal_bridge_width 0.5)
				(island_removal_mode 0)
			)
			(polygon
				(pts
					(xy 495.03076 -124.3203) (xy 495.53876 -124.3203) (xy 495.53876 -124.7013) (xy 495.03076 -124.7013)
				)
			)
		)
	)
	(footprint ""
		(layer "B.Cu")
		(at 412.329884 -47.822104 -90)
		(property "Reference" "R8F38"
			(at 0 0 90)
			(layer "B.SilkS")
			(hide yes)
			(effects
				(font
					(size 1.27 1.27)
				)
				(justify mirror)
			)
		)
		(property "Value" ""
			(at 0 0 90)
			(layer "B.Fab")
			(effects
				(font
					(size 1.27 1.27)
				)
				(justify mirror)
			)
		)
		(duplicate_pad_numbers_are_jumpers no)
		(fp_poly
			(pts
				(xy 0.2794 -0.1016) (xy -0.2794 -0.1016) (xy -0.2794 0.9906) (xy 0.2794 0.9906)
			)
			(stroke
				(width 0)
				(type default)
			)
			(fill no)
			(layer "B.CrtYd")
		)
		(fp_line
			(start -0.2794 0.9906)
			(end -0.2794 -0.1016)
			(stroke
				(width 0.1)
				(type default)
			)
			(layer "B.Fab")
		)
		(fp_line
			(start 0.2794 0.9906)
			(end -0.2794 0.9906)
			(stroke
				(width 0.1)
				(type default)
			)
			(layer "B.Fab")
		)
		(fp_line
			(start -0.2794 -0.1016)
			(end 0.2794 -0.1016)
			(stroke
				(width 0.1)
				(type default)
			)
			(layer "B.Fab")
		)
		(fp_line
			(start 0.2794 -0.1016)
			(end 0.2794 0.9906)
			(stroke
				(width 0.1)
				(type default)
			)
			(layer "B.Fab")
		)
		(pad "1" smd rect
			(at 0 0 90)
			(size 0.508 0.508)
			(layers "B.Cu" "B.Mask" "B.Paste")
			(net "FM_CPU_ERR0_LVT3_N")
		)
		(pad "2" smd rect
			(at 0 0.889 90)
			(size 0.508 0.508)
			(layers "B.Cu" "B.Mask" "B.Paste")
			(net "FM_CPU_ERR0_LVT3_BMC_N")
		)
		(zone
			(layer "B.Cu")
			(hatch none 0.5)
			(connect_pads
				(clearance 0)
			)
			(min_thickness 0.25)
			(keepout
				(tracks not_allowed)
				(vias allowed)
				(pads allowed)
				(copperpour not_allowed)
				(footprints allowed)
			)
			(placement
				(enabled no)
				(sheetname "")
			)
			(fill
				(thermal_gap 0.5)
				(thermal_bridge_width 0.5)
				(island_removal_mode 0)
			)
			(polygon
				(pts
					(xy 411.694884 -47.568104) (xy 411.694884 -48.076104) (xy 412.075884 -48.076104) (xy 412.075884 -47.568104)
				)
			)
		)
		(zone
			(layer "B.Cu")
			(hatch none 0.5)
			(connect_pads
				(clearance 0)
			)
			(min_thickness 0.25)
			(keepout
				(tracks allowed)
				(vias not_allowed)
				(pads allowed)
				(copperpour not_allowed)
				(footprints allowed)
			)
			(placement
				(enabled no)
				(sheetname "")
			)
			(fill
				(thermal_gap 0.5)
				(thermal_bridge_width 0.5)
				(island_removal_mode 0)
			)
			(polygon
				(pts
					(xy 412.075884 -47.568104) (xy 412.075884 -48.076104) (xy 411.694884 -48.076104) (xy 411.694884 -47.568104)
				)
			)
		)
	)
	(footprint ""
		(layer "B.Cu")
		(at 106.223054 -85.06714)
		(property "Reference" "C8P3"
			(at 0 0 0)
			(layer "B.SilkS")
			(hide yes)
			(effects
				(font
					(size 1.27 1.27)
				)
				(justify mirror)
			)
		)
		(property "Value" ""
			(at 0 0 0)
			(layer "B.Fab")
			(effects
				(font
					(size 1.27 1.27)
				)
				(justify mirror)
			)
		)
		(duplicate_pad_numbers_are_jumpers no)
		(fp_poly
			(pts
				(xy 0.7239 -0.2159) (xy -0.7239 -0.2159) (xy -0.7239 1.9939) (xy 0.7239 1.9939)
			)
			(stroke
				(width 0)
				(type default)
			)
			(fill no)
			(layer "B.CrtYd")
		)
		(fp_line
			(start -0.7239 -0.2159)
			(end 0.7239 -0.2159)
			(stroke
				(width 0.1)
				(type default)
			)
			(layer "B.Fab")
		)
		(fp_line
			(start -0.7239 1.9939)
			(end -0.7239 -0.2159)
			(stroke
				(width 0.1)
				(type default)
			)
			(layer "B.Fab")
		)
		(fp_line
			(start 0.7239 -0.2159)
			(end 0.7239 1.9939)
			(stroke
				(width 0.1)
				(type default)
			)
			(layer "B.Fab")
		)
		(fp_line
			(start 0.7239 1.9939)
			(end -0.7239 1.9939)
			(stroke
				(width 0.1)
				(type default)
			)
			(layer "B.Fab")
		)
		(pad "1" smd rect
			(at 0 0 180)
			(size 1.27 1.016)
			(layers "B.Cu" "B.Mask" "B.Paste")
			(net "PVDDQ_KLM")
		)
		(pad "2" smd rect
			(at 0 1.778 180)
			(size 1.27 1.016)
			(layers "B.Cu" "B.Mask" "B.Paste")
			(net "GND")
		)
		(zone
			(layer "B.Cu")
			(hatch none 0.5)
			(connect_pads
				(clearance 0)
			)
			(min_thickness 0.25)
			(keepout
				(tracks not_allowed)
				(vias allowed)
				(pads allowed)
				(copperpour not_allowed)
				(footprints allowed)
			)
			(placement
				(enabled no)
				(sheetname "")
			)
			(fill
				(thermal_gap 0.5)
				(thermal_bridge_width 0.5)
				(island_removal_mode 0)
			)
			(polygon
				(pts
					(xy 106.858054 -84.55914) (xy 105.588054 -84.55914) (xy 105.588054 -83.79714) (xy 106.858054 -83.79714)
				)
			)
		)
	)
	(footprint ""
		(layer "B.Cu")
		(at 7.366 -63.56604 180)
		(property "Reference" "R9R1"
			(at -4.191 -1.48971 0)
			(unlocked yes)
			(layer "B.SilkS")
			(effects
				(font
					(size 0.7874 0.5842)
					(thickness 0.1524)
				)
				(justify left mirror)
			)
		)
		(property "Value" ""
			(at 0 0 0)
			(layer "B.Fab")
			(effects
				(font
					(size 1.27 1.27)
				)
				(justify mirror)
			)
		)
		(duplicate_pad_numbers_are_jumpers no)
		(fp_circle
			(center 2.29362 -0.691642)
			(end 2.16662 -0.691642)
			(stroke
				(width 0.254)
				(type default)
			)
			(fill no)
			(layer "B.SilkS")
		)
		(fp_rect
			(start 0.8001 3.11658)
			(end -5.8039 -0.31242)
			(stroke
				(width 0)
				(type default)
			)
			(fill no)
			(layer "B.CrtYd")
		)
		(fp_line
			(start 0.8001 3.11658)
			(end 0.8001 -0.31242)
			(stroke
				(width 0.1)
				(type default)
			)
			(layer "B.Fab")
		)
		(fp_line
			(start 0.8001 -0.31242)
			(end -5.8039 -0.31242)
			(stroke
				(width 0.1)
				(type default)
			)
			(layer "B.Fab")
		)
		(fp_line
			(start -5.8039 3.11658)
			(end 0.8001 3.11658)
			(stroke
				(width 0.1)
				(type default)
			)
			(layer "B.Fab")
		)
		(fp_line
			(start -5.8039 -0.31242)
			(end -5.8039 3.11658)
			(stroke
				(width 0.1)
				(type default)
			)
			(layer "B.Fab")
		)
		(fp_circle
			(center 1.740916 -1.623822)
			(end 1.613916 -1.623822)
			(stroke
				(width 0.254)
				(type default)
			)
			(fill no)
			(layer "B.Fab")
		)
		(pad "1" smd rect
			(at 0 0)
			(size 3.4036 1.1938)
			(layers "B.Cu" "B.Mask" "B.Paste")
			(net "P12V_PSU")
		)
		(pad "2" smd rect
			(at -5.0038 0)
			(size 3.4036 1.1938)
			(layers "B.Cu" "B.Mask" "B.Paste")
			(net "P12V_MB0_SW")
		)
		(pad "3" smd rect
			(at 0 1.40208)
			(size 3.4036 0.6096)
			(layers "B.Cu" "B.Mask" "B.Paste")
			(net "P12V_HSC_SENP1")
		)
		(pad "4" smd rect
			(at -5.0038 1.40208)
			(size 3.4036 0.6096)
			(layers "B.Cu" "B.Mask" "B.Paste")
			(net "P12V_HSC_SENN1")
		)
		(pad "5" smd rect
			(at 0 2.80416)
			(size 3.4036 1.1938)
			(layers "B.Cu" "B.Mask" "B.Paste")
			(net "P12V_PSU")
		)
		(pad "6" smd rect
			(at -5.0038 2.80416)
			(size 3.4036 1.1938)
			(layers "B.Cu" "B.Mask" "B.Paste")
			(net "P12V_MB0_SW")
		)
		(zone
			(layer "B.Cu")
			(hatch none 0.5)
			(connect_pads
				(clearance 0)
			)
			(min_thickness 0.25)
			(keepout
				(tracks allowed)
				(vias not_allowed)
				(pads allowed)
				(copperpour not_allowed)
				(footprints allowed)
			)
			(placement
				(enabled no)
				(sheetname "")
			)
			(fill
				(thermal_gap 0.5)
				(thermal_bridge_width 0.5)
				(island_removal_mode 0)
			)
			(polygon
				(pts
					(xy 9.0678 -63.17996) (xy 9.0678 -66.9671) (xy 10.668 -66.9671) (xy 10.668 -62.96914) (xy 9.11352 -62.96914)
					(xy 9.0678 -62.96914)
				)
			)
		)
	)
	(footprint ""
		(layer "B.Cu")
		(at 181.0004 -77.1144 -90)
		(property "Reference" "R6P16"
			(at 0 0 90)
			(layer "B.SilkS")
			(hide yes)
			(effects
				(font
					(size 1.27 1.27)
				)
				(justify mirror)
			)
		)
		(property "Value" ""
			(at 0 0 90)
			(layer "B.Fab")
			(effects
				(font
					(size 1.27 1.27)
				)
				(justify mirror)
			)
		)
		(duplicate_pad_numbers_are_jumpers no)
		(fp_poly
			(pts
				(xy 0.2794 -0.1016) (xy -0.2794 -0.1016) (xy -0.2794 0.9906) (xy 0.2794 0.9906)
			)
			(stroke
				(width 0)
				(type default)
			)
			(fill no)
			(layer "B.CrtYd")
		)
		(fp_line
			(start -0.2794 0.9906)
			(end -0.2794 -0.1016)
			(stroke
				(width 0.1)
				(type default)
			)
			(layer "B.Fab")
		)
		(fp_line
			(start 0.2794 0.9906)
			(end -0.2794 0.9906)
			(stroke
				(width 0.1)
				(type default)
			)
			(layer "B.Fab")
		)
		(fp_line
			(start -0.2794 -0.1016)
			(end 0.2794 -0.1016)
			(stroke
				(width 0.1)
				(type default)
			)
			(layer "B.Fab")
		)
		(fp_line
			(start 0.2794 -0.1016)
			(end 0.2794 0.9906)
			(stroke
				(width 0.1)
				(type default)
			)
			(layer "B.Fab")
		)
		(pad "1" smd rect
			(at 0 0 90)
			(size 0.508 0.508)
			(layers "B.Cu" "B.Mask" "B.Paste")
			(net "PVCCIO_CPU0")
		)
		(pad "2" smd rect
			(at 0 0.889 90)
			(size 0.508 0.508)
			(layers "B.Cu" "B.Mask" "B.Paste")
			(net "VR_PVCCIN_CPU0_VREN")
		)
		(zone
			(layer "B.Cu")
			(hatch none 0.5)
			(connect_pads
				(clearance 0)
			)
			(min_thickness 0.25)
			(keepout
				(tracks not_allowed)
				(vias allowed)
				(pads allowed)
				(copperpour not_allowed)
				(footprints allowed)
			)
			(placement
				(enabled no)
				(sheetname "")
			)
			(fill
				(thermal_gap 0.5)
				(thermal_bridge_width 0.5)
				(island_removal_mode 0)
			)
			(polygon
				(pts
					(xy 180.3654 -76.8604) (xy 180.3654 -77.3684) (xy 180.7464 -77.3684) (xy 180.7464 -76.8604)
				)
			)
		)
		(zone
			(layer "B.Cu")
			(hatch none 0.5)
			(connect_pads
				(clearance 0)
			)
			(min_thickness 0.25)
			(keepout
				(tracks allowed)
				(vias not_allowed)
				(pads allowed)
				(copperpour not_allowed)
				(footprints allowed)
			)
			(placement
				(enabled no)
				(sheetname "")
			)
			(fill
				(thermal_gap 0.5)
				(thermal_bridge_width 0.5)
				(island_removal_mode 0)
			)
			(polygon
				(pts
					(xy 180.7464 -76.8604) (xy 180.7464 -77.3684) (xy 180.3654 -77.3684) (xy 180.3654 -76.8604)
				)
			)
		)
	)
	(footprint ""
		(layer "B.Cu")
		(at 17.9832 -8.9662 -90)
		(property "Reference" "C9U5"
			(at -2.00533 9.271 0)
			(unlocked yes)
			(layer "B.SilkS")
			(effects
				(font
					(size 0.7874 0.5842)
					(thickness 0.1524)
				)
				(justify mirror)
			)
		)
		(property "Value" ""
			(at 0 0 90)
			(layer "B.Fab")
			(effects
				(font
					(size 1.27 1.27)
				)
				(justify mirror)
			)
		)
		(duplicate_pad_numbers_are_jumpers no)
		(fp_line
			(start -2.286 7.366)
			(end -1.600708 7.366)
			(stroke
				(width 0.1524)
				(type default)
			)
			(layer "B.SilkS")
		)
		(fp_line
			(start -2.286 7.366)
			(end -2.286 1.63195)
			(stroke
				(width 0.1524)
				(type default)
			)
			(layer "B.SilkS")
		)
		(fp_line
			(start 2.286 7.366)
			(end 1.60147 7.366)
			(stroke
				(width 0.1524)
				(type default)
			)
			(layer "B.SilkS")
		)
		(fp_line
			(start 2.286 7.366)
			(end 2.286 1.632712)
			(stroke
				(width 0.1524)
				(type default)
			)
			(layer "B.SilkS")
		)
		(fp_line
			(start -2.504948 1.633728)
			(end -1.6002 1.633728)
			(stroke
				(width 0.1524)
				(type default)
			)
			(layer "B.SilkS")
		)
		(fp_line
			(start 2.563114 1.633728)
			(end 1.6002 1.633728)
			(stroke
				(width 0.1524)
				(type default)
			)
			(layer "B.SilkS")
		)
		(fp_line
			(start -2.504948 -1.616456)
			(end -2.504948 1.633728)
			(stroke
				(width 0.1524)
				(type default)
			)
			(layer "B.SilkS")
		)
		(fp_line
			(start -1.6002 -1.616456)
			(end -2.504948 -1.616456)
			(stroke
				(width 0.1524)
				(type default)
			)
			(layer "B.SilkS")
		)
		(fp_line
			(start 1.6002 -1.616456)
			(end 2.563114 -1.616456)
			(stroke
				(width 0.1524)
				(type default)
			)
			(layer "B.SilkS")
		)
		(fp_line
			(start 2.563114 -1.616456)
			(end 2.563114 1.633728)
			(stroke
				(width 0.1524)
				(type default)
			)
			(layer "B.SilkS")
		)
		(fp_rect
			(start 2.286 -0.254)
			(end -2.286 7.366)
			(stroke
				(width 0)
				(type default)
			)
			(fill no)
			(layer "B.CrtYd")
		)
		(fp_line
			(start -2.286 7.366)
			(end 2.286 7.366)
			(stroke
				(width 0.1)
				(type default)
			)
			(layer "B.Fab")
		)
		(fp_line
			(start 2.286 7.366)
			(end 2.286 -0.254)
			(stroke
				(width 0.1)
				(type default)
			)
			(layer "B.Fab")
		)
		(fp_line
			(start -2.286 -0.254)
			(end -2.286 7.366)
			(stroke
				(width 0.1)
				(type default)
			)
			(layer "B.Fab")
		)
		(fp_line
			(start 2.286 -0.254)
			(end -2.286 -0.254)
			(stroke
				(width 0.1)
				(type default)
			)
			(layer "B.Fab")
		)
		(pad "1" smd rect
			(at 0 0 90)
			(size 2.54 3.048)
			(layers "B.Cu" "B.Mask" "B.Paste")
			(net "PVDDQ_GHJ")
		)
		(pad "2" smd rect
			(at 0 7.112 90)
			(size 2.54 3.048)
			(layers "B.Cu" "B.Mask" "B.Paste")
			(net "GND")
		)
	)
	(footprint ""
		(layer "B.Cu")
		(at 437.930036 -137.044938)
		(property "Reference" "J2W1"
			(at 0 0 0)
			(layer "B.SilkS")
			(hide yes)
			(effects
				(font
					(size 1.27 1.27)
				)
				(justify mirror)
			)
		)
		(property "Value" "*"
			(at 2.3622 -8.3185 0)
			(unlocked yes)
			(layer "B.Fab")
			(hide yes)
			(effects
				(font
					(size 1.27 1.016)
					(thickness 0.1524)
				)
				(justify mirror)
			)
		)
		(property "Device Type" "SKT-SATA7P-6P-165-GP-U1_SOCKETA"
			(at 2.3622 -9.8425 0)
			(unlocked yes)
			(layer "B.Fab")
			(hide yes)
			(effects
				(font
					(size 1.27 1.016)
					(thickness 0.1524)
				)
				(justify mirror)
			)
		)
		(duplicate_pad_numbers_are_jumpers no)
		(fp_line
			(start -17.8054 -3.3909)
			(end -17.8054 2.9337)
			(stroke
				(width 0.1524)
				(type default)
			)
			(layer "B.SilkS")
		)
		(fp_line
			(start -17.8054 2.9337)
			(end 17.8054 2.9337)
			(stroke
				(width 0.1524)
				(type default)
			)
			(layer "B.SilkS")
		)
		(fp_line
			(start 3.68808 0.649224)
			(end 3.68808 0.750824)
			(stroke
				(width 0.3048)
				(type default)
			)
			(layer "B.SilkS")
		)
		(fp_line
			(start 10.21207 0.750824)
			(end 10.21207 0.649224)
			(stroke
				(width 0.3048)
				(type default)
			)
			(layer "B.SilkS")
		)
		(fp_line
			(start 17.8054 -3.3909)
			(end -17.8054 -3.3909)
			(stroke
				(width 0.1524)
				(type default)
			)
			(layer "B.SilkS")
		)
		(fp_line
			(start 17.8054 2.9337)
			(end 17.8054 -3.3909)
			(stroke
				(width 0.1524)
				(type default)
			)
			(layer "B.SilkS")
		)
		(fp_arc
			(start -8.744966 0.114808)
			(mid -8.109966 -0.163517)
			(end -7.474966 0.114808)
			(stroke
				(width 0.3048)
				(type default)
			)
			(layer "B.SilkS")
		)
		(fp_arc
			(start -8.744966 1.28524)
			(mid -10.243445 0.700048)
			(end -8.744966 0.114808)
			(stroke
				(width 0.3048)
				(type default)
			)
			(layer "B.SilkS")
		)
		(fp_arc
			(start -7.474966 0.114808)
			(mid -6.839966 -0.163517)
			(end -6.204966 0.114808)
			(stroke
				(width 0.3048)
				(type default)
			)
			(layer "B.SilkS")
		)
		(fp_arc
			(start -7.474966 1.28524)
			(mid -8.109966 1.563565)
			(end -8.744966 1.28524)
			(stroke
				(width 0.3048)
				(type default)
			)
			(layer "B.SilkS")
		)
		(fp_arc
			(start -6.204966 0.114808)
			(mid -5.569966 -0.163517)
			(end -4.934966 0.114808)
			(stroke
				(width 0.3048)
				(type default)
			)
			(layer "B.SilkS")
		)
		(fp_arc
			(start -6.204966 1.28524)
			(mid -6.839966 1.563565)
			(end -7.474966 1.28524)
			(stroke
				(width 0.3048)
				(type default)
			)
			(layer "B.SilkS")
		)
		(fp_arc
			(start -4.934966 0.114808)
			(mid -4.299966 -0.163517)
			(end -3.664966 0.114808)
			(stroke
				(width 0.3048)
				(type default)
			)
			(layer "B.SilkS")
		)
		(fp_arc
			(start -4.934966 1.28524)
			(mid -5.569966 1.563565)
			(end -6.204966 1.28524)
			(stroke
				(width 0.3048)
				(type default)
			)
			(layer "B.SilkS")
		)
		(fp_arc
			(start -3.664966 0.114808)
			(mid -3.029966 -0.163517)
			(end -2.394966 0.114808)
			(stroke
				(width 0.3048)
				(type default)
			)
			(layer "B.SilkS")
		)
		(fp_arc
			(start -3.664966 1.28524)
			(mid -4.299966 1.563565)
			(end -4.934966 1.28524)
			(stroke
				(width 0.3048)
				(type default)
			)
			(layer "B.SilkS")
		)
		(fp_arc
			(start -2.394966 0.114808)
			(mid -0.896364 0.700048)
			(end -2.394966 1.28524)
			(stroke
				(width 0.3048)
				(type default)
			)
			(layer "B.SilkS")
		)
		(fp_arc
			(start -2.394966 1.28524)
			(mid -3.029966 1.563565)
			(end -3.664966 1.28524)
			(stroke
				(width 0.3048)
				(type default)
			)
			(layer "B.SilkS")
		)
		(fp_arc
			(start 3.68808 0.649224)
			(mid 4.134076 -0.044139)
			(end 4.949952 0.074168)
			(stroke
				(width 0.3048)
				(type default)
			)
			(layer "B.SilkS")
		)
		(fp_arc
			(start 4.949952 0.074168)
			(mid 5.450078 -0.112888)
			(end 5.950204 0.074168)
			(stroke
				(width 0.3048)
				(type default)
			)
			(layer "B.SilkS")
		)
		(fp_arc
			(start 4.949952 1.32588)
			(mid 4.134088 1.444178)
			(end 3.68808 0.750824)
			(stroke
				(width 0.3048)
				(type default)
			)
			(layer "B.SilkS")
		)
		(fp_arc
			(start 5.950204 0.074168)
			(mid 6.450076 -0.112722)
			(end 6.949948 0.074168)
			(stroke
				(width 0.3048)
				(type default)
			)
			(layer "B.SilkS")
		)
		(fp_arc
			(start 5.950204 1.32588)
			(mid 5.450078 1.512936)
			(end 4.949952 1.32588)
			(stroke
				(width 0.3048)
				(type default)
			)
			(layer "B.SilkS")
		)
		(fp_arc
			(start 6.949948 0.074168)
			(mid 7.450074 -0.112888)
			(end 7.9502 0.074168)
			(stroke
				(width 0.3048)
				(type default)
			)
			(layer "B.SilkS")
		)
		(fp_arc
			(start 6.949948 1.32588)
			(mid 6.450076 1.51277)
			(end 5.950204 1.32588)
			(stroke
				(width 0.3048)
				(type default)
			)
			(layer "B.SilkS")
		)
		(fp_arc
			(start 7.9502 0.074168)
			(mid 8.450072 -0.112722)
			(end 8.949944 0.074168)
			(stroke
				(width 0.3048)
				(type default)
			)
			(layer "B.SilkS")
		)
		(fp_arc
			(start 7.9502 1.32588)
			(mid 7.450074 1.512936)
			(end 6.949948 1.32588)
			(stroke
				(width 0.3048)
				(type default)
			)
			(layer "B.SilkS")
		)
		(fp_arc
			(start 8.949944 0.074168)
			(mid 9.765935 -0.044223)
			(end 10.21207 0.649224)
			(stroke
				(width 0.3048)
				(type default)
			)
			(layer "B.SilkS")
		)
		(fp_arc
			(start 8.949944 1.32588)
			(mid 8.450072 1.51277)
			(end 7.9502 1.32588)
			(stroke
				(width 0.3048)
				(type default)
			)
			(layer "B.SilkS")
		)
		(fp_arc
			(start 10.21207 0.750824)
			(mid 9.766001 1.444362)
			(end 8.949944 1.32588)
			(stroke
				(width 0.3048)
				(type default)
			)
			(layer "B.SilkS")
		)
		(fp_poly
			(pts
				(xy 15.9512 -3.1369) (xy 15.9512 -1.2446) (xy 17.0053 -1.2446) (xy 17.0053 1.2446) (xy 15.9512 1.2446)
				(xy 15.9512 2.6797) (xy -15.9512 2.6797) (xy -15.9512 1.2446) (xy -17.0053 1.2446) (xy -17.0053 -1.2446)
				(xy -15.9512 -1.2446) (xy -15.9512 -3.1369)
			)
			(stroke
				(width 0)
				(type default)
			)
			(fill no)
			(layer "B.CrtYd")
		)
		(fp_poly
			(pts
				(xy 18.0594 3.1877) (xy 18.0594 -3.6449) (xy -18.0594 -3.6449) (xy -18.0594 3.1877) (xy 0.4953 3.1877)
				(xy 0.4953 2.6797) (xy -15.9512 2.6797) (xy -15.9512 1.2446) (xy -17.0053 1.2446) (xy -17.0053 -1.2446)
				(xy -15.9512 -1.2446) (xy -15.9512 -3.1369) (xy 15.9512 -3.1369) (xy 15.9512 -1.2446) (xy 17.0053 -1.2446)
				(xy 17.0053 1.2446) (xy 15.9512 1.2446) (xy 15.9512 2.6797) (xy 0.508 2.6797) (xy 0.508 3.1877)
			)
			(stroke
				(width 0)
				(type default)
			)
			(fill no)
			(layer "B.CrtYd")
		)
		(fp_rect
			(start 18.0594 3.1877)
			(end -18.0594 -3.6449)
			(stroke
				(width 0)
				(type default)
			)
			(fill no)
			(layer "B.Fab")
		)
		(pad "" np_thru_hole circle
			(at -12.500102 -1.400048 180)
			(size 0.254 0.254)
			(drill 1.651)
			(layers "*.Cu" "*.Mask")
			(clearance 1.0541)
			(thermal_gap 1.0541)
		)
		(pad "" np_thru_hole circle
			(at 12.500102 -1.400048 180)
			(size 0.254 0.254)
			(drill 1.651)
			(layers "*.Cu" "*.Mask")
			(clearance 1.0541)
			(thermal_gap 1.0541)
		)
		(pad "H1" smd rect
			(at -16.249904 0 180)
			(size 2.5908 3.683)
			(layers "B.Cu" "B.Mask" "B.Paste")
			(net "GND")
		)
		(pad "H2" smd rect
			(at 16.249904 0 180)
			(size 2.5908 3.683)
			(layers "B.Cu" "B.Mask" "B.Paste")
			(net "GND")
		)
		(pad "P1" thru_hole oval
			(at 4.45008 0.700024 180)
			(size 0.8128 0.9144)
			(drill 0.5588)
			(layers "*.Cu" "*.Mask")
			(remove_unused_layers no)
			(net "P5V_HDD_SATA")
			(clearance 0.2286)
			(thermal_gap 0.2286)
		)
		(pad "P2" thru_hole oval
			(at 5.450078 0.700024 180)
			(size 0.8128 0.9144)
			(drill 0.5588)
			(layers "*.Cu" "*.Mask")
			(remove_unused_layers no)
			(net "P5V_HDD_SATA")
			(clearance 0.2286)
			(thermal_gap 0.2286)
		)
		(pad "P3" thru_hole oval
			(at 6.450076 0.700024 180)
			(size 0.8128 0.9144)
			(drill 0.5588)
			(layers "*.Cu" "*.Mask")
			(remove_unused_layers no)
			(net "GND")
			(clearance 0.2286)
			(thermal_gap 0.2286)
		)
		(pad "P4" thru_hole oval
			(at 7.450074 0.700024 180)
			(size 0.8128 0.9144)
			(drill 0.5588)
			(layers "*.Cu" "*.Mask")
			(remove_unused_layers no)
			(net "GND")
			(clearance 0.2286)
			(thermal_gap 0.2286)
		)
		(pad "P5" thru_hole oval
			(at 8.450072 0.700024 180)
			(size 0.8128 0.9144)
			(drill 0.5588)
			(layers "*.Cu" "*.Mask")
			(remove_unused_layers no)
			(net "P12V_HDD_SATA")
			(clearance 0.2286)
			(thermal_gap 0.2286)
		)
		(pad "P6" thru_hole oval
			(at 9.45007 0.700024 180)
			(size 0.8128 0.9144)
			(drill 0.5588)
			(layers "*.Cu" "*.Mask")
			(remove_unused_layers no)
			(net "P12V_HDD_SATA")
			(clearance 0.2286)
			(thermal_gap 0.2286)
		)
		(pad "S1" thru_hole circle
			(at -9.379966 0.700024 180)
			(size 1.016 1.016)
			(drill 0.6604)
			(layers "*.Cu" "*.Mask")
			(remove_unused_layers no)
			(net "GND")
			(clearance 0.1778)
			(thermal_gap 0.1778)
		)
		(pad "S2" thru_hole circle
			(at -8.109966 0.700024 180)
			(size 1.016 1.016)
			(drill 0.6604)
			(layers "*.Cu" "*.Mask")
			(remove_unused_layers no)
			(net "SATA6G_S1_TX_C_DP")
			(clearance 0.1778)
			(thermal_gap 0.1778)
		)
		(pad "S3" thru_hole circle
			(at -6.839966 0.700024 180)
			(size 1.016 1.016)
			(drill 0.6604)
			(layers "*.Cu" "*.Mask")
			(remove_unused_layers no)
			(net "SATA6G_S1_TX_C_DN")
			(clearance 0.1778)
			(thermal_gap 0.1778)
		)
		(pad "S4" thru_hole circle
			(at -5.569966 0.700024 180)
			(size 1.016 1.016)
			(drill 0.6604)
			(layers "*.Cu" "*.Mask")
			(remove_unused_layers no)
			(net "GND")
			(clearance 0.1778)
			(thermal_gap 0.1778)
		)
		(pad "S5" thru_hole circle
			(at -4.299966 0.700024 180)
			(size 1.016 1.016)
			(drill 0.6604)
			(layers "*.Cu" "*.Mask")
			(remove_unused_layers no)
			(net "SATA6G_S1_RX_C_DN")
			(clearance 0.1778)
			(thermal_gap 0.1778)
		)
		(pad "S6" thru_hole circle
			(at -3.029966 0.700024 180)
			(size 1.016 1.016)
			(drill 0.6604)
			(layers "*.Cu" "*.Mask")
			(remove_unused_layers no)
			(net "SATA6G_S1_RX_C_DP")
			(clearance 0.1778)
			(thermal_gap 0.1778)
		)
		(pad "S7" thru_hole circle
			(at -1.759966 0.700024 180)
			(size 1.016 1.016)
			(drill 0.6604)
			(layers "*.Cu" "*.Mask")
			(remove_unused_layers no)
			(net "GND")
			(clearance 0.1778)
			(thermal_gap 0.1778)
		)
		(zone
			(layers "F.Cu" "B.Cu" "In1.Cu" "In2.Cu" "In3.Cu" "In4.Cu" "In5.Cu" "In6.Cu"
				"In7.Cu" "In8.Cu" "In9.Cu" "In10.Cu" "In11.Cu" "In12.Cu"
			)
			(hatch none 0.5)
			(connect_pads
				(clearance 0)
			)
			(min_thickness 0.25)
			(keepout
				(tracks not_allowed)
				(vias allowed)
				(pads allowed)
				(copperpour not_allowed)
				(footprints allowed)
			)
			(placement
				(enabled no)
				(sheetname "")
			)
			(fill
				(thermal_gap 0.5)
				(thermal_bridge_width 0.5)
				(island_removal_mode 0)
			)
			(polygon
				(pts
					(arc
						(start 426.560234 -138.444986)
						(mid 424.299634 -138.444986)
						(end 426.560234 -138.444986)
					)
				)
			)
		)
		(zone
			(layers "F.Cu" "B.Cu" "In1.Cu" "In2.Cu" "In3.Cu" "In4.Cu" "In5.Cu" "In6.Cu"
				"In7.Cu" "In8.Cu" "In9.Cu" "In10.Cu" "In11.Cu" "In12.Cu"
			)
			(hatch none 0.5)
			(connect_pads
				(clearance 0)
			)
			(min_thickness 0.25)
			(keepout
				(tracks not_allowed)
				(vias allowed)
				(pads allowed)
				(copperpour not_allowed)
				(footprints allowed)
			)
			(placement
				(enabled no)
				(sheetname "")
			)
			(fill
				(thermal_gap 0.5)
				(thermal_bridge_width 0.5)
				(island_removal_mode 0)
			)
			(polygon
				(pts
					(arc
						(start 451.560438 -138.444986)
						(mid 449.299838 -138.444986)
						(end 451.560438 -138.444986)
					)
				)
			)
		)
	)
	(footprint ""
		(layer "B.Cu")
		(at 363.87024 -137.52957 90)
		(property "Reference" "R3L13"
			(at 0 0 90)
			(layer "B.SilkS")
			(hide yes)
			(effects
				(font
					(size 1.27 1.27)
				)
				(justify mirror)
			)
		)
		(property "Value" ""
			(at 0 0 90)
			(layer "B.Fab")
			(effects
				(font
					(size 1.27 1.27)
				)
				(justify mirror)
			)
		)
		(duplicate_pad_numbers_are_jumpers no)
		(fp_rect
			(start -0.2794 -0.1016)
			(end 0.2794 0.9906)
			(stroke
				(width 0)
				(type default)
			)
			(fill no)
			(layer "B.CrtYd")
		)
		(fp_line
			(start 0.2794 -0.1016)
			(end 0.2794 0.9906)
			(stroke
				(width 0.1)
				(type default)
			)
			(layer "B.Fab")
		)
		(fp_line
			(start -0.2794 -0.1016)
			(end 0.2794 -0.1016)
			(stroke
				(width 0.1)
				(type default)
			)
			(layer "B.Fab")
		)
		(fp_line
			(start 0.2794 0.9906)
			(end -0.2794 0.9906)
			(stroke
				(width 0.1)
				(type default)
			)
			(layer "B.Fab")
		)
		(fp_line
			(start -0.2794 0.9906)
			(end -0.2794 -0.1016)
			(stroke
				(width 0.1)
				(type default)
			)
			(layer "B.Fab")
		)
		(pad "1" smd rect
			(at 0 0 270)
			(size 0.508 0.508)
			(layers "B.Cu" "B.Mask" "B.Paste")
			(net "PVCCIO_CPU0")
		)
		(pad "2" smd rect
			(at 0 0.889 270)
			(size 0.508 0.508)
			(layers "B.Cu" "B.Mask" "B.Paste")
			(net "SVID_CLK1_CPU0_R")
		)
		(zone
			(layer "B.Cu")
			(hatch none 0.5)
			(connect_pads
				(clearance 0)
			)
			(min_thickness 0.25)
			(keepout
				(tracks allowed)
				(vias not_allowed)
				(pads allowed)
				(copperpour not_allowed)
				(footprints allowed)
			)
			(placement
				(enabled no)
				(sheetname "")
			)
			(fill
				(thermal_gap 0.5)
				(thermal_bridge_width 0.5)
				(island_removal_mode 0)
			)
			(polygon
				(pts
					(xy 364.12424 -137.27557) (xy 364.50524 -137.27557) (xy 364.50524 -137.78357) (xy 364.12424 -137.78357)
				)
			)
		)
		(zone
			(layer "B.Cu")
			(hatch none 0.5)
			(connect_pads
				(clearance 0)
			)
			(min_thickness 0.25)
			(keepout
				(tracks not_allowed)
				(vias allowed)
				(pads allowed)
				(copperpour not_allowed)
				(footprints allowed)
			)
			(placement
				(enabled no)
				(sheetname "")
			)
			(fill
				(thermal_gap 0.5)
				(thermal_bridge_width 0.5)
				(island_removal_mode 0)
			)
			(polygon
				(pts
					(xy 364.12424 -137.27557) (xy 364.50524 -137.27557) (xy 364.50524 -137.78357) (xy 364.12424 -137.78357)
				)
			)
		)
	)
	(footprint ""
		(layer "B.Cu")
		(at 488.50804 -123.55068)
		(property "Reference" "C1M4"
			(at 0 0 0)
			(layer "B.SilkS")
			(hide yes)
			(effects
				(font
					(size 1.27 1.27)
				)
				(justify mirror)
			)
		)
		(property "Value" ""
			(at 0 0 0)
			(layer "B.Fab")
			(effects
				(font
					(size 1.27 1.27)
				)
				(justify mirror)
			)
		)
		(duplicate_pad_numbers_are_jumpers no)
		(fp_rect
			(start 0.3048 -0.1016)
			(end -0.3048 0.9906)
			(stroke
				(width 0)
				(type default)
			)
			(fill no)
			(layer "B.CrtYd")
		)
		(fp_line
			(start -0.3048 -0.1016)
			(end 0.3048 -0.1016)
			(stroke
				(width 0.1)
				(type default)
			)
			(layer "B.Fab")
		)
		(fp_line
			(start -0.3048 0.9906)
			(end -0.3048 -0.1016)
			(stroke
				(width 0.1)
				(type default)
			)
			(layer "B.Fab")
		)
		(fp_line
			(start 0.3048 -0.1016)
			(end 0.3048 0.9906)
			(stroke
				(width 0.1)
				(type default)
			)
			(layer "B.Fab")
		)
		(fp_line
			(start 0.3048 0.9906)
			(end -0.3048 0.9906)
			(stroke
				(width 0.1)
				(type default)
			)
			(layer "B.Fab")
		)
		(pad "1" smd rect
			(at 0 0 180)
			(size 0.508 0.508)
			(layers "B.Cu" "B.Mask" "B.Paste")
			(net "ISENSE_TMP421_1_DXP")
		)
		(pad "2" smd rect
			(at 0 0.889 180)
			(size 0.508 0.508)
			(layers "B.Cu" "B.Mask" "B.Paste")
			(net "ISENSE_TMP421_1_DXN")
		)
		(zone
			(layer "B.Cu")
			(hatch none 0.5)
			(connect_pads
				(clearance 0)
			)
			(min_thickness 0.25)
			(keepout
				(tracks not_allowed)
				(vias allowed)
				(pads allowed)
				(copperpour not_allowed)
				(footprints allowed)
			)
			(placement
				(enabled no)
				(sheetname "")
			)
			(fill
				(thermal_gap 0.5)
				(thermal_bridge_width 0.5)
				(island_removal_mode 0)
			)
			(polygon
				(pts
					(xy 488.76204 -123.29668) (xy 488.25404 -123.29668) (xy 488.25404 -122.91568) (xy 488.76204 -122.91568)
				)
			)
		)
		(zone
			(layer "B.Cu")
			(hatch none 0.5)
			(connect_pads
				(clearance 0)
			)
			(min_thickness 0.25)
			(keepout
				(tracks allowed)
				(vias not_allowed)
				(pads allowed)
				(copperpour not_allowed)
				(footprints allowed)
			)
			(placement
				(enabled no)
				(sheetname "")
			)
			(fill
				(thermal_gap 0.5)
				(thermal_bridge_width 0.5)
				(island_removal_mode 0)
			)
			(polygon
				(pts
					(xy 488.76204 -123.29668) (xy 488.25404 -123.29668) (xy 488.25404 -122.91568) (xy 488.76204 -122.91568)
				)
			)
		)
	)
	(footprint ""
		(layer "B.Cu")
		(at 440.968638 -150.713186 180)
		(property "Reference" "R25W168"
			(at 0.8382 -0.67818 180)
			(unlocked yes)
			(layer "B.SilkS")
			(effects
				(font
					(size 0.4064 0.254)
					(thickness 0.1524)
				)
				(justify left mirror)
			)
		)
		(property "Value" ""
			(at 0 0 0)
			(layer "B.Fab")
			(effects
				(font
					(size 1.27 1.27)
				)
				(justify mirror)
			)
		)
		(duplicate_pad_numbers_are_jumpers no)
		(fp_poly
			(pts
				(xy 0.2794 -0.1016) (xy -0.2794 -0.1016) (xy -0.2794 0.9906) (xy 0.2794 0.9906)
			)
			(stroke
				(width 0)
				(type default)
			)
			(fill no)
			(layer "B.CrtYd")
		)
		(fp_line
			(start 0.2794 0.9906)
			(end -0.2794 0.9906)
			(stroke
				(width 0.1)
				(type default)
			)
			(layer "B.Fab")
		)
		(fp_line
			(start 0.2794 -0.1016)
			(end 0.2794 0.9906)
			(stroke
				(width 0.1)
				(type default)
			)
			(layer "B.Fab")
		)
		(fp_line
			(start -0.2794 0.9906)
			(end -0.2794 -0.1016)
			(stroke
				(width 0.1)
				(type default)
			)
			(layer "B.Fab")
		)
		(fp_line
			(start -0.2794 -0.1016)
			(end 0.2794 -0.1016)
			(stroke
				(width 0.1)
				(type default)
			)
			(layer "B.Fab")
		)
		(pad "1" smd rect
			(at 0 0)
			(size 0.508 0.508)
			(layers "B.Cu" "B.Mask" "B.Paste")
			(net "JTAG_BMC_TCK0")
		)
		(pad "2" smd rect
			(at 0 0.889)
			(size 0.508 0.508)
			(layers "B.Cu" "B.Mask" "B.Paste")
			(net "GND")
		)
		(zone
			(layer "B.Cu")
			(hatch none 0.5)
			(connect_pads
				(clearance 0)
			)
			(min_thickness 0.25)
			(keepout
				(tracks not_allowed)
				(vias allowed)
				(pads allowed)
				(copperpour not_allowed)
				(footprints allowed)
			)
			(placement
				(enabled no)
				(sheetname "")
			)
			(fill
				(thermal_gap 0.5)
				(thermal_bridge_width 0.5)
				(island_removal_mode 0)
			)
			(polygon
				(pts
					(xy 440.714638 -151.348186) (xy 441.222638 -151.348186) (xy 441.222638 -150.967186) (xy 440.714638 -150.967186)
				)
			)
		)
		(zone
			(layer "B.Cu")
			(hatch none 0.5)
			(connect_pads
				(clearance 0)
			)
			(min_thickness 0.25)
			(keepout
				(tracks allowed)
				(vias not_allowed)
				(pads allowed)
				(copperpour not_allowed)
				(footprints allowed)
			)
			(placement
				(enabled no)
				(sheetname "")
			)
			(fill
				(thermal_gap 0.5)
				(thermal_bridge_width 0.5)
				(island_removal_mode 0)
			)
			(polygon
				(pts
					(xy 440.714638 -150.967186) (xy 441.222638 -150.967186) (xy 441.222638 -151.348186) (xy 440.714638 -151.348186)
				)
			)
		)
	)
	(footprint ""
		(layer "B.Cu")
		(at 428.279052 -13.794994 -90)
		(property "Reference" "R9G31"
			(at 0 0 90)
			(layer "B.SilkS")
			(hide yes)
			(effects
				(font
					(size 1.27 1.27)
				)
				(justify mirror)
			)
		)
		(property "Value" ""
			(at 0 0 90)
			(layer "B.Fab")
			(effects
				(font
					(size 1.27 1.27)
				)
				(justify mirror)
			)
		)
		(duplicate_pad_numbers_are_jumpers no)
		(fp_poly
			(pts
				(xy 0.2794 -0.1016) (xy -0.2794 -0.1016) (xy -0.2794 0.9906) (xy 0.2794 0.9906)
			)
			(stroke
				(width 0)
				(type default)
			)
			(fill no)
			(layer "B.CrtYd")
		)
		(fp_line
			(start -0.2794 0.9906)
			(end -0.2794 -0.1016)
			(stroke
				(width 0.1)
				(type default)
			)
			(layer "B.Fab")
		)
		(fp_line
			(start 0.2794 0.9906)
			(end -0.2794 0.9906)
			(stroke
				(width 0.1)
				(type default)
			)
			(layer "B.Fab")
		)
		(fp_line
			(start -0.2794 -0.1016)
			(end 0.2794 -0.1016)
			(stroke
				(width 0.1)
				(type default)
			)
			(layer "B.Fab")
		)
		(fp_line
			(start 0.2794 -0.1016)
			(end 0.2794 0.9906)
			(stroke
				(width 0.1)
				(type default)
			)
			(layer "B.Fab")
		)
		(pad "1" smd rect
			(at 0 0 90)
			(size 0.508 0.508)
			(layers "B.Cu" "B.Mask" "B.Paste")
			(net "H_CPU0_MEMDEF_MEMHOT_LVT3_K_N")
		)
		(pad "2" smd rect
			(at 0 0.889 90)
			(size 0.508 0.508)
			(layers "B.Cu" "B.Mask" "B.Paste")
			(net "H_CPU0_MEMDEF_MEMHOT_LVT3_N")
		)
		(zone
			(layer "B.Cu")
			(hatch none 0.5)
			(connect_pads
				(clearance 0)
			)
			(min_thickness 0.25)
			(keepout
				(tracks not_allowed)
				(vias allowed)
				(pads allowed)
				(copperpour not_allowed)
				(footprints allowed)
			)
			(placement
				(enabled no)
				(sheetname "")
			)
			(fill
				(thermal_gap 0.5)
				(thermal_bridge_width 0.5)
				(island_removal_mode 0)
			)
			(polygon
				(pts
					(xy 427.644052 -13.540994) (xy 427.644052 -14.048994) (xy 428.025052 -14.048994) (xy 428.025052 -13.540994)
				)
			)
		)
		(zone
			(layer "B.Cu")
			(hatch none 0.5)
			(connect_pads
				(clearance 0)
			)
			(min_thickness 0.25)
			(keepout
				(tracks allowed)
				(vias not_allowed)
				(pads allowed)
				(copperpour not_allowed)
				(footprints allowed)
			)
			(placement
				(enabled no)
				(sheetname "")
			)
			(fill
				(thermal_gap 0.5)
				(thermal_bridge_width 0.5)
				(island_removal_mode 0)
			)
			(polygon
				(pts
					(xy 428.025052 -13.540994) (xy 428.025052 -14.048994) (xy 427.644052 -14.048994) (xy 427.644052 -13.540994)
				)
			)
		)
	)
	(footprint ""
		(layer "B.Cu")
		(at 49.4284 -93.7514)
		(property "Reference" "C9N22"
			(at 0 0 0)
			(layer "B.SilkS")
			(hide yes)
			(effects
				(font
					(size 1.27 1.27)
				)
				(justify mirror)
			)
		)
		(property "Value" ""
			(at 0 0 0)
			(layer "B.Fab")
			(effects
				(font
					(size 1.27 1.27)
				)
				(justify mirror)
			)
		)
		(duplicate_pad_numbers_are_jumpers no)
		(fp_poly
			(pts
				(xy 0.4953 -0.2032) (xy -0.4953 -0.2032) (xy -0.4953 1.6002) (xy 0.4953 1.6002)
			)
			(stroke
				(width 0)
				(type default)
			)
			(fill no)
			(layer "B.CrtYd")
		)
		(fp_line
			(start -0.4953 -0.2032)
			(end -0.4953 1.6002)
			(stroke
				(width 0.1)
				(type default)
			)
			(layer "B.Fab")
		)
		(fp_line
			(start -0.4953 1.6002)
			(end 0.4953 1.6002)
			(stroke
				(width 0.1)
				(type default)
			)
			(layer "B.Fab")
		)
		(fp_line
			(start 0.4953 -0.2032)
			(end -0.4953 -0.2032)
			(stroke
				(width 0.1)
				(type default)
			)
			(layer "B.Fab")
		)
		(fp_line
			(start 0.4953 1.6002)
			(end 0.4953 -0.2032)
			(stroke
				(width 0.1)
				(type default)
			)
			(layer "B.Fab")
		)
		(pad "1" smd rect
			(at 0 0 180)
			(size 0.762 0.889)
			(layers "B.Cu" "B.Mask" "B.Paste")
			(net "PVSA_CPU1")
		)
		(pad "2" smd rect
			(at 0 1.397 180)
			(size 0.762 0.889)
			(layers "B.Cu" "B.Mask" "B.Paste")
			(net "GND")
		)
		(zone
			(layer "B.Cu")
			(hatch none 0.5)
			(connect_pads
				(clearance 0)
			)
			(min_thickness 0.25)
			(keepout
				(tracks not_allowed)
				(vias allowed)
				(pads allowed)
				(copperpour not_allowed)
				(footprints allowed)
			)
			(placement
				(enabled no)
				(sheetname "")
			)
			(fill
				(thermal_gap 0.5)
				(thermal_bridge_width 0.5)
				(island_removal_mode 0)
			)
			(polygon
				(pts
					(xy 49.8094 -93.3069) (xy 49.0474 -93.3069) (xy 49.0474 -92.7989) (xy 49.8094 -92.7989)
				)
			)
		)
	)
	(footprint ""
		(layer "B.Cu")
		(at 395.351 -88.2015)
		(property "Reference" "R2N21"
			(at 0 0 0)
			(layer "B.SilkS")
			(hide yes)
			(effects
				(font
					(size 1.27 1.27)
				)
				(justify mirror)
			)
		)
		(property "Value" ""
			(at 0 0 0)
			(layer "B.Fab")
			(effects
				(font
					(size 1.27 1.27)
				)
				(justify mirror)
			)
		)
		(duplicate_pad_numbers_are_jumpers no)
		(fp_poly
			(pts
				(xy 0.2794 -0.1016) (xy -0.2794 -0.1016) (xy -0.2794 0.9906) (xy 0.2794 0.9906)
			)
			(stroke
				(width 0)
				(type default)
			)
			(fill no)
			(layer "B.CrtYd")
		)
		(fp_line
			(start -0.2794 -0.1016)
			(end 0.2794 -0.1016)
			(stroke
				(width 0.1)
				(type default)
			)
			(layer "B.Fab")
		)
		(fp_line
			(start -0.2794 0.9906)
			(end -0.2794 -0.1016)
			(stroke
				(width 0.1)
				(type default)
			)
			(layer "B.Fab")
		)
		(fp_line
			(start 0.2794 -0.1016)
			(end 0.2794 0.9906)
			(stroke
				(width 0.1)
				(type default)
			)
			(layer "B.Fab")
		)
		(fp_line
			(start 0.2794 0.9906)
			(end -0.2794 0.9906)
			(stroke
				(width 0.1)
				(type default)
			)
			(layer "B.Fab")
		)
		(pad "1" smd rect
			(at 0 0 180)
			(size 0.508 0.508)
			(layers "B.Cu" "B.Mask" "B.Paste")
			(net "SMB_LAN_STBY_LVC3_SCL_R2")
		)
		(pad "2" smd rect
			(at 0 0.889 180)
			(size 0.508 0.508)
			(layers "B.Cu" "B.Mask" "B.Paste")
			(net "SMB_LAN_STBY_LVC3_SCL")
		)
		(zone
			(layer "B.Cu")
			(hatch none 0.5)
			(connect_pads
				(clearance 0)
			)
			(min_thickness 0.25)
			(keepout
				(tracks allowed)
				(vias not_allowed)
				(pads allowed)
				(copperpour not_allowed)
				(footprints allowed)
			)
			(placement
				(enabled no)
				(sheetname "")
			)
			(fill
				(thermal_gap 0.5)
				(thermal_bridge_width 0.5)
				(island_removal_mode 0)
			)
			(polygon
				(pts
					(xy 395.605 -87.9475) (xy 395.097 -87.9475) (xy 395.097 -87.5665) (xy 395.605 -87.5665)
				)
			)
		)
		(zone
			(layer "B.Cu")
			(hatch none 0.5)
			(connect_pads
				(clearance 0)
			)
			(min_thickness 0.25)
			(keepout
				(tracks not_allowed)
				(vias allowed)
				(pads allowed)
				(copperpour not_allowed)
				(footprints allowed)
			)
			(placement
				(enabled no)
				(sheetname "")
			)
			(fill
				(thermal_gap 0.5)
				(thermal_bridge_width 0.5)
				(island_removal_mode 0)
			)
			(polygon
				(pts
					(xy 395.605 -87.5665) (xy 395.097 -87.5665) (xy 395.097 -87.9475) (xy 395.605 -87.9475)
				)
			)
		)
	)
	(footprint ""
		(layer "B.Cu")
		(at 109.880654 -85.06714)
		(property "Reference" "C7P1"
			(at 0 0 0)
			(layer "B.SilkS")
			(hide yes)
			(effects
				(font
					(size 1.27 1.27)
				)
				(justify mirror)
			)
		)
		(property "Value" ""
			(at 0 0 0)
			(layer "B.Fab")
			(effects
				(font
					(size 1.27 1.27)
				)
				(justify mirror)
			)
		)
		(duplicate_pad_numbers_are_jumpers no)
		(fp_poly
			(pts
				(xy 0.7239 -0.2159) (xy -0.7239 -0.2159) (xy -0.7239 1.9939) (xy 0.7239 1.9939)
			)
			(stroke
				(width 0)
				(type default)
			)
			(fill no)
			(layer "B.CrtYd")
		)
		(fp_line
			(start -0.7239 -0.2159)
			(end 0.7239 -0.2159)
			(stroke
				(width 0.1)
				(type default)
			)
			(layer "B.Fab")
		)
		(fp_line
			(start -0.7239 1.9939)
			(end -0.7239 -0.2159)
			(stroke
				(width 0.1)
				(type default)
			)
			(layer "B.Fab")
		)
		(fp_line
			(start 0.7239 -0.2159)
			(end 0.7239 1.9939)
			(stroke
				(width 0.1)
				(type default)
			)
			(layer "B.Fab")
		)
		(fp_line
			(start 0.7239 1.9939)
			(end -0.7239 1.9939)
			(stroke
				(width 0.1)
				(type default)
			)
			(layer "B.Fab")
		)
		(pad "1" smd rect
			(at 0 0 180)
			(size 1.27 1.016)
			(layers "B.Cu" "B.Mask" "B.Paste")
			(net "PVDDQ_KLM")
		)
		(pad "2" smd rect
			(at 0 1.778 180)
			(size 1.27 1.016)
			(layers "B.Cu" "B.Mask" "B.Paste")
			(net "GND")
		)
		(zone
			(layer "B.Cu")
			(hatch none 0.5)
			(connect_pads
				(clearance 0)
			)
			(min_thickness 0.25)
			(keepout
				(tracks not_allowed)
				(vias allowed)
				(pads allowed)
				(copperpour not_allowed)
				(footprints allowed)
			)
			(placement
				(enabled no)
				(sheetname "")
			)
			(fill
				(thermal_gap 0.5)
				(thermal_bridge_width 0.5)
				(island_removal_mode 0)
			)
			(polygon
				(pts
					(xy 110.515654 -84.55914) (xy 109.245654 -84.55914) (xy 109.245654 -83.79714) (xy 110.515654 -83.79714)
				)
			)
		)
	)
	(footprint ""
		(layer "B.Cu")
		(at 11.9126 -74.8284 180)
		(property "Reference" "R9P18"
			(at 0 0 0)
			(layer "B.SilkS")
			(hide yes)
			(effects
				(font
					(size 1.27 1.27)
				)
				(justify mirror)
			)
		)
		(property "Value" ""
			(at 0 0 0)
			(layer "B.Fab")
			(effects
				(font
					(size 1.27 1.27)
				)
				(justify mirror)
			)
		)
		(duplicate_pad_numbers_are_jumpers no)
		(fp_rect
			(start 0.2794 -0.1016)
			(end -0.2794 0.9906)
			(stroke
				(width 0)
				(type default)
			)
			(fill no)
			(layer "B.CrtYd")
		)
		(fp_line
			(start 0.2794 0.9906)
			(end -0.2794 0.9906)
			(stroke
				(width 0.1)
				(type default)
			)
			(layer "B.Fab")
		)
		(fp_line
			(start 0.2794 -0.1016)
			(end 0.2794 0.9906)
			(stroke
				(width 0.1)
				(type default)
			)
			(layer "B.Fab")
		)
		(fp_line
			(start -0.2794 0.9906)
			(end -0.2794 -0.1016)
			(stroke
				(width 0.1)
				(type default)
			)
			(layer "B.Fab")
		)
		(fp_line
			(start -0.2794 -0.1016)
			(end 0.2794 -0.1016)
			(stroke
				(width 0.1)
				(type default)
			)
			(layer "B.Fab")
		)
		(pad "1" smd rect
			(at 0 0)
			(size 0.508 0.508)
			(layers "B.Cu" "B.Mask" "B.Paste")
			(net "P12V_STBY")
		)
		(pad "2" smd rect
			(at 0 0.889)
			(size 0.508 0.508)
			(layers "B.Cu" "B.Mask" "B.Paste")
			(net "PWRGD_P12V_R")
		)
		(zone
			(layer "B.Cu")
			(hatch none 0.5)
			(connect_pads
				(clearance 0)
			)
			(min_thickness 0.25)
			(keepout
				(tracks allowed)
				(vias not_allowed)
				(pads allowed)
				(copperpour not_allowed)
				(footprints allowed)
			)
			(placement
				(enabled no)
				(sheetname "")
			)
			(fill
				(thermal_gap 0.5)
				(thermal_bridge_width 0.5)
				(island_removal_mode 0)
			)
			(polygon
				(pts
					(xy 11.6586 -75.0824) (xy 12.1666 -75.0824) (xy 12.1666 -75.4634) (xy 11.6586 -75.4634)
				)
			)
		)
		(zone
			(layer "B.Cu")
			(hatch none 0.5)
			(connect_pads
				(clearance 0)
			)
			(min_thickness 0.25)
			(keepout
				(tracks not_allowed)
				(vias allowed)
				(pads allowed)
				(copperpour not_allowed)
				(footprints allowed)
			)
			(placement
				(enabled no)
				(sheetname "")
			)
			(fill
				(thermal_gap 0.5)
				(thermal_bridge_width 0.5)
				(island_removal_mode 0)
			)
			(polygon
				(pts
					(xy 11.6586 -75.0824) (xy 12.1666 -75.0824) (xy 12.1666 -75.4634) (xy 11.6586 -75.4634)
				)
			)
		)
	)
	(footprint ""
		(layer "B.Cu")
		(at 1.27 -15.9512 90)
		(property "Reference" "CT32"
			(at 0.8382 -0.84963 90)
			(unlocked yes)
			(layer "B.SilkS")
			(effects
				(font
					(size 0.7874 0.5842)
					(thickness 0.1524)
				)
				(justify left mirror)
			)
		)
		(property "Value" ""
			(at 0 0 90)
			(layer "B.Fab")
			(effects
				(font
					(size 1.27 1.27)
				)
				(justify mirror)
			)
		)
		(duplicate_pad_numbers_are_jumpers no)
		(fp_poly
			(pts
				(xy -0.3048 -0.1016) (xy -0.3048 0.9906) (xy 0.3048 0.9906) (xy 0.3048 -0.1016)
			)
			(stroke
				(width 0)
				(type default)
			)
			(fill no)
			(layer "B.CrtYd")
		)
		(fp_line
			(start 0.3048 -0.1016)
			(end 0.3048 0.9906)
			(stroke
				(width 0.1)
				(type default)
			)
			(layer "B.Fab")
		)
		(fp_line
			(start -0.3048 -0.1016)
			(end 0.3048 -0.1016)
			(stroke
				(width 0.1)
				(type default)
			)
			(layer "B.Fab")
		)
		(fp_line
			(start 0.3048 0.9906)
			(end -0.3048 0.9906)
			(stroke
				(width 0.1)
				(type default)
			)
			(layer "B.Fab")
		)
		(fp_line
			(start -0.3048 0.9906)
			(end -0.3048 -0.1016)
			(stroke
				(width 0.1)
				(type default)
			)
			(layer "B.Fab")
		)
		(pad "1" smd rect
			(at 0 0 270)
			(size 0.508 0.508)
			(layers "B.Cu" "B.Mask" "B.Paste")
			(net "A_TSENSE_PVDDQ_GHJ")
		)
		(pad "2" smd rect
			(at 0 0.889 270)
			(size 0.508 0.508)
			(layers "B.Cu" "B.Mask" "B.Paste")
			(net "GND")
		)
		(zone
			(layer "B.Cu")
			(hatch none 0.5)
			(connect_pads
				(clearance 0)
			)
			(min_thickness 0.25)
			(keepout
				(tracks allowed)
				(vias not_allowed)
				(pads allowed)
				(copperpour not_allowed)
				(footprints allowed)
			)
			(placement
				(enabled no)
				(sheetname "")
			)
			(fill
				(thermal_gap 0.5)
				(thermal_bridge_width 0.5)
				(island_removal_mode 0)
			)
			(polygon
				(pts
					(xy 1.524 -16.2052) (xy 1.524 -15.6972) (xy 1.905 -15.6972) (xy 1.905 -16.2052)
				)
			)
		)
		(zone
			(layer "B.Cu")
			(hatch none 0.5)
			(connect_pads
				(clearance 0)
			)
			(min_thickness 0.25)
			(keepout
				(tracks not_allowed)
				(vias allowed)
				(pads allowed)
				(copperpour not_allowed)
				(footprints allowed)
			)
			(placement
				(enabled no)
				(sheetname "")
			)
			(fill
				(thermal_gap 0.5)
				(thermal_bridge_width 0.5)
				(island_removal_mode 0)
			)
			(polygon
				(pts
					(xy 1.905 -16.2052) (xy 1.905 -15.6972) (xy 1.524 -15.6972) (xy 1.524 -16.2052)
				)
			)
		)
	)
	(footprint ""
		(layer "B.Cu")
		(at 390.144 -16.383 -90)
		(property "Reference" "C32W2"
			(at 0.8382 -0.67818 270)
			(unlocked yes)
			(layer "B.SilkS")
			(effects
				(font
					(size 0.4064 0.254)
					(thickness 0.1524)
				)
				(justify left mirror)
			)
		)
		(property "Value" ""
			(at 0 0 90)
			(layer "B.Fab")
			(effects
				(font
					(size 1.27 1.27)
				)
				(justify mirror)
			)
		)
		(duplicate_pad_numbers_are_jumpers no)
		(fp_poly
			(pts
				(xy -0.3048 -0.1016) (xy -0.3048 0.9906) (xy 0.3048 0.9906) (xy 0.3048 -0.1016)
			)
			(stroke
				(width 0)
				(type default)
			)
			(fill no)
			(layer "B.CrtYd")
		)
		(fp_line
			(start -0.3048 0.9906)
			(end -0.3048 -0.1016)
			(stroke
				(width 0.1)
				(type default)
			)
			(layer "B.Fab")
		)
		(fp_line
			(start 0.3048 0.9906)
			(end -0.3048 0.9906)
			(stroke
				(width 0.1)
				(type default)
			)
			(layer "B.Fab")
		)
		(fp_line
			(start -0.3048 -0.1016)
			(end 0.3048 -0.1016)
			(stroke
				(width 0.1)
				(type default)
			)
			(layer "B.Fab")
		)
		(fp_line
			(start 0.3048 -0.1016)
			(end 0.3048 0.9906)
			(stroke
				(width 0.1)
				(type default)
			)
			(layer "B.Fab")
		)
		(pad "1" smd rect
			(at 0 0 90)
			(size 0.508 0.508)
			(layers "B.Cu" "B.Mask" "B.Paste")
			(net "P3V3_STBY")
		)
		(pad "2" smd rect
			(at 0 0.889 90)
			(size 0.508 0.508)
			(layers "B.Cu" "B.Mask" "B.Paste")
			(net "GND")
		)
		(zone
			(layer "B.Cu")
			(hatch none 0.5)
			(connect_pads
				(clearance 0)
			)
			(min_thickness 0.25)
			(keepout
				(tracks not_allowed)
				(vias allowed)
				(pads allowed)
				(copperpour not_allowed)
				(footprints allowed)
			)
			(placement
				(enabled no)
				(sheetname "")
			)
			(fill
				(thermal_gap 0.5)
				(thermal_bridge_width 0.5)
				(island_removal_mode 0)
			)
			(polygon
				(pts
					(xy 389.509 -16.129) (xy 389.509 -16.637) (xy 389.89 -16.637) (xy 389.89 -16.129)
				)
			)
		)
		(zone
			(layer "B.Cu")
			(hatch none 0.5)
			(connect_pads
				(clearance 0)
			)
			(min_thickness 0.25)
			(keepout
				(tracks allowed)
				(vias not_allowed)
				(pads allowed)
				(copperpour not_allowed)
				(footprints allowed)
			)
			(placement
				(enabled no)
				(sheetname "")
			)
			(fill
				(thermal_gap 0.5)
				(thermal_bridge_width 0.5)
				(island_removal_mode 0)
			)
			(polygon
				(pts
					(xy 389.89 -16.129) (xy 389.89 -16.637) (xy 389.509 -16.637) (xy 389.509 -16.129)
				)
			)
		)
	)
	(footprint ""
		(layer "B.Cu")
		(at 87.158068 -135.4074 -90)
		(property "Reference" "C8M4"
			(at -1.848866 0.752348 270)
			(unlocked yes)
			(layer "B.SilkS")
			(effects
				(font
					(size 1.27 0.9652)
					(thickness 0.1524)
				)
				(justify mirror)
			)
		)
		(property "Value" ""
			(at 0 0 90)
			(layer "B.Fab")
			(effects
				(font
					(size 1.27 1.27)
				)
				(justify mirror)
			)
		)
		(duplicate_pad_numbers_are_jumpers no)
		(fp_rect
			(start 0.500126 1.598422)
			(end -0.500126 -0.201422)
			(stroke
				(width 0)
				(type default)
			)
			(fill no)
			(layer "B.CrtYd")
		)
		(fp_line
			(start -0.500126 1.598422)
			(end 0.500126 1.598422)
			(stroke
				(width 0.1)
				(type default)
			)
			(layer "B.Fab")
		)
		(fp_line
			(start 0.500126 1.598422)
			(end 0.500126 -0.201422)
			(stroke
				(width 0.1)
				(type default)
			)
			(layer "B.Fab")
		)
		(fp_line
			(start -0.500126 -0.201422)
			(end -0.500126 1.598422)
			(stroke
				(width 0.1)
				(type default)
			)
			(layer "B.Fab")
		)
		(fp_line
			(start 0.500126 -0.201422)
			(end -0.500126 -0.201422)
			(stroke
				(width 0.1)
				(type default)
			)
			(layer "B.Fab")
		)
		(pad "1" smd rect
			(at 0 0 180)
			(size 0.889 0.9906)
			(layers "B.Cu" "B.Mask" "B.Paste")
			(net "PVDDQ_KLM")
		)
		(pad "2" smd rect
			(at 0 1.397 180)
			(size 0.889 0.9906)
			(layers "B.Cu" "B.Mask" "B.Paste")
			(net "GND")
		)
		(zone
			(layer "B.Cu")
			(hatch none 0.5)
			(connect_pads
				(clearance 0)
			)
			(min_thickness 0.25)
			(keepout
				(tracks allowed)
				(vias not_allowed)
				(pads allowed)
				(copperpour not_allowed)
				(footprints allowed)
			)
			(placement
				(enabled no)
				(sheetname "")
			)
			(fill
				(thermal_gap 0.5)
				(thermal_bridge_width 0.5)
				(island_removal_mode 0)
			)
			(polygon
				(pts
					(xy 86.205568 -134.9121) (xy 86.713568 -134.9121) (xy 86.713568 -135.9027) (xy 86.205568 -135.9027)
				)
			)
		)
		(zone
			(layer "B.Cu")
			(hatch none 0.5)
			(connect_pads
				(clearance 0)
			)
			(min_thickness 0.25)
			(keepout
				(tracks not_allowed)
				(vias allowed)
				(pads allowed)
				(copperpour not_allowed)
				(footprints allowed)
			)
			(placement
				(enabled no)
				(sheetname "")
			)
			(fill
				(thermal_gap 0.5)
				(thermal_bridge_width 0.5)
				(island_removal_mode 0)
			)
			(polygon
				(pts
					(xy 86.205568 -134.9121) (xy 86.713568 -134.9121) (xy 86.713568 -135.9027) (xy 86.205568 -135.9027)
				)
			)
		)
	)
	(footprint ""
		(layer "B.Cu")
		(at 18.288 -87.7062)
		(property "Reference" "R9P1"
			(at 0 0 0)
			(layer "B.SilkS")
			(hide yes)
			(effects
				(font
					(size 1.27 1.27)
				)
				(justify mirror)
			)
		)
		(property "Value" ""
			(at 0 0 0)
			(layer "B.Fab")
			(effects
				(font
					(size 1.27 1.27)
				)
				(justify mirror)
			)
		)
		(duplicate_pad_numbers_are_jumpers no)
		(fp_poly
			(pts
				(xy 0.2794 -0.1016) (xy -0.2794 -0.1016) (xy -0.2794 0.9906) (xy 0.2794 0.9906)
			)
			(stroke
				(width 0)
				(type default)
			)
			(fill no)
			(layer "B.CrtYd")
		)
		(fp_line
			(start -0.2794 -0.1016)
			(end 0.2794 -0.1016)
			(stroke
				(width 0.1)
				(type default)
			)
			(layer "B.Fab")
		)
		(fp_line
			(start -0.2794 0.9906)
			(end -0.2794 -0.1016)
			(stroke
				(width 0.1)
				(type default)
			)
			(layer "B.Fab")
		)
		(fp_line
			(start 0.2794 -0.1016)
			(end 0.2794 0.9906)
			(stroke
				(width 0.1)
				(type default)
			)
			(layer "B.Fab")
		)
		(fp_line
			(start 0.2794 0.9906)
			(end -0.2794 0.9906)
			(stroke
				(width 0.1)
				(type default)
			)
			(layer "B.Fab")
		)
		(pad "1" smd rect
			(at 0 0 180)
			(size 0.508 0.508)
			(layers "B.Cu" "B.Mask" "B.Paste")
			(net "PVCCIO_CPU1")
		)
		(pad "2" smd rect
			(at 0 0.889 180)
			(size 0.508 0.508)
			(layers "B.Cu" "B.Mask" "B.Paste")
			(net "SVID_DIO0_CPU1_R")
		)
		(zone
			(layer "B.Cu")
			(hatch none 0.5)
			(connect_pads
				(clearance 0)
			)
			(min_thickness 0.25)
			(keepout
				(tracks allowed)
				(vias not_allowed)
				(pads allowed)
				(copperpour not_allowed)
				(footprints allowed)
			)
			(placement
				(enabled no)
				(sheetname "")
			)
			(fill
				(thermal_gap 0.5)
				(thermal_bridge_width 0.5)
				(island_removal_mode 0)
			)
			(polygon
				(pts
					(xy 18.542 -87.4522) (xy 18.034 -87.4522) (xy 18.034 -87.0712) (xy 18.542 -87.0712)
				)
			)
		)
		(zone
			(layer "B.Cu")
			(hatch none 0.5)
			(connect_pads
				(clearance 0)
			)
			(min_thickness 0.25)
			(keepout
				(tracks not_allowed)
				(vias allowed)
				(pads allowed)
				(copperpour not_allowed)
				(footprints allowed)
			)
			(placement
				(enabled no)
				(sheetname "")
			)
			(fill
				(thermal_gap 0.5)
				(thermal_bridge_width 0.5)
				(island_removal_mode 0)
			)
			(polygon
				(pts
					(xy 18.542 -87.0712) (xy 18.034 -87.0712) (xy 18.034 -87.4522) (xy 18.542 -87.4522)
				)
			)
		)
	)
	(footprint ""
		(layer "B.Cu")
		(at 269.559532 -8.1534 90)
		(property "Reference" "C5U4"
			(at -1.848866 0.752348 90)
			(unlocked yes)
			(layer "B.SilkS")
			(effects
				(font
					(size 1.27 0.9652)
					(thickness 0.1524)
				)
				(justify mirror)
			)
		)
		(property "Value" ""
			(at 0 0 90)
			(layer "B.Fab")
			(effects
				(font
					(size 1.27 1.27)
				)
				(justify mirror)
			)
		)
		(duplicate_pad_numbers_are_jumpers no)
		(fp_rect
			(start 0.500126 1.598422)
			(end -0.500126 -0.201422)
			(stroke
				(width 0)
				(type default)
			)
			(fill no)
			(layer "B.CrtYd")
		)
		(fp_line
			(start 0.500126 -0.201422)
			(end -0.500126 -0.201422)
			(stroke
				(width 0.1)
				(type default)
			)
			(layer "B.Fab")
		)
		(fp_line
			(start -0.500126 -0.201422)
			(end -0.500126 1.598422)
			(stroke
				(width 0.1)
				(type default)
			)
			(layer "B.Fab")
		)
		(fp_line
			(start 0.500126 1.598422)
			(end 0.500126 -0.201422)
			(stroke
				(width 0.1)
				(type default)
			)
			(layer "B.Fab")
		)
		(fp_line
			(start -0.500126 1.598422)
			(end 0.500126 1.598422)
			(stroke
				(width 0.1)
				(type default)
			)
			(layer "B.Fab")
		)
		(pad "1" smd rect
			(at 0 0)
			(size 0.889 0.9906)
			(layers "B.Cu" "B.Mask" "B.Paste")
			(net "PVDDQ_ABC")
		)
		(pad "2" smd rect
			(at 0 1.397)
			(size 0.889 0.9906)
			(layers "B.Cu" "B.Mask" "B.Paste")
			(net "GND")
		)
		(zone
			(layer "B.Cu")
			(hatch none 0.5)
			(connect_pads
				(clearance 0)
			)
			(min_thickness 0.25)
			(keepout
				(tracks allowed)
				(vias not_allowed)
				(pads allowed)
				(copperpour not_allowed)
				(footprints allowed)
			)
			(placement
				(enabled no)
				(sheetname "")
			)
			(fill
				(thermal_gap 0.5)
				(thermal_bridge_width 0.5)
				(island_removal_mode 0)
			)
			(polygon
				(pts
					(xy 270.512032 -8.6487) (xy 270.004032 -8.6487) (xy 270.004032 -7.6581) (xy 270.512032 -7.6581)
				)
			)
		)
		(zone
			(layer "B.Cu")
			(hatch none 0.5)
			(connect_pads
				(clearance 0)
			)
			(min_thickness 0.25)
			(keepout
				(tracks not_allowed)
				(vias allowed)
				(pads allowed)
				(copperpour not_allowed)
				(footprints allowed)
			)
			(placement
				(enabled no)
				(sheetname "")
			)
			(fill
				(thermal_gap 0.5)
				(thermal_bridge_width 0.5)
				(island_removal_mode 0)
			)
			(polygon
				(pts
					(xy 270.512032 -8.6487) (xy 270.004032 -8.6487) (xy 270.004032 -7.6581) (xy 270.512032 -7.6581)
				)
			)
		)
	)
	(footprint ""
		(layer "B.Cu")
		(at 236.715808 -164.90188 -90)
		(property "Reference" "T1D15"
			(at 0 0 90)
			(layer "B.SilkS")
			(hide yes)
			(effects
				(font
					(size 1.27 1.27)
				)
				(justify mirror)
			)
		)
		(property "Value" "*"
			(at 3.4036 -4.46405 270)
			(unlocked yes)
			(layer "B.Fab")
			(hide yes)
			(effects
				(font
					(size 0.889 0.889)
					(thickness 0.1524)
				)
				(justify mirror)
			)
		)
		(property "Device Type" "TEST-PAD-12P-1-GP-U_DISCRET-GBA"
			(at 3.4036 -5.98805 270)
			(unlocked yes)
			(layer "B.Fab")
			(hide yes)
			(effects
				(font
					(size 0.889 0.889)
					(thickness 0.1524)
				)
				(justify mirror)
			)
		)
		(duplicate_pad_numbers_are_jumpers no)
		(fp_line
			(start -2.3622 3.4798)
			(end 2.3876 3.4798)
			(stroke
				(width 0.1524)
				(type default)
			)
			(layer "B.SilkS")
		)
		(fp_line
			(start 2.3876 3.4798)
			(end 2.3876 -4.826)
			(stroke
				(width 0.1524)
				(type default)
			)
			(layer "B.SilkS")
		)
		(fp_line
			(start -2.3622 -4.826)
			(end -2.3622 3.4798)
			(stroke
				(width 0.1524)
				(type default)
			)
			(layer "B.SilkS")
		)
		(fp_line
			(start 2.3876 -4.826)
			(end -2.3622 -4.826)
			(stroke
				(width 0.1524)
				(type default)
			)
			(layer "B.SilkS")
		)
		(fp_rect
			(start 2.6416 3.7338)
			(end -2.6162 -5.08)
			(stroke
				(width 0)
				(type default)
			)
			(fill no)
			(layer "B.CrtYd")
		)
		(fp_rect
			(start 2.6416 3.7338)
			(end -2.6162 -5.08)
			(stroke
				(width 0)
				(type default)
			)
			(fill no)
			(layer "B.Fab")
		)
		(pad "1" smd circle
			(at -0.496824 -1.301496 90)
			(size 0.6604 0.6604)
			(layers "B.Cu" "B.Mask" "B.Paste")
			(net "L3_85OHM_10INCH_DP")
		)
		(pad "2" smd circle
			(at 0.503936 -1.301496 90)
			(size 0.6604 0.6604)
			(layers "B.Cu" "B.Mask" "B.Paste")
			(net "L3_85OHM_10INCH_DN")
		)
		(pad "3" smd custom
			(at 0.00889 0.370078 90)
			(size 0.74295 0.74295)
			(layers "B.Cu" "B.Mask" "B.Paste")
			(net "GND")
			(options
				(clearance outline)
				(anchor circle)
			)
			(primitives
				(gr_poly
					(pts
						(xy -2.1209 -1.4859) (xy 2.1209 -1.4859) (xy 2.1209 1.4859) (xy 1.08585 1.4859) (xy 1.08585 0.4699)
						(xy -1.08585 0.4699) (xy -1.08585 1.4859) (xy -2.1209 1.4859)
					)
					(width 0)
					(fill yes)
				)
			)
		)
		(pad "4" thru_hole circle
			(at -1.266444 -3.851656 90)
			(size 1.4478 1.4478)
			(drill 1.0414)
			(layers "*.Cu" "*.Mask")
			(remove_unused_layers no)
			(net "GND")
			(clearance 0.1524)
			(thermal_gap 0.1524)
		)
		(pad "5" thru_hole circle
			(at 1.273556 -3.851656 90)
			(size 1.4478 1.4478)
			(drill 1.0414)
			(layers "*.Cu" "*.Mask")
			(remove_unused_layers no)
			(net "GND")
			(clearance 0.1524)
			(thermal_gap 0.1524)
		)
		(pad "6" thru_hole circle
			(at -1.266444 2.498344 90)
			(size 1.4478 1.4478)
			(drill 1.0414)
			(layers "*.Cu" "*.Mask")
			(remove_unused_layers no)
			(net "GND")
			(clearance 0.1524)
			(thermal_gap 0.1524)
		)
		(pad "7" thru_hole circle
			(at 1.273556 2.498344 90)
			(size 1.4478 1.4478)
			(drill 1.0414)
			(layers "*.Cu" "*.Mask")
			(remove_unused_layers no)
			(net "GND")
			(clearance 0.1524)
			(thermal_gap 0.1524)
		)
		(pad "8" thru_hole circle
			(at -1.27 -0.4572 90)
			(size 0.7112 0.7112)
			(drill 0.4064)
			(layers "*.Cu" "*.Mask")
			(remove_unused_layers no)
			(net "GND")
			(clearance 0.1016)
			(thermal_gap 0.1016)
		)
		(pad "9" thru_hole circle
			(at -1.27 0.762 90)
			(size 0.7112 0.7112)
			(drill 0.4064)
			(layers "*.Cu" "*.Mask")
			(remove_unused_layers no)
			(net "GND")
			(clearance 0.1016)
			(thermal_gap 0.1016)
		)
		(pad "10" thru_hole circle
			(at 0.0254 0.762 90)
			(size 0.7112 0.7112)
			(drill 0.4064)
			(layers "*.Cu" "*.Mask")
			(remove_unused_layers no)
			(net "GND")
			(clearance 0.1016)
			(thermal_gap 0.1016)
		)
		(pad "11" thru_hole circle
			(at 1.27 0.762 90)
			(size 0.7112 0.7112)
			(drill 0.4064)
			(layers "*.Cu" "*.Mask")
			(remove_unused_layers no)
			(net "GND")
			(clearance 0.1016)
			(thermal_gap 0.1016)
		)
		(pad "12" thru_hole circle
			(at 1.27 -0.4572 90)
			(size 0.7112 0.7112)
			(drill 0.4064)
			(layers "*.Cu" "*.Mask")
			(remove_unused_layers no)
			(net "GND")
			(clearance 0.1016)
			(thermal_gap 0.1016)
		)
	)
	(footprint ""
		(layer "B.Cu")
		(at 497.794534 -38.029896 -90)
		(property "Reference" "R9F27"
			(at 0 0 90)
			(layer "B.SilkS")
			(hide yes)
			(effects
				(font
					(size 1.27 1.27)
				)
				(justify mirror)
			)
		)
		(property "Value" ""
			(at 0 0 90)
			(layer "B.Fab")
			(effects
				(font
					(size 1.27 1.27)
				)
				(justify mirror)
			)
		)
		(duplicate_pad_numbers_are_jumpers no)
		(fp_poly
			(pts
				(xy 0.2794 -0.1016) (xy -0.2794 -0.1016) (xy -0.2794 0.9906) (xy 0.2794 0.9906)
			)
			(stroke
				(width 0)
				(type default)
			)
			(fill no)
			(layer "B.CrtYd")
		)
		(fp_line
			(start -0.2794 0.9906)
			(end -0.2794 -0.1016)
			(stroke
				(width 0.1)
				(type default)
			)
			(layer "B.Fab")
		)
		(fp_line
			(start 0.2794 0.9906)
			(end -0.2794 0.9906)
			(stroke
				(width 0.1)
				(type default)
			)
			(layer "B.Fab")
		)
		(fp_line
			(start -0.2794 -0.1016)
			(end 0.2794 -0.1016)
			(stroke
				(width 0.1)
				(type default)
			)
			(layer "B.Fab")
		)
		(fp_line
			(start 0.2794 -0.1016)
			(end 0.2794 0.9906)
			(stroke
				(width 0.1)
				(type default)
			)
			(layer "B.Fab")
		)
		(pad "1" smd rect
			(at 0 0 90)
			(size 0.508 0.508)
			(layers "B.Cu" "B.Mask" "B.Paste")
			(net "UART_MUX_OUT_R")
		)
		(pad "2" smd rect
			(at 0 0.889 90)
			(size 0.508 0.508)
			(layers "B.Cu" "B.Mask" "B.Paste")
			(net "SPA_MID_DBG_TX")
		)
		(zone
			(layer "B.Cu")
			(hatch none 0.5)
			(connect_pads
				(clearance 0)
			)
			(min_thickness 0.25)
			(keepout
				(tracks not_allowed)
				(vias allowed)
				(pads allowed)
				(copperpour not_allowed)
				(footprints allowed)
			)
			(placement
				(enabled no)
				(sheetname "")
			)
			(fill
				(thermal_gap 0.5)
				(thermal_bridge_width 0.5)
				(island_removal_mode 0)
			)
			(polygon
				(pts
					(xy 497.159534 -37.775896) (xy 497.159534 -38.283896) (xy 497.540534 -38.283896) (xy 497.540534 -37.775896)
				)
			)
		)
		(zone
			(layer "B.Cu")
			(hatch none 0.5)
			(connect_pads
				(clearance 0)
			)
			(min_thickness 0.25)
			(keepout
				(tracks allowed)
				(vias not_allowed)
				(pads allowed)
				(copperpour not_allowed)
				(footprints allowed)
			)
			(placement
				(enabled no)
				(sheetname "")
			)
			(fill
				(thermal_gap 0.5)
				(thermal_bridge_width 0.5)
				(island_removal_mode 0)
			)
			(polygon
				(pts
					(xy 497.540534 -37.775896) (xy 497.540534 -38.283896) (xy 497.159534 -38.283896) (xy 497.159534 -37.775896)
				)
			)
		)
	)
	(footprint ""
		(layer "B.Cu")
		(at 431.609246 -17.585182 90)
		(property "Reference" "C1U19"
			(at 0 0 90)
			(layer "B.SilkS")
			(hide yes)
			(effects
				(font
					(size 1.27 1.27)
				)
				(justify mirror)
			)
		)
		(property "Value" ""
			(at 0 0 90)
			(layer "B.Fab")
			(effects
				(font
					(size 1.27 1.27)
				)
				(justify mirror)
			)
		)
		(duplicate_pad_numbers_are_jumpers no)
		(fp_poly
			(pts
				(xy -0.3048 -0.1016) (xy -0.3048 0.9906) (xy 0.3048 0.9906) (xy 0.3048 -0.1016)
			)
			(stroke
				(width 0)
				(type default)
			)
			(fill no)
			(layer "B.CrtYd")
		)
		(fp_line
			(start 0.3048 -0.1016)
			(end 0.3048 0.9906)
			(stroke
				(width 0.1)
				(type default)
			)
			(layer "B.Fab")
		)
		(fp_line
			(start -0.3048 -0.1016)
			(end 0.3048 -0.1016)
			(stroke
				(width 0.1)
				(type default)
			)
			(layer "B.Fab")
		)
		(fp_line
			(start 0.3048 0.9906)
			(end -0.3048 0.9906)
			(stroke
				(width 0.1)
				(type default)
			)
			(layer "B.Fab")
		)
		(fp_line
			(start -0.3048 0.9906)
			(end -0.3048 -0.1016)
			(stroke
				(width 0.1)
				(type default)
			)
			(layer "B.Fab")
		)
		(pad "1" smd rect
			(at 0 0 270)
			(size 0.508 0.508)
			(layers "B.Cu" "B.Mask" "B.Paste")
			(net "P3V3")
		)
		(pad "2" smd rect
			(at 0 0.889 270)
			(size 0.508 0.508)
			(layers "B.Cu" "B.Mask" "B.Paste")
			(net "GND")
		)
		(zone
			(layer "B.Cu")
			(hatch none 0.5)
			(connect_pads
				(clearance 0)
			)
			(min_thickness 0.25)
			(keepout
				(tracks allowed)
				(vias not_allowed)
				(pads allowed)
				(copperpour not_allowed)
				(footprints allowed)
			)
			(placement
				(enabled no)
				(sheetname "")
			)
			(fill
				(thermal_gap 0.5)
				(thermal_bridge_width 0.5)
				(island_removal_mode 0)
			)
			(polygon
				(pts
					(xy 431.863246 -17.839182) (xy 431.863246 -17.331182) (xy 432.244246 -17.331182) (xy 432.244246 -17.839182)
				)
			)
		)
		(zone
			(layer "B.Cu")
			(hatch none 0.5)
			(connect_pads
				(clearance 0)
			)
			(min_thickness 0.25)
			(keepout
				(tracks not_allowed)
				(vias allowed)
				(pads allowed)
				(copperpour not_allowed)
				(footprints allowed)
			)
			(placement
				(enabled no)
				(sheetname "")
			)
			(fill
				(thermal_gap 0.5)
				(thermal_bridge_width 0.5)
				(island_removal_mode 0)
			)
			(polygon
				(pts
					(xy 432.244246 -17.839182) (xy 432.244246 -17.331182) (xy 431.863246 -17.331182) (xy 431.863246 -17.839182)
				)
			)
		)
	)
	(footprint ""
		(layer "B.Cu")
		(at 348.615 -142.914624 -90)
		(property "Reference" "C3L16"
			(at 0 0 90)
			(layer "B.SilkS")
			(hide yes)
			(effects
				(font
					(size 1.27 1.27)
				)
				(justify mirror)
			)
		)
		(property "Value" ""
			(at 0 0 90)
			(layer "B.Fab")
			(effects
				(font
					(size 1.27 1.27)
				)
				(justify mirror)
			)
		)
		(duplicate_pad_numbers_are_jumpers no)
		(fp_poly
			(pts
				(xy 0.7239 -0.2159) (xy -0.7239 -0.2159) (xy -0.7239 1.9939) (xy 0.7239 1.9939)
			)
			(stroke
				(width 0)
				(type default)
			)
			(fill no)
			(layer "B.CrtYd")
		)
		(fp_line
			(start -0.7239 1.9939)
			(end -0.7239 -0.2159)
			(stroke
				(width 0.1)
				(type default)
			)
			(layer "B.Fab")
		)
		(fp_line
			(start 0.7239 1.9939)
			(end -0.7239 1.9939)
			(stroke
				(width 0.1)
				(type default)
			)
			(layer "B.Fab")
		)
		(fp_line
			(start -0.7239 -0.2159)
			(end 0.7239 -0.2159)
			(stroke
				(width 0.1)
				(type default)
			)
			(layer "B.Fab")
		)
		(fp_line
			(start 0.7239 -0.2159)
			(end 0.7239 1.9939)
			(stroke
				(width 0.1)
				(type default)
			)
			(layer "B.Fab")
		)
		(pad "1" smd rect
			(at 0 0 90)
			(size 1.27 1.016)
			(layers "B.Cu" "B.Mask" "B.Paste")
			(net "VR_FET_SW_P12V_STBY_PVDDQ_DEF")
		)
		(pad "2" smd rect
			(at 0 1.778 90)
			(size 1.27 1.016)
			(layers "B.Cu" "B.Mask" "B.Paste")
			(net "GND")
		)
		(zone
			(layer "B.Cu")
			(hatch none 0.5)
			(connect_pads
				(clearance 0)
			)
			(min_thickness 0.25)
			(keepout
				(tracks not_allowed)
				(vias allowed)
				(pads allowed)
				(copperpour not_allowed)
				(footprints allowed)
			)
			(placement
				(enabled no)
				(sheetname "")
			)
			(fill
				(thermal_gap 0.5)
				(thermal_bridge_width 0.5)
				(island_removal_mode 0)
			)
			(polygon
				(pts
					(xy 348.107 -142.279624) (xy 348.107 -143.549624) (xy 347.345 -143.549624) (xy 347.345 -142.279624)
				)
			)
		)
	)
	(footprint ""
		(layer "B.Cu")
		(at 117.1956 -71.882 -90)
		(property "Reference" "R7P19"
			(at 0 0 90)
			(layer "B.SilkS")
			(hide yes)
			(effects
				(font
					(size 1.27 1.27)
				)
				(justify mirror)
			)
		)
		(property "Value" ""
			(at 0 0 90)
			(layer "B.Fab")
			(effects
				(font
					(size 1.27 1.27)
				)
				(justify mirror)
			)
		)
		(duplicate_pad_numbers_are_jumpers no)
		(fp_poly
			(pts
				(xy 0.2794 -0.1016) (xy -0.2794 -0.1016) (xy -0.2794 0.9906) (xy 0.2794 0.9906)
			)
			(stroke
				(width 0)
				(type default)
			)
			(fill no)
			(layer "B.CrtYd")
		)
		(fp_line
			(start -0.2794 0.9906)
			(end -0.2794 -0.1016)
			(stroke
				(width 0.1)
				(type default)
			)
			(layer "B.Fab")
		)
		(fp_line
			(start 0.2794 0.9906)
			(end -0.2794 0.9906)
			(stroke
				(width 0.1)
				(type default)
			)
			(layer "B.Fab")
		)
		(fp_line
			(start -0.2794 -0.1016)
			(end 0.2794 -0.1016)
			(stroke
				(width 0.1)
				(type default)
			)
			(layer "B.Fab")
		)
		(fp_line
			(start 0.2794 -0.1016)
			(end 0.2794 0.9906)
			(stroke
				(width 0.1)
				(type default)
			)
			(layer "B.Fab")
		)
		(pad "1" smd rect
			(at 0 0 90)
			(size 0.508 0.508)
			(layers "B.Cu" "B.Mask" "B.Paste")
			(net "A_CPU1_GHJ_RCOMP2")
		)
		(pad "2" smd rect
			(at 0 0.889 90)
			(size 0.508 0.508)
			(layers "B.Cu" "B.Mask" "B.Paste")
			(net "GND")
		)
		(zone
			(layer "B.Cu")
			(hatch none 0.5)
			(connect_pads
				(clearance 0)
			)
			(min_thickness 0.25)
			(keepout
				(tracks not_allowed)
				(vias allowed)
				(pads allowed)
				(copperpour not_allowed)
				(footprints allowed)
			)
			(placement
				(enabled no)
				(sheetname "")
			)
			(fill
				(thermal_gap 0.5)
				(thermal_bridge_width 0.5)
				(island_removal_mode 0)
			)
			(polygon
				(pts
					(xy 116.5606 -71.628) (xy 116.5606 -72.136) (xy 116.9416 -72.136) (xy 116.9416 -71.628)
				)
			)
		)
		(zone
			(layer "B.Cu")
			(hatch none 0.5)
			(connect_pads
				(clearance 0)
			)
			(min_thickness 0.25)
			(keepout
				(tracks allowed)
				(vias not_allowed)
				(pads allowed)
				(copperpour not_allowed)
				(footprints allowed)
			)
			(placement
				(enabled no)
				(sheetname "")
			)
			(fill
				(thermal_gap 0.5)
				(thermal_bridge_width 0.5)
				(island_removal_mode 0)
			)
			(polygon
				(pts
					(xy 116.9416 -71.628) (xy 116.9416 -72.136) (xy 116.5606 -72.136) (xy 116.5606 -71.628)
				)
			)
		)
	)
	(footprint ""
		(layer "B.Cu")
		(at 482.65969 -58.069988 -90)
		(property "Reference" "R8E28"
			(at 0 0 90)
			(layer "B.SilkS")
			(hide yes)
			(effects
				(font
					(size 1.27 1.27)
				)
				(justify mirror)
			)
		)
		(property "Value" ""
			(at 0 0 90)
			(layer "B.Fab")
			(effects
				(font
					(size 1.27 1.27)
				)
				(justify mirror)
			)
		)
		(duplicate_pad_numbers_are_jumpers no)
		(fp_poly
			(pts
				(xy 0.2794 -0.1016) (xy -0.2794 -0.1016) (xy -0.2794 0.9906) (xy 0.2794 0.9906)
			)
			(stroke
				(width 0)
				(type default)
			)
			(fill no)
			(layer "B.CrtYd")
		)
		(fp_line
			(start -0.2794 0.9906)
			(end -0.2794 -0.1016)
			(stroke
				(width 0.1)
				(type default)
			)
			(layer "B.Fab")
		)
		(fp_line
			(start 0.2794 0.9906)
			(end -0.2794 0.9906)
			(stroke
				(width 0.1)
				(type default)
			)
			(layer "B.Fab")
		)
		(fp_line
			(start -0.2794 -0.1016)
			(end 0.2794 -0.1016)
			(stroke
				(width 0.1)
				(type default)
			)
			(layer "B.Fab")
		)
		(fp_line
			(start 0.2794 -0.1016)
			(end 0.2794 0.9906)
			(stroke
				(width 0.1)
				(type default)
			)
			(layer "B.Fab")
		)
		(pad "1" smd rect
			(at 0 0 90)
			(size 0.508 0.508)
			(layers "B.Cu" "B.Mask" "B.Paste")
			(net "FM_PE_SLOTX24_WAKE_N")
		)
		(pad "2" smd rect
			(at 0 0.889 90)
			(size 0.508 0.508)
			(layers "B.Cu" "B.Mask" "B.Paste")
			(net "FM_ALL_WAKE_N")
		)
		(zone
			(layer "B.Cu")
			(hatch none 0.5)
			(connect_pads
				(clearance 0)
			)
			(min_thickness 0.25)
			(keepout
				(tracks not_allowed)
				(vias allowed)
				(pads allowed)
				(copperpour not_allowed)
				(footprints allowed)
			)
			(placement
				(enabled no)
				(sheetname "")
			)
			(fill
				(thermal_gap 0.5)
				(thermal_bridge_width 0.5)
				(island_removal_mode 0)
			)
			(polygon
				(pts
					(xy 482.02469 -57.815988) (xy 482.02469 -58.323988) (xy 482.40569 -58.323988) (xy 482.40569 -57.815988)
				)
			)
		)
		(zone
			(layer "B.Cu")
			(hatch none 0.5)
			(connect_pads
				(clearance 0)
			)
			(min_thickness 0.25)
			(keepout
				(tracks allowed)
				(vias not_allowed)
				(pads allowed)
				(copperpour not_allowed)
				(footprints allowed)
			)
			(placement
				(enabled no)
				(sheetname "")
			)
			(fill
				(thermal_gap 0.5)
				(thermal_bridge_width 0.5)
				(island_removal_mode 0)
			)
			(polygon
				(pts
					(xy 482.40569 -57.815988) (xy 482.40569 -58.323988) (xy 482.02469 -58.323988) (xy 482.02469 -57.815988)
				)
			)
		)
	)
	(footprint ""
		(layer "B.Cu")
		(at 470.027 -61.722 -90)
		(property "Reference" "R1R17"
			(at 0 0 90)
			(layer "B.SilkS")
			(hide yes)
			(effects
				(font
					(size 1.27 1.27)
				)
				(justify mirror)
			)
		)
		(property "Value" ""
			(at 0 0 90)
			(layer "B.Fab")
			(effects
				(font
					(size 1.27 1.27)
				)
				(justify mirror)
			)
		)
		(duplicate_pad_numbers_are_jumpers no)
		(fp_poly
			(pts
				(xy 0.2794 -0.1016) (xy -0.2794 -0.1016) (xy -0.2794 0.9906) (xy 0.2794 0.9906)
			)
			(stroke
				(width 0)
				(type default)
			)
			(fill no)
			(layer "B.CrtYd")
		)
		(fp_line
			(start -0.2794 0.9906)
			(end -0.2794 -0.1016)
			(stroke
				(width 0.1)
				(type default)
			)
			(layer "B.Fab")
		)
		(fp_line
			(start 0.2794 0.9906)
			(end -0.2794 0.9906)
			(stroke
				(width 0.1)
				(type default)
			)
			(layer "B.Fab")
		)
		(fp_line
			(start -0.2794 -0.1016)
			(end 0.2794 -0.1016)
			(stroke
				(width 0.1)
				(type default)
			)
			(layer "B.Fab")
		)
		(fp_line
			(start 0.2794 -0.1016)
			(end 0.2794 0.9906)
			(stroke
				(width 0.1)
				(type default)
			)
			(layer "B.Fab")
		)
		(pad "1" smd rect
			(at 0 0 90)
			(size 0.508 0.508)
			(layers "B.Cu" "B.Mask" "B.Paste")
			(net "P3V3_STBY")
		)
		(pad "2" smd rect
			(at 0 0.889 90)
			(size 0.508 0.508)
			(layers "B.Cu" "B.Mask" "B.Paste")
			(net "SMB_PCH_MEZZ_LOM2_SDA")
		)
		(zone
			(layer "B.Cu")
			(hatch none 0.5)
			(connect_pads
				(clearance 0)
			)
			(min_thickness 0.25)
			(keepout
				(tracks not_allowed)
				(vias allowed)
				(pads allowed)
				(copperpour not_allowed)
				(footprints allowed)
			)
			(placement
				(enabled no)
				(sheetname "")
			)
			(fill
				(thermal_gap 0.5)
				(thermal_bridge_width 0.5)
				(island_removal_mode 0)
			)
			(polygon
				(pts
					(xy 469.392 -61.468) (xy 469.392 -61.976) (xy 469.773 -61.976) (xy 469.773 -61.468)
				)
			)
		)
		(zone
			(layer "B.Cu")
			(hatch none 0.5)
			(connect_pads
				(clearance 0)
			)
			(min_thickness 0.25)
			(keepout
				(tracks allowed)
				(vias not_allowed)
				(pads allowed)
				(copperpour not_allowed)
				(footprints allowed)
			)
			(placement
				(enabled no)
				(sheetname "")
			)
			(fill
				(thermal_gap 0.5)
				(thermal_bridge_width 0.5)
				(island_removal_mode 0)
			)
			(polygon
				(pts
					(xy 469.773 -61.468) (xy 469.773 -61.976) (xy 469.392 -61.976) (xy 469.392 -61.468)
				)
			)
		)
	)
	(footprint ""
		(layer "B.Cu")
		(at 29.690568 -135.763)
		(property "Reference" "R9L11"
			(at 0 0 0)
			(layer "B.SilkS")
			(hide yes)
			(effects
				(font
					(size 1.27 1.27)
				)
				(justify mirror)
			)
		)
		(property "Value" ""
			(at 0 0 0)
			(layer "B.Fab")
			(effects
				(font
					(size 1.27 1.27)
				)
				(justify mirror)
			)
		)
		(duplicate_pad_numbers_are_jumpers no)
		(fp_poly
			(pts
				(xy 0.2794 -0.1016) (xy -0.2794 -0.1016) (xy -0.2794 0.9906) (xy 0.2794 0.9906)
			)
			(stroke
				(width 0)
				(type default)
			)
			(fill no)
			(layer "B.CrtYd")
		)
		(fp_line
			(start -0.2794 -0.1016)
			(end 0.2794 -0.1016)
			(stroke
				(width 0.1)
				(type default)
			)
			(layer "B.Fab")
		)
		(fp_line
			(start -0.2794 0.9906)
			(end -0.2794 -0.1016)
			(stroke
				(width 0.1)
				(type default)
			)
			(layer "B.Fab")
		)
		(fp_line
			(start 0.2794 -0.1016)
			(end 0.2794 0.9906)
			(stroke
				(width 0.1)
				(type default)
			)
			(layer "B.Fab")
		)
		(fp_line
			(start 0.2794 0.9906)
			(end -0.2794 0.9906)
			(stroke
				(width 0.1)
				(type default)
			)
			(layer "B.Fab")
		)
		(pad "1" smd rect
			(at 0 0 180)
			(size 0.508 0.508)
			(layers "B.Cu" "B.Mask" "B.Paste")
			(net "M_K_VREF")
		)
		(pad "2" smd rect
			(at 0 0.889 180)
			(size 0.508 0.508)
			(layers "B.Cu" "B.Mask" "B.Paste")
			(net "GND")
		)
		(zone
			(layer "B.Cu")
			(hatch none 0.5)
			(connect_pads
				(clearance 0)
			)
			(min_thickness 0.25)
			(keepout
				(tracks allowed)
				(vias not_allowed)
				(pads allowed)
				(copperpour not_allowed)
				(footprints allowed)
			)
			(placement
				(enabled no)
				(sheetname "")
			)
			(fill
				(thermal_gap 0.5)
				(thermal_bridge_width 0.5)
				(island_removal_mode 0)
			)
			(polygon
				(pts
					(xy 29.944568 -135.509) (xy 29.436568 -135.509) (xy 29.436568 -135.128) (xy 29.944568 -135.128)
				)
			)
		)
		(zone
			(layer "B.Cu")
			(hatch none 0.5)
			(connect_pads
				(clearance 0)
			)
			(min_thickness 0.25)
			(keepout
				(tracks not_allowed)
				(vias allowed)
				(pads allowed)
				(copperpour not_allowed)
				(footprints allowed)
			)
			(placement
				(enabled no)
				(sheetname "")
			)
			(fill
				(thermal_gap 0.5)
				(thermal_bridge_width 0.5)
				(island_removal_mode 0)
			)
			(polygon
				(pts
					(xy 29.944568 -135.128) (xy 29.436568 -135.128) (xy 29.436568 -135.509) (xy 29.944568 -135.509)
				)
			)
		)
	)
	(footprint ""
		(layer "B.Cu")
		(at 351.421192 -77.834236 180)
		(property "Reference" "C3P28"
			(at 0 0 0)
			(layer "B.SilkS")
			(hide yes)
			(effects
				(font
					(size 1.27 1.27)
				)
				(justify mirror)
			)
		)
		(property "Value" ""
			(at 0 0 0)
			(layer "B.Fab")
			(effects
				(font
					(size 1.27 1.27)
				)
				(justify mirror)
			)
		)
		(duplicate_pad_numbers_are_jumpers no)
		(fp_poly
			(pts
				(xy -0.3048 -0.1016) (xy -0.3048 0.9906) (xy 0.3048 0.9906) (xy 0.3048 -0.1016)
			)
			(stroke
				(width 0)
				(type default)
			)
			(fill no)
			(layer "B.CrtYd")
		)
		(fp_line
			(start 0.3048 0.9906)
			(end -0.3048 0.9906)
			(stroke
				(width 0.1)
				(type default)
			)
			(layer "B.Fab")
		)
		(fp_line
			(start 0.3048 -0.1016)
			(end 0.3048 0.9906)
			(stroke
				(width 0.1)
				(type default)
			)
			(layer "B.Fab")
		)
		(fp_line
			(start -0.3048 0.9906)
			(end -0.3048 -0.1016)
			(stroke
				(width 0.1)
				(type default)
			)
			(layer "B.Fab")
		)
		(fp_line
			(start -0.3048 -0.1016)
			(end 0.3048 -0.1016)
			(stroke
				(width 0.1)
				(type default)
			)
			(layer "B.Fab")
		)
		(pad "1" smd rect
			(at 0 0)
			(size 0.508 0.508)
			(layers "B.Cu" "B.Mask" "B.Paste")
			(net "P3E_CPU0_PE1_SS_TXN<4>")
		)
		(pad "2" smd rect
			(at 0 0.889)
			(size 0.508 0.508)
			(layers "B.Cu" "B.Mask" "B.Paste")
			(net "P3E_CPU0_PE1_PCH_TXN<4>")
		)
		(zone
			(layer "B.Cu")
			(hatch none 0.5)
			(connect_pads
				(clearance 0)
			)
			(min_thickness 0.25)
			(keepout
				(tracks not_allowed)
				(vias allowed)
				(pads allowed)
				(copperpour not_allowed)
				(footprints allowed)
			)
			(placement
				(enabled no)
				(sheetname "")
			)
			(fill
				(thermal_gap 0.5)
				(thermal_bridge_width 0.5)
				(island_removal_mode 0)
			)
			(polygon
				(pts
					(xy 351.167192 -78.469236) (xy 351.675192 -78.469236) (xy 351.675192 -78.088236) (xy 351.167192 -78.088236)
				)
			)
		)
		(zone
			(layer "B.Cu")
			(hatch none 0.5)
			(connect_pads
				(clearance 0)
			)
			(min_thickness 0.25)
			(keepout
				(tracks allowed)
				(vias not_allowed)
				(pads allowed)
				(copperpour not_allowed)
				(footprints allowed)
			)
			(placement
				(enabled no)
				(sheetname "")
			)
			(fill
				(thermal_gap 0.5)
				(thermal_bridge_width 0.5)
				(island_removal_mode 0)
			)
			(polygon
				(pts
					(xy 351.167192 -78.088236) (xy 351.675192 -78.088236) (xy 351.675192 -78.469236) (xy 351.167192 -78.469236)
				)
			)
		)
	)
	(footprint ""
		(layer "B.Cu")
		(at 440.458606 -16.164306 90)
		(property "Reference" "R1U30"
			(at 0 0 90)
			(layer "B.SilkS")
			(hide yes)
			(effects
				(font
					(size 1.27 1.27)
				)
				(justify mirror)
			)
		)
		(property "Value" ""
			(at 0 0 90)
			(layer "B.Fab")
			(effects
				(font
					(size 1.27 1.27)
				)
				(justify mirror)
			)
		)
		(duplicate_pad_numbers_are_jumpers no)
		(fp_poly
			(pts
				(xy 0.2794 -0.1016) (xy -0.2794 -0.1016) (xy -0.2794 0.9906) (xy 0.2794 0.9906)
			)
			(stroke
				(width 0)
				(type default)
			)
			(fill no)
			(layer "B.CrtYd")
		)
		(fp_line
			(start 0.2794 -0.1016)
			(end 0.2794 0.9906)
			(stroke
				(width 0.1)
				(type default)
			)
			(layer "B.Fab")
		)
		(fp_line
			(start -0.2794 -0.1016)
			(end 0.2794 -0.1016)
			(stroke
				(width 0.1)
				(type default)
			)
			(layer "B.Fab")
		)
		(fp_line
			(start 0.2794 0.9906)
			(end -0.2794 0.9906)
			(stroke
				(width 0.1)
				(type default)
			)
			(layer "B.Fab")
		)
		(fp_line
			(start -0.2794 0.9906)
			(end -0.2794 -0.1016)
			(stroke
				(width 0.1)
				(type default)
			)
			(layer "B.Fab")
		)
		(pad "1" smd rect
			(at 0 0 270)
			(size 0.508 0.508)
			(layers "B.Cu" "B.Mask" "B.Paste")
			(net "PD_DIR_2")
		)
		(pad "2" smd rect
			(at 0 0.889 270)
			(size 0.508 0.508)
			(layers "B.Cu" "B.Mask" "B.Paste")
			(net "GND")
		)
		(zone
			(layer "B.Cu")
			(hatch none 0.5)
			(connect_pads
				(clearance 0)
			)
			(min_thickness 0.25)
			(keepout
				(tracks allowed)
				(vias not_allowed)
				(pads allowed)
				(copperpour not_allowed)
				(footprints allowed)
			)
			(placement
				(enabled no)
				(sheetname "")
			)
			(fill
				(thermal_gap 0.5)
				(thermal_bridge_width 0.5)
				(island_removal_mode 0)
			)
			(polygon
				(pts
					(xy 440.712606 -16.418306) (xy 440.712606 -15.910306) (xy 441.093606 -15.910306) (xy 441.093606 -16.418306)
				)
			)
		)
		(zone
			(layer "B.Cu")
			(hatch none 0.5)
			(connect_pads
				(clearance 0)
			)
			(min_thickness 0.25)
			(keepout
				(tracks not_allowed)
				(vias allowed)
				(pads allowed)
				(copperpour not_allowed)
				(footprints allowed)
			)
			(placement
				(enabled no)
				(sheetname "")
			)
			(fill
				(thermal_gap 0.5)
				(thermal_bridge_width 0.5)
				(island_removal_mode 0)
			)
			(polygon
				(pts
					(xy 441.093606 -16.418306) (xy 441.093606 -15.910306) (xy 440.712606 -15.910306) (xy 440.712606 -16.418306)
				)
			)
		)
	)
	(footprint ""
		(layer "B.Cu")
		(at 394.95984 -37.9984 180)
		(property "Reference" "U8G1"
			(at 0 0 0)
			(layer "B.SilkS")
			(hide yes)
			(effects
				(font
					(size 1.27 1.27)
				)
				(justify mirror)
			)
		)
		(property "Value" "*"
			(at 2.3622 -8.3185 180)
			(unlocked yes)
			(layer "B.Fab")
			(hide yes)
			(effects
				(font
					(size 1.27 1.016)
					(thickness 0.1524)
				)
				(justify mirror)
			)
		)
		(property "Device Type" "SN74LVC2G07DCKR-GP_DISCRET-G4-A"
			(at 2.3622 -10.2235 180)
			(unlocked yes)
			(layer "B.Fab")
			(hide yes)
			(effects
				(font
					(size 1.27 1.016)
					(thickness 0.1524)
				)
				(justify mirror)
			)
		)
		(duplicate_pad_numbers_are_jumpers no)
		(fp_line
			(start 1.5494 1.7907)
			(end 1.5494 0.8255)
			(stroke
				(width 0.3302)
				(type default)
			)
			(layer "B.SilkS")
		)
		(fp_line
			(start 1.4478 1.7018)
			(end -1.4478 1.7018)
			(stroke
				(width 0.1524)
				(type default)
			)
			(layer "B.SilkS")
		)
		(fp_line
			(start 1.4478 -1.7018)
			(end 1.4478 1.7018)
			(stroke
				(width 0.1524)
				(type default)
			)
			(layer "B.SilkS")
		)
		(fp_line
			(start 0.5715 1.7907)
			(end 1.5494 1.7907)
			(stroke
				(width 0.3302)
				(type default)
			)
			(layer "B.SilkS")
		)
		(fp_line
			(start -1.4478 1.7018)
			(end -1.4478 -1.7018)
			(stroke
				(width 0.1524)
				(type default)
			)
			(layer "B.SilkS")
		)
		(fp_line
			(start -1.4478 -1.7018)
			(end 1.4478 -1.7018)
			(stroke
				(width 0.1524)
				(type default)
			)
			(layer "B.SilkS")
		)
		(fp_poly
			(pts
				(xy 0.6604 1.7272) (xy 1.016 2.0828) (xy 0.3048 2.0828)
			)
			(stroke
				(width 0)
				(type default)
			)
			(fill yes)
			(layer "B.SilkS")
		)
		(fp_poly
			(pts
				(xy 1.524 -1.778) (xy -1.524 -1.778) (xy -1.524 1.778) (xy 1.524 1.778)
			)
			(stroke
				(width 0)
				(type default)
			)
			(fill no)
			(layer "B.CrtYd")
		)
		(fp_poly
			(pts
				(xy 1.524 -1.778) (xy -1.524 -1.778) (xy -1.524 1.778) (xy 1.524 1.778)
			)
			(stroke
				(width 0)
				(type default)
			)
			(fill no)
			(layer "B.Fab")
		)
		(pad "1" smd rect
			(at 0.65024 0.9398)
			(size 0.4064 1.016)
			(layers "B.Cu" "B.Mask" "B.Paste")
			(net "RST_PCH_SYSRST_BTN_OUT_N")
		)
		(pad "2" smd rect
			(at 0 0.9398)
			(size 0.4064 1.016)
			(layers "B.Cu" "B.Mask" "B.Paste")
			(net "GND")
		)
		(pad "3" smd rect
			(at -0.65024 0.9398)
			(size 0.4064 1.016)
			(layers "B.Cu" "B.Mask" "B.Paste")
			(net "FM_PCH_PWRBTN_OUT_N")
		)
		(pad "4" smd rect
			(at -0.65024 -0.9398)
			(size 0.4064 1.016)
			(layers "B.Cu" "B.Mask" "B.Paste")
			(net "FM_PCH_PWRBTN_R_N")
		)
		(pad "5" smd rect
			(at 0 -0.9398)
			(size 0.4064 1.016)
			(layers "B.Cu" "B.Mask" "B.Paste")
			(net "P3V3_STBY")
		)
		(pad "6" smd rect
			(at 0.65024 -0.9398)
			(size 0.4064 1.016)
			(layers "B.Cu" "B.Mask" "B.Paste")
			(net "RST_BMC_SYSRST_BTN_OUT_B_R_N")
		)
	)
	(footprint ""
		(layer "B.Cu")
		(at 395.548358 -12.589002)
		(property "Reference" "C32W1"
			(at 0.8382 -0.67818 0)
			(unlocked yes)
			(layer "B.SilkS")
			(effects
				(font
					(size 0.4064 0.254)
					(thickness 0.1524)
				)
				(justify left mirror)
			)
		)
		(property "Value" ""
			(at 0 0 0)
			(layer "B.Fab")
			(effects
				(font
					(size 1.27 1.27)
				)
				(justify mirror)
			)
		)
		(duplicate_pad_numbers_are_jumpers no)
		(fp_poly
			(pts
				(xy -0.3048 -0.1016) (xy -0.3048 0.9906) (xy 0.3048 0.9906) (xy 0.3048 -0.1016)
			)
			(stroke
				(width 0)
				(type default)
			)
			(fill no)
			(layer "B.CrtYd")
		)
		(fp_line
			(start -0.3048 -0.1016)
			(end 0.3048 -0.1016)
			(stroke
				(width 0.1)
				(type default)
			)
			(layer "B.Fab")
		)
		(fp_line
			(start -0.3048 0.9906)
			(end -0.3048 -0.1016)
			(stroke
				(width 0.1)
				(type default)
			)
			(layer "B.Fab")
		)
		(fp_line
			(start 0.3048 -0.1016)
			(end 0.3048 0.9906)
			(stroke
				(width 0.1)
				(type default)
			)
			(layer "B.Fab")
		)
		(fp_line
			(start 0.3048 0.9906)
			(end -0.3048 0.9906)
			(stroke
				(width 0.1)
				(type default)
			)
			(layer "B.Fab")
		)
		(pad "1" smd rect
			(at 0 0 180)
			(size 0.508 0.508)
			(layers "B.Cu" "B.Mask" "B.Paste")
			(net "P1V8_M2")
		)
		(pad "2" smd rect
			(at 0 0.889 180)
			(size 0.508 0.508)
			(layers "B.Cu" "B.Mask" "B.Paste")
			(net "GND")
		)
		(zone
			(layer "B.Cu")
			(hatch none 0.5)
			(connect_pads
				(clearance 0)
			)
			(min_thickness 0.25)
			(keepout
				(tracks allowed)
				(vias not_allowed)
				(pads allowed)
				(copperpour not_allowed)
				(footprints allowed)
			)
			(placement
				(enabled no)
				(sheetname "")
			)
			(fill
				(thermal_gap 0.5)
				(thermal_bridge_width 0.5)
				(island_removal_mode 0)
			)
			(polygon
				(pts
					(xy 395.802358 -12.335002) (xy 395.294358 -12.335002) (xy 395.294358 -11.954002) (xy 395.802358 -11.954002)
				)
			)
		)
		(zone
			(layer "B.Cu")
			(hatch none 0.5)
			(connect_pads
				(clearance 0)
			)
			(min_thickness 0.25)
			(keepout
				(tracks not_allowed)
				(vias allowed)
				(pads allowed)
				(copperpour not_allowed)
				(footprints allowed)
			)
			(placement
				(enabled no)
				(sheetname "")
			)
			(fill
				(thermal_gap 0.5)
				(thermal_bridge_width 0.5)
				(island_removal_mode 0)
			)
			(polygon
				(pts
					(xy 395.802358 -11.954002) (xy 395.294358 -11.954002) (xy 395.294358 -12.335002) (xy 395.802358 -12.335002)
				)
			)
		)
	)
	(footprint ""
		(layer "B.Cu")
		(at 355.349048 -86.93404 180)
		(property "Reference" "SH3P1"
			(at 0 0 0)
			(layer "B.SilkS")
			(hide yes)
			(effects
				(font
					(size 1.27 1.27)
				)
				(justify mirror)
			)
		)
		(property "Value" ""
			(at 0 0 0)
			(layer "B.Fab")
			(effects
				(font
					(size 1.27 1.27)
				)
				(justify mirror)
			)
		)
		(duplicate_pad_numbers_are_jumpers no)
		(fp_poly
			(pts
				(xy 0.1651 -0.0508) (xy 0.1651 0.5842) (xy -0.1651 0.5842) (xy -0.1651 -0.0508)
			)
			(stroke
				(width 0)
				(type default)
			)
			(fill no)
			(layer "B.CrtYd")
		)
		(fp_line
			(start 0.1651 0.5842)
			(end 0.1651 -0.0508)
			(stroke
				(width 0.1)
				(type default)
			)
			(layer "B.Fab")
		)
		(fp_line
			(start 0.1651 -0.0508)
			(end -0.1651 -0.0508)
			(stroke
				(width 0.1)
				(type default)
			)
			(layer "B.Fab")
		)
		(fp_line
			(start -0.1651 0.5842)
			(end 0.1651 0.5842)
			(stroke
				(width 0.1)
				(type default)
			)
			(layer "B.Fab")
		)
		(fp_line
			(start -0.1651 -0.0508)
			(end -0.1651 0.5842)
			(stroke
				(width 0.1)
				(type default)
			)
			(layer "B.Fab")
		)
		(pad "1" smd custom
			(at 0 0 180)
			(size 0.0762 0.0762)
			(layers "B.Cu" "B.Mask" "B.Paste")
			(net "VSENSE_PVCCIO_CPU0_SKT_VSEN")
			(options
				(clearance outline)
				(anchor circle)
			)
			(primitives
				(gr_poly
					(pts
						(arc
							(start -0.1524 0.10795)
							(mid -0.098518 0.130268)
							(end -0.0762 0.18415)
						)
						(xy -0.0762 0.22225) (xy 0.0762 0.22225)
						(arc
							(start 0.0762 0.18415)
							(mid 0.098518 0.130268)
							(end 0.1524 0.10795)
						)
						(xy 0.1524 -0.22225) (xy -0.1524 -0.22225)
					)
					(width 0)
					(fill yes)
				)
			)
		)
		(pad "2" smd custom
			(at 0 0.5334)
			(size 0.0762 0.0762)
			(layers "B.Cu" "B.Mask" "B.Paste")
			(net "VSENSE_PVCCIO_CPU0_AVSP")
			(options
				(clearance outline)
				(anchor circle)
			)
			(primitives
				(gr_poly
					(pts
						(arc
							(start -0.1524 0.10795)
							(mid -0.098518 0.130268)
							(end -0.0762 0.18415)
						)
						(xy -0.0762 0.22225) (xy 0.0762 0.22225)
						(arc
							(start 0.0762 0.18415)
							(mid 0.098518 0.130268)
							(end 0.1524 0.10795)
						)
						(xy 0.1524 -0.22225) (xy -0.1524 -0.22225)
					)
					(width 0)
					(fill yes)
				)
			)
		)
	)
	(footprint ""
		(layer "B.Cu")
		(at 167.61587 -22.749764 -90)
		(property "Reference" "R6T3"
			(at 0 0 90)
			(layer "B.SilkS")
			(hide yes)
			(effects
				(font
					(size 1.27 1.27)
				)
				(justify mirror)
			)
		)
		(property "Value" ""
			(at 0 0 90)
			(layer "B.Fab")
			(effects
				(font
					(size 1.27 1.27)
				)
				(justify mirror)
			)
		)
		(duplicate_pad_numbers_are_jumpers no)
		(fp_poly
			(pts
				(xy 0.2794 -0.101854) (xy -0.2794 -0.101854) (xy -0.2794 0.990346) (xy 0.2794 0.990346)
			)
			(stroke
				(width 0)
				(type default)
			)
			(fill no)
			(layer "B.CrtYd")
		)
		(fp_line
			(start -0.2794 0.990346)
			(end -0.2794 -0.101854)
			(stroke
				(width 0.1)
				(type default)
			)
			(layer "B.Fab")
		)
		(fp_line
			(start 0.2794 0.990346)
			(end -0.2794 0.990346)
			(stroke
				(width 0.1)
				(type default)
			)
			(layer "B.Fab")
		)
		(fp_line
			(start -0.2794 -0.101854)
			(end 0.2794 -0.101854)
			(stroke
				(width 0.1)
				(type default)
			)
			(layer "B.Fab")
		)
		(fp_line
			(start 0.2794 -0.101854)
			(end 0.2794 0.990346)
			(stroke
				(width 0.1)
				(type default)
			)
			(layer "B.Fab")
		)
		(pad "1" smd rect
			(at 0 0 90)
			(size 0.508 0.508)
			(layers "B.Cu" "B.Mask" "B.Paste")
			(net "SMB_DDR_GHJ_SCL_G_R")
		)
		(pad "2" smd rect
			(at 0 0.889 90)
			(size 0.508 0.508)
			(layers "B.Cu" "B.Mask" "B.Paste")
			(net "SMB_DDR_GHJ_SCL_G")
		)
		(zone
			(layer "B.Cu")
			(hatch none 0.5)
			(connect_pads
				(clearance 0)
			)
			(min_thickness 0.25)
			(keepout
				(tracks not_allowed)
				(vias allowed)
				(pads allowed)
				(copperpour not_allowed)
				(footprints allowed)
			)
			(placement
				(enabled no)
				(sheetname "")
			)
			(fill
				(thermal_gap 0.5)
				(thermal_bridge_width 0.5)
				(island_removal_mode 0)
			)
			(polygon
				(pts
					(xy 166.981124 -22.495764) (xy 166.981124 -23.003764) (xy 167.362124 -23.003764) (xy 167.362124 -22.495764)
				)
			)
		)
		(zone
			(layer "B.Cu")
			(hatch none 0.5)
			(connect_pads
				(clearance 0)
			)
			(min_thickness 0.25)
			(keepout
				(tracks allowed)
				(vias not_allowed)
				(pads allowed)
				(copperpour not_allowed)
				(footprints allowed)
			)
			(placement
				(enabled no)
				(sheetname "")
			)
			(fill
				(thermal_gap 0.5)
				(thermal_bridge_width 0.5)
				(island_removal_mode 0)
			)
			(polygon
				(pts
					(xy 167.362124 -22.495764) (xy 167.362124 -23.003764) (xy 166.981124 -23.003764) (xy 166.981124 -22.495764)
				)
			)
		)
	)
	(footprint ""
		(layer "B.Cu")
		(at 276.836886 -77.82814)
		(property "Reference" "C4P4"
			(at 0 0 0)
			(layer "B.SilkS")
			(hide yes)
			(effects
				(font
					(size 1.27 1.27)
				)
				(justify mirror)
			)
		)
		(property "Value" ""
			(at 0 0 0)
			(layer "B.Fab")
			(effects
				(font
					(size 1.27 1.27)
				)
				(justify mirror)
			)
		)
		(duplicate_pad_numbers_are_jumpers no)
		(fp_poly
			(pts
				(xy 0.7239 -0.2159) (xy -0.7239 -0.2159) (xy -0.7239 1.9939) (xy 0.7239 1.9939)
			)
			(stroke
				(width 0)
				(type default)
			)
			(fill no)
			(layer "B.CrtYd")
		)
		(fp_line
			(start -0.7239 -0.2159)
			(end 0.7239 -0.2159)
			(stroke
				(width 0.1)
				(type default)
			)
			(layer "B.Fab")
		)
		(fp_line
			(start -0.7239 1.9939)
			(end -0.7239 -0.2159)
			(stroke
				(width 0.1)
				(type default)
			)
			(layer "B.Fab")
		)
		(fp_line
			(start 0.7239 -0.2159)
			(end 0.7239 1.9939)
			(stroke
				(width 0.1)
				(type default)
			)
			(layer "B.Fab")
		)
		(fp_line
			(start 0.7239 1.9939)
			(end -0.7239 1.9939)
			(stroke
				(width 0.1)
				(type default)
			)
			(layer "B.Fab")
		)
		(pad "1" smd rect
			(at 0 0 180)
			(size 1.27 1.016)
			(layers "B.Cu" "B.Mask" "B.Paste")
			(net "PVCCMCP_CPU0")
		)
		(pad "2" smd rect
			(at 0 1.778 180)
			(size 1.27 1.016)
			(layers "B.Cu" "B.Mask" "B.Paste")
			(net "GND")
		)
		(zone
			(layer "B.Cu")
			(hatch none 0.5)
			(connect_pads
				(clearance 0)
			)
			(min_thickness 0.25)
			(keepout
				(tracks not_allowed)
				(vias allowed)
				(pads allowed)
				(copperpour not_allowed)
				(footprints allowed)
			)
			(placement
				(enabled no)
				(sheetname "")
			)
			(fill
				(thermal_gap 0.5)
				(thermal_bridge_width 0.5)
				(island_removal_mode 0)
			)
			(polygon
				(pts
					(xy 277.471886 -77.32014) (xy 276.201886 -77.32014) (xy 276.201886 -76.55814) (xy 277.471886 -76.55814)
				)
			)
		)
	)
	(footprint ""
		(layer "B.Cu")
		(at 111.983012 -29.94152 90)
		(property "Reference" "R7U2"
			(at 0 0 90)
			(layer "B.SilkS")
			(hide yes)
			(effects
				(font
					(size 1.27 1.27)
				)
				(justify mirror)
			)
		)
		(property "Value" ""
			(at 0 0 90)
			(layer "B.Fab")
			(effects
				(font
					(size 1.27 1.27)
				)
				(justify mirror)
			)
		)
		(duplicate_pad_numbers_are_jumpers no)
		(fp_poly
			(pts
				(xy 0.2794 -0.1016) (xy -0.2794 -0.1016) (xy -0.2794 0.9906) (xy 0.2794 0.9906)
			)
			(stroke
				(width 0)
				(type default)
			)
			(fill no)
			(layer "B.CrtYd")
		)
		(fp_line
			(start 0.2794 -0.1016)
			(end 0.2794 0.9906)
			(stroke
				(width 0.1)
				(type default)
			)
			(layer "B.Fab")
		)
		(fp_line
			(start -0.2794 -0.1016)
			(end 0.2794 -0.1016)
			(stroke
				(width 0.1)
				(type default)
			)
			(layer "B.Fab")
		)
		(fp_line
			(start 0.2794 0.9906)
			(end -0.2794 0.9906)
			(stroke
				(width 0.1)
				(type default)
			)
			(layer "B.Fab")
		)
		(fp_line
			(start -0.2794 0.9906)
			(end -0.2794 -0.1016)
			(stroke
				(width 0.1)
				(type default)
			)
			(layer "B.Fab")
		)
		(pad "1" smd rect
			(at 0 0 270)
			(size 0.508 0.508)
			(layers "B.Cu" "B.Mask" "B.Paste")
			(net "VSENSE_PVDDQ_GHJ_P")
		)
		(pad "2" smd rect
			(at 0 0.889 270)
			(size 0.508 0.508)
			(layers "B.Cu" "B.Mask" "B.Paste")
			(net "VSENSE_PVDDQ_GHJ_N")
		)
		(zone
			(layer "B.Cu")
			(hatch none 0.5)
			(connect_pads
				(clearance 0)
			)
			(min_thickness 0.25)
			(keepout
				(tracks allowed)
				(vias not_allowed)
				(pads allowed)
				(copperpour not_allowed)
				(footprints allowed)
			)
			(placement
				(enabled no)
				(sheetname "")
			)
			(fill
				(thermal_gap 0.5)
				(thermal_bridge_width 0.5)
				(island_removal_mode 0)
			)
			(polygon
				(pts
					(xy 112.237012 -30.19552) (xy 112.237012 -29.68752) (xy 112.618012 -29.68752) (xy 112.618012 -30.19552)
				)
			)
		)
		(zone
			(layer "B.Cu")
			(hatch none 0.5)
			(connect_pads
				(clearance 0)
			)
			(min_thickness 0.25)
			(keepout
				(tracks not_allowed)
				(vias allowed)
				(pads allowed)
				(copperpour not_allowed)
				(footprints allowed)
			)
			(placement
				(enabled no)
				(sheetname "")
			)
			(fill
				(thermal_gap 0.5)
				(thermal_bridge_width 0.5)
				(island_removal_mode 0)
			)
			(polygon
				(pts
					(xy 112.618012 -30.19552) (xy 112.618012 -29.68752) (xy 112.237012 -29.68752) (xy 112.237012 -30.19552)
				)
			)
		)
	)
	(footprint ""
		(layer "B.Cu")
		(at 402.463 -153.289 -90)
		(property "Reference" "R2L25"
			(at 0 0 90)
			(layer "B.SilkS")
			(hide yes)
			(effects
				(font
					(size 1.27 1.27)
				)
				(justify mirror)
			)
		)
		(property "Value" ""
			(at 0 0 90)
			(layer "B.Fab")
			(effects
				(font
					(size 1.27 1.27)
				)
				(justify mirror)
			)
		)
		(duplicate_pad_numbers_are_jumpers no)
		(fp_poly
			(pts
				(xy 0.2794 -0.1016) (xy -0.2794 -0.1016) (xy -0.2794 0.9906) (xy 0.2794 0.9906)
			)
			(stroke
				(width 0)
				(type default)
			)
			(fill no)
			(layer "B.CrtYd")
		)
		(fp_line
			(start -0.2794 0.9906)
			(end -0.2794 -0.1016)
			(stroke
				(width 0.1)
				(type default)
			)
			(layer "B.Fab")
		)
		(fp_line
			(start 0.2794 0.9906)
			(end -0.2794 0.9906)
			(stroke
				(width 0.1)
				(type default)
			)
			(layer "B.Fab")
		)
		(fp_line
			(start -0.2794 -0.1016)
			(end 0.2794 -0.1016)
			(stroke
				(width 0.1)
				(type default)
			)
			(layer "B.Fab")
		)
		(fp_line
			(start 0.2794 -0.1016)
			(end 0.2794 0.9906)
			(stroke
				(width 0.1)
				(type default)
			)
			(layer "B.Fab")
		)
		(pad "1" smd rect
			(at 0 0 90)
			(size 0.508 0.508)
			(layers "B.Cu" "B.Mask" "B.Paste")
			(net "P3V3_STBY")
		)
		(pad "2" smd rect
			(at 0 0.889 90)
			(size 0.508 0.508)
			(layers "B.Cu" "B.Mask" "B.Paste")
			(net "VID_PCH_CORE_PVNN_AUX_VID_1")
		)
		(zone
			(layer "B.Cu")
			(hatch none 0.5)
			(connect_pads
				(clearance 0)
			)
			(min_thickness 0.25)
			(keepout
				(tracks not_allowed)
				(vias allowed)
				(pads allowed)
				(copperpour not_allowed)
				(footprints allowed)
			)
			(placement
				(enabled no)
				(sheetname "")
			)
			(fill
				(thermal_gap 0.5)
				(thermal_bridge_width 0.5)
				(island_removal_mode 0)
			)
			(polygon
				(pts
					(xy 401.828 -153.035) (xy 401.828 -153.543) (xy 402.209 -153.543) (xy 402.209 -153.035)
				)
			)
		)
		(zone
			(layer "B.Cu")
			(hatch none 0.5)
			(connect_pads
				(clearance 0)
			)
			(min_thickness 0.25)
			(keepout
				(tracks allowed)
				(vias not_allowed)
				(pads allowed)
				(copperpour not_allowed)
				(footprints allowed)
			)
			(placement
				(enabled no)
				(sheetname "")
			)
			(fill
				(thermal_gap 0.5)
				(thermal_bridge_width 0.5)
				(island_removal_mode 0)
			)
			(polygon
				(pts
					(xy 402.209 -153.035) (xy 402.209 -153.543) (xy 401.828 -153.543) (xy 401.828 -153.035)
				)
			)
		)
	)
	(footprint ""
		(layer "B.Cu")
		(at 181.339998 2.425192 180)
		(property "Reference" "R6U15"
			(at 0 0 0)
			(layer "B.SilkS")
			(hide yes)
			(effects
				(font
					(size 1.27 1.27)
				)
				(justify mirror)
			)
		)
		(property "Value" ""
			(at 0 0 0)
			(layer "B.Fab")
			(effects
				(font
					(size 1.27 1.27)
				)
				(justify mirror)
			)
		)
		(duplicate_pad_numbers_are_jumpers no)
		(fp_rect
			(start 0.2794 -0.1016)
			(end -0.2794 0.9906)
			(stroke
				(width 0)
				(type default)
			)
			(fill no)
			(layer "B.CrtYd")
		)
		(fp_line
			(start 0.2794 0.9906)
			(end -0.2794 0.9906)
			(stroke
				(width 0.1)
				(type default)
			)
			(layer "B.Fab")
		)
		(fp_line
			(start 0.2794 -0.1016)
			(end 0.2794 0.9906)
			(stroke
				(width 0.1)
				(type default)
			)
			(layer "B.Fab")
		)
		(fp_line
			(start -0.2794 0.9906)
			(end -0.2794 -0.1016)
			(stroke
				(width 0.1)
				(type default)
			)
			(layer "B.Fab")
		)
		(fp_line
			(start -0.2794 -0.1016)
			(end 0.2794 -0.1016)
			(stroke
				(width 0.1)
				(type default)
			)
			(layer "B.Fab")
		)
		(pad "1" smd rect
			(at 0 0)
			(size 0.508 0.508)
			(layers "B.Cu" "B.Mask" "B.Paste")
			(net "P3V3")
		)
		(pad "2" smd rect
			(at 0 0.889)
			(size 0.508 0.508)
			(layers "B.Cu" "B.Mask" "B.Paste")
			(net "FM_PVTT_ABC_EN_R")
		)
		(zone
			(layer "B.Cu")
			(hatch none 0.5)
			(connect_pads
				(clearance 0)
			)
			(min_thickness 0.25)
			(keepout
				(tracks not_allowed)
				(vias allowed)
				(pads allowed)
				(copperpour not_allowed)
				(footprints allowed)
			)
			(placement
				(enabled no)
				(sheetname "")
			)
			(fill
				(thermal_gap 0.5)
				(thermal_bridge_width 0.5)
				(island_removal_mode 0)
			)
			(polygon
				(pts
					(xy 181.085998 2.171192) (xy 181.593998 2.171192) (xy 181.593998 1.790192) (xy 181.085998 1.790192)
				)
			)
		)
		(zone
			(layer "B.Cu")
			(hatch none 0.5)
			(connect_pads
				(clearance 0)
			)
			(min_thickness 0.25)
			(keepout
				(tracks allowed)
				(vias not_allowed)
				(pads allowed)
				(copperpour not_allowed)
				(footprints allowed)
			)
			(placement
				(enabled no)
				(sheetname "")
			)
			(fill
				(thermal_gap 0.5)
				(thermal_bridge_width 0.5)
				(island_removal_mode 0)
			)
			(polygon
				(pts
					(xy 181.085998 2.171192) (xy 181.593998 2.171192) (xy 181.593998 1.790192) (xy 181.085998 1.790192)
				)
			)
		)
	)
	(footprint ""
		(layer "B.Cu")
		(at 389.861806 -8.696452 -90)
		(property "Reference" "C32W3"
			(at 0.8382 -0.67818 270)
			(unlocked yes)
			(layer "B.SilkS")
			(effects
				(font
					(size 0.4064 0.254)
					(thickness 0.1524)
				)
				(justify left mirror)
			)
		)
		(property "Value" ""
			(at 0 0 90)
			(layer "B.Fab")
			(effects
				(font
					(size 1.27 1.27)
				)
				(justify mirror)
			)
		)
		(duplicate_pad_numbers_are_jumpers no)
		(fp_poly
			(pts
				(xy -0.3048 -0.1016) (xy -0.3048 0.9906) (xy 0.3048 0.9906) (xy 0.3048 -0.1016)
			)
			(stroke
				(width 0)
				(type default)
			)
			(fill no)
			(layer "B.CrtYd")
		)
		(fp_line
			(start -0.3048 0.9906)
			(end -0.3048 -0.1016)
			(stroke
				(width 0.1)
				(type default)
			)
			(layer "B.Fab")
		)
		(fp_line
			(start 0.3048 0.9906)
			(end -0.3048 0.9906)
			(stroke
				(width 0.1)
				(type default)
			)
			(layer "B.Fab")
		)
		(fp_line
			(start -0.3048 -0.1016)
			(end 0.3048 -0.1016)
			(stroke
				(width 0.1)
				(type default)
			)
			(layer "B.Fab")
		)
		(fp_line
			(start 0.3048 -0.1016)
			(end 0.3048 0.9906)
			(stroke
				(width 0.1)
				(type default)
			)
			(layer "B.Fab")
		)
		(pad "1" smd rect
			(at 0 0 90)
			(size 0.508 0.508)
			(layers "B.Cu" "B.Mask" "B.Paste")
			(net "P1V8_M2")
		)
		(pad "2" smd rect
			(at 0 0.889 90)
			(size 0.508 0.508)
			(layers "B.Cu" "B.Mask" "B.Paste")
			(net "GND")
		)
		(zone
			(layer "B.Cu")
			(hatch none 0.5)
			(connect_pads
				(clearance 0)
			)
			(min_thickness 0.25)
			(keepout
				(tracks not_allowed)
				(vias allowed)
				(pads allowed)
				(copperpour not_allowed)
				(footprints allowed)
			)
			(placement
				(enabled no)
				(sheetname "")
			)
			(fill
				(thermal_gap 0.5)
				(thermal_bridge_width 0.5)
				(island_removal_mode 0)
			)
			(polygon
				(pts
					(xy 389.226806 -8.442452) (xy 389.226806 -8.950452) (xy 389.607806 -8.950452) (xy 389.607806 -8.442452)
				)
			)
		)
		(zone
			(layer "B.Cu")
			(hatch none 0.5)
			(connect_pads
				(clearance 0)
			)
			(min_thickness 0.25)
			(keepout
				(tracks allowed)
				(vias not_allowed)
				(pads allowed)
				(copperpour not_allowed)
				(footprints allowed)
			)
			(placement
				(enabled no)
				(sheetname "")
			)
			(fill
				(thermal_gap 0.5)
				(thermal_bridge_width 0.5)
				(island_removal_mode 0)
			)
			(polygon
				(pts
					(xy 389.607806 -8.442452) (xy 389.607806 -8.950452) (xy 389.226806 -8.950452) (xy 389.226806 -8.442452)
				)
			)
		)
	)
	(footprint ""
		(layer "B.Cu")
		(at 361.188 -133.0198 180)
		(property "Reference" "R3M6"
			(at 0 0 0)
			(layer "B.SilkS")
			(hide yes)
			(effects
				(font
					(size 1.27 1.27)
				)
				(justify mirror)
			)
		)
		(property "Value" ""
			(at 0 0 0)
			(layer "B.Fab")
			(effects
				(font
					(size 1.27 1.27)
				)
				(justify mirror)
			)
		)
		(duplicate_pad_numbers_are_jumpers no)
		(fp_poly
			(pts
				(xy 0.2794 -0.1016) (xy -0.2794 -0.1016) (xy -0.2794 0.9906) (xy 0.2794 0.9906)
			)
			(stroke
				(width 0)
				(type default)
			)
			(fill no)
			(layer "B.CrtYd")
		)
		(fp_line
			(start 0.2794 0.9906)
			(end -0.2794 0.9906)
			(stroke
				(width 0.1)
				(type default)
			)
			(layer "B.Fab")
		)
		(fp_line
			(start 0.2794 -0.1016)
			(end 0.2794 0.9906)
			(stroke
				(width 0.1)
				(type default)
			)
			(layer "B.Fab")
		)
		(fp_line
			(start -0.2794 0.9906)
			(end -0.2794 -0.1016)
			(stroke
				(width 0.1)
				(type default)
			)
			(layer "B.Fab")
		)
		(fp_line
			(start -0.2794 -0.1016)
			(end 0.2794 -0.1016)
			(stroke
				(width 0.1)
				(type default)
			)
			(layer "B.Fab")
		)
		(pad "1" smd rect
			(at 0 0)
			(size 0.508 0.508)
			(layers "B.Cu" "B.Mask" "B.Paste")
			(net "FM_PVDDQ_DEF_EN")
		)
		(pad "2" smd rect
			(at 0 0.889)
			(size 0.508 0.508)
			(layers "B.Cu" "B.Mask" "B.Paste")
			(net "VR_PVDDQ_DEF_VREN")
		)
		(zone
			(layer "B.Cu")
			(hatch none 0.5)
			(connect_pads
				(clearance 0)
			)
			(min_thickness 0.25)
			(keepout
				(tracks not_allowed)
				(vias allowed)
				(pads allowed)
				(copperpour not_allowed)
				(footprints allowed)
			)
			(placement
				(enabled no)
				(sheetname "")
			)
			(fill
				(thermal_gap 0.5)
				(thermal_bridge_width 0.5)
				(island_removal_mode 0)
			)
			(polygon
				(pts
					(xy 360.934 -133.6548) (xy 361.442 -133.6548) (xy 361.442 -133.2738) (xy 360.934 -133.2738)
				)
			)
		)
		(zone
			(layer "B.Cu")
			(hatch none 0.5)
			(connect_pads
				(clearance 0)
			)
			(min_thickness 0.25)
			(keepout
				(tracks allowed)
				(vias not_allowed)
				(pads allowed)
				(copperpour not_allowed)
				(footprints allowed)
			)
			(placement
				(enabled no)
				(sheetname "")
			)
			(fill
				(thermal_gap 0.5)
				(thermal_bridge_width 0.5)
				(island_removal_mode 0)
			)
			(polygon
				(pts
					(xy 360.934 -133.2738) (xy 361.442 -133.2738) (xy 361.442 -133.6548) (xy 360.934 -133.6548)
				)
			)
		)
	)
	(footprint ""
		(layer "B.Cu")
		(at 386.709666 -45.691806 -90)
		(property "Reference" "R7E9"
			(at 0 0 90)
			(layer "B.SilkS")
			(hide yes)
			(effects
				(font
					(size 1.27 1.27)
				)
				(justify mirror)
			)
		)
		(property "Value" ""
			(at 0 0 90)
			(layer "B.Fab")
			(effects
				(font
					(size 1.27 1.27)
				)
				(justify mirror)
			)
		)
		(duplicate_pad_numbers_are_jumpers no)
		(fp_poly
			(pts
				(xy 0.2794 -0.1016) (xy -0.2794 -0.1016) (xy -0.2794 0.9906) (xy 0.2794 0.9906)
			)
			(stroke
				(width 0)
				(type default)
			)
			(fill no)
			(layer "B.CrtYd")
		)
		(fp_line
			(start -0.2794 0.9906)
			(end -0.2794 -0.1016)
			(stroke
				(width 0.1)
				(type default)
			)
			(layer "B.Fab")
		)
		(fp_line
			(start 0.2794 0.9906)
			(end -0.2794 0.9906)
			(stroke
				(width 0.1)
				(type default)
			)
			(layer "B.Fab")
		)
		(fp_line
			(start -0.2794 -0.1016)
			(end 0.2794 -0.1016)
			(stroke
				(width 0.1)
				(type default)
			)
			(layer "B.Fab")
		)
		(fp_line
			(start 0.2794 -0.1016)
			(end 0.2794 0.9906)
			(stroke
				(width 0.1)
				(type default)
			)
			(layer "B.Fab")
		)
		(pad "1" smd rect
			(at 0 0 90)
			(size 0.508 0.508)
			(layers "B.Cu" "B.Mask" "B.Paste")
			(net "FM_THROTTLE_N")
		)
		(pad "2" smd rect
			(at 0 0.889 90)
			(size 0.508 0.508)
			(layers "B.Cu" "B.Mask" "B.Paste")
			(net "FM_THROTTLE_R_N")
		)
		(zone
			(layer "B.Cu")
			(hatch none 0.5)
			(connect_pads
				(clearance 0)
			)
			(min_thickness 0.25)
			(keepout
				(tracks not_allowed)
				(vias allowed)
				(pads allowed)
				(copperpour not_allowed)
				(footprints allowed)
			)
			(placement
				(enabled no)
				(sheetname "")
			)
			(fill
				(thermal_gap 0.5)
				(thermal_bridge_width 0.5)
				(island_removal_mode 0)
			)
			(polygon
				(pts
					(xy 386.074666 -45.437806) (xy 386.074666 -45.945806) (xy 386.455666 -45.945806) (xy 386.455666 -45.437806)
				)
			)
		)
		(zone
			(layer "B.Cu")
			(hatch none 0.5)
			(connect_pads
				(clearance 0)
			)
			(min_thickness 0.25)
			(keepout
				(tracks allowed)
				(vias not_allowed)
				(pads allowed)
				(copperpour not_allowed)
				(footprints allowed)
			)
			(placement
				(enabled no)
				(sheetname "")
			)
			(fill
				(thermal_gap 0.5)
				(thermal_bridge_width 0.5)
				(island_removal_mode 0)
			)
			(polygon
				(pts
					(xy 386.455666 -45.437806) (xy 386.455666 -45.945806) (xy 386.074666 -45.945806) (xy 386.074666 -45.437806)
				)
			)
		)
	)
	(footprint ""
		(layer "B.Cu")
		(at 369.443 -109.601 -90)
		(property "Reference" "C3N13"
			(at 0 0 90)
			(layer "B.SilkS")
			(hide yes)
			(effects
				(font
					(size 1.27 1.27)
				)
				(justify mirror)
			)
		)
		(property "Value" ""
			(at 0 0 90)
			(layer "B.Fab")
			(effects
				(font
					(size 1.27 1.27)
				)
				(justify mirror)
			)
		)
		(duplicate_pad_numbers_are_jumpers no)
		(fp_poly
			(pts
				(xy -0.3048 -0.1016) (xy -0.3048 0.9906) (xy 0.3048 0.9906) (xy 0.3048 -0.1016)
			)
			(stroke
				(width 0)
				(type default)
			)
			(fill no)
			(layer "B.CrtYd")
		)
		(fp_line
			(start -0.3048 0.9906)
			(end -0.3048 -0.1016)
			(stroke
				(width 0.1)
				(type default)
			)
			(layer "B.Fab")
		)
		(fp_line
			(start 0.3048 0.9906)
			(end -0.3048 0.9906)
			(stroke
				(width 0.1)
				(type default)
			)
			(layer "B.Fab")
		)
		(fp_line
			(start -0.3048 -0.1016)
			(end 0.3048 -0.1016)
			(stroke
				(width 0.1)
				(type default)
			)
			(layer "B.Fab")
		)
		(fp_line
			(start 0.3048 -0.1016)
			(end 0.3048 0.9906)
			(stroke
				(width 0.1)
				(type default)
			)
			(layer "B.Fab")
		)
		(pad "1" smd rect
			(at 0 0 90)
			(size 0.508 0.508)
			(layers "B.Cu" "B.Mask" "B.Paste")
			(net "DMI_CPU0_PCH_RX_DN<3>")
		)
		(pad "2" smd rect
			(at 0 0.889 90)
			(size 0.508 0.508)
			(layers "B.Cu" "B.Mask" "B.Paste")
			(net "DMI_CPU0_PCH_RX_C_DN<3>")
		)
		(zone
			(layer "B.Cu")
			(hatch none 0.5)
			(connect_pads
				(clearance 0)
			)
			(min_thickness 0.25)
			(keepout
				(tracks not_allowed)
				(vias allowed)
				(pads allowed)
				(copperpour not_allowed)
				(footprints allowed)
			)
			(placement
				(enabled no)
				(sheetname "")
			)
			(fill
				(thermal_gap 0.5)
				(thermal_bridge_width 0.5)
				(island_removal_mode 0)
			)
			(polygon
				(pts
					(xy 368.808 -109.347) (xy 368.808 -109.855) (xy 369.189 -109.855) (xy 369.189 -109.347)
				)
			)
		)
		(zone
			(layer "B.Cu")
			(hatch none 0.5)
			(connect_pads
				(clearance 0)
			)
			(min_thickness 0.25)
			(keepout
				(tracks allowed)
				(vias not_allowed)
				(pads allowed)
				(copperpour not_allowed)
				(footprints allowed)
			)
			(placement
				(enabled no)
				(sheetname "")
			)
			(fill
				(thermal_gap 0.5)
				(thermal_bridge_width 0.5)
				(island_removal_mode 0)
			)
			(polygon
				(pts
					(xy 369.189 -109.347) (xy 369.189 -109.855) (xy 368.808 -109.855) (xy 368.808 -109.347)
				)
			)
		)
	)
	(footprint ""
		(layer "B.Cu")
		(at 87.158068 -12.954 -90)
		(property "Reference" "C5G81"
			(at -1.14681 0.76708 0)
			(unlocked yes)
			(layer "B.SilkS")
			(effects
				(font
					(size 0.7874 0.5842)
					(thickness 0.1524)
				)
				(justify mirror)
			)
		)
		(property "Value" ""
			(at 0 0 90)
			(layer "B.Fab")
			(effects
				(font
					(size 1.27 1.27)
				)
				(justify mirror)
			)
		)
		(duplicate_pad_numbers_are_jumpers no)
		(fp_rect
			(start 0.4953 1.6002)
			(end -0.4953 -0.2032)
			(stroke
				(width 0)
				(type default)
			)
			(fill no)
			(layer "B.CrtYd")
		)
		(fp_line
			(start -0.4953 1.6002)
			(end 0.4953 1.6002)
			(stroke
				(width 0.1)
				(type default)
			)
			(layer "B.Fab")
		)
		(fp_line
			(start 0.4953 1.6002)
			(end 0.4953 -0.2032)
			(stroke
				(width 0.1)
				(type default)
			)
			(layer "B.Fab")
		)
		(fp_line
			(start -0.4953 -0.2032)
			(end -0.4953 1.6002)
			(stroke
				(width 0.1)
				(type default)
			)
			(layer "B.Fab")
		)
		(fp_line
			(start 0.4953 -0.2032)
			(end -0.4953 -0.2032)
			(stroke
				(width 0.1)
				(type default)
			)
			(layer "B.Fab")
		)
		(pad "1" smd rect
			(at 0 0 90)
			(size 0.762 0.889)
			(layers "B.Cu" "B.Mask" "B.Paste")
			(net "PVDDQ_GHJ")
		)
		(pad "2" smd rect
			(at 0 1.397 90)
			(size 0.762 0.889)
			(layers "B.Cu" "B.Mask" "B.Paste")
			(net "GND")
		)
		(zone
			(layer "B.Cu")
			(hatch none 0.5)
			(connect_pads
				(clearance 0)
			)
			(min_thickness 0.25)
			(keepout
				(tracks not_allowed)
				(vias allowed)
				(pads allowed)
				(copperpour not_allowed)
				(footprints allowed)
			)
			(placement
				(enabled no)
				(sheetname "")
			)
			(fill
				(thermal_gap 0.5)
				(thermal_bridge_width 0.5)
				(island_removal_mode 0)
			)
			(polygon
				(pts
					(xy 86.205568 -12.573) (xy 86.713568 -12.573) (xy 86.713568 -13.335) (xy 86.205568 -13.335)
				)
			)
		)
	)
	(footprint ""
		(layer "B.Cu")
		(at 193.548 -144.4752 180)
		(property "Reference" "R6L13"
			(at 0 0 0)
			(layer "B.SilkS")
			(hide yes)
			(effects
				(font
					(size 1.27 1.27)
				)
				(justify mirror)
			)
		)
		(property "Value" ""
			(at 0 0 0)
			(layer "B.Fab")
			(effects
				(font
					(size 1.27 1.27)
				)
				(justify mirror)
			)
		)
		(duplicate_pad_numbers_are_jumpers no)
		(fp_poly
			(pts
				(xy 0.2794 -0.1016) (xy -0.2794 -0.1016) (xy -0.2794 0.9906) (xy 0.2794 0.9906)
			)
			(stroke
				(width 0)
				(type default)
			)
			(fill no)
			(layer "B.CrtYd")
		)
		(fp_line
			(start 0.2794 0.9906)
			(end -0.2794 0.9906)
			(stroke
				(width 0.1)
				(type default)
			)
			(layer "B.Fab")
		)
		(fp_line
			(start 0.2794 -0.1016)
			(end 0.2794 0.9906)
			(stroke
				(width 0.1)
				(type default)
			)
			(layer "B.Fab")
		)
		(fp_line
			(start -0.2794 0.9906)
			(end -0.2794 -0.1016)
			(stroke
				(width 0.1)
				(type default)
			)
			(layer "B.Fab")
		)
		(fp_line
			(start -0.2794 -0.1016)
			(end 0.2794 -0.1016)
			(stroke
				(width 0.1)
				(type default)
			)
			(layer "B.Fab")
		)
		(pad "1" smd rect
			(at 0 0)
			(size 0.508 0.508)
			(layers "B.Cu" "B.Mask" "B.Paste")
			(net "PVDDQ_DEF")
		)
		(pad "2" smd rect
			(at 0 0.889)
			(size 0.508 0.508)
			(layers "B.Cu" "B.Mask" "B.Paste")
			(net "M_E_VREF")
		)
		(zone
			(layer "B.Cu")
			(hatch none 0.5)
			(connect_pads
				(clearance 0)
			)
			(min_thickness 0.25)
			(keepout
				(tracks not_allowed)
				(vias allowed)
				(pads allowed)
				(copperpour not_allowed)
				(footprints allowed)
			)
			(placement
				(enabled no)
				(sheetname "")
			)
			(fill
				(thermal_gap 0.5)
				(thermal_bridge_width 0.5)
				(island_removal_mode 0)
			)
			(polygon
				(pts
					(xy 193.294 -145.1102) (xy 193.802 -145.1102) (xy 193.802 -144.7292) (xy 193.294 -144.7292)
				)
			)
		)
		(zone
			(layer "B.Cu")
			(hatch none 0.5)
			(connect_pads
				(clearance 0)
			)
			(min_thickness 0.25)
			(keepout
				(tracks allowed)
				(vias not_allowed)
				(pads allowed)
				(copperpour not_allowed)
				(footprints allowed)
			)
			(placement
				(enabled no)
				(sheetname "")
			)
			(fill
				(thermal_gap 0.5)
				(thermal_bridge_width 0.5)
				(island_removal_mode 0)
			)
			(polygon
				(pts
					(xy 193.294 -144.7292) (xy 193.802 -144.7292) (xy 193.802 -145.1102) (xy 193.294 -145.1102)
				)
			)
		)
	)
	(footprint ""
		(layer "B.Cu")
		(at 466.4583 -24.9555 -90)
		(property "Reference" "C2R11"
			(at 0 0 90)
			(layer "B.SilkS")
			(hide yes)
			(effects
				(font
					(size 1.27 1.27)
				)
				(justify mirror)
			)
		)
		(property "Value" "*"
			(at 0 -2.9337 270)
			(unlocked yes)
			(layer "B.Fab")
			(hide yes)
			(effects
				(font
					(size 1.27 1.016)
					(thickness 0.1524)
				)
				(justify mirror)
			)
		)
		(property "Device Type" "SC4D7U16V3KX-GP_SMD-BCG5-SC4D7A"
			(at 0 -4.4577 270)
			(unlocked yes)
			(layer "B.Fab")
			(hide yes)
			(effects
				(font
					(size 1.27 1.016)
					(thickness 0.1524)
				)
				(justify mirror)
			)
		)
		(duplicate_pad_numbers_are_jumpers no)
		(fp_line
			(start -0.508 0)
			(end 0.508 0)
			(stroke
				(width 0.2032)
				(type default)
			)
			(layer "B.SilkS")
		)
		(fp_rect
			(start 0.5842 1.3335)
			(end -0.5842 -1.3335)
			(stroke
				(width 0)
				(type default)
			)
			(fill no)
			(layer "B.CrtYd")
		)
		(fp_rect
			(start 0.5842 1.3335)
			(end -0.5842 -1.3335)
			(stroke
				(width 0)
				(type default)
			)
			(fill no)
			(layer "B.Fab")
		)
		(pad "1" smd custom
			(at 0 -0.762 90)
			(size 0.2159 0.2159)
			(layers "B.Cu" "B.Mask" "B.Paste")
			(net "P5V_STBY")
			(options
				(clearance outline)
				(anchor circle)
			)
			(primitives
				(gr_poly
					(pts
						(arc
							(start -0.3302 0.4318)
							(mid -0.402042 0.402042)
							(end -0.4318 0.3302)
						)
						(arc
							(start -0.4318 -0.3302)
							(mid -0.402042 -0.402042)
							(end -0.3302 -0.4318)
						)
						(arc
							(start 0.3302 -0.4318)
							(mid 0.402042 -0.402042)
							(end 0.4318 -0.3302)
						)
						(arc
							(start 0.4318 0.3302)
							(mid 0.402042 0.402042)
							(end 0.3302 0.4318)
						)
					)
					(width 0)
					(fill yes)
				)
			)
		)
		(pad "2" smd custom
			(at 0 0.762 90)
			(size 0.2159 0.2159)
			(layers "B.Cu" "B.Mask" "B.Paste")
			(net "AGND_P3V3_STBY")
			(options
				(clearance outline)
				(anchor circle)
			)
			(primitives
				(gr_poly
					(pts
						(arc
							(start -0.3302 0.4318)
							(mid -0.402042 0.402042)
							(end -0.4318 0.3302)
						)
						(arc
							(start -0.4318 -0.3302)
							(mid -0.402042 -0.402042)
							(end -0.3302 -0.4318)
						)
						(arc
							(start 0.3302 -0.4318)
							(mid 0.402042 -0.402042)
							(end 0.4318 -0.3302)
						)
						(arc
							(start 0.4318 0.3302)
							(mid 0.402042 0.402042)
							(end 0.3302 0.4318)
						)
					)
					(width 0)
					(fill yes)
				)
			)
		)
	)
	(footprint ""
		(layer "B.Cu")
		(at 443.0522 -64.7446 180)
		(property "Reference" "C2P16"
			(at 0 0 0)
			(layer "B.SilkS")
			(hide yes)
			(effects
				(font
					(size 1.27 1.27)
				)
				(justify mirror)
			)
		)
		(property "Value" ""
			(at 0 0 0)
			(layer "B.Fab")
			(effects
				(font
					(size 1.27 1.27)
				)
				(justify mirror)
			)
		)
		(duplicate_pad_numbers_are_jumpers no)
		(fp_poly
			(pts
				(xy -0.3048 -0.1016) (xy -0.3048 0.9906) (xy 0.3048 0.9906) (xy 0.3048 -0.1016)
			)
			(stroke
				(width 0)
				(type default)
			)
			(fill no)
			(layer "B.CrtYd")
		)
		(fp_line
			(start 0.3048 0.9906)
			(end -0.3048 0.9906)
			(stroke
				(width 0.1)
				(type default)
			)
			(layer "B.Fab")
		)
		(fp_line
			(start 0.3048 -0.1016)
			(end 0.3048 0.9906)
			(stroke
				(width 0.1)
				(type default)
			)
			(layer "B.Fab")
		)
		(fp_line
			(start -0.3048 0.9906)
			(end -0.3048 -0.1016)
			(stroke
				(width 0.1)
				(type default)
			)
			(layer "B.Fab")
		)
		(fp_line
			(start -0.3048 -0.1016)
			(end 0.3048 -0.1016)
			(stroke
				(width 0.1)
				(type default)
			)
			(layer "B.Fab")
		)
		(pad "1" smd rect
			(at 0 0)
			(size 0.508 0.508)
			(layers "B.Cu" "B.Mask" "B.Paste")
			(net "P12V_STBY")
		)
		(pad "2" smd rect
			(at 0 0.889)
			(size 0.508 0.508)
			(layers "B.Cu" "B.Mask" "B.Paste")
			(net "GND")
		)
		(zone
			(layer "B.Cu")
			(hatch none 0.5)
			(connect_pads
				(clearance 0)
			)
			(min_thickness 0.25)
			(keepout
				(tracks not_allowed)
				(vias allowed)
				(pads allowed)
				(copperpour not_allowed)
				(footprints allowed)
			)
			(placement
				(enabled no)
				(sheetname "")
			)
			(fill
				(thermal_gap 0.5)
				(thermal_bridge_width 0.5)
				(island_removal_mode 0)
			)
			(polygon
				(pts
					(xy 442.7982 -65.3796) (xy 443.3062 -65.3796) (xy 443.3062 -64.9986) (xy 442.7982 -64.9986)
				)
			)
		)
		(zone
			(layer "B.Cu")
			(hatch none 0.5)
			(connect_pads
				(clearance 0)
			)
			(min_thickness 0.25)
			(keepout
				(tracks allowed)
				(vias not_allowed)
				(pads allowed)
				(copperpour not_allowed)
				(footprints allowed)
			)
			(placement
				(enabled no)
				(sheetname "")
			)
			(fill
				(thermal_gap 0.5)
				(thermal_bridge_width 0.5)
				(island_removal_mode 0)
			)
			(polygon
				(pts
					(xy 442.7982 -64.9986) (xy 443.3062 -64.9986) (xy 443.3062 -65.3796) (xy 442.7982 -65.3796)
				)
			)
		)
	)
	(footprint ""
		(layer "B.Cu")
		(at 397.764 -75.1967 -90)
		(property "Reference" "C6W4"
			(at 0.8382 -0.67818 270)
			(unlocked yes)
			(layer "B.SilkS")
			(effects
				(font
					(size 0.4064 0.254)
					(thickness 0.1524)
				)
				(justify left mirror)
			)
		)
		(property "Value" ""
			(at 0 0 90)
			(layer "B.Fab")
			(effects
				(font
					(size 1.27 1.27)
				)
				(justify mirror)
			)
		)
		(duplicate_pad_numbers_are_jumpers no)
		(fp_poly
			(pts
				(xy -0.3048 -0.1016) (xy -0.3048 0.9906) (xy 0.3048 0.9906) (xy 0.3048 -0.1016)
			)
			(stroke
				(width 0)
				(type default)
			)
			(fill no)
			(layer "B.CrtYd")
		)
		(fp_line
			(start -0.3048 0.9906)
			(end -0.3048 -0.1016)
			(stroke
				(width 0.1)
				(type default)
			)
			(layer "B.Fab")
		)
		(fp_line
			(start 0.3048 0.9906)
			(end -0.3048 0.9906)
			(stroke
				(width 0.1)
				(type default)
			)
			(layer "B.Fab")
		)
		(fp_line
			(start -0.3048 -0.1016)
			(end 0.3048 -0.1016)
			(stroke
				(width 0.1)
				(type default)
			)
			(layer "B.Fab")
		)
		(fp_line
			(start 0.3048 -0.1016)
			(end 0.3048 0.9906)
			(stroke
				(width 0.1)
				(type default)
			)
			(layer "B.Fab")
		)
		(pad "1" smd rect
			(at 0 0 90)
			(size 0.508 0.508)
			(layers "B.Cu" "B.Mask" "B.Paste")
			(net "P3V3_STBY")
		)
		(pad "2" smd rect
			(at 0 0.889 90)
			(size 0.508 0.508)
			(layers "B.Cu" "B.Mask" "B.Paste")
			(net "GND")
		)
		(zone
			(layer "B.Cu")
			(hatch none 0.5)
			(connect_pads
				(clearance 0)
			)
			(min_thickness 0.25)
			(keepout
				(tracks not_allowed)
				(vias allowed)
				(pads allowed)
				(copperpour not_allowed)
				(footprints allowed)
			)
			(placement
				(enabled no)
				(sheetname "")
			)
			(fill
				(thermal_gap 0.5)
				(thermal_bridge_width 0.5)
				(island_removal_mode 0)
			)
			(polygon
				(pts
					(xy 397.129 -74.9427) (xy 397.129 -75.4507) (xy 397.51 -75.4507) (xy 397.51 -74.9427)
				)
			)
		)
		(zone
			(layer "B.Cu")
			(hatch none 0.5)
			(connect_pads
				(clearance 0)
			)
			(min_thickness 0.25)
			(keepout
				(tracks allowed)
				(vias not_allowed)
				(pads allowed)
				(copperpour not_allowed)
				(footprints allowed)
			)
			(placement
				(enabled no)
				(sheetname "")
			)
			(fill
				(thermal_gap 0.5)
				(thermal_bridge_width 0.5)
				(island_removal_mode 0)
			)
			(polygon
				(pts
					(xy 397.51 -74.9427) (xy 397.51 -75.4507) (xy 397.129 -75.4507) (xy 397.129 -74.9427)
				)
			)
		)
	)
	(footprint ""
		(layer "B.Cu")
		(at 95.377254 -73.51014)
		(property "Reference" "C8P28"
			(at 0 0 0)
			(layer "B.SilkS")
			(hide yes)
			(effects
				(font
					(size 1.27 1.27)
				)
				(justify mirror)
			)
		)
		(property "Value" ""
			(at 0 0 0)
			(layer "B.Fab")
			(effects
				(font
					(size 1.27 1.27)
				)
				(justify mirror)
			)
		)
		(duplicate_pad_numbers_are_jumpers no)
		(fp_poly
			(pts
				(xy 0.7239 -0.2159) (xy -0.7239 -0.2159) (xy -0.7239 1.9939) (xy 0.7239 1.9939)
			)
			(stroke
				(width 0)
				(type default)
			)
			(fill no)
			(layer "B.CrtYd")
		)
		(fp_line
			(start -0.7239 -0.2159)
			(end 0.7239 -0.2159)
			(stroke
				(width 0.1)
				(type default)
			)
			(layer "B.Fab")
		)
		(fp_line
			(start -0.7239 1.9939)
			(end -0.7239 -0.2159)
			(stroke
				(width 0.1)
				(type default)
			)
			(layer "B.Fab")
		)
		(fp_line
			(start 0.7239 -0.2159)
			(end 0.7239 1.9939)
			(stroke
				(width 0.1)
				(type default)
			)
			(layer "B.Fab")
		)
		(fp_line
			(start 0.7239 1.9939)
			(end -0.7239 1.9939)
			(stroke
				(width 0.1)
				(type default)
			)
			(layer "B.Fab")
		)
		(pad "1" smd rect
			(at 0 0 180)
			(size 1.27 1.016)
			(layers "B.Cu" "B.Mask" "B.Paste")
			(net "PVCCIN_CPU1")
		)
		(pad "2" smd rect
			(at 0 1.778 180)
			(size 1.27 1.016)
			(layers "B.Cu" "B.Mask" "B.Paste")
			(net "GND")
		)
		(zone
			(layer "B.Cu")
			(hatch none 0.5)
			(connect_pads
				(clearance 0)
			)
			(min_thickness 0.25)
			(keepout
				(tracks not_allowed)
				(vias allowed)
				(pads allowed)
				(copperpour not_allowed)
				(footprints allowed)
			)
			(placement
				(enabled no)
				(sheetname "")
			)
			(fill
				(thermal_gap 0.5)
				(thermal_bridge_width 0.5)
				(island_removal_mode 0)
			)
			(polygon
				(pts
					(xy 96.012254 -73.00214) (xy 94.742254 -73.00214) (xy 94.742254 -72.24014) (xy 96.012254 -72.24014)
				)
			)
		)
	)
	(footprint ""
		(layer "B.Cu")
		(at 347.346778 -101.449632 -90)
		(property "Reference" "C7C20"
			(at 0 0 90)
			(layer "B.SilkS")
			(hide yes)
			(effects
				(font
					(size 1.27 1.27)
				)
				(justify mirror)
			)
		)
		(property "Value" "*"
			(at -1.1811 -2.8194 270)
			(unlocked yes)
			(layer "B.Fab")
			(hide yes)
			(effects
				(font
					(size 1.27 1.016)
					(thickness 0.1524)
				)
				(justify mirror)
			)
		)
		(property "Device Type" "SC1U10V2KX-4-GP_SMD-BCG6-SC1U1A"
			(at -1.1811 -4.3434 270)
			(unlocked yes)
			(layer "B.Fab")
			(hide yes)
			(effects
				(font
					(size 1.27 1.016)
					(thickness 0.1524)
				)
				(justify mirror)
			)
		)
		(duplicate_pad_numbers_are_jumpers no)
		(fp_rect
			(start 0.4318 0.9525)
			(end -0.4318 -0.9525)
			(stroke
				(width 0)
				(type default)
			)
			(fill no)
			(layer "B.CrtYd")
		)
		(fp_rect
			(start 0.4318 0.9525)
			(end -0.4318 -0.9525)
			(stroke
				(width 0)
				(type default)
			)
			(fill no)
			(layer "B.Fab")
		)
		(pad "1" smd custom
			(at 0 -0.4445 90)
			(size 0.1524 0.1524)
			(layers "B.Cu" "B.Mask" "B.Paste")
			(net "P5V_STBY")
			(options
				(clearance outline)
				(anchor circle)
			)
			(primitives
				(gr_poly
					(pts
						(arc
							(start 0.3048 0.2032)
							(mid 0.275042 0.275042)
							(end 0.2032 0.3048)
						)
						(arc
							(start -0.2032 0.3048)
							(mid -0.275042 0.275042)
							(end -0.3048 0.2032)
						)
						(arc
							(start -0.3048 -0.2032)
							(mid -0.275042 -0.275042)
							(end -0.2032 -0.3048)
						)
						(arc
							(start 0.2032 -0.3048)
							(mid 0.275042 -0.275042)
							(end 0.3048 -0.2032)
						)
					)
					(width 0)
					(fill yes)
				)
			)
		)
		(pad "2" smd custom
			(at 0 0.4445 90)
			(size 0.1524 0.1524)
			(layers "B.Cu" "B.Mask" "B.Paste")
			(net "GND")
			(options
				(clearance outline)
				(anchor circle)
			)
			(primitives
				(gr_poly
					(pts
						(arc
							(start 0.3048 0.2032)
							(mid 0.275042 0.275042)
							(end 0.2032 0.3048)
						)
						(arc
							(start -0.2032 0.3048)
							(mid -0.275042 0.275042)
							(end -0.3048 0.2032)
						)
						(arc
							(start -0.3048 -0.2032)
							(mid -0.275042 -0.275042)
							(end -0.2032 -0.3048)
						)
						(arc
							(start 0.2032 -0.3048)
							(mid 0.275042 -0.275042)
							(end 0.3048 -0.2032)
						)
					)
					(width 0)
					(fill yes)
				)
			)
		)
	)
	(footprint ""
		(layer "B.Cu")
		(at 23.87854 -87.24138 90)
		(property "Reference" "CR9P1"
			(at 0 0 90)
			(layer "B.SilkS")
			(hide yes)
			(effects
				(font
					(size 1.27 1.27)
				)
				(justify mirror)
			)
		)
		(property "Value" ""
			(at 0 0 90)
			(layer "B.Fab")
			(effects
				(font
					(size 1.27 1.27)
				)
				(justify mirror)
			)
		)
		(duplicate_pad_numbers_are_jumpers no)
		(fp_line
			(start -0.546862 -0.332486)
			(end -0.546862 0.790956)
			(stroke
				(width 0.1524)
				(type default)
			)
			(layer "B.SilkS")
		)
		(fp_line
			(start -0.546862 0.790956)
			(end -1.027684 1.623822)
			(stroke
				(width 0.1524)
				(type default)
			)
			(layer "B.SilkS")
		)
		(fp_line
			(start -1.027684 0.790956)
			(end -0.06604 0.790956)
			(stroke
				(width 0.1524)
				(type default)
			)
			(layer "B.SilkS")
		)
		(fp_line
			(start -0.06604 1.623822)
			(end -0.546862 0.790956)
			(stroke
				(width 0.1524)
				(type default)
			)
			(layer "B.SilkS")
		)
		(fp_line
			(start -0.546862 1.623822)
			(end -0.06604 1.623822)
			(stroke
				(width 0.1524)
				(type default)
			)
			(layer "B.SilkS")
		)
		(fp_line
			(start -1.027684 1.623822)
			(end -0.546862 1.623822)
			(stroke
				(width 0.1524)
				(type default)
			)
			(layer "B.SilkS")
		)
		(fp_line
			(start -0.546862 2.535428)
			(end -0.546862 1.623822)
			(stroke
				(width 0.1524)
				(type default)
			)
			(layer "B.SilkS")
		)
		(fp_poly
			(pts
				(xy 0.67437 0.24384) (xy 0.67437 2.04216) (xy -0.67437 2.04216) (xy -0.67437 0.24384)
			)
			(stroke
				(width 0)
				(type default)
			)
			(fill no)
			(layer "B.CrtYd")
		)
		(fp_line
			(start 0.67437 0.24384)
			(end 0.67437 2.04216)
			(stroke
				(width 0.1)
				(type default)
			)
			(layer "B.Fab")
		)
		(fp_line
			(start -0.67437 0.24384)
			(end 0.67437 0.24384)
			(stroke
				(width 0.1)
				(type default)
			)
			(layer "B.Fab")
		)
		(fp_line
			(start -0.546862 0.790956)
			(end -0.546862 -0.332486)
			(stroke
				(width 0.1)
				(type default)
			)
			(layer "B.Fab")
		)
		(fp_line
			(start -0.546862 0.790956)
			(end -1.027684 1.623822)
			(stroke
				(width 0.1)
				(type default)
			)
			(layer "B.Fab")
		)
		(fp_line
			(start -1.027684 0.790956)
			(end -0.06604 0.790956)
			(stroke
				(width 0.1)
				(type default)
			)
			(layer "B.Fab")
		)
		(fp_line
			(start -0.06604 1.623822)
			(end -0.546862 0.790956)
			(stroke
				(width 0.1)
				(type default)
			)
			(layer "B.Fab")
		)
		(fp_line
			(start -0.546862 1.623822)
			(end -0.546862 2.535428)
			(stroke
				(width 0.1)
				(type default)
			)
			(layer "B.Fab")
		)
		(fp_line
			(start -1.027684 1.623822)
			(end -0.06604 1.623822)
			(stroke
				(width 0.1)
				(type default)
			)
			(layer "B.Fab")
		)
		(fp_line
			(start 0.67437 2.04216)
			(end -0.67437 2.04216)
			(stroke
				(width 0.1)
				(type default)
			)
			(layer "B.Fab")
		)
		(fp_line
			(start -0.67437 2.04216)
			(end -0.67437 0.24384)
			(stroke
				(width 0.1)
				(type default)
			)
			(layer "B.Fab")
		)
		(pad "1" smd rect
			(at 0 0 270)
			(size 0.4064 1.016)
			(layers "B.Cu" "B.Mask" "B.Paste")
			(net "IRQ_UV_DETECT_N")
		)
		(pad "2" smd rect
			(at 0 2.286 270)
			(size 0.4064 1.016)
			(layers "B.Cu" "B.Mask" "B.Paste")
			(net "FM_DISABLE_FAN_N")
		)
	)
	(footprint ""
		(layer "B.Cu")
		(at 382.0922 -137.541)
		(property "Reference" "C3L26"
			(at 0 0 0)
			(layer "B.SilkS")
			(hide yes)
			(effects
				(font
					(size 1.27 1.27)
				)
				(justify mirror)
			)
		)
		(property "Value" ""
			(at 0 0 0)
			(layer "B.Fab")
			(effects
				(font
					(size 1.27 1.27)
				)
				(justify mirror)
			)
		)
		(duplicate_pad_numbers_are_jumpers no)
		(fp_poly
			(pts
				(xy 0.4953 -0.2032) (xy -0.4953 -0.2032) (xy -0.4953 1.6002) (xy 0.4953 1.6002)
			)
			(stroke
				(width 0)
				(type default)
			)
			(fill no)
			(layer "B.CrtYd")
		)
		(fp_line
			(start -0.4953 -0.2032)
			(end -0.4953 1.6002)
			(stroke
				(width 0.1)
				(type default)
			)
			(layer "B.Fab")
		)
		(fp_line
			(start -0.4953 1.6002)
			(end 0.4953 1.6002)
			(stroke
				(width 0.1)
				(type default)
			)
			(layer "B.Fab")
		)
		(fp_line
			(start 0.4953 -0.2032)
			(end -0.4953 -0.2032)
			(stroke
				(width 0.1)
				(type default)
			)
			(layer "B.Fab")
		)
		(fp_line
			(start 0.4953 1.6002)
			(end 0.4953 -0.2032)
			(stroke
				(width 0.1)
				(type default)
			)
			(layer "B.Fab")
		)
		(pad "1" smd rect
			(at 0 0 180)
			(size 0.762 0.889)
			(layers "B.Cu" "B.Mask" "B.Paste")
			(net "PVNN_PCH_STBY")
		)
		(pad "2" smd rect
			(at 0 1.397 180)
			(size 0.762 0.889)
			(layers "B.Cu" "B.Mask" "B.Paste")
			(net "GND")
		)
		(zone
			(layer "B.Cu")
			(hatch none 0.5)
			(connect_pads
				(clearance 0)
			)
			(min_thickness 0.25)
			(keepout
				(tracks not_allowed)
				(vias allowed)
				(pads allowed)
				(copperpour not_allowed)
				(footprints allowed)
			)
			(placement
				(enabled no)
				(sheetname "")
			)
			(fill
				(thermal_gap 0.5)
				(thermal_bridge_width 0.5)
				(island_removal_mode 0)
			)
			(polygon
				(pts
					(xy 382.4732 -137.0965) (xy 381.7112 -137.0965) (xy 381.7112 -136.5885) (xy 382.4732 -136.5885)
				)
			)
		)
	)
	(footprint ""
		(layer "B.Cu")
		(at 429.046894 -16.042894 -90)
		(property "Reference" "R1U36"
			(at 0 0 90)
			(layer "B.SilkS")
			(hide yes)
			(effects
				(font
					(size 1.27 1.27)
				)
				(justify mirror)
			)
		)
		(property "Value" ""
			(at 0 0 90)
			(layer "B.Fab")
			(effects
				(font
					(size 1.27 1.27)
				)
				(justify mirror)
			)
		)
		(duplicate_pad_numbers_are_jumpers no)
		(fp_poly
			(pts
				(xy 0.2794 -0.1016) (xy -0.2794 -0.1016) (xy -0.2794 0.9906) (xy 0.2794 0.9906)
			)
			(stroke
				(width 0)
				(type default)
			)
			(fill no)
			(layer "B.CrtYd")
		)
		(fp_line
			(start -0.2794 0.9906)
			(end -0.2794 -0.1016)
			(stroke
				(width 0.1)
				(type default)
			)
			(layer "B.Fab")
		)
		(fp_line
			(start 0.2794 0.9906)
			(end -0.2794 0.9906)
			(stroke
				(width 0.1)
				(type default)
			)
			(layer "B.Fab")
		)
		(fp_line
			(start -0.2794 -0.1016)
			(end 0.2794 -0.1016)
			(stroke
				(width 0.1)
				(type default)
			)
			(layer "B.Fab")
		)
		(fp_line
			(start 0.2794 -0.1016)
			(end 0.2794 0.9906)
			(stroke
				(width 0.1)
				(type default)
			)
			(layer "B.Fab")
		)
		(pad "1" smd rect
			(at 0 0 90)
			(size 0.508 0.508)
			(layers "B.Cu" "B.Mask" "B.Paste")
			(net "H_CPU1_MEMGHJ_MEMHOT_LVT3_K_N")
		)
		(pad "2" smd rect
			(at 0 0.889 90)
			(size 0.508 0.508)
			(layers "B.Cu" "B.Mask" "B.Paste")
			(net "H_CPU1_MEMGHJ_MEMHOT_LVT3_N")
		)
		(zone
			(layer "B.Cu")
			(hatch none 0.5)
			(connect_pads
				(clearance 0)
			)
			(min_thickness 0.25)
			(keepout
				(tracks not_allowed)
				(vias allowed)
				(pads allowed)
				(copperpour not_allowed)
				(footprints allowed)
			)
			(placement
				(enabled no)
				(sheetname "")
			)
			(fill
				(thermal_gap 0.5)
				(thermal_bridge_width 0.5)
				(island_removal_mode 0)
			)
			(polygon
				(pts
					(xy 428.411894 -15.788894) (xy 428.411894 -16.296894) (xy 428.792894 -16.296894) (xy 428.792894 -15.788894)
				)
			)
		)
		(zone
			(layer "B.Cu")
			(hatch none 0.5)
			(connect_pads
				(clearance 0)
			)
			(min_thickness 0.25)
			(keepout
				(tracks allowed)
				(vias not_allowed)
				(pads allowed)
				(copperpour not_allowed)
				(footprints allowed)
			)
			(placement
				(enabled no)
				(sheetname "")
			)
			(fill
				(thermal_gap 0.5)
				(thermal_bridge_width 0.5)
				(island_removal_mode 0)
			)
			(polygon
				(pts
					(xy 428.792894 -15.788894) (xy 428.792894 -16.296894) (xy 428.411894 -16.296894) (xy 428.411894 -15.788894)
				)
			)
		)
	)
	(footprint ""
		(layer "B.Cu")
		(at 333.659226 -38.259766 90)
		(property "Reference" "C3T2"
			(at 0 0 90)
			(layer "B.SilkS")
			(hide yes)
			(effects
				(font
					(size 1.27 1.27)
				)
				(justify mirror)
			)
		)
		(property "Value" ""
			(at 0 0 90)
			(layer "B.Fab")
			(effects
				(font
					(size 1.27 1.27)
				)
				(justify mirror)
			)
		)
		(duplicate_pad_numbers_are_jumpers no)
		(fp_rect
			(start 0.500126 1.598422)
			(end -0.500126 -0.201422)
			(stroke
				(width 0)
				(type default)
			)
			(fill no)
			(layer "B.CrtYd")
		)
		(fp_line
			(start 0.500126 -0.201422)
			(end -0.500126 -0.201422)
			(stroke
				(width 0.1)
				(type default)
			)
			(layer "B.Fab")
		)
		(fp_line
			(start -0.500126 -0.201422)
			(end -0.500126 1.598422)
			(stroke
				(width 0.1)
				(type default)
			)
			(layer "B.Fab")
		)
		(fp_line
			(start 0.500126 1.598422)
			(end 0.500126 -0.201422)
			(stroke
				(width 0.1)
				(type default)
			)
			(layer "B.Fab")
		)
		(fp_line
			(start -0.500126 1.598422)
			(end 0.500126 1.598422)
			(stroke
				(width 0.1)
				(type default)
			)
			(layer "B.Fab")
		)
		(pad "1" smd rect
			(at 0 0)
			(size 0.889 0.9906)
			(layers "B.Cu" "B.Mask" "B.Paste")
			(net "P1V8_MCP_CPU0")
		)
		(pad "2" smd rect
			(at 0 1.397)
			(size 0.889 0.9906)
			(layers "B.Cu" "B.Mask" "B.Paste")
			(net "GND")
		)
		(zone
			(layer "B.Cu")
			(hatch none 0.5)
			(connect_pads
				(clearance 0)
			)
			(min_thickness 0.25)
			(keepout
				(tracks allowed)
				(vias not_allowed)
				(pads allowed)
				(copperpour not_allowed)
				(footprints allowed)
			)
			(placement
				(enabled no)
				(sheetname "")
			)
			(fill
				(thermal_gap 0.5)
				(thermal_bridge_width 0.5)
				(island_removal_mode 0)
			)
			(polygon
				(pts
					(xy 334.611726 -38.755066) (xy 334.103726 -38.755066) (xy 334.103726 -37.764466) (xy 334.611726 -37.764466)
				)
			)
		)
		(zone
			(layer "B.Cu")
			(hatch none 0.5)
			(connect_pads
				(clearance 0)
			)
			(min_thickness 0.25)
			(keepout
				(tracks not_allowed)
				(vias allowed)
				(pads allowed)
				(copperpour not_allowed)
				(footprints allowed)
			)
			(placement
				(enabled no)
				(sheetname "")
			)
			(fill
				(thermal_gap 0.5)
				(thermal_bridge_width 0.5)
				(island_removal_mode 0)
			)
			(polygon
				(pts
					(xy 334.611726 -38.755066) (xy 334.103726 -38.755066) (xy 334.103726 -37.764466) (xy 334.611726 -37.764466)
				)
			)
		)
	)
	(footprint ""
		(layer "B.Cu")
		(at 467.868 -4.3815)
		(property "Reference" "R7E22"
			(at 0 0 0)
			(layer "B.SilkS")
			(hide yes)
			(effects
				(font
					(size 1.27 1.27)
				)
				(justify mirror)
			)
		)
		(property "Value" ""
			(at 0 0 0)
			(layer "B.Fab")
			(effects
				(font
					(size 1.27 1.27)
				)
				(justify mirror)
			)
		)
		(duplicate_pad_numbers_are_jumpers no)
		(fp_poly
			(pts
				(xy 0.2794 -0.1016) (xy -0.2794 -0.1016) (xy -0.2794 0.9906) (xy 0.2794 0.9906)
			)
			(stroke
				(width 0)
				(type default)
			)
			(fill no)
			(layer "B.CrtYd")
		)
		(fp_line
			(start -0.2794 -0.1016)
			(end 0.2794 -0.1016)
			(stroke
				(width 0.1)
				(type default)
			)
			(layer "B.Fab")
		)
		(fp_line
			(start -0.2794 0.9906)
			(end -0.2794 -0.1016)
			(stroke
				(width 0.1)
				(type default)
			)
			(layer "B.Fab")
		)
		(fp_line
			(start 0.2794 -0.1016)
			(end 0.2794 0.9906)
			(stroke
				(width 0.1)
				(type default)
			)
			(layer "B.Fab")
		)
		(fp_line
			(start 0.2794 0.9906)
			(end -0.2794 0.9906)
			(stroke
				(width 0.1)
				(type default)
			)
			(layer "B.Fab")
		)
		(pad "1" smd rect
			(at 0 0 180)
			(size 0.508 0.508)
			(layers "B.Cu" "B.Mask" "B.Paste")
			(net "FM_PWRBRK_N")
		)
		(pad "2" smd rect
			(at 0 0.889 180)
			(size 0.508 0.508)
			(layers "B.Cu" "B.Mask" "B.Paste")
			(net "FM_PWRBRK_SLOT_N")
		)
		(zone
			(layer "B.Cu")
			(hatch none 0.5)
			(connect_pads
				(clearance 0)
			)
			(min_thickness 0.25)
			(keepout
				(tracks allowed)
				(vias not_allowed)
				(pads allowed)
				(copperpour not_allowed)
				(footprints allowed)
			)
			(placement
				(enabled no)
				(sheetname "")
			)
			(fill
				(thermal_gap 0.5)
				(thermal_bridge_width 0.5)
				(island_removal_mode 0)
			)
			(polygon
				(pts
					(xy 468.122 -4.1275) (xy 467.614 -4.1275) (xy 467.614 -3.7465) (xy 468.122 -3.7465)
				)
			)
		)
		(zone
			(layer "B.Cu")
			(hatch none 0.5)
			(connect_pads
				(clearance 0)
			)
			(min_thickness 0.25)
			(keepout
				(tracks not_allowed)
				(vias allowed)
				(pads allowed)
				(copperpour not_allowed)
				(footprints allowed)
			)
			(placement
				(enabled no)
				(sheetname "")
			)
			(fill
				(thermal_gap 0.5)
				(thermal_bridge_width 0.5)
				(island_removal_mode 0)
			)
			(polygon
				(pts
					(xy 468.122 -3.7465) (xy 467.614 -3.7465) (xy 467.614 -4.1275) (xy 468.122 -4.1275)
				)
			)
		)
	)
	(footprint ""
		(layer "B.Cu")
		(at 417.576 -6.5405)
		(property "Reference" "R3P50"
			(at 0 0 0)
			(layer "B.SilkS")
			(hide yes)
			(effects
				(font
					(size 1.27 1.27)
				)
				(justify mirror)
			)
		)
		(property "Value" ""
			(at 0 0 0)
			(layer "B.Fab")
			(effects
				(font
					(size 1.27 1.27)
				)
				(justify mirror)
			)
		)
		(duplicate_pad_numbers_are_jumpers no)
		(fp_rect
			(start -0.2794 0.9906)
			(end 0.2794 -0.1016)
			(stroke
				(width 0)
				(type default)
			)
			(fill no)
			(layer "B.CrtYd")
		)
		(fp_line
			(start -0.2794 -0.1016)
			(end 0.2794 -0.1016)
			(stroke
				(width 0.1)
				(type default)
			)
			(layer "B.Fab")
		)
		(fp_line
			(start -0.2794 0.9906)
			(end -0.2794 -0.1016)
			(stroke
				(width 0.1)
				(type default)
			)
			(layer "B.Fab")
		)
		(fp_line
			(start 0.2794 -0.1016)
			(end 0.2794 0.9906)
			(stroke
				(width 0.1)
				(type default)
			)
			(layer "B.Fab")
		)
		(fp_line
			(start 0.2794 0.9906)
			(end -0.2794 0.9906)
			(stroke
				(width 0.1)
				(type default)
			)
			(layer "B.Fab")
		)
		(pad "1" smd rect
			(at 0 0 180)
			(size 0.508 0.508)
			(layers "B.Cu" "B.Mask" "B.Paste")
			(net "P3V3_STBY")
		)
		(pad "2" smd rect
			(at 0 0.889 180)
			(size 0.508 0.508)
			(layers "B.Cu" "B.Mask" "B.Paste")
			(net "PWRGD_P3V3_STBY")
		)
		(zone
			(layer "B.Cu")
			(hatch none 0.5)
			(connect_pads
				(clearance 0)
			)
			(min_thickness 0.25)
			(keepout
				(tracks allowed)
				(vias not_allowed)
				(pads allowed)
				(copperpour not_allowed)
				(footprints allowed)
			)
			(placement
				(enabled no)
				(sheetname "")
			)
			(fill
				(thermal_gap 0.5)
				(thermal_bridge_width 0.5)
				(island_removal_mode 0)
			)
			(polygon
				(pts
					(xy 417.322 -5.9055) (xy 417.83 -5.9055) (xy 417.83 -6.2865) (xy 417.322 -6.2865)
				)
			)
		)
		(zone
			(layer "B.Cu")
			(hatch none 0.5)
			(connect_pads
				(clearance 0)
			)
			(min_thickness 0.25)
			(keepout
				(tracks not_allowed)
				(vias allowed)
				(pads allowed)
				(copperpour not_allowed)
				(footprints allowed)
			)
			(placement
				(enabled no)
				(sheetname "")
			)
			(fill
				(thermal_gap 0.5)
				(thermal_bridge_width 0.5)
				(island_removal_mode 0)
			)
			(polygon
				(pts
					(xy 417.322 -5.9055) (xy 417.83 -5.9055) (xy 417.83 -6.2865) (xy 417.322 -6.2865)
				)
			)
		)
	)
	(footprint ""
		(layer "B.Cu")
		(at 49.4284 -78.359)
		(property "Reference" "C9P10"
			(at 0 0 0)
			(layer "B.SilkS")
			(hide yes)
			(effects
				(font
					(size 1.27 1.27)
				)
				(justify mirror)
			)
		)
		(property "Value" ""
			(at 0 0 0)
			(layer "B.Fab")
			(effects
				(font
					(size 1.27 1.27)
				)
				(justify mirror)
			)
		)
		(duplicate_pad_numbers_are_jumpers no)
		(fp_poly
			(pts
				(xy 0.4953 -0.2032) (xy -0.4953 -0.2032) (xy -0.4953 1.6002) (xy 0.4953 1.6002)
			)
			(stroke
				(width 0)
				(type default)
			)
			(fill no)
			(layer "B.CrtYd")
		)
		(fp_line
			(start -0.4953 -0.2032)
			(end -0.4953 1.6002)
			(stroke
				(width 0.1)
				(type default)
			)
			(layer "B.Fab")
		)
		(fp_line
			(start -0.4953 1.6002)
			(end 0.4953 1.6002)
			(stroke
				(width 0.1)
				(type default)
			)
			(layer "B.Fab")
		)
		(fp_line
			(start 0.4953 -0.2032)
			(end -0.4953 -0.2032)
			(stroke
				(width 0.1)
				(type default)
			)
			(layer "B.Fab")
		)
		(fp_line
			(start 0.4953 1.6002)
			(end 0.4953 -0.2032)
			(stroke
				(width 0.1)
				(type default)
			)
			(layer "B.Fab")
		)
		(pad "1" smd rect
			(at 0 0 180)
			(size 0.762 0.889)
			(layers "B.Cu" "B.Mask" "B.Paste")
			(net "PVCCIN_CPU1")
		)
		(pad "2" smd rect
			(at 0 1.397 180)
			(size 0.762 0.889)
			(layers "B.Cu" "B.Mask" "B.Paste")
			(net "GND")
		)
		(zone
			(layer "B.Cu")
			(hatch none 0.5)
			(connect_pads
				(clearance 0)
			)
			(min_thickness 0.25)
			(keepout
				(tracks not_allowed)
				(vias allowed)
				(pads allowed)
				(copperpour not_allowed)
				(footprints allowed)
			)
			(placement
				(enabled no)
				(sheetname "")
			)
			(fill
				(thermal_gap 0.5)
				(thermal_bridge_width 0.5)
				(island_removal_mode 0)
			)
			(polygon
				(pts
					(xy 49.8094 -77.9145) (xy 49.0474 -77.9145) (xy 49.0474 -77.4065) (xy 49.8094 -77.4065)
				)
			)
		)
	)
	(footprint ""
		(layer "B.Cu")
		(at 19.05 -95.5294)
		(property "Reference" "R9N8"
			(at 0 0 0)
			(layer "B.SilkS")
			(hide yes)
			(effects
				(font
					(size 1.27 1.27)
				)
				(justify mirror)
			)
		)
		(property "Value" ""
			(at 0 0 0)
			(layer "B.Fab")
			(effects
				(font
					(size 1.27 1.27)
				)
				(justify mirror)
			)
		)
		(duplicate_pad_numbers_are_jumpers no)
		(fp_poly
			(pts
				(xy 0.2794 -0.1016) (xy -0.2794 -0.1016) (xy -0.2794 0.9906) (xy 0.2794 0.9906)
			)
			(stroke
				(width 0)
				(type default)
			)
			(fill no)
			(layer "B.CrtYd")
		)
		(fp_line
			(start -0.2794 -0.1016)
			(end 0.2794 -0.1016)
			(stroke
				(width 0.1)
				(type default)
			)
			(layer "B.Fab")
		)
		(fp_line
			(start -0.2794 0.9906)
			(end -0.2794 -0.1016)
			(stroke
				(width 0.1)
				(type default)
			)
			(layer "B.Fab")
		)
		(fp_line
			(start 0.2794 -0.1016)
			(end 0.2794 0.9906)
			(stroke
				(width 0.1)
				(type default)
			)
			(layer "B.Fab")
		)
		(fp_line
			(start 0.2794 0.9906)
			(end -0.2794 0.9906)
			(stroke
				(width 0.1)
				(type default)
			)
			(layer "B.Fab")
		)
		(pad "1" smd rect
			(at 0 0 180)
			(size 0.508 0.508)
			(layers "B.Cu" "B.Mask" "B.Paste")
			(net "VR_PVCCIN_CPU1_XADDR1")
		)
		(pad "2" smd rect
			(at 0 0.889 180)
			(size 0.508 0.508)
			(layers "B.Cu" "B.Mask" "B.Paste")
			(net "GND")
		)
		(zone
			(layer "B.Cu")
			(hatch none 0.5)
			(connect_pads
				(clearance 0)
			)
			(min_thickness 0.25)
			(keepout
				(tracks allowed)
				(vias not_allowed)
				(pads allowed)
				(copperpour not_allowed)
				(footprints allowed)
			)
			(placement
				(enabled no)
				(sheetname "")
			)
			(fill
				(thermal_gap 0.5)
				(thermal_bridge_width 0.5)
				(island_removal_mode 0)
			)
			(polygon
				(pts
					(xy 19.304 -95.2754) (xy 18.796 -95.2754) (xy 18.796 -94.8944) (xy 19.304 -94.8944)
				)
			)
		)
		(zone
			(layer "B.Cu")
			(hatch none 0.5)
			(connect_pads
				(clearance 0)
			)
			(min_thickness 0.25)
			(keepout
				(tracks not_allowed)
				(vias allowed)
				(pads allowed)
				(copperpour not_allowed)
				(footprints allowed)
			)
			(placement
				(enabled no)
				(sheetname "")
			)
			(fill
				(thermal_gap 0.5)
				(thermal_bridge_width 0.5)
				(island_removal_mode 0)
			)
			(polygon
				(pts
					(xy 19.304 -94.8944) (xy 18.796 -94.8944) (xy 18.796 -95.2754) (xy 19.304 -95.2754)
				)
			)
		)
	)
	(footprint ""
		(layer "B.Cu")
		(at 399.530824 -125.627384 90)
		(property "Reference" "C2M3"
			(at 0 0 90)
			(layer "B.SilkS")
			(hide yes)
			(effects
				(font
					(size 1.27 1.27)
				)
				(justify mirror)
			)
		)
		(property "Value" ""
			(at 0 0 90)
			(layer "B.Fab")
			(effects
				(font
					(size 1.27 1.27)
				)
				(justify mirror)
			)
		)
		(duplicate_pad_numbers_are_jumpers no)
		(fp_poly
			(pts
				(xy -0.3048 -0.1016) (xy -0.3048 0.9906) (xy 0.3048 0.9906) (xy 0.3048 -0.1016)
			)
			(stroke
				(width 0)
				(type default)
			)
			(fill no)
			(layer "B.CrtYd")
		)
		(fp_line
			(start 0.3048 -0.1016)
			(end 0.3048 0.9906)
			(stroke
				(width 0.1)
				(type default)
			)
			(layer "B.Fab")
		)
		(fp_line
			(start -0.3048 -0.1016)
			(end 0.3048 -0.1016)
			(stroke
				(width 0.1)
				(type default)
			)
			(layer "B.Fab")
		)
		(fp_line
			(start 0.3048 0.9906)
			(end -0.3048 0.9906)
			(stroke
				(width 0.1)
				(type default)
			)
			(layer "B.Fab")
		)
		(fp_line
			(start -0.3048 0.9906)
			(end -0.3048 -0.1016)
			(stroke
				(width 0.1)
				(type default)
			)
			(layer "B.Fab")
		)
		(pad "1" smd rect
			(at 0 0 270)
			(size 0.508 0.508)
			(layers "B.Cu" "B.Mask" "B.Paste")
			(net "P2E_SSB_BMC_TX_DN")
		)
		(pad "2" smd rect
			(at 0 0.889 270)
			(size 0.508 0.508)
			(layers "B.Cu" "B.Mask" "B.Paste")
			(net "P2E_SSB_BMC_TX_C_DN")
		)
		(zone
			(layer "B.Cu")
			(hatch none 0.5)
			(connect_pads
				(clearance 0)
			)
			(min_thickness 0.25)
			(keepout
				(tracks allowed)
				(vias not_allowed)
				(pads allowed)
				(copperpour not_allowed)
				(footprints allowed)
			)
			(placement
				(enabled no)
				(sheetname "")
			)
			(fill
				(thermal_gap 0.5)
				(thermal_bridge_width 0.5)
				(island_removal_mode 0)
			)
			(polygon
				(pts
					(xy 399.784824 -125.881384) (xy 399.784824 -125.373384) (xy 400.165824 -125.373384) (xy 400.165824 -125.881384)
				)
			)
		)
		(zone
			(layer "B.Cu")
			(hatch none 0.5)
			(connect_pads
				(clearance 0)
			)
			(min_thickness 0.25)
			(keepout
				(tracks not_allowed)
				(vias allowed)
				(pads allowed)
				(copperpour not_allowed)
				(footprints allowed)
			)
			(placement
				(enabled no)
				(sheetname "")
			)
			(fill
				(thermal_gap 0.5)
				(thermal_bridge_width 0.5)
				(island_removal_mode 0)
			)
			(polygon
				(pts
					(xy 400.165824 -125.881384) (xy 400.165824 -125.373384) (xy 399.784824 -125.373384) (xy 399.784824 -125.881384)
				)
			)
		)
	)
	(footprint ""
		(layer "B.Cu")
		(at 322.9737 -27.411172 90)
		(property "Reference" "R4T9"
			(at 0 0 90)
			(layer "B.SilkS")
			(hide yes)
			(effects
				(font
					(size 1.27 1.27)
				)
				(justify mirror)
			)
		)
		(property "Value" ""
			(at 0 0 90)
			(layer "B.Fab")
			(effects
				(font
					(size 1.27 1.27)
				)
				(justify mirror)
			)
		)
		(duplicate_pad_numbers_are_jumpers no)
		(fp_poly
			(pts
				(xy 0.2794 -0.1016) (xy -0.2794 -0.1016) (xy -0.2794 0.9906) (xy 0.2794 0.9906)
			)
			(stroke
				(width 0)
				(type default)
			)
			(fill no)
			(layer "B.CrtYd")
		)
		(fp_line
			(start 0.2794 -0.1016)
			(end 0.2794 0.9906)
			(stroke
				(width 0.1)
				(type default)
			)
			(layer "B.Fab")
		)
		(fp_line
			(start -0.2794 -0.1016)
			(end 0.2794 -0.1016)
			(stroke
				(width 0.1)
				(type default)
			)
			(layer "B.Fab")
		)
		(fp_line
			(start 0.2794 0.9906)
			(end -0.2794 0.9906)
			(stroke
				(width 0.1)
				(type default)
			)
			(layer "B.Fab")
		)
		(fp_line
			(start -0.2794 0.9906)
			(end -0.2794 -0.1016)
			(stroke
				(width 0.1)
				(type default)
			)
			(layer "B.Fab")
		)
		(pad "1" smd rect
			(at 0 0 270)
			(size 0.508 0.508)
			(layers "B.Cu" "B.Mask" "B.Paste")
			(net "SMB_DDR_ABC_VPP_SCL_R")
		)
		(pad "2" smd rect
			(at 0 0.889 270)
			(size 0.508 0.508)
			(layers "B.Cu" "B.Mask" "B.Paste")
			(net "SMB_DDR_ABC_VPP_SCL")
		)
		(zone
			(layer "B.Cu")
			(hatch none 0.5)
			(connect_pads
				(clearance 0)
			)
			(min_thickness 0.25)
			(keepout
				(tracks allowed)
				(vias not_allowed)
				(pads allowed)
				(copperpour not_allowed)
				(footprints allowed)
			)
			(placement
				(enabled no)
				(sheetname "")
			)
			(fill
				(thermal_gap 0.5)
				(thermal_bridge_width 0.5)
				(island_removal_mode 0)
			)
			(polygon
				(pts
					(xy 323.2277 -27.665172) (xy 323.2277 -27.157172) (xy 323.6087 -27.157172) (xy 323.6087 -27.665172)
				)
			)
		)
		(zone
			(layer "B.Cu")
			(hatch none 0.5)
			(connect_pads
				(clearance 0)
			)
			(min_thickness 0.25)
			(keepout
				(tracks not_allowed)
				(vias allowed)
				(pads allowed)
				(copperpour not_allowed)
				(footprints allowed)
			)
			(placement
				(enabled no)
				(sheetname "")
			)
			(fill
				(thermal_gap 0.5)
				(thermal_bridge_width 0.5)
				(island_removal_mode 0)
			)
			(polygon
				(pts
					(xy 323.6087 -27.665172) (xy 323.6087 -27.157172) (xy 323.2277 -27.157172) (xy 323.2277 -27.665172)
				)
			)
		)
	)
	(footprint ""
		(layer "B.Cu")
		(at 99.427792 -69.098414 -90)
		(property "Reference" "C8P30"
			(at 0 0 90)
			(layer "B.SilkS")
			(hide yes)
			(effects
				(font
					(size 1.27 1.27)
				)
				(justify mirror)
			)
		)
		(property "Value" ""
			(at 0 0 90)
			(layer "B.Fab")
			(effects
				(font
					(size 1.27 1.27)
				)
				(justify mirror)
			)
		)
		(duplicate_pad_numbers_are_jumpers no)
		(fp_poly
			(pts
				(xy 0.7239 -0.2159) (xy -0.7239 -0.2159) (xy -0.7239 1.9939) (xy 0.7239 1.9939)
			)
			(stroke
				(width 0)
				(type default)
			)
			(fill no)
			(layer "B.CrtYd")
		)
		(fp_line
			(start -0.7239 1.9939)
			(end -0.7239 -0.2159)
			(stroke
				(width 0.1)
				(type default)
			)
			(layer "B.Fab")
		)
		(fp_line
			(start 0.7239 1.9939)
			(end -0.7239 1.9939)
			(stroke
				(width 0.1)
				(type default)
			)
			(layer "B.Fab")
		)
		(fp_line
			(start -0.7239 -0.2159)
			(end 0.7239 -0.2159)
			(stroke
				(width 0.1)
				(type default)
			)
			(layer "B.Fab")
		)
		(fp_line
			(start 0.7239 -0.2159)
			(end 0.7239 1.9939)
			(stroke
				(width 0.1)
				(type default)
			)
			(layer "B.Fab")
		)
		(pad "1" smd rect
			(at 0 0 90)
			(size 1.27 1.016)
			(layers "B.Cu" "B.Mask" "B.Paste")
			(net "PVDDQ_GHJ")
		)
		(pad "2" smd rect
			(at 0 1.778 90)
			(size 1.27 1.016)
			(layers "B.Cu" "B.Mask" "B.Paste")
			(net "GND")
		)
		(zone
			(layer "B.Cu")
			(hatch none 0.5)
			(connect_pads
				(clearance 0)
			)
			(min_thickness 0.25)
			(keepout
				(tracks not_allowed)
				(vias allowed)
				(pads allowed)
				(copperpour not_allowed)
				(footprints allowed)
			)
			(placement
				(enabled no)
				(sheetname "")
			)
			(fill
				(thermal_gap 0.5)
				(thermal_bridge_width 0.5)
				(island_removal_mode 0)
			)
			(polygon
				(pts
					(xy 98.919792 -68.463414) (xy 98.919792 -69.733414) (xy 98.157792 -69.733414) (xy 98.157792 -68.463414)
				)
			)
		)
	)
	(footprint ""
		(layer "B.Cu")
		(at 420.776146 -48.922432 -90)
		(property "Reference" "R1T8"
			(at 0 0 90)
			(layer "B.SilkS")
			(hide yes)
			(effects
				(font
					(size 1.27 1.27)
				)
				(justify mirror)
			)
		)
		(property "Value" ""
			(at 0 0 90)
			(layer "B.Fab")
			(effects
				(font
					(size 1.27 1.27)
				)
				(justify mirror)
			)
		)
		(duplicate_pad_numbers_are_jumpers no)
		(fp_poly
			(pts
				(xy 0.2794 -0.1016) (xy -0.2794 -0.1016) (xy -0.2794 0.9906) (xy 0.2794 0.9906)
			)
			(stroke
				(width 0)
				(type default)
			)
			(fill no)
			(layer "B.CrtYd")
		)
		(fp_line
			(start -0.2794 0.9906)
			(end -0.2794 -0.1016)
			(stroke
				(width 0.1)
				(type default)
			)
			(layer "B.Fab")
		)
		(fp_line
			(start 0.2794 0.9906)
			(end -0.2794 0.9906)
			(stroke
				(width 0.1)
				(type default)
			)
			(layer "B.Fab")
		)
		(fp_line
			(start -0.2794 -0.1016)
			(end 0.2794 -0.1016)
			(stroke
				(width 0.1)
				(type default)
			)
			(layer "B.Fab")
		)
		(fp_line
			(start 0.2794 -0.1016)
			(end 0.2794 0.9906)
			(stroke
				(width 0.1)
				(type default)
			)
			(layer "B.Fab")
		)
		(pad "1" smd rect
			(at 0 0 90)
			(size 0.508 0.508)
			(layers "B.Cu" "B.Mask" "B.Paste")
			(net "SMB_SLOTX24_STBY_LVC3_SDA_R")
		)
		(pad "2" smd rect
			(at 0 0.889 90)
			(size 0.508 0.508)
			(layers "B.Cu" "B.Mask" "B.Paste")
			(net "SMB_SLOTX24_BMC_STBY_LVC3_SDA")
		)
		(zone
			(layer "B.Cu")
			(hatch none 0.5)
			(connect_pads
				(clearance 0)
			)
			(min_thickness 0.25)
			(keepout
				(tracks not_allowed)
				(vias allowed)
				(pads allowed)
				(copperpour not_allowed)
				(footprints allowed)
			)
			(placement
				(enabled no)
				(sheetname "")
			)
			(fill
				(thermal_gap 0.5)
				(thermal_bridge_width 0.5)
				(island_removal_mode 0)
			)
			(polygon
				(pts
					(xy 420.141146 -48.668432) (xy 420.141146 -49.176432) (xy 420.522146 -49.176432) (xy 420.522146 -48.668432)
				)
			)
		)
		(zone
			(layer "B.Cu")
			(hatch none 0.5)
			(connect_pads
				(clearance 0)
			)
			(min_thickness 0.25)
			(keepout
				(tracks allowed)
				(vias not_allowed)
				(pads allowed)
				(copperpour not_allowed)
				(footprints allowed)
			)
			(placement
				(enabled no)
				(sheetname "")
			)
			(fill
				(thermal_gap 0.5)
				(thermal_bridge_width 0.5)
				(island_removal_mode 0)
			)
			(polygon
				(pts
					(xy 420.522146 -48.668432) (xy 420.522146 -49.176432) (xy 420.141146 -49.176432) (xy 420.141146 -48.668432)
				)
			)
		)
	)
	(footprint ""
		(layer "B.Cu")
		(at 361.826556 -122.510042 -90)
		(property "Reference" "R778"
			(at 0.8382 -0.67818 270)
			(unlocked yes)
			(layer "B.SilkS")
			(effects
				(font
					(size 0.4064 0.254)
					(thickness 0.1524)
				)
				(justify left mirror)
			)
		)
		(property "Value" ""
			(at 0 0 90)
			(layer "B.Fab")
			(effects
				(font
					(size 1.27 1.27)
				)
				(justify mirror)
			)
		)
		(duplicate_pad_numbers_are_jumpers no)
		(fp_poly
			(pts
				(xy 0.2794 -0.1016) (xy -0.2794 -0.1016) (xy -0.2794 0.9906) (xy 0.2794 0.9906)
			)
			(stroke
				(width 0)
				(type default)
			)
			(fill no)
			(layer "B.CrtYd")
		)
		(fp_line
			(start -0.2794 0.9906)
			(end -0.2794 -0.1016)
			(stroke
				(width 0.1)
				(type default)
			)
			(layer "B.Fab")
		)
		(fp_line
			(start 0.2794 0.9906)
			(end -0.2794 0.9906)
			(stroke
				(width 0.1)
				(type default)
			)
			(layer "B.Fab")
		)
		(fp_line
			(start -0.2794 -0.1016)
			(end 0.2794 -0.1016)
			(stroke
				(width 0.1)
				(type default)
			)
			(layer "B.Fab")
		)
		(fp_line
			(start 0.2794 -0.1016)
			(end 0.2794 0.9906)
			(stroke
				(width 0.1)
				(type default)
			)
			(layer "B.Fab")
		)
		(pad "1" smd rect
			(at 0 0 90)
			(size 0.508 0.508)
			(layers "B.Cu" "B.Mask" "B.Paste")
			(net "P3E_CPU0_PE1_PCH_RXN<11>")
		)
		(pad "2" smd rect
			(at 0 0.889 90)
			(size 0.508 0.508)
			(layers "B.Cu" "B.Mask" "B.Paste")
			(net "P3E_CPU0_PE1_PCH_CON_RXN<11>")
		)
		(zone
			(layer "B.Cu")
			(hatch none 0.5)
			(connect_pads
				(clearance 0)
			)
			(min_thickness 0.25)
			(keepout
				(tracks not_allowed)
				(vias allowed)
				(pads allowed)
				(copperpour not_allowed)
				(footprints allowed)
			)
			(placement
				(enabled no)
				(sheetname "")
			)
			(fill
				(thermal_gap 0.5)
				(thermal_bridge_width 0.5)
				(island_removal_mode 0)
			)
			(polygon
				(pts
					(xy 361.191556 -122.256042) (xy 361.191556 -122.764042) (xy 361.572556 -122.764042) (xy 361.572556 -122.256042)
				)
			)
		)
		(zone
			(layer "B.Cu")
			(hatch none 0.5)
			(connect_pads
				(clearance 0)
			)
			(min_thickness 0.25)
			(keepout
				(tracks allowed)
				(vias not_allowed)
				(pads allowed)
				(copperpour not_allowed)
				(footprints allowed)
			)
			(placement
				(enabled no)
				(sheetname "")
			)
			(fill
				(thermal_gap 0.5)
				(thermal_bridge_width 0.5)
				(island_removal_mode 0)
			)
			(polygon
				(pts
					(xy 361.572556 -122.256042) (xy 361.572556 -122.764042) (xy 361.191556 -122.764042) (xy 361.191556 -122.256042)
				)
			)
		)
	)
	(footprint ""
		(layer "B.Cu")
		(at 373.498618 -89.78011)
		(property "Reference" "C7C19"
			(at 0 0 0)
			(layer "B.SilkS")
			(hide yes)
			(effects
				(font
					(size 1.27 1.27)
				)
				(justify mirror)
			)
		)
		(property "Value" ""
			(at 0 0 0)
			(layer "B.Fab")
			(effects
				(font
					(size 1.27 1.27)
				)
				(justify mirror)
			)
		)
		(duplicate_pad_numbers_are_jumpers no)
		(fp_poly
			(pts
				(xy -0.3048 -0.1016) (xy -0.3048 0.9906) (xy 0.3048 0.9906) (xy 0.3048 -0.1016)
			)
			(stroke
				(width 0)
				(type default)
			)
			(fill no)
			(layer "B.CrtYd")
		)
		(fp_line
			(start -0.3048 -0.1016)
			(end 0.3048 -0.1016)
			(stroke
				(width 0.1)
				(type default)
			)
			(layer "B.Fab")
		)
		(fp_line
			(start -0.3048 0.9906)
			(end -0.3048 -0.1016)
			(stroke
				(width 0.1)
				(type default)
			)
			(layer "B.Fab")
		)
		(fp_line
			(start 0.3048 -0.1016)
			(end 0.3048 0.9906)
			(stroke
				(width 0.1)
				(type default)
			)
			(layer "B.Fab")
		)
		(fp_line
			(start 0.3048 0.9906)
			(end -0.3048 0.9906)
			(stroke
				(width 0.1)
				(type default)
			)
			(layer "B.Fab")
		)
		(pad "1" smd rect
			(at 0 0 180)
			(size 0.508 0.508)
			(layers "B.Cu" "B.Mask" "B.Paste")
			(net "RST_RTCRST_N")
		)
		(pad "2" smd rect
			(at 0 0.889 180)
			(size 0.508 0.508)
			(layers "B.Cu" "B.Mask" "B.Paste")
			(net "GND")
		)
		(zone
			(layer "B.Cu")
			(hatch none 0.5)
			(connect_pads
				(clearance 0)
			)
			(min_thickness 0.25)
			(keepout
				(tracks allowed)
				(vias not_allowed)
				(pads allowed)
				(copperpour not_allowed)
				(footprints allowed)
			)
			(placement
				(enabled no)
				(sheetname "")
			)
			(fill
				(thermal_gap 0.5)
				(thermal_bridge_width 0.5)
				(island_removal_mode 0)
			)
			(polygon
				(pts
					(xy 373.752618 -89.52611) (xy 373.244618 -89.52611) (xy 373.244618 -89.14511) (xy 373.752618 -89.14511)
				)
			)
		)
		(zone
			(layer "B.Cu")
			(hatch none 0.5)
			(connect_pads
				(clearance 0)
			)
			(min_thickness 0.25)
			(keepout
				(tracks not_allowed)
				(vias allowed)
				(pads allowed)
				(copperpour not_allowed)
				(footprints allowed)
			)
			(placement
				(enabled no)
				(sheetname "")
			)
			(fill
				(thermal_gap 0.5)
				(thermal_bridge_width 0.5)
				(island_removal_mode 0)
			)
			(polygon
				(pts
					(xy 373.752618 -89.14511) (xy 373.244618 -89.14511) (xy 373.244618 -89.52611) (xy 373.752618 -89.52611)
				)
			)
		)
	)
	(footprint ""
		(layer "B.Cu")
		(at 117.221 -78.74 -90)
		(property "Reference" "R7P8"
			(at 0 0 90)
			(layer "B.SilkS")
			(hide yes)
			(effects
				(font
					(size 1.27 1.27)
				)
				(justify mirror)
			)
		)
		(property "Value" ""
			(at 0 0 90)
			(layer "B.Fab")
			(effects
				(font
					(size 1.27 1.27)
				)
				(justify mirror)
			)
		)
		(duplicate_pad_numbers_are_jumpers no)
		(fp_poly
			(pts
				(xy 0.2794 -0.1016) (xy -0.2794 -0.1016) (xy -0.2794 0.9906) (xy 0.2794 0.9906)
			)
			(stroke
				(width 0)
				(type default)
			)
			(fill no)
			(layer "B.CrtYd")
		)
		(fp_line
			(start -0.2794 0.9906)
			(end -0.2794 -0.1016)
			(stroke
				(width 0.1)
				(type default)
			)
			(layer "B.Fab")
		)
		(fp_line
			(start 0.2794 0.9906)
			(end -0.2794 0.9906)
			(stroke
				(width 0.1)
				(type default)
			)
			(layer "B.Fab")
		)
		(fp_line
			(start -0.2794 -0.1016)
			(end 0.2794 -0.1016)
			(stroke
				(width 0.1)
				(type default)
			)
			(layer "B.Fab")
		)
		(fp_line
			(start 0.2794 -0.1016)
			(end 0.2794 0.9906)
			(stroke
				(width 0.1)
				(type default)
			)
			(layer "B.Fab")
		)
		(pad "1" smd rect
			(at 0 0 90)
			(size 0.508 0.508)
			(layers "B.Cu" "B.Mask" "B.Paste")
			(net "A_CPU1_PE3_RBIAS")
		)
		(pad "2" smd rect
			(at 0 0.889 90)
			(size 0.508 0.508)
			(layers "B.Cu" "B.Mask" "B.Paste")
			(net "GND")
		)
		(zone
			(layer "B.Cu")
			(hatch none 0.5)
			(connect_pads
				(clearance 0)
			)
			(min_thickness 0.25)
			(keepout
				(tracks not_allowed)
				(vias allowed)
				(pads allowed)
				(copperpour not_allowed)
				(footprints allowed)
			)
			(placement
				(enabled no)
				(sheetname "")
			)
			(fill
				(thermal_gap 0.5)
				(thermal_bridge_width 0.5)
				(island_removal_mode 0)
			)
			(polygon
				(pts
					(xy 116.586 -78.486) (xy 116.586 -78.994) (xy 116.967 -78.994) (xy 116.967 -78.486)
				)
			)
		)
		(zone
			(layer "B.Cu")
			(hatch none 0.5)
			(connect_pads
				(clearance 0)
			)
			(min_thickness 0.25)
			(keepout
				(tracks allowed)
				(vias not_allowed)
				(pads allowed)
				(copperpour not_allowed)
				(footprints allowed)
			)
			(placement
				(enabled no)
				(sheetname "")
			)
			(fill
				(thermal_gap 0.5)
				(thermal_bridge_width 0.5)
				(island_removal_mode 0)
			)
			(polygon
				(pts
					(xy 116.967 -78.486) (xy 116.967 -78.994) (xy 116.586 -78.994) (xy 116.586 -78.486)
				)
			)
		)
	)
	(footprint ""
		(layer "B.Cu")
		(at 372.5164 -91.567 90)
		(property "Reference" "R3N13"
			(at 0 0 90)
			(layer "B.SilkS")
			(hide yes)
			(effects
				(font
					(size 1.27 1.27)
				)
				(justify mirror)
			)
		)
		(property "Value" ""
			(at 0 0 90)
			(layer "B.Fab")
			(effects
				(font
					(size 1.27 1.27)
				)
				(justify mirror)
			)
		)
		(duplicate_pad_numbers_are_jumpers no)
		(fp_poly
			(pts
				(xy 0.2794 -0.1016) (xy -0.2794 -0.1016) (xy -0.2794 0.9906) (xy 0.2794 0.9906)
			)
			(stroke
				(width 0)
				(type default)
			)
			(fill no)
			(layer "B.CrtYd")
		)
		(fp_line
			(start 0.2794 -0.1016)
			(end 0.2794 0.9906)
			(stroke
				(width 0.1)
				(type default)
			)
			(layer "B.Fab")
		)
		(fp_line
			(start -0.2794 -0.1016)
			(end 0.2794 -0.1016)
			(stroke
				(width 0.1)
				(type default)
			)
			(layer "B.Fab")
		)
		(fp_line
			(start 0.2794 0.9906)
			(end -0.2794 0.9906)
			(stroke
				(width 0.1)
				(type default)
			)
			(layer "B.Fab")
		)
		(fp_line
			(start -0.2794 0.9906)
			(end -0.2794 -0.1016)
			(stroke
				(width 0.1)
				(type default)
			)
			(layer "B.Fab")
		)
		(pad "1" smd rect
			(at 0 0 270)
			(size 0.508 0.508)
			(layers "B.Cu" "B.Mask" "B.Paste")
			(net "P3V3_STBY")
		)
		(pad "2" smd rect
			(at 0 0.889 270)
			(size 0.508 0.508)
			(layers "B.Cu" "B.Mask" "B.Paste")
			(net "IRQ_LVC3_WAKE_N")
		)
		(zone
			(layer "B.Cu")
			(hatch none 0.5)
			(connect_pads
				(clearance 0)
			)
			(min_thickness 0.25)
			(keepout
				(tracks allowed)
				(vias not_allowed)
				(pads allowed)
				(copperpour not_allowed)
				(footprints allowed)
			)
			(placement
				(enabled no)
				(sheetname "")
			)
			(fill
				(thermal_gap 0.5)
				(thermal_bridge_width 0.5)
				(island_removal_mode 0)
			)
			(polygon
				(pts
					(xy 372.7704 -91.821) (xy 372.7704 -91.313) (xy 373.1514 -91.313) (xy 373.1514 -91.821)
				)
			)
		)
		(zone
			(layer "B.Cu")
			(hatch none 0.5)
			(connect_pads
				(clearance 0)
			)
			(min_thickness 0.25)
			(keepout
				(tracks not_allowed)
				(vias allowed)
				(pads allowed)
				(copperpour not_allowed)
				(footprints allowed)
			)
			(placement
				(enabled no)
				(sheetname "")
			)
			(fill
				(thermal_gap 0.5)
				(thermal_bridge_width 0.5)
				(island_removal_mode 0)
			)
			(polygon
				(pts
					(xy 373.1514 -91.821) (xy 373.1514 -91.313) (xy 372.7704 -91.313) (xy 372.7704 -91.821)
				)
			)
		)
	)
	(footprint ""
		(layer "B.Cu")
		(at 388.1374 -113.4999)
		(property "Reference" "C3M42"
			(at 0 0 0)
			(layer "B.SilkS")
			(hide yes)
			(effects
				(font
					(size 1.27 1.27)
				)
				(justify mirror)
			)
		)
		(property "Value" ""
			(at 0 0 0)
			(layer "B.Fab")
			(effects
				(font
					(size 1.27 1.27)
				)
				(justify mirror)
			)
		)
		(duplicate_pad_numbers_are_jumpers no)
		(fp_poly
			(pts
				(xy -0.3048 -0.1016) (xy -0.3048 0.9906) (xy 0.3048 0.9906) (xy 0.3048 -0.1016)
			)
			(stroke
				(width 0)
				(type default)
			)
			(fill no)
			(layer "B.CrtYd")
		)
		(fp_line
			(start -0.3048 -0.1016)
			(end 0.3048 -0.1016)
			(stroke
				(width 0.1)
				(type default)
			)
			(layer "B.Fab")
		)
		(fp_line
			(start -0.3048 0.9906)
			(end -0.3048 -0.1016)
			(stroke
				(width 0.1)
				(type default)
			)
			(layer "B.Fab")
		)
		(fp_line
			(start 0.3048 -0.1016)
			(end 0.3048 0.9906)
			(stroke
				(width 0.1)
				(type default)
			)
			(layer "B.Fab")
		)
		(fp_line
			(start 0.3048 0.9906)
			(end -0.3048 0.9906)
			(stroke
				(width 0.1)
				(type default)
			)
			(layer "B.Fab")
		)
		(pad "1" smd rect
			(at 0 0 180)
			(size 0.508 0.508)
			(layers "B.Cu" "B.Mask" "B.Paste")
			(net "P1V05_PCH_STBY")
		)
		(pad "2" smd rect
			(at 0 0.889 180)
			(size 0.508 0.508)
			(layers "B.Cu" "B.Mask" "B.Paste")
			(net "GND")
		)
		(zone
			(layer "B.Cu")
			(hatch none 0.5)
			(connect_pads
				(clearance 0)
			)
			(min_thickness 0.25)
			(keepout
				(tracks allowed)
				(vias not_allowed)
				(pads allowed)
				(copperpour not_allowed)
				(footprints allowed)
			)
			(placement
				(enabled no)
				(sheetname "")
			)
			(fill
				(thermal_gap 0.5)
				(thermal_bridge_width 0.5)
				(island_removal_mode 0)
			)
			(polygon
				(pts
					(xy 388.3914 -113.2459) (xy 387.8834 -113.2459) (xy 387.8834 -112.8649) (xy 388.3914 -112.8649)
				)
			)
		)
		(zone
			(layer "B.Cu")
			(hatch none 0.5)
			(connect_pads
				(clearance 0)
			)
			(min_thickness 0.25)
			(keepout
				(tracks not_allowed)
				(vias allowed)
				(pads allowed)
				(copperpour not_allowed)
				(footprints allowed)
			)
			(placement
				(enabled no)
				(sheetname "")
			)
			(fill
				(thermal_gap 0.5)
				(thermal_bridge_width 0.5)
				(island_removal_mode 0)
			)
			(polygon
				(pts
					(xy 388.3914 -112.8649) (xy 387.8834 -112.8649) (xy 387.8834 -113.2459) (xy 388.3914 -113.2459)
				)
			)
		)
	)
	(footprint ""
		(layer "B.Cu")
		(at 176.149 -77.597 -90)
		(property "Reference" "R6P15"
			(at 0 0 90)
			(layer "B.SilkS")
			(hide yes)
			(effects
				(font
					(size 1.27 1.27)
				)
				(justify mirror)
			)
		)
		(property "Value" ""
			(at 0 0 90)
			(layer "B.Fab")
			(effects
				(font
					(size 1.27 1.27)
				)
				(justify mirror)
			)
		)
		(duplicate_pad_numbers_are_jumpers no)
		(fp_poly
			(pts
				(xy 0.2794 -0.1016) (xy -0.2794 -0.1016) (xy -0.2794 0.9906) (xy 0.2794 0.9906)
			)
			(stroke
				(width 0)
				(type default)
			)
			(fill no)
			(layer "B.CrtYd")
		)
		(fp_line
			(start -0.2794 0.9906)
			(end -0.2794 -0.1016)
			(stroke
				(width 0.1)
				(type default)
			)
			(layer "B.Fab")
		)
		(fp_line
			(start 0.2794 0.9906)
			(end -0.2794 0.9906)
			(stroke
				(width 0.1)
				(type default)
			)
			(layer "B.Fab")
		)
		(fp_line
			(start -0.2794 -0.1016)
			(end 0.2794 -0.1016)
			(stroke
				(width 0.1)
				(type default)
			)
			(layer "B.Fab")
		)
		(fp_line
			(start 0.2794 -0.1016)
			(end 0.2794 0.9906)
			(stroke
				(width 0.1)
				(type default)
			)
			(layer "B.Fab")
		)
		(pad "1" smd rect
			(at 0 0 90)
			(size 0.508 0.508)
			(layers "B.Cu" "B.Mask" "B.Paste")
			(net "CLK_100M_CPU0_BCLK0_DN")
		)
		(pad "2" smd rect
			(at 0 0.889 90)
			(size 0.508 0.508)
			(layers "B.Cu" "B.Mask" "B.Paste")
			(net "GND")
		)
		(zone
			(layer "B.Cu")
			(hatch none 0.5)
			(connect_pads
				(clearance 0)
			)
			(min_thickness 0.25)
			(keepout
				(tracks not_allowed)
				(vias allowed)
				(pads allowed)
				(copperpour not_allowed)
				(footprints allowed)
			)
			(placement
				(enabled no)
				(sheetname "")
			)
			(fill
				(thermal_gap 0.5)
				(thermal_bridge_width 0.5)
				(island_removal_mode 0)
			)
			(polygon
				(pts
					(xy 175.514 -77.343) (xy 175.514 -77.851) (xy 175.895 -77.851) (xy 175.895 -77.343)
				)
			)
		)
		(zone
			(layer "B.Cu")
			(hatch none 0.5)
			(connect_pads
				(clearance 0)
			)
			(min_thickness 0.25)
			(keepout
				(tracks allowed)
				(vias not_allowed)
				(pads allowed)
				(copperpour not_allowed)
				(footprints allowed)
			)
			(placement
				(enabled no)
				(sheetname "")
			)
			(fill
				(thermal_gap 0.5)
				(thermal_bridge_width 0.5)
				(island_removal_mode 0)
			)
			(polygon
				(pts
					(xy 175.895 -77.343) (xy 175.895 -77.851) (xy 175.514 -77.851) (xy 175.514 -77.343)
				)
			)
		)
	)
	(footprint ""
		(layer "B.Cu")
		(at 401.472146 -41.360852 90)
		(property "Reference" "R8F23"
			(at 0 0 90)
			(layer "B.SilkS")
			(hide yes)
			(effects
				(font
					(size 1.27 1.27)
				)
				(justify mirror)
			)
		)
		(property "Value" ""
			(at 0 0 90)
			(layer "B.Fab")
			(effects
				(font
					(size 1.27 1.27)
				)
				(justify mirror)
			)
		)
		(duplicate_pad_numbers_are_jumpers no)
		(fp_poly
			(pts
				(xy 0.2794 -0.1016) (xy -0.2794 -0.1016) (xy -0.2794 0.9906) (xy 0.2794 0.9906)
			)
			(stroke
				(width 0)
				(type default)
			)
			(fill no)
			(layer "B.CrtYd")
		)
		(fp_line
			(start 0.2794 -0.1016)
			(end 0.2794 0.9906)
			(stroke
				(width 0.1)
				(type default)
			)
			(layer "B.Fab")
		)
		(fp_line
			(start -0.2794 -0.1016)
			(end 0.2794 -0.1016)
			(stroke
				(width 0.1)
				(type default)
			)
			(layer "B.Fab")
		)
		(fp_line
			(start 0.2794 0.9906)
			(end -0.2794 0.9906)
			(stroke
				(width 0.1)
				(type default)
			)
			(layer "B.Fab")
		)
		(fp_line
			(start -0.2794 0.9906)
			(end -0.2794 -0.1016)
			(stroke
				(width 0.1)
				(type default)
			)
			(layer "B.Fab")
		)
		(pad "1" smd rect
			(at 0 0 270)
			(size 0.508 0.508)
			(layers "B.Cu" "B.Mask" "B.Paste")
			(net "P3V3_STBY")
		)
		(pad "2" smd rect
			(at 0 0.889 270)
			(size 0.508 0.508)
			(layers "B.Cu" "B.Mask" "B.Paste")
			(net "IRQ_MEZZ_LAN_ALERT_N")
		)
		(zone
			(layer "B.Cu")
			(hatch none 0.5)
			(connect_pads
				(clearance 0)
			)
			(min_thickness 0.25)
			(keepout
				(tracks allowed)
				(vias not_allowed)
				(pads allowed)
				(copperpour not_allowed)
				(footprints allowed)
			)
			(placement
				(enabled no)
				(sheetname "")
			)
			(fill
				(thermal_gap 0.5)
				(thermal_bridge_width 0.5)
				(island_removal_mode 0)
			)
			(polygon
				(pts
					(xy 401.726146 -41.614852) (xy 401.726146 -41.106852) (xy 402.107146 -41.106852) (xy 402.107146 -41.614852)
				)
			)
		)
		(zone
			(layer "B.Cu")
			(hatch none 0.5)
			(connect_pads
				(clearance 0)
			)
			(min_thickness 0.25)
			(keepout
				(tracks not_allowed)
				(vias allowed)
				(pads allowed)
				(copperpour not_allowed)
				(footprints allowed)
			)
			(placement
				(enabled no)
				(sheetname "")
			)
			(fill
				(thermal_gap 0.5)
				(thermal_bridge_width 0.5)
				(island_removal_mode 0)
			)
			(polygon
				(pts
					(xy 402.107146 -41.614852) (xy 402.107146 -41.106852) (xy 401.726146 -41.106852) (xy 401.726146 -41.614852)
				)
			)
		)
	)
	(footprint ""
		(layer "B.Cu")
		(at 483.6795 -139.5095 180)
		(property "Reference" "Q1L3"
			(at -2.48285 0.50546 90)
			(unlocked yes)
			(layer "B.SilkS")
			(effects
				(font
					(size 0.7874 0.5842)
					(thickness 0.1524)
				)
				(justify left mirror)
			)
		)
		(property "Value" ""
			(at 0 0 0)
			(layer "B.Fab")
			(effects
				(font
					(size 1.27 1.27)
				)
				(justify mirror)
			)
		)
		(duplicate_pad_numbers_are_jumpers no)
		(fp_line
			(start -0.381 0.635)
			(end -0.381 1.27)
			(stroke
				(width 0.1524)
				(type default)
			)
			(layer "B.SilkS")
		)
		(fp_line
			(start -0.9525 2.4765)
			(end -1.778 2.4765)
			(stroke
				(width 0.1524)
				(type default)
			)
			(layer "B.SilkS")
		)
		(fp_line
			(start -0.9525 -0.5715)
			(end -1.778 -0.5715)
			(stroke
				(width 0.1524)
				(type default)
			)
			(layer "B.SilkS")
		)
		(fp_line
			(start -1.778 2.4765)
			(end -1.778 1.5875)
			(stroke
				(width 0.1524)
				(type default)
			)
			(layer "B.SilkS")
		)
		(fp_line
			(start -1.778 -0.5715)
			(end -1.778 0.3175)
			(stroke
				(width 0.1524)
				(type default)
			)
			(layer "B.SilkS")
		)
		(fp_circle
			(center 0.9525 -0.9271)
			(end 0.8255 -0.9271)
			(stroke
				(width 0.254)
				(type default)
			)
			(fill no)
			(layer "B.SilkS")
		)
		(fp_poly
			(pts
				(xy -1.778 2.4765) (xy -0.381 2.4765) (xy -0.381 -0.5715) (xy -1.778 -0.5715)
			)
			(stroke
				(width 0)
				(type default)
			)
			(fill no)
			(layer "B.CrtYd")
		)
		(fp_line
			(start -0.381 2.4765)
			(end -1.778 2.4765)
			(stroke
				(width 0.1)
				(type default)
			)
			(layer "B.Fab")
		)
		(fp_line
			(start -0.381 -0.5715)
			(end -0.381 2.4765)
			(stroke
				(width 0.1)
				(type default)
			)
			(layer "B.Fab")
		)
		(fp_line
			(start -1.778 2.4765)
			(end -1.778 -0.5715)
			(stroke
				(width 0.1)
				(type default)
			)
			(layer "B.Fab")
		)
		(fp_line
			(start -1.778 -0.5715)
			(end -0.381 -0.5715)
			(stroke
				(width 0.1)
				(type default)
			)
			(layer "B.Fab")
		)
		(fp_circle
			(center 0.9525 -0.9271)
			(end 0.8255 -0.9271)
			(stroke
				(width 0.254)
				(type default)
			)
			(fill no)
			(layer "B.Fab")
		)
		(pad "1" smd rect
			(at 0 0)
			(size 1.143 0.508)
			(layers "B.Cu" "B.Mask" "B.Paste")
			(net "FM_DB_UART_SEL4_N")
		)
		(pad "2" smd rect
			(at 0 1.905)
			(size 1.143 0.508)
			(layers "B.Cu" "B.Mask" "B.Paste")
			(net "GND")
		)
		(pad "3" smd rect
			(at -2.159 0.9525)
			(size 1.143 0.508)
			(layers "B.Cu" "B.Mask" "B.Paste")
			(net "FM_DB_PRESENT")
		)
	)
	(footprint ""
		(layer "B.Cu")
		(at 279.896824 -70.673214 90)
		(property "Reference" "R4P14"
			(at 0 0 90)
			(layer "B.SilkS")
			(hide yes)
			(effects
				(font
					(size 1.27 1.27)
				)
				(justify mirror)
			)
		)
		(property "Value" ""
			(at 0 0 90)
			(layer "B.Fab")
			(effects
				(font
					(size 1.27 1.27)
				)
				(justify mirror)
			)
		)
		(duplicate_pad_numbers_are_jumpers no)
		(fp_poly
			(pts
				(xy 0.2794 -0.1016) (xy -0.2794 -0.1016) (xy -0.2794 0.9906) (xy 0.2794 0.9906)
			)
			(stroke
				(width 0)
				(type default)
			)
			(fill no)
			(layer "B.CrtYd")
		)
		(fp_line
			(start 0.2794 -0.1016)
			(end 0.2794 0.9906)
			(stroke
				(width 0.1)
				(type default)
			)
			(layer "B.Fab")
		)
		(fp_line
			(start -0.2794 -0.1016)
			(end 0.2794 -0.1016)
			(stroke
				(width 0.1)
				(type default)
			)
			(layer "B.Fab")
		)
		(fp_line
			(start 0.2794 0.9906)
			(end -0.2794 0.9906)
			(stroke
				(width 0.1)
				(type default)
			)
			(layer "B.Fab")
		)
		(fp_line
			(start -0.2794 0.9906)
			(end -0.2794 -0.1016)
			(stroke
				(width 0.1)
				(type default)
			)
			(layer "B.Fab")
		)
		(pad "1" smd rect
			(at 0 0 270)
			(size 0.508 0.508)
			(layers "B.Cu" "B.Mask" "B.Paste")
			(net "PVCCIO_CPU0")
		)
		(pad "2" smd rect
			(at 0 0.889 270)
			(size 0.508 0.508)
			(layers "B.Cu" "B.Mask" "B.Paste")
			(net "PU_CPU0_LEGACY_SKT")
		)
		(zone
			(layer "B.Cu")
			(hatch none 0.5)
			(connect_pads
				(clearance 0)
			)
			(min_thickness 0.25)
			(keepout
				(tracks allowed)
				(vias not_allowed)
				(pads allowed)
				(copperpour not_allowed)
				(footprints allowed)
			)
			(placement
				(enabled no)
				(sheetname "")
			)
			(fill
				(thermal_gap 0.5)
				(thermal_bridge_width 0.5)
				(island_removal_mode 0)
			)
			(polygon
				(pts
					(xy 280.150824 -70.927214) (xy 280.150824 -70.419214) (xy 280.531824 -70.419214) (xy 280.531824 -70.927214)
				)
			)
		)
		(zone
			(layer "B.Cu")
			(hatch none 0.5)
			(connect_pads
				(clearance 0)
			)
			(min_thickness 0.25)
			(keepout
				(tracks not_allowed)
				(vias allowed)
				(pads allowed)
				(copperpour not_allowed)
				(footprints allowed)
			)
			(placement
				(enabled no)
				(sheetname "")
			)
			(fill
				(thermal_gap 0.5)
				(thermal_bridge_width 0.5)
				(island_removal_mode 0)
			)
			(polygon
				(pts
					(xy 280.531824 -70.927214) (xy 280.531824 -70.419214) (xy 280.150824 -70.419214) (xy 280.150824 -70.927214)
				)
			)
		)
	)
	(footprint ""
		(layer "B.Cu")
		(at 411.9626 -121.9962 180)
		(property "Reference" "C8B16"
			(at 0 0 0)
			(layer "B.SilkS")
			(hide yes)
			(effects
				(font
					(size 1.27 1.27)
				)
				(justify mirror)
			)
		)
		(property "Value" ""
			(at 0 0 0)
			(layer "B.Fab")
			(effects
				(font
					(size 1.27 1.27)
				)
				(justify mirror)
			)
		)
		(duplicate_pad_numbers_are_jumpers no)
		(fp_rect
			(start -0.7239 1.9939)
			(end 0.7239 -0.2159)
			(stroke
				(width 0)
				(type default)
			)
			(fill no)
			(layer "B.CrtYd")
		)
		(fp_line
			(start 0.7239 1.9939)
			(end -0.7239 1.9939)
			(stroke
				(width 0.1)
				(type default)
			)
			(layer "B.Fab")
		)
		(fp_line
			(start 0.7239 -0.2159)
			(end 0.7239 1.9939)
			(stroke
				(width 0.1)
				(type default)
			)
			(layer "B.Fab")
		)
		(fp_line
			(start -0.7239 1.9939)
			(end -0.7239 -0.2159)
			(stroke
				(width 0.1)
				(type default)
			)
			(layer "B.Fab")
		)
		(fp_line
			(start -0.7239 -0.2159)
			(end 0.7239 -0.2159)
			(stroke
				(width 0.1)
				(type default)
			)
			(layer "B.Fab")
		)
		(pad "1" smd rect
			(at 0 0)
			(size 1.27 1.016)
			(layers "B.Cu" "B.Mask" "B.Paste")
			(net "P1V05_PCH_STBY")
		)
		(pad "2" smd rect
			(at 0 1.778)
			(size 1.27 1.016)
			(layers "B.Cu" "B.Mask" "B.Paste")
			(net "GND")
		)
		(zone
			(layer "B.Cu")
			(hatch none 0.5)
			(connect_pads
				(clearance 0)
			)
			(min_thickness 0.25)
			(keepout
				(tracks not_allowed)
				(vias allowed)
				(pads allowed)
				(copperpour not_allowed)
				(footprints allowed)
			)
			(placement
				(enabled no)
				(sheetname "")
			)
			(fill
				(thermal_gap 0.5)
				(thermal_bridge_width 0.5)
				(island_removal_mode 0)
			)
			(polygon
				(pts
					(xy 412.5976 -123.2662) (xy 411.3276 -123.2662) (xy 411.3276 -122.5042) (xy 412.5976 -122.5042)
				)
			)
		)
	)
	(footprint ""
		(layer "B.Cu")
		(at 40.994838 -104.252776 90)
		(property "Reference" "R1C4"
			(at 0 0 90)
			(layer "B.SilkS")
			(hide yes)
			(effects
				(font
					(size 1.27 1.27)
				)
				(justify mirror)
			)
		)
		(property "Value" ""
			(at 0 0 90)
			(layer "B.Fab")
			(effects
				(font
					(size 1.27 1.27)
				)
				(justify mirror)
			)
		)
		(duplicate_pad_numbers_are_jumpers no)
		(fp_poly
			(pts
				(xy 0.2794 -0.1016) (xy -0.2794 -0.1016) (xy -0.2794 0.9906) (xy 0.2794 0.9906)
			)
			(stroke
				(width 0)
				(type default)
			)
			(fill no)
			(layer "B.CrtYd")
		)
		(fp_line
			(start 0.2794 -0.1016)
			(end 0.2794 0.9906)
			(stroke
				(width 0.1)
				(type default)
			)
			(layer "B.Fab")
		)
		(fp_line
			(start -0.2794 -0.1016)
			(end 0.2794 -0.1016)
			(stroke
				(width 0.1)
				(type default)
			)
			(layer "B.Fab")
		)
		(fp_line
			(start 0.2794 0.9906)
			(end -0.2794 0.9906)
			(stroke
				(width 0.1)
				(type default)
			)
			(layer "B.Fab")
		)
		(fp_line
			(start -0.2794 0.9906)
			(end -0.2794 -0.1016)
			(stroke
				(width 0.1)
				(type default)
			)
			(layer "B.Fab")
		)
		(pad "1" smd rect
			(at 0 0 270)
			(size 0.508 0.508)
			(layers "B.Cu" "B.Mask" "B.Paste")
			(net "VSENSE_PVSA_CPU1_N")
		)
		(pad "2" smd rect
			(at 0 0.889 270)
			(size 0.508 0.508)
			(layers "B.Cu" "B.Mask" "B.Paste")
			(net "GND")
		)
		(zone
			(layer "B.Cu")
			(hatch none 0.5)
			(connect_pads
				(clearance 0)
			)
			(min_thickness 0.25)
			(keepout
				(tracks allowed)
				(vias not_allowed)
				(pads allowed)
				(copperpour not_allowed)
				(footprints allowed)
			)
			(placement
				(enabled no)
				(sheetname "")
			)
			(fill
				(thermal_gap 0.5)
				(thermal_bridge_width 0.5)
				(island_removal_mode 0)
			)
			(polygon
				(pts
					(xy 41.248838 -104.506776) (xy 41.248838 -103.998776) (xy 41.629838 -103.998776) (xy 41.629838 -104.506776)
				)
			)
		)
		(zone
			(layer "B.Cu")
			(hatch none 0.5)
			(connect_pads
				(clearance 0)
			)
			(min_thickness 0.25)
			(keepout
				(tracks not_allowed)
				(vias allowed)
				(pads allowed)
				(copperpour not_allowed)
				(footprints allowed)
			)
			(placement
				(enabled no)
				(sheetname "")
			)
			(fill
				(thermal_gap 0.5)
				(thermal_bridge_width 0.5)
				(island_removal_mode 0)
			)
			(polygon
				(pts
					(xy 41.629838 -104.506776) (xy 41.629838 -103.998776) (xy 41.248838 -103.998776) (xy 41.248838 -104.506776)
				)
			)
		)
	)
	(footprint ""
		(layer "B.Cu")
		(at 378.587 -81.8896 -90)
		(property "Reference" "R7W2"
			(at 0.8382 -0.67818 270)
			(unlocked yes)
			(layer "B.SilkS")
			(effects
				(font
					(size 0.4064 0.254)
					(thickness 0.1524)
				)
				(justify left mirror)
			)
		)
		(property "Value" ""
			(at 0 0 90)
			(layer "B.Fab")
			(effects
				(font
					(size 1.27 1.27)
				)
				(justify mirror)
			)
		)
		(duplicate_pad_numbers_are_jumpers no)
		(fp_poly
			(pts
				(xy 0.2794 -0.1016) (xy -0.2794 -0.1016) (xy -0.2794 0.9906) (xy 0.2794 0.9906)
			)
			(stroke
				(width 0)
				(type default)
			)
			(fill no)
			(layer "B.CrtYd")
		)
		(fp_line
			(start -0.2794 0.9906)
			(end -0.2794 -0.1016)
			(stroke
				(width 0.1)
				(type default)
			)
			(layer "B.Fab")
		)
		(fp_line
			(start 0.2794 0.9906)
			(end -0.2794 0.9906)
			(stroke
				(width 0.1)
				(type default)
			)
			(layer "B.Fab")
		)
		(fp_line
			(start -0.2794 -0.1016)
			(end 0.2794 -0.1016)
			(stroke
				(width 0.1)
				(type default)
			)
			(layer "B.Fab")
		)
		(fp_line
			(start 0.2794 -0.1016)
			(end 0.2794 0.9906)
			(stroke
				(width 0.1)
				(type default)
			)
			(layer "B.Fab")
		)
		(pad "1" smd rect
			(at 0 0 90)
			(size 0.508 0.508)
			(layers "B.Cu" "B.Mask" "B.Paste")
			(net "PECI_CPU_G")
		)
		(pad "2" smd rect
			(at 0 0.889 90)
			(size 0.508 0.508)
			(layers "B.Cu" "B.Mask" "B.Paste")
			(net "GND")
		)
		(zone
			(layer "B.Cu")
			(hatch none 0.5)
			(connect_pads
				(clearance 0)
			)
			(min_thickness 0.25)
			(keepout
				(tracks not_allowed)
				(vias allowed)
				(pads allowed)
				(copperpour not_allowed)
				(footprints allowed)
			)
			(placement
				(enabled no)
				(sheetname "")
			)
			(fill
				(thermal_gap 0.5)
				(thermal_bridge_width 0.5)
				(island_removal_mode 0)
			)
			(polygon
				(pts
					(xy 377.952 -81.6356) (xy 377.952 -82.1436) (xy 378.333 -82.1436) (xy 378.333 -81.6356)
				)
			)
		)
		(zone
			(layer "B.Cu")
			(hatch none 0.5)
			(connect_pads
				(clearance 0)
			)
			(min_thickness 0.25)
			(keepout
				(tracks allowed)
				(vias not_allowed)
				(pads allowed)
				(copperpour not_allowed)
				(footprints allowed)
			)
			(placement
				(enabled no)
				(sheetname "")
			)
			(fill
				(thermal_gap 0.5)
				(thermal_bridge_width 0.5)
				(island_removal_mode 0)
			)
			(polygon
				(pts
					(xy 378.333 -81.6356) (xy 378.333 -82.1436) (xy 377.952 -82.1436) (xy 377.952 -81.6356)
				)
			)
		)
	)
	(footprint ""
		(layer "B.Cu")
		(at 464.4644 -134.366 180)
		(property "Reference" "R9B10"
			(at 0 0 0)
			(layer "B.SilkS")
			(hide yes)
			(effects
				(font
					(size 1.27 1.27)
				)
				(justify mirror)
			)
		)
		(property "Value" ""
			(at 0 0 0)
			(layer "B.Fab")
			(effects
				(font
					(size 1.27 1.27)
				)
				(justify mirror)
			)
		)
		(duplicate_pad_numbers_are_jumpers no)
		(fp_poly
			(pts
				(xy 0.2794 -0.1016) (xy -0.2794 -0.1016) (xy -0.2794 0.9906) (xy 0.2794 0.9906)
			)
			(stroke
				(width 0)
				(type default)
			)
			(fill no)
			(layer "B.CrtYd")
		)
		(fp_line
			(start 0.2794 0.9906)
			(end -0.2794 0.9906)
			(stroke
				(width 0.1)
				(type default)
			)
			(layer "B.Fab")
		)
		(fp_line
			(start 0.2794 -0.1016)
			(end 0.2794 0.9906)
			(stroke
				(width 0.1)
				(type default)
			)
			(layer "B.Fab")
		)
		(fp_line
			(start -0.2794 0.9906)
			(end -0.2794 -0.1016)
			(stroke
				(width 0.1)
				(type default)
			)
			(layer "B.Fab")
		)
		(fp_line
			(start -0.2794 -0.1016)
			(end 0.2794 -0.1016)
			(stroke
				(width 0.1)
				(type default)
			)
			(layer "B.Fab")
		)
		(pad "1" smd rect
			(at 0 0)
			(size 0.508 0.508)
			(layers "B.Cu" "B.Mask" "B.Paste")
			(net "JTAG_MCP_TCK")
		)
		(pad "2" smd rect
			(at 0 0.889)
			(size 0.508 0.508)
			(layers "B.Cu" "B.Mask" "B.Paste")
			(net "JTAG_MCP_TCK_R1")
		)
		(zone
			(layer "B.Cu")
			(hatch none 0.5)
			(connect_pads
				(clearance 0)
			)
			(min_thickness 0.25)
			(keepout
				(tracks not_allowed)
				(vias allowed)
				(pads allowed)
				(copperpour not_allowed)
				(footprints allowed)
			)
			(placement
				(enabled no)
				(sheetname "")
			)
			(fill
				(thermal_gap 0.5)
				(thermal_bridge_width 0.5)
				(island_removal_mode 0)
			)
			(polygon
				(pts
					(xy 464.2104 -135.001) (xy 464.7184 -135.001) (xy 464.7184 -134.62) (xy 464.2104 -134.62)
				)
			)
		)
		(zone
			(layer "B.Cu")
			(hatch none 0.5)
			(connect_pads
				(clearance 0)
			)
			(min_thickness 0.25)
			(keepout
				(tracks allowed)
				(vias not_allowed)
				(pads allowed)
				(copperpour not_allowed)
				(footprints allowed)
			)
			(placement
				(enabled no)
				(sheetname "")
			)
			(fill
				(thermal_gap 0.5)
				(thermal_bridge_width 0.5)
				(island_removal_mode 0)
			)
			(polygon
				(pts
					(xy 464.2104 -134.62) (xy 464.7184 -134.62) (xy 464.7184 -135.001) (xy 464.2104 -135.001)
				)
			)
		)
	)
	(footprint ""
		(layer "B.Cu")
		(at 180.1114 -76.2254 90)
		(property "Reference" "R6P18"
			(at 0 0 90)
			(layer "B.SilkS")
			(hide yes)
			(effects
				(font
					(size 1.27 1.27)
				)
				(justify mirror)
			)
		)
		(property "Value" ""
			(at 0 0 90)
			(layer "B.Fab")
			(effects
				(font
					(size 1.27 1.27)
				)
				(justify mirror)
			)
		)
		(duplicate_pad_numbers_are_jumpers no)
		(fp_poly
			(pts
				(xy 0.2794 -0.1016) (xy -0.2794 -0.1016) (xy -0.2794 0.9906) (xy 0.2794 0.9906)
			)
			(stroke
				(width 0)
				(type default)
			)
			(fill no)
			(layer "B.CrtYd")
		)
		(fp_line
			(start 0.2794 -0.1016)
			(end 0.2794 0.9906)
			(stroke
				(width 0.1)
				(type default)
			)
			(layer "B.Fab")
		)
		(fp_line
			(start -0.2794 -0.1016)
			(end 0.2794 -0.1016)
			(stroke
				(width 0.1)
				(type default)
			)
			(layer "B.Fab")
		)
		(fp_line
			(start 0.2794 0.9906)
			(end -0.2794 0.9906)
			(stroke
				(width 0.1)
				(type default)
			)
			(layer "B.Fab")
		)
		(fp_line
			(start -0.2794 0.9906)
			(end -0.2794 -0.1016)
			(stroke
				(width 0.1)
				(type default)
			)
			(layer "B.Fab")
		)
		(pad "1" smd rect
			(at 0 0 270)
			(size 0.508 0.508)
			(layers "B.Cu" "B.Mask" "B.Paste")
			(net "FM_PVCCIN_PVCCSA_CPU0_EN_LVC1")
		)
		(pad "2" smd rect
			(at 0 0.889 270)
			(size 0.508 0.508)
			(layers "B.Cu" "B.Mask" "B.Paste")
			(net "VR_PVCCIN_CPU0_VREN")
		)
		(zone
			(layer "B.Cu")
			(hatch none 0.5)
			(connect_pads
				(clearance 0)
			)
			(min_thickness 0.25)
			(keepout
				(tracks allowed)
				(vias not_allowed)
				(pads allowed)
				(copperpour not_allowed)
				(footprints allowed)
			)
			(placement
				(enabled no)
				(sheetname "")
			)
			(fill
				(thermal_gap 0.5)
				(thermal_bridge_width 0.5)
				(island_removal_mode 0)
			)
			(polygon
				(pts
					(xy 180.3654 -76.4794) (xy 180.3654 -75.9714) (xy 180.7464 -75.9714) (xy 180.7464 -76.4794)
				)
			)
		)
		(zone
			(layer "B.Cu")
			(hatch none 0.5)
			(connect_pads
				(clearance 0)
			)
			(min_thickness 0.25)
			(keepout
				(tracks not_allowed)
				(vias allowed)
				(pads allowed)
				(copperpour not_allowed)
				(footprints allowed)
			)
			(placement
				(enabled no)
				(sheetname "")
			)
			(fill
				(thermal_gap 0.5)
				(thermal_bridge_width 0.5)
				(island_removal_mode 0)
			)
			(polygon
				(pts
					(xy 180.7464 -76.4794) (xy 180.7464 -75.9714) (xy 180.3654 -75.9714) (xy 180.3654 -76.4794)
				)
			)
		)
	)
	(footprint ""
		(layer "B.Cu")
		(at 365.506 -78.3336 -90)
		(property "Reference" "R7D38"
			(at 0 0 90)
			(layer "B.SilkS")
			(hide yes)
			(effects
				(font
					(size 1.27 1.27)
				)
				(justify mirror)
			)
		)
		(property "Value" ""
			(at 0 0 90)
			(layer "B.Fab")
			(effects
				(font
					(size 1.27 1.27)
				)
				(justify mirror)
			)
		)
		(duplicate_pad_numbers_are_jumpers no)
		(fp_poly
			(pts
				(xy 0.2794 -0.1016) (xy -0.2794 -0.1016) (xy -0.2794 0.9906) (xy 0.2794 0.9906)
			)
			(stroke
				(width 0)
				(type default)
			)
			(fill no)
			(layer "B.CrtYd")
		)
		(fp_line
			(start -0.2794 0.9906)
			(end -0.2794 -0.1016)
			(stroke
				(width 0.1)
				(type default)
			)
			(layer "B.Fab")
		)
		(fp_line
			(start 0.2794 0.9906)
			(end -0.2794 0.9906)
			(stroke
				(width 0.1)
				(type default)
			)
			(layer "B.Fab")
		)
		(fp_line
			(start -0.2794 -0.1016)
			(end 0.2794 -0.1016)
			(stroke
				(width 0.1)
				(type default)
			)
			(layer "B.Fab")
		)
		(fp_line
			(start 0.2794 -0.1016)
			(end 0.2794 0.9906)
			(stroke
				(width 0.1)
				(type default)
			)
			(layer "B.Fab")
		)
		(pad "1" smd rect
			(at 0 0 90)
			(size 0.508 0.508)
			(layers "B.Cu" "B.Mask" "B.Paste")
			(net "FM_CPU1_VRM_OSC_EN")
		)
		(pad "2" smd rect
			(at 0 0.889 90)
			(size 0.508 0.508)
			(layers "B.Cu" "B.Mask" "B.Paste")
			(net "FM_CPU1_STL_BRD_OSC_EN")
		)
		(zone
			(layer "B.Cu")
			(hatch none 0.5)
			(connect_pads
				(clearance 0)
			)
			(min_thickness 0.25)
			(keepout
				(tracks not_allowed)
				(vias allowed)
				(pads allowed)
				(copperpour not_allowed)
				(footprints allowed)
			)
			(placement
				(enabled no)
				(sheetname "")
			)
			(fill
				(thermal_gap 0.5)
				(thermal_bridge_width 0.5)
				(island_removal_mode 0)
			)
			(polygon
				(pts
					(xy 364.871 -78.0796) (xy 364.871 -78.5876) (xy 365.252 -78.5876) (xy 365.252 -78.0796)
				)
			)
		)
		(zone
			(layer "B.Cu")
			(hatch none 0.5)
			(connect_pads
				(clearance 0)
			)
			(min_thickness 0.25)
			(keepout
				(tracks allowed)
				(vias not_allowed)
				(pads allowed)
				(copperpour not_allowed)
				(footprints allowed)
			)
			(placement
				(enabled no)
				(sheetname "")
			)
			(fill
				(thermal_gap 0.5)
				(thermal_bridge_width 0.5)
				(island_removal_mode 0)
			)
			(polygon
				(pts
					(xy 365.252 -78.0796) (xy 365.252 -78.5876) (xy 364.871 -78.5876) (xy 364.871 -78.0796)
				)
			)
		)
	)
	(footprint ""
		(layer "B.Cu")
		(at 422.91 -7.5565)
		(property "Reference" "C3P45"
			(at 0 0 0)
			(layer "B.SilkS")
			(hide yes)
			(effects
				(font
					(size 1.27 1.27)
				)
				(justify mirror)
			)
		)
		(property "Value" ""
			(at 0 0 0)
			(layer "B.Fab")
			(effects
				(font
					(size 1.27 1.27)
				)
				(justify mirror)
			)
		)
		(duplicate_pad_numbers_are_jumpers no)
		(fp_rect
			(start -0.3048 0.9906)
			(end 0.3048 -0.1016)
			(stroke
				(width 0)
				(type default)
			)
			(fill no)
			(layer "B.CrtYd")
		)
		(fp_line
			(start -0.3048 -0.1016)
			(end 0.3048 -0.1016)
			(stroke
				(width 0.1)
				(type default)
			)
			(layer "B.Fab")
		)
		(fp_line
			(start -0.3048 0.9906)
			(end -0.3048 -0.1016)
			(stroke
				(width 0.1)
				(type default)
			)
			(layer "B.Fab")
		)
		(fp_line
			(start 0.3048 -0.1016)
			(end 0.3048 0.9906)
			(stroke
				(width 0.1)
				(type default)
			)
			(layer "B.Fab")
		)
		(fp_line
			(start 0.3048 0.9906)
			(end -0.3048 0.9906)
			(stroke
				(width 0.1)
				(type default)
			)
			(layer "B.Fab")
		)
		(pad "1" smd rect
			(at 0 0 180)
			(size 0.508 0.508)
			(layers "B.Cu" "B.Mask" "B.Paste")
			(net "A_ADM1085_CEXT")
		)
		(pad "2" smd rect
			(at 0 0.889 180)
			(size 0.508 0.508)
			(layers "B.Cu" "B.Mask" "B.Paste")
			(net "GND")
		)
		(zone
			(layer "B.Cu")
			(hatch none 0.5)
			(connect_pads
				(clearance 0)
			)
			(min_thickness 0.25)
			(keepout
				(tracks allowed)
				(vias not_allowed)
				(pads allowed)
				(copperpour not_allowed)
				(footprints allowed)
			)
			(placement
				(enabled no)
				(sheetname "")
			)
			(fill
				(thermal_gap 0.5)
				(thermal_bridge_width 0.5)
				(island_removal_mode 0)
			)
			(polygon
				(pts
					(xy 422.656 -6.9215) (xy 423.164 -6.9215) (xy 423.164 -7.3025) (xy 422.656 -7.3025)
				)
			)
		)
		(zone
			(layer "B.Cu")
			(hatch none 0.5)
			(connect_pads
				(clearance 0)
			)
			(min_thickness 0.25)
			(keepout
				(tracks not_allowed)
				(vias allowed)
				(pads allowed)
				(copperpour not_allowed)
				(footprints allowed)
			)
			(placement
				(enabled no)
				(sheetname "")
			)
			(fill
				(thermal_gap 0.5)
				(thermal_bridge_width 0.5)
				(island_removal_mode 0)
			)
			(polygon
				(pts
					(xy 422.656 -6.9215) (xy 423.164 -6.9215) (xy 423.164 -7.3025) (xy 422.656 -7.3025)
				)
			)
		)
	)
	(footprint ""
		(layer "B.Cu")
		(at 365.506 -115.189 -90)
		(property "Reference" "C3M37"
			(at 0 0 90)
			(layer "B.SilkS")
			(hide yes)
			(effects
				(font
					(size 1.27 1.27)
				)
				(justify mirror)
			)
		)
		(property "Value" ""
			(at 0 0 90)
			(layer "B.Fab")
			(effects
				(font
					(size 1.27 1.27)
				)
				(justify mirror)
			)
		)
		(duplicate_pad_numbers_are_jumpers no)
		(fp_poly
			(pts
				(xy -0.3048 -0.1016) (xy -0.3048 0.9906) (xy 0.3048 0.9906) (xy 0.3048 -0.1016)
			)
			(stroke
				(width 0)
				(type default)
			)
			(fill no)
			(layer "B.CrtYd")
		)
		(fp_line
			(start -0.3048 0.9906)
			(end -0.3048 -0.1016)
			(stroke
				(width 0.1)
				(type default)
			)
			(layer "B.Fab")
		)
		(fp_line
			(start 0.3048 0.9906)
			(end -0.3048 0.9906)
			(stroke
				(width 0.1)
				(type default)
			)
			(layer "B.Fab")
		)
		(fp_line
			(start -0.3048 -0.1016)
			(end 0.3048 -0.1016)
			(stroke
				(width 0.1)
				(type default)
			)
			(layer "B.Fab")
		)
		(fp_line
			(start 0.3048 -0.1016)
			(end 0.3048 0.9906)
			(stroke
				(width 0.1)
				(type default)
			)
			(layer "B.Fab")
		)
		(pad "1" smd rect
			(at 0 0 90)
			(size 0.508 0.508)
			(layers "B.Cu" "B.Mask" "B.Paste")
			(net "DMI_CPU0_PCH_RX_DP<1>")
		)
		(pad "2" smd rect
			(at 0 0.889 90)
			(size 0.508 0.508)
			(layers "B.Cu" "B.Mask" "B.Paste")
			(net "DMI_CPU0_PCH_RX_C_DP<1>")
		)
		(zone
			(layer "B.Cu")
			(hatch none 0.5)
			(connect_pads
				(clearance 0)
			)
			(min_thickness 0.25)
			(keepout
				(tracks not_allowed)
				(vias allowed)
				(pads allowed)
				(copperpour not_allowed)
				(footprints allowed)
			)
			(placement
				(enabled no)
				(sheetname "")
			)
			(fill
				(thermal_gap 0.5)
				(thermal_bridge_width 0.5)
				(island_removal_mode 0)
			)
			(polygon
				(pts
					(xy 364.871 -114.935) (xy 364.871 -115.443) (xy 365.252 -115.443) (xy 365.252 -114.935)
				)
			)
		)
		(zone
			(layer "B.Cu")
			(hatch none 0.5)
			(connect_pads
				(clearance 0)
			)
			(min_thickness 0.25)
			(keepout
				(tracks allowed)
				(vias not_allowed)
				(pads allowed)
				(copperpour not_allowed)
				(footprints allowed)
			)
			(placement
				(enabled no)
				(sheetname "")
			)
			(fill
				(thermal_gap 0.5)
				(thermal_bridge_width 0.5)
				(island_removal_mode 0)
			)
			(polygon
				(pts
					(xy 365.252 -114.935) (xy 365.252 -115.443) (xy 364.871 -115.443) (xy 364.871 -114.935)
				)
			)
		)
	)
	(footprint ""
		(layer "B.Cu")
		(at 353.367848 -89.98204 180)
		(property "Reference" "R3N20"
			(at 0 0 0)
			(layer "B.SilkS")
			(hide yes)
			(effects
				(font
					(size 1.27 1.27)
				)
				(justify mirror)
			)
		)
		(property "Value" ""
			(at 0 0 0)
			(layer "B.Fab")
			(effects
				(font
					(size 1.27 1.27)
				)
				(justify mirror)
			)
		)
		(duplicate_pad_numbers_are_jumpers no)
		(fp_poly
			(pts
				(xy 0.2794 -0.1016) (xy -0.2794 -0.1016) (xy -0.2794 0.9906) (xy 0.2794 0.9906)
			)
			(stroke
				(width 0)
				(type default)
			)
			(fill no)
			(layer "B.CrtYd")
		)
		(fp_line
			(start 0.2794 0.9906)
			(end -0.2794 0.9906)
			(stroke
				(width 0.1)
				(type default)
			)
			(layer "B.Fab")
		)
		(fp_line
			(start 0.2794 -0.1016)
			(end 0.2794 0.9906)
			(stroke
				(width 0.1)
				(type default)
			)
			(layer "B.Fab")
		)
		(fp_line
			(start -0.2794 0.9906)
			(end -0.2794 -0.1016)
			(stroke
				(width 0.1)
				(type default)
			)
			(layer "B.Fab")
		)
		(fp_line
			(start -0.2794 -0.1016)
			(end 0.2794 -0.1016)
			(stroke
				(width 0.1)
				(type default)
			)
			(layer "B.Fab")
		)
		(pad "1" smd rect
			(at 0 0)
			(size 0.508 0.508)
			(layers "B.Cu" "B.Mask" "B.Paste")
			(net "VSENSE_PVCCIO_CPU0_AVSN")
		)
		(pad "2" smd rect
			(at 0 0.889)
			(size 0.508 0.508)
			(layers "B.Cu" "B.Mask" "B.Paste")
			(net "GND")
		)
		(zone
			(layer "B.Cu")
			(hatch none 0.5)
			(connect_pads
				(clearance 0)
			)
			(min_thickness 0.25)
			(keepout
				(tracks not_allowed)
				(vias allowed)
				(pads allowed)
				(copperpour not_allowed)
				(footprints allowed)
			)
			(placement
				(enabled no)
				(sheetname "")
			)
			(fill
				(thermal_gap 0.5)
				(thermal_bridge_width 0.5)
				(island_removal_mode 0)
			)
			(polygon
				(pts
					(xy 353.113848 -90.61704) (xy 353.621848 -90.61704) (xy 353.621848 -90.23604) (xy 353.113848 -90.23604)
				)
			)
		)
		(zone
			(layer "B.Cu")
			(hatch none 0.5)
			(connect_pads
				(clearance 0)
			)
			(min_thickness 0.25)
			(keepout
				(tracks allowed)
				(vias not_allowed)
				(pads allowed)
				(copperpour not_allowed)
				(footprints allowed)
			)
			(placement
				(enabled no)
				(sheetname "")
			)
			(fill
				(thermal_gap 0.5)
				(thermal_bridge_width 0.5)
				(island_removal_mode 0)
			)
			(polygon
				(pts
					(xy 353.113848 -90.23604) (xy 353.621848 -90.23604) (xy 353.621848 -90.61704) (xy 353.113848 -90.61704)
				)
			)
		)
	)
	(footprint ""
		(layer "B.Cu")
		(at 17.83842 -99.71532 90)
		(property "Reference" "C9N15"
			(at 0 0 90)
			(layer "B.SilkS")
			(hide yes)
			(effects
				(font
					(size 1.27 1.27)
				)
				(justify mirror)
			)
		)
		(property "Value" ""
			(at 0 0 90)
			(layer "B.Fab")
			(effects
				(font
					(size 1.27 1.27)
				)
				(justify mirror)
			)
		)
		(duplicate_pad_numbers_are_jumpers no)
		(fp_poly
			(pts
				(xy -0.3048 -0.1016) (xy -0.3048 0.9906) (xy 0.3048 0.9906) (xy 0.3048 -0.1016)
			)
			(stroke
				(width 0)
				(type default)
			)
			(fill no)
			(layer "B.CrtYd")
		)
		(fp_line
			(start 0.3048 -0.1016)
			(end 0.3048 0.9906)
			(stroke
				(width 0.1)
				(type default)
			)
			(layer "B.Fab")
		)
		(fp_line
			(start -0.3048 -0.1016)
			(end 0.3048 -0.1016)
			(stroke
				(width 0.1)
				(type default)
			)
			(layer "B.Fab")
		)
		(fp_line
			(start 0.3048 0.9906)
			(end -0.3048 0.9906)
			(stroke
				(width 0.1)
				(type default)
			)
			(layer "B.Fab")
		)
		(fp_line
			(start -0.3048 0.9906)
			(end -0.3048 -0.1016)
			(stroke
				(width 0.1)
				(type default)
			)
			(layer "B.Fab")
		)
		(pad "1" smd rect
			(at 0 0 270)
			(size 0.508 0.508)
			(layers "B.Cu" "B.Mask" "B.Paste")
			(net "P3E_CPU1_PE3_MP_C_TXN<9>")
		)
		(pad "2" smd rect
			(at 0 0.889 270)
			(size 0.508 0.508)
			(layers "B.Cu" "B.Mask" "B.Paste")
			(net "P3E_CPU1_PE3_MP_TXN<9>")
		)
		(zone
			(layer "B.Cu")
			(hatch none 0.5)
			(connect_pads
				(clearance 0)
			)
			(min_thickness 0.25)
			(keepout
				(tracks allowed)
				(vias not_allowed)
				(pads allowed)
				(copperpour not_allowed)
				(footprints allowed)
			)
			(placement
				(enabled no)
				(sheetname "")
			)
			(fill
				(thermal_gap 0.5)
				(thermal_bridge_width 0.5)
				(island_removal_mode 0)
			)
			(polygon
				(pts
					(xy 18.09242 -99.96932) (xy 18.09242 -99.46132) (xy 18.47342 -99.46132) (xy 18.47342 -99.96932)
				)
			)
		)
		(zone
			(layer "B.Cu")
			(hatch none 0.5)
			(connect_pads
				(clearance 0)
			)
			(min_thickness 0.25)
			(keepout
				(tracks not_allowed)
				(vias allowed)
				(pads allowed)
				(copperpour not_allowed)
				(footprints allowed)
			)
			(placement
				(enabled no)
				(sheetname "")
			)
			(fill
				(thermal_gap 0.5)
				(thermal_bridge_width 0.5)
				(island_removal_mode 0)
			)
			(polygon
				(pts
					(xy 18.47342 -99.96932) (xy 18.47342 -99.46132) (xy 18.09242 -99.46132) (xy 18.09242 -99.96932)
				)
			)
		)
	)
	(footprint ""
		(layer "B.Cu")
		(at 334.518 -10.795 180)
		(property "Reference" "C3U1"
			(at -3.27533 3.683 270)
			(unlocked yes)
			(layer "B.SilkS")
			(effects
				(font
					(size 0.7874 0.5842)
					(thickness 0.1524)
				)
				(justify mirror)
			)
		)
		(property "Value" ""
			(at 0 0 0)
			(layer "B.Fab")
			(effects
				(font
					(size 1.27 1.27)
				)
				(justify mirror)
			)
		)
		(duplicate_pad_numbers_are_jumpers no)
		(fp_line
			(start 2.563114 1.633728)
			(end 1.6002 1.633728)
			(stroke
				(width 0.1524)
				(type default)
			)
			(layer "B.SilkS")
		)
		(fp_line
			(start 2.563114 -1.616456)
			(end 2.563114 1.633728)
			(stroke
				(width 0.1524)
				(type default)
			)
			(layer "B.SilkS")
		)
		(fp_line
			(start 2.286 7.366)
			(end 2.286 1.632712)
			(stroke
				(width 0.1524)
				(type default)
			)
			(layer "B.SilkS")
		)
		(fp_line
			(start 2.286 7.366)
			(end 1.60147 7.366)
			(stroke
				(width 0.1524)
				(type default)
			)
			(layer "B.SilkS")
		)
		(fp_line
			(start 1.6002 -1.616456)
			(end 2.563114 -1.616456)
			(stroke
				(width 0.1524)
				(type default)
			)
			(layer "B.SilkS")
		)
		(fp_line
			(start -1.6002 -1.616456)
			(end -2.504948 -1.616456)
			(stroke
				(width 0.1524)
				(type default)
			)
			(layer "B.SilkS")
		)
		(fp_line
			(start -2.286 7.366)
			(end -1.600708 7.366)
			(stroke
				(width 0.1524)
				(type default)
			)
			(layer "B.SilkS")
		)
		(fp_line
			(start -2.286 7.366)
			(end -2.286 1.63195)
			(stroke
				(width 0.1524)
				(type default)
			)
			(layer "B.SilkS")
		)
		(fp_line
			(start -2.504948 1.633728)
			(end -1.6002 1.633728)
			(stroke
				(width 0.1524)
				(type default)
			)
			(layer "B.SilkS")
		)
		(fp_line
			(start -2.504948 -1.616456)
			(end -2.504948 1.633728)
			(stroke
				(width 0.1524)
				(type default)
			)
			(layer "B.SilkS")
		)
		(fp_rect
			(start -2.286 -0.254)
			(end 2.286 7.366)
			(stroke
				(width 0)
				(type default)
			)
			(fill no)
			(layer "B.CrtYd")
		)
		(fp_line
			(start 2.286 7.366)
			(end 2.286 -0.254)
			(stroke
				(width 0.1)
				(type default)
			)
			(layer "B.Fab")
		)
		(fp_line
			(start 2.286 -0.254)
			(end -2.286 -0.254)
			(stroke
				(width 0.1)
				(type default)
			)
			(layer "B.Fab")
		)
		(fp_line
			(start -2.286 7.366)
			(end 2.286 7.366)
			(stroke
				(width 0.1)
				(type default)
			)
			(layer "B.Fab")
		)
		(fp_line
			(start -2.286 -0.254)
			(end -2.286 7.366)
			(stroke
				(width 0.1)
				(type default)
			)
			(layer "B.Fab")
		)
		(pad "1" smd rect
			(at 0 0)
			(size 2.54 3.048)
			(layers "B.Cu" "B.Mask" "B.Paste")
			(net "PVDDQ_ABC")
		)
		(pad "2" smd rect
			(at 0 7.112)
			(size 2.54 3.048)
			(layers "B.Cu" "B.Mask" "B.Paste")
			(net "GND")
		)
	)
	(footprint ""
		(layer "B.Cu")
		(at 462.5975 -23.114 180)
		(property "Reference" "R6W21"
			(at 0.8382 -0.67818 180)
			(unlocked yes)
			(layer "B.SilkS")
			(effects
				(font
					(size 0.4064 0.254)
					(thickness 0.1524)
				)
				(justify left mirror)
			)
		)
		(property "Value" ""
			(at 0 0 0)
			(layer "B.Fab")
			(effects
				(font
					(size 1.27 1.27)
				)
				(justify mirror)
			)
		)
		(duplicate_pad_numbers_are_jumpers no)
		(fp_poly
			(pts
				(xy 0.2794 -0.1016) (xy -0.2794 -0.1016) (xy -0.2794 0.9906) (xy 0.2794 0.9906)
			)
			(stroke
				(width 0)
				(type default)
			)
			(fill no)
			(layer "B.CrtYd")
		)
		(fp_line
			(start 0.2794 0.9906)
			(end -0.2794 0.9906)
			(stroke
				(width 0.1)
				(type default)
			)
			(layer "B.Fab")
		)
		(fp_line
			(start 0.2794 -0.1016)
			(end 0.2794 0.9906)
			(stroke
				(width 0.1)
				(type default)
			)
			(layer "B.Fab")
		)
		(fp_line
			(start -0.2794 0.9906)
			(end -0.2794 -0.1016)
			(stroke
				(width 0.1)
				(type default)
			)
			(layer "B.Fab")
		)
		(fp_line
			(start -0.2794 -0.1016)
			(end 0.2794 -0.1016)
			(stroke
				(width 0.1)
				(type default)
			)
			(layer "B.Fab")
		)
		(pad "1" smd rect
			(at 0 0)
			(size 0.508 0.508)
			(layers "B.Cu" "B.Mask" "B.Paste")
			(net "P3V3_STBY")
		)
		(pad "2" smd rect
			(at 0 0.889)
			(size 0.508 0.508)
			(layers "B.Cu" "B.Mask" "B.Paste")
			(net "PU_ID_EEPROM_A0")
		)
		(zone
			(layer "B.Cu")
			(hatch none 0.5)
			(connect_pads
				(clearance 0)
			)
			(min_thickness 0.25)
			(keepout
				(tracks not_allowed)
				(vias allowed)
				(pads allowed)
				(copperpour not_allowed)
				(footprints allowed)
			)
			(placement
				(enabled no)
				(sheetname "")
			)
			(fill
				(thermal_gap 0.5)
				(thermal_bridge_width 0.5)
				(island_removal_mode 0)
			)
			(polygon
				(pts
					(xy 462.3435 -23.749) (xy 462.8515 -23.749) (xy 462.8515 -23.368) (xy 462.3435 -23.368)
				)
			)
		)
		(zone
			(layer "B.Cu")
			(hatch none 0.5)
			(connect_pads
				(clearance 0)
			)
			(min_thickness 0.25)
			(keepout
				(tracks allowed)
				(vias not_allowed)
				(pads allowed)
				(copperpour not_allowed)
				(footprints allowed)
			)
			(placement
				(enabled no)
				(sheetname "")
			)
			(fill
				(thermal_gap 0.5)
				(thermal_bridge_width 0.5)
				(island_removal_mode 0)
			)
			(polygon
				(pts
					(xy 462.3435 -23.368) (xy 462.8515 -23.368) (xy 462.8515 -23.749) (xy 462.3435 -23.749)
				)
			)
		)
	)
	(footprint ""
		(layer "B.Cu")
		(at 379.984 -140.589 180)
		(property "Reference" "C3L20"
			(at -3.10007 3.24612 270)
			(unlocked yes)
			(layer "B.SilkS")
			(effects
				(font
					(size 0.7874 0.5842)
					(thickness 0.1524)
				)
				(justify mirror)
			)
		)
		(property "Value" ""
			(at 0 0 0)
			(layer "B.Fab")
			(effects
				(font
					(size 1.27 1.27)
				)
				(justify mirror)
			)
		)
		(duplicate_pad_numbers_are_jumpers no)
		(fp_line
			(start 2.563114 1.633728)
			(end 1.6002 1.633728)
			(stroke
				(width 0.1524)
				(type default)
			)
			(layer "B.SilkS")
		)
		(fp_line
			(start 2.563114 -1.616456)
			(end 2.563114 1.633728)
			(stroke
				(width 0.1524)
				(type default)
			)
			(layer "B.SilkS")
		)
		(fp_line
			(start 2.286 7.366)
			(end 2.286 1.632712)
			(stroke
				(width 0.1524)
				(type default)
			)
			(layer "B.SilkS")
		)
		(fp_line
			(start 2.286 7.366)
			(end 1.60147 7.366)
			(stroke
				(width 0.1524)
				(type default)
			)
			(layer "B.SilkS")
		)
		(fp_line
			(start 1.6002 -1.616456)
			(end 2.563114 -1.616456)
			(stroke
				(width 0.1524)
				(type default)
			)
			(layer "B.SilkS")
		)
		(fp_line
			(start -1.6002 -1.616456)
			(end -2.504948 -1.616456)
			(stroke
				(width 0.1524)
				(type default)
			)
			(layer "B.SilkS")
		)
		(fp_line
			(start -2.286 7.366)
			(end -1.600708 7.366)
			(stroke
				(width 0.1524)
				(type default)
			)
			(layer "B.SilkS")
		)
		(fp_line
			(start -2.286 7.366)
			(end -2.286 1.63195)
			(stroke
				(width 0.1524)
				(type default)
			)
			(layer "B.SilkS")
		)
		(fp_line
			(start -2.504948 1.633728)
			(end -1.6002 1.633728)
			(stroke
				(width 0.1524)
				(type default)
			)
			(layer "B.SilkS")
		)
		(fp_line
			(start -2.504948 -1.616456)
			(end -2.504948 1.633728)
			(stroke
				(width 0.1524)
				(type default)
			)
			(layer "B.SilkS")
		)
		(fp_rect
			(start 2.286 7.366)
			(end -2.286 -0.254)
			(stroke
				(width 0)
				(type default)
			)
			(fill no)
			(layer "B.CrtYd")
		)
		(fp_line
			(start 2.286 7.366)
			(end 2.286 -0.254)
			(stroke
				(width 0.1)
				(type default)
			)
			(layer "B.Fab")
		)
		(fp_line
			(start 2.286 -0.254)
			(end -2.286 -0.254)
			(stroke
				(width 0.1)
				(type default)
			)
			(layer "B.Fab")
		)
		(fp_line
			(start -2.286 7.366)
			(end 2.286 7.366)
			(stroke
				(width 0.1)
				(type default)
			)
			(layer "B.Fab")
		)
		(fp_line
			(start -2.286 -0.254)
			(end -2.286 7.366)
			(stroke
				(width 0.1)
				(type default)
			)
			(layer "B.Fab")
		)
		(pad "1" smd rect
			(at 0 0)
			(size 2.54 3.048)
			(layers "B.Cu" "B.Mask" "B.Paste")
			(net "PVNN_PCH_STBY")
		)
		(pad "2" smd rect
			(at 0 7.112)
			(size 2.54 3.048)
			(layers "B.Cu" "B.Mask" "B.Paste")
			(net "GND")
		)
	)
	(footprint ""
		(layer "B.Cu")
		(at 49.4284 -86.67242)
		(property "Reference" "C9P3"
			(at 0 0 0)
			(layer "B.SilkS")
			(hide yes)
			(effects
				(font
					(size 1.27 1.27)
				)
				(justify mirror)
			)
		)
		(property "Value" ""
			(at 0 0 0)
			(layer "B.Fab")
			(effects
				(font
					(size 1.27 1.27)
				)
				(justify mirror)
			)
		)
		(duplicate_pad_numbers_are_jumpers no)
		(fp_poly
			(pts
				(xy 0.4953 -0.2032) (xy -0.4953 -0.2032) (xy -0.4953 1.6002) (xy 0.4953 1.6002)
			)
			(stroke
				(width 0)
				(type default)
			)
			(fill no)
			(layer "B.CrtYd")
		)
		(fp_line
			(start -0.4953 -0.2032)
			(end -0.4953 1.6002)
			(stroke
				(width 0.1)
				(type default)
			)
			(layer "B.Fab")
		)
		(fp_line
			(start -0.4953 1.6002)
			(end 0.4953 1.6002)
			(stroke
				(width 0.1)
				(type default)
			)
			(layer "B.Fab")
		)
		(fp_line
			(start 0.4953 -0.2032)
			(end -0.4953 -0.2032)
			(stroke
				(width 0.1)
				(type default)
			)
			(layer "B.Fab")
		)
		(fp_line
			(start 0.4953 1.6002)
			(end 0.4953 -0.2032)
			(stroke
				(width 0.1)
				(type default)
			)
			(layer "B.Fab")
		)
		(pad "1" smd rect
			(at 0 0 180)
			(size 0.762 0.889)
			(layers "B.Cu" "B.Mask" "B.Paste")
			(net "PVCCIN_CPU1")
		)
		(pad "2" smd rect
			(at 0 1.397 180)
			(size 0.762 0.889)
			(layers "B.Cu" "B.Mask" "B.Paste")
			(net "GND")
		)
		(zone
			(layer "B.Cu")
			(hatch none 0.5)
			(connect_pads
				(clearance 0)
			)
			(min_thickness 0.25)
			(keepout
				(tracks not_allowed)
				(vias allowed)
				(pads allowed)
				(copperpour not_allowed)
				(footprints allowed)
			)
			(placement
				(enabled no)
				(sheetname "")
			)
			(fill
				(thermal_gap 0.5)
				(thermal_bridge_width 0.5)
				(island_removal_mode 0)
			)
			(polygon
				(pts
					(xy 49.8094 -86.22792) (xy 49.0474 -86.22792) (xy 49.0474 -85.71992) (xy 49.8094 -85.71992)
				)
			)
		)
	)
	(footprint ""
		(layer "B.Cu")
		(at 49.4284 -70.993)
		(property "Reference" "C9P20"
			(at 0 0 0)
			(layer "B.SilkS")
			(hide yes)
			(effects
				(font
					(size 1.27 1.27)
				)
				(justify mirror)
			)
		)
		(property "Value" ""
			(at 0 0 0)
			(layer "B.Fab")
			(effects
				(font
					(size 1.27 1.27)
				)
				(justify mirror)
			)
		)
		(duplicate_pad_numbers_are_jumpers no)
		(fp_poly
			(pts
				(xy 0.4953 -0.2032) (xy -0.4953 -0.2032) (xy -0.4953 1.6002) (xy 0.4953 1.6002)
			)
			(stroke
				(width 0)
				(type default)
			)
			(fill no)
			(layer "B.CrtYd")
		)
		(fp_line
			(start -0.4953 -0.2032)
			(end -0.4953 1.6002)
			(stroke
				(width 0.1)
				(type default)
			)
			(layer "B.Fab")
		)
		(fp_line
			(start -0.4953 1.6002)
			(end 0.4953 1.6002)
			(stroke
				(width 0.1)
				(type default)
			)
			(layer "B.Fab")
		)
		(fp_line
			(start 0.4953 -0.2032)
			(end -0.4953 -0.2032)
			(stroke
				(width 0.1)
				(type default)
			)
			(layer "B.Fab")
		)
		(fp_line
			(start 0.4953 1.6002)
			(end 0.4953 -0.2032)
			(stroke
				(width 0.1)
				(type default)
			)
			(layer "B.Fab")
		)
		(pad "1" smd rect
			(at 0 0 180)
			(size 0.762 0.889)
			(layers "B.Cu" "B.Mask" "B.Paste")
			(net "PVCCIN_CPU1")
		)
		(pad "2" smd rect
			(at 0 1.397 180)
			(size 0.762 0.889)
			(layers "B.Cu" "B.Mask" "B.Paste")
			(net "GND")
		)
		(zone
			(layer "B.Cu")
			(hatch none 0.5)
			(connect_pads
				(clearance 0)
			)
			(min_thickness 0.25)
			(keepout
				(tracks not_allowed)
				(vias allowed)
				(pads allowed)
				(copperpour not_allowed)
				(footprints allowed)
			)
			(placement
				(enabled no)
				(sheetname "")
			)
			(fill
				(thermal_gap 0.5)
				(thermal_bridge_width 0.5)
				(island_removal_mode 0)
			)
			(polygon
				(pts
					(xy 49.8094 -70.5485) (xy 49.0474 -70.5485) (xy 49.0474 -70.0405) (xy 49.8094 -70.0405)
				)
			)
		)
	)
	(footprint ""
		(layer "B.Cu")
		(at 420.624 -81.4705 180)
		(property "Reference" "C2P1"
			(at 0 0 0)
			(layer "B.SilkS")
			(hide yes)
			(effects
				(font
					(size 1.27 1.27)
				)
				(justify mirror)
			)
		)
		(property "Value" ""
			(at 0 0 0)
			(layer "B.Fab")
			(effects
				(font
					(size 1.27 1.27)
				)
				(justify mirror)
			)
		)
		(duplicate_pad_numbers_are_jumpers no)
		(fp_poly
			(pts
				(xy -0.3048 -0.1016) (xy -0.3048 0.9906) (xy 0.3048 0.9906) (xy 0.3048 -0.1016)
			)
			(stroke
				(width 0)
				(type default)
			)
			(fill no)
			(layer "B.CrtYd")
		)
		(fp_line
			(start 0.3048 0.9906)
			(end -0.3048 0.9906)
			(stroke
				(width 0.1)
				(type default)
			)
			(layer "B.Fab")
		)
		(fp_line
			(start 0.3048 -0.1016)
			(end 0.3048 0.9906)
			(stroke
				(width 0.1)
				(type default)
			)
			(layer "B.Fab")
		)
		(fp_line
			(start -0.3048 0.9906)
			(end -0.3048 -0.1016)
			(stroke
				(width 0.1)
				(type default)
			)
			(layer "B.Fab")
		)
		(fp_line
			(start -0.3048 -0.1016)
			(end 0.3048 -0.1016)
			(stroke
				(width 0.1)
				(type default)
			)
			(layer "B.Fab")
		)
		(pad "1" smd rect
			(at 0 0)
			(size 0.508 0.508)
			(layers "B.Cu" "B.Mask" "B.Paste")
			(net "P3V3_STBY")
		)
		(pad "2" smd rect
			(at 0 0.889)
			(size 0.508 0.508)
			(layers "B.Cu" "B.Mask" "B.Paste")
			(net "GND")
		)
		(zone
			(layer "B.Cu")
			(hatch none 0.5)
			(connect_pads
				(clearance 0)
			)
			(min_thickness 0.25)
			(keepout
				(tracks not_allowed)
				(vias allowed)
				(pads allowed)
				(copperpour not_allowed)
				(footprints allowed)
			)
			(placement
				(enabled no)
				(sheetname "")
			)
			(fill
				(thermal_gap 0.5)
				(thermal_bridge_width 0.5)
				(island_removal_mode 0)
			)
			(polygon
				(pts
					(xy 420.37 -82.1055) (xy 420.878 -82.1055) (xy 420.878 -81.7245) (xy 420.37 -81.7245)
				)
			)
		)
		(zone
			(layer "B.Cu")
			(hatch none 0.5)
			(connect_pads
				(clearance 0)
			)
			(min_thickness 0.25)
			(keepout
				(tracks allowed)
				(vias not_allowed)
				(pads allowed)
				(copperpour not_allowed)
				(footprints allowed)
			)
			(placement
				(enabled no)
				(sheetname "")
			)
			(fill
				(thermal_gap 0.5)
				(thermal_bridge_width 0.5)
				(island_removal_mode 0)
			)
			(polygon
				(pts
					(xy 420.37 -81.7245) (xy 420.878 -81.7245) (xy 420.878 -82.1055) (xy 420.37 -82.1055)
				)
			)
		)
	)
	(footprint ""
		(layer "B.Cu")
		(at 420.624 -155.829 90)
		(property "Reference" "C2L3"
			(at 0 0 90)
			(layer "B.SilkS")
			(hide yes)
			(effects
				(font
					(size 1.27 1.27)
				)
				(justify mirror)
			)
		)
		(property "Value" ""
			(at 0 0 90)
			(layer "B.Fab")
			(effects
				(font
					(size 1.27 1.27)
				)
				(justify mirror)
			)
		)
		(duplicate_pad_numbers_are_jumpers no)
		(fp_poly
			(pts
				(xy -0.3048 -0.1016) (xy -0.3048 0.9906) (xy 0.3048 0.9906) (xy 0.3048 -0.1016)
			)
			(stroke
				(width 0)
				(type default)
			)
			(fill no)
			(layer "B.CrtYd")
		)
		(fp_line
			(start 0.3048 -0.1016)
			(end 0.3048 0.9906)
			(stroke
				(width 0.1)
				(type default)
			)
			(layer "B.Fab")
		)
		(fp_line
			(start -0.3048 -0.1016)
			(end 0.3048 -0.1016)
			(stroke
				(width 0.1)
				(type default)
			)
			(layer "B.Fab")
		)
		(fp_line
			(start 0.3048 0.9906)
			(end -0.3048 0.9906)
			(stroke
				(width 0.1)
				(type default)
			)
			(layer "B.Fab")
		)
		(fp_line
			(start -0.3048 0.9906)
			(end -0.3048 -0.1016)
			(stroke
				(width 0.1)
				(type default)
			)
			(layer "B.Fab")
		)
		(pad "1" smd rect
			(at 0 0 270)
			(size 0.508 0.508)
			(layers "B.Cu" "B.Mask" "B.Paste")
			(net "SATA6G_PCH_PCIE_UP_SATA_RXN<3>")
		)
		(pad "2" smd rect
			(at 0 0.889 270)
			(size 0.508 0.508)
			(layers "B.Cu" "B.Mask" "B.Paste")
			(net "SATA6G_P3_RX_C_DN")
		)
		(zone
			(layer "B.Cu")
			(hatch none 0.5)
			(connect_pads
				(clearance 0)
			)
			(min_thickness 0.25)
			(keepout
				(tracks allowed)
				(vias not_allowed)
				(pads allowed)
				(copperpour not_allowed)
				(footprints allowed)
			)
			(placement
				(enabled no)
				(sheetname "")
			)
			(fill
				(thermal_gap 0.5)
				(thermal_bridge_width 0.5)
				(island_removal_mode 0)
			)
			(polygon
				(pts
					(xy 420.878 -156.083) (xy 420.878 -155.575) (xy 421.259 -155.575) (xy 421.259 -156.083)
				)
			)
		)
		(zone
			(layer "B.Cu")
			(hatch none 0.5)
			(connect_pads
				(clearance 0)
			)
			(min_thickness 0.25)
			(keepout
				(tracks not_allowed)
				(vias allowed)
				(pads allowed)
				(copperpour not_allowed)
				(footprints allowed)
			)
			(placement
				(enabled no)
				(sheetname "")
			)
			(fill
				(thermal_gap 0.5)
				(thermal_bridge_width 0.5)
				(island_removal_mode 0)
			)
			(polygon
				(pts
					(xy 421.259 -156.083) (xy 421.259 -155.575) (xy 420.878 -155.575) (xy 420.878 -156.083)
				)
			)
		)
	)
	(footprint ""
		(layer "B.Cu")
		(at 391.8839 -103.3272 90)
		(property "Reference" "C2N25"
			(at 0 0 90)
			(layer "B.SilkS")
			(hide yes)
			(effects
				(font
					(size 1.27 1.27)
				)
				(justify mirror)
			)
		)
		(property "Value" ""
			(at 0 0 90)
			(layer "B.Fab")
			(effects
				(font
					(size 1.27 1.27)
				)
				(justify mirror)
			)
		)
		(duplicate_pad_numbers_are_jumpers no)
		(fp_rect
			(start 0.2794 0.9144)
			(end -0.2794 -0.1143)
			(stroke
				(width 0)
				(type default)
			)
			(fill no)
			(layer "B.CrtYd")
		)
		(fp_line
			(start 0.2794 -0.1143)
			(end -0.2794 -0.1143)
			(stroke
				(width 0.1)
				(type default)
			)
			(layer "B.Fab")
		)
		(fp_line
			(start -0.2794 -0.1143)
			(end -0.2794 0.9144)
			(stroke
				(width 0.1)
				(type default)
			)
			(layer "B.Fab")
		)
		(fp_line
			(start 0.2794 0.9144)
			(end 0.2794 -0.1143)
			(stroke
				(width 0.1)
				(type default)
			)
			(layer "B.Fab")
		)
		(fp_line
			(start -0.2794 0.9144)
			(end 0.2794 0.9144)
			(stroke
				(width 0.1)
				(type default)
			)
			(layer "B.Fab")
		)
		(pad "1" smd custom
			(at 0 0)
			(size 0.10414 0.10414)
			(layers "B.Cu" "B.Mask" "B.Paste")
			(net "P3V3_STBY")
			(options
				(clearance outline)
				(anchor circle)
			)
			(primitives
				(gr_poly
					(pts
						(xy -0.20828 -0.08636) (xy -0.20828 0.08636) (xy -0.08636 0.20828) (xy 0.086614 0.20828) (xy 0.20828 0.086614)
						(xy 0.20828 -0.08636) (xy 0.08636 -0.20828) (xy -0.08636 -0.20828)
					)
					(width 0)
					(fill yes)
				)
			)
		)
		(pad "2" smd custom
			(at 0 0.8001)
			(size 0.10414 0.10414)
			(layers "B.Cu" "B.Mask" "B.Paste")
			(net "GND")
			(options
				(clearance outline)
				(anchor circle)
			)
			(primitives
				(gr_poly
					(pts
						(xy -0.20828 -0.08636) (xy -0.20828 0.08636) (xy -0.08636 0.20828) (xy 0.086614 0.20828) (xy 0.20828 0.086614)
						(xy 0.20828 -0.08636) (xy 0.08636 -0.20828) (xy -0.08636 -0.20828)
					)
					(width 0)
					(fill yes)
				)
			)
		)
		(zone
			(layer "B.Cu")
			(hatch none 0.5)
			(connect_pads
				(clearance 0)
			)
			(min_thickness 0.25)
			(keepout
				(tracks allowed)
				(vias not_allowed)
				(pads allowed)
				(copperpour not_allowed)
				(footprints allowed)
			)
			(placement
				(enabled no)
				(sheetname "")
			)
			(fill
				(thermal_gap 0.5)
				(thermal_bridge_width 0.5)
				(island_removal_mode 0)
			)
			(polygon
				(pts
					(xy 392.09345 -103.41483) (xy 392.47445 -103.41483) (xy 392.47445 -103.23957) (xy 392.09345 -103.239316)
				)
			)
		)
		(zone
			(layer "B.Cu")
			(hatch none 0.5)
			(connect_pads
				(clearance 0)
			)
			(min_thickness 0.25)
			(keepout
				(tracks not_allowed)
				(vias allowed)
				(pads allowed)
				(copperpour not_allowed)
				(footprints allowed)
			)
			(placement
				(enabled no)
				(sheetname "")
			)
			(fill
				(thermal_gap 0.5)
				(thermal_bridge_width 0.5)
				(island_removal_mode 0)
			)
			(polygon
				(pts
					(xy 392.09345 -103.41483) (xy 392.47445 -103.41483) (xy 392.47445 -103.23957) (xy 392.09345 -103.239316)
				)
			)
		)
	)
	(footprint ""
		(layer "B.Cu")
		(at 332.105 -141.351 90)
		(property "Reference" "C4L5"
			(at -3.07467 8.001 0)
			(unlocked yes)
			(layer "B.SilkS")
			(effects
				(font
					(size 0.7874 0.5842)
					(thickness 0.1524)
				)
				(justify mirror)
			)
		)
		(property "Value" ""
			(at 0 0 90)
			(layer "B.Fab")
			(effects
				(font
					(size 1.27 1.27)
				)
				(justify mirror)
			)
		)
		(duplicate_pad_numbers_are_jumpers no)
		(fp_line
			(start 2.563114 -1.616456)
			(end 2.563114 1.633728)
			(stroke
				(width 0.1524)
				(type default)
			)
			(layer "B.SilkS")
		)
		(fp_line
			(start 1.6002 -1.616456)
			(end 2.563114 -1.616456)
			(stroke
				(width 0.1524)
				(type default)
			)
			(layer "B.SilkS")
		)
		(fp_line
			(start -1.6002 -1.616456)
			(end -2.504948 -1.616456)
			(stroke
				(width 0.1524)
				(type default)
			)
			(layer "B.SilkS")
		)
		(fp_line
			(start -2.504948 -1.616456)
			(end -2.504948 1.633728)
			(stroke
				(width 0.1524)
				(type default)
			)
			(layer "B.SilkS")
		)
		(fp_line
			(start 2.563114 1.633728)
			(end 1.6002 1.633728)
			(stroke
				(width 0.1524)
				(type default)
			)
			(layer "B.SilkS")
		)
		(fp_line
			(start -2.504948 1.633728)
			(end -1.6002 1.633728)
			(stroke
				(width 0.1524)
				(type default)
			)
			(layer "B.SilkS")
		)
		(fp_line
			(start 2.286 7.366)
			(end 2.286 1.632712)
			(stroke
				(width 0.1524)
				(type default)
			)
			(layer "B.SilkS")
		)
		(fp_line
			(start 2.286 7.366)
			(end 1.60147 7.366)
			(stroke
				(width 0.1524)
				(type default)
			)
			(layer "B.SilkS")
		)
		(fp_line
			(start -2.286 7.366)
			(end -2.286 1.63195)
			(stroke
				(width 0.1524)
				(type default)
			)
			(layer "B.SilkS")
		)
		(fp_line
			(start -2.286 7.366)
			(end -1.600708 7.366)
			(stroke
				(width 0.1524)
				(type default)
			)
			(layer "B.SilkS")
		)
		(fp_rect
			(start 2.286 7.366)
			(end -2.286 -0.254)
			(stroke
				(width 0)
				(type default)
			)
			(fill no)
			(layer "B.CrtYd")
		)
		(fp_line
			(start 2.286 -0.254)
			(end -2.286 -0.254)
			(stroke
				(width 0.1)
				(type default)
			)
			(layer "B.Fab")
		)
		(fp_line
			(start -2.286 -0.254)
			(end -2.286 7.366)
			(stroke
				(width 0.1)
				(type default)
			)
			(layer "B.Fab")
		)
		(fp_line
			(start 2.286 7.366)
			(end 2.286 -0.254)
			(stroke
				(width 0.1)
				(type default)
			)
			(layer "B.Fab")
		)
		(fp_line
			(start -2.286 7.366)
			(end 2.286 7.366)
			(stroke
				(width 0.1)
				(type default)
			)
			(layer "B.Fab")
		)
		(pad "1" smd rect
			(at 0 0 270)
			(size 2.54 3.048)
			(layers "B.Cu" "B.Mask" "B.Paste")
			(net "PVDDQ_DEF")
		)
		(pad "2" smd rect
			(at 0 7.112 270)
			(size 2.54 3.048)
			(layers "B.Cu" "B.Mask" "B.Paste")
			(net "GND")
		)
	)
	(footprint ""
		(layer "B.Cu")
		(at 388.239 -105.918 180)
		(property "Reference" "C3N21"
			(at 0 0 0)
			(layer "B.SilkS")
			(hide yes)
			(effects
				(font
					(size 1.27 1.27)
				)
				(justify mirror)
			)
		)
		(property "Value" ""
			(at 0 0 0)
			(layer "B.Fab")
			(effects
				(font
					(size 1.27 1.27)
				)
				(justify mirror)
			)
		)
		(duplicate_pad_numbers_are_jumpers no)
		(fp_poly
			(pts
				(xy -0.3048 -0.1016) (xy -0.3048 0.9906) (xy 0.3048 0.9906) (xy 0.3048 -0.1016)
			)
			(stroke
				(width 0)
				(type default)
			)
			(fill no)
			(layer "B.CrtYd")
		)
		(fp_line
			(start 0.3048 0.9906)
			(end -0.3048 0.9906)
			(stroke
				(width 0.1)
				(type default)
			)
			(layer "B.Fab")
		)
		(fp_line
			(start 0.3048 -0.1016)
			(end 0.3048 0.9906)
			(stroke
				(width 0.1)
				(type default)
			)
			(layer "B.Fab")
		)
		(fp_line
			(start -0.3048 0.9906)
			(end -0.3048 -0.1016)
			(stroke
				(width 0.1)
				(type default)
			)
			(layer "B.Fab")
		)
		(fp_line
			(start -0.3048 -0.1016)
			(end 0.3048 -0.1016)
			(stroke
				(width 0.1)
				(type default)
			)
			(layer "B.Fab")
		)
		(pad "1" smd rect
			(at 0 0)
			(size 0.508 0.508)
			(layers "B.Cu" "B.Mask" "B.Paste")
			(net "P1V8_PCH_STBY")
		)
		(pad "2" smd rect
			(at 0 0.889)
			(size 0.508 0.508)
			(layers "B.Cu" "B.Mask" "B.Paste")
			(net "GND")
		)
		(zone
			(layer "B.Cu")
			(hatch none 0.5)
			(connect_pads
				(clearance 0)
			)
			(min_thickness 0.25)
			(keepout
				(tracks not_allowed)
				(vias allowed)
				(pads allowed)
				(copperpour not_allowed)
				(footprints allowed)
			)
			(placement
				(enabled no)
				(sheetname "")
			)
			(fill
				(thermal_gap 0.5)
				(thermal_bridge_width 0.5)
				(island_removal_mode 0)
			)
			(polygon
				(pts
					(xy 387.985 -106.553) (xy 388.493 -106.553) (xy 388.493 -106.172) (xy 387.985 -106.172)
				)
			)
		)
		(zone
			(layer "B.Cu")
			(hatch none 0.5)
			(connect_pads
				(clearance 0)
			)
			(min_thickness 0.25)
			(keepout
				(tracks allowed)
				(vias not_allowed)
				(pads allowed)
				(copperpour not_allowed)
				(footprints allowed)
			)
			(placement
				(enabled no)
				(sheetname "")
			)
			(fill
				(thermal_gap 0.5)
				(thermal_bridge_width 0.5)
				(island_removal_mode 0)
			)
			(polygon
				(pts
					(xy 387.985 -106.172) (xy 388.493 -106.172) (xy 388.493 -106.553) (xy 387.985 -106.553)
				)
			)
		)
	)
	(footprint ""
		(layer "B.Cu")
		(at 349.133414 -126.345442 -90)
		(property "Reference" "R769"
			(at 0.8382 -0.67818 270)
			(unlocked yes)
			(layer "B.SilkS")
			(effects
				(font
					(size 0.4064 0.254)
					(thickness 0.1524)
				)
				(justify left mirror)
			)
		)
		(property "Value" ""
			(at 0 0 90)
			(layer "B.Fab")
			(effects
				(font
					(size 1.27 1.27)
				)
				(justify mirror)
			)
		)
		(duplicate_pad_numbers_are_jumpers no)
		(fp_poly
			(pts
				(xy 0.2794 -0.1016) (xy -0.2794 -0.1016) (xy -0.2794 0.9906) (xy 0.2794 0.9906)
			)
			(stroke
				(width 0)
				(type default)
			)
			(fill no)
			(layer "B.CrtYd")
		)
		(fp_line
			(start -0.2794 0.9906)
			(end -0.2794 -0.1016)
			(stroke
				(width 0.1)
				(type default)
			)
			(layer "B.Fab")
		)
		(fp_line
			(start 0.2794 0.9906)
			(end -0.2794 0.9906)
			(stroke
				(width 0.1)
				(type default)
			)
			(layer "B.Fab")
		)
		(fp_line
			(start -0.2794 -0.1016)
			(end 0.2794 -0.1016)
			(stroke
				(width 0.1)
				(type default)
			)
			(layer "B.Fab")
		)
		(fp_line
			(start 0.2794 -0.1016)
			(end 0.2794 0.9906)
			(stroke
				(width 0.1)
				(type default)
			)
			(layer "B.Fab")
		)
		(pad "1" smd rect
			(at 0 0 90)
			(size 0.508 0.508)
			(layers "B.Cu" "B.Mask" "B.Paste")
			(net "P3E_CPU0_PE1_PCH_RXP<14>")
		)
		(pad "2" smd rect
			(at 0 0.889 90)
			(size 0.508 0.508)
			(layers "B.Cu" "B.Mask" "B.Paste")
			(net "P3E_CPU0_PE1_PCH_CON_RXP<14>")
		)
		(zone
			(layer "B.Cu")
			(hatch none 0.5)
			(connect_pads
				(clearance 0)
			)
			(min_thickness 0.25)
			(keepout
				(tracks not_allowed)
				(vias allowed)
				(pads allowed)
				(copperpour not_allowed)
				(footprints allowed)
			)
			(placement
				(enabled no)
				(sheetname "")
			)
			(fill
				(thermal_gap 0.5)
				(thermal_bridge_width 0.5)
				(island_removal_mode 0)
			)
			(polygon
				(pts
					(xy 348.498414 -126.091442) (xy 348.498414 -126.599442) (xy 348.879414 -126.599442) (xy 348.879414 -126.091442)
				)
			)
		)
		(zone
			(layer "B.Cu")
			(hatch none 0.5)
			(connect_pads
				(clearance 0)
			)
			(min_thickness 0.25)
			(keepout
				(tracks allowed)
				(vias not_allowed)
				(pads allowed)
				(copperpour not_allowed)
				(footprints allowed)
			)
			(placement
				(enabled no)
				(sheetname "")
			)
			(fill
				(thermal_gap 0.5)
				(thermal_bridge_width 0.5)
				(island_removal_mode 0)
			)
			(polygon
				(pts
					(xy 348.879414 -126.091442) (xy 348.879414 -126.599442) (xy 348.498414 -126.599442) (xy 348.498414 -126.091442)
				)
			)
		)
	)
	(footprint ""
		(layer "B.Cu")
		(at 370.078 -26.162)
		(property "Reference" "RN8F6"
			(at 0 0 0)
			(layer "B.SilkS")
			(hide yes)
			(effects
				(font
					(size 1.27 1.27)
				)
				(justify mirror)
			)
		)
		(property "Value" "*"
			(at -0.064008 -4.108196 0)
			(unlocked yes)
			(layer "B.Fab")
			(hide yes)
			(effects
				(font
					(size 1.27 1.016)
					(thickness 0.1524)
				)
				(justify mirror)
			)
		)
		(property "Device Type" "82KR2F-1-GP_SMD-RG-82KR2F-1-GPA"
			(at -0.064008 -5.632196 0)
			(unlocked yes)
			(layer "B.Fab")
			(hide yes)
			(effects
				(font
					(size 1.27 1.016)
					(thickness 0.1524)
				)
				(justify mirror)
			)
		)
		(duplicate_pad_numbers_are_jumpers no)
		(fp_line
			(start -0.508 -0.9398)
			(end 0.508 -0.9398)
			(stroke
				(width 0.1524)
				(type default)
			)
			(layer "B.SilkS")
		)
		(fp_line
			(start 0.508 -0.9398)
			(end 0.508 0.9398)
			(stroke
				(width 0.1524)
				(type default)
			)
			(layer "B.SilkS")
		)
		(fp_rect
			(start 0.508 0.9398)
			(end -0.508 -0.9398)
			(stroke
				(width 0)
				(type default)
			)
			(fill no)
			(layer "B.CrtYd")
		)
		(fp_rect
			(start 0.508 0.9398)
			(end -0.508 -0.9398)
			(stroke
				(width 0)
				(type default)
			)
			(fill no)
			(layer "B.Fab")
		)
		(pad "1" smd custom
			(at 0 -0.4445 180)
			(size 0.1397 0.1397)
			(layers "B.Cu" "B.Mask" "B.Paste")
			(net "TPM_SPI_BMC_WP_N")
			(options
				(clearance outline)
				(anchor circle)
			)
			(primitives
				(gr_poly
					(pts
						(arc
							(start -0.1778 0.2794)
							(mid -0.249642 0.249642)
							(end -0.2794 0.1778)
						)
						(arc
							(start -0.2794 -0.1778)
							(mid -0.249642 -0.249642)
							(end -0.1778 -0.2794)
						)
						(arc
							(start 0.1778 -0.2794)
							(mid 0.249642 -0.249642)
							(end 0.2794 -0.1778)
						)
						(arc
							(start 0.2794 0.1778)
							(mid 0.249642 0.249642)
							(end 0.1778 0.2794)
						)
					)
					(width 0)
					(fill yes)
				)
			)
		)
		(pad "2" smd custom
			(at 0 0.4445 180)
			(size 0.1397 0.1397)
			(layers "B.Cu" "B.Mask" "B.Paste")
			(net "GND")
			(options
				(clearance outline)
				(anchor circle)
			)
			(primitives
				(gr_poly
					(pts
						(arc
							(start -0.1778 0.2794)
							(mid -0.249642 0.249642)
							(end -0.2794 0.1778)
						)
						(arc
							(start -0.2794 -0.1778)
							(mid -0.249642 -0.249642)
							(end -0.1778 -0.2794)
						)
						(arc
							(start 0.1778 -0.2794)
							(mid 0.249642 -0.249642)
							(end 0.2794 -0.1778)
						)
						(arc
							(start 0.2794 0.1778)
							(mid 0.249642 0.249642)
							(end 0.1778 0.2794)
						)
					)
					(width 0)
					(fill yes)
				)
			)
		)
	)
	(footprint ""
		(layer "B.Cu")
		(at 437.7944 -50.4698 90)
		(property "Reference" "R2R8"
			(at 0 0 90)
			(layer "B.SilkS")
			(hide yes)
			(effects
				(font
					(size 1.27 1.27)
				)
				(justify mirror)
			)
		)
		(property "Value" "*"
			(at -0.064008 -4.108196 90)
			(unlocked yes)
			(layer "B.Fab")
			(hide yes)
			(effects
				(font
					(size 1.27 1.016)
					(thickness 0.1524)
				)
				(justify mirror)
			)
		)
		(property "Device Type" "887R2F-L-GP_SMD-RG-887R2F-L-GPA"
			(at -0.064008 -5.632196 90)
			(unlocked yes)
			(layer "B.Fab")
			(hide yes)
			(effects
				(font
					(size 1.27 1.016)
					(thickness 0.1524)
				)
				(justify mirror)
			)
		)
		(duplicate_pad_numbers_are_jumpers no)
		(fp_line
			(start 0.508 -0.9398)
			(end 0.508 0.9398)
			(stroke
				(width 0.1524)
				(type default)
			)
			(layer "B.SilkS")
		)
		(fp_line
			(start -0.508 -0.9398)
			(end 0.508 -0.9398)
			(stroke
				(width 0.1524)
				(type default)
			)
			(layer "B.SilkS")
		)
		(fp_rect
			(start 0.508 0.9398)
			(end -0.508 -0.9398)
			(stroke
				(width 0)
				(type default)
			)
			(fill no)
			(layer "B.CrtYd")
		)
		(fp_rect
			(start 0.508 0.9398)
			(end -0.508 -0.9398)
			(stroke
				(width 0)
				(type default)
			)
			(fill no)
			(layer "B.Fab")
		)
		(pad "1" smd custom
			(at 0 -0.4445 270)
			(size 0.1397 0.1397)
			(layers "B.Cu" "B.Mask" "B.Paste")
			(net "FM_MEZZB_PRSNT1_N")
			(options
				(clearance outline)
				(anchor circle)
			)
			(primitives
				(gr_poly
					(pts
						(arc
							(start -0.1778 0.2794)
							(mid -0.249642 0.249642)
							(end -0.2794 0.1778)
						)
						(arc
							(start -0.2794 -0.1778)
							(mid -0.249642 -0.249642)
							(end -0.1778 -0.2794)
						)
						(arc
							(start 0.1778 -0.2794)
							(mid 0.249642 -0.249642)
							(end 0.2794 -0.1778)
						)
						(arc
							(start 0.2794 0.1778)
							(mid 0.249642 0.249642)
							(end 0.1778 0.2794)
						)
					)
					(width 0)
					(fill yes)
				)
			)
		)
		(pad "2" smd custom
			(at 0 0.4445 270)
			(size 0.1397 0.1397)
			(layers "B.Cu" "B.Mask" "B.Paste")
			(net "GND")
			(options
				(clearance outline)
				(anchor circle)
			)
			(primitives
				(gr_poly
					(pts
						(arc
							(start -0.1778 0.2794)
							(mid -0.249642 0.249642)
							(end -0.2794 0.1778)
						)
						(arc
							(start -0.2794 -0.1778)
							(mid -0.249642 -0.249642)
							(end -0.1778 -0.2794)
						)
						(arc
							(start 0.1778 -0.2794)
							(mid 0.249642 -0.249642)
							(end 0.2794 -0.1778)
						)
						(arc
							(start 0.2794 0.1778)
							(mid 0.249642 0.249642)
							(end 0.1778 0.2794)
						)
					)
					(width 0)
					(fill yes)
				)
			)
		)
	)
	(footprint ""
		(layer "B.Cu")
		(at 198.803768 -77.613002 90)
		(property "Reference" "C4D6"
			(at 0 0 90)
			(layer "B.SilkS")
			(hide yes)
			(effects
				(font
					(size 1.27 1.27)
				)
				(justify mirror)
			)
		)
		(property "Value" "*"
			(at -1.1811 -2.8194 90)
			(unlocked yes)
			(layer "B.Fab")
			(hide yes)
			(effects
				(font
					(size 1.27 1.016)
					(thickness 0.1524)
				)
				(justify mirror)
			)
		)
		(property "Device Type" "SC1U10V2KX-4-GP_SMD-BCG6-SC1U1A"
			(at -1.1811 -4.3434 90)
			(unlocked yes)
			(layer "B.Fab")
			(hide yes)
			(effects
				(font
					(size 1.27 1.016)
					(thickness 0.1524)
				)
				(justify mirror)
			)
		)
		(duplicate_pad_numbers_are_jumpers no)
		(fp_rect
			(start 0.4318 0.9525)
			(end -0.4318 -0.9525)
			(stroke
				(width 0)
				(type default)
			)
			(fill no)
			(layer "B.CrtYd")
		)
		(fp_rect
			(start 0.4318 0.9525)
			(end -0.4318 -0.9525)
			(stroke
				(width 0)
				(type default)
			)
			(fill no)
			(layer "B.Fab")
		)
		(pad "1" smd custom
			(at 0 -0.4445 270)
			(size 0.1524 0.1524)
			(layers "B.Cu" "B.Mask" "B.Paste")
			(net "P5V_STBY")
			(options
				(clearance outline)
				(anchor circle)
			)
			(primitives
				(gr_poly
					(pts
						(arc
							(start 0.3048 0.2032)
							(mid 0.275042 0.275042)
							(end 0.2032 0.3048)
						)
						(arc
							(start -0.2032 0.3048)
							(mid -0.275042 0.275042)
							(end -0.3048 0.2032)
						)
						(arc
							(start -0.3048 -0.2032)
							(mid -0.275042 -0.275042)
							(end -0.2032 -0.3048)
						)
						(arc
							(start 0.2032 -0.3048)
							(mid 0.275042 -0.275042)
							(end 0.3048 -0.2032)
						)
					)
					(width 0)
					(fill yes)
				)
			)
		)
		(pad "2" smd custom
			(at 0 0.4445 270)
			(size 0.1524 0.1524)
			(layers "B.Cu" "B.Mask" "B.Paste")
			(net "GND")
			(options
				(clearance outline)
				(anchor circle)
			)
			(primitives
				(gr_poly
					(pts
						(arc
							(start 0.3048 0.2032)
							(mid 0.275042 0.275042)
							(end 0.2032 0.3048)
						)
						(arc
							(start -0.2032 0.3048)
							(mid -0.275042 0.275042)
							(end -0.3048 0.2032)
						)
						(arc
							(start -0.3048 -0.2032)
							(mid -0.275042 -0.275042)
							(end -0.2032 -0.3048)
						)
						(arc
							(start 0.2032 -0.3048)
							(mid 0.275042 -0.275042)
							(end 0.3048 -0.2032)
						)
					)
					(width 0)
					(fill yes)
				)
			)
		)
	)
	(footprint ""
		(layer "B.Cu")
		(at 210.847432 -67.945 -90)
		(property "Reference" "C6P23"
			(at 0.53467 -4.036568 0)
			(unlocked yes)
			(layer "B.SilkS")
			(effects
				(font
					(size 0.7874 0.5842)
					(thickness 0.1524)
				)
				(justify mirror)
			)
		)
		(property "Value" ""
			(at 0 0 90)
			(layer "B.Fab")
			(effects
				(font
					(size 1.27 1.27)
				)
				(justify mirror)
			)
		)
		(duplicate_pad_numbers_are_jumpers no)
		(fp_line
			(start -2.286 7.366)
			(end -1.600708 7.366)
			(stroke
				(width 0.1524)
				(type default)
			)
			(layer "B.SilkS")
		)
		(fp_line
			(start -2.286 7.366)
			(end -2.286 1.63195)
			(stroke
				(width 0.1524)
				(type default)
			)
			(layer "B.SilkS")
		)
		(fp_line
			(start 2.286 7.366)
			(end 1.60147 7.366)
			(stroke
				(width 0.1524)
				(type default)
			)
			(layer "B.SilkS")
		)
		(fp_line
			(start 2.286 7.366)
			(end 2.286 1.632712)
			(stroke
				(width 0.1524)
				(type default)
			)
			(layer "B.SilkS")
		)
		(fp_line
			(start -2.504948 1.633728)
			(end -1.6002 1.633728)
			(stroke
				(width 0.1524)
				(type default)
			)
			(layer "B.SilkS")
		)
		(fp_line
			(start 2.563114 1.633728)
			(end 1.6002 1.633728)
			(stroke
				(width 0.1524)
				(type default)
			)
			(layer "B.SilkS")
		)
		(fp_line
			(start -2.504948 -1.616456)
			(end -2.504948 1.633728)
			(stroke
				(width 0.1524)
				(type default)
			)
			(layer "B.SilkS")
		)
		(fp_line
			(start -1.6002 -1.616456)
			(end -2.504948 -1.616456)
			(stroke
				(width 0.1524)
				(type default)
			)
			(layer "B.SilkS")
		)
		(fp_line
			(start 1.6002 -1.616456)
			(end 2.563114 -1.616456)
			(stroke
				(width 0.1524)
				(type default)
			)
			(layer "B.SilkS")
		)
		(fp_line
			(start 2.563114 -1.616456)
			(end 2.563114 1.633728)
			(stroke
				(width 0.1524)
				(type default)
			)
			(layer "B.SilkS")
		)
		(fp_rect
			(start 2.286 7.366)
			(end -2.286 -0.254)
			(stroke
				(width 0)
				(type default)
			)
			(fill no)
			(layer "B.CrtYd")
		)
		(fp_line
			(start -2.286 7.366)
			(end 2.286 7.366)
			(stroke
				(width 0.1)
				(type default)
			)
			(layer "B.Fab")
		)
		(fp_line
			(start 2.286 7.366)
			(end 2.286 -0.254)
			(stroke
				(width 0.1)
				(type default)
			)
			(layer "B.Fab")
		)
		(fp_line
			(start -2.286 -0.254)
			(end -2.286 7.366)
			(stroke
				(width 0.1)
				(type default)
			)
			(layer "B.Fab")
		)
		(fp_line
			(start 2.286 -0.254)
			(end -2.286 -0.254)
			(stroke
				(width 0.1)
				(type default)
			)
			(layer "B.Fab")
		)
		(pad "1" smd rect
			(at 0 0 90)
			(size 2.54 3.048)
			(layers "B.Cu" "B.Mask" "B.Paste")
			(net "PVCCIN_CPU0")
		)
		(pad "2" smd rect
			(at 0 7.112 90)
			(size 2.54 3.048)
			(layers "B.Cu" "B.Mask" "B.Paste")
			(net "GND")
		)
	)
	(footprint ""
		(layer "B.Cu")
		(at 276.000464 -8.1534 90)
		(property "Reference" "C5U2"
			(at -1.848866 0.752348 90)
			(unlocked yes)
			(layer "B.SilkS")
			(effects
				(font
					(size 1.27 0.9652)
					(thickness 0.1524)
				)
				(justify mirror)
			)
		)
		(property "Value" ""
			(at 0 0 90)
			(layer "B.Fab")
			(effects
				(font
					(size 1.27 1.27)
				)
				(justify mirror)
			)
		)
		(duplicate_pad_numbers_are_jumpers no)
		(fp_rect
			(start 0.500126 1.598422)
			(end -0.500126 -0.201422)
			(stroke
				(width 0)
				(type default)
			)
			(fill no)
			(layer "B.CrtYd")
		)
		(fp_line
			(start 0.500126 -0.201422)
			(end -0.500126 -0.201422)
			(stroke
				(width 0.1)
				(type default)
			)
			(layer "B.Fab")
		)
		(fp_line
			(start -0.500126 -0.201422)
			(end -0.500126 1.598422)
			(stroke
				(width 0.1)
				(type default)
			)
			(layer "B.Fab")
		)
		(fp_line
			(start 0.500126 1.598422)
			(end 0.500126 -0.201422)
			(stroke
				(width 0.1)
				(type default)
			)
			(layer "B.Fab")
		)
		(fp_line
			(start -0.500126 1.598422)
			(end 0.500126 1.598422)
			(stroke
				(width 0.1)
				(type default)
			)
			(layer "B.Fab")
		)
		(pad "1" smd rect
			(at 0 0)
			(size 0.889 0.9906)
			(layers "B.Cu" "B.Mask" "B.Paste")
			(net "PVDDQ_ABC")
		)
		(pad "2" smd rect
			(at 0 1.397)
			(size 0.889 0.9906)
			(layers "B.Cu" "B.Mask" "B.Paste")
			(net "GND")
		)
		(zone
			(layer "B.Cu")
			(hatch none 0.5)
			(connect_pads
				(clearance 0)
			)
			(min_thickness 0.25)
			(keepout
				(tracks allowed)
				(vias not_allowed)
				(pads allowed)
				(copperpour not_allowed)
				(footprints allowed)
			)
			(placement
				(enabled no)
				(sheetname "")
			)
			(fill
				(thermal_gap 0.5)
				(thermal_bridge_width 0.5)
				(island_removal_mode 0)
			)
			(polygon
				(pts
					(xy 276.952964 -8.6487) (xy 276.444964 -8.6487) (xy 276.444964 -7.6581) (xy 276.952964 -7.6581)
				)
			)
		)
		(zone
			(layer "B.Cu")
			(hatch none 0.5)
			(connect_pads
				(clearance 0)
			)
			(min_thickness 0.25)
			(keepout
				(tracks not_allowed)
				(vias allowed)
				(pads allowed)
				(copperpour not_allowed)
				(footprints allowed)
			)
			(placement
				(enabled no)
				(sheetname "")
			)
			(fill
				(thermal_gap 0.5)
				(thermal_bridge_width 0.5)
				(island_removal_mode 0)
			)
			(polygon
				(pts
					(xy 276.952964 -8.6487) (xy 276.444964 -8.6487) (xy 276.444964 -7.6581) (xy 276.952964 -7.6581)
				)
			)
		)
	)
	(footprint ""
		(layer "B.Cu")
		(at 153.797 1.7018 -90)
		(property "Reference" "C7U6"
			(at 0 0 90)
			(layer "B.SilkS")
			(hide yes)
			(effects
				(font
					(size 1.27 1.27)
				)
				(justify mirror)
			)
		)
		(property "Value" ""
			(at 0 0 90)
			(layer "B.Fab")
			(effects
				(font
					(size 1.27 1.27)
				)
				(justify mirror)
			)
		)
		(duplicate_pad_numbers_are_jumpers no)
		(fp_poly
			(pts
				(xy 0.4953 -0.2032) (xy -0.4953 -0.2032) (xy -0.4953 1.6002) (xy 0.4953 1.6002)
			)
			(stroke
				(width 0)
				(type default)
			)
			(fill no)
			(layer "B.CrtYd")
		)
		(fp_line
			(start -0.4953 1.6002)
			(end 0.4953 1.6002)
			(stroke
				(width 0.1)
				(type default)
			)
			(layer "B.Fab")
		)
		(fp_line
			(start 0.4953 1.6002)
			(end 0.4953 -0.2032)
			(stroke
				(width 0.1)
				(type default)
			)
			(layer "B.Fab")
		)
		(fp_line
			(start -0.4953 -0.2032)
			(end -0.4953 1.6002)
			(stroke
				(width 0.1)
				(type default)
			)
			(layer "B.Fab")
		)
		(fp_line
			(start 0.4953 -0.2032)
			(end -0.4953 -0.2032)
			(stroke
				(width 0.1)
				(type default)
			)
			(layer "B.Fab")
		)
		(pad "1" smd rect
			(at 0 0 90)
			(size 0.762 0.889)
			(layers "B.Cu" "B.Mask" "B.Paste")
			(net "PVPP_GHJ")
		)
		(pad "2" smd rect
			(at 0 1.397 90)
			(size 0.762 0.889)
			(layers "B.Cu" "B.Mask" "B.Paste")
			(net "GND")
		)
		(zone
			(layer "B.Cu")
			(hatch none 0.5)
			(connect_pads
				(clearance 0)
			)
			(min_thickness 0.25)
			(keepout
				(tracks not_allowed)
				(vias allowed)
				(pads allowed)
				(copperpour not_allowed)
				(footprints allowed)
			)
			(placement
				(enabled no)
				(sheetname "")
			)
			(fill
				(thermal_gap 0.5)
				(thermal_bridge_width 0.5)
				(island_removal_mode 0)
			)
			(polygon
				(pts
					(xy 153.3525 2.0828) (xy 153.3525 1.3208) (xy 152.8445 1.3208) (xy 152.8445 2.0828)
				)
			)
		)
	)
	(footprint ""
		(layer "B.Cu")
		(at 450.215 -116.49202)
		(property "Reference" "C1M16"
			(at 0 0 0)
			(layer "B.SilkS")
			(hide yes)
			(effects
				(font
					(size 1.27 1.27)
				)
				(justify mirror)
			)
		)
		(property "Value" ""
			(at 0 0 0)
			(layer "B.Fab")
			(effects
				(font
					(size 1.27 1.27)
				)
				(justify mirror)
			)
		)
		(duplicate_pad_numbers_are_jumpers no)
		(fp_rect
			(start -0.3048 0.9906)
			(end 0.3048 -0.1016)
			(stroke
				(width 0)
				(type default)
			)
			(fill no)
			(layer "B.CrtYd")
		)
		(fp_line
			(start -0.3048 -0.1016)
			(end 0.3048 -0.1016)
			(stroke
				(width 0.1)
				(type default)
			)
			(layer "B.Fab")
		)
		(fp_line
			(start -0.3048 0.9906)
			(end -0.3048 -0.1016)
			(stroke
				(width 0.1)
				(type default)
			)
			(layer "B.Fab")
		)
		(fp_line
			(start 0.3048 -0.1016)
			(end 0.3048 0.9906)
			(stroke
				(width 0.1)
				(type default)
			)
			(layer "B.Fab")
		)
		(fp_line
			(start 0.3048 0.9906)
			(end -0.3048 0.9906)
			(stroke
				(width 0.1)
				(type default)
			)
			(layer "B.Fab")
		)
		(pad "1" smd rect
			(at 0 0 180)
			(size 0.508 0.508)
			(layers "B.Cu" "B.Mask" "B.Paste")
			(net "P3E_CPU0_PE3_OCP_TXP<10>")
		)
		(pad "2" smd rect
			(at 0 0.889 180)
			(size 0.508 0.508)
			(layers "B.Cu" "B.Mask" "B.Paste")
			(net "P3E_OCP_CPU0_PE3_C_TXP<10>")
		)
		(zone
			(layer "B.Cu")
			(hatch none 0.5)
			(connect_pads
				(clearance 0)
			)
			(min_thickness 0.25)
			(keepout
				(tracks not_allowed)
				(vias allowed)
				(pads allowed)
				(copperpour not_allowed)
				(footprints allowed)
			)
			(placement
				(enabled no)
				(sheetname "")
			)
			(fill
				(thermal_gap 0.5)
				(thermal_bridge_width 0.5)
				(island_removal_mode 0)
			)
			(polygon
				(pts
					(xy 449.961 -115.85702) (xy 450.469 -115.85702) (xy 450.469 -116.23802) (xy 449.961 -116.23802)
				)
			)
		)
		(zone
			(layer "B.Cu")
			(hatch none 0.5)
			(connect_pads
				(clearance 0)
			)
			(min_thickness 0.25)
			(keepout
				(tracks allowed)
				(vias not_allowed)
				(pads allowed)
				(copperpour not_allowed)
				(footprints allowed)
			)
			(placement
				(enabled no)
				(sheetname "")
			)
			(fill
				(thermal_gap 0.5)
				(thermal_bridge_width 0.5)
				(island_removal_mode 0)
			)
			(polygon
				(pts
					(xy 449.961 -115.85702) (xy 450.469 -115.85702) (xy 450.469 -116.23802) (xy 449.961 -116.23802)
				)
			)
		)
	)
	(footprint ""
		(layer "B.Cu")
		(at 348.2086 -8.8138 -90)
		(property "Reference" "R3U6"
			(at 0 0 90)
			(layer "B.SilkS")
			(hide yes)
			(effects
				(font
					(size 1.27 1.27)
				)
				(justify mirror)
			)
		)
		(property "Value" ""
			(at 0 0 90)
			(layer "B.Fab")
			(effects
				(font
					(size 1.27 1.27)
				)
				(justify mirror)
			)
		)
		(duplicate_pad_numbers_are_jumpers no)
		(fp_rect
			(start -0.2794 0.9906)
			(end 0.2794 -0.1016)
			(stroke
				(width 0)
				(type default)
			)
			(fill no)
			(layer "B.CrtYd")
		)
		(fp_line
			(start -0.2794 0.9906)
			(end -0.2794 -0.1016)
			(stroke
				(width 0.1)
				(type default)
			)
			(layer "B.Fab")
		)
		(fp_line
			(start 0.2794 0.9906)
			(end -0.2794 0.9906)
			(stroke
				(width 0.1)
				(type default)
			)
			(layer "B.Fab")
		)
		(fp_line
			(start -0.2794 -0.1016)
			(end 0.2794 -0.1016)
			(stroke
				(width 0.1)
				(type default)
			)
			(layer "B.Fab")
		)
		(fp_line
			(start 0.2794 -0.1016)
			(end 0.2794 0.9906)
			(stroke
				(width 0.1)
				(type default)
			)
			(layer "B.Fab")
		)
		(pad "1" smd rect
			(at 0 0 90)
			(size 0.508 0.508)
			(layers "B.Cu" "B.Mask" "B.Paste")
			(net "VR_PVDDQ_ABC_PH1_VCIN")
		)
		(pad "2" smd rect
			(at 0 0.889 90)
			(size 0.508 0.508)
			(layers "B.Cu" "B.Mask" "B.Paste")
			(net "P5V_STBY")
		)
		(zone
			(layer "B.Cu")
			(hatch none 0.5)
			(connect_pads
				(clearance 0)
			)
			(min_thickness 0.25)
			(keepout
				(tracks not_allowed)
				(vias allowed)
				(pads allowed)
				(copperpour not_allowed)
				(footprints allowed)
			)
			(placement
				(enabled no)
				(sheetname "")
			)
			(fill
				(thermal_gap 0.5)
				(thermal_bridge_width 0.5)
				(island_removal_mode 0)
			)
			(polygon
				(pts
					(xy 347.5736 -9.0678) (xy 347.5736 -8.5598) (xy 347.9546 -8.5598) (xy 347.9546 -9.0678)
				)
			)
		)
		(zone
			(layer "B.Cu")
			(hatch none 0.5)
			(connect_pads
				(clearance 0)
			)
			(min_thickness 0.25)
			(keepout
				(tracks allowed)
				(vias not_allowed)
				(pads allowed)
				(copperpour not_allowed)
				(footprints allowed)
			)
			(placement
				(enabled no)
				(sheetname "")
			)
			(fill
				(thermal_gap 0.5)
				(thermal_bridge_width 0.5)
				(island_removal_mode 0)
			)
			(polygon
				(pts
					(xy 347.5736 -9.0678) (xy 347.5736 -8.5598) (xy 347.9546 -8.5598) (xy 347.9546 -9.0678)
				)
			)
		)
	)
	(footprint ""
		(layer "B.Cu")
		(at 168.0972 -7.366)
		(property "Reference" "R6U3"
			(at 0 0 0)
			(layer "B.SilkS")
			(hide yes)
			(effects
				(font
					(size 1.27 1.27)
				)
				(justify mirror)
			)
		)
		(property "Value" ""
			(at 0 0 0)
			(layer "B.Fab")
			(effects
				(font
					(size 1.27 1.27)
				)
				(justify mirror)
			)
		)
		(duplicate_pad_numbers_are_jumpers no)
		(fp_rect
			(start -0.2794 -0.1016)
			(end 0.2794 0.9906)
			(stroke
				(width 0)
				(type default)
			)
			(fill no)
			(layer "B.CrtYd")
		)
		(fp_line
			(start -0.2794 -0.1016)
			(end 0.2794 -0.1016)
			(stroke
				(width 0.1)
				(type default)
			)
			(layer "B.Fab")
		)
		(fp_line
			(start -0.2794 0.9906)
			(end -0.2794 -0.1016)
			(stroke
				(width 0.1)
				(type default)
			)
			(layer "B.Fab")
		)
		(fp_line
			(start 0.2794 -0.1016)
			(end 0.2794 0.9906)
			(stroke
				(width 0.1)
				(type default)
			)
			(layer "B.Fab")
		)
		(fp_line
			(start 0.2794 0.9906)
			(end -0.2794 0.9906)
			(stroke
				(width 0.1)
				(type default)
			)
			(layer "B.Fab")
		)
		(pad "1" smd rect
			(at 0 0 180)
			(size 0.508 0.508)
			(layers "B.Cu" "B.Mask" "B.Paste")
			(net "P3V3")
		)
		(pad "2" smd rect
			(at 0 0.889 180)
			(size 0.508 0.508)
			(layers "B.Cu" "B.Mask" "B.Paste")
			(net "FM_PVTT_GHJ_EN_R")
		)
		(zone
			(layer "B.Cu")
			(hatch none 0.5)
			(connect_pads
				(clearance 0)
			)
			(min_thickness 0.25)
			(keepout
				(tracks not_allowed)
				(vias allowed)
				(pads allowed)
				(copperpour not_allowed)
				(footprints allowed)
			)
			(placement
				(enabled no)
				(sheetname "")
			)
			(fill
				(thermal_gap 0.5)
				(thermal_bridge_width 0.5)
				(island_removal_mode 0)
			)
			(polygon
				(pts
					(xy 167.8432 -7.112) (xy 167.8432 -6.731) (xy 168.3512 -6.731) (xy 168.3512 -7.112)
				)
			)
		)
		(zone
			(layer "B.Cu")
			(hatch none 0.5)
			(connect_pads
				(clearance 0)
			)
			(min_thickness 0.25)
			(keepout
				(tracks allowed)
				(vias not_allowed)
				(pads allowed)
				(copperpour not_allowed)
				(footprints allowed)
			)
			(placement
				(enabled no)
				(sheetname "")
			)
			(fill
				(thermal_gap 0.5)
				(thermal_bridge_width 0.5)
				(island_removal_mode 0)
			)
			(polygon
				(pts
					(xy 167.8432 -7.112) (xy 167.8432 -6.731) (xy 168.3512 -6.731) (xy 168.3512 -7.112)
				)
			)
		)
	)
	(footprint ""
		(layer "B.Cu")
		(at 411.099 -142.0368 -90)
		(property "Reference" "C2L38"
			(at 0 0 90)
			(layer "B.SilkS")
			(hide yes)
			(effects
				(font
					(size 1.27 1.27)
				)
				(justify mirror)
			)
		)
		(property "Value" ""
			(at 0 0 90)
			(layer "B.Fab")
			(effects
				(font
					(size 1.27 1.27)
				)
				(justify mirror)
			)
		)
		(duplicate_pad_numbers_are_jumpers no)
		(fp_poly
			(pts
				(xy -0.3048 -0.1016) (xy -0.3048 0.9906) (xy 0.3048 0.9906) (xy 0.3048 -0.1016)
			)
			(stroke
				(width 0)
				(type default)
			)
			(fill no)
			(layer "B.CrtYd")
		)
		(fp_line
			(start -0.3048 0.9906)
			(end -0.3048 -0.1016)
			(stroke
				(width 0.1)
				(type default)
			)
			(layer "B.Fab")
		)
		(fp_line
			(start 0.3048 0.9906)
			(end -0.3048 0.9906)
			(stroke
				(width 0.1)
				(type default)
			)
			(layer "B.Fab")
		)
		(fp_line
			(start -0.3048 -0.1016)
			(end 0.3048 -0.1016)
			(stroke
				(width 0.1)
				(type default)
			)
			(layer "B.Fab")
		)
		(fp_line
			(start 0.3048 -0.1016)
			(end 0.3048 0.9906)
			(stroke
				(width 0.1)
				(type default)
			)
			(layer "B.Fab")
		)
		(pad "1" smd rect
			(at 0 0 90)
			(size 0.508 0.508)
			(layers "B.Cu" "B.Mask" "B.Paste")
			(net "SATA6G_P6_TX_C_DN")
		)
		(pad "2" smd rect
			(at 0 0.889 90)
			(size 0.508 0.508)
			(layers "B.Cu" "B.Mask" "B.Paste")
			(net "SATA6G_PCH_PCIE_UP_SATA_TXN<6>")
		)
		(zone
			(layer "B.Cu")
			(hatch none 0.5)
			(connect_pads
				(clearance 0)
			)
			(min_thickness 0.25)
			(keepout
				(tracks not_allowed)
				(vias allowed)
				(pads allowed)
				(copperpour not_allowed)
				(footprints allowed)
			)
			(placement
				(enabled no)
				(sheetname "")
			)
			(fill
				(thermal_gap 0.5)
				(thermal_bridge_width 0.5)
				(island_removal_mode 0)
			)
			(polygon
				(pts
					(xy 410.464 -141.7828) (xy 410.464 -142.2908) (xy 410.845 -142.2908) (xy 410.845 -141.7828)
				)
			)
		)
		(zone
			(layer "B.Cu")
			(hatch none 0.5)
			(connect_pads
				(clearance 0)
			)
			(min_thickness 0.25)
			(keepout
				(tracks allowed)
				(vias not_allowed)
				(pads allowed)
				(copperpour not_allowed)
				(footprints allowed)
			)
			(placement
				(enabled no)
				(sheetname "")
			)
			(fill
				(thermal_gap 0.5)
				(thermal_bridge_width 0.5)
				(island_removal_mode 0)
			)
			(polygon
				(pts
					(xy 410.845 -141.7828) (xy 410.845 -142.2908) (xy 410.464 -142.2908) (xy 410.464 -141.7828)
				)
			)
		)
	)
	(footprint ""
		(layer "B.Cu")
		(at 111.000032 -8.1534 90)
		(property "Reference" "C7U1"
			(at -1.848866 0.752348 90)
			(unlocked yes)
			(layer "B.SilkS")
			(effects
				(font
					(size 1.27 0.9652)
					(thickness 0.1524)
				)
				(justify mirror)
			)
		)
		(property "Value" ""
			(at 0 0 90)
			(layer "B.Fab")
			(effects
				(font
					(size 1.27 1.27)
				)
				(justify mirror)
			)
		)
		(duplicate_pad_numbers_are_jumpers no)
		(fp_rect
			(start 0.500126 1.598422)
			(end -0.500126 -0.201422)
			(stroke
				(width 0)
				(type default)
			)
			(fill no)
			(layer "B.CrtYd")
		)
		(fp_line
			(start 0.500126 -0.201422)
			(end -0.500126 -0.201422)
			(stroke
				(width 0.1)
				(type default)
			)
			(layer "B.Fab")
		)
		(fp_line
			(start -0.500126 -0.201422)
			(end -0.500126 1.598422)
			(stroke
				(width 0.1)
				(type default)
			)
			(layer "B.Fab")
		)
		(fp_line
			(start 0.500126 1.598422)
			(end 0.500126 -0.201422)
			(stroke
				(width 0.1)
				(type default)
			)
			(layer "B.Fab")
		)
		(fp_line
			(start -0.500126 1.598422)
			(end 0.500126 1.598422)
			(stroke
				(width 0.1)
				(type default)
			)
			(layer "B.Fab")
		)
		(pad "1" smd rect
			(at 0 0)
			(size 0.889 0.9906)
			(layers "B.Cu" "B.Mask" "B.Paste")
			(net "PVDDQ_GHJ")
		)
		(pad "2" smd rect
			(at 0 1.397)
			(size 0.889 0.9906)
			(layers "B.Cu" "B.Mask" "B.Paste")
			(net "GND")
		)
		(zone
			(layer "B.Cu")
			(hatch none 0.5)
			(connect_pads
				(clearance 0)
			)
			(min_thickness 0.25)
			(keepout
				(tracks not_allowed)
				(vias allowed)
				(pads allowed)
				(copperpour not_allowed)
				(footprints allowed)
			)
			(placement
				(enabled no)
				(sheetname "")
			)
			(fill
				(thermal_gap 0.5)
				(thermal_bridge_width 0.5)
				(island_removal_mode 0)
			)
			(polygon
				(pts
					(xy 111.952532 -8.6487) (xy 111.444532 -8.6487) (xy 111.444532 -7.6581) (xy 111.952532 -7.6581)
				)
			)
		)
		(zone
			(layer "B.Cu")
			(hatch none 0.5)
			(connect_pads
				(clearance 0)
			)
			(min_thickness 0.25)
			(keepout
				(tracks allowed)
				(vias not_allowed)
				(pads allowed)
				(copperpour not_allowed)
				(footprints allowed)
			)
			(placement
				(enabled no)
				(sheetname "")
			)
			(fill
				(thermal_gap 0.5)
				(thermal_bridge_width 0.5)
				(island_removal_mode 0)
			)
			(polygon
				(pts
					(xy 111.952532 -8.6487) (xy 111.444532 -8.6487) (xy 111.444532 -7.6581) (xy 111.952532 -7.6581)
				)
			)
		)
	)
	(footprint ""
		(layer "B.Cu")
		(at 367.827814 -125.507242 -90)
		(property "Reference" "R782"
			(at 0.8382 -0.67818 270)
			(unlocked yes)
			(layer "B.SilkS")
			(effects
				(font
					(size 0.4064 0.254)
					(thickness 0.1524)
				)
				(justify left mirror)
			)
		)
		(property "Value" ""
			(at 0 0 90)
			(layer "B.Fab")
			(effects
				(font
					(size 1.27 1.27)
				)
				(justify mirror)
			)
		)
		(duplicate_pad_numbers_are_jumpers no)
		(fp_poly
			(pts
				(xy 0.2794 -0.1016) (xy -0.2794 -0.1016) (xy -0.2794 0.9906) (xy 0.2794 0.9906)
			)
			(stroke
				(width 0)
				(type default)
			)
			(fill no)
			(layer "B.CrtYd")
		)
		(fp_line
			(start -0.2794 0.9906)
			(end -0.2794 -0.1016)
			(stroke
				(width 0.1)
				(type default)
			)
			(layer "B.Fab")
		)
		(fp_line
			(start 0.2794 0.9906)
			(end -0.2794 0.9906)
			(stroke
				(width 0.1)
				(type default)
			)
			(layer "B.Fab")
		)
		(fp_line
			(start -0.2794 -0.1016)
			(end 0.2794 -0.1016)
			(stroke
				(width 0.1)
				(type default)
			)
			(layer "B.Fab")
		)
		(fp_line
			(start 0.2794 -0.1016)
			(end 0.2794 0.9906)
			(stroke
				(width 0.1)
				(type default)
			)
			(layer "B.Fab")
		)
		(pad "1" smd rect
			(at 0 0 90)
			(size 0.508 0.508)
			(layers "B.Cu" "B.Mask" "B.Paste")
			(net "P3E_CPU0_PE1_PCH_RXN<9>")
		)
		(pad "2" smd rect
			(at 0 0.889 90)
			(size 0.508 0.508)
			(layers "B.Cu" "B.Mask" "B.Paste")
			(net "P3E_CPU0_PE1_PCH_CON_RXN<9>")
		)
		(zone
			(layer "B.Cu")
			(hatch none 0.5)
			(connect_pads
				(clearance 0)
			)
			(min_thickness 0.25)
			(keepout
				(tracks not_allowed)
				(vias allowed)
				(pads allowed)
				(copperpour not_allowed)
				(footprints allowed)
			)
			(placement
				(enabled no)
				(sheetname "")
			)
			(fill
				(thermal_gap 0.5)
				(thermal_bridge_width 0.5)
				(island_removal_mode 0)
			)
			(polygon
				(pts
					(xy 367.192814 -125.253242) (xy 367.192814 -125.761242) (xy 367.573814 -125.761242) (xy 367.573814 -125.253242)
				)
			)
		)
		(zone
			(layer "B.Cu")
			(hatch none 0.5)
			(connect_pads
				(clearance 0)
			)
			(min_thickness 0.25)
			(keepout
				(tracks allowed)
				(vias not_allowed)
				(pads allowed)
				(copperpour not_allowed)
				(footprints allowed)
			)
			(placement
				(enabled no)
				(sheetname "")
			)
			(fill
				(thermal_gap 0.5)
				(thermal_bridge_width 0.5)
				(island_removal_mode 0)
			)
			(polygon
				(pts
					(xy 367.573814 -125.253242) (xy 367.573814 -125.761242) (xy 367.192814 -125.761242) (xy 367.192814 -125.253242)
				)
			)
		)
	)
	(footprint ""
		(layer "B.Cu")
		(at 279.046686 -79.60614 180)
		(property "Reference" "C4P2"
			(at 0 0 0)
			(layer "B.SilkS")
			(hide yes)
			(effects
				(font
					(size 1.27 1.27)
				)
				(justify mirror)
			)
		)
		(property "Value" ""
			(at 0 0 0)
			(layer "B.Fab")
			(effects
				(font
					(size 1.27 1.27)
				)
				(justify mirror)
			)
		)
		(duplicate_pad_numbers_are_jumpers no)
		(fp_poly
			(pts
				(xy 0.7239 -0.2159) (xy -0.7239 -0.2159) (xy -0.7239 1.9939) (xy 0.7239 1.9939)
			)
			(stroke
				(width 0)
				(type default)
			)
			(fill no)
			(layer "B.CrtYd")
		)
		(fp_line
			(start 0.7239 1.9939)
			(end -0.7239 1.9939)
			(stroke
				(width 0.1)
				(type default)
			)
			(layer "B.Fab")
		)
		(fp_line
			(start 0.7239 -0.2159)
			(end 0.7239 1.9939)
			(stroke
				(width 0.1)
				(type default)
			)
			(layer "B.Fab")
		)
		(fp_line
			(start -0.7239 1.9939)
			(end -0.7239 -0.2159)
			(stroke
				(width 0.1)
				(type default)
			)
			(layer "B.Fab")
		)
		(fp_line
			(start -0.7239 -0.2159)
			(end 0.7239 -0.2159)
			(stroke
				(width 0.1)
				(type default)
			)
			(layer "B.Fab")
		)
		(pad "1" smd rect
			(at 0 0)
			(size 1.27 1.016)
			(layers "B.Cu" "B.Mask" "B.Paste")
			(net "PVCCMCP_CPU0")
		)
		(pad "2" smd rect
			(at 0 1.778)
			(size 1.27 1.016)
			(layers "B.Cu" "B.Mask" "B.Paste")
			(net "GND")
		)
		(zone
			(layer "B.Cu")
			(hatch none 0.5)
			(connect_pads
				(clearance 0)
			)
			(min_thickness 0.25)
			(keepout
				(tracks not_allowed)
				(vias allowed)
				(pads allowed)
				(copperpour not_allowed)
				(footprints allowed)
			)
			(placement
				(enabled no)
				(sheetname "")
			)
			(fill
				(thermal_gap 0.5)
				(thermal_bridge_width 0.5)
				(island_removal_mode 0)
			)
			(polygon
				(pts
					(xy 278.411686 -80.11414) (xy 279.681686 -80.11414) (xy 279.681686 -80.87614) (xy 278.411686 -80.87614)
				)
			)
		)
	)
	(footprint ""
		(layer "B.Cu")
		(at 80.757268 -145.0086 -90)
		(property "Reference" "C8L10"
			(at -1.848866 0.752348 270)
			(unlocked yes)
			(layer "B.SilkS")
			(effects
				(font
					(size 1.27 0.9652)
					(thickness 0.1524)
				)
				(justify mirror)
			)
		)
		(property "Value" ""
			(at 0 0 90)
			(layer "B.Fab")
			(effects
				(font
					(size 1.27 1.27)
				)
				(justify mirror)
			)
		)
		(duplicate_pad_numbers_are_jumpers no)
		(fp_rect
			(start 0.500126 1.598422)
			(end -0.500126 -0.201422)
			(stroke
				(width 0)
				(type default)
			)
			(fill no)
			(layer "B.CrtYd")
		)
		(fp_line
			(start -0.500126 1.598422)
			(end 0.500126 1.598422)
			(stroke
				(width 0.1)
				(type default)
			)
			(layer "B.Fab")
		)
		(fp_line
			(start 0.500126 1.598422)
			(end 0.500126 -0.201422)
			(stroke
				(width 0.1)
				(type default)
			)
			(layer "B.Fab")
		)
		(fp_line
			(start -0.500126 -0.201422)
			(end -0.500126 1.598422)
			(stroke
				(width 0.1)
				(type default)
			)
			(layer "B.Fab")
		)
		(fp_line
			(start 0.500126 -0.201422)
			(end -0.500126 -0.201422)
			(stroke
				(width 0.1)
				(type default)
			)
			(layer "B.Fab")
		)
		(pad "1" smd rect
			(at 0 0 180)
			(size 0.889 0.9906)
			(layers "B.Cu" "B.Mask" "B.Paste")
			(net "PVDDQ_KLM")
		)
		(pad "2" smd rect
			(at 0 1.397 180)
			(size 0.889 0.9906)
			(layers "B.Cu" "B.Mask" "B.Paste")
			(net "GND")
		)
		(zone
			(layer "B.Cu")
			(hatch none 0.5)
			(connect_pads
				(clearance 0)
			)
			(min_thickness 0.25)
			(keepout
				(tracks not_allowed)
				(vias allowed)
				(pads allowed)
				(copperpour not_allowed)
				(footprints allowed)
			)
			(placement
				(enabled no)
				(sheetname "")
			)
			(fill
				(thermal_gap 0.5)
				(thermal_bridge_width 0.5)
				(island_removal_mode 0)
			)
			(polygon
				(pts
					(xy 79.804768 -144.5133) (xy 80.312768 -144.5133) (xy 80.312768 -145.5039) (xy 79.804768 -145.5039)
				)
			)
		)
		(zone
			(layer "B.Cu")
			(hatch none 0.5)
			(connect_pads
				(clearance 0)
			)
			(min_thickness 0.25)
			(keepout
				(tracks allowed)
				(vias not_allowed)
				(pads allowed)
				(copperpour not_allowed)
				(footprints allowed)
			)
			(placement
				(enabled no)
				(sheetname "")
			)
			(fill
				(thermal_gap 0.5)
				(thermal_bridge_width 0.5)
				(island_removal_mode 0)
			)
			(polygon
				(pts
					(xy 79.804768 -144.5133) (xy 80.312768 -144.5133) (xy 80.312768 -145.5039) (xy 79.804768 -145.5039)
				)
			)
		)
	)
	(footprint ""
		(layer "B.Cu")
		(at 476.479616 -140.712952 90)
		(property "Reference" "U6W1"
			(at 0 0 90)
			(layer "B.SilkS")
			(hide yes)
			(effects
				(font
					(size 1.27 1.27)
				)
				(justify mirror)
			)
		)
		(property "Value" "*"
			(at 0 -7.0485 90)
			(unlocked yes)
			(layer "B.Fab")
			(hide yes)
			(effects
				(font
					(size 1.27 1.016)
					(thickness 0.1524)
				)
				(justify mirror)
			)
		)
		(property "Device Type" "TCA9555PWR-GP_DISCRET-GC1-TCA9A"
			(at 0 -8.6995 90)
			(unlocked yes)
			(layer "B.Fab")
			(hide yes)
			(effects
				(font
					(size 1.27 1.016)
					(thickness 0.1524)
				)
				(justify mirror)
			)
		)
		(duplicate_pad_numbers_are_jumpers no)
		(fp_line
			(start 4.2291 -1.397)
			(end -3.81 -1.397)
			(stroke
				(width 0.1524)
				(type default)
			)
			(layer "B.SilkS")
		)
		(fp_line
			(start -3.81 -1.397)
			(end -3.81 1.397)
			(stroke
				(width 0.1524)
				(type default)
			)
			(layer "B.SilkS")
		)
		(fp_line
			(start 4.2291 -0.8001)
			(end 3.429 0)
			(stroke
				(width 0.1524)
				(type default)
			)
			(layer "B.SilkS")
		)
		(fp_line
			(start 3.429 0)
			(end 4.2291 0.8001)
			(stroke
				(width 0.1524)
				(type default)
			)
			(layer "B.SilkS")
		)
		(fp_line
			(start -3.81 1.397)
			(end 4.2291 1.397)
			(stroke
				(width 0.1524)
				(type default)
			)
			(layer "B.SilkS")
		)
		(fp_line
			(start 4.22656 3.81)
			(end 4.2291 1.397)
			(stroke
				(width 0.508)
				(type default)
			)
			(layer "B.SilkS")
		)
		(fp_line
			(start 4.2291 3.937)
			(end 4.2291 -1.397)
			(stroke
				(width 0.1524)
				(type default)
			)
			(layer "B.SilkS")
		)
		(fp_poly
			(pts
				(xy 3.90652 -1.8542) (xy -3.90652 -1.8542) (xy -3.90652 1.8542) (xy 3.90652 1.8542)
			)
			(stroke
				(width 0)
				(type default)
			)
			(fill yes)
			(layer "B.SilkS")
		)
		(fp_poly
			(pts
				(xy 4.2164 3.81) (xy -4.2164 3.81) (xy -4.22656 -3.81) (xy 4.2164 -3.81)
			)
			(stroke
				(width 0)
				(type default)
			)
			(fill no)
			(layer "B.CrtYd")
		)
		(fp_poly
			(pts
				(xy 4.22656 -3.81) (xy -4.22656 -3.81) (xy -4.22656 3.81) (xy 4.22656 3.81)
			)
			(stroke
				(width 0)
				(type default)
			)
			(fill no)
			(layer "B.Fab")
		)
		(pad "1" smd rect
			(at 3.57632 2.8194 270)
			(size 0.3556 1.524)
			(layers "B.Cu" "B.Mask" "B.Paste")
			(net "PCA9555_INT_N")
		)
		(pad "2" smd rect
			(at 2.92608 2.8194 270)
			(size 0.3556 1.524)
			(layers "B.Cu" "B.Mask" "B.Paste")
			(net "PCA9555_A1")
		)
		(pad "3" smd rect
			(at 2.27584 2.8194 270)
			(size 0.3556 1.524)
			(layers "B.Cu" "B.Mask" "B.Paste")
			(net "PCA9555_A2")
		)
		(pad "4" smd rect
			(at 1.6256 2.8194 270)
			(size 0.3556 1.524)
			(layers "B.Cu" "B.Mask" "B.Paste")
			(net "LED_POSTCODE_0_R")
		)
		(pad "5" smd rect
			(at 0.97536 2.8194 270)
			(size 0.3556 1.524)
			(layers "B.Cu" "B.Mask" "B.Paste")
			(net "LED_POSTCODE_1_R")
		)
		(pad "6" smd rect
			(at 0.32512 2.8194 270)
			(size 0.3556 1.524)
			(layers "B.Cu" "B.Mask" "B.Paste")
			(net "LED_POSTCODE_2_R")
		)
		(pad "7" smd rect
			(at -0.32512 2.8194 270)
			(size 0.3556 1.524)
			(layers "B.Cu" "B.Mask" "B.Paste")
			(net "LED_POSTCODE_3_R")
		)
		(pad "8" smd rect
			(at -0.97536 2.8194 270)
			(size 0.3556 1.524)
			(layers "B.Cu" "B.Mask" "B.Paste")
			(net "LED_POSTCODE_4_R")
		)
		(pad "9" smd rect
			(at -1.6256 2.8194 270)
			(size 0.3556 1.524)
			(layers "B.Cu" "B.Mask" "B.Paste")
			(net "LED_POSTCODE_5_R")
		)
		(pad "10" smd rect
			(at -2.27584 2.8194 270)
			(size 0.3556 1.524)
			(layers "B.Cu" "B.Mask" "B.Paste")
			(net "LED_POSTCODE_6_R")
		)
		(pad "11" smd rect
			(at -2.92608 2.8194 270)
			(size 0.3556 1.524)
			(layers "B.Cu" "B.Mask" "B.Paste")
			(net "LED_POSTCODE_7_R")
		)
		(pad "12" smd rect
			(at -3.57632 2.8194 270)
			(size 0.3556 1.524)
			(layers "B.Cu" "B.Mask" "B.Paste")
			(net "GND")
		)
		(pad "13" smd rect
			(at -3.57632 -2.8194 270)
			(size 0.3556 1.524)
			(layers "B.Cu" "B.Mask" "B.Paste")
			(net "FM_DEBUG_RST_BTN_N")
		)
		(pad "14" smd rect
			(at -2.92608 -2.8194 270)
			(size 0.3556 1.524)
			(layers "B.Cu" "B.Mask" "B.Paste")
			(net "FP_PWR_BTN_R_N")
		)
		(pad "15" smd rect
			(at -2.27584 -2.8194 270)
			(size 0.3556 1.524)
			(layers "B.Cu" "B.Mask" "B.Paste")
			(net "PWRGD_SYS_PWROK")
		)
		(pad "16" smd rect
			(at -1.6256 -2.8194 270)
			(size 0.3556 1.524)
			(layers "B.Cu" "B.Mask" "B.Paste")
			(net "RST_PLTRST_N")
		)
		(pad "17" smd rect
			(at -0.97536 -2.8194 270)
			(size 0.3556 1.524)
			(layers "B.Cu" "B.Mask" "B.Paste")
			(net "PWRGD_DSW_PWROK")
		)
		(pad "18" smd rect
			(at -0.32512 -2.8194 270)
			(size 0.3556 1.524)
			(layers "B.Cu" "B.Mask" "B.Paste")
			(net "FM_CPU_CATERR_MSMI_LVT3_N")
		)
		(pad "19" smd rect
			(at 0.32512 -2.8194 270)
			(size 0.3556 1.524)
			(layers "B.Cu" "B.Mask" "B.Paste")
			(net "FM_SLPS3_N")
		)
		(pad "20" smd rect
			(at 0.97536 -2.8194 270)
			(size 0.3556 1.524)
			(layers "B.Cu" "B.Mask" "B.Paste")
			(net "FM_UART_SWITCH_N")
		)
		(pad "21" smd rect
			(at 1.6256 -2.8194 270)
			(size 0.3556 1.524)
			(layers "B.Cu" "B.Mask" "B.Paste")
			(net "PCA9555_A0")
		)
		(pad "22" smd rect
			(at 2.27584 -2.8194 270)
			(size 0.3556 1.524)
			(layers "B.Cu" "B.Mask" "B.Paste")
			(net "SMB_DEBUG_STBY_LVC3_SCL")
		)
		(pad "23" smd rect
			(at 2.92608 -2.8194 270)
			(size 0.3556 1.524)
			(layers "B.Cu" "B.Mask" "B.Paste")
			(net "SMB_DEBUG_STBY_LVC3_SDA")
		)
		(pad "24" smd rect
			(at 3.57632 -2.8194 270)
			(size 0.3556 1.524)
			(layers "B.Cu" "B.Mask" "B.Paste")
			(net "P3V3_STBY")
		)
	)
	(footprint ""
		(layer "B.Cu")
		(at 5.62356 -6.237986 90)
		(property "Reference" "C1G4"
			(at 0 0 90)
			(layer "B.SilkS")
			(hide yes)
			(effects
				(font
					(size 1.27 1.27)
				)
				(justify mirror)
			)
		)
		(property "Value" "*"
			(at -1.1811 -2.8194 90)
			(unlocked yes)
			(layer "B.Fab")
			(hide yes)
			(effects
				(font
					(size 1.27 1.016)
					(thickness 0.1524)
				)
				(justify mirror)
			)
		)
		(property "Device Type" "SC1U10V2KX-4-GP_SMD-BCG6-SC1U1A"
			(at -1.1811 -4.3434 90)
			(unlocked yes)
			(layer "B.Fab")
			(hide yes)
			(effects
				(font
					(size 1.27 1.016)
					(thickness 0.1524)
				)
				(justify mirror)
			)
		)
		(duplicate_pad_numbers_are_jumpers no)
		(fp_rect
			(start 0.4318 0.9525)
			(end -0.4318 -0.9525)
			(stroke
				(width 0)
				(type default)
			)
			(fill no)
			(layer "B.CrtYd")
		)
		(fp_rect
			(start 0.4318 0.9525)
			(end -0.4318 -0.9525)
			(stroke
				(width 0)
				(type default)
			)
			(fill no)
			(layer "B.Fab")
		)
		(pad "1" smd custom
			(at 0 -0.4445 270)
			(size 0.1524 0.1524)
			(layers "B.Cu" "B.Mask" "B.Paste")
			(net "P5V_STBY")
			(options
				(clearance outline)
				(anchor circle)
			)
			(primitives
				(gr_poly
					(pts
						(arc
							(start 0.3048 0.2032)
							(mid 0.275042 0.275042)
							(end 0.2032 0.3048)
						)
						(arc
							(start -0.2032 0.3048)
							(mid -0.275042 0.275042)
							(end -0.3048 0.2032)
						)
						(arc
							(start -0.3048 -0.2032)
							(mid -0.275042 -0.275042)
							(end -0.2032 -0.3048)
						)
						(arc
							(start 0.2032 -0.3048)
							(mid 0.275042 -0.275042)
							(end 0.3048 -0.2032)
						)
					)
					(width 0)
					(fill yes)
				)
			)
		)
		(pad "2" smd custom
			(at 0 0.4445 270)
			(size 0.1524 0.1524)
			(layers "B.Cu" "B.Mask" "B.Paste")
			(net "GND")
			(options
				(clearance outline)
				(anchor circle)
			)
			(primitives
				(gr_poly
					(pts
						(arc
							(start 0.3048 0.2032)
							(mid 0.275042 0.275042)
							(end 0.2032 0.3048)
						)
						(arc
							(start -0.2032 0.3048)
							(mid -0.275042 0.275042)
							(end -0.3048 0.2032)
						)
						(arc
							(start -0.3048 -0.2032)
							(mid -0.275042 -0.275042)
							(end -0.2032 -0.3048)
						)
						(arc
							(start 0.2032 -0.3048)
							(mid 0.275042 -0.275042)
							(end 0.3048 -0.2032)
						)
					)
					(width 0)
					(fill yes)
				)
			)
		)
	)
	(footprint ""
		(layer "B.Cu")
		(at 376.8598 -131.6228 180)
		(property "Reference" "C3M30"
			(at 0 0 0)
			(layer "B.SilkS")
			(hide yes)
			(effects
				(font
					(size 1.27 1.27)
				)
				(justify mirror)
			)
		)
		(property "Value" ""
			(at 0 0 0)
			(layer "B.Fab")
			(effects
				(font
					(size 1.27 1.27)
				)
				(justify mirror)
			)
		)
		(duplicate_pad_numbers_are_jumpers no)
		(fp_poly
			(pts
				(xy -0.3048 -0.1016) (xy -0.3048 0.9906) (xy 0.3048 0.9906) (xy 0.3048 -0.1016)
			)
			(stroke
				(width 0)
				(type default)
			)
			(fill no)
			(layer "B.CrtYd")
		)
		(fp_line
			(start 0.3048 0.9906)
			(end -0.3048 0.9906)
			(stroke
				(width 0.1)
				(type default)
			)
			(layer "B.Fab")
		)
		(fp_line
			(start 0.3048 -0.1016)
			(end 0.3048 0.9906)
			(stroke
				(width 0.1)
				(type default)
			)
			(layer "B.Fab")
		)
		(fp_line
			(start -0.3048 0.9906)
			(end -0.3048 -0.1016)
			(stroke
				(width 0.1)
				(type default)
			)
			(layer "B.Fab")
		)
		(fp_line
			(start -0.3048 -0.1016)
			(end 0.3048 -0.1016)
			(stroke
				(width 0.1)
				(type default)
			)
			(layer "B.Fab")
		)
		(pad "1" smd rect
			(at 0 0)
			(size 0.508 0.508)
			(layers "B.Cu" "B.Mask" "B.Paste")
			(net "P1V05_PCH_STBY")
		)
		(pad "2" smd rect
			(at 0 0.889)
			(size 0.508 0.508)
			(layers "B.Cu" "B.Mask" "B.Paste")
			(net "GND")
		)
		(zone
			(layer "B.Cu")
			(hatch none 0.5)
			(connect_pads
				(clearance 0)
			)
			(min_thickness 0.25)
			(keepout
				(tracks not_allowed)
				(vias allowed)
				(pads allowed)
				(copperpour not_allowed)
				(footprints allowed)
			)
			(placement
				(enabled no)
				(sheetname "")
			)
			(fill
				(thermal_gap 0.5)
				(thermal_bridge_width 0.5)
				(island_removal_mode 0)
			)
			(polygon
				(pts
					(xy 376.6058 -132.2578) (xy 377.1138 -132.2578) (xy 377.1138 -131.8768) (xy 376.6058 -131.8768)
				)
			)
		)
		(zone
			(layer "B.Cu")
			(hatch none 0.5)
			(connect_pads
				(clearance 0)
			)
			(min_thickness 0.25)
			(keepout
				(tracks allowed)
				(vias not_allowed)
				(pads allowed)
				(copperpour not_allowed)
				(footprints allowed)
			)
			(placement
				(enabled no)
				(sheetname "")
			)
			(fill
				(thermal_gap 0.5)
				(thermal_bridge_width 0.5)
				(island_removal_mode 0)
			)
			(polygon
				(pts
					(xy 376.6058 -131.8768) (xy 377.1138 -131.8768) (xy 377.1138 -132.2578) (xy 376.6058 -132.2578)
				)
			)
		)
	)
	(footprint ""
		(layer "B.Cu")
		(at 419.4175 -6.589014 180)
		(property "Reference" "U7D3"
			(at 1.60147 1.397 270)
			(unlocked yes)
			(layer "B.SilkS")
			(effects
				(font
					(size 0.7874 0.5842)
					(thickness 0.1524)
				)
				(justify mirror)
			)
		)
		(property "Value" ""
			(at 0 0 0)
			(layer "B.Fab")
			(effects
				(font
					(size 1.27 1.27)
				)
				(justify mirror)
			)
		)
		(duplicate_pad_numbers_are_jumpers no)
		(fp_line
			(start -0.760222 1.75006)
			(end -1.146048 1.75006)
			(stroke
				(width 0.1524)
				(type default)
			)
			(layer "B.SilkS")
		)
		(fp_line
			(start -1.146048 -0.450088)
			(end -0.760222 -0.450088)
			(stroke
				(width 0.1524)
				(type default)
			)
			(layer "B.SilkS")
		)
		(fp_circle
			(center 1.194054 -0.610362)
			(end 1.067054 -0.610362)
			(stroke
				(width 0.254)
				(type default)
			)
			(fill no)
			(layer "B.SilkS")
		)
		(fp_poly
			(pts
				(xy -0.277622 -0.450088) (xy -0.277622 1.75006) (xy -1.627378 1.75006) (xy -1.627378 -0.450088)
			)
			(stroke
				(width 0)
				(type default)
			)
			(fill no)
			(layer "B.CrtYd")
		)
		(fp_line
			(start -0.277622 1.75006)
			(end -0.277622 -0.450088)
			(stroke
				(width 0.1)
				(type default)
			)
			(layer "B.Fab")
		)
		(fp_line
			(start -0.277622 -0.450088)
			(end -1.627378 -0.450088)
			(stroke
				(width 0.1)
				(type default)
			)
			(layer "B.Fab")
		)
		(fp_line
			(start -1.627378 1.75006)
			(end -0.277622 1.75006)
			(stroke
				(width 0.1)
				(type default)
			)
			(layer "B.Fab")
		)
		(fp_line
			(start -1.627378 -0.450088)
			(end -1.627378 1.75006)
			(stroke
				(width 0.1)
				(type default)
			)
			(layer "B.Fab")
		)
		(fp_circle
			(center 1.194054 -0.610362)
			(end 1.067054 -0.610362)
			(stroke
				(width 0.254)
				(type default)
			)
			(fill no)
			(layer "B.Fab")
		)
		(pad "1" smd rect
			(at 0 0)
			(size 1.016 0.4064)
			(layers "B.Cu" "B.Mask" "B.Paste")
			(net "PWRGD_P3V3_STBY")
		)
		(pad "2" smd rect
			(at 0 0.649986)
			(size 1.016 0.4064)
			(layers "B.Cu" "B.Mask" "B.Paste")
			(net "GND")
		)
		(pad "3" smd rect
			(at 0 1.299972)
			(size 1.016 0.4064)
			(layers "B.Cu" "B.Mask" "B.Paste")
			(net "VSENSE_P12V_ADM1085")
		)
		(pad "4" smd rect
			(at -1.905 1.299972)
			(size 1.016 0.4064)
			(layers "B.Cu" "B.Mask" "B.Paste")
			(net "PWRGD_DSW_PWROK")
		)
		(pad "5" smd rect
			(at -1.905 0.649986)
			(size 1.016 0.4064)
			(layers "B.Cu" "B.Mask" "B.Paste")
			(net "A_ADM1085_CEXT")
		)
		(pad "6" smd rect
			(at -1.905 0)
			(size 1.016 0.4064)
			(layers "B.Cu" "B.Mask" "B.Paste")
			(net "P3V3_STBY")
		)
	)
	(footprint ""
		(layer "B.Cu")
		(at 80.731868 -3.3528 -90)
		(property "Reference" "C5G87"
			(at -1.14681 0.76708 0)
			(unlocked yes)
			(layer "B.SilkS")
			(effects
				(font
					(size 0.7874 0.5842)
					(thickness 0.1524)
				)
				(justify mirror)
			)
		)
		(property "Value" ""
			(at 0 0 90)
			(layer "B.Fab")
			(effects
				(font
					(size 1.27 1.27)
				)
				(justify mirror)
			)
		)
		(duplicate_pad_numbers_are_jumpers no)
		(fp_rect
			(start 0.4953 1.6002)
			(end -0.4953 -0.2032)
			(stroke
				(width 0)
				(type default)
			)
			(fill no)
			(layer "B.CrtYd")
		)
		(fp_line
			(start -0.4953 1.6002)
			(end 0.4953 1.6002)
			(stroke
				(width 0.1)
				(type default)
			)
			(layer "B.Fab")
		)
		(fp_line
			(start 0.4953 1.6002)
			(end 0.4953 -0.2032)
			(stroke
				(width 0.1)
				(type default)
			)
			(layer "B.Fab")
		)
		(fp_line
			(start -0.4953 -0.2032)
			(end -0.4953 1.6002)
			(stroke
				(width 0.1)
				(type default)
			)
			(layer "B.Fab")
		)
		(fp_line
			(start 0.4953 -0.2032)
			(end -0.4953 -0.2032)
			(stroke
				(width 0.1)
				(type default)
			)
			(layer "B.Fab")
		)
		(pad "1" smd rect
			(at 0 0 90)
			(size 0.762 0.889)
			(layers "B.Cu" "B.Mask" "B.Paste")
			(net "PVDDQ_GHJ")
		)
		(pad "2" smd rect
			(at 0 1.397 90)
			(size 0.762 0.889)
			(layers "B.Cu" "B.Mask" "B.Paste")
			(net "GND")
		)
		(zone
			(layer "B.Cu")
			(hatch none 0.5)
			(connect_pads
				(clearance 0)
			)
			(min_thickness 0.25)
			(keepout
				(tracks not_allowed)
				(vias allowed)
				(pads allowed)
				(copperpour not_allowed)
				(footprints allowed)
			)
			(placement
				(enabled no)
				(sheetname "")
			)
			(fill
				(thermal_gap 0.5)
				(thermal_bridge_width 0.5)
				(island_removal_mode 0)
			)
			(polygon
				(pts
					(xy 79.779368 -2.9718) (xy 80.287368 -2.9718) (xy 80.287368 -3.7338) (xy 79.779368 -3.7338)
				)
			)
		)
	)
	(footprint ""
		(layer "B.Cu")
		(at 252.1585 -135.4074 -90)
		(property "Reference" "C5M5"
			(at -1.848866 0.752348 270)
			(unlocked yes)
			(layer "B.SilkS")
			(effects
				(font
					(size 1.27 0.9652)
					(thickness 0.1524)
				)
				(justify mirror)
			)
		)
		(property "Value" ""
			(at 0 0 90)
			(layer "B.Fab")
			(effects
				(font
					(size 1.27 1.27)
				)
				(justify mirror)
			)
		)
		(duplicate_pad_numbers_are_jumpers no)
		(fp_rect
			(start 0.500126 1.598422)
			(end -0.500126 -0.201422)
			(stroke
				(width 0)
				(type default)
			)
			(fill no)
			(layer "B.CrtYd")
		)
		(fp_line
			(start -0.500126 1.598422)
			(end 0.500126 1.598422)
			(stroke
				(width 0.1)
				(type default)
			)
			(layer "B.Fab")
		)
		(fp_line
			(start 0.500126 1.598422)
			(end 0.500126 -0.201422)
			(stroke
				(width 0.1)
				(type default)
			)
			(layer "B.Fab")
		)
		(fp_line
			(start -0.500126 -0.201422)
			(end -0.500126 1.598422)
			(stroke
				(width 0.1)
				(type default)
			)
			(layer "B.Fab")
		)
		(fp_line
			(start 0.500126 -0.201422)
			(end -0.500126 -0.201422)
			(stroke
				(width 0.1)
				(type default)
			)
			(layer "B.Fab")
		)
		(pad "1" smd rect
			(at 0 0 180)
			(size 0.889 0.9906)
			(layers "B.Cu" "B.Mask" "B.Paste")
			(net "PVDDQ_DEF")
		)
		(pad "2" smd rect
			(at 0 1.397 180)
			(size 0.889 0.9906)
			(layers "B.Cu" "B.Mask" "B.Paste")
			(net "GND")
		)
		(zone
			(layer "B.Cu")
			(hatch none 0.5)
			(connect_pads
				(clearance 0)
			)
			(min_thickness 0.25)
			(keepout
				(tracks not_allowed)
				(vias allowed)
				(pads allowed)
				(copperpour not_allowed)
				(footprints allowed)
			)
			(placement
				(enabled no)
				(sheetname "")
			)
			(fill
				(thermal_gap 0.5)
				(thermal_bridge_width 0.5)
				(island_removal_mode 0)
			)
			(polygon
				(pts
					(xy 251.206 -134.9121) (xy 251.714 -134.9121) (xy 251.714 -135.9027) (xy 251.206 -135.9027)
				)
			)
		)
		(zone
			(layer "B.Cu")
			(hatch none 0.5)
			(connect_pads
				(clearance 0)
			)
			(min_thickness 0.25)
			(keepout
				(tracks allowed)
				(vias not_allowed)
				(pads allowed)
				(copperpour not_allowed)
				(footprints allowed)
			)
			(placement
				(enabled no)
				(sheetname "")
			)
			(fill
				(thermal_gap 0.5)
				(thermal_bridge_width 0.5)
				(island_removal_mode 0)
			)
			(polygon
				(pts
					(xy 251.206 -134.9121) (xy 251.714 -134.9121) (xy 251.714 -135.9027) (xy 251.206 -135.9027)
				)
			)
		)
	)
	(footprint ""
		(layer "B.Cu")
		(at 83.856068 -17.7546 -90)
		(property "Reference" "C8T9"
			(at -1.848866 0.752348 270)
			(unlocked yes)
			(layer "B.SilkS")
			(effects
				(font
					(size 1.27 0.9652)
					(thickness 0.1524)
				)
				(justify mirror)
			)
		)
		(property "Value" ""
			(at 0 0 90)
			(layer "B.Fab")
			(effects
				(font
					(size 1.27 1.27)
				)
				(justify mirror)
			)
		)
		(duplicate_pad_numbers_are_jumpers no)
		(fp_rect
			(start 0.500126 1.598422)
			(end -0.500126 -0.201422)
			(stroke
				(width 0)
				(type default)
			)
			(fill no)
			(layer "B.CrtYd")
		)
		(fp_line
			(start -0.500126 1.598422)
			(end 0.500126 1.598422)
			(stroke
				(width 0.1)
				(type default)
			)
			(layer "B.Fab")
		)
		(fp_line
			(start 0.500126 1.598422)
			(end 0.500126 -0.201422)
			(stroke
				(width 0.1)
				(type default)
			)
			(layer "B.Fab")
		)
		(fp_line
			(start -0.500126 -0.201422)
			(end -0.500126 1.598422)
			(stroke
				(width 0.1)
				(type default)
			)
			(layer "B.Fab")
		)
		(fp_line
			(start 0.500126 -0.201422)
			(end -0.500126 -0.201422)
			(stroke
				(width 0.1)
				(type default)
			)
			(layer "B.Fab")
		)
		(pad "1" smd rect
			(at 0 0 180)
			(size 0.889 0.9906)
			(layers "B.Cu" "B.Mask" "B.Paste")
			(net "PVDDQ_GHJ")
		)
		(pad "2" smd rect
			(at 0 1.397 180)
			(size 0.889 0.9906)
			(layers "B.Cu" "B.Mask" "B.Paste")
			(net "GND")
		)
		(zone
			(layer "B.Cu")
			(hatch none 0.5)
			(connect_pads
				(clearance 0)
			)
			(min_thickness 0.25)
			(keepout
				(tracks allowed)
				(vias not_allowed)
				(pads allowed)
				(copperpour not_allowed)
				(footprints allowed)
			)
			(placement
				(enabled no)
				(sheetname "")
			)
			(fill
				(thermal_gap 0.5)
				(thermal_bridge_width 0.5)
				(island_removal_mode 0)
			)
			(polygon
				(pts
					(xy 82.903568 -17.2593) (xy 83.411568 -17.2593) (xy 83.411568 -18.2499) (xy 82.903568 -18.2499)
				)
			)
		)
		(zone
			(layer "B.Cu")
			(hatch none 0.5)
			(connect_pads
				(clearance 0)
			)
			(min_thickness 0.25)
			(keepout
				(tracks not_allowed)
				(vias allowed)
				(pads allowed)
				(copperpour not_allowed)
				(footprints allowed)
			)
			(placement
				(enabled no)
				(sheetname "")
			)
			(fill
				(thermal_gap 0.5)
				(thermal_bridge_width 0.5)
				(island_removal_mode 0)
			)
			(polygon
				(pts
					(xy 82.903568 -17.2593) (xy 83.411568 -17.2593) (xy 83.411568 -18.2499) (xy 82.903568 -18.2499)
				)
			)
		)
	)
	(footprint ""
		(layer "B.Cu")
		(at 473.130118 -134.958074 -90)
		(property "Reference" "C1W19"
			(at 0.8382 -0.67818 270)
			(unlocked yes)
			(layer "B.SilkS")
			(effects
				(font
					(size 0.4064 0.254)
					(thickness 0.1524)
				)
				(justify left mirror)
			)
		)
		(property "Value" ""
			(at 0 0 90)
			(layer "B.Fab")
			(effects
				(font
					(size 1.27 1.27)
				)
				(justify mirror)
			)
		)
		(duplicate_pad_numbers_are_jumpers no)
		(fp_poly
			(pts
				(xy -0.3048 -0.1016) (xy -0.3048 0.9906) (xy 0.3048 0.9906) (xy 0.3048 -0.1016)
			)
			(stroke
				(width 0)
				(type default)
			)
			(fill no)
			(layer "B.CrtYd")
		)
		(fp_line
			(start -0.3048 0.9906)
			(end -0.3048 -0.1016)
			(stroke
				(width 0.1)
				(type default)
			)
			(layer "B.Fab")
		)
		(fp_line
			(start 0.3048 0.9906)
			(end -0.3048 0.9906)
			(stroke
				(width 0.1)
				(type default)
			)
			(layer "B.Fab")
		)
		(fp_line
			(start -0.3048 -0.1016)
			(end 0.3048 -0.1016)
			(stroke
				(width 0.1)
				(type default)
			)
			(layer "B.Fab")
		)
		(fp_line
			(start 0.3048 -0.1016)
			(end 0.3048 0.9906)
			(stroke
				(width 0.1)
				(type default)
			)
			(layer "B.Fab")
		)
		(pad "1" smd rect
			(at 0 0 90)
			(size 0.508 0.508)
			(layers "B.Cu" "B.Mask" "B.Paste")
			(net "P3V3_STBY")
		)
		(pad "2" smd rect
			(at 0 0.889 90)
			(size 0.508 0.508)
			(layers "B.Cu" "B.Mask" "B.Paste")
			(net "GND")
		)
		(zone
			(layer "B.Cu")
			(hatch none 0.5)
			(connect_pads
				(clearance 0)
			)
			(min_thickness 0.25)
			(keepout
				(tracks not_allowed)
				(vias allowed)
				(pads allowed)
				(copperpour not_allowed)
				(footprints allowed)
			)
			(placement
				(enabled no)
				(sheetname "")
			)
			(fill
				(thermal_gap 0.5)
				(thermal_bridge_width 0.5)
				(island_removal_mode 0)
			)
			(polygon
				(pts
					(xy 472.495118 -134.704074) (xy 472.495118 -135.212074) (xy 472.876118 -135.212074) (xy 472.876118 -134.704074)
				)
			)
		)
		(zone
			(layer "B.Cu")
			(hatch none 0.5)
			(connect_pads
				(clearance 0)
			)
			(min_thickness 0.25)
			(keepout
				(tracks allowed)
				(vias not_allowed)
				(pads allowed)
				(copperpour not_allowed)
				(footprints allowed)
			)
			(placement
				(enabled no)
				(sheetname "")
			)
			(fill
				(thermal_gap 0.5)
				(thermal_bridge_width 0.5)
				(island_removal_mode 0)
			)
			(polygon
				(pts
					(xy 472.876118 -134.704074) (xy 472.876118 -135.212074) (xy 472.495118 -135.212074) (xy 472.495118 -134.704074)
				)
			)
		)
	)
	(footprint ""
		(layer "B.Cu")
		(at 180.467 -65.024)
		(property "Reference" "R6P45"
			(at 0 0 0)
			(layer "B.SilkS")
			(hide yes)
			(effects
				(font
					(size 1.27 1.27)
				)
				(justify mirror)
			)
		)
		(property "Value" ""
			(at 0 0 0)
			(layer "B.Fab")
			(effects
				(font
					(size 1.27 1.27)
				)
				(justify mirror)
			)
		)
		(duplicate_pad_numbers_are_jumpers no)
		(fp_poly
			(pts
				(xy 0.2794 -0.1016) (xy -0.2794 -0.1016) (xy -0.2794 0.9906) (xy 0.2794 0.9906)
			)
			(stroke
				(width 0)
				(type default)
			)
			(fill no)
			(layer "B.CrtYd")
		)
		(fp_line
			(start -0.2794 -0.1016)
			(end 0.2794 -0.1016)
			(stroke
				(width 0.1)
				(type default)
			)
			(layer "B.Fab")
		)
		(fp_line
			(start -0.2794 0.9906)
			(end -0.2794 -0.1016)
			(stroke
				(width 0.1)
				(type default)
			)
			(layer "B.Fab")
		)
		(fp_line
			(start 0.2794 -0.1016)
			(end 0.2794 0.9906)
			(stroke
				(width 0.1)
				(type default)
			)
			(layer "B.Fab")
		)
		(fp_line
			(start 0.2794 0.9906)
			(end -0.2794 0.9906)
			(stroke
				(width 0.1)
				(type default)
			)
			(layer "B.Fab")
		)
		(pad "1" smd rect
			(at 0 0 180)
			(size 0.508 0.508)
			(layers "B.Cu" "B.Mask" "B.Paste")
			(net "IRQ_PVCCIN_CPU0_VRHOT_LVC3_R_N")
		)
		(pad "2" smd rect
			(at 0 0.889 180)
			(size 0.508 0.508)
			(layers "B.Cu" "B.Mask" "B.Paste")
			(net "IRQ_PVCCIN_CPU0_VRHOT_LVC3_N")
		)
		(zone
			(layer "B.Cu")
			(hatch none 0.5)
			(connect_pads
				(clearance 0)
			)
			(min_thickness 0.25)
			(keepout
				(tracks allowed)
				(vias not_allowed)
				(pads allowed)
				(copperpour not_allowed)
				(footprints allowed)
			)
			(placement
				(enabled no)
				(sheetname "")
			)
			(fill
				(thermal_gap 0.5)
				(thermal_bridge_width 0.5)
				(island_removal_mode 0)
			)
			(polygon
				(pts
					(xy 180.721 -64.77) (xy 180.213 -64.77) (xy 180.213 -64.389) (xy 180.721 -64.389)
				)
			)
		)
		(zone
			(layer "B.Cu")
			(hatch none 0.5)
			(connect_pads
				(clearance 0)
			)
			(min_thickness 0.25)
			(keepout
				(tracks not_allowed)
				(vias allowed)
				(pads allowed)
				(copperpour not_allowed)
				(footprints allowed)
			)
			(placement
				(enabled no)
				(sheetname "")
			)
			(fill
				(thermal_gap 0.5)
				(thermal_bridge_width 0.5)
				(island_removal_mode 0)
			)
			(polygon
				(pts
					(xy 180.721 -64.389) (xy 180.213 -64.389) (xy 180.213 -64.77) (xy 180.721 -64.77)
				)
			)
		)
	)
	(footprint ""
		(layer "B.Cu")
		(at 390.93775 -106.25455 180)
		(property "Reference" "C2N15"
			(at 0 0 0)
			(layer "B.SilkS")
			(hide yes)
			(effects
				(font
					(size 1.27 1.27)
				)
				(justify mirror)
			)
		)
		(property "Value" ""
			(at 0 0 0)
			(layer "B.Fab")
			(effects
				(font
					(size 1.27 1.27)
				)
				(justify mirror)
			)
		)
		(duplicate_pad_numbers_are_jumpers no)
		(fp_rect
			(start 0.2794 0.9144)
			(end -0.2794 -0.1143)
			(stroke
				(width 0)
				(type default)
			)
			(fill no)
			(layer "B.CrtYd")
		)
		(fp_line
			(start 0.2794 0.9144)
			(end 0.2794 -0.1143)
			(stroke
				(width 0.1)
				(type default)
			)
			(layer "B.Fab")
		)
		(fp_line
			(start 0.2794 -0.1143)
			(end -0.2794 -0.1143)
			(stroke
				(width 0.1)
				(type default)
			)
			(layer "B.Fab")
		)
		(fp_line
			(start -0.2794 0.9144)
			(end 0.2794 0.9144)
			(stroke
				(width 0.1)
				(type default)
			)
			(layer "B.Fab")
		)
		(fp_line
			(start -0.2794 -0.1143)
			(end -0.2794 0.9144)
			(stroke
				(width 0.1)
				(type default)
			)
			(layer "B.Fab")
		)
		(pad "1" smd custom
			(at 0 0 90)
			(size 0.10414 0.10414)
			(layers "B.Cu" "B.Mask" "B.Paste")
			(net "P1V8_PCH_STBY")
			(options
				(clearance outline)
				(anchor circle)
			)
			(primitives
				(gr_poly
					(pts
						(xy -0.20828 -0.08636) (xy -0.20828 0.08636) (xy -0.08636 0.20828) (xy 0.086614 0.20828) (xy 0.20828 0.086614)
						(xy 0.20828 -0.08636) (xy 0.08636 -0.20828) (xy -0.08636 -0.20828)
					)
					(width 0)
					(fill yes)
				)
			)
		)
		(pad "2" smd custom
			(at 0 0.8001 90)
			(size 0.10414 0.10414)
			(layers "B.Cu" "B.Mask" "B.Paste")
			(net "GND")
			(options
				(clearance outline)
				(anchor circle)
			)
			(primitives
				(gr_poly
					(pts
						(xy -0.20828 -0.08636) (xy -0.20828 0.08636) (xy -0.08636 0.20828) (xy 0.086614 0.20828) (xy 0.20828 0.086614)
						(xy 0.20828 -0.08636) (xy 0.08636 -0.20828) (xy -0.08636 -0.20828)
					)
					(width 0)
					(fill yes)
				)
			)
		)
		(zone
			(layer "B.Cu")
			(hatch none 0.5)
			(connect_pads
				(clearance 0)
			)
			(min_thickness 0.25)
			(keepout
				(tracks not_allowed)
				(vias allowed)
				(pads allowed)
				(copperpour not_allowed)
				(footprints allowed)
			)
			(placement
				(enabled no)
				(sheetname "")
			)
			(fill
				(thermal_gap 0.5)
				(thermal_bridge_width 0.5)
				(island_removal_mode 0)
			)
			(polygon
				(pts
					(xy 390.85012 -106.4641) (xy 390.85012 -106.8451) (xy 391.02538 -106.8451) (xy 391.025634 -106.4641)
				)
			)
		)
		(zone
			(layer "B.Cu")
			(hatch none 0.5)
			(connect_pads
				(clearance 0)
			)
			(min_thickness 0.25)
			(keepout
				(tracks allowed)
				(vias not_allowed)
				(pads allowed)
				(copperpour not_allowed)
				(footprints allowed)
			)
			(placement
				(enabled no)
				(sheetname "")
			)
			(fill
				(thermal_gap 0.5)
				(thermal_bridge_width 0.5)
				(island_removal_mode 0)
			)
			(polygon
				(pts
					(xy 390.85012 -106.4641) (xy 390.85012 -106.8451) (xy 391.02538 -106.8451) (xy 391.025634 -106.4641)
				)
			)
		)
	)
	(footprint ""
		(layer "B.Cu")
		(at 376.344688 -77.096366 180)
		(property "Reference" "C3P52"
			(at 0 0 0)
			(layer "B.SilkS")
			(hide yes)
			(effects
				(font
					(size 1.27 1.27)
				)
				(justify mirror)
			)
		)
		(property "Value" ""
			(at 0 0 0)
			(layer "B.Fab")
			(effects
				(font
					(size 1.27 1.27)
				)
				(justify mirror)
			)
		)
		(duplicate_pad_numbers_are_jumpers no)
		(fp_rect
			(start 0.2794 0.9144)
			(end -0.2794 -0.1143)
			(stroke
				(width 0)
				(type default)
			)
			(fill no)
			(layer "B.CrtYd")
		)
		(fp_line
			(start 0.2794 0.9144)
			(end 0.2794 -0.1143)
			(stroke
				(width 0.1)
				(type default)
			)
			(layer "B.Fab")
		)
		(fp_line
			(start 0.2794 -0.1143)
			(end -0.2794 -0.1143)
			(stroke
				(width 0.1)
				(type default)
			)
			(layer "B.Fab")
		)
		(fp_line
			(start -0.2794 0.9144)
			(end 0.2794 0.9144)
			(stroke
				(width 0.1)
				(type default)
			)
			(layer "B.Fab")
		)
		(fp_line
			(start -0.2794 -0.1143)
			(end -0.2794 0.9144)
			(stroke
				(width 0.1)
				(type default)
			)
			(layer "B.Fab")
		)
		(pad "1" smd custom
			(at 0 0 90)
			(size 0.10414 0.10414)
			(layers "B.Cu" "B.Mask" "B.Paste")
			(net "P3V3_STBY")
			(options
				(clearance outline)
				(anchor circle)
			)
			(primitives
				(gr_poly
					(pts
						(xy -0.20828 -0.08636) (xy -0.20828 0.08636) (xy -0.08636 0.20828) (xy 0.086614 0.20828) (xy 0.20828 0.086614)
						(xy 0.20828 -0.08636) (xy 0.08636 -0.20828) (xy -0.08636 -0.20828)
					)
					(width 0)
					(fill yes)
				)
			)
		)
		(pad "2" smd custom
			(at 0 0.8001 90)
			(size 0.10414 0.10414)
			(layers "B.Cu" "B.Mask" "B.Paste")
			(net "GND")
			(options
				(clearance outline)
				(anchor circle)
			)
			(primitives
				(gr_poly
					(pts
						(xy -0.20828 -0.08636) (xy -0.20828 0.08636) (xy -0.08636 0.20828) (xy 0.086614 0.20828) (xy 0.20828 0.086614)
						(xy 0.20828 -0.08636) (xy 0.08636 -0.20828) (xy -0.08636 -0.20828)
					)
					(width 0)
					(fill yes)
				)
			)
		)
		(zone
			(layer "B.Cu")
			(hatch none 0.5)
			(connect_pads
				(clearance 0)
			)
			(min_thickness 0.25)
			(keepout
				(tracks not_allowed)
				(vias allowed)
				(pads allowed)
				(copperpour not_allowed)
				(footprints allowed)
			)
			(placement
				(enabled no)
				(sheetname "")
			)
			(fill
				(thermal_gap 0.5)
				(thermal_bridge_width 0.5)
				(island_removal_mode 0)
			)
			(polygon
				(pts
					(xy 376.257058 -77.305916) (xy 376.257058 -77.686916) (xy 376.432318 -77.686916) (xy 376.432572 -77.305916)
				)
			)
		)
		(zone
			(layer "B.Cu")
			(hatch none 0.5)
			(connect_pads
				(clearance 0)
			)
			(min_thickness 0.25)
			(keepout
				(tracks allowed)
				(vias not_allowed)
				(pads allowed)
				(copperpour not_allowed)
				(footprints allowed)
			)
			(placement
				(enabled no)
				(sheetname "")
			)
			(fill
				(thermal_gap 0.5)
				(thermal_bridge_width 0.5)
				(island_removal_mode 0)
			)
			(polygon
				(pts
					(xy 376.257058 -77.305916) (xy 376.257058 -77.686916) (xy 376.432318 -77.686916) (xy 376.432572 -77.305916)
				)
			)
		)
	)
	(footprint ""
		(layer "B.Cu")
		(at 461.658208 -132.842254 90)
		(property "Reference" "R1M3"
			(at 0 0 90)
			(layer "B.SilkS")
			(hide yes)
			(effects
				(font
					(size 1.27 1.27)
				)
				(justify mirror)
			)
		)
		(property "Value" ""
			(at 0 0 90)
			(layer "B.Fab")
			(effects
				(font
					(size 1.27 1.27)
				)
				(justify mirror)
			)
		)
		(duplicate_pad_numbers_are_jumpers no)
		(fp_poly
			(pts
				(xy 0.2794 -0.1016) (xy -0.2794 -0.1016) (xy -0.2794 0.9906) (xy 0.2794 0.9906)
			)
			(stroke
				(width 0)
				(type default)
			)
			(fill no)
			(layer "B.CrtYd")
		)
		(fp_line
			(start 0.2794 -0.1016)
			(end 0.2794 0.9906)
			(stroke
				(width 0.1)
				(type default)
			)
			(layer "B.Fab")
		)
		(fp_line
			(start -0.2794 -0.1016)
			(end 0.2794 -0.1016)
			(stroke
				(width 0.1)
				(type default)
			)
			(layer "B.Fab")
		)
		(fp_line
			(start 0.2794 0.9906)
			(end -0.2794 0.9906)
			(stroke
				(width 0.1)
				(type default)
			)
			(layer "B.Fab")
		)
		(fp_line
			(start -0.2794 0.9906)
			(end -0.2794 -0.1016)
			(stroke
				(width 0.1)
				(type default)
			)
			(layer "B.Fab")
		)
		(pad "1" smd rect
			(at 0 0 270)
			(size 0.508 0.508)
			(layers "B.Cu" "B.Mask" "B.Paste")
			(net "PVCCIO_CPU0")
		)
		(pad "2" smd rect
			(at 0 0.889 270)
			(size 0.508 0.508)
			(layers "B.Cu" "B.Mask" "B.Paste")
			(net "XDP_CPU_PRDY_N")
		)
		(zone
			(layer "B.Cu")
			(hatch none 0.5)
			(connect_pads
				(clearance 0)
			)
			(min_thickness 0.25)
			(keepout
				(tracks allowed)
				(vias not_allowed)
				(pads allowed)
				(copperpour not_allowed)
				(footprints allowed)
			)
			(placement
				(enabled no)
				(sheetname "")
			)
			(fill
				(thermal_gap 0.5)
				(thermal_bridge_width 0.5)
				(island_removal_mode 0)
			)
			(polygon
				(pts
					(xy 461.912208 -133.096254) (xy 461.912208 -132.588254) (xy 462.293208 -132.588254) (xy 462.293208 -133.096254)
				)
			)
		)
		(zone
			(layer "B.Cu")
			(hatch none 0.5)
			(connect_pads
				(clearance 0)
			)
			(min_thickness 0.25)
			(keepout
				(tracks not_allowed)
				(vias allowed)
				(pads allowed)
				(copperpour not_allowed)
				(footprints allowed)
			)
			(placement
				(enabled no)
				(sheetname "")
			)
			(fill
				(thermal_gap 0.5)
				(thermal_bridge_width 0.5)
				(island_removal_mode 0)
			)
			(polygon
				(pts
					(xy 462.293208 -133.096254) (xy 462.293208 -132.588254) (xy 461.912208 -132.588254) (xy 461.912208 -133.096254)
				)
			)
		)
	)
	(footprint ""
		(layer "B.Cu")
		(at 479.9965 -44.323 90)
		(property "Reference" "C1R29"
			(at 0 0 90)
			(layer "B.SilkS")
			(hide yes)
			(effects
				(font
					(size 1.27 1.27)
				)
				(justify mirror)
			)
		)
		(property "Value" ""
			(at 0 0 90)
			(layer "B.Fab")
			(effects
				(font
					(size 1.27 1.27)
				)
				(justify mirror)
			)
		)
		(duplicate_pad_numbers_are_jumpers no)
		(fp_poly
			(pts
				(xy -0.3048 -0.1016) (xy -0.3048 0.9906) (xy 0.3048 0.9906) (xy 0.3048 -0.1016)
			)
			(stroke
				(width 0)
				(type default)
			)
			(fill no)
			(layer "B.CrtYd")
		)
		(fp_line
			(start 0.3048 -0.1016)
			(end 0.3048 0.9906)
			(stroke
				(width 0.1)
				(type default)
			)
			(layer "B.Fab")
		)
		(fp_line
			(start -0.3048 -0.1016)
			(end 0.3048 -0.1016)
			(stroke
				(width 0.1)
				(type default)
			)
			(layer "B.Fab")
		)
		(fp_line
			(start 0.3048 0.9906)
			(end -0.3048 0.9906)
			(stroke
				(width 0.1)
				(type default)
			)
			(layer "B.Fab")
		)
		(fp_line
			(start -0.3048 0.9906)
			(end -0.3048 -0.1016)
			(stroke
				(width 0.1)
				(type default)
			)
			(layer "B.Fab")
		)
		(pad "1" smd rect
			(at 0 0 270)
			(size 0.508 0.508)
			(layers "B.Cu" "B.Mask" "B.Paste")
			(net "P1V5_LAN")
		)
		(pad "2" smd rect
			(at 0 0.889 270)
			(size 0.508 0.508)
			(layers "B.Cu" "B.Mask" "B.Paste")
			(net "GND")
		)
		(zone
			(layer "B.Cu")
			(hatch none 0.5)
			(connect_pads
				(clearance 0)
			)
			(min_thickness 0.25)
			(keepout
				(tracks allowed)
				(vias not_allowed)
				(pads allowed)
				(copperpour not_allowed)
				(footprints allowed)
			)
			(placement
				(enabled no)
				(sheetname "")
			)
			(fill
				(thermal_gap 0.5)
				(thermal_bridge_width 0.5)
				(island_removal_mode 0)
			)
			(polygon
				(pts
					(xy 480.2505 -44.577) (xy 480.2505 -44.069) (xy 480.6315 -44.069) (xy 480.6315 -44.577)
				)
			)
		)
		(zone
			(layer "B.Cu")
			(hatch none 0.5)
			(connect_pads
				(clearance 0)
			)
			(min_thickness 0.25)
			(keepout
				(tracks not_allowed)
				(vias allowed)
				(pads allowed)
				(copperpour not_allowed)
				(footprints allowed)
			)
			(placement
				(enabled no)
				(sheetname "")
			)
			(fill
				(thermal_gap 0.5)
				(thermal_bridge_width 0.5)
				(island_removal_mode 0)
			)
			(polygon
				(pts
					(xy 480.6315 -44.577) (xy 480.6315 -44.069) (xy 480.2505 -44.069) (xy 480.2505 -44.577)
				)
			)
		)
	)
	(footprint ""
		(layer "B.Cu")
		(at 406.8064 2.332228)
		(property "Reference" "U8G3"
			(at -2.667 -1.29667 180)
			(unlocked yes)
			(layer "B.SilkS")
			(effects
				(font
					(size 0.7874 0.5842)
					(thickness 0.1524)
				)
				(justify left mirror)
			)
		)
		(property "Value" ""
			(at 0 0 0)
			(layer "B.Fab")
			(effects
				(font
					(size 1.27 1.27)
				)
				(justify mirror)
			)
		)
		(duplicate_pad_numbers_are_jumpers no)
		(fp_circle
			(center 0.92964 -0.05588)
			(end 1.05664 -0.05588)
			(stroke
				(width 0.254)
				(type default)
			)
			(fill no)
			(layer "B.SilkS")
		)
		(fp_poly
			(pts
				(xy -0.21463 -0.450088) (xy -1.56337 -0.450088) (xy -1.56337 1.75006) (xy -0.21463 1.75006)
			)
			(stroke
				(width 0)
				(type default)
			)
			(fill no)
			(layer "B.CrtYd")
		)
		(fp_line
			(start -1.56337 -0.450088)
			(end -1.56337 1.75006)
			(stroke
				(width 0.1)
				(type default)
			)
			(layer "B.Fab")
		)
		(fp_line
			(start -1.56337 1.75006)
			(end -0.21463 1.75006)
			(stroke
				(width 0.1)
				(type default)
			)
			(layer "B.Fab")
		)
		(fp_line
			(start -0.21463 -0.450088)
			(end -1.56337 -0.450088)
			(stroke
				(width 0.1)
				(type default)
			)
			(layer "B.Fab")
		)
		(fp_line
			(start -0.21463 1.75006)
			(end -0.21463 -0.450088)
			(stroke
				(width 0.1)
				(type default)
			)
			(layer "B.Fab")
		)
		(fp_circle
			(center 0.4699 -0.8382)
			(end 0.5969 -0.8382)
			(stroke
				(width 0.254)
				(type default)
			)
			(fill no)
			(layer "B.Fab")
		)
		(pad "1" smd rect
			(at 0 0 180)
			(size 1.016 0.381)
			(layers "B.Cu" "B.Mask" "B.Paste")
			(net "Net_6468")
		)
		(pad "2" smd rect
			(at 0 0.649986 180)
			(size 1.016 0.381)
			(layers "B.Cu" "B.Mask" "B.Paste")
			(net "FAN_PWM_OUT_SYS1")
		)
		(pad "3" smd rect
			(at 0 1.299972 180)
			(size 1.016 0.381)
			(layers "B.Cu" "B.Mask" "B.Paste")
			(net "GND")
		)
		(pad "4" smd rect
			(at -1.778 1.299972 180)
			(size 1.016 0.381)
			(layers "B.Cu" "B.Mask" "B.Paste")
			(net "FAN_PWM_OUT_SYS1_BUF")
		)
		(pad "5" smd rect
			(at -1.778 0 180)
			(size 1.016 0.381)
			(layers "B.Cu" "B.Mask" "B.Paste")
			(net "P3V3_STBY")
		)
	)
	(footprint ""
		(layer "B.Cu")
		(at 0.762 -144.8562 90)
		(property "Reference" "R9L4"
			(at 0 0 90)
			(layer "B.SilkS")
			(hide yes)
			(effects
				(font
					(size 1.27 1.27)
				)
				(justify mirror)
			)
		)
		(property "Value" ""
			(at 0 0 90)
			(layer "B.Fab")
			(effects
				(font
					(size 1.27 1.27)
				)
				(justify mirror)
			)
		)
		(duplicate_pad_numbers_are_jumpers no)
		(fp_rect
			(start 0.2794 -0.1016)
			(end -0.2794 0.9906)
			(stroke
				(width 0)
				(type default)
			)
			(fill no)
			(layer "B.CrtYd")
		)
		(fp_line
			(start 0.2794 -0.1016)
			(end 0.2794 0.9906)
			(stroke
				(width 0.1)
				(type default)
			)
			(layer "B.Fab")
		)
		(fp_line
			(start -0.2794 -0.1016)
			(end 0.2794 -0.1016)
			(stroke
				(width 0.1)
				(type default)
			)
			(layer "B.Fab")
		)
		(fp_line
			(start 0.2794 0.9906)
			(end -0.2794 0.9906)
			(stroke
				(width 0.1)
				(type default)
			)
			(layer "B.Fab")
		)
		(fp_line
			(start -0.2794 0.9906)
			(end -0.2794 -0.1016)
			(stroke
				(width 0.1)
				(type default)
			)
			(layer "B.Fab")
		)
		(pad "1" smd rect
			(at 0 0 270)
			(size 0.508 0.508)
			(layers "B.Cu" "B.Mask" "B.Paste")
			(net "VR_PVDDQ_KLM_PH2_VCIN")
		)
		(pad "2" smd rect
			(at 0 0.889 270)
			(size 0.508 0.508)
			(layers "B.Cu" "B.Mask" "B.Paste")
			(net "P5V_STBY")
		)
		(zone
			(layer "B.Cu")
			(hatch none 0.5)
			(connect_pads
				(clearance 0)
			)
			(min_thickness 0.25)
			(keepout
				(tracks not_allowed)
				(vias allowed)
				(pads allowed)
				(copperpour not_allowed)
				(footprints allowed)
			)
			(placement
				(enabled no)
				(sheetname "")
			)
			(fill
				(thermal_gap 0.5)
				(thermal_bridge_width 0.5)
				(island_removal_mode 0)
			)
			(polygon
				(pts
					(xy 1.016 -145.1102) (xy 1.016 -144.6022) (xy 1.397 -144.6022) (xy 1.397 -145.1102)
				)
			)
		)
		(zone
			(layer "B.Cu")
			(hatch none 0.5)
			(connect_pads
				(clearance 0)
			)
			(min_thickness 0.25)
			(keepout
				(tracks allowed)
				(vias not_allowed)
				(pads allowed)
				(copperpour not_allowed)
				(footprints allowed)
			)
			(placement
				(enabled no)
				(sheetname "")
			)
			(fill
				(thermal_gap 0.5)
				(thermal_bridge_width 0.5)
				(island_removal_mode 0)
			)
			(polygon
				(pts
					(xy 1.016 -145.1102) (xy 1.016 -144.6022) (xy 1.397 -144.6022) (xy 1.397 -145.1102)
				)
			)
		)
	)
	(footprint ""
		(layer "B.Cu")
		(at 167.386 -87.757)
		(property "Reference" "R6P6"
			(at 0 0 0)
			(layer "B.SilkS")
			(hide yes)
			(effects
				(font
					(size 1.27 1.27)
				)
				(justify mirror)
			)
		)
		(property "Value" ""
			(at 0 0 0)
			(layer "B.Fab")
			(effects
				(font
					(size 1.27 1.27)
				)
				(justify mirror)
			)
		)
		(duplicate_pad_numbers_are_jumpers no)
		(fp_poly
			(pts
				(xy 0.2794 -0.1016) (xy -0.2794 -0.1016) (xy -0.2794 0.9906) (xy 0.2794 0.9906)
			)
			(stroke
				(width 0)
				(type default)
			)
			(fill no)
			(layer "B.CrtYd")
		)
		(fp_line
			(start -0.2794 -0.1016)
			(end 0.2794 -0.1016)
			(stroke
				(width 0.1)
				(type default)
			)
			(layer "B.Fab")
		)
		(fp_line
			(start -0.2794 0.9906)
			(end -0.2794 -0.1016)
			(stroke
				(width 0.1)
				(type default)
			)
			(layer "B.Fab")
		)
		(fp_line
			(start 0.2794 -0.1016)
			(end 0.2794 0.9906)
			(stroke
				(width 0.1)
				(type default)
			)
			(layer "B.Fab")
		)
		(fp_line
			(start 0.2794 0.9906)
			(end -0.2794 0.9906)
			(stroke
				(width 0.1)
				(type default)
			)
			(layer "B.Fab")
		)
		(pad "1" smd rect
			(at 0 0 180)
			(size 0.508 0.508)
			(layers "B.Cu" "B.Mask" "B.Paste")
			(net "CLK_100M_CPU1_BCLK0_DN")
		)
		(pad "2" smd rect
			(at 0 0.889 180)
			(size 0.508 0.508)
			(layers "B.Cu" "B.Mask" "B.Paste")
			(net "GND")
		)
		(zone
			(layer "B.Cu")
			(hatch none 0.5)
			(connect_pads
				(clearance 0)
			)
			(min_thickness 0.25)
			(keepout
				(tracks allowed)
				(vias not_allowed)
				(pads allowed)
				(copperpour not_allowed)
				(footprints allowed)
			)
			(placement
				(enabled no)
				(sheetname "")
			)
			(fill
				(thermal_gap 0.5)
				(thermal_bridge_width 0.5)
				(island_removal_mode 0)
			)
			(polygon
				(pts
					(xy 167.64 -87.503) (xy 167.132 -87.503) (xy 167.132 -87.122) (xy 167.64 -87.122)
				)
			)
		)
		(zone
			(layer "B.Cu")
			(hatch none 0.5)
			(connect_pads
				(clearance 0)
			)
			(min_thickness 0.25)
			(keepout
				(tracks not_allowed)
				(vias allowed)
				(pads allowed)
				(copperpour not_allowed)
				(footprints allowed)
			)
			(placement
				(enabled no)
				(sheetname "")
			)
			(fill
				(thermal_gap 0.5)
				(thermal_bridge_width 0.5)
				(island_removal_mode 0)
			)
			(polygon
				(pts
					(xy 167.64 -87.122) (xy 167.132 -87.122) (xy 167.132 -87.503) (xy 167.64 -87.503)
				)
			)
		)
	)
	(footprint ""
		(layer "B.Cu")
		(at 32.832802 -59.973464 90)
		(property "Reference" "C9R7"
			(at 0 0 90)
			(layer "B.SilkS")
			(hide yes)
			(effects
				(font
					(size 1.27 1.27)
				)
				(justify mirror)
			)
		)
		(property "Value" ""
			(at 0 0 90)
			(layer "B.Fab")
			(effects
				(font
					(size 1.27 1.27)
				)
				(justify mirror)
			)
		)
		(duplicate_pad_numbers_are_jumpers no)
		(fp_poly
			(pts
				(xy 0.7239 -0.2159) (xy -0.7239 -0.2159) (xy -0.7239 1.9939) (xy 0.7239 1.9939)
			)
			(stroke
				(width 0)
				(type default)
			)
			(fill no)
			(layer "B.CrtYd")
		)
		(fp_line
			(start 0.7239 -0.2159)
			(end 0.7239 1.9939)
			(stroke
				(width 0.1)
				(type default)
			)
			(layer "B.Fab")
		)
		(fp_line
			(start -0.7239 -0.2159)
			(end 0.7239 -0.2159)
			(stroke
				(width 0.1)
				(type default)
			)
			(layer "B.Fab")
		)
		(fp_line
			(start 0.7239 1.9939)
			(end -0.7239 1.9939)
			(stroke
				(width 0.1)
				(type default)
			)
			(layer "B.Fab")
		)
		(fp_line
			(start -0.7239 1.9939)
			(end -0.7239 -0.2159)
			(stroke
				(width 0.1)
				(type default)
			)
			(layer "B.Fab")
		)
		(pad "1" smd rect
			(at 0 0 270)
			(size 1.27 1.016)
			(layers "B.Cu" "B.Mask" "B.Paste")
			(net "VR_FET_SW_P12V_STBY_PVCCIN_CPU1")
		)
		(pad "2" smd rect
			(at 0 1.778 270)
			(size 1.27 1.016)
			(layers "B.Cu" "B.Mask" "B.Paste")
			(net "GND")
		)
		(zone
			(layer "B.Cu")
			(hatch none 0.5)
			(connect_pads
				(clearance 0)
			)
			(min_thickness 0.25)
			(keepout
				(tracks not_allowed)
				(vias allowed)
				(pads allowed)
				(copperpour not_allowed)
				(footprints allowed)
			)
			(placement
				(enabled no)
				(sheetname "")
			)
			(fill
				(thermal_gap 0.5)
				(thermal_bridge_width 0.5)
				(island_removal_mode 0)
			)
			(polygon
				(pts
					(xy 33.340802 -60.608464) (xy 33.340802 -59.338464) (xy 34.102802 -59.338464) (xy 34.102802 -60.608464)
				)
			)
		)
	)
	(footprint ""
		(layer "B.Cu")
		(at 401.412456 -31.000446)
		(property "Reference" "C25W70"
			(at -0.97536 0.76708 90)
			(unlocked yes)
			(layer "B.SilkS")
			(effects
				(font
					(size 0.4064 0.254)
					(thickness 0.1524)
				)
				(justify mirror)
			)
		)
		(property "Value" ""
			(at 0 0 0)
			(layer "B.Fab")
			(effects
				(font
					(size 1.27 1.27)
				)
				(justify mirror)
			)
		)
		(duplicate_pad_numbers_are_jumpers no)
		(fp_poly
			(pts
				(xy 0.4953 -0.2032) (xy -0.4953 -0.2032) (xy -0.4953 1.6002) (xy 0.4953 1.6002)
			)
			(stroke
				(width 0)
				(type default)
			)
			(fill no)
			(layer "B.CrtYd")
		)
		(fp_line
			(start -0.4953 -0.2032)
			(end -0.4953 1.6002)
			(stroke
				(width 0.1)
				(type default)
			)
			(layer "B.Fab")
		)
		(fp_line
			(start -0.4953 1.6002)
			(end 0.4953 1.6002)
			(stroke
				(width 0.1)
				(type default)
			)
			(layer "B.Fab")
		)
		(fp_line
			(start 0.4953 -0.2032)
			(end -0.4953 -0.2032)
			(stroke
				(width 0.1)
				(type default)
			)
			(layer "B.Fab")
		)
		(fp_line
			(start 0.4953 1.6002)
			(end 0.4953 -0.2032)
			(stroke
				(width 0.1)
				(type default)
			)
			(layer "B.Fab")
		)
		(pad "1" smd rect
			(at 0 0 180)
			(size 0.762 0.889)
			(layers "B.Cu" "B.Mask" "B.Paste")
			(net "P3V3_USB2A_ALG")
		)
		(pad "2" smd rect
			(at 0 1.397 180)
			(size 0.762 0.889)
			(layers "B.Cu" "B.Mask" "B.Paste")
			(net "GND")
		)
		(zone
			(layer "B.Cu")
			(hatch none 0.5)
			(connect_pads
				(clearance 0)
			)
			(min_thickness 0.25)
			(keepout
				(tracks not_allowed)
				(vias allowed)
				(pads allowed)
				(copperpour not_allowed)
				(footprints allowed)
			)
			(placement
				(enabled no)
				(sheetname "")
			)
			(fill
				(thermal_gap 0.5)
				(thermal_bridge_width 0.5)
				(island_removal_mode 0)
			)
			(polygon
				(pts
					(xy 401.793456 -30.555946) (xy 401.031456 -30.555946) (xy 401.031456 -30.047946) (xy 401.793456 -30.047946)
				)
			)
		)
	)
	(footprint ""
		(layer "B.Cu")
		(at -2.20726 -119.46636 180)
		(property "Reference" "R9M17"
			(at 0 0 0)
			(layer "B.SilkS")
			(hide yes)
			(effects
				(font
					(size 1.27 1.27)
				)
				(justify mirror)
			)
		)
		(property "Value" ""
			(at 0 0 0)
			(layer "B.Fab")
			(effects
				(font
					(size 1.27 1.27)
				)
				(justify mirror)
			)
		)
		(duplicate_pad_numbers_are_jumpers no)
		(fp_rect
			(start 0.2794 -0.1016)
			(end -0.2794 0.9906)
			(stroke
				(width 0)
				(type default)
			)
			(fill no)
			(layer "B.CrtYd")
		)
		(fp_line
			(start 0.2794 0.9906)
			(end -0.2794 0.9906)
			(stroke
				(width 0.1)
				(type default)
			)
			(layer "B.Fab")
		)
		(fp_line
			(start 0.2794 -0.1016)
			(end 0.2794 0.9906)
			(stroke
				(width 0.1)
				(type default)
			)
			(layer "B.Fab")
		)
		(fp_line
			(start -0.2794 0.9906)
			(end -0.2794 -0.1016)
			(stroke
				(width 0.1)
				(type default)
			)
			(layer "B.Fab")
		)
		(fp_line
			(start -0.2794 -0.1016)
			(end 0.2794 -0.1016)
			(stroke
				(width 0.1)
				(type default)
			)
			(layer "B.Fab")
		)
		(pad "1" smd rect
			(at 0 0)
			(size 0.508 0.508)
			(layers "B.Cu" "B.Mask" "B.Paste")
			(net "P3V3_STBY")
		)
		(pad "2" smd rect
			(at 0 0.889)
			(size 0.508 0.508)
			(layers "B.Cu" "B.Mask" "B.Paste")
			(net "SMB_PEHPCPU1_STBY_LVC3_R_SCL")
		)
		(zone
			(layer "B.Cu")
			(hatch none 0.5)
			(connect_pads
				(clearance 0)
			)
			(min_thickness 0.25)
			(keepout
				(tracks not_allowed)
				(vias allowed)
				(pads allowed)
				(copperpour not_allowed)
				(footprints allowed)
			)
			(placement
				(enabled no)
				(sheetname "")
			)
			(fill
				(thermal_gap 0.5)
				(thermal_bridge_width 0.5)
				(island_removal_mode 0)
			)
			(polygon
				(pts
					(xy -2.46126 -119.72036) (xy -1.95326 -119.72036) (xy -1.95326 -120.10136) (xy -2.46126 -120.10136)
				)
			)
		)
		(zone
			(layer "B.Cu")
			(hatch none 0.5)
			(connect_pads
				(clearance 0)
			)
			(min_thickness 0.25)
			(keepout
				(tracks allowed)
				(vias not_allowed)
				(pads allowed)
				(copperpour not_allowed)
				(footprints allowed)
			)
			(placement
				(enabled no)
				(sheetname "")
			)
			(fill
				(thermal_gap 0.5)
				(thermal_bridge_width 0.5)
				(island_removal_mode 0)
			)
			(polygon
				(pts
					(xy -2.46126 -119.72036) (xy -1.95326 -119.72036) (xy -1.95326 -120.10136) (xy -2.46126 -120.10136)
				)
			)
		)
	)
	(footprint ""
		(layer "B.Cu")
		(at 400.177 -111.379)
		(property "Reference" "C2N5"
			(at 0 0 0)
			(layer "B.SilkS")
			(hide yes)
			(effects
				(font
					(size 1.27 1.27)
				)
				(justify mirror)
			)
		)
		(property "Value" ""
			(at 0 0 0)
			(layer "B.Fab")
			(effects
				(font
					(size 1.27 1.27)
				)
				(justify mirror)
			)
		)
		(duplicate_pad_numbers_are_jumpers no)
		(fp_poly
			(pts
				(xy -0.3048 -0.1016) (xy -0.3048 0.9906) (xy 0.3048 0.9906) (xy 0.3048 -0.1016)
			)
			(stroke
				(width 0)
				(type default)
			)
			(fill no)
			(layer "B.CrtYd")
		)
		(fp_line
			(start -0.3048 -0.1016)
			(end 0.3048 -0.1016)
			(stroke
				(width 0.1)
				(type default)
			)
			(layer "B.Fab")
		)
		(fp_line
			(start -0.3048 0.9906)
			(end -0.3048 -0.1016)
			(stroke
				(width 0.1)
				(type default)
			)
			(layer "B.Fab")
		)
		(fp_line
			(start 0.3048 -0.1016)
			(end 0.3048 0.9906)
			(stroke
				(width 0.1)
				(type default)
			)
			(layer "B.Fab")
		)
		(fp_line
			(start 0.3048 0.9906)
			(end -0.3048 0.9906)
			(stroke
				(width 0.1)
				(type default)
			)
			(layer "B.Fab")
		)
		(pad "1" smd rect
			(at 0 0 180)
			(size 0.508 0.508)
			(layers "B.Cu" "B.Mask" "B.Paste")
			(net "P1V05_PCH_STBY_KR_PLL")
		)
		(pad "2" smd rect
			(at 0 0.889 180)
			(size 0.508 0.508)
			(layers "B.Cu" "B.Mask" "B.Paste")
			(net "GND")
		)
		(zone
			(layer "B.Cu")
			(hatch none 0.5)
			(connect_pads
				(clearance 0)
			)
			(min_thickness 0.25)
			(keepout
				(tracks allowed)
				(vias not_allowed)
				(pads allowed)
				(copperpour not_allowed)
				(footprints allowed)
			)
			(placement
				(enabled no)
				(sheetname "")
			)
			(fill
				(thermal_gap 0.5)
				(thermal_bridge_width 0.5)
				(island_removal_mode 0)
			)
			(polygon
				(pts
					(xy 400.431 -111.125) (xy 399.923 -111.125) (xy 399.923 -110.744) (xy 400.431 -110.744)
				)
			)
		)
		(zone
			(layer "B.Cu")
			(hatch none 0.5)
			(connect_pads
				(clearance 0)
			)
			(min_thickness 0.25)
			(keepout
				(tracks not_allowed)
				(vias allowed)
				(pads allowed)
				(copperpour not_allowed)
				(footprints allowed)
			)
			(placement
				(enabled no)
				(sheetname "")
			)
			(fill
				(thermal_gap 0.5)
				(thermal_bridge_width 0.5)
				(island_removal_mode 0)
			)
			(polygon
				(pts
					(xy 400.431 -110.744) (xy 399.923 -110.744) (xy 399.923 -111.125) (xy 400.431 -111.125)
				)
			)
		)
	)
	(footprint ""
		(layer "B.Cu")
		(at 197.848728 -67.978782 90)
		(property "Reference" "C6P22"
			(at 0 0 90)
			(layer "B.SilkS")
			(hide yes)
			(effects
				(font
					(size 1.27 1.27)
				)
				(justify mirror)
			)
		)
		(property "Value" ""
			(at 0 0 90)
			(layer "B.Fab")
			(effects
				(font
					(size 1.27 1.27)
				)
				(justify mirror)
			)
		)
		(duplicate_pad_numbers_are_jumpers no)
		(fp_rect
			(start -0.7239 -0.2159)
			(end 0.7239 1.9939)
			(stroke
				(width 0)
				(type default)
			)
			(fill no)
			(layer "B.CrtYd")
		)
		(fp_line
			(start 0.7239 -0.2159)
			(end 0.7239 1.9939)
			(stroke
				(width 0.1)
				(type default)
			)
			(layer "B.Fab")
		)
		(fp_line
			(start -0.7239 -0.2159)
			(end 0.7239 -0.2159)
			(stroke
				(width 0.1)
				(type default)
			)
			(layer "B.Fab")
		)
		(fp_line
			(start 0.7239 1.9939)
			(end -0.7239 1.9939)
			(stroke
				(width 0.1)
				(type default)
			)
			(layer "B.Fab")
		)
		(fp_line
			(start -0.7239 1.9939)
			(end -0.7239 -0.2159)
			(stroke
				(width 0.1)
				(type default)
			)
			(layer "B.Fab")
		)
		(pad "1" smd rect
			(at 0 0 270)
			(size 1.27 1.016)
			(layers "B.Cu" "B.Mask" "B.Paste")
			(net "VR_FET_SW_P12V_STBY_PVCCIN_CPU0")
		)
		(pad "2" smd rect
			(at 0 1.778 270)
			(size 1.27 1.016)
			(layers "B.Cu" "B.Mask" "B.Paste")
			(net "GND")
		)
		(zone
			(layer "B.Cu")
			(hatch none 0.5)
			(connect_pads
				(clearance 0)
			)
			(min_thickness 0.25)
			(keepout
				(tracks not_allowed)
				(vias allowed)
				(pads allowed)
				(copperpour not_allowed)
				(footprints allowed)
			)
			(placement
				(enabled no)
				(sheetname "")
			)
			(fill
				(thermal_gap 0.5)
				(thermal_bridge_width 0.5)
				(island_removal_mode 0)
			)
			(polygon
				(pts
					(xy 198.356728 -67.343782) (xy 199.118728 -67.343782) (xy 199.118728 -68.613782) (xy 198.356728 -68.613782)
				)
			)
		)
	)
	(footprint ""
		(layer "B.Cu")
		(at 420.624 -154.94 90)
		(property "Reference" "C2L4"
			(at 0 0 90)
			(layer "B.SilkS")
			(hide yes)
			(effects
				(font
					(size 1.27 1.27)
				)
				(justify mirror)
			)
		)
		(property "Value" ""
			(at 0 0 90)
			(layer "B.Fab")
			(effects
				(font
					(size 1.27 1.27)
				)
				(justify mirror)
			)
		)
		(duplicate_pad_numbers_are_jumpers no)
		(fp_poly
			(pts
				(xy -0.3048 -0.1016) (xy -0.3048 0.9906) (xy 0.3048 0.9906) (xy 0.3048 -0.1016)
			)
			(stroke
				(width 0)
				(type default)
			)
			(fill no)
			(layer "B.CrtYd")
		)
		(fp_line
			(start 0.3048 -0.1016)
			(end 0.3048 0.9906)
			(stroke
				(width 0.1)
				(type default)
			)
			(layer "B.Fab")
		)
		(fp_line
			(start -0.3048 -0.1016)
			(end 0.3048 -0.1016)
			(stroke
				(width 0.1)
				(type default)
			)
			(layer "B.Fab")
		)
		(fp_line
			(start 0.3048 0.9906)
			(end -0.3048 0.9906)
			(stroke
				(width 0.1)
				(type default)
			)
			(layer "B.Fab")
		)
		(fp_line
			(start -0.3048 0.9906)
			(end -0.3048 -0.1016)
			(stroke
				(width 0.1)
				(type default)
			)
			(layer "B.Fab")
		)
		(pad "1" smd rect
			(at 0 0 270)
			(size 0.508 0.508)
			(layers "B.Cu" "B.Mask" "B.Paste")
			(net "SATA6G_PCH_PCIE_UP_SATA_RXP<3>")
		)
		(pad "2" smd rect
			(at 0 0.889 270)
			(size 0.508 0.508)
			(layers "B.Cu" "B.Mask" "B.Paste")
			(net "SATA6G_P3_RX_C_DP")
		)
		(zone
			(layer "B.Cu")
			(hatch none 0.5)
			(connect_pads
				(clearance 0)
			)
			(min_thickness 0.25)
			(keepout
				(tracks allowed)
				(vias not_allowed)
				(pads allowed)
				(copperpour not_allowed)
				(footprints allowed)
			)
			(placement
				(enabled no)
				(sheetname "")
			)
			(fill
				(thermal_gap 0.5)
				(thermal_bridge_width 0.5)
				(island_removal_mode 0)
			)
			(polygon
				(pts
					(xy 420.878 -155.194) (xy 420.878 -154.686) (xy 421.259 -154.686) (xy 421.259 -155.194)
				)
			)
		)
		(zone
			(layer "B.Cu")
			(hatch none 0.5)
			(connect_pads
				(clearance 0)
			)
			(min_thickness 0.25)
			(keepout
				(tracks not_allowed)
				(vias allowed)
				(pads allowed)
				(copperpour not_allowed)
				(footprints allowed)
			)
			(placement
				(enabled no)
				(sheetname "")
			)
			(fill
				(thermal_gap 0.5)
				(thermal_bridge_width 0.5)
				(island_removal_mode 0)
			)
			(polygon
				(pts
					(xy 421.259 -155.194) (xy 421.259 -154.686) (xy 420.878 -154.686) (xy 420.878 -155.194)
				)
			)
		)
	)
	(footprint ""
		(layer "B.Cu")
		(at 336.042 -104.394 90)
		(property "Reference" "C3N26"
			(at 1.24333 -3.81 0)
			(unlocked yes)
			(layer "B.SilkS")
			(effects
				(font
					(size 0.7874 0.5842)
					(thickness 0.1524)
				)
				(justify mirror)
			)
		)
		(property "Value" ""
			(at 0 0 90)
			(layer "B.Fab")
			(effects
				(font
					(size 1.27 1.27)
				)
				(justify mirror)
			)
		)
		(duplicate_pad_numbers_are_jumpers no)
		(fp_line
			(start 2.563114 -1.616456)
			(end 2.563114 1.633728)
			(stroke
				(width 0.1524)
				(type default)
			)
			(layer "B.SilkS")
		)
		(fp_line
			(start 1.6002 -1.616456)
			(end 2.563114 -1.616456)
			(stroke
				(width 0.1524)
				(type default)
			)
			(layer "B.SilkS")
		)
		(fp_line
			(start -1.6002 -1.616456)
			(end -2.504948 -1.616456)
			(stroke
				(width 0.1524)
				(type default)
			)
			(layer "B.SilkS")
		)
		(fp_line
			(start -2.504948 -1.616456)
			(end -2.504948 1.633728)
			(stroke
				(width 0.1524)
				(type default)
			)
			(layer "B.SilkS")
		)
		(fp_line
			(start 2.563114 1.633728)
			(end 1.6002 1.633728)
			(stroke
				(width 0.1524)
				(type default)
			)
			(layer "B.SilkS")
		)
		(fp_line
			(start -2.504948 1.633728)
			(end -1.6002 1.633728)
			(stroke
				(width 0.1524)
				(type default)
			)
			(layer "B.SilkS")
		)
		(fp_line
			(start 2.286 7.366)
			(end 2.286 1.632712)
			(stroke
				(width 0.1524)
				(type default)
			)
			(layer "B.SilkS")
		)
		(fp_line
			(start 2.286 7.366)
			(end 1.60147 7.366)
			(stroke
				(width 0.1524)
				(type default)
			)
			(layer "B.SilkS")
		)
		(fp_line
			(start -2.286 7.366)
			(end -2.286 1.63195)
			(stroke
				(width 0.1524)
				(type default)
			)
			(layer "B.SilkS")
		)
		(fp_line
			(start -2.286 7.366)
			(end -1.600708 7.366)
			(stroke
				(width 0.1524)
				(type default)
			)
			(layer "B.SilkS")
		)
		(fp_rect
			(start 2.286 7.366)
			(end -2.286 -0.254)
			(stroke
				(width 0)
				(type default)
			)
			(fill no)
			(layer "B.CrtYd")
		)
		(fp_line
			(start 2.286 -0.254)
			(end -2.286 -0.254)
			(stroke
				(width 0.1)
				(type default)
			)
			(layer "B.Fab")
		)
		(fp_line
			(start -2.286 -0.254)
			(end -2.286 7.366)
			(stroke
				(width 0.1)
				(type default)
			)
			(layer "B.Fab")
		)
		(fp_line
			(start 2.286 7.366)
			(end 2.286 -0.254)
			(stroke
				(width 0.1)
				(type default)
			)
			(layer "B.Fab")
		)
		(fp_line
			(start -2.286 7.366)
			(end 2.286 7.366)
			(stroke
				(width 0.1)
				(type default)
			)
			(layer "B.Fab")
		)
		(pad "1" smd rect
			(at 0 0 270)
			(size 2.54 3.048)
			(layers "B.Cu" "B.Mask" "B.Paste")
			(net "PVCCIO_CPU0")
		)
		(pad "2" smd rect
			(at 0 7.112 270)
			(size 2.54 3.048)
			(layers "B.Cu" "B.Mask" "B.Paste")
			(net "GND")
		)
	)
	(footprint ""
		(layer "B.Cu")
		(at 368.184938 -102.18039 -90)
		(property "Reference" "C3N31"
			(at 0 0 90)
			(layer "B.SilkS")
			(hide yes)
			(effects
				(font
					(size 1.27 1.27)
				)
				(justify mirror)
			)
		)
		(property "Value" ""
			(at 0 0 90)
			(layer "B.Fab")
			(effects
				(font
					(size 1.27 1.27)
				)
				(justify mirror)
			)
		)
		(duplicate_pad_numbers_are_jumpers no)
		(fp_poly
			(pts
				(xy 0.4953 -0.2032) (xy -0.4953 -0.2032) (xy -0.4953 1.6002) (xy 0.4953 1.6002)
			)
			(stroke
				(width 0)
				(type default)
			)
			(fill no)
			(layer "B.CrtYd")
		)
		(fp_line
			(start -0.4953 1.6002)
			(end 0.4953 1.6002)
			(stroke
				(width 0.1)
				(type default)
			)
			(layer "B.Fab")
		)
		(fp_line
			(start 0.4953 1.6002)
			(end 0.4953 -0.2032)
			(stroke
				(width 0.1)
				(type default)
			)
			(layer "B.Fab")
		)
		(fp_line
			(start -0.4953 -0.2032)
			(end -0.4953 1.6002)
			(stroke
				(width 0.1)
				(type default)
			)
			(layer "B.Fab")
		)
		(fp_line
			(start 0.4953 -0.2032)
			(end -0.4953 -0.2032)
			(stroke
				(width 0.1)
				(type default)
			)
			(layer "B.Fab")
		)
		(pad "1" smd rect
			(at 0 0 90)
			(size 0.762 0.889)
			(layers "B.Cu" "B.Mask" "B.Paste")
			(net "PVNN_PCH_STBY")
		)
		(pad "2" smd rect
			(at 0 1.397 90)
			(size 0.762 0.889)
			(layers "B.Cu" "B.Mask" "B.Paste")
			(net "GND")
		)
		(zone
			(layer "B.Cu")
			(hatch none 0.5)
			(connect_pads
				(clearance 0)
			)
			(min_thickness 0.25)
			(keepout
				(tracks not_allowed)
				(vias allowed)
				(pads allowed)
				(copperpour not_allowed)
				(footprints allowed)
			)
			(placement
				(enabled no)
				(sheetname "")
			)
			(fill
				(thermal_gap 0.5)
				(thermal_bridge_width 0.5)
				(island_removal_mode 0)
			)
			(polygon
				(pts
					(xy 367.740438 -101.79939) (xy 367.740438 -102.56139) (xy 367.232438 -102.56139) (xy 367.232438 -101.79939)
				)
			)
		)
	)
	(footprint ""
		(layer "B.Cu")
		(at 438.833006 -41.648126 180)
		(property "Reference" "R25W10"
			(at 0 0 0)
			(layer "B.SilkS")
			(hide yes)
			(effects
				(font
					(size 1.27 1.27)
				)
				(justify mirror)
			)
		)
		(property "Value" "*"
			(at -0.064008 -4.108196 180)
			(unlocked yes)
			(layer "B.Fab")
			(hide yes)
			(effects
				(font
					(size 1.27 1.016)
					(thickness 0.1524)
				)
				(justify mirror)
			)
		)
		(property "Device Type" "120R2F-GP_RCL_GP-120R2F-GP,64.A"
			(at -0.064008 -5.632196 180)
			(unlocked yes)
			(layer "B.Fab")
			(hide yes)
			(effects
				(font
					(size 1.27 1.016)
					(thickness 0.1524)
				)
				(justify mirror)
			)
		)
		(duplicate_pad_numbers_are_jumpers no)
		(fp_line
			(start 0.508 -0.9398)
			(end 0.508 0.9398)
			(stroke
				(width 0.1524)
				(type default)
			)
			(layer "B.SilkS")
		)
		(fp_line
			(start -0.508 -0.9398)
			(end 0.508 -0.9398)
			(stroke
				(width 0.1524)
				(type default)
			)
			(layer "B.SilkS")
		)
		(fp_rect
			(start 0.508 0.9398)
			(end -0.508 -0.9398)
			(stroke
				(width 0)
				(type default)
			)
			(fill no)
			(layer "B.CrtYd")
		)
		(fp_rect
			(start 0.508 0.9398)
			(end -0.508 -0.9398)
			(stroke
				(width 0)
				(type default)
			)
			(fill no)
			(layer "B.Fab")
		)
		(pad "1" smd custom
			(at 0 -0.4445)
			(size 0.1397 0.1397)
			(layers "B.Cu" "B.Mask" "B.Paste")
			(net "GND")
			(options
				(clearance outline)
				(anchor circle)
			)
			(primitives
				(gr_poly
					(pts
						(arc
							(start -0.1778 0.2794)
							(mid -0.249642 0.249642)
							(end -0.2794 0.1778)
						)
						(arc
							(start -0.2794 -0.1778)
							(mid -0.249642 -0.249642)
							(end -0.1778 -0.2794)
						)
						(arc
							(start 0.1778 -0.2794)
							(mid 0.249642 -0.249642)
							(end 0.2794 -0.1778)
						)
						(arc
							(start 0.2794 0.1778)
							(mid 0.249642 0.249642)
							(end 0.1778 0.2794)
						)
					)
					(width 0)
					(fill yes)
				)
			)
		)
		(pad "2" smd custom
			(at 0 0.4445)
			(size 0.1397 0.1397)
			(layers "B.Cu" "B.Mask" "B.Paste")
			(net "BMC_M_BA1")
			(options
				(clearance outline)
				(anchor circle)
			)
			(primitives
				(gr_poly
					(pts
						(arc
							(start -0.1778 0.2794)
							(mid -0.249642 0.249642)
							(end -0.2794 0.1778)
						)
						(arc
							(start -0.2794 -0.1778)
							(mid -0.249642 -0.249642)
							(end -0.1778 -0.2794)
						)
						(arc
							(start 0.1778 -0.2794)
							(mid 0.249642 -0.249642)
							(end 0.2794 -0.1778)
						)
						(arc
							(start 0.2794 0.1778)
							(mid 0.249642 0.249642)
							(end 0.1778 0.2794)
						)
					)
					(width 0)
					(fill yes)
				)
			)
		)
	)
	(footprint ""
		(layer "B.Cu")
		(at 355.736398 -77.915516 180)
		(property "Reference" "C3P35"
			(at 0 0 0)
			(layer "B.SilkS")
			(hide yes)
			(effects
				(font
					(size 1.27 1.27)
				)
				(justify mirror)
			)
		)
		(property "Value" ""
			(at 0 0 0)
			(layer "B.Fab")
			(effects
				(font
					(size 1.27 1.27)
				)
				(justify mirror)
			)
		)
		(duplicate_pad_numbers_are_jumpers no)
		(fp_poly
			(pts
				(xy -0.3048 -0.1016) (xy -0.3048 0.9906) (xy 0.3048 0.9906) (xy 0.3048 -0.1016)
			)
			(stroke
				(width 0)
				(type default)
			)
			(fill no)
			(layer "B.CrtYd")
		)
		(fp_line
			(start 0.3048 0.9906)
			(end -0.3048 0.9906)
			(stroke
				(width 0.1)
				(type default)
			)
			(layer "B.Fab")
		)
		(fp_line
			(start 0.3048 -0.1016)
			(end 0.3048 0.9906)
			(stroke
				(width 0.1)
				(type default)
			)
			(layer "B.Fab")
		)
		(fp_line
			(start -0.3048 0.9906)
			(end -0.3048 -0.1016)
			(stroke
				(width 0.1)
				(type default)
			)
			(layer "B.Fab")
		)
		(fp_line
			(start -0.3048 -0.1016)
			(end 0.3048 -0.1016)
			(stroke
				(width 0.1)
				(type default)
			)
			(layer "B.Fab")
		)
		(pad "1" smd rect
			(at 0 0)
			(size 0.508 0.508)
			(layers "B.Cu" "B.Mask" "B.Paste")
			(net "P3E_CPU0_PE1_SS_TXP<6>")
		)
		(pad "2" smd rect
			(at 0 0.889)
			(size 0.508 0.508)
			(layers "B.Cu" "B.Mask" "B.Paste")
			(net "P3E_CPU0_PE1_PCH_TXP<6>")
		)
		(zone
			(layer "B.Cu")
			(hatch none 0.5)
			(connect_pads
				(clearance 0)
			)
			(min_thickness 0.25)
			(keepout
				(tracks not_allowed)
				(vias allowed)
				(pads allowed)
				(copperpour not_allowed)
				(footprints allowed)
			)
			(placement
				(enabled no)
				(sheetname "")
			)
			(fill
				(thermal_gap 0.5)
				(thermal_bridge_width 0.5)
				(island_removal_mode 0)
			)
			(polygon
				(pts
					(xy 355.482398 -78.550516) (xy 355.990398 -78.550516) (xy 355.990398 -78.169516) (xy 355.482398 -78.169516)
				)
			)
		)
		(zone
			(layer "B.Cu")
			(hatch none 0.5)
			(connect_pads
				(clearance 0)
			)
			(min_thickness 0.25)
			(keepout
				(tracks allowed)
				(vias not_allowed)
				(pads allowed)
				(copperpour not_allowed)
				(footprints allowed)
			)
			(placement
				(enabled no)
				(sheetname "")
			)
			(fill
				(thermal_gap 0.5)
				(thermal_bridge_width 0.5)
				(island_removal_mode 0)
			)
			(polygon
				(pts
					(xy 355.482398 -78.169516) (xy 355.990398 -78.169516) (xy 355.990398 -78.550516) (xy 355.482398 -78.550516)
				)
			)
		)
	)
	(footprint ""
		(layer "B.Cu")
		(at 336.140806 -60.368434)
		(property "Reference" "R2U16"
			(at 0 0 0)
			(layer "B.SilkS")
			(hide yes)
			(effects
				(font
					(size 1.27 1.27)
				)
				(justify mirror)
			)
		)
		(property "Value" ""
			(at 0 0 0)
			(layer "B.Fab")
			(effects
				(font
					(size 1.27 1.27)
				)
				(justify mirror)
			)
		)
		(duplicate_pad_numbers_are_jumpers no)
		(fp_poly
			(pts
				(xy 0.2794 -0.1016) (xy -0.2794 -0.1016) (xy -0.2794 0.9906) (xy 0.2794 0.9906)
			)
			(stroke
				(width 0)
				(type default)
			)
			(fill no)
			(layer "B.CrtYd")
		)
		(fp_line
			(start -0.2794 -0.1016)
			(end 0.2794 -0.1016)
			(stroke
				(width 0.1)
				(type default)
			)
			(layer "B.Fab")
		)
		(fp_line
			(start -0.2794 0.9906)
			(end -0.2794 -0.1016)
			(stroke
				(width 0.1)
				(type default)
			)
			(layer "B.Fab")
		)
		(fp_line
			(start 0.2794 -0.1016)
			(end 0.2794 0.9906)
			(stroke
				(width 0.1)
				(type default)
			)
			(layer "B.Fab")
		)
		(fp_line
			(start 0.2794 0.9906)
			(end -0.2794 0.9906)
			(stroke
				(width 0.1)
				(type default)
			)
			(layer "B.Fab")
		)
		(pad "1" smd rect
			(at 0 0 180)
			(size 0.508 0.508)
			(layers "B.Cu" "B.Mask" "B.Paste")
			(net "P3E_CPU0_PE1_SS_RXP<1>")
		)
		(pad "2" smd rect
			(at 0 0.889 180)
			(size 0.508 0.508)
			(layers "B.Cu" "B.Mask" "B.Paste")
			(net "P3E_CPU0_PE1_SS_R_RXP<1>")
		)
		(zone
			(layer "B.Cu")
			(hatch none 0.5)
			(connect_pads
				(clearance 0)
			)
			(min_thickness 0.25)
			(keepout
				(tracks allowed)
				(vias not_allowed)
				(pads allowed)
				(copperpour not_allowed)
				(footprints allowed)
			)
			(placement
				(enabled no)
				(sheetname "")
			)
			(fill
				(thermal_gap 0.5)
				(thermal_bridge_width 0.5)
				(island_removal_mode 0)
			)
			(polygon
				(pts
					(xy 336.394806 -60.114434) (xy 335.886806 -60.114434) (xy 335.886806 -59.733434) (xy 336.394806 -59.733434)
				)
			)
		)
		(zone
			(layer "B.Cu")
			(hatch none 0.5)
			(connect_pads
				(clearance 0)
			)
			(min_thickness 0.25)
			(keepout
				(tracks not_allowed)
				(vias allowed)
				(pads allowed)
				(copperpour not_allowed)
				(footprints allowed)
			)
			(placement
				(enabled no)
				(sheetname "")
			)
			(fill
				(thermal_gap 0.5)
				(thermal_bridge_width 0.5)
				(island_removal_mode 0)
			)
			(polygon
				(pts
					(xy 336.394806 -59.733434) (xy 335.886806 -59.733434) (xy 335.886806 -60.114434) (xy 336.394806 -60.114434)
				)
			)
		)
	)
	(footprint ""
		(layer "B.Cu")
		(at 10.551668 -3.321812 180)
		(property "Reference" "R9U3"
			(at 0 0 0)
			(layer "B.SilkS")
			(hide yes)
			(effects
				(font
					(size 1.27 1.27)
				)
				(justify mirror)
			)
		)
		(property "Value" ""
			(at 0 0 0)
			(layer "B.Fab")
			(effects
				(font
					(size 1.27 1.27)
				)
				(justify mirror)
			)
		)
		(duplicate_pad_numbers_are_jumpers no)
		(fp_rect
			(start 0.2794 0.9906)
			(end -0.2794 -0.1016)
			(stroke
				(width 0)
				(type default)
			)
			(fill no)
			(layer "B.CrtYd")
		)
		(fp_line
			(start 0.2794 0.9906)
			(end -0.2794 0.9906)
			(stroke
				(width 0.1)
				(type default)
			)
			(layer "B.Fab")
		)
		(fp_line
			(start 0.2794 -0.1016)
			(end 0.2794 0.9906)
			(stroke
				(width 0.1)
				(type default)
			)
			(layer "B.Fab")
		)
		(fp_line
			(start -0.2794 0.9906)
			(end -0.2794 -0.1016)
			(stroke
				(width 0.1)
				(type default)
			)
			(layer "B.Fab")
		)
		(fp_line
			(start -0.2794 -0.1016)
			(end 0.2794 -0.1016)
			(stroke
				(width 0.1)
				(type default)
			)
			(layer "B.Fab")
		)
		(pad "1" smd rect
			(at 0 0)
			(size 0.508 0.508)
			(layers "B.Cu" "B.Mask" "B.Paste")
			(net "PVCCIO_CPU1")
		)
		(pad "2" smd rect
			(at 0 0.889)
			(size 0.508 0.508)
			(layers "B.Cu" "B.Mask" "B.Paste")
			(net "SVID_DIO1_CPU1_R")
		)
		(zone
			(layer "B.Cu")
			(hatch none 0.5)
			(connect_pads
				(clearance 0)
			)
			(min_thickness 0.25)
			(keepout
				(tracks allowed)
				(vias not_allowed)
				(pads allowed)
				(copperpour not_allowed)
				(footprints allowed)
			)
			(placement
				(enabled no)
				(sheetname "")
			)
			(fill
				(thermal_gap 0.5)
				(thermal_bridge_width 0.5)
				(island_removal_mode 0)
			)
			(polygon
				(pts
					(xy 10.297668 -3.956812) (xy 10.297668 -3.575812) (xy 10.805668 -3.575812) (xy 10.805668 -3.956812)
				)
			)
		)
		(zone
			(layer "B.Cu")
			(hatch none 0.5)
			(connect_pads
				(clearance 0)
			)
			(min_thickness 0.25)
			(keepout
				(tracks not_allowed)
				(vias allowed)
				(pads allowed)
				(copperpour not_allowed)
				(footprints allowed)
			)
			(placement
				(enabled no)
				(sheetname "")
			)
			(fill
				(thermal_gap 0.5)
				(thermal_bridge_width 0.5)
				(island_removal_mode 0)
			)
			(polygon
				(pts
					(xy 10.297668 -3.956812) (xy 10.297668 -3.575812) (xy 10.805668 -3.575812) (xy 10.805668 -3.956812)
				)
			)
		)
	)
	(footprint ""
		(layer "B.Cu")
		(at 402.4503 -37.8968 -90)
		(property "Reference" "R2U10"
			(at 0 0 90)
			(layer "B.SilkS")
			(hide yes)
			(effects
				(font
					(size 1.27 1.27)
				)
				(justify mirror)
			)
		)
		(property "Value" ""
			(at 0 0 90)
			(layer "B.Fab")
			(effects
				(font
					(size 1.27 1.27)
				)
				(justify mirror)
			)
		)
		(duplicate_pad_numbers_are_jumpers no)
		(fp_poly
			(pts
				(xy 0.2794 -0.1016) (xy -0.2794 -0.1016) (xy -0.2794 0.9906) (xy 0.2794 0.9906)
			)
			(stroke
				(width 0)
				(type default)
			)
			(fill no)
			(layer "B.CrtYd")
		)
		(fp_line
			(start -0.2794 0.9906)
			(end -0.2794 -0.1016)
			(stroke
				(width 0.1)
				(type default)
			)
			(layer "B.Fab")
		)
		(fp_line
			(start 0.2794 0.9906)
			(end -0.2794 0.9906)
			(stroke
				(width 0.1)
				(type default)
			)
			(layer "B.Fab")
		)
		(fp_line
			(start -0.2794 -0.1016)
			(end 0.2794 -0.1016)
			(stroke
				(width 0.1)
				(type default)
			)
			(layer "B.Fab")
		)
		(fp_line
			(start 0.2794 -0.1016)
			(end 0.2794 0.9906)
			(stroke
				(width 0.1)
				(type default)
			)
			(layer "B.Fab")
		)
		(pad "1" smd rect
			(at 0 0 90)
			(size 0.508 0.508)
			(layers "B.Cu" "B.Mask" "B.Paste")
			(net "SMB_OCP_FRU_STBY_LVC3_SDA_R")
		)
		(pad "2" smd rect
			(at 0 0.889 90)
			(size 0.508 0.508)
			(layers "B.Cu" "B.Mask" "B.Paste")
			(net "SMB_OCP_FRU_STBY_LVC3_SDA")
		)
		(zone
			(layer "B.Cu")
			(hatch none 0.5)
			(connect_pads
				(clearance 0)
			)
			(min_thickness 0.25)
			(keepout
				(tracks not_allowed)
				(vias allowed)
				(pads allowed)
				(copperpour not_allowed)
				(footprints allowed)
			)
			(placement
				(enabled no)
				(sheetname "")
			)
			(fill
				(thermal_gap 0.5)
				(thermal_bridge_width 0.5)
				(island_removal_mode 0)
			)
			(polygon
				(pts
					(xy 401.8153 -37.6428) (xy 401.8153 -38.1508) (xy 402.1963 -38.1508) (xy 402.1963 -37.6428)
				)
			)
		)
		(zone
			(layer "B.Cu")
			(hatch none 0.5)
			(connect_pads
				(clearance 0)
			)
			(min_thickness 0.25)
			(keepout
				(tracks allowed)
				(vias not_allowed)
				(pads allowed)
				(copperpour not_allowed)
				(footprints allowed)
			)
			(placement
				(enabled no)
				(sheetname "")
			)
			(fill
				(thermal_gap 0.5)
				(thermal_bridge_width 0.5)
				(island_removal_mode 0)
			)
			(polygon
				(pts
					(xy 402.1963 -37.6428) (xy 402.1963 -38.1508) (xy 401.8153 -38.1508) (xy 401.8153 -37.6428)
				)
			)
		)
	)
	(footprint ""
		(layer "B.Cu")
		(at 344.59037 -133.92277 180)
		(property "Reference" "C22W7"
			(at 0 0 0)
			(layer "B.SilkS")
			(hide yes)
			(effects
				(font
					(size 1.27 1.27)
				)
				(justify mirror)
			)
		)
		(property "Value" "*"
			(at 0.0762 -6.2357 180)
			(unlocked yes)
			(layer "B.Fab")
			(hide yes)
			(effects
				(font
					(size 1.27 1.016)
					(thickness 0.1524)
				)
				(justify mirror)
			)
		)
		(property "Device Type" "SC22U16V5MX-4-GP_SMD-BCG5-SC22A"
			(at 0.0762 -8.2677 180)
			(unlocked yes)
			(layer "B.Fab")
			(hide yes)
			(effects
				(font
					(size 1.27 1.016)
					(thickness 0.1524)
				)
				(justify mirror)
			)
		)
		(duplicate_pad_numbers_are_jumpers no)
		(fp_line
			(start -0.635 0)
			(end 0.635 0)
			(stroke
				(width 0.508)
				(type default)
			)
			(layer "B.SilkS")
		)
		(fp_rect
			(start 0.9652 1.778)
			(end -0.9652 -1.778)
			(stroke
				(width 0)
				(type default)
			)
			(fill no)
			(layer "B.CrtYd")
		)
		(fp_poly
			(pts
				(xy 0.9652 -1.778) (xy -0.9652 -1.778) (xy -0.9652 1.778) (xy 0.9652 1.778)
			)
			(stroke
				(width 0)
				(type default)
			)
			(fill no)
			(layer "B.Fab")
		)
		(pad "1" smd rect
			(at 0 -0.9652)
			(size 1.397 1.143)
			(layers "B.Cu" "B.Mask" "B.Paste")
			(net "VR_FET_SW_P12V_STBY_PVPP_DEF")
		)
		(pad "2" smd rect
			(at 0 0.9652)
			(size 1.397 1.143)
			(layers "B.Cu" "B.Mask" "B.Paste")
			(net "GND")
		)
	)
	(footprint ""
		(layer "B.Cu")
		(at 380.8476 -137.541)
		(property "Reference" "C3L27"
			(at 0 0 0)
			(layer "B.SilkS")
			(hide yes)
			(effects
				(font
					(size 1.27 1.27)
				)
				(justify mirror)
			)
		)
		(property "Value" ""
			(at 0 0 0)
			(layer "B.Fab")
			(effects
				(font
					(size 1.27 1.27)
				)
				(justify mirror)
			)
		)
		(duplicate_pad_numbers_are_jumpers no)
		(fp_poly
			(pts
				(xy 0.4953 -0.2032) (xy -0.4953 -0.2032) (xy -0.4953 1.6002) (xy 0.4953 1.6002)
			)
			(stroke
				(width 0)
				(type default)
			)
			(fill no)
			(layer "B.CrtYd")
		)
		(fp_line
			(start -0.4953 -0.2032)
			(end -0.4953 1.6002)
			(stroke
				(width 0.1)
				(type default)
			)
			(layer "B.Fab")
		)
		(fp_line
			(start -0.4953 1.6002)
			(end 0.4953 1.6002)
			(stroke
				(width 0.1)
				(type default)
			)
			(layer "B.Fab")
		)
		(fp_line
			(start 0.4953 -0.2032)
			(end -0.4953 -0.2032)
			(stroke
				(width 0.1)
				(type default)
			)
			(layer "B.Fab")
		)
		(fp_line
			(start 0.4953 1.6002)
			(end 0.4953 -0.2032)
			(stroke
				(width 0.1)
				(type default)
			)
			(layer "B.Fab")
		)
		(pad "1" smd rect
			(at 0 0 180)
			(size 0.762 0.889)
			(layers "B.Cu" "B.Mask" "B.Paste")
			(net "PVNN_PCH_STBY")
		)
		(pad "2" smd rect
			(at 0 1.397 180)
			(size 0.762 0.889)
			(layers "B.Cu" "B.Mask" "B.Paste")
			(net "GND")
		)
		(zone
			(layer "B.Cu")
			(hatch none 0.5)
			(connect_pads
				(clearance 0)
			)
			(min_thickness 0.25)
			(keepout
				(tracks not_allowed)
				(vias allowed)
				(pads allowed)
				(copperpour not_allowed)
				(footprints allowed)
			)
			(placement
				(enabled no)
				(sheetname "")
			)
			(fill
				(thermal_gap 0.5)
				(thermal_bridge_width 0.5)
				(island_removal_mode 0)
			)
			(polygon
				(pts
					(xy 381.2286 -137.0965) (xy 380.4666 -137.0965) (xy 380.4666 -136.5885) (xy 381.2286 -136.5885)
				)
			)
		)
	)
	(footprint ""
		(layer "B.Cu")
		(at 49.4284 -63.080392)
		(property "Reference" "C9R2"
			(at 0 0 0)
			(layer "B.SilkS")
			(hide yes)
			(effects
				(font
					(size 1.27 1.27)
				)
				(justify mirror)
			)
		)
		(property "Value" ""
			(at 0 0 0)
			(layer "B.Fab")
			(effects
				(font
					(size 1.27 1.27)
				)
				(justify mirror)
			)
		)
		(duplicate_pad_numbers_are_jumpers no)
		(fp_poly
			(pts
				(xy 0.4953 -0.2032) (xy -0.4953 -0.2032) (xy -0.4953 1.6002) (xy 0.4953 1.6002)
			)
			(stroke
				(width 0)
				(type default)
			)
			(fill no)
			(layer "B.CrtYd")
		)
		(fp_line
			(start -0.4953 -0.2032)
			(end -0.4953 1.6002)
			(stroke
				(width 0.1)
				(type default)
			)
			(layer "B.Fab")
		)
		(fp_line
			(start -0.4953 1.6002)
			(end 0.4953 1.6002)
			(stroke
				(width 0.1)
				(type default)
			)
			(layer "B.Fab")
		)
		(fp_line
			(start 0.4953 -0.2032)
			(end -0.4953 -0.2032)
			(stroke
				(width 0.1)
				(type default)
			)
			(layer "B.Fab")
		)
		(fp_line
			(start 0.4953 1.6002)
			(end 0.4953 -0.2032)
			(stroke
				(width 0.1)
				(type default)
			)
			(layer "B.Fab")
		)
		(pad "1" smd rect
			(at 0 0 180)
			(size 0.762 0.889)
			(layers "B.Cu" "B.Mask" "B.Paste")
			(net "PVCCIN_CPU1")
		)
		(pad "2" smd rect
			(at 0 1.397 180)
			(size 0.762 0.889)
			(layers "B.Cu" "B.Mask" "B.Paste")
			(net "GND")
		)
		(zone
			(layer "B.Cu")
			(hatch none 0.5)
			(connect_pads
				(clearance 0)
			)
			(min_thickness 0.25)
			(keepout
				(tracks not_allowed)
				(vias allowed)
				(pads allowed)
				(copperpour not_allowed)
				(footprints allowed)
			)
			(placement
				(enabled no)
				(sheetname "")
			)
			(fill
				(thermal_gap 0.5)
				(thermal_bridge_width 0.5)
				(island_removal_mode 0)
			)
			(polygon
				(pts
					(xy 49.8094 -62.635892) (xy 49.0474 -62.635892) (xy 49.0474 -62.127892) (xy 49.8094 -62.127892)
				)
			)
		)
	)
	(footprint ""
		(layer "B.Cu")
		(at 167.616124 -23.562564 -90)
		(property "Reference" "R6T2"
			(at 0 0 90)
			(layer "B.SilkS")
			(hide yes)
			(effects
				(font
					(size 1.27 1.27)
				)
				(justify mirror)
			)
		)
		(property "Value" ""
			(at 0 0 90)
			(layer "B.Fab")
			(effects
				(font
					(size 1.27 1.27)
				)
				(justify mirror)
			)
		)
		(duplicate_pad_numbers_are_jumpers no)
		(fp_poly
			(pts
				(xy 0.2794 -0.1016) (xy -0.2794 -0.1016) (xy -0.2794 0.9906) (xy 0.2794 0.9906)
			)
			(stroke
				(width 0)
				(type default)
			)
			(fill no)
			(layer "B.CrtYd")
		)
		(fp_line
			(start -0.2794 0.9906)
			(end -0.2794 -0.1016)
			(stroke
				(width 0.1)
				(type default)
			)
			(layer "B.Fab")
		)
		(fp_line
			(start 0.2794 0.9906)
			(end -0.2794 0.9906)
			(stroke
				(width 0.1)
				(type default)
			)
			(layer "B.Fab")
		)
		(fp_line
			(start -0.2794 -0.1016)
			(end 0.2794 -0.1016)
			(stroke
				(width 0.1)
				(type default)
			)
			(layer "B.Fab")
		)
		(fp_line
			(start 0.2794 -0.1016)
			(end 0.2794 0.9906)
			(stroke
				(width 0.1)
				(type default)
			)
			(layer "B.Fab")
		)
		(pad "1" smd rect
			(at 0 0 90)
			(size 0.508 0.508)
			(layers "B.Cu" "B.Mask" "B.Paste")
			(net "PVCCIO_CPU1")
		)
		(pad "2" smd rect
			(at 0 0.889 90)
			(size 0.508 0.508)
			(layers "B.Cu" "B.Mask" "B.Paste")
			(net "SMB_DDR_GHJ_SCL_G")
		)
		(zone
			(layer "B.Cu")
			(hatch none 0.5)
			(connect_pads
				(clearance 0)
			)
			(min_thickness 0.25)
			(keepout
				(tracks not_allowed)
				(vias allowed)
				(pads allowed)
				(copperpour not_allowed)
				(footprints allowed)
			)
			(placement
				(enabled no)
				(sheetname "")
			)
			(fill
				(thermal_gap 0.5)
				(thermal_bridge_width 0.5)
				(island_removal_mode 0)
			)
			(polygon
				(pts
					(xy 166.981124 -23.308564) (xy 166.981124 -23.816564) (xy 167.362124 -23.816564) (xy 167.362124 -23.308564)
				)
			)
		)
		(zone
			(layer "B.Cu")
			(hatch none 0.5)
			(connect_pads
				(clearance 0)
			)
			(min_thickness 0.25)
			(keepout
				(tracks allowed)
				(vias not_allowed)
				(pads allowed)
				(copperpour not_allowed)
				(footprints allowed)
			)
			(placement
				(enabled no)
				(sheetname "")
			)
			(fill
				(thermal_gap 0.5)
				(thermal_bridge_width 0.5)
				(island_removal_mode 0)
			)
			(polygon
				(pts
					(xy 167.362124 -23.308564) (xy 167.362124 -23.816564) (xy 166.981124 -23.816564) (xy 166.981124 -23.308564)
				)
			)
		)
	)
	(footprint ""
		(layer "B.Cu")
		(at 174.809404 -4.57581 -90)
		(property "Reference" "R6U6"
			(at 0 0 90)
			(layer "B.SilkS")
			(hide yes)
			(effects
				(font
					(size 1.27 1.27)
				)
				(justify mirror)
			)
		)
		(property "Value" ""
			(at 0 0 90)
			(layer "B.Fab")
			(effects
				(font
					(size 1.27 1.27)
				)
				(justify mirror)
			)
		)
		(duplicate_pad_numbers_are_jumpers no)
		(fp_rect
			(start 0.2794 0.9906)
			(end -0.2794 -0.1016)
			(stroke
				(width 0)
				(type default)
			)
			(fill no)
			(layer "B.CrtYd")
		)
		(fp_line
			(start -0.2794 0.9906)
			(end -0.2794 -0.1016)
			(stroke
				(width 0.1)
				(type default)
			)
			(layer "B.Fab")
		)
		(fp_line
			(start 0.2794 0.9906)
			(end -0.2794 0.9906)
			(stroke
				(width 0.1)
				(type default)
			)
			(layer "B.Fab")
		)
		(fp_line
			(start -0.2794 -0.1016)
			(end 0.2794 -0.1016)
			(stroke
				(width 0.1)
				(type default)
			)
			(layer "B.Fab")
		)
		(fp_line
			(start 0.2794 -0.1016)
			(end 0.2794 0.9906)
			(stroke
				(width 0.1)
				(type default)
			)
			(layer "B.Fab")
		)
		(pad "1" smd rect
			(at 0 0 90)
			(size 0.508 0.508)
			(layers "B.Cu" "B.Mask" "B.Paste")
			(net "PVDDQ_GHJ")
		)
		(pad "2" smd rect
			(at 0 0.889 90)
			(size 0.508 0.508)
			(layers "B.Cu" "B.Mask" "B.Paste")
			(net "VSENSE_PVDDQ_GHJ_VTT")
		)
		(zone
			(layer "B.Cu")
			(hatch none 0.5)
			(connect_pads
				(clearance 0)
			)
			(min_thickness 0.25)
			(keepout
				(tracks allowed)
				(vias not_allowed)
				(pads allowed)
				(copperpour not_allowed)
				(footprints allowed)
			)
			(placement
				(enabled no)
				(sheetname "")
			)
			(fill
				(thermal_gap 0.5)
				(thermal_bridge_width 0.5)
				(island_removal_mode 0)
			)
			(polygon
				(pts
					(xy 174.174404 -4.32181) (xy 174.555404 -4.32181) (xy 174.555404 -4.82981) (xy 174.174404 -4.82981)
				)
			)
		)
		(zone
			(layer "B.Cu")
			(hatch none 0.5)
			(connect_pads
				(clearance 0)
			)
			(min_thickness 0.25)
			(keepout
				(tracks not_allowed)
				(vias allowed)
				(pads allowed)
				(copperpour not_allowed)
				(footprints allowed)
			)
			(placement
				(enabled no)
				(sheetname "")
			)
			(fill
				(thermal_gap 0.5)
				(thermal_bridge_width 0.5)
				(island_removal_mode 0)
			)
			(polygon
				(pts
					(xy 174.174404 -4.32181) (xy 174.555404 -4.32181) (xy 174.555404 -4.82981) (xy 174.174404 -4.82981)
				)
			)
		)
	)
	(footprint ""
		(layer "B.Cu")
		(at 269.521686 -73.51014)
		(property "Reference" "C5P31"
			(at 0 0 0)
			(layer "B.SilkS")
			(hide yes)
			(effects
				(font
					(size 1.27 1.27)
				)
				(justify mirror)
			)
		)
		(property "Value" ""
			(at 0 0 0)
			(layer "B.Fab")
			(effects
				(font
					(size 1.27 1.27)
				)
				(justify mirror)
			)
		)
		(duplicate_pad_numbers_are_jumpers no)
		(fp_poly
			(pts
				(xy 0.7239 -0.2159) (xy -0.7239 -0.2159) (xy -0.7239 1.9939) (xy 0.7239 1.9939)
			)
			(stroke
				(width 0)
				(type default)
			)
			(fill no)
			(layer "B.CrtYd")
		)
		(fp_line
			(start -0.7239 -0.2159)
			(end 0.7239 -0.2159)
			(stroke
				(width 0.1)
				(type default)
			)
			(layer "B.Fab")
		)
		(fp_line
			(start -0.7239 1.9939)
			(end -0.7239 -0.2159)
			(stroke
				(width 0.1)
				(type default)
			)
			(layer "B.Fab")
		)
		(fp_line
			(start 0.7239 -0.2159)
			(end 0.7239 1.9939)
			(stroke
				(width 0.1)
				(type default)
			)
			(layer "B.Fab")
		)
		(fp_line
			(start 0.7239 1.9939)
			(end -0.7239 1.9939)
			(stroke
				(width 0.1)
				(type default)
			)
			(layer "B.Fab")
		)
		(pad "1" smd rect
			(at 0 0 180)
			(size 1.27 1.016)
			(layers "B.Cu" "B.Mask" "B.Paste")
			(net "PVCCMCP_CPU0")
		)
		(pad "2" smd rect
			(at 0 1.778 180)
			(size 1.27 1.016)
			(layers "B.Cu" "B.Mask" "B.Paste")
			(net "GND")
		)
		(zone
			(layer "B.Cu")
			(hatch none 0.5)
			(connect_pads
				(clearance 0)
			)
			(min_thickness 0.25)
			(keepout
				(tracks not_allowed)
				(vias allowed)
				(pads allowed)
				(copperpour not_allowed)
				(footprints allowed)
			)
			(placement
				(enabled no)
				(sheetname "")
			)
			(fill
				(thermal_gap 0.5)
				(thermal_bridge_width 0.5)
				(island_removal_mode 0)
			)
			(polygon
				(pts
					(xy 270.156686 -73.00214) (xy 268.886686 -73.00214) (xy 268.886686 -72.24014) (xy 270.156686 -72.24014)
				)
			)
		)
	)
	(footprint ""
		(layer "B.Cu")
		(at 95.400368 3.4798 90)
		(property "Reference" "SH8U1"
			(at 0 0 90)
			(layer "B.SilkS")
			(hide yes)
			(effects
				(font
					(size 1.27 1.27)
				)
				(justify mirror)
			)
		)
		(property "Value" ""
			(at 0 0 90)
			(layer "B.Fab")
			(effects
				(font
					(size 1.27 1.27)
				)
				(justify mirror)
			)
		)
		(duplicate_pad_numbers_are_jumpers no)
		(fp_poly
			(pts
				(xy 0.1651 -0.0508) (xy 0.1651 0.5842) (xy -0.1651 0.5842) (xy -0.1651 -0.0508)
			)
			(stroke
				(width 0)
				(type default)
			)
			(fill no)
			(layer "B.CrtYd")
		)
		(fp_line
			(start 0.1651 -0.0508)
			(end -0.1651 -0.0508)
			(stroke
				(width 0.1)
				(type default)
			)
			(layer "B.Fab")
		)
		(fp_line
			(start -0.1651 -0.0508)
			(end -0.1651 0.5842)
			(stroke
				(width 0.1)
				(type default)
			)
			(layer "B.Fab")
		)
		(fp_line
			(start 0.1651 0.5842)
			(end 0.1651 -0.0508)
			(stroke
				(width 0.1)
				(type default)
			)
			(layer "B.Fab")
		)
		(fp_line
			(start -0.1651 0.5842)
			(end 0.1651 0.5842)
			(stroke
				(width 0.1)
				(type default)
			)
			(layer "B.Fab")
		)
		(pad "1" smd custom
			(at 0 0 90)
			(size 0.0762 0.0762)
			(layers "B.Cu" "B.Mask" "B.Paste")
			(net "VR_PVTT_GHJ_SNS")
			(options
				(clearance outline)
				(anchor circle)
			)
			(primitives
				(gr_poly
					(pts
						(arc
							(start -0.1524 0.10795)
							(mid -0.098518 0.130268)
							(end -0.0762 0.18415)
						)
						(xy -0.0762 0.22225) (xy 0.0762 0.22225)
						(arc
							(start 0.0762 0.18415)
							(mid 0.098518 0.130268)
							(end 0.1524 0.10795)
						)
						(xy 0.1524 -0.22225) (xy -0.1524 -0.22225)
					)
					(width 0)
					(fill yes)
				)
			)
		)
		(pad "2" smd custom
			(at 0 0.5334 270)
			(size 0.0762 0.0762)
			(layers "B.Cu" "B.Mask" "B.Paste")
			(net "PVTT_GHJ")
			(options
				(clearance outline)
				(anchor circle)
			)
			(primitives
				(gr_poly
					(pts
						(arc
							(start -0.1524 0.10795)
							(mid -0.098518 0.130268)
							(end -0.0762 0.18415)
						)
						(xy -0.0762 0.22225) (xy 0.0762 0.22225)
						(arc
							(start 0.0762 0.18415)
							(mid 0.098518 0.130268)
							(end 0.1524 0.10795)
						)
						(xy 0.1524 -0.22225) (xy -0.1524 -0.22225)
					)
					(width 0)
					(fill yes)
				)
			)
		)
	)
	(footprint ""
		(layer "B.Cu")
		(at 137.033 -121.412)
		(property "Reference" ""
			(at 0 0 0)
			(layer "B.SilkS")
			(hide yes)
			(effects
				(font
					(size 1.27 1.27)
				)
				(justify mirror)
			)
		)
		(property "Value" ""
			(at 0 0 0)
			(layer "B.Fab")
			(effects
				(font
					(size 1.27 1.27)
				)
				(justify mirror)
			)
		)
		(duplicate_pad_numbers_are_jumpers no)
		(fp_poly
			(pts
				(arc
					(start 2.032 0)
					(mid -2.032 0)
					(end 2.032 0)
				)
			)
			(stroke
				(width 0)
				(type default)
			)
			(fill no)
			(layer "B.CrtYd")
		)
		(pad "1" smd circle
			(at 0 0 180)
			(size 1.016 1.016)
			(layers "B.Cu" "B.Mask" "B.Paste")
			(net "Net_390")
		)
		(zone
			(layers "F.Cu" "B.Cu" "In1.Cu" "In2.Cu" "In3.Cu" "In4.Cu" "In5.Cu" "In6.Cu"
				"In7.Cu" "In8.Cu" "In9.Cu" "In10.Cu" "In11.Cu" "In12.Cu"
			)
			(hatch none 0.5)
			(connect_pads
				(clearance 0)
			)
			(min_thickness 0.25)
			(keepout
				(tracks allowed)
				(vias not_allowed)
				(pads allowed)
				(copperpour not_allowed)
				(footprints allowed)
			)
			(placement
				(enabled no)
				(sheetname "")
			)
			(fill
				(thermal_gap 0.5)
				(thermal_bridge_width 0.5)
				(island_removal_mode 0)
			)
			(polygon
				(pts
					(arc
						(start 138.557 -121.412)
						(mid 135.509 -121.412)
						(end 138.557 -121.412)
					)
				)
			)
		)
		(zone
			(layer "B.Cu")
			(hatch none 0.5)
			(connect_pads
				(clearance 0)
			)
			(min_thickness 0.25)
			(keepout
				(tracks not_allowed)
				(vias allowed)
				(pads allowed)
				(copperpour not_allowed)
				(footprints allowed)
			)
			(placement
				(enabled no)
				(sheetname "")
			)
			(fill
				(thermal_gap 0.5)
				(thermal_bridge_width 0.5)
				(island_removal_mode 0)
			)
			(polygon
				(pts
					(arc
						(start 138.557 -121.412)
						(mid 135.509 -121.412)
						(end 138.557 -121.412)
					)
				)
			)
		)
	)
	(footprint ""
		(layer "B.Cu")
		(at 275.008086 -77.82814)
		(property "Reference" "C5P18"
			(at 0 0 0)
			(layer "B.SilkS")
			(hide yes)
			(effects
				(font
					(size 1.27 1.27)
				)
				(justify mirror)
			)
		)
		(property "Value" ""
			(at 0 0 0)
			(layer "B.Fab")
			(effects
				(font
					(size 1.27 1.27)
				)
				(justify mirror)
			)
		)
		(duplicate_pad_numbers_are_jumpers no)
		(fp_poly
			(pts
				(xy 0.7239 -0.2159) (xy -0.7239 -0.2159) (xy -0.7239 1.9939) (xy 0.7239 1.9939)
			)
			(stroke
				(width 0)
				(type default)
			)
			(fill no)
			(layer "B.CrtYd")
		)
		(fp_line
			(start -0.7239 -0.2159)
			(end 0.7239 -0.2159)
			(stroke
				(width 0.1)
				(type default)
			)
			(layer "B.Fab")
		)
		(fp_line
			(start -0.7239 1.9939)
			(end -0.7239 -0.2159)
			(stroke
				(width 0.1)
				(type default)
			)
			(layer "B.Fab")
		)
		(fp_line
			(start 0.7239 -0.2159)
			(end 0.7239 1.9939)
			(stroke
				(width 0.1)
				(type default)
			)
			(layer "B.Fab")
		)
		(fp_line
			(start 0.7239 1.9939)
			(end -0.7239 1.9939)
			(stroke
				(width 0.1)
				(type default)
			)
			(layer "B.Fab")
		)
		(pad "1" smd rect
			(at 0 0 180)
			(size 1.27 1.016)
			(layers "B.Cu" "B.Mask" "B.Paste")
			(net "PVCCMCP_CPU0")
		)
		(pad "2" smd rect
			(at 0 1.778 180)
			(size 1.27 1.016)
			(layers "B.Cu" "B.Mask" "B.Paste")
			(net "GND")
		)
		(zone
			(layer "B.Cu")
			(hatch none 0.5)
			(connect_pads
				(clearance 0)
			)
			(min_thickness 0.25)
			(keepout
				(tracks not_allowed)
				(vias allowed)
				(pads allowed)
				(copperpour not_allowed)
				(footprints allowed)
			)
			(placement
				(enabled no)
				(sheetname "")
			)
			(fill
				(thermal_gap 0.5)
				(thermal_bridge_width 0.5)
				(island_removal_mode 0)
			)
			(polygon
				(pts
					(xy 275.643086 -77.32014) (xy 274.373086 -77.32014) (xy 274.373086 -76.55814) (xy 275.643086 -76.55814)
				)
			)
		)
	)
	(footprint ""
		(layer "B.Cu")
		(at 214.503 -70.358)
		(property "Reference" "C6P21"
			(at 0 0 0)
			(layer "B.SilkS")
			(hide yes)
			(effects
				(font
					(size 1.27 1.27)
				)
				(justify mirror)
			)
		)
		(property "Value" ""
			(at 0 0 0)
			(layer "B.Fab")
			(effects
				(font
					(size 1.27 1.27)
				)
				(justify mirror)
			)
		)
		(duplicate_pad_numbers_are_jumpers no)
		(fp_poly
			(pts
				(xy 0.4953 -0.2032) (xy -0.4953 -0.2032) (xy -0.4953 1.6002) (xy 0.4953 1.6002)
			)
			(stroke
				(width 0)
				(type default)
			)
			(fill no)
			(layer "B.CrtYd")
		)
		(fp_line
			(start -0.4953 -0.2032)
			(end -0.4953 1.6002)
			(stroke
				(width 0.1)
				(type default)
			)
			(layer "B.Fab")
		)
		(fp_line
			(start -0.4953 1.6002)
			(end 0.4953 1.6002)
			(stroke
				(width 0.1)
				(type default)
			)
			(layer "B.Fab")
		)
		(fp_line
			(start 0.4953 -0.2032)
			(end -0.4953 -0.2032)
			(stroke
				(width 0.1)
				(type default)
			)
			(layer "B.Fab")
		)
		(fp_line
			(start 0.4953 1.6002)
			(end 0.4953 -0.2032)
			(stroke
				(width 0.1)
				(type default)
			)
			(layer "B.Fab")
		)
		(pad "1" smd rect
			(at 0 0 180)
			(size 0.762 0.889)
			(layers "B.Cu" "B.Mask" "B.Paste")
			(net "PVCCIN_CPU0")
		)
		(pad "2" smd rect
			(at 0 1.397 180)
			(size 0.762 0.889)
			(layers "B.Cu" "B.Mask" "B.Paste")
			(net "GND")
		)
		(zone
			(layer "B.Cu")
			(hatch none 0.5)
			(connect_pads
				(clearance 0)
			)
			(min_thickness 0.25)
			(keepout
				(tracks not_allowed)
				(vias allowed)
				(pads allowed)
				(copperpour not_allowed)
				(footprints allowed)
			)
			(placement
				(enabled no)
				(sheetname "")
			)
			(fill
				(thermal_gap 0.5)
				(thermal_bridge_width 0.5)
				(island_removal_mode 0)
			)
			(polygon
				(pts
					(xy 214.884 -69.9135) (xy 214.122 -69.9135) (xy 214.122 -69.4055) (xy 214.884 -69.4055)
				)
			)
		)
	)
	(footprint ""
		(layer "B.Cu")
		(at 197.848728 -72.855582 90)
		(property "Reference" "C6P20"
			(at 0 0 90)
			(layer "B.SilkS")
			(hide yes)
			(effects
				(font
					(size 1.27 1.27)
				)
				(justify mirror)
			)
		)
		(property "Value" ""
			(at 0 0 90)
			(layer "B.Fab")
			(effects
				(font
					(size 1.27 1.27)
				)
				(justify mirror)
			)
		)
		(duplicate_pad_numbers_are_jumpers no)
		(fp_rect
			(start -0.7239 -0.2159)
			(end 0.7239 1.9939)
			(stroke
				(width 0)
				(type default)
			)
			(fill no)
			(layer "B.CrtYd")
		)
		(fp_line
			(start 0.7239 -0.2159)
			(end 0.7239 1.9939)
			(stroke
				(width 0.1)
				(type default)
			)
			(layer "B.Fab")
		)
		(fp_line
			(start -0.7239 -0.2159)
			(end 0.7239 -0.2159)
			(stroke
				(width 0.1)
				(type default)
			)
			(layer "B.Fab")
		)
		(fp_line
			(start 0.7239 1.9939)
			(end -0.7239 1.9939)
			(stroke
				(width 0.1)
				(type default)
			)
			(layer "B.Fab")
		)
		(fp_line
			(start -0.7239 1.9939)
			(end -0.7239 -0.2159)
			(stroke
				(width 0.1)
				(type default)
			)
			(layer "B.Fab")
		)
		(pad "1" smd rect
			(at 0 0 270)
			(size 1.27 1.016)
			(layers "B.Cu" "B.Mask" "B.Paste")
			(net "VR_FET_SW_P12V_STBY_PVCCIN_CPU0")
		)
		(pad "2" smd rect
			(at 0 1.778 270)
			(size 1.27 1.016)
			(layers "B.Cu" "B.Mask" "B.Paste")
			(net "GND")
		)
		(zone
			(layer "B.Cu")
			(hatch none 0.5)
			(connect_pads
				(clearance 0)
			)
			(min_thickness 0.25)
			(keepout
				(tracks not_allowed)
				(vias allowed)
				(pads allowed)
				(copperpour not_allowed)
				(footprints allowed)
			)
			(placement
				(enabled no)
				(sheetname "")
			)
			(fill
				(thermal_gap 0.5)
				(thermal_bridge_width 0.5)
				(island_removal_mode 0)
			)
			(polygon
				(pts
					(xy 198.356728 -72.220582) (xy 199.118728 -72.220582) (xy 199.118728 -73.490582) (xy 198.356728 -73.490582)
				)
			)
		)
	)
	(footprint ""
		(layer "B.Cu")
		(at 13.716 -54.889908 90)
		(property "Reference" "C1E15"
			(at 0 0 90)
			(layer "B.SilkS")
			(hide yes)
			(effects
				(font
					(size 1.27 1.27)
				)
				(justify mirror)
			)
		)
		(property "Value" ""
			(at 0 0 90)
			(layer "B.Fab")
			(effects
				(font
					(size 1.27 1.27)
				)
				(justify mirror)
			)
		)
		(duplicate_pad_numbers_are_jumpers no)
		(fp_rect
			(start -0.7239 -0.2159)
			(end 0.7239 1.9939)
			(stroke
				(width 0)
				(type default)
			)
			(fill no)
			(layer "B.CrtYd")
		)
		(fp_line
			(start 0.7239 -0.2159)
			(end 0.7239 1.9939)
			(stroke
				(width 0.1)
				(type default)
			)
			(layer "B.Fab")
		)
		(fp_line
			(start -0.7239 -0.2159)
			(end 0.7239 -0.2159)
			(stroke
				(width 0.1)
				(type default)
			)
			(layer "B.Fab")
		)
		(fp_line
			(start 0.7239 1.9939)
			(end -0.7239 1.9939)
			(stroke
				(width 0.1)
				(type default)
			)
			(layer "B.Fab")
		)
		(fp_line
			(start -0.7239 1.9939)
			(end -0.7239 -0.2159)
			(stroke
				(width 0.1)
				(type default)
			)
			(layer "B.Fab")
		)
		(pad "1" smd rect
			(at 0 0 270)
			(size 1.27 1.016)
			(layers "B.Cu" "B.Mask" "B.Paste")
			(net "P12V_PSU")
		)
		(pad "2" smd rect
			(at 0 1.778 270)
			(size 1.27 1.016)
			(layers "B.Cu" "B.Mask" "B.Paste")
			(net "GND")
		)
		(zone
			(layer "B.Cu")
			(hatch none 0.5)
			(connect_pads
				(clearance 0)
			)
			(min_thickness 0.25)
			(keepout
				(tracks not_allowed)
				(vias allowed)
				(pads allowed)
				(copperpour not_allowed)
				(footprints allowed)
			)
			(placement
				(enabled no)
				(sheetname "")
			)
			(fill
				(thermal_gap 0.5)
				(thermal_bridge_width 0.5)
				(island_removal_mode 0)
			)
			(polygon
				(pts
					(xy 14.224 -54.254908) (xy 14.986 -54.254908) (xy 14.986 -55.524908) (xy 14.224 -55.524908)
				)
			)
		)
	)
	(footprint ""
		(layer "B.Cu")
		(at 485.58577 -58.103262 180)
		(property "Reference" "L30W1"
			(at -0.127 -1.07188 180)
			(unlocked yes)
			(layer "B.SilkS")
			(effects
				(font
					(size 0.4064 0.254)
					(thickness 0.1524)
				)
				(justify left mirror)
			)
		)
		(property "Value" ""
			(at 0 0 0)
			(layer "B.Fab")
			(effects
				(font
					(size 1.27 1.27)
				)
				(justify mirror)
			)
		)
		(duplicate_pad_numbers_are_jumpers no)
		(fp_rect
			(start 0.08382 1.09982)
			(end -2.11582 -0.29972)
			(stroke
				(width 0)
				(type default)
			)
			(fill no)
			(layer "B.CrtYd")
		)
		(fp_line
			(start 0.08382 1.09982)
			(end 0.08382 -0.29972)
			(stroke
				(width 0.1)
				(type default)
			)
			(layer "B.Fab")
		)
		(fp_line
			(start 0.08382 -0.29972)
			(end -2.11582 -0.29972)
			(stroke
				(width 0.1)
				(type default)
			)
			(layer "B.Fab")
		)
		(fp_line
			(start -2.11582 1.09982)
			(end 0.08382 1.09982)
			(stroke
				(width 0.1)
				(type default)
			)
			(layer "B.Fab")
		)
		(fp_line
			(start -2.11582 -0.29972)
			(end -2.11582 1.09982)
			(stroke
				(width 0.1)
				(type default)
			)
			(layer "B.Fab")
		)
		(pad "1" smd rect
			(at 0 0)
			(size 1.27 0.508)
			(layers "B.Cu" "B.Mask" "B.Paste")
			(net "USB3_P01_RXP")
		)
		(pad "2" smd rect
			(at -2.032 0)
			(size 1.27 0.508)
			(layers "B.Cu" "B.Mask" "B.Paste")
			(net "USB3_P01_FB_RXP")
		)
		(pad "3" smd rect
			(at -2.032 0.8001)
			(size 1.27 0.508)
			(layers "B.Cu" "B.Mask" "B.Paste")
			(net "USB3_P01_FB_RXN")
		)
		(pad "4" smd rect
			(at 0 0.8001)
			(size 1.27 0.508)
			(layers "B.Cu" "B.Mask" "B.Paste")
			(net "USB3_P01_RXN")
		)
		(zone
			(layer "B.Cu")
			(hatch none 0.5)
			(connect_pads
				(clearance 0)
			)
			(min_thickness 0.25)
			(keepout
				(tracks not_allowed)
				(vias allowed)
				(pads allowed)
				(copperpour not_allowed)
				(footprints allowed)
			)
			(placement
				(enabled no)
				(sheetname "")
			)
			(fill
				(thermal_gap 0.5)
				(thermal_bridge_width 0.5)
				(island_removal_mode 0)
			)
			(polygon
				(pts
					(xy 484.95077 -58.649362) (xy 484.95077 -58.357262) (xy 486.22077 -58.357262) (xy 486.22077 -58.649362)
				)
			)
		)
		(zone
			(layer "B.Cu")
			(hatch none 0.5)
			(connect_pads
				(clearance 0)
			)
			(min_thickness 0.25)
			(keepout
				(tracks not_allowed)
				(vias allowed)
				(pads allowed)
				(copperpour not_allowed)
				(footprints allowed)
			)
			(placement
				(enabled no)
				(sheetname "")
			)
			(fill
				(thermal_gap 0.5)
				(thermal_bridge_width 0.5)
				(island_removal_mode 0)
			)
			(polygon
				(pts
					(xy 486.22077 -59.157362) (xy 486.98277 -59.157362) (xy 486.98277 -57.849262) (xy 486.22077 -57.849262)
				)
			)
		)
		(zone
			(layer "B.Cu")
			(hatch none 0.5)
			(connect_pads
				(clearance 0)
			)
			(min_thickness 0.25)
			(keepout
				(tracks allowed)
				(vias not_allowed)
				(pads allowed)
				(copperpour not_allowed)
				(footprints allowed)
			)
			(placement
				(enabled no)
				(sheetname "")
			)
			(fill
				(thermal_gap 0.5)
				(thermal_bridge_width 0.5)
				(island_removal_mode 0)
			)
			(polygon
				(pts
					(xy 486.22077 -57.849262) (xy 486.22077 -59.157362) (xy 486.98277 -59.157362) (xy 486.98277 -57.849262)
				)
			)
		)
	)
	(footprint ""
		(layer "B.Cu")
		(at 421.386 -14.9352 90)
		(property "Reference" "R2T7"
			(at 0 0 90)
			(layer "B.SilkS")
			(hide yes)
			(effects
				(font
					(size 1.27 1.27)
				)
				(justify mirror)
			)
		)
		(property "Value" ""
			(at 0 0 90)
			(layer "B.Fab")
			(effects
				(font
					(size 1.27 1.27)
				)
				(justify mirror)
			)
		)
		(duplicate_pad_numbers_are_jumpers no)
		(fp_poly
			(pts
				(xy 0.2794 -0.1016) (xy -0.2794 -0.1016) (xy -0.2794 0.9906) (xy 0.2794 0.9906)
			)
			(stroke
				(width 0)
				(type default)
			)
			(fill no)
			(layer "B.CrtYd")
		)
		(fp_line
			(start 0.2794 -0.1016)
			(end 0.2794 0.9906)
			(stroke
				(width 0.1)
				(type default)
			)
			(layer "B.Fab")
		)
		(fp_line
			(start -0.2794 -0.1016)
			(end 0.2794 -0.1016)
			(stroke
				(width 0.1)
				(type default)
			)
			(layer "B.Fab")
		)
		(fp_line
			(start 0.2794 0.9906)
			(end -0.2794 0.9906)
			(stroke
				(width 0.1)
				(type default)
			)
			(layer "B.Fab")
		)
		(fp_line
			(start -0.2794 0.9906)
			(end -0.2794 -0.1016)
			(stroke
				(width 0.1)
				(type default)
			)
			(layer "B.Fab")
		)
		(pad "1" smd rect
			(at 0 0 270)
			(size 0.508 0.508)
			(layers "B.Cu" "B.Mask" "B.Paste")
			(net "P3V3_STBY")
		)
		(pad "2" smd rect
			(at 0 0.889 270)
			(size 0.508 0.508)
			(layers "B.Cu" "B.Mask" "B.Paste")
			(net "H_CPU0_FAST_WAKE_LVT3_N")
		)
		(zone
			(layer "B.Cu")
			(hatch none 0.5)
			(connect_pads
				(clearance 0)
			)
			(min_thickness 0.25)
			(keepout
				(tracks allowed)
				(vias not_allowed)
				(pads allowed)
				(copperpour not_allowed)
				(footprints allowed)
			)
			(placement
				(enabled no)
				(sheetname "")
			)
			(fill
				(thermal_gap 0.5)
				(thermal_bridge_width 0.5)
				(island_removal_mode 0)
			)
			(polygon
				(pts
					(xy 421.64 -15.1892) (xy 421.64 -14.6812) (xy 422.021 -14.6812) (xy 422.021 -15.1892)
				)
			)
		)
		(zone
			(layer "B.Cu")
			(hatch none 0.5)
			(connect_pads
				(clearance 0)
			)
			(min_thickness 0.25)
			(keepout
				(tracks not_allowed)
				(vias allowed)
				(pads allowed)
				(copperpour not_allowed)
				(footprints allowed)
			)
			(placement
				(enabled no)
				(sheetname "")
			)
			(fill
				(thermal_gap 0.5)
				(thermal_bridge_width 0.5)
				(island_removal_mode 0)
			)
			(polygon
				(pts
					(xy 422.021 -15.1892) (xy 422.021 -14.6812) (xy 421.64 -14.6812) (xy 421.64 -15.1892)
				)
			)
		)
	)
	(footprint ""
		(layer "B.Cu")
		(at 276.836886 -73.51014)
		(property "Reference" "C4P7"
			(at 0 0 0)
			(layer "B.SilkS")
			(hide yes)
			(effects
				(font
					(size 1.27 1.27)
				)
				(justify mirror)
			)
		)
		(property "Value" ""
			(at 0 0 0)
			(layer "B.Fab")
			(effects
				(font
					(size 1.27 1.27)
				)
				(justify mirror)
			)
		)
		(duplicate_pad_numbers_are_jumpers no)
		(fp_poly
			(pts
				(xy 0.7239 -0.2159) (xy -0.7239 -0.2159) (xy -0.7239 1.9939) (xy 0.7239 1.9939)
			)
			(stroke
				(width 0)
				(type default)
			)
			(fill no)
			(layer "B.CrtYd")
		)
		(fp_line
			(start -0.7239 -0.2159)
			(end 0.7239 -0.2159)
			(stroke
				(width 0.1)
				(type default)
			)
			(layer "B.Fab")
		)
		(fp_line
			(start -0.7239 1.9939)
			(end -0.7239 -0.2159)
			(stroke
				(width 0.1)
				(type default)
			)
			(layer "B.Fab")
		)
		(fp_line
			(start 0.7239 -0.2159)
			(end 0.7239 1.9939)
			(stroke
				(width 0.1)
				(type default)
			)
			(layer "B.Fab")
		)
		(fp_line
			(start 0.7239 1.9939)
			(end -0.7239 1.9939)
			(stroke
				(width 0.1)
				(type default)
			)
			(layer "B.Fab")
		)
		(pad "1" smd rect
			(at 0 0 180)
			(size 1.27 1.016)
			(layers "B.Cu" "B.Mask" "B.Paste")
			(net "PVCCMCP_CPU0")
		)
		(pad "2" smd rect
			(at 0 1.778 180)
			(size 1.27 1.016)
			(layers "B.Cu" "B.Mask" "B.Paste")
			(net "GND")
		)
		(zone
			(layer "B.Cu")
			(hatch none 0.5)
			(connect_pads
				(clearance 0)
			)
			(min_thickness 0.25)
			(keepout
				(tracks not_allowed)
				(vias allowed)
				(pads allowed)
				(copperpour not_allowed)
				(footprints allowed)
			)
			(placement
				(enabled no)
				(sheetname "")
			)
			(fill
				(thermal_gap 0.5)
				(thermal_bridge_width 0.5)
				(island_removal_mode 0)
			)
			(polygon
				(pts
					(xy 277.471886 -73.00214) (xy 276.201886 -73.00214) (xy 276.201886 -72.24014) (xy 277.471886 -72.24014)
				)
			)
		)
	)
	(footprint ""
		(layer "B.Cu")
		(at 500.824246 -38.069774 -90)
		(property "Reference" "C1T10"
			(at 0 0 90)
			(layer "B.SilkS")
			(hide yes)
			(effects
				(font
					(size 1.27 1.27)
				)
				(justify mirror)
			)
		)
		(property "Value" ""
			(at 0 0 90)
			(layer "B.Fab")
			(effects
				(font
					(size 1.27 1.27)
				)
				(justify mirror)
			)
		)
		(duplicate_pad_numbers_are_jumpers no)
		(fp_poly
			(pts
				(xy -0.3048 -0.1016) (xy -0.3048 0.9906) (xy 0.3048 0.9906) (xy 0.3048 -0.1016)
			)
			(stroke
				(width 0)
				(type default)
			)
			(fill no)
			(layer "B.CrtYd")
		)
		(fp_line
			(start -0.3048 0.9906)
			(end -0.3048 -0.1016)
			(stroke
				(width 0.1)
				(type default)
			)
			(layer "B.Fab")
		)
		(fp_line
			(start 0.3048 0.9906)
			(end -0.3048 0.9906)
			(stroke
				(width 0.1)
				(type default)
			)
			(layer "B.Fab")
		)
		(fp_line
			(start -0.3048 -0.1016)
			(end 0.3048 -0.1016)
			(stroke
				(width 0.1)
				(type default)
			)
			(layer "B.Fab")
		)
		(fp_line
			(start 0.3048 -0.1016)
			(end 0.3048 0.9906)
			(stroke
				(width 0.1)
				(type default)
			)
			(layer "B.Fab")
		)
		(pad "1" smd rect
			(at 0 0 90)
			(size 0.508 0.508)
			(layers "B.Cu" "B.Mask" "B.Paste")
			(net "P3V3_STBY")
		)
		(pad "2" smd rect
			(at 0 0.889 90)
			(size 0.508 0.508)
			(layers "B.Cu" "B.Mask" "B.Paste")
			(net "GND")
		)
		(zone
			(layer "B.Cu")
			(hatch none 0.5)
			(connect_pads
				(clearance 0)
			)
			(min_thickness 0.25)
			(keepout
				(tracks not_allowed)
				(vias allowed)
				(pads allowed)
				(copperpour not_allowed)
				(footprints allowed)
			)
			(placement
				(enabled no)
				(sheetname "")
			)
			(fill
				(thermal_gap 0.5)
				(thermal_bridge_width 0.5)
				(island_removal_mode 0)
			)
			(polygon
				(pts
					(xy 500.189246 -37.815774) (xy 500.189246 -38.323774) (xy 500.570246 -38.323774) (xy 500.570246 -37.815774)
				)
			)
		)
		(zone
			(layer "B.Cu")
			(hatch none 0.5)
			(connect_pads
				(clearance 0)
			)
			(min_thickness 0.25)
			(keepout
				(tracks allowed)
				(vias not_allowed)
				(pads allowed)
				(copperpour not_allowed)
				(footprints allowed)
			)
			(placement
				(enabled no)
				(sheetname "")
			)
			(fill
				(thermal_gap 0.5)
				(thermal_bridge_width 0.5)
				(island_removal_mode 0)
			)
			(polygon
				(pts
					(xy 500.570246 -37.815774) (xy 500.570246 -38.323774) (xy 500.189246 -38.323774) (xy 500.189246 -37.815774)
				)
			)
		)
	)
	(footprint ""
		(layer "B.Cu")
		(at 373.520716 -59.289442 180)
		(property "Reference" "R3P49"
			(at 0 0 0)
			(layer "B.SilkS")
			(hide yes)
			(effects
				(font
					(size 1.27 1.27)
				)
				(justify mirror)
			)
		)
		(property "Value" ""
			(at 0 0 0)
			(layer "B.Fab")
			(effects
				(font
					(size 1.27 1.27)
				)
				(justify mirror)
			)
		)
		(duplicate_pad_numbers_are_jumpers no)
		(fp_poly
			(pts
				(xy 0.2794 -0.1016) (xy -0.2794 -0.1016) (xy -0.2794 0.9906) (xy 0.2794 0.9906)
			)
			(stroke
				(width 0)
				(type default)
			)
			(fill no)
			(layer "B.CrtYd")
		)
		(fp_line
			(start 0.2794 0.9906)
			(end -0.2794 0.9906)
			(stroke
				(width 0.1)
				(type default)
			)
			(layer "B.Fab")
		)
		(fp_line
			(start 0.2794 -0.1016)
			(end 0.2794 0.9906)
			(stroke
				(width 0.1)
				(type default)
			)
			(layer "B.Fab")
		)
		(fp_line
			(start -0.2794 0.9906)
			(end -0.2794 -0.1016)
			(stroke
				(width 0.1)
				(type default)
			)
			(layer "B.Fab")
		)
		(fp_line
			(start -0.2794 -0.1016)
			(end 0.2794 -0.1016)
			(stroke
				(width 0.1)
				(type default)
			)
			(layer "B.Fab")
		)
		(pad "1" smd rect
			(at 0 0)
			(size 0.508 0.508)
			(layers "B.Cu" "B.Mask" "B.Paste")
			(net "P0V7_GTL2104_VREF_1")
		)
		(pad "2" smd rect
			(at 0 0.889)
			(size 0.508 0.508)
			(layers "B.Cu" "B.Mask" "B.Paste")
			(net "GND")
		)
		(zone
			(layer "B.Cu")
			(hatch none 0.5)
			(connect_pads
				(clearance 0)
			)
			(min_thickness 0.25)
			(keepout
				(tracks not_allowed)
				(vias allowed)
				(pads allowed)
				(copperpour not_allowed)
				(footprints allowed)
			)
			(placement
				(enabled no)
				(sheetname "")
			)
			(fill
				(thermal_gap 0.5)
				(thermal_bridge_width 0.5)
				(island_removal_mode 0)
			)
			(polygon
				(pts
					(xy 373.266716 -59.924442) (xy 373.774716 -59.924442) (xy 373.774716 -59.543442) (xy 373.266716 -59.543442)
				)
			)
		)
		(zone
			(layer "B.Cu")
			(hatch none 0.5)
			(connect_pads
				(clearance 0)
			)
			(min_thickness 0.25)
			(keepout
				(tracks allowed)
				(vias not_allowed)
				(pads allowed)
				(copperpour not_allowed)
				(footprints allowed)
			)
			(placement
				(enabled no)
				(sheetname "")
			)
			(fill
				(thermal_gap 0.5)
				(thermal_bridge_width 0.5)
				(island_removal_mode 0)
			)
			(polygon
				(pts
					(xy 373.266716 -59.543442) (xy 373.774716 -59.543442) (xy 373.774716 -59.924442) (xy 373.266716 -59.924442)
				)
			)
		)
	)
	(footprint ""
		(layer "B.Cu")
		(at 164.973 -80.391 90)
		(property "Reference" "C6P12"
			(at 0 0 90)
			(layer "B.SilkS")
			(hide yes)
			(effects
				(font
					(size 1.27 1.27)
				)
				(justify mirror)
			)
		)
		(property "Value" ""
			(at 0 0 90)
			(layer "B.Fab")
			(effects
				(font
					(size 1.27 1.27)
				)
				(justify mirror)
			)
		)
		(duplicate_pad_numbers_are_jumpers no)
		(fp_poly
			(pts
				(xy -0.3048 -0.1016) (xy -0.3048 0.9906) (xy 0.3048 0.9906) (xy 0.3048 -0.1016)
			)
			(stroke
				(width 0)
				(type default)
			)
			(fill no)
			(layer "B.CrtYd")
		)
		(fp_line
			(start 0.3048 -0.1016)
			(end 0.3048 0.9906)
			(stroke
				(width 0.1)
				(type default)
			)
			(layer "B.Fab")
		)
		(fp_line
			(start -0.3048 -0.1016)
			(end 0.3048 -0.1016)
			(stroke
				(width 0.1)
				(type default)
			)
			(layer "B.Fab")
		)
		(fp_line
			(start 0.3048 0.9906)
			(end -0.3048 0.9906)
			(stroke
				(width 0.1)
				(type default)
			)
			(layer "B.Fab")
		)
		(fp_line
			(start -0.3048 0.9906)
			(end -0.3048 -0.1016)
			(stroke
				(width 0.1)
				(type default)
			)
			(layer "B.Fab")
		)
		(pad "1" smd rect
			(at 0 0 270)
			(size 0.508 0.508)
			(layers "B.Cu" "B.Mask" "B.Paste")
			(net "P3V3_DB1200")
		)
		(pad "2" smd rect
			(at 0 0.889 270)
			(size 0.508 0.508)
			(layers "B.Cu" "B.Mask" "B.Paste")
			(net "GND")
		)
		(zone
			(layer "B.Cu")
			(hatch none 0.5)
			(connect_pads
				(clearance 0)
			)
			(min_thickness 0.25)
			(keepout
				(tracks allowed)
				(vias not_allowed)
				(pads allowed)
				(copperpour not_allowed)
				(footprints allowed)
			)
			(placement
				(enabled no)
				(sheetname "")
			)
			(fill
				(thermal_gap 0.5)
				(thermal_bridge_width 0.5)
				(island_removal_mode 0)
			)
			(polygon
				(pts
					(xy 165.227 -80.645) (xy 165.227 -80.137) (xy 165.608 -80.137) (xy 165.608 -80.645)
				)
			)
		)
		(zone
			(layer "B.Cu")
			(hatch none 0.5)
			(connect_pads
				(clearance 0)
			)
			(min_thickness 0.25)
			(keepout
				(tracks not_allowed)
				(vias allowed)
				(pads allowed)
				(copperpour not_allowed)
				(footprints allowed)
			)
			(placement
				(enabled no)
				(sheetname "")
			)
			(fill
				(thermal_gap 0.5)
				(thermal_bridge_width 0.5)
				(island_removal_mode 0)
			)
			(polygon
				(pts
					(xy 165.608 -80.645) (xy 165.608 -80.137) (xy 165.227 -80.137) (xy 165.227 -80.645)
				)
			)
		)
	)
	(footprint ""
		(layer "B.Cu")
		(at 482.727 -53.1368 -90)
		(property "Reference" "R8E17"
			(at 0 0 90)
			(layer "B.SilkS")
			(hide yes)
			(effects
				(font
					(size 1.27 1.27)
				)
				(justify mirror)
			)
		)
		(property "Value" ""
			(at 0 0 90)
			(layer "B.Fab")
			(effects
				(font
					(size 1.27 1.27)
				)
				(justify mirror)
			)
		)
		(duplicate_pad_numbers_are_jumpers no)
		(fp_poly
			(pts
				(xy 0.2794 -0.1016) (xy -0.2794 -0.1016) (xy -0.2794 0.9906) (xy 0.2794 0.9906)
			)
			(stroke
				(width 0)
				(type default)
			)
			(fill no)
			(layer "B.CrtYd")
		)
		(fp_line
			(start -0.2794 0.9906)
			(end -0.2794 -0.1016)
			(stroke
				(width 0.1)
				(type default)
			)
			(layer "B.Fab")
		)
		(fp_line
			(start 0.2794 0.9906)
			(end -0.2794 0.9906)
			(stroke
				(width 0.1)
				(type default)
			)
			(layer "B.Fab")
		)
		(fp_line
			(start -0.2794 -0.1016)
			(end 0.2794 -0.1016)
			(stroke
				(width 0.1)
				(type default)
			)
			(layer "B.Fab")
		)
		(fp_line
			(start 0.2794 -0.1016)
			(end 0.2794 0.9906)
			(stroke
				(width 0.1)
				(type default)
			)
			(layer "B.Fab")
		)
		(pad "1" smd rect
			(at 0 0 90)
			(size 0.508 0.508)
			(layers "B.Cu" "B.Mask" "B.Paste")
			(net "IRQ_LVC3_WAKE_R_N")
		)
		(pad "2" smd rect
			(at 0 0.889 90)
			(size 0.508 0.508)
			(layers "B.Cu" "B.Mask" "B.Paste")
			(net "IRQ_LVC3_WAKE_N")
		)
		(zone
			(layer "B.Cu")
			(hatch none 0.5)
			(connect_pads
				(clearance 0)
			)
			(min_thickness 0.25)
			(keepout
				(tracks not_allowed)
				(vias allowed)
				(pads allowed)
				(copperpour not_allowed)
				(footprints allowed)
			)
			(placement
				(enabled no)
				(sheetname "")
			)
			(fill
				(thermal_gap 0.5)
				(thermal_bridge_width 0.5)
				(island_removal_mode 0)
			)
			(polygon
				(pts
					(xy 482.092 -52.8828) (xy 482.092 -53.3908) (xy 482.473 -53.3908) (xy 482.473 -52.8828)
				)
			)
		)
		(zone
			(layer "B.Cu")
			(hatch none 0.5)
			(connect_pads
				(clearance 0)
			)
			(min_thickness 0.25)
			(keepout
				(tracks allowed)
				(vias not_allowed)
				(pads allowed)
				(copperpour not_allowed)
				(footprints allowed)
			)
			(placement
				(enabled no)
				(sheetname "")
			)
			(fill
				(thermal_gap 0.5)
				(thermal_bridge_width 0.5)
				(island_removal_mode 0)
			)
			(polygon
				(pts
					(xy 482.473 -52.8828) (xy 482.473 -53.3908) (xy 482.092 -53.3908) (xy 482.092 -52.8828)
				)
			)
		)
	)
	(footprint ""
		(layer "B.Cu")
		(at 278.7142 -29.337 90)
		(property "Reference" "SH4U1"
			(at 0 0 90)
			(layer "B.SilkS")
			(hide yes)
			(effects
				(font
					(size 1.27 1.27)
				)
				(justify mirror)
			)
		)
		(property "Value" ""
			(at 0 0 90)
			(layer "B.Fab")
			(effects
				(font
					(size 1.27 1.27)
				)
				(justify mirror)
			)
		)
		(duplicate_pad_numbers_are_jumpers no)
		(fp_poly
			(pts
				(xy 0.1651 -0.0508) (xy 0.1651 0.5842) (xy -0.1651 0.5842) (xy -0.1651 -0.0508)
			)
			(stroke
				(width 0)
				(type default)
			)
			(fill no)
			(layer "B.CrtYd")
		)
		(fp_line
			(start 0.1651 -0.0508)
			(end -0.1651 -0.0508)
			(stroke
				(width 0.1)
				(type default)
			)
			(layer "B.Fab")
		)
		(fp_line
			(start -0.1651 -0.0508)
			(end -0.1651 0.5842)
			(stroke
				(width 0.1)
				(type default)
			)
			(layer "B.Fab")
		)
		(fp_line
			(start 0.1651 0.5842)
			(end 0.1651 -0.0508)
			(stroke
				(width 0.1)
				(type default)
			)
			(layer "B.Fab")
		)
		(fp_line
			(start -0.1651 0.5842)
			(end 0.1651 0.5842)
			(stroke
				(width 0.1)
				(type default)
			)
			(layer "B.Fab")
		)
		(pad "1" smd custom
			(at 0 0 90)
			(size 0.0762 0.0762)
			(layers "B.Cu" "B.Mask" "B.Paste")
			(net "VSENSE_PVDDQ_ABC_N")
			(options
				(clearance outline)
				(anchor circle)
			)
			(primitives
				(gr_poly
					(pts
						(arc
							(start -0.1524 0.10795)
							(mid -0.098518 0.130268)
							(end -0.0762 0.18415)
						)
						(xy -0.0762 0.22225) (xy 0.0762 0.22225)
						(arc
							(start 0.0762 0.18415)
							(mid 0.098518 0.130268)
							(end 0.1524 0.10795)
						)
						(xy 0.1524 -0.22225) (xy -0.1524 -0.22225)
					)
					(width 0)
					(fill yes)
				)
			)
		)
		(pad "2" smd custom
			(at 0 0.5334 270)
			(size 0.0762 0.0762)
			(layers "B.Cu" "B.Mask" "B.Paste")
			(net "GND")
			(options
				(clearance outline)
				(anchor circle)
			)
			(primitives
				(gr_poly
					(pts
						(arc
							(start -0.1524 0.10795)
							(mid -0.098518 0.130268)
							(end -0.0762 0.18415)
						)
						(xy -0.0762 0.22225) (xy 0.0762 0.22225)
						(arc
							(start 0.0762 0.18415)
							(mid 0.098518 0.130268)
							(end 0.1524 0.10795)
						)
						(xy 0.1524 -0.22225) (xy -0.1524 -0.22225)
					)
					(width 0)
					(fill yes)
				)
			)
		)
	)
	(footprint ""
		(layer "B.Cu")
		(at 13.97 -41.402 -90)
		(property "Reference" "R9R10"
			(at 0 0 90)
			(layer "B.SilkS")
			(hide yes)
			(effects
				(font
					(size 1.27 1.27)
				)
				(justify mirror)
			)
		)
		(property "Value" ""
			(at 0 0 90)
			(layer "B.Fab")
			(effects
				(font
					(size 1.27 1.27)
				)
				(justify mirror)
			)
		)
		(duplicate_pad_numbers_are_jumpers no)
		(fp_poly
			(pts
				(xy 0.2794 -0.1016) (xy -0.2794 -0.1016) (xy -0.2794 0.9906) (xy 0.2794 0.9906)
			)
			(stroke
				(width 0)
				(type default)
			)
			(fill no)
			(layer "B.CrtYd")
		)
		(fp_line
			(start -0.2794 0.9906)
			(end -0.2794 -0.1016)
			(stroke
				(width 0.1)
				(type default)
			)
			(layer "B.Fab")
		)
		(fp_line
			(start 0.2794 0.9906)
			(end -0.2794 0.9906)
			(stroke
				(width 0.1)
				(type default)
			)
			(layer "B.Fab")
		)
		(fp_line
			(start -0.2794 -0.1016)
			(end 0.2794 -0.1016)
			(stroke
				(width 0.1)
				(type default)
			)
			(layer "B.Fab")
		)
		(fp_line
			(start 0.2794 -0.1016)
			(end 0.2794 0.9906)
			(stroke
				(width 0.1)
				(type default)
			)
			(layer "B.Fab")
		)
		(pad "1" smd rect
			(at 0 0 90)
			(size 0.508 0.508)
			(layers "B.Cu" "B.Mask" "B.Paste")
			(net "FAN_TACH1")
		)
		(pad "2" smd rect
			(at 0 0.889 90)
			(size 0.508 0.508)
			(layers "B.Cu" "B.Mask" "B.Paste")
			(net "FAN_TACH1_R")
		)
		(zone
			(layer "B.Cu")
			(hatch none 0.5)
			(connect_pads
				(clearance 0)
			)
			(min_thickness 0.25)
			(keepout
				(tracks not_allowed)
				(vias allowed)
				(pads allowed)
				(copperpour not_allowed)
				(footprints allowed)
			)
			(placement
				(enabled no)
				(sheetname "")
			)
			(fill
				(thermal_gap 0.5)
				(thermal_bridge_width 0.5)
				(island_removal_mode 0)
			)
			(polygon
				(pts
					(xy 13.335 -41.148) (xy 13.335 -41.656) (xy 13.716 -41.656) (xy 13.716 -41.148)
				)
			)
		)
		(zone
			(layer "B.Cu")
			(hatch none 0.5)
			(connect_pads
				(clearance 0)
			)
			(min_thickness 0.25)
			(keepout
				(tracks allowed)
				(vias not_allowed)
				(pads allowed)
				(copperpour not_allowed)
				(footprints allowed)
			)
			(placement
				(enabled no)
				(sheetname "")
			)
			(fill
				(thermal_gap 0.5)
				(thermal_bridge_width 0.5)
				(island_removal_mode 0)
			)
			(polygon
				(pts
					(xy 13.716 -41.148) (xy 13.716 -41.656) (xy 13.335 -41.656) (xy 13.335 -41.148)
				)
			)
		)
	)
	(footprint ""
		(layer "B.Cu")
		(at 477.774 -34.0995)
		(property "Reference" "C2T37"
			(at 0 0 0)
			(layer "B.SilkS")
			(hide yes)
			(effects
				(font
					(size 1.27 1.27)
				)
				(justify mirror)
			)
		)
		(property "Value" ""
			(at 0 0 0)
			(layer "B.Fab")
			(effects
				(font
					(size 1.27 1.27)
				)
				(justify mirror)
			)
		)
		(duplicate_pad_numbers_are_jumpers no)
		(fp_poly
			(pts
				(xy -0.3048 -0.1016) (xy -0.3048 0.9906) (xy 0.3048 0.9906) (xy 0.3048 -0.1016)
			)
			(stroke
				(width 0)
				(type default)
			)
			(fill no)
			(layer "B.CrtYd")
		)
		(fp_line
			(start -0.3048 -0.1016)
			(end 0.3048 -0.1016)
			(stroke
				(width 0.1)
				(type default)
			)
			(layer "B.Fab")
		)
		(fp_line
			(start -0.3048 0.9906)
			(end -0.3048 -0.1016)
			(stroke
				(width 0.1)
				(type default)
			)
			(layer "B.Fab")
		)
		(fp_line
			(start 0.3048 -0.1016)
			(end 0.3048 0.9906)
			(stroke
				(width 0.1)
				(type default)
			)
			(layer "B.Fab")
		)
		(fp_line
			(start 0.3048 0.9906)
			(end -0.3048 0.9906)
			(stroke
				(width 0.1)
				(type default)
			)
			(layer "B.Fab")
		)
		(pad "1" smd rect
			(at 0 0 180)
			(size 0.508 0.508)
			(layers "B.Cu" "B.Mask" "B.Paste")
			(net "P3V3_STBY_MNG_RMII")
		)
		(pad "2" smd rect
			(at 0 0.889 180)
			(size 0.508 0.508)
			(layers "B.Cu" "B.Mask" "B.Paste")
			(net "GND")
		)
		(zone
			(layer "B.Cu")
			(hatch none 0.5)
			(connect_pads
				(clearance 0)
			)
			(min_thickness 0.25)
			(keepout
				(tracks allowed)
				(vias not_allowed)
				(pads allowed)
				(copperpour not_allowed)
				(footprints allowed)
			)
			(placement
				(enabled no)
				(sheetname "")
			)
			(fill
				(thermal_gap 0.5)
				(thermal_bridge_width 0.5)
				(island_removal_mode 0)
			)
			(polygon
				(pts
					(xy 478.028 -33.8455) (xy 477.52 -33.8455) (xy 477.52 -33.4645) (xy 478.028 -33.4645)
				)
			)
		)
		(zone
			(layer "B.Cu")
			(hatch none 0.5)
			(connect_pads
				(clearance 0)
			)
			(min_thickness 0.25)
			(keepout
				(tracks not_allowed)
				(vias allowed)
				(pads allowed)
				(copperpour not_allowed)
				(footprints allowed)
			)
			(placement
				(enabled no)
				(sheetname "")
			)
			(fill
				(thermal_gap 0.5)
				(thermal_bridge_width 0.5)
				(island_removal_mode 0)
			)
			(polygon
				(pts
					(xy 478.028 -33.4645) (xy 477.52 -33.4645) (xy 477.52 -33.8455) (xy 478.028 -33.8455)
				)
			)
		)
	)
	(footprint ""
		(layer "B.Cu")
		(at 260.6802 -26.475182 -90)
		(property "Reference" "C5T3"
			(at 0 0 90)
			(layer "B.SilkS")
			(hide yes)
			(effects
				(font
					(size 1.27 1.27)
				)
				(justify mirror)
			)
		)
		(property "Value" ""
			(at 0 0 90)
			(layer "B.Fab")
			(effects
				(font
					(size 1.27 1.27)
				)
				(justify mirror)
			)
		)
		(duplicate_pad_numbers_are_jumpers no)
		(fp_rect
			(start 0.500126 1.598422)
			(end -0.500126 -0.201422)
			(stroke
				(width 0)
				(type default)
			)
			(fill no)
			(layer "B.CrtYd")
		)
		(fp_line
			(start -0.500126 1.598422)
			(end 0.500126 1.598422)
			(stroke
				(width 0.1)
				(type default)
			)
			(layer "B.Fab")
		)
		(fp_line
			(start 0.500126 1.598422)
			(end 0.500126 -0.201422)
			(stroke
				(width 0.1)
				(type default)
			)
			(layer "B.Fab")
		)
		(fp_line
			(start -0.500126 -0.201422)
			(end -0.500126 1.598422)
			(stroke
				(width 0.1)
				(type default)
			)
			(layer "B.Fab")
		)
		(fp_line
			(start 0.500126 -0.201422)
			(end -0.500126 -0.201422)
			(stroke
				(width 0.1)
				(type default)
			)
			(layer "B.Fab")
		)
		(pad "1" smd rect
			(at 0 0 180)
			(size 0.889 0.9906)
			(layers "B.Cu" "B.Mask" "B.Paste")
			(net "PVTT_ABC")
		)
		(pad "2" smd rect
			(at 0 1.397 180)
			(size 0.889 0.9906)
			(layers "B.Cu" "B.Mask" "B.Paste")
			(net "GND")
		)
		(zone
			(layer "B.Cu")
			(hatch none 0.5)
			(connect_pads
				(clearance 0)
			)
			(min_thickness 0.25)
			(keepout
				(tracks not_allowed)
				(vias allowed)
				(pads allowed)
				(copperpour not_allowed)
				(footprints allowed)
			)
			(placement
				(enabled no)
				(sheetname "")
			)
			(fill
				(thermal_gap 0.5)
				(thermal_bridge_width 0.5)
				(island_removal_mode 0)
			)
			(polygon
				(pts
					(xy 259.7277 -25.979882) (xy 260.2357 -25.979882) (xy 260.2357 -26.970482) (xy 259.7277 -26.970482)
				)
			)
		)
		(zone
			(layer "B.Cu")
			(hatch none 0.5)
			(connect_pads
				(clearance 0)
			)
			(min_thickness 0.25)
			(keepout
				(tracks allowed)
				(vias not_allowed)
				(pads allowed)
				(copperpour not_allowed)
				(footprints allowed)
			)
			(placement
				(enabled no)
				(sheetname "")
			)
			(fill
				(thermal_gap 0.5)
				(thermal_bridge_width 0.5)
				(island_removal_mode 0)
			)
			(polygon
				(pts
					(xy 259.7277 -25.979882) (xy 260.2357 -25.979882) (xy 260.2357 -26.970482) (xy 259.7277 -26.970482)
				)
			)
		)
	)
	(footprint ""
		(layer "B.Cu")
		(at 101.3968 -8.1534 90)
		(property "Reference" "C8U3"
			(at -1.848866 0.752348 90)
			(unlocked yes)
			(layer "B.SilkS")
			(effects
				(font
					(size 1.27 0.9652)
					(thickness 0.1524)
				)
				(justify mirror)
			)
		)
		(property "Value" ""
			(at 0 0 90)
			(layer "B.Fab")
			(effects
				(font
					(size 1.27 1.27)
				)
				(justify mirror)
			)
		)
		(duplicate_pad_numbers_are_jumpers no)
		(fp_rect
			(start 0.500126 1.598422)
			(end -0.500126 -0.201422)
			(stroke
				(width 0)
				(type default)
			)
			(fill no)
			(layer "B.CrtYd")
		)
		(fp_line
			(start 0.500126 -0.201422)
			(end -0.500126 -0.201422)
			(stroke
				(width 0.1)
				(type default)
			)
			(layer "B.Fab")
		)
		(fp_line
			(start -0.500126 -0.201422)
			(end -0.500126 1.598422)
			(stroke
				(width 0.1)
				(type default)
			)
			(layer "B.Fab")
		)
		(fp_line
			(start 0.500126 1.598422)
			(end 0.500126 -0.201422)
			(stroke
				(width 0.1)
				(type default)
			)
			(layer "B.Fab")
		)
		(fp_line
			(start -0.500126 1.598422)
			(end 0.500126 1.598422)
			(stroke
				(width 0.1)
				(type default)
			)
			(layer "B.Fab")
		)
		(pad "1" smd rect
			(at 0 0)
			(size 0.889 0.9906)
			(layers "B.Cu" "B.Mask" "B.Paste")
			(net "PVDDQ_GHJ")
		)
		(pad "2" smd rect
			(at 0 1.397)
			(size 0.889 0.9906)
			(layers "B.Cu" "B.Mask" "B.Paste")
			(net "GND")
		)
		(zone
			(layer "B.Cu")
			(hatch none 0.5)
			(connect_pads
				(clearance 0)
			)
			(min_thickness 0.25)
			(keepout
				(tracks allowed)
				(vias not_allowed)
				(pads allowed)
				(copperpour not_allowed)
				(footprints allowed)
			)
			(placement
				(enabled no)
				(sheetname "")
			)
			(fill
				(thermal_gap 0.5)
				(thermal_bridge_width 0.5)
				(island_removal_mode 0)
			)
			(polygon
				(pts
					(xy 102.3493 -8.6487) (xy 101.8413 -8.6487) (xy 101.8413 -7.6581) (xy 102.3493 -7.6581)
				)
			)
		)
		(zone
			(layer "B.Cu")
			(hatch none 0.5)
			(connect_pads
				(clearance 0)
			)
			(min_thickness 0.25)
			(keepout
				(tracks not_allowed)
				(vias allowed)
				(pads allowed)
				(copperpour not_allowed)
				(footprints allowed)
			)
			(placement
				(enabled no)
				(sheetname "")
			)
			(fill
				(thermal_gap 0.5)
				(thermal_bridge_width 0.5)
				(island_removal_mode 0)
			)
			(polygon
				(pts
					(xy 102.3493 -8.6487) (xy 101.8413 -8.6487) (xy 101.8413 -7.6581) (xy 102.3493 -7.6581)
				)
			)
		)
	)
	(footprint ""
		(layer "B.Cu")
		(at 311.130696 -28.942792)
		(property "Reference" "R8D29"
			(at 0 0 0)
			(layer "B.SilkS")
			(hide yes)
			(effects
				(font
					(size 1.27 1.27)
				)
				(justify mirror)
			)
		)
		(property "Value" ""
			(at 0 0 0)
			(layer "B.Fab")
			(effects
				(font
					(size 1.27 1.27)
				)
				(justify mirror)
			)
		)
		(duplicate_pad_numbers_are_jumpers no)
		(fp_poly
			(pts
				(xy 0.2794 -0.1016) (xy -0.2794 -0.1016) (xy -0.2794 0.9906) (xy 0.2794 0.9906)
			)
			(stroke
				(width 0)
				(type default)
			)
			(fill no)
			(layer "B.CrtYd")
		)
		(fp_line
			(start -0.2794 -0.1016)
			(end 0.2794 -0.1016)
			(stroke
				(width 0.1)
				(type default)
			)
			(layer "B.Fab")
		)
		(fp_line
			(start -0.2794 0.9906)
			(end -0.2794 -0.1016)
			(stroke
				(width 0.1)
				(type default)
			)
			(layer "B.Fab")
		)
		(fp_line
			(start 0.2794 -0.1016)
			(end 0.2794 0.9906)
			(stroke
				(width 0.1)
				(type default)
			)
			(layer "B.Fab")
		)
		(fp_line
			(start 0.2794 0.9906)
			(end -0.2794 0.9906)
			(stroke
				(width 0.1)
				(type default)
			)
			(layer "B.Fab")
		)
		(pad "1" smd rect
			(at 0 0 180)
			(size 0.508 0.508)
			(layers "B.Cu" "B.Mask" "B.Paste")
			(net "P3V3_STBY")
		)
		(pad "2" smd rect
			(at 0 0.889 180)
			(size 0.508 0.508)
			(layers "B.Cu" "B.Mask" "B.Paste")
			(net "IRQ_DIMM_SAVE_LVT3")
		)
		(zone
			(layer "B.Cu")
			(hatch none 0.5)
			(connect_pads
				(clearance 0)
			)
			(min_thickness 0.25)
			(keepout
				(tracks allowed)
				(vias not_allowed)
				(pads allowed)
				(copperpour not_allowed)
				(footprints allowed)
			)
			(placement
				(enabled no)
				(sheetname "")
			)
			(fill
				(thermal_gap 0.5)
				(thermal_bridge_width 0.5)
				(island_removal_mode 0)
			)
			(polygon
				(pts
					(xy 311.384696 -28.688792) (xy 310.876696 -28.688792) (xy 310.876696 -28.307792) (xy 311.384696 -28.307792)
				)
			)
		)
		(zone
			(layer "B.Cu")
			(hatch none 0.5)
			(connect_pads
				(clearance 0)
			)
			(min_thickness 0.25)
			(keepout
				(tracks not_allowed)
				(vias allowed)
				(pads allowed)
				(copperpour not_allowed)
				(footprints allowed)
			)
			(placement
				(enabled no)
				(sheetname "")
			)
			(fill
				(thermal_gap 0.5)
				(thermal_bridge_width 0.5)
				(island_removal_mode 0)
			)
			(polygon
				(pts
					(xy 311.384696 -28.307792) (xy 310.876696 -28.307792) (xy 310.876696 -28.688792) (xy 311.384696 -28.688792)
				)
			)
		)
	)
	(footprint ""
		(layer "B.Cu")
		(at 387.604 -87.3125 180)
		(property "Reference" "R3N11"
			(at 0 0 0)
			(layer "B.SilkS")
			(hide yes)
			(effects
				(font
					(size 1.27 1.27)
				)
				(justify mirror)
			)
		)
		(property "Value" ""
			(at 0 0 0)
			(layer "B.Fab")
			(effects
				(font
					(size 1.27 1.27)
				)
				(justify mirror)
			)
		)
		(duplicate_pad_numbers_are_jumpers no)
		(fp_poly
			(pts
				(xy 0.2794 -0.1016) (xy -0.2794 -0.1016) (xy -0.2794 0.9906) (xy 0.2794 0.9906)
			)
			(stroke
				(width 0)
				(type default)
			)
			(fill no)
			(layer "B.CrtYd")
		)
		(fp_line
			(start 0.2794 0.9906)
			(end -0.2794 0.9906)
			(stroke
				(width 0.1)
				(type default)
			)
			(layer "B.Fab")
		)
		(fp_line
			(start 0.2794 -0.1016)
			(end 0.2794 0.9906)
			(stroke
				(width 0.1)
				(type default)
			)
			(layer "B.Fab")
		)
		(fp_line
			(start -0.2794 0.9906)
			(end -0.2794 -0.1016)
			(stroke
				(width 0.1)
				(type default)
			)
			(layer "B.Fab")
		)
		(fp_line
			(start -0.2794 -0.1016)
			(end 0.2794 -0.1016)
			(stroke
				(width 0.1)
				(type default)
			)
			(layer "B.Fab")
		)
		(pad "1" smd rect
			(at 0 0)
			(size 0.508 0.508)
			(layers "B.Cu" "B.Mask" "B.Paste")
			(net "P3V3_STBY")
		)
		(pad "2" smd rect
			(at 0 0.889)
			(size 0.508 0.508)
			(layers "B.Cu" "B.Mask" "B.Paste")
			(net "FM_MP_PS_REDUNDANT_LOST_N")
		)
		(zone
			(layer "B.Cu")
			(hatch none 0.5)
			(connect_pads
				(clearance 0)
			)
			(min_thickness 0.25)
			(keepout
				(tracks not_allowed)
				(vias allowed)
				(pads allowed)
				(copperpour not_allowed)
				(footprints allowed)
			)
			(placement
				(enabled no)
				(sheetname "")
			)
			(fill
				(thermal_gap 0.5)
				(thermal_bridge_width 0.5)
				(island_removal_mode 0)
			)
			(polygon
				(pts
					(xy 387.35 -87.9475) (xy 387.858 -87.9475) (xy 387.858 -87.5665) (xy 387.35 -87.5665)
				)
			)
		)
		(zone
			(layer "B.Cu")
			(hatch none 0.5)
			(connect_pads
				(clearance 0)
			)
			(min_thickness 0.25)
			(keepout
				(tracks allowed)
				(vias not_allowed)
				(pads allowed)
				(copperpour not_allowed)
				(footprints allowed)
			)
			(placement
				(enabled no)
				(sheetname "")
			)
			(fill
				(thermal_gap 0.5)
				(thermal_bridge_width 0.5)
				(island_removal_mode 0)
			)
			(polygon
				(pts
					(xy 387.35 -87.5665) (xy 387.858 -87.5665) (xy 387.858 -87.9475) (xy 387.35 -87.9475)
				)
			)
		)
	)
	(footprint ""
		(layer "B.Cu")
		(at 388.66064 -80.2386 -90)
		(property "Reference" "R3P63"
			(at 0.8382 -0.67818 270)
			(unlocked yes)
			(layer "B.SilkS")
			(effects
				(font
					(size 0.4064 0.254)
					(thickness 0.1524)
				)
				(justify left mirror)
			)
		)
		(property "Value" ""
			(at 0 0 90)
			(layer "B.Fab")
			(effects
				(font
					(size 1.27 1.27)
				)
				(justify mirror)
			)
		)
		(duplicate_pad_numbers_are_jumpers no)
		(fp_poly
			(pts
				(xy 0.2794 -0.1016) (xy -0.2794 -0.1016) (xy -0.2794 0.9906) (xy 0.2794 0.9906)
			)
			(stroke
				(width 0)
				(type default)
			)
			(fill no)
			(layer "B.CrtYd")
		)
		(fp_line
			(start -0.2794 0.9906)
			(end -0.2794 -0.1016)
			(stroke
				(width 0.1)
				(type default)
			)
			(layer "B.Fab")
		)
		(fp_line
			(start 0.2794 0.9906)
			(end -0.2794 0.9906)
			(stroke
				(width 0.1)
				(type default)
			)
			(layer "B.Fab")
		)
		(fp_line
			(start -0.2794 -0.1016)
			(end 0.2794 -0.1016)
			(stroke
				(width 0.1)
				(type default)
			)
			(layer "B.Fab")
		)
		(fp_line
			(start 0.2794 -0.1016)
			(end 0.2794 0.9906)
			(stroke
				(width 0.1)
				(type default)
			)
			(layer "B.Fab")
		)
		(pad "1" smd rect
			(at 0 0 90)
			(size 0.508 0.508)
			(layers "B.Cu" "B.Mask" "B.Paste")
			(net "H_CPU1_MEMGHJ_MEMHOT_LVT3_N")
		)
		(pad "2" smd rect
			(at 0 0.889 90)
			(size 0.508 0.508)
			(layers "B.Cu" "B.Mask" "B.Paste")
			(net "H_CPU1_MEMGHJ_MEMHOT_PCH_N")
		)
		(zone
			(layer "B.Cu")
			(hatch none 0.5)
			(connect_pads
				(clearance 0)
			)
			(min_thickness 0.25)
			(keepout
				(tracks not_allowed)
				(vias allowed)
				(pads allowed)
				(copperpour not_allowed)
				(footprints allowed)
			)
			(placement
				(enabled no)
				(sheetname "")
			)
			(fill
				(thermal_gap 0.5)
				(thermal_bridge_width 0.5)
				(island_removal_mode 0)
			)
			(polygon
				(pts
					(xy 388.02564 -79.9846) (xy 388.02564 -80.4926) (xy 388.40664 -80.4926) (xy 388.40664 -79.9846)
				)
			)
		)
		(zone
			(layer "B.Cu")
			(hatch none 0.5)
			(connect_pads
				(clearance 0)
			)
			(min_thickness 0.25)
			(keepout
				(tracks allowed)
				(vias not_allowed)
				(pads allowed)
				(copperpour not_allowed)
				(footprints allowed)
			)
			(placement
				(enabled no)
				(sheetname "")
			)
			(fill
				(thermal_gap 0.5)
				(thermal_bridge_width 0.5)
				(island_removal_mode 0)
			)
			(polygon
				(pts
					(xy 388.40664 -79.9846) (xy 388.40664 -80.4926) (xy 388.02564 -80.4926) (xy 388.02564 -79.9846)
				)
			)
		)
	)
	(footprint ""
		(layer "B.Cu")
		(at 488.95 -15.748)
		(property "Reference" ""
			(at 0 0 0)
			(layer "B.SilkS")
			(hide yes)
			(effects
				(font
					(size 1.27 1.27)
				)
				(justify mirror)
			)
		)
		(property "Value" ""
			(at 0 0 0)
			(layer "B.Fab")
			(effects
				(font
					(size 1.27 1.27)
				)
				(justify mirror)
			)
		)
		(duplicate_pad_numbers_are_jumpers no)
		(fp_poly
			(pts
				(arc
					(start 2.032 0)
					(mid -2.032 0)
					(end 2.032 0)
				)
			)
			(stroke
				(width 0)
				(type default)
			)
			(fill no)
			(layer "B.CrtYd")
		)
		(pad "1" smd circle
			(at 0 0 180)
			(size 1.016 1.016)
			(layers "B.Cu" "B.Mask" "B.Paste")
			(net "Net_128")
		)
		(zone
			(layers "F.Cu" "B.Cu" "In1.Cu" "In2.Cu" "In3.Cu" "In4.Cu" "In5.Cu" "In6.Cu"
				"In7.Cu" "In8.Cu" "In9.Cu" "In10.Cu" "In11.Cu" "In12.Cu"
			)
			(hatch none 0.5)
			(connect_pads
				(clearance 0)
			)
			(min_thickness 0.25)
			(keepout
				(tracks allowed)
				(vias not_allowed)
				(pads allowed)
				(copperpour not_allowed)
				(footprints allowed)
			)
			(placement
				(enabled no)
				(sheetname "")
			)
			(fill
				(thermal_gap 0.5)
				(thermal_bridge_width 0.5)
				(island_removal_mode 0)
			)
			(polygon
				(pts
					(arc
						(start 490.474 -15.748)
						(mid 487.426 -15.748)
						(end 490.474 -15.748)
					)
				)
			)
		)
		(zone
			(layer "B.Cu")
			(hatch none 0.5)
			(connect_pads
				(clearance 0)
			)
			(min_thickness 0.25)
			(keepout
				(tracks not_allowed)
				(vias allowed)
				(pads allowed)
				(copperpour not_allowed)
				(footprints allowed)
			)
			(placement
				(enabled no)
				(sheetname "")
			)
			(fill
				(thermal_gap 0.5)
				(thermal_bridge_width 0.5)
				(island_removal_mode 0)
			)
			(polygon
				(pts
					(arc
						(start 490.474 -15.748)
						(mid 487.426 -15.748)
						(end 490.474 -15.748)
					)
				)
			)
		)
	)
	(footprint ""
		(layer "B.Cu")
		(at 371.983 -65.6844 180)
		(property "Reference" "R4W1"
			(at 0.8382 -0.67818 180)
			(unlocked yes)
			(layer "B.SilkS")
			(effects
				(font
					(size 0.4064 0.254)
					(thickness 0.1524)
				)
				(justify left mirror)
			)
		)
		(property "Value" ""
			(at 0 0 0)
			(layer "B.Fab")
			(effects
				(font
					(size 1.27 1.27)
				)
				(justify mirror)
			)
		)
		(duplicate_pad_numbers_are_jumpers no)
		(fp_poly
			(pts
				(xy 0.2794 -0.1016) (xy -0.2794 -0.1016) (xy -0.2794 0.9906) (xy 0.2794 0.9906)
			)
			(stroke
				(width 0)
				(type default)
			)
			(fill no)
			(layer "B.CrtYd")
		)
		(fp_line
			(start 0.2794 0.9906)
			(end -0.2794 0.9906)
			(stroke
				(width 0.1)
				(type default)
			)
			(layer "B.Fab")
		)
		(fp_line
			(start 0.2794 -0.1016)
			(end 0.2794 0.9906)
			(stroke
				(width 0.1)
				(type default)
			)
			(layer "B.Fab")
		)
		(fp_line
			(start -0.2794 0.9906)
			(end -0.2794 -0.1016)
			(stroke
				(width 0.1)
				(type default)
			)
			(layer "B.Fab")
		)
		(fp_line
			(start -0.2794 -0.1016)
			(end 0.2794 -0.1016)
			(stroke
				(width 0.1)
				(type default)
			)
			(layer "B.Fab")
		)
		(pad "1" smd rect
			(at 0 0)
			(size 0.508 0.508)
			(layers "B.Cu" "B.Mask" "B.Paste")
			(net "P3V3_STBY")
		)
		(pad "2" smd rect
			(at 0 0.889)
			(size 0.508 0.508)
			(layers "B.Cu" "B.Mask" "B.Paste")
			(net "PU_CPLD1_PT20D_PROGRAMN")
		)
		(zone
			(layer "B.Cu")
			(hatch none 0.5)
			(connect_pads
				(clearance 0)
			)
			(min_thickness 0.25)
			(keepout
				(tracks not_allowed)
				(vias allowed)
				(pads allowed)
				(copperpour not_allowed)
				(footprints allowed)
			)
			(placement
				(enabled no)
				(sheetname "")
			)
			(fill
				(thermal_gap 0.5)
				(thermal_bridge_width 0.5)
				(island_removal_mode 0)
			)
			(polygon
				(pts
					(xy 371.729 -66.3194) (xy 372.237 -66.3194) (xy 372.237 -65.9384) (xy 371.729 -65.9384)
				)
			)
		)
		(zone
			(layer "B.Cu")
			(hatch none 0.5)
			(connect_pads
				(clearance 0)
			)
			(min_thickness 0.25)
			(keepout
				(tracks allowed)
				(vias not_allowed)
				(pads allowed)
				(copperpour not_allowed)
				(footprints allowed)
			)
			(placement
				(enabled no)
				(sheetname "")
			)
			(fill
				(thermal_gap 0.5)
				(thermal_bridge_width 0.5)
				(island_removal_mode 0)
			)
			(polygon
				(pts
					(xy 371.729 -65.9384) (xy 372.237 -65.9384) (xy 372.237 -66.3194) (xy 371.729 -66.3194)
				)
			)
		)
	)
	(footprint ""
		(layer "B.Cu")
		(at 11.6332 -128.8034 90)
		(property "Reference" "R12W18"
			(at 0 0 90)
			(layer "B.SilkS")
			(hide yes)
			(effects
				(font
					(size 1.27 1.27)
				)
				(justify mirror)
			)
		)
		(property "Value" "*"
			(at -0.064008 -4.108196 90)
			(unlocked yes)
			(layer "B.Fab")
			(hide yes)
			(effects
				(font
					(size 1.27 1.016)
					(thickness 0.1524)
				)
				(justify mirror)
			)
		)
		(property "Device Type" "4D02R2F-GP_SMD-RG2-4D02R2F-GP,A"
			(at -0.064008 -5.632196 90)
			(unlocked yes)
			(layer "B.Fab")
			(hide yes)
			(effects
				(font
					(size 1.27 1.016)
					(thickness 0.1524)
				)
				(justify mirror)
			)
		)
		(duplicate_pad_numbers_are_jumpers no)
		(fp_line
			(start 0.508 -0.9398)
			(end 0.508 0.9398)
			(stroke
				(width 0.1524)
				(type default)
			)
			(layer "B.SilkS")
		)
		(fp_line
			(start -0.508 -0.9398)
			(end 0.508 -0.9398)
			(stroke
				(width 0.1524)
				(type default)
			)
			(layer "B.SilkS")
		)
		(fp_rect
			(start 0.508 0.9398)
			(end -0.508 -0.9398)
			(stroke
				(width 0)
				(type default)
			)
			(fill no)
			(layer "B.CrtYd")
		)
		(fp_rect
			(start 0.508 0.9398)
			(end -0.508 -0.9398)
			(stroke
				(width 0)
				(type default)
			)
			(fill no)
			(layer "B.Fab")
		)
		(pad "1" smd custom
			(at 0 -0.4445 270)
			(size 0.1397 0.1397)
			(layers "B.Cu" "B.Mask" "B.Paste")
			(net "P12V_STBY")
			(options
				(clearance outline)
				(anchor circle)
			)
			(primitives
				(gr_poly
					(pts
						(arc
							(start -0.1778 0.2794)
							(mid -0.249642 0.249642)
							(end -0.2794 0.1778)
						)
						(arc
							(start -0.2794 -0.1778)
							(mid -0.249642 -0.249642)
							(end -0.1778 -0.2794)
						)
						(arc
							(start 0.1778 -0.2794)
							(mid 0.249642 -0.249642)
							(end 0.2794 -0.1778)
						)
						(arc
							(start 0.2794 0.1778)
							(mid 0.249642 0.249642)
							(end 0.1778 0.2794)
						)
					)
					(width 0)
					(fill yes)
				)
			)
		)
		(pad "2" smd custom
			(at 0 0.4445 270)
			(size 0.1397 0.1397)
			(layers "B.Cu" "B.Mask" "B.Paste")
			(net "P12V_NVDIMM_KLM_D")
			(options
				(clearance outline)
				(anchor circle)
			)
			(primitives
				(gr_poly
					(pts
						(arc
							(start -0.1778 0.2794)
							(mid -0.249642 0.249642)
							(end -0.2794 0.1778)
						)
						(arc
							(start -0.2794 -0.1778)
							(mid -0.249642 -0.249642)
							(end -0.1778 -0.2794)
						)
						(arc
							(start 0.1778 -0.2794)
							(mid 0.249642 -0.249642)
							(end 0.2794 -0.1778)
						)
						(arc
							(start 0.2794 0.1778)
							(mid 0.249642 0.249642)
							(end 0.1778 0.2794)
						)
					)
					(width 0)
					(fill yes)
				)
			)
		)
	)
	(footprint ""
		(layer "B.Cu")
		(at 452.501 -116.49202)
		(property "Reference" "C1M15"
			(at 0 0 0)
			(layer "B.SilkS")
			(hide yes)
			(effects
				(font
					(size 1.27 1.27)
				)
				(justify mirror)
			)
		)
		(property "Value" ""
			(at 0 0 0)
			(layer "B.Fab")
			(effects
				(font
					(size 1.27 1.27)
				)
				(justify mirror)
			)
		)
		(duplicate_pad_numbers_are_jumpers no)
		(fp_rect
			(start -0.3048 0.9906)
			(end 0.3048 -0.1016)
			(stroke
				(width 0)
				(type default)
			)
			(fill no)
			(layer "B.CrtYd")
		)
		(fp_line
			(start -0.3048 -0.1016)
			(end 0.3048 -0.1016)
			(stroke
				(width 0.1)
				(type default)
			)
			(layer "B.Fab")
		)
		(fp_line
			(start -0.3048 0.9906)
			(end -0.3048 -0.1016)
			(stroke
				(width 0.1)
				(type default)
			)
			(layer "B.Fab")
		)
		(fp_line
			(start 0.3048 -0.1016)
			(end 0.3048 0.9906)
			(stroke
				(width 0.1)
				(type default)
			)
			(layer "B.Fab")
		)
		(fp_line
			(start 0.3048 0.9906)
			(end -0.3048 0.9906)
			(stroke
				(width 0.1)
				(type default)
			)
			(layer "B.Fab")
		)
		(pad "1" smd rect
			(at 0 0 180)
			(size 0.508 0.508)
			(layers "B.Cu" "B.Mask" "B.Paste")
			(net "P3E_CPU0_PE3_OCP_TXN<11>")
		)
		(pad "2" smd rect
			(at 0 0.889 180)
			(size 0.508 0.508)
			(layers "B.Cu" "B.Mask" "B.Paste")
			(net "P3E_OCP_CPU0_PE3_C_TXN<11>")
		)
		(zone
			(layer "B.Cu")
			(hatch none 0.5)
			(connect_pads
				(clearance 0)
			)
			(min_thickness 0.25)
			(keepout
				(tracks allowed)
				(vias not_allowed)
				(pads allowed)
				(copperpour not_allowed)
				(footprints allowed)
			)
			(placement
				(enabled no)
				(sheetname "")
			)
			(fill
				(thermal_gap 0.5)
				(thermal_bridge_width 0.5)
				(island_removal_mode 0)
			)
			(polygon
				(pts
					(xy 452.247 -115.85702) (xy 452.755 -115.85702) (xy 452.755 -116.23802) (xy 452.247 -116.23802)
				)
			)
		)
		(zone
			(layer "B.Cu")
			(hatch none 0.5)
			(connect_pads
				(clearance 0)
			)
			(min_thickness 0.25)
			(keepout
				(tracks not_allowed)
				(vias allowed)
				(pads allowed)
				(copperpour not_allowed)
				(footprints allowed)
			)
			(placement
				(enabled no)
				(sheetname "")
			)
			(fill
				(thermal_gap 0.5)
				(thermal_bridge_width 0.5)
				(island_removal_mode 0)
			)
			(polygon
				(pts
					(xy 452.247 -115.85702) (xy 452.755 -115.85702) (xy 452.755 -116.23802) (xy 452.247 -116.23802)
				)
			)
		)
	)
	(footprint ""
		(layer "B.Cu")
		(at 28.674568 -154.559 180)
		(property "Reference" "R9L2"
			(at 0 0 0)
			(layer "B.SilkS")
			(hide yes)
			(effects
				(font
					(size 1.27 1.27)
				)
				(justify mirror)
			)
		)
		(property "Value" ""
			(at 0 0 0)
			(layer "B.Fab")
			(effects
				(font
					(size 1.27 1.27)
				)
				(justify mirror)
			)
		)
		(duplicate_pad_numbers_are_jumpers no)
		(fp_poly
			(pts
				(xy 0.2794 -0.1016) (xy -0.2794 -0.1016) (xy -0.2794 0.9906) (xy 0.2794 0.9906)
			)
			(stroke
				(width 0)
				(type default)
			)
			(fill no)
			(layer "B.CrtYd")
		)
		(fp_line
			(start 0.2794 0.9906)
			(end -0.2794 0.9906)
			(stroke
				(width 0.1)
				(type default)
			)
			(layer "B.Fab")
		)
		(fp_line
			(start 0.2794 -0.1016)
			(end 0.2794 0.9906)
			(stroke
				(width 0.1)
				(type default)
			)
			(layer "B.Fab")
		)
		(fp_line
			(start -0.2794 0.9906)
			(end -0.2794 -0.1016)
			(stroke
				(width 0.1)
				(type default)
			)
			(layer "B.Fab")
		)
		(fp_line
			(start -0.2794 -0.1016)
			(end 0.2794 -0.1016)
			(stroke
				(width 0.1)
				(type default)
			)
			(layer "B.Fab")
		)
		(pad "1" smd rect
			(at 0 0)
			(size 0.508 0.508)
			(layers "B.Cu" "B.Mask" "B.Paste")
			(net "PVDDQ_KLM")
		)
		(pad "2" smd rect
			(at 0 0.889)
			(size 0.508 0.508)
			(layers "B.Cu" "B.Mask" "B.Paste")
			(net "M_M_VREF")
		)
		(zone
			(layer "B.Cu")
			(hatch none 0.5)
			(connect_pads
				(clearance 0)
			)
			(min_thickness 0.25)
			(keepout
				(tracks not_allowed)
				(vias allowed)
				(pads allowed)
				(copperpour not_allowed)
				(footprints allowed)
			)
			(placement
				(enabled no)
				(sheetname "")
			)
			(fill
				(thermal_gap 0.5)
				(thermal_bridge_width 0.5)
				(island_removal_mode 0)
			)
			(polygon
				(pts
					(xy 28.420568 -155.194) (xy 28.928568 -155.194) (xy 28.928568 -154.813) (xy 28.420568 -154.813)
				)
			)
		)
		(zone
			(layer "B.Cu")
			(hatch none 0.5)
			(connect_pads
				(clearance 0)
			)
			(min_thickness 0.25)
			(keepout
				(tracks allowed)
				(vias not_allowed)
				(pads allowed)
				(copperpour not_allowed)
				(footprints allowed)
			)
			(placement
				(enabled no)
				(sheetname "")
			)
			(fill
				(thermal_gap 0.5)
				(thermal_bridge_width 0.5)
				(island_removal_mode 0)
			)
			(polygon
				(pts
					(xy 28.420568 -154.813) (xy 28.928568 -154.813) (xy 28.928568 -155.194) (xy 28.420568 -155.194)
				)
			)
		)
	)
	(footprint ""
		(layer "B.Cu")
		(at 433.833524 -42.91838 90)
		(property "Reference" "C1T21"
			(at 0 0 90)
			(layer "B.SilkS")
			(hide yes)
			(effects
				(font
					(size 1.27 1.27)
				)
				(justify mirror)
			)
		)
		(property "Value" ""
			(at 0 0 90)
			(layer "B.Fab")
			(effects
				(font
					(size 1.27 1.27)
				)
				(justify mirror)
			)
		)
		(duplicate_pad_numbers_are_jumpers no)
		(fp_poly
			(pts
				(xy -0.3048 -0.1016) (xy -0.3048 0.9906) (xy 0.3048 0.9906) (xy 0.3048 -0.1016)
			)
			(stroke
				(width 0)
				(type default)
			)
			(fill no)
			(layer "B.CrtYd")
		)
		(fp_line
			(start 0.3048 -0.1016)
			(end 0.3048 0.9906)
			(stroke
				(width 0.1)
				(type default)
			)
			(layer "B.Fab")
		)
		(fp_line
			(start -0.3048 -0.1016)
			(end 0.3048 -0.1016)
			(stroke
				(width 0.1)
				(type default)
			)
			(layer "B.Fab")
		)
		(fp_line
			(start 0.3048 0.9906)
			(end -0.3048 0.9906)
			(stroke
				(width 0.1)
				(type default)
			)
			(layer "B.Fab")
		)
		(fp_line
			(start -0.3048 0.9906)
			(end -0.3048 -0.1016)
			(stroke
				(width 0.1)
				(type default)
			)
			(layer "B.Fab")
		)
		(pad "1" smd rect
			(at 0 0 270)
			(size 0.508 0.508)
			(layers "B.Cu" "B.Mask" "B.Paste")
			(net "PVCCIO_CPU0")
		)
		(pad "2" smd rect
			(at 0 0.889 270)
			(size 0.508 0.508)
			(layers "B.Cu" "B.Mask" "B.Paste")
			(net "GND")
		)
		(zone
			(layer "B.Cu")
			(hatch none 0.5)
			(connect_pads
				(clearance 0)
			)
			(min_thickness 0.25)
			(keepout
				(tracks allowed)
				(vias not_allowed)
				(pads allowed)
				(copperpour not_allowed)
				(footprints allowed)
			)
			(placement
				(enabled no)
				(sheetname "")
			)
			(fill
				(thermal_gap 0.5)
				(thermal_bridge_width 0.5)
				(island_removal_mode 0)
			)
			(polygon
				(pts
					(xy 434.087524 -43.17238) (xy 434.087524 -42.66438) (xy 434.468524 -42.66438) (xy 434.468524 -43.17238)
				)
			)
		)
		(zone
			(layer "B.Cu")
			(hatch none 0.5)
			(connect_pads
				(clearance 0)
			)
			(min_thickness 0.25)
			(keepout
				(tracks not_allowed)
				(vias allowed)
				(pads allowed)
				(copperpour not_allowed)
				(footprints allowed)
			)
			(placement
				(enabled no)
				(sheetname "")
			)
			(fill
				(thermal_gap 0.5)
				(thermal_bridge_width 0.5)
				(island_removal_mode 0)
			)
			(polygon
				(pts
					(xy 434.468524 -43.17238) (xy 434.468524 -42.66438) (xy 434.087524 -42.66438) (xy 434.087524 -43.17238)
				)
			)
		)
	)
	(footprint ""
		(layer "B.Cu")
		(at 369.443 -62.9285 180)
		(property "Reference" "R3P42"
			(at 0 0 0)
			(layer "B.SilkS")
			(hide yes)
			(effects
				(font
					(size 1.27 1.27)
				)
				(justify mirror)
			)
		)
		(property "Value" ""
			(at 0 0 0)
			(layer "B.Fab")
			(effects
				(font
					(size 1.27 1.27)
				)
				(justify mirror)
			)
		)
		(duplicate_pad_numbers_are_jumpers no)
		(fp_poly
			(pts
				(xy 0.2794 -0.1016) (xy -0.2794 -0.1016) (xy -0.2794 0.9906) (xy 0.2794 0.9906)
			)
			(stroke
				(width 0)
				(type default)
			)
			(fill no)
			(layer "B.CrtYd")
		)
		(fp_line
			(start 0.2794 0.9906)
			(end -0.2794 0.9906)
			(stroke
				(width 0.1)
				(type default)
			)
			(layer "B.Fab")
		)
		(fp_line
			(start 0.2794 -0.1016)
			(end 0.2794 0.9906)
			(stroke
				(width 0.1)
				(type default)
			)
			(layer "B.Fab")
		)
		(fp_line
			(start -0.2794 0.9906)
			(end -0.2794 -0.1016)
			(stroke
				(width 0.1)
				(type default)
			)
			(layer "B.Fab")
		)
		(fp_line
			(start -0.2794 -0.1016)
			(end 0.2794 -0.1016)
			(stroke
				(width 0.1)
				(type default)
			)
			(layer "B.Fab")
		)
		(pad "1" smd rect
			(at 0 0)
			(size 0.508 0.508)
			(layers "B.Cu" "B.Mask" "B.Paste")
			(net "FM_CPU1_THERMTRIP_LVT3_R_N")
		)
		(pad "2" smd rect
			(at 0 0.889)
			(size 0.508 0.508)
			(layers "B.Cu" "B.Mask" "B.Paste")
			(net "FM_CPU1_THERMTRIP_LVT3_N")
		)
		(zone
			(layer "B.Cu")
			(hatch none 0.5)
			(connect_pads
				(clearance 0)
			)
			(min_thickness 0.25)
			(keepout
				(tracks not_allowed)
				(vias allowed)
				(pads allowed)
				(copperpour not_allowed)
				(footprints allowed)
			)
			(placement
				(enabled no)
				(sheetname "")
			)
			(fill
				(thermal_gap 0.5)
				(thermal_bridge_width 0.5)
				(island_removal_mode 0)
			)
			(polygon
				(pts
					(xy 369.189 -63.5635) (xy 369.697 -63.5635) (xy 369.697 -63.1825) (xy 369.189 -63.1825)
				)
			)
		)
		(zone
			(layer "B.Cu")
			(hatch none 0.5)
			(connect_pads
				(clearance 0)
			)
			(min_thickness 0.25)
			(keepout
				(tracks allowed)
				(vias not_allowed)
				(pads allowed)
				(copperpour not_allowed)
				(footprints allowed)
			)
			(placement
				(enabled no)
				(sheetname "")
			)
			(fill
				(thermal_gap 0.5)
				(thermal_bridge_width 0.5)
				(island_removal_mode 0)
			)
			(polygon
				(pts
					(xy 369.189 -63.1825) (xy 369.697 -63.1825) (xy 369.697 -63.5635) (xy 369.189 -63.5635)
				)
			)
		)
	)
	(footprint ""
		(layer "B.Cu")
		(at 454.4822 -128.6764 -90)
		(property "Reference" "U1M5"
			(at 1.4986 3.64109 270)
			(unlocked yes)
			(layer "B.SilkS")
			(effects
				(font
					(size 0.7874 0.5842)
					(thickness 0.1524)
				)
				(justify left mirror)
			)
		)
		(property "Value" ""
			(at 0 0 90)
			(layer "B.Fab")
			(effects
				(font
					(size 1.27 1.27)
				)
				(justify mirror)
			)
		)
		(duplicate_pad_numbers_are_jumpers no)
		(fp_circle
			(center 0.4699 -0.8382)
			(end 0.4699 -0.9652)
			(stroke
				(width 0.254)
				(type default)
			)
			(fill no)
			(layer "B.SilkS")
		)
		(fp_poly
			(pts
				(xy -0.21463 -0.450088) (xy -1.56337 -0.450088) (xy -1.56337 1.75006) (xy -0.21463 1.75006)
			)
			(stroke
				(width 0)
				(type default)
			)
			(fill no)
			(layer "B.CrtYd")
		)
		(fp_line
			(start -1.56337 1.75006)
			(end -0.21463 1.75006)
			(stroke
				(width 0.1)
				(type default)
			)
			(layer "B.Fab")
		)
		(fp_line
			(start -0.21463 1.75006)
			(end -0.21463 -0.450088)
			(stroke
				(width 0.1)
				(type default)
			)
			(layer "B.Fab")
		)
		(fp_line
			(start -1.56337 -0.450088)
			(end -1.56337 1.75006)
			(stroke
				(width 0.1)
				(type default)
			)
			(layer "B.Fab")
		)
		(fp_line
			(start -0.21463 -0.450088)
			(end -1.56337 -0.450088)
			(stroke
				(width 0.1)
				(type default)
			)
			(layer "B.Fab")
		)
		(fp_circle
			(center 0.4699 -0.8382)
			(end 0.4699 -0.9652)
			(stroke
				(width 0.254)
				(type default)
			)
			(fill no)
			(layer "B.Fab")
		)
		(pad "1" smd rect
			(at 0 0 90)
			(size 1.016 0.381)
			(layers "B.Cu" "B.Mask" "B.Paste")
			(net "FM_CPU0_OR_CPU1_MCP_PRES")
		)
		(pad "2" smd rect
			(at 0 0.649986 90)
			(size 1.016 0.381)
			(layers "B.Cu" "B.Mask" "B.Paste")
			(net "P1V8_MCP_CPU0")
		)
		(pad "3" smd rect
			(at 0 1.299972 90)
			(size 1.016 0.381)
			(layers "B.Cu" "B.Mask" "B.Paste")
			(net "GND")
		)
		(pad "4" smd rect
			(at -1.778 1.299972 90)
			(size 1.016 0.381)
			(layers "B.Cu" "B.Mask" "B.Paste")
			(net "JTAG_MCP_TMS_R1")
		)
		(pad "5" smd rect
			(at -1.778 0 90)
			(size 1.016 0.381)
			(layers "B.Cu" "B.Mask" "B.Paste")
			(net "P3V3_STBY")
		)
	)
	(footprint ""
		(layer "B.Cu")
		(at 408.305 -150.622 90)
		(property "Reference" "C2L16"
			(at 0 0 90)
			(layer "B.SilkS")
			(hide yes)
			(effects
				(font
					(size 1.27 1.27)
				)
				(justify mirror)
			)
		)
		(property "Value" ""
			(at 0 0 90)
			(layer "B.Fab")
			(effects
				(font
					(size 1.27 1.27)
				)
				(justify mirror)
			)
		)
		(duplicate_pad_numbers_are_jumpers no)
		(fp_poly
			(pts
				(xy -0.3048 -0.1016) (xy -0.3048 0.9906) (xy 0.3048 0.9906) (xy 0.3048 -0.1016)
			)
			(stroke
				(width 0)
				(type default)
			)
			(fill no)
			(layer "B.CrtYd")
		)
		(fp_line
			(start 0.3048 -0.1016)
			(end 0.3048 0.9906)
			(stroke
				(width 0.1)
				(type default)
			)
			(layer "B.Fab")
		)
		(fp_line
			(start -0.3048 -0.1016)
			(end 0.3048 -0.1016)
			(stroke
				(width 0.1)
				(type default)
			)
			(layer "B.Fab")
		)
		(fp_line
			(start 0.3048 0.9906)
			(end -0.3048 0.9906)
			(stroke
				(width 0.1)
				(type default)
			)
			(layer "B.Fab")
		)
		(fp_line
			(start -0.3048 0.9906)
			(end -0.3048 -0.1016)
			(stroke
				(width 0.1)
				(type default)
			)
			(layer "B.Fab")
		)
		(pad "1" smd rect
			(at 0 0 270)
			(size 0.508 0.508)
			(layers "B.Cu" "B.Mask" "B.Paste")
			(net "SATA6G_PCH_PCIE_UP_SATA_RXP<6>")
		)
		(pad "2" smd rect
			(at 0 0.889 270)
			(size 0.508 0.508)
			(layers "B.Cu" "B.Mask" "B.Paste")
			(net "SATA6G_P6_RX_C_DP")
		)
		(zone
			(layer "B.Cu")
			(hatch none 0.5)
			(connect_pads
				(clearance 0)
			)
			(min_thickness 0.25)
			(keepout
				(tracks allowed)
				(vias not_allowed)
				(pads allowed)
				(copperpour not_allowed)
				(footprints allowed)
			)
			(placement
				(enabled no)
				(sheetname "")
			)
			(fill
				(thermal_gap 0.5)
				(thermal_bridge_width 0.5)
				(island_removal_mode 0)
			)
			(polygon
				(pts
					(xy 408.559 -150.876) (xy 408.559 -150.368) (xy 408.94 -150.368) (xy 408.94 -150.876)
				)
			)
		)
		(zone
			(layer "B.Cu")
			(hatch none 0.5)
			(connect_pads
				(clearance 0)
			)
			(min_thickness 0.25)
			(keepout
				(tracks not_allowed)
				(vias allowed)
				(pads allowed)
				(copperpour not_allowed)
				(footprints allowed)
			)
			(placement
				(enabled no)
				(sheetname "")
			)
			(fill
				(thermal_gap 0.5)
				(thermal_bridge_width 0.5)
				(island_removal_mode 0)
			)
			(polygon
				(pts
					(xy 408.94 -150.876) (xy 408.94 -150.368) (xy 408.559 -150.368) (xy 408.559 -150.876)
				)
			)
		)
	)
	(footprint ""
		(layer "B.Cu")
		(at 484.251 -55.6641)
		(property "Reference" "D25W8"
			(at 0 0 0)
			(layer "B.SilkS")
			(hide yes)
			(effects
				(font
					(size 1.27 1.27)
				)
				(justify mirror)
			)
		)
		(property "Value" "*"
			(at 0 -6.8961 0)
			(unlocked yes)
			(layer "B.Fab")
			(hide yes)
			(effects
				(font
					(size 1.27 1.016)
					(thickness 0.1524)
				)
				(justify mirror)
			)
		)
		(property "Device Type" "RB551V30-GP_DISCRET-G-RB551V30A"
			(at 0 -8.8011 0)
			(unlocked yes)
			(layer "B.Fab")
			(hide yes)
			(effects
				(font
					(size 1.27 1.016)
					(thickness 0.1524)
				)
				(justify mirror)
			)
		)
		(duplicate_pad_numbers_are_jumpers no)
		(fp_line
			(start -0.889 -1.9304)
			(end -0.889 2.159)
			(stroke
				(width 0.1524)
				(type default)
			)
			(layer "B.SilkS")
		)
		(fp_line
			(start -0.889 2.159)
			(end 0.889 2.159)
			(stroke
				(width 0.1524)
				(type default)
			)
			(layer "B.SilkS")
		)
		(fp_line
			(start -0.762 2.0574)
			(end 0.762 2.0574)
			(stroke
				(width 0.508)
				(type default)
			)
			(layer "B.SilkS")
		)
		(fp_line
			(start 0.889 -1.9304)
			(end -0.889 -1.9304)
			(stroke
				(width 0.1524)
				(type default)
			)
			(layer "B.SilkS")
		)
		(fp_line
			(start 0.889 2.159)
			(end 0.889 -1.9304)
			(stroke
				(width 0.1524)
				(type default)
			)
			(layer "B.SilkS")
		)
		(fp_rect
			(start 1.016 2.3114)
			(end -1.016 -2.0066)
			(stroke
				(width 0)
				(type default)
			)
			(fill no)
			(layer "B.CrtYd")
		)
		(fp_poly
			(pts
				(xy 1.016 -2.0066) (xy -1.016 -2.0066) (xy -1.016 2.3114) (xy 1.016 2.3114)
			)
			(stroke
				(width 0)
				(type default)
			)
			(fill no)
			(layer "B.Fab")
		)
		(pad "A" smd rect
			(at 0 -1.143 180)
			(size 0.5588 1.016)
			(layers "B.Cu" "B.Mask" "B.Paste")
			(net "P5V")
		)
		(pad "K" smd rect
			(at 0 1.143 180)
			(size 0.5588 1.016)
			(layers "B.Cu" "B.Mask" "B.Paste")
			(net "P5V_VGA_D")
		)
	)
	(footprint ""
		(layer "B.Cu")
		(at 272.861532 -3.3528 90)
		(property "Reference" "C5G58"
			(at -1.14681 0.76708 180)
			(unlocked yes)
			(layer "B.SilkS")
			(effects
				(font
					(size 0.7874 0.5842)
					(thickness 0.1524)
				)
				(justify mirror)
			)
		)
		(property "Value" ""
			(at 0 0 90)
			(layer "B.Fab")
			(effects
				(font
					(size 1.27 1.27)
				)
				(justify mirror)
			)
		)
		(duplicate_pad_numbers_are_jumpers no)
		(fp_rect
			(start -0.4953 -0.2032)
			(end 0.4953 1.6002)
			(stroke
				(width 0)
				(type default)
			)
			(fill no)
			(layer "B.CrtYd")
		)
		(fp_line
			(start 0.4953 -0.2032)
			(end -0.4953 -0.2032)
			(stroke
				(width 0.1)
				(type default)
			)
			(layer "B.Fab")
		)
		(fp_line
			(start -0.4953 -0.2032)
			(end -0.4953 1.6002)
			(stroke
				(width 0.1)
				(type default)
			)
			(layer "B.Fab")
		)
		(fp_line
			(start 0.4953 1.6002)
			(end 0.4953 -0.2032)
			(stroke
				(width 0.1)
				(type default)
			)
			(layer "B.Fab")
		)
		(fp_line
			(start -0.4953 1.6002)
			(end 0.4953 1.6002)
			(stroke
				(width 0.1)
				(type default)
			)
			(layer "B.Fab")
		)
		(pad "1" smd rect
			(at 0 0 270)
			(size 0.762 0.889)
			(layers "B.Cu" "B.Mask" "B.Paste")
			(net "PVDDQ_ABC")
		)
		(pad "2" smd rect
			(at 0 1.397 270)
			(size 0.762 0.889)
			(layers "B.Cu" "B.Mask" "B.Paste")
			(net "GND")
		)
		(zone
			(layer "B.Cu")
			(hatch none 0.5)
			(connect_pads
				(clearance 0)
			)
			(min_thickness 0.25)
			(keepout
				(tracks not_allowed)
				(vias allowed)
				(pads allowed)
				(copperpour not_allowed)
				(footprints allowed)
			)
			(placement
				(enabled no)
				(sheetname "")
			)
			(fill
				(thermal_gap 0.5)
				(thermal_bridge_width 0.5)
				(island_removal_mode 0)
			)
			(polygon
				(pts
					(xy 273.306032 -2.9718) (xy 273.814032 -2.9718) (xy 273.814032 -3.7338) (xy 273.306032 -3.7338)
				)
			)
		)
	)
	(footprint ""
		(layer "B.Cu")
		(at 364.381288 -48.242728 90)
		(property "Reference" "C2T33"
			(at 0 0 90)
			(layer "B.SilkS")
			(hide yes)
			(effects
				(font
					(size 1.27 1.27)
				)
				(justify mirror)
			)
		)
		(property "Value" ""
			(at 0 0 90)
			(layer "B.Fab")
			(effects
				(font
					(size 1.27 1.27)
				)
				(justify mirror)
			)
		)
		(duplicate_pad_numbers_are_jumpers no)
		(fp_poly
			(pts
				(xy -0.3048 -0.1016) (xy -0.3048 0.9906) (xy 0.3048 0.9906) (xy 0.3048 -0.1016)
			)
			(stroke
				(width 0)
				(type default)
			)
			(fill no)
			(layer "B.CrtYd")
		)
		(fp_line
			(start 0.3048 -0.1016)
			(end 0.3048 0.9906)
			(stroke
				(width 0.1)
				(type default)
			)
			(layer "B.Fab")
		)
		(fp_line
			(start -0.3048 -0.1016)
			(end 0.3048 -0.1016)
			(stroke
				(width 0.1)
				(type default)
			)
			(layer "B.Fab")
		)
		(fp_line
			(start 0.3048 0.9906)
			(end -0.3048 0.9906)
			(stroke
				(width 0.1)
				(type default)
			)
			(layer "B.Fab")
		)
		(fp_line
			(start -0.3048 0.9906)
			(end -0.3048 -0.1016)
			(stroke
				(width 0.1)
				(type default)
			)
			(layer "B.Fab")
		)
		(pad "1" smd rect
			(at 0 0 270)
			(size 0.508 0.508)
			(layers "B.Cu" "B.Mask" "B.Paste")
			(net "P3V3")
		)
		(pad "2" smd rect
			(at 0 0.889 270)
			(size 0.508 0.508)
			(layers "B.Cu" "B.Mask" "B.Paste")
			(net "GND")
		)
		(zone
			(layer "B.Cu")
			(hatch none 0.5)
			(connect_pads
				(clearance 0)
			)
			(min_thickness 0.25)
			(keepout
				(tracks allowed)
				(vias not_allowed)
				(pads allowed)
				(copperpour not_allowed)
				(footprints allowed)
			)
			(placement
				(enabled no)
				(sheetname "")
			)
			(fill
				(thermal_gap 0.5)
				(thermal_bridge_width 0.5)
				(island_removal_mode 0)
			)
			(polygon
				(pts
					(xy 364.635288 -48.496728) (xy 364.635288 -47.988728) (xy 365.016288 -47.988728) (xy 365.016288 -48.496728)
				)
			)
		)
		(zone
			(layer "B.Cu")
			(hatch none 0.5)
			(connect_pads
				(clearance 0)
			)
			(min_thickness 0.25)
			(keepout
				(tracks not_allowed)
				(vias allowed)
				(pads allowed)
				(copperpour not_allowed)
				(footprints allowed)
			)
			(placement
				(enabled no)
				(sheetname "")
			)
			(fill
				(thermal_gap 0.5)
				(thermal_bridge_width 0.5)
				(island_removal_mode 0)
			)
			(polygon
				(pts
					(xy 365.016288 -48.496728) (xy 365.016288 -47.988728) (xy 364.635288 -47.988728) (xy 364.635288 -48.496728)
				)
			)
		)
	)
	(footprint ""
		(layer "B.Cu")
		(at 471.17 -113.0554 90)
		(property "Reference" "R1M15"
			(at 0 0 90)
			(layer "B.SilkS")
			(hide yes)
			(effects
				(font
					(size 1.27 1.27)
				)
				(justify mirror)
			)
		)
		(property "Value" ""
			(at 0 0 90)
			(layer "B.Fab")
			(effects
				(font
					(size 1.27 1.27)
				)
				(justify mirror)
			)
		)
		(duplicate_pad_numbers_are_jumpers no)
		(fp_poly
			(pts
				(xy 0.2794 -0.1016) (xy -0.2794 -0.1016) (xy -0.2794 0.9906) (xy 0.2794 0.9906)
			)
			(stroke
				(width 0)
				(type default)
			)
			(fill no)
			(layer "B.CrtYd")
		)
		(fp_line
			(start 0.2794 -0.1016)
			(end 0.2794 0.9906)
			(stroke
				(width 0.1)
				(type default)
			)
			(layer "B.Fab")
		)
		(fp_line
			(start -0.2794 -0.1016)
			(end 0.2794 -0.1016)
			(stroke
				(width 0.1)
				(type default)
			)
			(layer "B.Fab")
		)
		(fp_line
			(start 0.2794 0.9906)
			(end -0.2794 0.9906)
			(stroke
				(width 0.1)
				(type default)
			)
			(layer "B.Fab")
		)
		(fp_line
			(start -0.2794 0.9906)
			(end -0.2794 -0.1016)
			(stroke
				(width 0.1)
				(type default)
			)
			(layer "B.Fab")
		)
		(pad "1" smd rect
			(at 0 0 270)
			(size 0.508 0.508)
			(layers "B.Cu" "B.Mask" "B.Paste")
			(net "RMII_BMC_OCP_CRSDV")
		)
		(pad "2" smd rect
			(at 0 0.889 270)
			(size 0.508 0.508)
			(layers "B.Cu" "B.Mask" "B.Paste")
			(net "RMII_BMC_OCP_CRSDV_R")
		)
		(zone
			(layer "B.Cu")
			(hatch none 0.5)
			(connect_pads
				(clearance 0)
			)
			(min_thickness 0.25)
			(keepout
				(tracks allowed)
				(vias not_allowed)
				(pads allowed)
				(copperpour not_allowed)
				(footprints allowed)
			)
			(placement
				(enabled no)
				(sheetname "")
			)
			(fill
				(thermal_gap 0.5)
				(thermal_bridge_width 0.5)
				(island_removal_mode 0)
			)
			(polygon
				(pts
					(xy 471.424 -113.3094) (xy 471.424 -112.8014) (xy 471.805 -112.8014) (xy 471.805 -113.3094)
				)
			)
		)
		(zone
			(layer "B.Cu")
			(hatch none 0.5)
			(connect_pads
				(clearance 0)
			)
			(min_thickness 0.25)
			(keepout
				(tracks not_allowed)
				(vias allowed)
				(pads allowed)
				(copperpour not_allowed)
				(footprints allowed)
			)
			(placement
				(enabled no)
				(sheetname "")
			)
			(fill
				(thermal_gap 0.5)
				(thermal_bridge_width 0.5)
				(island_removal_mode 0)
			)
			(polygon
				(pts
					(xy 471.805 -113.3094) (xy 471.805 -112.8014) (xy 471.424 -112.8014) (xy 471.424 -113.3094)
				)
			)
		)
	)
	(footprint ""
		(layer "B.Cu")
		(at 197.950328 -84.493862 90)
		(property "Reference" "C6P7"
			(at 0 0 90)
			(layer "B.SilkS")
			(hide yes)
			(effects
				(font
					(size 1.27 1.27)
				)
				(justify mirror)
			)
		)
		(property "Value" ""
			(at 0 0 90)
			(layer "B.Fab")
			(effects
				(font
					(size 1.27 1.27)
				)
				(justify mirror)
			)
		)
		(duplicate_pad_numbers_are_jumpers no)
		(fp_rect
			(start -0.7239 -0.2159)
			(end 0.7239 1.9939)
			(stroke
				(width 0)
				(type default)
			)
			(fill no)
			(layer "B.CrtYd")
		)
		(fp_line
			(start 0.7239 -0.2159)
			(end 0.7239 1.9939)
			(stroke
				(width 0.1)
				(type default)
			)
			(layer "B.Fab")
		)
		(fp_line
			(start -0.7239 -0.2159)
			(end 0.7239 -0.2159)
			(stroke
				(width 0.1)
				(type default)
			)
			(layer "B.Fab")
		)
		(fp_line
			(start 0.7239 1.9939)
			(end -0.7239 1.9939)
			(stroke
				(width 0.1)
				(type default)
			)
			(layer "B.Fab")
		)
		(fp_line
			(start -0.7239 1.9939)
			(end -0.7239 -0.2159)
			(stroke
				(width 0.1)
				(type default)
			)
			(layer "B.Fab")
		)
		(pad "1" smd rect
			(at 0 0 270)
			(size 1.27 1.016)
			(layers "B.Cu" "B.Mask" "B.Paste")
			(net "VR_FET_SW_P12V_STBY_PVCCIN_CPU0")
		)
		(pad "2" smd rect
			(at 0 1.778 270)
			(size 1.27 1.016)
			(layers "B.Cu" "B.Mask" "B.Paste")
			(net "GND")
		)
		(zone
			(layer "B.Cu")
			(hatch none 0.5)
			(connect_pads
				(clearance 0)
			)
			(min_thickness 0.25)
			(keepout
				(tracks not_allowed)
				(vias allowed)
				(pads allowed)
				(copperpour not_allowed)
				(footprints allowed)
			)
			(placement
				(enabled no)
				(sheetname "")
			)
			(fill
				(thermal_gap 0.5)
				(thermal_bridge_width 0.5)
				(island_removal_mode 0)
			)
			(polygon
				(pts
					(xy 198.458328 -83.858862) (xy 199.220328 -83.858862) (xy 199.220328 -85.128862) (xy 198.458328 -85.128862)
				)
			)
		)
	)
	(footprint ""
		(layer "B.Cu")
		(at 338.0232 -56.8833)
		(property "Reference" "R4R3"
			(at 0 0 0)
			(layer "B.SilkS")
			(hide yes)
			(effects
				(font
					(size 1.27 1.27)
				)
				(justify mirror)
			)
		)
		(property "Value" ""
			(at 0 0 0)
			(layer "B.Fab")
			(effects
				(font
					(size 1.27 1.27)
				)
				(justify mirror)
			)
		)
		(duplicate_pad_numbers_are_jumpers no)
		(fp_poly
			(pts
				(xy 0.2794 -0.1016) (xy -0.2794 -0.1016) (xy -0.2794 0.9906) (xy 0.2794 0.9906)
			)
			(stroke
				(width 0)
				(type default)
			)
			(fill no)
			(layer "B.CrtYd")
		)
		(fp_line
			(start -0.2794 -0.1016)
			(end 0.2794 -0.1016)
			(stroke
				(width 0.1)
				(type default)
			)
			(layer "B.Fab")
		)
		(fp_line
			(start -0.2794 0.9906)
			(end -0.2794 -0.1016)
			(stroke
				(width 0.1)
				(type default)
			)
			(layer "B.Fab")
		)
		(fp_line
			(start 0.2794 -0.1016)
			(end 0.2794 0.9906)
			(stroke
				(width 0.1)
				(type default)
			)
			(layer "B.Fab")
		)
		(fp_line
			(start 0.2794 0.9906)
			(end -0.2794 0.9906)
			(stroke
				(width 0.1)
				(type default)
			)
			(layer "B.Fab")
		)
		(pad "1" smd rect
			(at 0 0 180)
			(size 0.508 0.508)
			(layers "B.Cu" "B.Mask" "B.Paste")
			(net "PVCCIO_CPU0")
		)
		(pad "2" smd rect
			(at 0 0.889 180)
			(size 0.508 0.508)
			(layers "B.Cu" "B.Mask" "B.Paste")
			(net "H_CPU0_PROCHOT_G_N")
		)
		(zone
			(layer "B.Cu")
			(hatch none 0.5)
			(connect_pads
				(clearance 0)
			)
			(min_thickness 0.25)
			(keepout
				(tracks allowed)
				(vias not_allowed)
				(pads allowed)
				(copperpour not_allowed)
				(footprints allowed)
			)
			(placement
				(enabled no)
				(sheetname "")
			)
			(fill
				(thermal_gap 0.5)
				(thermal_bridge_width 0.5)
				(island_removal_mode 0)
			)
			(polygon
				(pts
					(xy 338.2772 -56.6293) (xy 337.7692 -56.6293) (xy 337.7692 -56.2483) (xy 338.2772 -56.2483)
				)
			)
		)
		(zone
			(layer "B.Cu")
			(hatch none 0.5)
			(connect_pads
				(clearance 0)
			)
			(min_thickness 0.25)
			(keepout
				(tracks not_allowed)
				(vias allowed)
				(pads allowed)
				(copperpour not_allowed)
				(footprints allowed)
			)
			(placement
				(enabled no)
				(sheetname "")
			)
			(fill
				(thermal_gap 0.5)
				(thermal_bridge_width 0.5)
				(island_removal_mode 0)
			)
			(polygon
				(pts
					(xy 338.2772 -56.2483) (xy 337.7692 -56.2483) (xy 337.7692 -56.6293) (xy 338.2772 -56.6293)
				)
			)
		)
	)
	(footprint ""
		(layer "B.Cu")
		(at 468.181944 -9.64692 180)
		(property "Reference" "R2U36"
			(at 0.8382 -0.67818 180)
			(unlocked yes)
			(layer "B.SilkS")
			(effects
				(font
					(size 0.4064 0.254)
					(thickness 0.1524)
				)
				(justify left mirror)
			)
		)
		(property "Value" ""
			(at 0 0 0)
			(layer "B.Fab")
			(effects
				(font
					(size 1.27 1.27)
				)
				(justify mirror)
			)
		)
		(duplicate_pad_numbers_are_jumpers no)
		(fp_poly
			(pts
				(xy 0.2794 -0.1016) (xy -0.2794 -0.1016) (xy -0.2794 0.9906) (xy 0.2794 0.9906)
			)
			(stroke
				(width 0)
				(type default)
			)
			(fill no)
			(layer "B.CrtYd")
		)
		(fp_line
			(start 0.2794 0.9906)
			(end -0.2794 0.9906)
			(stroke
				(width 0.1)
				(type default)
			)
			(layer "B.Fab")
		)
		(fp_line
			(start 0.2794 -0.1016)
			(end 0.2794 0.9906)
			(stroke
				(width 0.1)
				(type default)
			)
			(layer "B.Fab")
		)
		(fp_line
			(start -0.2794 0.9906)
			(end -0.2794 -0.1016)
			(stroke
				(width 0.1)
				(type default)
			)
			(layer "B.Fab")
		)
		(fp_line
			(start -0.2794 -0.1016)
			(end 0.2794 -0.1016)
			(stroke
				(width 0.1)
				(type default)
			)
			(layer "B.Fab")
		)
		(pad "1" smd rect
			(at 0 0)
			(size 0.508 0.508)
			(layers "B.Cu" "B.Mask" "B.Paste")
			(net "SMB_SLOTX24_PCH_STBY_LVC3_SCL")
		)
		(pad "2" smd rect
			(at 0 0.889)
			(size 0.508 0.508)
			(layers "B.Cu" "B.Mask" "B.Paste")
			(net "SMB_SLOTX24_STBY_LVC3_SCL_R2")
		)
		(zone
			(layer "B.Cu")
			(hatch none 0.5)
			(connect_pads
				(clearance 0)
			)
			(min_thickness 0.25)
			(keepout
				(tracks not_allowed)
				(vias allowed)
				(pads allowed)
				(copperpour not_allowed)
				(footprints allowed)
			)
			(placement
				(enabled no)
				(sheetname "")
			)
			(fill
				(thermal_gap 0.5)
				(thermal_bridge_width 0.5)
				(island_removal_mode 0)
			)
			(polygon
				(pts
					(xy 467.927944 -10.28192) (xy 468.435944 -10.28192) (xy 468.435944 -9.90092) (xy 467.927944 -9.90092)
				)
			)
		)
		(zone
			(layer "B.Cu")
			(hatch none 0.5)
			(connect_pads
				(clearance 0)
			)
			(min_thickness 0.25)
			(keepout
				(tracks allowed)
				(vias not_allowed)
				(pads allowed)
				(copperpour not_allowed)
				(footprints allowed)
			)
			(placement
				(enabled no)
				(sheetname "")
			)
			(fill
				(thermal_gap 0.5)
				(thermal_bridge_width 0.5)
				(island_removal_mode 0)
			)
			(polygon
				(pts
					(xy 467.927944 -9.90092) (xy 468.435944 -9.90092) (xy 468.435944 -10.28192) (xy 467.927944 -10.28192)
				)
			)
		)
	)
	(footprint ""
		(layer "B.Cu")
		(at 348.713806 -61.257434)
		(property "Reference" "C2U14"
			(at 0 0 0)
			(layer "B.SilkS")
			(hide yes)
			(effects
				(font
					(size 1.27 1.27)
				)
				(justify mirror)
			)
		)
		(property "Value" ""
			(at 0 0 0)
			(layer "B.Fab")
			(effects
				(font
					(size 1.27 1.27)
				)
				(justify mirror)
			)
		)
		(duplicate_pad_numbers_are_jumpers no)
		(fp_poly
			(pts
				(xy -0.3048 -0.1016) (xy -0.3048 0.9906) (xy 0.3048 0.9906) (xy 0.3048 -0.1016)
			)
			(stroke
				(width 0)
				(type default)
			)
			(fill no)
			(layer "B.CrtYd")
		)
		(fp_line
			(start -0.3048 -0.1016)
			(end 0.3048 -0.1016)
			(stroke
				(width 0.1)
				(type default)
			)
			(layer "B.Fab")
		)
		(fp_line
			(start -0.3048 0.9906)
			(end -0.3048 -0.1016)
			(stroke
				(width 0.1)
				(type default)
			)
			(layer "B.Fab")
		)
		(fp_line
			(start 0.3048 -0.1016)
			(end 0.3048 0.9906)
			(stroke
				(width 0.1)
				(type default)
			)
			(layer "B.Fab")
		)
		(fp_line
			(start 0.3048 0.9906)
			(end -0.3048 0.9906)
			(stroke
				(width 0.1)
				(type default)
			)
			(layer "B.Fab")
		)
		(pad "1" smd rect
			(at 0 0 180)
			(size 0.508 0.508)
			(layers "B.Cu" "B.Mask" "B.Paste")
			(net "P3E_CPU0_PE1_PCH_RXN<5>")
		)
		(pad "2" smd rect
			(at 0 0.889 180)
			(size 0.508 0.508)
			(layers "B.Cu" "B.Mask" "B.Paste")
			(net "P3E_CPU0_PE1_SS_RXN<5>")
		)
		(zone
			(layer "B.Cu")
			(hatch none 0.5)
			(connect_pads
				(clearance 0)
			)
			(min_thickness 0.25)
			(keepout
				(tracks allowed)
				(vias not_allowed)
				(pads allowed)
				(copperpour not_allowed)
				(footprints allowed)
			)
			(placement
				(enabled no)
				(sheetname "")
			)
			(fill
				(thermal_gap 0.5)
				(thermal_bridge_width 0.5)
				(island_removal_mode 0)
			)
			(polygon
				(pts
					(xy 348.967806 -61.003434) (xy 348.459806 -61.003434) (xy 348.459806 -60.622434) (xy 348.967806 -60.622434)
				)
			)
		)
	)
	(footprint ""
		(layer "B.Cu")
		(at 197.866 -100.584 90)
		(property "Reference" "C6N2"
			(at 0 0 90)
			(layer "B.SilkS")
			(hide yes)
			(effects
				(font
					(size 1.27 1.27)
				)
				(justify mirror)
			)
		)
		(property "Value" ""
			(at 0 0 90)
			(layer "B.Fab")
			(effects
				(font
					(size 1.27 1.27)
				)
				(justify mirror)
			)
		)
		(duplicate_pad_numbers_are_jumpers no)
		(fp_rect
			(start -0.7239 -0.2159)
			(end 0.7239 1.9939)
			(stroke
				(width 0)
				(type default)
			)
			(fill no)
			(layer "B.CrtYd")
		)
		(fp_line
			(start 0.7239 -0.2159)
			(end 0.7239 1.9939)
			(stroke
				(width 0.1)
				(type default)
			)
			(layer "B.Fab")
		)
		(fp_line
			(start -0.7239 -0.2159)
			(end 0.7239 -0.2159)
			(stroke
				(width 0.1)
				(type default)
			)
			(layer "B.Fab")
		)
		(fp_line
			(start 0.7239 1.9939)
			(end -0.7239 1.9939)
			(stroke
				(width 0.1)
				(type default)
			)
			(layer "B.Fab")
		)
		(fp_line
			(start -0.7239 1.9939)
			(end -0.7239 -0.2159)
			(stroke
				(width 0.1)
				(type default)
			)
			(layer "B.Fab")
		)
		(pad "1" smd rect
			(at 0 0 270)
			(size 1.27 1.016)
			(layers "B.Cu" "B.Mask" "B.Paste")
			(net "VR_FET_SW_P12V_STBY_PVCCIN_CPU0")
		)
		(pad "2" smd rect
			(at 0 1.778 270)
			(size 1.27 1.016)
			(layers "B.Cu" "B.Mask" "B.Paste")
			(net "GND")
		)
		(zone
			(layer "B.Cu")
			(hatch none 0.5)
			(connect_pads
				(clearance 0)
			)
			(min_thickness 0.25)
			(keepout
				(tracks not_allowed)
				(vias allowed)
				(pads allowed)
				(copperpour not_allowed)
				(footprints allowed)
			)
			(placement
				(enabled no)
				(sheetname "")
			)
			(fill
				(thermal_gap 0.5)
				(thermal_bridge_width 0.5)
				(island_removal_mode 0)
			)
			(polygon
				(pts
					(xy 198.374 -99.949) (xy 199.136 -99.949) (xy 199.136 -101.219) (xy 198.374 -101.219)
				)
			)
		)
	)
	(footprint ""
		(layer "B.Cu")
		(at 111.000032 -140.208 90)
		(property "Reference" "C5G109"
			(at -1.14681 0.76708 180)
			(unlocked yes)
			(layer "B.SilkS")
			(effects
				(font
					(size 0.7874 0.5842)
					(thickness 0.1524)
				)
				(justify mirror)
			)
		)
		(property "Value" ""
			(at 0 0 90)
			(layer "B.Fab")
			(effects
				(font
					(size 1.27 1.27)
				)
				(justify mirror)
			)
		)
		(duplicate_pad_numbers_are_jumpers no)
		(fp_rect
			(start -0.4953 -0.2032)
			(end 0.4953 1.6002)
			(stroke
				(width 0)
				(type default)
			)
			(fill no)
			(layer "B.CrtYd")
		)
		(fp_line
			(start 0.4953 -0.2032)
			(end -0.4953 -0.2032)
			(stroke
				(width 0.1)
				(type default)
			)
			(layer "B.Fab")
		)
		(fp_line
			(start -0.4953 -0.2032)
			(end -0.4953 1.6002)
			(stroke
				(width 0.1)
				(type default)
			)
			(layer "B.Fab")
		)
		(fp_line
			(start 0.4953 1.6002)
			(end 0.4953 -0.2032)
			(stroke
				(width 0.1)
				(type default)
			)
			(layer "B.Fab")
		)
		(fp_line
			(start -0.4953 1.6002)
			(end 0.4953 1.6002)
			(stroke
				(width 0.1)
				(type default)
			)
			(layer "B.Fab")
		)
		(pad "1" smd rect
			(at 0 0 270)
			(size 0.762 0.889)
			(layers "B.Cu" "B.Mask" "B.Paste")
			(net "PVDDQ_KLM")
		)
		(pad "2" smd rect
			(at 0 1.397 270)
			(size 0.762 0.889)
			(layers "B.Cu" "B.Mask" "B.Paste")
			(net "GND")
		)
		(zone
			(layer "B.Cu")
			(hatch none 0.5)
			(connect_pads
				(clearance 0)
			)
			(min_thickness 0.25)
			(keepout
				(tracks not_allowed)
				(vias allowed)
				(pads allowed)
				(copperpour not_allowed)
				(footprints allowed)
			)
			(placement
				(enabled no)
				(sheetname "")
			)
			(fill
				(thermal_gap 0.5)
				(thermal_bridge_width 0.5)
				(island_removal_mode 0)
			)
			(polygon
				(pts
					(xy 111.444532 -139.827) (xy 111.952532 -139.827) (xy 111.952532 -140.589) (xy 111.444532 -140.589)
				)
			)
		)
	)
	(footprint ""
		(layer "B.Cu")
		(at 420.077646 -45.539152)
		(property "Reference" "R25W97"
			(at 0.8382 -0.67818 0)
			(unlocked yes)
			(layer "B.SilkS")
			(effects
				(font
					(size 0.4064 0.254)
					(thickness 0.1524)
				)
				(justify left mirror)
			)
		)
		(property "Value" ""
			(at 0 0 0)
			(layer "B.Fab")
			(effects
				(font
					(size 1.27 1.27)
				)
				(justify mirror)
			)
		)
		(duplicate_pad_numbers_are_jumpers no)
		(fp_poly
			(pts
				(xy 0.2794 -0.1016) (xy -0.2794 -0.1016) (xy -0.2794 0.9906) (xy 0.2794 0.9906)
			)
			(stroke
				(width 0)
				(type default)
			)
			(fill no)
			(layer "B.CrtYd")
		)
		(fp_line
			(start -0.2794 -0.1016)
			(end 0.2794 -0.1016)
			(stroke
				(width 0.1)
				(type default)
			)
			(layer "B.Fab")
		)
		(fp_line
			(start -0.2794 0.9906)
			(end -0.2794 -0.1016)
			(stroke
				(width 0.1)
				(type default)
			)
			(layer "B.Fab")
		)
		(fp_line
			(start 0.2794 -0.1016)
			(end 0.2794 0.9906)
			(stroke
				(width 0.1)
				(type default)
			)
			(layer "B.Fab")
		)
		(fp_line
			(start 0.2794 0.9906)
			(end -0.2794 0.9906)
			(stroke
				(width 0.1)
				(type default)
			)
			(layer "B.Fab")
		)
		(pad "1" smd rect
			(at 0 0 180)
			(size 0.508 0.508)
			(layers "B.Cu" "B.Mask" "B.Paste")
			(net "P3V3_STBY")
		)
		(pad "2" smd rect
			(at 0 0.889 180)
			(size 0.508 0.508)
			(layers "B.Cu" "B.Mask" "B.Paste")
			(net "SPI_BMC_BT_DI")
		)
		(zone
			(layer "B.Cu")
			(hatch none 0.5)
			(connect_pads
				(clearance 0)
			)
			(min_thickness 0.25)
			(keepout
				(tracks allowed)
				(vias not_allowed)
				(pads allowed)
				(copperpour not_allowed)
				(footprints allowed)
			)
			(placement
				(enabled no)
				(sheetname "")
			)
			(fill
				(thermal_gap 0.5)
				(thermal_bridge_width 0.5)
				(island_removal_mode 0)
			)
			(polygon
				(pts
					(xy 420.331646 -45.285152) (xy 419.823646 -45.285152) (xy 419.823646 -44.904152) (xy 420.331646 -44.904152)
				)
			)
		)
		(zone
			(layer "B.Cu")
			(hatch none 0.5)
			(connect_pads
				(clearance 0)
			)
			(min_thickness 0.25)
			(keepout
				(tracks not_allowed)
				(vias allowed)
				(pads allowed)
				(copperpour not_allowed)
				(footprints allowed)
			)
			(placement
				(enabled no)
				(sheetname "")
			)
			(fill
				(thermal_gap 0.5)
				(thermal_bridge_width 0.5)
				(island_removal_mode 0)
			)
			(polygon
				(pts
					(xy 420.331646 -44.904152) (xy 419.823646 -44.904152) (xy 419.823646 -45.285152) (xy 420.331646 -45.285152)
				)
			)
		)
	)
	(footprint ""
		(layer "B.Cu")
		(at 415.708846 -44.650152 180)
		(property "Reference" "R9F22"
			(at 0 0 0)
			(layer "B.SilkS")
			(hide yes)
			(effects
				(font
					(size 1.27 1.27)
				)
				(justify mirror)
			)
		)
		(property "Value" ""
			(at 0 0 0)
			(layer "B.Fab")
			(effects
				(font
					(size 1.27 1.27)
				)
				(justify mirror)
			)
		)
		(duplicate_pad_numbers_are_jumpers no)
		(fp_poly
			(pts
				(xy 0.2794 -0.1016) (xy -0.2794 -0.1016) (xy -0.2794 0.9906) (xy 0.2794 0.9906)
			)
			(stroke
				(width 0)
				(type default)
			)
			(fill no)
			(layer "B.CrtYd")
		)
		(fp_line
			(start 0.2794 0.9906)
			(end -0.2794 0.9906)
			(stroke
				(width 0.1)
				(type default)
			)
			(layer "B.Fab")
		)
		(fp_line
			(start 0.2794 -0.1016)
			(end 0.2794 0.9906)
			(stroke
				(width 0.1)
				(type default)
			)
			(layer "B.Fab")
		)
		(fp_line
			(start -0.2794 0.9906)
			(end -0.2794 -0.1016)
			(stroke
				(width 0.1)
				(type default)
			)
			(layer "B.Fab")
		)
		(fp_line
			(start -0.2794 -0.1016)
			(end 0.2794 -0.1016)
			(stroke
				(width 0.1)
				(type default)
			)
			(layer "B.Fab")
		)
		(pad "1" smd rect
			(at 0 0)
			(size 0.508 0.508)
			(layers "B.Cu" "B.Mask" "B.Paste")
			(net "SMB_LAN_STBY_LVC3_SCL_R")
		)
		(pad "2" smd rect
			(at 0 0.889)
			(size 0.508 0.508)
			(layers "B.Cu" "B.Mask" "B.Paste")
			(net "SMB_LAN_STBY_LVC3_SCL")
		)
		(zone
			(layer "B.Cu")
			(hatch none 0.5)
			(connect_pads
				(clearance 0)
			)
			(min_thickness 0.25)
			(keepout
				(tracks not_allowed)
				(vias allowed)
				(pads allowed)
				(copperpour not_allowed)
				(footprints allowed)
			)
			(placement
				(enabled no)
				(sheetname "")
			)
			(fill
				(thermal_gap 0.5)
				(thermal_bridge_width 0.5)
				(island_removal_mode 0)
			)
			(polygon
				(pts
					(xy 415.454846 -45.285152) (xy 415.962846 -45.285152) (xy 415.962846 -44.904152) (xy 415.454846 -44.904152)
				)
			)
		)
		(zone
			(layer "B.Cu")
			(hatch none 0.5)
			(connect_pads
				(clearance 0)
			)
			(min_thickness 0.25)
			(keepout
				(tracks allowed)
				(vias not_allowed)
				(pads allowed)
				(copperpour not_allowed)
				(footprints allowed)
			)
			(placement
				(enabled no)
				(sheetname "")
			)
			(fill
				(thermal_gap 0.5)
				(thermal_bridge_width 0.5)
				(island_removal_mode 0)
			)
			(polygon
				(pts
					(xy 415.454846 -44.904152) (xy 415.962846 -44.904152) (xy 415.962846 -45.285152) (xy 415.454846 -45.285152)
				)
			)
		)
	)
	(footprint ""
		(layer "B.Cu")
		(at 402.805646 -27.124152)
		(property "Reference" "R1U33"
			(at 0 0 0)
			(layer "B.SilkS")
			(hide yes)
			(effects
				(font
					(size 1.27 1.27)
				)
				(justify mirror)
			)
		)
		(property "Value" "*"
			(at -0.064008 -4.108196 0)
			(unlocked yes)
			(layer "B.Fab")
			(hide yes)
			(effects
				(font
					(size 1.27 1.016)
					(thickness 0.1524)
				)
				(justify mirror)
			)
		)
		(property "Device Type" "649R2F-GP_RCL_GP-649R2F-GP,64.A"
			(at -0.064008 -5.632196 0)
			(unlocked yes)
			(layer "B.Fab")
			(hide yes)
			(effects
				(font
					(size 1.27 1.016)
					(thickness 0.1524)
				)
				(justify mirror)
			)
		)
		(duplicate_pad_numbers_are_jumpers no)
		(fp_line
			(start -0.508 -0.9398)
			(end 0.508 -0.9398)
			(stroke
				(width 0.1524)
				(type default)
			)
			(layer "B.SilkS")
		)
		(fp_line
			(start 0.508 -0.9398)
			(end 0.508 0.9398)
			(stroke
				(width 0.1524)
				(type default)
			)
			(layer "B.SilkS")
		)
		(fp_rect
			(start 0.508 0.9398)
			(end -0.508 -0.9398)
			(stroke
				(width 0)
				(type default)
			)
			(fill no)
			(layer "B.CrtYd")
		)
		(fp_rect
			(start 0.508 0.9398)
			(end -0.508 -0.9398)
			(stroke
				(width 0)
				(type default)
			)
			(fill no)
			(layer "B.Fab")
		)
		(pad "1" smd custom
			(at 0 -0.4445 180)
			(size 0.1397 0.1397)
			(layers "B.Cu" "B.Mask" "B.Paste")
			(net "A_P12V_STBY_SCALED")
			(options
				(clearance outline)
				(anchor circle)
			)
			(primitives
				(gr_poly
					(pts
						(arc
							(start -0.1778 0.2794)
							(mid -0.249642 0.249642)
							(end -0.2794 0.1778)
						)
						(arc
							(start -0.2794 -0.1778)
							(mid -0.249642 -0.249642)
							(end -0.1778 -0.2794)
						)
						(arc
							(start 0.1778 -0.2794)
							(mid 0.249642 -0.249642)
							(end 0.2794 -0.1778)
						)
						(arc
							(start 0.2794 0.1778)
							(mid 0.249642 0.249642)
							(end 0.1778 0.2794)
						)
					)
					(width 0)
					(fill yes)
				)
			)
		)
		(pad "2" smd custom
			(at 0 0.4445 180)
			(size 0.1397 0.1397)
			(layers "B.Cu" "B.Mask" "B.Paste")
			(net "GND")
			(options
				(clearance outline)
				(anchor circle)
			)
			(primitives
				(gr_poly
					(pts
						(arc
							(start -0.1778 0.2794)
							(mid -0.249642 0.249642)
							(end -0.2794 0.1778)
						)
						(arc
							(start -0.2794 -0.1778)
							(mid -0.249642 -0.249642)
							(end -0.1778 -0.2794)
						)
						(arc
							(start 0.1778 -0.2794)
							(mid 0.249642 -0.249642)
							(end 0.2794 -0.1778)
						)
						(arc
							(start 0.2794 0.1778)
							(mid 0.249642 0.249642)
							(end 0.1778 0.2794)
						)
					)
					(width 0)
					(fill yes)
				)
			)
		)
	)
	(footprint ""
		(layer "B.Cu")
		(at 494.3729 -124.0663 180)
		(property "Reference" "R1M12"
			(at 0 0 0)
			(layer "B.SilkS")
			(hide yes)
			(effects
				(font
					(size 1.27 1.27)
				)
				(justify mirror)
			)
		)
		(property "Value" ""
			(at 0 0 0)
			(layer "B.Fab")
			(effects
				(font
					(size 1.27 1.27)
				)
				(justify mirror)
			)
		)
		(duplicate_pad_numbers_are_jumpers no)
		(fp_poly
			(pts
				(xy 0.2794 -0.1016) (xy -0.2794 -0.1016) (xy -0.2794 0.9906) (xy 0.2794 0.9906)
			)
			(stroke
				(width 0)
				(type default)
			)
			(fill no)
			(layer "B.CrtYd")
		)
		(fp_line
			(start 0.2794 0.9906)
			(end -0.2794 0.9906)
			(stroke
				(width 0.1)
				(type default)
			)
			(layer "B.Fab")
		)
		(fp_line
			(start 0.2794 -0.1016)
			(end 0.2794 0.9906)
			(stroke
				(width 0.1)
				(type default)
			)
			(layer "B.Fab")
		)
		(fp_line
			(start -0.2794 0.9906)
			(end -0.2794 -0.1016)
			(stroke
				(width 0.1)
				(type default)
			)
			(layer "B.Fab")
		)
		(fp_line
			(start -0.2794 -0.1016)
			(end 0.2794 -0.1016)
			(stroke
				(width 0.1)
				(type default)
			)
			(layer "B.Fab")
		)
		(pad "1" smd rect
			(at 0 0)
			(size 0.508 0.508)
			(layers "B.Cu" "B.Mask" "B.Paste")
			(net "P3V3")
		)
		(pad "2" smd rect
			(at 0 0.889)
			(size 0.508 0.508)
			(layers "B.Cu" "B.Mask" "B.Paste")
			(net "LED_SAS_ACT_R_N")
		)
		(zone
			(layer "B.Cu")
			(hatch none 0.5)
			(connect_pads
				(clearance 0)
			)
			(min_thickness 0.25)
			(keepout
				(tracks not_allowed)
				(vias allowed)
				(pads allowed)
				(copperpour not_allowed)
				(footprints allowed)
			)
			(placement
				(enabled no)
				(sheetname "")
			)
			(fill
				(thermal_gap 0.5)
				(thermal_bridge_width 0.5)
				(island_removal_mode 0)
			)
			(polygon
				(pts
					(xy 494.1189 -124.7013) (xy 494.6269 -124.7013) (xy 494.6269 -124.3203) (xy 494.1189 -124.3203)
				)
			)
		)
		(zone
			(layer "B.Cu")
			(hatch none 0.5)
			(connect_pads
				(clearance 0)
			)
			(min_thickness 0.25)
			(keepout
				(tracks allowed)
				(vias not_allowed)
				(pads allowed)
				(copperpour not_allowed)
				(footprints allowed)
			)
			(placement
				(enabled no)
				(sheetname "")
			)
			(fill
				(thermal_gap 0.5)
				(thermal_bridge_width 0.5)
				(island_removal_mode 0)
			)
			(polygon
				(pts
					(xy 494.1189 -124.3203) (xy 494.6269 -124.3203) (xy 494.6269 -124.7013) (xy 494.1189 -124.7013)
				)
			)
		)
	)
	(footprint ""
		(layer "B.Cu")
		(at 463.677 -4.5085)
		(property "Reference" "C2U23"
			(at 0 0 0)
			(layer "B.SilkS")
			(hide yes)
			(effects
				(font
					(size 1.27 1.27)
				)
				(justify mirror)
			)
		)
		(property "Value" ""
			(at 0 0 0)
			(layer "B.Fab")
			(effects
				(font
					(size 1.27 1.27)
				)
				(justify mirror)
			)
		)
		(duplicate_pad_numbers_are_jumpers no)
		(fp_poly
			(pts
				(xy -0.3048 -0.1016) (xy -0.3048 0.9906) (xy 0.3048 0.9906) (xy 0.3048 -0.1016)
			)
			(stroke
				(width 0)
				(type default)
			)
			(fill no)
			(layer "B.CrtYd")
		)
		(fp_line
			(start -0.3048 -0.1016)
			(end 0.3048 -0.1016)
			(stroke
				(width 0.1)
				(type default)
			)
			(layer "B.Fab")
		)
		(fp_line
			(start -0.3048 0.9906)
			(end -0.3048 -0.1016)
			(stroke
				(width 0.1)
				(type default)
			)
			(layer "B.Fab")
		)
		(fp_line
			(start 0.3048 -0.1016)
			(end 0.3048 0.9906)
			(stroke
				(width 0.1)
				(type default)
			)
			(layer "B.Fab")
		)
		(fp_line
			(start 0.3048 0.9906)
			(end -0.3048 0.9906)
			(stroke
				(width 0.1)
				(type default)
			)
			(layer "B.Fab")
		)
		(pad "1" smd rect
			(at 0 0 180)
			(size 0.508 0.508)
			(layers "B.Cu" "B.Mask" "B.Paste")
			(net "P3V3_STBY")
		)
		(pad "2" smd rect
			(at 0 0.889 180)
			(size 0.508 0.508)
			(layers "B.Cu" "B.Mask" "B.Paste")
			(net "GND")
		)
		(zone
			(layer "B.Cu")
			(hatch none 0.5)
			(connect_pads
				(clearance 0)
			)
			(min_thickness 0.25)
			(keepout
				(tracks allowed)
				(vias not_allowed)
				(pads allowed)
				(copperpour not_allowed)
				(footprints allowed)
			)
			(placement
				(enabled no)
				(sheetname "")
			)
			(fill
				(thermal_gap 0.5)
				(thermal_bridge_width 0.5)
				(island_removal_mode 0)
			)
			(polygon
				(pts
					(xy 463.931 -4.2545) (xy 463.423 -4.2545) (xy 463.423 -3.8735) (xy 463.931 -3.8735)
				)
			)
		)
		(zone
			(layer "B.Cu")
			(hatch none 0.5)
			(connect_pads
				(clearance 0)
			)
			(min_thickness 0.25)
			(keepout
				(tracks not_allowed)
				(vias allowed)
				(pads allowed)
				(copperpour not_allowed)
				(footprints allowed)
			)
			(placement
				(enabled no)
				(sheetname "")
			)
			(fill
				(thermal_gap 0.5)
				(thermal_bridge_width 0.5)
				(island_removal_mode 0)
			)
			(polygon
				(pts
					(xy 463.931 -3.8735) (xy 463.423 -3.8735) (xy 463.423 -4.2545) (xy 463.931 -4.2545)
				)
			)
		)
	)
	(footprint ""
		(layer "B.Cu")
		(at 1.3462 -149.987 90)
		(property "Reference" "C9L5"
			(at 0 0 90)
			(layer "B.SilkS")
			(hide yes)
			(effects
				(font
					(size 1.27 1.27)
				)
				(justify mirror)
			)
		)
		(property "Value" ""
			(at 0 0 90)
			(layer "B.Fab")
			(effects
				(font
					(size 1.27 1.27)
				)
				(justify mirror)
			)
		)
		(duplicate_pad_numbers_are_jumpers no)
		(fp_rect
			(start -0.7239 -0.2159)
			(end 0.7239 1.9939)
			(stroke
				(width 0)
				(type default)
			)
			(fill no)
			(layer "B.CrtYd")
		)
		(fp_line
			(start 0.7239 -0.2159)
			(end 0.7239 1.9939)
			(stroke
				(width 0.1)
				(type default)
			)
			(layer "B.Fab")
		)
		(fp_line
			(start -0.7239 -0.2159)
			(end 0.7239 -0.2159)
			(stroke
				(width 0.1)
				(type default)
			)
			(layer "B.Fab")
		)
		(fp_line
			(start 0.7239 1.9939)
			(end -0.7239 1.9939)
			(stroke
				(width 0.1)
				(type default)
			)
			(layer "B.Fab")
		)
		(fp_line
			(start -0.7239 1.9939)
			(end -0.7239 -0.2159)
			(stroke
				(width 0.1)
				(type default)
			)
			(layer "B.Fab")
		)
		(pad "1" smd rect
			(at 0 0 270)
			(size 1.27 1.016)
			(layers "B.Cu" "B.Mask" "B.Paste")
			(net "VR_FET_SW_P12V_STBY_PVDDQ_KLM")
		)
		(pad "2" smd rect
			(at 0 1.778 270)
			(size 1.27 1.016)
			(layers "B.Cu" "B.Mask" "B.Paste")
			(net "GND")
		)
		(zone
			(layer "B.Cu")
			(hatch none 0.5)
			(connect_pads
				(clearance 0)
			)
			(min_thickness 0.25)
			(keepout
				(tracks not_allowed)
				(vias allowed)
				(pads allowed)
				(copperpour not_allowed)
				(footprints allowed)
			)
			(placement
				(enabled no)
				(sheetname "")
			)
			(fill
				(thermal_gap 0.5)
				(thermal_bridge_width 0.5)
				(island_removal_mode 0)
			)
			(polygon
				(pts
					(xy 1.8542 -149.352) (xy 2.6162 -149.352) (xy 2.6162 -150.622) (xy 1.8542 -150.622)
				)
			)
		)
	)
	(footprint ""
		(layer "B.Cu")
		(at 197.239128 -78.915006 90)
		(property "Reference" "R6P10"
			(at 0 0 90)
			(layer "B.SilkS")
			(hide yes)
			(effects
				(font
					(size 1.27 1.27)
				)
				(justify mirror)
			)
		)
		(property "Value" ""
			(at 0 0 90)
			(layer "B.Fab")
			(effects
				(font
					(size 1.27 1.27)
				)
				(justify mirror)
			)
		)
		(duplicate_pad_numbers_are_jumpers no)
		(fp_rect
			(start 0.2794 -0.1016)
			(end -0.2794 0.9906)
			(stroke
				(width 0)
				(type default)
			)
			(fill no)
			(layer "B.CrtYd")
		)
		(fp_line
			(start 0.2794 -0.1016)
			(end 0.2794 0.9906)
			(stroke
				(width 0.1)
				(type default)
			)
			(layer "B.Fab")
		)
		(fp_line
			(start -0.2794 -0.1016)
			(end 0.2794 -0.1016)
			(stroke
				(width 0.1)
				(type default)
			)
			(layer "B.Fab")
		)
		(fp_line
			(start 0.2794 0.9906)
			(end -0.2794 0.9906)
			(stroke
				(width 0.1)
				(type default)
			)
			(layer "B.Fab")
		)
		(fp_line
			(start -0.2794 0.9906)
			(end -0.2794 -0.1016)
			(stroke
				(width 0.1)
				(type default)
			)
			(layer "B.Fab")
		)
		(pad "1" smd rect
			(at 0 0 270)
			(size 0.508 0.508)
			(layers "B.Cu" "B.Mask" "B.Paste")
			(net "VR_PVCCIN_CPU0_PH4_VCIN")
		)
		(pad "2" smd rect
			(at 0 0.889 270)
			(size 0.508 0.508)
			(layers "B.Cu" "B.Mask" "B.Paste")
			(net "P5V_STBY")
		)
		(zone
			(layer "B.Cu")
			(hatch none 0.5)
			(connect_pads
				(clearance 0)
			)
			(min_thickness 0.25)
			(keepout
				(tracks allowed)
				(vias not_allowed)
				(pads allowed)
				(copperpour not_allowed)
				(footprints allowed)
			)
			(placement
				(enabled no)
				(sheetname "")
			)
			(fill
				(thermal_gap 0.5)
				(thermal_bridge_width 0.5)
				(island_removal_mode 0)
			)
			(polygon
				(pts
					(xy 197.493128 -79.169006) (xy 197.493128 -78.661006) (xy 197.874128 -78.661006) (xy 197.874128 -79.169006)
				)
			)
		)
		(zone
			(layer "B.Cu")
			(hatch none 0.5)
			(connect_pads
				(clearance 0)
			)
			(min_thickness 0.25)
			(keepout
				(tracks not_allowed)
				(vias allowed)
				(pads allowed)
				(copperpour not_allowed)
				(footprints allowed)
			)
			(placement
				(enabled no)
				(sheetname "")
			)
			(fill
				(thermal_gap 0.5)
				(thermal_bridge_width 0.5)
				(island_removal_mode 0)
			)
			(polygon
				(pts
					(xy 197.493128 -79.169006) (xy 197.493128 -78.661006) (xy 197.874128 -78.661006) (xy 197.874128 -79.169006)
				)
			)
		)
	)
	(footprint ""
		(layer "B.Cu")
		(at 176.022 -88.646 180)
		(property "Reference" "R6N9"
			(at 0 0 0)
			(layer "B.SilkS")
			(hide yes)
			(effects
				(font
					(size 1.27 1.27)
				)
				(justify mirror)
			)
		)
		(property "Value" ""
			(at 0 0 0)
			(layer "B.Fab")
			(effects
				(font
					(size 1.27 1.27)
				)
				(justify mirror)
			)
		)
		(duplicate_pad_numbers_are_jumpers no)
		(fp_poly
			(pts
				(xy 0.2794 -0.1016) (xy -0.2794 -0.1016) (xy -0.2794 0.9906) (xy 0.2794 0.9906)
			)
			(stroke
				(width 0)
				(type default)
			)
			(fill no)
			(layer "B.CrtYd")
		)
		(fp_line
			(start 0.2794 0.9906)
			(end -0.2794 0.9906)
			(stroke
				(width 0.1)
				(type default)
			)
			(layer "B.Fab")
		)
		(fp_line
			(start 0.2794 -0.1016)
			(end 0.2794 0.9906)
			(stroke
				(width 0.1)
				(type default)
			)
			(layer "B.Fab")
		)
		(fp_line
			(start -0.2794 0.9906)
			(end -0.2794 -0.1016)
			(stroke
				(width 0.1)
				(type default)
			)
			(layer "B.Fab")
		)
		(fp_line
			(start -0.2794 -0.1016)
			(end 0.2794 -0.1016)
			(stroke
				(width 0.1)
				(type default)
			)
			(layer "B.Fab")
		)
		(pad "1" smd rect
			(at 0 0)
			(size 0.508 0.508)
			(layers "B.Cu" "B.Mask" "B.Paste")
			(net "SMB_CPU1_PE_HP_GTL_SDA")
		)
		(pad "2" smd rect
			(at 0 0.889)
			(size 0.508 0.508)
			(layers "B.Cu" "B.Mask" "B.Paste")
			(net "SMB_CPU1_PE_HP_GTL_R_SDA")
		)
		(zone
			(layer "B.Cu")
			(hatch none 0.5)
			(connect_pads
				(clearance 0)
			)
			(min_thickness 0.25)
			(keepout
				(tracks not_allowed)
				(vias allowed)
				(pads allowed)
				(copperpour not_allowed)
				(footprints allowed)
			)
			(placement
				(enabled no)
				(sheetname "")
			)
			(fill
				(thermal_gap 0.5)
				(thermal_bridge_width 0.5)
				(island_removal_mode 0)
			)
			(polygon
				(pts
					(xy 175.768 -89.281) (xy 176.276 -89.281) (xy 176.276 -88.9) (xy 175.768 -88.9)
				)
			)
		)
		(zone
			(layer "B.Cu")
			(hatch none 0.5)
			(connect_pads
				(clearance 0)
			)
			(min_thickness 0.25)
			(keepout
				(tracks allowed)
				(vias not_allowed)
				(pads allowed)
				(copperpour not_allowed)
				(footprints allowed)
			)
			(placement
				(enabled no)
				(sheetname "")
			)
			(fill
				(thermal_gap 0.5)
				(thermal_bridge_width 0.5)
				(island_removal_mode 0)
			)
			(polygon
				(pts
					(xy 175.768 -88.9) (xy 176.276 -88.9) (xy 176.276 -89.281) (xy 175.768 -89.281)
				)
			)
		)
	)
	(footprint ""
		(layer "B.Cu")
		(at 400.177 -108.077 180)
		(property "Reference" "C2N10"
			(at 0 0 0)
			(layer "B.SilkS")
			(hide yes)
			(effects
				(font
					(size 1.27 1.27)
				)
				(justify mirror)
			)
		)
		(property "Value" ""
			(at 0 0 0)
			(layer "B.Fab")
			(effects
				(font
					(size 1.27 1.27)
				)
				(justify mirror)
			)
		)
		(duplicate_pad_numbers_are_jumpers no)
		(fp_poly
			(pts
				(xy 0.4953 -0.2032) (xy -0.4953 -0.2032) (xy -0.4953 1.6002) (xy 0.4953 1.6002)
			)
			(stroke
				(width 0)
				(type default)
			)
			(fill no)
			(layer "B.CrtYd")
		)
		(fp_line
			(start 0.4953 1.6002)
			(end 0.4953 -0.2032)
			(stroke
				(width 0.1)
				(type default)
			)
			(layer "B.Fab")
		)
		(fp_line
			(start 0.4953 -0.2032)
			(end -0.4953 -0.2032)
			(stroke
				(width 0.1)
				(type default)
			)
			(layer "B.Fab")
		)
		(fp_line
			(start -0.4953 1.6002)
			(end 0.4953 1.6002)
			(stroke
				(width 0.1)
				(type default)
			)
			(layer "B.Fab")
		)
		(fp_line
			(start -0.4953 -0.2032)
			(end -0.4953 1.6002)
			(stroke
				(width 0.1)
				(type default)
			)
			(layer "B.Fab")
		)
		(pad "1" smd rect
			(at 0 0)
			(size 0.762 0.889)
			(layers "B.Cu" "B.Mask" "B.Paste")
			(net "P1V05_PCH_STBY")
		)
		(pad "2" smd rect
			(at 0 1.397)
			(size 0.762 0.889)
			(layers "B.Cu" "B.Mask" "B.Paste")
			(net "GND")
		)
		(zone
			(layer "B.Cu")
			(hatch none 0.5)
			(connect_pads
				(clearance 0)
			)
			(min_thickness 0.25)
			(keepout
				(tracks not_allowed)
				(vias allowed)
				(pads allowed)
				(copperpour not_allowed)
				(footprints allowed)
			)
			(placement
				(enabled no)
				(sheetname "")
			)
			(fill
				(thermal_gap 0.5)
				(thermal_bridge_width 0.5)
				(island_removal_mode 0)
			)
			(polygon
				(pts
					(xy 399.796 -108.5215) (xy 400.558 -108.5215) (xy 400.558 -109.0295) (xy 399.796 -109.0295)
				)
			)
		)
	)
	(footprint ""
		(layer "B.Cu")
		(at 83.856068 -12.954 -90)
		(property "Reference" "C5G80"
			(at -1.14681 0.76708 0)
			(unlocked yes)
			(layer "B.SilkS")
			(effects
				(font
					(size 0.7874 0.5842)
					(thickness 0.1524)
				)
				(justify mirror)
			)
		)
		(property "Value" ""
			(at 0 0 90)
			(layer "B.Fab")
			(effects
				(font
					(size 1.27 1.27)
				)
				(justify mirror)
			)
		)
		(duplicate_pad_numbers_are_jumpers no)
		(fp_rect
			(start 0.4953 1.6002)
			(end -0.4953 -0.2032)
			(stroke
				(width 0)
				(type default)
			)
			(fill no)
			(layer "B.CrtYd")
		)
		(fp_line
			(start -0.4953 1.6002)
			(end 0.4953 1.6002)
			(stroke
				(width 0.1)
				(type default)
			)
			(layer "B.Fab")
		)
		(fp_line
			(start 0.4953 1.6002)
			(end 0.4953 -0.2032)
			(stroke
				(width 0.1)
				(type default)
			)
			(layer "B.Fab")
		)
		(fp_line
			(start -0.4953 -0.2032)
			(end -0.4953 1.6002)
			(stroke
				(width 0.1)
				(type default)
			)
			(layer "B.Fab")
		)
		(fp_line
			(start 0.4953 -0.2032)
			(end -0.4953 -0.2032)
			(stroke
				(width 0.1)
				(type default)
			)
			(layer "B.Fab")
		)
		(pad "1" smd rect
			(at 0 0 90)
			(size 0.762 0.889)
			(layers "B.Cu" "B.Mask" "B.Paste")
			(net "PVDDQ_GHJ")
		)
		(pad "2" smd rect
			(at 0 1.397 90)
			(size 0.762 0.889)
			(layers "B.Cu" "B.Mask" "B.Paste")
			(net "GND")
		)
		(zone
			(layer "B.Cu")
			(hatch none 0.5)
			(connect_pads
				(clearance 0)
			)
			(min_thickness 0.25)
			(keepout
				(tracks not_allowed)
				(vias allowed)
				(pads allowed)
				(copperpour not_allowed)
				(footprints allowed)
			)
			(placement
				(enabled no)
				(sheetname "")
			)
			(fill
				(thermal_gap 0.5)
				(thermal_bridge_width 0.5)
				(island_removal_mode 0)
			)
			(polygon
				(pts
					(xy 82.903568 -12.573) (xy 83.411568 -12.573) (xy 83.411568 -13.335) (xy 82.903568 -13.335)
				)
			)
		)
	)
	(footprint ""
		(layer "B.Cu")
		(at 489.65739 -145.288 90)
		(property "Reference" "R1L20"
			(at 0 0 90)
			(layer "B.SilkS")
			(hide yes)
			(effects
				(font
					(size 1.27 1.27)
				)
				(justify mirror)
			)
		)
		(property "Value" ""
			(at 0 0 90)
			(layer "B.Fab")
			(effects
				(font
					(size 1.27 1.27)
				)
				(justify mirror)
			)
		)
		(duplicate_pad_numbers_are_jumpers no)
		(fp_poly
			(pts
				(xy 0.2794 -0.1016) (xy -0.2794 -0.1016) (xy -0.2794 0.9906) (xy 0.2794 0.9906)
			)
			(stroke
				(width 0)
				(type default)
			)
			(fill no)
			(layer "B.CrtYd")
		)
		(fp_line
			(start 0.2794 -0.1016)
			(end 0.2794 0.9906)
			(stroke
				(width 0.1)
				(type default)
			)
			(layer "B.Fab")
		)
		(fp_line
			(start -0.2794 -0.1016)
			(end 0.2794 -0.1016)
			(stroke
				(width 0.1)
				(type default)
			)
			(layer "B.Fab")
		)
		(fp_line
			(start 0.2794 0.9906)
			(end -0.2794 0.9906)
			(stroke
				(width 0.1)
				(type default)
			)
			(layer "B.Fab")
		)
		(fp_line
			(start -0.2794 0.9906)
			(end -0.2794 -0.1016)
			(stroke
				(width 0.1)
				(type default)
			)
			(layer "B.Fab")
		)
		(pad "1" smd rect
			(at 0 0 270)
			(size 0.508 0.508)
			(layers "B.Cu" "B.Mask" "B.Paste")
			(net "LED_POSTCODE_4")
		)
		(pad "2" smd rect
			(at 0 0.889 270)
			(size 0.508 0.508)
			(layers "B.Cu" "B.Mask" "B.Paste")
			(net "LED_POSTCODE_4_R")
		)
		(zone
			(layer "B.Cu")
			(hatch none 0.5)
			(connect_pads
				(clearance 0)
			)
			(min_thickness 0.25)
			(keepout
				(tracks allowed)
				(vias not_allowed)
				(pads allowed)
				(copperpour not_allowed)
				(footprints allowed)
			)
			(placement
				(enabled no)
				(sheetname "")
			)
			(fill
				(thermal_gap 0.5)
				(thermal_bridge_width 0.5)
				(island_removal_mode 0)
			)
			(polygon
				(pts
					(xy 489.91139 -145.542) (xy 489.91139 -145.034) (xy 490.29239 -145.034) (xy 490.29239 -145.542)
				)
			)
		)
		(zone
			(layer "B.Cu")
			(hatch none 0.5)
			(connect_pads
				(clearance 0)
			)
			(min_thickness 0.25)
			(keepout
				(tracks not_allowed)
				(vias allowed)
				(pads allowed)
				(copperpour not_allowed)
				(footprints allowed)
			)
			(placement
				(enabled no)
				(sheetname "")
			)
			(fill
				(thermal_gap 0.5)
				(thermal_bridge_width 0.5)
				(island_removal_mode 0)
			)
			(polygon
				(pts
					(xy 490.29239 -145.542) (xy 490.29239 -145.034) (xy 489.91139 -145.034) (xy 489.91139 -145.542)
				)
			)
		)
	)
	(footprint ""
		(layer "B.Cu")
		(at 259.5372 -135.376412 90)
		(property "Reference" "C5M8"
			(at 0 0 90)
			(layer "B.SilkS")
			(hide yes)
			(effects
				(font
					(size 1.27 1.27)
				)
				(justify mirror)
			)
		)
		(property "Value" ""
			(at 0 0 90)
			(layer "B.Fab")
			(effects
				(font
					(size 1.27 1.27)
				)
				(justify mirror)
			)
		)
		(duplicate_pad_numbers_are_jumpers no)
		(fp_rect
			(start -0.7239 -0.2159)
			(end 0.7239 1.9939)
			(stroke
				(width 0)
				(type default)
			)
			(fill no)
			(layer "B.CrtYd")
		)
		(fp_line
			(start 0.7239 -0.2159)
			(end 0.7239 1.9939)
			(stroke
				(width 0.1)
				(type default)
			)
			(layer "B.Fab")
		)
		(fp_line
			(start -0.7239 -0.2159)
			(end 0.7239 -0.2159)
			(stroke
				(width 0.1)
				(type default)
			)
			(layer "B.Fab")
		)
		(fp_line
			(start 0.7239 1.9939)
			(end -0.7239 1.9939)
			(stroke
				(width 0.1)
				(type default)
			)
			(layer "B.Fab")
		)
		(fp_line
			(start -0.7239 1.9939)
			(end -0.7239 -0.2159)
			(stroke
				(width 0.1)
				(type default)
			)
			(layer "B.Fab")
		)
		(pad "1" smd rect
			(at 0 0 270)
			(size 1.27 1.016)
			(layers "B.Cu" "B.Mask" "B.Paste")
			(net "PVDDQ_DEF")
		)
		(pad "2" smd rect
			(at 0 1.778 270)
			(size 1.27 1.016)
			(layers "B.Cu" "B.Mask" "B.Paste")
			(net "GND")
		)
		(zone
			(layer "B.Cu")
			(hatch none 0.5)
			(connect_pads
				(clearance 0)
			)
			(min_thickness 0.25)
			(keepout
				(tracks not_allowed)
				(vias allowed)
				(pads allowed)
				(copperpour not_allowed)
				(footprints allowed)
			)
			(placement
				(enabled no)
				(sheetname "")
			)
			(fill
				(thermal_gap 0.5)
				(thermal_bridge_width 0.5)
				(island_removal_mode 0)
			)
			(polygon
				(pts
					(xy 260.0452 -134.741412) (xy 260.8072 -134.741412) (xy 260.8072 -136.011412) (xy 260.0452 -136.011412)
				)
			)
		)
	)
	(footprint ""
		(layer "B.Cu")
		(at 439.4073 -141.097 180)
		(property "Reference" "C25W95"
			(at 0.8382 -0.67818 180)
			(unlocked yes)
			(layer "B.SilkS")
			(effects
				(font
					(size 0.4064 0.254)
					(thickness 0.1524)
				)
				(justify left mirror)
			)
		)
		(property "Value" ""
			(at 0 0 0)
			(layer "B.Fab")
			(effects
				(font
					(size 1.27 1.27)
				)
				(justify mirror)
			)
		)
		(duplicate_pad_numbers_are_jumpers no)
		(fp_poly
			(pts
				(xy -0.3048 -0.1016) (xy -0.3048 0.9906) (xy 0.3048 0.9906) (xy 0.3048 -0.1016)
			)
			(stroke
				(width 0)
				(type default)
			)
			(fill no)
			(layer "B.CrtYd")
		)
		(fp_line
			(start 0.3048 0.9906)
			(end -0.3048 0.9906)
			(stroke
				(width 0.1)
				(type default)
			)
			(layer "B.Fab")
		)
		(fp_line
			(start 0.3048 -0.1016)
			(end 0.3048 0.9906)
			(stroke
				(width 0.1)
				(type default)
			)
			(layer "B.Fab")
		)
		(fp_line
			(start -0.3048 0.9906)
			(end -0.3048 -0.1016)
			(stroke
				(width 0.1)
				(type default)
			)
			(layer "B.Fab")
		)
		(fp_line
			(start -0.3048 -0.1016)
			(end 0.3048 -0.1016)
			(stroke
				(width 0.1)
				(type default)
			)
			(layer "B.Fab")
		)
		(pad "1" smd rect
			(at 0 0)
			(size 0.508 0.508)
			(layers "B.Cu" "B.Mask" "B.Paste")
			(net "P3V3_STBY")
		)
		(pad "2" smd rect
			(at 0 0.889)
			(size 0.508 0.508)
			(layers "B.Cu" "B.Mask" "B.Paste")
			(net "GND")
		)
		(zone
			(layer "B.Cu")
			(hatch none 0.5)
			(connect_pads
				(clearance 0)
			)
			(min_thickness 0.25)
			(keepout
				(tracks not_allowed)
				(vias allowed)
				(pads allowed)
				(copperpour not_allowed)
				(footprints allowed)
			)
			(placement
				(enabled no)
				(sheetname "")
			)
			(fill
				(thermal_gap 0.5)
				(thermal_bridge_width 0.5)
				(island_removal_mode 0)
			)
			(polygon
				(pts
					(xy 439.1533 -141.732) (xy 439.6613 -141.732) (xy 439.6613 -141.351) (xy 439.1533 -141.351)
				)
			)
		)
		(zone
			(layer "B.Cu")
			(hatch none 0.5)
			(connect_pads
				(clearance 0)
			)
			(min_thickness 0.25)
			(keepout
				(tracks allowed)
				(vias not_allowed)
				(pads allowed)
				(copperpour not_allowed)
				(footprints allowed)
			)
			(placement
				(enabled no)
				(sheetname "")
			)
			(fill
				(thermal_gap 0.5)
				(thermal_bridge_width 0.5)
				(island_removal_mode 0)
			)
			(polygon
				(pts
					(xy 439.1533 -141.351) (xy 439.6613 -141.351) (xy 439.6613 -141.732) (xy 439.1533 -141.732)
				)
			)
		)
	)
	(footprint ""
		(layer "B.Cu")
		(at 386.93725 -111.05515 180)
		(property "Reference" "C3N5"
			(at 0 0 0)
			(layer "B.SilkS")
			(hide yes)
			(effects
				(font
					(size 1.27 1.27)
				)
				(justify mirror)
			)
		)
		(property "Value" ""
			(at 0 0 0)
			(layer "B.Fab")
			(effects
				(font
					(size 1.27 1.27)
				)
				(justify mirror)
			)
		)
		(duplicate_pad_numbers_are_jumpers no)
		(fp_rect
			(start 0.2794 0.9144)
			(end -0.2794 -0.1143)
			(stroke
				(width 0)
				(type default)
			)
			(fill no)
			(layer "B.CrtYd")
		)
		(fp_line
			(start 0.2794 0.9144)
			(end 0.2794 -0.1143)
			(stroke
				(width 0.1)
				(type default)
			)
			(layer "B.Fab")
		)
		(fp_line
			(start 0.2794 -0.1143)
			(end -0.2794 -0.1143)
			(stroke
				(width 0.1)
				(type default)
			)
			(layer "B.Fab")
		)
		(fp_line
			(start -0.2794 0.9144)
			(end 0.2794 0.9144)
			(stroke
				(width 0.1)
				(type default)
			)
			(layer "B.Fab")
		)
		(fp_line
			(start -0.2794 -0.1143)
			(end -0.2794 0.9144)
			(stroke
				(width 0.1)
				(type default)
			)
			(layer "B.Fab")
		)
		(pad "1" smd custom
			(at 0 0 90)
			(size 0.10414 0.10414)
			(layers "B.Cu" "B.Mask" "B.Paste")
			(net "PVNN_PCH_STBY")
			(options
				(clearance outline)
				(anchor circle)
			)
			(primitives
				(gr_poly
					(pts
						(xy -0.20828 -0.08636) (xy -0.20828 0.08636) (xy -0.08636 0.20828) (xy 0.086614 0.20828) (xy 0.20828 0.086614)
						(xy 0.20828 -0.08636) (xy 0.08636 -0.20828) (xy -0.08636 -0.20828)
					)
					(width 0)
					(fill yes)
				)
			)
		)
		(pad "2" smd custom
			(at 0 0.8001 90)
			(size 0.10414 0.10414)
			(layers "B.Cu" "B.Mask" "B.Paste")
			(net "GND")
			(options
				(clearance outline)
				(anchor circle)
			)
			(primitives
				(gr_poly
					(pts
						(xy -0.20828 -0.08636) (xy -0.20828 0.08636) (xy -0.08636 0.20828) (xy 0.086614 0.20828) (xy 0.20828 0.086614)
						(xy 0.20828 -0.08636) (xy 0.08636 -0.20828) (xy -0.08636 -0.20828)
					)
					(width 0)
					(fill yes)
				)
			)
		)
		(zone
			(layer "B.Cu")
			(hatch none 0.5)
			(connect_pads
				(clearance 0)
			)
			(min_thickness 0.25)
			(keepout
				(tracks allowed)
				(vias not_allowed)
				(pads allowed)
				(copperpour not_allowed)
				(footprints allowed)
			)
			(placement
				(enabled no)
				(sheetname "")
			)
			(fill
				(thermal_gap 0.5)
				(thermal_bridge_width 0.5)
				(island_removal_mode 0)
			)
			(polygon
				(pts
					(xy 386.84962 -111.2647) (xy 386.84962 -111.6457) (xy 387.02488 -111.6457) (xy 387.025134 -111.2647)
				)
			)
		)
		(zone
			(layer "B.Cu")
			(hatch none 0.5)
			(connect_pads
				(clearance 0)
			)
			(min_thickness 0.25)
			(keepout
				(tracks not_allowed)
				(vias allowed)
				(pads allowed)
				(copperpour not_allowed)
				(footprints allowed)
			)
			(placement
				(enabled no)
				(sheetname "")
			)
			(fill
				(thermal_gap 0.5)
				(thermal_bridge_width 0.5)
				(island_removal_mode 0)
			)
			(polygon
				(pts
					(xy 386.84962 -111.2647) (xy 386.84962 -111.6457) (xy 387.02488 -111.6457) (xy 387.025134 -111.2647)
				)
			)
		)
	)
	(footprint ""
		(layer "B.Cu")
		(at 381.508 -87.3125 180)
		(property "Reference" "R7D4"
			(at 0 0 0)
			(layer "B.SilkS")
			(hide yes)
			(effects
				(font
					(size 1.27 1.27)
				)
				(justify mirror)
			)
		)
		(property "Value" ""
			(at 0 0 0)
			(layer "B.Fab")
			(effects
				(font
					(size 1.27 1.27)
				)
				(justify mirror)
			)
		)
		(duplicate_pad_numbers_are_jumpers no)
		(fp_poly
			(pts
				(xy 0.2794 -0.1016) (xy -0.2794 -0.1016) (xy -0.2794 0.9906) (xy 0.2794 0.9906)
			)
			(stroke
				(width 0)
				(type default)
			)
			(fill no)
			(layer "B.CrtYd")
		)
		(fp_line
			(start 0.2794 0.9906)
			(end -0.2794 0.9906)
			(stroke
				(width 0.1)
				(type default)
			)
			(layer "B.Fab")
		)
		(fp_line
			(start 0.2794 -0.1016)
			(end 0.2794 0.9906)
			(stroke
				(width 0.1)
				(type default)
			)
			(layer "B.Fab")
		)
		(fp_line
			(start -0.2794 0.9906)
			(end -0.2794 -0.1016)
			(stroke
				(width 0.1)
				(type default)
			)
			(layer "B.Fab")
		)
		(fp_line
			(start -0.2794 -0.1016)
			(end 0.2794 -0.1016)
			(stroke
				(width 0.1)
				(type default)
			)
			(layer "B.Fab")
		)
		(pad "1" smd rect
			(at 0 0)
			(size 0.508 0.508)
			(layers "B.Cu" "B.Mask" "B.Paste")
			(net "P3V3_STBY")
		)
		(pad "2" smd rect
			(at 0 0.889)
			(size 0.508 0.508)
			(layers "B.Cu" "B.Mask" "B.Paste")
			(net "PU_IRQ_PCH_SCI_WHEA_N")
		)
		(zone
			(layer "B.Cu")
			(hatch none 0.5)
			(connect_pads
				(clearance 0)
			)
			(min_thickness 0.25)
			(keepout
				(tracks not_allowed)
				(vias allowed)
				(pads allowed)
				(copperpour not_allowed)
				(footprints allowed)
			)
			(placement
				(enabled no)
				(sheetname "")
			)
			(fill
				(thermal_gap 0.5)
				(thermal_bridge_width 0.5)
				(island_removal_mode 0)
			)
			(polygon
				(pts
					(xy 381.254 -87.9475) (xy 381.762 -87.9475) (xy 381.762 -87.5665) (xy 381.254 -87.5665)
				)
			)
		)
		(zone
			(layer "B.Cu")
			(hatch none 0.5)
			(connect_pads
				(clearance 0)
			)
			(min_thickness 0.25)
			(keepout
				(tracks allowed)
				(vias not_allowed)
				(pads allowed)
				(copperpour not_allowed)
				(footprints allowed)
			)
			(placement
				(enabled no)
				(sheetname "")
			)
			(fill
				(thermal_gap 0.5)
				(thermal_bridge_width 0.5)
				(island_removal_mode 0)
			)
			(polygon
				(pts
					(xy 381.254 -87.5665) (xy 381.762 -87.5665) (xy 381.762 -87.9475) (xy 381.254 -87.9475)
				)
			)
		)
	)
	(footprint ""
		(layer "B.Cu")
		(at 381.4826 -3.185414 90)
		(property "Reference" "R8W15"
			(at 0.8382 -0.67818 90)
			(unlocked yes)
			(layer "B.SilkS")
			(effects
				(font
					(size 0.4064 0.254)
					(thickness 0.1524)
				)
				(justify left mirror)
			)
		)
		(property "Value" ""
			(at 0 0 90)
			(layer "B.Fab")
			(effects
				(font
					(size 1.27 1.27)
				)
				(justify mirror)
			)
		)
		(duplicate_pad_numbers_are_jumpers no)
		(fp_poly
			(pts
				(xy 0.2794 -0.1016) (xy -0.2794 -0.1016) (xy -0.2794 0.9906) (xy 0.2794 0.9906)
			)
			(stroke
				(width 0)
				(type default)
			)
			(fill no)
			(layer "B.CrtYd")
		)
		(fp_line
			(start 0.2794 -0.1016)
			(end 0.2794 0.9906)
			(stroke
				(width 0.1)
				(type default)
			)
			(layer "B.Fab")
		)
		(fp_line
			(start -0.2794 -0.1016)
			(end 0.2794 -0.1016)
			(stroke
				(width 0.1)
				(type default)
			)
			(layer "B.Fab")
		)
		(fp_line
			(start 0.2794 0.9906)
			(end -0.2794 0.9906)
			(stroke
				(width 0.1)
				(type default)
			)
			(layer "B.Fab")
		)
		(fp_line
			(start -0.2794 0.9906)
			(end -0.2794 -0.1016)
			(stroke
				(width 0.1)
				(type default)
			)
			(layer "B.Fab")
		)
		(pad "1" smd rect
			(at 0 0 270)
			(size 0.508 0.508)
			(layers "B.Cu" "B.Mask" "B.Paste")
			(net "P3V3_STBY")
		)
		(pad "2" smd rect
			(at 0 0.889 270)
			(size 0.508 0.508)
			(layers "B.Cu" "B.Mask" "B.Paste")
			(net "JTAG_RISER_N")
		)
		(zone
			(layer "B.Cu")
			(hatch none 0.5)
			(connect_pads
				(clearance 0)
			)
			(min_thickness 0.25)
			(keepout
				(tracks allowed)
				(vias not_allowed)
				(pads allowed)
				(copperpour not_allowed)
				(footprints allowed)
			)
			(placement
				(enabled no)
				(sheetname "")
			)
			(fill
				(thermal_gap 0.5)
				(thermal_bridge_width 0.5)
				(island_removal_mode 0)
			)
			(polygon
				(pts
					(xy 381.7366 -3.439414) (xy 381.7366 -2.931414) (xy 382.1176 -2.931414) (xy 382.1176 -3.439414)
				)
			)
		)
		(zone
			(layer "B.Cu")
			(hatch none 0.5)
			(connect_pads
				(clearance 0)
			)
			(min_thickness 0.25)
			(keepout
				(tracks not_allowed)
				(vias allowed)
				(pads allowed)
				(copperpour not_allowed)
				(footprints allowed)
			)
			(placement
				(enabled no)
				(sheetname "")
			)
			(fill
				(thermal_gap 0.5)
				(thermal_bridge_width 0.5)
				(island_removal_mode 0)
			)
			(polygon
				(pts
					(xy 382.1176 -3.439414) (xy 382.1176 -2.931414) (xy 381.7366 -2.931414) (xy 381.7366 -3.439414)
				)
			)
		)
	)
	(footprint ""
		(layer "B.Cu")
		(at 386.575808 -84.729828 180)
		(property "Reference" "R3P6"
			(at 0.8382 -0.67818 180)
			(unlocked yes)
			(layer "B.SilkS")
			(effects
				(font
					(size 0.4064 0.254)
					(thickness 0.1524)
				)
				(justify left mirror)
			)
		)
		(property "Value" ""
			(at 0 0 0)
			(layer "B.Fab")
			(effects
				(font
					(size 1.27 1.27)
				)
				(justify mirror)
			)
		)
		(duplicate_pad_numbers_are_jumpers no)
		(fp_poly
			(pts
				(xy 0.2794 -0.1016) (xy -0.2794 -0.1016) (xy -0.2794 0.9906) (xy 0.2794 0.9906)
			)
			(stroke
				(width 0)
				(type default)
			)
			(fill no)
			(layer "B.CrtYd")
		)
		(fp_line
			(start 0.2794 0.9906)
			(end -0.2794 0.9906)
			(stroke
				(width 0.1)
				(type default)
			)
			(layer "B.Fab")
		)
		(fp_line
			(start 0.2794 -0.1016)
			(end 0.2794 0.9906)
			(stroke
				(width 0.1)
				(type default)
			)
			(layer "B.Fab")
		)
		(fp_line
			(start -0.2794 0.9906)
			(end -0.2794 -0.1016)
			(stroke
				(width 0.1)
				(type default)
			)
			(layer "B.Fab")
		)
		(fp_line
			(start -0.2794 -0.1016)
			(end 0.2794 -0.1016)
			(stroke
				(width 0.1)
				(type default)
			)
			(layer "B.Fab")
		)
		(pad "1" smd rect
			(at 0 0)
			(size 0.508 0.508)
			(layers "B.Cu" "B.Mask" "B.Paste")
			(net "P1V05_PCH_STBY")
		)
		(pad "2" smd rect
			(at 0 0.889)
			(size 0.508 0.508)
			(layers "B.Cu" "B.Mask" "B.Paste")
			(net "FM_PRSNT_2_3_N")
		)
		(zone
			(layer "B.Cu")
			(hatch none 0.5)
			(connect_pads
				(clearance 0)
			)
			(min_thickness 0.25)
			(keepout
				(tracks not_allowed)
				(vias allowed)
				(pads allowed)
				(copperpour not_allowed)
				(footprints allowed)
			)
			(placement
				(enabled no)
				(sheetname "")
			)
			(fill
				(thermal_gap 0.5)
				(thermal_bridge_width 0.5)
				(island_removal_mode 0)
			)
			(polygon
				(pts
					(xy 386.321808 -85.364828) (xy 386.829808 -85.364828) (xy 386.829808 -84.983828) (xy 386.321808 -84.983828)
				)
			)
		)
		(zone
			(layer "B.Cu")
			(hatch none 0.5)
			(connect_pads
				(clearance 0)
			)
			(min_thickness 0.25)
			(keepout
				(tracks allowed)
				(vias not_allowed)
				(pads allowed)
				(copperpour not_allowed)
				(footprints allowed)
			)
			(placement
				(enabled no)
				(sheetname "")
			)
			(fill
				(thermal_gap 0.5)
				(thermal_bridge_width 0.5)
				(island_removal_mode 0)
			)
			(polygon
				(pts
					(xy 386.321808 -84.983828) (xy 386.829808 -84.983828) (xy 386.829808 -85.364828) (xy 386.321808 -85.364828)
				)
			)
		)
	)
	(footprint ""
		(layer "B.Cu")
		(at 426.0215 -11.684 -90)
		(property "Reference" "R2U47"
			(at 0 0 90)
			(layer "B.SilkS")
			(hide yes)
			(effects
				(font
					(size 1.27 1.27)
				)
				(justify mirror)
			)
		)
		(property "Value" ""
			(at 0 0 90)
			(layer "B.Fab")
			(effects
				(font
					(size 1.27 1.27)
				)
				(justify mirror)
			)
		)
		(duplicate_pad_numbers_are_jumpers no)
		(fp_poly
			(pts
				(xy 0.2794 -0.1016) (xy -0.2794 -0.1016) (xy -0.2794 0.9906) (xy 0.2794 0.9906)
			)
			(stroke
				(width 0)
				(type default)
			)
			(fill no)
			(layer "B.CrtYd")
		)
		(fp_line
			(start -0.2794 0.9906)
			(end -0.2794 -0.1016)
			(stroke
				(width 0.1)
				(type default)
			)
			(layer "B.Fab")
		)
		(fp_line
			(start 0.2794 0.9906)
			(end -0.2794 0.9906)
			(stroke
				(width 0.1)
				(type default)
			)
			(layer "B.Fab")
		)
		(fp_line
			(start -0.2794 -0.1016)
			(end 0.2794 -0.1016)
			(stroke
				(width 0.1)
				(type default)
			)
			(layer "B.Fab")
		)
		(fp_line
			(start 0.2794 -0.1016)
			(end 0.2794 0.9906)
			(stroke
				(width 0.1)
				(type default)
			)
			(layer "B.Fab")
		)
		(pad "1" smd rect
			(at 0 0 90)
			(size 0.508 0.508)
			(layers "B.Cu" "B.Mask" "B.Paste")
			(net "H_CPU0_MEMABC_MEMHOT_LVT3_N")
		)
		(pad "2" smd rect
			(at 0 0.889 90)
			(size 0.508 0.508)
			(layers "B.Cu" "B.Mask" "B.Paste")
			(net "H_CPU0_MEMABC_MEMHOT_LVT3_BMC_N")
		)
		(zone
			(layer "B.Cu")
			(hatch none 0.5)
			(connect_pads
				(clearance 0)
			)
			(min_thickness 0.25)
			(keepout
				(tracks not_allowed)
				(vias allowed)
				(pads allowed)
				(copperpour not_allowed)
				(footprints allowed)
			)
			(placement
				(enabled no)
				(sheetname "")
			)
			(fill
				(thermal_gap 0.5)
				(thermal_bridge_width 0.5)
				(island_removal_mode 0)
			)
			(polygon
				(pts
					(xy 425.3865 -11.43) (xy 425.3865 -11.938) (xy 425.7675 -11.938) (xy 425.7675 -11.43)
				)
			)
		)
		(zone
			(layer "B.Cu")
			(hatch none 0.5)
			(connect_pads
				(clearance 0)
			)
			(min_thickness 0.25)
			(keepout
				(tracks allowed)
				(vias not_allowed)
				(pads allowed)
				(copperpour not_allowed)
				(footprints allowed)
			)
			(placement
				(enabled no)
				(sheetname "")
			)
			(fill
				(thermal_gap 0.5)
				(thermal_bridge_width 0.5)
				(island_removal_mode 0)
			)
			(polygon
				(pts
					(xy 425.7675 -11.43) (xy 425.7675 -11.938) (xy 425.3865 -11.938) (xy 425.3865 -11.43)
				)
			)
		)
	)
	(footprint ""
		(layer "B.Cu")
		(at 446.33388 -64.752982 180)
		(property "Reference" "C2P12"
			(at 0 0 0)
			(layer "B.SilkS")
			(hide yes)
			(effects
				(font
					(size 1.27 1.27)
				)
				(justify mirror)
			)
		)
		(property "Value" ""
			(at 0 0 0)
			(layer "B.Fab")
			(effects
				(font
					(size 1.27 1.27)
				)
				(justify mirror)
			)
		)
		(duplicate_pad_numbers_are_jumpers no)
		(fp_poly
			(pts
				(xy -0.3048 -0.1016) (xy -0.3048 0.9906) (xy 0.3048 0.9906) (xy 0.3048 -0.1016)
			)
			(stroke
				(width 0)
				(type default)
			)
			(fill no)
			(layer "B.CrtYd")
		)
		(fp_line
			(start 0.3048 0.9906)
			(end -0.3048 0.9906)
			(stroke
				(width 0.1)
				(type default)
			)
			(layer "B.Fab")
		)
		(fp_line
			(start 0.3048 -0.1016)
			(end 0.3048 0.9906)
			(stroke
				(width 0.1)
				(type default)
			)
			(layer "B.Fab")
		)
		(fp_line
			(start -0.3048 0.9906)
			(end -0.3048 -0.1016)
			(stroke
				(width 0.1)
				(type default)
			)
			(layer "B.Fab")
		)
		(fp_line
			(start -0.3048 -0.1016)
			(end 0.3048 -0.1016)
			(stroke
				(width 0.1)
				(type default)
			)
			(layer "B.Fab")
		)
		(pad "1" smd rect
			(at 0 0)
			(size 0.508 0.508)
			(layers "B.Cu" "B.Mask" "B.Paste")
			(net "P12V_STBY")
		)
		(pad "2" smd rect
			(at 0 0.889)
			(size 0.508 0.508)
			(layers "B.Cu" "B.Mask" "B.Paste")
			(net "GND")
		)
		(zone
			(layer "B.Cu")
			(hatch none 0.5)
			(connect_pads
				(clearance 0)
			)
			(min_thickness 0.25)
			(keepout
				(tracks not_allowed)
				(vias allowed)
				(pads allowed)
				(copperpour not_allowed)
				(footprints allowed)
			)
			(placement
				(enabled no)
				(sheetname "")
			)
			(fill
				(thermal_gap 0.5)
				(thermal_bridge_width 0.5)
				(island_removal_mode 0)
			)
			(polygon
				(pts
					(xy 446.07988 -65.387982) (xy 446.58788 -65.387982) (xy 446.58788 -65.006982) (xy 446.07988 -65.006982)
				)
			)
		)
		(zone
			(layer "B.Cu")
			(hatch none 0.5)
			(connect_pads
				(clearance 0)
			)
			(min_thickness 0.25)
			(keepout
				(tracks allowed)
				(vias not_allowed)
				(pads allowed)
				(copperpour not_allowed)
				(footprints allowed)
			)
			(placement
				(enabled no)
				(sheetname "")
			)
			(fill
				(thermal_gap 0.5)
				(thermal_bridge_width 0.5)
				(island_removal_mode 0)
			)
			(polygon
				(pts
					(xy 446.07988 -65.006982) (xy 446.58788 -65.006982) (xy 446.58788 -65.387982) (xy 446.07988 -65.387982)
				)
			)
		)
	)
	(footprint ""
		(layer "B.Cu")
		(at 269.775686 -68.17614 180)
		(property "Reference" "C5P43"
			(at 0 0 0)
			(layer "B.SilkS")
			(hide yes)
			(effects
				(font
					(size 1.27 1.27)
				)
				(justify mirror)
			)
		)
		(property "Value" ""
			(at 0 0 0)
			(layer "B.Fab")
			(effects
				(font
					(size 1.27 1.27)
				)
				(justify mirror)
			)
		)
		(duplicate_pad_numbers_are_jumpers no)
		(fp_poly
			(pts
				(xy 0.7239 -0.2159) (xy -0.7239 -0.2159) (xy -0.7239 1.9939) (xy 0.7239 1.9939)
			)
			(stroke
				(width 0)
				(type default)
			)
			(fill no)
			(layer "B.CrtYd")
		)
		(fp_line
			(start 0.7239 1.9939)
			(end -0.7239 1.9939)
			(stroke
				(width 0.1)
				(type default)
			)
			(layer "B.Fab")
		)
		(fp_line
			(start 0.7239 -0.2159)
			(end 0.7239 1.9939)
			(stroke
				(width 0.1)
				(type default)
			)
			(layer "B.Fab")
		)
		(fp_line
			(start -0.7239 1.9939)
			(end -0.7239 -0.2159)
			(stroke
				(width 0.1)
				(type default)
			)
			(layer "B.Fab")
		)
		(fp_line
			(start -0.7239 -0.2159)
			(end 0.7239 -0.2159)
			(stroke
				(width 0.1)
				(type default)
			)
			(layer "B.Fab")
		)
		(pad "1" smd rect
			(at 0 0)
			(size 1.27 1.016)
			(layers "B.Cu" "B.Mask" "B.Paste")
			(net "PVDDQ_ABC")
		)
		(pad "2" smd rect
			(at 0 1.778)
			(size 1.27 1.016)
			(layers "B.Cu" "B.Mask" "B.Paste")
			(net "GND")
		)
		(zone
			(layer "B.Cu")
			(hatch none 0.5)
			(connect_pads
				(clearance 0)
			)
			(min_thickness 0.25)
			(keepout
				(tracks not_allowed)
				(vias allowed)
				(pads allowed)
				(copperpour not_allowed)
				(footprints allowed)
			)
			(placement
				(enabled no)
				(sheetname "")
			)
			(fill
				(thermal_gap 0.5)
				(thermal_bridge_width 0.5)
				(island_removal_mode 0)
			)
			(polygon
				(pts
					(xy 269.140686 -68.68414) (xy 270.410686 -68.68414) (xy 270.410686 -69.44614) (xy 269.140686 -69.44614)
				)
			)
		)
	)
	(footprint ""
		(layer "B.Cu")
		(at 252.1585 -140.208 -90)
		(property "Reference" "C5G66"
			(at -1.14681 0.76708 0)
			(unlocked yes)
			(layer "B.SilkS")
			(effects
				(font
					(size 0.7874 0.5842)
					(thickness 0.1524)
				)
				(justify mirror)
			)
		)
		(property "Value" ""
			(at 0 0 90)
			(layer "B.Fab")
			(effects
				(font
					(size 1.27 1.27)
				)
				(justify mirror)
			)
		)
		(duplicate_pad_numbers_are_jumpers no)
		(fp_rect
			(start 0.4953 1.6002)
			(end -0.4953 -0.2032)
			(stroke
				(width 0)
				(type default)
			)
			(fill no)
			(layer "B.CrtYd")
		)
		(fp_line
			(start -0.4953 1.6002)
			(end 0.4953 1.6002)
			(stroke
				(width 0.1)
				(type default)
			)
			(layer "B.Fab")
		)
		(fp_line
			(start 0.4953 1.6002)
			(end 0.4953 -0.2032)
			(stroke
				(width 0.1)
				(type default)
			)
			(layer "B.Fab")
		)
		(fp_line
			(start -0.4953 -0.2032)
			(end -0.4953 1.6002)
			(stroke
				(width 0.1)
				(type default)
			)
			(layer "B.Fab")
		)
		(fp_line
			(start 0.4953 -0.2032)
			(end -0.4953 -0.2032)
			(stroke
				(width 0.1)
				(type default)
			)
			(layer "B.Fab")
		)
		(pad "1" smd rect
			(at 0 0 90)
			(size 0.762 0.889)
			(layers "B.Cu" "B.Mask" "B.Paste")
			(net "PVDDQ_DEF")
		)
		(pad "2" smd rect
			(at 0 1.397 90)
			(size 0.762 0.889)
			(layers "B.Cu" "B.Mask" "B.Paste")
			(net "GND")
		)
		(zone
			(layer "B.Cu")
			(hatch none 0.5)
			(connect_pads
				(clearance 0)
			)
			(min_thickness 0.25)
			(keepout
				(tracks not_allowed)
				(vias allowed)
				(pads allowed)
				(copperpour not_allowed)
				(footprints allowed)
			)
			(placement
				(enabled no)
				(sheetname "")
			)
			(fill
				(thermal_gap 0.5)
				(thermal_bridge_width 0.5)
				(island_removal_mode 0)
			)
			(polygon
				(pts
					(xy 251.206 -139.827) (xy 251.714 -139.827) (xy 251.714 -140.589) (xy 251.206 -140.589)
				)
			)
		)
	)
	(footprint ""
		(layer "B.Cu")
		(at 421.513 -147.828 -90)
		(property "Reference" "C2L22"
			(at 0 0 90)
			(layer "B.SilkS")
			(hide yes)
			(effects
				(font
					(size 1.27 1.27)
				)
				(justify mirror)
			)
		)
		(property "Value" ""
			(at 0 0 90)
			(layer "B.Fab")
			(effects
				(font
					(size 1.27 1.27)
				)
				(justify mirror)
			)
		)
		(duplicate_pad_numbers_are_jumpers no)
		(fp_poly
			(pts
				(xy -0.3048 -0.1016) (xy -0.3048 0.9906) (xy 0.3048 0.9906) (xy 0.3048 -0.1016)
			)
			(stroke
				(width 0)
				(type default)
			)
			(fill no)
			(layer "B.CrtYd")
		)
		(fp_line
			(start -0.3048 0.9906)
			(end -0.3048 -0.1016)
			(stroke
				(width 0.1)
				(type default)
			)
			(layer "B.Fab")
		)
		(fp_line
			(start 0.3048 0.9906)
			(end -0.3048 0.9906)
			(stroke
				(width 0.1)
				(type default)
			)
			(layer "B.Fab")
		)
		(fp_line
			(start -0.3048 -0.1016)
			(end 0.3048 -0.1016)
			(stroke
				(width 0.1)
				(type default)
			)
			(layer "B.Fab")
		)
		(fp_line
			(start 0.3048 -0.1016)
			(end 0.3048 0.9906)
			(stroke
				(width 0.1)
				(type default)
			)
			(layer "B.Fab")
		)
		(pad "1" smd rect
			(at 0 0 90)
			(size 0.508 0.508)
			(layers "B.Cu" "B.Mask" "B.Paste")
			(net "SATA6G_P3_TX_C_DN")
		)
		(pad "2" smd rect
			(at 0 0.889 90)
			(size 0.508 0.508)
			(layers "B.Cu" "B.Mask" "B.Paste")
			(net "SATA6G_PCH_PCIE_UP_SATA_TXN<3>")
		)
		(zone
			(layer "B.Cu")
			(hatch none 0.5)
			(connect_pads
				(clearance 0)
			)
			(min_thickness 0.25)
			(keepout
				(tracks not_allowed)
				(vias allowed)
				(pads allowed)
				(copperpour not_allowed)
				(footprints allowed)
			)
			(placement
				(enabled no)
				(sheetname "")
			)
			(fill
				(thermal_gap 0.5)
				(thermal_bridge_width 0.5)
				(island_removal_mode 0)
			)
			(polygon
				(pts
					(xy 420.878 -147.574) (xy 420.878 -148.082) (xy 421.259 -148.082) (xy 421.259 -147.574)
				)
			)
		)
		(zone
			(layer "B.Cu")
			(hatch none 0.5)
			(connect_pads
				(clearance 0)
			)
			(min_thickness 0.25)
			(keepout
				(tracks allowed)
				(vias not_allowed)
				(pads allowed)
				(copperpour not_allowed)
				(footprints allowed)
			)
			(placement
				(enabled no)
				(sheetname "")
			)
			(fill
				(thermal_gap 0.5)
				(thermal_bridge_width 0.5)
				(island_removal_mode 0)
			)
			(polygon
				(pts
					(xy 421.259 -147.574) (xy 421.259 -148.082) (xy 420.878 -148.082) (xy 420.878 -147.574)
				)
			)
		)
	)
	(footprint ""
		(layer "B.Cu")
		(at 181.9656 -135.9662 180)
		(property "Reference" "C6L11"
			(at 0 0 0)
			(layer "B.SilkS")
			(hide yes)
			(effects
				(font
					(size 1.27 1.27)
				)
				(justify mirror)
			)
		)
		(property "Value" ""
			(at 0 0 0)
			(layer "B.Fab")
			(effects
				(font
					(size 1.27 1.27)
				)
				(justify mirror)
			)
		)
		(duplicate_pad_numbers_are_jumpers no)
		(fp_poly
			(pts
				(xy -0.3048 -0.1016) (xy -0.3048 0.9906) (xy 0.3048 0.9906) (xy 0.3048 -0.1016)
			)
			(stroke
				(width 0)
				(type default)
			)
			(fill no)
			(layer "B.CrtYd")
		)
		(fp_line
			(start 0.3048 0.9906)
			(end -0.3048 0.9906)
			(stroke
				(width 0.1)
				(type default)
			)
			(layer "B.Fab")
		)
		(fp_line
			(start 0.3048 -0.1016)
			(end 0.3048 0.9906)
			(stroke
				(width 0.1)
				(type default)
			)
			(layer "B.Fab")
		)
		(fp_line
			(start -0.3048 0.9906)
			(end -0.3048 -0.1016)
			(stroke
				(width 0.1)
				(type default)
			)
			(layer "B.Fab")
		)
		(fp_line
			(start -0.3048 -0.1016)
			(end 0.3048 -0.1016)
			(stroke
				(width 0.1)
				(type default)
			)
			(layer "B.Fab")
		)
		(pad "1" smd rect
			(at 0 0)
			(size 0.508 0.508)
			(layers "B.Cu" "B.Mask" "B.Paste")
			(net "VR_FET_SW_P12V_STBY_PVPP_KLM")
		)
		(pad "2" smd rect
			(at 0 0.889)
			(size 0.508 0.508)
			(layers "B.Cu" "B.Mask" "B.Paste")
			(net "GND")
		)
		(zone
			(layer "B.Cu")
			(hatch none 0.5)
			(connect_pads
				(clearance 0)
			)
			(min_thickness 0.25)
			(keepout
				(tracks not_allowed)
				(vias allowed)
				(pads allowed)
				(copperpour not_allowed)
				(footprints allowed)
			)
			(placement
				(enabled no)
				(sheetname "")
			)
			(fill
				(thermal_gap 0.5)
				(thermal_bridge_width 0.5)
				(island_removal_mode 0)
			)
			(polygon
				(pts
					(xy 181.7116 -136.6012) (xy 182.2196 -136.6012) (xy 182.2196 -136.2202) (xy 181.7116 -136.2202)
				)
			)
		)
		(zone
			(layer "B.Cu")
			(hatch none 0.5)
			(connect_pads
				(clearance 0)
			)
			(min_thickness 0.25)
			(keepout
				(tracks allowed)
				(vias not_allowed)
				(pads allowed)
				(copperpour not_allowed)
				(footprints allowed)
			)
			(placement
				(enabled no)
				(sheetname "")
			)
			(fill
				(thermal_gap 0.5)
				(thermal_bridge_width 0.5)
				(island_removal_mode 0)
			)
			(polygon
				(pts
					(xy 181.7116 -136.2202) (xy 182.2196 -136.2202) (xy 182.2196 -136.6012) (xy 181.7116 -136.6012)
				)
			)
		)
	)
	(footprint ""
		(layer "B.Cu")
		(at 464.33486 -41.18102)
		(property "Reference" "C9W14"
			(at -0.97536 0.76708 90)
			(unlocked yes)
			(layer "B.SilkS")
			(effects
				(font
					(size 0.4064 0.254)
					(thickness 0.1524)
				)
				(justify mirror)
			)
		)
		(property "Value" ""
			(at 0 0 0)
			(layer "B.Fab")
			(effects
				(font
					(size 1.27 1.27)
				)
				(justify mirror)
			)
		)
		(duplicate_pad_numbers_are_jumpers no)
		(fp_poly
			(pts
				(xy 0.4953 -0.2032) (xy -0.4953 -0.2032) (xy -0.4953 1.6002) (xy 0.4953 1.6002)
			)
			(stroke
				(width 0)
				(type default)
			)
			(fill no)
			(layer "B.CrtYd")
		)
		(fp_line
			(start -0.4953 -0.2032)
			(end -0.4953 1.6002)
			(stroke
				(width 0.1)
				(type default)
			)
			(layer "B.Fab")
		)
		(fp_line
			(start -0.4953 1.6002)
			(end 0.4953 1.6002)
			(stroke
				(width 0.1)
				(type default)
			)
			(layer "B.Fab")
		)
		(fp_line
			(start 0.4953 -0.2032)
			(end -0.4953 -0.2032)
			(stroke
				(width 0.1)
				(type default)
			)
			(layer "B.Fab")
		)
		(fp_line
			(start 0.4953 1.6002)
			(end 0.4953 -0.2032)
			(stroke
				(width 0.1)
				(type default)
			)
			(layer "B.Fab")
		)
		(pad "1" smd rect
			(at 0 0 180)
			(size 0.762 0.889)
			(layers "B.Cu" "B.Mask" "B.Paste")
			(net "P3V3_STBY")
		)
		(pad "2" smd rect
			(at 0 1.397 180)
			(size 0.762 0.889)
			(layers "B.Cu" "B.Mask" "B.Paste")
			(net "GND")
		)
		(zone
			(layer "B.Cu")
			(hatch none 0.5)
			(connect_pads
				(clearance 0)
			)
			(min_thickness 0.25)
			(keepout
				(tracks not_allowed)
				(vias allowed)
				(pads allowed)
				(copperpour not_allowed)
				(footprints allowed)
			)
			(placement
				(enabled no)
				(sheetname "")
			)
			(fill
				(thermal_gap 0.5)
				(thermal_bridge_width 0.5)
				(island_removal_mode 0)
			)
			(polygon
				(pts
					(xy 464.71586 -40.73652) (xy 463.95386 -40.73652) (xy 463.95386 -40.22852) (xy 464.71586 -40.22852)
				)
			)
		)
	)
	(footprint ""
		(layer "B.Cu")
		(at 25.9842 -85.9028 90)
		(property "Reference" "R9P5"
			(at 0 0 90)
			(layer "B.SilkS")
			(hide yes)
			(effects
				(font
					(size 1.27 1.27)
				)
				(justify mirror)
			)
		)
		(property "Value" ""
			(at 0 0 90)
			(layer "B.Fab")
			(effects
				(font
					(size 1.27 1.27)
				)
				(justify mirror)
			)
		)
		(duplicate_pad_numbers_are_jumpers no)
		(fp_poly
			(pts
				(xy 0.2794 -0.1016) (xy -0.2794 -0.1016) (xy -0.2794 0.9906) (xy 0.2794 0.9906)
			)
			(stroke
				(width 0)
				(type default)
			)
			(fill no)
			(layer "B.CrtYd")
		)
		(fp_line
			(start 0.2794 -0.1016)
			(end 0.2794 0.9906)
			(stroke
				(width 0.1)
				(type default)
			)
			(layer "B.Fab")
		)
		(fp_line
			(start -0.2794 -0.1016)
			(end 0.2794 -0.1016)
			(stroke
				(width 0.1)
				(type default)
			)
			(layer "B.Fab")
		)
		(fp_line
			(start 0.2794 0.9906)
			(end -0.2794 0.9906)
			(stroke
				(width 0.1)
				(type default)
			)
			(layer "B.Fab")
		)
		(fp_line
			(start -0.2794 0.9906)
			(end -0.2794 -0.1016)
			(stroke
				(width 0.1)
				(type default)
			)
			(layer "B.Fab")
		)
		(pad "1" smd rect
			(at 0 0 270)
			(size 0.508 0.508)
			(layers "B.Cu" "B.Mask" "B.Paste")
			(net "P3V3_STBY")
		)
		(pad "2" smd rect
			(at 0 0.889 270)
			(size 0.508 0.508)
			(layers "B.Cu" "B.Mask" "B.Paste")
			(net "FM_DISABLE_FAN_N")
		)
		(zone
			(layer "B.Cu")
			(hatch none 0.5)
			(connect_pads
				(clearance 0)
			)
			(min_thickness 0.25)
			(keepout
				(tracks allowed)
				(vias not_allowed)
				(pads allowed)
				(copperpour not_allowed)
				(footprints allowed)
			)
			(placement
				(enabled no)
				(sheetname "")
			)
			(fill
				(thermal_gap 0.5)
				(thermal_bridge_width 0.5)
				(island_removal_mode 0)
			)
			(polygon
				(pts
					(xy 26.2382 -86.1568) (xy 26.2382 -85.6488) (xy 26.6192 -85.6488) (xy 26.6192 -86.1568)
				)
			)
		)
		(zone
			(layer "B.Cu")
			(hatch none 0.5)
			(connect_pads
				(clearance 0)
			)
			(min_thickness 0.25)
			(keepout
				(tracks not_allowed)
				(vias allowed)
				(pads allowed)
				(copperpour not_allowed)
				(footprints allowed)
			)
			(placement
				(enabled no)
				(sheetname "")
			)
			(fill
				(thermal_gap 0.5)
				(thermal_bridge_width 0.5)
				(island_removal_mode 0)
			)
			(polygon
				(pts
					(xy 26.6192 -86.1568) (xy 26.6192 -85.6488) (xy 26.2382 -85.6488) (xy 26.2382 -86.1568)
				)
			)
		)
	)
	(footprint ""
		(layer "B.Cu")
		(at 486.41 -111.94542 -90)
		(property "Reference" "C1M27"
			(at 0 0 90)
			(layer "B.SilkS")
			(hide yes)
			(effects
				(font
					(size 1.27 1.27)
				)
				(justify mirror)
			)
		)
		(property "Value" ""
			(at 0 0 90)
			(layer "B.Fab")
			(effects
				(font
					(size 1.27 1.27)
				)
				(justify mirror)
			)
		)
		(duplicate_pad_numbers_are_jumpers no)
		(fp_rect
			(start 0.7239 1.9939)
			(end -0.7239 -0.2159)
			(stroke
				(width 0)
				(type default)
			)
			(fill no)
			(layer "B.CrtYd")
		)
		(fp_line
			(start -0.7239 1.9939)
			(end -0.7239 -0.2159)
			(stroke
				(width 0.1)
				(type default)
			)
			(layer "B.Fab")
		)
		(fp_line
			(start 0.7239 1.9939)
			(end -0.7239 1.9939)
			(stroke
				(width 0.1)
				(type default)
			)
			(layer "B.Fab")
		)
		(fp_line
			(start -0.7239 -0.2159)
			(end 0.7239 -0.2159)
			(stroke
				(width 0.1)
				(type default)
			)
			(layer "B.Fab")
		)
		(fp_line
			(start 0.7239 -0.2159)
			(end 0.7239 1.9939)
			(stroke
				(width 0.1)
				(type default)
			)
			(layer "B.Fab")
		)
		(pad "1" smd rect
			(at 0 0 90)
			(size 1.27 1.016)
			(layers "B.Cu" "B.Mask" "B.Paste")
			(net "P12V_STBY")
		)
		(pad "2" smd rect
			(at 0 1.778 90)
			(size 1.27 1.016)
			(layers "B.Cu" "B.Mask" "B.Paste")
			(net "GND")
		)
		(zone
			(layer "B.Cu")
			(hatch none 0.5)
			(connect_pads
				(clearance 0)
			)
			(min_thickness 0.25)
			(keepout
				(tracks not_allowed)
				(vias allowed)
				(pads allowed)
				(copperpour not_allowed)
				(footprints allowed)
			)
			(placement
				(enabled no)
				(sheetname "")
			)
			(fill
				(thermal_gap 0.5)
				(thermal_bridge_width 0.5)
				(island_removal_mode 0)
			)
			(polygon
				(pts
					(xy 485.14 -111.31042) (xy 485.902 -111.31042) (xy 485.902 -112.58042) (xy 485.14 -112.58042)
				)
			)
		)
	)
	(footprint ""
		(layer "B.Cu")
		(at 405.9174 -33.4264 -90)
		(property "Reference" "R25W146"
			(at 0.8382 -0.67818 270)
			(unlocked yes)
			(layer "B.SilkS")
			(effects
				(font
					(size 0.4064 0.254)
					(thickness 0.1524)
				)
				(justify left mirror)
			)
		)
		(property "Value" ""
			(at 0 0 90)
			(layer "B.Fab")
			(effects
				(font
					(size 1.27 1.27)
				)
				(justify mirror)
			)
		)
		(duplicate_pad_numbers_are_jumpers no)
		(fp_poly
			(pts
				(xy 0.2794 -0.1016) (xy -0.2794 -0.1016) (xy -0.2794 0.9906) (xy 0.2794 0.9906)
			)
			(stroke
				(width 0)
				(type default)
			)
			(fill no)
			(layer "B.CrtYd")
		)
		(fp_line
			(start -0.2794 0.9906)
			(end -0.2794 -0.1016)
			(stroke
				(width 0.1)
				(type default)
			)
			(layer "B.Fab")
		)
		(fp_line
			(start 0.2794 0.9906)
			(end -0.2794 0.9906)
			(stroke
				(width 0.1)
				(type default)
			)
			(layer "B.Fab")
		)
		(fp_line
			(start -0.2794 -0.1016)
			(end 0.2794 -0.1016)
			(stroke
				(width 0.1)
				(type default)
			)
			(layer "B.Fab")
		)
		(fp_line
			(start 0.2794 -0.1016)
			(end 0.2794 0.9906)
			(stroke
				(width 0.1)
				(type default)
			)
			(layer "B.Fab")
		)
		(pad "1" smd rect
			(at 0 0 90)
			(size 0.508 0.508)
			(layers "B.Cu" "B.Mask" "B.Paste")
			(net "GND")
		)
		(pad "2" smd rect
			(at 0 0.889 90)
			(size 0.508 0.508)
			(layers "B.Cu" "B.Mask" "B.Paste")
			(net "RMII_BMC_OCP_TXEN")
		)
		(zone
			(layer "B.Cu")
			(hatch none 0.5)
			(connect_pads
				(clearance 0)
			)
			(min_thickness 0.25)
			(keepout
				(tracks not_allowed)
				(vias allowed)
				(pads allowed)
				(copperpour not_allowed)
				(footprints allowed)
			)
			(placement
				(enabled no)
				(sheetname "")
			)
			(fill
				(thermal_gap 0.5)
				(thermal_bridge_width 0.5)
				(island_removal_mode 0)
			)
			(polygon
				(pts
					(xy 405.2824 -33.1724) (xy 405.2824 -33.6804) (xy 405.6634 -33.6804) (xy 405.6634 -33.1724)
				)
			)
		)
		(zone
			(layer "B.Cu")
			(hatch none 0.5)
			(connect_pads
				(clearance 0)
			)
			(min_thickness 0.25)
			(keepout
				(tracks allowed)
				(vias not_allowed)
				(pads allowed)
				(copperpour not_allowed)
				(footprints allowed)
			)
			(placement
				(enabled no)
				(sheetname "")
			)
			(fill
				(thermal_gap 0.5)
				(thermal_bridge_width 0.5)
				(island_removal_mode 0)
			)
			(polygon
				(pts
					(xy 405.6634 -33.1724) (xy 405.6634 -33.6804) (xy 405.2824 -33.6804) (xy 405.2824 -33.1724)
				)
			)
		)
	)
	(footprint ""
		(layer "B.Cu")
		(at 407.654506 -32.661352 180)
		(property "Reference" "R25W85"
			(at 0.8382 -0.67818 180)
			(unlocked yes)
			(layer "B.SilkS")
			(effects
				(font
					(size 0.4064 0.254)
					(thickness 0.1524)
				)
				(justify left mirror)
			)
		)
		(property "Value" ""
			(at 0 0 0)
			(layer "B.Fab")
			(effects
				(font
					(size 1.27 1.27)
				)
				(justify mirror)
			)
		)
		(duplicate_pad_numbers_are_jumpers no)
		(fp_poly
			(pts
				(xy 0.2794 -0.1016) (xy -0.2794 -0.1016) (xy -0.2794 0.9906) (xy 0.2794 0.9906)
			)
			(stroke
				(width 0)
				(type default)
			)
			(fill no)
			(layer "B.CrtYd")
		)
		(fp_line
			(start 0.2794 0.9906)
			(end -0.2794 0.9906)
			(stroke
				(width 0.1)
				(type default)
			)
			(layer "B.Fab")
		)
		(fp_line
			(start 0.2794 -0.1016)
			(end 0.2794 0.9906)
			(stroke
				(width 0.1)
				(type default)
			)
			(layer "B.Fab")
		)
		(fp_line
			(start -0.2794 0.9906)
			(end -0.2794 -0.1016)
			(stroke
				(width 0.1)
				(type default)
			)
			(layer "B.Fab")
		)
		(fp_line
			(start -0.2794 -0.1016)
			(end 0.2794 -0.1016)
			(stroke
				(width 0.1)
				(type default)
			)
			(layer "B.Fab")
		)
		(pad "1" smd rect
			(at 0 0)
			(size 0.508 0.508)
			(layers "B.Cu" "B.Mask" "B.Paste")
			(net "RMII_BMC_OCP_TXEN_R")
		)
		(pad "2" smd rect
			(at 0 0.889)
			(size 0.508 0.508)
			(layers "B.Cu" "B.Mask" "B.Paste")
			(net "RMII_BMC_OCP_TXEN")
		)
		(zone
			(layer "B.Cu")
			(hatch none 0.5)
			(connect_pads
				(clearance 0)
			)
			(min_thickness 0.25)
			(keepout
				(tracks not_allowed)
				(vias allowed)
				(pads allowed)
				(copperpour not_allowed)
				(footprints allowed)
			)
			(placement
				(enabled no)
				(sheetname "")
			)
			(fill
				(thermal_gap 0.5)
				(thermal_bridge_width 0.5)
				(island_removal_mode 0)
			)
			(polygon
				(pts
					(xy 407.400506 -33.296352) (xy 407.908506 -33.296352) (xy 407.908506 -32.915352) (xy 407.400506 -32.915352)
				)
			)
		)
		(zone
			(layer "B.Cu")
			(hatch none 0.5)
			(connect_pads
				(clearance 0)
			)
			(min_thickness 0.25)
			(keepout
				(tracks allowed)
				(vias not_allowed)
				(pads allowed)
				(copperpour not_allowed)
				(footprints allowed)
			)
			(placement
				(enabled no)
				(sheetname "")
			)
			(fill
				(thermal_gap 0.5)
				(thermal_bridge_width 0.5)
				(island_removal_mode 0)
			)
			(polygon
				(pts
					(xy 407.400506 -32.915352) (xy 407.908506 -32.915352) (xy 407.908506 -33.296352) (xy 407.400506 -33.296352)
				)
			)
		)
	)
	(footprint ""
		(layer "B.Cu")
		(at 444.649606 -52.342034)
		(property "Reference" "C2R7"
			(at 0 0 0)
			(layer "B.SilkS")
			(hide yes)
			(effects
				(font
					(size 1.27 1.27)
				)
				(justify mirror)
			)
		)
		(property "Value" ""
			(at 0 0 0)
			(layer "B.Fab")
			(effects
				(font
					(size 1.27 1.27)
				)
				(justify mirror)
			)
		)
		(duplicate_pad_numbers_are_jumpers no)
		(fp_poly
			(pts
				(xy -0.3048 -0.1016) (xy -0.3048 0.9906) (xy 0.3048 0.9906) (xy 0.3048 -0.1016)
			)
			(stroke
				(width 0)
				(type default)
			)
			(fill no)
			(layer "B.CrtYd")
		)
		(fp_line
			(start -0.3048 -0.1016)
			(end 0.3048 -0.1016)
			(stroke
				(width 0.1)
				(type default)
			)
			(layer "B.Fab")
		)
		(fp_line
			(start -0.3048 0.9906)
			(end -0.3048 -0.1016)
			(stroke
				(width 0.1)
				(type default)
			)
			(layer "B.Fab")
		)
		(fp_line
			(start 0.3048 -0.1016)
			(end 0.3048 0.9906)
			(stroke
				(width 0.1)
				(type default)
			)
			(layer "B.Fab")
		)
		(fp_line
			(start 0.3048 0.9906)
			(end -0.3048 0.9906)
			(stroke
				(width 0.1)
				(type default)
			)
			(layer "B.Fab")
		)
		(pad "1" smd rect
			(at 0 0 180)
			(size 0.508 0.508)
			(layers "B.Cu" "B.Mask" "B.Paste")
			(net "P3E_CPU0_PE3_OCP_TXN<6>")
		)
		(pad "2" smd rect
			(at 0 0.889 180)
			(size 0.508 0.508)
			(layers "B.Cu" "B.Mask" "B.Paste")
			(net "P3E_OCP_CPU0_PE3_C_TXN<6>")
		)
		(zone
			(layer "B.Cu")
			(hatch none 0.5)
			(connect_pads
				(clearance 0)
			)
			(min_thickness 0.25)
			(keepout
				(tracks allowed)
				(vias not_allowed)
				(pads allowed)
				(copperpour not_allowed)
				(footprints allowed)
			)
			(placement
				(enabled no)
				(sheetname "")
			)
			(fill
				(thermal_gap 0.5)
				(thermal_bridge_width 0.5)
				(island_removal_mode 0)
			)
			(polygon
				(pts
					(xy 444.903606 -52.088034) (xy 444.395606 -52.088034) (xy 444.395606 -51.707034) (xy 444.903606 -51.707034)
				)
			)
		)
		(zone
			(layer "B.Cu")
			(hatch none 0.5)
			(connect_pads
				(clearance 0)
			)
			(min_thickness 0.25)
			(keepout
				(tracks not_allowed)
				(vias allowed)
				(pads allowed)
				(copperpour not_allowed)
				(footprints allowed)
			)
			(placement
				(enabled no)
				(sheetname "")
			)
			(fill
				(thermal_gap 0.5)
				(thermal_bridge_width 0.5)
				(island_removal_mode 0)
			)
			(polygon
				(pts
					(xy 444.903606 -51.707034) (xy 444.395606 -51.707034) (xy 444.395606 -52.088034) (xy 444.903606 -52.088034)
				)
			)
		)
	)
	(footprint ""
		(layer "B.Cu")
		(at 346.72524 -10.28446 -90)
		(property "Reference" "C7G35"
			(at 0 0 90)
			(layer "B.SilkS")
			(hide yes)
			(effects
				(font
					(size 1.27 1.27)
				)
				(justify mirror)
			)
		)
		(property "Value" "*"
			(at -1.1811 -2.8194 270)
			(unlocked yes)
			(layer "B.Fab")
			(hide yes)
			(effects
				(font
					(size 1.27 1.016)
					(thickness 0.1524)
				)
				(justify mirror)
			)
		)
		(property "Device Type" "SC1U10V2KX-4-GP_SMD-BCG6-SC1U1A"
			(at -1.1811 -4.3434 270)
			(unlocked yes)
			(layer "B.Fab")
			(hide yes)
			(effects
				(font
					(size 1.27 1.016)
					(thickness 0.1524)
				)
				(justify mirror)
			)
		)
		(duplicate_pad_numbers_are_jumpers no)
		(fp_rect
			(start 0.4318 0.9525)
			(end -0.4318 -0.9525)
			(stroke
				(width 0)
				(type default)
			)
			(fill no)
			(layer "B.CrtYd")
		)
		(fp_rect
			(start 0.4318 0.9525)
			(end -0.4318 -0.9525)
			(stroke
				(width 0)
				(type default)
			)
			(fill no)
			(layer "B.Fab")
		)
		(pad "1" smd custom
			(at 0 -0.4445 90)
			(size 0.1524 0.1524)
			(layers "B.Cu" "B.Mask" "B.Paste")
			(net "P5V_STBY")
			(options
				(clearance outline)
				(anchor circle)
			)
			(primitives
				(gr_poly
					(pts
						(arc
							(start 0.3048 0.2032)
							(mid 0.275042 0.275042)
							(end 0.2032 0.3048)
						)
						(arc
							(start -0.2032 0.3048)
							(mid -0.275042 0.275042)
							(end -0.3048 0.2032)
						)
						(arc
							(start -0.3048 -0.2032)
							(mid -0.275042 -0.275042)
							(end -0.2032 -0.3048)
						)
						(arc
							(start 0.2032 -0.3048)
							(mid 0.275042 -0.275042)
							(end 0.3048 -0.2032)
						)
					)
					(width 0)
					(fill yes)
				)
			)
		)
		(pad "2" smd custom
			(at 0 0.4445 90)
			(size 0.1524 0.1524)
			(layers "B.Cu" "B.Mask" "B.Paste")
			(net "GND")
			(options
				(clearance outline)
				(anchor circle)
			)
			(primitives
				(gr_poly
					(pts
						(arc
							(start 0.3048 0.2032)
							(mid 0.275042 0.275042)
							(end 0.2032 0.3048)
						)
						(arc
							(start -0.2032 0.3048)
							(mid -0.275042 0.275042)
							(end -0.3048 0.2032)
						)
						(arc
							(start -0.3048 -0.2032)
							(mid -0.275042 -0.275042)
							(end -0.2032 -0.3048)
						)
						(arc
							(start 0.2032 -0.3048)
							(mid 0.275042 -0.275042)
							(end 0.3048 -0.2032)
						)
					)
					(width 0)
					(fill yes)
				)
			)
		)
	)
	(footprint ""
		(layer "B.Cu")
		(at 470.8906 -131.2164 180)
		(property "Reference" "CR6W1"
			(at -1.06934 -0.39116 270)
			(unlocked yes)
			(layer "B.SilkS")
			(effects
				(font
					(size 0.4064 0.254)
					(thickness 0.1524)
				)
				(justify left mirror)
			)
		)
		(property "Value" ""
			(at 0 0 0)
			(layer "B.Fab")
			(effects
				(font
					(size 1.27 1.27)
				)
				(justify mirror)
			)
		)
		(duplicate_pad_numbers_are_jumpers no)
		(fp_line
			(start 1.18237 1.568958)
			(end 0.701548 0.736092)
			(stroke
				(width 0.1524)
				(type default)
			)
			(layer "B.SilkS")
		)
		(fp_line
			(start 0.701548 2.480564)
			(end 0.701548 1.568958)
			(stroke
				(width 0.1524)
				(type default)
			)
			(layer "B.SilkS")
		)
		(fp_line
			(start 0.701548 1.568958)
			(end 1.18237 1.568958)
			(stroke
				(width 0.1524)
				(type default)
			)
			(layer "B.SilkS")
		)
		(fp_line
			(start 0.701548 0.736092)
			(end 0.220726 1.568958)
			(stroke
				(width 0.1524)
				(type default)
			)
			(layer "B.SilkS")
		)
		(fp_line
			(start 0.701548 -0.38735)
			(end 0.701548 0.736092)
			(stroke
				(width 0.1524)
				(type default)
			)
			(layer "B.SilkS")
		)
		(fp_line
			(start 0.220726 1.568958)
			(end 0.701548 1.568958)
			(stroke
				(width 0.1524)
				(type default)
			)
			(layer "B.SilkS")
		)
		(fp_line
			(start 0.220726 0.736092)
			(end 1.18237 0.736092)
			(stroke
				(width 0.1524)
				(type default)
			)
			(layer "B.SilkS")
		)
		(fp_poly
			(pts
				(xy 0.67437 0.24384) (xy 0.67437 2.04216) (xy -0.67437 2.04216) (xy -0.67437 0.24384)
			)
			(stroke
				(width 0)
				(type default)
			)
			(fill no)
			(layer "B.CrtYd")
		)
		(fp_line
			(start 1.17602 1.554734)
			(end 0.695198 0.721868)
			(stroke
				(width 0.1)
				(type default)
			)
			(layer "B.Fab")
		)
		(fp_line
			(start 0.695198 1.554734)
			(end 0.695198 2.46634)
			(stroke
				(width 0.1)
				(type default)
			)
			(layer "B.Fab")
		)
		(fp_line
			(start 0.695198 0.721868)
			(end 0.695198 -0.401574)
			(stroke
				(width 0.1)
				(type default)
			)
			(layer "B.Fab")
		)
		(fp_line
			(start 0.695198 0.721868)
			(end 0.214376 1.554734)
			(stroke
				(width 0.1)
				(type default)
			)
			(layer "B.Fab")
		)
		(fp_line
			(start 0.67437 2.04216)
			(end -0.67437 2.04216)
			(stroke
				(width 0.1)
				(type default)
			)
			(layer "B.Fab")
		)
		(fp_line
			(start 0.67437 0.24384)
			(end 0.67437 2.04216)
			(stroke
				(width 0.1)
				(type default)
			)
			(layer "B.Fab")
		)
		(fp_line
			(start 0.214376 1.554734)
			(end 1.17602 1.554734)
			(stroke
				(width 0.1)
				(type default)
			)
			(layer "B.Fab")
		)
		(fp_line
			(start 0.214376 0.721868)
			(end 1.17602 0.721868)
			(stroke
				(width 0.1)
				(type default)
			)
			(layer "B.Fab")
		)
		(fp_line
			(start -0.67437 2.04216)
			(end -0.67437 0.24384)
			(stroke
				(width 0.1)
				(type default)
			)
			(layer "B.Fab")
		)
		(fp_line
			(start -0.67437 0.24384)
			(end 0.67437 0.24384)
			(stroke
				(width 0.1)
				(type default)
			)
			(layer "B.Fab")
		)
		(pad "1" smd rect
			(at 0 0)
			(size 0.4064 1.016)
			(layers "B.Cu" "B.Mask" "B.Paste")
			(net "FM_CPU_CATERR_LVT3_N")
		)
		(pad "2" smd rect
			(at 0 2.286)
			(size 0.4064 1.016)
			(layers "B.Cu" "B.Mask" "B.Paste")
			(net "FM_CPU_CATERR_MSMI_LVT3_N")
		)
	)
	(footprint ""
		(layer "B.Cu")
		(at 278.703024 -71.714614 180)
		(property "Reference" "C4P9"
			(at 0 0 0)
			(layer "B.SilkS")
			(hide yes)
			(effects
				(font
					(size 1.27 1.27)
				)
				(justify mirror)
			)
		)
		(property "Value" ""
			(at 0 0 0)
			(layer "B.Fab")
			(effects
				(font
					(size 1.27 1.27)
				)
				(justify mirror)
			)
		)
		(duplicate_pad_numbers_are_jumpers no)
		(fp_poly
			(pts
				(xy 0.7239 -0.2159) (xy -0.7239 -0.2159) (xy -0.7239 1.9939) (xy 0.7239 1.9939)
			)
			(stroke
				(width 0)
				(type default)
			)
			(fill no)
			(layer "B.CrtYd")
		)
		(fp_line
			(start 0.7239 1.9939)
			(end -0.7239 1.9939)
			(stroke
				(width 0.1)
				(type default)
			)
			(layer "B.Fab")
		)
		(fp_line
			(start 0.7239 -0.2159)
			(end 0.7239 1.9939)
			(stroke
				(width 0.1)
				(type default)
			)
			(layer "B.Fab")
		)
		(fp_line
			(start -0.7239 1.9939)
			(end -0.7239 -0.2159)
			(stroke
				(width 0.1)
				(type default)
			)
			(layer "B.Fab")
		)
		(fp_line
			(start -0.7239 -0.2159)
			(end 0.7239 -0.2159)
			(stroke
				(width 0.1)
				(type default)
			)
			(layer "B.Fab")
		)
		(pad "1" smd rect
			(at 0 0)
			(size 1.27 1.016)
			(layers "B.Cu" "B.Mask" "B.Paste")
			(net "PVCCIO_CPU0")
		)
		(pad "2" smd rect
			(at 0 1.778)
			(size 1.27 1.016)
			(layers "B.Cu" "B.Mask" "B.Paste")
			(net "GND")
		)
		(zone
			(layer "B.Cu")
			(hatch none 0.5)
			(connect_pads
				(clearance 0)
			)
			(min_thickness 0.25)
			(keepout
				(tracks not_allowed)
				(vias allowed)
				(pads allowed)
				(copperpour not_allowed)
				(footprints allowed)
			)
			(placement
				(enabled no)
				(sheetname "")
			)
			(fill
				(thermal_gap 0.5)
				(thermal_bridge_width 0.5)
				(island_removal_mode 0)
			)
			(polygon
				(pts
					(xy 278.068024 -72.222614) (xy 279.338024 -72.222614) (xy 279.338024 -72.984614) (xy 278.068024 -72.984614)
				)
			)
		)
	)
	(footprint ""
		(layer "B.Cu")
		(at 32.832802 -64.774064 90)
		(property "Reference" "C9P26"
			(at 0 0 90)
			(layer "B.SilkS")
			(hide yes)
			(effects
				(font
					(size 1.27 1.27)
				)
				(justify mirror)
			)
		)
		(property "Value" ""
			(at 0 0 90)
			(layer "B.Fab")
			(effects
				(font
					(size 1.27 1.27)
				)
				(justify mirror)
			)
		)
		(duplicate_pad_numbers_are_jumpers no)
		(fp_poly
			(pts
				(xy 0.7239 -0.2159) (xy -0.7239 -0.2159) (xy -0.7239 1.9939) (xy 0.7239 1.9939)
			)
			(stroke
				(width 0)
				(type default)
			)
			(fill no)
			(layer "B.CrtYd")
		)
		(fp_line
			(start 0.7239 -0.2159)
			(end 0.7239 1.9939)
			(stroke
				(width 0.1)
				(type default)
			)
			(layer "B.Fab")
		)
		(fp_line
			(start -0.7239 -0.2159)
			(end 0.7239 -0.2159)
			(stroke
				(width 0.1)
				(type default)
			)
			(layer "B.Fab")
		)
		(fp_line
			(start 0.7239 1.9939)
			(end -0.7239 1.9939)
			(stroke
				(width 0.1)
				(type default)
			)
			(layer "B.Fab")
		)
		(fp_line
			(start -0.7239 1.9939)
			(end -0.7239 -0.2159)
			(stroke
				(width 0.1)
				(type default)
			)
			(layer "B.Fab")
		)
		(pad "1" smd rect
			(at 0 0 270)
			(size 1.27 1.016)
			(layers "B.Cu" "B.Mask" "B.Paste")
			(net "VR_FET_SW_P12V_STBY_PVCCIN_CPU1")
		)
		(pad "2" smd rect
			(at 0 1.778 270)
			(size 1.27 1.016)
			(layers "B.Cu" "B.Mask" "B.Paste")
			(net "GND")
		)
		(zone
			(layer "B.Cu")
			(hatch none 0.5)
			(connect_pads
				(clearance 0)
			)
			(min_thickness 0.25)
			(keepout
				(tracks not_allowed)
				(vias allowed)
				(pads allowed)
				(copperpour not_allowed)
				(footprints allowed)
			)
			(placement
				(enabled no)
				(sheetname "")
			)
			(fill
				(thermal_gap 0.5)
				(thermal_bridge_width 0.5)
				(island_removal_mode 0)
			)
			(polygon
				(pts
					(xy 33.340802 -65.409064) (xy 33.340802 -64.139064) (xy 34.102802 -64.139064) (xy 34.102802 -65.409064)
				)
			)
		)
	)
	(footprint ""
		(layer "B.Cu")
		(at 11.313668 -3.321812 180)
		(property "Reference" "R9U4"
			(at 0 0 0)
			(layer "B.SilkS")
			(hide yes)
			(effects
				(font
					(size 1.27 1.27)
				)
				(justify mirror)
			)
		)
		(property "Value" ""
			(at 0 0 0)
			(layer "B.Fab")
			(effects
				(font
					(size 1.27 1.27)
				)
				(justify mirror)
			)
		)
		(duplicate_pad_numbers_are_jumpers no)
		(fp_rect
			(start 0.2794 0.9906)
			(end -0.2794 -0.1016)
			(stroke
				(width 0)
				(type default)
			)
			(fill no)
			(layer "B.CrtYd")
		)
		(fp_line
			(start 0.2794 0.9906)
			(end -0.2794 0.9906)
			(stroke
				(width 0.1)
				(type default)
			)
			(layer "B.Fab")
		)
		(fp_line
			(start 0.2794 -0.1016)
			(end 0.2794 0.9906)
			(stroke
				(width 0.1)
				(type default)
			)
			(layer "B.Fab")
		)
		(fp_line
			(start -0.2794 0.9906)
			(end -0.2794 -0.1016)
			(stroke
				(width 0.1)
				(type default)
			)
			(layer "B.Fab")
		)
		(fp_line
			(start -0.2794 -0.1016)
			(end 0.2794 -0.1016)
			(stroke
				(width 0.1)
				(type default)
			)
			(layer "B.Fab")
		)
		(pad "1" smd rect
			(at 0 0)
			(size 0.508 0.508)
			(layers "B.Cu" "B.Mask" "B.Paste")
			(net "PVCCIO_CPU1")
		)
		(pad "2" smd rect
			(at 0 0.889)
			(size 0.508 0.508)
			(layers "B.Cu" "B.Mask" "B.Paste")
			(net "SVID_CLK1_CPU1_R")
		)
		(zone
			(layer "B.Cu")
			(hatch none 0.5)
			(connect_pads
				(clearance 0)
			)
			(min_thickness 0.25)
			(keepout
				(tracks not_allowed)
				(vias allowed)
				(pads allowed)
				(copperpour not_allowed)
				(footprints allowed)
			)
			(placement
				(enabled no)
				(sheetname "")
			)
			(fill
				(thermal_gap 0.5)
				(thermal_bridge_width 0.5)
				(island_removal_mode 0)
			)
			(polygon
				(pts
					(xy 11.059668 -3.956812) (xy 11.059668 -3.575812) (xy 11.567668 -3.575812) (xy 11.567668 -3.956812)
				)
			)
		)
		(zone
			(layer "B.Cu")
			(hatch none 0.5)
			(connect_pads
				(clearance 0)
			)
			(min_thickness 0.25)
			(keepout
				(tracks allowed)
				(vias not_allowed)
				(pads allowed)
				(copperpour not_allowed)
				(footprints allowed)
			)
			(placement
				(enabled no)
				(sheetname "")
			)
			(fill
				(thermal_gap 0.5)
				(thermal_bridge_width 0.5)
				(island_removal_mode 0)
			)
			(polygon
				(pts
					(xy 11.059668 -3.956812) (xy 11.059668 -3.575812) (xy 11.567668 -3.575812) (xy 11.567668 -3.956812)
				)
			)
		)
	)
	(footprint ""
		(layer "B.Cu")
		(at 365.3028 -80.0354 -90)
		(property "Reference" "R3P34"
			(at 0 0 90)
			(layer "B.SilkS")
			(hide yes)
			(effects
				(font
					(size 1.27 1.27)
				)
				(justify mirror)
			)
		)
		(property "Value" ""
			(at 0 0 90)
			(layer "B.Fab")
			(effects
				(font
					(size 1.27 1.27)
				)
				(justify mirror)
			)
		)
		(duplicate_pad_numbers_are_jumpers no)
		(fp_poly
			(pts
				(xy 0.2794 -0.1016) (xy -0.2794 -0.1016) (xy -0.2794 0.9906) (xy 0.2794 0.9906)
			)
			(stroke
				(width 0)
				(type default)
			)
			(fill no)
			(layer "B.CrtYd")
		)
		(fp_line
			(start -0.2794 0.9906)
			(end -0.2794 -0.1016)
			(stroke
				(width 0.1)
				(type default)
			)
			(layer "B.Fab")
		)
		(fp_line
			(start 0.2794 0.9906)
			(end -0.2794 0.9906)
			(stroke
				(width 0.1)
				(type default)
			)
			(layer "B.Fab")
		)
		(fp_line
			(start -0.2794 -0.1016)
			(end 0.2794 -0.1016)
			(stroke
				(width 0.1)
				(type default)
			)
			(layer "B.Fab")
		)
		(fp_line
			(start 0.2794 -0.1016)
			(end 0.2794 0.9906)
			(stroke
				(width 0.1)
				(type default)
			)
			(layer "B.Fab")
		)
		(pad "1" smd rect
			(at 0 0 90)
			(size 0.508 0.508)
			(layers "B.Cu" "B.Mask" "B.Paste")
			(net "RST_CPU0_LVC3_R1_N")
		)
		(pad "2" smd rect
			(at 0 0.889 90)
			(size 0.508 0.508)
			(layers "B.Cu" "B.Mask" "B.Paste")
			(net "RST_CPU0_LVC3_N")
		)
		(zone
			(layer "B.Cu")
			(hatch none 0.5)
			(connect_pads
				(clearance 0)
			)
			(min_thickness 0.25)
			(keepout
				(tracks not_allowed)
				(vias allowed)
				(pads allowed)
				(copperpour not_allowed)
				(footprints allowed)
			)
			(placement
				(enabled no)
				(sheetname "")
			)
			(fill
				(thermal_gap 0.5)
				(thermal_bridge_width 0.5)
				(island_removal_mode 0)
			)
			(polygon
				(pts
					(xy 364.6678 -79.7814) (xy 364.6678 -80.2894) (xy 365.0488 -80.2894) (xy 365.0488 -79.7814)
				)
			)
		)
		(zone
			(layer "B.Cu")
			(hatch none 0.5)
			(connect_pads
				(clearance 0)
			)
			(min_thickness 0.25)
			(keepout
				(tracks allowed)
				(vias not_allowed)
				(pads allowed)
				(copperpour not_allowed)
				(footprints allowed)
			)
			(placement
				(enabled no)
				(sheetname "")
			)
			(fill
				(thermal_gap 0.5)
				(thermal_bridge_width 0.5)
				(island_removal_mode 0)
			)
			(polygon
				(pts
					(xy 365.0488 -79.7814) (xy 365.0488 -80.2894) (xy 364.6678 -80.2894) (xy 364.6678 -79.7814)
				)
			)
		)
	)
	(gr_line
		(start -3.429 -123.5456)
		(end -3.429 -124.333)
		(stroke
			(width 0.0635)
			(type default)
		)
		(layer "F.Cu")
	)
	(gr_circle
		(center -3.0734 -18.5674)
		(end -2.8194 -18.5674)
		(stroke
			(width 0.2)
			(type default)
		)
		(fill no)
		(layer "F.Cu")
	)
	(gr_line
		(start -2.5146 -124.3965)
		(end -2.3876 -124.5235)
		(stroke
			(width 0.0635)
			(type default)
		)
		(layer "F.Cu")
	)
	(gr_line
		(start -2.5146 -124.333)
		(end -2.5146 -124.3965)
		(stroke
			(width 0.0635)
			(type default)
		)
		(layer "F.Cu")
	)
	(gr_line
		(start -2.5146 -123.5456)
		(end -2.5146 -124.333)
		(stroke
			(width 0.0635)
			(type default)
		)
		(layer "F.Cu")
	)
	(gr_circle
		(center -2.447798 -18.567146)
		(end -2.193798 -18.567146)
		(stroke
			(width 0.2)
			(type default)
		)
		(fill no)
		(layer "F.Cu")
	)
	(gr_line
		(start -2.3876 -124.5235)
		(end -1.6129 -124.5235)
		(stroke
			(width 0.0635)
			(type default)
		)
		(layer "F.Cu")
	)
	(gr_line
		(start -1.6129 -124.5235)
		(end -0.3937 -125.7427)
		(stroke
			(width 0.0635)
			(type default)
		)
		(layer "F.Cu")
	)
	(gr_line
		(start -0.3937 -125.7427)
		(end -0.3937 -126.165102)
		(stroke
			(width 0.0635)
			(type default)
		)
		(layer "F.Cu")
	)
	(gr_poly
		(pts
			(xy 65.167764 -48.283114) (xy 65.155064 -48.092614) (xy 65.053464 -48.092614) (xy 65.040764 -48.283114)
			(xy 65.040764 -48.346614) (xy 65.167764 -48.346614)
		)
		(stroke
			(width 0)
			(type solid)
		)
		(fill yes)
		(layer "F.Cu")
		(net "M_H_DQ<28>")
	)
	(gr_poly
		(pts
			(xy 65.497964 -47.991014) (xy 65.497964 -47.940214) (xy 65.370964 -47.940214) (xy 65.370964 -47.991014)
			(xy 65.383664 -48.181514) (xy 65.485264 -48.181514)
		)
		(stroke
			(width 0)
			(type solid)
		)
		(fill yes)
		(layer "F.Cu")
		(net "M_H_DQ<29>")
	)
	(gr_poly
		(pts
			(xy 65.828164 -48.283114) (xy 65.815464 -48.092614) (xy 65.713864 -48.092614) (xy 65.701164 -48.283114)
			(xy 65.701164 -48.346614) (xy 65.828164 -48.346614)
		)
		(stroke
			(width 0)
			(type solid)
		)
		(fill yes)
		(layer "F.Cu")
		(net "M_H_DQ<28>")
	)
	(gr_poly
		(pts
			(xy 65.828164 -47.889414) (xy 65.815464 -47.698914) (xy 65.713864 -47.698914) (xy 65.701164 -47.889414)
			(xy 65.701164 -47.940214) (xy 65.828164 -47.940214)
		)
		(stroke
			(width 0)
			(type solid)
		)
		(fill yes)
		(layer "F.Cu")
		(net "M_H_DQ<29>")
	)
	(gr_poly
		(pts
			(xy 66.158364 -47.991014) (xy 66.158364 -47.940214) (xy 66.031364 -47.940214) (xy 66.031364 -47.991014)
			(xy 66.044064 -48.181514) (xy 66.145664 -48.181514)
		)
		(stroke
			(width 0)
			(type solid)
		)
		(fill yes)
		(layer "F.Cu")
		(net "M_H_DQ<29>")
	)
	(gr_poly
		(pts
			(xy 66.158364 -47.597314) (xy 66.158364 -47.546514) (xy 66.031364 -47.546514) (xy 66.031364 -47.597314)
			(xy 66.044064 -47.787814) (xy 66.145664 -47.787814)
		)
		(stroke
			(width 0)
			(type solid)
		)
		(fill yes)
		(layer "F.Cu")
		(net "M_H_DQ<24>")
	)
	(gr_poly
		(pts
			(xy 66.488564 -48.283114) (xy 66.475864 -48.092614) (xy 66.374264 -48.092614) (xy 66.361564 -48.283114)
			(xy 66.361564 -48.346614) (xy 66.488564 -48.346614)
		)
		(stroke
			(width 0)
			(type solid)
		)
		(fill yes)
		(layer "F.Cu")
		(net "M_H_DQ<28>")
	)
	(gr_poly
		(pts
			(xy 66.488564 -47.889414) (xy 66.475864 -47.698914) (xy 66.374264 -47.698914) (xy 66.361564 -47.889414)
			(xy 66.361564 -47.940214) (xy 66.488564 -47.940214)
		)
		(stroke
			(width 0)
			(type solid)
		)
		(fill yes)
		(layer "F.Cu")
		(net "M_H_DQ<29>")
	)
	(gr_poly
		(pts
			(xy 66.488564 -47.495714) (xy 66.475864 -47.305214) (xy 66.374264 -47.305214) (xy 66.361564 -47.495714)
			(xy 66.361564 -47.546514) (xy 66.488564 -47.546514)
		)
		(stroke
			(width 0)
			(type solid)
		)
		(fill yes)
		(layer "F.Cu")
		(net "M_H_DQ<24>")
	)
	(gr_poly
		(pts
			(xy 66.756788 -48.37811) (xy 66.882518 -48.234346) (xy 66.810636 -48.162464) (xy 66.667126 -48.288194)
			(xy 66.622168 -48.333152) (xy 66.71183 -48.422814)
		)
		(stroke
			(width 0)
			(type solid)
		)
		(fill yes)
		(layer "F.Cu")
		(net "M_H_DQ<28>")
	)
	(gr_poly
		(pts
			(xy 66.818764 -47.597314) (xy 66.818764 -47.546514) (xy 66.691764 -47.546514) (xy 66.691764 -47.597314)
			(xy 66.704464 -47.787814) (xy 66.806064 -47.787814)
		)
		(stroke
			(width 0)
			(type solid)
		)
		(fill yes)
		(layer "F.Cu")
		(net "M_H_DQ<24>")
	)
	(gr_poly
		(pts
			(xy 66.818764 -47.203614) (xy 66.818764 -47.152814) (xy 66.691764 -47.152814) (xy 66.691764 -47.203614)
			(xy 66.704464 -47.394114) (xy 66.806064 -47.394114)
		)
		(stroke
			(width 0)
			(type solid)
		)
		(fill yes)
		(layer "F.Cu")
		(net "M_H_DQ<25>")
	)
	(gr_poly
		(pts
			(xy 67.035172 -48.099726) (xy 67.160902 -47.955962) (xy 67.089274 -47.88408) (xy 66.94551 -48.00981)
			(xy 66.909442 -48.045624) (xy 66.999358 -48.13554)
		)
		(stroke
			(width 0)
			(type solid)
		)
		(fill yes)
		(layer "F.Cu")
		(net "M_H_DQ<29>")
	)
	(gr_poly
		(pts
			(xy 67.148964 -47.102014) (xy 67.136264 -46.911514) (xy 67.034664 -46.911514) (xy 67.021964 -47.102014)
			(xy 67.021964 -47.152814) (xy 67.148964 -47.152814)
		)
		(stroke
			(width 0)
			(type solid)
		)
		(fill yes)
		(layer "F.Cu")
		(net "M_H_DQ<25>")
	)
	(gr_poly
		(pts
			(xy 67.197224 -48.405288) (xy 67.233292 -48.369474) (xy 67.143376 -48.279558) (xy 67.107562 -48.315626)
			(xy 66.981832 -48.459136) (xy 67.053714 -48.531018)
		)
		(stroke
			(width 0)
			(type solid)
		)
		(fill yes)
		(layer "F.Cu")
		(net "M_H_DQ<29>")
	)
	(gr_poly
		(pts
			(xy 67.224148 -48.84547) (xy 67.349878 -48.701706) (xy 67.277996 -48.629824) (xy 67.134486 -48.755554)
			(xy 67.089528 -48.800512) (xy 67.17919 -48.890174)
		)
		(stroke
			(width 0)
			(type solid)
		)
		(fill yes)
		(layer "F.Cu")
		(net "M_H_DQ<28>")
	)
	(gr_poly
		(pts
			(xy 67.286886 -47.380906) (xy 67.322954 -47.345092) (xy 67.233038 -47.255176) (xy 67.197224 -47.291244)
			(xy 67.071494 -47.434754) (xy 67.143376 -47.506636)
		)
		(stroke
			(width 0)
			(type solid)
		)
		(fill yes)
		(layer "F.Cu")
		(net "M_H_DQ<25>")
	)
	(gr_poly
		(pts
			(xy 67.314064 -47.821596) (xy 67.439794 -47.677832) (xy 67.368166 -47.60595) (xy 67.224402 -47.73168)
			(xy 67.188334 -47.767494) (xy 67.27825 -47.85741)
		)
		(stroke
			(width 0)
			(type solid)
		)
		(fill yes)
		(layer "F.Cu")
		(net "M_H_DQ<24>")
	)
	(gr_poly
		(pts
			(xy 67.403726 -46.797214) (xy 67.529456 -46.65345) (xy 67.457828 -46.581568) (xy 67.314064 -46.707298)
			(xy 67.277996 -46.743112) (xy 67.367912 -46.833028)
		)
		(stroke
			(width 0)
			(type solid)
		)
		(fill yes)
		(layer "F.Cu")
		(net "M_H_DQS_DP<12>")
	)
	(gr_poly
		(pts
			(xy 67.475862 -48.126904) (xy 67.511676 -48.090836) (xy 67.422014 -48.001174) (xy 67.385946 -48.036988)
			(xy 67.260216 -48.180752) (xy 67.332098 -48.252634)
		)
		(stroke
			(width 0)
			(type solid)
		)
		(fill yes)
		(layer "F.Cu")
		(net "M_H_DQ<24>")
	)
	(gr_poly
		(pts
			(xy 67.502532 -48.567086) (xy 67.628262 -48.423322) (xy 67.556634 -48.35144) (xy 67.41287 -48.47717)
			(xy 67.376802 -48.512984) (xy 67.466718 -48.6029)
		)
		(stroke
			(width 0)
			(type solid)
		)
		(fill yes)
		(layer "F.Cu")
		(net "M_H_DQ<29>")
	)
	(gr_poly
		(pts
			(xy 67.565778 -47.102776) (xy 67.601846 -47.066962) (xy 67.51193 -46.977046) (xy 67.476116 -47.013114)
			(xy 67.350386 -47.156624) (xy 67.422268 -47.228506)
		)
		(stroke
			(width 0)
			(type solid)
		)
		(fill yes)
		(layer "F.Cu")
		(net "M_H_DQS_DP<12>")
	)
	(gr_poly
		(pts
			(xy 67.592702 -47.542958) (xy 67.718432 -47.399194) (xy 67.64655 -47.327566) (xy 67.502786 -47.453296)
			(xy 67.466972 -47.48911) (xy 67.556888 -47.579026)
		)
		(stroke
			(width 0)
			(type solid)
		)
		(fill yes)
		(layer "F.Cu")
		(net "M_H_DQ<25>")
	)
	(gr_poly
		(pts
			(xy 67.65544 -46.078394) (xy 67.691508 -46.04258) (xy 67.601592 -45.952664) (xy 67.565778 -45.988732)
			(xy 67.440048 -46.132242) (xy 67.51193 -46.204124)
		)
		(stroke
			(width 0)
			(type solid)
		)
		(fill yes)
		(layer "F.Cu")
		(net "M_H_DQS_DN<3>")
	)
	(gr_poly
		(pts
			(xy 67.66433 -48.872394) (xy 67.700144 -48.836326) (xy 67.610482 -48.746664) (xy 67.574414 -48.782478)
			(xy 67.448684 -48.926242) (xy 67.520566 -48.998124)
		)
		(stroke
			(width 0)
			(type solid)
		)
		(fill yes)
		(layer "F.Cu")
		(net "M_H_DQ<29>")
	)
	(gr_poly
		(pts
			(xy 67.682364 -46.518576) (xy 67.808094 -46.374812) (xy 67.736212 -46.303184) (xy 67.592448 -46.428914)
			(xy 67.556634 -46.464728) (xy 67.64655 -46.554644)
		)
		(stroke
			(width 0)
			(type solid)
		)
		(fill yes)
		(layer "F.Cu")
		(net "M_H_DQS_DN<12>")
	)
	(gr_poly
		(pts
			(xy 67.691508 -49.31283) (xy 67.817238 -49.169066) (xy 67.745356 -49.097184) (xy 67.601846 -49.222914)
			(xy 67.556888 -49.267872) (xy 67.64655 -49.357534)
		)
		(stroke
			(width 0)
			(type solid)
		)
		(fill yes)
		(layer "F.Cu")
		(net "M_H_DQ<28>")
	)
	(gr_poly
		(pts
			(xy 67.754246 -47.848266) (xy 67.790314 -47.812452) (xy 67.700398 -47.722536) (xy 67.664584 -47.758604)
			(xy 67.538854 -47.902114) (xy 67.610736 -47.973996)
		)
		(stroke
			(width 0)
			(type solid)
		)
		(fill yes)
		(layer "F.Cu")
		(net "M_H_DQ<25>")
	)
	(gr_poly
		(pts
			(xy 67.78117 -48.288448) (xy 67.9069 -48.144684) (xy 67.835018 -48.073056) (xy 67.691254 -48.198786)
			(xy 67.65544 -48.2346) (xy 67.745102 -48.324262)
		)
		(stroke
			(width 0)
			(type solid)
		)
		(fill yes)
		(layer "F.Cu")
		(net "M_H_DQ<24>")
	)
	(gr_poly
		(pts
			(xy 67.844416 -46.824392) (xy 67.88023 -46.788324) (xy 67.790568 -46.698662) (xy 67.7545 -46.734476)
			(xy 67.62877 -46.87824) (xy 67.700652 -46.950122)
		)
		(stroke
			(width 0)
			(type solid)
		)
		(fill yes)
		(layer "F.Cu")
		(net "M_H_DQS_DN<12>")
	)
	(gr_poly
		(pts
			(xy 67.871086 -47.264574) (xy 67.996816 -47.12081) (xy 67.925188 -47.048928) (xy 67.781424 -47.174658)
			(xy 67.745356 -47.210472) (xy 67.835272 -47.300388)
		)
		(stroke
			(width 0)
			(type solid)
		)
		(fill yes)
		(layer "F.Cu")
		(net "M_H_DQS_DP<12>")
	)
	(gr_poly
		(pts
			(xy 67.934078 -45.80001) (xy 67.969892 -45.763942) (xy 67.88023 -45.67428) (xy 67.844162 -45.710094)
			(xy 67.718432 -45.853858) (xy 67.790314 -45.92574)
		)
		(stroke
			(width 0)
			(type solid)
		)
		(fill yes)
		(layer "F.Cu")
		(net "M_H_DQS_DP<3>")
	)
	(gr_poly
		(pts
			(xy 67.943222 -48.594264) (xy 67.979036 -48.558196) (xy 67.889374 -48.468534) (xy 67.853306 -48.504348)
			(xy 67.727576 -48.648112) (xy 67.799458 -48.719994)
		)
		(stroke
			(width 0)
			(type solid)
		)
		(fill yes)
		(layer "F.Cu")
		(net "M_H_DQ<24>")
	)
	(gr_poly
		(pts
			(xy 67.961256 -46.240446) (xy 68.086986 -46.096682) (xy 68.015104 -46.025054) (xy 67.87134 -46.150784)
			(xy 67.835526 -46.186598) (xy 67.925442 -46.276514)
		)
		(stroke
			(width 0)
			(type solid)
		)
		(fill yes)
		(layer "F.Cu")
		(net "M_H_DQS_DN<3>")
	)
	(gr_poly
		(pts
			(xy 67.969892 -49.034446) (xy 68.095622 -48.890682) (xy 68.023994 -48.8188) (xy 67.88023 -48.94453)
			(xy 67.844162 -48.980344) (xy 67.934078 -49.07026)
		)
		(stroke
			(width 0)
			(type solid)
		)
		(fill yes)
		(layer "F.Cu")
		(net "M_H_DQ<29>")
	)
	(gr_poly
		(pts
			(xy 68.032884 -47.569882) (xy 68.068698 -47.533814) (xy 67.979036 -47.444152) (xy 67.942968 -47.479966)
			(xy 67.817238 -47.62373) (xy 67.88912 -47.695612)
		)
		(stroke
			(width 0)
			(type solid)
		)
		(fill yes)
		(layer "F.Cu")
		(net "M_H_DQS_DP<12>")
	)
	(gr_poly
		(pts
			(xy 68.060062 -48.010318) (xy 68.185792 -47.866554) (xy 68.11391 -47.794926) (xy 67.970146 -47.920656)
			(xy 67.934332 -47.95647) (xy 68.024248 -48.046386)
		)
		(stroke
			(width 0)
			(type solid)
		)
		(fill yes)
		(layer "F.Cu")
		(net "M_H_DQ<25>")
	)
	(gr_poly
		(pts
			(xy 68.1228 -46.545754) (xy 68.158868 -46.50994) (xy 68.068952 -46.420024) (xy 68.033138 -46.456092)
			(xy 67.907408 -46.599602) (xy 67.97929 -46.671484)
		)
		(stroke
			(width 0)
			(type solid)
		)
		(fill yes)
		(layer "F.Cu")
		(net "M_H_DQS_DN<3>")
	)
	(gr_poly
		(pts
			(xy 68.130928 -49.17059) (xy 68.130928 -49.11979) (xy 68.003928 -49.11979) (xy 68.003928 -49.17059)
			(xy 68.016628 -49.36109) (xy 68.118228 -49.36109)
		)
		(stroke
			(width 0)
			(type solid)
		)
		(fill yes)
		(layer "F.Cu")
		(net "M_H_DQ<29>")
	)
	(gr_poly
		(pts
			(xy 68.149724 -46.985936) (xy 68.275454 -46.842172) (xy 68.203572 -46.770544) (xy 68.059808 -46.896274)
			(xy 68.023994 -46.932088) (xy 68.11391 -47.022004)
		)
		(stroke
			(width 0)
			(type solid)
		)
		(fill yes)
		(layer "F.Cu")
		(net "M_H_DQS_DN<12>")
	)
	(gr_poly
		(pts
			(xy 68.212462 -45.521372) (xy 68.24853 -45.485558) (xy 68.158614 -45.395642) (xy 68.1228 -45.43171)
			(xy 67.99707 -45.57522) (xy 68.068952 -45.647102)
		)
		(stroke
			(width 0)
			(type solid)
		)
		(fill yes)
		(layer "F.Cu")
		(net "M_H_DQ<30>")
	)
	(gr_poly
		(pts
			(xy 68.221606 -48.315626) (xy 68.257674 -48.279812) (xy 68.167758 -48.189896) (xy 68.131944 -48.225964)
			(xy 68.006214 -48.369474) (xy 68.078096 -48.441356)
		)
		(stroke
			(width 0)
			(type solid)
		)
		(fill yes)
		(layer "F.Cu")
		(net "M_H_DQ<25>")
	)
	(gr_poly
		(pts
			(xy 68.23964 -45.962062) (xy 68.36537 -45.818298) (xy 68.293742 -45.746416) (xy 68.149978 -45.872146)
			(xy 68.11391 -45.90796) (xy 68.203826 -45.997876)
		)
		(stroke
			(width 0)
			(type solid)
		)
		(fill yes)
		(layer "F.Cu")
		(net "M_H_DQS_DP<3>")
	)
	(gr_poly
		(pts
			(xy 68.311268 -47.291244) (xy 68.347336 -47.25543) (xy 68.25742 -47.165514) (xy 68.221606 -47.201582)
			(xy 68.095876 -47.345092) (xy 68.167758 -47.416974)
		)
		(stroke
			(width 0)
			(type solid)
		)
		(fill yes)
		(layer "F.Cu")
		(net "M_H_DQS_DN<12>")
	)
	(gr_poly
		(pts
			(xy 68.338446 -47.731934) (xy 68.464176 -47.58817) (xy 68.392548 -47.516288) (xy 68.248784 -47.642018)
			(xy 68.212716 -47.677832) (xy 68.302632 -47.767748)
		)
		(stroke
			(width 0)
			(type solid)
		)
		(fill yes)
		(layer "F.Cu")
		(net "M_H_DQS_DP<12>")
	)
	(gr_poly
		(pts
			(xy 68.401438 -46.26737) (xy 68.437252 -46.231302) (xy 68.34759 -46.14164) (xy 68.311522 -46.177454)
			(xy 68.185792 -46.321218) (xy 68.257674 -46.3931)
		)
		(stroke
			(width 0)
			(type solid)
		)
		(fill yes)
		(layer "F.Cu")
		(net "M_H_DQS_DP<3>")
	)
	(gr_poly
		(pts
			(xy 68.428108 -46.707552) (xy 68.553838 -46.563788) (xy 68.48221 -46.491906) (xy 68.338446 -46.617636)
			(xy 68.302378 -46.65345) (xy 68.392294 -46.743366)
		)
		(stroke
			(width 0)
			(type solid)
		)
		(fill yes)
		(layer "F.Cu")
		(net "M_H_DQS_DN<3>")
	)
	(gr_poly
		(pts
			(xy 68.461128 -49.46269) (xy 68.448428 -49.27219) (xy 68.346828 -49.27219) (xy 68.334128 -49.46269)
			(xy 68.334128 -49.52619) (xy 68.461128 -49.52619)
		)
		(stroke
			(width 0)
			(type solid)
		)
		(fill yes)
		(layer "F.Cu")
		(net "M_H_DQ<28>")
	)
	(gr_poly
		(pts
			(xy 68.461128 -49.06899) (xy 68.448428 -48.87849) (xy 68.346828 -48.87849) (xy 68.334128 -49.06899)
			(xy 68.334128 -49.11979) (xy 68.461128 -49.11979)
		)
		(stroke
			(width 0)
			(type solid)
		)
		(fill yes)
		(layer "F.Cu")
		(net "M_H_DQ<29>")
	)
	(gr_poly
		(pts
			(xy 68.461128 -48.67529) (xy 68.448428 -48.48479) (xy 68.346828 -48.48479) (xy 68.334128 -48.67529)
			(xy 68.334128 -48.72609) (xy 68.461128 -48.72609)
		)
		(stroke
			(width 0)
			(type solid)
		)
		(fill yes)
		(layer "F.Cu")
		(net "M_H_DQ<24>")
	)
	(gr_poly
		(pts
			(xy 68.518278 -45.683424) (xy 68.644008 -45.53966) (xy 68.57238 -45.467778) (xy 68.428616 -45.593508)
			(xy 68.392548 -45.629322) (xy 68.482464 -45.719238)
		)
		(stroke
			(width 0)
			(type solid)
		)
		(fill yes)
		(layer "F.Cu")
		(net "M_H_DQ<30>")
	)
	(gr_poly
		(pts
			(xy 68.59016 -47.013114) (xy 68.626228 -46.9773) (xy 68.536312 -46.887384) (xy 68.500498 -46.923452)
			(xy 68.374768 -47.066962) (xy 68.44665 -47.138844)
		)
		(stroke
			(width 0)
			(type solid)
		)
		(fill yes)
		(layer "F.Cu")
		(net "M_H_DQS_DN<3>")
	)
	(gr_poly
		(pts
			(xy 68.617084 -47.453296) (xy 68.742814 -47.309532) (xy 68.670932 -47.237904) (xy 68.527168 -47.363634)
			(xy 68.491354 -47.399448) (xy 68.58127 -47.489364)
		)
		(stroke
			(width 0)
			(type solid)
		)
		(fill yes)
		(layer "F.Cu")
		(net "M_H_DQS_DN<12>")
	)
	(gr_poly
		(pts
			(xy 68.679822 -45.988732) (xy 68.71589 -45.952918) (xy 68.625974 -45.863002) (xy 68.59016 -45.89907)
			(xy 68.46443 -46.04258) (xy 68.536312 -46.114462)
		)
		(stroke
			(width 0)
			(type solid)
		)
		(fill yes)
		(layer "F.Cu")
		(net "M_H_DQ<30>")
	)
	(gr_poly
		(pts
			(xy 68.707 -46.429422) (xy 68.83273 -46.285658) (xy 68.761102 -46.213776) (xy 68.617338 -46.339506)
			(xy 68.58127 -46.37532) (xy 68.671186 -46.465236)
		)
		(stroke
			(width 0)
			(type solid)
		)
		(fill yes)
		(layer "F.Cu")
		(net "M_H_DQS_DP<3>")
	)
	(gr_poly
		(pts
			(xy 68.791328 -49.17059) (xy 68.791328 -49.11979) (xy 68.664328 -49.11979) (xy 68.664328 -49.17059)
			(xy 68.677028 -49.36109) (xy 68.778628 -49.36109)
		)
		(stroke
			(width 0)
			(type solid)
		)
		(fill yes)
		(layer "F.Cu")
		(net "M_H_DQ<29>")
	)
	(gr_poly
		(pts
			(xy 68.791328 -48.77689) (xy 68.791328 -48.72609) (xy 68.664328 -48.72609) (xy 68.664328 -48.77689)
			(xy 68.677028 -48.96739) (xy 68.778628 -48.96739)
		)
		(stroke
			(width 0)
			(type solid)
		)
		(fill yes)
		(layer "F.Cu")
		(net "M_H_DQ<24>")
	)
	(gr_poly
		(pts
			(xy 68.791328 -48.38319) (xy 68.791328 -48.33239) (xy 68.664328 -48.33239) (xy 68.664328 -48.38319)
			(xy 68.677028 -48.57369) (xy 68.778628 -48.57369)
		)
		(stroke
			(width 0)
			(type solid)
		)
		(fill yes)
		(layer "F.Cu")
		(net "M_H_DQ<25>")
	)
	(gr_poly
		(pts
			(xy 68.791328 -47.98949) (xy 68.791328 -47.93869) (xy 68.664328 -47.93869) (xy 68.664328 -47.98949)
			(xy 68.677028 -48.17999) (xy 68.778628 -48.17999)
		)
		(stroke
			(width 0)
			(type solid)
		)
		(fill yes)
		(layer "F.Cu")
		(net "M_H_DQS_DP<12>")
	)
	(gr_poly
		(pts
			(xy 68.791328 -47.59579) (xy 68.791328 -47.54499) (xy 68.664328 -47.54499) (xy 68.664328 -47.59579)
			(xy 68.677028 -47.78629) (xy 68.778628 -47.78629)
		)
		(stroke
			(width 0)
			(type solid)
		)
		(fill yes)
		(layer "F.Cu")
		(net "M_H_DQS_DN<12>")
	)
	(gr_poly
		(pts
			(xy 68.796916 -45.404786) (xy 68.922646 -45.261022) (xy 68.851018 -45.18914) (xy 68.707254 -45.31487)
			(xy 68.671186 -45.350684) (xy 68.761102 -45.4406)
		)
		(stroke
			(width 0)
			(type solid)
		)
		(fill yes)
		(layer "F.Cu")
		(net "M_H_DQ<31>")
	)
	(gr_poly
		(pts
			(xy 68.868798 -46.73473) (xy 68.904612 -46.698662) (xy 68.81495 -46.609) (xy 68.778882 -46.644814)
			(xy 68.653152 -46.788578) (xy 68.725034 -46.86046)
		)
		(stroke
			(width 0)
			(type solid)
		)
		(fill yes)
		(layer "F.Cu")
		(net "M_H_DQS_DP<3>")
	)
	(gr_poly
		(pts
			(xy 68.95846 -45.710348) (xy 68.994274 -45.67428) (xy 68.904612 -45.584618) (xy 68.868544 -45.620432)
			(xy 68.742814 -45.764196) (xy 68.814696 -45.836078)
		)
		(stroke
			(width 0)
			(type solid)
		)
		(fill yes)
		(layer "F.Cu")
		(net "M_H_DQ<31>")
	)
	(gr_poly
		(pts
			(xy 68.985638 -46.150784) (xy 69.111368 -46.00702) (xy 69.03974 -45.935138) (xy 68.895976 -46.060868)
			(xy 68.859908 -46.096682) (xy 68.949824 -46.186598)
		)
		(stroke
			(width 0)
			(type solid)
		)
		(fill yes)
		(layer "F.Cu")
		(net "M_H_DQ<30>")
	)
	(gr_poly
		(pts
			(xy 69.002402 -44.810934) (xy 68.938902 -44.810934) (xy 68.748402 -44.823634) (xy 68.748402 -44.925234)
			(xy 68.938902 -44.937934) (xy 69.002402 -44.937934)
		)
		(stroke
			(width 0)
			(type solid)
		)
		(fill yes)
		(layer "F.Cu")
		(net "M_H_DQ<26>")
	)
	(gr_poly
		(pts
			(xy 69.121528 -49.46269) (xy 69.108828 -49.27219) (xy 69.007228 -49.27219) (xy 68.994528 -49.46269)
			(xy 68.994528 -49.52619) (xy 69.121528 -49.52619)
		)
		(stroke
			(width 0)
			(type solid)
		)
		(fill yes)
		(layer "F.Cu")
		(net "M_H_DQ<28>")
	)
	(gr_poly
		(pts
			(xy 69.121528 -49.06899) (xy 69.108828 -48.87849) (xy 69.007228 -48.87849) (xy 68.994528 -49.06899)
			(xy 68.994528 -49.11979) (xy 69.121528 -49.11979)
		)
		(stroke
			(width 0)
			(type solid)
		)
		(fill yes)
		(layer "F.Cu")
		(net "M_H_DQ<29>")
	)
	(gr_poly
		(pts
			(xy 69.121528 -48.67529) (xy 69.108828 -48.48479) (xy 69.007228 -48.48479) (xy 68.994528 -48.67529)
			(xy 68.994528 -48.72609) (xy 69.121528 -48.72609)
		)
		(stroke
			(width 0)
			(type solid)
		)
		(fill yes)
		(layer "F.Cu")
		(net "M_H_DQ<24>")
	)
	(gr_poly
		(pts
			(xy 69.121528 -48.28159) (xy 69.108828 -48.09109) (xy 69.007228 -48.09109) (xy 68.994528 -48.28159)
			(xy 68.994528 -48.33239) (xy 69.121528 -48.33239)
		)
		(stroke
			(width 0)
			(type solid)
		)
		(fill yes)
		(layer "F.Cu")
		(net "M_H_DQ<25>")
	)
	(gr_poly
		(pts
			(xy 69.121528 -47.88789) (xy 69.108828 -47.69739) (xy 69.007228 -47.69739) (xy 68.994528 -47.88789)
			(xy 68.994528 -47.93869) (xy 69.121528 -47.93869)
		)
		(stroke
			(width 0)
			(type solid)
		)
		(fill yes)
		(layer "F.Cu")
		(net "M_H_DQS_DP<12>")
	)
	(gr_poly
		(pts
			(xy 69.121528 -47.49419) (xy 69.108828 -47.30369) (xy 69.007228 -47.30369) (xy 68.994528 -47.49419)
			(xy 68.994528 -47.54499) (xy 69.121528 -47.54499)
		)
		(stroke
			(width 0)
			(type solid)
		)
		(fill yes)
		(layer "F.Cu")
		(net "M_H_DQS_DN<12>")
	)
	(gr_poly
		(pts
			(xy 69.121528 -47.10049) (xy 69.108828 -46.90999) (xy 69.007228 -46.90999) (xy 68.994528 -47.10049)
			(xy 68.994528 -47.15129) (xy 69.121528 -47.15129)
		)
		(stroke
			(width 0)
			(type solid)
		)
		(fill yes)
		(layer "F.Cu")
		(net "M_H_DQS_DN<3>")
	)
	(gr_poly
		(pts
			(xy 69.147182 -46.456092) (xy 69.18325 -46.420278) (xy 69.093334 -46.330362) (xy 69.05752 -46.36643)
			(xy 68.93179 -46.50994) (xy 69.003672 -46.581822)
		)
		(stroke
			(width 0)
			(type solid)
		)
		(fill yes)
		(layer "F.Cu")
		(net "M_H_DQ<30>")
	)
	(gr_poly
		(pts
			(xy 69.237098 -45.43171) (xy 69.272912 -45.395642) (xy 69.18325 -45.30598) (xy 69.147182 -45.341794)
			(xy 69.021452 -45.485558) (xy 69.093334 -45.55744)
		)
		(stroke
			(width 0)
			(type solid)
		)
		(fill yes)
		(layer "F.Cu")
		(net "M_H_DQ<26>")
	)
	(gr_poly
		(pts
			(xy 69.243702 -44.595034) (xy 69.243702 -44.493434) (xy 69.053202 -44.480734) (xy 68.989702 -44.480734)
			(xy 68.989702 -44.607734) (xy 69.053202 -44.607734)
		)
		(stroke
			(width 0)
			(type solid)
		)
		(fill yes)
		(layer "F.Cu")
		(net "M_H_DQ<26>")
	)
	(gr_poly
		(pts
			(xy 69.264022 -45.872146) (xy 69.389752 -45.728382) (xy 69.318124 -45.6565) (xy 69.17436 -45.78223)
			(xy 69.138292 -45.818044) (xy 69.228208 -45.90796)
		)
		(stroke
			(width 0)
			(type solid)
		)
		(fill yes)
		(layer "F.Cu")
		(net "M_H_DQ<31>")
	)
	(gr_poly
		(pts
			(xy 69.408802 -44.810934) (xy 69.345302 -44.810934) (xy 69.154802 -44.823634) (xy 69.154802 -44.925234)
			(xy 69.345302 -44.937934) (xy 69.408802 -44.937934)
		)
		(stroke
			(width 0)
			(type solid)
		)
		(fill yes)
		(layer "F.Cu")
		(net "M_H_DQ<27>")
	)
	(gr_poly
		(pts
			(xy 69.408802 -44.150534) (xy 69.345302 -44.150534) (xy 69.154802 -44.163234) (xy 69.154802 -44.264834)
			(xy 69.345302 -44.277534) (xy 69.408802 -44.277534)
		)
		(stroke
			(width 0)
			(type solid)
		)
		(fill yes)
		(layer "F.Cu")
		(net "M_H_DQ<27>")
	)
	(gr_poly
		(pts
			(xy 69.451728 -49.17059) (xy 69.451728 -49.11979) (xy 69.324728 -49.11979) (xy 69.324728 -49.17059)
			(xy 69.337428 -49.36109) (xy 69.439028 -49.36109)
		)
		(stroke
			(width 0)
			(type solid)
		)
		(fill yes)
		(layer "F.Cu")
		(net "M_H_DQ<29>")
	)
	(gr_poly
		(pts
			(xy 69.451728 -48.77689) (xy 69.451728 -48.72609) (xy 69.324728 -48.72609) (xy 69.324728 -48.77689)
			(xy 69.337428 -48.96739) (xy 69.439028 -48.96739)
		)
		(stroke
			(width 0)
			(type solid)
		)
		(fill yes)
		(layer "F.Cu")
		(net "M_H_DQ<24>")
	)
	(gr_poly
		(pts
			(xy 69.451728 -48.38319) (xy 69.451728 -48.33239) (xy 69.324728 -48.33239) (xy 69.324728 -48.38319)
			(xy 69.337428 -48.57369) (xy 69.439028 -48.57369)
		)
		(stroke
			(width 0)
			(type solid)
		)
		(fill yes)
		(layer "F.Cu")
		(net "M_H_DQ<25>")
	)
	(gr_poly
		(pts
			(xy 69.451728 -47.98949) (xy 69.451728 -47.93869) (xy 69.324728 -47.93869) (xy 69.324728 -47.98949)
			(xy 69.337428 -48.17999) (xy 69.439028 -48.17999)
		)
		(stroke
			(width 0)
			(type solid)
		)
		(fill yes)
		(layer "F.Cu")
		(net "M_H_DQS_DP<12>")
	)
	(gr_poly
		(pts
			(xy 69.451728 -47.59579) (xy 69.451728 -47.54499) (xy 69.324728 -47.54499) (xy 69.324728 -47.59579)
			(xy 69.337428 -47.78629) (xy 69.439028 -47.78629)
		)
		(stroke
			(width 0)
			(type solid)
		)
		(fill yes)
		(layer "F.Cu")
		(net "M_H_DQS_DN<12>")
	)
	(gr_poly
		(pts
			(xy 69.451728 -47.20209) (xy 69.451728 -47.15129) (xy 69.324728 -47.15129) (xy 69.324728 -47.20209)
			(xy 69.337428 -47.39259) (xy 69.439028 -47.39259)
		)
		(stroke
			(width 0)
			(type solid)
		)
		(fill yes)
		(layer "F.Cu")
		(net "M_H_DQS_DN<3>")
	)
	(gr_poly
		(pts
			(xy 69.451728 -46.80839) (xy 69.451728 -46.75759) (xy 69.324728 -46.75759) (xy 69.324728 -46.80839)
			(xy 69.337428 -46.99889) (xy 69.439028 -46.99889)
		)
		(stroke
			(width 0)
			(type solid)
		)
		(fill yes)
		(layer "F.Cu")
		(net "M_H_DQS_DP<3>")
	)
	(gr_poly
		(pts
			(xy 69.451728 -46.41469) (xy 69.451728 -46.36389) (xy 69.324728 -46.36389) (xy 69.324728 -46.41469)
			(xy 69.337428 -46.60519) (xy 69.439028 -46.60519)
		)
		(stroke
			(width 0)
			(type solid)
		)
		(fill yes)
		(layer "F.Cu")
		(net "M_H_DQ<30>")
	)
	(gr_poly
		(pts
			(xy 69.451728 -46.02099) (xy 69.451728 -45.97019) (xy 69.324728 -45.97019) (xy 69.324728 -46.02099)
			(xy 69.337428 -46.21149) (xy 69.439028 -46.21149)
		)
		(stroke
			(width 0)
			(type solid)
		)
		(fill yes)
		(layer "F.Cu")
		(net "M_H_DQ<31>")
	)
	(gr_poly
		(pts
			(xy 69.515736 -45.153072) (xy 69.55155 -45.117004) (xy 69.461888 -45.027342) (xy 69.42582 -45.063156)
			(xy 69.30009 -45.20692) (xy 69.371972 -45.278802)
		)
		(stroke
			(width 0)
			(type solid)
		)
		(fill yes)
		(layer "F.Cu")
		(net "M_H_DQ<27>")
	)
	(gr_poly
		(pts
			(xy 69.781928 -49.46269) (xy 69.769228 -49.27219) (xy 69.667628 -49.27219) (xy 69.654928 -49.46269)
			(xy 69.654928 -49.52619) (xy 69.781928 -49.52619)
		)
		(stroke
			(width 0)
			(type solid)
		)
		(fill yes)
		(layer "F.Cu")
		(net "M_H_DQ<28>")
	)
	(gr_poly
		(pts
			(xy 69.781928 -49.06899) (xy 69.769228 -48.87849) (xy 69.667628 -48.87849) (xy 69.654928 -49.06899)
			(xy 69.654928 -49.11979) (xy 69.781928 -49.11979)
		)
		(stroke
			(width 0)
			(type solid)
		)
		(fill yes)
		(layer "F.Cu")
		(net "M_H_DQ<29>")
	)
	(gr_poly
		(pts
			(xy 69.781928 -48.67529) (xy 69.769228 -48.48479) (xy 69.667628 -48.48479) (xy 69.654928 -48.67529)
			(xy 69.654928 -48.72609) (xy 69.781928 -48.72609)
		)
		(stroke
			(width 0)
			(type solid)
		)
		(fill yes)
		(layer "F.Cu")
		(net "M_H_DQ<24>")
	)
	(gr_poly
		(pts
			(xy 69.781928 -48.28159) (xy 69.769228 -48.09109) (xy 69.667628 -48.09109) (xy 69.654928 -48.28159)
			(xy 69.654928 -48.33239) (xy 69.781928 -48.33239)
		)
		(stroke
			(width 0)
			(type solid)
		)
		(fill yes)
		(layer "F.Cu")
		(net "M_H_DQ<25>")
	)
	(gr_poly
		(pts
			(xy 69.781928 -47.88789) (xy 69.769228 -47.69739) (xy 69.667628 -47.69739) (xy 69.654928 -47.88789)
			(xy 69.654928 -47.93869) (xy 69.781928 -47.93869)
		)
		(stroke
			(width 0)
			(type solid)
		)
		(fill yes)
		(layer "F.Cu")
		(net "M_H_DQS_DP<12>")
	)
	(gr_poly
		(pts
			(xy 69.781928 -47.49419) (xy 69.769228 -47.30369) (xy 69.667628 -47.30369) (xy 69.654928 -47.49419)
			(xy 69.654928 -47.54499) (xy 69.781928 -47.54499)
		)
		(stroke
			(width 0)
			(type solid)
		)
		(fill yes)
		(layer "F.Cu")
		(net "M_H_DQS_DN<12>")
	)
	(gr_poly
		(pts
			(xy 69.781928 -47.10049) (xy 69.769228 -46.90999) (xy 69.667628 -46.90999) (xy 69.654928 -47.10049)
			(xy 69.654928 -47.15129) (xy 69.781928 -47.15129)
		)
		(stroke
			(width 0)
			(type solid)
		)
		(fill yes)
		(layer "F.Cu")
		(net "M_H_DQS_DN<3>")
	)
	(gr_poly
		(pts
			(xy 69.781928 -46.70679) (xy 69.769228 -46.51629) (xy 69.667628 -46.51629) (xy 69.654928 -46.70679)
			(xy 69.654928 -46.75759) (xy 69.781928 -46.75759)
		)
		(stroke
			(width 0)
			(type solid)
		)
		(fill yes)
		(layer "F.Cu")
		(net "M_H_DQS_DP<3>")
	)
	(gr_poly
		(pts
			(xy 69.781928 -46.31309) (xy 69.769228 -46.12259) (xy 69.667628 -46.12259) (xy 69.654928 -46.31309)
			(xy 69.654928 -46.36389) (xy 69.781928 -46.36389)
		)
		(stroke
			(width 0)
			(type solid)
		)
		(fill yes)
		(layer "F.Cu")
		(net "M_H_DQ<30>")
	)
	(gr_poly
		(pts
			(xy 69.781928 -45.91939) (xy 69.769228 -45.72889) (xy 69.667628 -45.72889) (xy 69.654928 -45.91939)
			(xy 69.654928 -45.97019) (xy 69.781928 -45.97019)
		)
		(stroke
			(width 0)
			(type solid)
		)
		(fill yes)
		(layer "F.Cu")
		(net "M_H_DQ<31>")
	)
	(gr_poly
		(pts
			(xy 69.781928 -45.52569) (xy 69.769228 -45.33519) (xy 69.667628 -45.33519) (xy 69.654928 -45.52569)
			(xy 69.654928 -45.57649) (xy 69.781928 -45.57649)
		)
		(stroke
			(width 0)
			(type solid)
		)
		(fill yes)
		(layer "F.Cu")
		(net "M_H_DQ<26>")
	)
	(gr_poly
		(pts
			(xy 70.112128 -49.17059) (xy 70.112128 -49.11979) (xy 69.985128 -49.11979) (xy 69.985128 -49.17059)
			(xy 69.997828 -49.36109) (xy 70.099428 -49.36109)
		)
		(stroke
			(width 0)
			(type solid)
		)
		(fill yes)
		(layer "F.Cu")
		(net "M_H_DQ<29>")
	)
	(gr_poly
		(pts
			(xy 70.112128 -48.77689) (xy 70.112128 -48.72609) (xy 69.985128 -48.72609) (xy 69.985128 -48.77689)
			(xy 69.997828 -48.96739) (xy 70.099428 -48.96739)
		)
		(stroke
			(width 0)
			(type solid)
		)
		(fill yes)
		(layer "F.Cu")
		(net "M_H_DQ<24>")
	)
	(gr_poly
		(pts
			(xy 70.112128 -48.38319) (xy 70.112128 -48.33239) (xy 69.985128 -48.33239) (xy 69.985128 -48.38319)
			(xy 69.997828 -48.57369) (xy 70.099428 -48.57369)
		)
		(stroke
			(width 0)
			(type solid)
		)
		(fill yes)
		(layer "F.Cu")
		(net "M_H_DQ<25>")
	)
	(gr_poly
		(pts
			(xy 70.112128 -47.98949) (xy 70.112128 -47.93869) (xy 69.985128 -47.93869) (xy 69.985128 -47.98949)
			(xy 69.997828 -48.17999) (xy 70.099428 -48.17999)
		)
		(stroke
			(width 0)
			(type solid)
		)
		(fill yes)
		(layer "F.Cu")
		(net "M_H_DQS_DP<12>")
	)
	(gr_poly
		(pts
			(xy 70.112128 -47.59579) (xy 70.112128 -47.54499) (xy 69.985128 -47.54499) (xy 69.985128 -47.59579)
			(xy 69.997828 -47.78629) (xy 70.099428 -47.78629)
		)
		(stroke
			(width 0)
			(type solid)
		)
		(fill yes)
		(layer "F.Cu")
		(net "M_H_DQS_DN<12>")
	)
	(gr_poly
		(pts
			(xy 70.112128 -47.20209) (xy 70.112128 -47.15129) (xy 69.985128 -47.15129) (xy 69.985128 -47.20209)
			(xy 69.997828 -47.39259) (xy 70.099428 -47.39259)
		)
		(stroke
			(width 0)
			(type solid)
		)
		(fill yes)
		(layer "F.Cu")
		(net "M_H_DQS_DN<3>")
	)
	(gr_poly
		(pts
			(xy 70.112128 -46.80839) (xy 70.112128 -46.75759) (xy 69.985128 -46.75759) (xy 69.985128 -46.80839)
			(xy 69.997828 -46.99889) (xy 70.099428 -46.99889)
		)
		(stroke
			(width 0)
			(type solid)
		)
		(fill yes)
		(layer "F.Cu")
		(net "M_H_DQS_DP<3>")
	)
	(gr_poly
		(pts
			(xy 70.112128 -46.41469) (xy 70.112128 -46.36389) (xy 69.985128 -46.36389) (xy 69.985128 -46.41469)
			(xy 69.997828 -46.60519) (xy 70.099428 -46.60519)
		)
		(stroke
			(width 0)
			(type solid)
		)
		(fill yes)
		(layer "F.Cu")
		(net "M_H_DQ<30>")
	)
	(gr_poly
		(pts
			(xy 70.112128 -46.02099) (xy 70.112128 -45.97019) (xy 69.985128 -45.97019) (xy 69.985128 -46.02099)
			(xy 69.997828 -46.21149) (xy 70.099428 -46.21149)
		)
		(stroke
			(width 0)
			(type solid)
		)
		(fill yes)
		(layer "F.Cu")
		(net "M_H_DQ<31>")
	)
	(gr_poly
		(pts
			(xy 70.112128 -45.62729) (xy 70.112128 -45.57649) (xy 69.985128 -45.57649) (xy 69.985128 -45.62729)
			(xy 69.997828 -45.81779) (xy 70.099428 -45.81779)
		)
		(stroke
			(width 0)
			(type solid)
		)
		(fill yes)
		(layer "F.Cu")
		(net "M_H_DQ<26>")
	)
	(gr_poly
		(pts
			(xy 70.112128 -45.23359) (xy 70.112128 -45.17009) (xy 69.985128 -45.17009) (xy 69.985128 -45.23359)
			(xy 69.997828 -45.42409) (xy 70.099428 -45.42409)
		)
		(stroke
			(width 0)
			(type solid)
		)
		(fill yes)
		(layer "F.Cu")
		(net "M_H_DQ<27>")
	)
	(gr_poly
		(pts
			(xy 70.442328 -49.46269) (xy 70.429628 -49.27219) (xy 70.328028 -49.27219) (xy 70.315328 -49.46269)
			(xy 70.315328 -49.52619) (xy 70.442328 -49.52619)
		)
		(stroke
			(width 0)
			(type solid)
		)
		(fill yes)
		(layer "F.Cu")
		(net "M_H_DQ<28>")
	)
	(gr_poly
		(pts
			(xy 70.442328 -49.06899) (xy 70.429628 -48.87849) (xy 70.328028 -48.87849) (xy 70.315328 -49.06899)
			(xy 70.315328 -49.11979) (xy 70.442328 -49.11979)
		)
		(stroke
			(width 0)
			(type solid)
		)
		(fill yes)
		(layer "F.Cu")
		(net "M_H_DQ<29>")
	)
	(gr_poly
		(pts
			(xy 70.442328 -48.67529) (xy 70.429628 -48.48479) (xy 70.328028 -48.48479) (xy 70.315328 -48.67529)
			(xy 70.315328 -48.72609) (xy 70.442328 -48.72609)
		)
		(stroke
			(width 0)
			(type solid)
		)
		(fill yes)
		(layer "F.Cu")
		(net "M_H_DQ<24>")
	)
	(gr_poly
		(pts
			(xy 70.442328 -48.28159) (xy 70.429628 -48.09109) (xy 70.328028 -48.09109) (xy 70.315328 -48.28159)
			(xy 70.315328 -48.33239) (xy 70.442328 -48.33239)
		)
		(stroke
			(width 0)
			(type solid)
		)
		(fill yes)
		(layer "F.Cu")
		(net "M_H_DQ<25>")
	)
	(gr_poly
		(pts
			(xy 70.442328 -47.88789) (xy 70.429628 -47.69739) (xy 70.328028 -47.69739) (xy 70.315328 -47.88789)
			(xy 70.315328 -47.93869) (xy 70.442328 -47.93869)
		)
		(stroke
			(width 0)
			(type solid)
		)
		(fill yes)
		(layer "F.Cu")
		(net "M_H_DQS_DP<12>")
	)
	(gr_poly
		(pts
			(xy 70.442328 -47.49419) (xy 70.429628 -47.30369) (xy 70.328028 -47.30369) (xy 70.315328 -47.49419)
			(xy 70.315328 -47.54499) (xy 70.442328 -47.54499)
		)
		(stroke
			(width 0)
			(type solid)
		)
		(fill yes)
		(layer "F.Cu")
		(net "M_H_DQS_DN<12>")
	)
	(gr_poly
		(pts
			(xy 70.442328 -47.10049) (xy 70.429628 -46.90999) (xy 70.328028 -46.90999) (xy 70.315328 -47.10049)
			(xy 70.315328 -47.15129) (xy 70.442328 -47.15129)
		)
		(stroke
			(width 0)
			(type solid)
		)
		(fill yes)
		(layer "F.Cu")
		(net "M_H_DQS_DN<3>")
	)
	(gr_poly
		(pts
			(xy 70.442328 -46.70679) (xy 70.429628 -46.51629) (xy 70.328028 -46.51629) (xy 70.315328 -46.70679)
			(xy 70.315328 -46.75759) (xy 70.442328 -46.75759)
		)
		(stroke
			(width 0)
			(type solid)
		)
		(fill yes)
		(layer "F.Cu")
		(net "M_H_DQS_DP<3>")
	)
	(gr_poly
		(pts
			(xy 70.442328 -46.31309) (xy 70.429628 -46.12259) (xy 70.328028 -46.12259) (xy 70.315328 -46.31309)
			(xy 70.315328 -46.36389) (xy 70.442328 -46.36389)
		)
		(stroke
			(width 0)
			(type solid)
		)
		(fill yes)
		(layer "F.Cu")
		(net "M_H_DQ<30>")
	)
	(gr_poly
		(pts
			(xy 70.442328 -45.91939) (xy 70.429628 -45.72889) (xy 70.328028 -45.72889) (xy 70.315328 -45.91939)
			(xy 70.315328 -45.97019) (xy 70.442328 -45.97019)
		)
		(stroke
			(width 0)
			(type solid)
		)
		(fill yes)
		(layer "F.Cu")
		(net "M_H_DQ<31>")
	)
	(gr_poly
		(pts
			(xy 70.442328 -45.52569) (xy 70.429628 -45.33519) (xy 70.328028 -45.33519) (xy 70.315328 -45.52569)
			(xy 70.315328 -45.57649) (xy 70.442328 -45.57649)
		)
		(stroke
			(width 0)
			(type solid)
		)
		(fill yes)
		(layer "F.Cu")
		(net "M_H_DQ<26>")
	)
	(gr_poly
		(pts
			(xy 70.772528 -49.17059) (xy 70.772528 -49.11979) (xy 70.645528 -49.11979) (xy 70.645528 -49.17059)
			(xy 70.658228 -49.36109) (xy 70.759828 -49.36109)
		)
		(stroke
			(width 0)
			(type solid)
		)
		(fill yes)
		(layer "F.Cu")
		(net "M_H_DQ<29>")
	)
	(gr_poly
		(pts
			(xy 70.772528 -48.77689) (xy 70.772528 -48.72609) (xy 70.645528 -48.72609) (xy 70.645528 -48.77689)
			(xy 70.658228 -48.96739) (xy 70.759828 -48.96739)
		)
		(stroke
			(width 0)
			(type solid)
		)
		(fill yes)
		(layer "F.Cu")
		(net "M_H_DQ<24>")
	)
	(gr_poly
		(pts
			(xy 70.772528 -48.38319) (xy 70.772528 -48.33239) (xy 70.645528 -48.33239) (xy 70.645528 -48.38319)
			(xy 70.658228 -48.57369) (xy 70.759828 -48.57369)
		)
		(stroke
			(width 0)
			(type solid)
		)
		(fill yes)
		(layer "F.Cu")
		(net "M_H_DQ<25>")
	)
	(gr_poly
		(pts
			(xy 70.772528 -47.98949) (xy 70.772528 -47.93869) (xy 70.645528 -47.93869) (xy 70.645528 -47.98949)
			(xy 70.658228 -48.17999) (xy 70.759828 -48.17999)
		)
		(stroke
			(width 0)
			(type solid)
		)
		(fill yes)
		(layer "F.Cu")
		(net "M_H_DQS_DP<12>")
	)
	(gr_poly
		(pts
			(xy 70.772528 -47.59579) (xy 70.772528 -47.54499) (xy 70.645528 -47.54499) (xy 70.645528 -47.59579)
			(xy 70.658228 -47.78629) (xy 70.759828 -47.78629)
		)
		(stroke
			(width 0)
			(type solid)
		)
		(fill yes)
		(layer "F.Cu")
		(net "M_H_DQS_DN<12>")
	)
	(gr_poly
		(pts
			(xy 70.772528 -47.20209) (xy 70.772528 -47.15129) (xy 70.645528 -47.15129) (xy 70.645528 -47.20209)
			(xy 70.658228 -47.39259) (xy 70.759828 -47.39259)
		)
		(stroke
			(width 0)
			(type solid)
		)
		(fill yes)
		(layer "F.Cu")
		(net "M_H_DQS_DN<3>")
	)
	(gr_poly
		(pts
			(xy 70.772528 -46.80839) (xy 70.772528 -46.75759) (xy 70.645528 -46.75759) (xy 70.645528 -46.80839)
			(xy 70.658228 -46.99889) (xy 70.759828 -46.99889)
		)
		(stroke
			(width 0)
			(type solid)
		)
		(fill yes)
		(layer "F.Cu")
		(net "M_H_DQS_DP<3>")
	)
	(gr_poly
		(pts
			(xy 70.772528 -46.41469) (xy 70.772528 -46.36389) (xy 70.645528 -46.36389) (xy 70.645528 -46.41469)
			(xy 70.658228 -46.60519) (xy 70.759828 -46.60519)
		)
		(stroke
			(width 0)
			(type solid)
		)
		(fill yes)
		(layer "F.Cu")
		(net "M_H_DQ<30>")
	)
	(gr_poly
		(pts
			(xy 70.772528 -46.02099) (xy 70.772528 -45.97019) (xy 70.645528 -45.97019) (xy 70.645528 -46.02099)
			(xy 70.658228 -46.21149) (xy 70.759828 -46.21149)
		)
		(stroke
			(width 0)
			(type solid)
		)
		(fill yes)
		(layer "F.Cu")
		(net "M_H_DQ<31>")
	)
	(gr_poly
		(pts
			(xy 70.772528 -45.62729) (xy 70.772528 -45.57649) (xy 70.645528 -45.57649) (xy 70.645528 -45.62729)
			(xy 70.658228 -45.81779) (xy 70.759828 -45.81779)
		)
		(stroke
			(width 0)
			(type solid)
		)
		(fill yes)
		(layer "F.Cu")
		(net "M_H_DQ<26>")
	)
	(gr_poly
		(pts
			(xy 70.772528 -45.23359) (xy 70.772528 -45.17009) (xy 70.645528 -45.17009) (xy 70.645528 -45.23359)
			(xy 70.658228 -45.42409) (xy 70.759828 -45.42409)
		)
		(stroke
			(width 0)
			(type solid)
		)
		(fill yes)
		(layer "F.Cu")
		(net "M_H_DQ<27>")
	)
	(gr_poly
		(pts
			(xy 71.102728 -49.46269) (xy 71.090028 -49.27219) (xy 70.988428 -49.27219) (xy 70.975728 -49.46269)
			(xy 70.975728 -49.52619) (xy 71.102728 -49.52619)
		)
		(stroke
			(width 0)
			(type solid)
		)
		(fill yes)
		(layer "F.Cu")
		(net "M_H_DQ<28>")
	)
	(gr_poly
		(pts
			(xy 71.102728 -49.06899) (xy 71.090028 -48.87849) (xy 70.988428 -48.87849) (xy 70.975728 -49.06899)
			(xy 70.975728 -49.11979) (xy 71.102728 -49.11979)
		)
		(stroke
			(width 0)
			(type solid)
		)
		(fill yes)
		(layer "F.Cu")
		(net "M_H_DQ<29>")
	)
	(gr_poly
		(pts
			(xy 71.102728 -48.67529) (xy 71.090028 -48.48479) (xy 70.988428 -48.48479) (xy 70.975728 -48.67529)
			(xy 70.975728 -48.72609) (xy 71.102728 -48.72609)
		)
		(stroke
			(width 0)
			(type solid)
		)
		(fill yes)
		(layer "F.Cu")
		(net "M_H_DQ<24>")
	)
	(gr_poly
		(pts
			(xy 71.102728 -48.28159) (xy 71.090028 -48.09109) (xy 70.988428 -48.09109) (xy 70.975728 -48.28159)
			(xy 70.975728 -48.33239) (xy 71.102728 -48.33239)
		)
		(stroke
			(width 0)
			(type solid)
		)
		(fill yes)
		(layer "F.Cu")
		(net "M_H_DQ<25>")
	)
	(gr_poly
		(pts
			(xy 71.102728 -47.88789) (xy 71.090028 -47.69739) (xy 70.988428 -47.69739) (xy 70.975728 -47.88789)
			(xy 70.975728 -47.93869) (xy 71.102728 -47.93869)
		)
		(stroke
			(width 0)
			(type solid)
		)
		(fill yes)
		(layer "F.Cu")
		(net "M_H_DQS_DP<12>")
	)
	(gr_poly
		(pts
			(xy 71.102728 -47.49419) (xy 71.090028 -47.30369) (xy 70.988428 -47.30369) (xy 70.975728 -47.49419)
			(xy 70.975728 -47.54499) (xy 71.102728 -47.54499)
		)
		(stroke
			(width 0)
			(type solid)
		)
		(fill yes)
		(layer "F.Cu")
		(net "M_H_DQS_DN<12>")
	)
	(gr_poly
		(pts
			(xy 71.102728 -47.10049) (xy 71.090028 -46.90999) (xy 70.988428 -46.90999) (xy 70.975728 -47.10049)
			(xy 70.975728 -47.15129) (xy 71.102728 -47.15129)
		)
		(stroke
			(width 0)
			(type solid)
		)
		(fill yes)
		(layer "F.Cu")
		(net "M_H_DQS_DN<3>")
	)
	(gr_poly
		(pts
			(xy 71.102728 -46.70679) (xy 71.090028 -46.51629) (xy 70.988428 -46.51629) (xy 70.975728 -46.70679)
			(xy 70.975728 -46.75759) (xy 71.102728 -46.75759)
		)
		(stroke
			(width 0)
			(type solid)
		)
		(fill yes)
		(layer "F.Cu")
		(net "M_H_DQS_DP<3>")
	)
	(gr_poly
		(pts
			(xy 71.102728 -46.31309) (xy 71.090028 -46.12259) (xy 70.988428 -46.12259) (xy 70.975728 -46.31309)
			(xy 70.975728 -46.36389) (xy 71.102728 -46.36389)
		)
		(stroke
			(width 0)
			(type solid)
		)
		(fill yes)
		(layer "F.Cu")
		(net "M_H_DQ<30>")
	)
	(gr_poly
		(pts
			(xy 71.102728 -45.91939) (xy 71.090028 -45.72889) (xy 70.988428 -45.72889) (xy 70.975728 -45.91939)
			(xy 70.975728 -45.97019) (xy 71.102728 -45.97019)
		)
		(stroke
			(width 0)
			(type solid)
		)
		(fill yes)
		(layer "F.Cu")
		(net "M_H_DQ<31>")
	)
	(gr_poly
		(pts
			(xy 71.102728 -45.52569) (xy 71.090028 -45.33519) (xy 70.988428 -45.33519) (xy 70.975728 -45.52569)
			(xy 70.975728 -45.57649) (xy 71.102728 -45.57649)
		)
		(stroke
			(width 0)
			(type solid)
		)
		(fill yes)
		(layer "F.Cu")
		(net "M_H_DQ<26>")
	)
	(gr_poly
		(pts
			(xy 71.432928 -49.17059) (xy 71.432928 -49.11979) (xy 71.305928 -49.11979) (xy 71.305928 -49.17059)
			(xy 71.318628 -49.36109) (xy 71.420228 -49.36109)
		)
		(stroke
			(width 0)
			(type solid)
		)
		(fill yes)
		(layer "F.Cu")
		(net "M_H_DQ<29>")
	)
	(gr_poly
		(pts
			(xy 71.432928 -48.77689) (xy 71.432928 -48.72609) (xy 71.305928 -48.72609) (xy 71.305928 -48.77689)
			(xy 71.318628 -48.96739) (xy 71.420228 -48.96739)
		)
		(stroke
			(width 0)
			(type solid)
		)
		(fill yes)
		(layer "F.Cu")
		(net "M_H_DQ<24>")
	)
	(gr_poly
		(pts
			(xy 71.432928 -48.38319) (xy 71.432928 -48.33239) (xy 71.305928 -48.33239) (xy 71.305928 -48.38319)
			(xy 71.318628 -48.57369) (xy 71.420228 -48.57369)
		)
		(stroke
			(width 0)
			(type solid)
		)
		(fill yes)
		(layer "F.Cu")
		(net "M_H_DQ<25>")
	)
	(gr_poly
		(pts
			(xy 71.432928 -47.98949) (xy 71.432928 -47.93869) (xy 71.305928 -47.93869) (xy 71.305928 -47.98949)
			(xy 71.318628 -48.17999) (xy 71.420228 -48.17999)
		)
		(stroke
			(width 0)
			(type solid)
		)
		(fill yes)
		(layer "F.Cu")
		(net "M_H_DQS_DP<12>")
	)
	(gr_poly
		(pts
			(xy 71.432928 -47.59579) (xy 71.432928 -47.54499) (xy 71.305928 -47.54499) (xy 71.305928 -47.59579)
			(xy 71.318628 -47.78629) (xy 71.420228 -47.78629)
		)
		(stroke
			(width 0)
			(type solid)
		)
		(fill yes)
		(layer "F.Cu")
		(net "M_H_DQS_DN<12>")
	)
	(gr_poly
		(pts
			(xy 71.432928 -47.20209) (xy 71.432928 -47.15129) (xy 71.305928 -47.15129) (xy 71.305928 -47.20209)
			(xy 71.318628 -47.39259) (xy 71.420228 -47.39259)
		)
		(stroke
			(width 0)
			(type solid)
		)
		(fill yes)
		(layer "F.Cu")
		(net "M_H_DQS_DN<3>")
	)
	(gr_poly
		(pts
			(xy 71.432928 -46.80839) (xy 71.432928 -46.75759) (xy 71.305928 -46.75759) (xy 71.305928 -46.80839)
			(xy 71.318628 -46.99889) (xy 71.420228 -46.99889)
		)
		(stroke
			(width 0)
			(type solid)
		)
		(fill yes)
		(layer "F.Cu")
		(net "M_H_DQS_DP<3>")
	)
	(gr_poly
		(pts
			(xy 71.432928 -46.41469) (xy 71.432928 -46.36389) (xy 71.305928 -46.36389) (xy 71.305928 -46.41469)
			(xy 71.318628 -46.60519) (xy 71.420228 -46.60519)
		)
		(stroke
			(width 0)
			(type solid)
		)
		(fill yes)
		(layer "F.Cu")
		(net "M_H_DQ<30>")
	)
	(gr_poly
		(pts
			(xy 71.432928 -46.02099) (xy 71.432928 -45.97019) (xy 71.305928 -45.97019) (xy 71.305928 -46.02099)
			(xy 71.318628 -46.21149) (xy 71.420228 -46.21149)
		)
		(stroke
			(width 0)
			(type solid)
		)
		(fill yes)
		(layer "F.Cu")
		(net "M_H_DQ<31>")
	)
	(gr_poly
		(pts
			(xy 71.432928 -45.62729) (xy 71.432928 -45.57649) (xy 71.305928 -45.57649) (xy 71.305928 -45.62729)
			(xy 71.318628 -45.81779) (xy 71.420228 -45.81779)
		)
		(stroke
			(width 0)
			(type solid)
		)
		(fill yes)
		(layer "F.Cu")
		(net "M_H_DQ<26>")
	)
	(gr_poly
		(pts
			(xy 71.432928 -45.23359) (xy 71.432928 -45.17009) (xy 71.305928 -45.17009) (xy 71.305928 -45.23359)
			(xy 71.318628 -45.42409) (xy 71.420228 -45.42409)
		)
		(stroke
			(width 0)
			(type solid)
		)
		(fill yes)
		(layer "F.Cu")
		(net "M_H_DQ<27>")
	)
	(gr_poly
		(pts
			(xy 71.597012 -103.027988) (xy 71.64197 -102.983284) (xy 71.51624 -102.857554) (xy 71.471282 -102.902258)
			(xy 71.424546 -102.999286) (xy 71.499984 -103.074724)
		)
		(stroke
			(width 0)
			(type solid)
		)
		(fill yes)
		(layer "F.Cu")
		(net "M_L_DQ<29>")
	)
	(gr_poly
		(pts
			(xy 71.763128 -49.46269) (xy 71.750428 -49.27219) (xy 71.648828 -49.27219) (xy 71.636128 -49.46269)
			(xy 71.636128 -49.52619) (xy 71.763128 -49.52619)
		)
		(stroke
			(width 0)
			(type solid)
		)
		(fill yes)
		(layer "F.Cu")
		(net "M_H_DQ<28>")
	)
	(gr_poly
		(pts
			(xy 71.763128 -49.06899) (xy 71.750428 -48.87849) (xy 71.648828 -48.87849) (xy 71.636128 -49.06899)
			(xy 71.636128 -49.11979) (xy 71.763128 -49.11979)
		)
		(stroke
			(width 0)
			(type solid)
		)
		(fill yes)
		(layer "F.Cu")
		(net "M_H_DQ<29>")
	)
	(gr_poly
		(pts
			(xy 71.763128 -48.67529) (xy 71.750428 -48.48479) (xy 71.648828 -48.48479) (xy 71.636128 -48.67529)
			(xy 71.636128 -48.72609) (xy 71.763128 -48.72609)
		)
		(stroke
			(width 0)
			(type solid)
		)
		(fill yes)
		(layer "F.Cu")
		(net "M_H_DQ<24>")
	)
	(gr_poly
		(pts
			(xy 71.763128 -48.28159) (xy 71.750428 -48.09109) (xy 71.648828 -48.09109) (xy 71.636128 -48.28159)
			(xy 71.636128 -48.33239) (xy 71.763128 -48.33239)
		)
		(stroke
			(width 0)
			(type solid)
		)
		(fill yes)
		(layer "F.Cu")
		(net "M_H_DQ<25>")
	)
	(gr_poly
		(pts
			(xy 71.763128 -47.88789) (xy 71.750428 -47.69739) (xy 71.648828 -47.69739) (xy 71.636128 -47.88789)
			(xy 71.636128 -47.93869) (xy 71.763128 -47.93869)
		)
		(stroke
			(width 0)
			(type solid)
		)
		(fill yes)
		(layer "F.Cu")
		(net "M_H_DQS_DP<12>")
	)
	(gr_poly
		(pts
			(xy 71.763128 -47.49419) (xy 71.750428 -47.30369) (xy 71.648828 -47.30369) (xy 71.636128 -47.49419)
			(xy 71.636128 -47.54499) (xy 71.763128 -47.54499)
		)
		(stroke
			(width 0)
			(type solid)
		)
		(fill yes)
		(layer "F.Cu")
		(net "M_H_DQS_DN<12>")
	)
	(gr_poly
		(pts
			(xy 71.763128 -47.10049) (xy 71.750428 -46.90999) (xy 71.648828 -46.90999) (xy 71.636128 -47.10049)
			(xy 71.636128 -47.15129) (xy 71.763128 -47.15129)
		)
		(stroke
			(width 0)
			(type solid)
		)
		(fill yes)
		(layer "F.Cu")
		(net "M_H_DQS_DN<3>")
	)
	(gr_poly
		(pts
			(xy 71.763128 -46.70679) (xy 71.750428 -46.51629) (xy 71.648828 -46.51629) (xy 71.636128 -46.70679)
			(xy 71.636128 -46.75759) (xy 71.763128 -46.75759)
		)
		(stroke
			(width 0)
			(type solid)
		)
		(fill yes)
		(layer "F.Cu")
		(net "M_H_DQS_DP<3>")
	)
	(gr_poly
		(pts
			(xy 71.763128 -46.31309) (xy 71.750428 -46.12259) (xy 71.648828 -46.12259) (xy 71.636128 -46.31309)
			(xy 71.636128 -46.36389) (xy 71.763128 -46.36389)
		)
		(stroke
			(width 0)
			(type solid)
		)
		(fill yes)
		(layer "F.Cu")
		(net "M_H_DQ<30>")
	)
	(gr_poly
		(pts
			(xy 71.763128 -45.91939) (xy 71.750428 -45.72889) (xy 71.648828 -45.72889) (xy 71.636128 -45.91939)
			(xy 71.636128 -45.97019) (xy 71.763128 -45.97019)
		)
		(stroke
			(width 0)
			(type solid)
		)
		(fill yes)
		(layer "F.Cu")
		(net "M_H_DQ<31>")
	)
	(gr_poly
		(pts
			(xy 71.763128 -45.52569) (xy 71.750428 -45.33519) (xy 71.648828 -45.33519) (xy 71.636128 -45.52569)
			(xy 71.636128 -45.57649) (xy 71.763128 -45.57649)
		)
		(stroke
			(width 0)
			(type solid)
		)
		(fill yes)
		(layer "F.Cu")
		(net "M_H_DQ<26>")
	)
	(gr_poly
		(pts
			(xy 71.79564 -104.190546) (xy 71.79564 -104.139746) (xy 71.61784 -104.139746) (xy 71.61784 -104.190546)
			(xy 71.6534 -104.292146) (xy 71.76008 -104.292146)
		)
		(stroke
			(width 0)
			(type solid)
		)
		(fill yes)
		(layer "F.Cu")
		(net "M_L_DQ<25>")
	)
	(gr_poly
		(pts
			(xy 71.812658 -102.812342) (xy 71.857362 -102.767384) (xy 71.731886 -102.641908) (xy 71.686928 -102.686612)
			(xy 71.640192 -102.78364) (xy 71.71563 -102.859078)
		)
		(stroke
			(width 0)
			(type solid)
		)
		(fill yes)
		(layer "F.Cu")
		(net "M_L_DQ<28>")
	)
	(gr_poly
		(pts
			(xy 71.821548 -103.10876) (xy 71.868284 -103.011732) (xy 71.792846 -102.936294) (xy 71.695818 -102.98303)
			(xy 71.660004 -103.019098) (xy 71.785734 -103.144828)
		)
		(stroke
			(width 0)
			(type solid)
		)
		(fill yes)
		(layer "F.Cu")
		(net "M_L_DQ<29>")
	)
	(gr_poly
		(pts
			(xy 71.90232 -103.333296) (xy 71.947278 -103.288592) (xy 71.821548 -103.162862) (xy 71.77659 -103.207566)
			(xy 71.729854 -103.304594) (xy 71.805292 -103.380032)
		)
		(stroke
			(width 0)
			(type solid)
		)
		(fill yes)
		(layer "F.Cu")
		(net "M_L_DQ<29>")
	)
	(gr_poly
		(pts
			(xy 72.01154 -104.088946) (xy 71.97598 -103.987346) (xy 71.8693 -103.987346) (xy 71.83374 -104.088946)
			(xy 71.83374 -104.139746) (xy 72.01154 -104.139746)
		)
		(stroke
			(width 0)
			(type solid)
		)
		(fill yes)
		(layer "F.Cu")
		(net "M_L_DQ<25>")
	)
	(gr_poly
		(pts
			(xy 72.093328 -49.17059) (xy 72.093328 -49.11979) (xy 71.966328 -49.11979) (xy 71.966328 -49.17059)
			(xy 71.979028 -49.36109) (xy 72.080628 -49.36109)
		)
		(stroke
			(width 0)
			(type solid)
		)
		(fill yes)
		(layer "F.Cu")
		(net "M_H_DQ<29>")
	)
	(gr_poly
		(pts
			(xy 72.093328 -48.77689) (xy 72.093328 -48.72609) (xy 71.966328 -48.72609) (xy 71.966328 -48.77689)
			(xy 71.979028 -48.96739) (xy 72.080628 -48.96739)
		)
		(stroke
			(width 0)
			(type solid)
		)
		(fill yes)
		(layer "F.Cu")
		(net "M_H_DQ<24>")
	)
	(gr_poly
		(pts
			(xy 72.093328 -48.38319) (xy 72.093328 -48.33239) (xy 71.966328 -48.33239) (xy 71.966328 -48.38319)
			(xy 71.979028 -48.57369) (xy 72.080628 -48.57369)
		)
		(stroke
			(width 0)
			(type solid)
		)
		(fill yes)
		(layer "F.Cu")
		(net "M_H_DQ<25>")
	)
	(gr_poly
		(pts
			(xy 72.093328 -47.98949) (xy 72.093328 -47.93869) (xy 71.966328 -47.93869) (xy 71.966328 -47.98949)
			(xy 71.979028 -48.17999) (xy 72.080628 -48.17999)
		)
		(stroke
			(width 0)
			(type solid)
		)
		(fill yes)
		(layer "F.Cu")
		(net "M_H_DQS_DP<12>")
	)
	(gr_poly
		(pts
			(xy 72.093328 -47.59579) (xy 72.093328 -47.54499) (xy 71.966328 -47.54499) (xy 71.966328 -47.59579)
			(xy 71.979028 -47.78629) (xy 72.080628 -47.78629)
		)
		(stroke
			(width 0)
			(type solid)
		)
		(fill yes)
		(layer "F.Cu")
		(net "M_H_DQS_DN<12>")
	)
	(gr_poly
		(pts
			(xy 72.093328 -47.20209) (xy 72.093328 -47.15129) (xy 71.966328 -47.15129) (xy 71.966328 -47.20209)
			(xy 71.979028 -47.39259) (xy 72.080628 -47.39259)
		)
		(stroke
			(width 0)
			(type solid)
		)
		(fill yes)
		(layer "F.Cu")
		(net "M_H_DQS_DN<3>")
	)
	(gr_poly
		(pts
			(xy 72.093328 -46.80839) (xy 72.093328 -46.75759) (xy 71.966328 -46.75759) (xy 71.966328 -46.80839)
			(xy 71.979028 -46.99889) (xy 72.080628 -46.99889)
		)
		(stroke
			(width 0)
			(type solid)
		)
		(fill yes)
		(layer "F.Cu")
		(net "M_H_DQS_DP<3>")
	)
	(gr_poly
		(pts
			(xy 72.093328 -46.41469) (xy 72.093328 -46.36389) (xy 71.966328 -46.36389) (xy 71.966328 -46.41469)
			(xy 71.979028 -46.60519) (xy 72.080628 -46.60519)
		)
		(stroke
			(width 0)
			(type solid)
		)
		(fill yes)
		(layer "F.Cu")
		(net "M_H_DQ<30>")
	)
	(gr_poly
		(pts
			(xy 72.093328 -46.02099) (xy 72.093328 -45.97019) (xy 71.966328 -45.97019) (xy 71.966328 -46.02099)
			(xy 71.979028 -46.21149) (xy 72.080628 -46.21149)
		)
		(stroke
			(width 0)
			(type solid)
		)
		(fill yes)
		(layer "F.Cu")
		(net "M_H_DQ<31>")
	)
	(gr_poly
		(pts
			(xy 72.093328 -45.62729) (xy 72.093328 -45.57649) (xy 71.966328 -45.57649) (xy 71.966328 -45.62729)
			(xy 71.979028 -45.81779) (xy 72.080628 -45.81779)
		)
		(stroke
			(width 0)
			(type solid)
		)
		(fill yes)
		(layer "F.Cu")
		(net "M_H_DQ<26>")
	)
	(gr_poly
		(pts
			(xy 72.093328 -45.23359) (xy 72.093328 -45.17009) (xy 71.966328 -45.17009) (xy 71.966328 -45.23359)
			(xy 71.979028 -45.42409) (xy 72.080628 -45.42409)
		)
		(stroke
			(width 0)
			(type solid)
		)
		(fill yes)
		(layer "F.Cu")
		(net "M_H_DQ<27>")
	)
	(gr_poly
		(pts
			(xy 72.117966 -103.11765) (xy 72.162924 -103.072946) (xy 72.037194 -102.947216) (xy 71.992236 -102.99192)
			(xy 71.9455 -103.088948) (xy 72.020938 -103.164386)
		)
		(stroke
			(width 0)
			(type solid)
		)
		(fill yes)
		(layer "F.Cu")
		(net "M_L_DQ<28>")
	)
	(gr_poly
		(pts
			(xy 72.126856 -103.414068) (xy 72.173592 -103.31704) (xy 72.098154 -103.241602) (xy 72.001126 -103.288338)
			(xy 71.965312 -103.324406) (xy 72.091042 -103.450136)
		)
		(stroke
			(width 0)
			(type solid)
		)
		(fill yes)
		(layer "F.Cu")
		(net "M_L_DQ<29>")
	)
	(gr_poly
		(pts
			(xy 72.22744 -104.190546) (xy 72.22744 -104.139746) (xy 72.04964 -104.139746) (xy 72.04964 -104.190546)
			(xy 72.0852 -104.292146) (xy 72.19188 -104.292146)
		)
		(stroke
			(width 0)
			(type solid)
		)
		(fill yes)
		(layer "F.Cu")
		(net "M_L_DQ<25>")
	)
	(gr_poly
		(pts
			(xy 72.22744 -103.885746) (xy 72.22744 -103.834946) (xy 72.04964 -103.834946) (xy 72.04964 -103.885746)
			(xy 72.0852 -103.987346) (xy 72.19188 -103.987346)
		)
		(stroke
			(width 0)
			(type solid)
		)
		(fill yes)
		(layer "F.Cu")
		(net "M_L_DQ<24>")
	)
	(gr_poly
		(pts
			(xy 72.423528 -49.06899) (xy 72.410828 -48.87849) (xy 72.309228 -48.87849) (xy 72.296528 -49.06899)
			(xy 72.296528 -49.11979) (xy 72.423528 -49.11979)
		)
		(stroke
			(width 0)
			(type solid)
		)
		(fill yes)
		(layer "F.Cu")
		(net "M_H_DQ<29>")
	)
	(gr_poly
		(pts
			(xy 72.423528 -48.28159) (xy 72.410828 -48.09109) (xy 72.309228 -48.09109) (xy 72.296528 -48.28159)
			(xy 72.296528 -48.33239) (xy 72.423528 -48.33239)
		)
		(stroke
			(width 0)
			(type solid)
		)
		(fill yes)
		(layer "F.Cu")
		(net "M_H_DQ<25>")
	)
	(gr_poly
		(pts
			(xy 72.423528 -47.88789) (xy 72.410828 -47.69739) (xy 72.309228 -47.69739) (xy 72.296528 -47.88789)
			(xy 72.296528 -47.93869) (xy 72.423528 -47.93869)
		)
		(stroke
			(width 0)
			(type solid)
		)
		(fill yes)
		(layer "F.Cu")
		(net "M_H_DQS_DP<12>")
	)
	(gr_poly
		(pts
			(xy 72.423528 -47.49419) (xy 72.410828 -47.30369) (xy 72.309228 -47.30369) (xy 72.296528 -47.49419)
			(xy 72.296528 -47.54499) (xy 72.423528 -47.54499)
		)
		(stroke
			(width 0)
			(type solid)
		)
		(fill yes)
		(layer "F.Cu")
		(net "M_H_DQS_DN<12>")
	)
	(gr_poly
		(pts
			(xy 72.423528 -47.10049) (xy 72.410828 -46.90999) (xy 72.309228 -46.90999) (xy 72.296528 -47.10049)
			(xy 72.296528 -47.15129) (xy 72.423528 -47.15129)
		)
		(stroke
			(width 0)
			(type solid)
		)
		(fill yes)
		(layer "F.Cu")
		(net "M_H_DQS_DN<3>")
	)
	(gr_poly
		(pts
			(xy 72.423528 -46.70679) (xy 72.410828 -46.51629) (xy 72.309228 -46.51629) (xy 72.296528 -46.70679)
			(xy 72.296528 -46.75759) (xy 72.423528 -46.75759)
		)
		(stroke
			(width 0)
			(type solid)
		)
		(fill yes)
		(layer "F.Cu")
		(net "M_H_DQS_DP<3>")
	)
	(gr_poly
		(pts
			(xy 72.423528 -46.31309) (xy 72.410828 -46.12259) (xy 72.309228 -46.12259) (xy 72.296528 -46.31309)
			(xy 72.296528 -46.36389) (xy 72.423528 -46.36389)
		)
		(stroke
			(width 0)
			(type solid)
		)
		(fill yes)
		(layer "F.Cu")
		(net "M_H_DQ<30>")
	)
	(gr_poly
		(pts
			(xy 72.423528 -45.91939) (xy 72.410828 -45.72889) (xy 72.309228 -45.72889) (xy 72.296528 -45.91939)
			(xy 72.296528 -45.97019) (xy 72.423528 -45.97019)
		)
		(stroke
			(width 0)
			(type solid)
		)
		(fill yes)
		(layer "F.Cu")
		(net "M_H_DQ<31>")
	)
	(gr_poly
		(pts
			(xy 72.423528 -45.52569) (xy 72.410828 -45.33519) (xy 72.309228 -45.33519) (xy 72.296528 -45.52569)
			(xy 72.296528 -45.57649) (xy 72.423528 -45.57649)
		)
		(stroke
			(width 0)
			(type solid)
		)
		(fill yes)
		(layer "F.Cu")
		(net "M_H_DQ<26>")
	)
	(gr_poly
		(pts
			(xy 72.44334 -104.088946) (xy 72.40778 -103.987346) (xy 72.3011 -103.987346) (xy 72.26554 -104.088946)
			(xy 72.26554 -104.139746) (xy 72.44334 -104.139746)
		)
		(stroke
			(width 0)
			(type solid)
		)
		(fill yes)
		(layer "F.Cu")
		(net "M_L_DQ<25>")
	)
	(gr_poly
		(pts
			(xy 72.44334 -103.784146) (xy 72.40778 -103.682546) (xy 72.3011 -103.682546) (xy 72.26554 -103.784146)
			(xy 72.26554 -103.834946) (xy 72.44334 -103.834946)
		)
		(stroke
			(width 0)
			(type solid)
		)
		(fill yes)
		(layer "F.Cu")
		(net "M_L_DQ<24>")
	)
	(gr_poly
		(pts
			(xy 72.44334 -103.479346) (xy 72.40778 -103.377746) (xy 72.3011 -103.377746) (xy 72.26554 -103.479346)
			(xy 72.26554 -103.530146) (xy 72.44334 -103.530146)
		)
		(stroke
			(width 0)
			(type solid)
		)
		(fill yes)
		(layer "F.Cu")
		(net "M_L_DQ<29>")
	)
	(gr_poly
		(pts
			(xy 72.587358 -108.245148) (xy 72.5424 -108.200444) (xy 72.445372 -108.153708) (xy 72.369934 -108.229146)
			(xy 72.41667 -108.326174) (xy 72.461628 -108.370878)
		)
		(stroke
			(width 0)
			(type solid)
		)
		(fill yes)
		(layer "F.Cu")
		(net "M_L_DQ<27>")
	)
	(gr_poly
		(pts
			(xy 72.598026 -108.001054) (xy 72.55129 -107.904026) (xy 72.515476 -107.867958) (xy 72.389746 -107.993688)
			(xy 72.42556 -108.029756) (xy 72.522588 -108.076238)
		)
		(stroke
			(width 0)
			(type solid)
		)
		(fill yes)
		(layer "F.Cu")
		(net "M_L_DQ<26>")
	)
	(gr_poly
		(pts
			(xy 72.652128 -49.46269) (xy 72.616568 -49.36109) (xy 72.509888 -49.36109) (xy 72.474328 -49.46269)
			(xy 72.474328 -49.52619) (xy 72.652128 -49.52619)
		)
		(stroke
			(width 0)
			(type solid)
		)
		(fill yes)
		(layer "F.Cu")
		(net "M_H_DQ<28>")
	)
	(gr_poly
		(pts
			(xy 72.65924 -104.190546) (xy 72.65924 -104.139746) (xy 72.48144 -104.139746) (xy 72.48144 -104.190546)
			(xy 72.517 -104.292146) (xy 72.62368 -104.292146)
		)
		(stroke
			(width 0)
			(type solid)
		)
		(fill yes)
		(layer "F.Cu")
		(net "M_L_DQ<25>")
	)
	(gr_poly
		(pts
			(xy 72.65924 -103.885746) (xy 72.65924 -103.834946) (xy 72.48144 -103.834946) (xy 72.48144 -103.885746)
			(xy 72.517 -103.987346) (xy 72.62368 -103.987346)
		)
		(stroke
			(width 0)
			(type solid)
		)
		(fill yes)
		(layer "F.Cu")
		(net "M_L_DQ<24>")
	)
	(gr_poly
		(pts
			(xy 72.65924 -103.580946) (xy 72.65924 -103.530146) (xy 72.48144 -103.530146) (xy 72.48144 -103.580946)
			(xy 72.517 -103.682546) (xy 72.62368 -103.682546)
		)
		(stroke
			(width 0)
			(type solid)
		)
		(fill yes)
		(layer "F.Cu")
		(net "M_L_DQ<29>")
	)
	(gr_poly
		(pts
			(xy 72.65924 -103.276146) (xy 72.65924 -103.212646) (xy 72.48144 -103.212646) (xy 72.48144 -103.276146)
			(xy 72.517 -103.377746) (xy 72.62368 -103.377746)
		)
		(stroke
			(width 0)
			(type solid)
		)
		(fill yes)
		(layer "F.Cu")
		(net "M_L_DQ<28>")
	)
	(gr_poly
		(pts
			(xy 72.667876 -48.545496) (xy 72.70369 -48.509428) (xy 72.57796 -48.383698) (xy 72.542146 -48.419766)
			(xy 72.49541 -48.516794) (xy 72.570848 -48.592232)
		)
		(stroke
			(width 0)
			(type solid)
		)
		(fill yes)
		(layer "F.Cu")
		(net "M_H_DQ<25>")
	)
	(gr_poly
		(pts
			(xy 72.66813 -107.715304) (xy 72.632062 -107.67949) (xy 72.535288 -107.632754) (xy 72.45985 -107.708192)
			(xy 72.506332 -107.80522) (xy 72.5424 -107.841034)
		)
		(stroke
			(width 0)
			(type solid)
		)
		(fill yes)
		(layer "F.Cu")
		(net "M_L_DQ<26>")
	)
	(gr_poly
		(pts
			(xy 72.676766 -48.841914) (xy 72.723502 -48.744886) (xy 72.648064 -48.669448) (xy 72.551036 -48.716184)
			(xy 72.514968 -48.751998) (xy 72.640698 -48.877728)
		)
		(stroke
			(width 0)
			(type solid)
		)
		(fill yes)
		(layer "F.Cu")
		(net "M_H_DQ<24>")
	)
	(gr_poly
		(pts
			(xy 72.713088 -47.58436) (xy 72.759824 -47.487332) (xy 72.684386 -47.411894) (xy 72.587358 -47.45863)
			(xy 72.55129 -47.494444) (xy 72.67702 -47.620174)
		)
		(stroke
			(width 0)
			(type solid)
		)
		(fill yes)
		(layer "F.Cu")
		(net "M_H_DQS_DN<12>")
	)
	(gr_poly
		(pts
			(xy 72.753728 -45.23359) (xy 72.753728 -45.17009) (xy 72.626728 -45.17009) (xy 72.626728 -45.23359)
			(xy 72.639428 -45.42409) (xy 72.741028 -45.42409)
		)
		(stroke
			(width 0)
			(type solid)
		)
		(fill yes)
		(layer "F.Cu")
		(net "M_H_DQ<27>")
	)
	(gr_poly
		(pts
			(xy 72.79386 -47.808896) (xy 72.829674 -47.772828) (xy 72.703944 -47.647098) (xy 72.66813 -47.683166)
			(xy 72.621394 -47.780194) (xy 72.696832 -47.855632)
		)
		(stroke
			(width 0)
			(type solid)
		)
		(fill yes)
		(layer "F.Cu")
		(net "M_H_DQS_DN<12>")
	)
	(gr_poly
		(pts
			(xy 72.80275 -48.105314) (xy 72.849486 -48.008286) (xy 72.774048 -47.932848) (xy 72.67702 -47.979584)
			(xy 72.640952 -48.015398) (xy 72.766682 -48.141128)
		)
		(stroke
			(width 0)
			(type solid)
		)
		(fill yes)
		(layer "F.Cu")
		(net "M_H_DQS_DP<12>")
	)
	(gr_poly
		(pts
			(xy 72.839072 -46.84776) (xy 72.885808 -46.750732) (xy 72.81037 -46.675294) (xy 72.713342 -46.72203)
			(xy 72.677274 -46.757844) (xy 72.803004 -46.883574)
		)
		(stroke
			(width 0)
			(type solid)
		)
		(fill yes)
		(layer "F.Cu")
		(net "M_H_DQS_DP<3>")
	)
	(gr_poly
		(pts
			(xy 72.868028 -49.25949) (xy 72.868028 -49.20869) (xy 72.690228 -49.20869) (xy 72.690228 -49.25949)
			(xy 72.725788 -49.36109) (xy 72.832468 -49.36109)
		)
		(stroke
			(width 0)
			(type solid)
		)
		(fill yes)
		(layer "F.Cu")
		(net "M_H_DQ<29>")
	)
	(gr_poly
		(pts
			(xy 72.87514 -104.088946) (xy 72.83958 -103.987346) (xy 72.7329 -103.987346) (xy 72.69734 -104.088946)
			(xy 72.69734 -104.139746) (xy 72.87514 -104.139746)
		)
		(stroke
			(width 0)
			(type solid)
		)
		(fill yes)
		(layer "F.Cu")
		(net "M_L_DQ<25>")
	)
	(gr_poly
		(pts
			(xy 72.87514 -103.784146) (xy 72.83958 -103.682546) (xy 72.7329 -103.682546) (xy 72.69734 -103.784146)
			(xy 72.69734 -103.834946) (xy 72.87514 -103.834946)
		)
		(stroke
			(width 0)
			(type solid)
		)
		(fill yes)
		(layer "F.Cu")
		(net "M_L_DQ<24>")
	)
	(gr_poly
		(pts
			(xy 72.87514 -103.479346) (xy 72.83958 -103.377746) (xy 72.7329 -103.377746) (xy 72.69734 -103.479346)
			(xy 72.69734 -103.530146) (xy 72.87514 -103.530146)
		)
		(stroke
			(width 0)
			(type solid)
		)
		(fill yes)
		(layer "F.Cu")
		(net "M_L_DQ<29>")
	)
	(gr_poly
		(pts
			(xy 72.883522 -48.32985) (xy 72.919336 -48.293782) (xy 72.793606 -48.168052) (xy 72.757792 -48.20412)
			(xy 72.711056 -48.301148) (xy 72.786494 -48.376586)
		)
		(stroke
			(width 0)
			(type solid)
		)
		(fill yes)
		(layer "F.Cu")
		(net "M_H_DQS_DP<12>")
	)
	(gr_poly
		(pts
			(xy 72.892666 -107.93984) (xy 72.847708 -107.895136) (xy 72.75068 -107.8484) (xy 72.675242 -107.923838)
			(xy 72.721978 -108.020612) (xy 72.766936 -108.06557)
		)
		(stroke
			(width 0)
			(type solid)
		)
		(fill yes)
		(layer "F.Cu")
		(net "M_L_DQ<27>")
	)
	(gr_poly
		(pts
			(xy 72.903334 -107.695746) (xy 72.856598 -107.598718) (xy 72.820784 -107.56265) (xy 72.695054 -107.68838)
			(xy 72.730868 -107.724448) (xy 72.827896 -107.77093)
		)
		(stroke
			(width 0)
			(type solid)
		)
		(fill yes)
		(layer "F.Cu")
		(net "M_L_DQ<26>")
	)
	(gr_poly
		(pts
			(xy 72.919844 -47.072296) (xy 72.955658 -47.036228) (xy 72.829928 -46.910498) (xy 72.794114 -46.946566)
			(xy 72.747378 -47.043594) (xy 72.822816 -47.119032)
		)
		(stroke
			(width 0)
			(type solid)
		)
		(fill yes)
		(layer "F.Cu")
		(net "M_H_DQS_DP<3>")
	)
	(gr_poly
		(pts
			(xy 72.928734 -47.368714) (xy 72.97547 -47.271686) (xy 72.900032 -47.196248) (xy 72.803004 -47.242984)
			(xy 72.766936 -47.278798) (xy 72.892666 -47.404528)
		)
		(stroke
			(width 0)
			(type solid)
		)
		(fill yes)
		(layer "F.Cu")
		(net "M_H_DQS_DN<3>")
	)
	(gr_poly
		(pts
			(xy 72.956166 -45.814742) (xy 72.99198 -45.778674) (xy 72.86625 -45.652944) (xy 72.830436 -45.689012)
			(xy 72.7837 -45.785786) (xy 72.859138 -45.861224)
		)
		(stroke
			(width 0)
			(type solid)
		)
		(fill yes)
		(layer "F.Cu")
		(net "M_H_DQ<26>")
	)
	(gr_poly
		(pts
			(xy 72.965056 -46.11116) (xy 73.011792 -46.014132) (xy 72.936354 -45.938694) (xy 72.839326 -45.98543)
			(xy 72.803258 -46.021244) (xy 72.928988 -46.146974)
		)
		(stroke
			(width 0)
			(type solid)
		)
		(fill yes)
		(layer "F.Cu")
		(net "M_H_DQ<31>")
	)
	(gr_poly
		(pts
			(xy 72.973438 -107.409996) (xy 72.93737 -107.374182) (xy 72.840596 -107.327446) (xy 72.765158 -107.402884)
			(xy 72.81164 -107.499912) (xy 72.847708 -107.535726)
		)
		(stroke
			(width 0)
			(type solid)
		)
		(fill yes)
		(layer "F.Cu")
		(net "M_L_DQ<26>")
	)
	(gr_poly
		(pts
			(xy 72.992996 -107.174538) (xy 72.94626 -107.077764) (xy 72.910446 -107.041696) (xy 72.784716 -107.167426)
			(xy 72.82053 -107.203494) (xy 72.917558 -107.249976)
		)
		(stroke
			(width 0)
			(type solid)
		)
		(fill yes)
		(layer "F.Cu")
		(net "M_L_DQ<31>")
	)
	(gr_poly
		(pts
			(xy 73.009506 -47.59325) (xy 73.04532 -47.557182) (xy 72.91959 -47.431452) (xy 72.883776 -47.46752)
			(xy 72.83704 -47.564548) (xy 72.912478 -47.639986)
		)
		(stroke
			(width 0)
			(type solid)
		)
		(fill yes)
		(layer "F.Cu")
		(net "M_H_DQS_DN<3>")
	)
	(gr_poly
		(pts
			(xy 73.018396 -47.889668) (xy 73.065132 -47.79264) (xy 72.989694 -47.717202) (xy 72.892666 -47.763938)
			(xy 72.856598 -47.799752) (xy 72.982328 -47.925482)
		)
		(stroke
			(width 0)
			(type solid)
		)
		(fill yes)
		(layer "F.Cu")
		(net "M_H_DQS_DN<12>")
	)
	(gr_poly
		(pts
			(xy 73.045828 -46.335696) (xy 73.081642 -46.299628) (xy 72.955912 -46.173898) (xy 72.920098 -46.209966)
			(xy 72.873362 -46.306994) (xy 72.9488 -46.382432)
		)
		(stroke
			(width 0)
			(type solid)
		)
		(fill yes)
		(layer "F.Cu")
		(net "M_H_DQ<31>")
	)
	(gr_poly
		(pts
			(xy 73.054718 -46.632114) (xy 73.101454 -46.535086) (xy 73.026016 -46.459648) (xy 72.928988 -46.506384)
			(xy 72.89292 -46.542198) (xy 73.01865 -46.667928)
		)
		(stroke
			(width 0)
			(type solid)
		)
		(fill yes)
		(layer "F.Cu")
		(net "M_H_DQ<30>")
	)
	(gr_poly
		(pts
			(xy 73.0631 -106.889042) (xy 73.027032 -106.853228) (xy 72.930258 -106.806492) (xy 72.85482 -106.88193)
			(xy 72.901302 -106.978958) (xy 72.93737 -107.014772)
		)
		(stroke
			(width 0)
			(type solid)
		)
		(fill yes)
		(layer "F.Cu")
		(net "M_L_DQ<31>")
	)
	(gr_poly
		(pts
			(xy 73.082658 -106.653584) (xy 73.035922 -106.556556) (xy 73.000108 -106.520742) (xy 72.874378 -106.646472)
			(xy 72.910192 -106.682286) (xy 73.00722 -106.729022)
		)
		(stroke
			(width 0)
			(type solid)
		)
		(fill yes)
		(layer "F.Cu")
		(net "M_L_DQ<30>")
	)
	(gr_poly
		(pts
			(xy 73.083928 -49.46269) (xy 73.048368 -49.36109) (xy 72.941688 -49.36109) (xy 72.906128 -49.46269)
			(xy 72.906128 -49.52619) (xy 73.083928 -49.52619)
		)
		(stroke
			(width 0)
			(type solid)
		)
		(fill yes)
		(layer "F.Cu")
		(net "M_H_DQ<28>")
	)
	(gr_poly
		(pts
			(xy 73.083928 -49.15789) (xy 73.048368 -49.05629) (xy 72.941688 -49.05629) (xy 72.906128 -49.15789)
			(xy 72.906128 -49.20869) (xy 73.083928 -49.20869)
		)
		(stroke
			(width 0)
			(type solid)
		)
		(fill yes)
		(layer "F.Cu")
		(net "M_H_DQ<29>")
	)
	(gr_poly
		(pts
			(xy 73.083928 -48.85309) (xy 73.048368 -48.75149) (xy 72.941688 -48.75149) (xy 72.906128 -48.85309)
			(xy 72.906128 -48.90389) (xy 73.083928 -48.90389)
		)
		(stroke
			(width 0)
			(type solid)
		)
		(fill yes)
		(layer "F.Cu")
		(net "M_H_DQ<24>")
	)
	(gr_poly
		(pts
			(xy 73.09104 -104.190546) (xy 73.09104 -104.139746) (xy 72.91324 -104.139746) (xy 72.91324 -104.190546)
			(xy 72.9488 -104.292146) (xy 73.05548 -104.292146)
		)
		(stroke
			(width 0)
			(type solid)
		)
		(fill yes)
		(layer "F.Cu")
		(net "M_L_DQ<25>")
	)
	(gr_poly
		(pts
			(xy 73.09104 -103.885746) (xy 73.09104 -103.834946) (xy 72.91324 -103.834946) (xy 72.91324 -103.885746)
			(xy 72.9488 -103.987346) (xy 73.05548 -103.987346)
		)
		(stroke
			(width 0)
			(type solid)
		)
		(fill yes)
		(layer "F.Cu")
		(net "M_L_DQ<24>")
	)
	(gr_poly
		(pts
			(xy 73.13549 -46.85665) (xy 73.171304 -46.820582) (xy 73.045574 -46.694852) (xy 73.00976 -46.73092)
			(xy 72.963024 -46.827948) (xy 73.038462 -46.903386)
		)
		(stroke
			(width 0)
			(type solid)
		)
		(fill yes)
		(layer "F.Cu")
		(net "M_H_DQ<30>")
	)
	(gr_poly
		(pts
			(xy 73.14438 -47.153068) (xy 73.191116 -47.05604) (xy 73.115678 -46.980602) (xy 73.01865 -47.027338)
			(xy 72.982582 -47.063152) (xy 73.108312 -47.188882)
		)
		(stroke
			(width 0)
			(type solid)
		)
		(fill yes)
		(layer "F.Cu")
		(net "M_H_DQS_DP<3>")
	)
	(gr_poly
		(pts
			(xy 73.152762 -106.368088) (xy 73.116948 -106.332274) (xy 73.01992 -106.285538) (xy 72.944482 -106.360976)
			(xy 72.991218 -106.458004) (xy 73.027032 -106.493818)
		)
		(stroke
			(width 0)
			(type solid)
		)
		(fill yes)
		(layer "F.Cu")
		(net "M_L_DQ<30>")
	)
	(gr_poly
		(pts
			(xy 73.168764 -103.33101) (xy 73.13295 -103.294942) (xy 73.035922 -103.248206) (xy 72.960484 -103.323644)
			(xy 73.00722 -103.420672) (xy 73.043034 -103.45674)
		)
		(stroke
			(width 0)
			(type solid)
		)
		(fill yes)
		(layer "F.Cu")
		(net "M_L_DQ<29>")
	)
	(gr_poly
		(pts
			(xy 73.171558 -45.599096) (xy 73.216516 -45.554138) (xy 73.090786 -45.428408) (xy 73.045828 -45.473366)
			(xy 72.999346 -45.570394) (xy 73.074784 -45.645832)
		)
		(stroke
			(width 0)
			(type solid)
		)
		(fill yes)
		(layer "F.Cu")
		(net "M_H_DQ<27>")
	)
	(gr_poly
		(pts
			(xy 73.180702 -45.895514) (xy 73.227184 -45.798486) (xy 73.151746 -45.723048) (xy 73.054972 -45.769784)
			(xy 73.018904 -45.805598) (xy 73.144634 -45.931328)
		)
		(stroke
			(width 0)
			(type solid)
		)
		(fill yes)
		(layer "F.Cu")
		(net "M_H_DQ<26>")
	)
	(gr_poly
		(pts
			(xy 73.188576 -103.095552) (xy 73.14184 -102.998524) (xy 73.096882 -102.95382) (xy 72.971152 -103.07955)
			(xy 73.01611 -103.124254) (xy 73.113138 -103.17099)
		)
		(stroke
			(width 0)
			(type solid)
		)
		(fill yes)
		(layer "F.Cu")
		(net "M_L_DQ<28>")
	)
	(gr_poly
		(pts
			(xy 73.197974 -107.634532) (xy 73.153016 -107.589574) (xy 73.055988 -107.543092) (xy 72.98055 -107.61853)
			(xy 73.027286 -107.715304) (xy 73.072244 -107.760262)
		)
		(stroke
			(width 0)
			(type solid)
		)
		(fill yes)
		(layer "F.Cu")
		(net "M_L_DQ<27>")
	)
	(gr_poly
		(pts
			(xy 73.206102 -104.58958) (xy 73.170288 -104.553512) (xy 73.07326 -104.506776) (xy 72.997822 -104.582214)
			(xy 73.044558 -104.679242) (xy 73.080372 -104.71531)
		)
		(stroke
			(width 0)
			(type solid)
		)
		(fill yes)
		(layer "F.Cu")
		(net "M_L_DQS_DP<12>")
	)
	(gr_poly
		(pts
			(xy 73.208642 -107.390184) (xy 73.161906 -107.29341) (xy 73.126092 -107.257342) (xy 73.000362 -107.383072)
			(xy 73.036176 -107.41914) (xy 73.133204 -107.465622)
		)
		(stroke
			(width 0)
			(type solid)
		)
		(fill yes)
		(layer "F.Cu")
		(net "M_L_DQ<26>")
	)
	(gr_poly
		(pts
			(xy 73.225152 -47.377604) (xy 73.260966 -47.341536) (xy 73.135236 -47.215806) (xy 73.099422 -47.251874)
			(xy 73.052686 -47.348902) (xy 73.128124 -47.42434)
		)
		(stroke
			(width 0)
			(type solid)
		)
		(fill yes)
		(layer "F.Cu")
		(net "M_H_DQS_DP<3>")
	)
	(gr_poly
		(pts
			(xy 73.242424 -105.847134) (xy 73.20661 -105.811066) (xy 73.109582 -105.764584) (xy 73.034144 -105.840022)
			(xy 73.08088 -105.936796) (xy 73.116694 -105.972864)
		)
		(stroke
			(width 0)
			(type solid)
		)
		(fill yes)
		(layer "F.Cu")
		(net "M_L_DQS_DP<3>")
	)
	(gr_poly
		(pts
			(xy 73.261474 -46.12005) (xy 73.297288 -46.083982) (xy 73.171558 -45.958252) (xy 73.135744 -45.99432)
			(xy 73.089008 -46.091094) (xy 73.164446 -46.166532)
		)
		(stroke
			(width 0)
			(type solid)
		)
		(fill yes)
		(layer "F.Cu")
		(net "M_H_DQ<26>")
	)
	(gr_poly
		(pts
			(xy 73.261982 -105.611676) (xy 73.2155 -105.514648) (xy 73.179432 -105.478834) (xy 73.053702 -105.604564)
			(xy 73.08977 -105.640378) (xy 73.186544 -105.687114)
		)
		(stroke
			(width 0)
			(type solid)
		)
		(fill yes)
		(layer "F.Cu")
		(net "M_L_DQS_DN<3>")
	)
	(gr_poly
		(pts
			(xy 73.270364 -46.416468) (xy 73.3171 -46.31944) (xy 73.241662 -46.244002) (xy 73.144634 -46.290738)
			(xy 73.108566 -46.326552) (xy 73.234296 -46.452282)
		)
		(stroke
			(width 0)
			(type solid)
		)
		(fill yes)
		(layer "F.Cu")
		(net "M_H_DQ<31>")
	)
	(gr_poly
		(pts
			(xy 73.278746 -107.104688) (xy 73.242678 -107.068874) (xy 73.145904 -107.022138) (xy 73.070466 -107.097576)
			(xy 73.116948 -107.194604) (xy 73.153016 -107.230418)
		)
		(stroke
			(width 0)
			(type solid)
		)
		(fill yes)
		(layer "F.Cu")
		(net "M_L_DQ<26>")
	)
	(gr_poly
		(pts
			(xy 73.298304 -106.86923) (xy 73.251568 -106.772456) (xy 73.215754 -106.736388) (xy 73.090024 -106.862118)
			(xy 73.125838 -106.897932) (xy 73.222866 -106.944668)
		)
		(stroke
			(width 0)
			(type solid)
		)
		(fill yes)
		(layer "F.Cu")
		(net "M_L_DQ<31>")
	)
	(gr_poly
		(pts
			(xy 73.299828 -49.25949) (xy 73.299828 -49.20869) (xy 73.122028 -49.20869) (xy 73.122028 -49.25949)
			(xy 73.157588 -49.36109) (xy 73.264268 -49.36109)
		)
		(stroke
			(width 0)
			(type solid)
		)
		(fill yes)
		(layer "F.Cu")
		(net "M_H_DQ<29>")
	)
	(gr_poly
		(pts
			(xy 73.299828 -48.95469) (xy 73.299828 -48.90389) (xy 73.122028 -48.90389) (xy 73.122028 -48.95469)
			(xy 73.157588 -49.05629) (xy 73.264268 -49.05629)
		)
		(stroke
			(width 0)
			(type solid)
		)
		(fill yes)
		(layer "F.Cu")
		(net "M_H_DQ<24>")
	)
	(gr_poly
		(pts
			(xy 73.299828 -48.64989) (xy 73.299828 -48.59909) (xy 73.122028 -48.59909) (xy 73.122028 -48.64989)
			(xy 73.157588 -48.75149) (xy 73.264268 -48.75149)
		)
		(stroke
			(width 0)
			(type solid)
		)
		(fill yes)
		(layer "F.Cu")
		(net "M_H_DQ<25>")
	)
	(gr_poly
		(pts
			(xy 73.299828 -48.34509) (xy 73.299828 -48.29429) (xy 73.122028 -48.29429) (xy 73.122028 -48.34509)
			(xy 73.157588 -48.44669) (xy 73.264268 -48.44669)
		)
		(stroke
			(width 0)
			(type solid)
		)
		(fill yes)
		(layer "F.Cu")
		(net "M_H_DQS_DP<12>")
	)
	(gr_poly
		(pts
			(xy 73.31456 -103.832152) (xy 73.267824 -103.735124) (xy 73.231756 -103.69931) (xy 73.106026 -103.82504)
			(xy 73.142094 -103.860854) (xy 73.239122 -103.90759)
		)
		(stroke
			(width 0)
			(type solid)
		)
		(fill yes)
		(layer "F.Cu")
		(net "M_L_DQ<24>")
	)
	(gr_poly
		(pts
			(xy 73.332086 -105.32618) (xy 73.296272 -105.290112) (xy 73.199244 -105.24363) (xy 73.123806 -105.319068)
			(xy 73.170542 -105.415842) (xy 73.206356 -105.45191)
		)
		(stroke
			(width 0)
			(type solid)
		)
		(fill yes)
		(layer "F.Cu")
		(net "M_L_DQS_DN<3>")
	)
	(gr_poly
		(pts
			(xy 73.351136 -46.641004) (xy 73.38695 -46.604936) (xy 73.26122 -46.479206) (xy 73.225406 -46.515274)
			(xy 73.17867 -46.612302) (xy 73.254108 -46.68774)
		)
		(stroke
			(width 0)
			(type solid)
		)
		(fill yes)
		(layer "F.Cu")
		(net "M_H_DQ<31>")
	)
	(gr_poly
		(pts
			(xy 73.360026 -46.937422) (xy 73.406762 -46.840394) (xy 73.331324 -46.764956) (xy 73.234296 -46.811692)
			(xy 73.198228 -46.847506) (xy 73.323958 -46.973236)
		)
		(stroke
			(width 0)
			(type solid)
		)
		(fill yes)
		(layer "F.Cu")
		(net "M_H_DQ<30>")
	)
	(gr_poly
		(pts
			(xy 73.368408 -106.583734) (xy 73.332594 -106.54792) (xy 73.235566 -106.501184) (xy 73.160128 -106.576622)
			(xy 73.206864 -106.67365) (xy 73.242678 -106.709464)
		)
		(stroke
			(width 0)
			(type solid)
		)
		(fill yes)
		(layer "F.Cu")
		(net "M_L_DQ<31>")
	)
	(gr_poly
		(pts
			(xy 73.38441 -103.546656) (xy 73.348596 -103.510588) (xy 73.251568 -103.463852) (xy 73.17613 -103.53929)
			(xy 73.222866 -103.636318) (xy 73.25868 -103.672386)
		)
		(stroke
			(width 0)
			(type solid)
		)
		(fill yes)
		(layer "F.Cu")
		(net "M_L_DQ<24>")
	)
	(gr_poly
		(pts
			(xy 73.387966 -106.348276) (xy 73.34123 -106.251248) (xy 73.305416 -106.215434) (xy 73.179686 -106.341164)
			(xy 73.2155 -106.376978) (xy 73.312528 -106.423714)
		)
		(stroke
			(width 0)
			(type solid)
		)
		(fill yes)
		(layer "F.Cu")
		(net "M_L_DQ<30>")
	)
	(gr_poly
		(pts
			(xy 73.404222 -103.311198) (xy 73.357486 -103.21417) (xy 73.321418 -103.178356) (xy 73.195688 -103.304086)
			(xy 73.231756 -103.3399) (xy 73.328784 -103.386636)
		)
		(stroke
			(width 0)
			(type solid)
		)
		(fill yes)
		(layer "F.Cu")
		(net "M_L_DQ<29>")
	)
	(gr_poly
		(pts
			(xy 73.421748 -104.805226) (xy 73.385934 -104.769158) (xy 73.288906 -104.722676) (xy 73.213468 -104.798114)
			(xy 73.260204 -104.894888) (xy 73.296018 -104.930956)
		)
		(stroke
			(width 0)
			(type solid)
		)
		(fill yes)
		(layer "F.Cu")
		(net "M_L_DQS_DN<12>")
	)
	(gr_poly
		(pts
			(xy 73.440798 -47.161958) (xy 73.476612 -47.12589) (xy 73.350882 -47.00016) (xy 73.315068 -47.036228)
			(xy 73.268332 -47.133256) (xy 73.34377 -47.208694)
		)
		(stroke
			(width 0)
			(type solid)
		)
		(fill yes)
		(layer "F.Cu")
		(net "M_H_DQ<30>")
	)
	(gr_poly
		(pts
			(xy 73.44156 -104.569768) (xy 73.394824 -104.47274) (xy 73.358756 -104.436926) (xy 73.233026 -104.562656)
			(xy 73.269094 -104.59847) (xy 73.366122 -104.645206)
		)
		(stroke
			(width 0)
			(type solid)
		)
		(fill yes)
		(layer "F.Cu")
		(net "M_L_DQS_DP<12>")
	)
	(gr_poly
		(pts
			(xy 73.45807 -106.06278) (xy 73.422256 -106.026966) (xy 73.325228 -105.98023) (xy 73.24979 -106.055668)
			(xy 73.296526 -106.152696) (xy 73.33234 -106.18851)
		)
		(stroke
			(width 0)
			(type solid)
		)
		(fill yes)
		(layer "F.Cu")
		(net "M_L_DQ<30>")
	)
	(gr_poly
		(pts
			(xy 73.474072 -103.025702) (xy 73.438258 -102.989634) (xy 73.34123 -102.942898) (xy 73.265792 -103.018336)
			(xy 73.312528 -103.115364) (xy 73.348342 -103.151432)
		)
		(stroke
			(width 0)
			(type solid)
		)
		(fill yes)
		(layer "F.Cu")
		(net "M_L_DQ<29>")
	)
	(gr_poly
		(pts
			(xy 73.476866 -45.904404) (xy 73.521824 -45.859446) (xy 73.396094 -45.733716) (xy 73.351136 -45.778674)
			(xy 73.304654 -45.875702) (xy 73.380092 -45.95114)
		)
		(stroke
			(width 0)
			(type solid)
		)
		(fill yes)
		(layer "F.Cu")
		(net "M_H_DQ<27>")
	)
	(gr_poly
		(pts
			(xy 73.477628 -105.827322) (xy 73.431146 -105.730294) (xy 73.395078 -105.69448) (xy 73.269348 -105.82021)
			(xy 73.305416 -105.856024) (xy 73.40219 -105.90276)
		)
		(stroke
			(width 0)
			(type solid)
		)
		(fill yes)
		(layer "F.Cu")
		(net "M_L_DQS_DP<3>")
	)
	(gr_poly
		(pts
			(xy 73.48601 -46.200822) (xy 73.532746 -46.103794) (xy 73.457308 -46.028356) (xy 73.36028 -46.075092)
			(xy 73.324212 -46.110906) (xy 73.449942 -46.236636)
		)
		(stroke
			(width 0)
			(type solid)
		)
		(fill yes)
		(layer "F.Cu")
		(net "M_H_DQ<26>")
	)
	(gr_poly
		(pts
			(xy 73.493884 -102.790244) (xy 73.447148 -102.693216) (xy 73.40219 -102.648512) (xy 73.276714 -102.773988)
			(xy 73.321418 -102.818946) (xy 73.418446 -102.865682)
		)
		(stroke
			(width 0)
			(type solid)
		)
		(fill yes)
		(layer "F.Cu")
		(net "M_L_DQ<28>")
	)
	(gr_poly
		(pts
			(xy 73.503282 -107.329224) (xy 73.458324 -107.284266) (xy 73.361296 -107.23753) (xy 73.285858 -107.312968)
			(xy 73.332594 -107.409996) (xy 73.377552 -107.454954)
		)
		(stroke
			(width 0)
			(type solid)
		)
		(fill yes)
		(layer "F.Cu")
		(net "M_L_DQ<27>")
	)
	(gr_poly
		(pts
			(xy 73.51141 -104.284272) (xy 73.475596 -104.248204) (xy 73.378568 -104.201468) (xy 73.30313 -104.276906)
			(xy 73.349866 -104.373934) (xy 73.38568 -104.410002)
		)
		(stroke
			(width 0)
			(type solid)
		)
		(fill yes)
		(layer "F.Cu")
		(net "M_L_DQS_DP<12>")
	)
	(gr_poly
		(pts
			(xy 73.51395 -107.084876) (xy 73.467214 -106.988102) (xy 73.4314 -106.952034) (xy 73.30567 -107.077764)
			(xy 73.341484 -107.113578) (xy 73.438512 -107.160314)
		)
		(stroke
			(width 0)
			(type solid)
		)
		(fill yes)
		(layer "F.Cu")
		(net "M_L_DQ<26>")
	)
	(gr_poly
		(pts
			(xy 73.515728 -49.46269) (xy 73.480168 -49.36109) (xy 73.373488 -49.36109) (xy 73.337928 -49.46269)
			(xy 73.337928 -49.52619) (xy 73.515728 -49.52619)
		)
		(stroke
			(width 0)
			(type solid)
		)
		(fill yes)
		(layer "F.Cu")
		(net "M_H_DQ<28>")
	)
	(gr_poly
		(pts
			(xy 73.515728 -49.15789) (xy 73.480168 -49.05629) (xy 73.373488 -49.05629) (xy 73.337928 -49.15789)
			(xy 73.337928 -49.20869) (xy 73.515728 -49.20869)
		)
		(stroke
			(width 0)
			(type solid)
		)
		(fill yes)
		(layer "F.Cu")
		(net "M_H_DQ<29>")
	)
	(gr_poly
		(pts
			(xy 73.515728 -48.85309) (xy 73.480168 -48.75149) (xy 73.373488 -48.75149) (xy 73.337928 -48.85309)
			(xy 73.337928 -48.90389) (xy 73.515728 -48.90389)
		)
		(stroke
			(width 0)
			(type solid)
		)
		(fill yes)
		(layer "F.Cu")
		(net "M_H_DQ<24>")
	)
	(gr_poly
		(pts
			(xy 73.515728 -48.54829) (xy 73.480168 -48.44669) (xy 73.373488 -48.44669) (xy 73.337928 -48.54829)
			(xy 73.337928 -48.59909) (xy 73.515728 -48.59909)
		)
		(stroke
			(width 0)
			(type solid)
		)
		(fill yes)
		(layer "F.Cu")
		(net "M_H_DQ<25>")
	)
	(gr_poly
		(pts
			(xy 73.515728 -48.24349) (xy 73.480168 -48.14189) (xy 73.373488 -48.14189) (xy 73.337928 -48.24349)
			(xy 73.337928 -48.29429) (xy 73.515728 -48.29429)
		)
		(stroke
			(width 0)
			(type solid)
		)
		(fill yes)
		(layer "F.Cu")
		(net "M_H_DQS_DP<12>")
	)
	(gr_poly
		(pts
			(xy 73.515728 -47.93869) (xy 73.480168 -47.83709) (xy 73.373488 -47.83709) (xy 73.337928 -47.93869)
			(xy 73.337928 -47.98949) (xy 73.515728 -47.98949)
		)
		(stroke
			(width 0)
			(type solid)
		)
		(fill yes)
		(layer "F.Cu")
		(net "M_H_DQS_DN<12>")
	)
	(gr_poly
		(pts
			(xy 73.515728 -47.63389) (xy 73.480168 -47.53229) (xy 73.373488 -47.53229) (xy 73.337928 -47.63389)
			(xy 73.337928 -47.68469) (xy 73.515728 -47.68469)
		)
		(stroke
			(width 0)
			(type solid)
		)
		(fill yes)
		(layer "F.Cu")
		(net "M_H_DQS_DN<3>")
	)
	(gr_poly
		(pts
			(xy 73.530206 -104.047798) (xy 73.48347 -103.95077) (xy 73.447402 -103.914956) (xy 73.321672 -104.040686)
			(xy 73.35774 -104.0765) (xy 73.454768 -104.123236)
		)
		(stroke
			(width 0)
			(type solid)
		)
		(fill yes)
		(layer "F.Cu")
		(net "M_L_DQ<25>")
	)
	(gr_poly
		(pts
			(xy 73.547732 -105.541826) (xy 73.511918 -105.505758) (xy 73.41489 -105.459276) (xy 73.339452 -105.534714)
			(xy 73.386188 -105.631488) (xy 73.422002 -105.667556)
		)
		(stroke
			(width 0)
			(type solid)
		)
		(fill yes)
		(layer "F.Cu")
		(net "M_L_DQS_DP<3>")
	)
	(gr_poly
		(pts
			(xy 73.566782 -46.425358) (xy 73.602596 -46.38929) (xy 73.476866 -46.26356) (xy 73.441052 -46.299628)
			(xy 73.394316 -46.396402) (xy 73.469754 -46.47184)
		)
		(stroke
			(width 0)
			(type solid)
		)
		(fill yes)
		(layer "F.Cu")
		(net "M_H_DQ<26>")
	)
	(gr_poly
		(pts
			(xy 73.56729 -105.306368) (xy 73.520808 -105.20934) (xy 73.48474 -105.173526) (xy 73.35901 -105.299256)
			(xy 73.395078 -105.33507) (xy 73.491852 -105.381806)
		)
		(stroke
			(width 0)
			(type solid)
		)
		(fill yes)
		(layer "F.Cu")
		(net "M_L_DQS_DN<3>")
	)
	(gr_poly
		(pts
			(xy 73.575672 -46.721776) (xy 73.622408 -46.624748) (xy 73.54697 -46.54931) (xy 73.449942 -46.596046)
			(xy 73.413874 -46.63186) (xy 73.539604 -46.75759)
		)
		(stroke
			(width 0)
			(type solid)
		)
		(fill yes)
		(layer "F.Cu")
		(net "M_H_DQ<31>")
	)
	(gr_poly
		(pts
			(xy 73.584054 -106.79938) (xy 73.54824 -106.763566) (xy 73.451212 -106.71683) (xy 73.375774 -106.792268)
			(xy 73.42251 -106.889296) (xy 73.458324 -106.92511)
		)
		(stroke
			(width 0)
			(type solid)
		)
		(fill yes)
		(layer "F.Cu")
		(net "M_L_DQ<26>")
	)
	(gr_poly
		(pts
			(xy 73.600056 -103.762302) (xy 73.564242 -103.726234) (xy 73.467214 -103.679498) (xy 73.391776 -103.754936)
			(xy 73.438512 -103.851964) (xy 73.474326 -103.888032)
		)
		(stroke
			(width 0)
			(type solid)
		)
		(fill yes)
		(layer "F.Cu")
		(net "M_L_DQ<25>")
	)
	(gr_poly
		(pts
			(xy 73.603612 -106.563922) (xy 73.556876 -106.466894) (xy 73.521062 -106.43108) (xy 73.395332 -106.55681)
			(xy 73.431146 -106.592624) (xy 73.528174 -106.63936)
		)
		(stroke
			(width 0)
			(type solid)
		)
		(fill yes)
		(layer "F.Cu")
		(net "M_L_DQ<31>")
	)
	(gr_poly
		(pts
			(xy 73.619868 -103.526844) (xy 73.573132 -103.429816) (xy 73.537064 -103.394002) (xy 73.411334 -103.519732)
			(xy 73.447402 -103.555546) (xy 73.54443 -103.602282)
		)
		(stroke
			(width 0)
			(type solid)
		)
		(fill yes)
		(layer "F.Cu")
		(net "M_L_DQ<24>")
	)
	(gr_poly
		(pts
			(xy 73.637394 -105.020872) (xy 73.60158 -104.984804) (xy 73.504552 -104.938322) (xy 73.429114 -105.01376)
			(xy 73.47585 -105.110534) (xy 73.511664 -105.146602)
		)
		(stroke
			(width 0)
			(type solid)
		)
		(fill yes)
		(layer "F.Cu")
		(net "M_L_DQS_DN<3>")
	)
	(gr_poly
		(pts
			(xy 73.657206 -104.785414) (xy 73.61047 -104.688386) (xy 73.574402 -104.652572) (xy 73.448672 -104.778302)
			(xy 73.48474 -104.814116) (xy 73.581768 -104.860852)
		)
		(stroke
			(width 0)
			(type solid)
		)
		(fill yes)
		(layer "F.Cu")
		(net "M_L_DQS_DN<12>")
	)
	(gr_poly
		(pts
			(xy 73.673716 -106.278426) (xy 73.637902 -106.242612) (xy 73.540874 -106.195876) (xy 73.465436 -106.271314)
			(xy 73.512172 -106.368342) (xy 73.547986 -106.404156)
		)
		(stroke
			(width 0)
			(type solid)
		)
		(fill yes)
		(layer "F.Cu")
		(net "M_L_DQ<31>")
	)
	(gr_poly
		(pts
			(xy 73.689718 -103.241348) (xy 73.653904 -103.20528) (xy 73.556876 -103.158544) (xy 73.481438 -103.233982)
			(xy 73.528174 -103.33101) (xy 73.563988 -103.367078)
		)
		(stroke
			(width 0)
			(type solid)
		)
		(fill yes)
		(layer "F.Cu")
		(net "M_L_DQ<24>")
	)
	(gr_poly
		(pts
			(xy 73.693274 -106.042968) (xy 73.646792 -105.94594) (xy 73.610724 -105.910126) (xy 73.484994 -106.035856)
			(xy 73.521062 -106.07167) (xy 73.617836 -106.118406)
		)
		(stroke
			(width 0)
			(type solid)
		)
		(fill yes)
		(layer "F.Cu")
		(net "M_L_DQ<30>")
	)
	(gr_poly
		(pts
			(xy 73.70953 -103.00589) (xy 73.662794 -102.908862) (xy 73.626726 -102.873048) (xy 73.50125 -102.998524)
			(xy 73.537064 -103.034592) (xy 73.634092 -103.081328)
		)
		(stroke
			(width 0)
			(type solid)
		)
		(fill yes)
		(layer "F.Cu")
		(net "M_L_DQ<29>")
	)
	(gr_poly
		(pts
			(xy 73.727056 -104.499918) (xy 73.691242 -104.46385) (xy 73.594214 -104.417114) (xy 73.518776 -104.492552)
			(xy 73.565512 -104.58958) (xy 73.601326 -104.625648)
		)
		(stroke
			(width 0)
			(type solid)
		)
		(fill yes)
		(layer "F.Cu")
		(net "M_L_DQS_DN<12>")
	)
	(gr_poly
		(pts
			(xy 73.731628 -49.25949) (xy 73.731628 -49.20869) (xy 73.553828 -49.20869) (xy 73.553828 -49.25949)
			(xy 73.589388 -49.36109) (xy 73.696068 -49.36109)
		)
		(stroke
			(width 0)
			(type solid)
		)
		(fill yes)
		(layer "F.Cu")
		(net "M_H_DQ<29>")
	)
	(gr_poly
		(pts
			(xy 73.731628 -48.95469) (xy 73.731628 -48.90389) (xy 73.553828 -48.90389) (xy 73.553828 -48.95469)
			(xy 73.589388 -49.05629) (xy 73.696068 -49.05629)
		)
		(stroke
			(width 0)
			(type solid)
		)
		(fill yes)
		(layer "F.Cu")
		(net "M_H_DQ<24>")
	)
	(gr_poly
		(pts
			(xy 73.731628 -48.64989) (xy 73.731628 -48.59909) (xy 73.553828 -48.59909) (xy 73.553828 -48.64989)
			(xy 73.589388 -48.75149) (xy 73.696068 -48.75149)
		)
		(stroke
			(width 0)
			(type solid)
		)
		(fill yes)
		(layer "F.Cu")
		(net "M_H_DQ<25>")
	)
	(gr_poly
		(pts
			(xy 73.731628 -48.34509) (xy 73.731628 -48.29429) (xy 73.553828 -48.29429) (xy 73.553828 -48.34509)
			(xy 73.589388 -48.44669) (xy 73.696068 -48.44669)
		)
		(stroke
			(width 0)
			(type solid)
		)
		(fill yes)
		(layer "F.Cu")
		(net "M_H_DQS_DP<12>")
	)
	(gr_poly
		(pts
			(xy 73.731628 -48.04029) (xy 73.731628 -47.98949) (xy 73.553828 -47.98949) (xy 73.553828 -48.04029)
			(xy 73.589388 -48.14189) (xy 73.696068 -48.14189)
		)
		(stroke
			(width 0)
			(type solid)
		)
		(fill yes)
		(layer "F.Cu")
		(net "M_H_DQS_DN<12>")
	)
	(gr_poly
		(pts
			(xy 73.731628 -47.73549) (xy 73.731628 -47.68469) (xy 73.553828 -47.68469) (xy 73.553828 -47.73549)
			(xy 73.589388 -47.83709) (xy 73.696068 -47.83709)
		)
		(stroke
			(width 0)
			(type solid)
		)
		(fill yes)
		(layer "F.Cu")
		(net "M_H_DQS_DN<3>")
	)
	(gr_poly
		(pts
			(xy 73.731628 -47.43069) (xy 73.731628 -47.37989) (xy 73.553828 -47.37989) (xy 73.553828 -47.43069)
			(xy 73.589388 -47.53229) (xy 73.696068 -47.53229)
		)
		(stroke
			(width 0)
			(type solid)
		)
		(fill yes)
		(layer "F.Cu")
		(net "M_H_DQS_DP<3>")
	)
	(gr_poly
		(pts
			(xy 73.731628 -47.12589) (xy 73.731628 -47.07509) (xy 73.553828 -47.07509) (xy 73.553828 -47.12589)
			(xy 73.589388 -47.22749) (xy 73.696068 -47.22749)
		)
		(stroke
			(width 0)
			(type solid)
		)
		(fill yes)
		(layer "F.Cu")
		(net "M_H_DQ<30>")
	)
	(gr_poly
		(pts
			(xy 73.746868 -104.26446) (xy 73.700132 -104.167432) (xy 73.664064 -104.131618) (xy 73.538334 -104.257348)
			(xy 73.574402 -104.293162) (xy 73.67143 -104.339898)
		)
		(stroke
			(width 0)
			(type solid)
		)
		(fill yes)
		(layer "F.Cu")
		(net "M_L_DQS_DP<12>")
	)
	(gr_poly
		(pts
			(xy 73.763378 -105.757472) (xy 73.727564 -105.721404) (xy 73.630536 -105.674922) (xy 73.555098 -105.75036)
			(xy 73.601834 -105.847134) (xy 73.637648 -105.883202)
		)
		(stroke
			(width 0)
			(type solid)
		)
		(fill yes)
		(layer "F.Cu")
		(net "M_L_DQ<30>")
	)
	(gr_poly
		(pts
			(xy 73.779634 -102.72014) (xy 73.743566 -102.684326) (xy 73.646538 -102.63759) (xy 73.5711 -102.713028)
			(xy 73.617836 -102.810056) (xy 73.653904 -102.84587)
		)
		(stroke
			(width 0)
			(type solid)
		)
		(fill yes)
		(layer "F.Cu")
		(net "M_L_DQ<29>")
	)
	(gr_poly
		(pts
			(xy 73.782174 -46.209712) (xy 73.827132 -46.164754) (xy 73.701402 -46.039024) (xy 73.656444 -46.083982)
			(xy 73.609962 -46.18101) (xy 73.6854 -46.256448)
		)
		(stroke
			(width 0)
			(type solid)
		)
		(fill yes)
		(layer "F.Cu")
		(net "M_H_DQ<27>")
	)
	(gr_poly
		(pts
			(xy 73.782936 -105.522014) (xy 73.736454 -105.424986) (xy 73.700386 -105.389172) (xy 73.574656 -105.514902)
			(xy 73.610724 -105.550716) (xy 73.707498 -105.597452)
		)
		(stroke
			(width 0)
			(type solid)
		)
		(fill yes)
		(layer "F.Cu")
		(net "M_L_DQS_DP<3>")
	)
	(gr_poly
		(pts
			(xy 73.799192 -102.484936) (xy 73.752456 -102.387908) (xy 73.707498 -102.343204) (xy 73.582022 -102.46868)
			(xy 73.626726 -102.513638) (xy 73.723754 -102.560374)
		)
		(stroke
			(width 0)
			(type solid)
		)
		(fill yes)
		(layer "F.Cu")
		(net "M_L_DQ<28>")
	)
	(gr_poly
		(pts
			(xy 73.80859 -107.023916) (xy 73.763632 -106.978958) (xy 73.666604 -106.932222) (xy 73.591166 -107.00766)
			(xy 73.637902 -107.104688) (xy 73.68286 -107.149646)
		)
		(stroke
			(width 0)
			(type solid)
		)
		(fill yes)
		(layer "F.Cu")
		(net "M_L_DQ<27>")
	)
	(gr_poly
		(pts
			(xy 73.816718 -103.978964) (xy 73.780904 -103.942896) (xy 73.683876 -103.89616) (xy 73.608438 -103.971598)
			(xy 73.655174 -104.068626) (xy 73.690988 -104.104694)
		)
		(stroke
			(width 0)
			(type solid)
		)
		(fill yes)
		(layer "F.Cu")
		(net "M_L_DQS_DP<12>")
	)
	(gr_poly
		(pts
			(xy 73.819258 -106.779568) (xy 73.772522 -106.68254) (xy 73.736708 -106.646726) (xy 73.610978 -106.772456)
			(xy 73.646792 -106.80827) (xy 73.74382 -106.855006)
		)
		(stroke
			(width 0)
			(type solid)
		)
		(fill yes)
		(layer "F.Cu")
		(net "M_L_DQ<26>")
	)
	(gr_poly
		(pts
			(xy 73.835514 -103.74249) (xy 73.788778 -103.645462) (xy 73.75271 -103.609648) (xy 73.62698 -103.735378)
			(xy 73.663048 -103.771192) (xy 73.760076 -103.817928)
		)
		(stroke
			(width 0)
			(type solid)
		)
		(fill yes)
		(layer "F.Cu")
		(net "M_L_DQ<25>")
	)
	(gr_poly
		(pts
			(xy 73.85304 -105.236518) (xy 73.817226 -105.20045) (xy 73.720198 -105.153968) (xy 73.64476 -105.229406)
			(xy 73.691496 -105.32618) (xy 73.72731 -105.362248)
		)
		(stroke
			(width 0)
			(type solid)
		)
		(fill yes)
		(layer "F.Cu")
		(net "M_L_DQS_DP<3>")
	)
	(gr_poly
		(pts
			(xy 73.872852 -105.00106) (xy 73.826116 -104.904032) (xy 73.790048 -104.868218) (xy 73.664318 -104.993948)
			(xy 73.700386 -105.029762) (xy 73.797414 -105.076498)
		)
		(stroke
			(width 0)
			(type solid)
		)
		(fill yes)
		(layer "F.Cu")
		(net "M_L_DQS_DN<3>")
	)
	(gr_poly
		(pts
			(xy 73.889362 -106.494072) (xy 73.853548 -106.458258) (xy 73.75652 -106.411522) (xy 73.681082 -106.48696)
			(xy 73.727818 -106.583988) (xy 73.763632 -106.619802)
		)
		(stroke
			(width 0)
			(type solid)
		)
		(fill yes)
		(layer "F.Cu")
		(net "M_L_DQ<26>")
	)
	(gr_poly
		(pts
			(xy 73.905364 -103.456994) (xy 73.86955 -103.420926) (xy 73.772522 -103.37419) (xy 73.697084 -103.449628)
			(xy 73.74382 -103.546656) (xy 73.779634 -103.582724)
		)
		(stroke
			(width 0)
			(type solid)
		)
		(fill yes)
		(layer "F.Cu")
		(net "M_L_DQ<25>")
	)
	(gr_poly
		(pts
			(xy 73.90892 -106.258614) (xy 73.862438 -106.161586) (xy 73.82637 -106.125772) (xy 73.70064 -106.251502)
			(xy 73.736708 -106.287316) (xy 73.833482 -106.334052)
		)
		(stroke
			(width 0)
			(type solid)
		)
		(fill yes)
		(layer "F.Cu")
		(net "M_L_DQ<31>")
	)
	(gr_poly
		(pts
			(xy 73.925176 -103.221536) (xy 73.87844 -103.124508) (xy 73.842372 -103.088694) (xy 73.716896 -103.21417)
			(xy 73.75271 -103.250238) (xy 73.849738 -103.296974)
		)
		(stroke
			(width 0)
			(type solid)
		)
		(fill yes)
		(layer "F.Cu")
		(net "M_L_DQ<24>")
	)
	(gr_poly
		(pts
			(xy 73.942702 -104.715564) (xy 73.906888 -104.679496) (xy 73.80986 -104.63276) (xy 73.734422 -104.708198)
			(xy 73.781158 -104.805226) (xy 73.816972 -104.841294)
		)
		(stroke
			(width 0)
			(type solid)
		)
		(fill yes)
		(layer "F.Cu")
		(net "M_L_DQS_DN<3>")
	)
	(gr_poly
		(pts
			(xy 73.947528 -49.46269) (xy 73.911968 -49.36109) (xy 73.805288 -49.36109) (xy 73.769728 -49.46269)
			(xy 73.769728 -49.52619) (xy 73.947528 -49.52619)
		)
		(stroke
			(width 0)
			(type solid)
		)
		(fill yes)
		(layer "F.Cu")
		(net "M_H_DQ<28>")
	)
	(gr_poly
		(pts
			(xy 73.947528 -49.15789) (xy 73.911968 -49.05629) (xy 73.805288 -49.05629) (xy 73.769728 -49.15789)
			(xy 73.769728 -49.20869) (xy 73.947528 -49.20869)
		)
		(stroke
			(width 0)
			(type solid)
		)
		(fill yes)
		(layer "F.Cu")
		(net "M_H_DQ<29>")
	)
	(gr_poly
		(pts
			(xy 73.947528 -48.85309) (xy 73.911968 -48.75149) (xy 73.805288 -48.75149) (xy 73.769728 -48.85309)
			(xy 73.769728 -48.90389) (xy 73.947528 -48.90389)
		)
		(stroke
			(width 0)
			(type solid)
		)
		(fill yes)
		(layer "F.Cu")
		(net "M_H_DQ<24>")
	)
	(gr_poly
		(pts
			(xy 73.947528 -48.54829) (xy 73.911968 -48.44669) (xy 73.805288 -48.44669) (xy 73.769728 -48.54829)
			(xy 73.769728 -48.59909) (xy 73.947528 -48.59909)
		)
		(stroke
			(width 0)
			(type solid)
		)
		(fill yes)
		(layer "F.Cu")
		(net "M_H_DQ<25>")
	)
	(gr_poly
		(pts
			(xy 73.947528 -48.24349) (xy 73.911968 -48.14189) (xy 73.805288 -48.14189) (xy 73.769728 -48.24349)
			(xy 73.769728 -48.29429) (xy 73.947528 -48.29429)
		)
		(stroke
			(width 0)
			(type solid)
		)
		(fill yes)
		(layer "F.Cu")
		(net "M_H_DQS_DP<12>")
	)
	(gr_poly
		(pts
			(xy 73.947528 -47.93869) (xy 73.911968 -47.83709) (xy 73.805288 -47.83709) (xy 73.769728 -47.93869)
			(xy 73.769728 -47.98949) (xy 73.947528 -47.98949)
		)
		(stroke
			(width 0)
			(type solid)
		)
		(fill yes)
		(layer "F.Cu")
		(net "M_H_DQS_DN<12>")
	)
	(gr_poly
		(pts
			(xy 73.947528 -47.63389) (xy 73.911968 -47.53229) (xy 73.805288 -47.53229) (xy 73.769728 -47.63389)
			(xy 73.769728 -47.68469) (xy 73.947528 -47.68469)
		)
		(stroke
			(width 0)
			(type solid)
		)
		(fill yes)
		(layer "F.Cu")
		(net "M_H_DQS_DN<3>")
	)
	(gr_poly
		(pts
			(xy 73.947528 -47.32909) (xy 73.911968 -47.22749) (xy 73.805288 -47.22749) (xy 73.769728 -47.32909)
			(xy 73.769728 -47.37989) (xy 73.947528 -47.37989)
		)
		(stroke
			(width 0)
			(type solid)
		)
		(fill yes)
		(layer "F.Cu")
		(net "M_H_DQS_DP<3>")
	)
	(gr_poly
		(pts
			(xy 73.947528 -47.02429) (xy 73.911968 -46.92269) (xy 73.805288 -46.92269) (xy 73.769728 -47.02429)
			(xy 73.769728 -47.07509) (xy 73.947528 -47.07509)
		)
		(stroke
			(width 0)
			(type solid)
		)
		(fill yes)
		(layer "F.Cu")
		(net "M_H_DQ<30>")
	)
	(gr_poly
		(pts
			(xy 73.947528 -46.71949) (xy 73.911968 -46.61789) (xy 73.805288 -46.61789) (xy 73.769728 -46.71949)
			(xy 73.769728 -46.77029) (xy 73.947528 -46.77029)
		)
		(stroke
			(width 0)
			(type solid)
		)
		(fill yes)
		(layer "F.Cu")
		(net "M_H_DQ<31>")
	)
	(gr_poly
		(pts
			(xy 73.962514 -104.480106) (xy 73.915778 -104.383078) (xy 73.87971 -104.347264) (xy 73.75398 -104.472994)
			(xy 73.790048 -104.508808) (xy 73.887076 -104.555544)
		)
		(stroke
			(width 0)
			(type solid)
		)
		(fill yes)
		(layer "F.Cu")
		(net "M_L_DQS_DN<12>")
	)
	(gr_poly
		(pts
			(xy 73.979024 -105.973118) (xy 73.94321 -105.93705) (xy 73.846182 -105.890568) (xy 73.770744 -105.966006)
			(xy 73.81748 -106.06278) (xy 73.853294 -106.098848)
		)
		(stroke
			(width 0)
			(type solid)
		)
		(fill yes)
		(layer "F.Cu")
		(net "M_L_DQ<31>")
	)
	(gr_poly
		(pts
			(xy 73.99528 -102.935786) (xy 73.959212 -102.899972) (xy 73.862184 -102.853236) (xy 73.786746 -102.928674)
			(xy 73.833482 -103.025702) (xy 73.86955 -103.061516)
		)
		(stroke
			(width 0)
			(type solid)
		)
		(fill yes)
		(layer "F.Cu")
		(net "M_L_DQ<24>")
	)
	(gr_poly
		(pts
			(xy 73.998582 -105.73766) (xy 73.9521 -105.640632) (xy 73.916032 -105.604818) (xy 73.790302 -105.730548)
			(xy 73.82637 -105.766362) (xy 73.923144 -105.813098)
		)
		(stroke
			(width 0)
			(type solid)
		)
		(fill yes)
		(layer "F.Cu")
		(net "M_L_DQ<30>")
	)
	(gr_poly
		(pts
			(xy 74.014838 -102.700582) (xy 73.968102 -102.603554) (xy 73.932034 -102.56774) (xy 73.806558 -102.693216)
			(xy 73.842372 -102.729284) (xy 73.9394 -102.77602)
		)
		(stroke
			(width 0)
			(type solid)
		)
		(fill yes)
		(layer "F.Cu")
		(net "M_L_DQ<29>")
	)
	(gr_poly
		(pts
			(xy 74.032364 -104.19461) (xy 73.99655 -104.158542) (xy 73.899522 -104.111806) (xy 73.824084 -104.187244)
			(xy 73.87082 -104.284272) (xy 73.906634 -104.32034)
		)
		(stroke
			(width 0)
			(type solid)
		)
		(fill yes)
		(layer "F.Cu")
		(net "M_L_DQS_DN<12>")
	)
	(gr_poly
		(pts
			(xy 74.052176 -103.959152) (xy 74.00544 -103.862124) (xy 73.969372 -103.82631) (xy 73.843642 -103.95204)
			(xy 73.87971 -103.987854) (xy 73.976738 -104.03459)
		)
		(stroke
			(width 0)
			(type solid)
		)
		(fill yes)
		(layer "F.Cu")
		(net "M_L_DQS_DP<12>")
	)
	(gr_poly
		(pts
			(xy 74.068686 -105.452164) (xy 74.032872 -105.416096) (xy 73.935844 -105.369614) (xy 73.860406 -105.445052)
			(xy 73.907142 -105.541826) (xy 73.942956 -105.577894)
		)
		(stroke
			(width 0)
			(type solid)
		)
		(fill yes)
		(layer "F.Cu")
		(net "M_L_DQ<30>")
	)
	(gr_poly
		(pts
			(xy 74.088498 -105.216706) (xy 74.041762 -105.119678) (xy 74.005694 -105.083864) (xy 73.879964 -105.209594)
			(xy 73.916032 -105.245408) (xy 74.01306 -105.292144)
		)
		(stroke
			(width 0)
			(type solid)
		)
		(fill yes)
		(layer "F.Cu")
		(net "M_L_DQS_DP<3>")
	)
	(gr_poly
		(pts
			(xy 74.113898 -106.718608) (xy 74.06894 -106.67365) (xy 73.971912 -106.626914) (xy 73.896474 -106.702352)
			(xy 73.94321 -106.79938) (xy 73.988168 -106.844338)
		)
		(stroke
			(width 0)
			(type solid)
		)
		(fill yes)
		(layer "F.Cu")
		(net "M_L_DQ<27>")
	)
	(gr_poly
		(pts
			(xy 74.122026 -103.673656) (xy 74.086212 -103.637588) (xy 73.989184 -103.590852) (xy 73.913746 -103.66629)
			(xy 73.960482 -103.763318) (xy 73.996296 -103.799386)
		)
		(stroke
			(width 0)
			(type solid)
		)
		(fill yes)
		(layer "F.Cu")
		(net "M_L_DQS_DP<12>")
	)
	(gr_poly
		(pts
			(xy 74.124566 -106.47426) (xy 74.078084 -106.377232) (xy 74.042016 -106.341418) (xy 73.916286 -106.467148)
			(xy 73.952354 -106.502962) (xy 74.049128 -106.549698)
		)
		(stroke
			(width 0)
			(type solid)
		)
		(fill yes)
		(layer "F.Cu")
		(net "M_L_DQ<26>")
	)
	(gr_poly
		(pts
			(xy 74.140822 -103.437182) (xy 74.094086 -103.340154) (xy 74.058018 -103.30434) (xy 73.932288 -103.43007)
			(xy 73.968356 -103.465884) (xy 74.065384 -103.51262)
		)
		(stroke
			(width 0)
			(type solid)
		)
		(fill yes)
		(layer "F.Cu")
		(net "M_L_DQ<25>")
	)
	(gr_poly
		(pts
			(xy 74.158348 -104.93121) (xy 74.122534 -104.895142) (xy 74.025506 -104.848406) (xy 73.950068 -104.923844)
			(xy 73.996804 -105.020872) (xy 74.032618 -105.05694)
		)
		(stroke
			(width 0)
			(type solid)
		)
		(fill yes)
		(layer "F.Cu")
		(net "M_L_DQS_DP<3>")
	)
	(gr_poly
		(pts
			(xy 74.163428 -49.25949) (xy 74.163428 -49.20869) (xy 73.985628 -49.20869) (xy 73.985628 -49.25949)
			(xy 74.021188 -49.36109) (xy 74.127868 -49.36109)
		)
		(stroke
			(width 0)
			(type solid)
		)
		(fill yes)
		(layer "F.Cu")
		(net "M_H_DQ<29>")
	)
	(gr_poly
		(pts
			(xy 74.163428 -48.95469) (xy 74.163428 -48.90389) (xy 73.985628 -48.90389) (xy 73.985628 -48.95469)
			(xy 74.021188 -49.05629) (xy 74.127868 -49.05629)
		)
		(stroke
			(width 0)
			(type solid)
		)
		(fill yes)
		(layer "F.Cu")
		(net "M_H_DQ<24>")
	)
	(gr_poly
		(pts
			(xy 74.163428 -48.64989) (xy 74.163428 -48.59909) (xy 73.985628 -48.59909) (xy 73.985628 -48.64989)
			(xy 74.021188 -48.75149) (xy 74.127868 -48.75149)
		)
		(stroke
			(width 0)
			(type solid)
		)
		(fill yes)
		(layer "F.Cu")
		(net "M_H_DQ<25>")
	)
	(gr_poly
		(pts
			(xy 74.163428 -48.34509) (xy 74.163428 -48.29429) (xy 73.985628 -48.29429) (xy 73.985628 -48.34509)
			(xy 74.021188 -48.44669) (xy 74.127868 -48.44669)
		)
		(stroke
			(width 0)
			(type solid)
		)
		(fill yes)
		(layer "F.Cu")
		(net "M_H_DQS_DP<12>")
	)
	(gr_poly
		(pts
			(xy 74.163428 -48.04029) (xy 74.163428 -47.98949) (xy 73.985628 -47.98949) (xy 73.985628 -48.04029)
			(xy 74.021188 -48.14189) (xy 74.127868 -48.14189)
		)
		(stroke
			(width 0)
			(type solid)
		)
		(fill yes)
		(layer "F.Cu")
		(net "M_H_DQS_DN<12>")
	)
	(gr_poly
		(pts
			(xy 74.163428 -47.73549) (xy 74.163428 -47.68469) (xy 73.985628 -47.68469) (xy 73.985628 -47.73549)
			(xy 74.021188 -47.83709) (xy 74.127868 -47.83709)
		)
		(stroke
			(width 0)
			(type solid)
		)
		(fill yes)
		(layer "F.Cu")
		(net "M_H_DQS_DN<3>")
	)
	(gr_poly
		(pts
			(xy 74.163428 -47.43069) (xy 74.163428 -47.37989) (xy 73.985628 -47.37989) (xy 73.985628 -47.43069)
			(xy 74.021188 -47.53229) (xy 74.127868 -47.53229)
		)
		(stroke
			(width 0)
			(type solid)
		)
		(fill yes)
		(layer "F.Cu")
		(net "M_H_DQS_DP<3>")
	)
	(gr_poly
		(pts
			(xy 74.163428 -47.12589) (xy 74.163428 -47.07509) (xy 73.985628 -47.07509) (xy 73.985628 -47.12589)
			(xy 74.021188 -47.22749) (xy 74.127868 -47.22749)
		)
		(stroke
			(width 0)
			(type solid)
		)
		(fill yes)
		(layer "F.Cu")
		(net "M_H_DQ<30>")
	)
	(gr_poly
		(pts
			(xy 74.163428 -46.82109) (xy 74.163428 -46.77029) (xy 73.985628 -46.77029) (xy 73.985628 -46.82109)
			(xy 74.021188 -46.92269) (xy 74.127868 -46.92269)
		)
		(stroke
			(width 0)
			(type solid)
		)
		(fill yes)
		(layer "F.Cu")
		(net "M_H_DQ<31>")
	)
	(gr_poly
		(pts
			(xy 74.163428 -46.51629) (xy 74.163428 -46.46549) (xy 73.985628 -46.46549) (xy 73.985628 -46.51629)
			(xy 74.021188 -46.61789) (xy 74.127868 -46.61789)
		)
		(stroke
			(width 0)
			(type solid)
		)
		(fill yes)
		(layer "F.Cu")
		(net "M_H_DQ<26>")
	)
	(gr_poly
		(pts
			(xy 74.163428 -46.21149) (xy 74.163428 -46.14799) (xy 73.985628 -46.14799) (xy 73.985628 -46.21149)
			(xy 74.021188 -46.31309) (xy 74.127868 -46.31309)
		)
		(stroke
			(width 0)
			(type solid)
		)
		(fill yes)
		(layer "F.Cu")
		(net "M_H_DQ<27>")
	)
	(gr_poly
		(pts
			(xy 74.17816 -104.695752) (xy 74.131424 -104.598724) (xy 74.095356 -104.56291) (xy 73.969626 -104.68864)
			(xy 74.005694 -104.724454) (xy 74.102722 -104.77119)
		)
		(stroke
			(width 0)
			(type solid)
		)
		(fill yes)
		(layer "F.Cu")
		(net "M_L_DQS_DN<3>")
	)
	(gr_poly
		(pts
			(xy 74.19467 -106.188764) (xy 74.158856 -106.152696) (xy 74.061828 -106.106214) (xy 73.98639 -106.181652)
			(xy 74.033126 -106.278426) (xy 74.06894 -106.314494)
		)
		(stroke
			(width 0)
			(type solid)
		)
		(fill yes)
		(layer "F.Cu")
		(net "M_L_DQ<26>")
	)
	(gr_poly
		(pts
			(xy 74.210672 -103.151686) (xy 74.174858 -103.115618) (xy 74.07783 -103.068882) (xy 74.002392 -103.14432)
			(xy 74.049128 -103.241348) (xy 74.084942 -103.277416)
		)
		(stroke
			(width 0)
			(type solid)
		)
		(fill yes)
		(layer "F.Cu")
		(net "M_L_DQ<25>")
	)
	(gr_poly
		(pts
			(xy 74.214228 -105.953306) (xy 74.167746 -105.856278) (xy 74.131678 -105.820464) (xy 74.005948 -105.946194)
			(xy 74.042016 -105.982008) (xy 74.13879 -106.028744)
		)
		(stroke
			(width 0)
			(type solid)
		)
		(fill yes)
		(layer "F.Cu")
		(net "M_L_DQ<31>")
	)
	(gr_poly
		(pts
			(xy 74.24801 -104.410256) (xy 74.212196 -104.374188) (xy 74.115168 -104.327452) (xy 74.03973 -104.40289)
			(xy 74.086466 -104.499918) (xy 74.12228 -104.535986)
		)
		(stroke
			(width 0)
			(type solid)
		)
		(fill yes)
		(layer "F.Cu")
		(net "M_L_DQS_DN<3>")
	)
	(gr_poly
		(pts
			(xy 74.267822 -104.174798) (xy 74.221086 -104.07777) (xy 74.185018 -104.041956) (xy 74.059288 -104.167686)
			(xy 74.095356 -104.2035) (xy 74.192384 -104.250236)
		)
		(stroke
			(width 0)
			(type solid)
		)
		(fill yes)
		(layer "F.Cu")
		(net "M_L_DQS_DN<12>")
	)
	(gr_poly
		(pts
			(xy 74.284332 -105.66781) (xy 74.248518 -105.631742) (xy 74.15149 -105.58526) (xy 74.076052 -105.660698)
			(xy 74.122788 -105.757472) (xy 74.158602 -105.79354)
		)
		(stroke
			(width 0)
			(type solid)
		)
		(fill yes)
		(layer "F.Cu")
		(net "M_L_DQ<31>")
	)
	(gr_poly
		(pts
			(xy 74.304144 -105.432352) (xy 74.257408 -105.335324) (xy 74.22134 -105.29951) (xy 74.09561 -105.42524)
			(xy 74.131678 -105.461054) (xy 74.228706 -105.50779)
		)
		(stroke
			(width 0)
			(type solid)
		)
		(fill yes)
		(layer "F.Cu")
		(net "M_L_DQ<30>")
	)
	(gr_poly
		(pts
			(xy 74.336402 -102.882954) (xy 74.336402 -102.832154) (xy 74.158602 -102.832154) (xy 74.158602 -102.882954)
			(xy 74.194162 -102.984554) (xy 74.300842 -102.984554)
		)
		(stroke
			(width 0)
			(type solid)
		)
		(fill yes)
		(layer "F.Cu")
		(net "M_L_DQ<24>")
	)
	(gr_poly
		(pts
			(xy 74.336402 -102.578154) (xy 74.336402 -102.527354) (xy 74.158602 -102.527354) (xy 74.158602 -102.578154)
			(xy 74.194162 -102.679754) (xy 74.300842 -102.679754)
		)
		(stroke
			(width 0)
			(type solid)
		)
		(fill yes)
		(layer "F.Cu")
		(net "M_L_DQ<29>")
	)
	(gr_poly
		(pts
			(xy 74.336402 -102.273354) (xy 74.336402 -102.209854) (xy 74.158602 -102.209854) (xy 74.158602 -102.273354)
			(xy 74.194162 -102.374954) (xy 74.300842 -102.374954)
		)
		(stroke
			(width 0)
			(type solid)
		)
		(fill yes)
		(layer "F.Cu")
		(net "M_L_DQ<28>")
	)
	(gr_poly
		(pts
			(xy 74.337672 -103.889302) (xy 74.301858 -103.853234) (xy 74.20483 -103.806498) (xy 74.129392 -103.881936)
			(xy 74.176128 -103.978964) (xy 74.211942 -104.015032)
		)
		(stroke
			(width 0)
			(type solid)
		)
		(fill yes)
		(layer "F.Cu")
		(net "M_L_DQS_DN<12>")
	)
	(gr_poly
		(pts
			(xy 74.357484 -103.653844) (xy 74.310748 -103.556816) (xy 74.27468 -103.521002) (xy 74.14895 -103.646732)
			(xy 74.185018 -103.682546) (xy 74.282046 -103.729282)
		)
		(stroke
			(width 0)
			(type solid)
		)
		(fill yes)
		(layer "F.Cu")
		(net "M_L_DQS_DP<12>")
	)
	(gr_poly
		(pts
			(xy 74.373994 -105.146856) (xy 74.33818 -105.110788) (xy 74.241152 -105.064052) (xy 74.165714 -105.13949)
			(xy 74.21245 -105.236518) (xy 74.248264 -105.272586)
		)
		(stroke
			(width 0)
			(type solid)
		)
		(fill yes)
		(layer "F.Cu")
		(net "M_L_DQ<30>")
	)
	(gr_poly
		(pts
			(xy 74.379328 -49.46269) (xy 74.343768 -49.36109) (xy 74.237088 -49.36109) (xy 74.201528 -49.46269)
			(xy 74.201528 -49.52619) (xy 74.379328 -49.52619)
		)
		(stroke
			(width 0)
			(type solid)
		)
		(fill yes)
		(layer "F.Cu")
		(net "M_H_DQ<28>")
	)
	(gr_poly
		(pts
			(xy 74.379328 -49.15789) (xy 74.343768 -49.05629) (xy 74.237088 -49.05629) (xy 74.201528 -49.15789)
			(xy 74.201528 -49.20869) (xy 74.379328 -49.20869)
		)
		(stroke
			(width 0)
			(type solid)
		)
		(fill yes)
		(layer "F.Cu")
		(net "M_H_DQ<29>")
	)
	(gr_poly
		(pts
			(xy 74.379328 -48.85309) (xy 74.343768 -48.75149) (xy 74.237088 -48.75149) (xy 74.201528 -48.85309)
			(xy 74.201528 -48.90389) (xy 74.379328 -48.90389)
		)
		(stroke
			(width 0)
			(type solid)
		)
		(fill yes)
		(layer "F.Cu")
		(net "M_H_DQ<24>")
	)
	(gr_poly
		(pts
			(xy 74.379328 -48.54829) (xy 74.343768 -48.44669) (xy 74.237088 -48.44669) (xy 74.201528 -48.54829)
			(xy 74.201528 -48.59909) (xy 74.379328 -48.59909)
		)
		(stroke
			(width 0)
			(type solid)
		)
		(fill yes)
		(layer "F.Cu")
		(net "M_H_DQ<25>")
	)
	(gr_poly
		(pts
			(xy 74.379328 -48.24349) (xy 74.343768 -48.14189) (xy 74.237088 -48.14189) (xy 74.201528 -48.24349)
			(xy 74.201528 -48.29429) (xy 74.379328 -48.29429)
		)
		(stroke
			(width 0)
			(type solid)
		)
		(fill yes)
		(layer "F.Cu")
		(net "M_H_DQS_DP<12>")
	)
	(gr_poly
		(pts
			(xy 74.379328 -47.93869) (xy 74.343768 -47.83709) (xy 74.237088 -47.83709) (xy 74.201528 -47.93869)
			(xy 74.201528 -47.98949) (xy 74.379328 -47.98949)
		)
		(stroke
			(width 0)
			(type solid)
		)
		(fill yes)
		(layer "F.Cu")
		(net "M_H_DQS_DN<12>")
	)
	(gr_poly
		(pts
			(xy 74.379328 -47.63389) (xy 74.343768 -47.53229) (xy 74.237088 -47.53229) (xy 74.201528 -47.63389)
			(xy 74.201528 -47.68469) (xy 74.379328 -47.68469)
		)
		(stroke
			(width 0)
			(type solid)
		)
		(fill yes)
		(layer "F.Cu")
		(net "M_H_DQS_DN<3>")
	)
	(gr_poly
		(pts
			(xy 74.379328 -47.32909) (xy 74.343768 -47.22749) (xy 74.237088 -47.22749) (xy 74.201528 -47.32909)
			(xy 74.201528 -47.37989) (xy 74.379328 -47.37989)
		)
		(stroke
			(width 0)
			(type solid)
		)
		(fill yes)
		(layer "F.Cu")
		(net "M_H_DQS_DP<3>")
	)
	(gr_poly
		(pts
			(xy 74.379328 -47.02429) (xy 74.343768 -46.92269) (xy 74.237088 -46.92269) (xy 74.201528 -47.02429)
			(xy 74.201528 -47.07509) (xy 74.379328 -47.07509)
		)
		(stroke
			(width 0)
			(type solid)
		)
		(fill yes)
		(layer "F.Cu")
		(net "M_H_DQ<30>")
	)
	(gr_poly
		(pts
			(xy 74.379328 -46.71949) (xy 74.343768 -46.61789) (xy 74.237088 -46.61789) (xy 74.201528 -46.71949)
			(xy 74.201528 -46.77029) (xy 74.379328 -46.77029)
		)
		(stroke
			(width 0)
			(type solid)
		)
		(fill yes)
		(layer "F.Cu")
		(net "M_H_DQ<31>")
	)
	(gr_poly
		(pts
			(xy 74.379328 -46.41469) (xy 74.343768 -46.31309) (xy 74.237088 -46.31309) (xy 74.201528 -46.41469)
			(xy 74.201528 -46.46549) (xy 74.379328 -46.46549)
		)
		(stroke
			(width 0)
			(type solid)
		)
		(fill yes)
		(layer "F.Cu")
		(net "M_H_DQ<26>")
	)
	(gr_poly
		(pts
			(xy 74.393806 -104.911398) (xy 74.34707 -104.81437) (xy 74.311002 -104.778556) (xy 74.185272 -104.904286)
			(xy 74.22134 -104.9401) (xy 74.318368 -104.986836)
		)
		(stroke
			(width 0)
			(type solid)
		)
		(fill yes)
		(layer "F.Cu")
		(net "M_L_DQS_DP<3>")
	)
	(gr_poly
		(pts
			(xy 74.419206 -106.4133) (xy 74.374248 -106.368342) (xy 74.277474 -106.321606) (xy 74.202036 -106.397044)
			(xy 74.248518 -106.494072) (xy 74.293476 -106.53903)
		)
		(stroke
			(width 0)
			(type solid)
		)
		(fill yes)
		(layer "F.Cu")
		(net "M_L_DQ<27>")
	)
	(gr_poly
		(pts
			(xy 74.429874 -106.168952) (xy 74.383392 -106.071924) (xy 74.347324 -106.03611) (xy 74.221594 -106.16184)
			(xy 74.257662 -106.197654) (xy 74.354436 -106.24439)
		)
		(stroke
			(width 0)
			(type solid)
		)
		(fill yes)
		(layer "F.Cu")
		(net "M_L_DQ<26>")
	)
	(gr_poly
		(pts
			(xy 74.463656 -104.625902) (xy 74.427842 -104.589834) (xy 74.330814 -104.543098) (xy 74.255376 -104.618536)
			(xy 74.302112 -104.715564) (xy 74.337926 -104.751632)
		)
		(stroke
			(width 0)
			(type solid)
		)
		(fill yes)
		(layer "F.Cu")
		(net "M_L_DQS_DP<3>")
	)
	(gr_poly
		(pts
			(xy 74.483468 -104.390444) (xy 74.436732 -104.293416) (xy 74.400664 -104.257602) (xy 74.274934 -104.383332)
			(xy 74.311002 -104.419146) (xy 74.40803 -104.465882)
		)
		(stroke
			(width 0)
			(type solid)
		)
		(fill yes)
		(layer "F.Cu")
		(net "M_L_DQS_DN<3>")
	)
	(gr_poly
		(pts
			(xy 74.499978 -105.883456) (xy 74.464164 -105.847388) (xy 74.367136 -105.800906) (xy 74.291698 -105.876344)
			(xy 74.338434 -105.973118) (xy 74.374248 -106.009186)
		)
		(stroke
			(width 0)
			(type solid)
		)
		(fill yes)
		(layer "F.Cu")
		(net "M_L_DQ<26>")
	)
	(gr_poly
		(pts
			(xy 74.51979 -105.647998) (xy 74.473054 -105.55097) (xy 74.436986 -105.515156) (xy 74.311256 -105.640886)
			(xy 74.347324 -105.6767) (xy 74.444352 -105.723436)
		)
		(stroke
			(width 0)
			(type solid)
		)
		(fill yes)
		(layer "F.Cu")
		(net "M_L_DQ<31>")
	)
	(gr_poly
		(pts
			(xy 74.552302 -103.390954) (xy 74.516742 -103.289354) (xy 74.410062 -103.289354) (xy 74.374502 -103.390954)
			(xy 74.374502 -103.441754) (xy 74.552302 -103.441754)
		)
		(stroke
			(width 0)
			(type solid)
		)
		(fill yes)
		(layer "F.Cu")
		(net "M_L_DQS_DP<12>")
	)
	(gr_poly
		(pts
			(xy 74.552302 -103.086154) (xy 74.516742 -102.984554) (xy 74.410062 -102.984554) (xy 74.374502 -103.086154)
			(xy 74.374502 -103.136954) (xy 74.552302 -103.136954)
		)
		(stroke
			(width 0)
			(type solid)
		)
		(fill yes)
		(layer "F.Cu")
		(net "M_L_DQ<25>")
	)
	(gr_poly
		(pts
			(xy 74.552302 -102.781354) (xy 74.516742 -102.679754) (xy 74.410062 -102.679754) (xy 74.374502 -102.781354)
			(xy 74.374502 -102.832154) (xy 74.552302 -102.832154)
		)
		(stroke
			(width 0)
			(type solid)
		)
		(fill yes)
		(layer "F.Cu")
		(net "M_L_DQ<24>")
	)
	(gr_poly
		(pts
			(xy 74.552302 -102.476554) (xy 74.516742 -102.374954) (xy 74.410062 -102.374954) (xy 74.374502 -102.476554)
			(xy 74.374502 -102.527354) (xy 74.552302 -102.527354)
		)
		(stroke
			(width 0)
			(type solid)
		)
		(fill yes)
		(layer "F.Cu")
		(net "M_L_DQ<29>")
	)
	(gr_poly
		(pts
			(xy 74.553318 -104.104948) (xy 74.517504 -104.06888) (xy 74.420476 -104.022144) (xy 74.345038 -104.097582)
			(xy 74.391774 -104.19461) (xy 74.427588 -104.230678)
		)
		(stroke
			(width 0)
			(type solid)
		)
		(fill yes)
		(layer "F.Cu")
		(net "M_L_DQS_DN<3>")
	)
	(gr_poly
		(pts
			(xy 74.58964 -105.362502) (xy 74.553826 -105.326434) (xy 74.456798 -105.279698) (xy 74.38136 -105.355136)
			(xy 74.428096 -105.452164) (xy 74.46391 -105.488232)
		)
		(stroke
			(width 0)
			(type solid)
		)
		(fill yes)
		(layer "F.Cu")
		(net "M_L_DQ<31>")
	)
	(gr_poly
		(pts
			(xy 74.595228 -49.25949) (xy 74.595228 -49.20869) (xy 74.417428 -49.20869) (xy 74.417428 -49.25949)
			(xy 74.452988 -49.36109) (xy 74.559668 -49.36109)
		)
		(stroke
			(width 0)
			(type solid)
		)
		(fill yes)
		(layer "F.Cu")
		(net "M_H_DQ<29>")
	)
	(gr_poly
		(pts
			(xy 74.595228 -48.95469) (xy 74.595228 -48.90389) (xy 74.417428 -48.90389) (xy 74.417428 -48.95469)
			(xy 74.452988 -49.05629) (xy 74.559668 -49.05629)
		)
		(stroke
			(width 0)
			(type solid)
		)
		(fill yes)
		(layer "F.Cu")
		(net "M_H_DQ<24>")
	)
	(gr_poly
		(pts
			(xy 74.595228 -48.64989) (xy 74.595228 -48.59909) (xy 74.417428 -48.59909) (xy 74.417428 -48.64989)
			(xy 74.452988 -48.75149) (xy 74.559668 -48.75149)
		)
		(stroke
			(width 0)
			(type solid)
		)
		(fill yes)
		(layer "F.Cu")
		(net "M_H_DQ<25>")
	)
	(gr_poly
		(pts
			(xy 74.595228 -48.34509) (xy 74.595228 -48.29429) (xy 74.417428 -48.29429) (xy 74.417428 -48.34509)
			(xy 74.452988 -48.44669) (xy 74.559668 -48.44669)
		)
		(stroke
			(width 0)
			(type solid)
		)
		(fill yes)
		(layer "F.Cu")
		(net "M_H_DQS_DP<12>")
	)
	(gr_poly
		(pts
			(xy 74.595228 -48.04029) (xy 74.595228 -47.98949) (xy 74.417428 -47.98949) (xy 74.417428 -48.04029)
			(xy 74.452988 -48.14189) (xy 74.559668 -48.14189)
		)
		(stroke
			(width 0)
			(type solid)
		)
		(fill yes)
		(layer "F.Cu")
		(net "M_H_DQS_DN<12>")
	)
	(gr_poly
		(pts
			(xy 74.595228 -47.73549) (xy 74.595228 -47.68469) (xy 74.417428 -47.68469) (xy 74.417428 -47.73549)
			(xy 74.452988 -47.83709) (xy 74.559668 -47.83709)
		)
		(stroke
			(width 0)
			(type solid)
		)
		(fill yes)
		(layer "F.Cu")
		(net "M_H_DQS_DN<3>")
	)
	(gr_poly
		(pts
			(xy 74.595228 -47.43069) (xy 74.595228 -47.37989) (xy 74.417428 -47.37989) (xy 74.417428 -47.43069)
			(xy 74.452988 -47.53229) (xy 74.559668 -47.53229)
		)
		(stroke
			(width 0)
			(type solid)
		)
		(fill yes)
		(layer "F.Cu")
		(net "M_H_DQS_DP<3>")
	)
	(gr_poly
		(pts
			(xy 74.595228 -47.12589) (xy 74.595228 -47.07509) (xy 74.417428 -47.07509) (xy 74.417428 -47.12589)
			(xy 74.452988 -47.22749) (xy 74.559668 -47.22749)
		)
		(stroke
			(width 0)
			(type solid)
		)
		(fill yes)
		(layer "F.Cu")
		(net "M_H_DQ<30>")
	)
	(gr_poly
		(pts
			(xy 74.595228 -46.82109) (xy 74.595228 -46.77029) (xy 74.417428 -46.77029) (xy 74.417428 -46.82109)
			(xy 74.452988 -46.92269) (xy 74.559668 -46.92269)
		)
		(stroke
			(width 0)
			(type solid)
		)
		(fill yes)
		(layer "F.Cu")
		(net "M_H_DQ<31>")
	)
	(gr_poly
		(pts
			(xy 74.595228 -46.51629) (xy 74.595228 -46.46549) (xy 74.417428 -46.46549) (xy 74.417428 -46.51629)
			(xy 74.452988 -46.61789) (xy 74.559668 -46.61789)
		)
		(stroke
			(width 0)
			(type solid)
		)
		(fill yes)
		(layer "F.Cu")
		(net "M_H_DQ<26>")
	)
	(gr_poly
		(pts
			(xy 74.595228 -46.21149) (xy 74.595228 -46.14799) (xy 74.417428 -46.14799) (xy 74.417428 -46.21149)
			(xy 74.452988 -46.31309) (xy 74.559668 -46.31309)
		)
		(stroke
			(width 0)
			(type solid)
		)
		(fill yes)
		(layer "F.Cu")
		(net "M_H_DQ<27>")
	)
	(gr_poly
		(pts
			(xy 74.609452 -105.127044) (xy 74.562716 -105.030016) (xy 74.526648 -104.994202) (xy 74.400918 -105.119932)
			(xy 74.436986 -105.155746) (xy 74.534014 -105.202482)
		)
		(stroke
			(width 0)
			(type solid)
		)
		(fill yes)
		(layer "F.Cu")
		(net "M_L_DQ<30>")
	)
	(gr_poly
		(pts
			(xy 74.679302 -104.841548) (xy 74.643488 -104.80548) (xy 74.54646 -104.758744) (xy 74.471022 -104.834182)
			(xy 74.517758 -104.93121) (xy 74.553572 -104.967278)
		)
		(stroke
			(width 0)
			(type solid)
		)
		(fill yes)
		(layer "F.Cu")
		(net "M_L_DQ<30>")
	)
	(gr_poly
		(pts
			(xy 74.699114 -104.60609) (xy 74.652378 -104.509062) (xy 74.61631 -104.473248) (xy 74.49058 -104.598978)
			(xy 74.526648 -104.634792) (xy 74.623676 -104.681528)
		)
		(stroke
			(width 0)
			(type solid)
		)
		(fill yes)
		(layer "F.Cu")
		(net "M_L_DQS_DP<3>")
	)
	(gr_poly
		(pts
			(xy 74.724514 -106.107992) (xy 74.679556 -106.063034) (xy 74.582782 -106.016298) (xy 74.507344 -106.091736)
			(xy 74.553826 -106.188764) (xy 74.598784 -106.233722)
		)
		(stroke
			(width 0)
			(type solid)
		)
		(fill yes)
		(layer "F.Cu")
		(net "M_L_DQ<27>")
	)
	(gr_poly
		(pts
			(xy 74.735436 -105.863644) (xy 74.6887 -105.766616) (xy 74.652632 -105.730802) (xy 74.526902 -105.856532)
			(xy 74.56297 -105.892346) (xy 74.659998 -105.939082)
		)
		(stroke
			(width 0)
			(type solid)
		)
		(fill yes)
		(layer "F.Cu")
		(net "M_L_DQ<26>")
	)
	(gr_poly
		(pts
			(xy 74.73696 -45.146468) (xy 74.72426 -44.955968) (xy 74.62266 -44.955968) (xy 74.60996 -45.146468)
			(xy 74.60996 -45.209968) (xy 74.73696 -45.209968)
		)
		(stroke
			(width 0)
			(type solid)
		)
		(fill yes)
		(layer "F.Cu")
		(net "M_H_ECC<4>")
	)
	(gr_poly
		(pts
			(xy 74.73696 -44.752768) (xy 74.72426 -44.562268) (xy 74.62266 -44.562268) (xy 74.60996 -44.752768)
			(xy 74.60996 -44.803568) (xy 74.73696 -44.803568)
		)
		(stroke
			(width 0)
			(type solid)
		)
		(fill yes)
		(layer "F.Cu")
		(net "M_H_ECC<5>")
	)
	(gr_poly
		(pts
			(xy 74.768202 -103.797354) (xy 74.768202 -103.746554) (xy 74.590402 -103.746554) (xy 74.590402 -103.797354)
			(xy 74.625962 -103.898954) (xy 74.732642 -103.898954)
		)
		(stroke
			(width 0)
			(type solid)
		)
		(fill yes)
		(layer "F.Cu")
		(net "M_L_DQS_DN<12>")
	)
	(gr_poly
		(pts
			(xy 74.768202 -103.492554) (xy 74.768202 -103.441754) (xy 74.590402 -103.441754) (xy 74.590402 -103.492554)
			(xy 74.625962 -103.594154) (xy 74.732642 -103.594154)
		)
		(stroke
			(width 0)
			(type solid)
		)
		(fill yes)
		(layer "F.Cu")
		(net "M_L_DQS_DP<12>")
	)
	(gr_poly
		(pts
			(xy 74.768202 -103.187754) (xy 74.768202 -103.136954) (xy 74.590402 -103.136954) (xy 74.590402 -103.187754)
			(xy 74.625962 -103.289354) (xy 74.732642 -103.289354)
		)
		(stroke
			(width 0)
			(type solid)
		)
		(fill yes)
		(layer "F.Cu")
		(net "M_L_DQ<25>")
	)
	(gr_poly
		(pts
			(xy 74.768202 -102.882954) (xy 74.768202 -102.832154) (xy 74.590402 -102.832154) (xy 74.590402 -102.882954)
			(xy 74.625962 -102.984554) (xy 74.732642 -102.984554)
		)
		(stroke
			(width 0)
			(type solid)
		)
		(fill yes)
		(layer "F.Cu")
		(net "M_L_DQ<24>")
	)
	(gr_poly
		(pts
			(xy 74.768202 -102.578154) (xy 74.768202 -102.527354) (xy 74.590402 -102.527354) (xy 74.590402 -102.578154)
			(xy 74.625962 -102.679754) (xy 74.732642 -102.679754)
		)
		(stroke
			(width 0)
			(type solid)
		)
		(fill yes)
		(layer "F.Cu")
		(net "M_L_DQ<29>")
	)
	(gr_poly
		(pts
			(xy 74.768202 -102.273354) (xy 74.768202 -102.209854) (xy 74.590402 -102.209854) (xy 74.590402 -102.273354)
			(xy 74.625962 -102.374954) (xy 74.732642 -102.374954)
		)
		(stroke
			(width 0)
			(type solid)
		)
		(fill yes)
		(layer "F.Cu")
		(net "M_L_DQ<28>")
	)
	(gr_poly
		(pts
			(xy 74.805286 -105.578148) (xy 74.769472 -105.54208) (xy 74.672444 -105.495344) (xy 74.597006 -105.570782)
			(xy 74.643742 -105.66781) (xy 74.679556 -105.703878)
		)
		(stroke
			(width 0)
			(type solid)
		)
		(fill yes)
		(layer "F.Cu")
		(net "M_L_DQ<26>")
	)
	(gr_poly
		(pts
			(xy 74.811128 -49.46269) (xy 74.775568 -49.36109) (xy 74.668888 -49.36109) (xy 74.633328 -49.46269)
			(xy 74.633328 -49.52619) (xy 74.811128 -49.52619)
		)
		(stroke
			(width 0)
			(type solid)
		)
		(fill yes)
		(layer "F.Cu")
		(net "M_H_DQ<28>")
	)
	(gr_poly
		(pts
			(xy 74.811128 -49.15789) (xy 74.775568 -49.05629) (xy 74.668888 -49.05629) (xy 74.633328 -49.15789)
			(xy 74.633328 -49.20869) (xy 74.811128 -49.20869)
		)
		(stroke
			(width 0)
			(type solid)
		)
		(fill yes)
		(layer "F.Cu")
		(net "M_H_DQ<29>")
	)
	(gr_poly
		(pts
			(xy 74.811128 -48.85309) (xy 74.775568 -48.75149) (xy 74.668888 -48.75149) (xy 74.633328 -48.85309)
			(xy 74.633328 -48.90389) (xy 74.811128 -48.90389)
		)
		(stroke
			(width 0)
			(type solid)
		)
		(fill yes)
		(layer "F.Cu")
		(net "M_H_DQ<24>")
	)
	(gr_poly
		(pts
			(xy 74.811128 -48.54829) (xy 74.775568 -48.44669) (xy 74.668888 -48.44669) (xy 74.633328 -48.54829)
			(xy 74.633328 -48.59909) (xy 74.811128 -48.59909)
		)
		(stroke
			(width 0)
			(type solid)
		)
		(fill yes)
		(layer "F.Cu")
		(net "M_H_DQ<25>")
	)
	(gr_poly
		(pts
			(xy 74.811128 -48.24349) (xy 74.775568 -48.14189) (xy 74.668888 -48.14189) (xy 74.633328 -48.24349)
			(xy 74.633328 -48.29429) (xy 74.811128 -48.29429)
		)
		(stroke
			(width 0)
			(type solid)
		)
		(fill yes)
		(layer "F.Cu")
		(net "M_H_DQS_DP<12>")
	)
	(gr_poly
		(pts
			(xy 74.811128 -47.93869) (xy 74.775568 -47.83709) (xy 74.668888 -47.83709) (xy 74.633328 -47.93869)
			(xy 74.633328 -47.98949) (xy 74.811128 -47.98949)
		)
		(stroke
			(width 0)
			(type solid)
		)
		(fill yes)
		(layer "F.Cu")
		(net "M_H_DQS_DN<12>")
	)
	(gr_poly
		(pts
			(xy 74.811128 -47.63389) (xy 74.775568 -47.53229) (xy 74.668888 -47.53229) (xy 74.633328 -47.63389)
			(xy 74.633328 -47.68469) (xy 74.811128 -47.68469)
		)
		(stroke
			(width 0)
			(type solid)
		)
		(fill yes)
		(layer "F.Cu")
		(net "M_H_DQS_DN<3>")
	)
	(gr_poly
		(pts
			(xy 74.811128 -47.32909) (xy 74.775568 -47.22749) (xy 74.668888 -47.22749) (xy 74.633328 -47.32909)
			(xy 74.633328 -47.37989) (xy 74.811128 -47.37989)
		)
		(stroke
			(width 0)
			(type solid)
		)
		(fill yes)
		(layer "F.Cu")
		(net "M_H_DQS_DP<3>")
	)
	(gr_poly
		(pts
			(xy 74.811128 -47.02429) (xy 74.775568 -46.92269) (xy 74.668888 -46.92269) (xy 74.633328 -47.02429)
			(xy 74.633328 -47.07509) (xy 74.811128 -47.07509)
		)
		(stroke
			(width 0)
			(type solid)
		)
		(fill yes)
		(layer "F.Cu")
		(net "M_H_DQ<30>")
	)
	(gr_poly
		(pts
			(xy 74.811128 -46.71949) (xy 74.775568 -46.61789) (xy 74.668888 -46.61789) (xy 74.633328 -46.71949)
			(xy 74.633328 -46.77029) (xy 74.811128 -46.77029)
		)
		(stroke
			(width 0)
			(type solid)
		)
		(fill yes)
		(layer "F.Cu")
		(net "M_H_DQ<31>")
	)
	(gr_poly
		(pts
			(xy 74.811128 -46.41469) (xy 74.775568 -46.31309) (xy 74.668888 -46.31309) (xy 74.633328 -46.41469)
			(xy 74.633328 -46.46549) (xy 74.811128 -46.46549)
		)
		(stroke
			(width 0)
			(type solid)
		)
		(fill yes)
		(layer "F.Cu")
		(net "M_H_DQ<26>")
	)
	(gr_poly
		(pts
			(xy 74.825098 -105.34269) (xy 74.778362 -105.245662) (xy 74.742294 -105.209848) (xy 74.616564 -105.335578)
			(xy 74.652632 -105.371392) (xy 74.74966 -105.418128)
		)
		(stroke
			(width 0)
			(type solid)
		)
		(fill yes)
		(layer "F.Cu")
		(net "M_L_DQ<31>")
	)
	(gr_poly
		(pts
			(xy 74.894948 -105.057194) (xy 74.859134 -105.021126) (xy 74.762106 -104.97439) (xy 74.686668 -105.049828)
			(xy 74.733404 -105.146856) (xy 74.769218 -105.182924)
		)
		(stroke
			(width 0)
			(type solid)
		)
		(fill yes)
		(layer "F.Cu")
		(net "M_L_DQ<31>")
	)
	(gr_poly
		(pts
			(xy 74.91476 -104.821736) (xy 74.868024 -104.724708) (xy 74.831956 -104.688894) (xy 74.706226 -104.814624)
			(xy 74.742294 -104.850438) (xy 74.839322 -104.897174)
		)
		(stroke
			(width 0)
			(type solid)
		)
		(fill yes)
		(layer "F.Cu")
		(net "M_L_DQ<30>")
	)
	(gr_poly
		(pts
			(xy 74.984102 -104.305354) (xy 74.948542 -104.203754) (xy 74.841862 -104.203754) (xy 74.806302 -104.305354)
			(xy 74.806302 -104.356154) (xy 74.984102 -104.356154)
		)
		(stroke
			(width 0)
			(type solid)
		)
		(fill yes)
		(layer "F.Cu")
		(net "M_L_DQS_DP<3>")
	)
	(gr_poly
		(pts
			(xy 74.984102 -104.000554) (xy 74.948542 -103.898954) (xy 74.841862 -103.898954) (xy 74.806302 -104.000554)
			(xy 74.806302 -104.051354) (xy 74.984102 -104.051354)
		)
		(stroke
			(width 0)
			(type solid)
		)
		(fill yes)
		(layer "F.Cu")
		(net "M_L_DQS_DN<3>")
	)
	(gr_poly
		(pts
			(xy 74.984102 -103.695754) (xy 74.948542 -103.594154) (xy 74.841862 -103.594154) (xy 74.806302 -103.695754)
			(xy 74.806302 -103.746554) (xy 74.984102 -103.746554)
		)
		(stroke
			(width 0)
			(type solid)
		)
		(fill yes)
		(layer "F.Cu")
		(net "M_L_DQS_DN<12>")
	)
	(gr_poly
		(pts
			(xy 74.984102 -103.390954) (xy 74.948542 -103.289354) (xy 74.841862 -103.289354) (xy 74.806302 -103.390954)
			(xy 74.806302 -103.441754) (xy 74.984102 -103.441754)
		)
		(stroke
			(width 0)
			(type solid)
		)
		(fill yes)
		(layer "F.Cu")
		(net "M_L_DQS_DP<12>")
	)
	(gr_poly
		(pts
			(xy 74.984102 -103.086154) (xy 74.948542 -102.984554) (xy 74.841862 -102.984554) (xy 74.806302 -103.086154)
			(xy 74.806302 -103.136954) (xy 74.984102 -103.136954)
		)
		(stroke
			(width 0)
			(type solid)
		)
		(fill yes)
		(layer "F.Cu")
		(net "M_L_DQ<25>")
	)
	(gr_poly
		(pts
			(xy 74.984102 -102.781354) (xy 74.948542 -102.679754) (xy 74.841862 -102.679754) (xy 74.806302 -102.781354)
			(xy 74.806302 -102.832154) (xy 74.984102 -102.832154)
		)
		(stroke
			(width 0)
			(type solid)
		)
		(fill yes)
		(layer "F.Cu")
		(net "M_L_DQ<24>")
	)
	(gr_poly
		(pts
			(xy 74.984102 -102.476554) (xy 74.948542 -102.374954) (xy 74.841862 -102.374954) (xy 74.806302 -102.476554)
			(xy 74.806302 -102.527354) (xy 74.984102 -102.527354)
		)
		(stroke
			(width 0)
			(type solid)
		)
		(fill yes)
		(layer "F.Cu")
		(net "M_L_DQ<29>")
	)
	(gr_poly
		(pts
			(xy 75.027028 -49.25949) (xy 75.027028 -49.20869) (xy 74.849228 -49.20869) (xy 74.849228 -49.25949)
			(xy 74.884788 -49.36109) (xy 74.991468 -49.36109)
		)
		(stroke
			(width 0)
			(type solid)
		)
		(fill yes)
		(layer "F.Cu")
		(net "M_H_DQ<29>")
	)
	(gr_poly
		(pts
			(xy 75.027028 -48.95469) (xy 75.027028 -48.90389) (xy 74.849228 -48.90389) (xy 74.849228 -48.95469)
			(xy 74.884788 -49.05629) (xy 74.991468 -49.05629)
		)
		(stroke
			(width 0)
			(type solid)
		)
		(fill yes)
		(layer "F.Cu")
		(net "M_H_DQ<24>")
	)
	(gr_poly
		(pts
			(xy 75.027028 -48.64989) (xy 75.027028 -48.59909) (xy 74.849228 -48.59909) (xy 74.849228 -48.64989)
			(xy 74.884788 -48.75149) (xy 74.991468 -48.75149)
		)
		(stroke
			(width 0)
			(type solid)
		)
		(fill yes)
		(layer "F.Cu")
		(net "M_H_DQ<25>")
	)
	(gr_poly
		(pts
			(xy 75.027028 -48.34509) (xy 75.027028 -48.29429) (xy 74.849228 -48.29429) (xy 74.849228 -48.34509)
			(xy 74.884788 -48.44669) (xy 74.991468 -48.44669)
		)
		(stroke
			(width 0)
			(type solid)
		)
		(fill yes)
		(layer "F.Cu")
		(net "M_H_DQS_DP<12>")
	)
	(gr_poly
		(pts
			(xy 75.027028 -48.04029) (xy 75.027028 -47.98949) (xy 74.849228 -47.98949) (xy 74.849228 -48.04029)
			(xy 74.884788 -48.14189) (xy 74.991468 -48.14189)
		)
		(stroke
			(width 0)
			(type solid)
		)
		(fill yes)
		(layer "F.Cu")
		(net "M_H_DQS_DN<12>")
	)
	(gr_poly
		(pts
			(xy 75.027028 -47.73549) (xy 75.027028 -47.68469) (xy 74.849228 -47.68469) (xy 74.849228 -47.73549)
			(xy 74.884788 -47.83709) (xy 74.991468 -47.83709)
		)
		(stroke
			(width 0)
			(type solid)
		)
		(fill yes)
		(layer "F.Cu")
		(net "M_H_DQS_DN<3>")
	)
	(gr_poly
		(pts
			(xy 75.027028 -47.43069) (xy 75.027028 -47.37989) (xy 74.849228 -47.37989) (xy 74.849228 -47.43069)
			(xy 74.884788 -47.53229) (xy 74.991468 -47.53229)
		)
		(stroke
			(width 0)
			(type solid)
		)
		(fill yes)
		(layer "F.Cu")
		(net "M_H_DQS_DP<3>")
	)
	(gr_poly
		(pts
			(xy 75.027028 -47.12589) (xy 75.027028 -47.07509) (xy 74.849228 -47.07509) (xy 74.849228 -47.12589)
			(xy 74.884788 -47.22749) (xy 74.991468 -47.22749)
		)
		(stroke
			(width 0)
			(type solid)
		)
		(fill yes)
		(layer "F.Cu")
		(net "M_H_DQ<30>")
	)
	(gr_poly
		(pts
			(xy 75.027028 -46.82109) (xy 75.027028 -46.77029) (xy 74.849228 -46.77029) (xy 74.849228 -46.82109)
			(xy 74.884788 -46.92269) (xy 74.991468 -46.92269)
		)
		(stroke
			(width 0)
			(type solid)
		)
		(fill yes)
		(layer "F.Cu")
		(net "M_H_DQ<31>")
	)
	(gr_poly
		(pts
			(xy 75.027028 -46.51629) (xy 75.027028 -46.46549) (xy 74.849228 -46.46549) (xy 74.849228 -46.51629)
			(xy 74.884788 -46.61789) (xy 74.991468 -46.61789)
		)
		(stroke
			(width 0)
			(type solid)
		)
		(fill yes)
		(layer "F.Cu")
		(net "M_H_DQ<26>")
	)
	(gr_poly
		(pts
			(xy 75.027028 -46.21149) (xy 75.027028 -46.14799) (xy 74.849228 -46.14799) (xy 74.849228 -46.21149)
			(xy 74.884788 -46.31309) (xy 74.991468 -46.31309)
		)
		(stroke
			(width 0)
			(type solid)
		)
		(fill yes)
		(layer "F.Cu")
		(net "M_H_DQ<27>")
	)
	(gr_poly
		(pts
			(xy 75.029822 -105.802684) (xy 74.985118 -105.757726) (xy 74.88809 -105.71099) (xy 74.812652 -105.786428)
			(xy 74.859388 -105.883456) (xy 74.904092 -105.928414)
		)
		(stroke
			(width 0)
			(type solid)
		)
		(fill yes)
		(layer "F.Cu")
		(net "M_L_DQ<27>")
	)
	(gr_poly
		(pts
			(xy 75.040744 -105.558336) (xy 74.994008 -105.461308) (xy 74.95794 -105.425494) (xy 74.83221 -105.551224)
			(xy 74.868278 -105.587038) (xy 74.965306 -105.633774)
		)
		(stroke
			(width 0)
			(type solid)
		)
		(fill yes)
		(layer "F.Cu")
		(net "M_L_DQ<26>")
	)
	(gr_poly
		(pts
			(xy 75.09256 -44.854368) (xy 75.09256 -44.803568) (xy 74.96556 -44.803568) (xy 74.96556 -44.854368)
			(xy 74.97826 -45.044868) (xy 75.07986 -45.044868)
		)
		(stroke
			(width 0)
			(type solid)
		)
		(fill yes)
		(layer "F.Cu")
		(net "M_H_ECC<5>")
	)
	(gr_poly
		(pts
			(xy 75.200002 -105.016554) (xy 75.200002 -104.965754) (xy 75.022202 -104.965754) (xy 75.022202 -105.016554)
			(xy 75.057762 -105.118154) (xy 75.164442 -105.118154)
		)
		(stroke
			(width 0)
			(type solid)
		)
		(fill yes)
		(layer "F.Cu")
		(net "M_L_DQ<31>")
	)
	(gr_poly
		(pts
			(xy 75.200002 -104.711754) (xy 75.200002 -104.660954) (xy 75.022202 -104.660954) (xy 75.022202 -104.711754)
			(xy 75.057762 -104.813354) (xy 75.164442 -104.813354)
		)
		(stroke
			(width 0)
			(type solid)
		)
		(fill yes)
		(layer "F.Cu")
		(net "M_L_DQ<30>")
	)
	(gr_poly
		(pts
			(xy 75.200002 -104.406954) (xy 75.200002 -104.356154) (xy 75.022202 -104.356154) (xy 75.022202 -104.406954)
			(xy 75.057762 -104.508554) (xy 75.164442 -104.508554)
		)
		(stroke
			(width 0)
			(type solid)
		)
		(fill yes)
		(layer "F.Cu")
		(net "M_L_DQS_DP<3>")
	)
	(gr_poly
		(pts
			(xy 75.200002 -104.102154) (xy 75.200002 -104.051354) (xy 75.022202 -104.051354) (xy 75.022202 -104.102154)
			(xy 75.057762 -104.203754) (xy 75.164442 -104.203754)
		)
		(stroke
			(width 0)
			(type solid)
		)
		(fill yes)
		(layer "F.Cu")
		(net "M_L_DQS_DN<3>")
	)
	(gr_poly
		(pts
			(xy 75.200002 -103.797354) (xy 75.200002 -103.746554) (xy 75.022202 -103.746554) (xy 75.022202 -103.797354)
			(xy 75.057762 -103.898954) (xy 75.164442 -103.898954)
		)
		(stroke
			(width 0)
			(type solid)
		)
		(fill yes)
		(layer "F.Cu")
		(net "M_L_DQS_DN<12>")
	)
	(gr_poly
		(pts
			(xy 75.200002 -103.492554) (xy 75.200002 -103.441754) (xy 75.022202 -103.441754) (xy 75.022202 -103.492554)
			(xy 75.057762 -103.594154) (xy 75.164442 -103.594154)
		)
		(stroke
			(width 0)
			(type solid)
		)
		(fill yes)
		(layer "F.Cu")
		(net "M_L_DQS_DP<12>")
	)
	(gr_poly
		(pts
			(xy 75.200002 -103.187754) (xy 75.200002 -103.136954) (xy 75.022202 -103.136954) (xy 75.022202 -103.187754)
			(xy 75.057762 -103.289354) (xy 75.164442 -103.289354)
		)
		(stroke
			(width 0)
			(type solid)
		)
		(fill yes)
		(layer "F.Cu")
		(net "M_L_DQ<25>")
	)
	(gr_poly
		(pts
			(xy 75.200002 -102.882954) (xy 75.200002 -102.832154) (xy 75.022202 -102.832154) (xy 75.022202 -102.882954)
			(xy 75.057762 -102.984554) (xy 75.164442 -102.984554)
		)
		(stroke
			(width 0)
			(type solid)
		)
		(fill yes)
		(layer "F.Cu")
		(net "M_L_DQ<24>")
	)
	(gr_poly
		(pts
			(xy 75.200002 -102.578154) (xy 75.200002 -102.527354) (xy 75.022202 -102.527354) (xy 75.022202 -102.578154)
			(xy 75.057762 -102.679754) (xy 75.164442 -102.679754)
		)
		(stroke
			(width 0)
			(type solid)
		)
		(fill yes)
		(layer "F.Cu")
		(net "M_L_DQ<29>")
	)
	(gr_poly
		(pts
			(xy 75.200002 -102.273354) (xy 75.200002 -102.209854) (xy 75.022202 -102.209854) (xy 75.022202 -102.273354)
			(xy 75.057762 -102.374954) (xy 75.164442 -102.374954)
		)
		(stroke
			(width 0)
			(type solid)
		)
		(fill yes)
		(layer "F.Cu")
		(net "M_L_DQ<28>")
	)
	(gr_poly
		(pts
			(xy 75.242928 -49.46269) (xy 75.207368 -49.36109) (xy 75.100688 -49.36109) (xy 75.065128 -49.46269)
			(xy 75.065128 -49.52619) (xy 75.242928 -49.52619)
		)
		(stroke
			(width 0)
			(type solid)
		)
		(fill yes)
		(layer "F.Cu")
		(net "M_H_DQ<28>")
	)
	(gr_poly
		(pts
			(xy 75.242928 -49.15789) (xy 75.207368 -49.05629) (xy 75.100688 -49.05629) (xy 75.065128 -49.15789)
			(xy 75.065128 -49.20869) (xy 75.242928 -49.20869)
		)
		(stroke
			(width 0)
			(type solid)
		)
		(fill yes)
		(layer "F.Cu")
		(net "M_H_DQ<29>")
	)
	(gr_poly
		(pts
			(xy 75.242928 -48.85309) (xy 75.207368 -48.75149) (xy 75.100688 -48.75149) (xy 75.065128 -48.85309)
			(xy 75.065128 -48.90389) (xy 75.242928 -48.90389)
		)
		(stroke
			(width 0)
			(type solid)
		)
		(fill yes)
		(layer "F.Cu")
		(net "M_H_DQ<24>")
	)
	(gr_poly
		(pts
			(xy 75.242928 -48.54829) (xy 75.207368 -48.44669) (xy 75.100688 -48.44669) (xy 75.065128 -48.54829)
			(xy 75.065128 -48.59909) (xy 75.242928 -48.59909)
		)
		(stroke
			(width 0)
			(type solid)
		)
		(fill yes)
		(layer "F.Cu")
		(net "M_H_DQ<25>")
	)
	(gr_poly
		(pts
			(xy 75.242928 -48.24349) (xy 75.207368 -48.14189) (xy 75.100688 -48.14189) (xy 75.065128 -48.24349)
			(xy 75.065128 -48.29429) (xy 75.242928 -48.29429)
		)
		(stroke
			(width 0)
			(type solid)
		)
		(fill yes)
		(layer "F.Cu")
		(net "M_H_DQS_DP<12>")
	)
	(gr_poly
		(pts
			(xy 75.242928 -47.93869) (xy 75.207368 -47.83709) (xy 75.100688 -47.83709) (xy 75.065128 -47.93869)
			(xy 75.065128 -47.98949) (xy 75.242928 -47.98949)
		)
		(stroke
			(width 0)
			(type solid)
		)
		(fill yes)
		(layer "F.Cu")
		(net "M_H_DQS_DN<12>")
	)
	(gr_poly
		(pts
			(xy 75.242928 -47.63389) (xy 75.207368 -47.53229) (xy 75.100688 -47.53229) (xy 75.065128 -47.63389)
			(xy 75.065128 -47.68469) (xy 75.242928 -47.68469)
		)
		(stroke
			(width 0)
			(type solid)
		)
		(fill yes)
		(layer "F.Cu")
		(net "M_H_DQS_DN<3>")
	)
	(gr_poly
		(pts
			(xy 75.242928 -47.32909) (xy 75.207368 -47.22749) (xy 75.100688 -47.22749) (xy 75.065128 -47.32909)
			(xy 75.065128 -47.37989) (xy 75.242928 -47.37989)
		)
		(stroke
			(width 0)
			(type solid)
		)
		(fill yes)
		(layer "F.Cu")
		(net "M_H_DQS_DP<3>")
	)
	(gr_poly
		(pts
			(xy 75.242928 -47.02429) (xy 75.207368 -46.92269) (xy 75.100688 -46.92269) (xy 75.065128 -47.02429)
			(xy 75.065128 -47.07509) (xy 75.242928 -47.07509)
		)
		(stroke
			(width 0)
			(type solid)
		)
		(fill yes)
		(layer "F.Cu")
		(net "M_H_DQ<30>")
	)
	(gr_poly
		(pts
			(xy 75.242928 -46.71949) (xy 75.207368 -46.61789) (xy 75.100688 -46.61789) (xy 75.065128 -46.71949)
			(xy 75.065128 -46.77029) (xy 75.242928 -46.77029)
		)
		(stroke
			(width 0)
			(type solid)
		)
		(fill yes)
		(layer "F.Cu")
		(net "M_H_DQ<31>")
	)
	(gr_poly
		(pts
			(xy 75.242928 -46.41469) (xy 75.207368 -46.31309) (xy 75.100688 -46.31309) (xy 75.065128 -46.41469)
			(xy 75.065128 -46.46549) (xy 75.242928 -46.46549)
		)
		(stroke
			(width 0)
			(type solid)
		)
		(fill yes)
		(layer "F.Cu")
		(net "M_H_DQ<26>")
	)
	(gr_poly
		(pts
			(xy 75.39736 -44.359068) (xy 75.38466 -44.168568) (xy 75.28306 -44.168568) (xy 75.27036 -44.359068)
			(xy 75.27036 -44.409868) (xy 75.39736 -44.409868)
		)
		(stroke
			(width 0)
			(type solid)
		)
		(fill yes)
		(layer "F.Cu")
		(net "M_H_ECC<0>")
	)
	(gr_poly
		(pts
			(xy 75.415902 -105.524554) (xy 75.380342 -105.422954) (xy 75.273662 -105.422954) (xy 75.238102 -105.524554)
			(xy 75.238102 -105.588054) (xy 75.415902 -105.588054)
		)
		(stroke
			(width 0)
			(type solid)
		)
		(fill yes)
		(layer "F.Cu")
		(net "M_L_DQ<27>")
	)
	(gr_poly
		(pts
			(xy 75.415902 -105.219754) (xy 75.380342 -105.118154) (xy 75.273662 -105.118154) (xy 75.238102 -105.219754)
			(xy 75.238102 -105.270554) (xy 75.415902 -105.270554)
		)
		(stroke
			(width 0)
			(type solid)
		)
		(fill yes)
		(layer "F.Cu")
		(net "M_L_DQ<26>")
	)
	(gr_poly
		(pts
			(xy 75.415902 -104.914954) (xy 75.380342 -104.813354) (xy 75.273662 -104.813354) (xy 75.238102 -104.914954)
			(xy 75.238102 -104.965754) (xy 75.415902 -104.965754)
		)
		(stroke
			(width 0)
			(type solid)
		)
		(fill yes)
		(layer "F.Cu")
		(net "M_L_DQ<31>")
	)
	(gr_poly
		(pts
			(xy 75.415902 -104.610154) (xy 75.380342 -104.508554) (xy 75.273662 -104.508554) (xy 75.238102 -104.610154)
			(xy 75.238102 -104.660954) (xy 75.415902 -104.660954)
		)
		(stroke
			(width 0)
			(type solid)
		)
		(fill yes)
		(layer "F.Cu")
		(net "M_L_DQ<30>")
	)
	(gr_poly
		(pts
			(xy 75.415902 -104.305354) (xy 75.380342 -104.203754) (xy 75.273662 -104.203754) (xy 75.238102 -104.305354)
			(xy 75.238102 -104.356154) (xy 75.415902 -104.356154)
		)
		(stroke
			(width 0)
			(type solid)
		)
		(fill yes)
		(layer "F.Cu")
		(net "M_L_DQS_DP<3>")
	)
	(gr_poly
		(pts
			(xy 75.415902 -104.000554) (xy 75.380342 -103.898954) (xy 75.273662 -103.898954) (xy 75.238102 -104.000554)
			(xy 75.238102 -104.051354) (xy 75.415902 -104.051354)
		)
		(stroke
			(width 0)
			(type solid)
		)
		(fill yes)
		(layer "F.Cu")
		(net "M_L_DQS_DN<3>")
	)
	(gr_poly
		(pts
			(xy 75.415902 -103.695754) (xy 75.380342 -103.594154) (xy 75.273662 -103.594154) (xy 75.238102 -103.695754)
			(xy 75.238102 -103.746554) (xy 75.415902 -103.746554)
		)
		(stroke
			(width 0)
			(type solid)
		)
		(fill yes)
		(layer "F.Cu")
		(net "M_L_DQS_DN<12>")
	)
	(gr_poly
		(pts
			(xy 75.415902 -103.390954) (xy 75.380342 -103.289354) (xy 75.273662 -103.289354) (xy 75.238102 -103.390954)
			(xy 75.238102 -103.441754) (xy 75.415902 -103.441754)
		)
		(stroke
			(width 0)
			(type solid)
		)
		(fill yes)
		(layer "F.Cu")
		(net "M_L_DQS_DP<12>")
	)
	(gr_poly
		(pts
			(xy 75.415902 -103.086154) (xy 75.380342 -102.984554) (xy 75.273662 -102.984554) (xy 75.238102 -103.086154)
			(xy 75.238102 -103.136954) (xy 75.415902 -103.136954)
		)
		(stroke
			(width 0)
			(type solid)
		)
		(fill yes)
		(layer "F.Cu")
		(net "M_L_DQ<25>")
	)
	(gr_poly
		(pts
			(xy 75.415902 -102.781354) (xy 75.380342 -102.679754) (xy 75.273662 -102.679754) (xy 75.238102 -102.781354)
			(xy 75.238102 -102.832154) (xy 75.415902 -102.832154)
		)
		(stroke
			(width 0)
			(type solid)
		)
		(fill yes)
		(layer "F.Cu")
		(net "M_L_DQ<24>")
	)
	(gr_poly
		(pts
			(xy 75.415902 -102.476554) (xy 75.380342 -102.374954) (xy 75.273662 -102.374954) (xy 75.238102 -102.476554)
			(xy 75.238102 -102.527354) (xy 75.415902 -102.527354)
		)
		(stroke
			(width 0)
			(type solid)
		)
		(fill yes)
		(layer "F.Cu")
		(net "M_L_DQ<29>")
	)
	(gr_poly
		(pts
			(xy 75.42276 -45.146468) (xy 75.41006 -44.955968) (xy 75.30846 -44.955968) (xy 75.29576 -45.146468)
			(xy 75.29576 -45.209968) (xy 75.42276 -45.209968)
		)
		(stroke
			(width 0)
			(type solid)
		)
		(fill yes)
		(layer "F.Cu")
		(net "M_H_ECC<4>")
	)
	(gr_poly
		(pts
			(xy 75.42276 -44.752768) (xy 75.41006 -44.562268) (xy 75.30846 -44.562268) (xy 75.29576 -44.752768)
			(xy 75.29576 -44.803568) (xy 75.42276 -44.803568)
		)
		(stroke
			(width 0)
			(type solid)
		)
		(fill yes)
		(layer "F.Cu")
		(net "M_H_ECC<5>")
	)
	(gr_poly
		(pts
			(xy 75.458828 -49.25949) (xy 75.458828 -49.20869) (xy 75.281028 -49.20869) (xy 75.281028 -49.25949)
			(xy 75.316588 -49.36109) (xy 75.423268 -49.36109)
		)
		(stroke
			(width 0)
			(type solid)
		)
		(fill yes)
		(layer "F.Cu")
		(net "M_H_DQ<29>")
	)
	(gr_poly
		(pts
			(xy 75.458828 -48.95469) (xy 75.458828 -48.90389) (xy 75.281028 -48.90389) (xy 75.281028 -48.95469)
			(xy 75.316588 -49.05629) (xy 75.423268 -49.05629)
		)
		(stroke
			(width 0)
			(type solid)
		)
		(fill yes)
		(layer "F.Cu")
		(net "M_H_DQ<24>")
	)
	(gr_poly
		(pts
			(xy 75.458828 -48.64989) (xy 75.458828 -48.59909) (xy 75.281028 -48.59909) (xy 75.281028 -48.64989)
			(xy 75.316588 -48.75149) (xy 75.423268 -48.75149)
		)
		(stroke
			(width 0)
			(type solid)
		)
		(fill yes)
		(layer "F.Cu")
		(net "M_H_DQ<25>")
	)
	(gr_poly
		(pts
			(xy 75.458828 -48.34509) (xy 75.458828 -48.29429) (xy 75.281028 -48.29429) (xy 75.281028 -48.34509)
			(xy 75.316588 -48.44669) (xy 75.423268 -48.44669)
		)
		(stroke
			(width 0)
			(type solid)
		)
		(fill yes)
		(layer "F.Cu")
		(net "M_H_DQS_DP<12>")
	)
	(gr_poly
		(pts
			(xy 75.458828 -48.04029) (xy 75.458828 -47.98949) (xy 75.281028 -47.98949) (xy 75.281028 -48.04029)
			(xy 75.316588 -48.14189) (xy 75.423268 -48.14189)
		)
		(stroke
			(width 0)
			(type solid)
		)
		(fill yes)
		(layer "F.Cu")
		(net "M_H_DQS_DN<12>")
	)
	(gr_poly
		(pts
			(xy 75.458828 -47.73549) (xy 75.458828 -47.68469) (xy 75.281028 -47.68469) (xy 75.281028 -47.73549)
			(xy 75.316588 -47.83709) (xy 75.423268 -47.83709)
		)
		(stroke
			(width 0)
			(type solid)
		)
		(fill yes)
		(layer "F.Cu")
		(net "M_H_DQS_DN<3>")
	)
	(gr_poly
		(pts
			(xy 75.458828 -47.43069) (xy 75.458828 -47.37989) (xy 75.281028 -47.37989) (xy 75.281028 -47.43069)
			(xy 75.316588 -47.53229) (xy 75.423268 -47.53229)
		)
		(stroke
			(width 0)
			(type solid)
		)
		(fill yes)
		(layer "F.Cu")
		(net "M_H_DQS_DP<3>")
	)
	(gr_poly
		(pts
			(xy 75.458828 -47.12589) (xy 75.458828 -47.07509) (xy 75.281028 -47.07509) (xy 75.281028 -47.12589)
			(xy 75.316588 -47.22749) (xy 75.423268 -47.22749)
		)
		(stroke
			(width 0)
			(type solid)
		)
		(fill yes)
		(layer "F.Cu")
		(net "M_H_DQ<30>")
	)
	(gr_poly
		(pts
			(xy 75.458828 -46.82109) (xy 75.458828 -46.77029) (xy 75.281028 -46.77029) (xy 75.281028 -46.82109)
			(xy 75.316588 -46.92269) (xy 75.423268 -46.92269)
		)
		(stroke
			(width 0)
			(type solid)
		)
		(fill yes)
		(layer "F.Cu")
		(net "M_H_DQ<31>")
	)
	(gr_poly
		(pts
			(xy 75.458828 -46.51629) (xy 75.458828 -46.46549) (xy 75.281028 -46.46549) (xy 75.281028 -46.51629)
			(xy 75.316588 -46.61789) (xy 75.423268 -46.61789)
		)
		(stroke
			(width 0)
			(type solid)
		)
		(fill yes)
		(layer "F.Cu")
		(net "M_H_DQ<26>")
	)
	(gr_poly
		(pts
			(xy 75.458828 -46.21149) (xy 75.458828 -46.14799) (xy 75.281028 -46.14799) (xy 75.281028 -46.21149)
			(xy 75.316588 -46.31309) (xy 75.423268 -46.31309)
		)
		(stroke
			(width 0)
			(type solid)
		)
		(fill yes)
		(layer "F.Cu")
		(net "M_H_DQ<27>")
	)
	(gr_poly
		(pts
			(xy 75.631802 -105.321354) (xy 75.631802 -105.270554) (xy 75.454002 -105.270554) (xy 75.454002 -105.321354)
			(xy 75.489562 -105.422954) (xy 75.596242 -105.422954)
		)
		(stroke
			(width 0)
			(type solid)
		)
		(fill yes)
		(layer "F.Cu")
		(net "M_L_DQ<26>")
	)
	(gr_poly
		(pts
			(xy 75.631802 -105.016554) (xy 75.631802 -104.965754) (xy 75.454002 -104.965754) (xy 75.454002 -105.016554)
			(xy 75.489562 -105.118154) (xy 75.596242 -105.118154)
		)
		(stroke
			(width 0)
			(type solid)
		)
		(fill yes)
		(layer "F.Cu")
		(net "M_L_DQ<31>")
	)
	(gr_poly
		(pts
			(xy 75.631802 -104.711754) (xy 75.631802 -104.660954) (xy 75.454002 -104.660954) (xy 75.454002 -104.711754)
			(xy 75.489562 -104.813354) (xy 75.596242 -104.813354)
		)
		(stroke
			(width 0)
			(type solid)
		)
		(fill yes)
		(layer "F.Cu")
		(net "M_L_DQ<30>")
	)
	(gr_poly
		(pts
			(xy 75.631802 -104.406954) (xy 75.631802 -104.356154) (xy 75.454002 -104.356154) (xy 75.454002 -104.406954)
			(xy 75.489562 -104.508554) (xy 75.596242 -104.508554)
		)
		(stroke
			(width 0)
			(type solid)
		)
		(fill yes)
		(layer "F.Cu")
		(net "M_L_DQS_DP<3>")
	)
	(gr_poly
		(pts
			(xy 75.631802 -104.102154) (xy 75.631802 -104.051354) (xy 75.454002 -104.051354) (xy 75.454002 -104.102154)
			(xy 75.489562 -104.203754) (xy 75.596242 -104.203754)
		)
		(stroke
			(width 0)
			(type solid)
		)
		(fill yes)
		(layer "F.Cu")
		(net "M_L_DQS_DN<3>")
	)
	(gr_poly
		(pts
			(xy 75.631802 -103.797354) (xy 75.631802 -103.746554) (xy 75.454002 -103.746554) (xy 75.454002 -103.797354)
			(xy 75.489562 -103.898954) (xy 75.596242 -103.898954)
		)
		(stroke
			(width 0)
			(type solid)
		)
		(fill yes)
		(layer "F.Cu")
		(net "M_L_DQS_DN<12>")
	)
	(gr_poly
		(pts
			(xy 75.631802 -103.492554) (xy 75.631802 -103.441754) (xy 75.454002 -103.441754) (xy 75.454002 -103.492554)
			(xy 75.489562 -103.594154) (xy 75.596242 -103.594154)
		)
		(stroke
			(width 0)
			(type solid)
		)
		(fill yes)
		(layer "F.Cu")
		(net "M_L_DQS_DP<12>")
	)
	(gr_poly
		(pts
			(xy 75.631802 -103.187754) (xy 75.631802 -103.136954) (xy 75.454002 -103.136954) (xy 75.454002 -103.187754)
			(xy 75.489562 -103.289354) (xy 75.596242 -103.289354)
		)
		(stroke
			(width 0)
			(type solid)
		)
		(fill yes)
		(layer "F.Cu")
		(net "M_L_DQ<25>")
	)
	(gr_poly
		(pts
			(xy 75.631802 -102.882954) (xy 75.631802 -102.832154) (xy 75.454002 -102.832154) (xy 75.454002 -102.882954)
			(xy 75.489562 -102.984554) (xy 75.596242 -102.984554)
		)
		(stroke
			(width 0)
			(type solid)
		)
		(fill yes)
		(layer "F.Cu")
		(net "M_L_DQ<24>")
	)
	(gr_poly
		(pts
			(xy 75.631802 -102.578154) (xy 75.631802 -102.527354) (xy 75.454002 -102.527354) (xy 75.454002 -102.578154)
			(xy 75.489562 -102.679754) (xy 75.596242 -102.679754)
		)
		(stroke
			(width 0)
			(type solid)
		)
		(fill yes)
		(layer "F.Cu")
		(net "M_L_DQ<29>")
	)
	(gr_poly
		(pts
			(xy 75.631802 -102.273354) (xy 75.631802 -102.209854) (xy 75.454002 -102.209854) (xy 75.454002 -102.273354)
			(xy 75.489562 -102.374954) (xy 75.596242 -102.374954)
		)
		(stroke
			(width 0)
			(type solid)
		)
		(fill yes)
		(layer "F.Cu")
		(net "M_L_DQ<28>")
	)
	(gr_poly
		(pts
			(xy 75.674728 -49.15789) (xy 75.639168 -49.05629) (xy 75.532488 -49.05629) (xy 75.496928 -49.15789)
			(xy 75.496928 -49.20869) (xy 75.674728 -49.20869)
		)
		(stroke
			(width 0)
			(type solid)
		)
		(fill yes)
		(layer "F.Cu")
		(net "M_H_DQ<29>")
	)
	(gr_poly
		(pts
			(xy 75.674728 -48.85309) (xy 75.639168 -48.75149) (xy 75.532488 -48.75149) (xy 75.496928 -48.85309)
			(xy 75.496928 -48.90389) (xy 75.674728 -48.90389)
		)
		(stroke
			(width 0)
			(type solid)
		)
		(fill yes)
		(layer "F.Cu")
		(net "M_H_DQ<24>")
	)
	(gr_poly
		(pts
			(xy 75.674728 -48.54829) (xy 75.639168 -48.44669) (xy 75.532488 -48.44669) (xy 75.496928 -48.54829)
			(xy 75.496928 -48.59909) (xy 75.674728 -48.59909)
		)
		(stroke
			(width 0)
			(type solid)
		)
		(fill yes)
		(layer "F.Cu")
		(net "M_H_DQ<25>")
	)
	(gr_poly
		(pts
			(xy 75.674728 -48.24349) (xy 75.639168 -48.14189) (xy 75.532488 -48.14189) (xy 75.496928 -48.24349)
			(xy 75.496928 -48.29429) (xy 75.674728 -48.29429)
		)
		(stroke
			(width 0)
			(type solid)
		)
		(fill yes)
		(layer "F.Cu")
		(net "M_H_DQS_DP<12>")
	)
	(gr_poly
		(pts
			(xy 75.674728 -47.93869) (xy 75.639168 -47.83709) (xy 75.532488 -47.83709) (xy 75.496928 -47.93869)
			(xy 75.496928 -47.98949) (xy 75.674728 -47.98949)
		)
		(stroke
			(width 0)
			(type solid)
		)
		(fill yes)
		(layer "F.Cu")
		(net "M_H_DQS_DN<12>")
	)
	(gr_poly
		(pts
			(xy 75.674728 -47.63389) (xy 75.639168 -47.53229) (xy 75.532488 -47.53229) (xy 75.496928 -47.63389)
			(xy 75.496928 -47.68469) (xy 75.674728 -47.68469)
		)
		(stroke
			(width 0)
			(type solid)
		)
		(fill yes)
		(layer "F.Cu")
		(net "M_H_DQS_DN<3>")
	)
	(gr_poly
		(pts
			(xy 75.674728 -47.32909) (xy 75.639168 -47.22749) (xy 75.532488 -47.22749) (xy 75.496928 -47.32909)
			(xy 75.496928 -47.37989) (xy 75.674728 -47.37989)
		)
		(stroke
			(width 0)
			(type solid)
		)
		(fill yes)
		(layer "F.Cu")
		(net "M_H_DQS_DP<3>")
	)
	(gr_poly
		(pts
			(xy 75.674728 -47.02429) (xy 75.639168 -46.92269) (xy 75.532488 -46.92269) (xy 75.496928 -47.02429)
			(xy 75.496928 -47.07509) (xy 75.674728 -47.07509)
		)
		(stroke
			(width 0)
			(type solid)
		)
		(fill yes)
		(layer "F.Cu")
		(net "M_H_DQ<30>")
	)
	(gr_poly
		(pts
			(xy 75.674728 -46.71949) (xy 75.639168 -46.61789) (xy 75.532488 -46.61789) (xy 75.496928 -46.71949)
			(xy 75.496928 -46.77029) (xy 75.674728 -46.77029)
		)
		(stroke
			(width 0)
			(type solid)
		)
		(fill yes)
		(layer "F.Cu")
		(net "M_H_DQ<31>")
	)
	(gr_poly
		(pts
			(xy 75.674728 -46.41469) (xy 75.639168 -46.31309) (xy 75.532488 -46.31309) (xy 75.496928 -46.41469)
			(xy 75.496928 -46.46549) (xy 75.674728 -46.46549)
		)
		(stroke
			(width 0)
			(type solid)
		)
		(fill yes)
		(layer "F.Cu")
		(net "M_H_DQ<26>")
	)
	(gr_poly
		(pts
			(xy 75.72756 -44.066968) (xy 75.72756 -44.016168) (xy 75.60056 -44.016168) (xy 75.60056 -44.066968)
			(xy 75.61326 -44.257468) (xy 75.71486 -44.257468)
		)
		(stroke
			(width 0)
			(type solid)
		)
		(fill yes)
		(layer "F.Cu")
		(net "M_H_ECC<1>")
	)
	(gr_poly
		(pts
			(xy 75.75296 -44.854368) (xy 75.75296 -44.803568) (xy 75.62596 -44.803568) (xy 75.62596 -44.854368)
			(xy 75.63866 -45.044868) (xy 75.74026 -45.044868)
		)
		(stroke
			(width 0)
			(type solid)
		)
		(fill yes)
		(layer "F.Cu")
		(net "M_H_ECC<5>")
	)
	(gr_poly
		(pts
			(xy 75.75296 -44.460668) (xy 75.75296 -44.409868) (xy 75.62596 -44.409868) (xy 75.62596 -44.460668)
			(xy 75.63866 -44.651168) (xy 75.74026 -44.651168)
		)
		(stroke
			(width 0)
			(type solid)
		)
		(fill yes)
		(layer "F.Cu")
		(net "M_H_ECC<0>")
	)
	(gr_poly
		(pts
			(xy 75.847702 -105.524554) (xy 75.812142 -105.422954) (xy 75.705462 -105.422954) (xy 75.669902 -105.524554)
			(xy 75.669902 -105.588054) (xy 75.847702 -105.588054)
		)
		(stroke
			(width 0)
			(type solid)
		)
		(fill yes)
		(layer "F.Cu")
		(net "M_L_DQ<27>")
	)
	(gr_poly
		(pts
			(xy 75.847702 -105.219754) (xy 75.812142 -105.118154) (xy 75.705462 -105.118154) (xy 75.669902 -105.219754)
			(xy 75.669902 -105.270554) (xy 75.847702 -105.270554)
		)
		(stroke
			(width 0)
			(type solid)
		)
		(fill yes)
		(layer "F.Cu")
		(net "M_L_DQ<26>")
	)
	(gr_poly
		(pts
			(xy 75.847702 -104.914954) (xy 75.812142 -104.813354) (xy 75.705462 -104.813354) (xy 75.669902 -104.914954)
			(xy 75.669902 -104.965754) (xy 75.847702 -104.965754)
		)
		(stroke
			(width 0)
			(type solid)
		)
		(fill yes)
		(layer "F.Cu")
		(net "M_L_DQ<31>")
	)
	(gr_poly
		(pts
			(xy 75.847702 -104.610154) (xy 75.812142 -104.508554) (xy 75.705462 -104.508554) (xy 75.669902 -104.610154)
			(xy 75.669902 -104.660954) (xy 75.847702 -104.660954)
		)
		(stroke
			(width 0)
			(type solid)
		)
		(fill yes)
		(layer "F.Cu")
		(net "M_L_DQ<30>")
	)
	(gr_poly
		(pts
			(xy 75.847702 -104.305354) (xy 75.812142 -104.203754) (xy 75.705462 -104.203754) (xy 75.669902 -104.305354)
			(xy 75.669902 -104.356154) (xy 75.847702 -104.356154)
		)
		(stroke
			(width 0)
			(type solid)
		)
		(fill yes)
		(layer "F.Cu")
		(net "M_L_DQS_DP<3>")
	)
	(gr_poly
		(pts
			(xy 75.847702 -104.000554) (xy 75.812142 -103.898954) (xy 75.705462 -103.898954) (xy 75.669902 -104.000554)
			(xy 75.669902 -104.051354) (xy 75.847702 -104.051354)
		)
		(stroke
			(width 0)
			(type solid)
		)
		(fill yes)
		(layer "F.Cu")
		(net "M_L_DQS_DN<3>")
	)
	(gr_poly
		(pts
			(xy 75.847702 -103.695754) (xy 75.812142 -103.594154) (xy 75.705462 -103.594154) (xy 75.669902 -103.695754)
			(xy 75.669902 -103.746554) (xy 75.847702 -103.746554)
		)
		(stroke
			(width 0)
			(type solid)
		)
		(fill yes)
		(layer "F.Cu")
		(net "M_L_DQS_DN<12>")
	)
	(gr_poly
		(pts
			(xy 75.847702 -103.390954) (xy 75.812142 -103.289354) (xy 75.705462 -103.289354) (xy 75.669902 -103.390954)
			(xy 75.669902 -103.441754) (xy 75.847702 -103.441754)
		)
		(stroke
			(width 0)
			(type solid)
		)
		(fill yes)
		(layer "F.Cu")
		(net "M_L_DQS_DP<12>")
	)
	(gr_poly
		(pts
			(xy 75.847702 -103.086154) (xy 75.812142 -102.984554) (xy 75.705462 -102.984554) (xy 75.669902 -103.086154)
			(xy 75.669902 -103.136954) (xy 75.847702 -103.136954)
		)
		(stroke
			(width 0)
			(type solid)
		)
		(fill yes)
		(layer "F.Cu")
		(net "M_L_DQ<25>")
	)
	(gr_poly
		(pts
			(xy 75.847702 -102.781354) (xy 75.812142 -102.679754) (xy 75.705462 -102.679754) (xy 75.669902 -102.781354)
			(xy 75.669902 -102.832154) (xy 75.847702 -102.832154)
		)
		(stroke
			(width 0)
			(type solid)
		)
		(fill yes)
		(layer "F.Cu")
		(net "M_L_DQ<24>")
	)
	(gr_poly
		(pts
			(xy 75.867768 -49.432718) (xy 75.903582 -49.396904) (xy 75.777852 -49.271174) (xy 75.742038 -49.306988)
			(xy 75.695302 -49.404016) (xy 75.77074 -49.479454)
		)
		(stroke
			(width 0)
			(type solid)
		)
		(fill yes)
		(layer "F.Cu")
		(net "M_H_DQ<29>")
	)
	(gr_poly
		(pts
			(xy 75.876658 -49.729136) (xy 75.923394 -49.632108) (xy 75.847956 -49.55667) (xy 75.750928 -49.603406)
			(xy 75.715114 -49.639474) (xy 75.840844 -49.765204)
		)
		(stroke
			(width 0)
			(type solid)
		)
		(fill yes)
		(layer "F.Cu")
		(net "M_H_DQ<28>")
	)
	(gr_poly
		(pts
			(xy 75.890628 -48.95469) (xy 75.890628 -48.90389) (xy 75.712828 -48.90389) (xy 75.712828 -48.95469)
			(xy 75.748388 -49.05629) (xy 75.855068 -49.05629)
		)
		(stroke
			(width 0)
			(type solid)
		)
		(fill yes)
		(layer "F.Cu")
		(net "M_H_DQ<24>")
	)
	(gr_poly
		(pts
			(xy 75.890628 -48.64989) (xy 75.890628 -48.59909) (xy 75.712828 -48.59909) (xy 75.712828 -48.64989)
			(xy 75.748388 -48.75149) (xy 75.855068 -48.75149)
		)
		(stroke
			(width 0)
			(type solid)
		)
		(fill yes)
		(layer "F.Cu")
		(net "M_H_DQ<25>")
	)
	(gr_poly
		(pts
			(xy 75.890628 -48.34509) (xy 75.890628 -48.29429) (xy 75.712828 -48.29429) (xy 75.712828 -48.34509)
			(xy 75.748388 -48.44669) (xy 75.855068 -48.44669)
		)
		(stroke
			(width 0)
			(type solid)
		)
		(fill yes)
		(layer "F.Cu")
		(net "M_H_DQS_DP<12>")
	)
	(gr_poly
		(pts
			(xy 75.890628 -48.04029) (xy 75.890628 -47.98949) (xy 75.712828 -47.98949) (xy 75.712828 -48.04029)
			(xy 75.748388 -48.14189) (xy 75.855068 -48.14189)
		)
		(stroke
			(width 0)
			(type solid)
		)
		(fill yes)
		(layer "F.Cu")
		(net "M_H_DQS_DN<12>")
	)
	(gr_poly
		(pts
			(xy 75.890628 -47.73549) (xy 75.890628 -47.68469) (xy 75.712828 -47.68469) (xy 75.712828 -47.73549)
			(xy 75.748388 -47.83709) (xy 75.855068 -47.83709)
		)
		(stroke
			(width 0)
			(type solid)
		)
		(fill yes)
		(layer "F.Cu")
		(net "M_H_DQS_DN<3>")
	)
	(gr_poly
		(pts
			(xy 75.890628 -47.43069) (xy 75.890628 -47.37989) (xy 75.712828 -47.37989) (xy 75.712828 -47.43069)
			(xy 75.748388 -47.53229) (xy 75.855068 -47.53229)
		)
		(stroke
			(width 0)
			(type solid)
		)
		(fill yes)
		(layer "F.Cu")
		(net "M_H_DQS_DP<3>")
	)
	(gr_poly
		(pts
			(xy 75.890628 -47.12589) (xy 75.890628 -47.07509) (xy 75.712828 -47.07509) (xy 75.712828 -47.12589)
			(xy 75.748388 -47.22749) (xy 75.855068 -47.22749)
		)
		(stroke
			(width 0)
			(type solid)
		)
		(fill yes)
		(layer "F.Cu")
		(net "M_H_DQ<30>")
	)
	(gr_poly
		(pts
			(xy 75.890628 -46.82109) (xy 75.890628 -46.77029) (xy 75.712828 -46.77029) (xy 75.712828 -46.82109)
			(xy 75.748388 -46.92269) (xy 75.855068 -46.92269)
		)
		(stroke
			(width 0)
			(type solid)
		)
		(fill yes)
		(layer "F.Cu")
		(net "M_H_DQ<31>")
	)
	(gr_poly
		(pts
			(xy 75.890628 -46.51629) (xy 75.890628 -46.46549) (xy 75.712828 -46.46549) (xy 75.712828 -46.51629)
			(xy 75.748388 -46.61789) (xy 75.855068 -46.61789)
		)
		(stroke
			(width 0)
			(type solid)
		)
		(fill yes)
		(layer "F.Cu")
		(net "M_H_DQ<26>")
	)
	(gr_poly
		(pts
			(xy 75.890628 -46.21149) (xy 75.890628 -46.14799) (xy 75.712828 -46.14799) (xy 75.712828 -46.21149)
			(xy 75.748388 -46.31309) (xy 75.855068 -46.31309)
		)
		(stroke
			(width 0)
			(type solid)
		)
		(fill yes)
		(layer "F.Cu")
		(net "M_H_DQ<27>")
	)
	(gr_poly
		(pts
			(xy 76.063602 -105.321354) (xy 76.063602 -105.270554) (xy 75.885802 -105.270554) (xy 75.885802 -105.321354)
			(xy 75.921362 -105.422954) (xy 76.028042 -105.422954)
		)
		(stroke
			(width 0)
			(type solid)
		)
		(fill yes)
		(layer "F.Cu")
		(net "M_L_DQ<26>")
	)
	(gr_poly
		(pts
			(xy 76.063602 -105.016554) (xy 76.063602 -104.965754) (xy 75.885802 -104.965754) (xy 75.885802 -105.016554)
			(xy 75.921362 -105.118154) (xy 76.028042 -105.118154)
		)
		(stroke
			(width 0)
			(type solid)
		)
		(fill yes)
		(layer "F.Cu")
		(net "M_L_DQ<31>")
	)
	(gr_poly
		(pts
			(xy 76.063602 -104.711754) (xy 76.063602 -104.660954) (xy 75.885802 -104.660954) (xy 75.885802 -104.711754)
			(xy 75.921362 -104.813354) (xy 76.028042 -104.813354)
		)
		(stroke
			(width 0)
			(type solid)
		)
		(fill yes)
		(layer "F.Cu")
		(net "M_L_DQ<30>")
	)
	(gr_poly
		(pts
			(xy 76.063602 -104.406954) (xy 76.063602 -104.356154) (xy 75.885802 -104.356154) (xy 75.885802 -104.406954)
			(xy 75.921362 -104.508554) (xy 76.028042 -104.508554)
		)
		(stroke
			(width 0)
			(type solid)
		)
		(fill yes)
		(layer "F.Cu")
		(net "M_L_DQS_DP<3>")
	)
	(gr_poly
		(pts
			(xy 76.063602 -104.102154) (xy 76.063602 -104.051354) (xy 75.885802 -104.051354) (xy 75.885802 -104.102154)
			(xy 75.921362 -104.203754) (xy 76.028042 -104.203754)
		)
		(stroke
			(width 0)
			(type solid)
		)
		(fill yes)
		(layer "F.Cu")
		(net "M_L_DQS_DN<3>")
	)
	(gr_poly
		(pts
			(xy 76.063602 -103.797354) (xy 76.063602 -103.746554) (xy 75.885802 -103.746554) (xy 75.885802 -103.797354)
			(xy 75.921362 -103.898954) (xy 76.028042 -103.898954)
		)
		(stroke
			(width 0)
			(type solid)
		)
		(fill yes)
		(layer "F.Cu")
		(net "M_L_DQS_DN<12>")
	)
	(gr_poly
		(pts
			(xy 76.063602 -103.492554) (xy 76.063602 -103.441754) (xy 75.885802 -103.441754) (xy 75.885802 -103.492554)
			(xy 75.921362 -103.594154) (xy 76.028042 -103.594154)
		)
		(stroke
			(width 0)
			(type solid)
		)
		(fill yes)
		(layer "F.Cu")
		(net "M_L_DQS_DP<12>")
	)
	(gr_poly
		(pts
			(xy 76.063602 -103.187754) (xy 76.063602 -103.136954) (xy 75.885802 -103.136954) (xy 75.885802 -103.187754)
			(xy 75.921362 -103.289354) (xy 76.028042 -103.289354)
		)
		(stroke
			(width 0)
			(type solid)
		)
		(fill yes)
		(layer "F.Cu")
		(net "M_L_DQ<25>")
	)
	(gr_poly
		(pts
			(xy 76.063602 -102.882954) (xy 76.063602 -102.832154) (xy 75.885802 -102.832154) (xy 75.885802 -102.882954)
			(xy 75.921362 -102.984554) (xy 76.028042 -102.984554)
		)
		(stroke
			(width 0)
			(type solid)
		)
		(fill yes)
		(layer "F.Cu")
		(net "M_L_DQ<24>")
	)
	(gr_poly
		(pts
			(xy 76.063602 -102.578154) (xy 76.063602 -102.527354) (xy 75.885802 -102.527354) (xy 75.885802 -102.578154)
			(xy 75.921362 -102.679754) (xy 76.028042 -102.679754)
		)
		(stroke
			(width 0)
			(type solid)
		)
		(fill yes)
		(layer "F.Cu")
		(net "M_L_DQ<29>")
	)
	(gr_poly
		(pts
			(xy 76.08316 -45.146468) (xy 76.07046 -44.955968) (xy 75.96886 -44.955968) (xy 75.95616 -45.146468)
			(xy 75.95616 -45.209968) (xy 76.08316 -45.209968)
		)
		(stroke
			(width 0)
			(type solid)
		)
		(fill yes)
		(layer "F.Cu")
		(net "M_H_ECC<4>")
	)
	(gr_poly
		(pts
			(xy 76.08316 -44.752768) (xy 76.07046 -44.562268) (xy 75.96886 -44.562268) (xy 75.95616 -44.752768)
			(xy 75.95616 -44.803568) (xy 76.08316 -44.803568)
		)
		(stroke
			(width 0)
			(type solid)
		)
		(fill yes)
		(layer "F.Cu")
		(net "M_H_ECC<5>")
	)
	(gr_poly
		(pts
			(xy 76.08316 -44.359068) (xy 76.07046 -44.168568) (xy 75.96886 -44.168568) (xy 75.95616 -44.359068)
			(xy 75.95616 -44.409868) (xy 76.08316 -44.409868)
		)
		(stroke
			(width 0)
			(type solid)
		)
		(fill yes)
		(layer "F.Cu")
		(net "M_H_ECC<0>")
	)
	(gr_poly
		(pts
			(xy 76.08316 -43.965368) (xy 76.07046 -43.774868) (xy 75.96886 -43.774868) (xy 75.95616 -43.965368)
			(xy 75.95616 -44.016168) (xy 76.08316 -44.016168)
		)
		(stroke
			(width 0)
			(type solid)
		)
		(fill yes)
		(layer "F.Cu")
		(net "M_H_ECC<1>")
	)
	(gr_poly
		(pts
			(xy 76.092304 -49.513744) (xy 76.13904 -49.416716) (xy 76.063602 -49.341278) (xy 75.966574 -49.388014)
			(xy 75.93076 -49.423828) (xy 76.05649 -49.549558)
		)
		(stroke
			(width 0)
			(type solid)
		)
		(fill yes)
		(layer "F.Cu")
		(net "M_H_DQ<29>")
	)
	(gr_poly
		(pts
			(xy 76.106528 -48.85309) (xy 76.070968 -48.75149) (xy 75.964288 -48.75149) (xy 75.928728 -48.85309)
			(xy 75.928728 -48.90389) (xy 76.106528 -48.90389)
		)
		(stroke
			(width 0)
			(type solid)
		)
		(fill yes)
		(layer "F.Cu")
		(net "M_H_DQ<24>")
	)
	(gr_poly
		(pts
			(xy 76.106528 -48.54829) (xy 76.070968 -48.44669) (xy 75.964288 -48.44669) (xy 75.928728 -48.54829)
			(xy 75.928728 -48.59909) (xy 76.106528 -48.59909)
		)
		(stroke
			(width 0)
			(type solid)
		)
		(fill yes)
		(layer "F.Cu")
		(net "M_H_DQ<25>")
	)
	(gr_poly
		(pts
			(xy 76.106528 -48.24349) (xy 76.070968 -48.14189) (xy 75.964288 -48.14189) (xy 75.928728 -48.24349)
			(xy 75.928728 -48.29429) (xy 76.106528 -48.29429)
		)
		(stroke
			(width 0)
			(type solid)
		)
		(fill yes)
		(layer "F.Cu")
		(net "M_H_DQS_DP<12>")
	)
	(gr_poly
		(pts
			(xy 76.106528 -47.93869) (xy 76.070968 -47.83709) (xy 75.964288 -47.83709) (xy 75.928728 -47.93869)
			(xy 75.928728 -47.98949) (xy 76.106528 -47.98949)
		)
		(stroke
			(width 0)
			(type solid)
		)
		(fill yes)
		(layer "F.Cu")
		(net "M_H_DQS_DN<12>")
	)
	(gr_poly
		(pts
			(xy 76.106528 -47.63389) (xy 76.070968 -47.53229) (xy 75.964288 -47.53229) (xy 75.928728 -47.63389)
			(xy 75.928728 -47.68469) (xy 76.106528 -47.68469)
		)
		(stroke
			(width 0)
			(type solid)
		)
		(fill yes)
		(layer "F.Cu")
		(net "M_H_DQS_DN<3>")
	)
	(gr_poly
		(pts
			(xy 76.106528 -47.32909) (xy 76.070968 -47.22749) (xy 75.964288 -47.22749) (xy 75.928728 -47.32909)
			(xy 75.928728 -47.37989) (xy 76.106528 -47.37989)
		)
		(stroke
			(width 0)
			(type solid)
		)
		(fill yes)
		(layer "F.Cu")
		(net "M_H_DQS_DP<3>")
	)
	(gr_poly
		(pts
			(xy 76.106528 -47.02429) (xy 76.070968 -46.92269) (xy 75.964288 -46.92269) (xy 75.928728 -47.02429)
			(xy 75.928728 -47.07509) (xy 76.106528 -47.07509)
		)
		(stroke
			(width 0)
			(type solid)
		)
		(fill yes)
		(layer "F.Cu")
		(net "M_H_DQ<30>")
	)
	(gr_poly
		(pts
			(xy 76.106528 -46.71949) (xy 76.070968 -46.61789) (xy 75.964288 -46.61789) (xy 75.928728 -46.71949)
			(xy 75.928728 -46.77029) (xy 76.106528 -46.77029)
		)
		(stroke
			(width 0)
			(type solid)
		)
		(fill yes)
		(layer "F.Cu")
		(net "M_H_DQ<31>")
	)
	(gr_poly
		(pts
			(xy 76.106528 -46.41469) (xy 76.070968 -46.31309) (xy 75.964288 -46.31309) (xy 75.928728 -46.41469)
			(xy 75.928728 -46.46549) (xy 76.106528 -46.46549)
		)
		(stroke
			(width 0)
			(type solid)
		)
		(fill yes)
		(layer "F.Cu")
		(net "M_H_DQ<26>")
	)
	(gr_poly
		(pts
			(xy 76.173076 -49.738026) (xy 76.20889 -49.702212) (xy 76.08316 -49.576482) (xy 76.047346 -49.612296)
			(xy 76.00061 -49.709324) (xy 76.076048 -49.784762)
		)
		(stroke
			(width 0)
			(type solid)
		)
		(fill yes)
		(layer "F.Cu")
		(net "M_H_DQ<29>")
	)
	(gr_poly
		(pts
			(xy 76.279502 -105.524554) (xy 76.243942 -105.422954) (xy 76.137262 -105.422954) (xy 76.101702 -105.524554)
			(xy 76.101702 -105.588054) (xy 76.279502 -105.588054)
		)
		(stroke
			(width 0)
			(type solid)
		)
		(fill yes)
		(layer "F.Cu")
		(net "M_L_DQ<27>")
	)
	(gr_poly
		(pts
			(xy 76.279502 -105.219754) (xy 76.243942 -105.118154) (xy 76.137262 -105.118154) (xy 76.101702 -105.219754)
			(xy 76.101702 -105.270554) (xy 76.279502 -105.270554)
		)
		(stroke
			(width 0)
			(type solid)
		)
		(fill yes)
		(layer "F.Cu")
		(net "M_L_DQ<26>")
	)
	(gr_poly
		(pts
			(xy 76.279502 -104.914954) (xy 76.243942 -104.813354) (xy 76.137262 -104.813354) (xy 76.101702 -104.914954)
			(xy 76.101702 -104.965754) (xy 76.279502 -104.965754)
		)
		(stroke
			(width 0)
			(type solid)
		)
		(fill yes)
		(layer "F.Cu")
		(net "M_L_DQ<31>")
	)
	(gr_poly
		(pts
			(xy 76.279502 -104.610154) (xy 76.243942 -104.508554) (xy 76.137262 -104.508554) (xy 76.101702 -104.610154)
			(xy 76.101702 -104.660954) (xy 76.279502 -104.660954)
		)
		(stroke
			(width 0)
			(type solid)
		)
		(fill yes)
		(layer "F.Cu")
		(net "M_L_DQ<30>")
	)
	(gr_poly
		(pts
			(xy 76.279502 -104.305354) (xy 76.243942 -104.203754) (xy 76.137262 -104.203754) (xy 76.101702 -104.305354)
			(xy 76.101702 -104.356154) (xy 76.279502 -104.356154)
		)
		(stroke
			(width 0)
			(type solid)
		)
		(fill yes)
		(layer "F.Cu")
		(net "M_L_DQS_DP<3>")
	)
	(gr_poly
		(pts
			(xy 76.279502 -104.000554) (xy 76.243942 -103.898954) (xy 76.137262 -103.898954) (xy 76.101702 -104.000554)
			(xy 76.101702 -104.051354) (xy 76.279502 -104.051354)
		)
		(stroke
			(width 0)
			(type solid)
		)
		(fill yes)
		(layer "F.Cu")
		(net "M_L_DQS_DN<3>")
	)
	(gr_poly
		(pts
			(xy 76.279502 -103.695754) (xy 76.243942 -103.594154) (xy 76.137262 -103.594154) (xy 76.101702 -103.695754)
			(xy 76.101702 -103.746554) (xy 76.279502 -103.746554)
		)
		(stroke
			(width 0)
			(type solid)
		)
		(fill yes)
		(layer "F.Cu")
		(net "M_L_DQS_DN<12>")
	)
	(gr_poly
		(pts
			(xy 76.279502 -103.390954) (xy 76.243942 -103.289354) (xy 76.137262 -103.289354) (xy 76.101702 -103.390954)
			(xy 76.101702 -103.441754) (xy 76.279502 -103.441754)
		)
		(stroke
			(width 0)
			(type solid)
		)
		(fill yes)
		(layer "F.Cu")
		(net "M_L_DQS_DP<12>")
	)
	(gr_poly
		(pts
			(xy 76.279502 -103.086154) (xy 76.243942 -102.984554) (xy 76.137262 -102.984554) (xy 76.101702 -103.086154)
			(xy 76.101702 -103.136954) (xy 76.279502 -103.136954)
		)
		(stroke
			(width 0)
			(type solid)
		)
		(fill yes)
		(layer "F.Cu")
		(net "M_L_DQ<25>")
	)
	(gr_poly
		(pts
			(xy 76.279502 -102.781354) (xy 76.243942 -102.679754) (xy 76.137262 -102.679754) (xy 76.101702 -102.781354)
			(xy 76.101702 -102.832154) (xy 76.279502 -102.832154)
		)
		(stroke
			(width 0)
			(type solid)
		)
		(fill yes)
		(layer "F.Cu")
		(net "M_L_DQ<24>")
	)
	(gr_poly
		(pts
			(xy 76.322428 -48.95469) (xy 76.322428 -48.90389) (xy 76.144628 -48.90389) (xy 76.144628 -48.95469)
			(xy 76.180188 -49.05629) (xy 76.286868 -49.05629)
		)
		(stroke
			(width 0)
			(type solid)
		)
		(fill yes)
		(layer "F.Cu")
		(net "M_H_DQ<24>")
	)
	(gr_poly
		(pts
			(xy 76.322428 -48.64989) (xy 76.322428 -48.59909) (xy 76.144628 -48.59909) (xy 76.144628 -48.64989)
			(xy 76.180188 -48.75149) (xy 76.286868 -48.75149)
		)
		(stroke
			(width 0)
			(type solid)
		)
		(fill yes)
		(layer "F.Cu")
		(net "M_H_DQ<25>")
	)
	(gr_poly
		(pts
			(xy 76.322428 -48.34509) (xy 76.322428 -48.29429) (xy 76.144628 -48.29429) (xy 76.144628 -48.34509)
			(xy 76.180188 -48.44669) (xy 76.286868 -48.44669)
		)
		(stroke
			(width 0)
			(type solid)
		)
		(fill yes)
		(layer "F.Cu")
		(net "M_H_DQS_DP<12>")
	)
	(gr_poly
		(pts
			(xy 76.322428 -48.04029) (xy 76.322428 -47.98949) (xy 76.144628 -47.98949) (xy 76.144628 -48.04029)
			(xy 76.180188 -48.14189) (xy 76.286868 -48.14189)
		)
		(stroke
			(width 0)
			(type solid)
		)
		(fill yes)
		(layer "F.Cu")
		(net "M_H_DQS_DN<12>")
	)
	(gr_poly
		(pts
			(xy 76.322428 -47.73549) (xy 76.322428 -47.68469) (xy 76.144628 -47.68469) (xy 76.144628 -47.73549)
			(xy 76.180188 -47.83709) (xy 76.286868 -47.83709)
		)
		(stroke
			(width 0)
			(type solid)
		)
		(fill yes)
		(layer "F.Cu")
		(net "M_H_DQS_DN<3>")
	)
	(gr_poly
		(pts
			(xy 76.322428 -47.43069) (xy 76.322428 -47.37989) (xy 76.144628 -47.37989) (xy 76.144628 -47.43069)
			(xy 76.180188 -47.53229) (xy 76.286868 -47.53229)
		)
		(stroke
			(width 0)
			(type solid)
		)
		(fill yes)
		(layer "F.Cu")
		(net "M_H_DQS_DP<3>")
	)
	(gr_poly
		(pts
			(xy 76.322428 -47.12589) (xy 76.322428 -47.07509) (xy 76.144628 -47.07509) (xy 76.144628 -47.12589)
			(xy 76.180188 -47.22749) (xy 76.286868 -47.22749)
		)
		(stroke
			(width 0)
			(type solid)
		)
		(fill yes)
		(layer "F.Cu")
		(net "M_H_DQ<30>")
	)
	(gr_poly
		(pts
			(xy 76.322428 -46.82109) (xy 76.322428 -46.77029) (xy 76.144628 -46.77029) (xy 76.144628 -46.82109)
			(xy 76.180188 -46.92269) (xy 76.286868 -46.92269)
		)
		(stroke
			(width 0)
			(type solid)
		)
		(fill yes)
		(layer "F.Cu")
		(net "M_H_DQ<31>")
	)
	(gr_poly
		(pts
			(xy 76.322428 -46.51629) (xy 76.322428 -46.46549) (xy 76.144628 -46.46549) (xy 76.144628 -46.51629)
			(xy 76.180188 -46.61789) (xy 76.286868 -46.61789)
		)
		(stroke
			(width 0)
			(type solid)
		)
		(fill yes)
		(layer "F.Cu")
		(net "M_H_DQ<26>")
	)
	(gr_poly
		(pts
			(xy 76.322428 -46.21149) (xy 76.322428 -46.14799) (xy 76.144628 -46.14799) (xy 76.144628 -46.21149)
			(xy 76.180188 -46.31309) (xy 76.286868 -46.31309)
		)
		(stroke
			(width 0)
			(type solid)
		)
		(fill yes)
		(layer "F.Cu")
		(net "M_H_DQ<27>")
	)
	(gr_poly
		(pts
			(xy 76.38796 -43.279568) (xy 76.38796 -43.228768) (xy 76.26096 -43.228768) (xy 76.26096 -43.279568)
			(xy 76.27366 -43.470068) (xy 76.37526 -43.470068)
		)
		(stroke
			(width 0)
			(type solid)
		)
		(fill yes)
		(layer "F.Cu")
		(net "M_H_DQS_DN<17>")
	)
	(gr_poly
		(pts
			(xy 76.41336 -44.854368) (xy 76.41336 -44.803568) (xy 76.28636 -44.803568) (xy 76.28636 -44.854368)
			(xy 76.29906 -45.044868) (xy 76.40066 -45.044868)
		)
		(stroke
			(width 0)
			(type solid)
		)
		(fill yes)
		(layer "F.Cu")
		(net "M_H_ECC<5>")
	)
	(gr_poly
		(pts
			(xy 76.41336 -44.460668) (xy 76.41336 -44.409868) (xy 76.28636 -44.409868) (xy 76.28636 -44.460668)
			(xy 76.29906 -44.651168) (xy 76.40066 -44.651168)
		)
		(stroke
			(width 0)
			(type solid)
		)
		(fill yes)
		(layer "F.Cu")
		(net "M_H_ECC<0>")
	)
	(gr_poly
		(pts
			(xy 76.41336 -44.066968) (xy 76.41336 -44.016168) (xy 76.28636 -44.016168) (xy 76.28636 -44.066968)
			(xy 76.29906 -44.257468) (xy 76.40066 -44.257468)
		)
		(stroke
			(width 0)
			(type solid)
		)
		(fill yes)
		(layer "F.Cu")
		(net "M_H_ECC<1>")
	)
	(gr_poly
		(pts
			(xy 76.41336 -43.673268) (xy 76.41336 -43.622468) (xy 76.28636 -43.622468) (xy 76.28636 -43.673268)
			(xy 76.29906 -43.863768) (xy 76.40066 -43.863768)
		)
		(stroke
			(width 0)
			(type solid)
		)
		(fill yes)
		(layer "F.Cu")
		(net "M_H_DQS_DP<17>")
	)
	(gr_poly
		(pts
			(xy 76.495402 -105.321354) (xy 76.495402 -105.270554) (xy 76.317602 -105.270554) (xy 76.317602 -105.321354)
			(xy 76.353162 -105.422954) (xy 76.459842 -105.422954)
		)
		(stroke
			(width 0)
			(type solid)
		)
		(fill yes)
		(layer "F.Cu")
		(net "M_L_DQ<26>")
	)
	(gr_poly
		(pts
			(xy 76.495402 -105.016554) (xy 76.495402 -104.965754) (xy 76.317602 -104.965754) (xy 76.317602 -105.016554)
			(xy 76.353162 -105.118154) (xy 76.459842 -105.118154)
		)
		(stroke
			(width 0)
			(type solid)
		)
		(fill yes)
		(layer "F.Cu")
		(net "M_L_DQ<31>")
	)
	(gr_poly
		(pts
			(xy 76.495402 -104.711754) (xy 76.495402 -104.660954) (xy 76.317602 -104.660954) (xy 76.317602 -104.711754)
			(xy 76.353162 -104.813354) (xy 76.459842 -104.813354)
		)
		(stroke
			(width 0)
			(type solid)
		)
		(fill yes)
		(layer "F.Cu")
		(net "M_L_DQ<30>")
	)
	(gr_poly
		(pts
			(xy 76.495402 -104.406954) (xy 76.495402 -104.356154) (xy 76.317602 -104.356154) (xy 76.317602 -104.406954)
			(xy 76.353162 -104.508554) (xy 76.459842 -104.508554)
		)
		(stroke
			(width 0)
			(type solid)
		)
		(fill yes)
		(layer "F.Cu")
		(net "M_L_DQS_DP<3>")
	)
	(gr_poly
		(pts
			(xy 76.495402 -104.102154) (xy 76.495402 -104.051354) (xy 76.317602 -104.051354) (xy 76.317602 -104.102154)
			(xy 76.353162 -104.203754) (xy 76.459842 -104.203754)
		)
		(stroke
			(width 0)
			(type solid)
		)
		(fill yes)
		(layer "F.Cu")
		(net "M_L_DQS_DN<3>")
	)
	(gr_poly
		(pts
			(xy 76.495402 -103.797354) (xy 76.495402 -103.746554) (xy 76.317602 -103.746554) (xy 76.317602 -103.797354)
			(xy 76.353162 -103.898954) (xy 76.459842 -103.898954)
		)
		(stroke
			(width 0)
			(type solid)
		)
		(fill yes)
		(layer "F.Cu")
		(net "M_L_DQS_DN<12>")
	)
	(gr_poly
		(pts
			(xy 76.495402 -103.492554) (xy 76.495402 -103.441754) (xy 76.317602 -103.441754) (xy 76.317602 -103.492554)
			(xy 76.353162 -103.594154) (xy 76.459842 -103.594154)
		)
		(stroke
			(width 0)
			(type solid)
		)
		(fill yes)
		(layer "F.Cu")
		(net "M_L_DQS_DP<12>")
	)
	(gr_poly
		(pts
			(xy 76.495402 -103.187754) (xy 76.495402 -103.136954) (xy 76.317602 -103.136954) (xy 76.317602 -103.187754)
			(xy 76.353162 -103.289354) (xy 76.459842 -103.289354)
		)
		(stroke
			(width 0)
			(type solid)
		)
		(fill yes)
		(layer "F.Cu")
		(net "M_L_DQ<25>")
	)
	(gr_poly
		(pts
			(xy 76.495402 -102.882954) (xy 76.495402 -102.832154) (xy 76.317602 -102.832154) (xy 76.317602 -102.882954)
			(xy 76.353162 -102.984554) (xy 76.459842 -102.984554)
		)
		(stroke
			(width 0)
			(type solid)
		)
		(fill yes)
		(layer "F.Cu")
		(net "M_L_DQ<24>")
	)
	(gr_poly
		(pts
			(xy 76.538328 -48.85309) (xy 76.502768 -48.75149) (xy 76.396088 -48.75149) (xy 76.360528 -48.85309)
			(xy 76.360528 -48.90389) (xy 76.538328 -48.90389)
		)
		(stroke
			(width 0)
			(type solid)
		)
		(fill yes)
		(layer "F.Cu")
		(net "M_H_DQ<24>")
	)
	(gr_poly
		(pts
			(xy 76.538328 -48.54829) (xy 76.502768 -48.44669) (xy 76.396088 -48.44669) (xy 76.360528 -48.54829)
			(xy 76.360528 -48.59909) (xy 76.538328 -48.59909)
		)
		(stroke
			(width 0)
			(type solid)
		)
		(fill yes)
		(layer "F.Cu")
		(net "M_H_DQ<25>")
	)
	(gr_poly
		(pts
			(xy 76.538328 -48.24349) (xy 76.502768 -48.14189) (xy 76.396088 -48.14189) (xy 76.360528 -48.24349)
			(xy 76.360528 -48.29429) (xy 76.538328 -48.29429)
		)
		(stroke
			(width 0)
			(type solid)
		)
		(fill yes)
		(layer "F.Cu")
		(net "M_H_DQS_DP<12>")
	)
	(gr_poly
		(pts
			(xy 76.538328 -47.93869) (xy 76.502768 -47.83709) (xy 76.396088 -47.83709) (xy 76.360528 -47.93869)
			(xy 76.360528 -47.98949) (xy 76.538328 -47.98949)
		)
		(stroke
			(width 0)
			(type solid)
		)
		(fill yes)
		(layer "F.Cu")
		(net "M_H_DQS_DN<12>")
	)
	(gr_poly
		(pts
			(xy 76.538328 -47.63389) (xy 76.502768 -47.53229) (xy 76.396088 -47.53229) (xy 76.360528 -47.63389)
			(xy 76.360528 -47.68469) (xy 76.538328 -47.68469)
		)
		(stroke
			(width 0)
			(type solid)
		)
		(fill yes)
		(layer "F.Cu")
		(net "M_H_DQS_DN<3>")
	)
	(gr_poly
		(pts
			(xy 76.538328 -47.32909) (xy 76.502768 -47.22749) (xy 76.396088 -47.22749) (xy 76.360528 -47.32909)
			(xy 76.360528 -47.37989) (xy 76.538328 -47.37989)
		)
		(stroke
			(width 0)
			(type solid)
		)
		(fill yes)
		(layer "F.Cu")
		(net "M_H_DQS_DP<3>")
	)
	(gr_poly
		(pts
			(xy 76.538328 -47.02429) (xy 76.502768 -46.92269) (xy 76.396088 -46.92269) (xy 76.360528 -47.02429)
			(xy 76.360528 -47.07509) (xy 76.538328 -47.07509)
		)
		(stroke
			(width 0)
			(type solid)
		)
		(fill yes)
		(layer "F.Cu")
		(net "M_H_DQ<30>")
	)
	(gr_poly
		(pts
			(xy 76.538328 -46.71949) (xy 76.502768 -46.61789) (xy 76.396088 -46.61789) (xy 76.360528 -46.71949)
			(xy 76.360528 -46.77029) (xy 76.538328 -46.77029)
		)
		(stroke
			(width 0)
			(type solid)
		)
		(fill yes)
		(layer "F.Cu")
		(net "M_H_DQ<31>")
	)
	(gr_poly
		(pts
			(xy 76.538328 -46.41469) (xy 76.502768 -46.31309) (xy 76.396088 -46.31309) (xy 76.360528 -46.41469)
			(xy 76.360528 -46.46549) (xy 76.538328 -46.46549)
		)
		(stroke
			(width 0)
			(type solid)
		)
		(fill yes)
		(layer "F.Cu")
		(net "M_H_DQ<26>")
	)
	(gr_poly
		(pts
			(xy 76.54544 -106.404664) (xy 76.54544 -106.341164) (xy 76.41844 -106.341164) (xy 76.41844 -106.404664)
			(xy 76.43114 -106.595164) (xy 76.53274 -106.595164)
		)
		(stroke
			(width 0)
			(type solid)
		)
		(fill yes)
		(layer "F.Cu")
		(net "M_L_ECC<4>")
	)
	(gr_poly
		(pts
			(xy 76.621132 -51.361848) (xy 76.586588 -50.964592) (xy 76.542138 -50.968402) (xy 76.38034 -51.07178)
			(xy 76.399644 -51.291998) (xy 76.576936 -51.365658)
		)
		(stroke
			(width 0)
			(type solid)
		)
		(fill yes)
		(layer "F.Cu")
		(net "M_H_DQ<28>")
	)
	(gr_poly
		(pts
			(xy 76.711302 -105.524554) (xy 76.675742 -105.422954) (xy 76.569062 -105.422954) (xy 76.533502 -105.524554)
			(xy 76.533502 -105.588054) (xy 76.711302 -105.588054)
		)
		(stroke
			(width 0)
			(type solid)
		)
		(fill yes)
		(layer "F.Cu")
		(net "M_L_DQ<27>")
	)
	(gr_poly
		(pts
			(xy 76.711302 -105.219754) (xy 76.675742 -105.118154) (xy 76.569062 -105.118154) (xy 76.533502 -105.219754)
			(xy 76.533502 -105.270554) (xy 76.711302 -105.270554)
		)
		(stroke
			(width 0)
			(type solid)
		)
		(fill yes)
		(layer "F.Cu")
		(net "M_L_DQ<26>")
	)
	(gr_poly
		(pts
			(xy 76.711302 -104.914954) (xy 76.675742 -104.813354) (xy 76.569062 -104.813354) (xy 76.533502 -104.914954)
			(xy 76.533502 -104.965754) (xy 76.711302 -104.965754)
		)
		(stroke
			(width 0)
			(type solid)
		)
		(fill yes)
		(layer "F.Cu")
		(net "M_L_DQ<31>")
	)
	(gr_poly
		(pts
			(xy 76.711302 -104.610154) (xy 76.675742 -104.508554) (xy 76.569062 -104.508554) (xy 76.533502 -104.610154)
			(xy 76.533502 -104.660954) (xy 76.711302 -104.660954)
		)
		(stroke
			(width 0)
			(type solid)
		)
		(fill yes)
		(layer "F.Cu")
		(net "M_L_DQ<30>")
	)
	(gr_poly
		(pts
			(xy 76.711302 -104.305354) (xy 76.675742 -104.203754) (xy 76.569062 -104.203754) (xy 76.533502 -104.305354)
			(xy 76.533502 -104.356154) (xy 76.711302 -104.356154)
		)
		(stroke
			(width 0)
			(type solid)
		)
		(fill yes)
		(layer "F.Cu")
		(net "M_L_DQS_DP<3>")
	)
	(gr_poly
		(pts
			(xy 76.711302 -104.000554) (xy 76.675742 -103.898954) (xy 76.569062 -103.898954) (xy 76.533502 -104.000554)
			(xy 76.533502 -104.051354) (xy 76.711302 -104.051354)
		)
		(stroke
			(width 0)
			(type solid)
		)
		(fill yes)
		(layer "F.Cu")
		(net "M_L_DQS_DN<3>")
	)
	(gr_poly
		(pts
			(xy 76.711302 -103.695754) (xy 76.675742 -103.594154) (xy 76.569062 -103.594154) (xy 76.533502 -103.695754)
			(xy 76.533502 -103.746554) (xy 76.711302 -103.746554)
		)
		(stroke
			(width 0)
			(type solid)
		)
		(fill yes)
		(layer "F.Cu")
		(net "M_L_DQS_DN<12>")
	)
	(gr_poly
		(pts
			(xy 76.711302 -103.390954) (xy 76.675742 -103.289354) (xy 76.569062 -103.289354) (xy 76.533502 -103.390954)
			(xy 76.533502 -103.441754) (xy 76.711302 -103.441754)
		)
		(stroke
			(width 0)
			(type solid)
		)
		(fill yes)
		(layer "F.Cu")
		(net "M_L_DQS_DP<12>")
	)
	(gr_poly
		(pts
			(xy 76.711302 -103.086154) (xy 76.675742 -102.984554) (xy 76.569062 -102.984554) (xy 76.533502 -103.086154)
			(xy 76.533502 -103.136954) (xy 76.711302 -103.136954)
		)
		(stroke
			(width 0)
			(type solid)
		)
		(fill yes)
		(layer "F.Cu")
		(net "M_L_DQ<25>")
	)
	(gr_poly
		(pts
			(xy 76.711302 -102.781354) (xy 76.675742 -102.679754) (xy 76.569062 -102.679754) (xy 76.533502 -102.781354)
			(xy 76.533502 -102.832154) (xy 76.711302 -102.832154)
		)
		(stroke
			(width 0)
			(type solid)
		)
		(fill yes)
		(layer "F.Cu")
		(net "M_L_DQ<24>")
	)
	(gr_poly
		(pts
			(xy 76.74356 -45.146468) (xy 76.73086 -44.955968) (xy 76.62926 -44.955968) (xy 76.61656 -45.146468)
			(xy 76.61656 -45.209968) (xy 76.74356 -45.209968)
		)
		(stroke
			(width 0)
			(type solid)
		)
		(fill yes)
		(layer "F.Cu")
		(net "M_H_ECC<4>")
	)
	(gr_poly
		(pts
			(xy 76.74356 -44.752768) (xy 76.73086 -44.562268) (xy 76.62926 -44.562268) (xy 76.61656 -44.752768)
			(xy 76.61656 -44.803568) (xy 76.74356 -44.803568)
		)
		(stroke
			(width 0)
			(type solid)
		)
		(fill yes)
		(layer "F.Cu")
		(net "M_H_ECC<5>")
	)
	(gr_poly
		(pts
			(xy 76.74356 -44.359068) (xy 76.73086 -44.168568) (xy 76.62926 -44.168568) (xy 76.61656 -44.359068)
			(xy 76.61656 -44.409868) (xy 76.74356 -44.409868)
		)
		(stroke
			(width 0)
			(type solid)
		)
		(fill yes)
		(layer "F.Cu")
		(net "M_H_ECC<0>")
	)
	(gr_poly
		(pts
			(xy 76.74356 -43.965368) (xy 76.73086 -43.774868) (xy 76.62926 -43.774868) (xy 76.61656 -43.965368)
			(xy 76.61656 -44.016168) (xy 76.74356 -44.016168)
		)
		(stroke
			(width 0)
			(type solid)
		)
		(fill yes)
		(layer "F.Cu")
		(net "M_H_ECC<1>")
	)
	(gr_poly
		(pts
			(xy 76.74356 -43.571668) (xy 76.73086 -43.381168) (xy 76.62926 -43.381168) (xy 76.61656 -43.571668)
			(xy 76.61656 -43.622468) (xy 76.74356 -43.622468)
		)
		(stroke
			(width 0)
			(type solid)
		)
		(fill yes)
		(layer "F.Cu")
		(net "M_H_DQS_DP<17>")
	)
	(gr_poly
		(pts
			(xy 76.74356 -43.177968) (xy 76.73086 -42.987468) (xy 76.62926 -42.987468) (xy 76.61656 -43.177968)
			(xy 76.61656 -43.228768) (xy 76.74356 -43.228768)
		)
		(stroke
			(width 0)
			(type solid)
		)
		(fill yes)
		(layer "F.Cu")
		(net "M_H_DQS_DN<17>")
	)
	(gr_poly
		(pts
			(xy 76.74356 -42.784268) (xy 76.73086 -42.593768) (xy 76.62926 -42.593768) (xy 76.61656 -42.784268)
			(xy 76.61656 -42.835068) (xy 76.74356 -42.835068)
		)
		(stroke
			(width 0)
			(type solid)
		)
		(fill yes)
		(layer "F.Cu")
		(net "M_H_DQS_DN<8>")
	)
	(gr_poly
		(pts
			(xy 76.754228 -48.34509) (xy 76.754228 -48.29429) (xy 76.576428 -48.29429) (xy 76.576428 -48.34509)
			(xy 76.611988 -48.44669) (xy 76.718668 -48.44669)
		)
		(stroke
			(width 0)
			(type solid)
		)
		(fill yes)
		(layer "F.Cu")
		(net "M_H_DQS_DP<12>")
	)
	(gr_poly
		(pts
			(xy 76.754228 -48.04029) (xy 76.754228 -47.98949) (xy 76.576428 -47.98949) (xy 76.576428 -48.04029)
			(xy 76.611988 -48.14189) (xy 76.718668 -48.14189)
		)
		(stroke
			(width 0)
			(type solid)
		)
		(fill yes)
		(layer "F.Cu")
		(net "M_H_DQS_DN<12>")
	)
	(gr_poly
		(pts
			(xy 76.754228 -47.73549) (xy 76.754228 -47.68469) (xy 76.576428 -47.68469) (xy 76.576428 -47.73549)
			(xy 76.611988 -47.83709) (xy 76.718668 -47.83709)
		)
		(stroke
			(width 0)
			(type solid)
		)
		(fill yes)
		(layer "F.Cu")
		(net "M_H_DQS_DN<3>")
	)
	(gr_poly
		(pts
			(xy 76.754228 -47.43069) (xy 76.754228 -47.37989) (xy 76.576428 -47.37989) (xy 76.576428 -47.43069)
			(xy 76.611988 -47.53229) (xy 76.718668 -47.53229)
		)
		(stroke
			(width 0)
			(type solid)
		)
		(fill yes)
		(layer "F.Cu")
		(net "M_H_DQS_DP<3>")
	)
	(gr_poly
		(pts
			(xy 76.754228 -47.12589) (xy 76.754228 -47.07509) (xy 76.576428 -47.07509) (xy 76.576428 -47.12589)
			(xy 76.611988 -47.22749) (xy 76.718668 -47.22749)
		)
		(stroke
			(width 0)
			(type solid)
		)
		(fill yes)
		(layer "F.Cu")
		(net "M_H_DQ<30>")
	)
	(gr_poly
		(pts
			(xy 76.754228 -46.82109) (xy 76.754228 -46.77029) (xy 76.576428 -46.77029) (xy 76.576428 -46.82109)
			(xy 76.611988 -46.92269) (xy 76.718668 -46.92269)
		)
		(stroke
			(width 0)
			(type solid)
		)
		(fill yes)
		(layer "F.Cu")
		(net "M_H_DQ<31>")
	)
	(gr_poly
		(pts
			(xy 76.754228 -46.51629) (xy 76.754228 -46.46549) (xy 76.576428 -46.46549) (xy 76.576428 -46.51629)
			(xy 76.611988 -46.61789) (xy 76.718668 -46.61789)
		)
		(stroke
			(width 0)
			(type solid)
		)
		(fill yes)
		(layer "F.Cu")
		(net "M_H_DQ<26>")
	)
	(gr_poly
		(pts
			(xy 76.754228 -46.21149) (xy 76.754228 -46.14799) (xy 76.576428 -46.14799) (xy 76.576428 -46.21149)
			(xy 76.611988 -46.31309) (xy 76.718668 -46.31309)
		)
		(stroke
			(width 0)
			(type solid)
		)
		(fill yes)
		(layer "F.Cu")
		(net "M_H_DQ<27>")
	)
	(gr_poly
		(pts
			(xy 76.87564 -106.696764) (xy 76.86294 -106.506264) (xy 76.76134 -106.506264) (xy 76.74864 -106.696764)
			(xy 76.74864 -106.747564) (xy 76.87564 -106.747564)
		)
		(stroke
			(width 0)
			(type solid)
		)
		(fill yes)
		(layer "F.Cu")
		(net "M_L_ECC<5>")
	)
	(gr_poly
		(pts
			(xy 76.914248 -48.804068) (xy 76.950062 -48.768) (xy 76.824586 -48.642524) (xy 76.788518 -48.678338)
			(xy 76.741782 -48.775366) (xy 76.81722 -48.850804)
		)
		(stroke
			(width 0)
			(type solid)
		)
		(fill yes)
		(layer "F.Cu")
		(net "M_H_DQ<25>")
	)
	(gr_poly
		(pts
			(xy 76.923138 -49.100486) (xy 76.969874 -49.003458) (xy 76.894436 -48.92802) (xy 76.797408 -48.974756)
			(xy 76.76134 -49.01057) (xy 76.88707 -49.1363)
		)
		(stroke
			(width 0)
			(type solid)
		)
		(fill yes)
		(layer "F.Cu")
		(net "M_H_DQ<24>")
	)
	(gr_poly
		(pts
			(xy 76.927202 -105.321354) (xy 76.927202 -105.270554) (xy 76.749402 -105.270554) (xy 76.749402 -105.321354)
			(xy 76.784962 -105.422954) (xy 76.891642 -105.422954)
		)
		(stroke
			(width 0)
			(type solid)
		)
		(fill yes)
		(layer "F.Cu")
		(net "M_L_DQ<26>")
	)
	(gr_poly
		(pts
			(xy 76.927202 -105.016554) (xy 76.927202 -104.965754) (xy 76.749402 -104.965754) (xy 76.749402 -105.016554)
			(xy 76.784962 -105.118154) (xy 76.891642 -105.118154)
		)
		(stroke
			(width 0)
			(type solid)
		)
		(fill yes)
		(layer "F.Cu")
		(net "M_L_DQ<31>")
	)
	(gr_poly
		(pts
			(xy 76.927202 -104.711754) (xy 76.927202 -104.660954) (xy 76.749402 -104.660954) (xy 76.749402 -104.711754)
			(xy 76.784962 -104.813354) (xy 76.891642 -104.813354)
		)
		(stroke
			(width 0)
			(type solid)
		)
		(fill yes)
		(layer "F.Cu")
		(net "M_L_DQ<30>")
	)
	(gr_poly
		(pts
			(xy 76.927202 -104.406954) (xy 76.927202 -104.356154) (xy 76.749402 -104.356154) (xy 76.749402 -104.406954)
			(xy 76.784962 -104.508554) (xy 76.891642 -104.508554)
		)
		(stroke
			(width 0)
			(type solid)
		)
		(fill yes)
		(layer "F.Cu")
		(net "M_L_DQS_DP<3>")
	)
	(gr_poly
		(pts
			(xy 76.927202 -104.102154) (xy 76.927202 -104.051354) (xy 76.749402 -104.051354) (xy 76.749402 -104.102154)
			(xy 76.784962 -104.203754) (xy 76.891642 -104.203754)
		)
		(stroke
			(width 0)
			(type solid)
		)
		(fill yes)
		(layer "F.Cu")
		(net "M_L_DQS_DN<3>")
	)
	(gr_poly
		(pts
			(xy 76.927202 -103.797354) (xy 76.927202 -103.746554) (xy 76.749402 -103.746554) (xy 76.749402 -103.797354)
			(xy 76.784962 -103.898954) (xy 76.891642 -103.898954)
		)
		(stroke
			(width 0)
			(type solid)
		)
		(fill yes)
		(layer "F.Cu")
		(net "M_L_DQS_DN<12>")
	)
	(gr_poly
		(pts
			(xy 76.927202 -103.492554) (xy 76.927202 -103.441754) (xy 76.749402 -103.441754) (xy 76.749402 -103.492554)
			(xy 76.784962 -103.594154) (xy 76.891642 -103.594154)
		)
		(stroke
			(width 0)
			(type solid)
		)
		(fill yes)
		(layer "F.Cu")
		(net "M_L_DQS_DP<12>")
	)
	(gr_poly
		(pts
			(xy 76.927202 -103.187754) (xy 76.927202 -103.136954) (xy 76.749402 -103.136954) (xy 76.749402 -103.187754)
			(xy 76.784962 -103.289354) (xy 76.891642 -103.289354)
		)
		(stroke
			(width 0)
			(type solid)
		)
		(fill yes)
		(layer "F.Cu")
		(net "M_L_DQ<25>")
	)
	(gr_poly
		(pts
			(xy 76.970128 -47.93869) (xy 76.934568 -47.83709) (xy 76.827888 -47.83709) (xy 76.792328 -47.93869)
			(xy 76.792328 -47.98949) (xy 76.970128 -47.98949)
		)
		(stroke
			(width 0)
			(type solid)
		)
		(fill yes)
		(layer "F.Cu")
		(net "M_H_DQS_DN<12>")
	)
	(gr_poly
		(pts
			(xy 76.970128 -47.63389) (xy 76.934568 -47.53229) (xy 76.827888 -47.53229) (xy 76.792328 -47.63389)
			(xy 76.792328 -47.68469) (xy 76.970128 -47.68469)
		)
		(stroke
			(width 0)
			(type solid)
		)
		(fill yes)
		(layer "F.Cu")
		(net "M_H_DQS_DN<3>")
	)
	(gr_poly
		(pts
			(xy 76.970128 -47.32909) (xy 76.934568 -47.22749) (xy 76.827888 -47.22749) (xy 76.792328 -47.32909)
			(xy 76.792328 -47.37989) (xy 76.970128 -47.37989)
		)
		(stroke
			(width 0)
			(type solid)
		)
		(fill yes)
		(layer "F.Cu")
		(net "M_H_DQS_DP<3>")
	)
	(gr_poly
		(pts
			(xy 76.970128 -47.02429) (xy 76.934568 -46.92269) (xy 76.827888 -46.92269) (xy 76.792328 -47.02429)
			(xy 76.792328 -47.07509) (xy 76.970128 -47.07509)
		)
		(stroke
			(width 0)
			(type solid)
		)
		(fill yes)
		(layer "F.Cu")
		(net "M_H_DQ<30>")
	)
	(gr_poly
		(pts
			(xy 76.970128 -46.71949) (xy 76.934568 -46.61789) (xy 76.827888 -46.61789) (xy 76.792328 -46.71949)
			(xy 76.792328 -46.77029) (xy 76.970128 -46.77029)
		)
		(stroke
			(width 0)
			(type solid)
		)
		(fill yes)
		(layer "F.Cu")
		(net "M_H_DQ<31>")
	)
	(gr_poly
		(pts
			(xy 76.970128 -46.41469) (xy 76.934568 -46.31309) (xy 76.827888 -46.31309) (xy 76.792328 -46.41469)
			(xy 76.792328 -46.46549) (xy 76.970128 -46.46549)
		)
		(stroke
			(width 0)
			(type solid)
		)
		(fill yes)
		(layer "F.Cu")
		(net "M_H_DQ<26>")
	)
	(gr_poly
		(pts
			(xy 77.049122 -48.363886) (xy 77.095858 -48.266858) (xy 77.02042 -48.19142) (xy 76.923392 -48.238156)
			(xy 76.887324 -48.27397) (xy 77.013054 -48.3997)
		)
		(stroke
			(width 0)
			(type solid)
		)
		(fill yes)
		(layer "F.Cu")
		(net "M_H_DQS_DP<12>")
	)
	(gr_poly
		(pts
			(xy 77.0636 -102.841044) (xy 77.016864 -102.744016) (xy 76.980796 -102.708202) (xy 76.85532 -102.833678)
			(xy 76.891134 -102.869746) (xy 76.988162 -102.916482)
		)
		(stroke
			(width 0)
			(type solid)
		)
		(fill yes)
		(layer "F.Cu")
		(net "M_L_DQ<24>")
	)
	(gr_poly
		(pts
			(xy 77.07122 -44.96816) (xy 77.107034 -44.932092) (xy 77.017372 -44.84243) (xy 76.981304 -44.878244)
			(xy 76.855574 -45.022008) (xy 76.927456 -45.09389)
		)
		(stroke
			(width 0)
			(type solid)
		)
		(fill yes)
		(layer "F.Cu")
		(net "M_H_ECC<5>")
	)
	(gr_poly
		(pts
			(xy 77.07376 -44.460668) (xy 77.07376 -44.409868) (xy 76.94676 -44.409868) (xy 76.94676 -44.460668)
			(xy 76.95946 -44.651168) (xy 77.06106 -44.651168)
		)
		(stroke
			(width 0)
			(type solid)
		)
		(fill yes)
		(layer "F.Cu")
		(net "M_H_ECC<0>")
	)
	(gr_poly
		(pts
			(xy 77.07376 -44.066968) (xy 77.07376 -44.016168) (xy 76.94676 -44.016168) (xy 76.94676 -44.066968)
			(xy 76.95946 -44.257468) (xy 77.06106 -44.257468)
		)
		(stroke
			(width 0)
			(type solid)
		)
		(fill yes)
		(layer "F.Cu")
		(net "M_H_ECC<1>")
	)
	(gr_poly
		(pts
			(xy 77.07376 -43.673268) (xy 77.07376 -43.622468) (xy 76.94676 -43.622468) (xy 76.94676 -43.673268)
			(xy 76.95946 -43.863768) (xy 77.06106 -43.863768)
		)
		(stroke
			(width 0)
			(type solid)
		)
		(fill yes)
		(layer "F.Cu")
		(net "M_H_DQS_DP<17>")
	)
	(gr_poly
		(pts
			(xy 77.07376 -43.279568) (xy 77.07376 -43.228768) (xy 76.94676 -43.228768) (xy 76.94676 -43.279568)
			(xy 76.95946 -43.470068) (xy 77.06106 -43.470068)
		)
		(stroke
			(width 0)
			(type solid)
		)
		(fill yes)
		(layer "F.Cu")
		(net "M_H_DQS_DN<17>")
	)
	(gr_poly
		(pts
			(xy 77.07376 -42.885868) (xy 77.07376 -42.835068) (xy 76.94676 -42.835068) (xy 76.94676 -42.885868)
			(xy 76.95946 -43.076368) (xy 77.06106 -43.076368)
		)
		(stroke
			(width 0)
			(type solid)
		)
		(fill yes)
		(layer "F.Cu")
		(net "M_H_DQS_DN<8>")
	)
	(gr_poly
		(pts
			(xy 77.07376 -42.492168) (xy 77.07376 -42.441368) (xy 76.94676 -42.441368) (xy 76.94676 -42.492168)
			(xy 76.95946 -42.682668) (xy 77.06106 -42.682668)
		)
		(stroke
			(width 0)
			(type solid)
		)
		(fill yes)
		(layer "F.Cu")
		(net "M_H_DQS_DP<8>")
	)
	(gr_poly
		(pts
			(xy 77.098144 -45.40885) (xy 77.223874 -45.265086) (xy 77.151992 -45.193458) (xy 77.008228 -45.319188)
			(xy 76.972414 -45.355002) (xy 77.06233 -45.444918)
		)
		(stroke
			(width 0)
			(type solid)
		)
		(fill yes)
		(layer "F.Cu")
		(net "M_H_ECC<4>")
	)
	(gr_poly
		(pts
			(xy 77.129894 -48.588422) (xy 77.165708 -48.552354) (xy 77.040232 -48.426878) (xy 77.004164 -48.462692)
			(xy 76.957428 -48.55972) (xy 77.032866 -48.635158)
		)
		(stroke
			(width 0)
			(type solid)
		)
		(fill yes)
		(layer "F.Cu")
		(net "M_H_DQS_DP<12>")
	)
	(gr_poly
		(pts
			(xy 77.138784 -48.88484) (xy 77.18552 -48.787812) (xy 77.110082 -48.712374) (xy 77.013054 -48.75911)
			(xy 76.976986 -48.794924) (xy 77.102716 -48.920654)
		)
		(stroke
			(width 0)
			(type solid)
		)
		(fill yes)
		(layer "F.Cu")
		(net "M_H_DQ<25>")
	)
	(gr_poly
		(pts
			(xy 77.140054 -50.74158) (xy 77.140054 -50.5206) (xy 76.969874 -50.4317) (xy 76.925424 -50.4317)
			(xy 76.925424 -50.83048) (xy 76.969874 -50.83048)
		)
		(stroke
			(width 0)
			(type solid)
		)
		(fill yes)
		(layer "F.Cu")
		(net "M_H_DQ<29>")
	)
	(gr_poly
		(pts
			(xy 77.143102 -105.524554) (xy 77.107542 -105.422954) (xy 77.000862 -105.422954) (xy 76.965302 -105.524554)
			(xy 76.965302 -105.588054) (xy 77.143102 -105.588054)
		)
		(stroke
			(width 0)
			(type solid)
		)
		(fill yes)
		(layer "F.Cu")
		(net "M_L_DQ<27>")
	)
	(gr_poly
		(pts
			(xy 77.143102 -105.219754) (xy 77.107542 -105.118154) (xy 77.000862 -105.118154) (xy 76.965302 -105.219754)
			(xy 76.965302 -105.270554) (xy 77.143102 -105.270554)
		)
		(stroke
			(width 0)
			(type solid)
		)
		(fill yes)
		(layer "F.Cu")
		(net "M_L_DQ<26>")
	)
	(gr_poly
		(pts
			(xy 77.143102 -104.914954) (xy 77.107542 -104.813354) (xy 77.000862 -104.813354) (xy 76.965302 -104.914954)
			(xy 76.965302 -104.965754) (xy 77.143102 -104.965754)
		)
		(stroke
			(width 0)
			(type solid)
		)
		(fill yes)
		(layer "F.Cu")
		(net "M_L_DQ<31>")
	)
	(gr_poly
		(pts
			(xy 77.143102 -104.610154) (xy 77.107542 -104.508554) (xy 77.000862 -104.508554) (xy 76.965302 -104.610154)
			(xy 76.965302 -104.660954) (xy 77.143102 -104.660954)
		)
		(stroke
			(width 0)
			(type solid)
		)
		(fill yes)
		(layer "F.Cu")
		(net "M_L_DQ<30>")
	)
	(gr_poly
		(pts
			(xy 77.143102 -104.305354) (xy 77.107542 -104.203754) (xy 77.000862 -104.203754) (xy 76.965302 -104.305354)
			(xy 76.965302 -104.356154) (xy 77.143102 -104.356154)
		)
		(stroke
			(width 0)
			(type solid)
		)
		(fill yes)
		(layer "F.Cu")
		(net "M_L_DQS_DP<3>")
	)
	(gr_poly
		(pts
			(xy 77.143102 -104.000554) (xy 77.107542 -103.898954) (xy 77.000862 -103.898954) (xy 76.965302 -104.000554)
			(xy 76.965302 -104.051354) (xy 77.143102 -104.051354)
		)
		(stroke
			(width 0)
			(type solid)
		)
		(fill yes)
		(layer "F.Cu")
		(net "M_L_DQS_DN<3>")
	)
	(gr_poly
		(pts
			(xy 77.143102 -103.695754) (xy 77.107542 -103.594154) (xy 77.000862 -103.594154) (xy 76.965302 -103.695754)
			(xy 76.965302 -103.746554) (xy 77.143102 -103.746554)
		)
		(stroke
			(width 0)
			(type solid)
		)
		(fill yes)
		(layer "F.Cu")
		(net "M_L_DQS_DN<12>")
	)
	(gr_poly
		(pts
			(xy 77.186028 -47.43069) (xy 77.186028 -47.37989) (xy 77.008228 -47.37989) (xy 77.008228 -47.43069)
			(xy 77.043788 -47.53229) (xy 77.150468 -47.53229)
		)
		(stroke
			(width 0)
			(type solid)
		)
		(fill yes)
		(layer "F.Cu")
		(net "M_H_DQS_DP<3>")
	)
	(gr_poly
		(pts
			(xy 77.186028 -47.12589) (xy 77.186028 -47.07509) (xy 77.008228 -47.07509) (xy 77.008228 -47.12589)
			(xy 77.043788 -47.22749) (xy 77.150468 -47.22749)
		)
		(stroke
			(width 0)
			(type solid)
		)
		(fill yes)
		(layer "F.Cu")
		(net "M_H_DQ<30>")
	)
	(gr_poly
		(pts
			(xy 77.186028 -46.82109) (xy 77.186028 -46.77029) (xy 77.008228 -46.77029) (xy 77.008228 -46.82109)
			(xy 77.043788 -46.92269) (xy 77.150468 -46.92269)
		)
		(stroke
			(width 0)
			(type solid)
		)
		(fill yes)
		(layer "F.Cu")
		(net "M_H_DQ<31>")
	)
	(gr_poly
		(pts
			(xy 77.186028 -46.51629) (xy 77.186028 -46.46549) (xy 77.008228 -46.46549) (xy 77.008228 -46.51629)
			(xy 77.043788 -46.61789) (xy 77.150468 -46.61789)
		)
		(stroke
			(width 0)
			(type solid)
		)
		(fill yes)
		(layer "F.Cu")
		(net "M_H_DQ<26>")
	)
	(gr_poly
		(pts
			(xy 77.186028 -46.21149) (xy 77.186028 -46.14799) (xy 77.008228 -46.14799) (xy 77.008228 -46.21149)
			(xy 77.043788 -46.31309) (xy 77.150468 -46.31309)
		)
		(stroke
			(width 0)
			(type solid)
		)
		(fill yes)
		(layer "F.Cu")
		(net "M_H_DQ<27>")
	)
	(gr_poly
		(pts
			(xy 77.20584 -107.19181) (xy 77.20584 -107.14101) (xy 77.07884 -107.14101) (xy 77.07884 -107.19181)
			(xy 77.09154 -107.38231) (xy 77.19314 -107.38231)
		)
		(stroke
			(width 0)
			(type solid)
		)
		(fill yes)
		(layer "F.Cu")
		(net "M_L_ECC<0>")
	)
	(gr_poly
		(pts
			(xy 77.20584 -106.798364) (xy 77.20584 -106.747564) (xy 77.07884 -106.747564) (xy 77.07884 -106.798364)
			(xy 77.09154 -106.988864) (xy 77.19314 -106.988864)
		)
		(stroke
			(width 0)
			(type solid)
		)
		(fill yes)
		(layer "F.Cu")
		(net "M_L_ECC<5>")
	)
	(gr_poly
		(pts
			(xy 77.20584 -106.404664) (xy 77.20584 -106.341164) (xy 77.07884 -106.341164) (xy 77.07884 -106.404664)
			(xy 77.09154 -106.595164) (xy 77.19314 -106.595164)
		)
		(stroke
			(width 0)
			(type solid)
		)
		(fill yes)
		(layer "F.Cu")
		(net "M_L_ECC<4>")
	)
	(gr_poly
		(pts
			(xy 77.219556 -49.109376) (xy 77.25537 -49.073308) (xy 77.129894 -48.947832) (xy 77.093826 -48.983646)
			(xy 77.04709 -49.080674) (xy 77.122528 -49.156112)
		)
		(stroke
			(width 0)
			(type solid)
		)
		(fill yes)
		(layer "F.Cu")
		(net "M_H_DQ<25>")
	)
	(gr_poly
		(pts
			(xy 77.228446 -49.405794) (xy 77.275182 -49.308766) (xy 77.199744 -49.233328) (xy 77.102716 -49.280064)
			(xy 77.066902 -49.316132) (xy 77.192632 -49.441862)
		)
		(stroke
			(width 0)
			(type solid)
		)
		(fill yes)
		(layer "F.Cu")
		(net "M_H_DQ<24>")
	)
	(gr_poly
		(pts
			(xy 77.259434 -103.292148) (xy 77.22362 -103.25608) (xy 77.126592 -103.209344) (xy 77.051154 -103.284782)
			(xy 77.09789 -103.38181) (xy 77.133704 -103.417878)
		)
		(stroke
			(width 0)
			(type solid)
		)
		(fill yes)
		(layer "F.Cu")
		(net "M_L_DQS_DP<12>")
	)
	(gr_poly
		(pts
			(xy 77.264768 -48.14824) (xy 77.311504 -48.051212) (xy 77.236066 -47.975774) (xy 77.139038 -48.02251)
			(xy 77.10297 -48.058324) (xy 77.2287 -48.184054)
		)
		(stroke
			(width 0)
			(type solid)
		)
		(fill yes)
		(layer "F.Cu")
		(net "M_H_DQS_DN<12>")
	)
	(gr_poly
		(pts
			(xy 77.279246 -103.05669) (xy 77.23251 -102.959662) (xy 77.196442 -102.923848) (xy 77.070966 -103.049324)
			(xy 77.10678 -103.085392) (xy 77.203808 -103.132128)
		)
		(stroke
			(width 0)
			(type solid)
		)
		(fill yes)
		(layer "F.Cu")
		(net "M_L_DQ<25>")
	)
	(gr_poly
		(pts
			(xy 77.34554 -48.372776) (xy 77.381354 -48.336708) (xy 77.255624 -48.210978) (xy 77.21981 -48.247046)
			(xy 77.173074 -48.344074) (xy 77.248512 -48.419512)
		)
		(stroke
			(width 0)
			(type solid)
		)
		(fill yes)
		(layer "F.Cu")
		(net "M_H_DQS_DN<12>")
	)
	(gr_poly
		(pts
			(xy 77.349096 -102.771194) (xy 77.313282 -102.735126) (xy 77.216254 -102.68839) (xy 77.140816 -102.763828)
			(xy 77.187552 -102.860856) (xy 77.223366 -102.896924)
		)
		(stroke
			(width 0)
			(type solid)
		)
		(fill yes)
		(layer "F.Cu")
		(net "M_L_DQ<25>")
	)
	(gr_poly
		(pts
			(xy 77.349858 -44.689522) (xy 77.385672 -44.653454) (xy 77.29601 -44.563792) (xy 77.259942 -44.599606)
			(xy 77.134212 -44.74337) (xy 77.206094 -44.815252)
		)
		(stroke
			(width 0)
			(type solid)
		)
		(fill yes)
		(layer "F.Cu")
		(net "M_H_ECC<0>")
	)
	(gr_poly
		(pts
			(xy 77.35443 -48.669194) (xy 77.401166 -48.572166) (xy 77.325728 -48.496728) (xy 77.2287 -48.543464)
			(xy 77.192632 -48.579278) (xy 77.318362 -48.705008)
		)
		(stroke
			(width 0)
			(type solid)
		)
		(fill yes)
		(layer "F.Cu")
		(net "M_H_DQS_DP<12>")
	)
	(gr_poly
		(pts
			(xy 77.359002 -105.321354) (xy 77.359002 -105.270554) (xy 77.181202 -105.270554) (xy 77.181202 -105.321354)
			(xy 77.216762 -105.422954) (xy 77.323442 -105.422954)
		)
		(stroke
			(width 0)
			(type solid)
		)
		(fill yes)
		(layer "F.Cu")
		(net "M_L_DQ<26>")
	)
	(gr_poly
		(pts
			(xy 77.359002 -105.016554) (xy 77.359002 -104.965754) (xy 77.181202 -104.965754) (xy 77.181202 -105.016554)
			(xy 77.216762 -105.118154) (xy 77.323442 -105.118154)
		)
		(stroke
			(width 0)
			(type solid)
		)
		(fill yes)
		(layer "F.Cu")
		(net "M_L_DQ<31>")
	)
	(gr_poly
		(pts
			(xy 77.359002 -104.711754) (xy 77.359002 -104.660954) (xy 77.181202 -104.660954) (xy 77.181202 -104.711754)
			(xy 77.216762 -104.813354) (xy 77.323442 -104.813354)
		)
		(stroke
			(width 0)
			(type solid)
		)
		(fill yes)
		(layer "F.Cu")
		(net "M_L_DQ<30>")
	)
	(gr_poly
		(pts
			(xy 77.359002 -104.406954) (xy 77.359002 -104.356154) (xy 77.181202 -104.356154) (xy 77.181202 -104.406954)
			(xy 77.216762 -104.508554) (xy 77.323442 -104.508554)
		)
		(stroke
			(width 0)
			(type solid)
		)
		(fill yes)
		(layer "F.Cu")
		(net "M_L_DQS_DP<3>")
	)
	(gr_poly
		(pts
			(xy 77.359002 -104.102154) (xy 77.359002 -104.051354) (xy 77.181202 -104.051354) (xy 77.181202 -104.102154)
			(xy 77.216762 -104.203754) (xy 77.323442 -104.203754)
		)
		(stroke
			(width 0)
			(type solid)
		)
		(fill yes)
		(layer "F.Cu")
		(net "M_L_DQS_DN<3>")
	)
	(gr_poly
		(pts
			(xy 77.368908 -102.535736) (xy 77.322172 -102.438708) (xy 77.286104 -102.402894) (xy 77.160628 -102.52837)
			(xy 77.196442 -102.564438) (xy 77.29347 -102.611174)
		)
		(stroke
			(width 0)
			(type solid)
		)
		(fill yes)
		(layer "F.Cu")
		(net "M_L_DQ<24>")
	)
	(gr_poly
		(pts
			(xy 77.376782 -45.130212) (xy 77.502512 -44.986448) (xy 77.43063 -44.91482) (xy 77.286866 -45.04055)
			(xy 77.251052 -45.076364) (xy 77.340968 -45.16628)
		)
		(stroke
			(width 0)
			(type solid)
		)
		(fill yes)
		(layer "F.Cu")
		(net "M_H_ECC<5>")
	)
	(gr_poly
		(pts
			(xy 77.401928 -47.02429) (xy 77.366368 -46.92269) (xy 77.259688 -46.92269) (xy 77.224128 -47.02429)
			(xy 77.224128 -47.07509) (xy 77.401928 -47.07509)
		)
		(stroke
			(width 0)
			(type solid)
		)
		(fill yes)
		(layer "F.Cu")
		(net "M_H_DQ<30>")
	)
	(gr_poly
		(pts
			(xy 77.401928 -46.71949) (xy 77.366368 -46.61789) (xy 77.259688 -46.61789) (xy 77.224128 -46.71949)
			(xy 77.224128 -46.77029) (xy 77.401928 -46.77029)
		)
		(stroke
			(width 0)
			(type solid)
		)
		(fill yes)
		(layer "F.Cu")
		(net "M_H_DQ<31>")
	)
	(gr_poly
		(pts
			(xy 77.401928 -46.41469) (xy 77.366368 -46.31309) (xy 77.259688 -46.31309) (xy 77.224128 -46.41469)
			(xy 77.224128 -46.46549) (xy 77.401928 -46.46549)
		)
		(stroke
			(width 0)
			(type solid)
		)
		(fill yes)
		(layer "F.Cu")
		(net "M_H_DQ<26>")
	)
	(gr_poly
		(pts
			(xy 77.40396 -43.571668) (xy 77.39126 -43.381168) (xy 77.28966 -43.381168) (xy 77.27696 -43.571668)
			(xy 77.27696 -43.622468) (xy 77.40396 -43.622468)
		)
		(stroke
			(width 0)
			(type solid)
		)
		(fill yes)
		(layer "F.Cu")
		(net "M_H_DQS_DP<17>")
	)
	(gr_poly
		(pts
			(xy 77.40396 -43.177968) (xy 77.39126 -42.987468) (xy 77.28966 -42.987468) (xy 77.27696 -43.177968)
			(xy 77.27696 -43.228768) (xy 77.40396 -43.228768)
		)
		(stroke
			(width 0)
			(type solid)
		)
		(fill yes)
		(layer "F.Cu")
		(net "M_H_DQS_DN<17>")
	)
	(gr_poly
		(pts
			(xy 77.40396 -42.784268) (xy 77.39126 -42.593768) (xy 77.28966 -42.593768) (xy 77.27696 -42.784268)
			(xy 77.27696 -42.835068) (xy 77.40396 -42.835068)
		)
		(stroke
			(width 0)
			(type solid)
		)
		(fill yes)
		(layer "F.Cu")
		(net "M_H_DQS_DN<8>")
	)
	(gr_poly
		(pts
			(xy 77.40396 -42.390568) (xy 77.39126 -42.200068) (xy 77.28966 -42.200068) (xy 77.27696 -42.390568)
			(xy 77.27696 -42.441368) (xy 77.40396 -42.441368)
		)
		(stroke
			(width 0)
			(type solid)
		)
		(fill yes)
		(layer "F.Cu")
		(net "M_H_DQS_DP<8>")
	)
	(gr_poly
		(pts
			(xy 77.40396 -41.996868) (xy 77.39126 -41.806368) (xy 77.28966 -41.806368) (xy 77.27696 -41.996868)
			(xy 77.27696 -42.047668) (xy 77.40396 -42.047668)
		)
		(stroke
			(width 0)
			(type solid)
		)
		(fill yes)
		(layer "F.Cu")
		(net "M_H_ECC<6>")
	)
	(gr_poly
		(pts
			(xy 77.435202 -48.89373) (xy 77.471016 -48.857662) (xy 77.34554 -48.732186) (xy 77.309472 -48.768)
			(xy 77.262736 -48.865028) (xy 77.338174 -48.940466)
		)
		(stroke
			(width 0)
			(type solid)
		)
		(fill yes)
		(layer "F.Cu")
		(net "M_H_DQS_DP<12>")
	)
	(gr_poly
		(pts
			(xy 77.439012 -102.249986) (xy 77.402944 -102.214172) (xy 77.305916 -102.167436) (xy 77.230478 -102.242874)
			(xy 77.277214 -102.339902) (xy 77.313282 -102.375716)
		)
		(stroke
			(width 0)
			(type solid)
		)
		(fill yes)
		(layer "F.Cu")
		(net "M_L_DQ<24>")
	)
	(gr_poly
		(pts
			(xy 77.444092 -49.190148) (xy 77.490828 -49.09312) (xy 77.41539 -49.017682) (xy 77.318362 -49.064418)
			(xy 77.282548 -49.100486) (xy 77.408278 -49.226216)
		)
		(stroke
			(width 0)
			(type solid)
		)
		(fill yes)
		(layer "F.Cu")
		(net "M_H_DQ<25>")
	)
	(gr_poly
		(pts
			(xy 77.466698 -44.105576) (xy 77.592428 -43.961812) (xy 77.520546 -43.890184) (xy 77.376782 -44.015914)
			(xy 77.340968 -44.051728) (xy 77.430884 -44.141644)
		)
		(stroke
			(width 0)
			(type solid)
		)
		(fill yes)
		(layer "F.Cu")
		(net "M_H_ECC<1>")
	)
	(gr_poly
		(pts
			(xy 77.471524 -47.636176) (xy 77.507338 -47.600108) (xy 77.381608 -47.474378) (xy 77.345794 -47.510446)
			(xy 77.299058 -47.607474) (xy 77.374496 -47.682912)
		)
		(stroke
			(width 0)
			(type solid)
		)
		(fill yes)
		(layer "F.Cu")
		(net "M_H_DQS_DP<3>")
	)
	(gr_poly
		(pts
			(xy 77.47508 -103.507794) (xy 77.439266 -103.471726) (xy 77.342238 -103.42499) (xy 77.2668 -103.500428)
			(xy 77.313536 -103.597456) (xy 77.34935 -103.633524)
		)
		(stroke
			(width 0)
			(type solid)
		)
		(fill yes)
		(layer "F.Cu")
		(net "M_L_DQS_DN<12>")
	)
	(gr_poly
		(pts
			(xy 77.480414 -47.932594) (xy 77.52715 -47.835566) (xy 77.451712 -47.760128) (xy 77.354684 -47.806864)
			(xy 77.318616 -47.842678) (xy 77.444346 -47.968408)
		)
		(stroke
			(width 0)
			(type solid)
		)
		(fill yes)
		(layer "F.Cu")
		(net "M_H_DQS_DN<3>")
	)
	(gr_poly
		(pts
			(xy 77.494892 -103.272336) (xy 77.448156 -103.175308) (xy 77.412088 -103.139494) (xy 77.286358 -103.265224)
			(xy 77.322426 -103.301038) (xy 77.419454 -103.347774)
		)
		(stroke
			(width 0)
			(type solid)
		)
		(fill yes)
		(layer "F.Cu")
		(net "M_L_DQS_DP<12>")
	)
	(gr_poly
		(pts
			(xy 77.524864 -49.414684) (xy 77.560932 -49.37887) (xy 77.435202 -49.25314) (xy 77.399134 -49.288954)
			(xy 77.352398 -49.385982) (xy 77.427836 -49.46142)
		)
		(stroke
			(width 0)
			(type solid)
		)
		(fill yes)
		(layer "F.Cu")
		(net "M_H_DQ<25>")
	)
	(gr_poly
		(pts
			(xy 77.53604 -107.09021) (xy 77.52334 -106.89971) (xy 77.42174 -106.89971) (xy 77.40904 -107.09021)
			(xy 77.40904 -107.14101) (xy 77.53604 -107.14101)
		)
		(stroke
			(width 0)
			(type solid)
		)
		(fill yes)
		(layer "F.Cu")
		(net "M_L_ECC<0>")
	)
	(gr_poly
		(pts
			(xy 77.53604 -106.696764) (xy 77.52334 -106.506264) (xy 77.42174 -106.506264) (xy 77.40904 -106.696764)
			(xy 77.40904 -106.747564) (xy 77.53604 -106.747564)
		)
		(stroke
			(width 0)
			(type solid)
		)
		(fill yes)
		(layer "F.Cu")
		(net "M_L_ECC<5>")
	)
	(gr_poly
		(pts
			(xy 77.561186 -48.15713) (xy 77.597 -48.121062) (xy 77.47127 -47.995332) (xy 77.435456 -48.0314)
			(xy 77.38872 -48.128428) (xy 77.464158 -48.203866)
		)
		(stroke
			(width 0)
			(type solid)
		)
		(fill yes)
		(layer "F.Cu")
		(net "M_H_DQS_DN<3>")
	)
	(gr_poly
		(pts
			(xy 77.564742 -102.98684) (xy 77.528928 -102.950772) (xy 77.4319 -102.904036) (xy 77.356462 -102.979474)
			(xy 77.403198 -103.076502) (xy 77.439012 -103.11257)
		)
		(stroke
			(width 0)
			(type solid)
		)
		(fill yes)
		(layer "F.Cu")
		(net "M_L_DQS_DP<12>")
	)
	(gr_poly
		(pts
			(xy 77.570076 -48.453548) (xy 77.616812 -48.35652) (xy 77.541374 -48.281082) (xy 77.444346 -48.327818)
			(xy 77.408278 -48.363632) (xy 77.534008 -48.489362)
		)
		(stroke
			(width 0)
			(type solid)
		)
		(fill yes)
		(layer "F.Cu")
		(net "M_H_DQS_DN<12>")
	)
	(gr_poly
		(pts
			(xy 77.574902 -105.524554) (xy 77.539342 -105.422954) (xy 77.432662 -105.422954) (xy 77.397102 -105.524554)
			(xy 77.397102 -105.588054) (xy 77.574902 -105.588054)
		)
		(stroke
			(width 0)
			(type solid)
		)
		(fill yes)
		(layer "F.Cu")
		(net "M_L_DQ<27>")
	)
	(gr_poly
		(pts
			(xy 77.574902 -105.219754) (xy 77.539342 -105.118154) (xy 77.432662 -105.118154) (xy 77.397102 -105.219754)
			(xy 77.397102 -105.270554) (xy 77.574902 -105.270554)
		)
		(stroke
			(width 0)
			(type solid)
		)
		(fill yes)
		(layer "F.Cu")
		(net "M_L_DQ<26>")
	)
	(gr_poly
		(pts
			(xy 77.574902 -104.914954) (xy 77.539342 -104.813354) (xy 77.432662 -104.813354) (xy 77.397102 -104.914954)
			(xy 77.397102 -104.965754) (xy 77.574902 -104.965754)
		)
		(stroke
			(width 0)
			(type solid)
		)
		(fill yes)
		(layer "F.Cu")
		(net "M_L_DQ<31>")
	)
	(gr_poly
		(pts
			(xy 77.584554 -102.751382) (xy 77.537818 -102.654354) (xy 77.50175 -102.61854) (xy 77.376274 -102.744016)
			(xy 77.412088 -102.780084) (xy 77.509116 -102.82682)
		)
		(stroke
			(width 0)
			(type solid)
		)
		(fill yes)
		(layer "F.Cu")
		(net "M_L_DQ<25>")
	)
	(gr_poly
		(pts
			(xy 77.606398 -47.195994) (xy 77.653134 -47.098966) (xy 77.577696 -47.023528) (xy 77.480668 -47.070264)
			(xy 77.4446 -47.106078) (xy 77.57033 -47.231808)
		)
		(stroke
			(width 0)
			(type solid)
		)
		(fill yes)
		(layer "F.Cu")
		(net "M_H_DQ<30>")
	)
	(gr_poly
		(pts
			(xy 77.617828 -46.21149) (xy 77.617828 -46.14799) (xy 77.440028 -46.14799) (xy 77.440028 -46.21149)
			(xy 77.475588 -46.31309) (xy 77.582268 -46.31309)
		)
		(stroke
			(width 0)
			(type solid)
		)
		(fill yes)
		(layer "F.Cu")
		(net "M_H_DQ<27>")
	)
	(gr_poly
		(pts
			(xy 77.620876 -104.008936) (xy 77.57414 -103.911908) (xy 77.538072 -103.876094) (xy 77.412342 -104.001824)
			(xy 77.44841 -104.037638) (xy 77.545438 -104.084374)
		)
		(stroke
			(width 0)
			(type solid)
		)
		(fill yes)
		(layer "F.Cu")
		(net "M_L_DQS_DN<3>")
	)
	(gr_poly
		(pts
			(xy 77.628496 -44.410884) (xy 77.66431 -44.374816) (xy 77.574648 -44.285154) (xy 77.53858 -44.320968)
			(xy 77.41285 -44.464732) (xy 77.484732 -44.536614)
		)
		(stroke
			(width 0)
			(type solid)
		)
		(fill yes)
		(layer "F.Cu")
		(net "M_H_ECC<1>")
	)
	(gr_poly
		(pts
			(xy 77.650848 -48.678084) (xy 77.686662 -48.642016) (xy 77.561186 -48.51654) (xy 77.525118 -48.552354)
			(xy 77.478382 -48.649382) (xy 77.55382 -48.72482)
		)
		(stroke
			(width 0)
			(type solid)
		)
		(fill yes)
		(layer "F.Cu")
		(net "M_H_DQS_DN<12>")
	)
	(gr_poly
		(pts
			(xy 77.654658 -102.465632) (xy 77.61859 -102.429818) (xy 77.521562 -102.383082) (xy 77.446124 -102.45852)
			(xy 77.49286 -102.555548) (xy 77.528928 -102.591362)
		)
		(stroke
			(width 0)
			(type solid)
		)
		(fill yes)
		(layer "F.Cu")
		(net "M_L_DQ<25>")
	)
	(gr_poly
		(pts
			(xy 77.65542 -44.851574) (xy 77.78115 -44.70781) (xy 77.709268 -44.636182) (xy 77.565504 -44.761912)
			(xy 77.52969 -44.797726) (xy 77.619606 -44.887642)
		)
		(stroke
			(width 0)
			(type solid)
		)
		(fill yes)
		(layer "F.Cu")
		(net "M_H_ECC<0>")
	)
	(gr_poly
		(pts
			(xy 77.659738 -48.974502) (xy 77.706474 -48.877474) (xy 77.631036 -48.802036) (xy 77.534008 -48.848772)
			(xy 77.498194 -48.88484) (xy 77.623924 -49.01057)
		)
		(stroke
			(width 0)
			(type solid)
		)
		(fill yes)
		(layer "F.Cu")
		(net "M_H_DQS_DP<12>")
	)
	(gr_poly
		(pts
			(xy 77.68717 -47.42053) (xy 77.722984 -47.384462) (xy 77.597254 -47.258732) (xy 77.56144 -47.2948)
			(xy 77.514704 -47.391828) (xy 77.590142 -47.467266)
		)
		(stroke
			(width 0)
			(type solid)
		)
		(fill yes)
		(layer "F.Cu")
		(net "M_H_DQ<30>")
	)
	(gr_poly
		(pts
			(xy 77.690726 -103.72344) (xy 77.654912 -103.687372) (xy 77.557884 -103.640636) (xy 77.482446 -103.716074)
			(xy 77.529182 -103.813102) (xy 77.564996 -103.84917)
		)
		(stroke
			(width 0)
			(type solid)
		)
		(fill yes)
		(layer "F.Cu")
		(net "M_L_DQS_DN<3>")
	)
	(gr_poly
		(pts
			(xy 77.69098 -51.677316) (xy 77.699108 -51.485546) (xy 77.507846 -51.375056) (xy 77.345794 -51.477926)
			(xy 77.323442 -51.516534) (xy 77.668882 -51.715924)
		)
		(stroke
			(width 0)
			(type solid)
		)
		(fill yes)
		(layer "F.Cu")
		(net "M_H_DQ<29>")
	)
	(gr_poly
		(pts
			(xy 77.69606 -47.716948) (xy 77.742796 -47.61992) (xy 77.667358 -47.544482) (xy 77.57033 -47.591218)
			(xy 77.534262 -47.627032) (xy 77.659992 -47.752762)
		)
		(stroke
			(width 0)
			(type solid)
		)
		(fill yes)
		(layer "F.Cu")
		(net "M_H_DQS_DP<3>")
	)
	(gr_poly
		(pts
			(xy 77.70622 -45.514514) (xy 77.67066 -45.412914) (xy 77.56398 -45.412914) (xy 77.52842 -45.514514)
			(xy 77.52842 -45.578014) (xy 77.70622 -45.578014)
		)
		(stroke
			(width 0)
			(type solid)
		)
		(fill yes)
		(layer "F.Cu")
		(net "M_H_ECC<4>")
	)
	(gr_poly
		(pts
			(xy 77.70622 -45.209714) (xy 77.67066 -45.108114) (xy 77.56398 -45.108114) (xy 77.52842 -45.209714)
			(xy 77.52842 -45.260514) (xy 77.70622 -45.260514)
		)
		(stroke
			(width 0)
			(type solid)
		)
		(fill yes)
		(layer "F.Cu")
		(net "M_H_ECC<5>")
	)
	(gr_poly
		(pts
			(xy 77.710538 -103.487982) (xy 77.663802 -103.390954) (xy 77.627734 -103.35514) (xy 77.502004 -103.48087)
			(xy 77.538072 -103.516684) (xy 77.6351 -103.56342)
		)
		(stroke
			(width 0)
			(type solid)
		)
		(fill yes)
		(layer "F.Cu")
		(net "M_L_DQS_DN<12>")
	)
	(gr_poly
		(pts
			(xy 77.718666 -43.386756) (xy 77.75448 -43.350688) (xy 77.664818 -43.261026) (xy 77.62875 -43.29684)
			(xy 77.50302 -43.440604) (xy 77.574902 -43.512486)
		)
		(stroke
			(width 0)
			(type solid)
		)
		(fill yes)
		(layer "F.Cu")
		(net "M_H_DQS_DN<17>")
	)
	(gr_poly
		(pts
			(xy 77.73416 -42.885868) (xy 77.73416 -42.835068) (xy 77.60716 -42.835068) (xy 77.60716 -42.885868)
			(xy 77.61986 -43.076368) (xy 77.72146 -43.076368)
		)
		(stroke
			(width 0)
			(type solid)
		)
		(fill yes)
		(layer "F.Cu")
		(net "M_H_DQS_DN<8>")
	)
	(gr_poly
		(pts
			(xy 77.73416 -42.492168) (xy 77.73416 -42.441368) (xy 77.60716 -42.441368) (xy 77.60716 -42.492168)
			(xy 77.61986 -42.682668) (xy 77.72146 -42.682668)
		)
		(stroke
			(width 0)
			(type solid)
		)
		(fill yes)
		(layer "F.Cu")
		(net "M_H_DQS_DP<8>")
	)
	(gr_poly
		(pts
			(xy 77.73416 -42.098468) (xy 77.73416 -42.047668) (xy 77.60716 -42.047668) (xy 77.60716 -42.098468)
			(xy 77.61986 -42.288968) (xy 77.72146 -42.288968)
		)
		(stroke
			(width 0)
			(type solid)
		)
		(fill yes)
		(layer "F.Cu")
		(net "M_H_ECC<6>")
	)
	(gr_poly
		(pts
			(xy 77.73416 -41.704768) (xy 77.73416 -41.653968) (xy 77.60716 -41.653968) (xy 77.60716 -41.704768)
			(xy 77.61986 -41.895268) (xy 77.72146 -41.895268)
		)
		(stroke
			(width 0)
			(type solid)
		)
		(fill yes)
		(layer "F.Cu")
		(net "M_H_ECC<7>")
	)
	(gr_poly
		(pts
			(xy 77.74051 -49.199038) (xy 77.776578 -49.163224) (xy 77.650848 -49.037494) (xy 77.61478 -49.073308)
			(xy 77.568044 -49.170336) (xy 77.643482 -49.245774)
		)
		(stroke
			(width 0)
			(type solid)
		)
		(fill yes)
		(layer "F.Cu")
		(net "M_H_DQS_DP<12>")
	)
	(gr_poly
		(pts
			(xy 77.745336 -43.826938) (xy 77.871066 -43.683174) (xy 77.799184 -43.611546) (xy 77.65542 -43.737276)
			(xy 77.619606 -43.77309) (xy 77.709522 -43.863006)
		)
		(stroke
			(width 0)
			(type solid)
		)
		(fill yes)
		(layer "F.Cu")
		(net "M_H_DQS_DP<17>")
	)
	(gr_poly
		(pts
			(xy 77.7494 -49.495456) (xy 77.796136 -49.398428) (xy 77.720698 -49.32299) (xy 77.62367 -49.369726)
			(xy 77.587856 -49.405794) (xy 77.713586 -49.531524)
		)
		(stroke
			(width 0)
			(type solid)
		)
		(fill yes)
		(layer "F.Cu")
		(net "M_H_DQ<25>")
	)
	(gr_poly
		(pts
			(xy 77.776832 -47.941484) (xy 77.812646 -47.905416) (xy 77.686916 -47.779686) (xy 77.651102 -47.815754)
			(xy 77.604366 -47.912782) (xy 77.679804 -47.98822)
		)
		(stroke
			(width 0)
			(type solid)
		)
		(fill yes)
		(layer "F.Cu")
		(net "M_H_DQS_DP<3>")
	)
	(gr_poly
		(pts
			(xy 77.780388 -103.202486) (xy 77.744574 -103.166418) (xy 77.647546 -103.119682) (xy 77.572108 -103.19512)
			(xy 77.618844 -103.292148) (xy 77.654658 -103.328216)
		)
		(stroke
			(width 0)
			(type solid)
		)
		(fill yes)
		(layer "F.Cu")
		(net "M_L_DQS_DN<12>")
	)
	(gr_poly
		(pts
			(xy 77.785722 -48.237902) (xy 77.832458 -48.140874) (xy 77.75702 -48.065436) (xy 77.659992 -48.112172)
			(xy 77.623924 -48.147986) (xy 77.749654 -48.273716)
		)
		(stroke
			(width 0)
			(type solid)
		)
		(fill yes)
		(layer "F.Cu")
		(net "M_H_DQS_DN<3>")
	)
	(gr_poly
		(pts
			(xy 77.790802 -105.321354) (xy 77.790802 -105.270554) (xy 77.613002 -105.270554) (xy 77.613002 -105.321354)
			(xy 77.648562 -105.422954) (xy 77.755242 -105.422954)
		)
		(stroke
			(width 0)
			(type solid)
		)
		(fill yes)
		(layer "F.Cu")
		(net "M_L_DQ<26>")
	)
	(gr_poly
		(pts
			(xy 77.8002 -102.967028) (xy 77.753464 -102.87) (xy 77.717396 -102.834186) (xy 77.59192 -102.959662)
			(xy 77.627734 -102.99573) (xy 77.724762 -103.042466)
		)
		(stroke
			(width 0)
			(type solid)
		)
		(fill yes)
		(layer "F.Cu")
		(net "M_L_DQS_DP<12>")
	)
	(gr_poly
		(pts
			(xy 77.813154 -46.68393) (xy 77.848968 -46.647862) (xy 77.723238 -46.522132) (xy 77.687424 -46.5582)
			(xy 77.640688 -46.655228) (xy 77.716126 -46.730666)
		)
		(stroke
			(width 0)
			(type solid)
		)
		(fill yes)
		(layer "F.Cu")
		(net "M_H_DQ<26>")
	)
	(gr_poly
		(pts
			(xy 77.81671 -104.46004) (xy 77.780896 -104.423972) (xy 77.683868 -104.377236) (xy 77.60843 -104.452674)
			(xy 77.655166 -104.549702) (xy 77.69098 -104.58577)
		)
		(stroke
			(width 0)
			(type solid)
		)
		(fill yes)
		(layer "F.Cu")
		(net "M_L_DQ<30>")
	)
	(gr_poly
		(pts
			(xy 77.822044 -46.980348) (xy 77.86878 -46.88332) (xy 77.793342 -46.807882) (xy 77.696314 -46.854618)
			(xy 77.660246 -46.890432) (xy 77.785976 -47.016162)
		)
		(stroke
			(width 0)
			(type solid)
		)
		(fill yes)
		(layer "F.Cu")
		(net "M_H_DQ<31>")
	)
	(gr_poly
		(pts
			(xy 77.830172 -49.719992) (xy 77.86624 -49.684178) (xy 77.74051 -49.558448) (xy 77.704442 -49.594262)
			(xy 77.657706 -49.69129) (xy 77.733144 -49.766728)
		)
		(stroke
			(width 0)
			(type solid)
		)
		(fill yes)
		(layer "F.Cu")
		(net "M_H_DQ<25>")
	)
	(gr_poly
		(pts
			(xy 77.836522 -104.224582) (xy 77.789786 -104.127554) (xy 77.753718 -104.09174) (xy 77.627988 -104.21747)
			(xy 77.664056 -104.253284) (xy 77.761084 -104.30002)
		)
		(stroke
			(width 0)
			(type solid)
		)
		(fill yes)
		(layer "F.Cu")
		(net "M_L_DQS_DP<3>")
	)
	(gr_poly
		(pts
			(xy 77.86624 -107.585256) (xy 77.86624 -107.534456) (xy 77.73924 -107.534456) (xy 77.73924 -107.585256)
			(xy 77.75194 -107.775756) (xy 77.85354 -107.775756)
		)
		(stroke
			(width 0)
			(type solid)
		)
		(fill yes)
		(layer "F.Cu")
		(net "M_L_ECC<1>")
	)
	(gr_poly
		(pts
			(xy 77.86624 -107.19181) (xy 77.86624 -107.14101) (xy 77.73924 -107.14101) (xy 77.73924 -107.19181)
			(xy 77.75194 -107.38231) (xy 77.85354 -107.38231)
		)
		(stroke
			(width 0)
			(type solid)
		)
		(fill yes)
		(layer "F.Cu")
		(net "M_L_ECC<0>")
	)
	(gr_poly
		(pts
			(xy 77.86624 -106.798364) (xy 77.86624 -106.747564) (xy 77.73924 -106.747564) (xy 77.73924 -106.798364)
			(xy 77.75194 -106.988864) (xy 77.85354 -106.988864)
		)
		(stroke
			(width 0)
			(type solid)
		)
		(fill yes)
		(layer "F.Cu")
		(net "M_L_ECC<5>")
	)
	(gr_poly
		(pts
			(xy 77.86624 -106.404664) (xy 77.86624 -106.341164) (xy 77.73924 -106.341164) (xy 77.73924 -106.404664)
			(xy 77.75194 -106.595164) (xy 77.85354 -106.595164)
		)
		(stroke
			(width 0)
			(type solid)
		)
		(fill yes)
		(layer "F.Cu")
		(net "M_L_ECC<4>")
	)
	(gr_poly
		(pts
			(xy 77.866494 -48.462438) (xy 77.902308 -48.42637) (xy 77.776832 -48.300894) (xy 77.740764 -48.336708)
			(xy 77.694028 -48.433736) (xy 77.769466 -48.509174)
		)
		(stroke
			(width 0)
			(type solid)
		)
		(fill yes)
		(layer "F.Cu")
		(net "M_H_DQS_DN<3>")
	)
	(gr_poly
		(pts
			(xy 77.870304 -102.681278) (xy 77.834236 -102.645464) (xy 77.737208 -102.598728) (xy 77.66177 -102.674166)
			(xy 77.708506 -102.771194) (xy 77.744574 -102.807008)
		)
		(stroke
			(width 0)
			(type solid)
		)
		(fill yes)
		(layer "F.Cu")
		(net "M_L_DQS_DP<12>")
	)
	(gr_poly
		(pts
			(xy 77.875384 -48.758856) (xy 77.92212 -48.661828) (xy 77.846682 -48.58639) (xy 77.749654 -48.633126)
			(xy 77.71384 -48.669194) (xy 77.83957 -48.794924)
		)
		(stroke
			(width 0)
			(type solid)
		)
		(fill yes)
		(layer "F.Cu")
		(net "M_H_DQS_DN<12>")
	)
	(gr_poly
		(pts
			(xy 77.889862 -102.446074) (xy 77.843126 -102.349046) (xy 77.807312 -102.312978) (xy 77.681582 -102.438708)
			(xy 77.717396 -102.474776) (xy 77.814424 -102.521512)
		)
		(stroke
			(width 0)
			(type solid)
		)
		(fill yes)
		(layer "F.Cu")
		(net "M_L_DQ<25>")
	)
	(gr_poly
		(pts
			(xy 77.902816 -47.204884) (xy 77.93863 -47.168816) (xy 77.8129 -47.043086) (xy 77.777086 -47.079154)
			(xy 77.73035 -47.176182) (xy 77.805788 -47.25162)
		)
		(stroke
			(width 0)
			(type solid)
		)
		(fill yes)
		(layer "F.Cu")
		(net "M_H_DQ<31>")
	)
	(gr_poly
		(pts
			(xy 77.906372 -103.939086) (xy 77.870558 -103.903018) (xy 77.77353 -103.856282) (xy 77.698092 -103.93172)
			(xy 77.744828 -104.028748) (xy 77.780642 -104.064816)
		)
		(stroke
			(width 0)
			(type solid)
		)
		(fill yes)
		(layer "F.Cu")
		(net "M_L_DQS_DP<3>")
	)
	(gr_poly
		(pts
			(xy 77.907134 -44.132246) (xy 77.942948 -44.096178) (xy 77.853286 -44.006516) (xy 77.817218 -44.04233)
			(xy 77.691488 -44.186094) (xy 77.76337 -44.257976)
		)
		(stroke
			(width 0)
			(type solid)
		)
		(fill yes)
		(layer "F.Cu")
		(net "M_H_DQS_DP<17>")
	)
	(gr_poly
		(pts
			(xy 77.911706 -47.501302) (xy 77.958442 -47.404274) (xy 77.883004 -47.328836) (xy 77.785976 -47.375572)
			(xy 77.749908 -47.411386) (xy 77.875638 -47.537116)
		)
		(stroke
			(width 0)
			(type solid)
		)
		(fill yes)
		(layer "F.Cu")
		(net "M_H_DQ<30>")
	)
	(gr_poly
		(pts
			(xy 77.92212 -45.311314) (xy 77.92212 -45.260514) (xy 77.74432 -45.260514) (xy 77.74432 -45.311314)
			(xy 77.77988 -45.412914) (xy 77.88656 -45.412914)
		)
		(stroke
			(width 0)
			(type solid)
		)
		(fill yes)
		(layer "F.Cu")
		(net "M_H_ECC<5>")
	)
	(gr_poly
		(pts
			(xy 77.92212 -45.006514) (xy 77.92212 -44.955714) (xy 77.74432 -44.955714) (xy 77.74432 -45.006514)
			(xy 77.77988 -45.108114) (xy 77.88656 -45.108114)
		)
		(stroke
			(width 0)
			(type solid)
		)
		(fill yes)
		(layer "F.Cu")
		(net "M_H_ECC<0>")
	)
	(gr_poly
		(pts
			(xy 77.926184 -103.703628) (xy 77.879448 -103.6066) (xy 77.84338 -103.570786) (xy 77.71765 -103.696516)
			(xy 77.753718 -103.73233) (xy 77.850746 -103.779066)
		)
		(stroke
			(width 0)
			(type solid)
		)
		(fill yes)
		(layer "F.Cu")
		(net "M_L_DQS_DN<3>")
	)
	(gr_poly
		(pts
			(xy 77.934058 -44.572936) (xy 78.059788 -44.429172) (xy 77.987906 -44.357544) (xy 77.844142 -44.483274)
			(xy 77.808328 -44.519088) (xy 77.898244 -44.609004)
		)
		(stroke
			(width 0)
			(type solid)
		)
		(fill yes)
		(layer "F.Cu")
		(net "M_H_ECC<1>")
	)
	(gr_poly
		(pts
			(xy 77.956156 -48.983392) (xy 77.992224 -48.947578) (xy 77.866494 -48.821848) (xy 77.830426 -48.857662)
			(xy 77.78369 -48.95469) (xy 77.859128 -49.030128)
		)
		(stroke
			(width 0)
			(type solid)
		)
		(fill yes)
		(layer "F.Cu")
		(net "M_H_DQS_DN<12>")
	)
	(gr_poly
		(pts
			(xy 77.962506 -104.961182) (xy 77.91577 -104.864154) (xy 77.879702 -104.82834) (xy 77.753972 -104.95407)
			(xy 77.79004 -104.989884) (xy 77.887068 -105.03662)
		)
		(stroke
			(width 0)
			(type solid)
		)
		(fill yes)
		(layer "F.Cu")
		(net "M_L_DQ<31>")
	)
	(gr_poly
		(pts
			(xy 77.965046 -49.27981) (xy 78.011782 -49.182782) (xy 77.936344 -49.107344) (xy 77.839316 -49.15408)
			(xy 77.803502 -49.190148) (xy 77.929232 -49.315878)
		)
		(stroke
			(width 0)
			(type solid)
		)
		(fill yes)
		(layer "F.Cu")
		(net "M_H_DQS_DP<12>")
	)
	(gr_poly
		(pts
			(xy 77.992478 -47.725838) (xy 78.028292 -47.68977) (xy 77.902562 -47.56404) (xy 77.866748 -47.600108)
			(xy 77.820012 -47.697136) (xy 77.89545 -47.772574)
		)
		(stroke
			(width 0)
			(type solid)
		)
		(fill yes)
		(layer "F.Cu")
		(net "M_H_DQ<30>")
	)
	(gr_poly
		(pts
			(xy 77.996034 -103.418132) (xy 77.96022 -103.382064) (xy 77.863192 -103.335328) (xy 77.787754 -103.410766)
			(xy 77.83449 -103.507794) (xy 77.870304 -103.543862)
		)
		(stroke
			(width 0)
			(type solid)
		)
		(fill yes)
		(layer "F.Cu")
		(net "M_L_DQS_DN<3>")
	)
	(gr_poly
		(pts
			(xy 77.99705 -43.108372) (xy 78.032864 -43.072304) (xy 77.943202 -42.982642) (xy 77.907134 -43.018456)
			(xy 77.781404 -43.16222) (xy 77.853286 -43.234102)
		)
		(stroke
			(width 0)
			(type solid)
		)
		(fill yes)
		(layer "F.Cu")
		(net "M_H_DQS_DN<8>")
	)
	(gr_poly
		(pts
			(xy 78.001368 -48.022256) (xy 78.048104 -47.925228) (xy 77.972666 -47.84979) (xy 77.875638 -47.896526)
			(xy 77.83957 -47.93234) (xy 77.9653 -48.05807)
		)
		(stroke
			(width 0)
			(type solid)
		)
		(fill yes)
		(layer "F.Cu")
		(net "M_H_DQS_DP<3>")
	)
	(gr_poly
		(pts
			(xy 78.015846 -103.182674) (xy 77.96911 -103.085646) (xy 77.933042 -103.049832) (xy 77.807566 -103.175308)
			(xy 77.84338 -103.211376) (xy 77.940408 -103.258112)
		)
		(stroke
			(width 0)
			(type solid)
		)
		(fill yes)
		(layer "F.Cu")
		(net "M_L_DQS_DN<12>")
	)
	(gr_poly
		(pts
			(xy 78.023974 -43.5483) (xy 78.149704 -43.404536) (xy 78.077822 -43.332908) (xy 77.934058 -43.458638)
			(xy 77.898244 -43.494452) (xy 77.98816 -43.584368)
		)
		(stroke
			(width 0)
			(type solid)
		)
		(fill yes)
		(layer "F.Cu")
		(net "M_H_DQS_DN<17>")
	)
	(gr_poly
		(pts
			(xy 78.028546 -46.468284) (xy 78.073504 -46.423326) (xy 77.947774 -46.297596) (xy 77.902816 -46.342554)
			(xy 77.856334 -46.439582) (xy 77.931772 -46.51502)
		)
		(stroke
			(width 0)
			(type solid)
		)
		(fill yes)
		(layer "F.Cu")
		(net "M_H_DQ<27>")
	)
	(gr_poly
		(pts
			(xy 78.032356 -104.675686) (xy 77.996542 -104.639618) (xy 77.899514 -104.592882) (xy 77.824076 -104.66832)
			(xy 77.870812 -104.765348) (xy 77.906626 -104.801416)
		)
		(stroke
			(width 0)
			(type solid)
		)
		(fill yes)
		(layer "F.Cu")
		(net "M_L_DQ<31>")
	)
	(gr_poly
		(pts
			(xy 78.03769 -46.764702) (xy 78.084426 -46.667674) (xy 78.008988 -46.592236) (xy 77.91196 -46.638972)
			(xy 77.875892 -46.674786) (xy 78.001622 -46.800516)
		)
		(stroke
			(width 0)
			(type solid)
		)
		(fill yes)
		(layer "F.Cu")
		(net "M_H_DQ<26>")
	)
	(gr_poly
		(pts
			(xy 78.052168 -104.440228) (xy 78.005432 -104.3432) (xy 77.969364 -104.307386) (xy 77.843634 -104.433116)
			(xy 77.879702 -104.46893) (xy 77.97673 -104.515666)
		)
		(stroke
			(width 0)
			(type solid)
		)
		(fill yes)
		(layer "F.Cu")
		(net "M_L_DQ<30>")
	)
	(gr_poly
		(pts
			(xy 78.05674 -41.996868) (xy 78.04404 -41.806368) (xy 77.94244 -41.806368) (xy 77.92974 -41.996868)
			(xy 77.92974 -42.047668) (xy 78.05674 -42.047668)
		)
		(stroke
			(width 0)
			(type solid)
		)
		(fill yes)
		(layer "F.Cu")
		(net "M_H_ECC<6>")
	)
	(gr_poly
		(pts
			(xy 78.06436 -41.603168) (xy 78.05166 -41.412668) (xy 77.95006 -41.412668) (xy 77.93736 -41.603168)
			(xy 77.93736 -41.653968) (xy 78.06436 -41.653968)
		)
		(stroke
			(width 0)
			(type solid)
		)
		(fill yes)
		(layer "F.Cu")
		(net "M_H_ECC<7>")
	)
	(gr_poly
		(pts
			(xy 78.08214 -48.246792) (xy 78.117954 -48.210724) (xy 77.992478 -48.085248) (xy 77.95641 -48.121062)
			(xy 77.909674 -48.21809) (xy 77.985112 -48.293528)
		)
		(stroke
			(width 0)
			(type solid)
		)
		(fill yes)
		(layer "F.Cu")
		(net "M_H_DQS_DP<3>")
	)
	(gr_poly
		(pts
			(xy 78.08595 -102.896924) (xy 78.049882 -102.86111) (xy 77.952854 -102.814374) (xy 77.877416 -102.889812)
			(xy 77.924152 -102.98684) (xy 77.96022 -103.022654)
		)
		(stroke
			(width 0)
			(type solid)
		)
		(fill yes)
		(layer "F.Cu")
		(net "M_L_DQS_DN<12>")
	)
	(gr_poly
		(pts
			(xy 78.09103 -48.54321) (xy 78.137766 -48.446182) (xy 78.062328 -48.370744) (xy 77.9653 -48.41748)
			(xy 77.929486 -48.453548) (xy 78.055216 -48.579278)
		)
		(stroke
			(width 0)
			(type solid)
		)
		(fill yes)
		(layer "F.Cu")
		(net "M_H_DQS_DN<3>")
	)
	(gr_poly
		(pts
			(xy 78.105508 -102.66172) (xy 78.058772 -102.564692) (xy 78.022958 -102.528624) (xy 77.897228 -102.654354)
			(xy 77.933042 -102.690422) (xy 78.03007 -102.737158)
		)
		(stroke
			(width 0)
			(type solid)
		)
		(fill yes)
		(layer "F.Cu")
		(net "M_L_DQS_DP<12>")
	)
	(gr_poly
		(pts
			(xy 78.113382 -42.524172) (xy 78.239112 -42.380408) (xy 78.167484 -42.308526) (xy 78.02372 -42.434256)
			(xy 77.987652 -42.47007) (xy 78.077568 -42.559986)
		)
		(stroke
			(width 0)
			(type solid)
		)
		(fill yes)
		(layer "F.Cu")
		(net "M_H_DQS_DP<8>")
	)
	(gr_poly
		(pts
			(xy 78.118462 -46.989238) (xy 78.154276 -46.95317) (xy 78.028546 -46.82744) (xy 77.992732 -46.863508)
			(xy 77.945996 -46.960536) (xy 78.021434 -47.035974)
		)
		(stroke
			(width 0)
			(type solid)
		)
		(fill yes)
		(layer "F.Cu")
		(net "M_H_DQ<26>")
	)
	(gr_poly
		(pts
			(xy 78.122018 -104.154732) (xy 78.086204 -104.118664) (xy 77.989176 -104.071928) (xy 77.913738 -104.147366)
			(xy 77.960474 -104.244394) (xy 77.996288 -104.280462)
		)
		(stroke
			(width 0)
			(type solid)
		)
		(fill yes)
		(layer "F.Cu")
		(net "M_L_DQ<30>")
	)
	(gr_poly
		(pts
			(xy 78.127352 -47.285656) (xy 78.174088 -47.188628) (xy 78.09865 -47.11319) (xy 78.001622 -47.159926)
			(xy 77.965554 -47.19574) (xy 78.091284 -47.32147)
		)
		(stroke
			(width 0)
			(type solid)
		)
		(fill yes)
		(layer "F.Cu")
		(net "M_H_DQ<31>")
	)
	(gr_poly
		(pts
			(xy 78.13802 -45.514514) (xy 78.10246 -45.412914) (xy 77.99578 -45.412914) (xy 77.96022 -45.514514)
			(xy 77.96022 -45.578014) (xy 78.13802 -45.578014)
		)
		(stroke
			(width 0)
			(type solid)
		)
		(fill yes)
		(layer "F.Cu")
		(net "M_H_ECC<4>")
	)
	(gr_poly
		(pts
			(xy 78.13802 -45.209714) (xy 78.10246 -45.108114) (xy 77.99578 -45.108114) (xy 77.96022 -45.209714)
			(xy 77.96022 -45.260514) (xy 78.13802 -45.260514)
		)
		(stroke
			(width 0)
			(type solid)
		)
		(fill yes)
		(layer "F.Cu")
		(net "M_H_ECC<5>")
	)
	(gr_poly
		(pts
			(xy 78.13802 -44.904914) (xy 78.10246 -44.803314) (xy 77.99578 -44.803314) (xy 77.96022 -44.904914)
			(xy 77.96022 -44.955714) (xy 78.13802 -44.955714)
		)
		(stroke
			(width 0)
			(type solid)
		)
		(fill yes)
		(layer "F.Cu")
		(net "M_H_ECC<0>")
	)
	(gr_poly
		(pts
			(xy 78.14183 -103.919274) (xy 78.095094 -103.822246) (xy 78.059026 -103.786432) (xy 77.933296 -103.912162)
			(xy 77.969364 -103.947976) (xy 78.066392 -103.994712)
		)
		(stroke
			(width 0)
			(type solid)
		)
		(fill yes)
		(layer "F.Cu")
		(net "M_L_DQS_DP<3>")
	)
	(gr_poly
		(pts
			(xy 78.16723 -105.421176) (xy 78.122526 -105.376218) (xy 78.025498 -105.329482) (xy 77.95006 -105.40492)
			(xy 77.996796 -105.501948) (xy 78.0415 -105.546906)
		)
		(stroke
			(width 0)
			(type solid)
		)
		(fill yes)
		(layer "F.Cu")
		(net "M_L_DQ<27>")
	)
	(gr_poly
		(pts
			(xy 78.171802 -48.767746) (xy 78.20787 -48.731932) (xy 78.08214 -48.606202) (xy 78.046072 -48.642016)
			(xy 77.999336 -48.739044) (xy 78.074774 -48.814482)
		)
		(stroke
			(width 0)
			(type solid)
		)
		(fill yes)
		(layer "F.Cu")
		(net "M_H_DQS_DN<3>")
	)
	(gr_poly
		(pts
			(xy 78.178152 -105.176828) (xy 78.131416 -105.0798) (xy 78.095348 -105.043986) (xy 77.969618 -105.169716)
			(xy 78.005686 -105.20553) (xy 78.102714 -105.252266)
		)
		(stroke
			(width 0)
			(type solid)
		)
		(fill yes)
		(layer "F.Cu")
		(net "M_L_DQ<26>")
	)
	(gr_poly
		(pts
			(xy 78.180692 -49.064164) (xy 78.227428 -48.967136) (xy 78.15199 -48.891698) (xy 78.054962 -48.938434)
			(xy 78.019148 -48.974502) (xy 78.144878 -49.100232)
		)
		(stroke
			(width 0)
			(type solid)
		)
		(fill yes)
		(layer "F.Cu")
		(net "M_H_DQS_DN<12>")
	)
	(gr_poly
		(pts
			(xy 78.185518 -43.853608) (xy 78.221586 -43.817794) (xy 78.13167 -43.727878) (xy 78.095856 -43.763946)
			(xy 77.970126 -43.907456) (xy 78.042008 -43.979338)
		)
		(stroke
			(width 0)
			(type solid)
		)
		(fill yes)
		(layer "F.Cu")
		(net "M_H_DQS_DN<17>")
	)
	(gr_poly
		(pts
			(xy 78.19644 -107.483656) (xy 78.18374 -107.293156) (xy 78.08214 -107.293156) (xy 78.06944 -107.483656)
			(xy 78.06944 -107.534456) (xy 78.19644 -107.534456)
		)
		(stroke
			(width 0)
			(type solid)
		)
		(fill yes)
		(layer "F.Cu")
		(net "M_L_ECC<1>")
	)
	(gr_poly
		(pts
			(xy 78.19644 -107.09021) (xy 78.18374 -106.89971) (xy 78.08214 -106.89971) (xy 78.06944 -107.09021)
			(xy 78.06944 -107.14101) (xy 78.19644 -107.14101)
		)
		(stroke
			(width 0)
			(type solid)
		)
		(fill yes)
		(layer "F.Cu")
		(net "M_L_ECC<0>")
	)
	(gr_poly
		(pts
			(xy 78.19644 -106.696764) (xy 78.18374 -106.506264) (xy 78.08214 -106.506264) (xy 78.06944 -106.696764)
			(xy 78.06944 -106.747564) (xy 78.19644 -106.747564)
		)
		(stroke
			(width 0)
			(type solid)
		)
		(fill yes)
		(layer "F.Cu")
		(net "M_L_ECC<5>")
	)
	(gr_poly
		(pts
			(xy 78.208124 -47.510192) (xy 78.243938 -47.474124) (xy 78.118208 -47.348394) (xy 78.082394 -47.384462)
			(xy 78.035658 -47.48149) (xy 78.111096 -47.556928)
		)
		(stroke
			(width 0)
			(type solid)
		)
		(fill yes)
		(layer "F.Cu")
		(net "M_H_DQ<31>")
	)
	(gr_poly
		(pts
			(xy 78.21168 -103.633778) (xy 78.175866 -103.59771) (xy 78.078838 -103.550974) (xy 78.0034 -103.626412)
			(xy 78.050136 -103.72344) (xy 78.08595 -103.759508)
		)
		(stroke
			(width 0)
			(type solid)
		)
		(fill yes)
		(layer "F.Cu")
		(net "M_L_DQS_DP<3>")
	)
	(gr_poly
		(pts
			(xy 78.217014 -47.80661) (xy 78.26375 -47.709582) (xy 78.188312 -47.634144) (xy 78.091284 -47.68088)
			(xy 78.055216 -47.716694) (xy 78.180946 -47.842424)
		)
		(stroke
			(width 0)
			(type solid)
		)
		(fill yes)
		(layer "F.Cu")
		(net "M_H_DQ<30>")
	)
	(gr_poly
		(pts
			(xy 78.231492 -103.39832) (xy 78.184756 -103.301292) (xy 78.148688 -103.265478) (xy 78.023212 -103.390954)
			(xy 78.059026 -103.427022) (xy 78.156054 -103.473758)
		)
		(stroke
			(width 0)
			(type solid)
		)
		(fill yes)
		(layer "F.Cu")
		(net "M_L_DQS_DN<3>")
	)
	(gr_poly
		(pts
			(xy 78.248002 -104.891332) (xy 78.212188 -104.855264) (xy 78.11516 -104.808528) (xy 78.039722 -104.883966)
			(xy 78.086458 -104.980994) (xy 78.122272 -105.017062)
		)
		(stroke
			(width 0)
			(type solid)
		)
		(fill yes)
		(layer "F.Cu")
		(net "M_L_DQ<26>")
	)
	(gr_poly
		(pts
			(xy 78.267814 -104.655874) (xy 78.221078 -104.558846) (xy 78.18501 -104.523032) (xy 78.05928 -104.648762)
			(xy 78.095348 -104.684576) (xy 78.192376 -104.731312)
		)
		(stroke
			(width 0)
			(type solid)
		)
		(fill yes)
		(layer "F.Cu")
		(net "M_L_DQ<31>")
	)
	(gr_poly
		(pts
			(xy 78.275434 -42.829734) (xy 78.311502 -42.79392) (xy 78.221586 -42.704004) (xy 78.185772 -42.740072)
			(xy 78.060042 -42.883582) (xy 78.131924 -42.955464)
		)
		(stroke
			(width 0)
			(type solid)
		)
		(fill yes)
		(layer "F.Cu")
		(net "M_H_DQS_DP<8>")
	)
	(gr_poly
		(pts
			(xy 78.297786 -48.031146) (xy 78.3336 -47.995078) (xy 78.208124 -47.869602) (xy 78.172056 -47.905416)
			(xy 78.12532 -48.002444) (xy 78.200758 -48.077882)
		)
		(stroke
			(width 0)
			(type solid)
		)
		(fill yes)
		(layer "F.Cu")
		(net "M_H_DQ<30>")
	)
	(gr_poly
		(pts
			(xy 78.301596 -103.11257) (xy 78.265528 -103.076756) (xy 78.1685 -103.03002) (xy 78.093062 -103.105458)
			(xy 78.139798 -103.202486) (xy 78.175866 -103.2383)
		)
		(stroke
			(width 0)
			(type solid)
		)
		(fill yes)
		(layer "F.Cu")
		(net "M_L_DQS_DN<3>")
	)
	(gr_poly
		(pts
			(xy 78.302358 -43.269916) (xy 78.428088 -43.126152) (xy 78.356206 -43.054524) (xy 78.212442 -43.180254)
			(xy 78.176628 -43.216068) (xy 78.266544 -43.305984)
		)
		(stroke
			(width 0)
			(type solid)
		)
		(fill yes)
		(layer "F.Cu")
		(net "M_H_DQS_DN<8>")
	)
	(gr_poly
		(pts
			(xy 78.306676 -48.327564) (xy 78.353412 -48.230536) (xy 78.277974 -48.155098) (xy 78.180946 -48.201834)
			(xy 78.145132 -48.237902) (xy 78.270862 -48.363632)
		)
		(stroke
			(width 0)
			(type solid)
		)
		(fill yes)
		(layer "F.Cu")
		(net "M_H_DQS_DP<3>")
	)
	(gr_poly
		(pts
			(xy 78.321154 -102.877366) (xy 78.274418 -102.780338) (xy 78.238604 -102.74427) (xy 78.112874 -102.87)
			(xy 78.148688 -102.906068) (xy 78.245716 -102.952804)
		)
		(stroke
			(width 0)
			(type solid)
		)
		(fill yes)
		(layer "F.Cu")
		(net "M_L_DQS_DN<12>")
	)
	(gr_poly
		(pts
			(xy 78.334108 -46.773592) (xy 78.378812 -46.728634) (xy 78.253082 -46.602904) (xy 78.208378 -46.647862)
			(xy 78.161642 -46.74489) (xy 78.23708 -46.820328)
		)
		(stroke
			(width 0)
			(type solid)
		)
		(fill yes)
		(layer "F.Cu")
		(net "M_H_DQ<27>")
	)
	(gr_poly
		(pts
			(xy 78.337664 -104.370378) (xy 78.30185 -104.33431) (xy 78.204822 -104.287574) (xy 78.129384 -104.363012)
			(xy 78.17612 -104.46004) (xy 78.211934 -104.496108)
		)
		(stroke
			(width 0)
			(type solid)
		)
		(fill yes)
		(layer "F.Cu")
		(net "M_L_DQ<31>")
	)
	(gr_poly
		(pts
			(xy 78.33868 -51.893724) (xy 78.294484 -51.889914) (xy 78.117192 -51.963574) (xy 78.097888 -52.183792)
			(xy 78.259686 -52.28717) (xy 78.304136 -52.29098)
		)
		(stroke
			(width 0)
			(type solid)
		)
		(fill yes)
		(layer "F.Cu")
		(net "M_H_DQS_DN<3>")
	)
	(gr_poly
		(pts
			(xy 78.342998 -47.07001) (xy 78.389734 -46.972982) (xy 78.314296 -46.897544) (xy 78.217268 -46.94428)
			(xy 78.1812 -46.980094) (xy 78.30693 -47.105824)
		)
		(stroke
			(width 0)
			(type solid)
		)
		(fill yes)
		(layer "F.Cu")
		(net "M_H_DQ<26>")
	)
	(gr_poly
		(pts
			(xy 78.35392 -45.311314) (xy 78.35392 -45.260514) (xy 78.17612 -45.260514) (xy 78.17612 -45.311314)
			(xy 78.21168 -45.412914) (xy 78.31836 -45.412914)
		)
		(stroke
			(width 0)
			(type solid)
		)
		(fill yes)
		(layer "F.Cu")
		(net "M_H_ECC<5>")
	)
	(gr_poly
		(pts
			(xy 78.35392 -45.006514) (xy 78.35392 -44.955714) (xy 78.17612 -44.955714) (xy 78.17612 -45.006514)
			(xy 78.21168 -45.108114) (xy 78.31836 -45.108114)
		)
		(stroke
			(width 0)
			(type solid)
		)
		(fill yes)
		(layer "F.Cu")
		(net "M_H_ECC<0>")
	)
	(gr_poly
		(pts
			(xy 78.35392 -44.701714) (xy 78.35392 -44.650914) (xy 78.17612 -44.650914) (xy 78.17612 -44.701714)
			(xy 78.21168 -44.803314) (xy 78.31836 -44.803314)
		)
		(stroke
			(width 0)
			(type solid)
		)
		(fill yes)
		(layer "F.Cu")
		(net "M_H_ECC<1>")
	)
	(gr_poly
		(pts
			(xy 78.35392 -44.396914) (xy 78.35392 -44.346114) (xy 78.17612 -44.346114) (xy 78.17612 -44.396914)
			(xy 78.21168 -44.498514) (xy 78.31836 -44.498514)
		)
		(stroke
			(width 0)
			(type solid)
		)
		(fill yes)
		(layer "F.Cu")
		(net "M_H_DQS_DP<17>")
	)
	(gr_poly
		(pts
			(xy 78.357476 -104.13492) (xy 78.31074 -104.037892) (xy 78.274672 -104.002078) (xy 78.148942 -104.127808)
			(xy 78.18501 -104.163622) (xy 78.282038 -104.210358)
		)
		(stroke
			(width 0)
			(type solid)
		)
		(fill yes)
		(layer "F.Cu")
		(net "M_L_DQ<30>")
	)
	(gr_poly
		(pts
			(xy 78.365096 -41.805352) (xy 78.401164 -41.769538) (xy 78.311248 -41.679622) (xy 78.275434 -41.71569)
			(xy 78.149704 -41.8592) (xy 78.221586 -41.931082)
		)
		(stroke
			(width 0)
			(type solid)
		)
		(fill yes)
		(layer "F.Cu")
		(net "M_H_ECC<7>")
	)
	(gr_poly
		(pts
			(xy 78.387448 -48.5521) (xy 78.423516 -48.516286) (xy 78.297786 -48.390556) (xy 78.261718 -48.42637)
			(xy 78.214982 -48.523398) (xy 78.29042 -48.598836)
		)
		(stroke
			(width 0)
			(type solid)
		)
		(fill yes)
		(layer "F.Cu")
		(net "M_H_DQS_DP<3>")
	)
	(gr_poly
		(pts
			(xy 78.39202 -42.245534) (xy 78.51775 -42.10177) (xy 78.446122 -42.029888) (xy 78.302358 -42.155618)
			(xy 78.26629 -42.191432) (xy 78.356206 -42.281348)
		)
		(stroke
			(width 0)
			(type solid)
		)
		(fill yes)
		(layer "F.Cu")
		(net "M_H_ECC<6>")
	)
	(gr_poly
		(pts
			(xy 78.396338 -48.848518) (xy 78.443074 -48.75149) (xy 78.367636 -48.676052) (xy 78.270608 -48.722788)
			(xy 78.234794 -48.758856) (xy 78.360524 -48.884586)
		)
		(stroke
			(width 0)
			(type solid)
		)
		(fill yes)
		(layer "F.Cu")
		(net "M_H_DQS_DN<3>")
	)
	(gr_poly
		(pts
			(xy 78.42377 -47.294546) (xy 78.459584 -47.258478) (xy 78.333854 -47.132748) (xy 78.29804 -47.168816)
			(xy 78.251304 -47.265844) (xy 78.326742 -47.341282)
		)
		(stroke
			(width 0)
			(type solid)
		)
		(fill yes)
		(layer "F.Cu")
		(net "M_H_DQ<26>")
	)
	(gr_poly
		(pts
			(xy 78.427326 -103.849424) (xy 78.391512 -103.813356) (xy 78.294484 -103.76662) (xy 78.219046 -103.842058)
			(xy 78.265782 -103.939086) (xy 78.301596 -103.975154)
		)
		(stroke
			(width 0)
			(type solid)
		)
		(fill yes)
		(layer "F.Cu")
		(net "M_L_DQ<30>")
	)
	(gr_poly
		(pts
			(xy 78.43266 -47.590964) (xy 78.479396 -47.493936) (xy 78.403958 -47.418498) (xy 78.30693 -47.465234)
			(xy 78.270862 -47.501048) (xy 78.396592 -47.626778)
		)
		(stroke
			(width 0)
			(type solid)
		)
		(fill yes)
		(layer "F.Cu")
		(net "M_H_DQ<31>")
	)
	(gr_poly
		(pts
			(xy 78.447138 -103.613966) (xy 78.400402 -103.516938) (xy 78.364334 -103.481124) (xy 78.238858 -103.6066)
			(xy 78.274672 -103.642668) (xy 78.3717 -103.689404)
		)
		(stroke
			(width 0)
			(type solid)
		)
		(fill yes)
		(layer "F.Cu")
		(net "M_L_DQS_DP<3>")
	)
	(gr_poly
		(pts
			(xy 78.463902 -43.575224) (xy 78.49997 -43.53941) (xy 78.410054 -43.449494) (xy 78.37424 -43.485562)
			(xy 78.24851 -43.629072) (xy 78.320392 -43.700954)
		)
		(stroke
			(width 0)
			(type solid)
		)
		(fill yes)
		(layer "F.Cu")
		(net "M_H_DQS_DN<8>")
	)
	(gr_poly
		(pts
			(xy 78.472538 -105.115868) (xy 78.427834 -105.07091) (xy 78.330806 -105.024174) (xy 78.255368 -105.099612)
			(xy 78.302104 -105.19664) (xy 78.346808 -105.241598)
		)
		(stroke
			(width 0)
			(type solid)
		)
		(fill yes)
		(layer "F.Cu")
		(net "M_L_DQ<27>")
	)
	(gr_poly
		(pts
			(xy 78.47711 -49.073054) (xy 78.513178 -49.03724) (xy 78.387448 -48.91151) (xy 78.35138 -48.947324)
			(xy 78.304644 -49.044352) (xy 78.380082 -49.11979)
		)
		(stroke
			(width 0)
			(type solid)
		)
		(fill yes)
		(layer "F.Cu")
		(net "M_H_DQS_DN<3>")
	)
	(gr_poly
		(pts
			(xy 78.481936 -41.22166) (xy 78.607666 -41.077896) (xy 78.536038 -41.006014) (xy 78.392274 -41.131744)
			(xy 78.356206 -41.167558) (xy 78.446122 -41.257474)
		)
		(stroke
			(width 0)
			(type solid)
		)
		(fill yes)
		(layer "F.Cu")
		(net "M_H_ECC<2>")
	)
	(gr_poly
		(pts
			(xy 78.48346 -104.87152) (xy 78.436724 -104.774492) (xy 78.400656 -104.738678) (xy 78.274926 -104.864408)
			(xy 78.310994 -104.900222) (xy 78.408022 -104.946958)
		)
		(stroke
			(width 0)
			(type solid)
		)
		(fill yes)
		(layer "F.Cu")
		(net "M_L_DQ<26>")
	)
	(gr_poly
		(pts
			(xy 78.513432 -47.8155) (xy 78.549246 -47.779432) (xy 78.42377 -47.653956) (xy 78.387702 -47.68977)
			(xy 78.340966 -47.786798) (xy 78.416404 -47.862236)
		)
		(stroke
			(width 0)
			(type solid)
		)
		(fill yes)
		(layer "F.Cu")
		(net "M_H_DQ<31>")
	)
	(gr_poly
		(pts
			(xy 78.517242 -103.328216) (xy 78.481174 -103.292402) (xy 78.384146 -103.245666) (xy 78.308708 -103.321104)
			(xy 78.355444 -103.418132) (xy 78.391512 -103.453946)
		)
		(stroke
			(width 0)
			(type solid)
		)
		(fill yes)
		(layer "F.Cu")
		(net "M_L_DQS_DP<3>")
	)
	(gr_poly
		(pts
			(xy 78.522322 -48.111918) (xy 78.569058 -48.01489) (xy 78.49362 -47.939452) (xy 78.396592 -47.986188)
			(xy 78.360778 -48.022256) (xy 78.486508 -48.147986)
		)
		(stroke
			(width 0)
			(type solid)
		)
		(fill yes)
		(layer "F.Cu")
		(net "M_H_DQ<30>")
	)
	(gr_poly
		(pts
			(xy 78.52664 -108.372402) (xy 78.52664 -108.321602) (xy 78.39964 -108.321602) (xy 78.39964 -108.372402)
			(xy 78.41234 -108.562902) (xy 78.51394 -108.562902)
		)
		(stroke
			(width 0)
			(type solid)
		)
		(fill yes)
		(layer "F.Cu")
		(net "M_L_DQS_DN<17>")
	)
	(gr_poly
		(pts
			(xy 78.52664 -107.978702) (xy 78.52664 -107.927902) (xy 78.39964 -107.927902) (xy 78.39964 -107.978702)
			(xy 78.41234 -108.169202) (xy 78.51394 -108.169202)
		)
		(stroke
			(width 0)
			(type solid)
		)
		(fill yes)
		(layer "F.Cu")
		(net "M_L_DQS_DP<17>")
	)
	(gr_poly
		(pts
			(xy 78.52664 -107.585256) (xy 78.52664 -107.534456) (xy 78.39964 -107.534456) (xy 78.39964 -107.585256)
			(xy 78.41234 -107.775756) (xy 78.51394 -107.775756)
		)
		(stroke
			(width 0)
			(type solid)
		)
		(fill yes)
		(layer "F.Cu")
		(net "M_L_ECC<1>")
	)
	(gr_poly
		(pts
			(xy 78.52664 -107.19181) (xy 78.52664 -107.14101) (xy 78.39964 -107.14101) (xy 78.39964 -107.19181)
			(xy 78.41234 -107.38231) (xy 78.51394 -107.38231)
		)
		(stroke
			(width 0)
			(type solid)
		)
		(fill yes)
		(layer "F.Cu")
		(net "M_L_ECC<0>")
	)
	(gr_poly
		(pts
			(xy 78.5368 -103.093012) (xy 78.490064 -102.995984) (xy 78.45425 -102.959916) (xy 78.32852 -103.085646)
			(xy 78.364334 -103.121714) (xy 78.461362 -103.16845)
		)
		(stroke
			(width 0)
			(type solid)
		)
		(fill yes)
		(layer "F.Cu")
		(net "M_L_DQS_DN<3>")
	)
	(gr_poly
		(pts
			(xy 78.55331 -104.586024) (xy 78.517496 -104.549956) (xy 78.420468 -104.50322) (xy 78.34503 -104.578658)
			(xy 78.391766 -104.675686) (xy 78.42758 -104.711754)
		)
		(stroke
			(width 0)
			(type solid)
		)
		(fill yes)
		(layer "F.Cu")
		(net "M_L_DQ<26>")
	)
	(gr_poly
		(pts
			(xy 78.554072 -42.551096) (xy 78.59014 -42.515282) (xy 78.500224 -42.425366) (xy 78.46441 -42.461434)
			(xy 78.33868 -42.604944) (xy 78.410562 -42.676826)
		)
		(stroke
			(width 0)
			(type solid)
		)
		(fill yes)
		(layer "F.Cu")
		(net "M_H_ECC<6>")
	)
	(gr_poly
		(pts
			(xy 78.56982 -45.209714) (xy 78.53426 -45.108114) (xy 78.42758 -45.108114) (xy 78.39202 -45.209714)
			(xy 78.39202 -45.260514) (xy 78.56982 -45.260514)
		)
		(stroke
			(width 0)
			(type solid)
		)
		(fill yes)
		(layer "F.Cu")
		(net "M_H_ECC<5>")
	)
	(gr_poly
		(pts
			(xy 78.56982 -44.904914) (xy 78.53426 -44.803314) (xy 78.42758 -44.803314) (xy 78.39202 -44.904914)
			(xy 78.39202 -44.955714) (xy 78.56982 -44.955714)
		)
		(stroke
			(width 0)
			(type solid)
		)
		(fill yes)
		(layer "F.Cu")
		(net "M_H_ECC<0>")
	)
	(gr_poly
		(pts
			(xy 78.56982 -44.600114) (xy 78.53426 -44.498514) (xy 78.42758 -44.498514) (xy 78.39202 -44.600114)
			(xy 78.39202 -44.650914) (xy 78.56982 -44.650914)
		)
		(stroke
			(width 0)
			(type solid)
		)
		(fill yes)
		(layer "F.Cu")
		(net "M_H_ECC<1>")
	)
	(gr_poly
		(pts
			(xy 78.56982 -44.295314) (xy 78.53426 -44.193714) (xy 78.42758 -44.193714) (xy 78.39202 -44.295314)
			(xy 78.39202 -44.346114) (xy 78.56982 -44.346114)
		)
		(stroke
			(width 0)
			(type solid)
		)
		(fill yes)
		(layer "F.Cu")
		(net "M_H_DQS_DP<17>")
	)
	(gr_poly
		(pts
			(xy 78.573122 -104.350566) (xy 78.526386 -104.253538) (xy 78.490318 -104.217724) (xy 78.364588 -104.343454)
			(xy 78.400656 -104.379268) (xy 78.497684 -104.426004)
		)
		(stroke
			(width 0)
			(type solid)
		)
		(fill yes)
		(layer "F.Cu")
		(net "M_L_DQ<31>")
	)
	(gr_poly
		(pts
			(xy 78.580742 -42.991532) (xy 78.706472 -42.847768) (xy 78.634844 -42.775886) (xy 78.49108 -42.901616)
			(xy 78.455012 -42.93743) (xy 78.544928 -43.027346)
		)
		(stroke
			(width 0)
			(type solid)
		)
		(fill yes)
		(layer "F.Cu")
		(net "M_H_DQS_DP<8>")
	)
	(gr_poly
		(pts
			(xy 78.603094 -48.336454) (xy 78.639162 -48.30064) (xy 78.513432 -48.17491) (xy 78.477364 -48.210724)
			(xy 78.430628 -48.307752) (xy 78.506066 -48.38319)
		)
		(stroke
			(width 0)
			(type solid)
		)
		(fill yes)
		(layer "F.Cu")
		(net "M_H_DQ<30>")
	)
	(gr_poly
		(pts
			(xy 78.606904 -102.807262) (xy 78.570836 -102.771448) (xy 78.473808 -102.724712) (xy 78.39837 -102.80015)
			(xy 78.445106 -102.897178) (xy 78.481174 -102.932992)
		)
		(stroke
			(width 0)
			(type solid)
		)
		(fill yes)
		(layer "F.Cu")
		(net "M_L_DQS_DN<3>")
	)
	(gr_poly
		(pts
			(xy 78.611984 -48.632872) (xy 78.65872 -48.535844) (xy 78.583282 -48.460406) (xy 78.486254 -48.507142)
			(xy 78.45044 -48.54321) (xy 78.57617 -48.66894)
		)
		(stroke
			(width 0)
			(type solid)
		)
		(fill yes)
		(layer "F.Cu")
		(net "M_H_DQS_DP<3>")
	)
	(gr_poly
		(pts
			(xy 78.639416 -47.0789) (xy 78.68412 -47.033942) (xy 78.55839 -46.908212) (xy 78.513686 -46.95317)
			(xy 78.46695 -47.050198) (xy 78.542388 -47.125636)
		)
		(stroke
			(width 0)
			(type solid)
		)
		(fill yes)
		(layer "F.Cu")
		(net "M_H_DQ<27>")
	)
	(gr_poly
		(pts
			(xy 78.642972 -104.06507) (xy 78.607158 -104.029002) (xy 78.51013 -103.982266) (xy 78.434692 -104.057704)
			(xy 78.481428 -104.154732) (xy 78.517242 -104.1908)
		)
		(stroke
			(width 0)
			(type solid)
		)
		(fill yes)
		(layer "F.Cu")
		(net "M_L_DQ<31>")
	)
	(gr_poly
		(pts
			(xy 78.643734 -41.526968) (xy 78.679548 -41.4909) (xy 78.589886 -41.401238) (xy 78.553818 -41.437052)
			(xy 78.428088 -41.580816) (xy 78.49997 -41.652698)
		)
		(stroke
			(width 0)
			(type solid)
		)
		(fill yes)
		(layer "F.Cu")
		(net "M_H_ECC<2>")
	)
	(gr_poly
		(pts
			(xy 78.648306 -47.375318) (xy 78.695042 -47.27829) (xy 78.619604 -47.202852) (xy 78.522576 -47.249588)
			(xy 78.486508 -47.285402) (xy 78.612238 -47.411132)
		)
		(stroke
			(width 0)
			(type solid)
		)
		(fill yes)
		(layer "F.Cu")
		(net "M_H_DQ<26>")
	)
	(gr_poly
		(pts
			(xy 78.662784 -103.829612) (xy 78.616048 -103.732584) (xy 78.57998 -103.69677) (xy 78.454504 -103.822246)
			(xy 78.490318 -103.858314) (xy 78.587346 -103.90505)
		)
		(stroke
			(width 0)
			(type solid)
		)
		(fill yes)
		(layer "F.Cu")
		(net "M_L_DQ<30>")
	)
	(gr_poly
		(pts
			(xy 78.670912 -41.967404) (xy 78.796642 -41.82364) (xy 78.72476 -41.752012) (xy 78.580996 -41.877742)
			(xy 78.545182 -41.913556) (xy 78.635098 -42.003472)
		)
		(stroke
			(width 0)
			(type solid)
		)
		(fill yes)
		(layer "F.Cu")
		(net "M_H_ECC<7>")
	)
	(gr_poly
		(pts
			(xy 78.688946 -106.82478) (xy 78.563216 -106.68127) (xy 78.527402 -106.645202) (xy 78.437486 -106.735118)
			(xy 78.473554 -106.770932) (xy 78.617064 -106.896662)
		)
		(stroke
			(width 0)
			(type solid)
		)
		(fill yes)
		(layer "F.Cu")
		(net "M_L_ECC<5>")
	)
	(gr_poly
		(pts
			(xy 78.692756 -48.857408) (xy 78.728824 -48.821594) (xy 78.603094 -48.695864) (xy 78.567026 -48.731678)
			(xy 78.52029 -48.828706) (xy 78.595728 -48.904144)
		)
		(stroke
			(width 0)
			(type solid)
		)
		(fill yes)
		(layer "F.Cu")
		(net "M_H_DQS_DP<3>")
	)
	(gr_poly
		(pts
			(xy 78.696058 -45.660818) (xy 78.742794 -45.56379) (xy 78.667356 -45.488352) (xy 78.570328 -45.535088)
			(xy 78.525624 -45.580046) (xy 78.651354 -45.705776)
		)
		(stroke
			(width 0)
			(type solid)
		)
		(fill yes)
		(layer "F.Cu")
		(net "M_H_ECC<4>")
	)
	(gr_poly
		(pts
			(xy 78.729078 -47.599854) (xy 78.764892 -47.563786) (xy 78.639416 -47.43831) (xy 78.603348 -47.474124)
			(xy 78.556612 -47.571152) (xy 78.63205 -47.64659)
		)
		(stroke
			(width 0)
			(type solid)
		)
		(fill yes)
		(layer "F.Cu")
		(net "M_H_DQ<26>")
	)
	(gr_poly
		(pts
			(xy 78.732888 -103.543862) (xy 78.69682 -103.508048) (xy 78.599792 -103.461312) (xy 78.524354 -103.53675)
			(xy 78.57109 -103.633778) (xy 78.607158 -103.669592)
		)
		(stroke
			(width 0)
			(type solid)
		)
		(fill yes)
		(layer "F.Cu")
		(net "M_L_DQ<30>")
	)
	(gr_poly
		(pts
			(xy 78.737968 -47.896272) (xy 78.784704 -47.799244) (xy 78.709266 -47.723806) (xy 78.612238 -47.770542)
			(xy 78.576424 -47.80661) (xy 78.702154 -47.93234)
		)
		(stroke
			(width 0)
			(type solid)
		)
		(fill yes)
		(layer "F.Cu")
		(net "M_H_DQ<31>")
	)
	(gr_poly
		(pts
			(xy 78.742794 -43.297094) (xy 78.778862 -43.26128) (xy 78.688946 -43.171364) (xy 78.653132 -43.207432)
			(xy 78.527402 -43.350942) (xy 78.599284 -43.422824)
		)
		(stroke
			(width 0)
			(type solid)
		)
		(fill yes)
		(layer "F.Cu")
		(net "M_H_DQS_DP<8>")
	)
	(gr_poly
		(pts
			(xy 78.752446 -103.308658) (xy 78.70571 -103.21163) (xy 78.669896 -103.175562) (xy 78.544166 -103.301292)
			(xy 78.57998 -103.33736) (xy 78.677008 -103.384096)
		)
		(stroke
			(width 0)
			(type solid)
		)
		(fill yes)
		(layer "F.Cu")
		(net "M_L_DQS_DP<3>")
	)
	(gr_poly
		(pts
			(xy 78.761336 -106.411268) (xy 78.725268 -106.375454) (xy 78.581504 -106.249724) (xy 78.509876 -106.321606)
			(xy 78.635606 -106.46537) (xy 78.67142 -106.501184)
		)
		(stroke
			(width 0)
			(type solid)
		)
		(fill yes)
		(layer "F.Cu")
		(net "M_L_ECC<5>")
	)
	(gr_poly
		(pts
			(xy 78.777846 -104.81056) (xy 78.733142 -104.765602) (xy 78.636114 -104.718866) (xy 78.560676 -104.794304)
			(xy 78.607412 -104.891332) (xy 78.652116 -104.93629)
		)
		(stroke
			(width 0)
			(type solid)
		)
		(fill yes)
		(layer "F.Cu")
		(net "M_L_DQ<27>")
	)
	(gr_poly
		(pts
			(xy 78.78572 -44.701714) (xy 78.78572 -44.650914) (xy 78.60792 -44.650914) (xy 78.60792 -44.701714)
			(xy 78.64348 -44.803314) (xy 78.75016 -44.803314)
		)
		(stroke
			(width 0)
			(type solid)
		)
		(fill yes)
		(layer "F.Cu")
		(net "M_H_ECC<1>")
	)
	(gr_poly
		(pts
			(xy 78.78572 -44.396914) (xy 78.78572 -44.346114) (xy 78.60792 -44.346114) (xy 78.60792 -44.396914)
			(xy 78.64348 -44.498514) (xy 78.75016 -44.498514)
		)
		(stroke
			(width 0)
			(type solid)
		)
		(fill yes)
		(layer "F.Cu")
		(net "M_H_DQS_DP<17>")
	)
	(gr_poly
		(pts
			(xy 78.78572 -44.092114) (xy 78.78572 -44.041314) (xy 78.60792 -44.041314) (xy 78.60792 -44.092114)
			(xy 78.64348 -44.193714) (xy 78.75016 -44.193714)
		)
		(stroke
			(width 0)
			(type solid)
		)
		(fill yes)
		(layer "F.Cu")
		(net "M_H_DQS_DN<17>")
	)
	(gr_poly
		(pts
			(xy 78.788768 -104.566212) (xy 78.742032 -104.469184) (xy 78.705964 -104.43337) (xy 78.580234 -104.5591)
			(xy 78.616302 -104.594914) (xy 78.71333 -104.64165)
		)
		(stroke
			(width 0)
			(type solid)
		)
		(fill yes)
		(layer "F.Cu")
		(net "M_L_DQ<26>")
	)
	(gr_poly
		(pts
			(xy 78.81874 -48.120808) (xy 78.854808 -48.084994) (xy 78.729078 -47.959264) (xy 78.69301 -47.995078)
			(xy 78.646274 -48.092106) (xy 78.721712 -48.167544)
		)
		(stroke
			(width 0)
			(type solid)
		)
		(fill yes)
		(layer "F.Cu")
		(net "M_H_DQ<31>")
	)
	(gr_poly
		(pts
			(xy 78.82255 -103.022908) (xy 78.786482 -102.987094) (xy 78.689454 -102.940358) (xy 78.614016 -103.015796)
			(xy 78.660752 -103.112824) (xy 78.69682 -103.148638)
		)
		(stroke
			(width 0)
			(type solid)
		)
		(fill yes)
		(layer "F.Cu")
		(net "M_L_DQS_DP<3>")
	)
	(gr_poly
		(pts
			(xy 78.82763 -48.417226) (xy 78.874366 -48.320198) (xy 78.798928 -48.24476) (xy 78.7019 -48.291496)
			(xy 78.666086 -48.327564) (xy 78.791816 -48.453294)
		)
		(stroke
			(width 0)
			(type solid)
		)
		(fill yes)
		(layer "F.Cu")
		(net "M_H_DQ<30>")
	)
	(gr_poly
		(pts
			(xy 78.832456 -42.272712) (xy 78.868524 -42.236898) (xy 78.778608 -42.146982) (xy 78.742794 -42.18305)
			(xy 78.617064 -42.32656) (xy 78.688946 -42.398442)
		)
		(stroke
			(width 0)
			(type solid)
		)
		(fill yes)
		(layer "F.Cu")
		(net "M_H_ECC<7>")
	)
	(gr_poly
		(pts
			(xy 78.842108 -102.787704) (xy 78.795372 -102.690676) (xy 78.759558 -102.654608) (xy 78.633828 -102.780338)
			(xy 78.669642 -102.816406) (xy 78.76667 -102.863142)
		)
		(stroke
			(width 0)
			(type solid)
		)
		(fill yes)
		(layer "F.Cu")
		(net "M_L_DQS_DN<3>")
	)
	(gr_poly
		(pts
			(xy 78.85684 -108.271056) (xy 78.84414 -108.080556) (xy 78.74254 -108.080556) (xy 78.72984 -108.271056)
			(xy 78.72984 -108.321856) (xy 78.85684 -108.321856)
		)
		(stroke
			(width 0)
			(type solid)
		)
		(fill yes)
		(layer "F.Cu")
		(net "M_L_DQS_DN<17>")
	)
	(gr_poly
		(pts
			(xy 78.858618 -104.280716) (xy 78.822804 -104.244648) (xy 78.725776 -104.197912) (xy 78.650338 -104.27335)
			(xy 78.697074 -104.370378) (xy 78.732888 -104.406446)
		)
		(stroke
			(width 0)
			(type solid)
		)
		(fill yes)
		(layer "F.Cu")
		(net "M_L_DQ<26>")
	)
	(gr_poly
		(pts
			(xy 78.85938 -42.712894) (xy 78.98511 -42.56913) (xy 78.913482 -42.497248) (xy 78.769718 -42.622978)
			(xy 78.73365 -42.658792) (xy 78.823566 -42.748708)
		)
		(stroke
			(width 0)
			(type solid)
		)
		(fill yes)
		(layer "F.Cu")
		(net "M_H_ECC<6>")
	)
	(gr_poly
		(pts
			(xy 78.877922 -106.079036) (xy 78.752192 -105.935272) (xy 78.707234 -105.890568) (xy 78.617572 -105.98023)
			(xy 78.66253 -106.025188) (xy 78.80604 -106.150918)
		)
		(stroke
			(width 0)
			(type solid)
		)
		(fill yes)
		(layer "F.Cu")
		(net "M_L_ECC<4>")
	)
	(gr_poly
		(pts
			(xy 78.87843 -104.045258) (xy 78.831694 -103.94823) (xy 78.795626 -103.912416) (xy 78.67015 -104.037892)
			(xy 78.705964 -104.07396) (xy 78.802992 -104.120696)
		)
		(stroke
			(width 0)
			(type solid)
		)
		(fill yes)
		(layer "F.Cu")
		(net "M_L_DQ<31>")
	)
	(gr_poly
		(pts
			(xy 78.908402 -48.641762) (xy 78.94447 -48.605948) (xy 78.81874 -48.480218) (xy 78.782672 -48.516032)
			(xy 78.735936 -48.61306) (xy 78.811374 -48.688498)
		)
		(stroke
			(width 0)
			(type solid)
		)
		(fill yes)
		(layer "F.Cu")
		(net "M_H_DQ<30>")
	)
	(gr_poly
		(pts
			(xy 78.911704 -45.445172) (xy 78.95844 -45.348144) (xy 78.883002 -45.272706) (xy 78.785974 -45.319442)
			(xy 78.75016 -45.35551) (xy 78.87589 -45.48124)
		)
		(stroke
			(width 0)
			(type solid)
		)
		(fill yes)
		(layer "F.Cu")
		(net "M_H_ECC<5>")
	)
	(gr_poly
		(pts
			(xy 78.922372 -41.24833) (xy 78.967076 -41.203372) (xy 78.877414 -41.11371) (xy 78.832456 -41.158668)
			(xy 78.706726 -41.302178) (xy 78.778608 -41.37406)
		)
		(stroke
			(width 0)
			(type solid)
		)
		(fill yes)
		(layer "F.Cu")
		(net "M_H_ECC<3>")
	)
	(gr_poly
		(pts
			(xy 78.944724 -47.384208) (xy 78.989428 -47.33925) (xy 78.863952 -47.213774) (xy 78.818994 -47.258478)
			(xy 78.772258 -47.355506) (xy 78.847696 -47.430944)
		)
		(stroke
			(width 0)
			(type solid)
		)
		(fill yes)
		(layer "F.Cu")
		(net "M_H_DQ<27>")
	)
	(gr_poly
		(pts
			(xy 78.948534 -103.759508) (xy 78.912466 -103.723694) (xy 78.815438 -103.676958) (xy 78.74 -103.752396)
			(xy 78.786736 -103.849424) (xy 78.822804 -103.885238)
		)
		(stroke
			(width 0)
			(type solid)
		)
		(fill yes)
		(layer "F.Cu")
		(net "M_L_DQ<31>")
	)
	(gr_poly
		(pts
			(xy 78.949296 -41.68902) (xy 79.075026 -41.545256) (xy 79.003398 -41.473374) (xy 78.859634 -41.599104)
			(xy 78.823566 -41.634918) (xy 78.913482 -41.724834)
		)
		(stroke
			(width 0)
			(type solid)
		)
		(fill yes)
		(layer "F.Cu")
		(net "M_H_ECC<2>")
	)
	(gr_poly
		(pts
			(xy 78.953614 -47.680626) (xy 79.00035 -47.583598) (xy 78.924912 -47.50816) (xy 78.827884 -47.554896)
			(xy 78.79207 -47.590964) (xy 78.9178 -47.716694)
		)
		(stroke
			(width 0)
			(type solid)
		)
		(fill yes)
		(layer "F.Cu")
		(net "M_H_DQ<26>")
	)
	(gr_poly
		(pts
			(xy 78.967838 -107.10291) (xy 78.842108 -106.9594) (xy 78.806294 -106.923332) (xy 78.716378 -107.013248)
			(xy 78.752446 -107.049062) (xy 78.895956 -107.174792)
		)
		(stroke
			(width 0)
			(type solid)
		)
		(fill yes)
		(layer "F.Cu")
		(net "M_L_ECC<0>")
	)
	(gr_poly
		(pts
			(xy 78.968092 -103.524304) (xy 78.921356 -103.427276) (xy 78.885542 -103.391208) (xy 78.759812 -103.516938)
			(xy 78.795626 -103.553006) (xy 78.892654 -103.599742)
		)
		(stroke
			(width 0)
			(type solid)
		)
		(fill yes)
		(layer "F.Cu")
		(net "M_L_DQ<30>")
	)
	(gr_poly
		(pts
			(xy 78.992476 -45.669708) (xy 79.028544 -45.633894) (xy 78.902814 -45.508164) (xy 78.866746 -45.543978)
			(xy 78.82001 -45.641006) (xy 78.895448 -45.716444)
		)
		(stroke
			(width 0)
			(type solid)
		)
		(fill yes)
		(layer "F.Cu")
		(net "M_H_ECC<5>")
	)
	(gr_poly
		(pts
			(xy 79.001366 -45.966126) (xy 79.048102 -45.869098) (xy 78.972664 -45.79366) (xy 78.875636 -45.840396)
			(xy 78.830932 -45.885354) (xy 78.956662 -46.011084)
		)
		(stroke
			(width 0)
			(type solid)
		)
		(fill yes)
		(layer "F.Cu")
		(net "M_H_ECC<4>")
	)
	(gr_poly
		(pts
			(xy 79.00162 -44.295314) (xy 78.96606 -44.193714) (xy 78.85938 -44.193714) (xy 78.82382 -44.295314)
			(xy 78.82382 -44.346114) (xy 79.00162 -44.346114)
		)
		(stroke
			(width 0)
			(type solid)
		)
		(fill yes)
		(layer "F.Cu")
		(net "M_H_DQS_DP<17>")
	)
	(gr_poly
		(pts
			(xy 79.00162 -43.990514) (xy 78.96606 -43.888914) (xy 78.85938 -43.888914) (xy 78.82382 -43.990514)
			(xy 78.82382 -44.041314) (xy 79.00162 -44.041314)
		)
		(stroke
			(width 0)
			(type solid)
		)
		(fill yes)
		(layer "F.Cu")
		(net "M_H_DQS_DN<17>")
	)
	(gr_poly
		(pts
			(xy 79.00162 -43.685714) (xy 78.96606 -43.584114) (xy 78.85938 -43.584114) (xy 78.82382 -43.685714)
			(xy 78.82382 -43.736514) (xy 79.00162 -43.736514)
		)
		(stroke
			(width 0)
			(type solid)
		)
		(fill yes)
		(layer "F.Cu")
		(net "M_H_DQS_DN<8>")
	)
	(gr_poly
		(pts
			(xy 79.021432 -43.018456) (xy 79.0575 -42.982642) (xy 78.967584 -42.892726) (xy 78.93177 -42.928794)
			(xy 78.80604 -43.072304) (xy 78.877922 -43.144186)
		)
		(stroke
			(width 0)
			(type solid)
		)
		(fill yes)
		(layer "F.Cu")
		(net "M_H_ECC<6>")
	)
	(gr_poly
		(pts
			(xy 79.034386 -47.905162) (xy 79.070454 -47.869348) (xy 78.944724 -47.743618) (xy 78.908656 -47.779432)
			(xy 78.86192 -47.87646) (xy 78.937358 -47.951898)
		)
		(stroke
			(width 0)
			(type solid)
		)
		(fill yes)
		(layer "F.Cu")
		(net "M_H_DQ<26>")
	)
	(gr_poly
		(pts
			(xy 79.037688 -44.708572) (xy 79.084424 -44.611544) (xy 79.008986 -44.536106) (xy 78.911958 -44.582842)
			(xy 78.876144 -44.61891) (xy 79.001874 -44.74464)
		)
		(stroke
			(width 0)
			(type solid)
		)
		(fill yes)
		(layer "F.Cu")
		(net "M_H_ECC<1>")
	)
	(gr_poly
		(pts
			(xy 79.038196 -103.238554) (xy 79.002128 -103.20274) (xy 78.9051 -103.156004) (xy 78.829662 -103.231442)
			(xy 78.876398 -103.32847) (xy 78.912466 -103.364284)
		)
		(stroke
			(width 0)
			(type solid)
		)
		(fill yes)
		(layer "F.Cu")
		(net "M_L_DQ<30>")
	)
	(gr_poly
		(pts
			(xy 79.03972 -106.689906) (xy 79.003906 -106.653838) (xy 78.860142 -106.528108) (xy 78.78826 -106.59999)
			(xy 78.91399 -106.743754) (xy 78.950058 -106.779568)
		)
		(stroke
			(width 0)
			(type solid)
		)
		(fill yes)
		(layer "F.Cu")
		(net "M_L_ECC<0>")
	)
	(gr_poly
		(pts
			(xy 79.043276 -48.20158) (xy 79.090012 -48.104552) (xy 79.014574 -48.029114) (xy 78.917546 -48.07585)
			(xy 78.881732 -48.111918) (xy 79.007462 -48.237648)
		)
		(stroke
			(width 0)
			(type solid)
		)
		(fill yes)
		(layer "F.Cu")
		(net "M_H_DQ<31>")
	)
	(gr_poly
		(pts
			(xy 79.057754 -103.00335) (xy 79.011018 -102.906322) (xy 78.975204 -102.870254) (xy 78.849474 -102.995984)
			(xy 78.885288 -103.032052) (xy 78.982316 -103.078788)
		)
		(stroke
			(width 0)
			(type solid)
		)
		(fill yes)
		(layer "F.Cu")
		(net "M_L_DQS_DP<3>")
	)
	(gr_poly
		(pts
			(xy 79.083154 -104.505252) (xy 79.03845 -104.460294) (xy 78.941422 -104.413558) (xy 78.865984 -104.488996)
			(xy 78.91272 -104.586024) (xy 78.957424 -104.630982)
		)
		(stroke
			(width 0)
			(type solid)
		)
		(fill yes)
		(layer "F.Cu")
		(net "M_L_DQ<27>")
	)
	(gr_poly
		(pts
			(xy 79.094076 -104.260904) (xy 79.04734 -104.163876) (xy 79.011272 -104.128062) (xy 78.885796 -104.253538)
			(xy 78.92161 -104.289606) (xy 79.018638 -104.336342)
		)
		(stroke
			(width 0)
			(type solid)
		)
		(fill yes)
		(layer "F.Cu")
		(net "M_L_DQ<26>")
	)
	(gr_poly
		(pts
			(xy 79.111094 -41.994328) (xy 79.146908 -41.95826) (xy 79.057246 -41.868598) (xy 79.021178 -41.904412)
			(xy 78.895448 -42.048176) (xy 78.96733 -42.120058)
		)
		(stroke
			(width 0)
			(type solid)
		)
		(fill yes)
		(layer "F.Cu")
		(net "M_H_ECC<2>")
	)
	(gr_poly
		(pts
			(xy 79.11846 -44.933108) (xy 79.154528 -44.897294) (xy 79.028798 -44.771564) (xy 78.99273 -44.807378)
			(xy 78.945994 -44.904406) (xy 79.021432 -44.979844)
		)
		(stroke
			(width 0)
			(type solid)
		)
		(fill yes)
		(layer "F.Cu")
		(net "M_H_ECC<1>")
	)
	(gr_poly
		(pts
			(xy 79.124048 -48.426116) (xy 79.160116 -48.390302) (xy 79.034386 -48.264572) (xy 78.998318 -48.300386)
			(xy 78.951582 -48.397414) (xy 79.02702 -48.472852)
		)
		(stroke
			(width 0)
			(type solid)
		)
		(fill yes)
		(layer "F.Cu")
		(net "M_H_DQ<31>")
	)
	(gr_poly
		(pts
			(xy 79.12735 -45.229526) (xy 79.174086 -45.132498) (xy 79.098648 -45.05706) (xy 79.00162 -45.103796)
			(xy 78.965806 -45.139864) (xy 79.091536 -45.265594)
		)
		(stroke
			(width 0)
			(type solid)
		)
		(fill yes)
		(layer "F.Cu")
		(net "M_H_ECC<0>")
	)
	(gr_poly
		(pts
			(xy 79.129636 -107.713526) (xy 79.093568 -107.677712) (xy 78.950058 -107.551982) (xy 78.878176 -107.623864)
			(xy 79.003906 -107.767628) (xy 79.03972 -107.803442)
		)
		(stroke
			(width 0)
			(type solid)
		)
		(fill yes)
		(layer "F.Cu")
		(net "M_L_DQS_DP<17>")
	)
	(gr_poly
		(pts
			(xy 79.132938 -48.722534) (xy 79.179674 -48.625506) (xy 79.104236 -48.550068) (xy 79.007208 -48.596804)
			(xy 78.971394 -48.632872) (xy 79.097124 -48.758602)
		)
		(stroke
			(width 0)
			(type solid)
		)
		(fill yes)
		(layer "F.Cu")
		(net "M_H_DQ<30>")
	)
	(gr_poly
		(pts
			(xy 79.137764 -42.43451) (xy 79.263494 -42.290746) (xy 79.191866 -42.218864) (xy 79.048102 -42.344594)
			(xy 79.012034 -42.380408) (xy 79.10195 -42.470324)
		)
		(stroke
			(width 0)
			(type solid)
		)
		(fill yes)
		(layer "F.Cu")
		(net "M_H_ECC<7>")
	)
	(gr_poly
		(pts
			(xy 79.156306 -106.35742) (xy 79.030576 -106.21391) (xy 78.994762 -106.177842) (xy 78.904846 -106.267758)
			(xy 78.940914 -106.303572) (xy 79.084424 -106.429302)
		)
		(stroke
			(width 0)
			(type solid)
		)
		(fill yes)
		(layer "F.Cu")
		(net "M_L_ECC<5>")
	)
	(gr_poly
		(pts
			(xy 79.16418 -103.975154) (xy 79.128112 -103.93934) (xy 79.031084 -103.892604) (xy 78.955646 -103.968042)
			(xy 79.002382 -104.06507) (xy 79.03845 -104.100884)
		)
		(stroke
			(width 0)
			(type solid)
		)
		(fill yes)
		(layer "F.Cu")
		(net "M_L_DQ<26>")
	)
	(gr_poly
		(pts
			(xy 79.183738 -103.73995) (xy 79.137002 -103.642922) (xy 79.101188 -103.606854) (xy 78.975458 -103.732584)
			(xy 79.011272 -103.768652) (xy 79.1083 -103.815388)
		)
		(stroke
			(width 0)
			(type solid)
		)
		(fill yes)
		(layer "F.Cu")
		(net "M_L_DQ<31>")
	)
	(gr_poly
		(pts
			(xy 79.208122 -45.454062) (xy 79.24419 -45.418248) (xy 79.11846 -45.292518) (xy 79.082392 -45.328332)
			(xy 79.035656 -45.42536) (xy 79.111094 -45.500798)
		)
		(stroke
			(width 0)
			(type solid)
		)
		(fill yes)
		(layer "F.Cu")
		(net "M_H_ECC<0>")
	)
	(gr_poly
		(pts
			(xy 79.21371 -48.94707) (xy 79.249778 -48.911256) (xy 79.124048 -48.785526) (xy 79.08798 -48.82134)
			(xy 79.041244 -48.918368) (xy 79.116682 -48.993806)
		)
		(stroke
			(width 0)
			(type solid)
		)
		(fill yes)
		(layer "F.Cu")
		(net "M_H_DQ<30>")
	)
	(gr_poly
		(pts
			(xy 79.217012 -45.75048) (xy 79.263748 -45.653452) (xy 79.18831 -45.578014) (xy 79.091282 -45.62475)
			(xy 79.055468 -45.660818) (xy 79.181198 -45.786548)
		)
		(stroke
			(width 0)
			(type solid)
		)
		(fill yes)
		(layer "F.Cu")
		(net "M_H_ECC<5>")
	)
	(gr_poly
		(pts
			(xy 79.21752 -43.787314) (xy 79.21752 -43.736514) (xy 79.03972 -43.736514) (xy 79.03972 -43.787314)
			(xy 79.07528 -43.888914) (xy 79.18196 -43.888914)
		)
		(stroke
			(width 0)
			(type solid)
		)
		(fill yes)
		(layer "F.Cu")
		(net "M_H_DQS_DN<8>")
	)
	(gr_poly
		(pts
			(xy 79.21752 -43.482514) (xy 79.21752 -43.431714) (xy 79.03972 -43.431714) (xy 79.03972 -43.482514)
			(xy 79.07528 -43.584114) (xy 79.18196 -43.584114)
		)
		(stroke
			(width 0)
			(type solid)
		)
		(fill yes)
		(layer "F.Cu")
		(net "M_H_DQS_DP<8>")
	)
	(gr_poly
		(pts
			(xy 79.228188 -105.944416) (xy 79.192374 -105.908348) (xy 79.04861 -105.782872) (xy 78.976728 -105.8545)
			(xy 79.102458 -105.998264) (xy 79.138526 -106.034078)
		)
		(stroke
			(width 0)
			(type solid)
		)
		(fill yes)
		(layer "F.Cu")
		(net "M_L_ECC<5>")
	)
	(gr_poly
		(pts
			(xy 79.246222 -107.381294) (xy 79.120492 -107.237784) (xy 79.084678 -107.201716) (xy 78.994762 -107.291632)
			(xy 79.03083 -107.327446) (xy 79.17434 -107.453176)
		)
		(stroke
			(width 0)
			(type solid)
		)
		(fill yes)
		(layer "F.Cu")
		(net "M_L_ECC<1>")
	)
	(gr_poly
		(pts
			(xy 79.250032 -47.689516) (xy 79.29499 -47.644812) (xy 79.16926 -47.519082) (xy 79.124302 -47.563786)
			(xy 79.077566 -47.660814) (xy 79.153004 -47.736252)
		)
		(stroke
			(width 0)
			(type solid)
		)
		(fill yes)
		(layer "F.Cu")
		(net "M_H_DQ<27>")
	)
	(gr_poly
		(pts
			(xy 79.253842 -103.4542) (xy 79.217774 -103.418386) (xy 79.120746 -103.37165) (xy 79.045308 -103.447088)
			(xy 79.092044 -103.544116) (xy 79.128112 -103.57993)
		)
		(stroke
			(width 0)
			(type solid)
		)
		(fill yes)
		(layer "F.Cu")
		(net "M_L_DQ<31>")
	)
	(gr_poly
		(pts
			(xy 79.258922 -47.985934) (xy 79.305658 -47.888906) (xy 79.23022 -47.813468) (xy 79.133192 -47.860204)
			(xy 79.097378 -47.896272) (xy 79.223108 -48.022002)
		)
		(stroke
			(width 0)
			(type solid)
		)
		(fill yes)
		(layer "F.Cu")
		(net "M_H_DQ<26>")
	)
	(gr_poly
		(pts
			(xy 79.2734 -103.218996) (xy 79.226664 -103.121968) (xy 79.19085 -103.0859) (xy 79.06512 -103.21163)
			(xy 79.100934 -103.247698) (xy 79.197962 -103.294434)
		)
		(stroke
			(width 0)
			(type solid)
		)
		(fill yes)
		(layer "F.Cu")
		(net "M_L_DQ<30>")
	)
	(gr_poly
		(pts
			(xy 79.297784 -45.975016) (xy 79.333852 -45.939202) (xy 79.208122 -45.813472) (xy 79.172054 -45.849286)
			(xy 79.125318 -45.946314) (xy 79.200756 -46.021752)
		)
		(stroke
			(width 0)
			(type solid)
		)
		(fill yes)
		(layer "F.Cu")
		(net "M_H_ECC<5>")
	)
	(gr_poly
		(pts
			(xy 79.299816 -42.740072) (xy 79.335884 -42.704258) (xy 79.245968 -42.614342) (xy 79.210154 -42.65041)
			(xy 79.084424 -42.79392) (xy 79.156306 -42.865802)
		)
		(stroke
			(width 0)
			(type solid)
		)
		(fill yes)
		(layer "F.Cu")
		(net "M_H_ECC<7>")
	)
	(gr_poly
		(pts
			(xy 79.306928 -46.271434) (xy 79.35341 -46.174406) (xy 79.277972 -46.098968) (xy 79.181198 -46.145704)
			(xy 79.13624 -46.190662) (xy 79.26197 -46.316392)
		)
		(stroke
			(width 0)
			(type solid)
		)
		(fill yes)
		(layer "F.Cu")
		(net "M_H_ECC<4>")
	)
	(gr_poly
		(pts
			(xy 79.318104 -106.96829) (xy 79.28229 -106.932222) (xy 79.138526 -106.806492) (xy 79.066644 -106.878374)
			(xy 79.192374 -107.022138) (xy 79.228442 -107.057952)
		)
		(stroke
			(width 0)
			(type solid)
		)
		(fill yes)
		(layer "F.Cu")
		(net "M_L_ECC<1>")
	)
	(gr_poly
		(pts
			(xy 79.334106 -44.717462) (xy 79.370174 -44.681648) (xy 79.244444 -44.555918) (xy 79.208376 -44.591732)
			(xy 79.16164 -44.68876) (xy 79.237078 -44.764198)
		)
		(stroke
			(width 0)
			(type solid)
		)
		(fill yes)
		(layer "F.Cu")
		(net "M_H_DQS_DP<17>")
	)
	(gr_poly
		(pts
			(xy 79.33563 -108.405422) (xy 79.2099 -108.261912) (xy 79.174086 -108.225844) (xy 79.08417 -108.31576)
			(xy 79.120238 -108.351574) (xy 79.263748 -108.477304)
		)
		(stroke
			(width 0)
			(type solid)
		)
		(fill yes)
		(layer "F.Cu")
		(net "M_L_DQS_DN<17>")
	)
	(gr_poly
		(pts
			(xy 79.339694 -48.21047) (xy 79.375762 -48.174656) (xy 79.250032 -48.048926) (xy 79.213964 -48.08474)
			(xy 79.167228 -48.181768) (xy 79.242666 -48.257206)
		)
		(stroke
			(width 0)
			(type solid)
		)
		(fill yes)
		(layer "F.Cu")
		(net "M_H_DQ<26>")
	)
	(gr_poly
		(pts
			(xy 79.342996 -45.01388) (xy 79.389732 -44.916852) (xy 79.314294 -44.841414) (xy 79.217266 -44.88815)
			(xy 79.181452 -44.924218) (xy 79.307182 -45.049948)
		)
		(stroke
			(width 0)
			(type solid)
		)
		(fill yes)
		(layer "F.Cu")
		(net "M_H_ECC<1>")
	)
	(gr_poly
		(pts
			(xy 79.345028 -105.612184) (xy 79.219298 -105.46842) (xy 79.17434 -105.423462) (xy 79.084424 -105.513378)
			(xy 79.129382 -105.558336) (xy 79.273146 -105.683812)
		)
		(stroke
			(width 0)
			(type solid)
		)
		(fill yes)
		(layer "F.Cu")
		(net "M_L_ECC<4>")
	)
	(gr_poly
		(pts
			(xy 79.348584 -48.506888) (xy 79.39532 -48.40986) (xy 79.319882 -48.334422) (xy 79.222854 -48.381158)
			(xy 79.18704 -48.417226) (xy 79.31277 -48.542956)
		)
		(stroke
			(width 0)
			(type solid)
		)
		(fill yes)
		(layer "F.Cu")
		(net "M_H_DQ<31>")
	)
	(gr_poly
		(pts
			(xy 79.388716 -104.19969) (xy 79.343758 -104.154986) (xy 79.24673 -104.10825) (xy 79.171292 -104.183688)
			(xy 79.218028 -104.280716) (xy 79.262986 -104.32542)
		)
		(stroke
			(width 0)
			(type solid)
		)
		(fill yes)
		(layer "F.Cu")
		(net "M_L_DQ<27>")
	)
	(gr_poly
		(pts
			(xy 79.389732 -41.71569) (xy 79.434436 -41.670732) (xy 79.344774 -41.58107) (xy 79.299816 -41.626028)
			(xy 79.174086 -41.769538) (xy 79.245968 -41.84142)
		)
		(stroke
			(width 0)
			(type solid)
		)
		(fill yes)
		(layer "F.Cu")
		(net "M_H_ECC<3>")
	)
	(gr_poly
		(pts
			(xy 79.399384 -103.955596) (xy 79.352648 -103.858568) (xy 79.316834 -103.8225) (xy 79.191104 -103.94823)
			(xy 79.226918 -103.984298) (xy 79.323946 -104.031034)
		)
		(stroke
			(width 0)
			(type solid)
		)
		(fill yes)
		(layer "F.Cu")
		(net "M_L_DQ<26>")
	)
	(gr_poly
		(pts
			(xy 79.40802 -107.99191) (xy 79.371952 -107.956096) (xy 79.228442 -107.830366) (xy 79.15656 -107.902248)
			(xy 79.28229 -108.046012) (xy 79.318104 -108.081826)
		)
		(stroke
			(width 0)
			(type solid)
		)
		(fill yes)
		(layer "F.Cu")
		(net "M_L_DQS_DN<17>")
	)
	(gr_poly
		(pts
			(xy 79.416402 -42.155872) (xy 79.542132 -42.012108) (xy 79.47025 -41.94048) (xy 79.326486 -42.06621)
			(xy 79.290672 -42.102024) (xy 79.380588 -42.19194)
		)
		(stroke
			(width 0)
			(type solid)
		)
		(fill yes)
		(layer "F.Cu")
		(net "M_H_ECC<2>")
	)
	(gr_poly
		(pts
			(xy 79.423768 -45.238416) (xy 79.459836 -45.202602) (xy 79.334106 -45.076872) (xy 79.298038 -45.112686)
			(xy 79.251302 -45.209714) (xy 79.32674 -45.285152)
		)
		(stroke
			(width 0)
			(type solid)
		)
		(fill yes)
		(layer "F.Cu")
		(net "M_H_ECC<1>")
	)
	(gr_poly
		(pts
			(xy 79.429356 -48.731424) (xy 79.465424 -48.69561) (xy 79.339694 -48.56988) (xy 79.303626 -48.605694)
			(xy 79.25689 -48.702722) (xy 79.332328 -48.77816)
		)
		(stroke
			(width 0)
			(type solid)
		)
		(fill yes)
		(layer "F.Cu")
		(net "M_H_DQ<31>")
	)
	(gr_poly
		(pts
			(xy 79.432658 -45.534834) (xy 79.479394 -45.437806) (xy 79.403956 -45.362368) (xy 79.306928 -45.409104)
			(xy 79.271114 -45.445172) (xy 79.396844 -45.570902)
		)
		(stroke
			(width 0)
			(type solid)
		)
		(fill yes)
		(layer "F.Cu")
		(net "M_H_ECC<0>")
	)
	(gr_poly
		(pts
			(xy 79.43342 -43.076114) (xy 79.39786 -42.974514) (xy 79.29118 -42.974514) (xy 79.25562 -43.076114)
			(xy 79.25562 -43.126914) (xy 79.43342 -43.126914)
		)
		(stroke
			(width 0)
			(type solid)
		)
		(fill yes)
		(layer "F.Cu")
		(net "M_H_ECC<6>")
	)
	(gr_poly
		(pts
			(xy 79.434944 -106.636058) (xy 79.309214 -106.492294) (xy 79.273146 -106.45648) (xy 79.183484 -106.546142)
			(xy 79.219298 -106.58221) (xy 79.363062 -106.70794)
		)
		(stroke
			(width 0)
			(type solid)
		)
		(fill yes)
		(layer "F.Cu")
		(net "M_L_ECC<0>")
	)
	(gr_poly
		(pts
			(xy 79.438246 -49.027842) (xy 79.484982 -48.931068) (xy 79.409544 -48.85563) (xy 79.312516 -48.902112)
			(xy 79.276702 -48.93818) (xy 79.402432 -49.06391)
		)
		(stroke
			(width 0)
			(type solid)
		)
		(fill yes)
		(layer "F.Cu")
		(net "M_H_DQ<30>")
	)
	(gr_poly
		(pts
			(xy 79.46009 -43.980862) (xy 79.496158 -43.945048) (xy 79.370428 -43.819318) (xy 79.33436 -43.855132)
			(xy 79.287624 -43.95216) (xy 79.363062 -44.027598)
		)
		(stroke
			(width 0)
			(type solid)
		)
		(fill yes)
		(layer "F.Cu")
		(net "M_H_DQS_DN<8>")
	)
	(gr_poly
		(pts
			(xy 79.46898 -44.27728) (xy 79.515716 -44.180252) (xy 79.440278 -44.104814) (xy 79.34325 -44.15155)
			(xy 79.307436 -44.187618) (xy 79.433166 -44.313348)
		)
		(stroke
			(width 0)
			(type solid)
		)
		(fill yes)
		(layer "F.Cu")
		(net "M_H_DQS_DN<17>")
	)
	(gr_poly
		(pts
			(xy 79.469488 -103.669846) (xy 79.43342 -103.634032) (xy 79.336392 -103.587296) (xy 79.260954 -103.662734)
			(xy 79.30769 -103.759762) (xy 79.343758 -103.795576)
		)
		(stroke
			(width 0)
			(type solid)
		)
		(fill yes)
		(layer "F.Cu")
		(net "M_L_DQ<26>")
	)
	(gr_poly
		(pts
			(xy 79.489046 -103.434642) (xy 79.44231 -103.337614) (xy 79.406496 -103.301546) (xy 79.280766 -103.427276)
			(xy 79.31658 -103.463344) (xy 79.413608 -103.51008)
		)
		(stroke
			(width 0)
			(type solid)
		)
		(fill yes)
		(layer "F.Cu")
		(net "M_L_DQ<31>")
	)
	(gr_poly
		(pts
			(xy 79.497428 -109.016038) (xy 79.46136 -108.980224) (xy 79.31785 -108.854494) (xy 79.245968 -108.926376)
			(xy 79.371698 -109.07014) (xy 79.407512 -109.105954)
		)
		(stroke
			(width 0)
			(type solid)
		)
		(fill yes)
		(layer "F.Cu")
		(net "M_L_DQS_DP<8>")
	)
	(gr_poly
		(pts
			(xy 79.506826 -106.2228) (xy 79.470758 -106.186986) (xy 79.326994 -106.061256) (xy 79.255366 -106.133138)
			(xy 79.381096 -106.276902) (xy 79.41691 -106.312716)
		)
		(stroke
			(width 0)
			(type solid)
		)
		(fill yes)
		(layer "F.Cu")
		(net "M_L_ECC<0>")
	)
	(gr_poly
		(pts
			(xy 79.51343 -45.75937) (xy 79.549498 -45.723556) (xy 79.423768 -45.597826) (xy 79.3877 -45.63364)
			(xy 79.340964 -45.730668) (xy 79.416402 -45.806106)
		)
		(stroke
			(width 0)
			(type solid)
		)
		(fill yes)
		(layer "F.Cu")
		(net "M_H_ECC<0>")
	)
	(gr_poly
		(pts
			(xy 79.519018 -49.252378) (xy 79.555086 -49.216564) (xy 79.429356 -49.090834) (xy 79.393288 -49.126648)
			(xy 79.346552 -49.223676) (xy 79.42199 -49.299114)
		)
		(stroke
			(width 0)
			(type solid)
		)
		(fill yes)
		(layer "F.Cu")
		(net "M_H_DQ<30>")
	)
	(gr_poly
		(pts
			(xy 79.52232 -46.055788) (xy 79.569056 -45.95876) (xy 79.493618 -45.883322) (xy 79.39659 -45.930058)
			(xy 79.360776 -45.966126) (xy 79.486506 -46.091856)
		)
		(stroke
			(width 0)
			(type solid)
		)
		(fill yes)
		(layer "F.Cu")
		(net "M_H_ECC<5>")
	)
	(gr_poly
		(pts
			(xy 79.524606 -107.659678) (xy 79.398876 -107.516168) (xy 79.363062 -107.4801) (xy 79.273146 -107.570016)
			(xy 79.309214 -107.60583) (xy 79.452724 -107.73156)
		)
		(stroke
			(width 0)
			(type solid)
		)
		(fill yes)
		(layer "F.Cu")
		(net "M_L_DQS_DP<17>")
	)
	(gr_poly
		(pts
			(xy 79.549752 -44.501816) (xy 79.58582 -44.466002) (xy 79.46009 -44.340272) (xy 79.424022 -44.376086)
			(xy 79.377286 -44.473114) (xy 79.452724 -44.548552)
		)
		(stroke
			(width 0)
			(type solid)
		)
		(fill yes)
		(layer "F.Cu")
		(net "M_H_DQS_DN<17>")
	)
	(gr_poly
		(pts
			(xy 79.55534 -47.994824) (xy 79.600298 -47.95012) (xy 79.474568 -47.82439) (xy 79.42961 -47.869094)
			(xy 79.382874 -47.966122) (xy 79.458312 -48.04156)
		)
		(stroke
			(width 0)
			(type solid)
		)
		(fill yes)
		(layer "F.Cu")
		(net "M_H_DQ<27>")
	)
	(gr_poly
		(pts
			(xy 79.558642 -44.798234) (xy 79.605378 -44.701206) (xy 79.52994 -44.625768) (xy 79.432912 -44.672504)
			(xy 79.397098 -44.708572) (xy 79.522828 -44.834302)
		)
		(stroke
			(width 0)
			(type solid)
		)
		(fill yes)
		(layer "F.Cu")
		(net "M_H_DQS_DP<17>")
	)
	(gr_poly
		(pts
			(xy 79.55915 -103.148892) (xy 79.523082 -103.113078) (xy 79.426054 -103.066342) (xy 79.350616 -103.14178)
			(xy 79.397352 -103.238808) (xy 79.43342 -103.274622)
		)
		(stroke
			(width 0)
			(type solid)
		)
		(fill yes)
		(layer "F.Cu")
		(net "M_L_DQ<31>")
	)
	(gr_poly
		(pts
			(xy 79.56423 -48.291242) (xy 79.610966 -48.194214) (xy 79.535528 -48.118776) (xy 79.4385 -48.165512)
			(xy 79.402686 -48.20158) (xy 79.528416 -48.32731)
		)
		(stroke
			(width 0)
			(type solid)
		)
		(fill yes)
		(layer "F.Cu")
		(net "M_H_DQ<26>")
	)
	(gr_poly
		(pts
			(xy 79.578454 -42.461688) (xy 79.614268 -42.42562) (xy 79.524606 -42.335958) (xy 79.488538 -42.371772)
			(xy 79.362808 -42.515536) (xy 79.43469 -42.587418)
		)
		(stroke
			(width 0)
			(type solid)
		)
		(fill yes)
		(layer "F.Cu")
		(net "M_H_ECC<2>")
	)
	(gr_poly
		(pts
			(xy 79.594964 -43.54068) (xy 79.6417 -43.443652) (xy 79.566262 -43.368214) (xy 79.469234 -43.41495)
			(xy 79.43342 -43.451018) (xy 79.558896 -43.576494)
		)
		(stroke
			(width 0)
			(type solid)
		)
		(fill yes)
		(layer "F.Cu")
		(net "M_H_DQS_DP<8>")
	)
	(gr_poly
		(pts
			(xy 79.596488 -107.246674) (xy 79.560674 -107.210606) (xy 79.41691 -107.084876) (xy 79.345028 -107.156758)
			(xy 79.470758 -107.300522) (xy 79.506826 -107.336336)
		)
		(stroke
			(width 0)
			(type solid)
		)
		(fill yes)
		(layer "F.Cu")
		(net "M_L_DQS_DP<17>")
	)
	(gr_poly
		(pts
			(xy 79.603092 -46.280324) (xy 79.63916 -46.24451) (xy 79.51343 -46.11878) (xy 79.477362 -46.154594)
			(xy 79.43088 -46.251622) (xy 79.506318 -46.32706)
		)
		(stroke
			(width 0)
			(type solid)
		)
		(fill yes)
		(layer "F.Cu")
		(net "M_H_ECC<5>")
	)
	(gr_poly
		(pts
			(xy 79.612236 -46.576742) (xy 79.658718 -46.479714) (xy 79.58328 -46.404276) (xy 79.486506 -46.451012)
			(xy 79.441548 -46.49597) (xy 79.567278 -46.6217)
		)
		(stroke
			(width 0)
			(type solid)
		)
		(fill yes)
		(layer "F.Cu")
		(net "M_H_ECC<4>")
	)
	(gr_poly
		(pts
			(xy 79.614522 -108.683552) (xy 79.488792 -108.539788) (xy 79.452724 -108.503974) (xy 79.363062 -108.593636)
			(xy 79.398876 -108.629704) (xy 79.54264 -108.755434)
		)
		(stroke
			(width 0)
			(type solid)
		)
		(fill yes)
		(layer "F.Cu")
		(net "M_L_DQS_DN<8>")
	)
	(gr_poly
		(pts
			(xy 79.623412 -105.890568) (xy 79.497682 -105.746804) (xy 79.461614 -105.71099) (xy 79.371952 -105.800652)
			(xy 79.407766 -105.83672) (xy 79.55153 -105.96245)
		)
		(stroke
			(width 0)
			(type solid)
		)
		(fill yes)
		(layer "F.Cu")
		(net "M_L_ECC<5>")
	)
	(gr_poly
		(pts
			(xy 79.639414 -45.02277) (xy 79.675482 -44.986956) (xy 79.549752 -44.861226) (xy 79.513684 -44.89704)
			(xy 79.466948 -44.994068) (xy 79.542386 -45.069506)
		)
		(stroke
			(width 0)
			(type solid)
		)
		(fill yes)
		(layer "F.Cu")
		(net "M_H_DQS_DP<17>")
	)
	(gr_poly
		(pts
			(xy 79.645002 -48.515778) (xy 79.68107 -48.479964) (xy 79.55534 -48.354234) (xy 79.519272 -48.390048)
			(xy 79.472536 -48.487076) (xy 79.547974 -48.562514)
		)
		(stroke
			(width 0)
			(type solid)
		)
		(fill yes)
		(layer "F.Cu")
		(net "M_H_DQ<26>")
	)
	(gr_poly
		(pts
			(xy 79.648304 -45.319188) (xy 79.69504 -45.22216) (xy 79.619602 -45.146722) (xy 79.522574 -45.193458)
			(xy 79.48676 -45.229526) (xy 79.61249 -45.355256)
		)
		(stroke
			(width 0)
			(type solid)
		)
		(fill yes)
		(layer "F.Cu")
		(net "M_H_ECC<1>")
	)
	(gr_poly
		(pts
			(xy 79.64932 -42.872914) (xy 79.64932 -42.822114) (xy 79.47152 -42.822114) (xy 79.47152 -42.872914)
			(xy 79.50708 -42.974514) (xy 79.61376 -42.974514)
		)
		(stroke
			(width 0)
			(type solid)
		)
		(fill yes)
		(layer "F.Cu")
		(net "M_H_ECC<7>")
	)
	(gr_poly
		(pts
			(xy 79.653892 -48.812196) (xy 79.700628 -48.715422) (xy 79.62519 -48.639984) (xy 79.528162 -48.686466)
			(xy 79.492348 -48.722534) (xy 79.618078 -48.848264)
		)
		(stroke
			(width 0)
			(type solid)
		)
		(fill yes)
		(layer "F.Cu")
		(net "M_H_DQ<31>")
	)
	(gr_poly
		(pts
			(xy 79.675736 -43.765216) (xy 79.71155 -43.729148) (xy 79.58582 -43.603418) (xy 79.550006 -43.639486)
			(xy 79.50327 -43.736514) (xy 79.578708 -43.811952)
		)
		(stroke
			(width 0)
			(type solid)
		)
		(fill yes)
		(layer "F.Cu")
		(net "M_H_DQS_DP<8>")
	)
	(gr_poly
		(pts
			(xy 79.684626 -44.061634) (xy 79.731362 -43.964606) (xy 79.655924 -43.889168) (xy 79.558896 -43.935904)
			(xy 79.523082 -43.971972) (xy 79.648558 -44.097448)
		)
		(stroke
			(width 0)
			(type solid)
		)
		(fill yes)
		(layer "F.Cu")
		(net "M_H_DQS_DN<8>")
	)
	(gr_poly
		(pts
			(xy 79.686404 -108.270294) (xy 79.650336 -108.23448) (xy 79.506826 -108.10875) (xy 79.434944 -108.180632)
			(xy 79.560674 -108.324396) (xy 79.596488 -108.36021)
		)
		(stroke
			(width 0)
			(type solid)
		)
		(fill yes)
		(layer "F.Cu")
		(net "M_L_DQS_DN<8>")
	)
	(gr_poly
		(pts
			(xy 79.694024 -103.894382) (xy 79.649066 -103.849678) (xy 79.552038 -103.802942) (xy 79.4766 -103.87838)
			(xy 79.523336 -103.975408) (xy 79.568294 -104.020112)
		)
		(stroke
			(width 0)
			(type solid)
		)
		(fill yes)
		(layer "F.Cu")
		(net "M_L_DQ<27>")
	)
	(gr_poly
		(pts
			(xy 79.695294 -105.47731) (xy 79.659226 -105.441496) (xy 79.515462 -105.315766) (xy 79.443834 -105.387648)
			(xy 79.569564 -105.531412) (xy 79.605378 -105.567226)
		)
		(stroke
			(width 0)
			(type solid)
		)
		(fill yes)
		(layer "F.Cu")
		(net "M_L_ECC<5>")
	)
	(gr_poly
		(pts
			(xy 79.704692 -103.650288) (xy 79.657956 -103.55326) (xy 79.622142 -103.517192) (xy 79.496412 -103.642922)
			(xy 79.532226 -103.67899) (xy 79.629254 -103.725726)
		)
		(stroke
			(width 0)
			(type solid)
		)
		(fill yes)
		(layer "F.Cu")
		(net "M_L_DQ<26>")
	)
	(gr_poly
		(pts
			(xy 79.713328 -106.914442) (xy 79.587598 -106.770678) (xy 79.55153 -106.734864) (xy 79.461868 -106.824526)
			(xy 79.497682 -106.860594) (xy 79.641446 -106.986324)
		)
		(stroke
			(width 0)
			(type solid)
		)
		(fill yes)
		(layer "F.Cu")
		(net "M_L_ECC<1>")
	)
	(gr_poly
		(pts
			(xy 79.715614 -51.241452) (xy 79.71536 -51.020472) (xy 79.544926 -50.931826) (xy 79.50073 -50.931826)
			(xy 79.501492 -51.330606) (xy 79.545688 -51.330606)
		)
		(stroke
			(width 0)
			(type solid)
		)
		(fill yes)
		(layer "F.Cu")
		(net "M_H_DQS_DP<3>")
	)
	(gr_poly
		(pts
			(xy 79.729076 -45.543724) (xy 79.765144 -45.50791) (xy 79.639414 -45.38218) (xy 79.603346 -45.417994)
			(xy 79.55661 -45.515022) (xy 79.632048 -45.59046)
		)
		(stroke
			(width 0)
			(type solid)
		)
		(fill yes)
		(layer "F.Cu")
		(net "M_H_ECC<1>")
	)
	(gr_poly
		(pts
			(xy 79.734664 -49.036732) (xy 79.770732 -49.000918) (xy 79.645002 -48.875188) (xy 79.608934 -48.911002)
			(xy 79.562452 -49.00803) (xy 79.63789 -49.083468)
		)
		(stroke
			(width 0)
			(type solid)
		)
		(fill yes)
		(layer "F.Cu")
		(net "M_H_DQ<31>")
	)
	(gr_poly
		(pts
			(xy 79.737966 -45.840142) (xy 79.784702 -45.743114) (xy 79.709264 -45.667676) (xy 79.612236 -45.714412)
			(xy 79.576422 -45.75048) (xy 79.702152 -45.87621)
		)
		(stroke
			(width 0)
			(type solid)
		)
		(fill yes)
		(layer "F.Cu")
		(net "M_H_ECC<0>")
	)
	(gr_poly
		(pts
			(xy 79.743554 -49.33315) (xy 79.79029 -49.236376) (xy 79.714852 -49.160938) (xy 79.617824 -49.20742)
			(xy 79.58201 -49.243488) (xy 79.70774 -49.369218)
		)
		(stroke
			(width 0)
			(type solid)
		)
		(fill yes)
		(layer "F.Cu")
		(net "M_H_DQ<30>")
	)
	(gr_poly
		(pts
			(xy 79.765398 -44.28617) (xy 79.801466 -44.250356) (xy 79.675736 -44.124626) (xy 79.639668 -44.16044)
			(xy 79.592932 -44.257468) (xy 79.66837 -44.332906)
		)
		(stroke
			(width 0)
			(type solid)
		)
		(fill yes)
		(layer "F.Cu")
		(net "M_H_DQS_DN<8>")
	)
	(gr_poly
		(pts
			(xy 79.774288 -44.582588) (xy 79.821024 -44.48556) (xy 79.745586 -44.410122) (xy 79.648558 -44.456858)
			(xy 79.612744 -44.492926) (xy 79.738474 -44.618656)
		)
		(stroke
			(width 0)
			(type solid)
		)
		(fill yes)
		(layer "F.Cu")
		(net "M_H_DQS_DN<17>")
	)
	(gr_poly
		(pts
			(xy 79.774796 -103.364538) (xy 79.738728 -103.328724) (xy 79.6417 -103.281988) (xy 79.566262 -103.357426)
			(xy 79.612998 -103.454454) (xy 79.649066 -103.490268)
		)
		(stroke
			(width 0)
			(type solid)
		)
		(fill yes)
		(layer "F.Cu")
		(net "M_L_DQ<26>")
	)
	(gr_poly
		(pts
			(xy 79.776066 -109.294168) (xy 79.740252 -109.2581) (xy 79.596488 -109.13237) (xy 79.524606 -109.204252)
			(xy 79.650336 -109.348016) (xy 79.686404 -109.38383)
		)
		(stroke
			(width 0)
			(type solid)
		)
		(fill yes)
		(layer "F.Cu")
		(net "M_L_ECC<6>")
	)
	(gr_poly
		(pts
			(xy 79.78521 -106.501184) (xy 79.749142 -106.46537) (xy 79.605378 -106.33964) (xy 79.53375 -106.411522)
			(xy 79.65948 -106.555286) (xy 79.695294 -106.5911)
		)
		(stroke
			(width 0)
			(type solid)
		)
		(fill yes)
		(layer "F.Cu")
		(net "M_L_ECC<1>")
	)
	(gr_poly
		(pts
			(xy 79.80299 -107.938062) (xy 79.67726 -107.794552) (xy 79.641446 -107.758484) (xy 79.55153 -107.8484)
			(xy 79.587598 -107.884214) (xy 79.731108 -108.009944)
		)
		(stroke
			(width 0)
			(type solid)
		)
		(fill yes)
		(layer "F.Cu")
		(net "M_L_DQS_DN<17>")
	)
	(gr_poly
		(pts
			(xy 79.81061 -43.325034) (xy 79.857346 -43.228006) (xy 79.781908 -43.152568) (xy 79.68488 -43.199304)
			(xy 79.649066 -43.235372) (xy 79.774542 -43.360848)
		)
		(stroke
			(width 0)
			(type solid)
		)
		(fill yes)
		(layer "F.Cu")
		(net "M_H_ECC<6>")
	)
	(gr_poly
		(pts
			(xy 79.81188 -105.145078) (xy 79.68615 -105.001314) (xy 79.641192 -104.95661) (xy 79.55153 -105.046272)
			(xy 79.596488 -105.09123) (xy 79.739998 -105.21696)
		)
		(stroke
			(width 0)
			(type solid)
		)
		(fill yes)
		(layer "F.Cu")
		(net "M_L_ECC<4>")
	)
	(gr_poly
		(pts
			(xy 79.818738 -46.064678) (xy 79.854806 -46.028864) (xy 79.729076 -45.903134) (xy 79.693008 -45.938948)
			(xy 79.646526 -46.035976) (xy 79.721964 -46.111414)
		)
		(stroke
			(width 0)
			(type solid)
		)
		(fill yes)
		(layer "F.Cu")
		(net "M_H_ECC<0>")
	)
	(gr_poly
		(pts
			(xy 79.827628 -46.361096) (xy 79.874364 -46.264322) (xy 79.798926 -46.188884) (xy 79.701898 -46.235366)
			(xy 79.666084 -46.271434) (xy 79.791814 -46.397164)
		)
		(stroke
			(width 0)
			(type solid)
		)
		(fill yes)
		(layer "F.Cu")
		(net "M_H_ECC<5>")
	)
	(gr_poly
		(pts
			(xy 79.85506 -44.807124) (xy 79.891128 -44.77131) (xy 79.765398 -44.64558) (xy 79.72933 -44.681394)
			(xy 79.682594 -44.778422) (xy 79.758032 -44.85386)
		)
		(stroke
			(width 0)
			(type solid)
		)
		(fill yes)
		(layer "F.Cu")
		(net "M_H_DQS_DN<17>")
	)
	(gr_poly
		(pts
			(xy 79.857092 -42.18305) (xy 79.901796 -42.138092) (xy 79.812134 -42.04843) (xy 79.767176 -42.093388)
			(xy 79.641446 -42.236898) (xy 79.713328 -42.30878)
		)
		(stroke
			(width 0)
			(type solid)
		)
		(fill yes)
		(layer "F.Cu")
		(net "M_H_ECC<3>")
	)
	(gr_poly
		(pts
			(xy 79.860648 -48.300386) (xy 79.905606 -48.255428) (xy 79.779876 -48.129698) (xy 79.734918 -48.174656)
			(xy 79.688182 -48.27143) (xy 79.76362 -48.346868)
		)
		(stroke
			(width 0)
			(type solid)
		)
		(fill yes)
		(layer "F.Cu")
		(net "M_H_DQ<27>")
	)
	(gr_poly
		(pts
			(xy 79.86395 -45.103542) (xy 79.910686 -45.006514) (xy 79.835248 -44.931076) (xy 79.73822 -44.977812)
			(xy 79.702406 -45.01388) (xy 79.828136 -45.13961)
		)
		(stroke
			(width 0)
			(type solid)
		)
		(fill yes)
		(layer "F.Cu")
		(net "M_H_DQS_DP<17>")
	)
	(gr_poly
		(pts
			(xy 79.869538 -48.59655) (xy 79.916274 -48.499776) (xy 79.840836 -48.424338) (xy 79.743808 -48.47082)
			(xy 79.707994 -48.506888) (xy 79.833724 -48.632618)
		)
		(stroke
			(width 0)
			(type solid)
		)
		(fill yes)
		(layer "F.Cu")
		(net "M_H_DQ<26>")
	)
	(gr_poly
		(pts
			(xy 79.874872 -107.525058) (xy 79.839058 -107.48899) (xy 79.695294 -107.36326) (xy 79.623412 -107.435142)
			(xy 79.749142 -107.578906) (xy 79.78521 -107.61472)
		)
		(stroke
			(width 0)
			(type solid)
		)
		(fill yes)
		(layer "F.Cu")
		(net "M_L_DQS_DN<17>")
	)
	(gr_poly
		(pts
			(xy 79.891382 -43.54957) (xy 79.927196 -43.513502) (xy 79.801466 -43.387772) (xy 79.765652 -43.42384)
			(xy 79.718916 -43.520868) (xy 79.794354 -43.596306)
		)
		(stroke
			(width 0)
			(type solid)
		)
		(fill yes)
		(layer "F.Cu")
		(net "M_H_ECC<6>")
	)
	(gr_poly
		(pts
			(xy 79.892906 -108.961936) (xy 79.767176 -108.818172) (xy 79.731108 -108.782358) (xy 79.641446 -108.87202)
			(xy 79.67726 -108.908088) (xy 79.821024 -109.033818)
		)
		(stroke
			(width 0)
			(type solid)
		)
		(fill yes)
		(layer "F.Cu")
		(net "M_L_DQS_DP<8>")
	)
	(gr_poly
		(pts
			(xy 79.900272 -43.845988) (xy 79.947008 -43.74896) (xy 79.87157 -43.673522) (xy 79.774542 -43.720258)
			(xy 79.738728 -43.756326) (xy 79.864204 -43.881802)
		)
		(stroke
			(width 0)
			(type solid)
		)
		(fill yes)
		(layer "F.Cu")
		(net "M_H_DQS_DP<8>")
	)
	(gr_poly
		(pts
			(xy 79.901796 -106.168952) (xy 79.776066 -106.025442) (xy 79.740252 -105.989374) (xy 79.650336 -106.07929)
			(xy 79.686404 -106.115104) (xy 79.829914 -106.240834)
		)
		(stroke
			(width 0)
			(type solid)
		)
		(fill yes)
		(layer "F.Cu")
		(net "M_L_ECC<0>")
	)
	(gr_poly
		(pts
			(xy 79.9084 -46.585632) (xy 79.944468 -46.549818) (xy 79.818738 -46.424088) (xy 79.78267 -46.459902)
			(xy 79.736188 -46.55693) (xy 79.811626 -46.632368)
		)
		(stroke
			(width 0)
			(type solid)
		)
		(fill yes)
		(layer "F.Cu")
		(net "M_H_ECC<5>")
	)
	(gr_poly
		(pts
			(xy 79.917544 -46.88205) (xy 79.96428 -46.785022) (xy 79.888842 -46.709584) (xy 79.791814 -46.75632)
			(xy 79.746856 -46.801278) (xy 79.872586 -46.927008)
		)
		(stroke
			(width 0)
			(type solid)
		)
		(fill yes)
		(layer "F.Cu")
		(net "M_H_ECC<4>")
	)
	(gr_poly
		(pts
			(xy 79.944722 -45.328078) (xy 79.98079 -45.292264) (xy 79.85506 -45.166534) (xy 79.818992 -45.202348)
			(xy 79.772256 -45.299376) (xy 79.847694 -45.374814)
		)
		(stroke
			(width 0)
			(type solid)
		)
		(fill yes)
		(layer "F.Cu")
		(net "M_H_DQS_DP<17>")
	)
	(gr_poly
		(pts
			(xy 79.953612 -45.624496) (xy 80.000348 -45.527468) (xy 79.92491 -45.45203) (xy 79.827882 -45.498766)
			(xy 79.792068 -45.534834) (xy 79.917798 -45.660564)
		)
		(stroke
			(width 0)
			(type solid)
		)
		(fill yes)
		(layer "F.Cu")
		(net "M_H_ECC<1>")
	)
	(gr_poly
		(pts
			(xy 79.9592 -49.117504) (xy 80.005936 -49.02073) (xy 79.930498 -48.945292) (xy 79.83347 -48.991774)
			(xy 79.797656 -49.027842) (xy 79.923386 -49.153572)
		)
		(stroke
			(width 0)
			(type solid)
		)
		(fill yes)
		(layer "F.Cu")
		(net "M_H_DQ<31>")
	)
	(gr_poly
		(pts
			(xy 79.964788 -108.548678) (xy 79.92872 -108.512864) (xy 79.78521 -108.387134) (xy 79.713328 -108.459016)
			(xy 79.839058 -108.60278) (xy 79.874872 -108.638594)
		)
		(stroke
			(width 0)
			(type solid)
		)
		(fill yes)
		(layer "F.Cu")
		(net "M_L_DQS_DP<8>")
	)
	(gr_poly
		(pts
			(xy 79.973678 -105.755948) (xy 79.937864 -105.720134) (xy 79.7941 -105.594404) (xy 79.722218 -105.666032)
			(xy 79.847948 -105.809796) (xy 79.884016 -105.84561)
		)
		(stroke
			(width 0)
			(type solid)
		)
		(fill yes)
		(layer "F.Cu")
		(net "M_L_ECC<0>")
	)
	(gr_poly
		(pts
			(xy 79.981044 -44.070524) (xy 80.017112 -44.03471) (xy 79.891382 -43.90898) (xy 79.855314 -43.944794)
			(xy 79.808578 -44.041822) (xy 79.884016 -44.11726)
		)
		(stroke
			(width 0)
			(type solid)
		)
		(fill yes)
		(layer "F.Cu")
		(net "M_H_DQS_DP<8>")
	)
	(gr_poly
		(pts
			(xy 79.982568 -109.985556) (xy 79.856838 -109.842046) (xy 79.821024 -109.805978) (xy 79.731108 -109.895894)
			(xy 79.767176 -109.931708) (xy 79.910686 -110.057438)
		)
		(stroke
			(width 0)
			(type solid)
		)
		(fill yes)
		(layer "F.Cu")
		(net "M_L_ECC<7>")
	)
	(gr_poly
		(pts
			(xy 79.989934 -44.366942) (xy 80.03667 -44.269914) (xy 79.961232 -44.194476) (xy 79.864204 -44.241212)
			(xy 79.82839 -44.27728) (xy 79.95412 -44.40301)
		)
		(stroke
			(width 0)
			(type solid)
		)
		(fill yes)
		(layer "F.Cu")
		(net "M_H_DQS_DN<8>")
	)
	(gr_poly
		(pts
			(xy 79.991712 -107.192826) (xy 79.865982 -107.049062) (xy 79.829914 -107.013248) (xy 79.740252 -107.10291)
			(xy 79.776066 -107.138978) (xy 79.91983 -107.264708)
		)
		(stroke
			(width 0)
			(type solid)
		)
		(fill yes)
		(layer "F.Cu")
		(net "M_L_DQS_DP<17>")
	)
	(gr_poly
		(pts
			(xy 79.999332 -103.589074) (xy 79.954374 -103.54437) (xy 79.857346 -103.497634) (xy 79.781908 -103.573072)
			(xy 79.828644 -103.6701) (xy 79.873602 -103.714804)
		)
		(stroke
			(width 0)
			(type solid)
		)
		(fill yes)
		(layer "F.Cu")
		(net "M_L_DQ<27>")
	)
	(gr_poly
		(pts
			(xy 80.017366 -42.81297) (xy 80.05318 -42.776902) (xy 79.92745 -42.651172) (xy 79.891636 -42.68724)
			(xy 79.8449 -42.784268) (xy 79.920338 -42.859706)
		)
		(stroke
			(width 0)
			(type solid)
		)
		(fill yes)
		(layer "F.Cu")
		(net "M_H_ECC<2>")
	)
	(gr_poly
		(pts
			(xy 80.026256 -43.109388) (xy 80.072992 -43.01236) (xy 79.997554 -42.936922) (xy 79.900526 -42.983658)
			(xy 79.864458 -43.019472) (xy 79.990188 -43.145202)
		)
		(stroke
			(width 0)
			(type solid)
		)
		(fill yes)
		(layer "F.Cu")
		(net "M_H_ECC<7>")
	)
	(gr_poly
		(pts
			(xy 80.034384 -45.849032) (xy 80.070452 -45.813218) (xy 79.944722 -45.687488) (xy 79.908654 -45.723302)
			(xy 79.862172 -45.82033) (xy 79.93761 -45.895768)
		)
		(stroke
			(width 0)
			(type solid)
		)
		(fill yes)
		(layer "F.Cu")
		(net "M_H_ECC<1>")
	)
	(gr_poly
		(pts
			(xy 80.039972 -49.34204) (xy 80.07604 -49.306226) (xy 79.95031 -49.180496) (xy 79.914242 -49.21631)
			(xy 79.86776 -49.313338) (xy 79.943198 -49.388776)
		)
		(stroke
			(width 0)
			(type solid)
		)
		(fill yes)
		(layer "F.Cu")
		(net "M_H_DQ<31>")
	)
	(gr_poly
		(pts
			(xy 80.043274 -46.14545) (xy 80.09001 -46.048676) (xy 80.014572 -45.973238) (xy 79.917544 -46.01972)
			(xy 79.88173 -46.055788) (xy 80.00746 -46.181518)
		)
		(stroke
			(width 0)
			(type solid)
		)
		(fill yes)
		(layer "F.Cu")
		(net "M_H_ECC<0>")
	)
	(gr_poly
		(pts
			(xy 80.05445 -109.572552) (xy 80.018636 -109.536484) (xy 79.874872 -109.410754) (xy 79.80299 -109.482636)
			(xy 79.92872 -109.6264) (xy 79.964788 -109.662214)
		)
		(stroke
			(width 0)
			(type solid)
		)
		(fill yes)
		(layer "F.Cu")
		(net "M_L_ECC<7>")
	)
	(gr_poly
		(pts
			(xy 80.063594 -106.779568) (xy 80.027526 -106.743754) (xy 79.883762 -106.618024) (xy 79.812134 -106.689906)
			(xy 79.937864 -106.83367) (xy 79.973678 -106.869484)
		)
		(stroke
			(width 0)
			(type solid)
		)
		(fill yes)
		(layer "F.Cu")
		(net "M_L_DQS_DP<17>")
	)
	(gr_poly
		(pts
			(xy 80.070706 -44.591478) (xy 80.106774 -44.555664) (xy 79.981044 -44.429934) (xy 79.944976 -44.465748)
			(xy 79.89824 -44.562776) (xy 79.973678 -44.638214)
		)
		(stroke
			(width 0)
			(type solid)
		)
		(fill yes)
		(layer "F.Cu")
		(net "M_H_DQS_DN<8>")
	)
	(gr_poly
		(pts
			(xy 80.079596 -44.887896) (xy 80.126332 -44.790868) (xy 80.050894 -44.71543) (xy 79.953866 -44.762166)
			(xy 79.918052 -44.798234) (xy 80.043782 -44.923964)
		)
		(stroke
			(width 0)
			(type solid)
		)
		(fill yes)
		(layer "F.Cu")
		(net "M_H_DQS_DN<17>")
	)
	(gr_poly
		(pts
			(xy 80.081374 -108.216446) (xy 79.955644 -108.072936) (xy 79.91983 -108.036868) (xy 79.829914 -108.126784)
			(xy 79.865982 -108.162598) (xy 80.009492 -108.288328)
		)
		(stroke
			(width 0)
			(type solid)
		)
		(fill yes)
		(layer "F.Cu")
		(net "M_L_DQS_DN<8>")
	)
	(gr_poly
		(pts
			(xy 80.090264 -105.423462) (xy 79.964534 -105.279952) (xy 79.92872 -105.243884) (xy 79.838804 -105.3338)
			(xy 79.874872 -105.369614) (xy 80.018382 -105.495344)
		)
		(stroke
			(width 0)
			(type solid)
		)
		(fill yes)
		(layer "F.Cu")
		(net "M_L_ECC<5>")
	)
	(gr_poly
		(pts
			(xy 80.107028 -43.333924) (xy 80.142842 -43.297856) (xy 80.017112 -43.172126) (xy 79.981298 -43.208194)
			(xy 79.934562 -43.305222) (xy 80.01 -43.38066)
		)
		(stroke
			(width 0)
			(type solid)
		)
		(fill yes)
		(layer "F.Cu")
		(net "M_H_ECC<7>")
	)
	(gr_poly
		(pts
			(xy 80.115918 -43.630342) (xy 80.162654 -43.533314) (xy 80.087216 -43.457876) (xy 79.990188 -43.504612)
			(xy 79.954374 -43.54068) (xy 80.07985 -43.666156)
		)
		(stroke
			(width 0)
			(type solid)
		)
		(fill yes)
		(layer "F.Cu")
		(net "M_H_ECC<6>")
	)
	(gr_poly
		(pts
			(xy 80.124046 -46.369986) (xy 80.160114 -46.334172) (xy 80.034384 -46.208442) (xy 79.998316 -46.244256)
			(xy 79.951834 -46.341284) (xy 80.027272 -46.416722)
		)
		(stroke
			(width 0)
			(type solid)
		)
		(fill yes)
		(layer "F.Cu")
		(net "M_H_ECC<0>")
	)
	(gr_poly
		(pts
			(xy 80.132936 -46.666404) (xy 80.179672 -46.56963) (xy 80.104234 -46.494192) (xy 80.007206 -46.540928)
			(xy 79.971392 -46.576742) (xy 80.097122 -46.702472)
		)
		(stroke
			(width 0)
			(type solid)
		)
		(fill yes)
		(layer "F.Cu")
		(net "M_H_ECC<5>")
	)
	(gr_poly
		(pts
			(xy 80.153256 -107.803442) (xy 80.117442 -107.767374) (xy 79.973678 -107.641644) (xy 79.901796 -107.713526)
			(xy 80.027526 -107.85729) (xy 80.063594 -107.893104)
		)
		(stroke
			(width 0)
			(type solid)
		)
		(fill yes)
		(layer "F.Cu")
		(net "M_L_DQS_DN<8>")
	)
	(gr_poly
		(pts
			(xy 80.160368 -45.112432) (xy 80.196436 -45.076618) (xy 80.070706 -44.950888) (xy 80.034638 -44.986702)
			(xy 79.987902 -45.08373) (xy 80.06334 -45.159168)
		)
		(stroke
			(width 0)
			(type solid)
		)
		(fill yes)
		(layer "F.Cu")
		(net "M_H_DQS_DN<17>")
	)
	(gr_poly
		(pts
			(xy 80.162146 -105.010458) (xy 80.126332 -104.974644) (xy 79.982568 -104.848914) (xy 79.910686 -104.920542)
			(xy 80.036416 -105.064306) (xy 80.07223 -105.100374)
		)
		(stroke
			(width 0)
			(type solid)
		)
		(fill yes)
		(layer "F.Cu")
		(net "M_L_ECC<5>")
	)
	(gr_poly
		(pts
			(xy 80.169258 -45.40885) (xy 80.215994 -45.311822) (xy 80.140556 -45.236384) (xy 80.043528 -45.28312)
			(xy 80.007714 -45.319188) (xy 80.133444 -45.444918)
		)
		(stroke
			(width 0)
			(type solid)
		)
		(fill yes)
		(layer "F.Cu")
		(net "M_H_DQS_DP<17>")
	)
	(gr_poly
		(pts
			(xy 80.17129 -109.24032) (xy 80.04556 -109.096556) (xy 80.009492 -109.060742) (xy 79.91983 -109.150404)
			(xy 79.955644 -109.186472) (xy 80.099408 -109.312202)
		)
		(stroke
			(width 0)
			(type solid)
		)
		(fill yes)
		(layer "F.Cu")
		(net "M_L_ECC<6>")
	)
	(gr_poly
		(pts
			(xy 80.18018 -106.447336) (xy 80.05445 -106.303826) (xy 80.018636 -106.267758) (xy 79.92872 -106.357674)
			(xy 79.964788 -106.393488) (xy 80.108298 -106.519218)
		)
		(stroke
			(width 0)
			(type solid)
		)
		(fill yes)
		(layer "F.Cu")
		(net "M_L_ECC<1>")
	)
	(gr_poly
		(pts
			(xy 80.19669 -43.854878) (xy 80.232758 -43.819064) (xy 80.107028 -43.693334) (xy 80.07096 -43.729148)
			(xy 80.024224 -43.826176) (xy 80.099662 -43.901614)
		)
		(stroke
			(width 0)
			(type solid)
		)
		(fill yes)
		(layer "F.Cu")
		(net "M_H_ECC<6>")
	)
	(gr_poly
		(pts
			(xy 80.20558 -44.151296) (xy 80.252316 -44.054268) (xy 80.176878 -43.97883) (xy 80.07985 -44.025566)
			(xy 80.044036 -44.061634) (xy 80.169766 -44.187364)
		)
		(stroke
			(width 0)
			(type solid)
		)
		(fill yes)
		(layer "F.Cu")
		(net "M_H_DQS_DP<8>")
	)
	(gr_poly
		(pts
			(xy 80.213962 -46.89094) (xy 80.249776 -46.855126) (xy 80.124046 -46.729396) (xy 80.088232 -46.76521)
			(xy 80.041496 -46.862238) (xy 80.116934 -46.937676)
		)
		(stroke
			(width 0)
			(type solid)
		)
		(fill yes)
		(layer "F.Cu")
		(net "M_H_ECC<5>")
	)
	(gr_poly
		(pts
			(xy 80.222852 -47.187358) (xy 80.269588 -47.09033) (xy 80.19415 -47.014892) (xy 80.097122 -47.061628)
			(xy 80.052164 -47.106586) (xy 80.177894 -47.232316)
		)
		(stroke
			(width 0)
			(type solid)
		)
		(fill yes)
		(layer "F.Cu")
		(net "M_H_ECC<4>")
	)
	(gr_poly
		(pts
			(xy 80.233012 -42.597324) (xy 80.277716 -42.552366) (xy 80.151986 -42.426636) (xy 80.107282 -42.471594)
			(xy 80.060546 -42.568622) (xy 80.135984 -42.64406)
		)
		(stroke
			(width 0)
			(type solid)
		)
		(fill yes)
		(layer "F.Cu")
		(net "M_H_ECC<3>")
	)
	(gr_poly
		(pts
			(xy 80.241902 -42.893742) (xy 80.288638 -42.796714) (xy 80.2132 -42.721276) (xy 80.116172 -42.768012)
			(xy 80.080104 -42.803826) (xy 80.205834 -42.929556)
		)
		(stroke
			(width 0)
			(type solid)
		)
		(fill yes)
		(layer "F.Cu")
		(net "M_H_ECC<2>")
	)
	(gr_poly
		(pts
			(xy 80.243172 -108.827062) (xy 80.207104 -108.791248) (xy 80.063594 -108.665518) (xy 79.991712 -108.7374)
			(xy 80.117442 -108.881164) (xy 80.153256 -108.916978)
		)
		(stroke
			(width 0)
			(type solid)
		)
		(fill yes)
		(layer "F.Cu")
		(net "M_L_ECC<6>")
	)
	(gr_poly
		(pts
			(xy 80.25003 -45.633386) (xy 80.286098 -45.597572) (xy 80.160368 -45.471842) (xy 80.1243 -45.507656)
			(xy 80.077818 -45.604684) (xy 80.153256 -45.680122)
		)
		(stroke
			(width 0)
			(type solid)
		)
		(fill yes)
		(layer "F.Cu")
		(net "M_H_DQS_DP<17>")
	)
	(gr_poly
		(pts
			(xy 80.252062 -106.034332) (xy 80.216248 -105.998518) (xy 80.072484 -105.872788) (xy 80.000602 -105.944416)
			(xy 80.126332 -106.08818) (xy 80.1624 -106.123994)
		)
		(stroke
			(width 0)
			(type solid)
		)
		(fill yes)
		(layer "F.Cu")
		(net "M_L_ECC<1>")
	)
	(gr_poly
		(pts
			(xy 80.25892 -45.929804) (xy 80.305656 -45.83303) (xy 80.230218 -45.757592) (xy 80.13319 -45.804074)
			(xy 80.097376 -45.840142) (xy 80.223106 -45.965872)
		)
		(stroke
			(width 0)
			(type solid)
		)
		(fill yes)
		(layer "F.Cu")
		(net "M_H_ECC<1>")
	)
	(gr_poly
		(pts
			(xy 80.270096 -107.47121) (xy 80.144366 -107.327446) (xy 80.108298 -107.291632) (xy 80.018636 -107.381294)
			(xy 80.05445 -107.417362) (xy 80.198214 -107.543092)
		)
		(stroke
			(width 0)
			(type solid)
		)
		(fill yes)
		(layer "F.Cu")
		(net "M_L_DQS_DN<17>")
	)
	(gr_poly
		(pts
			(xy 80.278986 -104.678226) (xy 80.153256 -104.534462) (xy 80.108298 -104.489504) (xy 80.018382 -104.57942)
			(xy 80.06334 -104.624378) (xy 80.207104 -104.750108)
		)
		(stroke
			(width 0)
			(type solid)
		)
		(fill yes)
		(layer "F.Cu")
		(net "M_L_ECC<4>")
	)
	(gr_poly
		(pts
			(xy 80.286352 -44.375832) (xy 80.32242 -44.340018) (xy 80.19669 -44.214288) (xy 80.160622 -44.250102)
			(xy 80.113886 -44.34713) (xy 80.189324 -44.422568)
		)
		(stroke
			(width 0)
			(type solid)
		)
		(fill yes)
		(layer "F.Cu")
		(net "M_H_DQS_DP<8>")
	)
	(gr_poly
		(pts
			(xy 80.295242 -44.67225) (xy 80.341978 -44.575222) (xy 80.26654 -44.499784) (xy 80.169512 -44.54652)
			(xy 80.133698 -44.582588) (xy 80.259428 -44.708318)
		)
		(stroke
			(width 0)
			(type solid)
		)
		(fill yes)
		(layer "F.Cu")
		(net "M_H_DQS_DN<8>")
	)
	(gr_poly
		(pts
			(xy 80.322674 -43.118278) (xy 80.358488 -43.08221) (xy 80.232758 -42.95648) (xy 80.196944 -42.992548)
			(xy 80.150208 -43.089576) (xy 80.225646 -43.165014)
		)
		(stroke
			(width 0)
			(type solid)
		)
		(fill yes)
		(layer "F.Cu")
		(net "M_H_ECC<2>")
	)
	(gr_poly
		(pts
			(xy 80.331564 -43.414696) (xy 80.3783 -43.317668) (xy 80.302862 -43.24223) (xy 80.205834 -43.288966)
			(xy 80.17002 -43.325034) (xy 80.295496 -43.45051)
		)
		(stroke
			(width 0)
			(type solid)
		)
		(fill yes)
		(layer "F.Cu")
		(net "M_H_ECC<7>")
	)
	(gr_poly
		(pts
			(xy 80.332834 -109.850936) (xy 80.29702 -109.814868) (xy 80.153256 -109.689138) (xy 80.081374 -109.76102)
			(xy 80.207104 -109.904784) (xy 80.243172 -109.940598)
		)
		(stroke
			(width 0)
			(type solid)
		)
		(fill yes)
		(layer "F.Cu")
		(net "M_L_ECC<2>")
	)
	(gr_poly
		(pts
			(xy 80.339692 -46.15434) (xy 80.37576 -46.118526) (xy 80.25003 -45.992796) (xy 80.213962 -46.02861)
			(xy 80.16748 -46.125638) (xy 80.242918 -46.201076)
		)
		(stroke
			(width 0)
			(type solid)
		)
		(fill yes)
		(layer "F.Cu")
		(net "M_H_ECC<1>")
	)
	(gr_poly
		(pts
			(xy 80.341978 -107.057952) (xy 80.30591 -107.022138) (xy 80.162146 -106.896408) (xy 80.090518 -106.96829)
			(xy 80.216248 -107.112054) (xy 80.252062 -107.147868)
		)
		(stroke
			(width 0)
			(type solid)
		)
		(fill yes)
		(layer "F.Cu")
		(net "M_L_DQS_DN<17>")
	)
	(gr_poly
		(pts
			(xy 80.348582 -46.450758) (xy 80.395318 -46.353984) (xy 80.31988 -46.278546) (xy 80.222852 -46.325282)
			(xy 80.187038 -46.361096) (xy 80.312768 -46.486826)
		)
		(stroke
			(width 0)
			(type solid)
		)
		(fill yes)
		(layer "F.Cu")
		(net "M_H_ECC<0>")
	)
	(gr_poly
		(pts
			(xy 80.359758 -108.49483) (xy 80.234028 -108.35132) (xy 80.198214 -108.315252) (xy 80.108298 -108.405168)
			(xy 80.144366 -108.440982) (xy 80.287876 -108.566712)
		)
		(stroke
			(width 0)
			(type solid)
		)
		(fill yes)
		(layer "F.Cu")
		(net "M_L_DQS_DP<8>")
	)
	(gr_poly
		(pts
			(xy 80.368902 -105.7021) (xy 80.243172 -105.558336) (xy 80.207104 -105.522522) (xy 80.117442 -105.612184)
			(xy 80.153256 -105.648252) (xy 80.29702 -105.773982)
		)
		(stroke
			(width 0)
			(type solid)
		)
		(fill yes)
		(layer "F.Cu")
		(net "M_L_ECC<0>")
	)
	(gr_poly
		(pts
			(xy 80.376014 -44.896786) (xy 80.412082 -44.860972) (xy 80.286352 -44.735242) (xy 80.250284 -44.771056)
			(xy 80.203548 -44.868084) (xy 80.278986 -44.943522)
		)
		(stroke
			(width 0)
			(type solid)
		)
		(fill yes)
		(layer "F.Cu")
		(net "M_H_DQS_DN<8>")
	)
	(gr_poly
		(pts
			(xy 80.384904 -45.193204) (xy 80.43164 -45.096176) (xy 80.356202 -45.020738) (xy 80.259174 -45.067474)
			(xy 80.22336 -45.103542) (xy 80.34909 -45.229272)
		)
		(stroke
			(width 0)
			(type solid)
		)
		(fill yes)
		(layer "F.Cu")
		(net "M_H_DQS_DN<17>")
	)
	(gr_poly
		(pts
			(xy 80.412336 -43.639232) (xy 80.448404 -43.603418) (xy 80.322674 -43.477688) (xy 80.286606 -43.513502)
			(xy 80.23987 -43.61053) (xy 80.315308 -43.685968)
		)
		(stroke
			(width 0)
			(type solid)
		)
		(fill yes)
		(layer "F.Cu")
		(net "M_H_ECC<7>")
	)
	(gr_poly
		(pts
			(xy 80.421226 -43.93565) (xy 80.467962 -43.838622) (xy 80.392524 -43.763184) (xy 80.295496 -43.80992)
			(xy 80.259682 -43.845988) (xy 80.385412 -43.971718)
		)
		(stroke
			(width 0)
			(type solid)
		)
		(fill yes)
		(layer "F.Cu")
		(net "M_H_ECC<6>")
	)
	(gr_poly
		(pts
			(xy 80.429608 -46.675294) (xy 80.465422 -46.63948) (xy 80.339692 -46.51375) (xy 80.303878 -46.549564)
			(xy 80.257142 -46.646592) (xy 80.33258 -46.72203)
		)
		(stroke
			(width 0)
			(type solid)
		)
		(fill yes)
		(layer "F.Cu")
		(net "M_H_ECC<0>")
	)
	(gr_poly
		(pts
			(xy 80.43164 -108.081826) (xy 80.395826 -108.045758) (xy 80.252062 -107.920028) (xy 80.18018 -107.99191)
			(xy 80.30591 -108.135674) (xy 80.341978 -108.171488)
		)
		(stroke
			(width 0)
			(type solid)
		)
		(fill yes)
		(layer "F.Cu")
		(net "M_L_DQS_DP<8>")
	)
	(gr_poly
		(pts
			(xy 80.438244 -46.971966) (xy 80.48498 -46.874938) (xy 80.409542 -46.7995) (xy 80.312514 -46.846236)
			(xy 80.2767 -46.88205) (xy 80.40243 -47.00778)
		)
		(stroke
			(width 0)
			(type solid)
		)
		(fill yes)
		(layer "F.Cu")
		(net "M_H_ECC<5>")
	)
	(gr_poly
		(pts
			(xy 80.440784 -105.288842) (xy 80.404716 -105.253028) (xy 80.260952 -105.127298) (xy 80.189324 -105.19918)
			(xy 80.315054 -105.342944) (xy 80.350868 -105.378758)
		)
		(stroke
			(width 0)
			(type solid)
		)
		(fill yes)
		(layer "F.Cu")
		(net "M_L_ECC<0>")
	)
	(gr_poly
		(pts
			(xy 80.449674 -109.518704) (xy 80.323944 -109.37494) (xy 80.287876 -109.339126) (xy 80.198214 -109.428788)
			(xy 80.234028 -109.464856) (xy 80.377792 -109.590586)
		)
		(stroke
			(width 0)
			(type solid)
		)
		(fill yes)
		(layer "F.Cu")
		(net "M_L_ECC<7>")
	)
	(gr_poly
		(pts
			(xy 80.458564 -106.72572) (xy 80.332834 -106.58221) (xy 80.29702 -106.546142) (xy 80.207104 -106.636058)
			(xy 80.243172 -106.671872) (xy 80.386682 -106.797602)
		)
		(stroke
			(width 0)
			(type solid)
		)
		(fill yes)
		(layer "F.Cu")
		(net "M_L_DQS_DP<17>")
	)
	(gr_poly
		(pts
			(xy 80.465676 -45.41774) (xy 80.501744 -45.381926) (xy 80.376014 -45.256196) (xy 80.339946 -45.29201)
			(xy 80.293464 -45.389038) (xy 80.368902 -45.464476)
		)
		(stroke
			(width 0)
			(type solid)
		)
		(fill yes)
		(layer "F.Cu")
		(net "M_H_DQS_DN<17>")
	)
	(gr_poly
		(pts
			(xy 80.474566 -45.714158) (xy 80.521302 -45.617384) (xy 80.445864 -45.541946) (xy 80.348836 -45.588428)
			(xy 80.313022 -45.624496) (xy 80.438752 -45.750226)
		)
		(stroke
			(width 0)
			(type solid)
		)
		(fill yes)
		(layer "F.Cu")
		(net "M_H_DQS_DP<17>")
	)
	(gr_poly
		(pts
			(xy 80.501998 -44.160186) (xy 80.538066 -44.124372) (xy 80.412336 -43.998642) (xy 80.376268 -44.034456)
			(xy 80.329532 -44.131484) (xy 80.40497 -44.206922)
		)
		(stroke
			(width 0)
			(type solid)
		)
		(fill yes)
		(layer "F.Cu")
		(net "M_H_ECC<6>")
	)
	(gr_poly
		(pts
			(xy 80.510888 -44.456604) (xy 80.557624 -44.359576) (xy 80.482186 -44.284138) (xy 80.385158 -44.330874)
			(xy 80.349344 -44.366942) (xy 80.475074 -44.492672)
		)
		(stroke
			(width 0)
			(type solid)
		)
		(fill yes)
		(layer "F.Cu")
		(net "M_H_DQS_DP<8>")
	)
	(gr_poly
		(pts
			(xy 80.51927 -47.196248) (xy 80.555084 -47.160434) (xy 80.429354 -47.034704) (xy 80.39354 -47.070518)
			(xy 80.346804 -47.167546) (xy 80.422242 -47.242984)
		)
		(stroke
			(width 0)
			(type solid)
		)
		(fill yes)
		(layer "F.Cu")
		(net "M_H_ECC<5>")
	)
	(gr_poly
		(pts
			(xy 80.521556 -109.105446) (xy 80.485488 -109.069632) (xy 80.341978 -108.943902) (xy 80.270096 -109.015784)
			(xy 80.395826 -109.159548) (xy 80.43164 -109.195362)
		)
		(stroke
			(width 0)
			(type solid)
		)
		(fill yes)
		(layer "F.Cu")
		(net "M_L_ECC<7>")
	)
	(gr_poly
		(pts
			(xy 80.52816 -47.492666) (xy 80.574896 -47.395638) (xy 80.499458 -47.3202) (xy 80.40243 -47.366936)
			(xy 80.357472 -47.411894) (xy 80.483202 -47.537624)
		)
		(stroke
			(width 0)
			(type solid)
		)
		(fill yes)
		(layer "F.Cu")
		(net "M_H_ECC<4>")
	)
	(gr_poly
		(pts
			(xy 80.530446 -106.312716) (xy 80.494632 -106.276902) (xy 80.350868 -106.151172) (xy 80.278986 -106.2228)
			(xy 80.404716 -106.366564) (xy 80.440784 -106.402378)
		)
		(stroke
			(width 0)
			(type solid)
		)
		(fill yes)
		(layer "F.Cu")
		(net "M_L_DQS_DP<17>")
	)
	(gr_poly
		(pts
			(xy 80.53832 -42.902632) (xy 80.583024 -42.857674) (xy 80.457294 -42.731944) (xy 80.41259 -42.776902)
			(xy 80.365854 -42.87393) (xy 80.441292 -42.949368)
		)
		(stroke
			(width 0)
			(type solid)
		)
		(fill yes)
		(layer "F.Cu")
		(net "M_H_ECC<3>")
	)
	(gr_poly
		(pts
			(xy 80.54721 -43.19905) (xy 80.593946 -43.102022) (xy 80.518508 -43.026584) (xy 80.42148 -43.07332)
			(xy 80.385666 -43.109388) (xy 80.511142 -43.234864)
		)
		(stroke
			(width 0)
			(type solid)
		)
		(fill yes)
		(layer "F.Cu")
		(net "M_H_ECC<2>")
	)
	(gr_poly
		(pts
			(xy 80.54848 -107.749594) (xy 80.42275 -107.60583) (xy 80.386682 -107.570016) (xy 80.29702 -107.659678)
			(xy 80.332834 -107.695746) (xy 80.476598 -107.821476)
		)
		(stroke
			(width 0)
			(type solid)
		)
		(fill yes)
		(layer "F.Cu")
		(net "M_L_DQS_DN<8>")
	)
	(gr_poly
		(pts
			(xy 80.555338 -45.938694) (xy 80.591406 -45.90288) (xy 80.465676 -45.77715) (xy 80.429608 -45.812964)
			(xy 80.383126 -45.909992) (xy 80.458564 -45.98543)
		)
		(stroke
			(width 0)
			(type solid)
		)
		(fill yes)
		(layer "F.Cu")
		(net "M_H_DQS_DP<17>")
	)
	(gr_poly
		(pts
			(xy 80.55737 -104.95661) (xy 80.43164 -104.812846) (xy 80.395572 -104.777032) (xy 80.30591 -104.866694)
			(xy 80.341724 -104.902762) (xy 80.485488 -105.028492)
		)
		(stroke
			(width 0)
			(type solid)
		)
		(fill yes)
		(layer "F.Cu")
		(net "M_L_ECC<5>")
	)
	(gr_poly
		(pts
			(xy 80.564228 -46.235112) (xy 80.610964 -46.138338) (xy 80.535526 -46.0629) (xy 80.438498 -46.109636)
			(xy 80.402684 -46.14545) (xy 80.528414 -46.27118)
		)
		(stroke
			(width 0)
			(type solid)
		)
		(fill yes)
		(layer "F.Cu")
		(net "M_H_ECC<1>")
	)
	(gr_poly
		(pts
			(xy 80.59166 -44.68114) (xy 80.627728 -44.645326) (xy 80.501998 -44.519596) (xy 80.46593 -44.55541)
			(xy 80.419194 -44.652438) (xy 80.494632 -44.727876)
		)
		(stroke
			(width 0)
			(type solid)
		)
		(fill yes)
		(layer "F.Cu")
		(net "M_H_DQS_DP<8>")
	)
	(gr_poly
		(pts
			(xy 80.60055 -44.977558) (xy 80.647286 -44.88053) (xy 80.571848 -44.805092) (xy 80.47482 -44.851828)
			(xy 80.439006 -44.887896) (xy 80.564736 -45.013626)
		)
		(stroke
			(width 0)
			(type solid)
		)
		(fill yes)
		(layer "F.Cu")
		(net "M_H_DQS_DN<8>")
	)
	(gr_poly
		(pts
			(xy 80.620362 -110.137956) (xy 80.575404 -110.092998) (xy 80.431894 -109.967268) (xy 80.360012 -110.03915)
			(xy 80.485742 -110.182914) (xy 80.5307 -110.227618)
		)
		(stroke
			(width 0)
			(type solid)
		)
		(fill yes)
		(layer "F.Cu")
		(net "M_L_ECC<3>")
	)
	(gr_poly
		(pts
			(xy 80.620362 -107.336336) (xy 80.584294 -107.300522) (xy 80.44053 -107.174792) (xy 80.368902 -107.246674)
			(xy 80.494632 -107.390438) (xy 80.530446 -107.426252)
		)
		(stroke
			(width 0)
			(type solid)
		)
		(fill yes)
		(layer "F.Cu")
		(net "M_L_DQS_DN<8>")
	)
	(gr_poly
		(pts
			(xy 80.627982 -43.423586) (xy 80.66405 -43.387772) (xy 80.53832 -43.262042) (xy 80.502252 -43.297856)
			(xy 80.455516 -43.394884) (xy 80.530954 -43.470322)
		)
		(stroke
			(width 0)
			(type solid)
		)
		(fill yes)
		(layer "F.Cu")
		(net "M_H_ECC<2>")
	)
	(gr_poly
		(pts
			(xy 80.629252 -104.543352) (xy 80.593184 -104.507538) (xy 80.44942 -104.381808) (xy 80.377792 -104.45369)
			(xy 80.503522 -104.597454) (xy 80.539336 -104.633268)
		)
		(stroke
			(width 0)
			(type solid)
		)
		(fill yes)
		(layer "F.Cu")
		(net "M_L_ECC<5>")
	)
	(gr_poly
		(pts
			(xy 80.636872 -43.720004) (xy 80.683608 -43.622976) (xy 80.60817 -43.547538) (xy 80.511142 -43.594274)
			(xy 80.475328 -43.630342) (xy 80.601058 -43.756072)
		)
		(stroke
			(width 0)
			(type solid)
		)
		(fill yes)
		(layer "F.Cu")
		(net "M_H_ECC<7>")
	)
	(gr_poly
		(pts
			(xy 80.638142 -108.773214) (xy 80.512412 -108.629704) (xy 80.476598 -108.593636) (xy 80.386682 -108.683552)
			(xy 80.42275 -108.719366) (xy 80.56626 -108.845096)
		)
		(stroke
			(width 0)
			(type solid)
		)
		(fill yes)
		(layer "F.Cu")
		(net "M_L_ECC<6>")
	)
	(gr_poly
		(pts
			(xy 80.645254 -46.459648) (xy 80.681068 -46.423834) (xy 80.555338 -46.298104) (xy 80.519524 -46.333918)
			(xy 80.472788 -46.430946) (xy 80.548226 -46.506384)
		)
		(stroke
			(width 0)
			(type solid)
		)
		(fill yes)
		(layer "F.Cu")
		(net "M_H_ECC<1>")
	)
	(gr_poly
		(pts
			(xy 80.647286 -105.980484) (xy 80.521556 -105.83672) (xy 80.485488 -105.800906) (xy 80.395826 -105.890568)
			(xy 80.43164 -105.926636) (xy 80.575404 -106.052366)
		)
		(stroke
			(width 0)
			(type solid)
		)
		(fill yes)
		(layer "F.Cu")
		(net "M_L_ECC<1>")
	)
	(gr_poly
		(pts
			(xy 80.65389 -46.75632) (xy 80.700626 -46.659292) (xy 80.625188 -46.583854) (xy 80.52816 -46.63059)
			(xy 80.492346 -46.666404) (xy 80.618076 -46.792134)
		)
		(stroke
			(width 0)
			(type solid)
		)
		(fill yes)
		(layer "F.Cu")
		(net "M_H_ECC<0>")
	)
	(gr_poly
		(pts
			(xy 80.681322 -45.202094) (xy 80.71739 -45.16628) (xy 80.59166 -45.04055) (xy 80.555592 -45.076364)
			(xy 80.50911 -45.173392) (xy 80.584548 -45.24883)
		)
		(stroke
			(width 0)
			(type solid)
		)
		(fill yes)
		(layer "F.Cu")
		(net "M_H_DQS_DN<8>")
	)
	(gr_poly
		(pts
			(xy 80.690212 -45.498512) (xy 80.736948 -45.401738) (xy 80.66151 -45.3263) (xy 80.564482 -45.372782)
			(xy 80.528668 -45.40885) (xy 80.654398 -45.53458)
		)
		(stroke
			(width 0)
			(type solid)
		)
		(fill yes)
		(layer "F.Cu")
		(net "M_H_DQS_DN<17>")
	)
	(gr_poly
		(pts
			(xy 80.710024 -108.36021) (xy 80.67421 -108.324142) (xy 80.530446 -108.198412) (xy 80.458564 -108.270294)
			(xy 80.584294 -108.414058) (xy 80.620362 -108.449872)
		)
		(stroke
			(width 0)
			(type solid)
		)
		(fill yes)
		(layer "F.Cu")
		(net "M_L_ECC<6>")
	)
	(gr_poly
		(pts
			(xy 80.717644 -43.94454) (xy 80.753712 -43.908726) (xy 80.627982 -43.782996) (xy 80.591914 -43.81881)
			(xy 80.545178 -43.915838) (xy 80.620616 -43.991276)
		)
		(stroke
			(width 0)
			(type solid)
		)
		(fill yes)
		(layer "F.Cu")
		(net "M_H_ECC<7>")
	)
	(gr_poly
		(pts
			(xy 80.719168 -105.567226) (xy 80.6831 -105.531412) (xy 80.539336 -105.405682) (xy 80.467708 -105.477564)
			(xy 80.593438 -105.621328) (xy 80.629252 -105.657142)
		)
		(stroke
			(width 0)
			(type solid)
		)
		(fill yes)
		(layer "F.Cu")
		(net "M_L_ECC<1>")
	)
	(gr_poly
		(pts
			(xy 80.726534 -44.240958) (xy 80.77327 -44.14393) (xy 80.697832 -44.068492) (xy 80.600804 -44.115228)
			(xy 80.56499 -44.151296) (xy 80.69072 -44.277026)
		)
		(stroke
			(width 0)
			(type solid)
		)
		(fill yes)
		(layer "F.Cu")
		(net "M_H_ECC<6>")
	)
	(gr_poly
		(pts
			(xy 80.728058 -109.797088) (xy 80.602328 -109.653324) (xy 80.56626 -109.61751) (xy 80.476598 -109.707172)
			(xy 80.512412 -109.74324) (xy 80.656176 -109.86897)
		)
		(stroke
			(width 0)
			(type solid)
		)
		(fill yes)
		(layer "F.Cu")
		(net "M_L_ECC<2>")
	)
	(gr_poly
		(pts
			(xy 80.734916 -46.980602) (xy 80.77073 -46.944788) (xy 80.645 -46.819058) (xy 80.609186 -46.854872)
			(xy 80.56245 -46.9519) (xy 80.637888 -47.027338)
		)
		(stroke
			(width 0)
			(type solid)
		)
		(fill yes)
		(layer "F.Cu")
		(net "M_H_ECC<0>")
	)
	(gr_poly
		(pts
			(xy 80.736948 -107.004104) (xy 80.611218 -106.860594) (xy 80.575404 -106.824526) (xy 80.485488 -106.914442)
			(xy 80.521556 -106.950256) (xy 80.665066 -107.075986)
		)
		(stroke
			(width 0)
			(type solid)
		)
		(fill yes)
		(layer "F.Cu")
		(net "M_L_DQS_DN<17>")
	)
	(gr_poly
		(pts
			(xy 80.743552 -47.277274) (xy 80.790288 -47.180246) (xy 80.71485 -47.104808) (xy 80.618076 -47.151544)
			(xy 80.582008 -47.187358) (xy 80.707738 -47.313088)
		)
		(stroke
			(width 0)
			(type solid)
		)
		(fill yes)
		(layer "F.Cu")
		(net "M_H_ECC<5>")
	)
	(gr_poly
		(pts
			(xy 80.745838 -104.21112) (xy 80.620108 -104.06761) (xy 80.57515 -104.022652) (xy 80.485488 -104.112314)
			(xy 80.530192 -104.157272) (xy 80.673956 -104.283002)
		)
		(stroke
			(width 0)
			(type solid)
		)
		(fill yes)
		(layer "F.Cu")
		(net "M_L_ECC<4>")
	)
	(gr_poly
		(pts
			(xy 80.770984 -45.723048) (xy 80.807052 -45.687234) (xy 80.681322 -45.561504) (xy 80.645254 -45.597318)
			(xy 80.598772 -45.694346) (xy 80.67421 -45.769784)
		)
		(stroke
			(width 0)
			(type solid)
		)
		(fill yes)
		(layer "F.Cu")
		(net "M_H_DQS_DN<17>")
	)
	(gr_poly
		(pts
			(xy 80.779874 -46.019466) (xy 80.82661 -45.922692) (xy 80.751172 -45.847254) (xy 80.654144 -45.89399)
			(xy 80.61833 -45.929804) (xy 80.74406 -46.055534)
		)
		(stroke
			(width 0)
			(type solid)
		)
		(fill yes)
		(layer "F.Cu")
		(net "M_H_DQS_DP<17>")
	)
	(gr_poly
		(pts
			(xy 80.79994 -109.38383) (xy 80.763872 -109.348016) (xy 80.620362 -109.222286) (xy 80.54848 -109.294168)
			(xy 80.67421 -109.437932) (xy 80.710024 -109.473746)
		)
		(stroke
			(width 0)
			(type solid)
		)
		(fill yes)
		(layer "F.Cu")
		(net "M_L_ECC<2>")
	)
	(gr_poly
		(pts
			(xy 80.807306 -44.465494) (xy 80.843374 -44.42968) (xy 80.717644 -44.30395) (xy 80.681576 -44.339764)
			(xy 80.63484 -44.436792) (xy 80.710278 -44.51223)
		)
		(stroke
			(width 0)
			(type solid)
		)
		(fill yes)
		(layer "F.Cu")
		(net "M_H_ECC<6>")
	)
	(gr_poly
		(pts
			(xy 80.80883 -106.5911) (xy 80.773016 -106.555286) (xy 80.629252 -106.429556) (xy 80.55737 -106.501184)
			(xy 80.6831 -106.644948) (xy 80.719168 -106.680762)
		)
		(stroke
			(width 0)
			(type solid)
		)
		(fill yes)
		(layer "F.Cu")
		(net "M_L_DQS_DN<17>")
	)
	(gr_poly
		(pts
			(xy 80.816196 -44.761912) (xy 80.862932 -44.664884) (xy 80.787494 -44.589446) (xy 80.690466 -44.636182)
			(xy 80.654652 -44.67225) (xy 80.780382 -44.79798)
		)
		(stroke
			(width 0)
			(type solid)
		)
		(fill yes)
		(layer "F.Cu")
		(net "M_H_DQS_DP<8>")
	)
	(gr_poly
		(pts
			(xy 80.824578 -47.50181) (xy 80.860392 -47.465742) (xy 80.734662 -47.340012) (xy 80.698848 -47.37608)
			(xy 80.652112 -47.472854) (xy 80.72755 -47.548292)
		)
		(stroke
			(width 0)
			(type solid)
		)
		(fill yes)
		(layer "F.Cu")
		(net "M_H_ECC<5>")
	)
	(gr_poly
		(pts
			(xy 80.826864 -108.027978) (xy 80.701134 -107.884214) (xy 80.665066 -107.8484) (xy 80.575404 -107.938062)
			(xy 80.611218 -107.97413) (xy 80.754982 -108.09986)
		)
		(stroke
			(width 0)
			(type solid)
		)
		(fill yes)
		(layer "F.Cu")
		(net "M_L_DQS_DP<8>")
	)
	(gr_poly
		(pts
			(xy 80.833468 -47.797974) (xy 80.880204 -47.7012) (xy 80.804766 -47.625762) (xy 80.707738 -47.672244)
			(xy 80.66278 -47.717202) (xy 80.78851 -47.842932)
		)
		(stroke
			(width 0)
			(type solid)
		)
		(fill yes)
		(layer "F.Cu")
		(net "M_H_ECC<4>")
	)
	(gr_poly
		(pts
			(xy 80.835754 -105.234994) (xy 80.710024 -105.091484) (xy 80.67421 -105.055416) (xy 80.584294 -105.145332)
			(xy 80.620362 -105.181146) (xy 80.763872 -105.306876)
		)
		(stroke
			(width 0)
			(type solid)
		)
		(fill yes)
		(layer "F.Cu")
		(net "M_L_ECC<0>")
	)
	(gr_poly
		(pts
			(xy 80.843628 -43.20794) (xy 80.888586 -43.163236) (xy 80.762856 -43.037506) (xy 80.717898 -43.08221)
			(xy 80.671162 -43.179238) (xy 80.7466 -43.254676)
		)
		(stroke
			(width 0)
			(type solid)
		)
		(fill yes)
		(layer "F.Cu")
		(net "M_H_ECC<3>")
	)
	(gr_poly
		(pts
			(xy 80.852518 -43.504358) (xy 80.899254 -43.40733) (xy 80.823816 -43.331892) (xy 80.726788 -43.378628)
			(xy 80.690974 -43.414696) (xy 80.816704 -43.540426)
		)
		(stroke
			(width 0)
			(type solid)
		)
		(fill yes)
		(layer "F.Cu")
		(net "M_H_ECC<2>")
	)
	(gr_poly
		(pts
			(xy 80.8609 -46.244002) (xy 80.896714 -46.208188) (xy 80.770984 -46.082458) (xy 80.73517 -46.118272)
			(xy 80.688434 -46.2153) (xy 80.763872 -46.290738)
		)
		(stroke
			(width 0)
			(type solid)
		)
		(fill yes)
		(layer "F.Cu")
		(net "M_H_DQS_DP<17>")
	)
	(gr_poly
		(pts
			(xy 80.869536 -46.540674) (xy 80.916272 -46.443646) (xy 80.840834 -46.368208) (xy 80.743806 -46.414944)
			(xy 80.707992 -46.450758) (xy 80.833722 -46.576488)
		)
		(stroke
			(width 0)
			(type solid)
		)
		(fill yes)
		(layer "F.Cu")
		(net "M_H_ECC<1>")
	)
	(gr_poly
		(pts
			(xy 80.894174 -53.4035) (xy 80.849724 -53.4035) (xy 80.679544 -53.4924) (xy 80.679544 -53.71338)
			(xy 80.849724 -53.80228) (xy 80.894174 -53.80228)
		)
		(stroke
			(width 0)
			(type solid)
		)
		(fill yes)
		(layer "F.Cu")
		(net "M_H_ECC<4>")
	)
	(gr_poly
		(pts
			(xy 80.896968 -44.986448) (xy 80.933036 -44.950634) (xy 80.807306 -44.824904) (xy 80.771238 -44.860718)
			(xy 80.724756 -44.957746) (xy 80.800194 -45.033184)
		)
		(stroke
			(width 0)
			(type solid)
		)
		(fill yes)
		(layer "F.Cu")
		(net "M_H_DQS_DP<8>")
	)
	(gr_poly
		(pts
			(xy 80.898746 -107.61472) (xy 80.862678 -107.578906) (xy 80.718914 -107.453176) (xy 80.647286 -107.525058)
			(xy 80.773016 -107.668822) (xy 80.80883 -107.704636)
		)
		(stroke
			(width 0)
			(type solid)
		)
		(fill yes)
		(layer "F.Cu")
		(net "M_L_DQS_DP<8>")
	)
	(gr_poly
		(pts
			(xy 80.905858 -45.282866) (xy 80.952594 -45.186092) (xy 80.877156 -45.110654) (xy 80.780128 -45.157136)
			(xy 80.744314 -45.193204) (xy 80.870044 -45.318934)
		)
		(stroke
			(width 0)
			(type solid)
		)
		(fill yes)
		(layer "F.Cu")
		(net "M_H_DQS_DN<8>")
	)
	(gr_poly
		(pts
			(xy 80.907636 -104.82199) (xy 80.871822 -104.786176) (xy 80.728058 -104.660446) (xy 80.656176 -104.732074)
			(xy 80.781906 -104.875838) (xy 80.81772 -104.911906)
		)
		(stroke
			(width 0)
			(type solid)
		)
		(fill yes)
		(layer "F.Cu")
		(net "M_L_ECC<0>")
	)
	(gr_poly
		(pts
			(xy 80.916526 -109.051598) (xy 80.790796 -108.908088) (xy 80.754982 -108.87202) (xy 80.665066 -108.961936)
			(xy 80.701134 -108.99775) (xy 80.844644 -109.12348)
		)
		(stroke
			(width 0)
			(type solid)
		)
		(fill yes)
		(layer "F.Cu")
		(net "M_L_ECC<7>")
	)
	(gr_poly
		(pts
			(xy 80.92567 -106.258868) (xy 80.79994 -106.115104) (xy 80.763872 -106.07929) (xy 80.67421 -106.168952)
			(xy 80.710024 -106.20502) (xy 80.853788 -106.33075)
		)
		(stroke
			(width 0)
			(type solid)
		)
		(fill yes)
		(layer "F.Cu")
		(net "M_L_DQS_DP<17>")
	)
	(gr_poly
		(pts
			(xy 80.93329 -43.728894) (xy 80.969358 -43.69308) (xy 80.843628 -43.56735) (xy 80.80756 -43.603164)
			(xy 80.760824 -43.700192) (xy 80.836262 -43.77563)
		)
		(stroke
			(width 0)
			(type solid)
		)
		(fill yes)
		(layer "F.Cu")
		(net "M_H_ECC<2>")
	)
	(gr_poly
		(pts
			(xy 80.94218 -44.025312) (xy 80.988916 -43.928284) (xy 80.913478 -43.852846) (xy 80.81645 -43.899582)
			(xy 80.780636 -43.93565) (xy 80.906366 -44.06138)
		)
		(stroke
			(width 0)
			(type solid)
		)
		(fill yes)
		(layer "F.Cu")
		(net "M_H_ECC<7>")
	)
	(gr_poly
		(pts
			(xy 80.950562 -46.764956) (xy 80.986376 -46.729142) (xy 80.860646 -46.603412) (xy 80.824832 -46.639226)
			(xy 80.778096 -46.736254) (xy 80.853534 -46.811692)
		)
		(stroke
			(width 0)
			(type solid)
		)
		(fill yes)
		(layer "F.Cu")
		(net "M_H_ECC<1>")
	)
	(gr_poly
		(pts
			(xy 80.959198 -47.061628) (xy 81.005934 -46.9646) (xy 80.930496 -46.889162) (xy 80.833722 -46.935898)
			(xy 80.797654 -46.971712) (xy 80.923384 -47.097442)
		)
		(stroke
			(width 0)
			(type solid)
		)
		(fill yes)
		(layer "F.Cu")
		(net "M_H_ECC<0>")
	)
	(gr_poly
		(pts
			(xy 80.98663 -45.507402) (xy 81.022698 -45.471588) (xy 80.896968 -45.345858) (xy 80.8609 -45.381672)
			(xy 80.814418 -45.4787) (xy 80.889856 -45.554138)
		)
		(stroke
			(width 0)
			(type solid)
		)
		(fill yes)
		(layer "F.Cu")
		(net "M_H_DQS_DN<8>")
	)
	(gr_poly
		(pts
			(xy 80.988408 -108.638594) (xy 80.952594 -108.602526) (xy 80.80883 -108.476796) (xy 80.736948 -108.548678)
			(xy 80.862678 -108.692442) (xy 80.898746 -108.728256)
		)
		(stroke
			(width 0)
			(type solid)
		)
		(fill yes)
		(layer "F.Cu")
		(net "M_L_ECC<7>")
	)
	(gr_poly
		(pts
			(xy 80.99552 -45.80382) (xy 81.042256 -45.707046) (xy 80.966818 -45.631608) (xy 80.86979 -45.678344)
			(xy 80.833976 -45.714158) (xy 80.959706 -45.839888)
		)
		(stroke
			(width 0)
			(type solid)
		)
		(fill yes)
		(layer "F.Cu")
		(net "M_H_DQS_DN<17>")
	)
	(gr_poly
		(pts
			(xy 80.997552 -105.84561) (xy 80.961484 -105.809796) (xy 80.81772 -105.684066) (xy 80.746092 -105.755948)
			(xy 80.871822 -105.899712) (xy 80.907636 -105.935526)
		)
		(stroke
			(width 0)
			(type solid)
		)
		(fill yes)
		(layer "F.Cu")
		(net "M_L_DQS_DP<17>")
	)
	(gr_poly
		(pts
			(xy 81.015332 -107.282488) (xy 80.889602 -107.138978) (xy 80.853788 -107.10291) (xy 80.763872 -107.192826)
			(xy 80.79994 -107.22864) (xy 80.94345 -107.35437)
		)
		(stroke
			(width 0)
			(type solid)
		)
		(fill yes)
		(layer "F.Cu")
		(net "M_L_DQS_DN<8>")
	)
	(gr_poly
		(pts
			(xy 81.022952 -44.249848) (xy 81.05902 -44.214034) (xy 80.93329 -44.088304) (xy 80.897222 -44.124118)
			(xy 80.850486 -44.221146) (xy 80.925924 -44.296584)
		)
		(stroke
			(width 0)
			(type solid)
		)
		(fill yes)
		(layer "F.Cu")
		(net "M_H_ECC<7>")
	)
	(gr_poly
		(pts
			(xy 81.024222 -104.489504) (xy 80.898492 -104.345994) (xy 80.862678 -104.309926) (xy 80.772762 -104.399842)
			(xy 80.80883 -104.435656) (xy 80.95234 -104.561386)
		)
		(stroke
			(width 0)
			(type solid)
		)
		(fill yes)
		(layer "F.Cu")
		(net "M_L_ECC<5>")
	)
	(gr_poly
		(pts
			(xy 81.031842 -44.546266) (xy 81.078578 -44.449238) (xy 81.00314 -44.3738) (xy 80.906112 -44.420536)
			(xy 80.870298 -44.456604) (xy 80.996028 -44.582334)
		)
		(stroke
			(width 0)
			(type solid)
		)
		(fill yes)
		(layer "F.Cu")
		(net "M_H_ECC<6>")
	)
	(gr_poly
		(pts
			(xy 81.040224 -47.286164) (xy 81.076038 -47.250096) (xy 80.950308 -47.124366) (xy 80.914494 -47.160434)
			(xy 80.867758 -47.257208) (xy 80.943196 -47.332646)
		)
		(stroke
			(width 0)
			(type solid)
		)
		(fill yes)
		(layer "F.Cu")
		(net "M_H_ECC<0>")
	)
	(gr_poly
		(pts
			(xy 81.049114 -47.582582) (xy 81.095596 -47.485554) (xy 81.020158 -47.410116) (xy 80.923384 -47.456852)
			(xy 80.887316 -47.492666) (xy 81.013046 -47.618396)
		)
		(stroke
			(width 0)
			(type solid)
		)
		(fill yes)
		(layer "F.Cu")
		(net "M_H_ECC<5>")
	)
	(gr_poly
		(pts
			(xy 81.076546 -46.028356) (xy 81.11236 -45.992542) (xy 80.98663 -45.866812) (xy 80.950816 -45.902626)
			(xy 80.90408 -45.999654) (xy 80.979518 -46.075092)
		)
		(stroke
			(width 0)
			(type solid)
		)
		(fill yes)
		(layer "F.Cu")
		(net "M_H_DQS_DN<17>")
	)
	(gr_poly
		(pts
			(xy 81.085182 -46.325028) (xy 81.131918 -46.228) (xy 81.05648 -46.152562) (xy 80.959452 -46.199298)
			(xy 80.923638 -46.235112) (xy 81.049368 -46.360842)
		)
		(stroke
			(width 0)
			(type solid)
		)
		(fill yes)
		(layer "F.Cu")
		(net "M_H_DQS_DP<17>")
	)
	(gr_poly
		(pts
			(xy 81.087214 -109.671104) (xy 81.042256 -109.626146) (xy 80.898746 -109.500416) (xy 80.826864 -109.572298)
			(xy 80.952594 -109.716062) (xy 80.997552 -109.760766)
		)
		(stroke
			(width 0)
			(type solid)
		)
		(fill yes)
		(layer "F.Cu")
		(net "M_L_ECC<3>")
	)
	(gr_poly
		(pts
			(xy 81.087214 -106.869484) (xy 81.0514 -106.83367) (xy 80.907636 -106.70794) (xy 80.835754 -106.779568)
			(xy 80.961484 -106.923332) (xy 80.997552 -106.959146)
		)
		(stroke
			(width 0)
			(type solid)
		)
		(fill yes)
		(layer "F.Cu")
		(net "M_L_DQS_DN<8>")
	)
	(gr_poly
		(pts
			(xy 81.096104 -104.0765) (xy 81.06029 -104.040686) (xy 80.916526 -103.914956) (xy 80.844644 -103.986584)
			(xy 80.970374 -104.130348) (xy 81.006188 -104.166416)
		)
		(stroke
			(width 0)
			(type solid)
		)
		(fill yes)
		(layer "F.Cu")
		(net "M_L_ECC<5>")
	)
	(gr_poly
		(pts
			(xy 81.105248 -108.306362) (xy 80.979518 -108.162598) (xy 80.94345 -108.126784) (xy 80.853788 -108.216446)
			(xy 80.889602 -108.252514) (xy 81.033366 -108.378244)
		)
		(stroke
			(width 0)
			(type solid)
		)
		(fill yes)
		(layer "F.Cu")
		(net "M_L_ECC<6>")
	)
	(gr_poly
		(pts
			(xy 81.112614 -44.770802) (xy 81.148682 -44.734988) (xy 81.022952 -44.609258) (xy 80.986884 -44.645072)
			(xy 80.940402 -44.7421) (xy 81.01584 -44.817538)
		)
		(stroke
			(width 0)
			(type solid)
		)
		(fill yes)
		(layer "F.Cu")
		(net "M_H_ECC<6>")
	)
	(gr_poly
		(pts
			(xy 81.114138 -105.513378) (xy 80.988408 -105.369868) (xy 80.952594 -105.3338) (xy 80.862678 -105.423716)
			(xy 80.898746 -105.45953) (xy 81.042256 -105.58526)
		)
		(stroke
			(width 0)
			(type solid)
		)
		(fill yes)
		(layer "F.Cu")
		(net "M_L_ECC<1>")
	)
	(gr_poly
		(pts
			(xy 81.121504 -45.06722) (xy 81.16824 -44.970446) (xy 81.092802 -44.895008) (xy 80.995774 -44.94149)
			(xy 80.95996 -44.977558) (xy 81.08569 -45.103288)
		)
		(stroke
			(width 0)
			(type solid)
		)
		(fill yes)
		(layer "F.Cu")
		(net "M_H_DQS_DP<8>")
	)
	(gr_poly
		(pts
			(xy 81.129886 -47.807118) (xy 81.1657 -47.77105) (xy 81.03997 -47.64532) (xy 81.004156 -47.681388)
			(xy 80.95742 -47.778162) (xy 81.032858 -47.8536)
		)
		(stroke
			(width 0)
			(type solid)
		)
		(fill yes)
		(layer "F.Cu")
		(net "M_H_ECC<5>")
	)
	(gr_poly
		(pts
			(xy 81.138776 -48.103282) (xy 81.185512 -48.006508) (xy 81.110074 -47.93107) (xy 81.013046 -47.977552)
			(xy 80.968088 -48.02251) (xy 81.093818 -48.14824)
		)
		(stroke
			(width 0)
			(type solid)
		)
		(fill yes)
		(layer "F.Cu")
		(net "M_H_ECC<4>")
	)
	(gr_poly
		(pts
			(xy 81.148936 -43.513248) (xy 81.193894 -43.468544) (xy 81.068164 -43.342814) (xy 81.023206 -43.387518)
			(xy 80.97647 -43.484546) (xy 81.051908 -43.559984)
		)
		(stroke
			(width 0)
			(type solid)
		)
		(fill yes)
		(layer "F.Cu")
		(net "M_H_ECC<3>")
	)
	(gr_poly
		(pts
			(xy 81.157826 -43.809666) (xy 81.204562 -43.712638) (xy 81.129124 -43.6372) (xy 81.032096 -43.683936)
			(xy 80.996282 -43.720004) (xy 81.122012 -43.845734)
		)
		(stroke
			(width 0)
			(type solid)
		)
		(fill yes)
		(layer "F.Cu")
		(net "M_H_ECC<2>")
	)
	(gr_poly
		(pts
			(xy 81.166208 -46.54931) (xy 81.202022 -46.513496) (xy 81.076292 -46.387766) (xy 81.040478 -46.42358)
			(xy 80.993742 -46.520608) (xy 81.06918 -46.596046)
		)
		(stroke
			(width 0)
			(type solid)
		)
		(fill yes)
		(layer "F.Cu")
		(net "M_H_DQS_DP<17>")
	)
	(gr_poly
		(pts
			(xy 81.174844 -46.845982) (xy 81.22158 -46.748954) (xy 81.146142 -46.673516) (xy 81.049368 -46.720252)
			(xy 81.0133 -46.756066) (xy 81.13903 -46.881796)
		)
		(stroke
			(width 0)
			(type solid)
		)
		(fill yes)
		(layer "F.Cu")
		(net "M_H_ECC<1>")
	)
	(gr_poly
		(pts
			(xy 81.17713 -107.893104) (xy 81.141062 -107.85729) (xy 80.997298 -107.73156) (xy 80.92567 -107.803442)
			(xy 81.0514 -107.947206) (xy 81.087214 -107.98302)
		)
		(stroke
			(width 0)
			(type solid)
		)
		(fill yes)
		(layer "F.Cu")
		(net "M_L_ECC<6>")
	)
	(gr_poly
		(pts
			(xy 81.18602 -105.100374) (xy 81.150206 -105.06456) (xy 81.006442 -104.93883) (xy 80.93456 -105.010458)
			(xy 81.06029 -105.154222) (xy 81.096104 -105.19029)
		)
		(stroke
			(width 0)
			(type solid)
		)
		(fill yes)
		(layer "F.Cu")
		(net "M_L_ECC<1>")
	)
	(gr_poly
		(pts
			(xy 81.19491 -109.329982) (xy 81.06918 -109.186472) (xy 81.033366 -109.150404) (xy 80.94345 -109.24032)
			(xy 80.979518 -109.276134) (xy 81.123028 -109.401864)
		)
		(stroke
			(width 0)
			(type solid)
		)
		(fill yes)
		(layer "F.Cu")
		(net "M_L_ECC<2>")
	)
	(gr_poly
		(pts
			(xy 81.202276 -45.291756) (xy 81.238344 -45.255942) (xy 81.112614 -45.130212) (xy 81.076546 -45.166026)
			(xy 81.030064 -45.263054) (xy 81.105502 -45.338492)
		)
		(stroke
			(width 0)
			(type solid)
		)
		(fill yes)
		(layer "F.Cu")
		(net "M_H_DQS_DP<8>")
	)
	(gr_poly
		(pts
			(xy 81.204054 -106.537252) (xy 81.078324 -106.393488) (xy 81.042256 -106.357674) (xy 80.952594 -106.447336)
			(xy 80.988408 -106.483404) (xy 81.132172 -106.609134)
		)
		(stroke
			(width 0)
			(type solid)
		)
		(fill yes)
		(layer "F.Cu")
		(net "M_L_DQS_DN<17>")
	)
	(gr_poly
		(pts
			(xy 81.211166 -45.588174) (xy 81.257902 -45.4914) (xy 81.182464 -45.415962) (xy 81.085436 -45.462698)
			(xy 81.049622 -45.498512) (xy 81.175352 -45.624242)
		)
		(stroke
			(width 0)
			(type solid)
		)
		(fill yes)
		(layer "F.Cu")
		(net "M_H_DQS_DN<8>")
	)
	(gr_poly
		(pts
			(xy 81.21269 -103.744268) (xy 81.087214 -103.600504) (xy 81.042256 -103.555546) (xy 80.95234 -103.645462)
			(xy 80.997298 -103.69042) (xy 81.141062 -103.81615)
		)
		(stroke
			(width 0)
			(type solid)
		)
		(fill yes)
		(layer "F.Cu")
		(net "M_L_ECC<4>")
	)
	(gr_poly
		(pts
			(xy 81.238598 -44.034202) (xy 81.274666 -43.998388) (xy 81.148936 -43.872658) (xy 81.112868 -43.908472)
			(xy 81.066132 -44.0055) (xy 81.14157 -44.080938)
		)
		(stroke
			(width 0)
			(type solid)
		)
		(fill yes)
		(layer "F.Cu")
		(net "M_H_ECC<2>")
	)
	(gr_poly
		(pts
			(xy 81.247488 -44.33062) (xy 81.294224 -44.233592) (xy 81.218786 -44.158154) (xy 81.121758 -44.20489)
			(xy 81.085944 -44.240958) (xy 81.211674 -44.366688)
		)
		(stroke
			(width 0)
			(type solid)
		)
		(fill yes)
		(layer "F.Cu")
		(net "M_H_ECC<7>")
	)
	(gr_poly
		(pts
			(xy 81.25587 -47.070518) (xy 81.291684 -47.03445) (xy 81.165954 -46.90872) (xy 81.13014 -46.944788)
			(xy 81.083404 -47.041562) (xy 81.158842 -47.117)
		)
		(stroke
			(width 0)
			(type solid)
		)
		(fill yes)
		(layer "F.Cu")
		(net "M_H_ECC<1>")
	)
	(gr_poly
		(pts
			(xy 81.26476 -47.366936) (xy 81.311242 -47.269908) (xy 81.235804 -47.19447) (xy 81.13903 -47.241206)
			(xy 81.102962 -47.27702) (xy 81.228692 -47.40275)
		)
		(stroke
			(width 0)
			(type solid)
		)
		(fill yes)
		(layer "F.Cu")
		(net "M_H_ECC<0>")
	)
	(gr_poly
		(pts
			(xy 81.266792 -108.916978) (xy 81.230978 -108.88091) (xy 81.087214 -108.75518) (xy 81.015332 -108.827062)
			(xy 81.141062 -108.970826) (xy 81.17713 -109.00664)
		)
		(stroke
			(width 0)
			(type solid)
		)
		(fill yes)
		(layer "F.Cu")
		(net "M_L_ECC<2>")
	)
	(gr_poly
		(pts
			(xy 81.275936 -106.123994) (xy 81.239868 -106.08818) (xy 81.096104 -105.96245) (xy 81.024476 -106.034332)
			(xy 81.150206 -106.178096) (xy 81.18602 -106.21391)
		)
		(stroke
			(width 0)
			(type solid)
		)
		(fill yes)
		(layer "F.Cu")
		(net "M_L_DQS_DN<17>")
	)
	(gr_poly
		(pts
			(xy 81.292192 -45.81271) (xy 81.328006 -45.776896) (xy 81.202276 -45.651166) (xy 81.166462 -45.68698)
			(xy 81.119726 -45.784008) (xy 81.195164 -45.859446)
		)
		(stroke
			(width 0)
			(type solid)
		)
		(fill yes)
		(layer "F.Cu")
		(net "M_H_DQS_DN<8>")
	)
	(gr_poly
		(pts
			(xy 81.293716 -107.560872) (xy 81.167986 -107.417362) (xy 81.132172 -107.381294) (xy 81.042256 -107.47121)
			(xy 81.078324 -107.507024) (xy 81.221834 -107.632754)
		)
		(stroke
			(width 0)
			(type solid)
		)
		(fill yes)
		(layer "F.Cu")
		(net "M_L_DQS_DP<8>")
	)
	(gr_poly
		(pts
			(xy 81.300828 -46.109382) (xy 81.347564 -46.012354) (xy 81.272126 -45.936916) (xy 81.175098 -45.983652)
			(xy 81.139284 -46.019466) (xy 81.265014 -46.145196)
		)
		(stroke
			(width 0)
			(type solid)
		)
		(fill yes)
		(layer "F.Cu")
		(net "M_H_DQS_DN<17>")
	)
	(gr_poly
		(pts
			(xy 81.30286 -104.768142) (xy 81.17713 -104.624378) (xy 81.141062 -104.588564) (xy 81.0514 -104.678226)
			(xy 81.087214 -104.714294) (xy 81.230978 -104.840024)
		)
		(stroke
			(width 0)
			(type solid)
		)
		(fill yes)
		(layer "F.Cu")
		(net "M_L_ECC<0>")
	)
	(gr_poly
		(pts
			(xy 81.32826 -44.555156) (xy 81.364328 -44.519342) (xy 81.238598 -44.393612) (xy 81.20253 -44.429426)
			(xy 81.156048 -44.526454) (xy 81.231486 -44.601892)
		)
		(stroke
			(width 0)
			(type solid)
		)
		(fill yes)
		(layer "F.Cu")
		(net "M_H_ECC<7>")
	)
	(gr_poly
		(pts
			(xy 81.33715 -44.851574) (xy 81.383886 -44.7548) (xy 81.308448 -44.679362) (xy 81.21142 -44.725844)
			(xy 81.175606 -44.761912) (xy 81.301336 -44.887642)
		)
		(stroke
			(width 0)
			(type solid)
		)
		(fill yes)
		(layer "F.Cu")
		(net "M_H_ECC<6>")
	)
	(gr_poly
		(pts
			(xy 81.345532 -47.591472) (xy 81.381346 -47.555404) (xy 81.255616 -47.429674) (xy 81.219802 -47.465742)
			(xy 81.173066 -47.562516) (xy 81.248504 -47.637954)
		)
		(stroke
			(width 0)
			(type solid)
		)
		(fill yes)
		(layer "F.Cu")
		(net "M_H_ECC<0>")
	)
	(gr_poly
		(pts
			(xy 81.354422 -47.88789) (xy 81.401158 -47.790862) (xy 81.32572 -47.715424) (xy 81.228692 -47.76216)
			(xy 81.192624 -47.797974) (xy 81.318354 -47.923704)
		)
		(stroke
			(width 0)
			(type solid)
		)
		(fill yes)
		(layer "F.Cu")
		(net "M_H_ECC<5>")
	)
	(gr_poly
		(pts
			(xy 81.365598 -107.147868) (xy 81.329784 -107.112054) (xy 81.18602 -106.986324) (xy 81.114138 -107.057952)
			(xy 81.239868 -107.201716) (xy 81.275936 -107.23753)
		)
		(stroke
			(width 0)
			(type solid)
		)
		(fill yes)
		(layer "F.Cu")
		(net "M_L_DQS_DP<8>")
	)
	(gr_poly
		(pts
			(xy 81.374488 -104.355138) (xy 81.338674 -104.31907) (xy 81.19491 -104.19334) (xy 81.123282 -104.265222)
			(xy 81.249012 -104.408986) (xy 81.284826 -104.4448)
		)
		(stroke
			(width 0)
			(type solid)
		)
		(fill yes)
		(layer "F.Cu")
		(net "M_L_ECC<0>")
	)
	(gr_poly
		(pts
			(xy 81.381854 -46.333664) (xy 81.417668 -46.29785) (xy 81.291938 -46.17212) (xy 81.256124 -46.207934)
			(xy 81.209388 -46.304962) (xy 81.284826 -46.3804)
		)
		(stroke
			(width 0)
			(type solid)
		)
		(fill yes)
		(layer "F.Cu")
		(net "M_H_DQS_DN<17>")
	)
	(gr_poly
		(pts
			(xy 81.383632 -108.584746) (xy 81.257902 -108.440982) (xy 81.221834 -108.405168) (xy 81.132172 -108.49483)
			(xy 81.167986 -108.530898) (xy 81.31175 -108.656628)
		)
		(stroke
			(width 0)
			(type solid)
		)
		(fill yes)
		(layer "F.Cu")
		(net "M_L_ECC<7>")
	)
	(gr_poly
		(pts
			(xy 81.39049 -46.630336) (xy 81.437226 -46.533308) (xy 81.361788 -46.45787) (xy 81.265014 -46.504606)
			(xy 81.228946 -46.54042) (xy 81.354676 -46.66615)
		)
		(stroke
			(width 0)
			(type solid)
		)
		(fill yes)
		(layer "F.Cu")
		(net "M_H_DQS_DP<17>")
	)
	(gr_poly
		(pts
			(xy 81.392522 -105.791762) (xy 81.266792 -105.648252) (xy 81.230978 -105.612184) (xy 81.141062 -105.7021)
			(xy 81.17713 -105.737914) (xy 81.32064 -105.863644)
		)
		(stroke
			(width 0)
			(type solid)
		)
		(fill yes)
		(layer "F.Cu")
		(net "M_L_DQS_DP<17>")
	)
	(gr_poly
		(pts
			(xy 81.417922 -45.07611) (xy 81.45399 -45.040296) (xy 81.32826 -44.914566) (xy 81.292192 -44.95038)
			(xy 81.24571 -45.047408) (xy 81.321148 -45.122846)
		)
		(stroke
			(width 0)
			(type solid)
		)
		(fill yes)
		(layer "F.Cu")
		(net "M_H_ECC<6>")
	)
	(gr_poly
		(pts
			(xy 81.426812 -45.372528) (xy 81.473548 -45.275754) (xy 81.39811 -45.200316) (xy 81.301082 -45.247052)
			(xy 81.265268 -45.282866) (xy 81.390998 -45.408596)
		)
		(stroke
			(width 0)
			(type solid)
		)
		(fill yes)
		(layer "F.Cu")
		(net "M_H_DQS_DP<8>")
	)
	(gr_poly
		(pts
			(xy 81.435194 -48.112426) (xy 81.471008 -48.076358) (xy 81.345278 -47.950628) (xy 81.309464 -47.986696)
			(xy 81.262728 -48.083724) (xy 81.338166 -48.159162)
		)
		(stroke
			(width 0)
			(type solid)
		)
		(fill yes)
		(layer "F.Cu")
		(net "M_H_ECC<5>")
	)
	(gr_poly
		(pts
			(xy 81.444084 -48.408844) (xy 81.49082 -48.311816) (xy 81.415382 -48.236378) (xy 81.318354 -48.283114)
			(xy 81.273396 -48.327818) (xy 81.399126 -48.453548)
		)
		(stroke
			(width 0)
			(type solid)
		)
		(fill yes)
		(layer "F.Cu")
		(net "M_H_ECC<4>")
	)
	(gr_poly
		(pts
			(xy 81.454244 -43.818556) (xy 81.499202 -43.773852) (xy 81.373472 -43.648122) (xy 81.328514 -43.69308)
			(xy 81.281778 -43.789854) (xy 81.357216 -43.865292)
		)
		(stroke
			(width 0)
			(type solid)
		)
		(fill yes)
		(layer "F.Cu")
		(net "M_H_ECC<3>")
	)
	(gr_poly
		(pts
			(xy 81.455514 -108.171488) (xy 81.419446 -108.135674) (xy 81.275682 -108.009944) (xy 81.204054 -108.081826)
			(xy 81.329784 -108.22559) (xy 81.365598 -108.261404)
		)
		(stroke
			(width 0)
			(type solid)
		)
		(fill yes)
		(layer "F.Cu")
		(net "M_L_ECC<7>")
	)
	(gr_poly
		(pts
			(xy 81.463134 -44.114974) (xy 81.50987 -44.017946) (xy 81.434432 -43.942508) (xy 81.337404 -43.989244)
			(xy 81.30159 -44.025312) (xy 81.42732 -44.151042)
		)
		(stroke
			(width 0)
			(type solid)
		)
		(fill yes)
		(layer "F.Cu")
		(net "M_H_ECC<2>")
	)
	(gr_poly
		(pts
			(xy 81.464404 -105.378758) (xy 81.42859 -105.342944) (xy 81.284826 -105.217214) (xy 81.212944 -105.288842)
			(xy 81.338674 -105.432606) (xy 81.374488 -105.468674)
		)
		(stroke
			(width 0)
			(type solid)
		)
		(fill yes)
		(layer "F.Cu")
		(net "M_L_DQS_DP<17>")
	)
	(gr_poly
		(pts
			(xy 81.471516 -46.854872) (xy 81.50733 -46.818804) (xy 81.3816 -46.693074) (xy 81.345786 -46.729142)
			(xy 81.29905 -46.825916) (xy 81.374488 -46.901354)
		)
		(stroke
			(width 0)
			(type solid)
		)
		(fill yes)
		(layer "F.Cu")
		(net "M_H_DQS_DP<17>")
	)
	(gr_poly
		(pts
			(xy 81.480406 -47.15129) (xy 81.526888 -47.054262) (xy 81.45145 -46.978824) (xy 81.354676 -47.02556)
			(xy 81.318608 -47.061374) (xy 81.444338 -47.187104)
		)
		(stroke
			(width 0)
			(type solid)
		)
		(fill yes)
		(layer "F.Cu")
		(net "M_H_ECC<1>")
	)
	(gr_poly
		(pts
			(xy 81.482438 -106.815636) (xy 81.356708 -106.671872) (xy 81.32064 -106.636058) (xy 81.230978 -106.72572)
			(xy 81.266792 -106.761788) (xy 81.410556 -106.887518)
		)
		(stroke
			(width 0)
			(type solid)
		)
		(fill yes)
		(layer "F.Cu")
		(net "M_L_DQS_DN<8>")
	)
	(gr_poly
		(pts
			(xy 81.491328 -104.022652) (xy 81.365598 -103.878888) (xy 81.32953 -103.843074) (xy 81.239868 -103.932736)
			(xy 81.275682 -103.968804) (xy 81.419446 -104.094534)
		)
		(stroke
			(width 0)
			(type solid)
		)
		(fill yes)
		(layer "F.Cu")
		(net "M_L_ECC<5>")
	)
	(gr_poly
		(pts
			(xy 81.507838 -45.597064) (xy 81.543652 -45.56125) (xy 81.417922 -45.43552) (xy 81.382108 -45.471334)
			(xy 81.335372 -45.568362) (xy 81.41081 -45.6438)
		)
		(stroke
			(width 0)
			(type solid)
		)
		(fill yes)
		(layer "F.Cu")
		(net "M_H_DQS_DP<8>")
	)
	(gr_poly
		(pts
			(xy 81.516474 -45.893736) (xy 81.56321 -45.796708) (xy 81.487772 -45.72127) (xy 81.390744 -45.768006)
			(xy 81.35493 -45.80382) (xy 81.48066 -45.92955)
		)
		(stroke
			(width 0)
			(type solid)
		)
		(fill yes)
		(layer "F.Cu")
		(net "M_H_DQS_DN<8>")
	)
	(gr_poly
		(pts
			(xy 81.543906 -44.33951) (xy 81.579974 -44.303696) (xy 81.454244 -44.177966) (xy 81.418176 -44.21378)
			(xy 81.371694 -44.310808) (xy 81.447132 -44.386246)
		)
		(stroke
			(width 0)
			(type solid)
		)
		(fill yes)
		(layer "F.Cu")
		(net "M_H_ECC<2>")
	)
	(gr_poly
		(pts
			(xy 81.552796 -44.635928) (xy 81.599532 -44.539154) (xy 81.524094 -44.463716) (xy 81.427066 -44.510198)
			(xy 81.391252 -44.546266) (xy 81.516982 -44.671996)
		)
		(stroke
			(width 0)
			(type solid)
		)
		(fill yes)
		(layer "F.Cu")
		(net "M_H_ECC<7>")
	)
	(gr_poly
		(pts
			(xy 81.554066 -109.204252) (xy 81.509108 -109.159294) (xy 81.365598 -109.033564) (xy 81.293716 -109.105446)
			(xy 81.419446 -109.24921) (xy 81.464404 -109.293914)
		)
		(stroke
			(width 0)
			(type solid)
		)
		(fill yes)
		(layer "F.Cu")
		(net "M_L_ECC<3>")
	)
	(gr_poly
		(pts
			(xy 81.55432 -106.402378) (xy 81.518252 -106.366564) (xy 81.374488 -106.240834) (xy 81.30286 -106.312716)
			(xy 81.42859 -106.45648) (xy 81.464404 -106.492294)
		)
		(stroke
			(width 0)
			(type solid)
		)
		(fill yes)
		(layer "F.Cu")
		(net "M_L_DQS_DN<8>")
	)
	(gr_poly
		(pts
			(xy 81.561178 -47.375826) (xy 81.596992 -47.339758) (xy 81.471262 -47.214028) (xy 81.435448 -47.250096)
			(xy 81.388712 -47.34687) (xy 81.46415 -47.422308)
		)
		(stroke
			(width 0)
			(type solid)
		)
		(fill yes)
		(layer "F.Cu")
		(net "M_H_ECC<1>")
	)
	(gr_poly
		(pts
			(xy 81.562956 -103.609648) (xy 81.527142 -103.57358) (xy 81.383378 -103.44785) (xy 81.31175 -103.519732)
			(xy 81.437226 -103.663496) (xy 81.473294 -103.69931)
		)
		(stroke
			(width 0)
			(type solid)
		)
		(fill yes)
		(layer "F.Cu")
		(net "M_L_ECC<5>")
	)
	(gr_poly
		(pts
			(xy 81.570068 -47.672244) (xy 81.616804 -47.575216) (xy 81.541366 -47.499778) (xy 81.444338 -47.546514)
			(xy 81.40827 -47.582328) (xy 81.534 -47.708058)
		)
		(stroke
			(width 0)
			(type solid)
		)
		(fill yes)
		(layer "F.Cu")
		(net "M_H_ECC<0>")
	)
	(gr_poly
		(pts
			(xy 81.5721 -107.839256) (xy 81.44637 -107.695746) (xy 81.410556 -107.659678) (xy 81.32064 -107.749594)
			(xy 81.356708 -107.785408) (xy 81.500218 -107.911138)
		)
		(stroke
			(width 0)
			(type solid)
		)
		(fill yes)
		(layer "F.Cu")
		(net "M_L_ECC<6>")
	)
	(gr_poly
		(pts
			(xy 81.581244 -105.046526) (xy 81.455514 -104.902762) (xy 81.419446 -104.866948) (xy 81.329784 -104.95661)
			(xy 81.365598 -104.992678) (xy 81.509362 -105.118408)
		)
		(stroke
			(width 0)
			(type solid)
		)
		(fill yes)
		(layer "F.Cu")
		(net "M_L_ECC<1>")
	)
	(gr_poly
		(pts
			(xy 81.5975 -46.118018) (xy 81.633314 -46.082204) (xy 81.507584 -45.956474) (xy 81.47177 -45.992288)
			(xy 81.425034 -46.089316) (xy 81.500472 -46.164754)
		)
		(stroke
			(width 0)
			(type solid)
		)
		(fill yes)
		(layer "F.Cu")
		(net "M_H_DQS_DN<8>")
	)
	(gr_poly
		(pts
			(xy 81.606136 -46.41469) (xy 81.652872 -46.317662) (xy 81.577434 -46.242224) (xy 81.48066 -46.28896)
			(xy 81.444592 -46.324774) (xy 81.570322 -46.450504)
		)
		(stroke
			(width 0)
			(type solid)
		)
		(fill yes)
		(layer "F.Cu")
		(net "M_H_DQS_DN<17>")
	)
	(gr_poly
		(pts
			(xy 81.633568 -44.860464) (xy 81.669636 -44.82465) (xy 81.543906 -44.69892) (xy 81.507838 -44.734734)
			(xy 81.461356 -44.831762) (xy 81.536794 -44.9072)
		)
		(stroke
			(width 0)
			(type solid)
		)
		(fill yes)
		(layer "F.Cu")
		(net "M_H_ECC<7>")
	)
	(gr_poly
		(pts
			(xy 81.639156 -53.16474) (xy 81.626964 -53.122322) (xy 81.494884 -52.982876) (xy 81.282286 -53.043074)
			(xy 81.24317 -53.231034) (xy 81.255616 -53.27396)
		)
		(stroke
			(width 0)
			(type solid)
		)
		(fill yes)
		(layer "F.Cu")
		(net "M_H_ECC<5>")
	)
	(gr_poly
		(pts
			(xy 81.642458 -45.156882) (xy 81.689194 -45.060108) (xy 81.613756 -44.98467) (xy 81.516728 -45.031406)
			(xy 81.480914 -45.06722) (xy 81.606644 -45.19295)
		)
		(stroke
			(width 0)
			(type solid)
		)
		(fill yes)
		(layer "F.Cu")
		(net "M_H_ECC<6>")
	)
	(gr_poly
		(pts
			(xy 81.643982 -107.426252) (xy 81.608168 -107.390438) (xy 81.464404 -107.264708) (xy 81.392522 -107.336336)
			(xy 81.518252 -107.4801) (xy 81.55432 -107.515914)
		)
		(stroke
			(width 0)
			(type solid)
		)
		(fill yes)
		(layer "F.Cu")
		(net "M_L_ECC<6>")
	)
	(gr_poly
		(pts
			(xy 81.65084 -47.89678) (xy 81.686654 -47.860712) (xy 81.560924 -47.734982) (xy 81.52511 -47.77105)
			(xy 81.478374 -47.868078) (xy 81.553812 -47.943516)
		)
		(stroke
			(width 0)
			(type solid)
		)
		(fill yes)
		(layer "F.Cu")
		(net "M_H_ECC<0>")
	)
	(gr_poly
		(pts
			(xy 81.652872 -104.633522) (xy 81.617058 -104.597454) (xy 81.473294 -104.471724) (xy 81.401666 -104.543606)
			(xy 81.527396 -104.68737) (xy 81.56321 -104.723184)
		)
		(stroke
			(width 0)
			(type solid)
		)
		(fill yes)
		(layer "F.Cu")
		(net "M_L_ECC<1>")
	)
	(gr_poly
		(pts
			(xy 81.65973 -48.193198) (xy 81.706466 -48.09617) (xy 81.631028 -48.020732) (xy 81.534 -48.067468)
			(xy 81.497932 -48.103282) (xy 81.623662 -48.229012)
		)
		(stroke
			(width 0)
			(type solid)
		)
		(fill yes)
		(layer "F.Cu")
		(net "M_H_ECC<5>")
	)
	(gr_poly
		(pts
			(xy 81.662016 -108.86313) (xy 81.536286 -108.719366) (xy 81.500218 -108.683552) (xy 81.410556 -108.773214)
			(xy 81.44637 -108.809282) (xy 81.590134 -108.935012)
		)
		(stroke
			(width 0)
			(type solid)
		)
		(fill yes)
		(layer "F.Cu")
		(net "M_L_ECC<2>")
	)
	(gr_poly
		(pts
			(xy 81.670906 -106.070146) (xy 81.545176 -105.926636) (xy 81.509362 -105.890568) (xy 81.419446 -105.980484)
			(xy 81.455514 -106.016298) (xy 81.599024 -106.142028)
		)
		(stroke
			(width 0)
			(type solid)
		)
		(fill yes)
		(layer "F.Cu")
		(net "M_L_DQS_DN<17>")
	)
	(gr_poly
		(pts
			(xy 81.679796 -103.277162) (xy 81.554066 -103.133652) (xy 81.509108 -103.088694) (xy 81.419446 -103.178356)
			(xy 81.46415 -103.223314) (xy 81.607914 -103.349044)
		)
		(stroke
			(width 0)
			(type solid)
		)
		(fill yes)
		(layer "F.Cu")
		(net "M_L_ECC<4>")
	)
	(gr_poly
		(pts
			(xy 81.687162 -46.639226) (xy 81.722976 -46.603158) (xy 81.597246 -46.477428) (xy 81.561432 -46.513496)
			(xy 81.514696 -46.61027) (xy 81.590134 -46.685708)
		)
		(stroke
			(width 0)
			(type solid)
		)
		(fill yes)
		(layer "F.Cu")
		(net "M_H_DQS_DN<17>")
	)
	(gr_poly
		(pts
			(xy 81.696052 -46.935644) (xy 81.742534 -46.838616) (xy 81.667096 -46.763178) (xy 81.570322 -46.809914)
			(xy 81.534254 -46.845728) (xy 81.659984 -46.971458)
		)
		(stroke
			(width 0)
			(type solid)
		)
		(fill yes)
		(layer "F.Cu")
		(net "M_H_DQS_DP<17>")
	)
	(gr_poly
		(pts
			(xy 81.723484 -45.381418) (xy 81.759298 -45.345604) (xy 81.633568 -45.219874) (xy 81.597754 -45.255688)
			(xy 81.551018 -45.352716) (xy 81.626456 -45.428154)
		)
		(stroke
			(width 0)
			(type solid)
		)
		(fill yes)
		(layer "F.Cu")
		(net "M_H_ECC<6>")
	)
	(gr_poly
		(pts
			(xy 81.73212 -45.67809) (xy 81.778856 -45.581062) (xy 81.703418 -45.505624) (xy 81.60639 -45.55236)
			(xy 81.570576 -45.588174) (xy 81.696306 -45.713904)
		)
		(stroke
			(width 0)
			(type solid)
		)
		(fill yes)
		(layer "F.Cu")
		(net "M_H_DQS_DP<8>")
	)
	(gr_poly
		(pts
			(xy 81.733898 -108.449872) (xy 81.69783 -108.414058) (xy 81.554066 -108.288328) (xy 81.482438 -108.36021)
			(xy 81.608168 -108.503974) (xy 81.643982 -108.539788)
		)
		(stroke
			(width 0)
			(type solid)
		)
		(fill yes)
		(layer "F.Cu")
		(net "M_L_ECC<2>")
	)
	(gr_poly
		(pts
			(xy 81.740502 -48.417734) (xy 81.776316 -48.381666) (xy 81.650586 -48.255936) (xy 81.614772 -48.292004)
			(xy 81.568036 -48.389032) (xy 81.643474 -48.46447)
		)
		(stroke
			(width 0)
			(type solid)
		)
		(fill yes)
		(layer "F.Cu")
		(net "M_H_ECC<5>")
	)
	(gr_poly
		(pts
			(xy 81.742788 -105.657142) (xy 81.706974 -105.621328) (xy 81.56321 -105.495598) (xy 81.491328 -105.567226)
			(xy 81.617058 -105.71099) (xy 81.652872 -105.747058)
		)
		(stroke
			(width 0)
			(type solid)
		)
		(fill yes)
		(layer "F.Cu")
		(net "M_L_DQS_DN<17>")
	)
	(gr_poly
		(pts
			(xy 81.749392 -48.714152) (xy 81.796128 -48.617124) (xy 81.72069 -48.541686) (xy 81.623662 -48.588422)
			(xy 81.578704 -48.633126) (xy 81.704434 -48.758856)
		)
		(stroke
			(width 0)
			(type solid)
		)
		(fill yes)
		(layer "F.Cu")
		(net "M_H_ECC<4>")
	)
	(gr_poly
		(pts
			(xy 81.752694 -98.488246) (xy 81.708244 -98.488246) (xy 81.538064 -98.577146) (xy 81.538064 -98.798126)
			(xy 81.708244 -98.887026) (xy 81.752694 -98.887026)
		)
		(stroke
			(width 0)
			(type solid)
		)
		(fill yes)
		(layer "F.Cu")
		(net "M_L_ECC<4>")
	)
	(gr_poly
		(pts
			(xy 81.759552 -44.124118) (xy 81.80451 -44.07916) (xy 81.67878 -43.95343) (xy 81.633822 -43.998388)
			(xy 81.587086 -44.095162) (xy 81.662524 -44.1706)
		)
		(stroke
			(width 0)
			(type solid)
		)
		(fill yes)
		(layer "F.Cu")
		(net "M_H_ECC<3>")
	)
	(gr_poly
		(pts
			(xy 81.760822 -107.09402) (xy 81.635092 -106.950256) (xy 81.599024 -106.914442) (xy 81.509362 -107.004104)
			(xy 81.545176 -107.040172) (xy 81.68894 -107.165902)
		)
		(stroke
			(width 0)
			(type solid)
		)
		(fill yes)
		(layer "F.Cu")
		(net "M_L_DQS_DP<8>")
	)
	(gr_poly
		(pts
			(xy 81.768442 -44.420282) (xy 81.815178 -44.323508) (xy 81.73974 -44.24807) (xy 81.642712 -44.294552)
			(xy 81.606898 -44.33062) (xy 81.732628 -44.45635)
		)
		(stroke
			(width 0)
			(type solid)
		)
		(fill yes)
		(layer "F.Cu")
		(net "M_H_ECC<2>")
	)
	(gr_poly
		(pts
			(xy 81.769712 -104.301036) (xy 81.643982 -104.157526) (xy 81.608168 -104.121458) (xy 81.518252 -104.211374)
			(xy 81.55432 -104.247188) (xy 81.69783 -104.372918)
		)
		(stroke
			(width 0)
			(type solid)
		)
		(fill yes)
		(layer "F.Cu")
		(net "M_L_ECC<0>")
	)
	(gr_poly
		(pts
			(xy 81.776824 -47.16018) (xy 81.812638 -47.124112) (xy 81.686908 -46.998382) (xy 81.651094 -47.03445)
			(xy 81.604358 -47.131224) (xy 81.679796 -47.206662)
		)
		(stroke
			(width 0)
			(type solid)
		)
		(fill yes)
		(layer "F.Cu")
		(net "M_H_DQS_DP<17>")
	)
	(gr_poly
		(pts
			(xy 81.785714 -47.456598) (xy 81.83245 -47.35957) (xy 81.757012 -47.284132) (xy 81.659984 -47.330868)
			(xy 81.623916 -47.366682) (xy 81.749646 -47.492412)
		)
		(stroke
			(width 0)
			(type solid)
		)
		(fill yes)
		(layer "F.Cu")
		(net "M_H_ECC<1>")
	)
	(gr_poly
		(pts
			(xy 81.813146 -45.902372) (xy 81.84896 -45.866558) (xy 81.72323 -45.740828) (xy 81.687416 -45.776642)
			(xy 81.64068 -45.87367) (xy 81.716118 -45.949108)
		)
		(stroke
			(width 0)
			(type solid)
		)
		(fill yes)
		(layer "F.Cu")
		(net "M_H_DQS_DP<8>")
	)
	(gr_poly
		(pts
			(xy 81.821782 -46.199044) (xy 81.868518 -46.102016) (xy 81.79308 -46.026578) (xy 81.696306 -46.073314)
			(xy 81.660238 -46.109128) (xy 81.785968 -46.234858)
		)
		(stroke
			(width 0)
			(type solid)
		)
		(fill yes)
		(layer "F.Cu")
		(net "M_H_DQS_DN<8>")
	)
	(gr_poly
		(pts
			(xy 81.832704 -106.680762) (xy 81.796636 -106.644948) (xy 81.652872 -106.519218) (xy 81.581244 -106.5911)
			(xy 81.706974 -106.734864) (xy 81.742788 -106.770678)
		)
		(stroke
			(width 0)
			(type solid)
		)
		(fill yes)
		(layer "F.Cu")
		(net "M_L_DQS_DP<8>")
	)
	(gr_poly
		(pts
			(xy 81.841594 -103.888032) (xy 81.80578 -103.852218) (xy 81.662016 -103.726488) (xy 81.590134 -103.798116)
			(xy 81.715864 -103.94188) (xy 81.751678 -103.977948)
		)
		(stroke
			(width 0)
			(type solid)
		)
		(fill yes)
		(layer "F.Cu")
		(net "M_L_ECC<0>")
	)
	(gr_poly
		(pts
			(xy 81.849214 -44.644818) (xy 81.885282 -44.609004) (xy 81.759552 -44.483274) (xy 81.723484 -44.519088)
			(xy 81.677002 -44.616116) (xy 81.75244 -44.691554)
		)
		(stroke
			(width 0)
			(type solid)
		)
		(fill yes)
		(layer "F.Cu")
		(net "M_H_ECC<2>")
	)
	(gr_poly
		(pts
			(xy 81.850484 -108.11764) (xy 81.724754 -107.97413) (xy 81.68894 -107.938062) (xy 81.599024 -108.027978)
			(xy 81.635092 -108.063792) (xy 81.778602 -108.189522)
		)
		(stroke
			(width 0)
			(type solid)
		)
		(fill yes)
		(layer "F.Cu")
		(net "M_L_ECC<7>")
	)
	(gr_poly
		(pts
			(xy 81.858104 -44.941236) (xy 81.90484 -44.844462) (xy 81.829402 -44.769024) (xy 81.732374 -44.81576)
			(xy 81.69656 -44.851574) (xy 81.82229 -44.977304)
		)
		(stroke
			(width 0)
			(type solid)
		)
		(fill yes)
		(layer "F.Cu")
		(net "M_H_ECC<7>")
	)
	(gr_poly
		(pts
			(xy 81.859628 -105.32491) (xy 81.733898 -105.181146) (xy 81.69783 -105.145332) (xy 81.608168 -105.234994)
			(xy 81.643982 -105.271062) (xy 81.787746 -105.396792)
		)
		(stroke
			(width 0)
			(type solid)
		)
		(fill yes)
		(layer "F.Cu")
		(net "M_L_DQS_DP<17>")
	)
	(gr_poly
		(pts
			(xy 81.866486 -47.681134) (xy 81.9023 -47.645066) (xy 81.77657 -47.519336) (xy 81.740756 -47.555404)
			(xy 81.69402 -47.652432) (xy 81.769458 -47.72787)
		)
		(stroke
			(width 0)
			(type solid)
		)
		(fill yes)
		(layer "F.Cu")
		(net "M_H_ECC<1>")
	)
	(gr_poly
		(pts
			(xy 81.871566 -49.608232) (xy 81.871566 -49.501298) (xy 81.769966 -49.465992) (xy 81.706466 -49.465992)
			(xy 81.706466 -49.643792) (xy 81.769966 -49.643792)
		)
		(stroke
			(width 0)
			(type solid)
		)
		(fill yes)
		(layer "F.Cu")
		(net "M_H_ECC<4>")
	)
	(gr_poly
		(pts
			(xy 81.871566 -49.176432) (xy 81.871566 -49.069498) (xy 81.769966 -49.034192) (xy 81.706466 -49.034192)
			(xy 81.706466 -49.211992) (xy 81.769966 -49.211992)
		)
		(stroke
			(width 0)
			(type solid)
		)
		(fill yes)
		(layer "F.Cu")
		(net "M_H_ECC<4>")
	)
	(gr_poly
		(pts
			(xy 81.875376 -47.977552) (xy 81.922112 -47.880524) (xy 81.846674 -47.805086) (xy 81.749646 -47.851822)
			(xy 81.713578 -47.887636) (xy 81.839308 -48.013366)
		)
		(stroke
			(width 0)
			(type solid)
		)
		(fill yes)
		(layer "F.Cu")
		(net "M_H_ECC<0>")
	)
	(gr_poly
		(pts
			(xy 81.902808 -46.42358) (xy 81.938622 -46.387512) (xy 81.812892 -46.261782) (xy 81.777078 -46.29785)
			(xy 81.730342 -46.394624) (xy 81.80578 -46.470062)
		)
		(stroke
			(width 0)
			(type solid)
		)
		(fill yes)
		(layer "F.Cu")
		(net "M_H_DQS_DN<8>")
	)
	(gr_poly
		(pts
			(xy 81.911698 -46.719998) (xy 81.95818 -46.62297) (xy 81.882742 -46.547532) (xy 81.785968 -46.594268)
			(xy 81.7499 -46.630082) (xy 81.87563 -46.755812)
		)
		(stroke
			(width 0)
			(type solid)
		)
		(fill yes)
		(layer "F.Cu")
		(net "M_H_DQS_DN<17>")
	)
	(gr_poly
		(pts
			(xy 81.922366 -107.704636) (xy 81.886552 -107.668822) (xy 81.742788 -107.543092) (xy 81.670906 -107.61472)
			(xy 81.796636 -107.758484) (xy 81.832704 -107.794298)
		)
		(stroke
			(width 0)
			(type solid)
		)
		(fill yes)
		(layer "F.Cu")
		(net "M_L_ECC<7>")
	)
	(gr_poly
		(pts
			(xy 81.931256 -104.911906) (xy 81.895442 -104.875838) (xy 81.751678 -104.750108) (xy 81.68005 -104.82199)
			(xy 81.80578 -104.965754) (xy 81.841594 -105.001568)
		)
		(stroke
			(width 0)
			(type solid)
		)
		(fill yes)
		(layer "F.Cu")
		(net "M_L_DQS_DP<17>")
	)
	(gr_poly
		(pts
			(xy 81.93913 -45.165772) (xy 81.974944 -45.129958) (xy 81.849214 -45.004228) (xy 81.8134 -45.040042)
			(xy 81.766664 -45.13707) (xy 81.842102 -45.212508)
		)
		(stroke
			(width 0)
			(type solid)
		)
		(fill yes)
		(layer "F.Cu")
		(net "M_H_ECC<7>")
	)
	(gr_poly
		(pts
			(xy 81.947766 -45.462444) (xy 81.994502 -45.365416) (xy 81.919064 -45.289978) (xy 81.822036 -45.336714)
			(xy 81.786222 -45.372528) (xy 81.911952 -45.498258)
		)
		(stroke
			(width 0)
			(type solid)
		)
		(fill yes)
		(layer "F.Cu")
		(net "M_H_ECC<6>")
	)
	(gr_poly
		(pts
			(xy 81.94929 -106.34853) (xy 81.82356 -106.20502) (xy 81.787746 -106.168952) (xy 81.69783 -106.258868)
			(xy 81.733898 -106.294682) (xy 81.877408 -106.420412)
		)
		(stroke
			(width 0)
			(type solid)
		)
		(fill yes)
		(layer "F.Cu")
		(net "M_L_DQS_DN<8>")
	)
	(gr_poly
		(pts
			(xy 81.956148 -48.202088) (xy 81.991962 -48.16602) (xy 81.866232 -48.04029) (xy 81.830418 -48.076358)
			(xy 81.783682 -48.173386) (xy 81.85912 -48.248824)
		)
		(stroke
			(width 0)
			(type solid)
		)
		(fill yes)
		(layer "F.Cu")
		(net "M_H_ECC<0>")
	)
	(gr_poly
		(pts
			(xy 81.95818 -103.555546) (xy 81.83245 -103.412036) (xy 81.796636 -103.375968) (xy 81.70672 -103.465884)
			(xy 81.742788 -103.501698) (xy 81.886298 -103.627428)
		)
		(stroke
			(width 0)
			(type solid)
		)
		(fill yes)
		(layer "F.Cu")
		(net "M_L_ECC<5>")
	)
	(gr_poly
		(pts
			(xy 81.965038 -48.498506) (xy 82.011774 -48.401478) (xy 81.936336 -48.32604) (xy 81.839308 -48.372776)
			(xy 81.80324 -48.40859) (xy 81.92897 -48.53432)
		)
		(stroke
			(width 0)
			(type solid)
		)
		(fill yes)
		(layer "F.Cu")
		(net "M_H_ECC<5>")
	)
	(gr_poly
		(pts
			(xy 81.99247 -46.944534) (xy 82.028284 -46.908466) (xy 81.902554 -46.782736) (xy 81.86674 -46.818804)
			(xy 81.820004 -46.915578) (xy 81.895442 -46.991016)
		)
		(stroke
			(width 0)
			(type solid)
		)
		(fill yes)
		(layer "F.Cu")
		(net "M_H_DQS_DN<17>")
	)
	(gr_poly
		(pts
			(xy 82.00136 -47.240952) (xy 82.048096 -47.143924) (xy 81.972658 -47.068486) (xy 81.87563 -47.115222)
			(xy 81.839562 -47.151036) (xy 81.965292 -47.276766)
		)
		(stroke
			(width 0)
			(type solid)
		)
		(fill yes)
		(layer "F.Cu")
		(net "M_H_DQS_DP<17>")
	)
	(gr_poly
		(pts
			(xy 82.021172 -108.737146) (xy 81.976214 -108.692442) (xy 81.83245 -108.566712) (xy 81.760568 -108.638594)
			(xy 81.886298 -108.782104) (xy 81.931256 -108.827062)
		)
		(stroke
			(width 0)
			(type solid)
		)
		(fill yes)
		(layer "F.Cu")
		(net "M_L_ECC<3>")
	)
	(gr_poly
		(pts
			(xy 82.021172 -105.935526) (xy 81.985358 -105.899712) (xy 81.841594 -105.773982) (xy 81.769712 -105.84561)
			(xy 81.895442 -105.989374) (xy 81.931256 -106.025442)
		)
		(stroke
			(width 0)
			(type solid)
		)
		(fill yes)
		(layer "F.Cu")
		(net "M_L_DQS_DN<8>")
	)
	(gr_poly
		(pts
			(xy 82.023966 -49.681892) (xy 81.973166 -49.681892) (xy 81.871566 -49.717198) (xy 81.871566 -49.824132)
			(xy 81.973166 -49.859692) (xy 82.023966 -49.859692)
		)
		(stroke
			(width 0)
			(type solid)
		)
		(fill yes)
		(layer "F.Cu")
		(net "M_H_ECC<5>")
	)
	(gr_poly
		(pts
			(xy 82.023966 -49.250092) (xy 81.973166 -49.250092) (xy 81.871566 -49.285398) (xy 81.871566 -49.392332)
			(xy 81.973166 -49.427892) (xy 82.023966 -49.427892)
		)
		(stroke
			(width 0)
			(type solid)
		)
		(fill yes)
		(layer "F.Cu")
		(net "M_H_ECC<5>")
	)
	(gr_poly
		(pts
			(xy 82.023966 -48.818292) (xy 81.973166 -48.818292) (xy 81.871566 -48.853598) (xy 81.871566 -48.960532)
			(xy 81.973166 -48.996092) (xy 82.023966 -48.996092)
		)
		(stroke
			(width 0)
			(type solid)
		)
		(fill yes)
		(layer "F.Cu")
		(net "M_H_ECC<5>")
	)
	(gr_poly
		(pts
			(xy 82.028792 -45.686726) (xy 82.064606 -45.650912) (xy 81.938876 -45.525182) (xy 81.903062 -45.560996)
			(xy 81.856326 -45.658024) (xy 81.931764 -45.733462)
		)
		(stroke
			(width 0)
			(type solid)
		)
		(fill yes)
		(layer "F.Cu")
		(net "M_H_ECC<6>")
	)
	(gr_poly
		(pts
			(xy 82.030062 -103.142542) (xy 81.994248 -103.106728) (xy 81.850484 -102.980998) (xy 81.778602 -103.052626)
			(xy 81.904332 -103.19639) (xy 81.940146 -103.232458)
		)
		(stroke
			(width 0)
			(type solid)
		)
		(fill yes)
		(layer "F.Cu")
		(net "M_L_ECC<5>")
	)
	(gr_poly
		(pts
			(xy 82.037428 -45.983398) (xy 82.084164 -45.88637) (xy 82.008726 -45.810932) (xy 81.911952 -45.857668)
			(xy 81.875884 -45.893482) (xy 82.001614 -46.019212)
		)
		(stroke
			(width 0)
			(type solid)
		)
		(fill yes)
		(layer "F.Cu")
		(net "M_H_DQS_DP<8>")
	)
	(gr_poly
		(pts
			(xy 82.039206 -107.372404) (xy 81.913476 -107.22864) (xy 81.877408 -107.192826) (xy 81.787746 -107.282488)
			(xy 81.82356 -107.318556) (xy 81.967324 -107.444286)
		)
		(stroke
			(width 0)
			(type solid)
		)
		(fill yes)
		(layer "F.Cu")
		(net "M_L_ECC<6>")
	)
	(gr_poly
		(pts
			(xy 82.048096 -104.57942) (xy 81.922366 -104.43591) (xy 81.886552 -104.399842) (xy 81.796636 -104.489758)
			(xy 81.832704 -104.525572) (xy 81.976214 -104.651302)
		)
		(stroke
			(width 0)
			(type solid)
		)
		(fill yes)
		(layer "F.Cu")
		(net "M_L_ECC<1>")
	)
	(gr_poly
		(pts
			(xy 82.06486 -44.429426) (xy 82.109818 -44.384468) (xy 81.984088 -44.258738) (xy 81.93913 -44.303696)
			(xy 81.892394 -44.400724) (xy 81.967832 -44.475908)
		)
		(stroke
			(width 0)
			(type solid)
		)
		(fill yes)
		(layer "F.Cu")
		(net "M_H_ECC<3>")
	)
	(gr_poly
		(pts
			(xy 82.07375 -44.72559) (xy 82.120486 -44.628816) (xy 82.045048 -44.553378) (xy 81.94802 -44.600114)
			(xy 81.912206 -44.635928) (xy 82.037936 -44.761658)
		)
		(stroke
			(width 0)
			(type solid)
		)
		(fill yes)
		(layer "F.Cu")
		(net "M_H_ECC<2>")
	)
	(gr_poly
		(pts
			(xy 82.082132 -47.465488) (xy 82.117946 -47.42942) (xy 81.992216 -47.30369) (xy 81.956402 -47.339758)
			(xy 81.909666 -47.436786) (xy 81.985104 -47.512224)
		)
		(stroke
			(width 0)
			(type solid)
		)
		(fill yes)
		(layer "F.Cu")
		(net "M_H_DQS_DP<17>")
	)
	(gr_poly
		(pts
			(xy 82.091022 -47.761906) (xy 82.137758 -47.664878) (xy 82.06232 -47.58944) (xy 81.965292 -47.636176)
			(xy 81.929224 -47.67199) (xy 82.054954 -47.79772)
		)
		(stroke
			(width 0)
			(type solid)
		)
		(fill yes)
		(layer "F.Cu")
		(net "M_H_ECC<1>")
	)
	(gr_poly
		(pts
			(xy 82.111088 -106.959146) (xy 82.07502 -106.923332) (xy 81.931256 -106.797602) (xy 81.859628 -106.869484)
			(xy 81.985358 -107.013248) (xy 82.021172 -107.049062)
		)
		(stroke
			(width 0)
			(type solid)
		)
		(fill yes)
		(layer "F.Cu")
		(net "M_L_ECC<6>")
	)
	(gr_poly
		(pts
			(xy 82.118454 -46.207934) (xy 82.154268 -46.171866) (xy 82.028538 -46.046136) (xy 81.992724 -46.082204)
			(xy 81.945988 -46.178978) (xy 82.021426 -46.254416)
		)
		(stroke
			(width 0)
			(type solid)
		)
		(fill yes)
		(layer "F.Cu")
		(net "M_H_DQS_DP<8>")
	)
	(gr_poly
		(pts
			(xy 82.119978 -104.166416) (xy 82.084164 -104.130602) (xy 81.9404 -104.004872) (xy 81.868518 -104.0765)
			(xy 81.994248 -104.220264) (xy 82.030062 -104.256332)
		)
		(stroke
			(width 0)
			(type solid)
		)
		(fill yes)
		(layer "F.Cu")
		(net "M_L_ECC<1>")
	)
	(gr_poly
		(pts
			(xy 82.127344 -46.504352) (xy 82.173826 -46.407324) (xy 82.098388 -46.331886) (xy 82.001614 -46.378622)
			(xy 81.965546 -46.414436) (xy 82.091276 -46.540166)
		)
		(stroke
			(width 0)
			(type solid)
		)
		(fill yes)
		(layer "F.Cu")
		(net "M_H_DQS_DN<8>")
	)
	(gr_poly
		(pts
			(xy 82.128868 -108.396024) (xy 82.003138 -108.252514) (xy 81.967324 -108.216446) (xy 81.877408 -108.306362)
			(xy 81.913476 -108.342176) (xy 82.056986 -108.467906)
		)
		(stroke
			(width 0)
			(type solid)
		)
		(fill yes)
		(layer "F.Cu")
		(net "M_L_ECC<2>")
	)
	(gr_poly
		(pts
			(xy 82.138012 -105.603294) (xy 82.012282 -105.45953) (xy 81.976214 -105.423716) (xy 81.886552 -105.513378)
			(xy 81.922366 -105.549446) (xy 82.06613 -105.675176)
		)
		(stroke
			(width 0)
			(type solid)
		)
		(fill yes)
		(layer "F.Cu")
		(net "M_L_DQS_DN<17>")
	)
	(gr_poly
		(pts
			(xy 82.154776 -44.950126) (xy 82.19059 -44.914312) (xy 82.06486 -44.788582) (xy 82.029046 -44.824396)
			(xy 81.98231 -44.921424) (xy 82.057748 -44.996862)
		)
		(stroke
			(width 0)
			(type solid)
		)
		(fill yes)
		(layer "F.Cu")
		(net "M_H_ECC<2>")
	)
	(gr_poly
		(pts
			(xy 82.163412 -45.246798) (xy 82.210148 -45.14977) (xy 82.13471 -45.074332) (xy 82.037682 -45.121068)
			(xy 82.001868 -45.156882) (xy 82.127598 -45.282612)
		)
		(stroke
			(width 0)
			(type solid)
		)
		(fill yes)
		(layer "F.Cu")
		(net "M_H_ECC<7>")
	)
	(gr_poly
		(pts
			(xy 82.171794 -47.986442) (xy 82.207608 -47.950374) (xy 82.081878 -47.824644) (xy 82.046064 -47.860712)
			(xy 81.999328 -47.95774) (xy 82.074766 -48.033178)
		)
		(stroke
			(width 0)
			(type solid)
		)
		(fill yes)
		(layer "F.Cu")
		(net "M_H_ECC<1>")
	)
	(gr_poly
		(pts
			(xy 82.176366 -49.608232) (xy 82.176366 -49.501298) (xy 82.074766 -49.465992) (xy 82.023966 -49.465992)
			(xy 82.023966 -49.643792) (xy 82.074766 -49.643792)
		)
		(stroke
			(width 0)
			(type solid)
		)
		(fill yes)
		(layer "F.Cu")
		(net "M_H_ECC<5>")
	)
	(gr_poly
		(pts
			(xy 82.176366 -49.176432) (xy 82.176366 -49.069498) (xy 82.074766 -49.034192) (xy 82.023966 -49.034192)
			(xy 82.023966 -49.211992) (xy 82.074766 -49.211992)
		)
		(stroke
			(width 0)
			(type solid)
		)
		(fill yes)
		(layer "F.Cu")
		(net "M_H_ECC<5>")
	)
	(gr_poly
		(pts
			(xy 82.176366 -48.744632) (xy 82.176366 -48.637698) (xy 82.074766 -48.602392) (xy 82.023966 -48.602392)
			(xy 82.023966 -48.780192) (xy 82.074766 -48.780192)
		)
		(stroke
			(width 0)
			(type solid)
		)
		(fill yes)
		(layer "F.Cu")
		(net "M_H_ECC<5>")
	)
	(gr_poly
		(pts
			(xy 82.180684 -48.28286) (xy 82.22742 -48.185832) (xy 82.151982 -48.110394) (xy 82.054954 -48.15713)
			(xy 82.018886 -48.192944) (xy 82.144616 -48.318674)
		)
		(stroke
			(width 0)
			(type solid)
		)
		(fill yes)
		(layer "F.Cu")
		(net "M_H_ECC<0>")
	)
	(gr_poly
		(pts
			(xy 82.183224 -54.743604) (xy 82.018632 -54.380384) (xy 81.9785 -54.398672) (xy 81.859882 -54.549802)
			(xy 81.950814 -54.751224) (xy 82.142584 -54.762146)
		)
		(stroke
			(width 0)
			(type solid)
		)
		(fill yes)
		(layer "F.Cu")
		(net "M_H_ECC<5>")
	)
	(gr_poly
		(pts
			(xy 82.20075 -107.98302) (xy 82.164936 -107.947206) (xy 82.021172 -107.821476) (xy 81.94929 -107.893104)
			(xy 82.07502 -108.036868) (xy 82.111088 -108.072682)
		)
		(stroke
			(width 0)
			(type solid)
		)
		(fill yes)
		(layer "F.Cu")
		(net "M_L_ECC<2>")
	)
	(gr_poly
		(pts
			(xy 82.208116 -46.728888) (xy 82.24393 -46.69282) (xy 82.1182 -46.56709) (xy 82.082386 -46.603158)
			(xy 82.03565 -46.699932) (xy 82.111088 -46.77537)
		)
		(stroke
			(width 0)
			(type solid)
		)
		(fill yes)
		(layer "F.Cu")
		(net "M_H_DQS_DN<8>")
	)
	(gr_poly
		(pts
			(xy 82.20964 -105.19029) (xy 82.173826 -105.154222) (xy 82.030062 -105.028492) (xy 81.958434 -105.100374)
			(xy 82.084164 -105.244138) (xy 82.119978 -105.279952)
		)
		(stroke
			(width 0)
			(type solid)
		)
		(fill yes)
		(layer "F.Cu")
		(net "M_L_DQS_DN<17>")
	)
	(gr_poly
		(pts
			(xy 82.217006 -47.025306) (xy 82.263742 -46.928278) (xy 82.188304 -46.85284) (xy 82.091276 -46.899576)
			(xy 82.055208 -46.93539) (xy 82.180938 -47.06112)
		)
		(stroke
			(width 0)
			(type solid)
		)
		(fill yes)
		(layer "F.Cu")
		(net "M_H_DQS_DN<17>")
	)
	(gr_poly
		(pts
			(xy 82.227674 -106.626914) (xy 82.101944 -106.483404) (xy 82.06613 -106.447336) (xy 81.976214 -106.537252)
			(xy 82.012282 -106.573066) (xy 82.155792 -106.698796)
		)
		(stroke
			(width 0)
			(type solid)
		)
		(fill yes)
		(layer "F.Cu")
		(net "M_L_DQS_DP<8>")
	)
	(gr_poly
		(pts
			(xy 82.236818 -103.834184) (xy 82.111088 -103.69042) (xy 82.07502 -103.654606) (xy 81.985358 -103.744268)
			(xy 82.021172 -103.780336) (xy 82.164936 -103.906066)
		)
		(stroke
			(width 0)
			(type solid)
		)
		(fill yes)
		(layer "F.Cu")
		(net "M_L_ECC<0>")
	)
	(gr_poly
		(pts
			(xy 82.244438 -45.47108) (xy 82.280252 -45.435266) (xy 82.154522 -45.309536) (xy 82.118708 -45.34535)
			(xy 82.071972 -45.442378) (xy 82.14741 -45.517816)
		)
		(stroke
			(width 0)
			(type solid)
		)
		(fill yes)
		(layer "F.Cu")
		(net "M_H_ECC<7>")
	)
	(gr_poly
		(pts
			(xy 82.253074 -45.767752) (xy 82.29981 -45.670724) (xy 82.224372 -45.595286) (xy 82.127598 -45.642022)
			(xy 82.09153 -45.677836) (xy 82.21726 -45.803566)
		)
		(stroke
			(width 0)
			(type solid)
		)
		(fill yes)
		(layer "F.Cu")
		(net "M_H_ECC<6>")
	)
	(gr_poly
		(pts
			(xy 82.297778 -47.249842) (xy 82.333592 -47.213774) (xy 82.207862 -47.088044) (xy 82.172048 -47.124112)
			(xy 82.125312 -47.22114) (xy 82.20075 -47.296578)
		)
		(stroke
			(width 0)
			(type solid)
		)
		(fill yes)
		(layer "F.Cu")
		(net "M_H_DQS_DN<17>")
	)
	(gr_poly
		(pts
			(xy 82.299556 -106.21391) (xy 82.263742 -106.178096) (xy 82.119978 -106.052366) (xy 82.048096 -106.123994)
			(xy 82.173826 -106.267758) (xy 82.20964 -106.303826)
		)
		(stroke
			(width 0)
			(type solid)
		)
		(fill yes)
		(layer "F.Cu")
		(net "M_L_DQS_DP<8>")
	)
	(gr_poly
		(pts
			(xy 82.304636 -52.724812) (xy 82.303874 -52.504086) (xy 82.13344 -52.415694) (xy 82.088736 -52.415948)
			(xy 82.09026 -52.814474) (xy 82.13471 -52.814474)
		)
		(stroke
			(width 0)
			(type solid)
		)
		(fill yes)
		(layer "F.Cu")
		(net "M_H_ECC<0>")
	)
	(gr_poly
		(pts
			(xy 82.306668 -47.54626) (xy 82.353404 -47.449232) (xy 82.277966 -47.373794) (xy 82.180938 -47.42053)
			(xy 82.14487 -47.456344) (xy 82.2706 -47.582074)
		)
		(stroke
			(width 0)
			(type solid)
		)
		(fill yes)
		(layer "F.Cu")
		(net "M_H_DQS_DP<17>")
	)
	(gr_poly
		(pts
			(xy 82.311494 -97.247202) (xy 82.289142 -97.208848) (xy 82.12709 -97.105978) (xy 81.935828 -97.216468)
			(xy 81.943956 -97.408238) (xy 81.966054 -97.446846)
		)
		(stroke
			(width 0)
			(type solid)
		)
		(fill yes)
		(layer "F.Cu")
		(net "M_L_ECC<4>")
	)
	(gr_poly
		(pts
			(xy 82.31759 -107.650788) (xy 82.19186 -107.507024) (xy 82.155792 -107.47121) (xy 82.06613 -107.560872)
			(xy 82.101944 -107.59694) (xy 82.245708 -107.72267)
		)
		(stroke
			(width 0)
			(type solid)
		)
		(fill yes)
		(layer "F.Cu")
		(net "M_L_ECC<7>")
	)
	(gr_poly
		(pts
			(xy 82.32648 -104.857804) (xy 82.20075 -104.714294) (xy 82.164936 -104.678226) (xy 82.07502 -104.768142)
			(xy 82.111088 -104.803956) (xy 82.254598 -104.929686)
		)
		(stroke
			(width 0)
			(type solid)
		)
		(fill yes)
		(layer "F.Cu")
		(net "M_L_DQS_DP<17>")
	)
	(gr_poly
		(pts
			(xy 82.328766 -49.681892) (xy 82.277966 -49.681892) (xy 82.176366 -49.717198) (xy 82.176366 -49.824132)
			(xy 82.277966 -49.859692) (xy 82.328766 -49.859692)
		)
		(stroke
			(width 0)
			(type solid)
		)
		(fill yes)
		(layer "F.Cu")
		(net "M_H_ECC<0>")
	)
	(gr_poly
		(pts
			(xy 82.328766 -49.250092) (xy 82.277966 -49.250092) (xy 82.176366 -49.285398) (xy 82.176366 -49.392332)
			(xy 82.277966 -49.427892) (xy 82.328766 -49.427892)
		)
		(stroke
			(width 0)
			(type solid)
		)
		(fill yes)
		(layer "F.Cu")
		(net "M_H_ECC<0>")
	)
	(gr_poly
		(pts
			(xy 82.328766 -48.818292) (xy 82.277966 -48.818292) (xy 82.176366 -48.853598) (xy 82.176366 -48.960532)
			(xy 82.277966 -48.996092) (xy 82.328766 -48.996092)
		)
		(stroke
			(width 0)
			(type solid)
		)
		(fill yes)
		(layer "F.Cu")
		(net "M_H_ECC<0>")
	)
	(gr_poly
		(pts
			(xy 82.3341 -45.992288) (xy 82.369914 -45.95622) (xy 82.244184 -45.83049) (xy 82.20837 -45.866558)
			(xy 82.161634 -45.963332) (xy 82.237072 -46.03877)
		)
		(stroke
			(width 0)
			(type solid)
		)
		(fill yes)
		(layer "F.Cu")
		(net "M_H_ECC<6>")
	)
	(gr_poly
		(pts
			(xy 82.34299 -46.288706) (xy 82.389472 -46.191678) (xy 82.314034 -46.11624) (xy 82.21726 -46.162976)
			(xy 82.181192 -46.19879) (xy 82.306922 -46.32452)
		)
		(stroke
			(width 0)
			(type solid)
		)
		(fill yes)
		(layer "F.Cu")
		(net "M_H_DQS_DP<8>")
	)
	(gr_poly
		(pts
			(xy 82.370168 -44.734734) (xy 82.415126 -44.689776) (xy 82.289396 -44.564046) (xy 82.244438 -44.609004)
			(xy 82.197702 -44.706032) (xy 82.27314 -44.78147)
		)
		(stroke
			(width 0)
			(type solid)
		)
		(fill yes)
		(layer "F.Cu")
		(net "M_H_ECC<3>")
	)
	(gr_poly
		(pts
			(xy 82.375756 -103.569262) (xy 82.32902 -103.472488) (xy 82.293206 -103.43642) (xy 82.167476 -103.56215)
			(xy 82.20329 -103.598218) (xy 82.300318 -103.6447)
		)
		(stroke
			(width 0)
			(type solid)
		)
		(fill yes)
		(layer "F.Cu")
		(net "M_L_ECC<0>")
	)
	(gr_poly
		(pts
			(xy 82.379058 -45.031152) (xy 82.425794 -44.934124) (xy 82.350356 -44.858686) (xy 82.253328 -44.905422)
			(xy 82.217514 -44.941236) (xy 82.343244 -45.066966)
		)
		(stroke
			(width 0)
			(type solid)
		)
		(fill yes)
		(layer "F.Cu")
		(net "M_H_ECC<2>")
	)
	(gr_poly
		(pts
			(xy 82.38744 -47.770796) (xy 82.423254 -47.734728) (xy 82.297524 -47.608998) (xy 82.26171 -47.645066)
			(xy 82.214974 -47.742094) (xy 82.290412 -47.817532)
		)
		(stroke
			(width 0)
			(type solid)
		)
		(fill yes)
		(layer "F.Cu")
		(net "M_H_DQS_DP<17>")
	)
	(gr_poly
		(pts
			(xy 82.389472 -107.23753) (xy 82.353404 -107.201716) (xy 82.20964 -107.075986) (xy 82.138012 -107.147868)
			(xy 82.263742 -107.291632) (xy 82.299556 -107.327446)
		)
		(stroke
			(width 0)
			(type solid)
		)
		(fill yes)
		(layer "F.Cu")
		(net "M_L_ECC<7>")
	)
	(gr_poly
		(pts
			(xy 82.39633 -48.067214) (xy 82.443066 -47.970186) (xy 82.367628 -47.894748) (xy 82.2706 -47.941484)
			(xy 82.234532 -47.977298) (xy 82.360262 -48.103028)
		)
		(stroke
			(width 0)
			(type solid)
		)
		(fill yes)
		(layer "F.Cu")
		(net "M_H_ECC<1>")
	)
	(gr_poly
		(pts
			(xy 82.398362 -104.4448) (xy 82.362548 -104.408986) (xy 82.218784 -104.283256) (xy 82.146902 -104.354884)
			(xy 82.272632 -104.498648) (xy 82.308446 -104.534716)
		)
		(stroke
			(width 0)
			(type solid)
		)
		(fill yes)
		(layer "F.Cu")
		(net "M_L_DQS_DP<17>")
	)
	(gr_poly
		(pts
			(xy 82.416396 -105.881678) (xy 82.290666 -105.737914) (xy 82.254598 -105.7021) (xy 82.164936 -105.791762)
			(xy 82.20075 -105.82783) (xy 82.344514 -105.95356)
		)
		(stroke
			(width 0)
			(type solid)
		)
		(fill yes)
		(layer "F.Cu")
		(net "M_L_DQS_DN<8>")
	)
	(gr_poly
		(pts
			(xy 82.423762 -46.513242) (xy 82.459576 -46.477174) (xy 82.333846 -46.351444) (xy 82.298032 -46.387512)
			(xy 82.251296 -46.484286) (xy 82.326734 -46.559724)
		)
		(stroke
			(width 0)
			(type solid)
		)
		(fill yes)
		(layer "F.Cu")
		(net "M_H_DQS_DP<8>")
	)
	(gr_poly
		(pts
			(xy 82.432652 -46.80966) (xy 82.479388 -46.712632) (xy 82.40395 -46.637194) (xy 82.306922 -46.68393)
			(xy 82.270854 -46.719744) (xy 82.396584 -46.845474)
		)
		(stroke
			(width 0)
			(type solid)
		)
		(fill yes)
		(layer "F.Cu")
		(net "M_H_DQS_DN<8>")
	)
	(gr_poly
		(pts
			(xy 82.44586 -103.283766) (xy 82.410046 -103.247952) (xy 82.313018 -103.201216) (xy 82.23758 -103.276654)
			(xy 82.284316 -103.373682) (xy 82.32013 -103.409496)
		)
		(stroke
			(width 0)
			(type solid)
		)
		(fill yes)
		(layer "F.Cu")
		(net "M_L_ECC<0>")
	)
	(gr_poly
		(pts
			(xy 82.460084 -45.255434) (xy 82.495898 -45.21962) (xy 82.370168 -45.09389) (xy 82.334354 -45.129704)
			(xy 82.287618 -45.226732) (xy 82.363056 -45.30217)
		)
		(stroke
			(width 0)
			(type solid)
		)
		(fill yes)
		(layer "F.Cu")
		(net "M_H_ECC<2>")
	)
	(gr_poly
		(pts
			(xy 82.46872 -45.552106) (xy 82.515456 -45.455078) (xy 82.440018 -45.37964) (xy 82.343244 -45.426376)
			(xy 82.307176 -45.46219) (xy 82.432906 -45.58792)
		)
		(stroke
			(width 0)
			(type solid)
		)
		(fill yes)
		(layer "F.Cu")
		(net "M_H_ECC<7>")
	)
	(gr_poly
		(pts
			(xy 82.477102 -48.29175) (xy 82.512916 -48.255682) (xy 82.387186 -48.129952) (xy 82.351372 -48.16602)
			(xy 82.304636 -48.263048) (xy 82.380074 -48.338486)
		)
		(stroke
			(width 0)
			(type solid)
		)
		(fill yes)
		(layer "F.Cu")
		(net "M_H_ECC<1>")
	)
	(gr_poly
		(pts
			(xy 82.481166 -49.608232) (xy 82.481166 -49.501298) (xy 82.379566 -49.465992) (xy 82.328766 -49.465992)
			(xy 82.328766 -49.643792) (xy 82.379566 -49.643792)
		)
		(stroke
			(width 0)
			(type solid)
		)
		(fill yes)
		(layer "F.Cu")
		(net "M_H_ECC<0>")
	)
	(gr_poly
		(pts
			(xy 82.481166 -49.176432) (xy 82.481166 -49.069498) (xy 82.379566 -49.034192) (xy 82.328766 -49.034192)
			(xy 82.328766 -49.211992) (xy 82.379566 -49.211992)
		)
		(stroke
			(width 0)
			(type solid)
		)
		(fill yes)
		(layer "F.Cu")
		(net "M_H_ECC<0>")
	)
	(gr_poly
		(pts
			(xy 82.481166 -48.744632) (xy 82.481166 -48.637698) (xy 82.379566 -48.602392) (xy 82.328766 -48.602392)
			(xy 82.328766 -48.780192) (xy 82.379566 -48.780192)
		)
		(stroke
			(width 0)
			(type solid)
		)
		(fill yes)
		(layer "F.Cu")
		(net "M_H_ECC<0>")
	)
	(gr_poly
		(pts
			(xy 82.488024 -108.270294) (xy 82.443066 -108.225336) (xy 82.299556 -108.099606) (xy 82.227674 -108.171488)
			(xy 82.353404 -108.315252) (xy 82.398362 -108.359956)
		)
		(stroke
			(width 0)
			(type solid)
		)
		(fill yes)
		(layer "F.Cu")
		(net "M_L_ECC<3>")
	)
	(gr_poly
		(pts
			(xy 82.488024 -105.468674) (xy 82.45221 -105.432606) (xy 82.308446 -105.306876) (xy 82.236818 -105.378758)
			(xy 82.362548 -105.522522) (xy 82.398362 -105.558336)
		)
		(stroke
			(width 0)
			(type solid)
		)
		(fill yes)
		(layer "F.Cu")
		(net "M_L_DQS_DN<8>")
	)
	(gr_poly
		(pts
			(xy 82.506058 -106.905298) (xy 82.380328 -106.761788) (xy 82.344514 -106.72572) (xy 82.254598 -106.815636)
			(xy 82.290666 -106.85145) (xy 82.434176 -106.97718)
		)
		(stroke
			(width 0)
			(type solid)
		)
		(fill yes)
		(layer "F.Cu")
		(net "M_L_ECC<6>")
	)
	(gr_poly
		(pts
			(xy 82.513424 -47.034196) (xy 82.549238 -46.998128) (xy 82.423508 -46.872398) (xy 82.387694 -46.908466)
			(xy 82.340958 -47.005494) (xy 82.416396 -47.080932)
		)
		(stroke
			(width 0)
			(type solid)
		)
		(fill yes)
		(layer "F.Cu")
		(net "M_H_DQS_DN<8>")
	)
	(gr_poly
		(pts
			(xy 82.515456 -104.11206) (xy 82.389726 -103.96855) (xy 82.353912 -103.932482) (xy 82.263996 -104.022398)
			(xy 82.300064 -104.058212) (xy 82.443574 -104.183942)
		)
		(stroke
			(width 0)
			(type solid)
		)
		(fill yes)
		(layer "F.Cu")
		(net "M_L_ECC<1>")
	)
	(gr_poly
		(pts
			(xy 82.522314 -47.330614) (xy 82.56905 -47.233586) (xy 82.493612 -47.158148) (xy 82.396584 -47.204884)
			(xy 82.360516 -47.240698) (xy 82.486246 -47.366428)
		)
		(stroke
			(width 0)
			(type solid)
		)
		(fill yes)
		(layer "F.Cu")
		(net "M_H_DQS_DN<17>")
	)
	(gr_poly
		(pts
			(xy 82.549746 -45.776642) (xy 82.58556 -45.740574) (xy 82.45983 -45.614844) (xy 82.424016 -45.650912)
			(xy 82.37728 -45.747686) (xy 82.452718 -45.823124)
		)
		(stroke
			(width 0)
			(type solid)
		)
		(fill yes)
		(layer "F.Cu")
		(net "M_H_ECC<7>")
	)
	(gr_poly
		(pts
			(xy 82.558636 -46.07306) (xy 82.605118 -45.976032) (xy 82.52968 -45.900594) (xy 82.432906 -45.94733)
			(xy 82.396838 -45.983144) (xy 82.522568 -46.108874)
		)
		(stroke
			(width 0)
			(type solid)
		)
		(fill yes)
		(layer "F.Cu")
		(net "M_H_ECC<6>")
	)
	(gr_poly
		(pts
			(xy 82.57794 -106.492294) (xy 82.542126 -106.45648) (xy 82.398362 -106.33075) (xy 82.32648 -106.402378)
			(xy 82.45221 -106.546142) (xy 82.488024 -106.58221)
		)
		(stroke
			(width 0)
			(type solid)
		)
		(fill yes)
		(layer "F.Cu")
		(net "M_L_ECC<6>")
	)
	(gr_poly
		(pts
			(xy 82.595974 -107.929172) (xy 82.470244 -107.785408) (xy 82.434176 -107.749594) (xy 82.344514 -107.839256)
			(xy 82.380328 -107.875324) (xy 82.524092 -108.001054)
		)
		(stroke
			(width 0)
			(type solid)
		)
		(fill yes)
		(layer "F.Cu")
		(net "M_L_ECC<2>")
	)
	(gr_poly
		(pts
			(xy 82.603086 -47.55515) (xy 82.6389 -47.519082) (xy 82.51317 -47.393352) (xy 82.477356 -47.42942)
			(xy 82.43062 -47.526448) (xy 82.506058 -47.601886)
		)
		(stroke
			(width 0)
			(type solid)
		)
		(fill yes)
		(layer "F.Cu")
		(net "M_H_DQS_DN<17>")
	)
	(gr_poly
		(pts
			(xy 82.604864 -105.136188) (xy 82.479134 -104.992678) (xy 82.44332 -104.95661) (xy 82.353404 -105.046526)
			(xy 82.389472 -105.08234) (xy 82.532982 -105.20807)
		)
		(stroke
			(width 0)
			(type solid)
		)
		(fill yes)
		(layer "F.Cu")
		(net "M_L_DQS_DN<17>")
	)
	(gr_poly
		(pts
			(xy 82.611722 -54.415436) (xy 82.567272 -54.415436) (xy 82.397092 -54.504082) (xy 82.396838 -54.725062)
			(xy 82.566764 -54.814216) (xy 82.611468 -54.814216)
		)
		(stroke
			(width 0)
			(type solid)
		)
		(fill yes)
		(layer "F.Cu")
		(net "M_H_DQS_DN<8>")
	)
	(gr_poly
		(pts
			(xy 82.611976 -47.851568) (xy 82.658712 -47.75454) (xy 82.583274 -47.679102) (xy 82.486246 -47.725838)
			(xy 82.450178 -47.761652) (xy 82.575908 -47.887382)
		)
		(stroke
			(width 0)
			(type solid)
		)
		(fill yes)
		(layer "F.Cu")
		(net "M_H_DQS_DP<17>")
	)
	(gr_poly
		(pts
			(xy 82.633566 -49.681892) (xy 82.582766 -49.681892) (xy 82.481166 -49.717198) (xy 82.481166 -49.824132)
			(xy 82.582766 -49.859692) (xy 82.633566 -49.859692)
		)
		(stroke
			(width 0)
			(type solid)
		)
		(fill yes)
		(layer "F.Cu")
		(net "M_H_ECC<1>")
	)
	(gr_poly
		(pts
			(xy 82.633566 -49.250092) (xy 82.582766 -49.250092) (xy 82.481166 -49.285398) (xy 82.481166 -49.392332)
			(xy 82.582766 -49.427892) (xy 82.633566 -49.427892)
		)
		(stroke
			(width 0)
			(type solid)
		)
		(fill yes)
		(layer "F.Cu")
		(net "M_H_ECC<1>")
	)
	(gr_poly
		(pts
			(xy 82.633566 -48.818292) (xy 82.582766 -48.818292) (xy 82.481166 -48.853598) (xy 82.481166 -48.960532)
			(xy 82.582766 -48.996092) (xy 82.633566 -48.996092)
		)
		(stroke
			(width 0)
			(type solid)
		)
		(fill yes)
		(layer "F.Cu")
		(net "M_H_ECC<1>")
	)
	(gr_poly
		(pts
			(xy 82.633566 -48.386492) (xy 82.582766 -48.386492) (xy 82.481166 -48.421798) (xy 82.481166 -48.528732)
			(xy 82.582766 -48.564292) (xy 82.633566 -48.564292)
		)
		(stroke
			(width 0)
			(type solid)
		)
		(fill yes)
		(layer "F.Cu")
		(net "M_H_ECC<1>")
	)
	(gr_poly
		(pts
			(xy 82.639408 -46.297596) (xy 82.675222 -46.261528) (xy 82.549492 -46.135798) (xy 82.513678 -46.171866)
			(xy 82.466942 -46.26864) (xy 82.54238 -46.344078)
		)
		(stroke
			(width 0)
			(type solid)
		)
		(fill yes)
		(layer "F.Cu")
		(net "M_H_ECC<6>")
	)
	(gr_poly
		(pts
			(xy 82.648298 -46.594014) (xy 82.695034 -46.496986) (xy 82.619596 -46.421548) (xy 82.522568 -46.468284)
			(xy 82.4865 -46.504098) (xy 82.61223 -46.629828)
		)
		(stroke
			(width 0)
			(type solid)
		)
		(fill yes)
		(layer "F.Cu")
		(net "M_H_DQS_DP<8>")
	)
	(gr_poly
		(pts
			(xy 82.661506 -103.499412) (xy 82.625692 -103.463598) (xy 82.528664 -103.416862) (xy 82.453226 -103.4923)
			(xy 82.499962 -103.589328) (xy 82.535776 -103.625142)
		)
		(stroke
			(width 0)
			(type solid)
		)
		(fill yes)
		(layer "F.Cu")
		(net "M_L_ECC<1>")
	)
	(gr_poly
		(pts
			(xy 82.667856 -107.515914) (xy 82.631788 -107.4801) (xy 82.488024 -107.35437) (xy 82.416396 -107.426252)
			(xy 82.542126 -107.570016) (xy 82.57794 -107.60583)
		)
		(stroke
			(width 0)
			(type solid)
		)
		(fill yes)
		(layer "F.Cu")
		(net "M_L_ECC<2>")
	)
	(gr_poly
		(pts
			(xy 82.675476 -45.040042) (xy 82.720434 -44.995084) (xy 82.594704 -44.869354) (xy 82.549746 -44.914312)
			(xy 82.50301 -45.01134) (xy 82.578448 -45.086778)
		)
		(stroke
			(width 0)
			(type solid)
		)
		(fill yes)
		(layer "F.Cu")
		(net "M_H_ECC<3>")
	)
	(gr_poly
		(pts
			(xy 82.676746 -104.723184) (xy 82.640932 -104.68737) (xy 82.497168 -104.56164) (xy 82.425286 -104.633268)
			(xy 82.551016 -104.777032) (xy 82.58683 -104.8131)
		)
		(stroke
			(width 0)
			(type solid)
		)
		(fill yes)
		(layer "F.Cu")
		(net "M_L_DQS_DN<17>")
	)
	(gr_poly
		(pts
			(xy 82.681064 -103.263954) (xy 82.634328 -103.166926) (xy 82.598514 -103.131112) (xy 82.472784 -103.256842)
			(xy 82.508598 -103.292656) (xy 82.605626 -103.339392)
		)
		(stroke
			(width 0)
			(type solid)
		)
		(fill yes)
		(layer "F.Cu")
		(net "M_L_ECC<0>")
	)
	(gr_poly
		(pts
			(xy 82.684366 -45.33646) (xy 82.731102 -45.239432) (xy 82.655664 -45.163994) (xy 82.55889 -45.21073)
			(xy 82.522822 -45.246544) (xy 82.648552 -45.372274)
		)
		(stroke
			(width 0)
			(type solid)
		)
		(fill yes)
		(layer "F.Cu")
		(net "M_H_ECC<2>")
	)
	(gr_poly
		(pts
			(xy 82.692748 -48.076104) (xy 82.728562 -48.040036) (xy 82.602832 -47.914306) (xy 82.567018 -47.950374)
			(xy 82.520282 -48.047402) (xy 82.59572 -48.12284)
		)
		(stroke
			(width 0)
			(type solid)
		)
		(fill yes)
		(layer "F.Cu")
		(net "M_H_DQS_DP<17>")
	)
	(gr_poly
		(pts
			(xy 82.69478 -106.160062) (xy 82.56905 -106.016298) (xy 82.532982 -105.980484) (xy 82.44332 -106.070146)
			(xy 82.479134 -106.106214) (xy 82.622898 -106.231944)
		)
		(stroke
			(width 0)
			(type solid)
		)
		(fill yes)
		(layer "F.Cu")
		(net "M_L_DQS_DP<8>")
	)
	(gr_poly
		(pts
			(xy 82.72907 -46.81855) (xy 82.764884 -46.782482) (xy 82.639154 -46.656752) (xy 82.60334 -46.69282)
			(xy 82.556604 -46.789848) (xy 82.632042 -46.865286)
		)
		(stroke
			(width 0)
			(type solid)
		)
		(fill yes)
		(layer "F.Cu")
		(net "M_H_DQS_DP<8>")
	)
	(gr_poly
		(pts
			(xy 82.73796 -47.114968) (xy 82.784696 -47.01794) (xy 82.709258 -46.942502) (xy 82.61223 -46.989238)
			(xy 82.576162 -47.025052) (xy 82.701892 -47.150782)
		)
		(stroke
			(width 0)
			(type solid)
		)
		(fill yes)
		(layer "F.Cu")
		(net "M_H_DQS_DN<8>")
	)
	(gr_poly
		(pts
			(xy 82.751168 -102.978458) (xy 82.715354 -102.942644) (xy 82.618326 -102.895908) (xy 82.542888 -102.971346)
			(xy 82.589624 -103.068374) (xy 82.625438 -103.104188)
		)
		(stroke
			(width 0)
			(type solid)
		)
		(fill yes)
		(layer "F.Cu")
		(net "M_L_ECC<0>")
	)
	(gr_poly
		(pts
			(xy 82.765392 -45.560996) (xy 82.801206 -45.524928) (xy 82.675476 -45.399198) (xy 82.639662 -45.435266)
			(xy 82.592926 -45.53204) (xy 82.668364 -45.607478)
		)
		(stroke
			(width 0)
			(type solid)
		)
		(fill yes)
		(layer "F.Cu")
		(net "M_H_ECC<2>")
	)
	(gr_poly
		(pts
			(xy 82.766408 -105.747058) (xy 82.730594 -105.71099) (xy 82.58683 -105.58526) (xy 82.515202 -105.657142)
			(xy 82.640932 -105.800906) (xy 82.676746 -105.83672)
		)
		(stroke
			(width 0)
			(type solid)
		)
		(fill yes)
		(layer "F.Cu")
		(net "M_L_DQS_DP<8>")
	)
	(gr_poly
		(pts
			(xy 82.774282 -45.857414) (xy 82.820764 -45.760386) (xy 82.745326 -45.684948) (xy 82.648552 -45.731684)
			(xy 82.612484 -45.767498) (xy 82.738214 -45.893228)
		)
		(stroke
			(width 0)
			(type solid)
		)
		(fill yes)
		(layer "F.Cu")
		(net "M_H_ECC<7>")
	)
	(gr_poly
		(pts
			(xy 82.784442 -107.183682) (xy 82.658712 -107.040172) (xy 82.622898 -107.004104) (xy 82.532982 -107.09402)
			(xy 82.56905 -107.129834) (xy 82.71256 -107.255564)
		)
		(stroke
			(width 0)
			(type solid)
		)
		(fill yes)
		(layer "F.Cu")
		(net "M_L_ECC<7>")
	)
	(gr_poly
		(pts
			(xy 82.785966 -49.608232) (xy 82.785966 -49.501298) (xy 82.684366 -49.465992) (xy 82.633566 -49.465992)
			(xy 82.633566 -49.643792) (xy 82.684366 -49.643792)
		)
		(stroke
			(width 0)
			(type solid)
		)
		(fill yes)
		(layer "F.Cu")
		(net "M_H_ECC<1>")
	)
	(gr_poly
		(pts
			(xy 82.785966 -49.176432) (xy 82.785966 -49.069498) (xy 82.684366 -49.034192) (xy 82.633566 -49.034192)
			(xy 82.633566 -49.211992) (xy 82.684366 -49.211992)
		)
		(stroke
			(width 0)
			(type solid)
		)
		(fill yes)
		(layer "F.Cu")
		(net "M_H_ECC<1>")
	)
	(gr_poly
		(pts
			(xy 82.785966 -48.744632) (xy 82.785966 -48.637698) (xy 82.684366 -48.602392) (xy 82.633566 -48.602392)
			(xy 82.633566 -48.780192) (xy 82.684366 -48.780192)
		)
		(stroke
			(width 0)
			(type solid)
		)
		(fill yes)
		(layer "F.Cu")
		(net "M_H_ECC<1>")
	)
	(gr_poly
		(pts
			(xy 82.793586 -104.390952) (xy 82.667856 -104.247188) (xy 82.631788 -104.211374) (xy 82.542126 -104.301036)
			(xy 82.57794 -104.337104) (xy 82.721704 -104.462834)
		)
		(stroke
			(width 0)
			(type solid)
		)
		(fill yes)
		(layer "F.Cu")
		(net "M_L_DQS_DP<17>")
	)
	(gr_poly
		(pts
			(xy 82.818732 -102.260654) (xy 82.767932 -102.260654) (xy 82.666332 -102.296214) (xy 82.666332 -102.402894)
			(xy 82.767932 -102.438454) (xy 82.818732 -102.438454)
		)
		(stroke
			(width 0)
			(type solid)
		)
		(fill yes)
		(layer "F.Cu")
		(net "M_L_ECC<0>")
	)
	(gr_poly
		(pts
			(xy 82.818732 -101.828854) (xy 82.767932 -101.828854) (xy 82.666332 -101.864414) (xy 82.666332 -101.971094)
			(xy 82.767932 -102.006654) (xy 82.818732 -102.006654)
		)
		(stroke
			(width 0)
			(type solid)
		)
		(fill yes)
		(layer "F.Cu")
		(net "M_L_ECC<0>")
	)
	(gr_poly
		(pts
			(xy 82.818732 -100.965254) (xy 82.767932 -100.965254) (xy 82.666332 -101.000814) (xy 82.666332 -101.107494)
			(xy 82.767932 -101.143054) (xy 82.818732 -101.143054)
		)
		(stroke
			(width 0)
			(type solid)
		)
		(fill yes)
		(layer "F.Cu")
		(net "M_L_ECC<0>")
	)
	(gr_poly
		(pts
			(xy 82.818732 -47.339504) (xy 82.854546 -47.303436) (xy 82.728816 -47.177706) (xy 82.693002 -47.213774)
			(xy 82.646266 -47.310802) (xy 82.721704 -47.38624)
		)
		(stroke
			(width 0)
			(type solid)
		)
		(fill yes)
		(layer "F.Cu")
		(net "M_H_DQS_DN<8>")
	)
	(gr_poly
		(pts
			(xy 82.827622 -47.635922) (xy 82.874358 -47.538894) (xy 82.79892 -47.463456) (xy 82.701892 -47.510192)
			(xy 82.665824 -47.546006) (xy 82.791554 -47.671736)
		)
		(stroke
			(width 0)
			(type solid)
		)
		(fill yes)
		(layer "F.Cu")
		(net "M_H_DQS_DN<17>")
	)
	(gr_poly
		(pts
			(xy 82.855054 -46.08195) (xy 82.890868 -46.045882) (xy 82.765138 -45.920152) (xy 82.729324 -45.95622)
			(xy 82.682588 -46.052994) (xy 82.758026 -46.128432)
		)
		(stroke
			(width 0)
			(type solid)
		)
		(fill yes)
		(layer "F.Cu")
		(net "M_H_ECC<7>")
	)
	(gr_poly
		(pts
			(xy 82.856324 -106.770678) (xy 82.82051 -106.734864) (xy 82.676746 -106.609134) (xy 82.604864 -106.680762)
			(xy 82.730594 -106.824526) (xy 82.766408 -106.860594)
		)
		(stroke
			(width 0)
			(type solid)
		)
		(fill yes)
		(layer "F.Cu")
		(net "M_L_ECC<7>")
	)
	(gr_poly
		(pts
			(xy 82.863944 -46.378368) (xy 82.91068 -46.28134) (xy 82.835242 -46.205902) (xy 82.738214 -46.252638)
			(xy 82.702146 -46.288452) (xy 82.827876 -46.414182)
		)
		(stroke
			(width 0)
			(type solid)
		)
		(fill yes)
		(layer "F.Cu")
		(net "M_H_ECC<6>")
	)
	(gr_poly
		(pts
			(xy 82.877152 -103.715058) (xy 82.841338 -103.679244) (xy 82.74431 -103.632508) (xy 82.668872 -103.707946)
			(xy 82.715608 -103.804974) (xy 82.751422 -103.840788)
		)
		(stroke
			(width 0)
			(type solid)
		)
		(fill yes)
		(layer "F.Cu")
		(net "M_L_DQS_DP<17>")
	)
	(gr_poly
		(pts
			(xy 82.883248 -105.414572) (xy 82.757518 -105.271062) (xy 82.721704 -105.234994) (xy 82.631788 -105.32491)
			(xy 82.667856 -105.360724) (xy 82.811366 -105.486454)
		)
		(stroke
			(width 0)
			(type solid)
		)
		(fill yes)
		(layer "F.Cu")
		(net "M_L_DQS_DN<8>")
	)
	(gr_poly
		(pts
			(xy 82.892392 -104.031034) (xy 82.892392 -103.924354) (xy 82.790792 -103.888794) (xy 82.739992 -103.888794)
			(xy 82.739992 -104.066594) (xy 82.790792 -104.066594)
		)
		(stroke
			(width 0)
			(type solid)
		)
		(fill yes)
		(layer "F.Cu")
		(net "M_L_DQS_DP<17>")
	)
	(gr_poly
		(pts
			(xy 82.89671 -103.4796) (xy 82.849974 -103.382572) (xy 82.81416 -103.346758) (xy 82.68843 -103.472488)
			(xy 82.724244 -103.508302) (xy 82.821272 -103.555038)
		)
		(stroke
			(width 0)
			(type solid)
		)
		(fill yes)
		(layer "F.Cu")
		(net "M_L_ECC<1>")
	)
	(gr_poly
		(pts
			(xy 82.908394 -47.860458) (xy 82.944208 -47.82439) (xy 82.818478 -47.69866) (xy 82.782664 -47.734728)
			(xy 82.735928 -47.831756) (xy 82.811366 -47.907194)
		)
		(stroke
			(width 0)
			(type solid)
		)
		(fill yes)
		(layer "F.Cu")
		(net "M_H_DQS_DN<17>")
	)
	(gr_poly
		(pts
			(xy 82.917284 -48.156876) (xy 82.96402 -48.059848) (xy 82.888582 -47.98441) (xy 82.791554 -48.031146)
			(xy 82.755486 -48.06696) (xy 82.881216 -48.19269)
		)
		(stroke
			(width 0)
			(type solid)
		)
		(fill yes)
		(layer "F.Cu")
		(net "M_H_DQS_DP<17>")
	)
	(gr_poly
		(pts
			(xy 82.938366 -49.681892) (xy 82.887566 -49.681892) (xy 82.785966 -49.717198) (xy 82.785966 -49.824132)
			(xy 82.887566 -49.859692) (xy 82.938366 -49.859692)
		)
		(stroke
			(width 0)
			(type solid)
		)
		(fill yes)
		(layer "F.Cu")
		(net "M_H_DQS_DP<17>")
	)
	(gr_poly
		(pts
			(xy 82.938366 -49.250092) (xy 82.887566 -49.250092) (xy 82.785966 -49.285398) (xy 82.785966 -49.392332)
			(xy 82.887566 -49.427892) (xy 82.938366 -49.427892)
		)
		(stroke
			(width 0)
			(type solid)
		)
		(fill yes)
		(layer "F.Cu")
		(net "M_H_DQS_DP<17>")
	)
	(gr_poly
		(pts
			(xy 82.938366 -48.818292) (xy 82.887566 -48.818292) (xy 82.785966 -48.853598) (xy 82.785966 -48.960532)
			(xy 82.887566 -48.996092) (xy 82.938366 -48.996092)
		)
		(stroke
			(width 0)
			(type solid)
		)
		(fill yes)
		(layer "F.Cu")
		(net "M_H_DQS_DP<17>")
	)
	(gr_poly
		(pts
			(xy 82.938366 -48.386492) (xy 82.887566 -48.386492) (xy 82.785966 -48.421798) (xy 82.785966 -48.528732)
			(xy 82.887566 -48.564292) (xy 82.938366 -48.564292)
		)
		(stroke
			(width 0)
			(type solid)
		)
		(fill yes)
		(layer "F.Cu")
		(net "M_H_DQS_DP<17>")
	)
	(gr_poly
		(pts
			(xy 82.944716 -46.602904) (xy 82.98053 -46.566836) (xy 82.8548 -46.441106) (xy 82.818986 -46.477174)
			(xy 82.77225 -46.574202) (xy 82.847688 -46.64964)
		)
		(stroke
			(width 0)
			(type solid)
		)
		(fill yes)
		(layer "F.Cu")
		(net "M_H_ECC<6>")
	)
	(gr_poly
		(pts
			(xy 82.953606 -46.899322) (xy 83.000342 -46.802294) (xy 82.924904 -46.726856) (xy 82.827876 -46.773592)
			(xy 82.791808 -46.809406) (xy 82.917538 -46.935136)
		)
		(stroke
			(width 0)
			(type solid)
		)
		(fill yes)
		(layer "F.Cu")
		(net "M_H_DQS_DP<8>")
	)
	(gr_poly
		(pts
			(xy 82.95513 -107.803188) (xy 82.910172 -107.758484) (xy 82.766408 -107.632754) (xy 82.694526 -107.704636)
			(xy 82.820256 -107.848146) (xy 82.865214 -107.893104)
		)
		(stroke
			(width 0)
			(type solid)
		)
		(fill yes)
		(layer "F.Cu")
		(net "M_L_ECC<3>")
	)
	(gr_poly
		(pts
			(xy 82.95513 -105.001568) (xy 82.919316 -104.965754) (xy 82.775552 -104.840024) (xy 82.70367 -104.911652)
			(xy 82.8294 -105.055416) (xy 82.865214 -105.091484)
		)
		(stroke
			(width 0)
			(type solid)
		)
		(fill yes)
		(layer "F.Cu")
		(net "M_L_DQS_DN<8>")
	)
	(gr_poly
		(pts
			(xy 82.966814 -103.194104) (xy 82.931 -103.15829) (xy 82.833972 -103.111554) (xy 82.758534 -103.186992)
			(xy 82.80527 -103.28402) (xy 82.841084 -103.319834)
		)
		(stroke
			(width 0)
			(type solid)
		)
		(fill yes)
		(layer "F.Cu")
		(net "M_L_ECC<1>")
	)
	(gr_poly
		(pts
			(xy 82.971132 -102.618794) (xy 82.971132 -102.512114) (xy 82.869532 -102.476554) (xy 82.818732 -102.476554)
			(xy 82.818732 -102.654354) (xy 82.869532 -102.654354)
		)
		(stroke
			(width 0)
			(type solid)
		)
		(fill yes)
		(layer "F.Cu")
		(net "M_L_ECC<0>")
	)
	(gr_poly
		(pts
			(xy 82.971132 -102.186994) (xy 82.971132 -102.080314) (xy 82.869532 -102.044754) (xy 82.818732 -102.044754)
			(xy 82.818732 -102.222554) (xy 82.869532 -102.222554)
		)
		(stroke
			(width 0)
			(type solid)
		)
		(fill yes)
		(layer "F.Cu")
		(net "M_L_ECC<0>")
	)
	(gr_poly
		(pts
			(xy 82.971132 -101.755194) (xy 82.971132 -101.648514) (xy 82.869532 -101.612954) (xy 82.818732 -101.612954)
			(xy 82.818732 -101.790754) (xy 82.869532 -101.790754)
		)
		(stroke
			(width 0)
			(type solid)
		)
		(fill yes)
		(layer "F.Cu")
		(net "M_L_ECC<0>")
	)
	(gr_poly
		(pts
			(xy 82.971132 -101.323394) (xy 82.971132 -101.216714) (xy 82.869532 -101.181154) (xy 82.818732 -101.181154)
			(xy 82.818732 -101.358954) (xy 82.869532 -101.358954)
		)
		(stroke
			(width 0)
			(type solid)
		)
		(fill yes)
		(layer "F.Cu")
		(net "M_L_ECC<0>")
	)
	(gr_poly
		(pts
			(xy 82.971132 -100.891594) (xy 82.971132 -100.784914) (xy 82.869532 -100.749354) (xy 82.818732 -100.749354)
			(xy 82.818732 -100.927154) (xy 82.869532 -100.927154)
		)
		(stroke
			(width 0)
			(type solid)
		)
		(fill yes)
		(layer "F.Cu")
		(net "M_L_ECC<0>")
	)
	(gr_poly
		(pts
			(xy 82.973164 -106.438446) (xy 82.847434 -106.294682) (xy 82.811366 -106.258868) (xy 82.721704 -106.34853)
			(xy 82.757518 -106.384598) (xy 82.901282 -106.510328)
		)
		(stroke
			(width 0)
			(type solid)
		)
		(fill yes)
		(layer "F.Cu")
		(net "M_L_ECC<6>")
	)
	(gr_poly
		(pts
			(xy 82.980784 -45.34535) (xy 83.025742 -45.300392) (xy 82.900012 -45.174662) (xy 82.855054 -45.21962)
			(xy 82.808572 -45.316648) (xy 82.883756 -45.392086)
		)
		(stroke
			(width 0)
			(type solid)
		)
		(fill yes)
		(layer "F.Cu")
		(net "M_H_ECC<3>")
	)
	(gr_poly
		(pts
			(xy 82.989928 -45.641768) (xy 83.03641 -45.54474) (xy 82.960972 -45.469302) (xy 82.864198 -45.516038)
			(xy 82.82813 -45.551852) (xy 82.95386 -45.677582)
		)
		(stroke
			(width 0)
			(type solid)
		)
		(fill yes)
		(layer "F.Cu")
		(net "M_H_ECC<2>")
	)
	(gr_poly
		(pts
			(xy 83.034378 -47.123858) (xy 83.070192 -47.08779) (xy 82.944462 -46.96206) (xy 82.908648 -46.998128)
			(xy 82.861912 -47.095156) (xy 82.93735 -47.170594)
		)
		(stroke
			(width 0)
			(type solid)
		)
		(fill yes)
		(layer "F.Cu")
		(net "M_H_DQS_DP<8>")
	)
	(gr_poly
		(pts
			(xy 83.043268 -47.420276) (xy 83.090004 -47.323248) (xy 83.014566 -47.24781) (xy 82.917538 -47.294546)
			(xy 82.88147 -47.33036) (xy 83.0072 -47.45609)
		)
		(stroke
			(width 0)
			(type solid)
		)
		(fill yes)
		(layer "F.Cu")
		(net "M_H_DQS_DN<8>")
	)
	(gr_poly
		(pts
			(xy 83.044792 -106.025442) (xy 83.008978 -105.989374) (xy 82.865214 -105.863644) (xy 82.793586 -105.935526)
			(xy 82.919316 -106.07929) (xy 82.95513 -106.115104)
		)
		(stroke
			(width 0)
			(type solid)
		)
		(fill yes)
		(layer "F.Cu")
		(net "M_L_ECC<6>")
	)
	(gr_poly
		(pts
			(xy 83.044792 -104.104694) (xy 82.993992 -104.104694) (xy 82.892392 -104.140254) (xy 82.892392 -104.246934)
			(xy 82.993992 -104.282494) (xy 83.044792 -104.282494)
		)
		(stroke
			(width 0)
			(type solid)
		)
		(fill yes)
		(layer "F.Cu")
		(net "M_L_DQS_DN<17>")
	)
	(gr_poly
		(pts
			(xy 83.062826 -107.462066) (xy 82.937096 -107.318556) (xy 82.901282 -107.282488) (xy 82.811366 -107.372404)
			(xy 82.847434 -107.408218) (xy 82.990944 -107.533948)
		)
		(stroke
			(width 0)
			(type solid)
		)
		(fill yes)
		(layer "F.Cu")
		(net "M_L_ECC<2>")
	)
	(gr_poly
		(pts
			(xy 83.0707 -45.866304) (xy 83.106514 -45.830236) (xy 82.980784 -45.704506) (xy 82.94497 -45.740574)
			(xy 82.898234 -45.837348) (xy 82.973672 -45.912786)
		)
		(stroke
			(width 0)
			(type solid)
		)
		(fill yes)
		(layer "F.Cu")
		(net "M_H_ECC<2>")
	)
	(gr_poly
		(pts
			(xy 83.07197 -104.669336) (xy 82.94624 -104.525572) (xy 82.910172 -104.489758) (xy 82.82051 -104.57942)
			(xy 82.856324 -104.615488) (xy 83.000088 -104.741218)
		)
		(stroke
			(width 0)
			(type solid)
		)
		(fill yes)
		(layer "F.Cu")
		(net "M_L_DQS_DN<17>")
	)
	(gr_poly
		(pts
			(xy 83.07959 -46.162722) (xy 83.126326 -46.065694) (xy 83.050888 -45.990256) (xy 82.95386 -46.036992)
			(xy 82.917792 -46.072806) (xy 83.043522 -46.198536)
		)
		(stroke
			(width 0)
			(type solid)
		)
		(fill yes)
		(layer "F.Cu")
		(net "M_H_ECC<7>")
	)
	(gr_poly
		(pts
			(xy 83.090766 -49.608232) (xy 83.090766 -49.501298) (xy 82.989166 -49.465992) (xy 82.938366 -49.465992)
			(xy 82.938366 -49.643792) (xy 82.989166 -49.643792)
		)
		(stroke
			(width 0)
			(type solid)
		)
		(fill yes)
		(layer "F.Cu")
		(net "M_H_DQS_DP<17>")
	)
	(gr_poly
		(pts
			(xy 83.090766 -49.176432) (xy 83.090766 -49.069498) (xy 82.989166 -49.034192) (xy 82.938366 -49.034192)
			(xy 82.938366 -49.211992) (xy 82.989166 -49.211992)
		)
		(stroke
			(width 0)
			(type solid)
		)
		(fill yes)
		(layer "F.Cu")
		(net "M_H_DQS_DP<17>")
	)
	(gr_poly
		(pts
			(xy 83.090766 -48.744632) (xy 83.090766 -48.637698) (xy 82.989166 -48.602392) (xy 82.938366 -48.602392)
			(xy 82.938366 -48.780192) (xy 82.989166 -48.780192)
		)
		(stroke
			(width 0)
			(type solid)
		)
		(fill yes)
		(layer "F.Cu")
		(net "M_H_DQS_DP<17>")
	)
	(gr_poly
		(pts
			(xy 83.112356 -103.695246) (xy 83.06562 -103.598218) (xy 83.029806 -103.562404) (xy 82.904076 -103.688134)
			(xy 82.93989 -103.723948) (xy 83.036918 -103.770684)
		)
		(stroke
			(width 0)
			(type solid)
		)
		(fill yes)
		(layer "F.Cu")
		(net "M_L_DQS_DP<17>")
	)
	(gr_poly
		(pts
			(xy 83.123532 -102.692454) (xy 83.072732 -102.692454) (xy 82.971132 -102.728014) (xy 82.971132 -102.834694)
			(xy 83.072732 -102.870254) (xy 83.123532 -102.870254)
		)
		(stroke
			(width 0)
			(type solid)
		)
		(fill yes)
		(layer "F.Cu")
		(net "M_L_ECC<1>")
	)
	(gr_poly
		(pts
			(xy 83.123532 -102.260654) (xy 83.072732 -102.260654) (xy 82.971132 -102.296214) (xy 82.971132 -102.402894)
			(xy 83.072732 -102.438454) (xy 83.123532 -102.438454)
		)
		(stroke
			(width 0)
			(type solid)
		)
		(fill yes)
		(layer "F.Cu")
		(net "M_L_ECC<1>")
	)
	(gr_poly
		(pts
			(xy 83.123532 -101.828854) (xy 83.072732 -101.828854) (xy 82.971132 -101.864414) (xy 82.971132 -101.971094)
			(xy 83.072732 -102.006654) (xy 83.123532 -102.006654)
		)
		(stroke
			(width 0)
			(type solid)
		)
		(fill yes)
		(layer "F.Cu")
		(net "M_L_ECC<1>")
	)
	(gr_poly
		(pts
			(xy 83.123532 -101.397054) (xy 83.072732 -101.397054) (xy 82.971132 -101.432614) (xy 82.971132 -101.539294)
			(xy 83.072732 -101.574854) (xy 83.123532 -101.574854)
		)
		(stroke
			(width 0)
			(type solid)
		)
		(fill yes)
		(layer "F.Cu")
		(net "M_L_ECC<1>")
	)
	(gr_poly
		(pts
			(xy 83.123532 -100.965254) (xy 83.072732 -100.965254) (xy 82.971132 -101.000814) (xy 82.971132 -101.107494)
			(xy 83.072732 -101.143054) (xy 83.123532 -101.143054)
		)
		(stroke
			(width 0)
			(type solid)
		)
		(fill yes)
		(layer "F.Cu")
		(net "M_L_ECC<1>")
	)
	(gr_poly
		(pts
			(xy 83.123532 -100.533454) (xy 83.072732 -100.533454) (xy 82.971132 -100.569014) (xy 82.971132 -100.675694)
			(xy 83.072732 -100.711254) (xy 83.123532 -100.711254)
		)
		(stroke
			(width 0)
			(type solid)
		)
		(fill yes)
		(layer "F.Cu")
		(net "M_L_ECC<1>")
	)
	(gr_poly
		(pts
			(xy 83.12404 -47.644812) (xy 83.159854 -47.608744) (xy 83.034124 -47.483014) (xy 82.99831 -47.519082)
			(xy 82.951574 -47.61611) (xy 83.027012 -47.691548)
		)
		(stroke
			(width 0)
			(type solid)
		)
		(fill yes)
		(layer "F.Cu")
		(net "M_H_DQS_DN<8>")
	)
	(gr_poly
		(pts
			(xy 83.13293 -47.94123) (xy 83.179666 -47.844202) (xy 83.104228 -47.768764) (xy 83.0072 -47.8155)
			(xy 82.971132 -47.851314) (xy 83.096862 -47.977044)
		)
		(stroke
			(width 0)
			(type solid)
		)
		(fill yes)
		(layer "F.Cu")
		(net "M_H_DQS_DN<17>")
	)
	(gr_poly
		(pts
			(xy 83.134708 -107.049062) (xy 83.098894 -107.013248) (xy 82.95513 -106.887518) (xy 82.883248 -106.959146)
			(xy 83.008978 -107.10291) (xy 83.044792 -107.138978)
		)
		(stroke
			(width 0)
			(type solid)
		)
		(fill yes)
		(layer "F.Cu")
		(net "M_L_ECC<2>")
	)
	(gr_poly
		(pts
			(xy 83.160362 -46.387258) (xy 83.196176 -46.35119) (xy 83.070446 -46.22546) (xy 83.034632 -46.261528)
			(xy 82.987896 -46.358556) (xy 83.063334 -46.433994)
		)
		(stroke
			(width 0)
			(type solid)
		)
		(fill yes)
		(layer "F.Cu")
		(net "M_H_ECC<7>")
	)
	(gr_poly
		(pts
			(xy 83.161632 -105.692956) (xy 83.035902 -105.549446) (xy 83.000088 -105.513378) (xy 82.910172 -105.603294)
			(xy 82.94624 -105.639108) (xy 83.08975 -105.764838)
		)
		(stroke
			(width 0)
			(type solid)
		)
		(fill yes)
		(layer "F.Cu")
		(net "M_L_DQS_DP<8>")
	)
	(gr_poly
		(pts
			(xy 83.169252 -46.683676) (xy 83.215988 -46.586648) (xy 83.14055 -46.51121) (xy 83.043522 -46.557946)
			(xy 83.007454 -46.59376) (xy 83.133184 -46.71949)
		)
		(stroke
			(width 0)
			(type solid)
		)
		(fill yes)
		(layer "F.Cu")
		(net "M_H_ECC<6>")
	)
	(gr_poly
		(pts
			(xy 83.18246 -103.40975) (xy 83.146646 -103.373936) (xy 83.049618 -103.3272) (xy 82.97418 -103.402638)
			(xy 83.020916 -103.499666) (xy 83.05673 -103.53548)
		)
		(stroke
			(width 0)
			(type solid)
		)
		(fill yes)
		(layer "F.Cu")
		(net "M_L_DQS_DP<17>")
	)
	(gr_poly
		(pts
			(xy 83.202018 -103.174292) (xy 83.155282 -103.077264) (xy 83.119468 -103.04145) (xy 82.993738 -103.16718)
			(xy 83.029552 -103.202994) (xy 83.12658 -103.24973)
		)
		(stroke
			(width 0)
			(type solid)
		)
		(fill yes)
		(layer "F.Cu")
		(net "M_L_ECC<1>")
	)
	(gr_poly
		(pts
			(xy 83.233514 -105.279952) (xy 83.1977 -105.244138) (xy 83.053936 -105.118408) (xy 82.982054 -105.190036)
			(xy 83.107784 -105.3338) (xy 83.143598 -105.369868)
		)
		(stroke
			(width 0)
			(type solid)
		)
		(fill yes)
		(layer "F.Cu")
		(net "M_L_DQS_DP<8>")
	)
	(gr_poly
		(pts
			(xy 83.243166 -49.681892) (xy 83.192366 -49.681892) (xy 83.090766 -49.717198) (xy 83.090766 -49.824132)
			(xy 83.192366 -49.859692) (xy 83.243166 -49.859692)
		)
		(stroke
			(width 0)
			(type solid)
		)
		(fill yes)
		(layer "F.Cu")
		(net "M_H_DQS_DN<17>")
	)
	(gr_poly
		(pts
			(xy 83.243166 -49.250092) (xy 83.192366 -49.250092) (xy 83.090766 -49.285398) (xy 83.090766 -49.392332)
			(xy 83.192366 -49.427892) (xy 83.243166 -49.427892)
		)
		(stroke
			(width 0)
			(type solid)
		)
		(fill yes)
		(layer "F.Cu")
		(net "M_H_DQS_DN<17>")
	)
	(gr_poly
		(pts
			(xy 83.243166 -48.818292) (xy 83.192366 -48.818292) (xy 83.090766 -48.853598) (xy 83.090766 -48.960532)
			(xy 83.192366 -48.996092) (xy 83.243166 -48.996092)
		)
		(stroke
			(width 0)
			(type solid)
		)
		(fill yes)
		(layer "F.Cu")
		(net "M_H_DQS_DN<17>")
	)
	(gr_poly
		(pts
			(xy 83.243166 -48.386492) (xy 83.192366 -48.386492) (xy 83.090766 -48.421798) (xy 83.090766 -48.528732)
			(xy 83.192366 -48.564292) (xy 83.243166 -48.564292)
		)
		(stroke
			(width 0)
			(type solid)
		)
		(fill yes)
		(layer "F.Cu")
		(net "M_H_DQS_DN<17>")
	)
	(gr_poly
		(pts
			(xy 83.250024 -46.908212) (xy 83.285838 -46.872144) (xy 83.160108 -46.746414) (xy 83.124294 -46.782482)
			(xy 83.077558 -46.87951) (xy 83.152996 -46.954948)
		)
		(stroke
			(width 0)
			(type solid)
		)
		(fill yes)
		(layer "F.Cu")
		(net "M_H_ECC<6>")
	)
	(gr_poly
		(pts
			(xy 83.251548 -106.71683) (xy 83.125818 -106.573066) (xy 83.08975 -106.537252) (xy 83.000088 -106.626914)
			(xy 83.035902 -106.662982) (xy 83.179666 -106.788712)
		)
		(stroke
			(width 0)
			(type solid)
		)
		(fill yes)
		(layer "F.Cu")
		(net "M_L_ECC<7>")
	)
	(gr_poly
		(pts
			(xy 83.258914 -47.20463) (xy 83.30565 -47.107602) (xy 83.230212 -47.032164) (xy 83.133184 -47.0789)
			(xy 83.097116 -47.114714) (xy 83.222846 -47.240444)
		)
		(stroke
			(width 0)
			(type solid)
		)
		(fill yes)
		(layer "F.Cu")
		(net "M_H_DQS_DP<8>")
	)
	(gr_poly
		(pts
			(xy 83.275932 -102.618794) (xy 83.275932 -102.512114) (xy 83.174332 -102.476554) (xy 83.123532 -102.476554)
			(xy 83.123532 -102.654354) (xy 83.174332 -102.654354)
		)
		(stroke
			(width 0)
			(type solid)
		)
		(fill yes)
		(layer "F.Cu")
		(net "M_L_ECC<1>")
	)
	(gr_poly
		(pts
			(xy 83.275932 -102.186994) (xy 83.275932 -102.080314) (xy 83.174332 -102.044754) (xy 83.123532 -102.044754)
			(xy 83.123532 -102.222554) (xy 83.174332 -102.222554)
		)
		(stroke
			(width 0)
			(type solid)
		)
		(fill yes)
		(layer "F.Cu")
		(net "M_L_ECC<1>")
	)
	(gr_poly
		(pts
			(xy 83.275932 -101.755194) (xy 83.275932 -101.648514) (xy 83.174332 -101.612954) (xy 83.123532 -101.612954)
			(xy 83.123532 -101.790754) (xy 83.174332 -101.790754)
		)
		(stroke
			(width 0)
			(type solid)
		)
		(fill yes)
		(layer "F.Cu")
		(net "M_L_ECC<1>")
	)
	(gr_poly
		(pts
			(xy 83.275932 -101.323394) (xy 83.275932 -101.216714) (xy 83.174332 -101.181154) (xy 83.123532 -101.181154)
			(xy 83.123532 -101.358954) (xy 83.174332 -101.358954)
		)
		(stroke
			(width 0)
			(type solid)
		)
		(fill yes)
		(layer "F.Cu")
		(net "M_L_ECC<1>")
	)
	(gr_poly
		(pts
			(xy 83.275932 -100.891594) (xy 83.275932 -100.784914) (xy 83.174332 -100.749354) (xy 83.123532 -100.749354)
			(xy 83.123532 -100.927154) (xy 83.174332 -100.927154)
		)
		(stroke
			(width 0)
			(type solid)
		)
		(fill yes)
		(layer "F.Cu")
		(net "M_L_ECC<1>")
	)
	(gr_poly
		(pts
			(xy 83.286092 -45.650658) (xy 83.33105 -45.6057) (xy 83.20532 -45.47997) (xy 83.160362 -45.524928)
			(xy 83.11388 -45.621956) (xy 83.189318 -45.697394)
		)
		(stroke
			(width 0)
			(type solid)
		)
		(fill yes)
		(layer "F.Cu")
		(net "M_H_ECC<3>")
	)
	(gr_poly
		(pts
			(xy 83.295236 -45.947076) (xy 83.341972 -45.850048) (xy 83.266534 -45.77461) (xy 83.169506 -45.821346)
			(xy 83.133438 -45.85716) (xy 83.259168 -45.98289)
		)
		(stroke
			(width 0)
			(type solid)
		)
		(fill yes)
		(layer "F.Cu")
		(net "M_H_ECC<2>")
	)
	(gr_poly
		(pts
			(xy 83.323176 -106.303826) (xy 83.287362 -106.267758) (xy 83.143598 -106.142028) (xy 83.07197 -106.21391)
			(xy 83.1977 -106.357674) (xy 83.233514 -106.393488)
		)
		(stroke
			(width 0)
			(type solid)
		)
		(fill yes)
		(layer "F.Cu")
		(net "M_L_ECC<7>")
	)
	(gr_poly
		(pts
			(xy 83.328002 -103.910892) (xy 83.281266 -103.813864) (xy 83.245452 -103.77805) (xy 83.119722 -103.90378)
			(xy 83.155536 -103.939594) (xy 83.252564 -103.98633)
		)
		(stroke
			(width 0)
			(type solid)
		)
		(fill yes)
		(layer "F.Cu")
		(net "M_L_DQS_DN<17>")
	)
	(gr_poly
		(pts
			(xy 83.339686 -47.429166) (xy 83.3755 -47.393098) (xy 83.24977 -47.267368) (xy 83.213956 -47.303436)
			(xy 83.16722 -47.400464) (xy 83.242658 -47.475902)
		)
		(stroke
			(width 0)
			(type solid)
		)
		(fill yes)
		(layer "F.Cu")
		(net "M_H_DQS_DP<8>")
	)
	(gr_poly
		(pts
			(xy 83.348576 -47.725584) (xy 83.395312 -47.628556) (xy 83.319874 -47.553118) (xy 83.222846 -47.599854)
			(xy 83.187032 -47.635922) (xy 83.312508 -47.761398)
		)
		(stroke
			(width 0)
			(type solid)
		)
		(fill yes)
		(layer "F.Cu")
		(net "M_H_DQS_DN<8>")
	)
	(gr_poly
		(pts
			(xy 83.349592 -104.104694) (xy 83.298792 -104.104694) (xy 83.197192 -104.140254) (xy 83.197192 -104.246934)
			(xy 83.298792 -104.282494) (xy 83.349592 -104.282494)
		)
		(stroke
			(width 0)
			(type solid)
		)
		(fill yes)
		(layer "F.Cu")
		(net "M_L_DQS_DN<8>")
	)
	(gr_poly
		(pts
			(xy 83.350354 -104.94772) (xy 83.224624 -104.803956) (xy 83.188556 -104.768142) (xy 83.098894 -104.857804)
			(xy 83.134708 -104.893872) (xy 83.278472 -105.019602)
		)
		(stroke
			(width 0)
			(type solid)
		)
		(fill yes)
		(layer "F.Cu")
		(net "M_L_DQS_DN<8>")
	)
	(gr_poly
		(pts
			(xy 83.376008 -46.171612) (xy 83.411822 -46.135544) (xy 83.286092 -46.009814) (xy 83.250278 -46.045882)
			(xy 83.203542 -46.14291) (xy 83.27898 -46.218348)
		)
		(stroke
			(width 0)
			(type solid)
		)
		(fill yes)
		(layer "F.Cu")
		(net "M_H_ECC<2>")
	)
	(gr_poly
		(pts
			(xy 83.384898 -46.46803) (xy 83.431634 -46.371002) (xy 83.356196 -46.295564) (xy 83.259168 -46.3423)
			(xy 83.2231 -46.378114) (xy 83.34883 -46.503844)
		)
		(stroke
			(width 0)
			(type solid)
		)
		(fill yes)
		(layer "F.Cu")
		(net "M_H_ECC<7>")
	)
	(gr_poly
		(pts
			(xy 83.395566 -49.608232) (xy 83.395566 -49.501298) (xy 83.293966 -49.465992) (xy 83.243166 -49.465992)
			(xy 83.243166 -49.643792) (xy 83.293966 -49.643792)
		)
		(stroke
			(width 0)
			(type solid)
		)
		(fill yes)
		(layer "F.Cu")
		(net "M_H_DQS_DN<17>")
	)
	(gr_poly
		(pts
			(xy 83.395566 -49.176432) (xy 83.395566 -49.069498) (xy 83.293966 -49.034192) (xy 83.243166 -49.034192)
			(xy 83.243166 -49.211992) (xy 83.293966 -49.211992)
		)
		(stroke
			(width 0)
			(type solid)
		)
		(fill yes)
		(layer "F.Cu")
		(net "M_H_DQS_DN<17>")
	)
	(gr_poly
		(pts
			(xy 83.395566 -48.744632) (xy 83.395566 -48.637698) (xy 83.293966 -48.602392) (xy 83.243166 -48.602392)
			(xy 83.243166 -48.780192) (xy 83.293966 -48.780192)
		)
		(stroke
			(width 0)
			(type solid)
		)
		(fill yes)
		(layer "F.Cu")
		(net "M_H_DQS_DN<17>")
	)
	(gr_poly
		(pts
			(xy 83.395566 -48.312832) (xy 83.395566 -48.205898) (xy 83.293966 -48.170592) (xy 83.243166 -48.170592)
			(xy 83.243166 -48.348392) (xy 83.293966 -48.348392)
		)
		(stroke
			(width 0)
			(type solid)
		)
		(fill yes)
		(layer "F.Cu")
		(net "M_H_DQS_DN<17>")
	)
	(gr_poly
		(pts
			(xy 83.398106 -103.625396) (xy 83.362292 -103.589582) (xy 83.265264 -103.542846) (xy 83.189826 -103.618284)
			(xy 83.236562 -103.715312) (xy 83.272376 -103.751126)
		)
		(stroke
			(width 0)
			(type solid)
		)
		(fill yes)
		(layer "F.Cu")
		(net "M_L_DQS_DN<17>")
	)
	(gr_poly
		(pts
			(xy 83.417664 -103.389938) (xy 83.370928 -103.29291) (xy 83.335114 -103.257096) (xy 83.209384 -103.382826)
			(xy 83.245452 -103.41864) (xy 83.342226 -103.465376)
		)
		(stroke
			(width 0)
			(type solid)
		)
		(fill yes)
		(layer "F.Cu")
		(net "M_L_DQS_DP<17>")
	)
	(gr_poly
		(pts
			(xy 83.421982 -107.336336) (xy 83.377024 -107.291378) (xy 83.233514 -107.165648) (xy 83.161632 -107.23753)
			(xy 83.287362 -107.381294) (xy 83.332066 -107.426252)
		)
		(stroke
			(width 0)
			(type solid)
		)
		(fill yes)
		(layer "F.Cu")
		(net "M_L_ECC<3>")
	)
	(gr_poly
		(pts
			(xy 83.428332 -102.692454) (xy 83.377532 -102.692454) (xy 83.275932 -102.728014) (xy 83.275932 -102.834694)
			(xy 83.377532 -102.870254) (xy 83.428332 -102.870254)
		)
		(stroke
			(width 0)
			(type solid)
		)
		(fill yes)
		(layer "F.Cu")
		(net "M_L_DQS_DP<17>")
	)
	(gr_poly
		(pts
			(xy 83.428332 -102.260654) (xy 83.377532 -102.260654) (xy 83.275932 -102.296214) (xy 83.275932 -102.402894)
			(xy 83.377532 -102.438454) (xy 83.428332 -102.438454)
		)
		(stroke
			(width 0)
			(type solid)
		)
		(fill yes)
		(layer "F.Cu")
		(net "M_L_DQS_DP<17>")
	)
	(gr_poly
		(pts
			(xy 83.428332 -101.828854) (xy 83.377532 -101.828854) (xy 83.275932 -101.864414) (xy 83.275932 -101.971094)
			(xy 83.377532 -102.006654) (xy 83.428332 -102.006654)
		)
		(stroke
			(width 0)
			(type solid)
		)
		(fill yes)
		(layer "F.Cu")
		(net "M_L_DQS_DP<17>")
	)
	(gr_poly
		(pts
			(xy 83.428332 -101.397054) (xy 83.377532 -101.397054) (xy 83.275932 -101.432614) (xy 83.275932 -101.539294)
			(xy 83.377532 -101.574854) (xy 83.428332 -101.574854)
		)
		(stroke
			(width 0)
			(type solid)
		)
		(fill yes)
		(layer "F.Cu")
		(net "M_L_DQS_DP<17>")
	)
	(gr_poly
		(pts
			(xy 83.428332 -100.965254) (xy 83.377532 -100.965254) (xy 83.275932 -101.000814) (xy 83.275932 -101.107494)
			(xy 83.377532 -101.143054) (xy 83.428332 -101.143054)
		)
		(stroke
			(width 0)
			(type solid)
		)
		(fill yes)
		(layer "F.Cu")
		(net "M_L_DQS_DP<17>")
	)
	(gr_poly
		(pts
			(xy 83.428332 -100.533454) (xy 83.377532 -100.533454) (xy 83.275932 -100.569014) (xy 83.275932 -100.675694)
			(xy 83.377532 -100.711254) (xy 83.428332 -100.711254)
		)
		(stroke
			(width 0)
			(type solid)
		)
		(fill yes)
		(layer "F.Cu")
		(net "M_L_DQS_DP<17>")
	)
	(gr_poly
		(pts
			(xy 83.429348 -47.95012) (xy 83.465162 -47.914052) (xy 83.339432 -47.788322) (xy 83.303618 -47.82439)
			(xy 83.256882 -47.921418) (xy 83.33232 -47.996856)
		)
		(stroke
			(width 0)
			(type solid)
		)
		(fill yes)
		(layer "F.Cu")
		(net "M_H_DQS_DN<8>")
	)
	(gr_poly
		(pts
			(xy 83.440016 -105.97134) (xy 83.314286 -105.82783) (xy 83.278472 -105.791762) (xy 83.188556 -105.881678)
			(xy 83.224624 -105.917492) (xy 83.368134 -106.043222)
		)
		(stroke
			(width 0)
			(type solid)
		)
		(fill yes)
		(layer "F.Cu")
		(net "M_L_ECC<6>")
	)
	(gr_poly
		(pts
			(xy 83.46567 -46.692566) (xy 83.501484 -46.656498) (xy 83.375754 -46.530768) (xy 83.33994 -46.566836)
			(xy 83.293204 -46.663864) (xy 83.368642 -46.739302)
		)
		(stroke
			(width 0)
			(type solid)
		)
		(fill yes)
		(layer "F.Cu")
		(net "M_H_ECC<7>")
	)
	(gr_poly
		(pts
			(xy 83.469734 -52.914296) (xy 83.425284 -52.914296) (xy 83.255104 -53.003196) (xy 83.255104 -53.224176)
			(xy 83.425284 -53.313076) (xy 83.469734 -53.313076)
		)
		(stroke
			(width 0)
			(type solid)
		)
		(fill yes)
		(layer "F.Cu")
		(net "M_H_DQS_DN<8>")
	)
	(gr_poly
		(pts
			(xy 83.47456 -46.988984) (xy 83.521296 -46.891956) (xy 83.445858 -46.816518) (xy 83.34883 -46.863254)
			(xy 83.312762 -46.899068) (xy 83.438492 -47.024798)
		)
		(stroke
			(width 0)
			(type solid)
		)
		(fill yes)
		(layer "F.Cu")
		(net "M_H_ECC<6>")
	)
	(gr_poly
		(pts
			(xy 83.501992 -104.462834) (xy 83.501992 -104.356154) (xy 83.400392 -104.320594) (xy 83.349592 -104.320594)
			(xy 83.349592 -104.498394) (xy 83.400392 -104.498394)
		)
		(stroke
			(width 0)
			(type solid)
		)
		(fill yes)
		(layer "F.Cu")
		(net "M_L_DQS_DN<8>")
	)
	(gr_poly
		(pts
			(xy 83.511898 -105.558336) (xy 83.476084 -105.522522) (xy 83.33232 -105.396792) (xy 83.260438 -105.46842)
			(xy 83.386168 -105.612184) (xy 83.421982 -105.648252)
		)
		(stroke
			(width 0)
			(type solid)
		)
		(fill yes)
		(layer "F.Cu")
		(net "M_L_ECC<6>")
	)
	(gr_poly
		(pts
			(xy 83.529932 -106.995214) (xy 83.404202 -106.85145) (xy 83.368134 -106.815636) (xy 83.278472 -106.905298)
			(xy 83.314286 -106.941366) (xy 83.45805 -107.067096)
		)
		(stroke
			(width 0)
			(type solid)
		)
		(fill yes)
		(layer "F.Cu")
		(net "M_L_ECC<2>")
	)
	(gr_poly
		(pts
			(xy 83.547966 -49.681892) (xy 83.497166 -49.681892) (xy 83.395566 -49.717198) (xy 83.395566 -49.824132)
			(xy 83.497166 -49.859692) (xy 83.547966 -49.859692)
		)
		(stroke
			(width 0)
			(type solid)
		)
		(fill yes)
		(layer "F.Cu")
		(net "M_H_DQS_DN<8>")
	)
	(gr_poly
		(pts
			(xy 83.547966 -49.250092) (xy 83.497166 -49.250092) (xy 83.395566 -49.285398) (xy 83.395566 -49.392332)
			(xy 83.497166 -49.427892) (xy 83.547966 -49.427892)
		)
		(stroke
			(width 0)
			(type solid)
		)
		(fill yes)
		(layer "F.Cu")
		(net "M_H_DQS_DN<8>")
	)
	(gr_poly
		(pts
			(xy 83.547966 -48.818292) (xy 83.497166 -48.818292) (xy 83.395566 -48.853598) (xy 83.395566 -48.960532)
			(xy 83.497166 -48.996092) (xy 83.547966 -48.996092)
		)
		(stroke
			(width 0)
			(type solid)
		)
		(fill yes)
		(layer "F.Cu")
		(net "M_H_DQS_DN<8>")
	)
	(gr_poly
		(pts
			(xy 83.547966 -48.386492) (xy 83.497166 -48.386492) (xy 83.395566 -48.421798) (xy 83.395566 -48.528732)
			(xy 83.497166 -48.564292) (xy 83.547966 -48.564292)
		)
		(stroke
			(width 0)
			(type solid)
		)
		(fill yes)
		(layer "F.Cu")
		(net "M_H_DQS_DN<8>")
	)
	(gr_poly
		(pts
			(xy 83.555332 -47.21352) (xy 83.591146 -47.177452) (xy 83.465416 -47.051722) (xy 83.429602 -47.08779)
			(xy 83.382866 -47.184818) (xy 83.458304 -47.260256)
		)
		(stroke
			(width 0)
			(type solid)
		)
		(fill yes)
		(layer "F.Cu")
		(net "M_H_ECC<6>")
	)
	(gr_poly
		(pts
			(xy 83.564222 -47.509938) (xy 83.610958 -47.41291) (xy 83.53552 -47.337472) (xy 83.438492 -47.384208)
			(xy 83.402678 -47.420276) (xy 83.528154 -47.545752)
		)
		(stroke
			(width 0)
			(type solid)
		)
		(fill yes)
		(layer "F.Cu")
		(net "M_H_DQS_DP<8>")
	)
	(gr_poly
		(pts
			(xy 83.580732 -103.050594) (xy 83.580732 -102.943914) (xy 83.479132 -102.908354) (xy 83.428332 -102.908354)
			(xy 83.428332 -103.086154) (xy 83.479132 -103.086154)
		)
		(stroke
			(width 0)
			(type solid)
		)
		(fill yes)
		(layer "F.Cu")
		(net "M_L_DQS_DP<17>")
	)
	(gr_poly
		(pts
			(xy 83.580732 -102.618794) (xy 83.580732 -102.512114) (xy 83.479132 -102.476554) (xy 83.428332 -102.476554)
			(xy 83.428332 -102.654354) (xy 83.479132 -102.654354)
		)
		(stroke
			(width 0)
			(type solid)
		)
		(fill yes)
		(layer "F.Cu")
		(net "M_L_DQS_DP<17>")
	)
	(gr_poly
		(pts
			(xy 83.580732 -102.186994) (xy 83.580732 -102.080314) (xy 83.479132 -102.044754) (xy 83.428332 -102.044754)
			(xy 83.428332 -102.222554) (xy 83.479132 -102.222554)
		)
		(stroke
			(width 0)
			(type solid)
		)
		(fill yes)
		(layer "F.Cu")
		(net "M_L_DQS_DP<17>")
	)
	(gr_poly
		(pts
			(xy 83.580732 -101.755194) (xy 83.580732 -101.648514) (xy 83.479132 -101.612954) (xy 83.428332 -101.612954)
			(xy 83.428332 -101.790754) (xy 83.479132 -101.790754)
		)
		(stroke
			(width 0)
			(type solid)
		)
		(fill yes)
		(layer "F.Cu")
		(net "M_L_DQS_DP<17>")
	)
	(gr_poly
		(pts
			(xy 83.580732 -101.323394) (xy 83.580732 -101.216714) (xy 83.479132 -101.181154) (xy 83.428332 -101.181154)
			(xy 83.428332 -101.358954) (xy 83.479132 -101.358954)
		)
		(stroke
			(width 0)
			(type solid)
		)
		(fill yes)
		(layer "F.Cu")
		(net "M_L_DQS_DP<17>")
	)
	(gr_poly
		(pts
			(xy 83.580732 -100.891594) (xy 83.580732 -100.784914) (xy 83.479132 -100.749354) (xy 83.428332 -100.749354)
			(xy 83.428332 -100.927154) (xy 83.479132 -100.927154)
		)
		(stroke
			(width 0)
			(type solid)
		)
		(fill yes)
		(layer "F.Cu")
		(net "M_L_DQS_DP<17>")
	)
	(gr_poly
		(pts
			(xy 83.5914 -45.955966) (xy 83.636358 -45.911008) (xy 83.510628 -45.785278) (xy 83.465924 -45.830236)
			(xy 83.419188 -45.927264) (xy 83.494626 -46.002702)
		)
		(stroke
			(width 0)
			(type solid)
		)
		(fill yes)
		(layer "F.Cu")
		(net "M_H_ECC<3>")
	)
	(gr_poly
		(pts
			(xy 83.600544 -46.252384) (xy 83.64728 -46.155356) (xy 83.571842 -46.079918) (xy 83.474814 -46.126654)
			(xy 83.438746 -46.162468) (xy 83.564476 -46.288198)
		)
		(stroke
			(width 0)
			(type solid)
		)
		(fill yes)
		(layer "F.Cu")
		(net "M_H_ECC<2>")
	)
	(gr_poly
		(pts
			(xy 83.60156 -106.58221) (xy 83.565746 -106.546142) (xy 83.421982 -106.420412) (xy 83.350354 -106.492294)
			(xy 83.476084 -106.636058) (xy 83.511898 -106.671872)
		)
		(stroke
			(width 0)
			(type solid)
		)
		(fill yes)
		(layer "F.Cu")
		(net "M_L_ECC<2>")
	)
	(gr_poly
		(pts
			(xy 83.613752 -103.841042) (xy 83.577938 -103.805228) (xy 83.48091 -103.758492) (xy 83.405472 -103.83393)
			(xy 83.452208 -103.930958) (xy 83.488022 -103.966772)
		)
		(stroke
			(width 0)
			(type solid)
		)
		(fill yes)
		(layer "F.Cu")
		(net "M_L_DQS_DN<8>")
	)
	(gr_poly
		(pts
			(xy 83.628738 -105.226104) (xy 83.503008 -105.08234) (xy 83.46694 -105.046526) (xy 83.377278 -105.136188)
			(xy 83.413092 -105.172256) (xy 83.556856 -105.297986)
		)
		(stroke
			(width 0)
			(type solid)
		)
		(fill yes)
		(layer "F.Cu")
		(net "M_L_DQS_DP<8>")
	)
	(gr_poly
		(pts
			(xy 83.63331 -103.605584) (xy 83.586574 -103.508556) (xy 83.55076 -103.472742) (xy 83.42503 -103.598472)
			(xy 83.461098 -103.634286) (xy 83.557872 -103.681022)
		)
		(stroke
			(width 0)
			(type solid)
		)
		(fill yes)
		(layer "F.Cu")
		(net "M_L_DQS_DN<17>")
	)
	(gr_poly
		(pts
			(xy 83.644994 -47.734474) (xy 83.681062 -47.69866) (xy 83.555332 -47.57293) (xy 83.519264 -47.608744)
			(xy 83.472528 -47.705772) (xy 83.547966 -47.78121)
		)
		(stroke
			(width 0)
			(type solid)
		)
		(fill yes)
		(layer "F.Cu")
		(net "M_H_DQS_DP<8>")
	)
	(gr_poly
		(pts
			(xy 83.654392 -104.536494) (xy 83.603592 -104.536494) (xy 83.501992 -104.572054) (xy 83.501992 -104.678734)
			(xy 83.603592 -104.714294) (xy 83.654392 -104.714294)
		)
		(stroke
			(width 0)
			(type solid)
		)
		(fill yes)
		(layer "F.Cu")
		(net "M_L_DQS_DP<8>")
	)
	(gr_poly
		(pts
			(xy 83.681316 -46.47692) (xy 83.71713 -46.440852) (xy 83.5914 -46.315122) (xy 83.555586 -46.35119)
			(xy 83.50885 -46.448218) (xy 83.584288 -46.523656)
		)
		(stroke
			(width 0)
			(type solid)
		)
		(fill yes)
		(layer "F.Cu")
		(net "M_H_ECC<2>")
	)
	(gr_poly
		(pts
			(xy 83.690206 -46.773338) (xy 83.736942 -46.67631) (xy 83.661504 -46.600872) (xy 83.564476 -46.647608)
			(xy 83.528408 -46.683422) (xy 83.654138 -46.809152)
		)
		(stroke
			(width 0)
			(type solid)
		)
		(fill yes)
		(layer "F.Cu")
		(net "M_H_ECC<7>")
	)
	(gr_poly
		(pts
			(xy 83.700366 -49.608232) (xy 83.700366 -49.501298) (xy 83.598766 -49.465992) (xy 83.547966 -49.465992)
			(xy 83.547966 -49.643792) (xy 83.598766 -49.643792)
		)
		(stroke
			(width 0)
			(type solid)
		)
		(fill yes)
		(layer "F.Cu")
		(net "M_H_DQS_DN<8>")
	)
	(gr_poly
		(pts
			(xy 83.700366 -49.176432) (xy 83.700366 -49.069498) (xy 83.598766 -49.034192) (xy 83.547966 -49.034192)
			(xy 83.547966 -49.211992) (xy 83.598766 -49.211992)
		)
		(stroke
			(width 0)
			(type solid)
		)
		(fill yes)
		(layer "F.Cu")
		(net "M_H_DQS_DN<8>")
	)
	(gr_poly
		(pts
			(xy 83.700366 -48.744632) (xy 83.700366 -48.637698) (xy 83.598766 -48.602392) (xy 83.547966 -48.602392)
			(xy 83.547966 -48.780192) (xy 83.598766 -48.780192)
		)
		(stroke
			(width 0)
			(type solid)
		)
		(fill yes)
		(layer "F.Cu")
		(net "M_H_DQS_DN<8>")
	)
	(gr_poly
		(pts
			(xy 83.700366 -48.312832) (xy 83.700366 -48.205898) (xy 83.598766 -48.170592) (xy 83.547966 -48.170592)
			(xy 83.547966 -48.348392) (xy 83.598766 -48.348392)
		)
		(stroke
			(width 0)
			(type solid)
		)
		(fill yes)
		(layer "F.Cu")
		(net "M_H_DQS_DN<8>")
	)
	(gr_poly
		(pts
			(xy 83.7184 -106.249724) (xy 83.59267 -106.106214) (xy 83.556856 -106.070146) (xy 83.46694 -106.160062)
			(xy 83.503008 -106.195876) (xy 83.646518 -106.321606)
		)
		(stroke
			(width 0)
			(type solid)
		)
		(fill yes)
		(layer "F.Cu")
		(net "M_L_ECC<7>")
	)
	(gr_poly
		(pts
			(xy 83.733132 -102.692454) (xy 83.682332 -102.692454) (xy 83.580732 -102.728014) (xy 83.580732 -102.834694)
			(xy 83.682332 -102.870254) (xy 83.733132 -102.870254)
		)
		(stroke
			(width 0)
			(type solid)
		)
		(fill yes)
		(layer "F.Cu")
		(net "M_L_DQS_DN<17>")
	)
	(gr_poly
		(pts
			(xy 83.733132 -102.260654) (xy 83.682332 -102.260654) (xy 83.580732 -102.296214) (xy 83.580732 -102.402894)
			(xy 83.682332 -102.438454) (xy 83.733132 -102.438454)
		)
		(stroke
			(width 0)
			(type solid)
		)
		(fill yes)
		(layer "F.Cu")
		(net "M_L_DQS_DN<17>")
	)
	(gr_poly
		(pts
			(xy 83.733132 -101.828854) (xy 83.682332 -101.828854) (xy 83.580732 -101.864414) (xy 83.580732 -101.971094)
			(xy 83.682332 -102.006654) (xy 83.733132 -102.006654)
		)
		(stroke
			(width 0)
			(type solid)
		)
		(fill yes)
		(layer "F.Cu")
		(net "M_L_DQS_DN<17>")
	)
	(gr_poly
		(pts
			(xy 83.733132 -101.397054) (xy 83.682332 -101.397054) (xy 83.580732 -101.432614) (xy 83.580732 -101.539294)
			(xy 83.682332 -101.574854) (xy 83.733132 -101.574854)
		)
		(stroke
			(width 0)
			(type solid)
		)
		(fill yes)
		(layer "F.Cu")
		(net "M_L_DQS_DN<17>")
	)
	(gr_poly
		(pts
			(xy 83.733132 -100.965254) (xy 83.682332 -100.965254) (xy 83.580732 -101.000814) (xy 83.580732 -101.107494)
			(xy 83.682332 -101.143054) (xy 83.733132 -101.143054)
		)
		(stroke
			(width 0)
			(type solid)
		)
		(fill yes)
		(layer "F.Cu")
		(net "M_L_DQS_DN<17>")
	)
	(gr_poly
		(pts
			(xy 83.733132 -100.533454) (xy 83.682332 -100.533454) (xy 83.580732 -100.569014) (xy 83.580732 -100.675694)
			(xy 83.682332 -100.711254) (xy 83.733132 -100.711254)
		)
		(stroke
			(width 0)
			(type solid)
		)
		(fill yes)
		(layer "F.Cu")
		(net "M_L_DQS_DN<17>")
	)
	(gr_poly
		(pts
			(xy 83.770978 -46.997874) (xy 83.806792 -46.961806) (xy 83.681062 -46.836076) (xy 83.645248 -46.872144)
			(xy 83.598512 -46.969172) (xy 83.67395 -47.04461)
		)
		(stroke
			(width 0)
			(type solid)
		)
		(fill yes)
		(layer "F.Cu")
		(net "M_H_ECC<7>")
	)
	(gr_poly
		(pts
			(xy 83.779868 -47.294292) (xy 83.826604 -47.197264) (xy 83.751166 -47.121826) (xy 83.654138 -47.168562)
			(xy 83.618324 -47.20463) (xy 83.7438 -47.330106)
		)
		(stroke
			(width 0)
			(type solid)
		)
		(fill yes)
		(layer "F.Cu")
		(net "M_H_ECC<6>")
	)
	(gr_poly
		(pts
			(xy 83.790282 -105.83672) (xy 83.754468 -105.800906) (xy 83.610704 -105.675176) (xy 83.538822 -105.746804)
			(xy 83.664552 -105.890568) (xy 83.700366 -105.926636)
		)
		(stroke
			(width 0)
			(type solid)
		)
		(fill yes)
		(layer "F.Cu")
		(net "M_L_ECC<7>")
	)
	(gr_poly
		(pts
			(xy 83.806792 -104.462834) (xy 83.806792 -104.356154) (xy 83.705192 -104.320594) (xy 83.654392 -104.320594)
			(xy 83.654392 -104.498394) (xy 83.705192 -104.498394)
		)
		(stroke
			(width 0)
			(type solid)
		)
		(fill yes)
		(layer "F.Cu")
		(net "M_L_DQS_DP<8>")
	)
	(gr_poly
		(pts
			(xy 83.829398 -104.056688) (xy 83.793584 -104.02062) (xy 83.696556 -103.974138) (xy 83.621118 -104.049576)
			(xy 83.667854 -104.14635) (xy 83.703668 -104.182418)
		)
		(stroke
			(width 0)
			(type solid)
		)
		(fill yes)
		(layer "F.Cu")
		(net "M_L_DQS_DP<8>")
	)
	(gr_poly
		(pts
			(xy 83.848956 -103.82123) (xy 83.80222 -103.724202) (xy 83.766406 -103.688388) (xy 83.640676 -103.814118)
			(xy 83.676744 -103.849932) (xy 83.773518 -103.896668)
		)
		(stroke
			(width 0)
			(type solid)
		)
		(fill yes)
		(layer "F.Cu")
		(net "M_L_DQS_DN<8>")
	)
	(gr_poly
		(pts
			(xy 83.852766 -49.681892) (xy 83.801966 -49.681892) (xy 83.700366 -49.717198) (xy 83.700366 -49.824132)
			(xy 83.801966 -49.859692) (xy 83.852766 -49.859692)
		)
		(stroke
			(width 0)
			(type solid)
		)
		(fill yes)
		(layer "F.Cu")
		(net "M_H_DQS_DP<8>")
	)
	(gr_poly
		(pts
			(xy 83.852766 -49.250092) (xy 83.801966 -49.250092) (xy 83.700366 -49.285398) (xy 83.700366 -49.392332)
			(xy 83.801966 -49.427892) (xy 83.852766 -49.427892)
		)
		(stroke
			(width 0)
			(type solid)
		)
		(fill yes)
		(layer "F.Cu")
		(net "M_H_DQS_DP<8>")
	)
	(gr_poly
		(pts
			(xy 83.852766 -48.818292) (xy 83.801966 -48.818292) (xy 83.700366 -48.853598) (xy 83.700366 -48.960532)
			(xy 83.801966 -48.996092) (xy 83.852766 -48.996092)
		)
		(stroke
			(width 0)
			(type solid)
		)
		(fill yes)
		(layer "F.Cu")
		(net "M_H_DQS_DP<8>")
	)
	(gr_poly
		(pts
			(xy 83.852766 -48.386492) (xy 83.801966 -48.386492) (xy 83.700366 -48.421798) (xy 83.700366 -48.528732)
			(xy 83.801966 -48.564292) (xy 83.852766 -48.564292)
		)
		(stroke
			(width 0)
			(type solid)
		)
		(fill yes)
		(layer "F.Cu")
		(net "M_H_DQS_DP<8>")
	)
	(gr_poly
		(pts
			(xy 83.852766 -47.954692) (xy 83.801966 -47.954692) (xy 83.700366 -47.989998) (xy 83.700366 -48.096932)
			(xy 83.801966 -48.132492) (xy 83.852766 -48.132492)
		)
		(stroke
			(width 0)
			(type solid)
		)
		(fill yes)
		(layer "F.Cu")
		(net "M_H_DQS_DP<8>")
	)
	(gr_poly
		(pts
			(xy 83.86064 -47.518828) (xy 83.896708 -47.483014) (xy 83.770978 -47.357284) (xy 83.73491 -47.393098)
			(xy 83.688174 -47.490126) (xy 83.763612 -47.565564)
		)
		(stroke
			(width 0)
			(type solid)
		)
		(fill yes)
		(layer "F.Cu")
		(net "M_H_ECC<6>")
	)
	(gr_poly
		(pts
			(xy 83.86953 -47.815246) (xy 83.916266 -47.718218) (xy 83.840828 -47.64278) (xy 83.7438 -47.689516)
			(xy 83.707986 -47.725584) (xy 83.833462 -47.85106)
		)
		(stroke
			(width 0)
			(type solid)
		)
		(fill yes)
		(layer "F.Cu")
		(net "M_H_DQS_DP<8>")
	)
	(gr_poly
		(pts
			(xy 83.885532 -103.050594) (xy 83.885532 -102.943914) (xy 83.783932 -102.908354) (xy 83.733132 -102.908354)
			(xy 83.733132 -103.086154) (xy 83.783932 -103.086154)
		)
		(stroke
			(width 0)
			(type solid)
		)
		(fill yes)
		(layer "F.Cu")
		(net "M_L_DQS_DN<17>")
	)
	(gr_poly
		(pts
			(xy 83.885532 -102.618794) (xy 83.885532 -102.512114) (xy 83.783932 -102.476554) (xy 83.733132 -102.476554)
			(xy 83.733132 -102.654354) (xy 83.783932 -102.654354)
		)
		(stroke
			(width 0)
			(type solid)
		)
		(fill yes)
		(layer "F.Cu")
		(net "M_L_DQS_DN<17>")
	)
	(gr_poly
		(pts
			(xy 83.885532 -102.186994) (xy 83.885532 -102.080314) (xy 83.783932 -102.044754) (xy 83.733132 -102.044754)
			(xy 83.733132 -102.222554) (xy 83.783932 -102.222554)
		)
		(stroke
			(width 0)
			(type solid)
		)
		(fill yes)
		(layer "F.Cu")
		(net "M_L_DQS_DN<17>")
	)
	(gr_poly
		(pts
			(xy 83.885532 -101.755194) (xy 83.885532 -101.648514) (xy 83.783932 -101.612954) (xy 83.733132 -101.612954)
			(xy 83.733132 -101.790754) (xy 83.783932 -101.790754)
		)
		(stroke
			(width 0)
			(type solid)
		)
		(fill yes)
		(layer "F.Cu")
		(net "M_L_DQS_DN<17>")
	)
	(gr_poly
		(pts
			(xy 83.885532 -101.323394) (xy 83.885532 -101.216714) (xy 83.783932 -101.181154) (xy 83.733132 -101.181154)
			(xy 83.733132 -101.358954) (xy 83.783932 -101.358954)
		)
		(stroke
			(width 0)
			(type solid)
		)
		(fill yes)
		(layer "F.Cu")
		(net "M_L_DQS_DN<17>")
	)
	(gr_poly
		(pts
			(xy 83.885532 -100.891594) (xy 83.885532 -100.784914) (xy 83.783932 -100.749354) (xy 83.733132 -100.749354)
			(xy 83.733132 -100.927154) (xy 83.783932 -100.927154)
		)
		(stroke
			(width 0)
			(type solid)
		)
		(fill yes)
		(layer "F.Cu")
		(net "M_L_DQS_DN<17>")
	)
	(gr_poly
		(pts
			(xy 83.888834 -106.869484) (xy 83.84413 -106.824526) (xy 83.700366 -106.698796) (xy 83.628484 -106.770678)
			(xy 83.754214 -106.914188) (xy 83.799172 -106.959146)
		)
		(stroke
			(width 0)
			(type solid)
		)
		(fill yes)
		(layer "F.Cu")
		(net "M_L_ECC<3>")
	)
	(gr_poly
		(pts
			(xy 83.896962 -46.261274) (xy 83.941666 -46.216316) (xy 83.815936 -46.090586) (xy 83.771232 -46.135544)
			(xy 83.724496 -46.232572) (xy 83.799934 -46.30801)
		)
		(stroke
			(width 0)
			(type solid)
		)
		(fill yes)
		(layer "F.Cu")
		(net "M_H_ECC<3>")
	)
	(gr_poly
		(pts
			(xy 83.905852 -46.557692) (xy 83.952588 -46.460664) (xy 83.87715 -46.385226) (xy 83.780122 -46.431962)
			(xy 83.744054 -46.467776) (xy 83.869784 -46.593506)
		)
		(stroke
			(width 0)
			(type solid)
		)
		(fill yes)
		(layer "F.Cu")
		(net "M_H_ECC<2>")
	)
	(gr_poly
		(pts
			(xy 83.907122 -105.504488) (xy 83.781392 -105.360724) (xy 83.745324 -105.32491) (xy 83.655662 -105.414572)
			(xy 83.691476 -105.45064) (xy 83.83524 -105.57637)
		)
		(stroke
			(width 0)
			(type solid)
		)
		(fill yes)
		(layer "F.Cu")
		(net "M_L_ECC<6>")
	)
	(gr_poly
		(pts
			(xy 83.91906 -103.535734) (xy 83.883246 -103.49992) (xy 83.786218 -103.453184) (xy 83.71078 -103.528622)
			(xy 83.757516 -103.62565) (xy 83.79333 -103.661464)
		)
		(stroke
			(width 0)
			(type solid)
		)
		(fill yes)
		(layer "F.Cu")
		(net "M_L_DQS_DN<8>")
	)
	(gr_poly
		(pts
			(xy 83.959192 -104.536494) (xy 83.908392 -104.536494) (xy 83.806792 -104.572054) (xy 83.806792 -104.678734)
			(xy 83.908392 -104.714294) (xy 83.959192 -104.714294)
		)
		(stroke
			(width 0)
			(type solid)
		)
		(fill yes)
		(layer "F.Cu")
		(net "M_L_ECC<6>")
	)
	(gr_poly
		(pts
			(xy 83.986624 -46.782228) (xy 84.022438 -46.74616) (xy 83.896708 -46.62043) (xy 83.860894 -46.656498)
			(xy 83.814158 -46.753526) (xy 83.889596 -46.828964)
		)
		(stroke
			(width 0)
			(type solid)
		)
		(fill yes)
		(layer "F.Cu")
		(net "M_H_ECC<2>")
	)
	(gr_poly
		(pts
			(xy 83.995514 -47.078646) (xy 84.04225 -46.981618) (xy 83.966812 -46.90618) (xy 83.869784 -46.952916)
			(xy 83.83397 -46.988984) (xy 83.959446 -47.11446)
		)
		(stroke
			(width 0)
			(type solid)
		)
		(fill yes)
		(layer "F.Cu")
		(net "M_H_ECC<7>")
	)
	(gr_poly
		(pts
			(xy 83.996784 -106.528108) (xy 83.871054 -106.384598) (xy 83.83524 -106.34853) (xy 83.745324 -106.438446)
			(xy 83.781392 -106.47426) (xy 83.924902 -106.59999)
		)
		(stroke
			(width 0)
			(type solid)
		)
		(fill yes)
		(layer "F.Cu")
		(net "M_L_ECC<2>")
	)
	(gr_poly
		(pts
			(xy 84.005166 -49.608232) (xy 84.005166 -49.501298) (xy 83.903566 -49.465992) (xy 83.852766 -49.465992)
			(xy 83.852766 -49.643792) (xy 83.903566 -49.643792)
		)
		(stroke
			(width 0)
			(type solid)
		)
		(fill yes)
		(layer "F.Cu")
		(net "M_H_DQS_DP<8>")
	)
	(gr_poly
		(pts
			(xy 84.005166 -49.176432) (xy 84.005166 -49.069498) (xy 83.903566 -49.034192) (xy 83.852766 -49.034192)
			(xy 83.852766 -49.211992) (xy 83.903566 -49.211992)
		)
		(stroke
			(width 0)
			(type solid)
		)
		(fill yes)
		(layer "F.Cu")
		(net "M_H_DQS_DP<8>")
	)
	(gr_poly
		(pts
			(xy 84.005166 -48.744632) (xy 84.005166 -48.637698) (xy 83.903566 -48.602392) (xy 83.852766 -48.602392)
			(xy 83.852766 -48.780192) (xy 83.903566 -48.780192)
		)
		(stroke
			(width 0)
			(type solid)
		)
		(fill yes)
		(layer "F.Cu")
		(net "M_H_DQS_DP<8>")
	)
	(gr_poly
		(pts
			(xy 84.005166 -48.312832) (xy 84.005166 -48.205898) (xy 83.903566 -48.170592) (xy 83.852766 -48.170592)
			(xy 83.852766 -48.348392) (xy 83.903566 -48.348392)
		)
		(stroke
			(width 0)
			(type solid)
		)
		(fill yes)
		(layer "F.Cu")
		(net "M_H_DQS_DP<8>")
	)
	(gr_poly
		(pts
			(xy 84.00796 -53.725826) (xy 84.00796 -53.504846) (xy 83.83778 -53.415946) (xy 83.79333 -53.415946)
			(xy 83.79333 -53.814726) (xy 83.83778 -53.814726)
		)
		(stroke
			(width 0)
			(type solid)
		)
		(fill yes)
		(layer "F.Cu")
		(net "M_H_DQS_DP<8>")
	)
	(gr_poly
		(pts
			(xy 84.00796 -52.735226) (xy 84.00796 -52.514246) (xy 83.83778 -52.425346) (xy 83.79333 -52.425346)
			(xy 83.79333 -52.824126) (xy 83.83778 -52.824126)
		)
		(stroke
			(width 0)
			(type solid)
		)
		(fill yes)
		(layer "F.Cu")
		(net "M_H_DQS_DP<8>")
	)
	(gr_poly
		(pts
			(xy 84.037932 -103.124254) (xy 83.987132 -103.124254) (xy 83.885532 -103.159814) (xy 83.885532 -103.266494)
			(xy 83.987132 -103.302054) (xy 84.037932 -103.302054)
		)
		(stroke
			(width 0)
			(type solid)
		)
		(fill yes)
		(layer "F.Cu")
		(net "M_L_DQS_DN<8>")
	)
	(gr_poly
		(pts
			(xy 84.037932 -102.692454) (xy 83.987132 -102.692454) (xy 83.885532 -102.728014) (xy 83.885532 -102.834694)
			(xy 83.987132 -102.870254) (xy 84.037932 -102.870254)
		)
		(stroke
			(width 0)
			(type solid)
		)
		(fill yes)
		(layer "F.Cu")
		(net "M_L_DQS_DN<8>")
	)
	(gr_poly
		(pts
			(xy 84.037932 -102.260654) (xy 83.987132 -102.260654) (xy 83.885532 -102.296214) (xy 83.885532 -102.402894)
			(xy 83.987132 -102.438454) (xy 84.037932 -102.438454)
		)
		(stroke
			(width 0)
			(type solid)
		)
		(fill yes)
		(layer "F.Cu")
		(net "M_L_DQS_DN<8>")
	)
	(gr_poly
		(pts
			(xy 84.037932 -101.828854) (xy 83.987132 -101.828854) (xy 83.885532 -101.864414) (xy 83.885532 -101.971094)
			(xy 83.987132 -102.006654) (xy 84.037932 -102.006654)
		)
		(stroke
			(width 0)
			(type solid)
		)
		(fill yes)
		(layer "F.Cu")
		(net "M_L_DQS_DN<8>")
	)
	(gr_poly
		(pts
			(xy 84.037932 -101.397054) (xy 83.987132 -101.397054) (xy 83.885532 -101.432614) (xy 83.885532 -101.539294)
			(xy 83.987132 -101.574854) (xy 84.037932 -101.574854)
		)
		(stroke
			(width 0)
			(type solid)
		)
		(fill yes)
		(layer "F.Cu")
		(net "M_L_DQS_DN<8>")
	)
	(gr_poly
		(pts
			(xy 84.037932 -100.965254) (xy 83.987132 -100.965254) (xy 83.885532 -101.000814) (xy 83.885532 -101.107494)
			(xy 83.987132 -101.143054) (xy 84.037932 -101.143054)
		)
		(stroke
			(width 0)
			(type solid)
		)
		(fill yes)
		(layer "F.Cu")
		(net "M_L_DQS_DN<8>")
	)
	(gr_poly
		(pts
			(xy 84.037932 -100.533454) (xy 83.987132 -100.533454) (xy 83.885532 -100.569014) (xy 83.885532 -100.675694)
			(xy 83.987132 -100.711254) (xy 84.037932 -100.711254)
		)
		(stroke
			(width 0)
			(type solid)
		)
		(fill yes)
		(layer "F.Cu")
		(net "M_L_DQS_DN<8>")
	)
	(gr_poly
		(pts
			(xy 84.064602 -104.036876) (xy 84.017866 -103.939848) (xy 83.982052 -103.904034) (xy 83.856322 -104.029764)
			(xy 83.89239 -104.065578) (xy 83.989164 -104.112314)
		)
		(stroke
			(width 0)
			(type solid)
		)
		(fill yes)
		(layer "F.Cu")
		(net "M_L_DQS_DP<8>")
	)
	(gr_poly
		(pts
			(xy 84.068666 -106.115104) (xy 84.032852 -106.07929) (xy 83.889088 -105.95356) (xy 83.817206 -106.025188)
			(xy 83.942936 -106.168952) (xy 83.97875 -106.20502)
		)
		(stroke
			(width 0)
			(type solid)
		)
		(fill yes)
		(layer "F.Cu")
		(net "M_L_ECC<2>")
	)
	(gr_poly
		(pts
			(xy 84.076286 -47.303182) (xy 84.112354 -47.267368) (xy 83.986624 -47.141638) (xy 83.950556 -47.177452)
			(xy 83.90382 -47.27448) (xy 83.979258 -47.349918)
		)
		(stroke
			(width 0)
			(type solid)
		)
		(fill yes)
		(layer "F.Cu")
		(net "M_H_ECC<7>")
	)
	(gr_poly
		(pts
			(xy 84.085176 -47.5996) (xy 84.131912 -47.502572) (xy 84.056474 -47.427134) (xy 83.959446 -47.47387)
			(xy 83.923632 -47.509938) (xy 84.049108 -47.635414)
		)
		(stroke
			(width 0)
			(type solid)
		)
		(fill yes)
		(layer "F.Cu")
		(net "M_H_ECC<6>")
	)
	(gr_poly
		(pts
			(xy 84.111592 -104.894634) (xy 84.111592 -104.787954) (xy 84.009992 -104.752394) (xy 83.959192 -104.752394)
			(xy 83.959192 -104.930194) (xy 84.009992 -104.930194)
		)
		(stroke
			(width 0)
			(type solid)
		)
		(fill yes)
		(layer "F.Cu")
		(net "M_L_ECC<6>")
	)
	(gr_poly
		(pts
			(xy 84.134706 -103.75138) (xy 84.098892 -103.715312) (xy 84.001864 -103.66883) (xy 83.926426 -103.744268)
			(xy 83.973162 -103.841042) (xy 84.008976 -103.87711)
		)
		(stroke
			(width 0)
			(type solid)
		)
		(fill yes)
		(layer "F.Cu")
		(net "M_L_DQS_DP<8>")
	)
	(gr_poly
		(pts
			(xy 84.154264 -103.515922) (xy 84.107528 -103.418894) (xy 84.071714 -103.38308) (xy 83.945984 -103.50881)
			(xy 83.982052 -103.544624) (xy 84.078826 -103.59136)
		)
		(stroke
			(width 0)
			(type solid)
		)
		(fill yes)
		(layer "F.Cu")
		(net "M_L_DQS_DN<8>")
	)
	(gr_poly
		(pts
			(xy 84.157566 -49.681892) (xy 84.106766 -49.681892) (xy 84.005166 -49.717198) (xy 84.005166 -49.824132)
			(xy 84.106766 -49.859692) (xy 84.157566 -49.859692)
		)
		(stroke
			(width 0)
			(type solid)
		)
		(fill yes)
		(layer "F.Cu")
		(net "M_H_ECC<6>")
	)
	(gr_poly
		(pts
			(xy 84.157566 -49.250092) (xy 84.106766 -49.250092) (xy 84.005166 -49.285398) (xy 84.005166 -49.392332)
			(xy 84.106766 -49.427892) (xy 84.157566 -49.427892)
		)
		(stroke
			(width 0)
			(type solid)
		)
		(fill yes)
		(layer "F.Cu")
		(net "M_H_ECC<6>")
	)
	(gr_poly
		(pts
			(xy 84.157566 -48.818292) (xy 84.106766 -48.818292) (xy 84.005166 -48.853598) (xy 84.005166 -48.960532)
			(xy 84.106766 -48.996092) (xy 84.157566 -48.996092)
		)
		(stroke
			(width 0)
			(type solid)
		)
		(fill yes)
		(layer "F.Cu")
		(net "M_H_ECC<6>")
	)
	(gr_poly
		(pts
			(xy 84.157566 -48.386492) (xy 84.106766 -48.386492) (xy 84.005166 -48.421798) (xy 84.005166 -48.528732)
			(xy 84.106766 -48.564292) (xy 84.157566 -48.564292)
		)
		(stroke
			(width 0)
			(type solid)
		)
		(fill yes)
		(layer "F.Cu")
		(net "M_H_ECC<6>")
	)
	(gr_poly
		(pts
			(xy 84.157566 -47.954692) (xy 84.106766 -47.954692) (xy 84.005166 -47.989998) (xy 84.005166 -48.096932)
			(xy 84.106766 -48.132492) (xy 84.157566 -48.132492)
		)
		(stroke
			(width 0)
			(type solid)
		)
		(fill yes)
		(layer "F.Cu")
		(net "M_H_ECC<6>")
	)
	(gr_poly
		(pts
			(xy 84.185506 -105.782872) (xy 84.059776 -105.639108) (xy 84.023708 -105.603294) (xy 83.934046 -105.692956)
			(xy 83.96986 -105.729024) (xy 84.113624 -105.854754)
		)
		(stroke
			(width 0)
			(type solid)
		)
		(fill yes)
		(layer "F.Cu")
		(net "M_L_ECC<7>")
	)
	(gr_poly
		(pts
			(xy 84.190332 -103.050594) (xy 84.190332 -102.943914) (xy 84.088732 -102.908354) (xy 84.037932 -102.908354)
			(xy 84.037932 -103.086154) (xy 84.088732 -103.086154)
		)
		(stroke
			(width 0)
			(type solid)
		)
		(fill yes)
		(layer "F.Cu")
		(net "M_L_DQS_DN<8>")
	)
	(gr_poly
		(pts
			(xy 84.190332 -102.618794) (xy 84.190332 -102.512114) (xy 84.088732 -102.476554) (xy 84.037932 -102.476554)
			(xy 84.037932 -102.654354) (xy 84.088732 -102.654354)
		)
		(stroke
			(width 0)
			(type solid)
		)
		(fill yes)
		(layer "F.Cu")
		(net "M_L_DQS_DN<8>")
	)
	(gr_poly
		(pts
			(xy 84.190332 -102.186994) (xy 84.190332 -102.080314) (xy 84.088732 -102.044754) (xy 84.037932 -102.044754)
			(xy 84.037932 -102.222554) (xy 84.088732 -102.222554)
		)
		(stroke
			(width 0)
			(type solid)
		)
		(fill yes)
		(layer "F.Cu")
		(net "M_L_DQS_DN<8>")
	)
	(gr_poly
		(pts
			(xy 84.190332 -101.755194) (xy 84.190332 -101.648514) (xy 84.088732 -101.612954) (xy 84.037932 -101.612954)
			(xy 84.037932 -101.790754) (xy 84.088732 -101.790754)
		)
		(stroke
			(width 0)
			(type solid)
		)
		(fill yes)
		(layer "F.Cu")
		(net "M_L_DQS_DN<8>")
	)
	(gr_poly
		(pts
			(xy 84.190332 -101.323394) (xy 84.190332 -101.216714) (xy 84.088732 -101.181154) (xy 84.037932 -101.181154)
			(xy 84.037932 -101.358954) (xy 84.088732 -101.358954)
		)
		(stroke
			(width 0)
			(type solid)
		)
		(fill yes)
		(layer "F.Cu")
		(net "M_L_DQS_DN<8>")
	)
	(gr_poly
		(pts
			(xy 84.190332 -100.891594) (xy 84.190332 -100.784914) (xy 84.088732 -100.749354) (xy 84.037932 -100.749354)
			(xy 84.037932 -100.927154) (xy 84.088732 -100.927154)
		)
		(stroke
			(width 0)
			(type solid)
		)
		(fill yes)
		(layer "F.Cu")
		(net "M_L_DQS_DN<8>")
	)
	(gr_poly
		(pts
			(xy 84.20227 -46.566582) (xy 84.246974 -46.521624) (xy 84.121244 -46.395894) (xy 84.07654 -46.440852)
			(xy 84.029804 -46.53788) (xy 84.105242 -46.613318)
		)
		(stroke
			(width 0)
			(type solid)
		)
		(fill yes)
		(layer "F.Cu")
		(net "M_H_ECC<3>")
	)
	(gr_poly
		(pts
			(xy 84.21116 -46.863) (xy 84.257896 -46.765972) (xy 84.182458 -46.690534) (xy 84.08543 -46.73727)
			(xy 84.049616 -46.773338) (xy 84.175092 -46.898814)
		)
		(stroke
			(width 0)
			(type solid)
		)
		(fill yes)
		(layer "F.Cu")
		(net "M_H_ECC<2>")
	)
	(gr_poly
		(pts
			(xy 84.263992 -104.968294) (xy 84.213192 -104.968294) (xy 84.111592 -105.003854) (xy 84.111592 -105.110534)
			(xy 84.213192 -105.146094) (xy 84.263992 -105.146094)
		)
		(stroke
			(width 0)
			(type solid)
		)
		(fill yes)
		(layer "F.Cu")
		(net "M_L_ECC<7>")
	)
	(gr_poly
		(pts
			(xy 84.263992 -104.536494) (xy 84.213192 -104.536494) (xy 84.111592 -104.572054) (xy 84.111592 -104.678734)
			(xy 84.213192 -104.714294) (xy 84.263992 -104.714294)
		)
		(stroke
			(width 0)
			(type solid)
		)
		(fill yes)
		(layer "F.Cu")
		(net "M_L_ECC<7>")
	)
	(gr_poly
		(pts
			(xy 84.280248 -104.252522) (xy 84.233512 -104.155494) (xy 84.197698 -104.11968) (xy 84.071968 -104.24541)
			(xy 84.108036 -104.281224) (xy 84.20481 -104.32796)
		)
		(stroke
			(width 0)
			(type solid)
		)
		(fill yes)
		(layer "F.Cu")
		(net "M_L_ECC<6>")
	)
	(gr_poly
		(pts
			(xy 84.291932 -47.087536) (xy 84.328 -47.051722) (xy 84.20227 -46.925992) (xy 84.166202 -46.961806)
			(xy 84.119466 -47.058834) (xy 84.194904 -47.134272)
		)
		(stroke
			(width 0)
			(type solid)
		)
		(fill yes)
		(layer "F.Cu")
		(net "M_H_ECC<2>")
	)
	(gr_poly
		(pts
			(xy 84.300822 -47.383954) (xy 84.347558 -47.286926) (xy 84.27212 -47.211488) (xy 84.175092 -47.258224)
			(xy 84.139278 -47.294292) (xy 84.265008 -47.420022)
		)
		(stroke
			(width 0)
			(type solid)
		)
		(fill yes)
		(layer "F.Cu")
		(net "M_H_ECC<7>")
	)
	(gr_poly
		(pts
			(xy 84.309966 -49.608232) (xy 84.309966 -49.501298) (xy 84.208366 -49.465992) (xy 84.157566 -49.465992)
			(xy 84.157566 -49.643792) (xy 84.208366 -49.643792)
		)
		(stroke
			(width 0)
			(type solid)
		)
		(fill yes)
		(layer "F.Cu")
		(net "M_H_ECC<6>")
	)
	(gr_poly
		(pts
			(xy 84.309966 -49.176432) (xy 84.309966 -49.069498) (xy 84.208366 -49.034192) (xy 84.157566 -49.034192)
			(xy 84.157566 -49.211992) (xy 84.208366 -49.211992)
		)
		(stroke
			(width 0)
			(type solid)
		)
		(fill yes)
		(layer "F.Cu")
		(net "M_H_ECC<6>")
	)
	(gr_poly
		(pts
			(xy 84.309966 -48.744632) (xy 84.309966 -48.637698) (xy 84.208366 -48.602392) (xy 84.157566 -48.602392)
			(xy 84.157566 -48.780192) (xy 84.208366 -48.780192)
		)
		(stroke
			(width 0)
			(type solid)
		)
		(fill yes)
		(layer "F.Cu")
		(net "M_H_ECC<6>")
	)
	(gr_poly
		(pts
			(xy 84.309966 -48.312832) (xy 84.309966 -48.205898) (xy 84.208366 -48.170592) (xy 84.157566 -48.170592)
			(xy 84.157566 -48.348392) (xy 84.208366 -48.348392)
		)
		(stroke
			(width 0)
			(type solid)
		)
		(fill yes)
		(layer "F.Cu")
		(net "M_H_ECC<6>")
	)
	(gr_poly
		(pts
			(xy 84.309966 -47.881032) (xy 84.309966 -47.774098) (xy 84.208366 -47.738792) (xy 84.157566 -47.738792)
			(xy 84.157566 -47.916592) (xy 84.208366 -47.916592)
		)
		(stroke
			(width 0)
			(type solid)
		)
		(fill yes)
		(layer "F.Cu")
		(net "M_H_ECC<6>")
	)
	(gr_poly
		(pts
			(xy 84.331302 -52.829206) (xy 84.330286 -52.43068) (xy 84.285836 -52.43068) (xy 84.115656 -52.520088)
			(xy 84.116418 -52.741068) (xy 84.286852 -52.82946)
		)
		(stroke
			(width 0)
			(type solid)
		)
		(fill yes)
		(layer "F.Cu")
		(net "M_H_ECC<6>")
	)
	(gr_poly
		(pts
			(xy 84.342732 -103.124254) (xy 84.291932 -103.124254) (xy 84.190332 -103.159814) (xy 84.190332 -103.266494)
			(xy 84.291932 -103.302054) (xy 84.342732 -103.302054)
		)
		(stroke
			(width 0)
			(type solid)
		)
		(fill yes)
		(layer "F.Cu")
		(net "M_L_DQS_DP<8>")
	)
	(gr_poly
		(pts
			(xy 84.342732 -102.692454) (xy 84.291932 -102.692454) (xy 84.190332 -102.728014) (xy 84.190332 -102.834694)
			(xy 84.291932 -102.870254) (xy 84.342732 -102.870254)
		)
		(stroke
			(width 0)
			(type solid)
		)
		(fill yes)
		(layer "F.Cu")
		(net "M_L_DQS_DP<8>")
	)
	(gr_poly
		(pts
			(xy 84.342732 -102.260654) (xy 84.291932 -102.260654) (xy 84.190332 -102.296214) (xy 84.190332 -102.402894)
			(xy 84.291932 -102.438454) (xy 84.342732 -102.438454)
		)
		(stroke
			(width 0)
			(type solid)
		)
		(fill yes)
		(layer "F.Cu")
		(net "M_L_DQS_DP<8>")
	)
	(gr_poly
		(pts
			(xy 84.342732 -101.828854) (xy 84.291932 -101.828854) (xy 84.190332 -101.864414) (xy 84.190332 -101.971094)
			(xy 84.291932 -102.006654) (xy 84.342732 -102.006654)
		)
		(stroke
			(width 0)
			(type solid)
		)
		(fill yes)
		(layer "F.Cu")
		(net "M_L_DQS_DP<8>")
	)
	(gr_poly
		(pts
			(xy 84.342732 -101.397054) (xy 84.291932 -101.397054) (xy 84.190332 -101.432614) (xy 84.190332 -101.539294)
			(xy 84.291932 -101.574854) (xy 84.342732 -101.574854)
		)
		(stroke
			(width 0)
			(type solid)
		)
		(fill yes)
		(layer "F.Cu")
		(net "M_L_DQS_DP<8>")
	)
	(gr_poly
		(pts
			(xy 84.342732 -100.965254) (xy 84.291932 -100.965254) (xy 84.190332 -101.000814) (xy 84.190332 -101.107494)
			(xy 84.291932 -101.143054) (xy 84.342732 -101.143054)
		)
		(stroke
			(width 0)
			(type solid)
		)
		(fill yes)
		(layer "F.Cu")
		(net "M_L_DQS_DP<8>")
	)
	(gr_poly
		(pts
			(xy 84.342732 -100.533454) (xy 84.291932 -100.533454) (xy 84.190332 -100.569014) (xy 84.190332 -100.675694)
			(xy 84.291932 -100.711254) (xy 84.342732 -100.711254)
		)
		(stroke
			(width 0)
			(type solid)
		)
		(fill yes)
		(layer "F.Cu")
		(net "M_L_DQS_DP<8>")
	)
	(gr_poly
		(pts
			(xy 84.350352 -103.967026) (xy 84.314538 -103.930958) (xy 84.21751 -103.884476) (xy 84.142072 -103.959914)
			(xy 84.188808 -104.056688) (xy 84.224622 -104.092756)
		)
		(stroke
			(width 0)
			(type solid)
		)
		(fill yes)
		(layer "F.Cu")
		(net "M_L_ECC<6>")
	)
	(gr_poly
		(pts
			(xy 84.35594 -106.402378) (xy 84.310982 -106.35742) (xy 84.167472 -106.23169) (xy 84.09559 -106.303572)
			(xy 84.22132 -106.447336) (xy 84.266024 -106.492294)
		)
		(stroke
			(width 0)
			(type solid)
		)
		(fill yes)
		(layer "F.Cu")
		(net "M_L_ECC<3>")
	)
	(gr_poly
		(pts
			(xy 84.36991 -103.731568) (xy 84.323174 -103.63454) (xy 84.28736 -103.598726) (xy 84.16163 -103.724456)
			(xy 84.197698 -103.76027) (xy 84.294472 -103.807006)
		)
		(stroke
			(width 0)
			(type solid)
		)
		(fill yes)
		(layer "F.Cu")
		(net "M_L_DQS_DP<8>")
	)
	(gr_poly
		(pts
			(xy 84.381594 -47.60849) (xy 84.417662 -47.572676) (xy 84.291932 -47.446946) (xy 84.255864 -47.48276)
			(xy 84.209128 -47.579788) (xy 84.284566 -47.655226)
		)
		(stroke
			(width 0)
			(type solid)
		)
		(fill yes)
		(layer "F.Cu")
		(net "M_H_ECC<7>")
	)
	(gr_poly
		(pts
			(xy 84.416392 -105.326434) (xy 84.416392 -105.219754) (xy 84.314792 -105.184194) (xy 84.263992 -105.184194)
			(xy 84.263992 -105.361994) (xy 84.314792 -105.361994)
		)
		(stroke
			(width 0)
			(type solid)
		)
		(fill yes)
		(layer "F.Cu")
		(net "M_L_ECC<7>")
	)
	(gr_poly
		(pts
			(xy 84.416392 -104.894634) (xy 84.416392 -104.787954) (xy 84.314792 -104.752394) (xy 84.263992 -104.752394)
			(xy 84.263992 -104.930194) (xy 84.314792 -104.930194)
		)
		(stroke
			(width 0)
			(type solid)
		)
		(fill yes)
		(layer "F.Cu")
		(net "M_L_ECC<7>")
	)
	(gr_poly
		(pts
			(xy 84.462366 -49.681892) (xy 84.411566 -49.681892) (xy 84.309966 -49.717198) (xy 84.309966 -49.824132)
			(xy 84.411566 -49.859692) (xy 84.462366 -49.859692)
		)
		(stroke
			(width 0)
			(type solid)
		)
		(fill yes)
		(layer "F.Cu")
		(net "M_H_ECC<7>")
	)
	(gr_poly
		(pts
			(xy 84.462366 -49.250092) (xy 84.411566 -49.250092) (xy 84.309966 -49.285398) (xy 84.309966 -49.392332)
			(xy 84.411566 -49.427892) (xy 84.462366 -49.427892)
		)
		(stroke
			(width 0)
			(type solid)
		)
		(fill yes)
		(layer "F.Cu")
		(net "M_H_ECC<7>")
	)
	(gr_poly
		(pts
			(xy 84.462366 -48.818292) (xy 84.411566 -48.818292) (xy 84.309966 -48.853598) (xy 84.309966 -48.960532)
			(xy 84.411566 -48.996092) (xy 84.462366 -48.996092)
		)
		(stroke
			(width 0)
			(type solid)
		)
		(fill yes)
		(layer "F.Cu")
		(net "M_H_ECC<7>")
	)
	(gr_poly
		(pts
			(xy 84.462366 -48.386492) (xy 84.411566 -48.386492) (xy 84.309966 -48.421798) (xy 84.309966 -48.528732)
			(xy 84.411566 -48.564292) (xy 84.462366 -48.564292)
		)
		(stroke
			(width 0)
			(type solid)
		)
		(fill yes)
		(layer "F.Cu")
		(net "M_H_ECC<7>")
	)
	(gr_poly
		(pts
			(xy 84.462366 -47.954692) (xy 84.411566 -47.954692) (xy 84.309966 -47.989998) (xy 84.309966 -48.096932)
			(xy 84.411566 -48.132492) (xy 84.462366 -48.132492)
		)
		(stroke
			(width 0)
			(type solid)
		)
		(fill yes)
		(layer "F.Cu")
		(net "M_H_ECC<7>")
	)
	(gr_poly
		(pts
			(xy 84.46389 -106.061256) (xy 84.33816 -105.917492) (xy 84.302092 -105.881678) (xy 84.21243 -105.97134)
			(xy 84.248244 -106.007408) (xy 84.392008 -106.133138)
		)
		(stroke
			(width 0)
			(type solid)
		)
		(fill yes)
		(layer "F.Cu")
		(net "M_L_ECC<2>")
	)
	(gr_poly
		(pts
			(xy 84.495132 -103.481378) (xy 84.495132 -103.374698) (xy 84.393532 -103.339138) (xy 84.342732 -103.339138)
			(xy 84.342732 -103.516938) (xy 84.393532 -103.516938)
		)
		(stroke
			(width 0)
			(type solid)
		)
		(fill yes)
		(layer "F.Cu")
		(net "M_L_DQS_DP<8>")
	)
	(gr_poly
		(pts
			(xy 84.495132 -103.050594) (xy 84.495132 -102.943914) (xy 84.393532 -102.908354) (xy 84.342732 -102.908354)
			(xy 84.342732 -103.086154) (xy 84.393532 -103.086154)
		)
		(stroke
			(width 0)
			(type solid)
		)
		(fill yes)
		(layer "F.Cu")
		(net "M_L_DQS_DP<8>")
	)
	(gr_poly
		(pts
			(xy 84.495132 -102.618794) (xy 84.495132 -102.512114) (xy 84.393532 -102.476554) (xy 84.342732 -102.476554)
			(xy 84.342732 -102.654354) (xy 84.393532 -102.654354)
		)
		(stroke
			(width 0)
			(type solid)
		)
		(fill yes)
		(layer "F.Cu")
		(net "M_L_DQS_DP<8>")
	)
	(gr_poly
		(pts
			(xy 84.495132 -102.186994) (xy 84.495132 -102.080314) (xy 84.393532 -102.044754) (xy 84.342732 -102.044754)
			(xy 84.342732 -102.222554) (xy 84.393532 -102.222554)
		)
		(stroke
			(width 0)
			(type solid)
		)
		(fill yes)
		(layer "F.Cu")
		(net "M_L_DQS_DP<8>")
	)
	(gr_poly
		(pts
			(xy 84.495132 -101.755194) (xy 84.495132 -101.648514) (xy 84.393532 -101.612954) (xy 84.342732 -101.612954)
			(xy 84.342732 -101.790754) (xy 84.393532 -101.790754)
		)
		(stroke
			(width 0)
			(type solid)
		)
		(fill yes)
		(layer "F.Cu")
		(net "M_L_DQS_DP<8>")
	)
	(gr_poly
		(pts
			(xy 84.495132 -101.323394) (xy 84.495132 -101.216714) (xy 84.393532 -101.181154) (xy 84.342732 -101.181154)
			(xy 84.342732 -101.358954) (xy 84.393532 -101.358954)
		)
		(stroke
			(width 0)
			(type solid)
		)
		(fill yes)
		(layer "F.Cu")
		(net "M_L_DQS_DP<8>")
	)
	(gr_poly
		(pts
			(xy 84.495132 -100.891594) (xy 84.495132 -100.784914) (xy 84.393532 -100.749354) (xy 84.342732 -100.749354)
			(xy 84.342732 -100.927154) (xy 84.393532 -100.927154)
		)
		(stroke
			(width 0)
			(type solid)
		)
		(fill yes)
		(layer "F.Cu")
		(net "M_L_DQS_DP<8>")
	)
	(gr_poly
		(pts
			(xy 84.495894 -104.468168) (xy 84.449158 -104.37114) (xy 84.413344 -104.335326) (xy 84.287614 -104.461056)
			(xy 84.323682 -104.49687) (xy 84.420456 -104.543606)
		)
		(stroke
			(width 0)
			(type solid)
		)
		(fill yes)
		(layer "F.Cu")
		(net "M_L_ECC<7>")
	)
	(gr_poly
		(pts
			(xy 84.507578 -46.87189) (xy 84.552536 -46.827186) (xy 84.426806 -46.701456) (xy 84.381848 -46.74616)
			(xy 84.335112 -46.843188) (xy 84.41055 -46.918626)
		)
		(stroke
			(width 0)
			(type solid)
		)
		(fill yes)
		(layer "F.Cu")
		(net "M_H_ECC<3>")
	)
	(gr_poly
		(pts
			(xy 84.516468 -47.168308) (xy 84.563204 -47.07128) (xy 84.487766 -46.995842) (xy 84.390738 -47.042578)
			(xy 84.354924 -47.078646) (xy 84.480654 -47.204376)
		)
		(stroke
			(width 0)
			(type solid)
		)
		(fill yes)
		(layer "F.Cu")
		(net "M_H_ECC<2>")
	)
	(gr_poly
		(pts
			(xy 84.536026 -105.647744) (xy 84.500212 -105.61193) (xy 84.356448 -105.4862) (xy 84.284566 -105.557828)
			(xy 84.410296 -105.701592) (xy 84.44611 -105.73766)
		)
		(stroke
			(width 0)
			(type solid)
		)
		(fill yes)
		(layer "F.Cu")
		(net "M_L_ECC<2>")
	)
	(gr_poly
		(pts
			(xy 84.565998 -104.182672) (xy 84.530184 -104.146604) (xy 84.433156 -104.100122) (xy 84.357718 -104.17556)
			(xy 84.404454 -104.272334) (xy 84.440268 -104.308402)
		)
		(stroke
			(width 0)
			(type solid)
		)
		(fill yes)
		(layer "F.Cu")
		(net "M_L_ECC<7>")
	)
	(gr_poly
		(pts
			(xy 84.568792 -104.968294) (xy 84.517992 -104.968294) (xy 84.416392 -105.003854) (xy 84.416392 -105.110534)
			(xy 84.517992 -105.146094) (xy 84.568792 -105.146094)
		)
		(stroke
			(width 0)
			(type solid)
		)
		(fill yes)
		(layer "F.Cu")
		(net "M_L_ECC<2>")
	)
	(gr_poly
		(pts
			(xy 84.585556 -103.947214) (xy 84.539074 -103.850186) (xy 84.503006 -103.814372) (xy 84.377276 -103.940102)
			(xy 84.413344 -103.975916) (xy 84.510118 -104.022652)
		)
		(stroke
			(width 0)
			(type solid)
		)
		(fill yes)
		(layer "F.Cu")
		(net "M_L_ECC<6>")
	)
	(gr_poly
		(pts
			(xy 84.59724 -47.392844) (xy 84.633308 -47.35703) (xy 84.507578 -47.2313) (xy 84.47151 -47.267114)
			(xy 84.424774 -47.364142) (xy 84.500212 -47.43958)
		)
		(stroke
			(width 0)
			(type solid)
		)
		(fill yes)
		(layer "F.Cu")
		(net "M_H_ECC<2>")
	)
	(gr_poly
		(pts
			(xy 84.614766 -49.608232) (xy 84.614766 -49.501298) (xy 84.513166 -49.465992) (xy 84.462366 -49.465992)
			(xy 84.462366 -49.643792) (xy 84.513166 -49.643792)
		)
		(stroke
			(width 0)
			(type solid)
		)
		(fill yes)
		(layer "F.Cu")
		(net "M_H_ECC<7>")
	)
	(gr_poly
		(pts
			(xy 84.614766 -49.176432) (xy 84.614766 -49.069498) (xy 84.513166 -49.034192) (xy 84.462366 -49.034192)
			(xy 84.462366 -49.211992) (xy 84.513166 -49.211992)
		)
		(stroke
			(width 0)
			(type solid)
		)
		(fill yes)
		(layer "F.Cu")
		(net "M_H_ECC<7>")
	)
	(gr_poly
		(pts
			(xy 84.614766 -48.744632) (xy 84.614766 -48.637698) (xy 84.513166 -48.602392) (xy 84.462366 -48.602392)
			(xy 84.462366 -48.780192) (xy 84.513166 -48.780192)
		)
		(stroke
			(width 0)
			(type solid)
		)
		(fill yes)
		(layer "F.Cu")
		(net "M_H_ECC<7>")
	)
	(gr_poly
		(pts
			(xy 84.614766 -48.312832) (xy 84.614766 -48.205898) (xy 84.513166 -48.170592) (xy 84.462366 -48.170592)
			(xy 84.462366 -48.348392) (xy 84.513166 -48.348392)
		)
		(stroke
			(width 0)
			(type solid)
		)
		(fill yes)
		(layer "F.Cu")
		(net "M_H_ECC<7>")
	)
	(gr_poly
		(pts
			(xy 84.614766 -47.881032) (xy 84.614766 -47.774098) (xy 84.513166 -47.738792) (xy 84.462366 -47.738792)
			(xy 84.462366 -47.916592) (xy 84.513166 -47.916592)
		)
		(stroke
			(width 0)
			(type solid)
		)
		(fill yes)
		(layer "F.Cu")
		(net "M_H_ECC<7>")
	)
	(gr_poly
		(pts
			(xy 84.647532 -103.124254) (xy 84.596732 -103.124254) (xy 84.495132 -103.159814) (xy 84.495132 -103.266494)
			(xy 84.596732 -103.302054) (xy 84.647532 -103.302054)
		)
		(stroke
			(width 0)
			(type solid)
		)
		(fill yes)
		(layer "F.Cu")
		(net "M_L_ECC<6>")
	)
	(gr_poly
		(pts
			(xy 84.647532 -102.692454) (xy 84.596732 -102.692454) (xy 84.495132 -102.728014) (xy 84.495132 -102.834694)
			(xy 84.596732 -102.870254) (xy 84.647532 -102.870254)
		)
		(stroke
			(width 0)
			(type solid)
		)
		(fill yes)
		(layer "F.Cu")
		(net "M_L_ECC<6>")
	)
	(gr_poly
		(pts
			(xy 84.647532 -102.260654) (xy 84.596732 -102.260654) (xy 84.495132 -102.296214) (xy 84.495132 -102.402894)
			(xy 84.596732 -102.438454) (xy 84.647532 -102.438454)
		)
		(stroke
			(width 0)
			(type solid)
		)
		(fill yes)
		(layer "F.Cu")
		(net "M_L_ECC<6>")
	)
	(gr_poly
		(pts
			(xy 84.647532 -101.828854) (xy 84.596732 -101.828854) (xy 84.495132 -101.864414) (xy 84.495132 -101.971094)
			(xy 84.596732 -102.006654) (xy 84.647532 -102.006654)
		)
		(stroke
			(width 0)
			(type solid)
		)
		(fill yes)
		(layer "F.Cu")
		(net "M_L_ECC<6>")
	)
	(gr_poly
		(pts
			(xy 84.647532 -101.397054) (xy 84.596732 -101.397054) (xy 84.495132 -101.432614) (xy 84.495132 -101.539294)
			(xy 84.596732 -101.574854) (xy 84.647532 -101.574854)
		)
		(stroke
			(width 0)
			(type solid)
		)
		(fill yes)
		(layer "F.Cu")
		(net "M_L_ECC<6>")
	)
	(gr_poly
		(pts
			(xy 84.647532 -100.965254) (xy 84.596732 -100.965254) (xy 84.495132 -101.000814) (xy 84.495132 -101.107494)
			(xy 84.596732 -101.143054) (xy 84.647532 -101.143054)
		)
		(stroke
			(width 0)
			(type solid)
		)
		(fill yes)
		(layer "F.Cu")
		(net "M_L_ECC<6>")
	)
	(gr_poly
		(pts
			(xy 84.647532 -100.533454) (xy 84.596732 -100.533454) (xy 84.495132 -100.569014) (xy 84.495132 -100.675694)
			(xy 84.596732 -100.711254) (xy 84.647532 -100.711254)
		)
		(stroke
			(width 0)
			(type solid)
		)
		(fill yes)
		(layer "F.Cu")
		(net "M_L_ECC<6>")
	)
	(gr_poly
		(pts
			(xy 84.675726 -54.219856) (xy 84.675726 -53.998876) (xy 84.505546 -53.909976) (xy 84.461096 -53.909976)
			(xy 84.461096 -54.308756) (xy 84.505546 -54.308756)
		)
		(stroke
			(width 0)
			(type solid)
		)
		(fill yes)
		(layer "F.Cu")
		(net "M_H_ECC<7>")
	)
	(gr_poly
		(pts
			(xy 84.721192 -105.326434) (xy 84.721192 -105.219754) (xy 84.619592 -105.184194) (xy 84.568792 -105.184194)
			(xy 84.568792 -105.361994) (xy 84.619592 -105.361994)
		)
		(stroke
			(width 0)
			(type solid)
		)
		(fill yes)
		(layer "F.Cu")
		(net "M_L_ECC<2>")
	)
	(gr_poly
		(pts
			(xy 84.721192 -104.894634) (xy 84.721192 -104.787954) (xy 84.619592 -104.752394) (xy 84.568792 -104.752394)
			(xy 84.568792 -104.930194) (xy 84.619592 -104.930194)
		)
		(stroke
			(width 0)
			(type solid)
		)
		(fill yes)
		(layer "F.Cu")
		(net "M_L_ECC<2>")
	)
	(gr_poly
		(pts
			(xy 84.767166 -49.250092) (xy 84.716366 -49.250092) (xy 84.614766 -49.285398) (xy 84.614766 -49.392332)
			(xy 84.716366 -49.427892) (xy 84.767166 -49.427892)
		)
		(stroke
			(width 0)
			(type solid)
		)
		(fill yes)
		(layer "F.Cu")
		(net "M_H_ECC<2>")
	)
	(gr_poly
		(pts
			(xy 84.767166 -48.818292) (xy 84.716366 -48.818292) (xy 84.614766 -48.853598) (xy 84.614766 -48.960532)
			(xy 84.716366 -48.996092) (xy 84.767166 -48.996092)
		)
		(stroke
			(width 0)
			(type solid)
		)
		(fill yes)
		(layer "F.Cu")
		(net "M_H_ECC<2>")
	)
	(gr_poly
		(pts
			(xy 84.767166 -48.386492) (xy 84.716366 -48.386492) (xy 84.614766 -48.421798) (xy 84.614766 -48.528732)
			(xy 84.716366 -48.564292) (xy 84.767166 -48.564292)
		)
		(stroke
			(width 0)
			(type solid)
		)
		(fill yes)
		(layer "F.Cu")
		(net "M_H_ECC<2>")
	)
	(gr_poly
		(pts
			(xy 84.767166 -47.954692) (xy 84.716366 -47.954692) (xy 84.614766 -47.989998) (xy 84.614766 -48.096932)
			(xy 84.716366 -48.132492) (xy 84.767166 -48.132492)
		)
		(stroke
			(width 0)
			(type solid)
		)
		(fill yes)
		(layer "F.Cu")
		(net "M_H_ECC<2>")
	)
	(gr_poly
		(pts
			(xy 84.767166 -47.522892) (xy 84.716366 -47.522892) (xy 84.614766 -47.558198) (xy 84.614766 -47.665132)
			(xy 84.716366 -47.700692) (xy 84.767166 -47.700692)
		)
		(stroke
			(width 0)
			(type solid)
		)
		(fill yes)
		(layer "F.Cu")
		(net "M_H_ECC<2>")
	)
	(gr_poly
		(pts
			(xy 84.781644 -104.398318) (xy 84.74583 -104.36225) (xy 84.648802 -104.315768) (xy 84.573364 -104.391206)
			(xy 84.6201 -104.48798) (xy 84.655914 -104.524048)
		)
		(stroke
			(width 0)
			(type solid)
		)
		(fill yes)
		(layer "F.Cu")
		(net "M_L_ECC<2>")
	)
	(gr_poly
		(pts
			(xy 84.799932 -103.482394) (xy 84.799932 -103.375714) (xy 84.698332 -103.340154) (xy 84.647532 -103.340154)
			(xy 84.647532 -103.517954) (xy 84.698332 -103.517954)
		)
		(stroke
			(width 0)
			(type solid)
		)
		(fill yes)
		(layer "F.Cu")
		(net "M_L_ECC<6>")
	)
	(gr_poly
		(pts
			(xy 84.799932 -103.050594) (xy 84.799932 -102.943914) (xy 84.698332 -102.908354) (xy 84.647532 -102.908354)
			(xy 84.647532 -103.086154) (xy 84.698332 -103.086154)
		)
		(stroke
			(width 0)
			(type solid)
		)
		(fill yes)
		(layer "F.Cu")
		(net "M_L_ECC<6>")
	)
	(gr_poly
		(pts
			(xy 84.799932 -102.618794) (xy 84.799932 -102.512114) (xy 84.698332 -102.476554) (xy 84.647532 -102.476554)
			(xy 84.647532 -102.654354) (xy 84.698332 -102.654354)
		)
		(stroke
			(width 0)
			(type solid)
		)
		(fill yes)
		(layer "F.Cu")
		(net "M_L_ECC<6>")
	)
	(gr_poly
		(pts
			(xy 84.799932 -102.186994) (xy 84.799932 -102.080314) (xy 84.698332 -102.044754) (xy 84.647532 -102.044754)
			(xy 84.647532 -102.222554) (xy 84.698332 -102.222554)
		)
		(stroke
			(width 0)
			(type solid)
		)
		(fill yes)
		(layer "F.Cu")
		(net "M_L_ECC<6>")
	)
	(gr_poly
		(pts
			(xy 84.799932 -101.755194) (xy 84.799932 -101.648514) (xy 84.698332 -101.612954) (xy 84.647532 -101.612954)
			(xy 84.647532 -101.790754) (xy 84.698332 -101.790754)
		)
		(stroke
			(width 0)
			(type solid)
		)
		(fill yes)
		(layer "F.Cu")
		(net "M_L_ECC<6>")
	)
	(gr_poly
		(pts
			(xy 84.799932 -101.323394) (xy 84.799932 -101.216714) (xy 84.698332 -101.181154) (xy 84.647532 -101.181154)
			(xy 84.647532 -101.358954) (xy 84.698332 -101.358954)
		)
		(stroke
			(width 0)
			(type solid)
		)
		(fill yes)
		(layer "F.Cu")
		(net "M_L_ECC<6>")
	)
	(gr_poly
		(pts
			(xy 84.799932 -100.891594) (xy 84.799932 -100.784914) (xy 84.698332 -100.749354) (xy 84.647532 -100.749354)
			(xy 84.647532 -100.927154) (xy 84.698332 -100.927154)
		)
		(stroke
			(width 0)
			(type solid)
		)
		(fill yes)
		(layer "F.Cu")
		(net "M_L_ECC<6>")
	)
	(gr_poly
		(pts
			(xy 84.801202 -104.16286) (xy 84.75472 -104.065832) (xy 84.718652 -104.030018) (xy 84.592922 -104.155748)
			(xy 84.62899 -104.191562) (xy 84.725764 -104.238298)
		)
		(stroke
			(width 0)
			(type solid)
		)
		(fill yes)
		(layer "F.Cu")
		(net "M_L_ECC<7>")
	)
	(gr_poly
		(pts
			(xy 84.812886 -47.177198) (xy 84.857844 -47.132494) (xy 84.732114 -47.006764) (xy 84.687156 -47.051468)
			(xy 84.64042 -47.148496) (xy 84.715858 -47.223934)
		)
		(stroke
			(width 0)
			(type solid)
		)
		(fill yes)
		(layer "F.Cu")
		(net "M_H_ECC<3>")
	)
	(gr_poly
		(pts
			(xy 84.821776 -47.473616) (xy 84.868512 -47.376588) (xy 84.793074 -47.30115) (xy 84.696046 -47.347886)
			(xy 84.660232 -47.383954) (xy 84.785962 -47.509684)
		)
		(stroke
			(width 0)
			(type solid)
		)
		(fill yes)
		(layer "F.Cu")
		(net "M_H_ECC<2>")
	)
	(gr_poly
		(pts
			(xy 84.8233 -105.935018) (xy 84.778342 -105.89006) (xy 84.634832 -105.76433) (xy 84.56295 -105.836212)
			(xy 84.68868 -105.979976) (xy 84.733384 -106.024934)
		)
		(stroke
			(width 0)
			(type solid)
		)
		(fill yes)
		(layer "F.Cu")
		(net "M_L_ECC<3>")
	)
	(gr_poly
		(pts
			(xy 84.86648 -53.224176) (xy 84.86648 -53.003196) (xy 84.6963 -52.914296) (xy 84.65185 -52.914296)
			(xy 84.65185 -53.313076) (xy 84.6963 -53.313076)
		)
		(stroke
			(width 0)
			(type solid)
		)
		(fill yes)
		(layer "F.Cu")
		(net "M_H_ECC<7>")
	)
	(gr_poly
		(pts
			(xy 84.871306 -103.877364) (xy 84.835492 -103.841296) (xy 84.738464 -103.794814) (xy 84.663026 -103.870252)
			(xy 84.709762 -103.967026) (xy 84.745576 -104.003094)
		)
		(stroke
			(width 0)
			(type solid)
		)
		(fill yes)
		(layer "F.Cu")
		(net "M_L_ECC<7>")
	)
	(gr_poly
		(pts
			(xy 84.886292 -105.400094) (xy 84.822792 -105.400094) (xy 84.721192 -105.435654) (xy 84.721192 -105.542334)
			(xy 84.822792 -105.577894) (xy 84.886292 -105.577894)
		)
		(stroke
			(width 0)
			(type solid)
		)
		(fill yes)
		(layer "F.Cu")
		(net "M_L_ECC<3>")
	)
	(gr_poly
		(pts
			(xy 84.886292 -104.968294) (xy 84.822792 -104.968294) (xy 84.721192 -105.003854) (xy 84.721192 -105.110534)
			(xy 84.822792 -105.146094) (xy 84.886292 -105.146094)
		)
		(stroke
			(width 0)
			(type solid)
		)
		(fill yes)
		(layer "F.Cu")
		(net "M_L_ECC<3>")
	)
	(gr_poly
		(pts
			(xy 84.919566 -49.176432) (xy 84.919566 -49.069498) (xy 84.817966 -49.034192) (xy 84.767166 -49.034192)
			(xy 84.767166 -49.211992) (xy 84.817966 -49.211992)
		)
		(stroke
			(width 0)
			(type solid)
		)
		(fill yes)
		(layer "F.Cu")
		(net "M_H_ECC<2>")
	)
	(gr_poly
		(pts
			(xy 84.919566 -48.744632) (xy 84.919566 -48.637698) (xy 84.817966 -48.602392) (xy 84.767166 -48.602392)
			(xy 84.767166 -48.780192) (xy 84.817966 -48.780192)
		)
		(stroke
			(width 0)
			(type solid)
		)
		(fill yes)
		(layer "F.Cu")
		(net "M_H_ECC<2>")
	)
	(gr_poly
		(pts
			(xy 84.919566 -48.312832) (xy 84.919566 -48.205898) (xy 84.817966 -48.170592) (xy 84.767166 -48.170592)
			(xy 84.767166 -48.348392) (xy 84.817966 -48.348392)
		)
		(stroke
			(width 0)
			(type solid)
		)
		(fill yes)
		(layer "F.Cu")
		(net "M_H_ECC<2>")
	)
	(gr_poly
		(pts
			(xy 84.919566 -47.881032) (xy 84.919566 -47.774098) (xy 84.817966 -47.738792) (xy 84.767166 -47.738792)
			(xy 84.767166 -47.916592) (xy 84.817966 -47.916592)
		)
		(stroke
			(width 0)
			(type solid)
		)
		(fill yes)
		(layer "F.Cu")
		(net "M_H_ECC<2>")
	)
	(gr_poly
		(pts
			(xy 84.952332 -103.556054) (xy 84.901532 -103.556054) (xy 84.799932 -103.591614) (xy 84.799932 -103.698294)
			(xy 84.901532 -103.733854) (xy 84.952332 -103.733854)
		)
		(stroke
			(width 0)
			(type solid)
		)
		(fill yes)
		(layer "F.Cu")
		(net "M_L_ECC<7>")
	)
	(gr_poly
		(pts
			(xy 84.952332 -103.124254) (xy 84.901532 -103.124254) (xy 84.799932 -103.159814) (xy 84.799932 -103.266494)
			(xy 84.901532 -103.302054) (xy 84.952332 -103.302054)
		)
		(stroke
			(width 0)
			(type solid)
		)
		(fill yes)
		(layer "F.Cu")
		(net "M_L_ECC<7>")
	)
	(gr_poly
		(pts
			(xy 84.952332 -102.692454) (xy 84.901532 -102.692454) (xy 84.799932 -102.728014) (xy 84.799932 -102.834694)
			(xy 84.901532 -102.870254) (xy 84.952332 -102.870254)
		)
		(stroke
			(width 0)
			(type solid)
		)
		(fill yes)
		(layer "F.Cu")
		(net "M_L_ECC<7>")
	)
	(gr_poly
		(pts
			(xy 84.952332 -102.260654) (xy 84.901532 -102.260654) (xy 84.799932 -102.296214) (xy 84.799932 -102.402894)
			(xy 84.901532 -102.438454) (xy 84.952332 -102.438454)
		)
		(stroke
			(width 0)
			(type solid)
		)
		(fill yes)
		(layer "F.Cu")
		(net "M_L_ECC<7>")
	)
	(gr_poly
		(pts
			(xy 84.952332 -101.828854) (xy 84.901532 -101.828854) (xy 84.799932 -101.864414) (xy 84.799932 -101.971094)
			(xy 84.901532 -102.006654) (xy 84.952332 -102.006654)
		)
		(stroke
			(width 0)
			(type solid)
		)
		(fill yes)
		(layer "F.Cu")
		(net "M_L_ECC<7>")
	)
	(gr_poly
		(pts
			(xy 84.952332 -101.397054) (xy 84.901532 -101.397054) (xy 84.799932 -101.432614) (xy 84.799932 -101.539294)
			(xy 84.901532 -101.574854) (xy 84.952332 -101.574854)
		)
		(stroke
			(width 0)
			(type solid)
		)
		(fill yes)
		(layer "F.Cu")
		(net "M_L_ECC<7>")
	)
	(gr_poly
		(pts
			(xy 84.952332 -100.965254) (xy 84.901532 -100.965254) (xy 84.799932 -101.000814) (xy 84.799932 -101.107494)
			(xy 84.901532 -101.143054) (xy 84.952332 -101.143054)
		)
		(stroke
			(width 0)
			(type solid)
		)
		(fill yes)
		(layer "F.Cu")
		(net "M_L_ECC<7>")
	)
	(gr_poly
		(pts
			(xy 84.952332 -100.533454) (xy 84.901532 -100.533454) (xy 84.799932 -100.569014) (xy 84.799932 -100.675694)
			(xy 84.901532 -100.711254) (xy 84.952332 -100.711254)
		)
		(stroke
			(width 0)
			(type solid)
		)
		(fill yes)
		(layer "F.Cu")
		(net "M_L_ECC<7>")
	)
	(gr_poly
		(pts
			(xy 85.00618 -104.622854) (xy 84.961222 -104.577896) (xy 84.864448 -104.53116) (xy 84.78901 -104.606598)
			(xy 84.835492 -104.703626) (xy 84.88045 -104.748584)
		)
		(stroke
			(width 0)
			(type solid)
		)
		(fill yes)
		(layer "F.Cu")
		(net "M_L_ECC<3>")
	)
	(gr_poly
		(pts
			(xy 85.016848 -104.378506) (xy 84.970366 -104.281478) (xy 84.934298 -104.245664) (xy 84.808568 -104.371394)
			(xy 84.844636 -104.407208) (xy 84.94141 -104.453944)
		)
		(stroke
			(width 0)
			(type solid)
		)
		(fill yes)
		(layer "F.Cu")
		(net "M_L_ECC<2>")
	)
	(gr_poly
		(pts
			(xy 85.084666 -49.250092) (xy 85.021166 -49.250092) (xy 84.919566 -49.285398) (xy 84.919566 -49.392332)
			(xy 85.021166 -49.427892) (xy 85.084666 -49.427892)
		)
		(stroke
			(width 0)
			(type solid)
		)
		(fill yes)
		(layer "F.Cu")
		(net "M_H_ECC<3>")
	)
	(gr_poly
		(pts
			(xy 85.084666 -48.818292) (xy 85.021166 -48.818292) (xy 84.919566 -48.853598) (xy 84.919566 -48.960532)
			(xy 85.021166 -48.996092) (xy 85.084666 -48.996092)
		)
		(stroke
			(width 0)
			(type solid)
		)
		(fill yes)
		(layer "F.Cu")
		(net "M_H_ECC<3>")
	)
	(gr_poly
		(pts
			(xy 85.084666 -48.386492) (xy 85.021166 -48.386492) (xy 84.919566 -48.421798) (xy 84.919566 -48.528732)
			(xy 85.021166 -48.564292) (xy 85.084666 -48.564292)
		)
		(stroke
			(width 0)
			(type solid)
		)
		(fill yes)
		(layer "F.Cu")
		(net "M_H_ECC<3>")
	)
	(gr_poly
		(pts
			(xy 85.084666 -47.954692) (xy 85.021166 -47.954692) (xy 84.919566 -47.989998) (xy 84.919566 -48.096932)
			(xy 85.021166 -48.132492) (xy 85.084666 -48.132492)
		)
		(stroke
			(width 0)
			(type solid)
		)
		(fill yes)
		(layer "F.Cu")
		(net "M_H_ECC<3>")
	)
	(gr_poly
		(pts
			(xy 85.084666 -47.522892) (xy 85.021166 -47.522892) (xy 84.919566 -47.558198) (xy 84.919566 -47.665132)
			(xy 85.021166 -47.700692) (xy 85.084666 -47.700692)
		)
		(stroke
			(width 0)
			(type solid)
		)
		(fill yes)
		(layer "F.Cu")
		(net "M_H_ECC<3>")
	)
	(gr_poly
		(pts
			(xy 85.086952 -104.09301) (xy 85.051138 -104.056942) (xy 84.95411 -104.01046) (xy 84.878672 -104.085898)
			(xy 84.925408 -104.182672) (xy 84.961222 -104.21874)
		)
		(stroke
			(width 0)
			(type solid)
		)
		(fill yes)
		(layer "F.Cu")
		(net "M_L_ECC<2>")
	)
	(gr_poly
		(pts
			(xy 85.104732 -103.482394) (xy 85.104732 -103.375714) (xy 85.003132 -103.340154) (xy 84.952332 -103.340154)
			(xy 84.952332 -103.517954) (xy 85.003132 -103.517954)
		)
		(stroke
			(width 0)
			(type solid)
		)
		(fill yes)
		(layer "F.Cu")
		(net "M_L_ECC<7>")
	)
	(gr_poly
		(pts
			(xy 85.104732 -103.050594) (xy 85.104732 -102.943914) (xy 85.003132 -102.908354) (xy 84.952332 -102.908354)
			(xy 84.952332 -103.086154) (xy 85.003132 -103.086154)
		)
		(stroke
			(width 0)
			(type solid)
		)
		(fill yes)
		(layer "F.Cu")
		(net "M_L_ECC<7>")
	)
	(gr_poly
		(pts
			(xy 85.104732 -102.618794) (xy 85.104732 -102.512114) (xy 85.003132 -102.476554) (xy 84.952332 -102.476554)
			(xy 84.952332 -102.654354) (xy 85.003132 -102.654354)
		)
		(stroke
			(width 0)
			(type solid)
		)
		(fill yes)
		(layer "F.Cu")
		(net "M_L_ECC<7>")
	)
	(gr_poly
		(pts
			(xy 85.104732 -102.186994) (xy 85.104732 -102.080314) (xy 85.003132 -102.044754) (xy 84.952332 -102.044754)
			(xy 84.952332 -102.222554) (xy 85.003132 -102.222554)
		)
		(stroke
			(width 0)
			(type solid)
		)
		(fill yes)
		(layer "F.Cu")
		(net "M_L_ECC<7>")
	)
	(gr_poly
		(pts
			(xy 85.104732 -101.755194) (xy 85.104732 -101.648514) (xy 85.003132 -101.612954) (xy 84.952332 -101.612954)
			(xy 84.952332 -101.790754) (xy 85.003132 -101.790754)
		)
		(stroke
			(width 0)
			(type solid)
		)
		(fill yes)
		(layer "F.Cu")
		(net "M_L_ECC<7>")
	)
	(gr_poly
		(pts
			(xy 85.104732 -101.323394) (xy 85.104732 -101.216714) (xy 85.003132 -101.181154) (xy 84.952332 -101.181154)
			(xy 84.952332 -101.358954) (xy 85.003132 -101.358954)
		)
		(stroke
			(width 0)
			(type solid)
		)
		(fill yes)
		(layer "F.Cu")
		(net "M_L_ECC<7>")
	)
	(gr_poly
		(pts
			(xy 85.104732 -100.891594) (xy 85.104732 -100.784914) (xy 85.003132 -100.749354) (xy 84.952332 -100.749354)
			(xy 84.952332 -100.927154) (xy 85.003132 -100.927154)
		)
		(stroke
			(width 0)
			(type solid)
		)
		(fill yes)
		(layer "F.Cu")
		(net "M_L_ECC<7>")
	)
	(gr_poly
		(pts
			(xy 85.186774 -52.914296) (xy 85.142324 -52.914296) (xy 84.972144 -53.003196) (xy 84.972144 -53.224176)
			(xy 85.142324 -53.313076) (xy 85.186774 -53.313076)
		)
		(stroke
			(width 0)
			(type solid)
		)
		(fill yes)
		(layer "F.Cu")
		(net "M_H_ECC<2>")
	)
	(gr_poly
		(pts
			(xy 85.257132 -103.556054) (xy 85.206332 -103.556054) (xy 85.104732 -103.591614) (xy 85.104732 -103.698294)
			(xy 85.206332 -103.733854) (xy 85.257132 -103.733854)
		)
		(stroke
			(width 0)
			(type solid)
		)
		(fill yes)
		(layer "F.Cu")
		(net "M_L_ECC<2>")
	)
	(gr_poly
		(pts
			(xy 85.257132 -103.124254) (xy 85.206332 -103.124254) (xy 85.104732 -103.159814) (xy 85.104732 -103.266494)
			(xy 85.206332 -103.302054) (xy 85.257132 -103.302054)
		)
		(stroke
			(width 0)
			(type solid)
		)
		(fill yes)
		(layer "F.Cu")
		(net "M_L_ECC<2>")
	)
	(gr_poly
		(pts
			(xy 85.257132 -102.692454) (xy 85.206332 -102.692454) (xy 85.104732 -102.728014) (xy 85.104732 -102.834694)
			(xy 85.206332 -102.870254) (xy 85.257132 -102.870254)
		)
		(stroke
			(width 0)
			(type solid)
		)
		(fill yes)
		(layer "F.Cu")
		(net "M_L_ECC<2>")
	)
	(gr_poly
		(pts
			(xy 85.257132 -102.260654) (xy 85.206332 -102.260654) (xy 85.104732 -102.296214) (xy 85.104732 -102.402894)
			(xy 85.206332 -102.438454) (xy 85.257132 -102.438454)
		)
		(stroke
			(width 0)
			(type solid)
		)
		(fill yes)
		(layer "F.Cu")
		(net "M_L_ECC<2>")
	)
	(gr_poly
		(pts
			(xy 85.257132 -101.828854) (xy 85.206332 -101.828854) (xy 85.104732 -101.864414) (xy 85.104732 -101.971094)
			(xy 85.206332 -102.006654) (xy 85.257132 -102.006654)
		)
		(stroke
			(width 0)
			(type solid)
		)
		(fill yes)
		(layer "F.Cu")
		(net "M_L_ECC<2>")
	)
	(gr_poly
		(pts
			(xy 85.257132 -101.397054) (xy 85.206332 -101.397054) (xy 85.104732 -101.432614) (xy 85.104732 -101.539294)
			(xy 85.206332 -101.574854) (xy 85.257132 -101.574854)
		)
		(stroke
			(width 0)
			(type solid)
		)
		(fill yes)
		(layer "F.Cu")
		(net "M_L_ECC<2>")
	)
	(gr_poly
		(pts
			(xy 85.257132 -100.965254) (xy 85.206332 -100.965254) (xy 85.104732 -101.000814) (xy 85.104732 -101.107494)
			(xy 85.206332 -101.143054) (xy 85.257132 -101.143054)
		)
		(stroke
			(width 0)
			(type solid)
		)
		(fill yes)
		(layer "F.Cu")
		(net "M_L_ECC<2>")
	)
	(gr_poly
		(pts
			(xy 85.257132 -100.533454) (xy 85.206332 -100.533454) (xy 85.104732 -100.569014) (xy 85.104732 -100.675694)
			(xy 85.206332 -100.711254) (xy 85.257132 -100.711254)
		)
		(stroke
			(width 0)
			(type solid)
		)
		(fill yes)
		(layer "F.Cu")
		(net "M_L_ECC<2>")
	)
	(gr_poly
		(pts
			(xy 85.311488 -104.317546) (xy 85.26653 -104.272588) (xy 85.169756 -104.225852) (xy 85.094318 -104.30129)
			(xy 85.1408 -104.398318) (xy 85.185758 -104.443276)
		)
		(stroke
			(width 0)
			(type solid)
		)
		(fill yes)
		(layer "F.Cu")
		(net "M_L_ECC<3>")
	)
	(gr_poly
		(pts
			(xy 85.322156 -104.073198) (xy 85.275674 -103.97617) (xy 85.239606 -103.940356) (xy 85.113876 -104.066086)
			(xy 85.149944 -104.1019) (xy 85.246718 -104.148636)
		)
		(stroke
			(width 0)
			(type solid)
		)
		(fill yes)
		(layer "F.Cu")
		(net "M_L_ECC<2>")
	)
	(gr_poly
		(pts
			(xy 85.409532 -103.482394) (xy 85.409532 -103.375714) (xy 85.307932 -103.340154) (xy 85.257132 -103.340154)
			(xy 85.257132 -103.517954) (xy 85.307932 -103.517954)
		)
		(stroke
			(width 0)
			(type solid)
		)
		(fill yes)
		(layer "F.Cu")
		(net "M_L_ECC<2>")
	)
	(gr_poly
		(pts
			(xy 85.409532 -103.050594) (xy 85.409532 -102.943914) (xy 85.307932 -102.908354) (xy 85.257132 -102.908354)
			(xy 85.257132 -103.086154) (xy 85.307932 -103.086154)
		)
		(stroke
			(width 0)
			(type solid)
		)
		(fill yes)
		(layer "F.Cu")
		(net "M_L_ECC<2>")
	)
	(gr_poly
		(pts
			(xy 85.409532 -102.618794) (xy 85.409532 -102.512114) (xy 85.307932 -102.476554) (xy 85.257132 -102.476554)
			(xy 85.257132 -102.654354) (xy 85.307932 -102.654354)
		)
		(stroke
			(width 0)
			(type solid)
		)
		(fill yes)
		(layer "F.Cu")
		(net "M_L_ECC<2>")
	)
	(gr_poly
		(pts
			(xy 85.409532 -102.186994) (xy 85.409532 -102.080314) (xy 85.307932 -102.044754) (xy 85.257132 -102.044754)
			(xy 85.257132 -102.222554) (xy 85.307932 -102.222554)
		)
		(stroke
			(width 0)
			(type solid)
		)
		(fill yes)
		(layer "F.Cu")
		(net "M_L_ECC<2>")
	)
	(gr_poly
		(pts
			(xy 85.409532 -101.755194) (xy 85.409532 -101.648514) (xy 85.307932 -101.612954) (xy 85.257132 -101.612954)
			(xy 85.257132 -101.790754) (xy 85.307932 -101.790754)
		)
		(stroke
			(width 0)
			(type solid)
		)
		(fill yes)
		(layer "F.Cu")
		(net "M_L_ECC<2>")
	)
	(gr_poly
		(pts
			(xy 85.409532 -101.323394) (xy 85.409532 -101.216714) (xy 85.307932 -101.181154) (xy 85.257132 -101.181154)
			(xy 85.257132 -101.358954) (xy 85.307932 -101.358954)
		)
		(stroke
			(width 0)
			(type solid)
		)
		(fill yes)
		(layer "F.Cu")
		(net "M_L_ECC<2>")
	)
	(gr_poly
		(pts
			(xy 85.409532 -100.891594) (xy 85.409532 -100.784914) (xy 85.307932 -100.749354) (xy 85.257132 -100.749354)
			(xy 85.257132 -100.927154) (xy 85.307932 -100.927154)
		)
		(stroke
			(width 0)
			(type solid)
		)
		(fill yes)
		(layer "F.Cu")
		(net "M_L_ECC<2>")
	)
	(gr_poly
		(pts
			(xy 85.442298 -54.231286) (xy 85.428074 -54.03977) (xy 85.404452 -54.001924) (xy 85.065616 -54.212236)
			(xy 85.089238 -54.250082) (xy 85.254338 -54.347872)
		)
		(stroke
			(width 0)
			(type solid)
		)
		(fill yes)
		(layer "F.Cu")
		(net "M_H_ECC<3>")
	)
	(gr_poly
		(pts
			(xy 85.574632 -103.556054) (xy 85.511132 -103.556054) (xy 85.409532 -103.591614) (xy 85.409532 -103.698294)
			(xy 85.511132 -103.733854) (xy 85.574632 -103.733854)
		)
		(stroke
			(width 0)
			(type solid)
		)
		(fill yes)
		(layer "F.Cu")
		(net "M_L_ECC<3>")
	)
	(gr_poly
		(pts
			(xy 85.574632 -103.124254) (xy 85.511132 -103.124254) (xy 85.409532 -103.159814) (xy 85.409532 -103.266494)
			(xy 85.511132 -103.302054) (xy 85.574632 -103.302054)
		)
		(stroke
			(width 0)
			(type solid)
		)
		(fill yes)
		(layer "F.Cu")
		(net "M_L_ECC<3>")
	)
	(gr_poly
		(pts
			(xy 85.574632 -102.692454) (xy 85.511132 -102.692454) (xy 85.409532 -102.728014) (xy 85.409532 -102.834694)
			(xy 85.511132 -102.870254) (xy 85.574632 -102.870254)
		)
		(stroke
			(width 0)
			(type solid)
		)
		(fill yes)
		(layer "F.Cu")
		(net "M_L_ECC<3>")
	)
	(gr_poly
		(pts
			(xy 85.574632 -102.260654) (xy 85.511132 -102.260654) (xy 85.409532 -102.296214) (xy 85.409532 -102.402894)
			(xy 85.511132 -102.438454) (xy 85.574632 -102.438454)
		)
		(stroke
			(width 0)
			(type solid)
		)
		(fill yes)
		(layer "F.Cu")
		(net "M_L_ECC<3>")
	)
	(gr_poly
		(pts
			(xy 85.574632 -101.828854) (xy 85.511132 -101.828854) (xy 85.409532 -101.864414) (xy 85.409532 -101.971094)
			(xy 85.511132 -102.006654) (xy 85.574632 -102.006654)
		)
		(stroke
			(width 0)
			(type solid)
		)
		(fill yes)
		(layer "F.Cu")
		(net "M_L_ECC<3>")
	)
	(gr_poly
		(pts
			(xy 85.574632 -101.397054) (xy 85.511132 -101.397054) (xy 85.409532 -101.432614) (xy 85.409532 -101.539294)
			(xy 85.511132 -101.574854) (xy 85.574632 -101.574854)
		)
		(stroke
			(width 0)
			(type solid)
		)
		(fill yes)
		(layer "F.Cu")
		(net "M_L_ECC<3>")
	)
	(gr_poly
		(pts
			(xy 85.574632 -100.965254) (xy 85.511132 -100.965254) (xy 85.409532 -101.000814) (xy 85.409532 -101.107494)
			(xy 85.511132 -101.143054) (xy 85.574632 -101.143054)
		)
		(stroke
			(width 0)
			(type solid)
		)
		(fill yes)
		(layer "F.Cu")
		(net "M_L_ECC<3>")
	)
	(gr_poly
		(pts
			(xy 85.574632 -100.533454) (xy 85.511132 -100.533454) (xy 85.409532 -100.569014) (xy 85.409532 -100.675694)
			(xy 85.511132 -100.711254) (xy 85.574632 -100.711254)
		)
		(stroke
			(width 0)
			(type solid)
		)
		(fill yes)
		(layer "F.Cu")
		(net "M_L_ECC<3>")
	)
	(gr_poly
		(pts
			(xy 106.622342 -49.306988) (xy 106.571542 -49.306988) (xy 106.381042 -49.319688) (xy 106.381042 -49.421288)
			(xy 106.571542 -49.433988) (xy 106.622342 -49.433988)
		)
		(stroke
			(width 0)
			(type solid)
		)
		(fill yes)
		(layer "F.Cu")
		(net "M_G_DQ<36>")
	)
	(gr_poly
		(pts
			(xy 106.622342 -48.646588) (xy 106.571542 -48.646588) (xy 106.381042 -48.659288) (xy 106.381042 -48.760888)
			(xy 106.571542 -48.773588) (xy 106.622342 -48.773588)
		)
		(stroke
			(width 0)
			(type solid)
		)
		(fill yes)
		(layer "F.Cu")
		(net "M_G_DQ<36>")
	)
	(gr_poly
		(pts
			(xy 106.622342 -47.986188) (xy 106.571542 -47.986188) (xy 106.381042 -47.998888) (xy 106.381042 -48.100488)
			(xy 106.571542 -48.113188) (xy 106.622342 -48.113188)
		)
		(stroke
			(width 0)
			(type solid)
		)
		(fill yes)
		(layer "F.Cu")
		(net "M_G_DQ<36>")
	)
	(gr_poly
		(pts
			(xy 106.622342 -47.325788) (xy 106.571542 -47.325788) (xy 106.381042 -47.338488) (xy 106.381042 -47.440088)
			(xy 106.571542 -47.452788) (xy 106.622342 -47.452788)
		)
		(stroke
			(width 0)
			(type solid)
		)
		(fill yes)
		(layer "F.Cu")
		(net "M_G_DQ<36>")
	)
	(gr_poly
		(pts
			(xy 106.622342 -46.665388) (xy 106.571542 -46.665388) (xy 106.381042 -46.678088) (xy 106.381042 -46.779688)
			(xy 106.571542 -46.792388) (xy 106.622342 -46.792388)
		)
		(stroke
			(width 0)
			(type solid)
		)
		(fill yes)
		(layer "F.Cu")
		(net "M_G_DQ<36>")
	)
	(gr_poly
		(pts
			(xy 106.622342 -46.004988) (xy 106.571542 -46.004988) (xy 106.381042 -46.017688) (xy 106.381042 -46.119288)
			(xy 106.571542 -46.131988) (xy 106.622342 -46.131988)
		)
		(stroke
			(width 0)
			(type solid)
		)
		(fill yes)
		(layer "F.Cu")
		(net "M_G_DQ<36>")
	)
	(gr_poly
		(pts
			(xy 106.622342 -45.344588) (xy 106.571542 -45.344588) (xy 106.381042 -45.357288) (xy 106.381042 -45.458888)
			(xy 106.571542 -45.471588) (xy 106.622342 -45.471588)
		)
		(stroke
			(width 0)
			(type solid)
		)
		(fill yes)
		(layer "F.Cu")
		(net "M_G_DQ<36>")
	)
	(gr_poly
		(pts
			(xy 106.622342 -44.684188) (xy 106.571542 -44.684188) (xy 106.381042 -44.696888) (xy 106.381042 -44.798488)
			(xy 106.571542 -44.811188) (xy 106.622342 -44.811188)
		)
		(stroke
			(width 0)
			(type solid)
		)
		(fill yes)
		(layer "F.Cu")
		(net "M_G_DQ<36>")
	)
	(gr_poly
		(pts
			(xy 106.622342 -44.023788) (xy 106.571542 -44.023788) (xy 106.381042 -44.036488) (xy 106.381042 -44.138088)
			(xy 106.571542 -44.150788) (xy 106.622342 -44.150788)
		)
		(stroke
			(width 0)
			(type solid)
		)
		(fill yes)
		(layer "F.Cu")
		(net "M_G_DQ<36>")
	)
	(gr_poly
		(pts
			(xy 106.622342 -43.363388) (xy 106.571542 -43.363388) (xy 106.381042 -43.376088) (xy 106.381042 -43.477688)
			(xy 106.571542 -43.490388) (xy 106.622342 -43.490388)
		)
		(stroke
			(width 0)
			(type solid)
		)
		(fill yes)
		(layer "F.Cu")
		(net "M_G_DQ<36>")
	)
	(gr_poly
		(pts
			(xy 106.622342 -42.702988) (xy 106.571542 -42.702988) (xy 106.381042 -42.715688) (xy 106.381042 -42.817288)
			(xy 106.571542 -42.829988) (xy 106.622342 -42.829988)
		)
		(stroke
			(width 0)
			(type solid)
		)
		(fill yes)
		(layer "F.Cu")
		(net "M_G_DQ<36>")
	)
	(gr_poly
		(pts
			(xy 106.622342 -42.042588) (xy 106.571542 -42.042588) (xy 106.381042 -42.055288) (xy 106.381042 -42.156888)
			(xy 106.571542 -42.169588) (xy 106.622342 -42.169588)
		)
		(stroke
			(width 0)
			(type solid)
		)
		(fill yes)
		(layer "F.Cu")
		(net "M_G_DQ<36>")
	)
	(gr_poly
		(pts
			(xy 106.863642 -49.091088) (xy 106.863642 -48.989488) (xy 106.673142 -48.976788) (xy 106.622342 -48.976788)
			(xy 106.622342 -49.103788) (xy 106.673142 -49.103788)
		)
		(stroke
			(width 0)
			(type solid)
		)
		(fill yes)
		(layer "F.Cu")
		(net "M_G_DQ<36>")
	)
	(gr_poly
		(pts
			(xy 106.863642 -48.430688) (xy 106.863642 -48.329088) (xy 106.673142 -48.316388) (xy 106.622342 -48.316388)
			(xy 106.622342 -48.443388) (xy 106.673142 -48.443388)
		)
		(stroke
			(width 0)
			(type solid)
		)
		(fill yes)
		(layer "F.Cu")
		(net "M_G_DQ<36>")
	)
	(gr_poly
		(pts
			(xy 106.863642 -47.770288) (xy 106.863642 -47.668688) (xy 106.673142 -47.655988) (xy 106.622342 -47.655988)
			(xy 106.622342 -47.782988) (xy 106.673142 -47.782988)
		)
		(stroke
			(width 0)
			(type solid)
		)
		(fill yes)
		(layer "F.Cu")
		(net "M_G_DQ<36>")
	)
	(gr_poly
		(pts
			(xy 106.863642 -47.109888) (xy 106.863642 -47.008288) (xy 106.673142 -46.995588) (xy 106.622342 -46.995588)
			(xy 106.622342 -47.122588) (xy 106.673142 -47.122588)
		)
		(stroke
			(width 0)
			(type solid)
		)
		(fill yes)
		(layer "F.Cu")
		(net "M_G_DQ<36>")
	)
	(gr_poly
		(pts
			(xy 106.863642 -46.449488) (xy 106.863642 -46.347888) (xy 106.673142 -46.335188) (xy 106.622342 -46.335188)
			(xy 106.622342 -46.462188) (xy 106.673142 -46.462188)
		)
		(stroke
			(width 0)
			(type solid)
		)
		(fill yes)
		(layer "F.Cu")
		(net "M_G_DQ<36>")
	)
	(gr_poly
		(pts
			(xy 106.863642 -45.789088) (xy 106.863642 -45.687488) (xy 106.673142 -45.674788) (xy 106.622342 -45.674788)
			(xy 106.622342 -45.801788) (xy 106.673142 -45.801788)
		)
		(stroke
			(width 0)
			(type solid)
		)
		(fill yes)
		(layer "F.Cu")
		(net "M_G_DQ<36>")
	)
	(gr_poly
		(pts
			(xy 106.863642 -45.128688) (xy 106.863642 -45.027088) (xy 106.673142 -45.014388) (xy 106.622342 -45.014388)
			(xy 106.622342 -45.141388) (xy 106.673142 -45.141388)
		)
		(stroke
			(width 0)
			(type solid)
		)
		(fill yes)
		(layer "F.Cu")
		(net "M_G_DQ<36>")
	)
	(gr_poly
		(pts
			(xy 106.863642 -44.468288) (xy 106.863642 -44.366688) (xy 106.673142 -44.353988) (xy 106.622342 -44.353988)
			(xy 106.622342 -44.480988) (xy 106.673142 -44.480988)
		)
		(stroke
			(width 0)
			(type solid)
		)
		(fill yes)
		(layer "F.Cu")
		(net "M_G_DQ<36>")
	)
	(gr_poly
		(pts
			(xy 106.863642 -43.807888) (xy 106.863642 -43.706288) (xy 106.673142 -43.693588) (xy 106.622342 -43.693588)
			(xy 106.622342 -43.820588) (xy 106.673142 -43.820588)
		)
		(stroke
			(width 0)
			(type solid)
		)
		(fill yes)
		(layer "F.Cu")
		(net "M_G_DQ<36>")
	)
	(gr_poly
		(pts
			(xy 106.863642 -43.147488) (xy 106.863642 -43.045888) (xy 106.673142 -43.033188) (xy 106.622342 -43.033188)
			(xy 106.622342 -43.160188) (xy 106.673142 -43.160188)
		)
		(stroke
			(width 0)
			(type solid)
		)
		(fill yes)
		(layer "F.Cu")
		(net "M_G_DQ<36>")
	)
	(gr_poly
		(pts
			(xy 106.863642 -42.487088) (xy 106.863642 -42.385488) (xy 106.673142 -42.372788) (xy 106.622342 -42.372788)
			(xy 106.622342 -42.499788) (xy 106.673142 -42.499788)
		)
		(stroke
			(width 0)
			(type solid)
		)
		(fill yes)
		(layer "F.Cu")
		(net "M_G_DQ<36>")
	)
	(gr_poly
		(pts
			(xy 107.001564 -52.065936) (xy 107.001564 -51.844956) (xy 106.831384 -51.756056) (xy 106.786934 -51.756056)
			(xy 106.786934 -52.154836) (xy 106.831384 -52.154836)
		)
		(stroke
			(width 0)
			(type solid)
		)
		(fill yes)
		(layer "F.Cu")
		(net "M_G_DQ<37>")
	)
	(gr_poly
		(pts
			(xy 107.016042 -49.306988) (xy 106.965242 -49.306988) (xy 106.774742 -49.319688) (xy 106.774742 -49.421288)
			(xy 106.965242 -49.433988) (xy 107.016042 -49.433988)
		)
		(stroke
			(width 0)
			(type solid)
		)
		(fill yes)
		(layer "F.Cu")
		(net "M_G_DQ<37>")
	)
	(gr_poly
		(pts
			(xy 107.016042 -48.646588) (xy 106.965242 -48.646588) (xy 106.774742 -48.659288) (xy 106.774742 -48.760888)
			(xy 106.965242 -48.773588) (xy 107.016042 -48.773588)
		)
		(stroke
			(width 0)
			(type solid)
		)
		(fill yes)
		(layer "F.Cu")
		(net "M_G_DQ<37>")
	)
	(gr_poly
		(pts
			(xy 107.016042 -47.986188) (xy 106.965242 -47.986188) (xy 106.774742 -47.998888) (xy 106.774742 -48.100488)
			(xy 106.965242 -48.113188) (xy 107.016042 -48.113188)
		)
		(stroke
			(width 0)
			(type solid)
		)
		(fill yes)
		(layer "F.Cu")
		(net "M_G_DQ<37>")
	)
	(gr_poly
		(pts
			(xy 107.016042 -47.325788) (xy 106.965242 -47.325788) (xy 106.774742 -47.338488) (xy 106.774742 -47.440088)
			(xy 106.965242 -47.452788) (xy 107.016042 -47.452788)
		)
		(stroke
			(width 0)
			(type solid)
		)
		(fill yes)
		(layer "F.Cu")
		(net "M_G_DQ<37>")
	)
	(gr_poly
		(pts
			(xy 107.016042 -46.665388) (xy 106.965242 -46.665388) (xy 106.774742 -46.678088) (xy 106.774742 -46.779688)
			(xy 106.965242 -46.792388) (xy 107.016042 -46.792388)
		)
		(stroke
			(width 0)
			(type solid)
		)
		(fill yes)
		(layer "F.Cu")
		(net "M_G_DQ<37>")
	)
	(gr_poly
		(pts
			(xy 107.016042 -46.004988) (xy 106.965242 -46.004988) (xy 106.774742 -46.017688) (xy 106.774742 -46.119288)
			(xy 106.965242 -46.131988) (xy 107.016042 -46.131988)
		)
		(stroke
			(width 0)
			(type solid)
		)
		(fill yes)
		(layer "F.Cu")
		(net "M_G_DQ<37>")
	)
	(gr_poly
		(pts
			(xy 107.016042 -45.344588) (xy 106.965242 -45.344588) (xy 106.774742 -45.357288) (xy 106.774742 -45.458888)
			(xy 106.965242 -45.471588) (xy 107.016042 -45.471588)
		)
		(stroke
			(width 0)
			(type solid)
		)
		(fill yes)
		(layer "F.Cu")
		(net "M_G_DQ<37>")
	)
	(gr_poly
		(pts
			(xy 107.016042 -44.684188) (xy 106.965242 -44.684188) (xy 106.774742 -44.696888) (xy 106.774742 -44.798488)
			(xy 106.965242 -44.811188) (xy 107.016042 -44.811188)
		)
		(stroke
			(width 0)
			(type solid)
		)
		(fill yes)
		(layer "F.Cu")
		(net "M_G_DQ<37>")
	)
	(gr_poly
		(pts
			(xy 107.016042 -44.023788) (xy 106.965242 -44.023788) (xy 106.774742 -44.036488) (xy 106.774742 -44.138088)
			(xy 106.965242 -44.150788) (xy 107.016042 -44.150788)
		)
		(stroke
			(width 0)
			(type solid)
		)
		(fill yes)
		(layer "F.Cu")
		(net "M_G_DQ<37>")
	)
	(gr_poly
		(pts
			(xy 107.016042 -43.363388) (xy 106.965242 -43.363388) (xy 106.774742 -43.376088) (xy 106.774742 -43.477688)
			(xy 106.965242 -43.490388) (xy 107.016042 -43.490388)
		)
		(stroke
			(width 0)
			(type solid)
		)
		(fill yes)
		(layer "F.Cu")
		(net "M_G_DQ<37>")
	)
	(gr_poly
		(pts
			(xy 107.016042 -42.702988) (xy 106.965242 -42.702988) (xy 106.774742 -42.715688) (xy 106.774742 -42.817288)
			(xy 106.965242 -42.829988) (xy 107.016042 -42.829988)
		)
		(stroke
			(width 0)
			(type solid)
		)
		(fill yes)
		(layer "F.Cu")
		(net "M_G_DQ<37>")
	)
	(gr_poly
		(pts
			(xy 107.016042 -42.042588) (xy 106.965242 -42.042588) (xy 106.774742 -42.055288) (xy 106.774742 -42.156888)
			(xy 106.965242 -42.169588) (xy 107.016042 -42.169588)
		)
		(stroke
			(width 0)
			(type solid)
		)
		(fill yes)
		(layer "F.Cu")
		(net "M_G_DQ<37>")
	)
	(gr_poly
		(pts
			(xy 107.257342 -49.091088) (xy 107.257342 -48.989488) (xy 107.066842 -48.976788) (xy 107.016042 -48.976788)
			(xy 107.016042 -49.103788) (xy 107.066842 -49.103788)
		)
		(stroke
			(width 0)
			(type solid)
		)
		(fill yes)
		(layer "F.Cu")
		(net "M_G_DQ<37>")
	)
	(gr_poly
		(pts
			(xy 107.257342 -48.430688) (xy 107.257342 -48.329088) (xy 107.066842 -48.316388) (xy 107.016042 -48.316388)
			(xy 107.016042 -48.443388) (xy 107.066842 -48.443388)
		)
		(stroke
			(width 0)
			(type solid)
		)
		(fill yes)
		(layer "F.Cu")
		(net "M_G_DQ<37>")
	)
	(gr_poly
		(pts
			(xy 107.257342 -47.770288) (xy 107.257342 -47.668688) (xy 107.066842 -47.655988) (xy 107.016042 -47.655988)
			(xy 107.016042 -47.782988) (xy 107.066842 -47.782988)
		)
		(stroke
			(width 0)
			(type solid)
		)
		(fill yes)
		(layer "F.Cu")
		(net "M_G_DQ<37>")
	)
	(gr_poly
		(pts
			(xy 107.257342 -47.109888) (xy 107.257342 -47.008288) (xy 107.066842 -46.995588) (xy 107.016042 -46.995588)
			(xy 107.016042 -47.122588) (xy 107.066842 -47.122588)
		)
		(stroke
			(width 0)
			(type solid)
		)
		(fill yes)
		(layer "F.Cu")
		(net "M_G_DQ<37>")
	)
	(gr_poly
		(pts
			(xy 107.257342 -46.449488) (xy 107.257342 -46.347888) (xy 107.066842 -46.335188) (xy 107.016042 -46.335188)
			(xy 107.016042 -46.462188) (xy 107.066842 -46.462188)
		)
		(stroke
			(width 0)
			(type solid)
		)
		(fill yes)
		(layer "F.Cu")
		(net "M_G_DQ<37>")
	)
	(gr_poly
		(pts
			(xy 107.257342 -45.789088) (xy 107.257342 -45.687488) (xy 107.066842 -45.674788) (xy 107.016042 -45.674788)
			(xy 107.016042 -45.801788) (xy 107.066842 -45.801788)
		)
		(stroke
			(width 0)
			(type solid)
		)
		(fill yes)
		(layer "F.Cu")
		(net "M_G_DQ<37>")
	)
	(gr_poly
		(pts
			(xy 107.257342 -45.128688) (xy 107.257342 -45.027088) (xy 107.066842 -45.014388) (xy 107.016042 -45.014388)
			(xy 107.016042 -45.141388) (xy 107.066842 -45.141388)
		)
		(stroke
			(width 0)
			(type solid)
		)
		(fill yes)
		(layer "F.Cu")
		(net "M_G_DQ<37>")
	)
	(gr_poly
		(pts
			(xy 107.257342 -44.468288) (xy 107.257342 -44.366688) (xy 107.066842 -44.353988) (xy 107.016042 -44.353988)
			(xy 107.016042 -44.480988) (xy 107.066842 -44.480988)
		)
		(stroke
			(width 0)
			(type solid)
		)
		(fill yes)
		(layer "F.Cu")
		(net "M_G_DQ<37>")
	)
	(gr_poly
		(pts
			(xy 107.257342 -43.807888) (xy 107.257342 -43.706288) (xy 107.066842 -43.693588) (xy 107.016042 -43.693588)
			(xy 107.016042 -43.820588) (xy 107.066842 -43.820588)
		)
		(stroke
			(width 0)
			(type solid)
		)
		(fill yes)
		(layer "F.Cu")
		(net "M_G_DQ<37>")
	)
	(gr_poly
		(pts
			(xy 107.257342 -43.147488) (xy 107.257342 -43.045888) (xy 107.066842 -43.033188) (xy 107.016042 -43.033188)
			(xy 107.016042 -43.160188) (xy 107.066842 -43.160188)
		)
		(stroke
			(width 0)
			(type solid)
		)
		(fill yes)
		(layer "F.Cu")
		(net "M_G_DQ<37>")
	)
	(gr_poly
		(pts
			(xy 107.257342 -42.487088) (xy 107.257342 -42.385488) (xy 107.066842 -42.372788) (xy 107.016042 -42.372788)
			(xy 107.016042 -42.499788) (xy 107.066842 -42.499788)
		)
		(stroke
			(width 0)
			(type solid)
		)
		(fill yes)
		(layer "F.Cu")
		(net "M_G_DQ<37>")
	)
	(gr_poly
		(pts
			(xy 107.397042 -111.565436) (xy 107.346242 -111.565436) (xy 107.155742 -111.578136) (xy 107.155742 -111.679736)
			(xy 107.346242 -111.692436) (xy 107.397042 -111.692436)
		)
		(stroke
			(width 0)
			(type solid)
		)
		(fill yes)
		(layer "F.Cu")
		(net "M_K_DQ<36>")
	)
	(gr_poly
		(pts
			(xy 107.397042 -110.905036) (xy 107.346242 -110.905036) (xy 107.155742 -110.917736) (xy 107.155742 -111.019336)
			(xy 107.346242 -111.032036) (xy 107.397042 -111.032036)
		)
		(stroke
			(width 0)
			(type solid)
		)
		(fill yes)
		(layer "F.Cu")
		(net "M_K_DQ<36>")
	)
	(gr_poly
		(pts
			(xy 107.397042 -110.244636) (xy 107.346242 -110.244636) (xy 107.155742 -110.257336) (xy 107.155742 -110.358936)
			(xy 107.346242 -110.371636) (xy 107.397042 -110.371636)
		)
		(stroke
			(width 0)
			(type solid)
		)
		(fill yes)
		(layer "F.Cu")
		(net "M_K_DQ<36>")
	)
	(gr_poly
		(pts
			(xy 107.397042 -109.584236) (xy 107.346242 -109.584236) (xy 107.155742 -109.596936) (xy 107.155742 -109.698536)
			(xy 107.346242 -109.711236) (xy 107.397042 -109.711236)
		)
		(stroke
			(width 0)
			(type solid)
		)
		(fill yes)
		(layer "F.Cu")
		(net "M_K_DQ<36>")
	)
	(gr_poly
		(pts
			(xy 107.397042 -108.923836) (xy 107.346242 -108.923836) (xy 107.155742 -108.936536) (xy 107.155742 -109.038136)
			(xy 107.346242 -109.050836) (xy 107.397042 -109.050836)
		)
		(stroke
			(width 0)
			(type solid)
		)
		(fill yes)
		(layer "F.Cu")
		(net "M_K_DQ<36>")
	)
	(gr_poly
		(pts
			(xy 107.397042 -108.263436) (xy 107.346242 -108.263436) (xy 107.155742 -108.276136) (xy 107.155742 -108.377736)
			(xy 107.346242 -108.390436) (xy 107.397042 -108.390436)
		)
		(stroke
			(width 0)
			(type solid)
		)
		(fill yes)
		(layer "F.Cu")
		(net "M_K_DQ<36>")
	)
	(gr_poly
		(pts
			(xy 107.397042 -107.603036) (xy 107.346242 -107.603036) (xy 107.155742 -107.615736) (xy 107.155742 -107.717336)
			(xy 107.346242 -107.730036) (xy 107.397042 -107.730036)
		)
		(stroke
			(width 0)
			(type solid)
		)
		(fill yes)
		(layer "F.Cu")
		(net "M_K_DQ<36>")
	)
	(gr_poly
		(pts
			(xy 107.397042 -106.942636) (xy 107.346242 -106.942636) (xy 107.155742 -106.955336) (xy 107.155742 -107.056936)
			(xy 107.346242 -107.069636) (xy 107.397042 -107.069636)
		)
		(stroke
			(width 0)
			(type solid)
		)
		(fill yes)
		(layer "F.Cu")
		(net "M_K_DQ<36>")
	)
	(gr_poly
		(pts
			(xy 107.409742 -49.306988) (xy 107.358942 -49.306988) (xy 107.168442 -49.319688) (xy 107.168442 -49.421288)
			(xy 107.358942 -49.433988) (xy 107.409742 -49.433988)
		)
		(stroke
			(width 0)
			(type solid)
		)
		(fill yes)
		(layer "F.Cu")
		(net "M_G_DQ<32>")
	)
	(gr_poly
		(pts
			(xy 107.409742 -48.646588) (xy 107.358942 -48.646588) (xy 107.168442 -48.659288) (xy 107.168442 -48.760888)
			(xy 107.358942 -48.773588) (xy 107.409742 -48.773588)
		)
		(stroke
			(width 0)
			(type solid)
		)
		(fill yes)
		(layer "F.Cu")
		(net "M_G_DQ<32>")
	)
	(gr_poly
		(pts
			(xy 107.409742 -47.986188) (xy 107.358942 -47.986188) (xy 107.168442 -47.998888) (xy 107.168442 -48.100488)
			(xy 107.358942 -48.113188) (xy 107.409742 -48.113188)
		)
		(stroke
			(width 0)
			(type solid)
		)
		(fill yes)
		(layer "F.Cu")
		(net "M_G_DQ<32>")
	)
	(gr_poly
		(pts
			(xy 107.409742 -47.325788) (xy 107.358942 -47.325788) (xy 107.168442 -47.338488) (xy 107.168442 -47.440088)
			(xy 107.358942 -47.452788) (xy 107.409742 -47.452788)
		)
		(stroke
			(width 0)
			(type solid)
		)
		(fill yes)
		(layer "F.Cu")
		(net "M_G_DQ<32>")
	)
	(gr_poly
		(pts
			(xy 107.409742 -46.665388) (xy 107.358942 -46.665388) (xy 107.168442 -46.678088) (xy 107.168442 -46.779688)
			(xy 107.358942 -46.792388) (xy 107.409742 -46.792388)
		)
		(stroke
			(width 0)
			(type solid)
		)
		(fill yes)
		(layer "F.Cu")
		(net "M_G_DQ<32>")
	)
	(gr_poly
		(pts
			(xy 107.409742 -46.004988) (xy 107.358942 -46.004988) (xy 107.168442 -46.017688) (xy 107.168442 -46.119288)
			(xy 107.358942 -46.131988) (xy 107.409742 -46.131988)
		)
		(stroke
			(width 0)
			(type solid)
		)
		(fill yes)
		(layer "F.Cu")
		(net "M_G_DQ<32>")
	)
	(gr_poly
		(pts
			(xy 107.409742 -45.344588) (xy 107.358942 -45.344588) (xy 107.168442 -45.357288) (xy 107.168442 -45.458888)
			(xy 107.358942 -45.471588) (xy 107.409742 -45.471588)
		)
		(stroke
			(width 0)
			(type solid)
		)
		(fill yes)
		(layer "F.Cu")
		(net "M_G_DQ<32>")
	)
	(gr_poly
		(pts
			(xy 107.409742 -44.684188) (xy 107.358942 -44.684188) (xy 107.168442 -44.696888) (xy 107.168442 -44.798488)
			(xy 107.358942 -44.811188) (xy 107.409742 -44.811188)
		)
		(stroke
			(width 0)
			(type solid)
		)
		(fill yes)
		(layer "F.Cu")
		(net "M_G_DQ<32>")
	)
	(gr_poly
		(pts
			(xy 107.409742 -44.023788) (xy 107.358942 -44.023788) (xy 107.168442 -44.036488) (xy 107.168442 -44.138088)
			(xy 107.358942 -44.150788) (xy 107.409742 -44.150788)
		)
		(stroke
			(width 0)
			(type solid)
		)
		(fill yes)
		(layer "F.Cu")
		(net "M_G_DQ<32>")
	)
	(gr_poly
		(pts
			(xy 107.409742 -43.363388) (xy 107.358942 -43.363388) (xy 107.168442 -43.376088) (xy 107.168442 -43.477688)
			(xy 107.358942 -43.490388) (xy 107.409742 -43.490388)
		)
		(stroke
			(width 0)
			(type solid)
		)
		(fill yes)
		(layer "F.Cu")
		(net "M_G_DQ<32>")
	)
	(gr_poly
		(pts
			(xy 107.409742 -42.702988) (xy 107.358942 -42.702988) (xy 107.168442 -42.715688) (xy 107.168442 -42.817288)
			(xy 107.358942 -42.829988) (xy 107.409742 -42.829988)
		)
		(stroke
			(width 0)
			(type solid)
		)
		(fill yes)
		(layer "F.Cu")
		(net "M_G_DQ<32>")
	)
	(gr_poly
		(pts
			(xy 107.409742 -42.042588) (xy 107.358942 -42.042588) (xy 107.168442 -42.055288) (xy 107.168442 -42.156888)
			(xy 107.358942 -42.169588) (xy 107.409742 -42.169588)
		)
		(stroke
			(width 0)
			(type solid)
		)
		(fill yes)
		(layer "F.Cu")
		(net "M_G_DQ<32>")
	)
	(gr_poly
		(pts
			(xy 107.498642 -105.205784) (xy 107.454192 -105.205784) (xy 107.261152 -105.294684) (xy 107.261152 -105.523284)
			(xy 107.454192 -105.612184) (xy 107.498642 -105.612184)
		)
		(stroke
			(width 0)
			(type solid)
		)
		(fill yes)
		(layer "F.Cu")
		(net "M_K_DQ<36>")
	)
	(gr_poly
		(pts
			(xy 107.498642 -104.215184) (xy 107.454192 -104.215184) (xy 107.261152 -104.304084) (xy 107.261152 -104.532684)
			(xy 107.454192 -104.621584) (xy 107.498642 -104.621584)
		)
		(stroke
			(width 0)
			(type solid)
		)
		(fill yes)
		(layer "F.Cu")
		(net "M_K_DQ<36>")
	)
	(gr_poly
		(pts
			(xy 107.54614 -52.982622) (xy 107.548172 -52.790852) (xy 107.353608 -52.686204) (xy 107.194858 -52.794154)
			(xy 107.173776 -52.833524) (xy 107.525058 -53.021992)
		)
		(stroke
			(width 0)
			(type solid)
		)
		(fill yes)
		(layer "F.Cu")
		(net "M_G_DQ<37>")
	)
	(gr_poly
		(pts
			(xy 107.638342 -111.349536) (xy 107.638342 -111.247936) (xy 107.447842 -111.235236) (xy 107.397042 -111.235236)
			(xy 107.397042 -111.362236) (xy 107.447842 -111.362236)
		)
		(stroke
			(width 0)
			(type solid)
		)
		(fill yes)
		(layer "F.Cu")
		(net "M_K_DQ<36>")
	)
	(gr_poly
		(pts
			(xy 107.638342 -110.689136) (xy 107.638342 -110.587536) (xy 107.447842 -110.574836) (xy 107.397042 -110.574836)
			(xy 107.397042 -110.701836) (xy 107.447842 -110.701836)
		)
		(stroke
			(width 0)
			(type solid)
		)
		(fill yes)
		(layer "F.Cu")
		(net "M_K_DQ<36>")
	)
	(gr_poly
		(pts
			(xy 107.638342 -110.028736) (xy 107.638342 -109.927136) (xy 107.447842 -109.914436) (xy 107.397042 -109.914436)
			(xy 107.397042 -110.041436) (xy 107.447842 -110.041436)
		)
		(stroke
			(width 0)
			(type solid)
		)
		(fill yes)
		(layer "F.Cu")
		(net "M_K_DQ<36>")
	)
	(gr_poly
		(pts
			(xy 107.638342 -109.368336) (xy 107.638342 -109.266736) (xy 107.447842 -109.254036) (xy 107.397042 -109.254036)
			(xy 107.397042 -109.381036) (xy 107.447842 -109.381036)
		)
		(stroke
			(width 0)
			(type solid)
		)
		(fill yes)
		(layer "F.Cu")
		(net "M_K_DQ<36>")
	)
	(gr_poly
		(pts
			(xy 107.638342 -108.707936) (xy 107.638342 -108.606336) (xy 107.447842 -108.593636) (xy 107.397042 -108.593636)
			(xy 107.397042 -108.720636) (xy 107.447842 -108.720636)
		)
		(stroke
			(width 0)
			(type solid)
		)
		(fill yes)
		(layer "F.Cu")
		(net "M_K_DQ<36>")
	)
	(gr_poly
		(pts
			(xy 107.638342 -108.047536) (xy 107.638342 -107.945936) (xy 107.447842 -107.933236) (xy 107.397042 -107.933236)
			(xy 107.397042 -108.060236) (xy 107.447842 -108.060236)
		)
		(stroke
			(width 0)
			(type solid)
		)
		(fill yes)
		(layer "F.Cu")
		(net "M_K_DQ<36>")
	)
	(gr_poly
		(pts
			(xy 107.638342 -107.387136) (xy 107.638342 -107.285536) (xy 107.447842 -107.272836) (xy 107.397042 -107.272836)
			(xy 107.397042 -107.399836) (xy 107.447842 -107.399836)
		)
		(stroke
			(width 0)
			(type solid)
		)
		(fill yes)
		(layer "F.Cu")
		(net "M_K_DQ<36>")
	)
	(gr_poly
		(pts
			(xy 107.651042 -49.091088) (xy 107.651042 -48.989488) (xy 107.460542 -48.976788) (xy 107.409742 -48.976788)
			(xy 107.409742 -49.103788) (xy 107.460542 -49.103788)
		)
		(stroke
			(width 0)
			(type solid)
		)
		(fill yes)
		(layer "F.Cu")
		(net "M_G_DQ<32>")
	)
	(gr_poly
		(pts
			(xy 107.651042 -48.430688) (xy 107.651042 -48.329088) (xy 107.460542 -48.316388) (xy 107.409742 -48.316388)
			(xy 107.409742 -48.443388) (xy 107.460542 -48.443388)
		)
		(stroke
			(width 0)
			(type solid)
		)
		(fill yes)
		(layer "F.Cu")
		(net "M_G_DQ<32>")
	)
	(gr_poly
		(pts
			(xy 107.651042 -47.770288) (xy 107.651042 -47.668688) (xy 107.460542 -47.655988) (xy 107.409742 -47.655988)
			(xy 107.409742 -47.782988) (xy 107.460542 -47.782988)
		)
		(stroke
			(width 0)
			(type solid)
		)
		(fill yes)
		(layer "F.Cu")
		(net "M_G_DQ<32>")
	)
	(gr_poly
		(pts
			(xy 107.651042 -47.109888) (xy 107.651042 -47.008288) (xy 107.460542 -46.995588) (xy 107.409742 -46.995588)
			(xy 107.409742 -47.122588) (xy 107.460542 -47.122588)
		)
		(stroke
			(width 0)
			(type solid)
		)
		(fill yes)
		(layer "F.Cu")
		(net "M_G_DQ<32>")
	)
	(gr_poly
		(pts
			(xy 107.651042 -46.449488) (xy 107.651042 -46.347888) (xy 107.460542 -46.335188) (xy 107.409742 -46.335188)
			(xy 107.409742 -46.462188) (xy 107.460542 -46.462188)
		)
		(stroke
			(width 0)
			(type solid)
		)
		(fill yes)
		(layer "F.Cu")
		(net "M_G_DQ<32>")
	)
	(gr_poly
		(pts
			(xy 107.651042 -45.789088) (xy 107.651042 -45.687488) (xy 107.460542 -45.674788) (xy 107.409742 -45.674788)
			(xy 107.409742 -45.801788) (xy 107.460542 -45.801788)
		)
		(stroke
			(width 0)
			(type solid)
		)
		(fill yes)
		(layer "F.Cu")
		(net "M_G_DQ<32>")
	)
	(gr_poly
		(pts
			(xy 107.651042 -45.128688) (xy 107.651042 -45.027088) (xy 107.460542 -45.014388) (xy 107.409742 -45.014388)
			(xy 107.409742 -45.141388) (xy 107.460542 -45.141388)
		)
		(stroke
			(width 0)
			(type solid)
		)
		(fill yes)
		(layer "F.Cu")
		(net "M_G_DQ<32>")
	)
	(gr_poly
		(pts
			(xy 107.651042 -44.468288) (xy 107.651042 -44.366688) (xy 107.460542 -44.353988) (xy 107.409742 -44.353988)
			(xy 107.409742 -44.480988) (xy 107.460542 -44.480988)
		)
		(stroke
			(width 0)
			(type solid)
		)
		(fill yes)
		(layer "F.Cu")
		(net "M_G_DQ<32>")
	)
	(gr_poly
		(pts
			(xy 107.651042 -43.807888) (xy 107.651042 -43.706288) (xy 107.460542 -43.693588) (xy 107.409742 -43.693588)
			(xy 107.409742 -43.820588) (xy 107.460542 -43.820588)
		)
		(stroke
			(width 0)
			(type solid)
		)
		(fill yes)
		(layer "F.Cu")
		(net "M_G_DQ<32>")
	)
	(gr_poly
		(pts
			(xy 107.651042 -43.147488) (xy 107.651042 -43.045888) (xy 107.460542 -43.033188) (xy 107.409742 -43.033188)
			(xy 107.409742 -43.160188) (xy 107.460542 -43.160188)
		)
		(stroke
			(width 0)
			(type solid)
		)
		(fill yes)
		(layer "F.Cu")
		(net "M_G_DQ<32>")
	)
	(gr_poly
		(pts
			(xy 107.651042 -42.487088) (xy 107.651042 -42.385488) (xy 107.460542 -42.372788) (xy 107.409742 -42.372788)
			(xy 107.409742 -42.499788) (xy 107.460542 -42.499788)
		)
		(stroke
			(width 0)
			(type solid)
		)
		(fill yes)
		(layer "F.Cu")
		(net "M_G_DQ<32>")
	)
	(gr_poly
		(pts
			(xy 107.790742 -111.565436) (xy 107.739942 -111.565436) (xy 107.549442 -111.578136) (xy 107.549442 -111.679736)
			(xy 107.739942 -111.692436) (xy 107.790742 -111.692436)
		)
		(stroke
			(width 0)
			(type solid)
		)
		(fill yes)
		(layer "F.Cu")
		(net "M_K_DQ<37>")
	)
	(gr_poly
		(pts
			(xy 107.790742 -110.905036) (xy 107.739942 -110.905036) (xy 107.549442 -110.917736) (xy 107.549442 -111.019336)
			(xy 107.739942 -111.032036) (xy 107.790742 -111.032036)
		)
		(stroke
			(width 0)
			(type solid)
		)
		(fill yes)
		(layer "F.Cu")
		(net "M_K_DQ<37>")
	)
	(gr_poly
		(pts
			(xy 107.790742 -110.244636) (xy 107.739942 -110.244636) (xy 107.549442 -110.257336) (xy 107.549442 -110.358936)
			(xy 107.739942 -110.371636) (xy 107.790742 -110.371636)
		)
		(stroke
			(width 0)
			(type solid)
		)
		(fill yes)
		(layer "F.Cu")
		(net "M_K_DQ<37>")
	)
	(gr_poly
		(pts
			(xy 107.790742 -109.584236) (xy 107.739942 -109.584236) (xy 107.549442 -109.596936) (xy 107.549442 -109.698536)
			(xy 107.739942 -109.711236) (xy 107.790742 -109.711236)
		)
		(stroke
			(width 0)
			(type solid)
		)
		(fill yes)
		(layer "F.Cu")
		(net "M_K_DQ<37>")
	)
	(gr_poly
		(pts
			(xy 107.790742 -108.923836) (xy 107.739942 -108.923836) (xy 107.549442 -108.936536) (xy 107.549442 -109.038136)
			(xy 107.739942 -109.050836) (xy 107.790742 -109.050836)
		)
		(stroke
			(width 0)
			(type solid)
		)
		(fill yes)
		(layer "F.Cu")
		(net "M_K_DQ<37>")
	)
	(gr_poly
		(pts
			(xy 107.790742 -108.263436) (xy 107.739942 -108.263436) (xy 107.549442 -108.276136) (xy 107.549442 -108.377736)
			(xy 107.739942 -108.390436) (xy 107.790742 -108.390436)
		)
		(stroke
			(width 0)
			(type solid)
		)
		(fill yes)
		(layer "F.Cu")
		(net "M_K_DQ<37>")
	)
	(gr_poly
		(pts
			(xy 107.790742 -107.603036) (xy 107.739942 -107.603036) (xy 107.549442 -107.615736) (xy 107.549442 -107.717336)
			(xy 107.739942 -107.730036) (xy 107.790742 -107.730036)
		)
		(stroke
			(width 0)
			(type solid)
		)
		(fill yes)
		(layer "F.Cu")
		(net "M_K_DQ<37>")
	)
	(gr_poly
		(pts
			(xy 107.790742 -106.942636) (xy 107.739942 -106.942636) (xy 107.549442 -106.955336) (xy 107.549442 -107.056936)
			(xy 107.739942 -107.069636) (xy 107.790742 -107.069636)
		)
		(stroke
			(width 0)
			(type solid)
		)
		(fill yes)
		(layer "F.Cu")
		(net "M_K_DQ<37>")
	)
	(gr_poly
		(pts
			(xy 107.803442 -49.306988) (xy 107.752642 -49.306988) (xy 107.562142 -49.319688) (xy 107.562142 -49.421288)
			(xy 107.752642 -49.433988) (xy 107.803442 -49.433988)
		)
		(stroke
			(width 0)
			(type solid)
		)
		(fill yes)
		(layer "F.Cu")
		(net "M_G_DQ<33>")
	)
	(gr_poly
		(pts
			(xy 107.803442 -48.646588) (xy 107.752642 -48.646588) (xy 107.562142 -48.659288) (xy 107.562142 -48.760888)
			(xy 107.752642 -48.773588) (xy 107.803442 -48.773588)
		)
		(stroke
			(width 0)
			(type solid)
		)
		(fill yes)
		(layer "F.Cu")
		(net "M_G_DQ<33>")
	)
	(gr_poly
		(pts
			(xy 107.803442 -47.986188) (xy 107.752642 -47.986188) (xy 107.562142 -47.998888) (xy 107.562142 -48.100488)
			(xy 107.752642 -48.113188) (xy 107.803442 -48.113188)
		)
		(stroke
			(width 0)
			(type solid)
		)
		(fill yes)
		(layer "F.Cu")
		(net "M_G_DQ<33>")
	)
	(gr_poly
		(pts
			(xy 107.803442 -47.325788) (xy 107.752642 -47.325788) (xy 107.562142 -47.338488) (xy 107.562142 -47.440088)
			(xy 107.752642 -47.452788) (xy 107.803442 -47.452788)
		)
		(stroke
			(width 0)
			(type solid)
		)
		(fill yes)
		(layer "F.Cu")
		(net "M_G_DQ<33>")
	)
	(gr_poly
		(pts
			(xy 107.803442 -46.665388) (xy 107.752642 -46.665388) (xy 107.562142 -46.678088) (xy 107.562142 -46.779688)
			(xy 107.752642 -46.792388) (xy 107.803442 -46.792388)
		)
		(stroke
			(width 0)
			(type solid)
		)
		(fill yes)
		(layer "F.Cu")
		(net "M_G_DQ<33>")
	)
	(gr_poly
		(pts
			(xy 107.803442 -46.004988) (xy 107.752642 -46.004988) (xy 107.562142 -46.017688) (xy 107.562142 -46.119288)
			(xy 107.752642 -46.131988) (xy 107.803442 -46.131988)
		)
		(stroke
			(width 0)
			(type solid)
		)
		(fill yes)
		(layer "F.Cu")
		(net "M_G_DQ<33>")
	)
	(gr_poly
		(pts
			(xy 107.803442 -45.344588) (xy 107.752642 -45.344588) (xy 107.562142 -45.357288) (xy 107.562142 -45.458888)
			(xy 107.752642 -45.471588) (xy 107.803442 -45.471588)
		)
		(stroke
			(width 0)
			(type solid)
		)
		(fill yes)
		(layer "F.Cu")
		(net "M_G_DQ<33>")
	)
	(gr_poly
		(pts
			(xy 107.803442 -44.684188) (xy 107.752642 -44.684188) (xy 107.562142 -44.696888) (xy 107.562142 -44.798488)
			(xy 107.752642 -44.811188) (xy 107.803442 -44.811188)
		)
		(stroke
			(width 0)
			(type solid)
		)
		(fill yes)
		(layer "F.Cu")
		(net "M_G_DQ<33>")
	)
	(gr_poly
		(pts
			(xy 107.803442 -44.023788) (xy 107.752642 -44.023788) (xy 107.562142 -44.036488) (xy 107.562142 -44.138088)
			(xy 107.752642 -44.150788) (xy 107.803442 -44.150788)
		)
		(stroke
			(width 0)
			(type solid)
		)
		(fill yes)
		(layer "F.Cu")
		(net "M_G_DQ<33>")
	)
	(gr_poly
		(pts
			(xy 107.803442 -43.363388) (xy 107.752642 -43.363388) (xy 107.562142 -43.376088) (xy 107.562142 -43.477688)
			(xy 107.752642 -43.490388) (xy 107.803442 -43.490388)
		)
		(stroke
			(width 0)
			(type solid)
		)
		(fill yes)
		(layer "F.Cu")
		(net "M_G_DQ<33>")
	)
	(gr_poly
		(pts
			(xy 107.803442 -42.702988) (xy 107.752642 -42.702988) (xy 107.562142 -42.715688) (xy 107.562142 -42.817288)
			(xy 107.752642 -42.829988) (xy 107.803442 -42.829988)
		)
		(stroke
			(width 0)
			(type solid)
		)
		(fill yes)
		(layer "F.Cu")
		(net "M_G_DQ<33>")
	)
	(gr_poly
		(pts
			(xy 107.803442 -42.042588) (xy 107.752642 -42.042588) (xy 107.562142 -42.055288) (xy 107.562142 -42.156888)
			(xy 107.752642 -42.169588) (xy 107.803442 -42.169588)
		)
		(stroke
			(width 0)
			(type solid)
		)
		(fill yes)
		(layer "F.Cu")
		(net "M_G_DQ<33>")
	)
	(gr_poly
		(pts
			(xy 107.863132 -103.062532) (xy 107.831636 -103.03129) (xy 107.632246 -102.95763) (xy 107.470702 -103.119174)
			(xy 107.544362 -103.318564) (xy 107.575604 -103.35006)
		)
		(stroke
			(width 0)
			(type solid)
		)
		(fill yes)
		(layer "F.Cu")
		(net "M_K_DQ<36>")
	)
	(gr_poly
		(pts
			(xy 107.926632 -105.523284) (xy 107.926632 -105.294684) (xy 107.733592 -105.205784) (xy 107.689142 -105.205784)
			(xy 107.689142 -105.612184) (xy 107.733592 -105.612184)
		)
		(stroke
			(width 0)
			(type solid)
		)
		(fill yes)
		(layer "F.Cu")
		(net "M_K_DQ<37>")
	)
	(gr_poly
		(pts
			(xy 107.926632 -104.532684) (xy 107.926632 -104.304084) (xy 107.733592 -104.215184) (xy 107.689142 -104.215184)
			(xy 107.689142 -104.621584) (xy 107.733592 -104.621584)
		)
		(stroke
			(width 0)
			(type solid)
		)
		(fill yes)
		(layer "F.Cu")
		(net "M_K_DQ<37>")
	)
	(gr_poly
		(pts
			(xy 108.032042 -111.349536) (xy 108.032042 -111.247936) (xy 107.841542 -111.235236) (xy 107.790742 -111.235236)
			(xy 107.790742 -111.362236) (xy 107.841542 -111.362236)
		)
		(stroke
			(width 0)
			(type solid)
		)
		(fill yes)
		(layer "F.Cu")
		(net "M_K_DQ<37>")
	)
	(gr_poly
		(pts
			(xy 108.032042 -110.689136) (xy 108.032042 -110.587536) (xy 107.841542 -110.574836) (xy 107.790742 -110.574836)
			(xy 107.790742 -110.701836) (xy 107.841542 -110.701836)
		)
		(stroke
			(width 0)
			(type solid)
		)
		(fill yes)
		(layer "F.Cu")
		(net "M_K_DQ<37>")
	)
	(gr_poly
		(pts
			(xy 108.032042 -110.028736) (xy 108.032042 -109.927136) (xy 107.841542 -109.914436) (xy 107.790742 -109.914436)
			(xy 107.790742 -110.041436) (xy 107.841542 -110.041436)
		)
		(stroke
			(width 0)
			(type solid)
		)
		(fill yes)
		(layer "F.Cu")
		(net "M_K_DQ<37>")
	)
	(gr_poly
		(pts
			(xy 108.032042 -109.368336) (xy 108.032042 -109.266736) (xy 107.841542 -109.254036) (xy 107.790742 -109.254036)
			(xy 107.790742 -109.381036) (xy 107.841542 -109.381036)
		)
		(stroke
			(width 0)
			(type solid)
		)
		(fill yes)
		(layer "F.Cu")
		(net "M_K_DQ<37>")
	)
	(gr_poly
		(pts
			(xy 108.032042 -108.707936) (xy 108.032042 -108.606336) (xy 107.841542 -108.593636) (xy 107.790742 -108.593636)
			(xy 107.790742 -108.720636) (xy 107.841542 -108.720636)
		)
		(stroke
			(width 0)
			(type solid)
		)
		(fill yes)
		(layer "F.Cu")
		(net "M_K_DQ<37>")
	)
	(gr_poly
		(pts
			(xy 108.032042 -108.047536) (xy 108.032042 -107.945936) (xy 107.841542 -107.933236) (xy 107.790742 -107.933236)
			(xy 107.790742 -108.060236) (xy 107.841542 -108.060236)
		)
		(stroke
			(width 0)
			(type solid)
		)
		(fill yes)
		(layer "F.Cu")
		(net "M_K_DQ<37>")
	)
	(gr_poly
		(pts
			(xy 108.032042 -107.387136) (xy 108.032042 -107.285536) (xy 107.841542 -107.272836) (xy 107.790742 -107.272836)
			(xy 107.790742 -107.399836) (xy 107.841542 -107.399836)
		)
		(stroke
			(width 0)
			(type solid)
		)
		(fill yes)
		(layer "F.Cu")
		(net "M_K_DQ<37>")
	)
	(gr_poly
		(pts
			(xy 108.044742 -49.091088) (xy 108.044742 -48.989488) (xy 107.854242 -48.976788) (xy 107.803442 -48.976788)
			(xy 107.803442 -49.103788) (xy 107.854242 -49.103788)
		)
		(stroke
			(width 0)
			(type solid)
		)
		(fill yes)
		(layer "F.Cu")
		(net "M_G_DQ<33>")
	)
	(gr_poly
		(pts
			(xy 108.044742 -48.430688) (xy 108.044742 -48.329088) (xy 107.854242 -48.316388) (xy 107.803442 -48.316388)
			(xy 107.803442 -48.443388) (xy 107.854242 -48.443388)
		)
		(stroke
			(width 0)
			(type solid)
		)
		(fill yes)
		(layer "F.Cu")
		(net "M_G_DQ<33>")
	)
	(gr_poly
		(pts
			(xy 108.044742 -47.770288) (xy 108.044742 -47.668688) (xy 107.854242 -47.655988) (xy 107.803442 -47.655988)
			(xy 107.803442 -47.782988) (xy 107.854242 -47.782988)
		)
		(stroke
			(width 0)
			(type solid)
		)
		(fill yes)
		(layer "F.Cu")
		(net "M_G_DQ<33>")
	)
	(gr_poly
		(pts
			(xy 108.044742 -47.109888) (xy 108.044742 -47.008288) (xy 107.854242 -46.995588) (xy 107.803442 -46.995588)
			(xy 107.803442 -47.122588) (xy 107.854242 -47.122588)
		)
		(stroke
			(width 0)
			(type solid)
		)
		(fill yes)
		(layer "F.Cu")
		(net "M_G_DQ<33>")
	)
	(gr_poly
		(pts
			(xy 108.044742 -46.449488) (xy 108.044742 -46.347888) (xy 107.854242 -46.335188) (xy 107.803442 -46.335188)
			(xy 107.803442 -46.462188) (xy 107.854242 -46.462188)
		)
		(stroke
			(width 0)
			(type solid)
		)
		(fill yes)
		(layer "F.Cu")
		(net "M_G_DQ<33>")
	)
	(gr_poly
		(pts
			(xy 108.044742 -45.789088) (xy 108.044742 -45.687488) (xy 107.854242 -45.674788) (xy 107.803442 -45.674788)
			(xy 107.803442 -45.801788) (xy 107.854242 -45.801788)
		)
		(stroke
			(width 0)
			(type solid)
		)
		(fill yes)
		(layer "F.Cu")
		(net "M_G_DQ<33>")
	)
	(gr_poly
		(pts
			(xy 108.044742 -45.128688) (xy 108.044742 -45.027088) (xy 107.854242 -45.014388) (xy 107.803442 -45.014388)
			(xy 107.803442 -45.141388) (xy 107.854242 -45.141388)
		)
		(stroke
			(width 0)
			(type solid)
		)
		(fill yes)
		(layer "F.Cu")
		(net "M_G_DQ<33>")
	)
	(gr_poly
		(pts
			(xy 108.044742 -44.468288) (xy 108.044742 -44.366688) (xy 107.854242 -44.353988) (xy 107.803442 -44.353988)
			(xy 107.803442 -44.480988) (xy 107.854242 -44.480988)
		)
		(stroke
			(width 0)
			(type solid)
		)
		(fill yes)
		(layer "F.Cu")
		(net "M_G_DQ<33>")
	)
	(gr_poly
		(pts
			(xy 108.044742 -43.807888) (xy 108.044742 -43.706288) (xy 107.854242 -43.693588) (xy 107.803442 -43.693588)
			(xy 107.803442 -43.820588) (xy 107.854242 -43.820588)
		)
		(stroke
			(width 0)
			(type solid)
		)
		(fill yes)
		(layer "F.Cu")
		(net "M_G_DQ<33>")
	)
	(gr_poly
		(pts
			(xy 108.044742 -43.147488) (xy 108.044742 -43.045888) (xy 107.854242 -43.033188) (xy 107.803442 -43.033188)
			(xy 107.803442 -43.160188) (xy 107.854242 -43.160188)
		)
		(stroke
			(width 0)
			(type solid)
		)
		(fill yes)
		(layer "F.Cu")
		(net "M_G_DQ<33>")
	)
	(gr_poly
		(pts
			(xy 108.044742 -42.487088) (xy 108.044742 -42.385488) (xy 107.854242 -42.372788) (xy 107.803442 -42.372788)
			(xy 107.803442 -42.499788) (xy 107.854242 -42.499788)
		)
		(stroke
			(width 0)
			(type solid)
		)
		(fill yes)
		(layer "F.Cu")
		(net "M_G_DQ<33>")
	)
	(gr_poly
		(pts
			(xy 108.105702 -103.431086) (xy 108.032042 -103.231696) (xy 108.0008 -103.2002) (xy 107.713272 -103.487728)
			(xy 107.744768 -103.51897) (xy 107.944158 -103.59263)
		)
		(stroke
			(width 0)
			(type solid)
		)
		(fill yes)
		(layer "F.Cu")
		(net "M_K_DQ<37>")
	)
	(gr_poly
		(pts
			(xy 108.184442 -111.565436) (xy 108.133642 -111.565436) (xy 107.943142 -111.578136) (xy 107.943142 -111.679736)
			(xy 108.133642 -111.692436) (xy 108.184442 -111.692436)
		)
		(stroke
			(width 0)
			(type solid)
		)
		(fill yes)
		(layer "F.Cu")
		(net "M_K_DQ<32>")
	)
	(gr_poly
		(pts
			(xy 108.184442 -110.905036) (xy 108.133642 -110.905036) (xy 107.943142 -110.917736) (xy 107.943142 -111.019336)
			(xy 108.133642 -111.032036) (xy 108.184442 -111.032036)
		)
		(stroke
			(width 0)
			(type solid)
		)
		(fill yes)
		(layer "F.Cu")
		(net "M_K_DQ<32>")
	)
	(gr_poly
		(pts
			(xy 108.184442 -110.244636) (xy 108.133642 -110.244636) (xy 107.943142 -110.257336) (xy 107.943142 -110.358936)
			(xy 108.133642 -110.371636) (xy 108.184442 -110.371636)
		)
		(stroke
			(width 0)
			(type solid)
		)
		(fill yes)
		(layer "F.Cu")
		(net "M_K_DQ<32>")
	)
	(gr_poly
		(pts
			(xy 108.184442 -109.584236) (xy 108.133642 -109.584236) (xy 107.943142 -109.596936) (xy 107.943142 -109.698536)
			(xy 108.133642 -109.711236) (xy 108.184442 -109.711236)
		)
		(stroke
			(width 0)
			(type solid)
		)
		(fill yes)
		(layer "F.Cu")
		(net "M_K_DQ<32>")
	)
	(gr_poly
		(pts
			(xy 108.184442 -108.923836) (xy 108.133642 -108.923836) (xy 107.943142 -108.936536) (xy 107.943142 -109.038136)
			(xy 108.133642 -109.050836) (xy 108.184442 -109.050836)
		)
		(stroke
			(width 0)
			(type solid)
		)
		(fill yes)
		(layer "F.Cu")
		(net "M_K_DQ<32>")
	)
	(gr_poly
		(pts
			(xy 108.184442 -108.263436) (xy 108.133642 -108.263436) (xy 107.943142 -108.276136) (xy 107.943142 -108.377736)
			(xy 108.133642 -108.390436) (xy 108.184442 -108.390436)
		)
		(stroke
			(width 0)
			(type solid)
		)
		(fill yes)
		(layer "F.Cu")
		(net "M_K_DQ<32>")
	)
	(gr_poly
		(pts
			(xy 108.184442 -107.603036) (xy 108.133642 -107.603036) (xy 107.943142 -107.615736) (xy 107.943142 -107.717336)
			(xy 108.133642 -107.730036) (xy 108.184442 -107.730036)
		)
		(stroke
			(width 0)
			(type solid)
		)
		(fill yes)
		(layer "F.Cu")
		(net "M_K_DQ<32>")
	)
	(gr_poly
		(pts
			(xy 108.184442 -106.942636) (xy 108.133642 -106.942636) (xy 107.943142 -106.955336) (xy 107.943142 -107.056936)
			(xy 108.133642 -107.069636) (xy 108.184442 -107.069636)
		)
		(stroke
			(width 0)
			(type solid)
		)
		(fill yes)
		(layer "F.Cu")
		(net "M_K_DQ<32>")
	)
	(gr_poly
		(pts
			(xy 108.197142 -49.306988) (xy 108.146342 -49.306988) (xy 107.955842 -49.319688) (xy 107.955842 -49.421288)
			(xy 108.146342 -49.433988) (xy 108.197142 -49.433988)
		)
		(stroke
			(width 0)
			(type solid)
		)
		(fill yes)
		(layer "F.Cu")
		(net "M_G_DQS_DP<13>")
	)
	(gr_poly
		(pts
			(xy 108.197142 -48.646588) (xy 108.146342 -48.646588) (xy 107.955842 -48.659288) (xy 107.955842 -48.760888)
			(xy 108.146342 -48.773588) (xy 108.197142 -48.773588)
		)
		(stroke
			(width 0)
			(type solid)
		)
		(fill yes)
		(layer "F.Cu")
		(net "M_G_DQS_DP<13>")
	)
	(gr_poly
		(pts
			(xy 108.197142 -47.986188) (xy 108.146342 -47.986188) (xy 107.955842 -47.998888) (xy 107.955842 -48.100488)
			(xy 108.146342 -48.113188) (xy 108.197142 -48.113188)
		)
		(stroke
			(width 0)
			(type solid)
		)
		(fill yes)
		(layer "F.Cu")
		(net "M_G_DQS_DP<13>")
	)
	(gr_poly
		(pts
			(xy 108.197142 -47.325788) (xy 108.146342 -47.325788) (xy 107.955842 -47.338488) (xy 107.955842 -47.440088)
			(xy 108.146342 -47.452788) (xy 108.197142 -47.452788)
		)
		(stroke
			(width 0)
			(type solid)
		)
		(fill yes)
		(layer "F.Cu")
		(net "M_G_DQS_DP<13>")
	)
	(gr_poly
		(pts
			(xy 108.197142 -46.665388) (xy 108.146342 -46.665388) (xy 107.955842 -46.678088) (xy 107.955842 -46.779688)
			(xy 108.146342 -46.792388) (xy 108.197142 -46.792388)
		)
		(stroke
			(width 0)
			(type solid)
		)
		(fill yes)
		(layer "F.Cu")
		(net "M_G_DQS_DP<13>")
	)
	(gr_poly
		(pts
			(xy 108.197142 -46.004988) (xy 108.146342 -46.004988) (xy 107.955842 -46.017688) (xy 107.955842 -46.119288)
			(xy 108.146342 -46.131988) (xy 108.197142 -46.131988)
		)
		(stroke
			(width 0)
			(type solid)
		)
		(fill yes)
		(layer "F.Cu")
		(net "M_G_DQS_DP<13>")
	)
	(gr_poly
		(pts
			(xy 108.197142 -45.344588) (xy 108.146342 -45.344588) (xy 107.955842 -45.357288) (xy 107.955842 -45.458888)
			(xy 108.146342 -45.471588) (xy 108.197142 -45.471588)
		)
		(stroke
			(width 0)
			(type solid)
		)
		(fill yes)
		(layer "F.Cu")
		(net "M_G_DQS_DP<13>")
	)
	(gr_poly
		(pts
			(xy 108.197142 -44.684188) (xy 108.146342 -44.684188) (xy 107.955842 -44.696888) (xy 107.955842 -44.798488)
			(xy 108.146342 -44.811188) (xy 108.197142 -44.811188)
		)
		(stroke
			(width 0)
			(type solid)
		)
		(fill yes)
		(layer "F.Cu")
		(net "M_G_DQS_DP<13>")
	)
	(gr_poly
		(pts
			(xy 108.197142 -44.023788) (xy 108.146342 -44.023788) (xy 107.955842 -44.036488) (xy 107.955842 -44.138088)
			(xy 108.146342 -44.150788) (xy 108.197142 -44.150788)
		)
		(stroke
			(width 0)
			(type solid)
		)
		(fill yes)
		(layer "F.Cu")
		(net "M_G_DQS_DP<13>")
	)
	(gr_poly
		(pts
			(xy 108.197142 -43.363388) (xy 108.146342 -43.363388) (xy 107.955842 -43.376088) (xy 107.955842 -43.477688)
			(xy 108.146342 -43.490388) (xy 108.197142 -43.490388)
		)
		(stroke
			(width 0)
			(type solid)
		)
		(fill yes)
		(layer "F.Cu")
		(net "M_G_DQS_DP<13>")
	)
	(gr_poly
		(pts
			(xy 108.197142 -42.702988) (xy 108.146342 -42.702988) (xy 107.955842 -42.715688) (xy 107.955842 -42.817288)
			(xy 108.146342 -42.829988) (xy 108.197142 -42.829988)
		)
		(stroke
			(width 0)
			(type solid)
		)
		(fill yes)
		(layer "F.Cu")
		(net "M_G_DQS_DP<13>")
	)
	(gr_poly
		(pts
			(xy 108.197142 -42.042588) (xy 108.146342 -42.042588) (xy 107.955842 -42.055288) (xy 107.955842 -42.156888)
			(xy 108.146342 -42.169588) (xy 108.197142 -42.169588)
		)
		(stroke
			(width 0)
			(type solid)
		)
		(fill yes)
		(layer "F.Cu")
		(net "M_G_DQS_DP<13>")
	)
	(gr_poly
		(pts
			(xy 108.286042 -105.949242) (xy 108.241592 -105.949242) (xy 108.048552 -106.038142) (xy 108.048552 -106.266742)
			(xy 108.241592 -106.355642) (xy 108.286042 -106.355642)
		)
		(stroke
			(width 0)
			(type solid)
		)
		(fill yes)
		(layer "F.Cu")
		(net "M_K_DQ<32>")
	)
	(gr_poly
		(pts
			(xy 108.286042 -105.060242) (xy 108.241592 -105.060242) (xy 108.048552 -105.149142) (xy 108.048552 -105.377742)
			(xy 108.241592 -105.466642) (xy 108.286042 -105.466642)
		)
		(stroke
			(width 0)
			(type solid)
		)
		(fill yes)
		(layer "F.Cu")
		(net "M_K_DQ<32>")
	)
	(gr_poly
		(pts
			(xy 108.425742 -111.349536) (xy 108.425742 -111.247936) (xy 108.235242 -111.235236) (xy 108.184442 -111.235236)
			(xy 108.184442 -111.362236) (xy 108.235242 -111.362236)
		)
		(stroke
			(width 0)
			(type solid)
		)
		(fill yes)
		(layer "F.Cu")
		(net "M_K_DQ<32>")
	)
	(gr_poly
		(pts
			(xy 108.425742 -110.689136) (xy 108.425742 -110.587536) (xy 108.235242 -110.574836) (xy 108.184442 -110.574836)
			(xy 108.184442 -110.701836) (xy 108.235242 -110.701836)
		)
		(stroke
			(width 0)
			(type solid)
		)
		(fill yes)
		(layer "F.Cu")
		(net "M_K_DQ<32>")
	)
	(gr_poly
		(pts
			(xy 108.425742 -110.028736) (xy 108.425742 -109.927136) (xy 108.235242 -109.914436) (xy 108.184442 -109.914436)
			(xy 108.184442 -110.041436) (xy 108.235242 -110.041436)
		)
		(stroke
			(width 0)
			(type solid)
		)
		(fill yes)
		(layer "F.Cu")
		(net "M_K_DQ<32>")
	)
	(gr_poly
		(pts
			(xy 108.425742 -109.368336) (xy 108.425742 -109.266736) (xy 108.235242 -109.254036) (xy 108.184442 -109.254036)
			(xy 108.184442 -109.381036) (xy 108.235242 -109.381036)
		)
		(stroke
			(width 0)
			(type solid)
		)
		(fill yes)
		(layer "F.Cu")
		(net "M_K_DQ<32>")
	)
	(gr_poly
		(pts
			(xy 108.425742 -108.707936) (xy 108.425742 -108.606336) (xy 108.235242 -108.593636) (xy 108.184442 -108.593636)
			(xy 108.184442 -108.720636) (xy 108.235242 -108.720636)
		)
		(stroke
			(width 0)
			(type solid)
		)
		(fill yes)
		(layer "F.Cu")
		(net "M_K_DQ<32>")
	)
	(gr_poly
		(pts
			(xy 108.425742 -108.047536) (xy 108.425742 -107.945936) (xy 108.235242 -107.933236) (xy 108.184442 -107.933236)
			(xy 108.184442 -108.060236) (xy 108.235242 -108.060236)
		)
		(stroke
			(width 0)
			(type solid)
		)
		(fill yes)
		(layer "F.Cu")
		(net "M_K_DQ<32>")
	)
	(gr_poly
		(pts
			(xy 108.425742 -107.387136) (xy 108.425742 -107.285536) (xy 108.235242 -107.272836) (xy 108.184442 -107.272836)
			(xy 108.184442 -107.399836) (xy 108.235242 -107.399836)
		)
		(stroke
			(width 0)
			(type solid)
		)
		(fill yes)
		(layer "F.Cu")
		(net "M_K_DQ<32>")
	)
	(gr_poly
		(pts
			(xy 108.438442 -49.091088) (xy 108.438442 -48.989488) (xy 108.247942 -48.976788) (xy 108.197142 -48.976788)
			(xy 108.197142 -49.103788) (xy 108.247942 -49.103788)
		)
		(stroke
			(width 0)
			(type solid)
		)
		(fill yes)
		(layer "F.Cu")
		(net "M_G_DQS_DP<13>")
	)
	(gr_poly
		(pts
			(xy 108.438442 -48.430688) (xy 108.438442 -48.329088) (xy 108.247942 -48.316388) (xy 108.197142 -48.316388)
			(xy 108.197142 -48.443388) (xy 108.247942 -48.443388)
		)
		(stroke
			(width 0)
			(type solid)
		)
		(fill yes)
		(layer "F.Cu")
		(net "M_G_DQS_DP<13>")
	)
	(gr_poly
		(pts
			(xy 108.438442 -47.770288) (xy 108.438442 -47.668688) (xy 108.247942 -47.655988) (xy 108.197142 -47.655988)
			(xy 108.197142 -47.782988) (xy 108.247942 -47.782988)
		)
		(stroke
			(width 0)
			(type solid)
		)
		(fill yes)
		(layer "F.Cu")
		(net "M_G_DQS_DP<13>")
	)
	(gr_poly
		(pts
			(xy 108.438442 -47.109888) (xy 108.438442 -47.008288) (xy 108.247942 -46.995588) (xy 108.197142 -46.995588)
			(xy 108.197142 -47.122588) (xy 108.247942 -47.122588)
		)
		(stroke
			(width 0)
			(type solid)
		)
		(fill yes)
		(layer "F.Cu")
		(net "M_G_DQS_DP<13>")
	)
	(gr_poly
		(pts
			(xy 108.438442 -46.449488) (xy 108.438442 -46.347888) (xy 108.247942 -46.335188) (xy 108.197142 -46.335188)
			(xy 108.197142 -46.462188) (xy 108.247942 -46.462188)
		)
		(stroke
			(width 0)
			(type solid)
		)
		(fill yes)
		(layer "F.Cu")
		(net "M_G_DQS_DP<13>")
	)
	(gr_poly
		(pts
			(xy 108.438442 -45.789088) (xy 108.438442 -45.687488) (xy 108.247942 -45.674788) (xy 108.197142 -45.674788)
			(xy 108.197142 -45.801788) (xy 108.247942 -45.801788)
		)
		(stroke
			(width 0)
			(type solid)
		)
		(fill yes)
		(layer "F.Cu")
		(net "M_G_DQS_DP<13>")
	)
	(gr_poly
		(pts
			(xy 108.438442 -45.128688) (xy 108.438442 -45.027088) (xy 108.247942 -45.014388) (xy 108.197142 -45.014388)
			(xy 108.197142 -45.141388) (xy 108.247942 -45.141388)
		)
		(stroke
			(width 0)
			(type solid)
		)
		(fill yes)
		(layer "F.Cu")
		(net "M_G_DQS_DP<13>")
	)
	(gr_poly
		(pts
			(xy 108.438442 -44.468288) (xy 108.438442 -44.366688) (xy 108.247942 -44.353988) (xy 108.197142 -44.353988)
			(xy 108.197142 -44.480988) (xy 108.247942 -44.480988)
		)
		(stroke
			(width 0)
			(type solid)
		)
		(fill yes)
		(layer "F.Cu")
		(net "M_G_DQS_DP<13>")
	)
	(gr_poly
		(pts
			(xy 108.438442 -43.807888) (xy 108.438442 -43.706288) (xy 108.247942 -43.693588) (xy 108.197142 -43.693588)
			(xy 108.197142 -43.820588) (xy 108.247942 -43.820588)
		)
		(stroke
			(width 0)
			(type solid)
		)
		(fill yes)
		(layer "F.Cu")
		(net "M_G_DQS_DP<13>")
	)
	(gr_poly
		(pts
			(xy 108.438442 -43.147488) (xy 108.438442 -43.045888) (xy 108.247942 -43.033188) (xy 108.197142 -43.033188)
			(xy 108.197142 -43.160188) (xy 108.247942 -43.160188)
		)
		(stroke
			(width 0)
			(type solid)
		)
		(fill yes)
		(layer "F.Cu")
		(net "M_G_DQS_DP<13>")
	)
	(gr_poly
		(pts
			(xy 108.438442 -42.487088) (xy 108.438442 -42.385488) (xy 108.247942 -42.372788) (xy 108.197142 -42.372788)
			(xy 108.197142 -42.499788) (xy 108.247942 -42.499788)
		)
		(stroke
			(width 0)
			(type solid)
		)
		(fill yes)
		(layer "F.Cu")
		(net "M_G_DQS_DP<13>")
	)
	(gr_poly
		(pts
			(xy 108.578142 -111.565436) (xy 108.527342 -111.565436) (xy 108.336842 -111.578136) (xy 108.336842 -111.679736)
			(xy 108.527342 -111.692436) (xy 108.578142 -111.692436)
		)
		(stroke
			(width 0)
			(type solid)
		)
		(fill yes)
		(layer "F.Cu")
		(net "M_K_DQ<33>")
	)
	(gr_poly
		(pts
			(xy 108.578142 -110.905036) (xy 108.527342 -110.905036) (xy 108.336842 -110.917736) (xy 108.336842 -111.019336)
			(xy 108.527342 -111.032036) (xy 108.578142 -111.032036)
		)
		(stroke
			(width 0)
			(type solid)
		)
		(fill yes)
		(layer "F.Cu")
		(net "M_K_DQ<33>")
	)
	(gr_poly
		(pts
			(xy 108.578142 -110.244636) (xy 108.527342 -110.244636) (xy 108.336842 -110.257336) (xy 108.336842 -110.358936)
			(xy 108.527342 -110.371636) (xy 108.578142 -110.371636)
		)
		(stroke
			(width 0)
			(type solid)
		)
		(fill yes)
		(layer "F.Cu")
		(net "M_K_DQ<33>")
	)
	(gr_poly
		(pts
			(xy 108.578142 -109.584236) (xy 108.527342 -109.584236) (xy 108.336842 -109.596936) (xy 108.336842 -109.698536)
			(xy 108.527342 -109.711236) (xy 108.578142 -109.711236)
		)
		(stroke
			(width 0)
			(type solid)
		)
		(fill yes)
		(layer "F.Cu")
		(net "M_K_DQ<33>")
	)
	(gr_poly
		(pts
			(xy 108.578142 -108.923836) (xy 108.527342 -108.923836) (xy 108.336842 -108.936536) (xy 108.336842 -109.038136)
			(xy 108.527342 -109.050836) (xy 108.578142 -109.050836)
		)
		(stroke
			(width 0)
			(type solid)
		)
		(fill yes)
		(layer "F.Cu")
		(net "M_K_DQ<33>")
	)
	(gr_poly
		(pts
			(xy 108.578142 -108.263436) (xy 108.527342 -108.263436) (xy 108.336842 -108.276136) (xy 108.336842 -108.377736)
			(xy 108.527342 -108.390436) (xy 108.578142 -108.390436)
		)
		(stroke
			(width 0)
			(type solid)
		)
		(fill yes)
		(layer "F.Cu")
		(net "M_K_DQ<33>")
	)
	(gr_poly
		(pts
			(xy 108.578142 -107.603036) (xy 108.527342 -107.603036) (xy 108.336842 -107.615736) (xy 108.336842 -107.717336)
			(xy 108.527342 -107.730036) (xy 108.578142 -107.730036)
		)
		(stroke
			(width 0)
			(type solid)
		)
		(fill yes)
		(layer "F.Cu")
		(net "M_K_DQ<33>")
	)
	(gr_poly
		(pts
			(xy 108.578142 -106.942636) (xy 108.527342 -106.942636) (xy 108.336842 -106.955336) (xy 108.336842 -107.056936)
			(xy 108.527342 -107.069636) (xy 108.578142 -107.069636)
		)
		(stroke
			(width 0)
			(type solid)
		)
		(fill yes)
		(layer "F.Cu")
		(net "M_K_DQ<33>")
	)
	(gr_poly
		(pts
			(xy 108.590842 -49.306988) (xy 108.540042 -49.306988) (xy 108.349542 -49.319688) (xy 108.349542 -49.421288)
			(xy 108.540042 -49.433988) (xy 108.590842 -49.433988)
		)
		(stroke
			(width 0)
			(type solid)
		)
		(fill yes)
		(layer "F.Cu")
		(net "M_G_DQS_DN<13>")
	)
	(gr_poly
		(pts
			(xy 108.590842 -48.646588) (xy 108.540042 -48.646588) (xy 108.349542 -48.659288) (xy 108.349542 -48.760888)
			(xy 108.540042 -48.773588) (xy 108.590842 -48.773588)
		)
		(stroke
			(width 0)
			(type solid)
		)
		(fill yes)
		(layer "F.Cu")
		(net "M_G_DQS_DN<13>")
	)
	(gr_poly
		(pts
			(xy 108.590842 -47.986188) (xy 108.540042 -47.986188) (xy 108.349542 -47.998888) (xy 108.349542 -48.100488)
			(xy 108.540042 -48.113188) (xy 108.590842 -48.113188)
		)
		(stroke
			(width 0)
			(type solid)
		)
		(fill yes)
		(layer "F.Cu")
		(net "M_G_DQS_DN<13>")
	)
	(gr_poly
		(pts
			(xy 108.590842 -47.325788) (xy 108.540042 -47.325788) (xy 108.349542 -47.338488) (xy 108.349542 -47.440088)
			(xy 108.540042 -47.452788) (xy 108.590842 -47.452788)
		)
		(stroke
			(width 0)
			(type solid)
		)
		(fill yes)
		(layer "F.Cu")
		(net "M_G_DQS_DN<13>")
	)
	(gr_poly
		(pts
			(xy 108.590842 -46.665388) (xy 108.540042 -46.665388) (xy 108.349542 -46.678088) (xy 108.349542 -46.779688)
			(xy 108.540042 -46.792388) (xy 108.590842 -46.792388)
		)
		(stroke
			(width 0)
			(type solid)
		)
		(fill yes)
		(layer "F.Cu")
		(net "M_G_DQS_DN<13>")
	)
	(gr_poly
		(pts
			(xy 108.590842 -46.004988) (xy 108.540042 -46.004988) (xy 108.349542 -46.017688) (xy 108.349542 -46.119288)
			(xy 108.540042 -46.131988) (xy 108.590842 -46.131988)
		)
		(stroke
			(width 0)
			(type solid)
		)
		(fill yes)
		(layer "F.Cu")
		(net "M_G_DQS_DN<13>")
	)
	(gr_poly
		(pts
			(xy 108.590842 -45.344588) (xy 108.540042 -45.344588) (xy 108.349542 -45.357288) (xy 108.349542 -45.458888)
			(xy 108.540042 -45.471588) (xy 108.590842 -45.471588)
		)
		(stroke
			(width 0)
			(type solid)
		)
		(fill yes)
		(layer "F.Cu")
		(net "M_G_DQS_DN<13>")
	)
	(gr_poly
		(pts
			(xy 108.590842 -44.684188) (xy 108.540042 -44.684188) (xy 108.349542 -44.696888) (xy 108.349542 -44.798488)
			(xy 108.540042 -44.811188) (xy 108.590842 -44.811188)
		)
		(stroke
			(width 0)
			(type solid)
		)
		(fill yes)
		(layer "F.Cu")
		(net "M_G_DQS_DN<13>")
	)
	(gr_poly
		(pts
			(xy 108.590842 -44.023788) (xy 108.540042 -44.023788) (xy 108.349542 -44.036488) (xy 108.349542 -44.138088)
			(xy 108.540042 -44.150788) (xy 108.590842 -44.150788)
		)
		(stroke
			(width 0)
			(type solid)
		)
		(fill yes)
		(layer "F.Cu")
		(net "M_G_DQS_DN<13>")
	)
	(gr_poly
		(pts
			(xy 108.590842 -43.363388) (xy 108.540042 -43.363388) (xy 108.349542 -43.376088) (xy 108.349542 -43.477688)
			(xy 108.540042 -43.490388) (xy 108.590842 -43.490388)
		)
		(stroke
			(width 0)
			(type solid)
		)
		(fill yes)
		(layer "F.Cu")
		(net "M_G_DQS_DN<13>")
	)
	(gr_poly
		(pts
			(xy 108.590842 -42.702988) (xy 108.540042 -42.702988) (xy 108.349542 -42.715688) (xy 108.349542 -42.817288)
			(xy 108.540042 -42.829988) (xy 108.590842 -42.829988)
		)
		(stroke
			(width 0)
			(type solid)
		)
		(fill yes)
		(layer "F.Cu")
		(net "M_G_DQS_DN<13>")
	)
	(gr_poly
		(pts
			(xy 108.590842 -42.042588) (xy 108.540042 -42.042588) (xy 108.349542 -42.055288) (xy 108.349542 -42.156888)
			(xy 108.540042 -42.169588) (xy 108.590842 -42.169588)
		)
		(stroke
			(width 0)
			(type solid)
		)
		(fill yes)
		(layer "F.Cu")
		(net "M_G_DQS_DN<13>")
	)
	(gr_poly
		(pts
			(xy 108.63834 -100.369624) (xy 108.616242 -100.33127) (xy 108.45419 -100.2284) (xy 108.262928 -100.338636)
			(xy 108.271056 -100.530406) (xy 108.293154 -100.569268)
		)
		(stroke
			(width 0)
			(type solid)
		)
		(fill yes)
		(layer "F.Cu")
		(net "M_K_DQ<36>")
	)
	(gr_poly
		(pts
			(xy 108.714032 -106.266742) (xy 108.714032 -106.038142) (xy 108.520992 -105.949242) (xy 108.476542 -105.949242)
			(xy 108.476542 -106.355642) (xy 108.520992 -106.355642)
		)
		(stroke
			(width 0)
			(type solid)
		)
		(fill yes)
		(layer "F.Cu")
		(net "M_K_DQ<33>")
	)
	(gr_poly
		(pts
			(xy 108.714032 -105.377742) (xy 108.714032 -105.149142) (xy 108.520992 -105.060242) (xy 108.476542 -105.060242)
			(xy 108.476542 -105.466642) (xy 108.520992 -105.466642)
		)
		(stroke
			(width 0)
			(type solid)
		)
		(fill yes)
		(layer "F.Cu")
		(net "M_K_DQ<33>")
	)
	(gr_poly
		(pts
			(xy 108.71581 -102.567232) (xy 108.71581 -102.346252) (xy 108.54563 -102.257352) (xy 108.50118 -102.257352)
			(xy 108.50118 -102.656132) (xy 108.54563 -102.656132)
		)
		(stroke
			(width 0)
			(type solid)
		)
		(fill yes)
		(layer "F.Cu")
		(net "M_K_DQ<37>")
	)
	(gr_poly
		(pts
			(xy 108.819442 -111.349536) (xy 108.819442 -111.247936) (xy 108.628942 -111.235236) (xy 108.578142 -111.235236)
			(xy 108.578142 -111.362236) (xy 108.628942 -111.362236)
		)
		(stroke
			(width 0)
			(type solid)
		)
		(fill yes)
		(layer "F.Cu")
		(net "M_K_DQ<33>")
	)
	(gr_poly
		(pts
			(xy 108.819442 -110.689136) (xy 108.819442 -110.587536) (xy 108.628942 -110.574836) (xy 108.578142 -110.574836)
			(xy 108.578142 -110.701836) (xy 108.628942 -110.701836)
		)
		(stroke
			(width 0)
			(type solid)
		)
		(fill yes)
		(layer "F.Cu")
		(net "M_K_DQ<33>")
	)
	(gr_poly
		(pts
			(xy 108.819442 -110.028736) (xy 108.819442 -109.927136) (xy 108.628942 -109.914436) (xy 108.578142 -109.914436)
			(xy 108.578142 -110.041436) (xy 108.628942 -110.041436)
		)
		(stroke
			(width 0)
			(type solid)
		)
		(fill yes)
		(layer "F.Cu")
		(net "M_K_DQ<33>")
	)
	(gr_poly
		(pts
			(xy 108.819442 -109.368336) (xy 108.819442 -109.266736) (xy 108.628942 -109.254036) (xy 108.578142 -109.254036)
			(xy 108.578142 -109.381036) (xy 108.628942 -109.381036)
		)
		(stroke
			(width 0)
			(type solid)
		)
		(fill yes)
		(layer "F.Cu")
		(net "M_K_DQ<33>")
	)
	(gr_poly
		(pts
			(xy 108.819442 -108.707936) (xy 108.819442 -108.606336) (xy 108.628942 -108.593636) (xy 108.578142 -108.593636)
			(xy 108.578142 -108.720636) (xy 108.628942 -108.720636)
		)
		(stroke
			(width 0)
			(type solid)
		)
		(fill yes)
		(layer "F.Cu")
		(net "M_K_DQ<33>")
	)
	(gr_poly
		(pts
			(xy 108.819442 -108.047536) (xy 108.819442 -107.945936) (xy 108.628942 -107.933236) (xy 108.578142 -107.933236)
			(xy 108.578142 -108.060236) (xy 108.628942 -108.060236)
		)
		(stroke
			(width 0)
			(type solid)
		)
		(fill yes)
		(layer "F.Cu")
		(net "M_K_DQ<33>")
	)
	(gr_poly
		(pts
			(xy 108.819442 -107.387136) (xy 108.819442 -107.285536) (xy 108.628942 -107.272836) (xy 108.578142 -107.272836)
			(xy 108.578142 -107.399836) (xy 108.628942 -107.399836)
		)
		(stroke
			(width 0)
			(type solid)
		)
		(fill yes)
		(layer "F.Cu")
		(net "M_K_DQ<33>")
	)
	(gr_poly
		(pts
			(xy 108.832142 -49.091088) (xy 108.832142 -48.989488) (xy 108.641642 -48.976788) (xy 108.590842 -48.976788)
			(xy 108.590842 -49.103788) (xy 108.641642 -49.103788)
		)
		(stroke
			(width 0)
			(type solid)
		)
		(fill yes)
		(layer "F.Cu")
		(net "M_G_DQS_DN<13>")
	)
	(gr_poly
		(pts
			(xy 108.832142 -48.430688) (xy 108.832142 -48.329088) (xy 108.641642 -48.316388) (xy 108.590842 -48.316388)
			(xy 108.590842 -48.443388) (xy 108.641642 -48.443388)
		)
		(stroke
			(width 0)
			(type solid)
		)
		(fill yes)
		(layer "F.Cu")
		(net "M_G_DQS_DN<13>")
	)
	(gr_poly
		(pts
			(xy 108.832142 -47.770288) (xy 108.832142 -47.668688) (xy 108.641642 -47.655988) (xy 108.590842 -47.655988)
			(xy 108.590842 -47.782988) (xy 108.641642 -47.782988)
		)
		(stroke
			(width 0)
			(type solid)
		)
		(fill yes)
		(layer "F.Cu")
		(net "M_G_DQS_DN<13>")
	)
	(gr_poly
		(pts
			(xy 108.832142 -47.109888) (xy 108.832142 -47.008288) (xy 108.641642 -46.995588) (xy 108.590842 -46.995588)
			(xy 108.590842 -47.122588) (xy 108.641642 -47.122588)
		)
		(stroke
			(width 0)
			(type solid)
		)
		(fill yes)
		(layer "F.Cu")
		(net "M_G_DQS_DN<13>")
	)
	(gr_poly
		(pts
			(xy 108.832142 -46.449488) (xy 108.832142 -46.347888) (xy 108.641642 -46.335188) (xy 108.590842 -46.335188)
			(xy 108.590842 -46.462188) (xy 108.641642 -46.462188)
		)
		(stroke
			(width 0)
			(type solid)
		)
		(fill yes)
		(layer "F.Cu")
		(net "M_G_DQS_DN<13>")
	)
	(gr_poly
		(pts
			(xy 108.832142 -45.789088) (xy 108.832142 -45.687488) (xy 108.641642 -45.674788) (xy 108.590842 -45.674788)
			(xy 108.590842 -45.801788) (xy 108.641642 -45.801788)
		)
		(stroke
			(width 0)
			(type solid)
		)
		(fill yes)
		(layer "F.Cu")
		(net "M_G_DQS_DN<13>")
	)
	(gr_poly
		(pts
			(xy 108.832142 -45.128688) (xy 108.832142 -45.027088) (xy 108.641642 -45.014388) (xy 108.590842 -45.014388)
			(xy 108.590842 -45.141388) (xy 108.641642 -45.141388)
		)
		(stroke
			(width 0)
			(type solid)
		)
		(fill yes)
		(layer "F.Cu")
		(net "M_G_DQS_DN<13>")
	)
	(gr_poly
		(pts
			(xy 108.832142 -44.468288) (xy 108.832142 -44.366688) (xy 108.641642 -44.353988) (xy 108.590842 -44.353988)
			(xy 108.590842 -44.480988) (xy 108.641642 -44.480988)
		)
		(stroke
			(width 0)
			(type solid)
		)
		(fill yes)
		(layer "F.Cu")
		(net "M_G_DQS_DN<13>")
	)
	(gr_poly
		(pts
			(xy 108.832142 -43.807888) (xy 108.832142 -43.706288) (xy 108.641642 -43.693588) (xy 108.590842 -43.693588)
			(xy 108.590842 -43.820588) (xy 108.641642 -43.820588)
		)
		(stroke
			(width 0)
			(type solid)
		)
		(fill yes)
		(layer "F.Cu")
		(net "M_G_DQS_DN<13>")
	)
	(gr_poly
		(pts
			(xy 108.832142 -43.147488) (xy 108.832142 -43.045888) (xy 108.641642 -43.033188) (xy 108.590842 -43.033188)
			(xy 108.590842 -43.160188) (xy 108.641642 -43.160188)
		)
		(stroke
			(width 0)
			(type solid)
		)
		(fill yes)
		(layer "F.Cu")
		(net "M_G_DQS_DN<13>")
	)
	(gr_poly
		(pts
			(xy 108.832142 -42.487088) (xy 108.832142 -42.385488) (xy 108.641642 -42.372788) (xy 108.590842 -42.372788)
			(xy 108.590842 -42.499788) (xy 108.641642 -42.499788)
		)
		(stroke
			(width 0)
			(type solid)
		)
		(fill yes)
		(layer "F.Cu")
		(net "M_G_DQS_DN<13>")
	)
	(gr_poly
		(pts
			(xy 108.877608 -104.21747) (xy 108.846112 -104.186228) (xy 108.646722 -104.112568) (xy 108.485178 -104.274112)
			(xy 108.558838 -104.473502) (xy 108.59008 -104.504998)
		)
		(stroke
			(width 0)
			(type solid)
		)
		(fill yes)
		(layer "F.Cu")
		(net "M_K_DQ<32>")
	)
	(gr_poly
		(pts
			(xy 108.971842 -111.565436) (xy 108.921042 -111.565436) (xy 108.730542 -111.578136) (xy 108.730542 -111.679736)
			(xy 108.921042 -111.692436) (xy 108.971842 -111.692436)
		)
		(stroke
			(width 0)
			(type solid)
		)
		(fill yes)
		(layer "F.Cu")
		(net "M_K_DQS_DP<13>")
	)
	(gr_poly
		(pts
			(xy 108.971842 -110.905036) (xy 108.921042 -110.905036) (xy 108.730542 -110.917736) (xy 108.730542 -111.019336)
			(xy 108.921042 -111.032036) (xy 108.971842 -111.032036)
		)
		(stroke
			(width 0)
			(type solid)
		)
		(fill yes)
		(layer "F.Cu")
		(net "M_K_DQS_DP<13>")
	)
	(gr_poly
		(pts
			(xy 108.971842 -110.244636) (xy 108.921042 -110.244636) (xy 108.730542 -110.257336) (xy 108.730542 -110.358936)
			(xy 108.921042 -110.371636) (xy 108.971842 -110.371636)
		)
		(stroke
			(width 0)
			(type solid)
		)
		(fill yes)
		(layer "F.Cu")
		(net "M_K_DQS_DP<13>")
	)
	(gr_poly
		(pts
			(xy 108.971842 -109.584236) (xy 108.921042 -109.584236) (xy 108.730542 -109.596936) (xy 108.730542 -109.698536)
			(xy 108.921042 -109.711236) (xy 108.971842 -109.711236)
		)
		(stroke
			(width 0)
			(type solid)
		)
		(fill yes)
		(layer "F.Cu")
		(net "M_K_DQS_DP<13>")
	)
	(gr_poly
		(pts
			(xy 108.971842 -108.923836) (xy 108.921042 -108.923836) (xy 108.730542 -108.936536) (xy 108.730542 -109.038136)
			(xy 108.921042 -109.050836) (xy 108.971842 -109.050836)
		)
		(stroke
			(width 0)
			(type solid)
		)
		(fill yes)
		(layer "F.Cu")
		(net "M_K_DQS_DP<13>")
	)
	(gr_poly
		(pts
			(xy 108.971842 -108.263436) (xy 108.921042 -108.263436) (xy 108.730542 -108.276136) (xy 108.730542 -108.377736)
			(xy 108.921042 -108.390436) (xy 108.971842 -108.390436)
		)
		(stroke
			(width 0)
			(type solid)
		)
		(fill yes)
		(layer "F.Cu")
		(net "M_K_DQS_DP<13>")
	)
	(gr_poly
		(pts
			(xy 108.971842 -107.603036) (xy 108.921042 -107.603036) (xy 108.730542 -107.615736) (xy 108.730542 -107.717336)
			(xy 108.921042 -107.730036) (xy 108.971842 -107.730036)
		)
		(stroke
			(width 0)
			(type solid)
		)
		(fill yes)
		(layer "F.Cu")
		(net "M_K_DQS_DP<13>")
	)
	(gr_poly
		(pts
			(xy 108.971842 -106.942636) (xy 108.921042 -106.942636) (xy 108.730542 -106.955336) (xy 108.730542 -107.056936)
			(xy 108.921042 -107.069636) (xy 108.971842 -107.069636)
		)
		(stroke
			(width 0)
			(type solid)
		)
		(fill yes)
		(layer "F.Cu")
		(net "M_K_DQS_DP<13>")
	)
	(gr_poly
		(pts
			(xy 108.984542 -49.306988) (xy 108.933742 -49.306988) (xy 108.743242 -49.319688) (xy 108.743242 -49.421288)
			(xy 108.933742 -49.433988) (xy 108.984542 -49.433988)
		)
		(stroke
			(width 0)
			(type solid)
		)
		(fill yes)
		(layer "F.Cu")
		(net "M_G_DQS_DN<4>")
	)
	(gr_poly
		(pts
			(xy 108.984542 -48.646588) (xy 108.933742 -48.646588) (xy 108.743242 -48.659288) (xy 108.743242 -48.760888)
			(xy 108.933742 -48.773588) (xy 108.984542 -48.773588)
		)
		(stroke
			(width 0)
			(type solid)
		)
		(fill yes)
		(layer "F.Cu")
		(net "M_G_DQS_DN<4>")
	)
	(gr_poly
		(pts
			(xy 108.984542 -47.986188) (xy 108.933742 -47.986188) (xy 108.743242 -47.998888) (xy 108.743242 -48.100488)
			(xy 108.933742 -48.113188) (xy 108.984542 -48.113188)
		)
		(stroke
			(width 0)
			(type solid)
		)
		(fill yes)
		(layer "F.Cu")
		(net "M_G_DQS_DN<4>")
	)
	(gr_poly
		(pts
			(xy 108.984542 -47.325788) (xy 108.933742 -47.325788) (xy 108.743242 -47.338488) (xy 108.743242 -47.440088)
			(xy 108.933742 -47.452788) (xy 108.984542 -47.452788)
		)
		(stroke
			(width 0)
			(type solid)
		)
		(fill yes)
		(layer "F.Cu")
		(net "M_G_DQS_DN<4>")
	)
	(gr_poly
		(pts
			(xy 108.984542 -46.665388) (xy 108.933742 -46.665388) (xy 108.743242 -46.678088) (xy 108.743242 -46.779688)
			(xy 108.933742 -46.792388) (xy 108.984542 -46.792388)
		)
		(stroke
			(width 0)
			(type solid)
		)
		(fill yes)
		(layer "F.Cu")
		(net "M_G_DQS_DN<4>")
	)
	(gr_poly
		(pts
			(xy 108.984542 -46.004988) (xy 108.933742 -46.004988) (xy 108.743242 -46.017688) (xy 108.743242 -46.119288)
			(xy 108.933742 -46.131988) (xy 108.984542 -46.131988)
		)
		(stroke
			(width 0)
			(type solid)
		)
		(fill yes)
		(layer "F.Cu")
		(net "M_G_DQS_DN<4>")
	)
	(gr_poly
		(pts
			(xy 108.984542 -45.344588) (xy 108.933742 -45.344588) (xy 108.743242 -45.357288) (xy 108.743242 -45.458888)
			(xy 108.933742 -45.471588) (xy 108.984542 -45.471588)
		)
		(stroke
			(width 0)
			(type solid)
		)
		(fill yes)
		(layer "F.Cu")
		(net "M_G_DQS_DN<4>")
	)
	(gr_poly
		(pts
			(xy 108.984542 -44.684188) (xy 108.933742 -44.684188) (xy 108.743242 -44.696888) (xy 108.743242 -44.798488)
			(xy 108.933742 -44.811188) (xy 108.984542 -44.811188)
		)
		(stroke
			(width 0)
			(type solid)
		)
		(fill yes)
		(layer "F.Cu")
		(net "M_G_DQS_DN<4>")
	)
	(gr_poly
		(pts
			(xy 108.984542 -44.023788) (xy 108.933742 -44.023788) (xy 108.743242 -44.036488) (xy 108.743242 -44.138088)
			(xy 108.933742 -44.150788) (xy 108.984542 -44.150788)
		)
		(stroke
			(width 0)
			(type solid)
		)
		(fill yes)
		(layer "F.Cu")
		(net "M_G_DQS_DN<4>")
	)
	(gr_poly
		(pts
			(xy 108.984542 -43.363388) (xy 108.933742 -43.363388) (xy 108.743242 -43.376088) (xy 108.743242 -43.477688)
			(xy 108.933742 -43.490388) (xy 108.984542 -43.490388)
		)
		(stroke
			(width 0)
			(type solid)
		)
		(fill yes)
		(layer "F.Cu")
		(net "M_G_DQS_DN<4>")
	)
	(gr_poly
		(pts
			(xy 108.984542 -42.702988) (xy 108.933742 -42.702988) (xy 108.743242 -42.715688) (xy 108.743242 -42.817288)
			(xy 108.933742 -42.829988) (xy 108.984542 -42.829988)
		)
		(stroke
			(width 0)
			(type solid)
		)
		(fill yes)
		(layer "F.Cu")
		(net "M_G_DQS_DN<4>")
	)
	(gr_poly
		(pts
			(xy 108.984542 -42.042588) (xy 108.933742 -42.042588) (xy 108.743242 -42.055288) (xy 108.743242 -42.156888)
			(xy 108.933742 -42.169588) (xy 108.984542 -42.169588)
		)
		(stroke
			(width 0)
			(type solid)
		)
		(fill yes)
		(layer "F.Cu")
		(net "M_G_DQS_DN<4>")
	)
	(gr_poly
		(pts
			(xy 109.073442 -105.64622) (xy 109.028992 -105.64622) (xy 108.835952 -105.73512) (xy 108.835952 -105.96372)
			(xy 109.028992 -106.05262) (xy 109.073442 -106.05262)
		)
		(stroke
			(width 0)
			(type solid)
		)
		(fill yes)
		(layer "F.Cu")
		(net "M_K_DQS_DP<13>")
	)
	(gr_poly
		(pts
			(xy 109.117384 -104.58323) (xy 109.043724 -104.38384) (xy 109.012482 -104.352344) (xy 108.724954 -104.639872)
			(xy 108.75645 -104.671114) (xy 108.95584 -104.744774)
		)
		(stroke
			(width 0)
			(type solid)
		)
		(fill yes)
		(layer "F.Cu")
		(net "M_K_DQ<33>")
	)
	(gr_poly
		(pts
			(xy 109.181646 -102.33533) (xy 109.137196 -102.33533) (xy 108.944156 -102.42423) (xy 108.944156 -102.65283)
			(xy 109.137196 -102.74173) (xy 109.181646 -102.74173)
		)
		(stroke
			(width 0)
			(type solid)
		)
		(fill yes)
		(layer "F.Cu")
		(net "M_K_DQ<32>")
	)
	(gr_poly
		(pts
			(xy 109.213142 -111.349536) (xy 109.213142 -111.247936) (xy 109.022642 -111.235236) (xy 108.971842 -111.235236)
			(xy 108.971842 -111.362236) (xy 109.022642 -111.362236)
		)
		(stroke
			(width 0)
			(type solid)
		)
		(fill yes)
		(layer "F.Cu")
		(net "M_K_DQS_DP<13>")
	)
	(gr_poly
		(pts
			(xy 109.213142 -110.689136) (xy 109.213142 -110.587536) (xy 109.022642 -110.574836) (xy 108.971842 -110.574836)
			(xy 108.971842 -110.701836) (xy 109.022642 -110.701836)
		)
		(stroke
			(width 0)
			(type solid)
		)
		(fill yes)
		(layer "F.Cu")
		(net "M_K_DQS_DP<13>")
	)
	(gr_poly
		(pts
			(xy 109.213142 -110.028736) (xy 109.213142 -109.927136) (xy 109.022642 -109.914436) (xy 108.971842 -109.914436)
			(xy 108.971842 -110.041436) (xy 109.022642 -110.041436)
		)
		(stroke
			(width 0)
			(type solid)
		)
		(fill yes)
		(layer "F.Cu")
		(net "M_K_DQS_DP<13>")
	)
	(gr_poly
		(pts
			(xy 109.213142 -109.368336) (xy 109.213142 -109.266736) (xy 109.022642 -109.254036) (xy 108.971842 -109.254036)
			(xy 108.971842 -109.381036) (xy 109.022642 -109.381036)
		)
		(stroke
			(width 0)
			(type solid)
		)
		(fill yes)
		(layer "F.Cu")
		(net "M_K_DQS_DP<13>")
	)
	(gr_poly
		(pts
			(xy 109.213142 -108.707936) (xy 109.213142 -108.606336) (xy 109.022642 -108.593636) (xy 108.971842 -108.593636)
			(xy 108.971842 -108.720636) (xy 109.022642 -108.720636)
		)
		(stroke
			(width 0)
			(type solid)
		)
		(fill yes)
		(layer "F.Cu")
		(net "M_K_DQS_DP<13>")
	)
	(gr_poly
		(pts
			(xy 109.213142 -108.047536) (xy 109.213142 -107.945936) (xy 109.022642 -107.933236) (xy 108.971842 -107.933236)
			(xy 108.971842 -108.060236) (xy 109.022642 -108.060236)
		)
		(stroke
			(width 0)
			(type solid)
		)
		(fill yes)
		(layer "F.Cu")
		(net "M_K_DQS_DP<13>")
	)
	(gr_poly
		(pts
			(xy 109.213142 -107.387136) (xy 109.213142 -107.285536) (xy 109.022642 -107.272836) (xy 108.971842 -107.272836)
			(xy 108.971842 -107.399836) (xy 109.022642 -107.399836)
		)
		(stroke
			(width 0)
			(type solid)
		)
		(fill yes)
		(layer "F.Cu")
		(net "M_K_DQS_DP<13>")
	)
	(gr_poly
		(pts
			(xy 109.225842 -49.091088) (xy 109.225842 -48.989488) (xy 109.035342 -48.976788) (xy 108.984542 -48.976788)
			(xy 108.984542 -49.103788) (xy 109.035342 -49.103788)
		)
		(stroke
			(width 0)
			(type solid)
		)
		(fill yes)
		(layer "F.Cu")
		(net "M_G_DQS_DN<4>")
	)
	(gr_poly
		(pts
			(xy 109.225842 -48.430688) (xy 109.225842 -48.329088) (xy 109.035342 -48.316388) (xy 108.984542 -48.316388)
			(xy 108.984542 -48.443388) (xy 109.035342 -48.443388)
		)
		(stroke
			(width 0)
			(type solid)
		)
		(fill yes)
		(layer "F.Cu")
		(net "M_G_DQS_DN<4>")
	)
	(gr_poly
		(pts
			(xy 109.225842 -47.770288) (xy 109.225842 -47.668688) (xy 109.035342 -47.655988) (xy 108.984542 -47.655988)
			(xy 108.984542 -47.782988) (xy 109.035342 -47.782988)
		)
		(stroke
			(width 0)
			(type solid)
		)
		(fill yes)
		(layer "F.Cu")
		(net "M_G_DQS_DN<4>")
	)
	(gr_poly
		(pts
			(xy 109.225842 -47.109888) (xy 109.225842 -47.008288) (xy 109.035342 -46.995588) (xy 108.984542 -46.995588)
			(xy 108.984542 -47.122588) (xy 109.035342 -47.122588)
		)
		(stroke
			(width 0)
			(type solid)
		)
		(fill yes)
		(layer "F.Cu")
		(net "M_G_DQS_DN<4>")
	)
	(gr_poly
		(pts
			(xy 109.225842 -46.449488) (xy 109.225842 -46.347888) (xy 109.035342 -46.335188) (xy 108.984542 -46.335188)
			(xy 108.984542 -46.462188) (xy 109.035342 -46.462188)
		)
		(stroke
			(width 0)
			(type solid)
		)
		(fill yes)
		(layer "F.Cu")
		(net "M_G_DQS_DN<4>")
	)
	(gr_poly
		(pts
			(xy 109.225842 -45.789088) (xy 109.225842 -45.687488) (xy 109.035342 -45.674788) (xy 108.984542 -45.674788)
			(xy 108.984542 -45.801788) (xy 109.035342 -45.801788)
		)
		(stroke
			(width 0)
			(type solid)
		)
		(fill yes)
		(layer "F.Cu")
		(net "M_G_DQS_DN<4>")
	)
	(gr_poly
		(pts
			(xy 109.225842 -45.128688) (xy 109.225842 -45.027088) (xy 109.035342 -45.014388) (xy 108.984542 -45.014388)
			(xy 108.984542 -45.141388) (xy 109.035342 -45.141388)
		)
		(stroke
			(width 0)
			(type solid)
		)
		(fill yes)
		(layer "F.Cu")
		(net "M_G_DQS_DN<4>")
	)
	(gr_poly
		(pts
			(xy 109.225842 -44.468288) (xy 109.225842 -44.366688) (xy 109.035342 -44.353988) (xy 108.984542 -44.353988)
			(xy 108.984542 -44.480988) (xy 109.035342 -44.480988)
		)
		(stroke
			(width 0)
			(type solid)
		)
		(fill yes)
		(layer "F.Cu")
		(net "M_G_DQS_DN<4>")
	)
	(gr_poly
		(pts
			(xy 109.225842 -43.807888) (xy 109.225842 -43.706288) (xy 109.035342 -43.693588) (xy 108.984542 -43.693588)
			(xy 108.984542 -43.820588) (xy 109.035342 -43.820588)
		)
		(stroke
			(width 0)
			(type solid)
		)
		(fill yes)
		(layer "F.Cu")
		(net "M_G_DQS_DN<4>")
	)
	(gr_poly
		(pts
			(xy 109.225842 -43.147488) (xy 109.225842 -43.045888) (xy 109.035342 -43.033188) (xy 108.984542 -43.033188)
			(xy 108.984542 -43.160188) (xy 109.035342 -43.160188)
		)
		(stroke
			(width 0)
			(type solid)
		)
		(fill yes)
		(layer "F.Cu")
		(net "M_G_DQS_DN<4>")
	)
	(gr_poly
		(pts
			(xy 109.225842 -42.487088) (xy 109.225842 -42.385488) (xy 109.035342 -42.372788) (xy 108.984542 -42.372788)
			(xy 108.984542 -42.499788) (xy 109.035342 -42.499788)
		)
		(stroke
			(width 0)
			(type solid)
		)
		(fill yes)
		(layer "F.Cu")
		(net "M_G_DQS_DN<4>")
	)
	(gr_poly
		(pts
			(xy 109.365542 -111.565436) (xy 109.314742 -111.565436) (xy 109.124242 -111.578136) (xy 109.124242 -111.679736)
			(xy 109.314742 -111.692436) (xy 109.365542 -111.692436)
		)
		(stroke
			(width 0)
			(type solid)
		)
		(fill yes)
		(layer "F.Cu")
		(net "M_K_DQS_DN<13>")
	)
	(gr_poly
		(pts
			(xy 109.365542 -110.905036) (xy 109.314742 -110.905036) (xy 109.124242 -110.917736) (xy 109.124242 -111.019336)
			(xy 109.314742 -111.032036) (xy 109.365542 -111.032036)
		)
		(stroke
			(width 0)
			(type solid)
		)
		(fill yes)
		(layer "F.Cu")
		(net "M_K_DQS_DN<13>")
	)
	(gr_poly
		(pts
			(xy 109.365542 -110.244636) (xy 109.314742 -110.244636) (xy 109.124242 -110.257336) (xy 109.124242 -110.358936)
			(xy 109.314742 -110.371636) (xy 109.365542 -110.371636)
		)
		(stroke
			(width 0)
			(type solid)
		)
		(fill yes)
		(layer "F.Cu")
		(net "M_K_DQS_DN<13>")
	)
	(gr_poly
		(pts
			(xy 109.365542 -109.584236) (xy 109.314742 -109.584236) (xy 109.124242 -109.596936) (xy 109.124242 -109.698536)
			(xy 109.314742 -109.711236) (xy 109.365542 -109.711236)
		)
		(stroke
			(width 0)
			(type solid)
		)
		(fill yes)
		(layer "F.Cu")
		(net "M_K_DQS_DN<13>")
	)
	(gr_poly
		(pts
			(xy 109.365542 -108.923836) (xy 109.314742 -108.923836) (xy 109.124242 -108.936536) (xy 109.124242 -109.038136)
			(xy 109.314742 -109.050836) (xy 109.365542 -109.050836)
		)
		(stroke
			(width 0)
			(type solid)
		)
		(fill yes)
		(layer "F.Cu")
		(net "M_K_DQS_DN<13>")
	)
	(gr_poly
		(pts
			(xy 109.365542 -108.263436) (xy 109.314742 -108.263436) (xy 109.124242 -108.276136) (xy 109.124242 -108.377736)
			(xy 109.314742 -108.390436) (xy 109.365542 -108.390436)
		)
		(stroke
			(width 0)
			(type solid)
		)
		(fill yes)
		(layer "F.Cu")
		(net "M_K_DQS_DN<13>")
	)
	(gr_poly
		(pts
			(xy 109.365542 -107.603036) (xy 109.314742 -107.603036) (xy 109.124242 -107.615736) (xy 109.124242 -107.717336)
			(xy 109.314742 -107.730036) (xy 109.365542 -107.730036)
		)
		(stroke
			(width 0)
			(type solid)
		)
		(fill yes)
		(layer "F.Cu")
		(net "M_K_DQS_DN<13>")
	)
	(gr_poly
		(pts
			(xy 109.365542 -106.942636) (xy 109.314742 -106.942636) (xy 109.124242 -106.955336) (xy 109.124242 -107.056936)
			(xy 109.314742 -107.069636) (xy 109.365542 -107.069636)
		)
		(stroke
			(width 0)
			(type solid)
		)
		(fill yes)
		(layer "F.Cu")
		(net "M_K_DQS_DN<13>")
	)
	(gr_poly
		(pts
			(xy 109.378242 -49.306988) (xy 109.327442 -49.306988) (xy 109.136942 -49.319688) (xy 109.136942 -49.421288)
			(xy 109.327442 -49.433988) (xy 109.378242 -49.433988)
		)
		(stroke
			(width 0)
			(type solid)
		)
		(fill yes)
		(layer "F.Cu")
		(net "M_G_DQS_DP<4>")
	)
	(gr_poly
		(pts
			(xy 109.378242 -48.646588) (xy 109.327442 -48.646588) (xy 109.136942 -48.659288) (xy 109.136942 -48.760888)
			(xy 109.327442 -48.773588) (xy 109.378242 -48.773588)
		)
		(stroke
			(width 0)
			(type solid)
		)
		(fill yes)
		(layer "F.Cu")
		(net "M_G_DQS_DP<4>")
	)
	(gr_poly
		(pts
			(xy 109.378242 -47.986188) (xy 109.327442 -47.986188) (xy 109.136942 -47.998888) (xy 109.136942 -48.100488)
			(xy 109.327442 -48.113188) (xy 109.378242 -48.113188)
		)
		(stroke
			(width 0)
			(type solid)
		)
		(fill yes)
		(layer "F.Cu")
		(net "M_G_DQS_DP<4>")
	)
	(gr_poly
		(pts
			(xy 109.378242 -47.325788) (xy 109.327442 -47.325788) (xy 109.136942 -47.338488) (xy 109.136942 -47.440088)
			(xy 109.327442 -47.452788) (xy 109.378242 -47.452788)
		)
		(stroke
			(width 0)
			(type solid)
		)
		(fill yes)
		(layer "F.Cu")
		(net "M_G_DQS_DP<4>")
	)
	(gr_poly
		(pts
			(xy 109.378242 -46.665388) (xy 109.327442 -46.665388) (xy 109.136942 -46.678088) (xy 109.136942 -46.779688)
			(xy 109.327442 -46.792388) (xy 109.378242 -46.792388)
		)
		(stroke
			(width 0)
			(type solid)
		)
		(fill yes)
		(layer "F.Cu")
		(net "M_G_DQS_DP<4>")
	)
	(gr_poly
		(pts
			(xy 109.378242 -46.004988) (xy 109.327442 -46.004988) (xy 109.136942 -46.017688) (xy 109.136942 -46.119288)
			(xy 109.327442 -46.131988) (xy 109.378242 -46.131988)
		)
		(stroke
			(width 0)
			(type solid)
		)
		(fill yes)
		(layer "F.Cu")
		(net "M_G_DQS_DP<4>")
	)
	(gr_poly
		(pts
			(xy 109.378242 -45.344588) (xy 109.327442 -45.344588) (xy 109.136942 -45.357288) (xy 109.136942 -45.458888)
			(xy 109.327442 -45.471588) (xy 109.378242 -45.471588)
		)
		(stroke
			(width 0)
			(type solid)
		)
		(fill yes)
		(layer "F.Cu")
		(net "M_G_DQS_DP<4>")
	)
	(gr_poly
		(pts
			(xy 109.378242 -44.684188) (xy 109.327442 -44.684188) (xy 109.136942 -44.696888) (xy 109.136942 -44.798488)
			(xy 109.327442 -44.811188) (xy 109.378242 -44.811188)
		)
		(stroke
			(width 0)
			(type solid)
		)
		(fill yes)
		(layer "F.Cu")
		(net "M_G_DQS_DP<4>")
	)
	(gr_poly
		(pts
			(xy 109.378242 -44.023788) (xy 109.327442 -44.023788) (xy 109.136942 -44.036488) (xy 109.136942 -44.138088)
			(xy 109.327442 -44.150788) (xy 109.378242 -44.150788)
		)
		(stroke
			(width 0)
			(type solid)
		)
		(fill yes)
		(layer "F.Cu")
		(net "M_G_DQS_DP<4>")
	)
	(gr_poly
		(pts
			(xy 109.378242 -43.363388) (xy 109.327442 -43.363388) (xy 109.136942 -43.376088) (xy 109.136942 -43.477688)
			(xy 109.327442 -43.490388) (xy 109.378242 -43.490388)
		)
		(stroke
			(width 0)
			(type solid)
		)
		(fill yes)
		(layer "F.Cu")
		(net "M_G_DQS_DP<4>")
	)
	(gr_poly
		(pts
			(xy 109.378242 -42.702988) (xy 109.327442 -42.702988) (xy 109.136942 -42.715688) (xy 109.136942 -42.817288)
			(xy 109.327442 -42.829988) (xy 109.378242 -42.829988)
		)
		(stroke
			(width 0)
			(type solid)
		)
		(fill yes)
		(layer "F.Cu")
		(net "M_G_DQS_DP<4>")
	)
	(gr_poly
		(pts
			(xy 109.378242 -42.042588) (xy 109.327442 -42.042588) (xy 109.136942 -42.055288) (xy 109.136942 -42.156888)
			(xy 109.327442 -42.169588) (xy 109.378242 -42.169588)
		)
		(stroke
			(width 0)
			(type solid)
		)
		(fill yes)
		(layer "F.Cu")
		(net "M_G_DQS_DP<4>")
	)
	(gr_poly
		(pts
			(xy 109.501432 -105.96372) (xy 109.501432 -105.73512) (xy 109.308392 -105.64622) (xy 109.263942 -105.64622)
			(xy 109.263942 -106.05262) (xy 109.308392 -106.05262)
		)
		(stroke
			(width 0)
			(type solid)
		)
		(fill yes)
		(layer "F.Cu")
		(net "M_K_DQS_DN<13>")
	)
	(gr_poly
		(pts
			(xy 109.606842 -111.349536) (xy 109.606842 -111.247936) (xy 109.416342 -111.235236) (xy 109.365542 -111.235236)
			(xy 109.365542 -111.362236) (xy 109.416342 -111.362236)
		)
		(stroke
			(width 0)
			(type solid)
		)
		(fill yes)
		(layer "F.Cu")
		(net "M_K_DQS_DN<13>")
	)
	(gr_poly
		(pts
			(xy 109.606842 -110.689136) (xy 109.606842 -110.587536) (xy 109.416342 -110.574836) (xy 109.365542 -110.574836)
			(xy 109.365542 -110.701836) (xy 109.416342 -110.701836)
		)
		(stroke
			(width 0)
			(type solid)
		)
		(fill yes)
		(layer "F.Cu")
		(net "M_K_DQS_DN<13>")
	)
	(gr_poly
		(pts
			(xy 109.606842 -110.028736) (xy 109.606842 -109.927136) (xy 109.416342 -109.914436) (xy 109.365542 -109.914436)
			(xy 109.365542 -110.041436) (xy 109.416342 -110.041436)
		)
		(stroke
			(width 0)
			(type solid)
		)
		(fill yes)
		(layer "F.Cu")
		(net "M_K_DQS_DN<13>")
	)
	(gr_poly
		(pts
			(xy 109.606842 -109.368336) (xy 109.606842 -109.266736) (xy 109.416342 -109.254036) (xy 109.365542 -109.254036)
			(xy 109.365542 -109.381036) (xy 109.416342 -109.381036)
		)
		(stroke
			(width 0)
			(type solid)
		)
		(fill yes)
		(layer "F.Cu")
		(net "M_K_DQS_DN<13>")
	)
	(gr_poly
		(pts
			(xy 109.606842 -108.707936) (xy 109.606842 -108.606336) (xy 109.416342 -108.593636) (xy 109.365542 -108.593636)
			(xy 109.365542 -108.720636) (xy 109.416342 -108.720636)
		)
		(stroke
			(width 0)
			(type solid)
		)
		(fill yes)
		(layer "F.Cu")
		(net "M_K_DQS_DN<13>")
	)
	(gr_poly
		(pts
			(xy 109.606842 -108.047536) (xy 109.606842 -107.945936) (xy 109.416342 -107.933236) (xy 109.365542 -107.933236)
			(xy 109.365542 -108.060236) (xy 109.416342 -108.060236)
		)
		(stroke
			(width 0)
			(type solid)
		)
		(fill yes)
		(layer "F.Cu")
		(net "M_K_DQS_DN<13>")
	)
	(gr_poly
		(pts
			(xy 109.606842 -107.387136) (xy 109.606842 -107.285536) (xy 109.416342 -107.272836) (xy 109.365542 -107.272836)
			(xy 109.365542 -107.399836) (xy 109.416342 -107.399836)
		)
		(stroke
			(width 0)
			(type solid)
		)
		(fill yes)
		(layer "F.Cu")
		(net "M_K_DQS_DN<13>")
	)
	(gr_poly
		(pts
			(xy 109.609636 -103.41483) (xy 109.609636 -103.18623) (xy 109.416596 -103.09733) (xy 109.372146 -103.09733)
			(xy 109.372146 -103.50373) (xy 109.416596 -103.50373)
		)
		(stroke
			(width 0)
			(type solid)
		)
		(fill yes)
		(layer "F.Cu")
		(net "M_K_DQ<33>")
	)
	(gr_poly
		(pts
			(xy 109.619542 -49.091088) (xy 109.619542 -48.989488) (xy 109.429042 -48.976788) (xy 109.378242 -48.976788)
			(xy 109.378242 -49.103788) (xy 109.429042 -49.103788)
		)
		(stroke
			(width 0)
			(type solid)
		)
		(fill yes)
		(layer "F.Cu")
		(net "M_G_DQS_DP<4>")
	)
	(gr_poly
		(pts
			(xy 109.619542 -48.430688) (xy 109.619542 -48.329088) (xy 109.429042 -48.316388) (xy 109.378242 -48.316388)
			(xy 109.378242 -48.443388) (xy 109.429042 -48.443388)
		)
		(stroke
			(width 0)
			(type solid)
		)
		(fill yes)
		(layer "F.Cu")
		(net "M_G_DQS_DP<4>")
	)
	(gr_poly
		(pts
			(xy 109.619542 -47.770288) (xy 109.619542 -47.668688) (xy 109.429042 -47.655988) (xy 109.378242 -47.655988)
			(xy 109.378242 -47.782988) (xy 109.429042 -47.782988)
		)
		(stroke
			(width 0)
			(type solid)
		)
		(fill yes)
		(layer "F.Cu")
		(net "M_G_DQS_DP<4>")
	)
	(gr_poly
		(pts
			(xy 109.619542 -47.109888) (xy 109.619542 -47.008288) (xy 109.429042 -46.995588) (xy 109.378242 -46.995588)
			(xy 109.378242 -47.122588) (xy 109.429042 -47.122588)
		)
		(stroke
			(width 0)
			(type solid)
		)
		(fill yes)
		(layer "F.Cu")
		(net "M_G_DQS_DP<4>")
	)
	(gr_poly
		(pts
			(xy 109.619542 -46.449488) (xy 109.619542 -46.347888) (xy 109.429042 -46.335188) (xy 109.378242 -46.335188)
			(xy 109.378242 -46.462188) (xy 109.429042 -46.462188)
		)
		(stroke
			(width 0)
			(type solid)
		)
		(fill yes)
		(layer "F.Cu")
		(net "M_G_DQS_DP<4>")
	)
	(gr_poly
		(pts
			(xy 109.619542 -45.789088) (xy 109.619542 -45.687488) (xy 109.429042 -45.674788) (xy 109.378242 -45.674788)
			(xy 109.378242 -45.801788) (xy 109.429042 -45.801788)
		)
		(stroke
			(width 0)
			(type solid)
		)
		(fill yes)
		(layer "F.Cu")
		(net "M_G_DQS_DP<4>")
	)
	(gr_poly
		(pts
			(xy 109.619542 -45.128688) (xy 109.619542 -45.027088) (xy 109.429042 -45.014388) (xy 109.378242 -45.014388)
			(xy 109.378242 -45.141388) (xy 109.429042 -45.141388)
		)
		(stroke
			(width 0)
			(type solid)
		)
		(fill yes)
		(layer "F.Cu")
		(net "M_G_DQS_DP<4>")
	)
	(gr_poly
		(pts
			(xy 109.619542 -44.468288) (xy 109.619542 -44.366688) (xy 109.429042 -44.353988) (xy 109.378242 -44.353988)
			(xy 109.378242 -44.480988) (xy 109.429042 -44.480988)
		)
		(stroke
			(width 0)
			(type solid)
		)
		(fill yes)
		(layer "F.Cu")
		(net "M_G_DQS_DP<4>")
	)
	(gr_poly
		(pts
			(xy 109.619542 -43.807888) (xy 109.619542 -43.706288) (xy 109.429042 -43.693588) (xy 109.378242 -43.693588)
			(xy 109.378242 -43.820588) (xy 109.429042 -43.820588)
		)
		(stroke
			(width 0)
			(type solid)
		)
		(fill yes)
		(layer "F.Cu")
		(net "M_G_DQS_DP<4>")
	)
	(gr_poly
		(pts
			(xy 109.619542 -43.147488) (xy 109.619542 -43.045888) (xy 109.429042 -43.033188) (xy 109.378242 -43.033188)
			(xy 109.378242 -43.160188) (xy 109.429042 -43.160188)
		)
		(stroke
			(width 0)
			(type solid)
		)
		(fill yes)
		(layer "F.Cu")
		(net "M_G_DQS_DP<4>")
	)
	(gr_poly
		(pts
			(xy 109.619542 -42.487088) (xy 109.619542 -42.385488) (xy 109.429042 -42.372788) (xy 109.378242 -42.372788)
			(xy 109.378242 -42.499788) (xy 109.429042 -42.499788)
		)
		(stroke
			(width 0)
			(type solid)
		)
		(fill yes)
		(layer "F.Cu")
		(net "M_G_DQS_DP<4>")
	)
	(gr_poly
		(pts
			(xy 109.687614 -104.533446) (xy 109.656118 -104.502204) (xy 109.456728 -104.428544) (xy 109.295184 -104.590088)
			(xy 109.368844 -104.789478) (xy 109.400086 -104.820974)
		)
		(stroke
			(width 0)
			(type solid)
		)
		(fill yes)
		(layer "F.Cu")
		(net "M_K_DQS_DP<13>")
	)
	(gr_poly
		(pts
			(xy 109.759242 -111.565436) (xy 109.708442 -111.565436) (xy 109.517942 -111.578136) (xy 109.517942 -111.679736)
			(xy 109.708442 -111.692436) (xy 109.759242 -111.692436)
		)
		(stroke
			(width 0)
			(type solid)
		)
		(fill yes)
		(layer "F.Cu")
		(net "M_K_DQS_DN<4>")
	)
	(gr_poly
		(pts
			(xy 109.759242 -110.905036) (xy 109.708442 -110.905036) (xy 109.517942 -110.917736) (xy 109.517942 -111.019336)
			(xy 109.708442 -111.032036) (xy 109.759242 -111.032036)
		)
		(stroke
			(width 0)
			(type solid)
		)
		(fill yes)
		(layer "F.Cu")
		(net "M_K_DQS_DN<4>")
	)
	(gr_poly
		(pts
			(xy 109.759242 -110.244636) (xy 109.708442 -110.244636) (xy 109.517942 -110.257336) (xy 109.517942 -110.358936)
			(xy 109.708442 -110.371636) (xy 109.759242 -110.371636)
		)
		(stroke
			(width 0)
			(type solid)
		)
		(fill yes)
		(layer "F.Cu")
		(net "M_K_DQS_DN<4>")
	)
	(gr_poly
		(pts
			(xy 109.759242 -109.584236) (xy 109.708442 -109.584236) (xy 109.517942 -109.596936) (xy 109.517942 -109.698536)
			(xy 109.708442 -109.711236) (xy 109.759242 -109.711236)
		)
		(stroke
			(width 0)
			(type solid)
		)
		(fill yes)
		(layer "F.Cu")
		(net "M_K_DQS_DN<4>")
	)
	(gr_poly
		(pts
			(xy 109.759242 -108.923836) (xy 109.708442 -108.923836) (xy 109.517942 -108.936536) (xy 109.517942 -109.038136)
			(xy 109.708442 -109.050836) (xy 109.759242 -109.050836)
		)
		(stroke
			(width 0)
			(type solid)
		)
		(fill yes)
		(layer "F.Cu")
		(net "M_K_DQS_DN<4>")
	)
	(gr_poly
		(pts
			(xy 109.759242 -108.263436) (xy 109.708442 -108.263436) (xy 109.517942 -108.276136) (xy 109.517942 -108.377736)
			(xy 109.708442 -108.390436) (xy 109.759242 -108.390436)
		)
		(stroke
			(width 0)
			(type solid)
		)
		(fill yes)
		(layer "F.Cu")
		(net "M_K_DQS_DN<4>")
	)
	(gr_poly
		(pts
			(xy 109.759242 -107.603036) (xy 109.708442 -107.603036) (xy 109.517942 -107.615736) (xy 109.517942 -107.717336)
			(xy 109.708442 -107.730036) (xy 109.759242 -107.730036)
		)
		(stroke
			(width 0)
			(type solid)
		)
		(fill yes)
		(layer "F.Cu")
		(net "M_K_DQS_DN<4>")
	)
	(gr_poly
		(pts
			(xy 109.759242 -106.942636) (xy 109.708442 -106.942636) (xy 109.517942 -106.955336) (xy 109.517942 -107.056936)
			(xy 109.708442 -107.069636) (xy 109.759242 -107.069636)
		)
		(stroke
			(width 0)
			(type solid)
		)
		(fill yes)
		(layer "F.Cu")
		(net "M_K_DQS_DN<4>")
	)
	(gr_poly
		(pts
			(xy 109.771942 -49.306988) (xy 109.721142 -49.306988) (xy 109.530642 -49.319688) (xy 109.530642 -49.421288)
			(xy 109.721142 -49.433988) (xy 109.771942 -49.433988)
		)
		(stroke
			(width 0)
			(type solid)
		)
		(fill yes)
		(layer "F.Cu")
		(net "M_G_DQ<38>")
	)
	(gr_poly
		(pts
			(xy 109.771942 -48.646588) (xy 109.721142 -48.646588) (xy 109.530642 -48.659288) (xy 109.530642 -48.760888)
			(xy 109.721142 -48.773588) (xy 109.771942 -48.773588)
		)
		(stroke
			(width 0)
			(type solid)
		)
		(fill yes)
		(layer "F.Cu")
		(net "M_G_DQ<38>")
	)
	(gr_poly
		(pts
			(xy 109.771942 -47.986188) (xy 109.721142 -47.986188) (xy 109.530642 -47.998888) (xy 109.530642 -48.100488)
			(xy 109.721142 -48.113188) (xy 109.771942 -48.113188)
		)
		(stroke
			(width 0)
			(type solid)
		)
		(fill yes)
		(layer "F.Cu")
		(net "M_G_DQ<38>")
	)
	(gr_poly
		(pts
			(xy 109.771942 -47.325788) (xy 109.721142 -47.325788) (xy 109.530642 -47.338488) (xy 109.530642 -47.440088)
			(xy 109.721142 -47.452788) (xy 109.771942 -47.452788)
		)
		(stroke
			(width 0)
			(type solid)
		)
		(fill yes)
		(layer "F.Cu")
		(net "M_G_DQ<38>")
	)
	(gr_poly
		(pts
			(xy 109.771942 -46.665388) (xy 109.721142 -46.665388) (xy 109.530642 -46.678088) (xy 109.530642 -46.779688)
			(xy 109.721142 -46.792388) (xy 109.771942 -46.792388)
		)
		(stroke
			(width 0)
			(type solid)
		)
		(fill yes)
		(layer "F.Cu")
		(net "M_G_DQ<38>")
	)
	(gr_poly
		(pts
			(xy 109.771942 -46.004988) (xy 109.721142 -46.004988) (xy 109.530642 -46.017688) (xy 109.530642 -46.119288)
			(xy 109.721142 -46.131988) (xy 109.771942 -46.131988)
		)
		(stroke
			(width 0)
			(type solid)
		)
		(fill yes)
		(layer "F.Cu")
		(net "M_G_DQ<38>")
	)
	(gr_poly
		(pts
			(xy 109.771942 -45.344588) (xy 109.721142 -45.344588) (xy 109.530642 -45.357288) (xy 109.530642 -45.458888)
			(xy 109.721142 -45.471588) (xy 109.771942 -45.471588)
		)
		(stroke
			(width 0)
			(type solid)
		)
		(fill yes)
		(layer "F.Cu")
		(net "M_G_DQ<38>")
	)
	(gr_poly
		(pts
			(xy 109.771942 -44.684188) (xy 109.721142 -44.684188) (xy 109.530642 -44.696888) (xy 109.530642 -44.798488)
			(xy 109.721142 -44.811188) (xy 109.771942 -44.811188)
		)
		(stroke
			(width 0)
			(type solid)
		)
		(fill yes)
		(layer "F.Cu")
		(net "M_G_DQ<38>")
	)
	(gr_poly
		(pts
			(xy 109.771942 -44.023788) (xy 109.721142 -44.023788) (xy 109.530642 -44.036488) (xy 109.530642 -44.138088)
			(xy 109.721142 -44.150788) (xy 109.771942 -44.150788)
		)
		(stroke
			(width 0)
			(type solid)
		)
		(fill yes)
		(layer "F.Cu")
		(net "M_G_DQ<38>")
	)
	(gr_poly
		(pts
			(xy 109.771942 -43.363388) (xy 109.721142 -43.363388) (xy 109.530642 -43.376088) (xy 109.530642 -43.477688)
			(xy 109.721142 -43.490388) (xy 109.771942 -43.490388)
		)
		(stroke
			(width 0)
			(type solid)
		)
		(fill yes)
		(layer "F.Cu")
		(net "M_G_DQ<38>")
	)
	(gr_poly
		(pts
			(xy 109.771942 -42.702988) (xy 109.721142 -42.702988) (xy 109.530642 -42.715688) (xy 109.530642 -42.817288)
			(xy 109.721142 -42.829988) (xy 109.771942 -42.829988)
		)
		(stroke
			(width 0)
			(type solid)
		)
		(fill yes)
		(layer "F.Cu")
		(net "M_G_DQ<38>")
	)
	(gr_poly
		(pts
			(xy 109.771942 -42.042588) (xy 109.721142 -42.042588) (xy 109.530642 -42.055288) (xy 109.530642 -42.156888)
			(xy 109.721142 -42.169588) (xy 109.771942 -42.169588)
		)
		(stroke
			(width 0)
			(type solid)
		)
		(fill yes)
		(layer "F.Cu")
		(net "M_G_DQ<38>")
	)
	(gr_poly
		(pts
			(xy 109.860842 -105.79862) (xy 109.816392 -105.79862) (xy 109.623352 -105.88752) (xy 109.623352 -106.11612)
			(xy 109.816392 -106.20502) (xy 109.860842 -106.20502)
		)
		(stroke
			(width 0)
			(type solid)
		)
		(fill yes)
		(layer "F.Cu")
		(net "M_K_DQS_DN<4>")
	)
	(gr_poly
		(pts
			(xy 109.894624 -101.761798) (xy 109.850174 -101.761798) (xy 109.679994 -101.850698) (xy 109.679994 -102.071678)
			(xy 109.850174 -102.160578) (xy 109.894624 -102.160578)
		)
		(stroke
			(width 0)
			(type solid)
		)
		(fill yes)
		(layer "F.Cu")
		(net "M_K_DQS_DP<13>")
	)
	(gr_poly
		(pts
			(xy 109.902752 -103.459534) (xy 109.858302 -103.459534) (xy 109.665262 -103.548434) (xy 109.665262 -103.777034)
			(xy 109.858302 -103.865934) (xy 109.902752 -103.865934)
		)
		(stroke
			(width 0)
			(type solid)
		)
		(fill yes)
		(layer "F.Cu")
		(net "M_K_DQS_DP<13>")
	)
	(gr_poly
		(pts
			(xy 109.916468 -101.184202) (xy 109.881924 -100.7872) (xy 109.837474 -100.79101) (xy 109.675676 -100.894388)
			(xy 109.69498 -101.114352) (xy 109.872272 -101.188012)
		)
		(stroke
			(width 0)
			(type solid)
		)
		(fill yes)
		(layer "F.Cu")
		(net "M_K_DQS_DP<13>")
	)
	(gr_poly
		(pts
			(xy 109.92739 -104.898952) (xy 109.85373 -104.699816) (xy 109.822234 -104.66832) (xy 109.53496 -104.955594)
			(xy 109.566456 -104.98709) (xy 109.765592 -105.06075)
		)
		(stroke
			(width 0)
			(type solid)
		)
		(fill yes)
		(layer "F.Cu")
		(net "M_K_DQS_DN<13>")
	)
	(gr_poly
		(pts
			(xy 110.000542 -111.349536) (xy 110.000542 -111.247936) (xy 109.810042 -111.235236) (xy 109.759242 -111.235236)
			(xy 109.759242 -111.362236) (xy 109.810042 -111.362236)
		)
		(stroke
			(width 0)
			(type solid)
		)
		(fill yes)
		(layer "F.Cu")
		(net "M_K_DQS_DN<4>")
	)
	(gr_poly
		(pts
			(xy 110.000542 -110.689136) (xy 110.000542 -110.587536) (xy 109.810042 -110.574836) (xy 109.759242 -110.574836)
			(xy 109.759242 -110.701836) (xy 109.810042 -110.701836)
		)
		(stroke
			(width 0)
			(type solid)
		)
		(fill yes)
		(layer "F.Cu")
		(net "M_K_DQS_DN<4>")
	)
	(gr_poly
		(pts
			(xy 110.000542 -110.028736) (xy 110.000542 -109.927136) (xy 109.810042 -109.914436) (xy 109.759242 -109.914436)
			(xy 109.759242 -110.041436) (xy 109.810042 -110.041436)
		)
		(stroke
			(width 0)
			(type solid)
		)
		(fill yes)
		(layer "F.Cu")
		(net "M_K_DQS_DN<4>")
	)
	(gr_poly
		(pts
			(xy 110.000542 -109.368336) (xy 110.000542 -109.266736) (xy 109.810042 -109.254036) (xy 109.759242 -109.254036)
			(xy 109.759242 -109.381036) (xy 109.810042 -109.381036)
		)
		(stroke
			(width 0)
			(type solid)
		)
		(fill yes)
		(layer "F.Cu")
		(net "M_K_DQS_DN<4>")
	)
	(gr_poly
		(pts
			(xy 110.000542 -108.707936) (xy 110.000542 -108.606336) (xy 109.810042 -108.593636) (xy 109.759242 -108.593636)
			(xy 109.759242 -108.720636) (xy 109.810042 -108.720636)
		)
		(stroke
			(width 0)
			(type solid)
		)
		(fill yes)
		(layer "F.Cu")
		(net "M_K_DQS_DN<4>")
	)
	(gr_poly
		(pts
			(xy 110.000542 -108.047536) (xy 110.000542 -107.945936) (xy 109.810042 -107.933236) (xy 109.759242 -107.933236)
			(xy 109.759242 -108.060236) (xy 109.810042 -108.060236)
		)
		(stroke
			(width 0)
			(type solid)
		)
		(fill yes)
		(layer "F.Cu")
		(net "M_K_DQS_DN<4>")
	)
	(gr_poly
		(pts
			(xy 110.000542 -107.387136) (xy 110.000542 -107.285536) (xy 109.810042 -107.272836) (xy 109.759242 -107.272836)
			(xy 109.759242 -107.399836) (xy 109.810042 -107.399836)
		)
		(stroke
			(width 0)
			(type solid)
		)
		(fill yes)
		(layer "F.Cu")
		(net "M_K_DQS_DN<4>")
	)
	(gr_poly
		(pts
			(xy 110.013242 -49.091088) (xy 110.013242 -48.989488) (xy 109.822742 -48.976788) (xy 109.771942 -48.976788)
			(xy 109.771942 -49.103788) (xy 109.822742 -49.103788)
		)
		(stroke
			(width 0)
			(type solid)
		)
		(fill yes)
		(layer "F.Cu")
		(net "M_G_DQ<38>")
	)
	(gr_poly
		(pts
			(xy 110.013242 -48.430688) (xy 110.013242 -48.329088) (xy 109.822742 -48.316388) (xy 109.771942 -48.316388)
			(xy 109.771942 -48.443388) (xy 109.822742 -48.443388)
		)
		(stroke
			(width 0)
			(type solid)
		)
		(fill yes)
		(layer "F.Cu")
		(net "M_G_DQ<38>")
	)
	(gr_poly
		(pts
			(xy 110.013242 -47.770288) (xy 110.013242 -47.668688) (xy 109.822742 -47.655988) (xy 109.771942 -47.655988)
			(xy 109.771942 -47.782988) (xy 109.822742 -47.782988)
		)
		(stroke
			(width 0)
			(type solid)
		)
		(fill yes)
		(layer "F.Cu")
		(net "M_G_DQ<38>")
	)
	(gr_poly
		(pts
			(xy 110.013242 -47.109888) (xy 110.013242 -47.008288) (xy 109.822742 -46.995588) (xy 109.771942 -46.995588)
			(xy 109.771942 -47.122588) (xy 109.822742 -47.122588)
		)
		(stroke
			(width 0)
			(type solid)
		)
		(fill yes)
		(layer "F.Cu")
		(net "M_G_DQ<38>")
	)
	(gr_poly
		(pts
			(xy 110.013242 -46.449488) (xy 110.013242 -46.347888) (xy 109.822742 -46.335188) (xy 109.771942 -46.335188)
			(xy 109.771942 -46.462188) (xy 109.822742 -46.462188)
		)
		(stroke
			(width 0)
			(type solid)
		)
		(fill yes)
		(layer "F.Cu")
		(net "M_G_DQ<38>")
	)
	(gr_poly
		(pts
			(xy 110.013242 -45.789088) (xy 110.013242 -45.687488) (xy 109.822742 -45.674788) (xy 109.771942 -45.674788)
			(xy 109.771942 -45.801788) (xy 109.822742 -45.801788)
		)
		(stroke
			(width 0)
			(type solid)
		)
		(fill yes)
		(layer "F.Cu")
		(net "M_G_DQ<38>")
	)
	(gr_poly
		(pts
			(xy 110.013242 -45.128688) (xy 110.013242 -45.027088) (xy 109.822742 -45.014388) (xy 109.771942 -45.014388)
			(xy 109.771942 -45.141388) (xy 109.822742 -45.141388)
		)
		(stroke
			(width 0)
			(type solid)
		)
		(fill yes)
		(layer "F.Cu")
		(net "M_G_DQ<38>")
	)
	(gr_poly
		(pts
			(xy 110.013242 -44.468288) (xy 110.013242 -44.366688) (xy 109.822742 -44.353988) (xy 109.771942 -44.353988)
			(xy 109.771942 -44.480988) (xy 109.822742 -44.480988)
		)
		(stroke
			(width 0)
			(type solid)
		)
		(fill yes)
		(layer "F.Cu")
		(net "M_G_DQ<38>")
	)
	(gr_poly
		(pts
			(xy 110.013242 -43.807888) (xy 110.013242 -43.706288) (xy 109.822742 -43.693588) (xy 109.771942 -43.693588)
			(xy 109.771942 -43.820588) (xy 109.822742 -43.820588)
		)
		(stroke
			(width 0)
			(type solid)
		)
		(fill yes)
		(layer "F.Cu")
		(net "M_G_DQ<38>")
	)
	(gr_poly
		(pts
			(xy 110.013242 -43.147488) (xy 110.013242 -43.045888) (xy 109.822742 -43.033188) (xy 109.771942 -43.033188)
			(xy 109.771942 -43.160188) (xy 109.822742 -43.160188)
		)
		(stroke
			(width 0)
			(type solid)
		)
		(fill yes)
		(layer "F.Cu")
		(net "M_G_DQ<38>")
	)
	(gr_poly
		(pts
			(xy 110.013242 -42.487088) (xy 110.013242 -42.385488) (xy 109.822742 -42.372788) (xy 109.771942 -42.372788)
			(xy 109.771942 -42.499788) (xy 109.822742 -42.499788)
		)
		(stroke
			(width 0)
			(type solid)
		)
		(fill yes)
		(layer "F.Cu")
		(net "M_G_DQ<38>")
	)
	(gr_poly
		(pts
			(xy 110.152942 -111.565436) (xy 110.102142 -111.565436) (xy 109.911642 -111.578136) (xy 109.911642 -111.679736)
			(xy 110.102142 -111.692436) (xy 110.152942 -111.692436)
		)
		(stroke
			(width 0)
			(type solid)
		)
		(fill yes)
		(layer "F.Cu")
		(net "M_K_DQS_DP<4>")
	)
	(gr_poly
		(pts
			(xy 110.152942 -110.905036) (xy 110.102142 -110.905036) (xy 109.911642 -110.917736) (xy 109.911642 -111.019336)
			(xy 110.102142 -111.032036) (xy 110.152942 -111.032036)
		)
		(stroke
			(width 0)
			(type solid)
		)
		(fill yes)
		(layer "F.Cu")
		(net "M_K_DQS_DP<4>")
	)
	(gr_poly
		(pts
			(xy 110.152942 -110.244636) (xy 110.102142 -110.244636) (xy 109.911642 -110.257336) (xy 109.911642 -110.358936)
			(xy 110.102142 -110.371636) (xy 110.152942 -110.371636)
		)
		(stroke
			(width 0)
			(type solid)
		)
		(fill yes)
		(layer "F.Cu")
		(net "M_K_DQS_DP<4>")
	)
	(gr_poly
		(pts
			(xy 110.152942 -109.584236) (xy 110.102142 -109.584236) (xy 109.911642 -109.596936) (xy 109.911642 -109.698536)
			(xy 110.102142 -109.711236) (xy 110.152942 -109.711236)
		)
		(stroke
			(width 0)
			(type solid)
		)
		(fill yes)
		(layer "F.Cu")
		(net "M_K_DQS_DP<4>")
	)
	(gr_poly
		(pts
			(xy 110.152942 -108.923836) (xy 110.102142 -108.923836) (xy 109.911642 -108.936536) (xy 109.911642 -109.038136)
			(xy 110.102142 -109.050836) (xy 110.152942 -109.050836)
		)
		(stroke
			(width 0)
			(type solid)
		)
		(fill yes)
		(layer "F.Cu")
		(net "M_K_DQS_DP<4>")
	)
	(gr_poly
		(pts
			(xy 110.152942 -108.263436) (xy 110.102142 -108.263436) (xy 109.911642 -108.276136) (xy 109.911642 -108.377736)
			(xy 110.102142 -108.390436) (xy 110.152942 -108.390436)
		)
		(stroke
			(width 0)
			(type solid)
		)
		(fill yes)
		(layer "F.Cu")
		(net "M_K_DQS_DP<4>")
	)
	(gr_poly
		(pts
			(xy 110.152942 -107.603036) (xy 110.102142 -107.603036) (xy 109.911642 -107.615736) (xy 109.911642 -107.717336)
			(xy 110.102142 -107.730036) (xy 110.152942 -107.730036)
		)
		(stroke
			(width 0)
			(type solid)
		)
		(fill yes)
		(layer "F.Cu")
		(net "M_K_DQS_DP<4>")
	)
	(gr_poly
		(pts
			(xy 110.152942 -106.942636) (xy 110.102142 -106.942636) (xy 109.911642 -106.955336) (xy 109.911642 -107.056936)
			(xy 110.102142 -107.069636) (xy 110.152942 -107.069636)
		)
		(stroke
			(width 0)
			(type solid)
		)
		(fill yes)
		(layer "F.Cu")
		(net "M_K_DQS_DP<4>")
	)
	(gr_poly
		(pts
			(xy 110.165642 -49.306988) (xy 110.114842 -49.306988) (xy 109.924342 -49.319688) (xy 109.924342 -49.421288)
			(xy 110.114842 -49.433988) (xy 110.165642 -49.433988)
		)
		(stroke
			(width 0)
			(type solid)
		)
		(fill yes)
		(layer "F.Cu")
		(net "M_G_DQ<39>")
	)
	(gr_poly
		(pts
			(xy 110.165642 -48.646588) (xy 110.114842 -48.646588) (xy 109.924342 -48.659288) (xy 109.924342 -48.760888)
			(xy 110.114842 -48.773588) (xy 110.165642 -48.773588)
		)
		(stroke
			(width 0)
			(type solid)
		)
		(fill yes)
		(layer "F.Cu")
		(net "M_G_DQ<39>")
	)
	(gr_poly
		(pts
			(xy 110.165642 -47.986188) (xy 110.114842 -47.986188) (xy 109.924342 -47.998888) (xy 109.924342 -48.100488)
			(xy 110.114842 -48.113188) (xy 110.165642 -48.113188)
		)
		(stroke
			(width 0)
			(type solid)
		)
		(fill yes)
		(layer "F.Cu")
		(net "M_G_DQ<39>")
	)
	(gr_poly
		(pts
			(xy 110.165642 -47.325788) (xy 110.114842 -47.325788) (xy 109.924342 -47.338488) (xy 109.924342 -47.440088)
			(xy 110.114842 -47.452788) (xy 110.165642 -47.452788)
		)
		(stroke
			(width 0)
			(type solid)
		)
		(fill yes)
		(layer "F.Cu")
		(net "M_G_DQ<39>")
	)
	(gr_poly
		(pts
			(xy 110.165642 -46.665388) (xy 110.114842 -46.665388) (xy 109.924342 -46.678088) (xy 109.924342 -46.779688)
			(xy 110.114842 -46.792388) (xy 110.165642 -46.792388)
		)
		(stroke
			(width 0)
			(type solid)
		)
		(fill yes)
		(layer "F.Cu")
		(net "M_G_DQ<39>")
	)
	(gr_poly
		(pts
			(xy 110.165642 -46.004988) (xy 110.114842 -46.004988) (xy 109.924342 -46.017688) (xy 109.924342 -46.119288)
			(xy 110.114842 -46.131988) (xy 110.165642 -46.131988)
		)
		(stroke
			(width 0)
			(type solid)
		)
		(fill yes)
		(layer "F.Cu")
		(net "M_G_DQ<39>")
	)
	(gr_poly
		(pts
			(xy 110.165642 -45.344588) (xy 110.114842 -45.344588) (xy 109.924342 -45.357288) (xy 109.924342 -45.458888)
			(xy 110.114842 -45.471588) (xy 110.165642 -45.471588)
		)
		(stroke
			(width 0)
			(type solid)
		)
		(fill yes)
		(layer "F.Cu")
		(net "M_G_DQ<39>")
	)
	(gr_poly
		(pts
			(xy 110.165642 -44.684188) (xy 110.114842 -44.684188) (xy 109.924342 -44.696888) (xy 109.924342 -44.798488)
			(xy 110.114842 -44.811188) (xy 110.165642 -44.811188)
		)
		(stroke
			(width 0)
			(type solid)
		)
		(fill yes)
		(layer "F.Cu")
		(net "M_G_DQ<39>")
	)
	(gr_poly
		(pts
			(xy 110.165642 -44.023788) (xy 110.114842 -44.023788) (xy 109.924342 -44.036488) (xy 109.924342 -44.138088)
			(xy 110.114842 -44.150788) (xy 110.165642 -44.150788)
		)
		(stroke
			(width 0)
			(type solid)
		)
		(fill yes)
		(layer "F.Cu")
		(net "M_G_DQ<39>")
	)
	(gr_poly
		(pts
			(xy 110.165642 -43.363388) (xy 110.114842 -43.363388) (xy 109.924342 -43.376088) (xy 109.924342 -43.477688)
			(xy 110.114842 -43.490388) (xy 110.165642 -43.490388)
		)
		(stroke
			(width 0)
			(type solid)
		)
		(fill yes)
		(layer "F.Cu")
		(net "M_G_DQ<39>")
	)
	(gr_poly
		(pts
			(xy 110.165642 -42.702988) (xy 110.114842 -42.702988) (xy 109.924342 -42.715688) (xy 109.924342 -42.817288)
			(xy 110.114842 -42.829988) (xy 110.165642 -42.829988)
		)
		(stroke
			(width 0)
			(type solid)
		)
		(fill yes)
		(layer "F.Cu")
		(net "M_G_DQ<39>")
	)
	(gr_poly
		(pts
			(xy 110.165642 -42.042588) (xy 110.114842 -42.042588) (xy 109.924342 -42.055288) (xy 109.924342 -42.156888)
			(xy 110.114842 -42.169588) (xy 110.165642 -42.169588)
		)
		(stroke
			(width 0)
			(type solid)
		)
		(fill yes)
		(layer "F.Cu")
		(net "M_G_DQ<39>")
	)
	(gr_poly
		(pts
			(xy 110.288832 -106.11612) (xy 110.288832 -105.88752) (xy 110.095792 -105.79862) (xy 110.051342 -105.79862)
			(xy 110.051342 -106.20502) (xy 110.095792 -106.20502)
		)
		(stroke
			(width 0)
			(type solid)
		)
		(fill yes)
		(layer "F.Cu")
		(net "M_K_DQS_DP<4>")
	)
	(gr_poly
		(pts
			(xy 110.330742 -104.208834) (xy 110.330742 -103.980234) (xy 110.137702 -103.891334) (xy 110.093252 -103.891334)
			(xy 110.093252 -104.297734) (xy 110.137702 -104.297734)
		)
		(stroke
			(width 0)
			(type solid)
		)
		(fill yes)
		(layer "F.Cu")
		(net "M_K_DQS_DN<13>")
	)
	(gr_poly
		(pts
			(xy 110.338108 -104.97566) (xy 110.306612 -104.944418) (xy 110.107222 -104.870758) (xy 109.945678 -105.032302)
			(xy 110.019338 -105.231692) (xy 110.05058 -105.263188)
		)
		(stroke
			(width 0)
			(type solid)
		)
		(fill yes)
		(layer "F.Cu")
		(net "M_K_DQS_DN<4>")
	)
	(gr_poly
		(pts
			(xy 110.394242 -111.349536) (xy 110.394242 -111.247936) (xy 110.203742 -111.235236) (xy 110.152942 -111.235236)
			(xy 110.152942 -111.362236) (xy 110.203742 -111.362236)
		)
		(stroke
			(width 0)
			(type solid)
		)
		(fill yes)
		(layer "F.Cu")
		(net "M_K_DQS_DP<4>")
	)
	(gr_poly
		(pts
			(xy 110.394242 -110.689136) (xy 110.394242 -110.587536) (xy 110.203742 -110.574836) (xy 110.152942 -110.574836)
			(xy 110.152942 -110.701836) (xy 110.203742 -110.701836)
		)
		(stroke
			(width 0)
			(type solid)
		)
		(fill yes)
		(layer "F.Cu")
		(net "M_K_DQS_DP<4>")
	)
	(gr_poly
		(pts
			(xy 110.394242 -110.028736) (xy 110.394242 -109.927136) (xy 110.203742 -109.914436) (xy 110.152942 -109.914436)
			(xy 110.152942 -110.041436) (xy 110.203742 -110.041436)
		)
		(stroke
			(width 0)
			(type solid)
		)
		(fill yes)
		(layer "F.Cu")
		(net "M_K_DQS_DP<4>")
	)
	(gr_poly
		(pts
			(xy 110.394242 -109.368336) (xy 110.394242 -109.266736) (xy 110.203742 -109.254036) (xy 110.152942 -109.254036)
			(xy 110.152942 -109.381036) (xy 110.203742 -109.381036)
		)
		(stroke
			(width 0)
			(type solid)
		)
		(fill yes)
		(layer "F.Cu")
		(net "M_K_DQS_DP<4>")
	)
	(gr_poly
		(pts
			(xy 110.394242 -108.707936) (xy 110.394242 -108.606336) (xy 110.203742 -108.593636) (xy 110.152942 -108.593636)
			(xy 110.152942 -108.720636) (xy 110.203742 -108.720636)
		)
		(stroke
			(width 0)
			(type solid)
		)
		(fill yes)
		(layer "F.Cu")
		(net "M_K_DQS_DP<4>")
	)
	(gr_poly
		(pts
			(xy 110.394242 -108.047536) (xy 110.394242 -107.945936) (xy 110.203742 -107.933236) (xy 110.152942 -107.933236)
			(xy 110.152942 -108.060236) (xy 110.203742 -108.060236)
		)
		(stroke
			(width 0)
			(type solid)
		)
		(fill yes)
		(layer "F.Cu")
		(net "M_K_DQS_DP<4>")
	)
	(gr_poly
		(pts
			(xy 110.394242 -107.387136) (xy 110.394242 -107.285536) (xy 110.203742 -107.272836) (xy 110.152942 -107.272836)
			(xy 110.152942 -107.399836) (xy 110.203742 -107.399836)
		)
		(stroke
			(width 0)
			(type solid)
		)
		(fill yes)
		(layer "F.Cu")
		(net "M_K_DQS_DP<4>")
	)
	(gr_poly
		(pts
			(xy 110.406942 -49.091088) (xy 110.406942 -48.989488) (xy 110.216442 -48.976788) (xy 110.165642 -48.976788)
			(xy 110.165642 -49.103788) (xy 110.216442 -49.103788)
		)
		(stroke
			(width 0)
			(type solid)
		)
		(fill yes)
		(layer "F.Cu")
		(net "M_G_DQ<39>")
	)
	(gr_poly
		(pts
			(xy 110.406942 -48.430688) (xy 110.406942 -48.329088) (xy 110.216442 -48.316388) (xy 110.165642 -48.316388)
			(xy 110.165642 -48.443388) (xy 110.216442 -48.443388)
		)
		(stroke
			(width 0)
			(type solid)
		)
		(fill yes)
		(layer "F.Cu")
		(net "M_G_DQ<39>")
	)
	(gr_poly
		(pts
			(xy 110.406942 -47.770288) (xy 110.406942 -47.668688) (xy 110.216442 -47.655988) (xy 110.165642 -47.655988)
			(xy 110.165642 -47.782988) (xy 110.216442 -47.782988)
		)
		(stroke
			(width 0)
			(type solid)
		)
		(fill yes)
		(layer "F.Cu")
		(net "M_G_DQ<39>")
	)
	(gr_poly
		(pts
			(xy 110.406942 -47.109888) (xy 110.406942 -47.008288) (xy 110.216442 -46.995588) (xy 110.165642 -46.995588)
			(xy 110.165642 -47.122588) (xy 110.216442 -47.122588)
		)
		(stroke
			(width 0)
			(type solid)
		)
		(fill yes)
		(layer "F.Cu")
		(net "M_G_DQ<39>")
	)
	(gr_poly
		(pts
			(xy 110.406942 -46.449488) (xy 110.406942 -46.347888) (xy 110.216442 -46.335188) (xy 110.165642 -46.335188)
			(xy 110.165642 -46.462188) (xy 110.216442 -46.462188)
		)
		(stroke
			(width 0)
			(type solid)
		)
		(fill yes)
		(layer "F.Cu")
		(net "M_G_DQ<39>")
	)
	(gr_poly
		(pts
			(xy 110.406942 -45.789088) (xy 110.406942 -45.687488) (xy 110.216442 -45.674788) (xy 110.165642 -45.674788)
			(xy 110.165642 -45.801788) (xy 110.216442 -45.801788)
		)
		(stroke
			(width 0)
			(type solid)
		)
		(fill yes)
		(layer "F.Cu")
		(net "M_G_DQ<39>")
	)
	(gr_poly
		(pts
			(xy 110.406942 -45.128688) (xy 110.406942 -45.027088) (xy 110.216442 -45.014388) (xy 110.165642 -45.014388)
			(xy 110.165642 -45.141388) (xy 110.216442 -45.141388)
		)
		(stroke
			(width 0)
			(type solid)
		)
		(fill yes)
		(layer "F.Cu")
		(net "M_G_DQ<39>")
	)
	(gr_poly
		(pts
			(xy 110.406942 -44.468288) (xy 110.406942 -44.366688) (xy 110.216442 -44.353988) (xy 110.165642 -44.353988)
			(xy 110.165642 -44.480988) (xy 110.216442 -44.480988)
		)
		(stroke
			(width 0)
			(type solid)
		)
		(fill yes)
		(layer "F.Cu")
		(net "M_G_DQ<39>")
	)
	(gr_poly
		(pts
			(xy 110.406942 -43.807888) (xy 110.406942 -43.706288) (xy 110.216442 -43.693588) (xy 110.165642 -43.693588)
			(xy 110.165642 -43.820588) (xy 110.216442 -43.820588)
		)
		(stroke
			(width 0)
			(type solid)
		)
		(fill yes)
		(layer "F.Cu")
		(net "M_G_DQ<39>")
	)
	(gr_poly
		(pts
			(xy 110.406942 -43.147488) (xy 110.406942 -43.045888) (xy 110.216442 -43.033188) (xy 110.165642 -43.033188)
			(xy 110.165642 -43.160188) (xy 110.216442 -43.160188)
		)
		(stroke
			(width 0)
			(type solid)
		)
		(fill yes)
		(layer "F.Cu")
		(net "M_G_DQ<39>")
	)
	(gr_poly
		(pts
			(xy 110.406942 -42.487088) (xy 110.406942 -42.385488) (xy 110.216442 -42.372788) (xy 110.165642 -42.372788)
			(xy 110.165642 -42.499788) (xy 110.216442 -42.499788)
		)
		(stroke
			(width 0)
			(type solid)
		)
		(fill yes)
		(layer "F.Cu")
		(net "M_G_DQ<39>")
	)
	(gr_poly
		(pts
			(xy 110.432596 -102.579932) (xy 110.432596 -102.358952) (xy 110.262416 -102.270052) (xy 110.217966 -102.270052)
			(xy 110.217966 -102.668832) (xy 110.262416 -102.668832)
		)
		(stroke
			(width 0)
			(type solid)
		)
		(fill yes)
		(layer "F.Cu")
		(net "M_K_DQS_DN<13>")
	)
	(gr_poly
		(pts
			(xy 110.43285 -101.582474) (xy 110.43285 -101.361494) (xy 110.26267 -101.272594) (xy 110.21822 -101.272594)
			(xy 110.21822 -101.671374) (xy 110.26267 -101.671374)
		)
		(stroke
			(width 0)
			(type solid)
		)
		(fill yes)
		(layer "F.Cu")
		(net "M_K_DQS_DN<13>")
	)
	(gr_poly
		(pts
			(xy 110.527592 -103.449374) (xy 110.483142 -103.449374) (xy 110.290102 -103.538274) (xy 110.290102 -103.766874)
			(xy 110.483142 -103.855774) (xy 110.527592 -103.855774)
		)
		(stroke
			(width 0)
			(type solid)
		)
		(fill yes)
		(layer "F.Cu")
		(net "M_K_DQS_DN<4>")
	)
	(gr_poly
		(pts
			(xy 110.546642 -111.565436) (xy 110.495842 -111.565436) (xy 110.305342 -111.578136) (xy 110.305342 -111.679736)
			(xy 110.495842 -111.692436) (xy 110.546642 -111.692436)
		)
		(stroke
			(width 0)
			(type solid)
		)
		(fill yes)
		(layer "F.Cu")
		(net "M_K_DQ<38>")
	)
	(gr_poly
		(pts
			(xy 110.546642 -110.905036) (xy 110.495842 -110.905036) (xy 110.305342 -110.917736) (xy 110.305342 -111.019336)
			(xy 110.495842 -111.032036) (xy 110.546642 -111.032036)
		)
		(stroke
			(width 0)
			(type solid)
		)
		(fill yes)
		(layer "F.Cu")
		(net "M_K_DQ<38>")
	)
	(gr_poly
		(pts
			(xy 110.546642 -110.244636) (xy 110.495842 -110.244636) (xy 110.305342 -110.257336) (xy 110.305342 -110.358936)
			(xy 110.495842 -110.371636) (xy 110.546642 -110.371636)
		)
		(stroke
			(width 0)
			(type solid)
		)
		(fill yes)
		(layer "F.Cu")
		(net "M_K_DQ<38>")
	)
	(gr_poly
		(pts
			(xy 110.546642 -109.584236) (xy 110.495842 -109.584236) (xy 110.305342 -109.596936) (xy 110.305342 -109.698536)
			(xy 110.495842 -109.711236) (xy 110.546642 -109.711236)
		)
		(stroke
			(width 0)
			(type solid)
		)
		(fill yes)
		(layer "F.Cu")
		(net "M_K_DQ<38>")
	)
	(gr_poly
		(pts
			(xy 110.546642 -108.923836) (xy 110.495842 -108.923836) (xy 110.305342 -108.936536) (xy 110.305342 -109.038136)
			(xy 110.495842 -109.050836) (xy 110.546642 -109.050836)
		)
		(stroke
			(width 0)
			(type solid)
		)
		(fill yes)
		(layer "F.Cu")
		(net "M_K_DQ<38>")
	)
	(gr_poly
		(pts
			(xy 110.546642 -108.263436) (xy 110.495842 -108.263436) (xy 110.305342 -108.276136) (xy 110.305342 -108.377736)
			(xy 110.495842 -108.390436) (xy 110.546642 -108.390436)
		)
		(stroke
			(width 0)
			(type solid)
		)
		(fill yes)
		(layer "F.Cu")
		(net "M_K_DQ<38>")
	)
	(gr_poly
		(pts
			(xy 110.546642 -107.603036) (xy 110.495842 -107.603036) (xy 110.305342 -107.615736) (xy 110.305342 -107.717336)
			(xy 110.495842 -107.730036) (xy 110.546642 -107.730036)
		)
		(stroke
			(width 0)
			(type solid)
		)
		(fill yes)
		(layer "F.Cu")
		(net "M_K_DQ<38>")
	)
	(gr_poly
		(pts
			(xy 110.546642 -106.942636) (xy 110.495842 -106.942636) (xy 110.305342 -106.955336) (xy 110.305342 -107.056936)
			(xy 110.495842 -107.069636) (xy 110.546642 -107.069636)
		)
		(stroke
			(width 0)
			(type solid)
		)
		(fill yes)
		(layer "F.Cu")
		(net "M_K_DQ<38>")
	)
	(gr_poly
		(pts
			(xy 110.559342 -49.306988) (xy 110.508542 -49.306988) (xy 110.318042 -49.319688) (xy 110.318042 -49.421288)
			(xy 110.508542 -49.433988) (xy 110.559342 -49.433988)
		)
		(stroke
			(width 0)
			(type solid)
		)
		(fill yes)
		(layer "F.Cu")
		(net "M_G_DQ<34>")
	)
	(gr_poly
		(pts
			(xy 110.559342 -48.646588) (xy 110.508542 -48.646588) (xy 110.318042 -48.659288) (xy 110.318042 -48.760888)
			(xy 110.508542 -48.773588) (xy 110.559342 -48.773588)
		)
		(stroke
			(width 0)
			(type solid)
		)
		(fill yes)
		(layer "F.Cu")
		(net "M_G_DQ<34>")
	)
	(gr_poly
		(pts
			(xy 110.559342 -47.986188) (xy 110.508542 -47.986188) (xy 110.318042 -47.998888) (xy 110.318042 -48.100488)
			(xy 110.508542 -48.113188) (xy 110.559342 -48.113188)
		)
		(stroke
			(width 0)
			(type solid)
		)
		(fill yes)
		(layer "F.Cu")
		(net "M_G_DQ<34>")
	)
	(gr_poly
		(pts
			(xy 110.559342 -47.325788) (xy 110.508542 -47.325788) (xy 110.318042 -47.338488) (xy 110.318042 -47.440088)
			(xy 110.508542 -47.452788) (xy 110.559342 -47.452788)
		)
		(stroke
			(width 0)
			(type solid)
		)
		(fill yes)
		(layer "F.Cu")
		(net "M_G_DQ<34>")
	)
	(gr_poly
		(pts
			(xy 110.559342 -46.665388) (xy 110.508542 -46.665388) (xy 110.318042 -46.678088) (xy 110.318042 -46.779688)
			(xy 110.508542 -46.792388) (xy 110.559342 -46.792388)
		)
		(stroke
			(width 0)
			(type solid)
		)
		(fill yes)
		(layer "F.Cu")
		(net "M_G_DQ<34>")
	)
	(gr_poly
		(pts
			(xy 110.559342 -46.004988) (xy 110.508542 -46.004988) (xy 110.318042 -46.017688) (xy 110.318042 -46.119288)
			(xy 110.508542 -46.131988) (xy 110.559342 -46.131988)
		)
		(stroke
			(width 0)
			(type solid)
		)
		(fill yes)
		(layer "F.Cu")
		(net "M_G_DQ<34>")
	)
	(gr_poly
		(pts
			(xy 110.559342 -45.344588) (xy 110.508542 -45.344588) (xy 110.318042 -45.357288) (xy 110.318042 -45.458888)
			(xy 110.508542 -45.471588) (xy 110.559342 -45.471588)
		)
		(stroke
			(width 0)
			(type solid)
		)
		(fill yes)
		(layer "F.Cu")
		(net "M_G_DQ<34>")
	)
	(gr_poly
		(pts
			(xy 110.559342 -44.684188) (xy 110.508542 -44.684188) (xy 110.318042 -44.696888) (xy 110.318042 -44.798488)
			(xy 110.508542 -44.811188) (xy 110.559342 -44.811188)
		)
		(stroke
			(width 0)
			(type solid)
		)
		(fill yes)
		(layer "F.Cu")
		(net "M_G_DQ<34>")
	)
	(gr_poly
		(pts
			(xy 110.559342 -44.023788) (xy 110.508542 -44.023788) (xy 110.318042 -44.036488) (xy 110.318042 -44.138088)
			(xy 110.508542 -44.150788) (xy 110.559342 -44.150788)
		)
		(stroke
			(width 0)
			(type solid)
		)
		(fill yes)
		(layer "F.Cu")
		(net "M_G_DQ<34>")
	)
	(gr_poly
		(pts
			(xy 110.559342 -43.363388) (xy 110.508542 -43.363388) (xy 110.318042 -43.376088) (xy 110.318042 -43.477688)
			(xy 110.508542 -43.490388) (xy 110.559342 -43.490388)
		)
		(stroke
			(width 0)
			(type solid)
		)
		(fill yes)
		(layer "F.Cu")
		(net "M_G_DQ<34>")
	)
	(gr_poly
		(pts
			(xy 110.559342 -42.702988) (xy 110.508542 -42.702988) (xy 110.318042 -42.715688) (xy 110.318042 -42.817288)
			(xy 110.508542 -42.829988) (xy 110.559342 -42.829988)
		)
		(stroke
			(width 0)
			(type solid)
		)
		(fill yes)
		(layer "F.Cu")
		(net "M_G_DQ<34>")
	)
	(gr_poly
		(pts
			(xy 110.559342 -42.042588) (xy 110.508542 -42.042588) (xy 110.318042 -42.055288) (xy 110.318042 -42.156888)
			(xy 110.508542 -42.169588) (xy 110.559342 -42.169588)
		)
		(stroke
			(width 0)
			(type solid)
		)
		(fill yes)
		(layer "F.Cu")
		(net "M_G_DQ<34>")
	)
	(gr_poly
		(pts
			(xy 110.63351 -105.28554) (xy 110.55985 -105.086404) (xy 110.528354 -105.054908) (xy 110.24108 -105.342182)
			(xy 110.272576 -105.373678) (xy 110.471712 -105.447338)
		)
		(stroke
			(width 0)
			(type solid)
		)
		(fill yes)
		(layer "F.Cu")
		(net "M_K_DQS_DP<4>")
	)
	(gr_poly
		(pts
			(xy 110.787942 -111.349536) (xy 110.787942 -111.247936) (xy 110.597442 -111.235236) (xy 110.546642 -111.235236)
			(xy 110.546642 -111.362236) (xy 110.597442 -111.362236)
		)
		(stroke
			(width 0)
			(type solid)
		)
		(fill yes)
		(layer "F.Cu")
		(net "M_K_DQ<38>")
	)
	(gr_poly
		(pts
			(xy 110.787942 -110.689136) (xy 110.787942 -110.587536) (xy 110.597442 -110.574836) (xy 110.546642 -110.574836)
			(xy 110.546642 -110.701836) (xy 110.597442 -110.701836)
		)
		(stroke
			(width 0)
			(type solid)
		)
		(fill yes)
		(layer "F.Cu")
		(net "M_K_DQ<38>")
	)
	(gr_poly
		(pts
			(xy 110.787942 -110.028736) (xy 110.787942 -109.927136) (xy 110.597442 -109.914436) (xy 110.546642 -109.914436)
			(xy 110.546642 -110.041436) (xy 110.597442 -110.041436)
		)
		(stroke
			(width 0)
			(type solid)
		)
		(fill yes)
		(layer "F.Cu")
		(net "M_K_DQ<38>")
	)
	(gr_poly
		(pts
			(xy 110.787942 -109.368336) (xy 110.787942 -109.266736) (xy 110.597442 -109.254036) (xy 110.546642 -109.254036)
			(xy 110.546642 -109.381036) (xy 110.597442 -109.381036)
		)
		(stroke
			(width 0)
			(type solid)
		)
		(fill yes)
		(layer "F.Cu")
		(net "M_K_DQ<38>")
	)
	(gr_poly
		(pts
			(xy 110.787942 -108.707936) (xy 110.787942 -108.606336) (xy 110.597442 -108.593636) (xy 110.546642 -108.593636)
			(xy 110.546642 -108.720636) (xy 110.597442 -108.720636)
		)
		(stroke
			(width 0)
			(type solid)
		)
		(fill yes)
		(layer "F.Cu")
		(net "M_K_DQ<38>")
	)
	(gr_poly
		(pts
			(xy 110.787942 -108.047536) (xy 110.787942 -107.945936) (xy 110.597442 -107.933236) (xy 110.546642 -107.933236)
			(xy 110.546642 -108.060236) (xy 110.597442 -108.060236)
		)
		(stroke
			(width 0)
			(type solid)
		)
		(fill yes)
		(layer "F.Cu")
		(net "M_K_DQ<38>")
	)
	(gr_poly
		(pts
			(xy 110.787942 -107.387136) (xy 110.787942 -107.285536) (xy 110.597442 -107.272836) (xy 110.546642 -107.272836)
			(xy 110.546642 -107.399836) (xy 110.597442 -107.399836)
		)
		(stroke
			(width 0)
			(type solid)
		)
		(fill yes)
		(layer "F.Cu")
		(net "M_K_DQ<38>")
	)
	(gr_poly
		(pts
			(xy 110.800642 -49.091088) (xy 110.800642 -48.989488) (xy 110.610142 -48.976788) (xy 110.559342 -48.976788)
			(xy 110.559342 -49.103788) (xy 110.610142 -49.103788)
		)
		(stroke
			(width 0)
			(type solid)
		)
		(fill yes)
		(layer "F.Cu")
		(net "M_G_DQ<34>")
	)
	(gr_poly
		(pts
			(xy 110.800642 -48.430688) (xy 110.800642 -48.329088) (xy 110.610142 -48.316388) (xy 110.559342 -48.316388)
			(xy 110.559342 -48.443388) (xy 110.610142 -48.443388)
		)
		(stroke
			(width 0)
			(type solid)
		)
		(fill yes)
		(layer "F.Cu")
		(net "M_G_DQ<34>")
	)
	(gr_poly
		(pts
			(xy 110.800642 -47.770288) (xy 110.800642 -47.668688) (xy 110.610142 -47.655988) (xy 110.559342 -47.655988)
			(xy 110.559342 -47.782988) (xy 110.610142 -47.782988)
		)
		(stroke
			(width 0)
			(type solid)
		)
		(fill yes)
		(layer "F.Cu")
		(net "M_G_DQ<34>")
	)
	(gr_poly
		(pts
			(xy 110.800642 -47.109888) (xy 110.800642 -47.008288) (xy 110.610142 -46.995588) (xy 110.559342 -46.995588)
			(xy 110.559342 -47.122588) (xy 110.610142 -47.122588)
		)
		(stroke
			(width 0)
			(type solid)
		)
		(fill yes)
		(layer "F.Cu")
		(net "M_G_DQ<34>")
	)
	(gr_poly
		(pts
			(xy 110.800642 -46.449488) (xy 110.800642 -46.347888) (xy 110.610142 -46.335188) (xy 110.559342 -46.335188)
			(xy 110.559342 -46.462188) (xy 110.610142 -46.462188)
		)
		(stroke
			(width 0)
			(type solid)
		)
		(fill yes)
		(layer "F.Cu")
		(net "M_G_DQ<34>")
	)
	(gr_poly
		(pts
			(xy 110.800642 -45.789088) (xy 110.800642 -45.687488) (xy 110.610142 -45.674788) (xy 110.559342 -45.674788)
			(xy 110.559342 -45.801788) (xy 110.610142 -45.801788)
		)
		(stroke
			(width 0)
			(type solid)
		)
		(fill yes)
		(layer "F.Cu")
		(net "M_G_DQ<34>")
	)
	(gr_poly
		(pts
			(xy 110.800642 -45.128688) (xy 110.800642 -45.027088) (xy 110.610142 -45.014388) (xy 110.559342 -45.014388)
			(xy 110.559342 -45.141388) (xy 110.610142 -45.141388)
		)
		(stroke
			(width 0)
			(type solid)
		)
		(fill yes)
		(layer "F.Cu")
		(net "M_G_DQ<34>")
	)
	(gr_poly
		(pts
			(xy 110.800642 -44.468288) (xy 110.800642 -44.366688) (xy 110.610142 -44.353988) (xy 110.559342 -44.353988)
			(xy 110.559342 -44.480988) (xy 110.610142 -44.480988)
		)
		(stroke
			(width 0)
			(type solid)
		)
		(fill yes)
		(layer "F.Cu")
		(net "M_G_DQ<34>")
	)
	(gr_poly
		(pts
			(xy 110.800642 -43.807888) (xy 110.800642 -43.706288) (xy 110.610142 -43.693588) (xy 110.559342 -43.693588)
			(xy 110.559342 -43.820588) (xy 110.610142 -43.820588)
		)
		(stroke
			(width 0)
			(type solid)
		)
		(fill yes)
		(layer "F.Cu")
		(net "M_G_DQ<34>")
	)
	(gr_poly
		(pts
			(xy 110.800642 -43.147488) (xy 110.800642 -43.045888) (xy 110.610142 -43.033188) (xy 110.559342 -43.033188)
			(xy 110.559342 -43.160188) (xy 110.610142 -43.160188)
		)
		(stroke
			(width 0)
			(type solid)
		)
		(fill yes)
		(layer "F.Cu")
		(net "M_G_DQ<34>")
	)
	(gr_poly
		(pts
			(xy 110.800642 -42.487088) (xy 110.800642 -42.385488) (xy 110.610142 -42.372788) (xy 110.559342 -42.372788)
			(xy 110.559342 -42.499788) (xy 110.610142 -42.499788)
		)
		(stroke
			(width 0)
			(type solid)
		)
		(fill yes)
		(layer "F.Cu")
		(net "M_G_DQ<34>")
	)
	(gr_poly
		(pts
			(xy 110.940342 -111.565436) (xy 110.889542 -111.565436) (xy 110.699042 -111.578136) (xy 110.699042 -111.679736)
			(xy 110.889542 -111.692436) (xy 110.940342 -111.692436)
		)
		(stroke
			(width 0)
			(type solid)
		)
		(fill yes)
		(layer "F.Cu")
		(net "M_K_DQ<39>")
	)
	(gr_poly
		(pts
			(xy 110.940342 -110.905036) (xy 110.889542 -110.905036) (xy 110.699042 -110.917736) (xy 110.699042 -111.019336)
			(xy 110.889542 -111.032036) (xy 110.940342 -111.032036)
		)
		(stroke
			(width 0)
			(type solid)
		)
		(fill yes)
		(layer "F.Cu")
		(net "M_K_DQ<39>")
	)
	(gr_poly
		(pts
			(xy 110.940342 -110.244636) (xy 110.889542 -110.244636) (xy 110.699042 -110.257336) (xy 110.699042 -110.358936)
			(xy 110.889542 -110.371636) (xy 110.940342 -110.371636)
		)
		(stroke
			(width 0)
			(type solid)
		)
		(fill yes)
		(layer "F.Cu")
		(net "M_K_DQ<39>")
	)
	(gr_poly
		(pts
			(xy 110.940342 -109.584236) (xy 110.889542 -109.584236) (xy 110.699042 -109.596936) (xy 110.699042 -109.698536)
			(xy 110.889542 -109.711236) (xy 110.940342 -109.711236)
		)
		(stroke
			(width 0)
			(type solid)
		)
		(fill yes)
		(layer "F.Cu")
		(net "M_K_DQ<39>")
	)
	(gr_poly
		(pts
			(xy 110.940342 -108.923836) (xy 110.889542 -108.923836) (xy 110.699042 -108.936536) (xy 110.699042 -109.038136)
			(xy 110.889542 -109.050836) (xy 110.940342 -109.050836)
		)
		(stroke
			(width 0)
			(type solid)
		)
		(fill yes)
		(layer "F.Cu")
		(net "M_K_DQ<39>")
	)
	(gr_poly
		(pts
			(xy 110.940342 -108.263436) (xy 110.889542 -108.263436) (xy 110.699042 -108.276136) (xy 110.699042 -108.377736)
			(xy 110.889542 -108.390436) (xy 110.940342 -108.390436)
		)
		(stroke
			(width 0)
			(type solid)
		)
		(fill yes)
		(layer "F.Cu")
		(net "M_K_DQ<39>")
	)
	(gr_poly
		(pts
			(xy 110.940342 -107.603036) (xy 110.889542 -107.603036) (xy 110.699042 -107.615736) (xy 110.699042 -107.717336)
			(xy 110.889542 -107.730036) (xy 110.940342 -107.730036)
		)
		(stroke
			(width 0)
			(type solid)
		)
		(fill yes)
		(layer "F.Cu")
		(net "M_K_DQ<39>")
	)
	(gr_poly
		(pts
			(xy 110.940342 -106.942636) (xy 110.889542 -106.942636) (xy 110.699042 -106.955336) (xy 110.699042 -107.056936)
			(xy 110.889542 -107.069636) (xy 110.940342 -107.069636)
		)
		(stroke
			(width 0)
			(type solid)
		)
		(fill yes)
		(layer "F.Cu")
		(net "M_K_DQ<39>")
	)
	(gr_poly
		(pts
			(xy 110.943898 -101.273102) (xy 110.899448 -101.273102) (xy 110.729268 -101.362002) (xy 110.729268 -101.582982)
			(xy 110.899448 -101.671882) (xy 110.943898 -101.671882)
		)
		(stroke
			(width 0)
			(type solid)
		)
		(fill yes)
		(layer "F.Cu")
		(net "M_K_DQ<38>")
	)
	(gr_poly
		(pts
			(xy 110.953042 -49.306988) (xy 110.902242 -49.306988) (xy 110.711742 -49.319688) (xy 110.711742 -49.421288)
			(xy 110.902242 -49.433988) (xy 110.953042 -49.433988)
		)
		(stroke
			(width 0)
			(type solid)
		)
		(fill yes)
		(layer "F.Cu")
		(net "M_G_DQ<35>")
	)
	(gr_poly
		(pts
			(xy 110.953042 -48.646588) (xy 110.902242 -48.646588) (xy 110.711742 -48.659288) (xy 110.711742 -48.760888)
			(xy 110.902242 -48.773588) (xy 110.953042 -48.773588)
		)
		(stroke
			(width 0)
			(type solid)
		)
		(fill yes)
		(layer "F.Cu")
		(net "M_G_DQ<35>")
	)
	(gr_poly
		(pts
			(xy 110.953042 -47.986188) (xy 110.902242 -47.986188) (xy 110.711742 -47.998888) (xy 110.711742 -48.100488)
			(xy 110.902242 -48.113188) (xy 110.953042 -48.113188)
		)
		(stroke
			(width 0)
			(type solid)
		)
		(fill yes)
		(layer "F.Cu")
		(net "M_G_DQ<35>")
	)
	(gr_poly
		(pts
			(xy 110.953042 -47.325788) (xy 110.902242 -47.325788) (xy 110.711742 -47.338488) (xy 110.711742 -47.440088)
			(xy 110.902242 -47.452788) (xy 110.953042 -47.452788)
		)
		(stroke
			(width 0)
			(type solid)
		)
		(fill yes)
		(layer "F.Cu")
		(net "M_G_DQ<35>")
	)
	(gr_poly
		(pts
			(xy 110.953042 -46.665388) (xy 110.902242 -46.665388) (xy 110.711742 -46.678088) (xy 110.711742 -46.779688)
			(xy 110.902242 -46.792388) (xy 110.953042 -46.792388)
		)
		(stroke
			(width 0)
			(type solid)
		)
		(fill yes)
		(layer "F.Cu")
		(net "M_G_DQ<35>")
	)
	(gr_poly
		(pts
			(xy 110.953042 -46.004988) (xy 110.902242 -46.004988) (xy 110.711742 -46.017688) (xy 110.711742 -46.119288)
			(xy 110.902242 -46.131988) (xy 110.953042 -46.131988)
		)
		(stroke
			(width 0)
			(type solid)
		)
		(fill yes)
		(layer "F.Cu")
		(net "M_G_DQ<35>")
	)
	(gr_poly
		(pts
			(xy 110.953042 -45.344588) (xy 110.902242 -45.344588) (xy 110.711742 -45.357288) (xy 110.711742 -45.458888)
			(xy 110.902242 -45.471588) (xy 110.953042 -45.471588)
		)
		(stroke
			(width 0)
			(type solid)
		)
		(fill yes)
		(layer "F.Cu")
		(net "M_G_DQ<35>")
	)
	(gr_poly
		(pts
			(xy 110.953042 -44.684188) (xy 110.902242 -44.684188) (xy 110.711742 -44.696888) (xy 110.711742 -44.798488)
			(xy 110.902242 -44.811188) (xy 110.953042 -44.811188)
		)
		(stroke
			(width 0)
			(type solid)
		)
		(fill yes)
		(layer "F.Cu")
		(net "M_G_DQ<35>")
	)
	(gr_poly
		(pts
			(xy 110.953042 -44.023788) (xy 110.902242 -44.023788) (xy 110.711742 -44.036488) (xy 110.711742 -44.138088)
			(xy 110.902242 -44.150788) (xy 110.953042 -44.150788)
		)
		(stroke
			(width 0)
			(type solid)
		)
		(fill yes)
		(layer "F.Cu")
		(net "M_G_DQ<35>")
	)
	(gr_poly
		(pts
			(xy 110.953042 -43.363388) (xy 110.902242 -43.363388) (xy 110.711742 -43.376088) (xy 110.711742 -43.477688)
			(xy 110.902242 -43.490388) (xy 110.953042 -43.490388)
		)
		(stroke
			(width 0)
			(type solid)
		)
		(fill yes)
		(layer "F.Cu")
		(net "M_G_DQ<35>")
	)
	(gr_poly
		(pts
			(xy 110.953042 -42.702988) (xy 110.902242 -42.702988) (xy 110.711742 -42.715688) (xy 110.711742 -42.817288)
			(xy 110.902242 -42.829988) (xy 110.953042 -42.829988)
		)
		(stroke
			(width 0)
			(type solid)
		)
		(fill yes)
		(layer "F.Cu")
		(net "M_G_DQ<35>")
	)
	(gr_poly
		(pts
			(xy 110.953042 -42.042588) (xy 110.902242 -42.042588) (xy 110.711742 -42.055288) (xy 110.711742 -42.156888)
			(xy 110.902242 -42.169588) (xy 110.953042 -42.169588)
		)
		(stroke
			(width 0)
			(type solid)
		)
		(fill yes)
		(layer "F.Cu")
		(net "M_G_DQ<35>")
	)
	(gr_poly
		(pts
			(xy 110.955582 -103.766874) (xy 110.955582 -103.538274) (xy 110.762542 -103.449374) (xy 110.718092 -103.449374)
			(xy 110.718092 -103.855774) (xy 110.762542 -103.855774)
		)
		(stroke
			(width 0)
			(type solid)
		)
		(fill yes)
		(layer "F.Cu")
		(net "M_K_DQS_DP<4>")
	)
	(gr_poly
		(pts
			(xy 111.181642 -111.349536) (xy 111.181642 -111.247936) (xy 110.991142 -111.235236) (xy 110.940342 -111.235236)
			(xy 110.940342 -111.362236) (xy 110.991142 -111.362236)
		)
		(stroke
			(width 0)
			(type solid)
		)
		(fill yes)
		(layer "F.Cu")
		(net "M_K_DQ<39>")
	)
	(gr_poly
		(pts
			(xy 111.181642 -110.689136) (xy 111.181642 -110.587536) (xy 110.991142 -110.574836) (xy 110.940342 -110.574836)
			(xy 110.940342 -110.701836) (xy 110.991142 -110.701836)
		)
		(stroke
			(width 0)
			(type solid)
		)
		(fill yes)
		(layer "F.Cu")
		(net "M_K_DQ<39>")
	)
	(gr_poly
		(pts
			(xy 111.181642 -110.028736) (xy 111.181642 -109.927136) (xy 110.991142 -109.914436) (xy 110.940342 -109.914436)
			(xy 110.940342 -110.041436) (xy 110.991142 -110.041436)
		)
		(stroke
			(width 0)
			(type solid)
		)
		(fill yes)
		(layer "F.Cu")
		(net "M_K_DQ<39>")
	)
	(gr_poly
		(pts
			(xy 111.181642 -109.368336) (xy 111.181642 -109.266736) (xy 110.991142 -109.254036) (xy 110.940342 -109.254036)
			(xy 110.940342 -109.381036) (xy 110.991142 -109.381036)
		)
		(stroke
			(width 0)
			(type solid)
		)
		(fill yes)
		(layer "F.Cu")
		(net "M_K_DQ<39>")
	)
	(gr_poly
		(pts
			(xy 111.181642 -108.707936) (xy 111.181642 -108.606336) (xy 110.991142 -108.593636) (xy 110.940342 -108.593636)
			(xy 110.940342 -108.720636) (xy 110.991142 -108.720636)
		)
		(stroke
			(width 0)
			(type solid)
		)
		(fill yes)
		(layer "F.Cu")
		(net "M_K_DQ<39>")
	)
	(gr_poly
		(pts
			(xy 111.181642 -108.047536) (xy 111.181642 -107.945936) (xy 110.991142 -107.933236) (xy 110.940342 -107.933236)
			(xy 110.940342 -108.060236) (xy 110.991142 -108.060236)
		)
		(stroke
			(width 0)
			(type solid)
		)
		(fill yes)
		(layer "F.Cu")
		(net "M_K_DQ<39>")
	)
	(gr_poly
		(pts
			(xy 111.181642 -107.387136) (xy 111.181642 -107.285536) (xy 110.991142 -107.272836) (xy 110.940342 -107.272836)
			(xy 110.940342 -107.399836) (xy 110.991142 -107.399836)
		)
		(stroke
			(width 0)
			(type solid)
		)
		(fill yes)
		(layer "F.Cu")
		(net "M_K_DQ<39>")
	)
	(gr_poly
		(pts
			(xy 111.194342 -49.091088) (xy 111.194342 -48.989488) (xy 111.003842 -48.976788) (xy 110.953042 -48.976788)
			(xy 110.953042 -49.103788) (xy 111.003842 -49.103788)
		)
		(stroke
			(width 0)
			(type solid)
		)
		(fill yes)
		(layer "F.Cu")
		(net "M_G_DQ<35>")
	)
	(gr_poly
		(pts
			(xy 111.194342 -48.430688) (xy 111.194342 -48.329088) (xy 111.003842 -48.316388) (xy 110.953042 -48.316388)
			(xy 110.953042 -48.443388) (xy 111.003842 -48.443388)
		)
		(stroke
			(width 0)
			(type solid)
		)
		(fill yes)
		(layer "F.Cu")
		(net "M_G_DQ<35>")
	)
	(gr_poly
		(pts
			(xy 111.194342 -47.770288) (xy 111.194342 -47.668688) (xy 111.003842 -47.655988) (xy 110.953042 -47.655988)
			(xy 110.953042 -47.782988) (xy 111.003842 -47.782988)
		)
		(stroke
			(width 0)
			(type solid)
		)
		(fill yes)
		(layer "F.Cu")
		(net "M_G_DQ<35>")
	)
	(gr_poly
		(pts
			(xy 111.194342 -47.109888) (xy 111.194342 -47.008288) (xy 111.003842 -46.995588) (xy 110.953042 -46.995588)
			(xy 110.953042 -47.122588) (xy 111.003842 -47.122588)
		)
		(stroke
			(width 0)
			(type solid)
		)
		(fill yes)
		(layer "F.Cu")
		(net "M_G_DQ<35>")
	)
	(gr_poly
		(pts
			(xy 111.194342 -46.449488) (xy 111.194342 -46.347888) (xy 111.003842 -46.335188) (xy 110.953042 -46.335188)
			(xy 110.953042 -46.462188) (xy 111.003842 -46.462188)
		)
		(stroke
			(width 0)
			(type solid)
		)
		(fill yes)
		(layer "F.Cu")
		(net "M_G_DQ<35>")
	)
	(gr_poly
		(pts
			(xy 111.194342 -45.789088) (xy 111.194342 -45.687488) (xy 111.003842 -45.674788) (xy 110.953042 -45.674788)
			(xy 110.953042 -45.801788) (xy 111.003842 -45.801788)
		)
		(stroke
			(width 0)
			(type solid)
		)
		(fill yes)
		(layer "F.Cu")
		(net "M_G_DQ<35>")
	)
	(gr_poly
		(pts
			(xy 111.194342 -45.128688) (xy 111.194342 -45.027088) (xy 111.003842 -45.014388) (xy 110.953042 -45.014388)
			(xy 110.953042 -45.141388) (xy 111.003842 -45.141388)
		)
		(stroke
			(width 0)
			(type solid)
		)
		(fill yes)
		(layer "F.Cu")
		(net "M_G_DQ<35>")
	)
	(gr_poly
		(pts
			(xy 111.194342 -44.468288) (xy 111.194342 -44.366688) (xy 111.003842 -44.353988) (xy 110.953042 -44.353988)
			(xy 110.953042 -44.480988) (xy 111.003842 -44.480988)
		)
		(stroke
			(width 0)
			(type solid)
		)
		(fill yes)
		(layer "F.Cu")
		(net "M_G_DQ<35>")
	)
	(gr_poly
		(pts
			(xy 111.194342 -43.807888) (xy 111.194342 -43.706288) (xy 111.003842 -43.693588) (xy 110.953042 -43.693588)
			(xy 110.953042 -43.820588) (xy 111.003842 -43.820588)
		)
		(stroke
			(width 0)
			(type solid)
		)
		(fill yes)
		(layer "F.Cu")
		(net "M_G_DQ<35>")
	)
	(gr_poly
		(pts
			(xy 111.194342 -43.147488) (xy 111.194342 -43.045888) (xy 111.003842 -43.033188) (xy 110.953042 -43.033188)
			(xy 110.953042 -43.160188) (xy 111.003842 -43.160188)
		)
		(stroke
			(width 0)
			(type solid)
		)
		(fill yes)
		(layer "F.Cu")
		(net "M_G_DQ<35>")
	)
	(gr_poly
		(pts
			(xy 111.194342 -42.487088) (xy 111.194342 -42.385488) (xy 111.003842 -42.372788) (xy 110.953042 -42.372788)
			(xy 110.953042 -42.499788) (xy 111.003842 -42.499788)
		)
		(stroke
			(width 0)
			(type solid)
		)
		(fill yes)
		(layer "F.Cu")
		(net "M_G_DQ<35>")
	)
	(gr_poly
		(pts
			(xy 111.29137 -102.084378) (xy 111.29137 -101.863398) (xy 111.12119 -101.774498) (xy 111.07674 -101.774498)
			(xy 111.07674 -102.173278) (xy 111.12119 -102.173278)
		)
		(stroke
			(width 0)
			(type solid)
		)
		(fill yes)
		(layer "F.Cu")
		(net "M_K_DQ<38>")
	)
	(gr_poly
		(pts
			(xy 111.303562 -104.202484) (xy 111.259112 -104.202484) (xy 111.066072 -104.291384) (xy 111.066072 -104.519984)
			(xy 111.259112 -104.608884) (xy 111.303562 -104.608884)
		)
		(stroke
			(width 0)
			(type solid)
		)
		(fill yes)
		(layer "F.Cu")
		(net "M_K_DQ<38>")
	)
	(gr_poly
		(pts
			(xy 111.334042 -111.565436) (xy 111.283242 -111.565436) (xy 111.092742 -111.578136) (xy 111.092742 -111.679736)
			(xy 111.283242 -111.692436) (xy 111.334042 -111.692436)
		)
		(stroke
			(width 0)
			(type solid)
		)
		(fill yes)
		(layer "F.Cu")
		(net "M_K_DQ<34>")
	)
	(gr_poly
		(pts
			(xy 111.334042 -110.905036) (xy 111.283242 -110.905036) (xy 111.092742 -110.917736) (xy 111.092742 -111.019336)
			(xy 111.283242 -111.032036) (xy 111.334042 -111.032036)
		)
		(stroke
			(width 0)
			(type solid)
		)
		(fill yes)
		(layer "F.Cu")
		(net "M_K_DQ<34>")
	)
	(gr_poly
		(pts
			(xy 111.334042 -110.244636) (xy 111.283242 -110.244636) (xy 111.092742 -110.257336) (xy 111.092742 -110.358936)
			(xy 111.283242 -110.371636) (xy 111.334042 -110.371636)
		)
		(stroke
			(width 0)
			(type solid)
		)
		(fill yes)
		(layer "F.Cu")
		(net "M_K_DQ<34>")
	)
	(gr_poly
		(pts
			(xy 111.334042 -109.584236) (xy 111.283242 -109.584236) (xy 111.092742 -109.596936) (xy 111.092742 -109.698536)
			(xy 111.283242 -109.711236) (xy 111.334042 -109.711236)
		)
		(stroke
			(width 0)
			(type solid)
		)
		(fill yes)
		(layer "F.Cu")
		(net "M_K_DQ<34>")
	)
	(gr_poly
		(pts
			(xy 111.334042 -108.923836) (xy 111.283242 -108.923836) (xy 111.092742 -108.936536) (xy 111.092742 -109.038136)
			(xy 111.283242 -109.050836) (xy 111.334042 -109.050836)
		)
		(stroke
			(width 0)
			(type solid)
		)
		(fill yes)
		(layer "F.Cu")
		(net "M_K_DQ<34>")
	)
	(gr_poly
		(pts
			(xy 111.334042 -108.263436) (xy 111.283242 -108.263436) (xy 111.092742 -108.276136) (xy 111.092742 -108.377736)
			(xy 111.283242 -108.390436) (xy 111.334042 -108.390436)
		)
		(stroke
			(width 0)
			(type solid)
		)
		(fill yes)
		(layer "F.Cu")
		(net "M_K_DQ<34>")
	)
	(gr_poly
		(pts
			(xy 111.334042 -107.603036) (xy 111.283242 -107.603036) (xy 111.092742 -107.615736) (xy 111.092742 -107.717336)
			(xy 111.283242 -107.730036) (xy 111.334042 -107.730036)
		)
		(stroke
			(width 0)
			(type solid)
		)
		(fill yes)
		(layer "F.Cu")
		(net "M_K_DQ<34>")
	)
	(gr_poly
		(pts
			(xy 111.334042 -106.942636) (xy 111.283242 -106.942636) (xy 111.092742 -106.955336) (xy 111.092742 -107.056936)
			(xy 111.283242 -107.069636) (xy 111.334042 -107.069636)
		)
		(stroke
			(width 0)
			(type solid)
		)
		(fill yes)
		(layer "F.Cu")
		(net "M_K_DQ<34>")
	)
	(gr_poly
		(pts
			(xy 111.415068 -105.733088) (xy 111.341408 -105.533698) (xy 111.310166 -105.502202) (xy 111.022638 -105.78973)
			(xy 111.054134 -105.820972) (xy 111.253524 -105.894632)
		)
		(stroke
			(width 0)
			(type solid)
		)
		(fill yes)
		(layer "F.Cu")
		(net "M_K_DQ<39>")
	)
	(gr_poly
		(pts
			(xy 111.575342 -111.349536) (xy 111.575342 -111.247936) (xy 111.384842 -111.235236) (xy 111.334042 -111.235236)
			(xy 111.334042 -111.362236) (xy 111.384842 -111.362236)
		)
		(stroke
			(width 0)
			(type solid)
		)
		(fill yes)
		(layer "F.Cu")
		(net "M_K_DQ<34>")
	)
	(gr_poly
		(pts
			(xy 111.575342 -110.689136) (xy 111.575342 -110.587536) (xy 111.384842 -110.574836) (xy 111.334042 -110.574836)
			(xy 111.334042 -110.701836) (xy 111.384842 -110.701836)
		)
		(stroke
			(width 0)
			(type solid)
		)
		(fill yes)
		(layer "F.Cu")
		(net "M_K_DQ<34>")
	)
	(gr_poly
		(pts
			(xy 111.575342 -110.028736) (xy 111.575342 -109.927136) (xy 111.384842 -109.914436) (xy 111.334042 -109.914436)
			(xy 111.334042 -110.041436) (xy 111.384842 -110.041436)
		)
		(stroke
			(width 0)
			(type solid)
		)
		(fill yes)
		(layer "F.Cu")
		(net "M_K_DQ<34>")
	)
	(gr_poly
		(pts
			(xy 111.575342 -109.368336) (xy 111.575342 -109.266736) (xy 111.384842 -109.254036) (xy 111.334042 -109.254036)
			(xy 111.334042 -109.381036) (xy 111.384842 -109.381036)
		)
		(stroke
			(width 0)
			(type solid)
		)
		(fill yes)
		(layer "F.Cu")
		(net "M_K_DQ<34>")
	)
	(gr_poly
		(pts
			(xy 111.575342 -108.707936) (xy 111.575342 -108.606336) (xy 111.384842 -108.593636) (xy 111.334042 -108.593636)
			(xy 111.334042 -108.720636) (xy 111.384842 -108.720636)
		)
		(stroke
			(width 0)
			(type solid)
		)
		(fill yes)
		(layer "F.Cu")
		(net "M_K_DQ<34>")
	)
	(gr_poly
		(pts
			(xy 111.575342 -108.047536) (xy 111.575342 -107.945936) (xy 111.384842 -107.933236) (xy 111.334042 -107.933236)
			(xy 111.334042 -108.060236) (xy 111.384842 -108.060236)
		)
		(stroke
			(width 0)
			(type solid)
		)
		(fill yes)
		(layer "F.Cu")
		(net "M_K_DQ<34>")
	)
	(gr_poly
		(pts
			(xy 111.575342 -107.387136) (xy 111.575342 -107.285536) (xy 111.384842 -107.272836) (xy 111.334042 -107.272836)
			(xy 111.334042 -107.399836) (xy 111.384842 -107.399836)
		)
		(stroke
			(width 0)
			(type solid)
		)
		(fill yes)
		(layer "F.Cu")
		(net "M_K_DQ<34>")
	)
	(gr_poly
		(pts
			(xy 111.579152 -103.630984) (xy 111.579152 -103.402384) (xy 111.386112 -103.313484) (xy 111.341662 -103.313484)
			(xy 111.341662 -103.719884) (xy 111.386112 -103.719884)
		)
		(stroke
			(width 0)
			(type solid)
		)
		(fill yes)
		(layer "F.Cu")
		(net "M_K_DQ<39>")
	)
	(gr_poly
		(pts
			(xy 111.607092 -50.776124) (xy 111.562642 -50.776124) (xy 111.392462 -50.865024) (xy 111.392462 -51.086004)
			(xy 111.562642 -51.174904) (xy 111.607092 -51.174904)
		)
		(stroke
			(width 0)
			(type solid)
		)
		(fill yes)
		(layer "F.Cu")
		(net "M_H_DQ<44>")
	)
	(gr_poly
		(pts
			(xy 111.618522 -101.774244) (xy 111.573818 -101.774498) (xy 111.404146 -101.863652) (xy 111.404654 -102.084632)
			(xy 111.575088 -102.173024) (xy 111.619538 -102.173024)
		)
		(stroke
			(width 0)
			(type solid)
		)
		(fill yes)
		(layer "F.Cu")
		(net "M_K_DQ<34>")
	)
	(gr_poly
		(pts
			(xy 111.727742 -111.565436) (xy 111.676942 -111.565436) (xy 111.486442 -111.578136) (xy 111.486442 -111.679736)
			(xy 111.676942 -111.692436) (xy 111.727742 -111.692436)
		)
		(stroke
			(width 0)
			(type solid)
		)
		(fill yes)
		(layer "F.Cu")
		(net "M_K_DQ<35>")
	)
	(gr_poly
		(pts
			(xy 111.727742 -110.905036) (xy 111.676942 -110.905036) (xy 111.486442 -110.917736) (xy 111.486442 -111.019336)
			(xy 111.676942 -111.032036) (xy 111.727742 -111.032036)
		)
		(stroke
			(width 0)
			(type solid)
		)
		(fill yes)
		(layer "F.Cu")
		(net "M_K_DQ<35>")
	)
	(gr_poly
		(pts
			(xy 111.727742 -110.244636) (xy 111.676942 -110.244636) (xy 111.486442 -110.257336) (xy 111.486442 -110.358936)
			(xy 111.676942 -110.371636) (xy 111.727742 -110.371636)
		)
		(stroke
			(width 0)
			(type solid)
		)
		(fill yes)
		(layer "F.Cu")
		(net "M_K_DQ<35>")
	)
	(gr_poly
		(pts
			(xy 111.727742 -109.584236) (xy 111.676942 -109.584236) (xy 111.486442 -109.596936) (xy 111.486442 -109.698536)
			(xy 111.676942 -109.711236) (xy 111.727742 -109.711236)
		)
		(stroke
			(width 0)
			(type solid)
		)
		(fill yes)
		(layer "F.Cu")
		(net "M_K_DQ<35>")
	)
	(gr_poly
		(pts
			(xy 111.727742 -108.923836) (xy 111.676942 -108.923836) (xy 111.486442 -108.936536) (xy 111.486442 -109.038136)
			(xy 111.676942 -109.050836) (xy 111.727742 -109.050836)
		)
		(stroke
			(width 0)
			(type solid)
		)
		(fill yes)
		(layer "F.Cu")
		(net "M_K_DQ<35>")
	)
	(gr_poly
		(pts
			(xy 111.727742 -108.263436) (xy 111.676942 -108.263436) (xy 111.486442 -108.276136) (xy 111.486442 -108.377736)
			(xy 111.676942 -108.390436) (xy 111.727742 -108.390436)
		)
		(stroke
			(width 0)
			(type solid)
		)
		(fill yes)
		(layer "F.Cu")
		(net "M_K_DQ<35>")
	)
	(gr_poly
		(pts
			(xy 111.727742 -107.603036) (xy 111.676942 -107.603036) (xy 111.486442 -107.615736) (xy 111.486442 -107.717336)
			(xy 111.676942 -107.730036) (xy 111.727742 -107.730036)
		)
		(stroke
			(width 0)
			(type solid)
		)
		(fill yes)
		(layer "F.Cu")
		(net "M_K_DQ<35>")
	)
	(gr_poly
		(pts
			(xy 111.727742 -106.942636) (xy 111.676942 -106.942636) (xy 111.486442 -106.955336) (xy 111.486442 -107.056936)
			(xy 111.676942 -107.069636) (xy 111.727742 -107.069636)
		)
		(stroke
			(width 0)
			(type solid)
		)
		(fill yes)
		(layer "F.Cu")
		(net "M_K_DQ<35>")
	)
	(gr_poly
		(pts
			(xy 111.731552 -104.519984) (xy 111.731552 -104.291384) (xy 111.538512 -104.202484) (xy 111.494062 -104.202484)
			(xy 111.494062 -104.608884) (xy 111.538512 -104.608884)
		)
		(stroke
			(width 0)
			(type solid)
		)
		(fill yes)
		(layer "F.Cu")
		(net "M_K_DQ<39>")
	)
	(gr_poly
		(pts
			(xy 111.835692 -49.543208) (xy 111.784892 -49.543208) (xy 111.594392 -49.555908) (xy 111.594392 -49.657508)
			(xy 111.784892 -49.670208) (xy 111.835692 -49.670208)
		)
		(stroke
			(width 0)
			(type solid)
		)
		(fill yes)
		(layer "F.Cu")
		(net "M_H_DQ<44>")
	)
	(gr_poly
		(pts
			(xy 111.835692 -48.882808) (xy 111.784892 -48.882808) (xy 111.594392 -48.895508) (xy 111.594392 -48.997108)
			(xy 111.784892 -49.009808) (xy 111.835692 -49.009808)
		)
		(stroke
			(width 0)
			(type solid)
		)
		(fill yes)
		(layer "F.Cu")
		(net "M_H_DQ<44>")
	)
	(gr_poly
		(pts
			(xy 111.835692 -48.222408) (xy 111.784892 -48.222408) (xy 111.594392 -48.235108) (xy 111.594392 -48.336708)
			(xy 111.784892 -48.349408) (xy 111.835692 -48.349408)
		)
		(stroke
			(width 0)
			(type solid)
		)
		(fill yes)
		(layer "F.Cu")
		(net "M_H_DQ<44>")
	)
	(gr_poly
		(pts
			(xy 111.835692 -47.562008) (xy 111.784892 -47.562008) (xy 111.594392 -47.574708) (xy 111.594392 -47.676308)
			(xy 111.784892 -47.689008) (xy 111.835692 -47.689008)
		)
		(stroke
			(width 0)
			(type solid)
		)
		(fill yes)
		(layer "F.Cu")
		(net "M_H_DQ<44>")
	)
	(gr_poly
		(pts
			(xy 111.835692 -46.901608) (xy 111.784892 -46.901608) (xy 111.594392 -46.914308) (xy 111.594392 -47.015908)
			(xy 111.784892 -47.028608) (xy 111.835692 -47.028608)
		)
		(stroke
			(width 0)
			(type solid)
		)
		(fill yes)
		(layer "F.Cu")
		(net "M_H_DQ<44>")
	)
	(gr_poly
		(pts
			(xy 111.909606 -105.69829) (xy 111.87811 -105.666794) (xy 111.678974 -105.593134) (xy 111.517176 -105.754932)
			(xy 111.590836 -105.954068) (xy 111.622332 -105.985564)
		)
		(stroke
			(width 0)
			(type solid)
		)
		(fill yes)
		(layer "F.Cu")
		(net "M_K_DQ<34>")
	)
	(gr_poly
		(pts
			(xy 111.969042 -111.349536) (xy 111.969042 -111.247936) (xy 111.778542 -111.235236) (xy 111.727742 -111.235236)
			(xy 111.727742 -111.362236) (xy 111.778542 -111.362236)
		)
		(stroke
			(width 0)
			(type solid)
		)
		(fill yes)
		(layer "F.Cu")
		(net "M_K_DQ<35>")
	)
	(gr_poly
		(pts
			(xy 111.969042 -110.689136) (xy 111.969042 -110.587536) (xy 111.778542 -110.574836) (xy 111.727742 -110.574836)
			(xy 111.727742 -110.701836) (xy 111.778542 -110.701836)
		)
		(stroke
			(width 0)
			(type solid)
		)
		(fill yes)
		(layer "F.Cu")
		(net "M_K_DQ<35>")
	)
	(gr_poly
		(pts
			(xy 111.969042 -110.028736) (xy 111.969042 -109.927136) (xy 111.778542 -109.914436) (xy 111.727742 -109.914436)
			(xy 111.727742 -110.041436) (xy 111.778542 -110.041436)
		)
		(stroke
			(width 0)
			(type solid)
		)
		(fill yes)
		(layer "F.Cu")
		(net "M_K_DQ<35>")
	)
	(gr_poly
		(pts
			(xy 111.969042 -109.368336) (xy 111.969042 -109.266736) (xy 111.778542 -109.254036) (xy 111.727742 -109.254036)
			(xy 111.727742 -109.381036) (xy 111.778542 -109.381036)
		)
		(stroke
			(width 0)
			(type solid)
		)
		(fill yes)
		(layer "F.Cu")
		(net "M_K_DQ<35>")
	)
	(gr_poly
		(pts
			(xy 111.969042 -108.707936) (xy 111.969042 -108.606336) (xy 111.778542 -108.593636) (xy 111.727742 -108.593636)
			(xy 111.727742 -108.720636) (xy 111.778542 -108.720636)
		)
		(stroke
			(width 0)
			(type solid)
		)
		(fill yes)
		(layer "F.Cu")
		(net "M_K_DQ<35>")
	)
	(gr_poly
		(pts
			(xy 111.969042 -108.047536) (xy 111.969042 -107.945936) (xy 111.778542 -107.933236) (xy 111.727742 -107.933236)
			(xy 111.727742 -108.060236) (xy 111.778542 -108.060236)
		)
		(stroke
			(width 0)
			(type solid)
		)
		(fill yes)
		(layer "F.Cu")
		(net "M_K_DQ<35>")
	)
	(gr_poly
		(pts
			(xy 111.969042 -107.387136) (xy 111.969042 -107.285536) (xy 111.778542 -107.272836) (xy 111.727742 -107.272836)
			(xy 111.727742 -107.399836) (xy 111.778542 -107.399836)
		)
		(stroke
			(width 0)
			(type solid)
		)
		(fill yes)
		(layer "F.Cu")
		(net "M_K_DQ<35>")
	)
	(gr_poly
		(pts
			(xy 112.032796 -103.953818) (xy 112.071404 -103.931466) (xy 111.86795 -103.579676) (xy 111.829596 -103.601774)
			(xy 111.706914 -103.77551) (xy 111.821214 -103.973376)
		)
		(stroke
			(width 0)
			(type solid)
		)
		(fill yes)
		(layer "F.Cu")
		(net "M_K_DQ<34>")
	)
	(gr_poly
		(pts
			(xy 112.076992 -49.327308) (xy 112.076992 -49.225708) (xy 111.886492 -49.213008) (xy 111.835692 -49.213008)
			(xy 111.835692 -49.340008) (xy 111.886492 -49.340008)
		)
		(stroke
			(width 0)
			(type solid)
		)
		(fill yes)
		(layer "F.Cu")
		(net "M_H_DQ<44>")
	)
	(gr_poly
		(pts
			(xy 112.076992 -48.666908) (xy 112.076992 -48.565308) (xy 111.886492 -48.552608) (xy 111.835692 -48.552608)
			(xy 111.835692 -48.679608) (xy 111.886492 -48.679608)
		)
		(stroke
			(width 0)
			(type solid)
		)
		(fill yes)
		(layer "F.Cu")
		(net "M_H_DQ<44>")
	)
	(gr_poly
		(pts
			(xy 112.076992 -48.006508) (xy 112.076992 -47.904908) (xy 111.886492 -47.892208) (xy 111.835692 -47.892208)
			(xy 111.835692 -48.019208) (xy 111.886492 -48.019208)
		)
		(stroke
			(width 0)
			(type solid)
		)
		(fill yes)
		(layer "F.Cu")
		(net "M_H_DQ<44>")
	)
	(gr_poly
		(pts
			(xy 112.076992 -47.346108) (xy 112.076992 -47.244508) (xy 111.886492 -47.231808) (xy 111.835692 -47.231808)
			(xy 111.835692 -47.358808) (xy 111.886492 -47.358808)
		)
		(stroke
			(width 0)
			(type solid)
		)
		(fill yes)
		(layer "F.Cu")
		(net "M_H_DQ<44>")
	)
	(gr_poly
		(pts
			(xy 112.096296 -104.542336) (xy 112.051846 -104.542336) (xy 111.858806 -104.631236) (xy 111.858806 -104.859836)
			(xy 112.051846 -104.948736) (xy 112.096296 -104.948736)
		)
		(stroke
			(width 0)
			(type solid)
		)
		(fill yes)
		(layer "F.Cu")
		(net "M_K_DQ<34>")
	)
	(gr_poly
		(pts
			(xy 112.14989 -102.579424) (xy 112.14989 -102.358444) (xy 111.97971 -102.269544) (xy 111.93526 -102.269544)
			(xy 111.93526 -102.668324) (xy 111.97971 -102.668324)
		)
		(stroke
			(width 0)
			(type solid)
		)
		(fill yes)
		(layer "F.Cu")
		(net "M_K_DQ<35>")
	)
	(gr_poly
		(pts
			(xy 112.14989 -52.052474) (xy 112.14989 -51.831494) (xy 111.97971 -51.742594) (xy 111.93526 -51.742594)
			(xy 111.93526 -52.141374) (xy 111.97971 -52.141374)
		)
		(stroke
			(width 0)
			(type solid)
		)
		(fill yes)
		(layer "F.Cu")
		(net "M_H_DQ<45>")
	)
	(gr_poly
		(pts
			(xy 112.163098 -106.077258) (xy 112.089438 -105.878122) (xy 112.057942 -105.846626) (xy 111.770668 -106.1339)
			(xy 111.802164 -106.165396) (xy 112.0013 -106.239056)
		)
		(stroke
			(width 0)
			(type solid)
		)
		(fill yes)
		(layer "F.Cu")
		(net "M_K_DQ<35>")
	)
	(gr_poly
		(pts
			(xy 112.185704 -46.694598) (xy 112.059974 -46.550834) (xy 112.023906 -46.51502) (xy 111.934244 -46.604682)
			(xy 111.970058 -46.64075) (xy 112.113822 -46.76648)
		)
		(stroke
			(width 0)
			(type solid)
		)
		(fill yes)
		(layer "F.Cu")
		(net "M_H_DQ<44>")
	)
	(gr_poly
		(pts
			(xy 112.229392 -49.543208) (xy 112.178592 -49.543208) (xy 111.988092 -49.555908) (xy 111.988092 -49.657508)
			(xy 112.178592 -49.670208) (xy 112.229392 -49.670208)
		)
		(stroke
			(width 0)
			(type solid)
		)
		(fill yes)
		(layer "F.Cu")
		(net "M_H_DQ<45>")
	)
	(gr_poly
		(pts
			(xy 112.229392 -48.882808) (xy 112.178592 -48.882808) (xy 111.988092 -48.895508) (xy 111.988092 -48.997108)
			(xy 112.178592 -49.009808) (xy 112.229392 -49.009808)
		)
		(stroke
			(width 0)
			(type solid)
		)
		(fill yes)
		(layer "F.Cu")
		(net "M_H_DQ<45>")
	)
	(gr_poly
		(pts
			(xy 112.229392 -48.222408) (xy 112.178592 -48.222408) (xy 111.988092 -48.235108) (xy 111.988092 -48.336708)
			(xy 112.178592 -48.349408) (xy 112.229392 -48.349408)
		)
		(stroke
			(width 0)
			(type solid)
		)
		(fill yes)
		(layer "F.Cu")
		(net "M_H_DQ<45>")
	)
	(gr_poly
		(pts
			(xy 112.229392 -47.562008) (xy 112.178592 -47.562008) (xy 111.988092 -47.574708) (xy 111.988092 -47.676308)
			(xy 112.178592 -47.689008) (xy 112.229392 -47.689008)
		)
		(stroke
			(width 0)
			(type solid)
		)
		(fill yes)
		(layer "F.Cu")
		(net "M_H_DQ<45>")
	)
	(gr_poly
		(pts
			(xy 112.257332 -46.281594) (xy 112.221518 -46.245526) (xy 112.077754 -46.119796) (xy 112.006126 -46.191678)
			(xy 112.131602 -46.335442) (xy 112.16767 -46.371256)
		)
		(stroke
			(width 0)
			(type solid)
		)
		(fill yes)
		(layer "F.Cu")
		(net "M_H_DQ<44>")
	)
	(gr_poly
		(pts
			(xy 112.274604 -103.814118) (xy 112.397032 -103.640636) (xy 112.282732 -103.442516) (xy 112.07115 -103.462328)
			(xy 112.032542 -103.484426) (xy 112.235996 -103.83647)
		)
		(stroke
			(width 0)
			(type solid)
		)
		(fill yes)
		(layer "F.Cu")
		(net "M_K_DQ<35>")
	)
	(gr_poly
		(pts
			(xy 112.470692 -49.327308) (xy 112.470692 -49.225708) (xy 112.280192 -49.213008) (xy 112.229392 -49.213008)
			(xy 112.229392 -49.340008) (xy 112.280192 -49.340008)
		)
		(stroke
			(width 0)
			(type solid)
		)
		(fill yes)
		(layer "F.Cu")
		(net "M_H_DQ<45>")
	)
	(gr_poly
		(pts
			(xy 112.470692 -48.666908) (xy 112.470692 -48.565308) (xy 112.280192 -48.552608) (xy 112.229392 -48.552608)
			(xy 112.229392 -48.679608) (xy 112.280192 -48.679608)
		)
		(stroke
			(width 0)
			(type solid)
		)
		(fill yes)
		(layer "F.Cu")
		(net "M_H_DQ<45>")
	)
	(gr_poly
		(pts
			(xy 112.470692 -48.006508) (xy 112.470692 -47.904908) (xy 112.280192 -47.892208) (xy 112.229392 -47.892208)
			(xy 112.229392 -48.019208) (xy 112.280192 -48.019208)
		)
		(stroke
			(width 0)
			(type solid)
		)
		(fill yes)
		(layer "F.Cu")
		(net "M_H_DQ<45>")
	)
	(gr_poly
		(pts
			(xy 112.470692 -47.346108) (xy 112.470692 -47.244508) (xy 112.280192 -47.231808) (xy 112.229392 -47.231808)
			(xy 112.229392 -47.358808) (xy 112.280192 -47.358808)
		)
		(stroke
			(width 0)
			(type solid)
		)
		(fill yes)
		(layer "F.Cu")
		(net "M_H_DQ<45>")
	)
	(gr_poly
		(pts
			(xy 112.524286 -104.859836) (xy 112.524286 -104.631236) (xy 112.331246 -104.542336) (xy 112.286796 -104.542336)
			(xy 112.286796 -104.948736) (xy 112.331246 -104.948736)
		)
		(stroke
			(width 0)
			(type solid)
		)
		(fill yes)
		(layer "F.Cu")
		(net "M_K_DQ<35>")
	)
	(gr_poly
		(pts
			(xy 112.53597 -46.559978) (xy 112.500156 -46.524164) (xy 112.356392 -46.398434) (xy 112.28451 -46.470062)
			(xy 112.41024 -46.613826) (xy 112.446054 -46.649894)
		)
		(stroke
			(width 0)
			(type solid)
		)
		(fill yes)
		(layer "F.Cu")
		(net "M_H_DQ<45>")
	)
	(gr_poly
		(pts
			(xy 112.623092 -48.882808) (xy 112.572292 -48.882808) (xy 112.381792 -48.895508) (xy 112.381792 -48.997108)
			(xy 112.572292 -49.009808) (xy 112.623092 -49.009808)
		)
		(stroke
			(width 0)
			(type solid)
		)
		(fill yes)
		(layer "F.Cu")
		(net "M_H_DQ<40>")
	)
	(gr_poly
		(pts
			(xy 112.623092 -48.222408) (xy 112.572292 -48.222408) (xy 112.381792 -48.235108) (xy 112.381792 -48.336708)
			(xy 112.572292 -48.349408) (xy 112.623092 -48.349408)
		)
		(stroke
			(width 0)
			(type solid)
		)
		(fill yes)
		(layer "F.Cu")
		(net "M_H_DQ<40>")
	)
	(gr_poly
		(pts
			(xy 112.623092 -47.562008) (xy 112.572292 -47.562008) (xy 112.381792 -47.574708) (xy 112.381792 -47.676308)
			(xy 112.572292 -47.689008) (xy 112.623092 -47.689008)
		)
		(stroke
			(width 0)
			(type solid)
		)
		(fill yes)
		(layer "F.Cu")
		(net "M_H_DQ<40>")
	)
	(gr_poly
		(pts
			(xy 112.652556 -46.227492) (xy 112.526826 -46.083982) (xy 112.491012 -46.047914) (xy 112.401096 -46.13783)
			(xy 112.437164 -46.173644) (xy 112.580674 -46.299374)
		)
		(stroke
			(width 0)
			(type solid)
		)
		(fill yes)
		(layer "F.Cu")
		(net "M_H_DQ<44>")
	)
	(gr_poly
		(pts
			(xy 112.724438 -45.814488) (xy 112.688624 -45.778674) (xy 112.54486 -45.652944) (xy 112.472978 -45.724826)
			(xy 112.598708 -45.868336) (xy 112.634522 -45.904404)
		)
		(stroke
			(width 0)
			(type solid)
		)
		(fill yes)
		(layer "F.Cu")
		(net "M_H_DQ<44>")
	)
	(gr_poly
		(pts
			(xy 112.78489 -50.946558) (xy 112.74044 -50.946558) (xy 112.57026 -51.035458) (xy 112.57026 -51.256438)
			(xy 112.74044 -51.345338) (xy 112.78489 -51.345338)
		)
		(stroke
			(width 0)
			(type solid)
		)
		(fill yes)
		(layer "F.Cu")
		(net "M_H_DQ<40>")
	)
	(gr_poly
		(pts
			(xy 112.814354 -46.838616) (xy 112.77854 -46.802548) (xy 112.634776 -46.676818) (xy 112.563148 -46.7487)
			(xy 112.688624 -46.892464) (xy 112.724692 -46.928278)
		)
		(stroke
			(width 0)
			(type solid)
		)
		(fill yes)
		(layer "F.Cu")
		(net "M_H_DQ<40>")
	)
	(gr_poly
		(pts
			(xy 112.864392 -49.327308) (xy 112.864392 -49.225708) (xy 112.673892 -49.213008) (xy 112.623092 -49.213008)
			(xy 112.623092 -49.340008) (xy 112.673892 -49.340008)
		)
		(stroke
			(width 0)
			(type solid)
		)
		(fill yes)
		(layer "F.Cu")
		(net "M_H_DQ<40>")
	)
	(gr_poly
		(pts
			(xy 112.864392 -48.666908) (xy 112.864392 -48.565308) (xy 112.673892 -48.552608) (xy 112.623092 -48.552608)
			(xy 112.623092 -48.679608) (xy 112.673892 -48.679608)
		)
		(stroke
			(width 0)
			(type solid)
		)
		(fill yes)
		(layer "F.Cu")
		(net "M_H_DQ<40>")
	)
	(gr_poly
		(pts
			(xy 112.864392 -48.006508) (xy 112.864392 -47.904908) (xy 112.673892 -47.892208) (xy 112.623092 -47.892208)
			(xy 112.623092 -48.019208) (xy 112.673892 -48.019208)
		)
		(stroke
			(width 0)
			(type solid)
		)
		(fill yes)
		(layer "F.Cu")
		(net "M_H_DQ<40>")
	)
	(gr_poly
		(pts
			(xy 112.864392 -47.346108) (xy 112.864392 -47.244508) (xy 112.673892 -47.231808) (xy 112.623092 -47.231808)
			(xy 112.623092 -47.358808) (xy 112.673892 -47.358808)
		)
		(stroke
			(width 0)
			(type solid)
		)
		(fill yes)
		(layer "F.Cu")
		(net "M_H_DQ<40>")
	)
	(gr_poly
		(pts
			(xy 112.931194 -46.50613) (xy 112.805464 -46.362366) (xy 112.769396 -46.326552) (xy 112.679734 -46.416214)
			(xy 112.715548 -46.452282) (xy 112.859312 -46.578012)
		)
		(stroke
			(width 0)
			(type solid)
		)
		(fill yes)
		(layer "F.Cu")
		(net "M_H_DQ<45>")
	)
	(gr_poly
		(pts
			(xy 113.002822 -46.093126) (xy 112.967008 -46.057058) (xy 112.823244 -45.931328) (xy 112.751362 -46.00321)
			(xy 112.877092 -46.146974) (xy 112.91316 -46.182788)
		)
		(stroke
			(width 0)
			(type solid)
		)
		(fill yes)
		(layer "F.Cu")
		(net "M_H_DQ<45>")
	)
	(gr_poly
		(pts
			(xy 113.016792 -49.543208) (xy 112.965992 -49.543208) (xy 112.775492 -49.555908) (xy 112.775492 -49.657508)
			(xy 112.965992 -49.670208) (xy 113.016792 -49.670208)
		)
		(stroke
			(width 0)
			(type solid)
		)
		(fill yes)
		(layer "F.Cu")
		(net "M_H_DQ<41>")
	)
	(gr_poly
		(pts
			(xy 113.016792 -48.882808) (xy 112.965992 -48.882808) (xy 112.775492 -48.895508) (xy 112.775492 -48.997108)
			(xy 112.965992 -49.009808) (xy 113.016792 -49.009808)
		)
		(stroke
			(width 0)
			(type solid)
		)
		(fill yes)
		(layer "F.Cu")
		(net "M_H_DQ<41>")
	)
	(gr_poly
		(pts
			(xy 113.016792 -48.222408) (xy 112.965992 -48.222408) (xy 112.775492 -48.235108) (xy 112.775492 -48.336708)
			(xy 112.965992 -48.349408) (xy 113.016792 -48.349408)
		)
		(stroke
			(width 0)
			(type solid)
		)
		(fill yes)
		(layer "F.Cu")
		(net "M_H_DQ<41>")
	)
	(gr_poly
		(pts
			(xy 113.016792 -47.562008) (xy 112.965992 -47.562008) (xy 112.775492 -47.574708) (xy 112.775492 -47.676308)
			(xy 112.965992 -47.689008) (xy 113.016792 -47.689008)
		)
		(stroke
			(width 0)
			(type solid)
		)
		(fill yes)
		(layer "F.Cu")
		(net "M_H_DQ<41>")
	)
	(gr_poly
		(pts
			(xy 113.119662 -45.76064) (xy 112.993932 -45.616876) (xy 112.957864 -45.581062) (xy 112.868202 -45.670724)
			(xy 112.904016 -45.706792) (xy 113.04778 -45.832522)
		)
		(stroke
			(width 0)
			(type solid)
		)
		(fill yes)
		(layer "F.Cu")
		(net "M_H_DQ<44>")
	)
	(gr_poly
		(pts
			(xy 113.19002 -51.3842) (xy 113.19002 -51.16322) (xy 113.01984 -51.07432) (xy 112.97539 -51.07432)
			(xy 112.97539 -51.4731) (xy 113.01984 -51.4731)
		)
		(stroke
			(width 0)
			(type solid)
		)
		(fill yes)
		(layer "F.Cu")
		(net "M_H_DQ<41>")
	)
	(gr_poly
		(pts
			(xy 113.19129 -45.347636) (xy 113.155476 -45.311568) (xy 113.011712 -45.185838) (xy 112.93983 -45.25772)
			(xy 113.06556 -45.401484) (xy 113.101628 -45.437298)
		)
		(stroke
			(width 0)
			(type solid)
		)
		(fill yes)
		(layer "F.Cu")
		(net "M_H_DQ<44>")
	)
	(gr_poly
		(pts
			(xy 113.209578 -46.784514) (xy 113.083848 -46.641004) (xy 113.048034 -46.604936) (xy 112.958118 -46.694852)
			(xy 112.994186 -46.730666) (xy 113.137696 -46.856396)
		)
		(stroke
			(width 0)
			(type solid)
		)
		(fill yes)
		(layer "F.Cu")
		(net "M_H_DQ<40>")
	)
	(gr_poly
		(pts
			(xy 113.258092 -49.327308) (xy 113.258092 -49.225708) (xy 113.067592 -49.213008) (xy 113.016792 -49.213008)
			(xy 113.016792 -49.340008) (xy 113.067592 -49.340008)
		)
		(stroke
			(width 0)
			(type solid)
		)
		(fill yes)
		(layer "F.Cu")
		(net "M_H_DQ<41>")
	)
	(gr_poly
		(pts
			(xy 113.258092 -48.666908) (xy 113.258092 -48.565308) (xy 113.067592 -48.552608) (xy 113.016792 -48.552608)
			(xy 113.016792 -48.679608) (xy 113.067592 -48.679608)
		)
		(stroke
			(width 0)
			(type solid)
		)
		(fill yes)
		(layer "F.Cu")
		(net "M_H_DQ<41>")
	)
	(gr_poly
		(pts
			(xy 113.258092 -48.006508) (xy 113.258092 -47.904908) (xy 113.067592 -47.892208) (xy 113.016792 -47.892208)
			(xy 113.016792 -48.019208) (xy 113.067592 -48.019208)
		)
		(stroke
			(width 0)
			(type solid)
		)
		(fill yes)
		(layer "F.Cu")
		(net "M_H_DQ<41>")
	)
	(gr_poly
		(pts
			(xy 113.28146 -46.37151) (xy 113.245646 -46.335696) (xy 113.101882 -46.209966) (xy 113.03 -46.281848)
			(xy 113.15573 -46.425358) (xy 113.191544 -46.461426)
		)
		(stroke
			(width 0)
			(type solid)
		)
		(fill yes)
		(layer "F.Cu")
		(net "M_H_DQ<40>")
	)
	(gr_poly
		(pts
			(xy 113.302288 -109.417104) (xy 113.251488 -109.417104) (xy 113.060988 -109.429804) (xy 113.060988 -109.531404)
			(xy 113.251488 -109.544104) (xy 113.302288 -109.544104)
		)
		(stroke
			(width 0)
			(type solid)
		)
		(fill yes)
		(layer "F.Cu")
		(net "M_L_DQ<44>")
	)
	(gr_poly
		(pts
			(xy 113.302288 -108.756704) (xy 113.251488 -108.756704) (xy 113.060988 -108.769404) (xy 113.060988 -108.871004)
			(xy 113.251488 -108.883704) (xy 113.302288 -108.883704)
		)
		(stroke
			(width 0)
			(type solid)
		)
		(fill yes)
		(layer "F.Cu")
		(net "M_L_DQ<44>")
	)
	(gr_poly
		(pts
			(xy 113.302288 -108.096304) (xy 113.251488 -108.096304) (xy 113.060988 -108.109004) (xy 113.060988 -108.210604)
			(xy 113.251488 -108.223304) (xy 113.302288 -108.223304)
		)
		(stroke
			(width 0)
			(type solid)
		)
		(fill yes)
		(layer "F.Cu")
		(net "M_L_DQ<44>")
	)
	(gr_poly
		(pts
			(xy 113.302288 -107.435904) (xy 113.251488 -107.435904) (xy 113.060988 -107.448604) (xy 113.060988 -107.550204)
			(xy 113.251488 -107.562904) (xy 113.302288 -107.562904)
		)
		(stroke
			(width 0)
			(type solid)
		)
		(fill yes)
		(layer "F.Cu")
		(net "M_L_DQ<44>")
	)
	(gr_poly
		(pts
			(xy 113.302288 -106.775504) (xy 113.251488 -106.775504) (xy 113.060988 -106.788204) (xy 113.060988 -106.889804)
			(xy 113.251488 -106.902504) (xy 113.302288 -106.902504)
		)
		(stroke
			(width 0)
			(type solid)
		)
		(fill yes)
		(layer "F.Cu")
		(net "M_L_DQ<44>")
	)
	(gr_poly
		(pts
			(xy 113.302288 -106.115104) (xy 113.251488 -106.115104) (xy 113.060988 -106.127804) (xy 113.060988 -106.229404)
			(xy 113.251488 -106.242104) (xy 113.302288 -106.242104)
		)
		(stroke
			(width 0)
			(type solid)
		)
		(fill yes)
		(layer "F.Cu")
		(net "M_L_DQ<44>")
	)
	(gr_poly
		(pts
			(xy 113.398046 -46.039024) (xy 113.272316 -45.895514) (xy 113.236502 -45.859446) (xy 113.146586 -45.949362)
			(xy 113.182654 -45.985176) (xy 113.326164 -46.110906)
		)
		(stroke
			(width 0)
			(type solid)
		)
		(fill yes)
		(layer "F.Cu")
		(net "M_H_DQ<45>")
	)
	(gr_poly
		(pts
			(xy 113.403888 -105.233216) (xy 113.359438 -105.233216) (xy 113.166398 -105.322116) (xy 113.166398 -105.550716)
			(xy 113.359438 -105.639616) (xy 113.403888 -105.639616)
		)
		(stroke
			(width 0)
			(type solid)
		)
		(fill yes)
		(layer "F.Cu")
		(net "M_L_DQ<44>")
	)
	(gr_poly
		(pts
			(xy 113.403888 -104.344216) (xy 113.359438 -104.344216) (xy 113.166398 -104.433116) (xy 113.166398 -104.661716)
			(xy 113.359438 -104.750616) (xy 113.403888 -104.750616)
		)
		(stroke
			(width 0)
			(type solid)
		)
		(fill yes)
		(layer "F.Cu")
		(net "M_L_DQ<44>")
	)
	(gr_poly
		(pts
			(xy 113.410492 -48.882808) (xy 113.359692 -48.882808) (xy 113.169192 -48.895508) (xy 113.169192 -48.997108)
			(xy 113.359692 -49.009808) (xy 113.410492 -49.009808)
		)
		(stroke
			(width 0)
			(type solid)
		)
		(fill yes)
		(layer "F.Cu")
		(net "M_H_DQS_DP<14>")
	)
	(gr_poly
		(pts
			(xy 113.410492 -48.222408) (xy 113.359692 -48.222408) (xy 113.169192 -48.235108) (xy 113.169192 -48.336708)
			(xy 113.359692 -48.349408) (xy 113.410492 -48.349408)
		)
		(stroke
			(width 0)
			(type solid)
		)
		(fill yes)
		(layer "F.Cu")
		(net "M_H_DQS_DP<14>")
	)
	(gr_poly
		(pts
			(xy 113.410492 -47.562008) (xy 113.359692 -47.562008) (xy 113.169192 -47.574708) (xy 113.169192 -47.676308)
			(xy 113.359692 -47.689008) (xy 113.410492 -47.689008)
		)
		(stroke
			(width 0)
			(type solid)
		)
		(fill yes)
		(layer "F.Cu")
		(net "M_H_DQS_DP<14>")
	)
	(gr_poly
		(pts
			(xy 113.469928 -45.62602) (xy 113.43386 -45.590206) (xy 113.29035 -45.464476) (xy 113.218468 -45.536358)
			(xy 113.344198 -45.679868) (xy 113.380012 -45.715936)
		)
		(stroke
			(width 0)
			(type solid)
		)
		(fill yes)
		(layer "F.Cu")
		(net "M_H_DQ<45>")
	)
	(gr_poly
		(pts
			(xy 113.488216 -47.063152) (xy 113.362486 -46.919388) (xy 113.326418 -46.883574) (xy 113.236756 -46.973236)
			(xy 113.27257 -47.009304) (xy 113.416334 -47.135034)
		)
		(stroke
			(width 0)
			(type solid)
		)
		(fill yes)
		(layer "F.Cu")
		(net "M_H_DQ<41>")
	)
	(gr_poly
		(pts
			(xy 113.510568 -50.359056) (xy 113.466118 -50.359056) (xy 113.295938 -50.447956) (xy 113.295938 -50.668936)
			(xy 113.466118 -50.757836) (xy 113.510568 -50.757836)
		)
		(stroke
			(width 0)
			(type solid)
		)
		(fill yes)
		(layer "F.Cu")
		(net "M_H_DQS_DP<14>")
	)
	(gr_poly
		(pts
			(xy 113.519966 -100.782374) (xy 113.475516 -100.782374) (xy 113.305082 -100.871274) (xy 113.305082 -101.092)
			(xy 113.475008 -101.181154) (xy 113.519204 -101.181154)
		)
		(stroke
			(width 0)
			(type solid)
		)
		(fill yes)
		(layer "F.Cu")
		(net "M_L_DQ<44>")
	)
	(gr_poly
		(pts
			(xy 113.543588 -109.201204) (xy 113.543588 -109.099604) (xy 113.353088 -109.086904) (xy 113.302288 -109.086904)
			(xy 113.302288 -109.213904) (xy 113.353088 -109.213904)
		)
		(stroke
			(width 0)
			(type solid)
		)
		(fill yes)
		(layer "F.Cu")
		(net "M_L_DQ<44>")
	)
	(gr_poly
		(pts
			(xy 113.543588 -108.540804) (xy 113.543588 -108.439204) (xy 113.353088 -108.426504) (xy 113.302288 -108.426504)
			(xy 113.302288 -108.553504) (xy 113.353088 -108.553504)
		)
		(stroke
			(width 0)
			(type solid)
		)
		(fill yes)
		(layer "F.Cu")
		(net "M_L_DQ<44>")
	)
	(gr_poly
		(pts
			(xy 113.543588 -107.880404) (xy 113.543588 -107.778804) (xy 113.353088 -107.766104) (xy 113.302288 -107.766104)
			(xy 113.302288 -107.893104) (xy 113.353088 -107.893104)
		)
		(stroke
			(width 0)
			(type solid)
		)
		(fill yes)
		(layer "F.Cu")
		(net "M_L_DQ<44>")
	)
	(gr_poly
		(pts
			(xy 113.543588 -107.220004) (xy 113.543588 -107.118404) (xy 113.353088 -107.105704) (xy 113.302288 -107.105704)
			(xy 113.302288 -107.232704) (xy 113.353088 -107.232704)
		)
		(stroke
			(width 0)
			(type solid)
		)
		(fill yes)
		(layer "F.Cu")
		(net "M_L_DQ<44>")
	)
	(gr_poly
		(pts
			(xy 113.543588 -106.559604) (xy 113.543588 -106.458004) (xy 113.353088 -106.445304) (xy 113.302288 -106.445304)
			(xy 113.302288 -106.572304) (xy 113.353088 -106.572304)
		)
		(stroke
			(width 0)
			(type solid)
		)
		(fill yes)
		(layer "F.Cu")
		(net "M_L_DQ<44>")
	)
	(gr_poly
		(pts
			(xy 113.559844 -46.650148) (xy 113.52403 -46.61408) (xy 113.380266 -46.48835) (xy 113.308384 -46.560232)
			(xy 113.434114 -46.703996) (xy 113.470182 -46.73981)
		)
		(stroke
			(width 0)
			(type solid)
		)
		(fill yes)
		(layer "F.Cu")
		(net "M_H_DQ<41>")
	)
	(gr_poly
		(pts
			(xy 113.586514 -45.293534) (xy 113.460784 -45.150024) (xy 113.42497 -45.113956) (xy 113.335054 -45.203872)
			(xy 113.371122 -45.239686) (xy 113.514632 -45.365416)
		)
		(stroke
			(width 0)
			(type solid)
		)
		(fill yes)
		(layer "F.Cu")
		(net "M_H_DQ<44>")
	)
	(gr_poly
		(pts
			(xy 113.651792 -49.327308) (xy 113.651792 -49.225708) (xy 113.461292 -49.213008) (xy 113.410492 -49.213008)
			(xy 113.410492 -49.340008) (xy 113.461292 -49.340008)
		)
		(stroke
			(width 0)
			(type solid)
		)
		(fill yes)
		(layer "F.Cu")
		(net "M_H_DQS_DP<14>")
	)
	(gr_poly
		(pts
			(xy 113.651792 -48.666908) (xy 113.651792 -48.565308) (xy 113.461292 -48.552608) (xy 113.410492 -48.552608)
			(xy 113.410492 -48.679608) (xy 113.461292 -48.679608)
		)
		(stroke
			(width 0)
			(type solid)
		)
		(fill yes)
		(layer "F.Cu")
		(net "M_H_DQS_DP<14>")
	)
	(gr_poly
		(pts
			(xy 113.651792 -48.006508) (xy 113.651792 -47.904908) (xy 113.461292 -47.892208) (xy 113.410492 -47.892208)
			(xy 113.410492 -48.019208) (xy 113.461292 -48.019208)
		)
		(stroke
			(width 0)
			(type solid)
		)
		(fill yes)
		(layer "F.Cu")
		(net "M_H_DQS_DP<14>")
	)
	(gr_poly
		(pts
			(xy 113.658396 -44.88053) (xy 113.622328 -44.844716) (xy 113.478818 -44.718986) (xy 113.406936 -44.790868)
			(xy 113.532666 -44.934378) (xy 113.56848 -44.970446)
		)
		(stroke
			(width 0)
			(type solid)
		)
		(fill yes)
		(layer "F.Cu")
		(net "M_H_DQ<44>")
	)
	(gr_poly
		(pts
			(xy 113.661698 -110.07471) (xy 113.787428 -109.9312) (xy 113.715546 -109.859318) (xy 113.572036 -109.985048)
			(xy 113.535968 -110.020862) (xy 113.625884 -110.110778)
		)
		(stroke
			(width 0)
			(type solid)
		)
		(fill yes)
		(layer "F.Cu")
		(net "M_L_DQ<44>")
	)
	(gr_poly
		(pts
			(xy 113.676684 -46.317662) (xy 113.550954 -46.173898) (xy 113.514886 -46.138084) (xy 113.425224 -46.227746)
			(xy 113.461038 -46.263814) (xy 113.604802 -46.389544)
		)
		(stroke
			(width 0)
			(type solid)
		)
		(fill yes)
		(layer "F.Cu")
		(net "M_H_DQ<40>")
	)
	(gr_poly
		(pts
			(xy 113.695988 -109.417104) (xy 113.645188 -109.417104) (xy 113.454688 -109.429804) (xy 113.454688 -109.531404)
			(xy 113.645188 -109.544104) (xy 113.695988 -109.544104)
		)
		(stroke
			(width 0)
			(type solid)
		)
		(fill yes)
		(layer "F.Cu")
		(net "M_L_DQ<45>")
	)
	(gr_poly
		(pts
			(xy 113.695988 -108.756704) (xy 113.645188 -108.756704) (xy 113.454688 -108.769404) (xy 113.454688 -108.871004)
			(xy 113.645188 -108.883704) (xy 113.695988 -108.883704)
		)
		(stroke
			(width 0)
			(type solid)
		)
		(fill yes)
		(layer "F.Cu")
		(net "M_L_DQ<45>")
	)
	(gr_poly
		(pts
			(xy 113.695988 -108.096304) (xy 113.645188 -108.096304) (xy 113.454688 -108.109004) (xy 113.454688 -108.210604)
			(xy 113.645188 -108.223304) (xy 113.695988 -108.223304)
		)
		(stroke
			(width 0)
			(type solid)
		)
		(fill yes)
		(layer "F.Cu")
		(net "M_L_DQ<45>")
	)
	(gr_poly
		(pts
			(xy 113.695988 -107.435904) (xy 113.645188 -107.435904) (xy 113.454688 -107.448604) (xy 113.454688 -107.550204)
			(xy 113.645188 -107.562904) (xy 113.695988 -107.562904)
		)
		(stroke
			(width 0)
			(type solid)
		)
		(fill yes)
		(layer "F.Cu")
		(net "M_L_DQ<45>")
	)
	(gr_poly
		(pts
			(xy 113.695988 -106.775504) (xy 113.645188 -106.775504) (xy 113.454688 -106.788204) (xy 113.454688 -106.889804)
			(xy 113.645188 -106.902504) (xy 113.695988 -106.902504)
		)
		(stroke
			(width 0)
			(type solid)
		)
		(fill yes)
		(layer "F.Cu")
		(net "M_L_DQ<45>")
	)
	(gr_poly
		(pts
			(xy 113.695988 -106.115104) (xy 113.645188 -106.115104) (xy 113.454688 -106.127804) (xy 113.454688 -106.229404)
			(xy 113.645188 -106.242104) (xy 113.695988 -106.242104)
		)
		(stroke
			(width 0)
			(type solid)
		)
		(fill yes)
		(layer "F.Cu")
		(net "M_L_DQ<45>")
	)
	(gr_poly
		(pts
			(xy 113.748312 -45.904658) (xy 113.712498 -45.86859) (xy 113.568734 -45.74286) (xy 113.496852 -45.814742)
			(xy 113.622582 -45.958506) (xy 113.65865 -45.99432)
		)
		(stroke
			(width 0)
			(type solid)
		)
		(fill yes)
		(layer "F.Cu")
		(net "M_H_DQ<40>")
	)
	(gr_poly
		(pts
			(xy 113.7666 -47.341536) (xy 113.64087 -47.198026) (xy 113.605056 -47.161958) (xy 113.51514 -47.251874)
			(xy 113.551208 -47.287688) (xy 113.694718 -47.413418)
		)
		(stroke
			(width 0)
			(type solid)
		)
		(fill yes)
		(layer "F.Cu")
		(net "M_H_DQS_DP<14>")
	)
	(gr_poly
		(pts
			(xy 113.804192 -48.882808) (xy 113.753392 -48.882808) (xy 113.562892 -48.895508) (xy 113.562892 -48.997108)
			(xy 113.753392 -49.009808) (xy 113.804192 -49.009808)
		)
		(stroke
			(width 0)
			(type solid)
		)
		(fill yes)
		(layer "F.Cu")
		(net "M_H_DQS_DN<14>")
	)
	(gr_poly
		(pts
			(xy 113.804192 -48.222408) (xy 113.753392 -48.222408) (xy 113.562892 -48.235108) (xy 113.562892 -48.336708)
			(xy 113.753392 -48.349408) (xy 113.804192 -48.349408)
		)
		(stroke
			(width 0)
			(type solid)
		)
		(fill yes)
		(layer "F.Cu")
		(net "M_H_DQS_DN<14>")
	)
	(gr_poly
		(pts
			(xy 113.823242 -110.380018) (xy 113.85931 -110.344204) (xy 113.769394 -110.254288) (xy 113.73358 -110.290356)
			(xy 113.60785 -110.433866) (xy 113.679732 -110.505748)
		)
		(stroke
			(width 0)
			(type solid)
		)
		(fill yes)
		(layer "F.Cu")
		(net "M_L_DQ<44>")
	)
	(gr_poly
		(pts
			(xy 113.831878 -105.550716) (xy 113.831878 -105.322116) (xy 113.638838 -105.233216) (xy 113.594388 -105.233216)
			(xy 113.594388 -105.639616) (xy 113.638838 -105.639616)
		)
		(stroke
			(width 0)
			(type solid)
		)
		(fill yes)
		(layer "F.Cu")
		(net "M_L_DQ<45>")
	)
	(gr_poly
		(pts
			(xy 113.831878 -104.661716) (xy 113.831878 -104.433116) (xy 113.638838 -104.344216) (xy 113.594388 -104.344216)
			(xy 113.594388 -104.750616) (xy 113.638838 -104.750616)
		)
		(stroke
			(width 0)
			(type solid)
		)
		(fill yes)
		(layer "F.Cu")
		(net "M_L_DQ<45>")
	)
	(gr_poly
		(pts
			(xy 113.838482 -46.928532) (xy 113.802668 -46.892718) (xy 113.658904 -46.766988) (xy 113.587022 -46.83887)
			(xy 113.712752 -46.98238) (xy 113.748566 -47.018448)
		)
		(stroke
			(width 0)
			(type solid)
		)
		(fill yes)
		(layer "F.Cu")
		(net "M_H_DQS_DP<14>")
	)
	(gr_poly
		(pts
			(xy 113.865152 -45.572172) (xy 113.739422 -45.428408) (xy 113.703354 -45.392594) (xy 113.613692 -45.482256)
			(xy 113.649506 -45.518324) (xy 113.79327 -45.644054)
		)
		(stroke
			(width 0)
			(type solid)
		)
		(fill yes)
		(layer "F.Cu")
		(net "M_H_DQ<45>")
	)
	(gr_poly
		(pts
			(xy 113.867438 -102.577138) (xy 113.867438 -102.356158) (xy 113.697258 -102.267258) (xy 113.652808 -102.267258)
			(xy 113.652808 -102.666038) (xy 113.697258 -102.666038)
		)
		(stroke
			(width 0)
			(type solid)
		)
		(fill yes)
		(layer "F.Cu")
		(net "M_L_DQ<45>")
	)
	(gr_poly
		(pts
			(xy 113.913412 -101.571298) (xy 114.006884 -101.371146) (xy 113.890044 -101.218746) (xy 113.849912 -101.19995)
			(xy 113.681256 -101.561138) (xy 113.721642 -101.579934)
		)
		(stroke
			(width 0)
			(type solid)
		)
		(fill yes)
		(layer "F.Cu")
		(net "M_L_DQ<45>")
	)
	(gr_poly
		(pts
			(xy 113.915698 -50.682652) (xy 113.915698 -50.461672) (xy 113.745518 -50.372772) (xy 113.701068 -50.372772)
			(xy 113.701068 -50.771552) (xy 113.745518 -50.771552)
		)
		(stroke
			(width 0)
			(type solid)
		)
		(fill yes)
		(layer "F.Cu")
		(net "M_H_DQS_DN<14>")
	)
	(gr_poly
		(pts
			(xy 113.93678 -45.159168) (xy 113.900966 -45.1231) (xy 113.757202 -44.99737) (xy 113.68532 -45.069252)
			(xy 113.81105 -45.213016) (xy 113.847118 -45.24883)
		)
		(stroke
			(width 0)
			(type solid)
		)
		(fill yes)
		(layer "F.Cu")
		(net "M_H_DQ<45>")
	)
	(gr_poly
		(pts
			(xy 113.937288 -109.201204) (xy 113.937288 -109.099604) (xy 113.746788 -109.086904) (xy 113.695988 -109.086904)
			(xy 113.695988 -109.213904) (xy 113.746788 -109.213904)
		)
		(stroke
			(width 0)
			(type solid)
		)
		(fill yes)
		(layer "F.Cu")
		(net "M_L_DQ<45>")
	)
	(gr_poly
		(pts
			(xy 113.937288 -108.540804) (xy 113.937288 -108.439204) (xy 113.746788 -108.426504) (xy 113.695988 -108.426504)
			(xy 113.695988 -108.553504) (xy 113.746788 -108.553504)
		)
		(stroke
			(width 0)
			(type solid)
		)
		(fill yes)
		(layer "F.Cu")
		(net "M_L_DQ<45>")
	)
	(gr_poly
		(pts
			(xy 113.937288 -107.880404) (xy 113.937288 -107.778804) (xy 113.746788 -107.766104) (xy 113.695988 -107.766104)
			(xy 113.695988 -107.893104) (xy 113.746788 -107.893104)
		)
		(stroke
			(width 0)
			(type solid)
		)
		(fill yes)
		(layer "F.Cu")
		(net "M_L_DQ<45>")
	)
	(gr_poly
		(pts
			(xy 113.937288 -107.220004) (xy 113.937288 -107.118404) (xy 113.746788 -107.105704) (xy 113.695988 -107.105704)
			(xy 113.695988 -107.232704) (xy 113.746788 -107.232704)
		)
		(stroke
			(width 0)
			(type solid)
		)
		(fill yes)
		(layer "F.Cu")
		(net "M_L_DQ<45>")
	)
	(gr_poly
		(pts
			(xy 113.937288 -106.559604) (xy 113.937288 -106.458004) (xy 113.746788 -106.445304) (xy 113.695988 -106.445304)
			(xy 113.695988 -106.572304) (xy 113.746788 -106.572304)
		)
		(stroke
			(width 0)
			(type solid)
		)
		(fill yes)
		(layer "F.Cu")
		(net "M_L_DQ<45>")
	)
	(gr_poly
		(pts
			(xy 113.940336 -109.796326) (xy 114.066066 -109.652562) (xy 113.994184 -109.58068) (xy 113.85042 -109.70641)
			(xy 113.814606 -109.742478) (xy 113.904268 -109.83214)
		)
		(stroke
			(width 0)
			(type solid)
		)
		(fill yes)
		(layer "F.Cu")
		(net "M_L_DQ<45>")
	)
	(gr_poly
		(pts
			(xy 113.955068 -46.596046) (xy 113.829338 -46.452536) (xy 113.793524 -46.416468) (xy 113.703608 -46.506384)
			(xy 113.739676 -46.542198) (xy 113.883186 -46.667928)
		)
		(stroke
			(width 0)
			(type solid)
		)
		(fill yes)
		(layer "F.Cu")
		(net "M_H_DQ<41>")
	)
	(gr_poly
		(pts
			(xy 114.02695 -46.183042) (xy 113.990882 -46.147228) (xy 113.847372 -46.021498) (xy 113.77549 -46.09338)
			(xy 113.90122 -46.23689) (xy 113.937034 -46.272958)
		)
		(stroke
			(width 0)
			(type solid)
		)
		(fill yes)
		(layer "F.Cu")
		(net "M_H_DQ<41>")
	)
	(gr_poly
		(pts
			(xy 114.045492 -49.327308) (xy 114.045492 -49.225708) (xy 113.854992 -49.213008) (xy 113.804192 -49.213008)
			(xy 113.804192 -49.340008) (xy 113.854992 -49.340008)
		)
		(stroke
			(width 0)
			(type solid)
		)
		(fill yes)
		(layer "F.Cu")
		(net "M_H_DQS_DN<14>")
	)
	(gr_poly
		(pts
			(xy 114.045492 -48.666908) (xy 114.045492 -48.565308) (xy 113.854992 -48.552608) (xy 113.804192 -48.552608)
			(xy 113.804192 -48.679608) (xy 113.854992 -48.679608)
		)
		(stroke
			(width 0)
			(type solid)
		)
		(fill yes)
		(layer "F.Cu")
		(net "M_H_DQS_DN<14>")
	)
	(gr_poly
		(pts
			(xy 114.045492 -48.006508) (xy 114.045492 -47.904908) (xy 113.854992 -47.892208) (xy 113.804192 -47.892208)
			(xy 113.804192 -48.019208) (xy 113.854992 -48.019208)
		)
		(stroke
			(width 0)
			(type solid)
		)
		(fill yes)
		(layer "F.Cu")
		(net "M_H_DQS_DN<14>")
	)
	(gr_poly
		(pts
			(xy 114.05362 -44.826682) (xy 113.92789 -44.682918) (xy 113.891822 -44.647104) (xy 113.80216 -44.736766)
			(xy 113.837974 -44.772834) (xy 113.981738 -44.898564)
		)
		(stroke
			(width 0)
			(type solid)
		)
		(fill yes)
		(layer "F.Cu")
		(net "M_H_DQ<44>")
	)
	(gr_poly
		(pts
			(xy 114.089688 -108.756704) (xy 114.038888 -108.756704) (xy 113.848388 -108.769404) (xy 113.848388 -108.871004)
			(xy 114.038888 -108.883704) (xy 114.089688 -108.883704)
		)
		(stroke
			(width 0)
			(type solid)
		)
		(fill yes)
		(layer "F.Cu")
		(net "M_L_DQ<40>")
	)
	(gr_poly
		(pts
			(xy 114.089688 -108.096304) (xy 114.038888 -108.096304) (xy 113.848388 -108.109004) (xy 113.848388 -108.210604)
			(xy 114.038888 -108.223304) (xy 114.089688 -108.223304)
		)
		(stroke
			(width 0)
			(type solid)
		)
		(fill yes)
		(layer "F.Cu")
		(net "M_L_DQ<40>")
	)
	(gr_poly
		(pts
			(xy 114.089688 -107.435904) (xy 114.038888 -107.435904) (xy 113.848388 -107.448604) (xy 113.848388 -107.550204)
			(xy 114.038888 -107.562904) (xy 114.089688 -107.562904)
		)
		(stroke
			(width 0)
			(type solid)
		)
		(fill yes)
		(layer "F.Cu")
		(net "M_L_DQ<40>")
	)
	(gr_poly
		(pts
			(xy 114.089688 -106.775504) (xy 114.038888 -106.775504) (xy 113.848388 -106.788204) (xy 113.848388 -106.889804)
			(xy 114.038888 -106.902504) (xy 114.089688 -106.902504)
		)
		(stroke
			(width 0)
			(type solid)
		)
		(fill yes)
		(layer "F.Cu")
		(net "M_L_DQ<40>")
	)
	(gr_poly
		(pts
			(xy 114.089688 -106.115104) (xy 114.038888 -106.115104) (xy 113.848388 -106.127804) (xy 113.848388 -106.229404)
			(xy 114.038888 -106.242104) (xy 114.089688 -106.242104)
		)
		(stroke
			(width 0)
			(type solid)
		)
		(fill yes)
		(layer "F.Cu")
		(net "M_L_DQ<40>")
	)
	(gr_poly
		(pts
			(xy 114.10188 -110.101634) (xy 114.137694 -110.065566) (xy 114.048032 -109.975904) (xy 114.011964 -110.011718)
			(xy 113.886234 -110.155482) (xy 113.958116 -110.227364)
		)
		(stroke
			(width 0)
			(type solid)
		)
		(fill yes)
		(layer "F.Cu")
		(net "M_L_DQ<45>")
	)
	(gr_poly
		(pts
			(xy 114.116866 -47.20717) (xy 114.081052 -47.171102) (xy 113.937288 -47.045372) (xy 113.865406 -47.117254)
			(xy 113.991136 -47.261018) (xy 114.027204 -47.296832)
		)
		(stroke
			(width 0)
			(type solid)
		)
		(fill yes)
		(layer "F.Cu")
		(net "M_H_DQS_DN<14>")
	)
	(gr_poly
		(pts
			(xy 114.125248 -44.413678) (xy 114.089434 -44.37761) (xy 113.94567 -44.25188) (xy 113.873788 -44.323762)
			(xy 113.999518 -44.467526) (xy 114.035586 -44.50334)
		)
		(stroke
			(width 0)
			(type solid)
		)
		(fill yes)
		(layer "F.Cu")
		(net "M_H_DQ<44>")
	)
	(gr_poly
		(pts
			(xy 114.128804 -110.541816) (xy 114.254534 -110.398052) (xy 114.182652 -110.32617) (xy 114.038888 -110.4519)
			(xy 114.003074 -110.487968) (xy 114.092736 -110.57763)
		)
		(stroke
			(width 0)
			(type solid)
		)
		(fill yes)
		(layer "F.Cu")
		(net "M_L_DQ<44>")
	)
	(gr_poly
		(pts
			(xy 114.143536 -45.850556) (xy 114.017806 -45.707046) (xy 113.981992 -45.670978) (xy 113.892076 -45.760894)
			(xy 113.928144 -45.796708) (xy 114.071654 -45.922438)
		)
		(stroke
			(width 0)
			(type solid)
		)
		(fill yes)
		(layer "F.Cu")
		(net "M_H_DQ<40>")
	)
	(gr_poly
		(pts
			(xy 114.191288 -105.108248) (xy 114.146838 -105.108248) (xy 113.953798 -105.197148) (xy 113.953798 -105.425748)
			(xy 114.146838 -105.514648) (xy 114.191288 -105.514648)
		)
		(stroke
			(width 0)
			(type solid)
		)
		(fill yes)
		(layer "F.Cu")
		(net "M_L_DQ<40>")
	)
	(gr_poly
		(pts
			(xy 114.191288 -104.117648) (xy 114.146838 -104.117648) (xy 113.953798 -104.206548) (xy 113.953798 -104.435148)
			(xy 114.146838 -104.524048) (xy 114.191288 -104.524048)
		)
		(stroke
			(width 0)
			(type solid)
		)
		(fill yes)
		(layer "F.Cu")
		(net "M_L_DQ<40>")
	)
	(gr_poly
		(pts
			(xy 114.197892 -48.882808) (xy 114.147092 -48.882808) (xy 113.956592 -48.895508) (xy 113.956592 -48.997108)
			(xy 114.147092 -49.009808) (xy 114.197892 -49.009808)
		)
		(stroke
			(width 0)
			(type solid)
		)
		(fill yes)
		(layer "F.Cu")
		(net "M_H_DQS_DN<5>")
	)
	(gr_poly
		(pts
			(xy 114.197892 -48.222408) (xy 114.147092 -48.222408) (xy 113.956592 -48.235108) (xy 113.956592 -48.336708)
			(xy 114.147092 -48.349408) (xy 114.197892 -48.349408)
		)
		(stroke
			(width 0)
			(type solid)
		)
		(fill yes)
		(layer "F.Cu")
		(net "M_H_DQS_DN<5>")
	)
	(gr_poly
		(pts
			(xy 114.215418 -45.437552) (xy 114.17935 -45.401738) (xy 114.03584 -45.276008) (xy 113.963958 -45.34789)
			(xy 114.089688 -45.4914) (xy 114.125502 -45.527468)
		)
		(stroke
			(width 0)
			(type solid)
		)
		(fill yes)
		(layer "F.Cu")
		(net "M_H_DQ<40>")
	)
	(gr_poly
		(pts
			(xy 114.233706 -46.874684) (xy 114.107976 -46.73092) (xy 114.071908 -46.695106) (xy 113.982246 -46.784768)
			(xy 114.01806 -46.820836) (xy 114.161824 -46.946566)
		)
		(stroke
			(width 0)
			(type solid)
		)
		(fill yes)
		(layer "F.Cu")
		(net "M_H_DQS_DP<14>")
	)
	(gr_poly
		(pts
			(xy 114.290348 -110.847124) (xy 114.326162 -110.811056) (xy 114.2365 -110.721394) (xy 114.200432 -110.757208)
			(xy 114.074702 -110.900972) (xy 114.146584 -110.972854)
		)
		(stroke
			(width 0)
			(type solid)
		)
		(fill yes)
		(layer "F.Cu")
		(net "M_L_DQ<44>")
	)
	(gr_poly
		(pts
			(xy 114.296952 -50.623724) (xy 114.252502 -50.623724) (xy 114.082322 -50.712624) (xy 114.082322 -50.933604)
			(xy 114.252502 -51.022504) (xy 114.296952 -51.022504)
		)
		(stroke
			(width 0)
			(type solid)
		)
		(fill yes)
		(layer "F.Cu")
		(net "M_H_DQS_DN<5>")
	)
	(gr_poly
		(pts
			(xy 114.305334 -46.46168) (xy 114.26952 -46.425612) (xy 114.125756 -46.299882) (xy 114.053874 -46.371764)
			(xy 114.179604 -46.515528) (xy 114.215672 -46.551342)
		)
		(stroke
			(width 0)
			(type solid)
		)
		(fill yes)
		(layer "F.Cu")
		(net "M_H_DQS_DP<14>")
	)
	(gr_poly
		(pts
			(xy 114.330988 -109.201204) (xy 114.330988 -109.099604) (xy 114.140488 -109.086904) (xy 114.089688 -109.086904)
			(xy 114.089688 -109.213904) (xy 114.140488 -109.213904)
		)
		(stroke
			(width 0)
			(type solid)
		)
		(fill yes)
		(layer "F.Cu")
		(net "M_L_DQ<40>")
	)
	(gr_poly
		(pts
			(xy 114.330988 -108.540804) (xy 114.330988 -108.439204) (xy 114.140488 -108.426504) (xy 114.089688 -108.426504)
			(xy 114.089688 -108.553504) (xy 114.140488 -108.553504)
		)
		(stroke
			(width 0)
			(type solid)
		)
		(fill yes)
		(layer "F.Cu")
		(net "M_L_DQ<40>")
	)
	(gr_poly
		(pts
			(xy 114.330988 -107.880404) (xy 114.330988 -107.778804) (xy 114.140488 -107.766104) (xy 114.089688 -107.766104)
			(xy 114.089688 -107.893104) (xy 114.140488 -107.893104)
		)
		(stroke
			(width 0)
			(type solid)
		)
		(fill yes)
		(layer "F.Cu")
		(net "M_L_DQ<40>")
	)
	(gr_poly
		(pts
			(xy 114.330988 -107.220004) (xy 114.330988 -107.118404) (xy 114.140488 -107.105704) (xy 114.089688 -107.105704)
			(xy 114.089688 -107.232704) (xy 114.140488 -107.232704)
		)
		(stroke
			(width 0)
			(type solid)
		)
		(fill yes)
		(layer "F.Cu")
		(net "M_L_DQ<40>")
	)
	(gr_poly
		(pts
			(xy 114.330988 -106.559604) (xy 114.330988 -106.458004) (xy 114.140488 -106.445304) (xy 114.089688 -106.445304)
			(xy 114.089688 -106.572304) (xy 114.140488 -106.572304)
		)
		(stroke
			(width 0)
			(type solid)
		)
		(fill yes)
		(layer "F.Cu")
		(net "M_L_DQ<40>")
	)
	(gr_poly
		(pts
			(xy 114.332004 -45.105066) (xy 114.206274 -44.961556) (xy 114.17046 -44.925488) (xy 114.080544 -45.015404)
			(xy 114.116358 -45.051218) (xy 114.260122 -45.176948)
		)
		(stroke
			(width 0)
			(type solid)
		)
		(fill yes)
		(layer "F.Cu")
		(net "M_H_DQ<45>")
	)
	(gr_poly
		(pts
			(xy 114.380264 -109.822996) (xy 114.416332 -109.787182) (xy 114.326416 -109.697266) (xy 114.290602 -109.733334)
			(xy 114.164872 -109.876844) (xy 114.236754 -109.948726)
		)
		(stroke
			(width 0)
			(type solid)
		)
		(fill yes)
		(layer "F.Cu")
		(net "M_L_DQ<40>")
	)
	(gr_poly
		(pts
			(xy 114.395504 -47.485554) (xy 114.35969 -47.44974) (xy 114.215926 -47.32401) (xy 114.144044 -47.395892)
			(xy 114.269774 -47.539402) (xy 114.305588 -47.57547)
		)
		(stroke
			(width 0)
			(type solid)
		)
		(fill yes)
		(layer "F.Cu")
		(net "M_H_DQS_DN<5>")
	)
	(gr_poly
		(pts
			(xy 114.403886 -44.692062) (xy 114.367818 -44.656248) (xy 114.224308 -44.530518) (xy 114.152426 -44.6024)
			(xy 114.278156 -44.74591) (xy 114.31397 -44.781978)
		)
		(stroke
			(width 0)
			(type solid)
		)
		(fill yes)
		(layer "F.Cu")
		(net "M_H_DQ<45>")
	)
	(gr_poly
		(pts
			(xy 114.407188 -110.263178) (xy 114.532918 -110.119668) (xy 114.461036 -110.047786) (xy 114.317272 -110.173516)
			(xy 114.281458 -110.20933) (xy 114.371374 -110.299246)
		)
		(stroke
			(width 0)
			(type solid)
		)
		(fill yes)
		(layer "F.Cu")
		(net "M_L_DQ<45>")
	)
	(gr_poly
		(pts
			(xy 114.422174 -46.129194) (xy 114.296444 -45.98543) (xy 114.260376 -45.949616) (xy 114.170714 -46.039278)
			(xy 114.206528 -46.075346) (xy 114.350292 -46.201076)
		)
		(stroke
			(width 0)
			(type solid)
		)
		(fill yes)
		(layer "F.Cu")
		(net "M_H_DQ<41>")
	)
	(gr_poly
		(pts
			(xy 114.42954 -100.531168) (xy 114.424968 -100.486718) (xy 114.319558 -100.326444) (xy 114.099848 -100.348542)
			(xy 114.028474 -100.526596) (xy 114.032792 -100.570792)
		)
		(stroke
			(width 0)
			(type solid)
		)
		(fill yes)
		(layer "F.Cu")
		(net "M_L_DQ<44>")
	)
	(gr_poly
		(pts
			(xy 114.439192 -49.327308) (xy 114.439192 -49.225708) (xy 114.248692 -49.213008) (xy 114.197892 -49.213008)
			(xy 114.197892 -49.340008) (xy 114.248692 -49.340008)
		)
		(stroke
			(width 0)
			(type solid)
		)
		(fill yes)
		(layer "F.Cu")
		(net "M_H_DQS_DN<5>")
	)
	(gr_poly
		(pts
			(xy 114.439192 -48.666908) (xy 114.439192 -48.565308) (xy 114.248692 -48.552608) (xy 114.197892 -48.552608)
			(xy 114.197892 -48.679608) (xy 114.248692 -48.679608)
		)
		(stroke
			(width 0)
			(type solid)
		)
		(fill yes)
		(layer "F.Cu")
		(net "M_H_DQS_DN<5>")
	)
	(gr_poly
		(pts
			(xy 114.439192 -48.006508) (xy 114.439192 -47.904908) (xy 114.248692 -47.892208) (xy 114.197892 -47.892208)
			(xy 114.197892 -48.019208) (xy 114.248692 -48.019208)
		)
		(stroke
			(width 0)
			(type solid)
		)
		(fill yes)
		(layer "F.Cu")
		(net "M_H_DQS_DN<5>")
	)
	(gr_poly
		(pts
			(xy 114.483388 -108.756704) (xy 114.432588 -108.756704) (xy 114.242088 -108.769404) (xy 114.242088 -108.871004)
			(xy 114.432588 -108.883704) (xy 114.483388 -108.883704)
		)
		(stroke
			(width 0)
			(type solid)
		)
		(fill yes)
		(layer "F.Cu")
		(net "M_L_DQ<41>")
	)
	(gr_poly
		(pts
			(xy 114.483388 -108.096304) (xy 114.432588 -108.096304) (xy 114.242088 -108.109004) (xy 114.242088 -108.210604)
			(xy 114.432588 -108.223304) (xy 114.483388 -108.223304)
		)
		(stroke
			(width 0)
			(type solid)
		)
		(fill yes)
		(layer "F.Cu")
		(net "M_L_DQ<41>")
	)
	(gr_poly
		(pts
			(xy 114.483388 -107.435904) (xy 114.432588 -107.435904) (xy 114.242088 -107.448604) (xy 114.242088 -107.550204)
			(xy 114.432588 -107.562904) (xy 114.483388 -107.562904)
		)
		(stroke
			(width 0)
			(type solid)
		)
		(fill yes)
		(layer "F.Cu")
		(net "M_L_DQ<41>")
	)
	(gr_poly
		(pts
			(xy 114.483388 -106.775504) (xy 114.432588 -106.775504) (xy 114.242088 -106.788204) (xy 114.242088 -106.889804)
			(xy 114.432588 -106.902504) (xy 114.483388 -106.902504)
		)
		(stroke
			(width 0)
			(type solid)
		)
		(fill yes)
		(layer "F.Cu")
		(net "M_L_DQ<41>")
	)
	(gr_poly
		(pts
			(xy 114.483388 -106.115104) (xy 114.432588 -106.115104) (xy 114.242088 -106.127804) (xy 114.242088 -106.229404)
			(xy 114.432588 -106.242104) (xy 114.483388 -106.242104)
		)
		(stroke
			(width 0)
			(type solid)
		)
		(fill yes)
		(layer "F.Cu")
		(net "M_L_DQ<41>")
	)
	(gr_poly
		(pts
			(xy 114.493802 -45.71619) (xy 114.457988 -45.680122) (xy 114.314224 -45.554392) (xy 114.242342 -45.626274)
			(xy 114.368072 -45.770038) (xy 114.40414 -45.805852)
		)
		(stroke
			(width 0)
			(type solid)
		)
		(fill yes)
		(layer "F.Cu")
		(net "M_H_DQ<41>")
	)
	(gr_poly
		(pts
			(xy 114.51209 -47.153068) (xy 114.38636 -47.009558) (xy 114.350546 -46.97349) (xy 114.26063 -47.063406)
			(xy 114.296698 -47.09922) (xy 114.440208 -47.22495)
		)
		(stroke
			(width 0)
			(type solid)
		)
		(fill yes)
		(layer "F.Cu")
		(net "M_H_DQS_DN<14>")
	)
	(gr_poly
		(pts
			(xy 114.520472 -44.35983) (xy 114.394742 -44.216066) (xy 114.358928 -44.179998) (xy 114.269012 -44.269914)
			(xy 114.304826 -44.305728) (xy 114.44859 -44.431458)
		)
		(stroke
			(width 0)
			(type solid)
		)
		(fill yes)
		(layer "F.Cu")
		(net "M_H_DQ<44>")
	)
	(gr_poly
		(pts
			(xy 114.568732 -110.568486) (xy 114.6048 -110.532672) (xy 114.514884 -110.442756) (xy 114.47907 -110.478824)
			(xy 114.35334 -110.622334) (xy 114.425222 -110.694216)
		)
		(stroke
			(width 0)
			(type solid)
		)
		(fill yes)
		(layer "F.Cu")
		(net "M_L_DQ<45>")
	)
	(gr_poly
		(pts
			(xy 114.583972 -46.740064) (xy 114.547904 -46.70425) (xy 114.404394 -46.57852) (xy 114.332512 -46.650402)
			(xy 114.458242 -46.793912) (xy 114.494056 -46.82998)
		)
		(stroke
			(width 0)
			(type solid)
		)
		(fill yes)
		(layer "F.Cu")
		(net "M_H_DQS_DN<14>")
	)
	(gr_poly
		(pts
			(xy 114.591592 -48.882808) (xy 114.540792 -48.882808) (xy 114.350292 -48.895508) (xy 114.350292 -48.997108)
			(xy 114.540792 -49.009808) (xy 114.591592 -49.009808)
		)
		(stroke
			(width 0)
			(type solid)
		)
		(fill yes)
		(layer "F.Cu")
		(net "M_H_DQS_DP<5>")
	)
	(gr_poly
		(pts
			(xy 114.591592 -48.222408) (xy 114.540792 -48.222408) (xy 114.350292 -48.235108) (xy 114.350292 -48.336708)
			(xy 114.540792 -48.349408) (xy 114.591592 -48.349408)
		)
		(stroke
			(width 0)
			(type solid)
		)
		(fill yes)
		(layer "F.Cu")
		(net "M_H_DQS_DP<5>")
	)
	(gr_poly
		(pts
			(xy 114.592354 -43.946572) (xy 114.556286 -43.910758) (xy 114.412776 -43.785028) (xy 114.340894 -43.85691)
			(xy 114.466624 -44.00042) (xy 114.502438 -44.036488)
		)
		(stroke
			(width 0)
			(type solid)
		)
		(fill yes)
		(layer "F.Cu")
		(net "M_H_DQ<44>")
	)
	(gr_poly
		(pts
			(xy 114.595656 -111.008668) (xy 114.721386 -110.864904) (xy 114.649504 -110.793276) (xy 114.50574 -110.919006)
			(xy 114.469926 -110.95482) (xy 114.559842 -111.044736)
		)
		(stroke
			(width 0)
			(type solid)
		)
		(fill yes)
		(layer "F.Cu")
		(net "M_L_DQ<44>")
	)
	(gr_poly
		(pts
			(xy 114.610642 -45.383704) (xy 114.484912 -45.23994) (xy 114.448844 -45.204126) (xy 114.359182 -45.293788)
			(xy 114.394996 -45.329856) (xy 114.53876 -45.455586)
		)
		(stroke
			(width 0)
			(type solid)
		)
		(fill yes)
		(layer "F.Cu")
		(net "M_H_DQ<40>")
	)
	(gr_poly
		(pts
			(xy 114.619278 -105.425748) (xy 114.619278 -105.197148) (xy 114.426238 -105.108248) (xy 114.381788 -105.108248)
			(xy 114.381788 -105.514648) (xy 114.426238 -105.514648)
		)
		(stroke
			(width 0)
			(type solid)
		)
		(fill yes)
		(layer "F.Cu")
		(net "M_L_DQ<41>")
	)
	(gr_poly
		(pts
			(xy 114.619278 -104.435148) (xy 114.619278 -104.206548) (xy 114.426238 -104.117648) (xy 114.381788 -104.117648)
			(xy 114.381788 -104.524048) (xy 114.426238 -104.524048)
		)
		(stroke
			(width 0)
			(type solid)
		)
		(fill yes)
		(layer "F.Cu")
		(net "M_L_DQ<41>")
	)
	(gr_poly
		(pts
			(xy 114.658902 -109.544612) (xy 114.694716 -109.508544) (xy 114.605054 -109.418882) (xy 114.568986 -109.454696)
			(xy 114.443256 -109.59846) (xy 114.515138 -109.670342)
		)
		(stroke
			(width 0)
			(type solid)
		)
		(fill yes)
		(layer "F.Cu")
		(net "M_L_DQ<41>")
	)
	(gr_poly
		(pts
			(xy 114.68227 -44.9707) (xy 114.646456 -44.934632) (xy 114.502692 -44.808902) (xy 114.43081 -44.880784)
			(xy 114.55654 -45.024548) (xy 114.592608 -45.060362)
		)
		(stroke
			(width 0)
			(type solid)
		)
		(fill yes)
		(layer "F.Cu")
		(net "M_H_DQ<40>")
	)
	(gr_poly
		(pts
			(xy 114.685826 -109.984794) (xy 114.811556 -109.84103) (xy 114.739674 -109.769148) (xy 114.59591 -109.894878)
			(xy 114.560096 -109.930946) (xy 114.649758 -110.020608)
		)
		(stroke
			(width 0)
			(type solid)
		)
		(fill yes)
		(layer "F.Cu")
		(net "M_L_DQ<40>")
	)
	(gr_poly
		(pts
			(xy 114.700558 -46.407578) (xy 114.574828 -46.264068) (xy 114.539014 -46.228) (xy 114.449098 -46.317916)
			(xy 114.485166 -46.35373) (xy 114.628676 -46.47946)
		)
		(stroke
			(width 0)
			(type solid)
		)
		(fill yes)
		(layer "F.Cu")
		(net "M_H_DQS_DP<14>")
	)
	(gr_poly
		(pts
			(xy 114.702082 -50.94732) (xy 114.702082 -50.72634) (xy 114.531902 -50.63744) (xy 114.487452 -50.63744)
			(xy 114.487452 -51.03622) (xy 114.531902 -51.03622)
		)
		(stroke
			(width 0)
			(type solid)
		)
		(fill yes)
		(layer "F.Cu")
		(net "M_H_DQS_DP<5>")
	)
	(gr_poly
		(pts
			(xy 114.724688 -108.540804) (xy 114.724688 -108.439204) (xy 114.534188 -108.426504) (xy 114.483388 -108.426504)
			(xy 114.483388 -108.553504) (xy 114.534188 -108.553504)
		)
		(stroke
			(width 0)
			(type solid)
		)
		(fill yes)
		(layer "F.Cu")
		(net "M_L_DQ<41>")
	)
	(gr_poly
		(pts
			(xy 114.724688 -107.880404) (xy 114.724688 -107.778804) (xy 114.534188 -107.766104) (xy 114.483388 -107.766104)
			(xy 114.483388 -107.893104) (xy 114.534188 -107.893104)
		)
		(stroke
			(width 0)
			(type solid)
		)
		(fill yes)
		(layer "F.Cu")
		(net "M_L_DQ<41>")
	)
	(gr_poly
		(pts
			(xy 114.724688 -107.220004) (xy 114.724688 -107.118404) (xy 114.534188 -107.105704) (xy 114.483388 -107.105704)
			(xy 114.483388 -107.232704) (xy 114.534188 -107.232704)
		)
		(stroke
			(width 0)
			(type solid)
		)
		(fill yes)
		(layer "F.Cu")
		(net "M_L_DQ<41>")
	)
	(gr_poly
		(pts
			(xy 114.724688 -106.559604) (xy 114.724688 -106.458004) (xy 114.534188 -106.445304) (xy 114.483388 -106.445304)
			(xy 114.483388 -106.572304) (xy 114.534188 -106.572304)
		)
		(stroke
			(width 0)
			(type solid)
		)
		(fill yes)
		(layer "F.Cu")
		(net "M_L_DQ<41>")
	)
	(gr_poly
		(pts
			(xy 114.7572 -111.313976) (xy 114.793268 -111.278162) (xy 114.703352 -111.188246) (xy 114.667538 -111.224314)
			(xy 114.541808 -111.367824) (xy 114.61369 -111.439706)
		)
		(stroke
			(width 0)
			(type solid)
		)
		(fill yes)
		(layer "F.Cu")
		(net "M_L_DQ<44>")
	)
	(gr_poly
		(pts
			(xy 114.77244 -45.994574) (xy 114.736372 -45.95876) (xy 114.592862 -45.83303) (xy 114.52098 -45.904912)
			(xy 114.64671 -46.048422) (xy 114.682524 -46.08449)
		)
		(stroke
			(width 0)
			(type solid)
		)
		(fill yes)
		(layer "F.Cu")
		(net "M_H_DQS_DP<14>")
	)
	(gr_poly
		(pts
			(xy 114.790728 -47.431706) (xy 114.664998 -47.287942) (xy 114.62893 -47.252128) (xy 114.539268 -47.34179)
			(xy 114.575082 -47.377858) (xy 114.718846 -47.503588)
		)
		(stroke
			(width 0)
			(type solid)
		)
		(fill yes)
		(layer "F.Cu")
		(net "M_H_DQS_DN<5>")
	)
	(gr_poly
		(pts
			(xy 114.79911 -44.638214) (xy 114.67338 -44.49445) (xy 114.637312 -44.458636) (xy 114.54765 -44.548298)
			(xy 114.583464 -44.584366) (xy 114.727228 -44.710096)
		)
		(stroke
			(width 0)
			(type solid)
		)
		(fill yes)
		(layer "F.Cu")
		(net "M_H_DQ<45>")
	)
	(gr_poly
		(pts
			(xy 114.832892 -49.327308) (xy 114.832892 -49.225708) (xy 114.642392 -49.213008) (xy 114.591592 -49.213008)
			(xy 114.591592 -49.340008) (xy 114.642392 -49.340008)
		)
		(stroke
			(width 0)
			(type solid)
		)
		(fill yes)
		(layer "F.Cu")
		(net "M_H_DQS_DP<5>")
	)
	(gr_poly
		(pts
			(xy 114.832892 -48.666908) (xy 114.832892 -48.565308) (xy 114.642392 -48.552608) (xy 114.591592 -48.552608)
			(xy 114.591592 -48.679608) (xy 114.642392 -48.679608)
		)
		(stroke
			(width 0)
			(type solid)
		)
		(fill yes)
		(layer "F.Cu")
		(net "M_H_DQS_DP<5>")
	)
	(gr_poly
		(pts
			(xy 114.84737 -110.290102) (xy 114.883184 -110.254034) (xy 114.793522 -110.164372) (xy 114.757454 -110.200186)
			(xy 114.631724 -110.34395) (xy 114.703606 -110.415832)
		)
		(stroke
			(width 0)
			(type solid)
		)
		(fill yes)
		(layer "F.Cu")
		(net "M_L_DQ<40>")
	)
	(gr_poly
		(pts
			(xy 114.862356 -47.018702) (xy 114.826542 -46.982634) (xy 114.682778 -46.856904) (xy 114.610896 -46.928786)
			(xy 114.736626 -47.07255) (xy 114.772694 -47.108364)
		)
		(stroke
			(width 0)
			(type solid)
		)
		(fill yes)
		(layer "F.Cu")
		(net "M_H_DQS_DN<5>")
	)
	(gr_poly
		(pts
			(xy 114.870738 -44.22521) (xy 114.834924 -44.189142) (xy 114.69116 -44.063412) (xy 114.619278 -44.135294)
			(xy 114.745008 -44.279058) (xy 114.781076 -44.314872)
		)
		(stroke
			(width 0)
			(type solid)
		)
		(fill yes)
		(layer "F.Cu")
		(net "M_H_DQ<45>")
	)
	(gr_poly
		(pts
			(xy 114.874294 -110.730284) (xy 115.000024 -110.58652) (xy 114.928142 -110.514638) (xy 114.784378 -110.640368)
			(xy 114.748564 -110.676436) (xy 114.838226 -110.766098)
		)
		(stroke
			(width 0)
			(type solid)
		)
		(fill yes)
		(layer "F.Cu")
		(net "M_L_DQ<45>")
	)
	(gr_poly
		(pts
			(xy 114.877088 -108.756704) (xy 114.826288 -108.756704) (xy 114.635788 -108.769404) (xy 114.635788 -108.871004)
			(xy 114.826288 -108.883704) (xy 114.877088 -108.883704)
		)
		(stroke
			(width 0)
			(type solid)
		)
		(fill yes)
		(layer "F.Cu")
		(net "M_L_DQS_DP<14>")
	)
	(gr_poly
		(pts
			(xy 114.877088 -108.096304) (xy 114.826288 -108.096304) (xy 114.635788 -108.109004) (xy 114.635788 -108.210604)
			(xy 114.826288 -108.223304) (xy 114.877088 -108.223304)
		)
		(stroke
			(width 0)
			(type solid)
		)
		(fill yes)
		(layer "F.Cu")
		(net "M_L_DQS_DP<14>")
	)
	(gr_poly
		(pts
			(xy 114.877088 -107.435904) (xy 114.826288 -107.435904) (xy 114.635788 -107.448604) (xy 114.635788 -107.550204)
			(xy 114.826288 -107.562904) (xy 114.877088 -107.562904)
		)
		(stroke
			(width 0)
			(type solid)
		)
		(fill yes)
		(layer "F.Cu")
		(net "M_L_DQS_DP<14>")
	)
	(gr_poly
		(pts
			(xy 114.877088 -106.775504) (xy 114.826288 -106.775504) (xy 114.635788 -106.788204) (xy 114.635788 -106.889804)
			(xy 114.826288 -106.902504) (xy 114.877088 -106.902504)
		)
		(stroke
			(width 0)
			(type solid)
		)
		(fill yes)
		(layer "F.Cu")
		(net "M_L_DQS_DP<14>")
	)
	(gr_poly
		(pts
			(xy 114.877088 -106.115104) (xy 114.826288 -106.115104) (xy 114.635788 -106.127804) (xy 114.635788 -106.229404)
			(xy 114.826288 -106.242104) (xy 114.877088 -106.242104)
		)
		(stroke
			(width 0)
			(type solid)
		)
		(fill yes)
		(layer "F.Cu")
		(net "M_L_DQS_DP<14>")
	)
	(gr_poly
		(pts
			(xy 114.889026 -45.662088) (xy 114.763296 -45.518578) (xy 114.727482 -45.48251) (xy 114.637566 -45.572426)
			(xy 114.67338 -45.60824) (xy 114.817144 -45.73397)
		)
		(stroke
			(width 0)
			(type solid)
		)
		(fill yes)
		(layer "F.Cu")
		(net "M_H_DQ<41>")
	)
	(gr_poly
		(pts
			(xy 114.909092 -51.119786) (xy 114.864642 -51.119786) (xy 114.694462 -51.208686) (xy 114.694462 -51.429666)
			(xy 114.864642 -51.518566) (xy 114.909092 -51.518566)
		)
		(stroke
			(width 0)
			(type solid)
		)
		(fill yes)
		(layer "F.Cu")
		(net "M_H_DQ<46>")
	)
	(gr_poly
		(pts
			(xy 114.909092 -50.129186) (xy 114.864642 -50.129186) (xy 114.694462 -50.218086) (xy 114.694462 -50.439066)
			(xy 114.864642 -50.527966) (xy 114.909092 -50.527966)
		)
		(stroke
			(width 0)
			(type solid)
		)
		(fill yes)
		(layer "F.Cu")
		(net "M_H_DQ<46>")
	)
	(gr_poly
		(pts
			(xy 114.960908 -45.249084) (xy 114.92484 -45.21327) (xy 114.78133 -45.08754) (xy 114.709448 -45.159422)
			(xy 114.835178 -45.302932) (xy 114.870992 -45.339)
		)
		(stroke
			(width 0)
			(type solid)
		)
		(fill yes)
		(layer "F.Cu")
		(net "M_H_DQ<41>")
	)
	(gr_poly
		(pts
			(xy 114.96421 -109.706156) (xy 115.08994 -109.562646) (xy 115.018058 -109.490764) (xy 114.874294 -109.616494)
			(xy 114.83848 -109.652308) (xy 114.928396 -109.742224)
		)
		(stroke
			(width 0)
			(type solid)
		)
		(fill yes)
		(layer "F.Cu")
		(net "M_L_DQ<41>")
	)
	(gr_poly
		(pts
			(xy 114.978688 -105.235248) (xy 114.934238 -105.235248) (xy 114.741198 -105.324148) (xy 114.741198 -105.552748)
			(xy 114.934238 -105.641648) (xy 114.978688 -105.641648)
		)
		(stroke
			(width 0)
			(type solid)
		)
		(fill yes)
		(layer "F.Cu")
		(net "M_L_DQS_DP<14>")
	)
	(gr_poly
		(pts
			(xy 114.978688 -104.244648) (xy 114.934238 -104.244648) (xy 114.741198 -104.333548) (xy 114.741198 -104.562148)
			(xy 114.934238 -104.651048) (xy 114.978688 -104.651048)
		)
		(stroke
			(width 0)
			(type solid)
		)
		(fill yes)
		(layer "F.Cu")
		(net "M_L_DQS_DP<14>")
	)
	(gr_poly
		(pts
			(xy 114.979196 -46.686216) (xy 114.853466 -46.542452) (xy 114.817398 -46.506638) (xy 114.727736 -46.5963)
			(xy 114.76355 -46.632368) (xy 114.907314 -46.758098)
		)
		(stroke
			(width 0)
			(type solid)
		)
		(fill yes)
		(layer "F.Cu")
		(net "M_H_DQS_DN<14>")
	)
	(gr_poly
		(pts
			(xy 114.985292 -48.882808) (xy 114.934492 -48.882808) (xy 114.743992 -48.895508) (xy 114.743992 -48.997108)
			(xy 114.934492 -49.009808) (xy 114.985292 -49.009808)
		)
		(stroke
			(width 0)
			(type solid)
		)
		(fill yes)
		(layer "F.Cu")
		(net "M_H_DQ<46>")
	)
	(gr_poly
		(pts
			(xy 114.985292 -48.222408) (xy 114.934492 -48.222408) (xy 114.743992 -48.235108) (xy 114.743992 -48.336708)
			(xy 114.934492 -48.349408) (xy 114.985292 -48.349408)
		)
		(stroke
			(width 0)
			(type solid)
		)
		(fill yes)
		(layer "F.Cu")
		(net "M_H_DQ<46>")
	)
	(gr_poly
		(pts
			(xy 114.987324 -43.892724) (xy 114.861848 -43.74896) (xy 114.82578 -43.713146) (xy 114.736118 -43.802808)
			(xy 114.771932 -43.838876) (xy 114.915696 -43.964606)
		)
		(stroke
			(width 0)
			(type solid)
		)
		(fill yes)
		(layer "F.Cu")
		(net "M_H_DQ<44>")
	)
	(gr_poly
		(pts
			(xy 115.035838 -111.035592) (xy 115.071652 -110.999524) (xy 114.98199 -110.909862) (xy 114.945922 -110.945676)
			(xy 114.820192 -111.08944) (xy 114.892074 -111.161322)
		)
		(stroke
			(width 0)
			(type solid)
		)
		(fill yes)
		(layer "F.Cu")
		(net "M_L_DQ<45>")
	)
	(gr_poly
		(pts
			(xy 115.045744 -101.761798) (xy 115.001294 -101.761798) (xy 114.831114 -101.850698) (xy 114.831114 -102.071678)
			(xy 115.001294 -102.160578) (xy 115.045744 -102.160578)
		)
		(stroke
			(width 0)
			(type solid)
		)
		(fill yes)
		(layer "F.Cu")
		(net "M_L_DQS_DP<14>")
	)
	(gr_poly
		(pts
			(xy 115.050824 -46.273212) (xy 115.01501 -46.237144) (xy 114.871246 -46.111414) (xy 114.799364 -46.183296)
			(xy 114.925094 -46.32706) (xy 114.961162 -46.362874)
		)
		(stroke
			(width 0)
			(type solid)
		)
		(fill yes)
		(layer "F.Cu")
		(net "M_H_DQS_DN<14>")
	)
	(gr_poly
		(pts
			(xy 115.059206 -43.47972) (xy 115.023392 -43.443652) (xy 114.879628 -43.317922) (xy 114.807746 -43.389804)
			(xy 114.933476 -43.533568) (xy 114.969544 -43.569382)
		)
		(stroke
			(width 0)
			(type solid)
		)
		(fill yes)
		(layer "F.Cu")
		(net "M_H_DQ<44>")
	)
	(gr_poly
		(pts
			(xy 115.062762 -111.475774) (xy 115.188238 -111.33201) (xy 115.11661 -111.260128) (xy 114.972846 -111.385858)
			(xy 114.937032 -111.421926) (xy 115.026694 -111.511588)
		)
		(stroke
			(width 0)
			(type solid)
		)
		(fill yes)
		(layer "F.Cu")
		(net "M_L_DQ<44>")
	)
	(gr_poly
		(pts
			(xy 115.069112 -47.71009) (xy 114.943382 -47.56658) (xy 114.907568 -47.530512) (xy 114.817652 -47.620428)
			(xy 114.85372 -47.656242) (xy 114.99723 -47.781972)
		)
		(stroke
			(width 0)
			(type solid)
		)
		(fill yes)
		(layer "F.Cu")
		(net "M_H_DQS_DP<5>")
	)
	(gr_poly
		(pts
			(xy 115.077494 -44.916852) (xy 114.951764 -44.773088) (xy 114.91595 -44.73702) (xy 114.826034 -44.826936)
			(xy 114.861848 -44.86275) (xy 115.005612 -44.98848)
		)
		(stroke
			(width 0)
			(type solid)
		)
		(fill yes)
		(layer "F.Cu")
		(net "M_H_DQ<40>")
	)
	(gr_poly
		(pts
			(xy 115.118388 -108.540804) (xy 115.118388 -108.439204) (xy 114.927888 -108.426504) (xy 114.877088 -108.426504)
			(xy 114.877088 -108.553504) (xy 114.927888 -108.553504)
		)
		(stroke
			(width 0)
			(type solid)
		)
		(fill yes)
		(layer "F.Cu")
		(net "M_L_DQS_DP<14>")
	)
	(gr_poly
		(pts
			(xy 115.118388 -107.880404) (xy 115.118388 -107.778804) (xy 114.927888 -107.766104) (xy 114.877088 -107.766104)
			(xy 114.877088 -107.893104) (xy 114.927888 -107.893104)
		)
		(stroke
			(width 0)
			(type solid)
		)
		(fill yes)
		(layer "F.Cu")
		(net "M_L_DQS_DP<14>")
	)
	(gr_poly
		(pts
			(xy 115.118388 -107.220004) (xy 115.118388 -107.118404) (xy 114.927888 -107.105704) (xy 114.877088 -107.105704)
			(xy 114.877088 -107.232704) (xy 114.927888 -107.232704)
		)
		(stroke
			(width 0)
			(type solid)
		)
		(fill yes)
		(layer "F.Cu")
		(net "M_L_DQS_DP<14>")
	)
	(gr_poly
		(pts
			(xy 115.118388 -106.559604) (xy 115.118388 -106.458004) (xy 114.927888 -106.445304) (xy 114.877088 -106.445304)
			(xy 114.877088 -106.572304) (xy 114.927888 -106.572304)
		)
		(stroke
			(width 0)
			(type solid)
		)
		(fill yes)
		(layer "F.Cu")
		(net "M_L_DQS_DP<14>")
	)
	(gr_poly
		(pts
			(xy 115.125754 -110.011464) (xy 115.161822 -109.97565) (xy 115.071906 -109.885734) (xy 115.036092 -109.921802)
			(xy 114.910362 -110.065312) (xy 114.982244 -110.137194)
		)
		(stroke
			(width 0)
			(type solid)
		)
		(fill yes)
		(layer "F.Cu")
		(net "M_L_DQ<41>")
	)
	(gr_poly
		(pts
			(xy 115.140994 -47.297086) (xy 115.104926 -47.261272) (xy 114.961416 -47.135542) (xy 114.889534 -47.207424)
			(xy 115.015264 -47.350934) (xy 115.051078 -47.387002)
		)
		(stroke
			(width 0)
			(type solid)
		)
		(fill yes)
		(layer "F.Cu")
		(net "M_H_DQS_DP<5>")
	)
	(gr_poly
		(pts
			(xy 115.149376 -44.503594) (xy 115.113308 -44.46778) (xy 114.969798 -44.34205) (xy 114.897916 -44.413932)
			(xy 115.023646 -44.557442) (xy 115.05946 -44.59351)
		)
		(stroke
			(width 0)
			(type solid)
		)
		(fill yes)
		(layer "F.Cu")
		(net "M_H_DQ<40>")
	)
	(gr_poly
		(pts
			(xy 115.152678 -110.451646) (xy 115.278408 -110.307882) (xy 115.206526 -110.236254) (xy 115.062762 -110.361984)
			(xy 115.026948 -110.397798) (xy 115.116864 -110.487714)
		)
		(stroke
			(width 0)
			(type solid)
		)
		(fill yes)
		(layer "F.Cu")
		(net "M_L_DQ<40>")
	)
	(gr_poly
		(pts
			(xy 115.167664 -45.940726) (xy 115.041934 -45.796962) (xy 115.005866 -45.761148) (xy 114.916204 -45.85081)
			(xy 114.952018 -45.886878) (xy 115.095782 -46.012608)
		)
		(stroke
			(width 0)
			(type solid)
		)
		(fill yes)
		(layer "F.Cu")
		(net "M_H_DQS_DP<14>")
	)
	(gr_poly
		(pts
			(xy 115.224306 -111.781082) (xy 115.26012 -111.745014) (xy 115.170458 -111.655352) (xy 115.13439 -111.691166)
			(xy 115.00866 -111.83493) (xy 115.080542 -111.906812)
		)
		(stroke
			(width 0)
			(type solid)
		)
		(fill yes)
		(layer "F.Cu")
		(net "M_L_DQ<44>")
	)
	(gr_poly
		(pts
			(xy 115.226592 -49.327308) (xy 115.226592 -49.225708) (xy 115.036092 -49.213008) (xy 114.985292 -49.213008)
			(xy 114.985292 -49.340008) (xy 115.036092 -49.340008)
		)
		(stroke
			(width 0)
			(type solid)
		)
		(fill yes)
		(layer "F.Cu")
		(net "M_H_DQ<46>")
	)
	(gr_poly
		(pts
			(xy 115.226592 -48.666908) (xy 115.226592 -48.565308) (xy 115.036092 -48.552608) (xy 114.985292 -48.552608)
			(xy 114.985292 -48.679608) (xy 115.036092 -48.679608)
		)
		(stroke
			(width 0)
			(type solid)
		)
		(fill yes)
		(layer "F.Cu")
		(net "M_H_DQ<46>")
	)
	(gr_poly
		(pts
			(xy 115.239292 -45.527722) (xy 115.203478 -45.491654) (xy 115.059714 -45.365924) (xy 114.987832 -45.437806)
			(xy 115.113562 -45.58157) (xy 115.14963 -45.617384)
		)
		(stroke
			(width 0)
			(type solid)
		)
		(fill yes)
		(layer "F.Cu")
		(net "M_H_DQS_DP<14>")
	)
	(gr_poly
		(pts
			(xy 115.242848 -109.427772) (xy 115.368578 -109.284008) (xy 115.296696 -109.212126) (xy 115.152932 -109.337856)
			(xy 115.117118 -109.373924) (xy 115.20678 -109.463586)
		)
		(stroke
			(width 0)
			(type solid)
		)
		(fill yes)
		(layer "F.Cu")
		(net "M_L_DQS_DP<14>")
	)
	(gr_poly
		(pts
			(xy 115.25758 -46.9646) (xy 115.13185 -46.82109) (xy 115.096036 -46.785022) (xy 115.00612 -46.874938)
			(xy 115.042188 -46.910752) (xy 115.185698 -47.036482)
		)
		(stroke
			(width 0)
			(type solid)
		)
		(fill yes)
		(layer "F.Cu")
		(net "M_H_DQS_DN<5>")
	)
	(gr_poly
		(pts
			(xy 115.265962 -44.171362) (xy 115.140232 -44.027598) (xy 115.104418 -43.99153) (xy 115.014502 -44.081446)
			(xy 115.050316 -44.11726) (xy 115.19408 -44.24299)
		)
		(stroke
			(width 0)
			(type solid)
		)
		(fill yes)
		(layer "F.Cu")
		(net "M_H_DQ<45>")
	)
	(gr_poly
		(pts
			(xy 115.270788 -108.756704) (xy 115.219988 -108.756704) (xy 115.029488 -108.769404) (xy 115.029488 -108.871004)
			(xy 115.219988 -108.883704) (xy 115.270788 -108.883704)
		)
		(stroke
			(width 0)
			(type solid)
		)
		(fill yes)
		(layer "F.Cu")
		(net "M_L_DQS_DN<14>")
	)
	(gr_poly
		(pts
			(xy 115.270788 -108.096304) (xy 115.219988 -108.096304) (xy 115.029488 -108.109004) (xy 115.029488 -108.210604)
			(xy 115.219988 -108.223304) (xy 115.270788 -108.223304)
		)
		(stroke
			(width 0)
			(type solid)
		)
		(fill yes)
		(layer "F.Cu")
		(net "M_L_DQS_DN<14>")
	)
	(gr_poly
		(pts
			(xy 115.270788 -107.435904) (xy 115.219988 -107.435904) (xy 115.029488 -107.448604) (xy 115.029488 -107.550204)
			(xy 115.219988 -107.562904) (xy 115.270788 -107.562904)
		)
		(stroke
			(width 0)
			(type solid)
		)
		(fill yes)
		(layer "F.Cu")
		(net "M_L_DQS_DN<14>")
	)
	(gr_poly
		(pts
			(xy 115.270788 -106.775504) (xy 115.219988 -106.775504) (xy 115.029488 -106.788204) (xy 115.029488 -106.889804)
			(xy 115.219988 -106.902504) (xy 115.270788 -106.902504)
		)
		(stroke
			(width 0)
			(type solid)
		)
		(fill yes)
		(layer "F.Cu")
		(net "M_L_DQS_DN<14>")
	)
	(gr_poly
		(pts
			(xy 115.270788 -106.115104) (xy 115.219988 -106.115104) (xy 115.029488 -106.127804) (xy 115.029488 -106.229404)
			(xy 115.219988 -106.242104) (xy 115.270788 -106.242104)
		)
		(stroke
			(width 0)
			(type solid)
		)
		(fill yes)
		(layer "F.Cu")
		(net "M_L_DQS_DN<14>")
	)
	(gr_poly
		(pts
			(xy 115.314222 -110.756954) (xy 115.35029 -110.72114) (xy 115.260374 -110.631224) (xy 115.22456 -110.667292)
			(xy 115.09883 -110.810802) (xy 115.170712 -110.882684)
		)
		(stroke
			(width 0)
			(type solid)
		)
		(fill yes)
		(layer "F.Cu")
		(net "M_L_DQ<40>")
	)
	(gr_poly
		(pts
			(xy 115.314222 -51.00066) (xy 115.314222 -50.77968) (xy 115.144042 -50.69078) (xy 115.099592 -50.69078)
			(xy 115.099592 -51.08956) (xy 115.144042 -51.08956)
		)
		(stroke
			(width 0)
			(type solid)
		)
		(fill yes)
		(layer "F.Cu")
		(net "M_H_DQ<47>")
	)
	(gr_poly
		(pts
			(xy 115.329462 -46.551596) (xy 115.293394 -46.515782) (xy 115.149884 -46.390052) (xy 115.078002 -46.461934)
			(xy 115.203732 -46.605444) (xy 115.239546 -46.641512)
		)
		(stroke
			(width 0)
			(type solid)
		)
		(fill yes)
		(layer "F.Cu")
		(net "M_H_DQS_DN<5>")
	)
	(gr_poly
		(pts
			(xy 115.337844 -43.758104) (xy 115.301776 -43.72229) (xy 115.158266 -43.59656) (xy 115.086384 -43.668442)
			(xy 115.212114 -43.811952) (xy 115.247928 -43.84802)
		)
		(stroke
			(width 0)
			(type solid)
		)
		(fill yes)
		(layer "F.Cu")
		(net "M_H_DQ<45>")
	)
	(gr_poly
		(pts
			(xy 115.341146 -111.197136) (xy 115.466876 -111.053372) (xy 115.394994 -110.981744) (xy 115.25123 -111.107474)
			(xy 115.215416 -111.143288) (xy 115.305332 -111.233204)
		)
		(stroke
			(width 0)
			(type solid)
		)
		(fill yes)
		(layer "F.Cu")
		(net "M_L_DQ<45>")
	)
	(gr_poly
		(pts
			(xy 115.34775 -47.988728) (xy 115.22202 -47.844964) (xy 115.185952 -47.80915) (xy 115.09629 -47.898812)
			(xy 115.132104 -47.93488) (xy 115.275868 -48.06061)
		)
		(stroke
			(width 0)
			(type solid)
		)
		(fill yes)
		(layer "F.Cu")
		(net "M_H_DQ<46>")
	)
	(gr_poly
		(pts
			(xy 115.356132 -45.195236) (xy 115.230402 -45.051472) (xy 115.194334 -45.015658) (xy 115.104672 -45.10532)
			(xy 115.140486 -45.141388) (xy 115.28425 -45.267118)
		)
		(stroke
			(width 0)
			(type solid)
		)
		(fill yes)
		(layer "F.Cu")
		(net "M_H_DQ<41>")
	)
	(gr_poly
		(pts
			(xy 115.378992 -48.882808) (xy 115.328192 -48.882808) (xy 115.137692 -48.895508) (xy 115.137692 -48.997108)
			(xy 115.328192 -49.009808) (xy 115.378992 -49.009808)
		)
		(stroke
			(width 0)
			(type solid)
		)
		(fill yes)
		(layer "F.Cu")
		(net "M_H_DQ<47>")
	)
	(gr_poly
		(pts
			(xy 115.393216 -53.043328) (xy 115.393216 -52.822348) (xy 115.223036 -52.733448) (xy 115.178586 -52.733448)
			(xy 115.178586 -53.132228) (xy 115.223036 -53.132228)
		)
		(stroke
			(width 0)
			(type solid)
		)
		(fill yes)
		(layer "F.Cu")
		(net "M_H_DQ<47>")
	)
	(gr_poly
		(pts
			(xy 115.393216 -52.057554) (xy 115.393216 -51.836574) (xy 115.223036 -51.747674) (xy 115.178586 -51.747674)
			(xy 115.178586 -52.146454) (xy 115.223036 -52.146454)
		)
		(stroke
			(width 0)
			(type solid)
		)
		(fill yes)
		(layer "F.Cu")
		(net "M_H_DQ<47>")
	)
	(gr_poly
		(pts
			(xy 115.404392 -109.73308) (xy 115.440206 -109.697012) (xy 115.350544 -109.60735) (xy 115.314476 -109.643164)
			(xy 115.188746 -109.786928) (xy 115.260628 -109.85881)
		)
		(stroke
			(width 0)
			(type solid)
		)
		(fill yes)
		(layer "F.Cu")
		(net "M_L_DQS_DP<14>")
	)
	(gr_poly
		(pts
			(xy 115.406678 -105.552748) (xy 115.406678 -105.324148) (xy 115.213638 -105.235248) (xy 115.169188 -105.235248)
			(xy 115.169188 -105.641648) (xy 115.213638 -105.641648)
		)
		(stroke
			(width 0)
			(type solid)
		)
		(fill yes)
		(layer "F.Cu")
		(net "M_L_DQS_DN<14>")
	)
	(gr_poly
		(pts
			(xy 115.406678 -104.562148) (xy 115.406678 -104.333548) (xy 115.213638 -104.244648) (xy 115.169188 -104.244648)
			(xy 115.169188 -104.651048) (xy 115.213638 -104.651048)
		)
		(stroke
			(width 0)
			(type solid)
		)
		(fill yes)
		(layer "F.Cu")
		(net "M_L_DQS_DN<14>")
	)
	(gr_poly
		(pts
			(xy 115.419378 -47.575724) (xy 115.383564 -47.539656) (xy 115.2398 -47.413926) (xy 115.167918 -47.485808)
			(xy 115.293648 -47.629572) (xy 115.329716 -47.665386)
		)
		(stroke
			(width 0)
			(type solid)
		)
		(fill yes)
		(layer "F.Cu")
		(net "M_H_DQ<46>")
	)
	(gr_poly
		(pts
			(xy 115.42776 -44.782232) (xy 115.391946 -44.746164) (xy 115.248182 -44.620434) (xy 115.1763 -44.692316)
			(xy 115.30203 -44.83608) (xy 115.338098 -44.871894)
		)
		(stroke
			(width 0)
			(type solid)
		)
		(fill yes)
		(layer "F.Cu")
		(net "M_H_DQ<41>")
	)
	(gr_poly
		(pts
			(xy 115.431316 -110.173262) (xy 115.557046 -110.029498) (xy 115.485164 -109.957616) (xy 115.3414 -110.083346)
			(xy 115.305586 -110.119414) (xy 115.395248 -110.209076)
		)
		(stroke
			(width 0)
			(type solid)
		)
		(fill yes)
		(layer "F.Cu")
		(net "M_L_DQ<41>")
	)
	(gr_poly
		(pts
			(xy 115.446048 -46.21911) (xy 115.320318 -46.0756) (xy 115.284504 -46.039532) (xy 115.194588 -46.129448)
			(xy 115.230402 -46.165262) (xy 115.374166 -46.290992)
		)
		(stroke
			(width 0)
			(type solid)
		)
		(fill yes)
		(layer "F.Cu")
		(net "M_H_DQS_DN<14>")
	)
	(gr_poly
		(pts
			(xy 115.45443 -43.425872) (xy 115.3287 -43.282108) (xy 115.292886 -43.24604) (xy 115.20297 -43.335956)
			(xy 115.238784 -43.37177) (xy 115.382548 -43.4975)
		)
		(stroke
			(width 0)
			(type solid)
		)
		(fill yes)
		(layer "F.Cu")
		(net "M_H_DQ<44>")
	)
	(gr_poly
		(pts
			(xy 115.50269 -111.502444) (xy 115.538758 -111.46663) (xy 115.448842 -111.376714) (xy 115.413028 -111.412782)
			(xy 115.287298 -111.556292) (xy 115.35918 -111.628174)
		)
		(stroke
			(width 0)
			(type solid)
		)
		(fill yes)
		(layer "F.Cu")
		(net "M_L_DQ<45>")
	)
	(gr_poly
		(pts
			(xy 115.512088 -108.540804) (xy 115.512088 -108.439204) (xy 115.321588 -108.426504) (xy 115.270788 -108.426504)
			(xy 115.270788 -108.553504) (xy 115.321588 -108.553504)
		)
		(stroke
			(width 0)
			(type solid)
		)
		(fill yes)
		(layer "F.Cu")
		(net "M_L_DQS_DN<14>")
	)
	(gr_poly
		(pts
			(xy 115.512088 -107.880404) (xy 115.512088 -107.778804) (xy 115.321588 -107.766104) (xy 115.270788 -107.766104)
			(xy 115.270788 -107.893104) (xy 115.321588 -107.893104)
		)
		(stroke
			(width 0)
			(type solid)
		)
		(fill yes)
		(layer "F.Cu")
		(net "M_L_DQS_DN<14>")
	)
	(gr_poly
		(pts
			(xy 115.512088 -107.220004) (xy 115.512088 -107.118404) (xy 115.321588 -107.105704) (xy 115.270788 -107.105704)
			(xy 115.270788 -107.232704) (xy 115.321588 -107.232704)
		)
		(stroke
			(width 0)
			(type solid)
		)
		(fill yes)
		(layer "F.Cu")
		(net "M_L_DQS_DN<14>")
	)
	(gr_poly
		(pts
			(xy 115.512088 -106.559604) (xy 115.512088 -106.458004) (xy 115.321588 -106.445304) (xy 115.270788 -106.445304)
			(xy 115.270788 -106.572304) (xy 115.321588 -106.572304)
		)
		(stroke
			(width 0)
			(type solid)
		)
		(fill yes)
		(layer "F.Cu")
		(net "M_L_DQS_DN<14>")
	)
	(gr_poly
		(pts
			(xy 115.51793 -45.806106) (xy 115.481862 -45.770292) (xy 115.338352 -45.644562) (xy 115.26647 -45.716444)
			(xy 115.3922 -45.859954) (xy 115.428014 -45.896022)
		)
		(stroke
			(width 0)
			(type solid)
		)
		(fill yes)
		(layer "F.Cu")
		(net "M_H_DQS_DN<14>")
	)
	(gr_poly
		(pts
			(xy 115.521232 -109.149134) (xy 115.646962 -109.005624) (xy 115.57508 -108.933742) (xy 115.431316 -109.059472)
			(xy 115.395502 -109.095286) (xy 115.485418 -109.185202)
		)
		(stroke
			(width 0)
			(type solid)
		)
		(fill yes)
		(layer "F.Cu")
		(net "M_L_DQS_DN<14>")
	)
	(gr_poly
		(pts
			(xy 115.529614 -111.942626) (xy 115.655344 -111.798862) (xy 115.583462 -111.727234) (xy 115.439698 -111.852964)
			(xy 115.403884 -111.888778) (xy 115.4938 -111.978694)
		)
		(stroke
			(width 0)
			(type solid)
		)
		(fill yes)
		(layer "F.Cu")
		(net "M_L_DQ<44>")
	)
	(gr_poly
		(pts
			(xy 115.536218 -47.243238) (xy 115.410488 -47.099474) (xy 115.37442 -47.06366) (xy 115.284758 -47.153322)
			(xy 115.320572 -47.18939) (xy 115.464336 -47.31512)
		)
		(stroke
			(width 0)
			(type solid)
		)
		(fill yes)
		(layer "F.Cu")
		(net "M_H_DQS_DP<5>")
	)
	(gr_poly
		(pts
			(xy 115.544346 -44.449746) (xy 115.41887 -44.305982) (xy 115.382802 -44.270168) (xy 115.29314 -44.35983)
			(xy 115.328954 -44.395898) (xy 115.472718 -44.521628)
		)
		(stroke
			(width 0)
			(type solid)
		)
		(fill yes)
		(layer "F.Cu")
		(net "M_H_DQ<40>")
	)
	(gr_poly
		(pts
			(xy 115.555268 -42.437812) (xy 115.504468 -42.437812) (xy 115.313968 -42.450512) (xy 115.313968 -42.552112)
			(xy 115.504468 -42.564812) (xy 115.555268 -42.564812)
		)
		(stroke
			(width 0)
			(type solid)
		)
		(fill yes)
		(layer "F.Cu")
		(net "M_H_DQ<44>")
	)
	(gr_poly
		(pts
			(xy 115.555268 -41.777412) (xy 115.504468 -41.777412) (xy 115.313968 -41.790112) (xy 115.313968 -41.891712)
			(xy 115.504468 -41.904412) (xy 115.555268 -41.904412)
		)
		(stroke
			(width 0)
			(type solid)
		)
		(fill yes)
		(layer "F.Cu")
		(net "M_H_DQ<44>")
	)
	(gr_poly
		(pts
			(xy 115.58397 -102.579424) (xy 115.58397 -102.358444) (xy 115.41379 -102.269544) (xy 115.36934 -102.269544)
			(xy 115.36934 -102.668324) (xy 115.41379 -102.668324)
		)
		(stroke
			(width 0)
			(type solid)
		)
		(fill yes)
		(layer "F.Cu")
		(net "M_L_DQS_DN<14>")
	)
	(gr_poly
		(pts
			(xy 115.58397 -101.582474) (xy 115.58397 -101.361494) (xy 115.41379 -101.272594) (xy 115.36934 -101.272594)
			(xy 115.36934 -101.671374) (xy 115.41379 -101.671374)
		)
		(stroke
			(width 0)
			(type solid)
		)
		(fill yes)
		(layer "F.Cu")
		(net "M_L_DQS_DN<14>")
	)
	(gr_poly
		(pts
			(xy 115.59286 -110.47857) (xy 115.628674 -110.442502) (xy 115.539012 -110.35284) (xy 115.502944 -110.388654)
			(xy 115.377214 -110.532418) (xy 115.449096 -110.6043)
		)
		(stroke
			(width 0)
			(type solid)
		)
		(fill yes)
		(layer "F.Cu")
		(net "M_L_DQ<41>")
	)
	(gr_poly
		(pts
			(xy 115.607846 -46.830234) (xy 115.572032 -46.794166) (xy 115.428268 -46.668436) (xy 115.356386 -46.740318)
			(xy 115.482116 -46.884082) (xy 115.518184 -46.919896)
		)
		(stroke
			(width 0)
			(type solid)
		)
		(fill yes)
		(layer "F.Cu")
		(net "M_H_DQS_DP<5>")
	)
	(gr_poly
		(pts
			(xy 115.616228 -44.036742) (xy 115.580414 -44.000674) (xy 115.43665 -43.874944) (xy 115.364768 -43.946826)
			(xy 115.490498 -44.09059) (xy 115.526566 -44.126404)
		)
		(stroke
			(width 0)
			(type solid)
		)
		(fill yes)
		(layer "F.Cu")
		(net "M_H_DQ<40>")
	)
	(gr_poly
		(pts
			(xy 115.619784 -110.918752) (xy 115.74526 -110.774988) (xy 115.673632 -110.703106) (xy 115.529868 -110.828836)
			(xy 115.494054 -110.864904) (xy 115.583716 -110.954566)
		)
		(stroke
			(width 0)
			(type solid)
		)
		(fill yes)
		(layer "F.Cu")
		(net "M_L_DQ<40>")
	)
	(gr_poly
		(pts
			(xy 115.620292 -49.327308) (xy 115.620292 -49.225708) (xy 115.429792 -49.213008) (xy 115.378992 -49.213008)
			(xy 115.378992 -49.340008) (xy 115.429792 -49.340008)
		)
		(stroke
			(width 0)
			(type solid)
		)
		(fill yes)
		(layer "F.Cu")
		(net "M_H_DQ<47>")
	)
	(gr_poly
		(pts
			(xy 115.620292 -48.666908) (xy 115.620292 -48.565308) (xy 115.429792 -48.552608) (xy 115.378992 -48.552608)
			(xy 115.378992 -48.679608) (xy 115.429792 -48.679608)
		)
		(stroke
			(width 0)
			(type solid)
		)
		(fill yes)
		(layer "F.Cu")
		(net "M_H_DQ<47>")
	)
	(gr_poly
		(pts
			(xy 115.634516 -45.473874) (xy 115.508786 -45.33011) (xy 115.472972 -45.294042) (xy 115.383056 -45.383958)
			(xy 115.41887 -45.419772) (xy 115.562634 -45.545502)
		)
		(stroke
			(width 0)
			(type solid)
		)
		(fill yes)
		(layer "F.Cu")
		(net "M_H_DQS_DP<14>")
	)
	(gr_poly
		(pts
			(xy 115.664488 -108.096304) (xy 115.613688 -108.096304) (xy 115.423188 -108.109004) (xy 115.423188 -108.210604)
			(xy 115.613688 -108.223304) (xy 115.664488 -108.223304)
		)
		(stroke
			(width 0)
			(type solid)
		)
		(fill yes)
		(layer "F.Cu")
		(net "M_L_DQS_DN<5>")
	)
	(gr_poly
		(pts
			(xy 115.664488 -107.435904) (xy 115.613688 -107.435904) (xy 115.423188 -107.448604) (xy 115.423188 -107.550204)
			(xy 115.613688 -107.562904) (xy 115.664488 -107.562904)
		)
		(stroke
			(width 0)
			(type solid)
		)
		(fill yes)
		(layer "F.Cu")
		(net "M_L_DQS_DN<5>")
	)
	(gr_poly
		(pts
			(xy 115.664488 -106.775504) (xy 115.613688 -106.775504) (xy 115.423188 -106.788204) (xy 115.423188 -106.889804)
			(xy 115.613688 -106.902504) (xy 115.664488 -106.902504)
		)
		(stroke
			(width 0)
			(type solid)
		)
		(fill yes)
		(layer "F.Cu")
		(net "M_L_DQS_DN<5>")
	)
	(gr_poly
		(pts
			(xy 115.664488 -106.115104) (xy 115.613688 -106.115104) (xy 115.423188 -106.127804) (xy 115.423188 -106.229404)
			(xy 115.613688 -106.242104) (xy 115.664488 -106.242104)
		)
		(stroke
			(width 0)
			(type solid)
		)
		(fill yes)
		(layer "F.Cu")
		(net "M_L_DQS_DN<5>")
	)
	(gr_poly
		(pts
			(xy 115.682776 -109.454442) (xy 115.718844 -109.418628) (xy 115.628928 -109.328712) (xy 115.593114 -109.36478)
			(xy 115.467384 -109.50829) (xy 115.539266 -109.580172)
		)
		(stroke
			(width 0)
			(type solid)
		)
		(fill yes)
		(layer "F.Cu")
		(net "M_L_DQS_DN<14>")
	)
	(gr_poly
		(pts
			(xy 115.691158 -112.247934) (xy 115.727226 -112.21212) (xy 115.63731 -112.122204) (xy 115.601496 -112.158272)
			(xy 115.475766 -112.301782) (xy 115.547648 -112.373664)
		)
		(stroke
			(width 0)
			(type solid)
		)
		(fill yes)
		(layer "F.Cu")
		(net "M_L_DQ<44>")
	)
	(gr_poly
		(pts
			(xy 115.698016 -47.854108) (xy 115.661948 -47.818294) (xy 115.518438 -47.692564) (xy 115.446556 -47.764446)
			(xy 115.572286 -47.907956) (xy 115.6081 -47.944024)
		)
		(stroke
			(width 0)
			(type solid)
		)
		(fill yes)
		(layer "F.Cu")
		(net "M_H_DQ<47>")
	)
	(gr_poly
		(pts
			(xy 115.706398 -45.060616) (xy 115.67033 -45.024802) (xy 115.52682 -44.899072) (xy 115.454938 -44.970954)
			(xy 115.580668 -45.114464) (xy 115.616482 -45.150532)
		)
		(stroke
			(width 0)
			(type solid)
		)
		(fill yes)
		(layer "F.Cu")
		(net "M_H_DQS_DP<14>")
	)
	(gr_poly
		(pts
			(xy 115.7097 -109.894624) (xy 115.83543 -109.75086) (xy 115.763548 -109.679232) (xy 115.619784 -109.804962)
			(xy 115.58397 -109.840776) (xy 115.673886 -109.930692)
		)
		(stroke
			(width 0)
			(type solid)
		)
		(fill yes)
		(layer "F.Cu")
		(net "M_L_DQS_DP<14>")
	)
	(gr_poly
		(pts
			(xy 115.724686 -46.497748) (xy 115.598956 -46.353984) (xy 115.562888 -46.31817) (xy 115.473226 -46.407832)
			(xy 115.50904 -46.4439) (xy 115.652804 -46.56963)
		)
		(stroke
			(width 0)
			(type solid)
		)
		(fill yes)
		(layer "F.Cu")
		(net "M_H_DQS_DN<5>")
	)
	(gr_poly
		(pts
			(xy 115.732814 -43.704256) (xy 115.607084 -43.560492) (xy 115.57127 -43.524678) (xy 115.481608 -43.61434)
			(xy 115.517422 -43.650408) (xy 115.661186 -43.776138)
		)
		(stroke
			(width 0)
			(type solid)
		)
		(fill yes)
		(layer "F.Cu")
		(net "M_H_DQ<45>")
	)
	(gr_poly
		(pts
			(xy 115.766088 -105.234232) (xy 115.721638 -105.234232) (xy 115.528598 -105.323132) (xy 115.528598 -105.551732)
			(xy 115.721638 -105.640632) (xy 115.766088 -105.640632)
		)
		(stroke
			(width 0)
			(type solid)
		)
		(fill yes)
		(layer "F.Cu")
		(net "M_L_DQS_DN<5>")
	)
	(gr_poly
		(pts
			(xy 115.766088 -104.243632) (xy 115.721638 -104.243632) (xy 115.528598 -104.332532) (xy 115.528598 -104.561132)
			(xy 115.721638 -104.650032) (xy 115.766088 -104.650032)
		)
		(stroke
			(width 0)
			(type solid)
		)
		(fill yes)
		(layer "F.Cu")
		(net "M_L_DQS_DN<5>")
	)
	(gr_poly
		(pts
			(xy 115.772692 -48.882808) (xy 115.721892 -48.882808) (xy 115.531392 -48.895508) (xy 115.531392 -48.997108)
			(xy 115.721892 -49.009808) (xy 115.772692 -49.009808)
		)
		(stroke
			(width 0)
			(type solid)
		)
		(fill yes)
		(layer "F.Cu")
		(net "M_H_DQ<42>")
	)
	(gr_poly
		(pts
			(xy 115.781328 -111.22406) (xy 115.817142 -111.187992) (xy 115.72748 -111.09833) (xy 115.691412 -111.134144)
			(xy 115.565682 -111.277908) (xy 115.637564 -111.34979)
		)
		(stroke
			(width 0)
			(type solid)
		)
		(fill yes)
		(layer "F.Cu")
		(net "M_L_DQ<40>")
	)
	(gr_poly
		(pts
			(xy 115.796314 -46.084744) (xy 115.7605 -46.048676) (xy 115.616736 -45.922946) (xy 115.544854 -45.994828)
			(xy 115.670584 -46.138592) (xy 115.706652 -46.174406)
		)
		(stroke
			(width 0)
			(type solid)
		)
		(fill yes)
		(layer "F.Cu")
		(net "M_H_DQS_DN<5>")
	)
	(gr_poly
		(pts
			(xy 115.796568 -42.882312) (xy 115.796568 -42.780712) (xy 115.606068 -42.768012) (xy 115.555268 -42.768012)
			(xy 115.555268 -42.895012) (xy 115.606068 -42.895012)
		)
		(stroke
			(width 0)
			(type solid)
		)
		(fill yes)
		(layer "F.Cu")
		(net "M_H_DQ<44>")
	)
	(gr_poly
		(pts
			(xy 115.796568 -42.221912) (xy 115.796568 -42.120312) (xy 115.606068 -42.107612) (xy 115.555268 -42.107612)
			(xy 115.555268 -42.234612) (xy 115.606068 -42.234612)
		)
		(stroke
			(width 0)
			(type solid)
		)
		(fill yes)
		(layer "F.Cu")
		(net "M_H_DQ<44>")
	)
	(gr_poly
		(pts
			(xy 115.804696 -43.291252) (xy 115.768882 -43.255184) (xy 115.625118 -43.129454) (xy 115.553236 -43.201336)
			(xy 115.678966 -43.3451) (xy 115.715034 -43.380914)
		)
		(stroke
			(width 0)
			(type solid)
		)
		(fill yes)
		(layer "F.Cu")
		(net "M_H_DQ<45>")
	)
	(gr_poly
		(pts
			(xy 115.807998 -111.664242) (xy 115.933728 -111.520478) (xy 115.8621 -111.448596) (xy 115.718336 -111.574326)
			(xy 115.682522 -111.610394) (xy 115.772184 -111.700056)
		)
		(stroke
			(width 0)
			(type solid)
		)
		(fill yes)
		(layer "F.Cu")
		(net "M_L_DQ<45>")
	)
	(gr_poly
		(pts
			(xy 115.814602 -47.521622) (xy 115.688872 -47.378112) (xy 115.653058 -47.342044) (xy 115.563142 -47.43196)
			(xy 115.59921 -47.467774) (xy 115.74272 -47.593504)
		)
		(stroke
			(width 0)
			(type solid)
		)
		(fill yes)
		(layer "F.Cu")
		(net "M_H_DQ<46>")
	)
	(gr_poly
		(pts
			(xy 115.822984 -44.728384) (xy 115.697254 -44.58462) (xy 115.66144 -44.548552) (xy 115.571524 -44.638468)
			(xy 115.607338 -44.674282) (xy 115.751102 -44.800012)
		)
		(stroke
			(width 0)
			(type solid)
		)
		(fill yes)
		(layer "F.Cu")
		(net "M_H_DQ<41>")
	)
	(gr_poly
		(pts
			(xy 115.871244 -110.199932) (xy 115.907312 -110.164118) (xy 115.817396 -110.074202) (xy 115.781582 -110.11027)
			(xy 115.655852 -110.25378) (xy 115.727734 -110.325662)
		)
		(stroke
			(width 0)
			(type solid)
		)
		(fill yes)
		(layer "F.Cu")
		(net "M_L_DQS_DP<14>")
	)
	(gr_poly
		(pts
			(xy 115.886484 -47.108618) (xy 115.850416 -47.072804) (xy 115.706906 -46.947074) (xy 115.635024 -47.018956)
			(xy 115.760754 -47.162466) (xy 115.796568 -47.198534)
		)
		(stroke
			(width 0)
			(type solid)
		)
		(fill yes)
		(layer "F.Cu")
		(net "M_H_DQ<46>")
	)
	(gr_poly
		(pts
			(xy 115.894866 -44.315126) (xy 115.858798 -44.279312) (xy 115.715288 -44.153582) (xy 115.643406 -44.225464)
			(xy 115.769136 -44.368974) (xy 115.80495 -44.405042)
		)
		(stroke
			(width 0)
			(type solid)
		)
		(fill yes)
		(layer "F.Cu")
		(net "M_H_DQ<41>")
	)
	(gr_poly
		(pts
			(xy 115.898168 -110.640114) (xy 116.023898 -110.49635) (xy 115.952016 -110.424722) (xy 115.808252 -110.550452)
			(xy 115.772438 -110.586266) (xy 115.862354 -110.676182)
		)
		(stroke
			(width 0)
			(type solid)
		)
		(fill yes)
		(layer "F.Cu")
		(net "M_L_DQ<41>")
	)
	(gr_poly
		(pts
			(xy 115.902994 -51.822858) (xy 115.8621 -51.805078) (xy 115.670584 -51.819048) (xy 115.582954 -52.02174)
			(xy 115.703858 -52.171092) (xy 115.744498 -52.188618)
		)
		(stroke
			(width 0)
			(type solid)
		)
		(fill yes)
		(layer "F.Cu")
		(net "M_H_DQ<42>")
	)
	(gr_poly
		(pts
			(xy 115.905788 -108.540804) (xy 115.905788 -108.439204) (xy 115.715288 -108.426504) (xy 115.664488 -108.426504)
			(xy 115.664488 -108.553504) (xy 115.715288 -108.553504)
		)
		(stroke
			(width 0)
			(type solid)
		)
		(fill yes)
		(layer "F.Cu")
		(net "M_L_DQS_DN<5>")
	)
	(gr_poly
		(pts
			(xy 115.905788 -107.880404) (xy 115.905788 -107.778804) (xy 115.715288 -107.766104) (xy 115.664488 -107.766104)
			(xy 115.664488 -107.893104) (xy 115.715288 -107.893104)
		)
		(stroke
			(width 0)
			(type solid)
		)
		(fill yes)
		(layer "F.Cu")
		(net "M_L_DQS_DN<5>")
	)
	(gr_poly
		(pts
			(xy 115.905788 -107.220004) (xy 115.905788 -107.118404) (xy 115.715288 -107.105704) (xy 115.664488 -107.105704)
			(xy 115.664488 -107.232704) (xy 115.715288 -107.232704)
		)
		(stroke
			(width 0)
			(type solid)
		)
		(fill yes)
		(layer "F.Cu")
		(net "M_L_DQS_DN<5>")
	)
	(gr_poly
		(pts
			(xy 115.905788 -106.559604) (xy 115.905788 -106.458004) (xy 115.715288 -106.445304) (xy 115.664488 -106.445304)
			(xy 115.664488 -106.572304) (xy 115.715288 -106.572304)
		)
		(stroke
			(width 0)
			(type solid)
		)
		(fill yes)
		(layer "F.Cu")
		(net "M_L_DQS_DN<5>")
	)
	(gr_poly
		(pts
			(xy 115.913154 -45.752258) (xy 115.787424 -45.608494) (xy 115.751356 -45.57268) (xy 115.661694 -45.662342)
			(xy 115.697508 -45.69841) (xy 115.841272 -45.82414)
		)
		(stroke
			(width 0)
			(type solid)
		)
		(fill yes)
		(layer "F.Cu")
		(net "M_H_DQS_DN<14>")
	)
	(gr_poly
		(pts
			(xy 115.948968 -42.437812) (xy 115.898168 -42.437812) (xy 115.707668 -42.450512) (xy 115.707668 -42.552112)
			(xy 115.898168 -42.564812) (xy 115.948968 -42.564812)
		)
		(stroke
			(width 0)
			(type solid)
		)
		(fill yes)
		(layer "F.Cu")
		(net "M_H_DQ<45>")
	)
	(gr_poly
		(pts
			(xy 115.948968 -41.777412) (xy 115.898168 -41.777412) (xy 115.707668 -41.790112) (xy 115.707668 -41.891712)
			(xy 115.898168 -41.904412) (xy 115.948968 -41.904412)
		)
		(stroke
			(width 0)
			(type solid)
		)
		(fill yes)
		(layer "F.Cu")
		(net "M_H_DQ<45>")
	)
	(gr_poly
		(pts
			(xy 115.961414 -109.175804) (xy 115.997482 -109.13999) (xy 115.907566 -109.050074) (xy 115.871752 -109.086142)
			(xy 115.746022 -109.229652) (xy 115.817904 -109.301534)
		)
		(stroke
			(width 0)
			(type solid)
		)
		(fill yes)
		(layer "F.Cu")
		(net "M_L_DQS_DN<5>")
	)
	(gr_poly
		(pts
			(xy 115.969796 -111.96955) (xy 116.00561 -111.933482) (xy 115.915948 -111.84382) (xy 115.87988 -111.879634)
			(xy 115.75415 -112.023398) (xy 115.826032 -112.09528)
		)
		(stroke
			(width 0)
			(type solid)
		)
		(fill yes)
		(layer "F.Cu")
		(net "M_L_DQ<45>")
	)
	(gr_poly
		(pts
			(xy 115.9764 -48.132746) (xy 115.940586 -48.096678) (xy 115.796822 -47.970948) (xy 115.72494 -48.04283)
			(xy 115.85067 -48.186594) (xy 115.886738 -48.222408)
		)
		(stroke
			(width 0)
			(type solid)
		)
		(fill yes)
		(layer "F.Cu")
		(net "M_H_DQ<42>")
	)
	(gr_poly
		(pts
			(xy 115.984782 -45.339254) (xy 115.948968 -45.303186) (xy 115.805204 -45.177456) (xy 115.733322 -45.249338)
			(xy 115.859052 -45.393102) (xy 115.89512 -45.428916)
		)
		(stroke
			(width 0)
			(type solid)
		)
		(fill yes)
		(layer "F.Cu")
		(net "M_H_DQS_DN<14>")
	)
	(gr_poly
		(pts
			(xy 115.988338 -109.61624) (xy 116.114068 -109.472476) (xy 116.042186 -109.400594) (xy 115.898422 -109.526324)
			(xy 115.862608 -109.562392) (xy 115.95227 -109.652054)
		)
		(stroke
			(width 0)
			(type solid)
		)
		(fill yes)
		(layer "F.Cu")
		(net "M_L_DQS_DN<14>")
	)
	(gr_poly
		(pts
			(xy 115.99291 -53.145944) (xy 116.080794 -52.943252) (xy 115.960144 -52.7939) (xy 115.91925 -52.776374)
			(xy 115.760754 -53.142134) (xy 115.801394 -53.159914)
		)
		(stroke
			(width 0)
			(type solid)
		)
		(fill yes)
		(layer "F.Cu")
		(net "M_H_DQ<43>")
	)
	(gr_poly
		(pts
			(xy 115.996466 -112.409732) (xy 116.122196 -112.265968) (xy 116.050568 -112.194086) (xy 115.906804 -112.319816)
			(xy 115.870736 -112.35563) (xy 115.960652 -112.445546)
		)
		(stroke
			(width 0)
			(type solid)
		)
		(fill yes)
		(layer "F.Cu")
		(net "M_L_DQ<44>")
	)
	(gr_poly
		(pts
			(xy 116.00307 -46.776132) (xy 115.87734 -46.632622) (xy 115.841526 -46.596554) (xy 115.75161 -46.68647)
			(xy 115.787424 -46.722284) (xy 115.931188 -46.848014)
		)
		(stroke
			(width 0)
			(type solid)
		)
		(fill yes)
		(layer "F.Cu")
		(net "M_H_DQS_DP<5>")
	)
	(gr_poly
		(pts
			(xy 116.011452 -43.982894) (xy 115.885722 -43.83913) (xy 115.849908 -43.803062) (xy 115.759992 -43.892978)
			(xy 115.795806 -43.928792) (xy 115.93957 -44.054522)
		)
		(stroke
			(width 0)
			(type solid)
		)
		(fill yes)
		(layer "F.Cu")
		(net "M_H_DQ<40>")
	)
	(gr_poly
		(pts
			(xy 116.013992 -48.666908) (xy 116.013992 -48.565308) (xy 115.823492 -48.552608) (xy 115.772692 -48.552608)
			(xy 115.772692 -48.679608) (xy 115.823492 -48.679608)
		)
		(stroke
			(width 0)
			(type solid)
		)
		(fill yes)
		(layer "F.Cu")
		(net "M_H_DQ<42>")
	)
	(gr_poly
		(pts
			(xy 116.058188 -108.096304) (xy 116.007388 -108.096304) (xy 115.816888 -108.109004) (xy 115.816888 -108.210604)
			(xy 116.007388 -108.223304) (xy 116.058188 -108.223304)
		)
		(stroke
			(width 0)
			(type solid)
		)
		(fill yes)
		(layer "F.Cu")
		(net "M_L_DQS_DP<5>")
	)
	(gr_poly
		(pts
			(xy 116.058188 -107.435904) (xy 116.007388 -107.435904) (xy 115.816888 -107.448604) (xy 115.816888 -107.550204)
			(xy 116.007388 -107.562904) (xy 116.058188 -107.562904)
		)
		(stroke
			(width 0)
			(type solid)
		)
		(fill yes)
		(layer "F.Cu")
		(net "M_L_DQS_DP<5>")
	)
	(gr_poly
		(pts
			(xy 116.058188 -106.775504) (xy 116.007388 -106.775504) (xy 115.816888 -106.788204) (xy 115.816888 -106.889804)
			(xy 116.007388 -106.902504) (xy 116.058188 -106.902504)
		)
		(stroke
			(width 0)
			(type solid)
		)
		(fill yes)
		(layer "F.Cu")
		(net "M_L_DQS_DP<5>")
	)
	(gr_poly
		(pts
			(xy 116.058188 -106.115104) (xy 116.007388 -106.115104) (xy 115.816888 -106.127804) (xy 115.816888 -106.229404)
			(xy 116.007388 -106.242104) (xy 116.058188 -106.242104)
		)
		(stroke
			(width 0)
			(type solid)
		)
		(fill yes)
		(layer "F.Cu")
		(net "M_L_DQS_DP<5>")
	)
	(gr_poly
		(pts
			(xy 116.059712 -110.945422) (xy 116.09578 -110.909608) (xy 116.005864 -110.819692) (xy 115.97005 -110.85576)
			(xy 115.84432 -110.99927) (xy 115.916202 -111.071152)
		)
		(stroke
			(width 0)
			(type solid)
		)
		(fill yes)
		(layer "F.Cu")
		(net "M_L_DQ<41>")
	)
	(gr_poly
		(pts
			(xy 116.074952 -46.363128) (xy 116.038884 -46.327314) (xy 115.895374 -46.201584) (xy 115.823492 -46.273466)
			(xy 115.949222 -46.416976) (xy 115.985036 -46.453044)
		)
		(stroke
			(width 0)
			(type solid)
		)
		(fill yes)
		(layer "F.Cu")
		(net "M_H_DQS_DP<5>")
	)
	(gr_poly
		(pts
			(xy 116.083334 -43.569636) (xy 116.047266 -43.533822) (xy 115.903756 -43.408092) (xy 115.831874 -43.479974)
			(xy 115.957604 -43.623484) (xy 115.993418 -43.659552)
		)
		(stroke
			(width 0)
			(type solid)
		)
		(fill yes)
		(layer "F.Cu")
		(net "M_H_DQ<40>")
	)
	(gr_poly
		(pts
			(xy 116.086636 -111.385604) (xy 116.212366 -111.24184) (xy 116.140484 -111.170212) (xy 115.99672 -111.295942)
			(xy 115.960906 -111.331756) (xy 116.050822 -111.421672)
		)
		(stroke
			(width 0)
			(type solid)
		)
		(fill yes)
		(layer "F.Cu")
		(net "M_L_DQ<40>")
	)
	(gr_poly
		(pts
			(xy 116.09324 -47.80026) (xy 115.96751 -47.656496) (xy 115.931442 -47.620682) (xy 115.84178 -47.710344)
			(xy 115.877594 -47.746412) (xy 116.021358 -47.872142)
		)
		(stroke
			(width 0)
			(type solid)
		)
		(fill yes)
		(layer "F.Cu")
		(net "M_H_DQ<47>")
	)
	(gr_poly
		(pts
			(xy 116.095018 -101.273102) (xy 116.050568 -101.273102) (xy 115.880388 -101.362002) (xy 115.880388 -101.582982)
			(xy 116.050568 -101.671882) (xy 116.095018 -101.671882)
		)
		(stroke
			(width 0)
			(type solid)
		)
		(fill yes)
		(layer "F.Cu")
		(net "M_L_DQ<46>")
	)
	(gr_poly
		(pts
			(xy 116.101368 -45.006768) (xy 115.975892 -44.863004) (xy 115.939824 -44.82719) (xy 115.850162 -44.916852)
			(xy 115.885976 -44.95292) (xy 116.02974 -45.07865)
		)
		(stroke
			(width 0)
			(type solid)
		)
		(fill yes)
		(layer "F.Cu")
		(net "M_H_DQS_DP<14>")
	)
	(gr_poly
		(pts
			(xy 116.149882 -109.921548) (xy 116.185696 -109.88548) (xy 116.096034 -109.795818) (xy 116.059966 -109.831632)
			(xy 115.934236 -109.975396) (xy 116.006118 -110.047278)
		)
		(stroke
			(width 0)
			(type solid)
		)
		(fill yes)
		(layer "F.Cu")
		(net "M_L_DQS_DN<14>")
	)
	(gr_poly
		(pts
			(xy 116.158264 -112.71504) (xy 116.194078 -112.678972) (xy 116.104416 -112.58931) (xy 116.068348 -112.625124)
			(xy 115.942618 -112.768888) (xy 116.0145 -112.84077)
		)
		(stroke
			(width 0)
			(type solid)
		)
		(fill yes)
		(layer "F.Cu")
		(net "M_L_DQ<44>")
	)
	(gr_poly
		(pts
			(xy 116.164868 -47.387256) (xy 116.129054 -47.351188) (xy 115.98529 -47.225458) (xy 115.913408 -47.29734)
			(xy 116.039138 -47.441104) (xy 116.075206 -47.476918)
		)
		(stroke
			(width 0)
			(type solid)
		)
		(fill yes)
		(layer "F.Cu")
		(net "M_H_DQ<47>")
	)
	(gr_poly
		(pts
			(xy 116.166392 -48.882808) (xy 116.115592 -48.882808) (xy 115.925092 -48.895508) (xy 115.925092 -48.997108)
			(xy 116.115592 -49.009808) (xy 116.166392 -49.009808)
		)
		(stroke
			(width 0)
			(type solid)
		)
		(fill yes)
		(layer "F.Cu")
		(net "M_H_DQ<43>")
	)
	(gr_poly
		(pts
			(xy 116.17325 -44.593764) (xy 116.137436 -44.557696) (xy 115.993672 -44.431966) (xy 115.92179 -44.503848)
			(xy 116.04752 -44.647612) (xy 116.083588 -44.683426)
		)
		(stroke
			(width 0)
			(type solid)
		)
		(fill yes)
		(layer "F.Cu")
		(net "M_H_DQS_DP<14>")
	)
	(gr_poly
		(pts
			(xy 116.176806 -110.36173) (xy 116.302282 -110.217966) (xy 116.230654 -110.146084) (xy 116.08689 -110.271814)
			(xy 116.051076 -110.307882) (xy 116.140738 -110.397544)
		)
		(stroke
			(width 0)
			(type solid)
		)
		(fill yes)
		(layer "F.Cu")
		(net "M_L_DQS_DP<14>")
	)
	(gr_poly
		(pts
			(xy 116.190268 -42.882312) (xy 116.190268 -42.780712) (xy 115.999768 -42.768012) (xy 115.948968 -42.768012)
			(xy 115.948968 -42.895012) (xy 115.999768 -42.895012)
		)
		(stroke
			(width 0)
			(type solid)
		)
		(fill yes)
		(layer "F.Cu")
		(net "M_H_DQ<45>")
	)
	(gr_poly
		(pts
			(xy 116.190268 -42.221912) (xy 116.190268 -42.120312) (xy 115.999768 -42.107612) (xy 115.948968 -42.107612)
			(xy 115.948968 -42.234612) (xy 115.999768 -42.234612)
		)
		(stroke
			(width 0)
			(type solid)
		)
		(fill yes)
		(layer "F.Cu")
		(net "M_H_DQ<45>")
	)
	(gr_poly
		(pts
			(xy 116.190268 -41.561512) (xy 116.190268 -41.459912) (xy 115.999768 -41.447212) (xy 115.948968 -41.447212)
			(xy 115.948968 -41.574212) (xy 115.999768 -41.574212)
		)
		(stroke
			(width 0)
			(type solid)
		)
		(fill yes)
		(layer "F.Cu")
		(net "M_H_DQ<45>")
	)
	(gr_poly
		(pts
			(xy 116.191538 -46.030896) (xy 116.065808 -45.887132) (xy 116.029994 -45.851064) (xy 115.940078 -45.94098)
			(xy 115.975892 -45.976794) (xy 116.119656 -46.102524)
		)
		(stroke
			(width 0)
			(type solid)
		)
		(fill yes)
		(layer "F.Cu")
		(net "M_H_DQS_DN<5>")
	)
	(gr_poly
		(pts
			(xy 116.194078 -105.551732) (xy 116.194078 -105.323132) (xy 116.001038 -105.234232) (xy 115.956588 -105.234232)
			(xy 115.956588 -105.640632) (xy 116.001038 -105.640632)
		)
		(stroke
			(width 0)
			(type solid)
		)
		(fill yes)
		(layer "F.Cu")
		(net "M_L_DQS_DP<5>")
	)
	(gr_poly
		(pts
			(xy 116.194078 -104.561132) (xy 116.194078 -104.332532) (xy 116.001038 -104.243632) (xy 115.956588 -104.243632)
			(xy 115.956588 -104.650032) (xy 116.001038 -104.650032)
		)
		(stroke
			(width 0)
			(type solid)
		)
		(fill yes)
		(layer "F.Cu")
		(net "M_L_DQS_DP<5>")
	)
	(gr_poly
		(pts
			(xy 116.240052 -108.89742) (xy 116.275866 -108.861352) (xy 116.186204 -108.77169) (xy 116.150136 -108.807504)
			(xy 116.024406 -108.951268) (xy 116.096288 -109.02315)
		)
		(stroke
			(width 0)
			(type solid)
		)
		(fill yes)
		(layer "F.Cu")
		(net "M_L_DQS_DP<5>")
	)
	(gr_poly
		(pts
			(xy 116.24818 -111.690912) (xy 116.284248 -111.655098) (xy 116.194332 -111.565182) (xy 116.158518 -111.60125)
			(xy 116.032788 -111.74476) (xy 116.10467 -111.816642)
		)
		(stroke
			(width 0)
			(type solid)
		)
		(fill yes)
		(layer "F.Cu")
		(net "M_L_DQ<40>")
	)
	(gr_poly
		(pts
			(xy 116.26342 -45.617638) (xy 116.227352 -45.581824) (xy 116.083842 -45.456094) (xy 116.01196 -45.527976)
			(xy 116.13769 -45.671486) (xy 116.173504 -45.707554)
		)
		(stroke
			(width 0)
			(type solid)
		)
		(fill yes)
		(layer "F.Cu")
		(net "M_H_DQS_DN<5>")
	)
	(gr_poly
		(pts
			(xy 116.266976 -109.337602) (xy 116.392706 -109.193838) (xy 116.320824 -109.121956) (xy 116.17706 -109.247686)
			(xy 116.141246 -109.283754) (xy 116.230908 -109.373416)
		)
		(stroke
			(width 0)
			(type solid)
		)
		(fill yes)
		(layer "F.Cu")
		(net "M_L_DQS_DN<5>")
	)
	(gr_poly
		(pts
			(xy 116.275104 -112.131094) (xy 116.400834 -111.98733) (xy 116.328952 -111.915702) (xy 116.185188 -112.041432)
			(xy 116.149374 -112.077246) (xy 116.23929 -112.167162)
		)
		(stroke
			(width 0)
			(type solid)
		)
		(fill yes)
		(layer "F.Cu")
		(net "M_L_DQ<45>")
	)
	(gr_poly
		(pts
			(xy 116.281708 -47.05477) (xy 116.155978 -46.911006) (xy 116.11991 -46.875192) (xy 116.030248 -46.964854)
			(xy 116.066062 -47.000922) (xy 116.209826 -47.126652)
		)
		(stroke
			(width 0)
			(type solid)
		)
		(fill yes)
		(layer "F.Cu")
		(net "M_H_DQ<46>")
	)
	(gr_poly
		(pts
			(xy 116.289836 -44.261278) (xy 116.164106 -44.117514) (xy 116.128292 -44.0817) (xy 116.03863 -44.171362)
			(xy 116.074444 -44.20743) (xy 116.218208 -44.33316)
		)
		(stroke
			(width 0)
			(type solid)
		)
		(fill yes)
		(layer "F.Cu")
		(net "M_H_DQ<41>")
	)
	(gr_poly
		(pts
			(xy 116.299488 -107.880404) (xy 116.299488 -107.778804) (xy 116.108988 -107.766104) (xy 116.058188 -107.766104)
			(xy 116.058188 -107.893104) (xy 116.108988 -107.893104)
		)
		(stroke
			(width 0)
			(type solid)
		)
		(fill yes)
		(layer "F.Cu")
		(net "M_L_DQS_DP<5>")
	)
	(gr_poly
		(pts
			(xy 116.299488 -107.220004) (xy 116.299488 -107.118404) (xy 116.108988 -107.105704) (xy 116.058188 -107.105704)
			(xy 116.058188 -107.232704) (xy 116.108988 -107.232704)
		)
		(stroke
			(width 0)
			(type solid)
		)
		(fill yes)
		(layer "F.Cu")
		(net "M_L_DQS_DP<5>")
	)
	(gr_poly
		(pts
			(xy 116.299488 -106.559604) (xy 116.299488 -106.458004) (xy 116.108988 -106.445304) (xy 116.058188 -106.445304)
			(xy 116.058188 -106.572304) (xy 116.108988 -106.572304)
		)
		(stroke
			(width 0)
			(type solid)
		)
		(fill yes)
		(layer "F.Cu")
		(net "M_L_DQS_DP<5>")
	)
	(gr_poly
		(pts
			(xy 116.33835 -110.667038) (xy 116.374164 -110.63097) (xy 116.284502 -110.541308) (xy 116.248434 -110.577122)
			(xy 116.122704 -110.720886) (xy 116.194586 -110.792768)
		)
		(stroke
			(width 0)
			(type solid)
		)
		(fill yes)
		(layer "F.Cu")
		(net "M_L_DQS_DP<14>")
	)
	(gr_poly
		(pts
			(xy 116.342668 -42.437812) (xy 116.291868 -42.437812) (xy 116.101368 -42.450512) (xy 116.101368 -42.552112)
			(xy 116.291868 -42.564812) (xy 116.342668 -42.564812)
		)
		(stroke
			(width 0)
			(type solid)
		)
		(fill yes)
		(layer "F.Cu")
		(net "M_H_DQ<40>")
	)
	(gr_poly
		(pts
			(xy 116.342668 -41.777412) (xy 116.291868 -41.777412) (xy 116.101368 -41.790112) (xy 116.101368 -41.891712)
			(xy 116.291868 -41.904412) (xy 116.342668 -41.904412)
		)
		(stroke
			(width 0)
			(type solid)
		)
		(fill yes)
		(layer "F.Cu")
		(net "M_H_DQ<40>")
	)
	(gr_poly
		(pts
			(xy 116.353336 -46.641766) (xy 116.317522 -46.605698) (xy 116.173758 -46.479968) (xy 116.101876 -46.55185)
			(xy 116.227606 -46.695614) (xy 116.263674 -46.731428)
		)
		(stroke
			(width 0)
			(type solid)
		)
		(fill yes)
		(layer "F.Cu")
		(net "M_H_DQ<46>")
	)
	(gr_poly
		(pts
			(xy 116.361718 -43.848274) (xy 116.325904 -43.812206) (xy 116.18214 -43.686476) (xy 116.110258 -43.758358)
			(xy 116.235988 -43.902122) (xy 116.272056 -43.937936)
		)
		(stroke
			(width 0)
			(type solid)
		)
		(fill yes)
		(layer "F.Cu")
		(net "M_H_DQ<41>")
	)
	(gr_poly
		(pts
			(xy 116.36502 -111.10722) (xy 116.49075 -110.963456) (xy 116.419122 -110.891574) (xy 116.275358 -111.017304)
			(xy 116.239544 -111.053372) (xy 116.329206 -111.143034)
		)
		(stroke
			(width 0)
			(type solid)
		)
		(fill yes)
		(layer "F.Cu")
		(net "M_L_DQ<41>")
	)
	(gr_poly
		(pts
			(xy 116.371624 -48.078644) (xy 116.245894 -47.935134) (xy 116.21008 -47.899066) (xy 116.120164 -47.988982)
			(xy 116.156232 -48.024796) (xy 116.299742 -48.150526)
		)
		(stroke
			(width 0)
			(type solid)
		)
		(fill yes)
		(layer "F.Cu")
		(net "M_H_DQ<42>")
	)
	(gr_poly
		(pts
			(xy 116.380006 -45.285406) (xy 116.254276 -45.141642) (xy 116.218462 -45.105574) (xy 116.128546 -45.19549)
			(xy 116.16436 -45.231304) (xy 116.308124 -45.357034)
		)
		(stroke
			(width 0)
			(type solid)
		)
		(fill yes)
		(layer "F.Cu")
		(net "M_H_DQS_DN<14>")
	)
	(gr_poly
		(pts
			(xy 116.42852 -109.64291) (xy 116.464334 -109.606842) (xy 116.374672 -109.51718) (xy 116.338604 -109.552994)
			(xy 116.212874 -109.696758) (xy 116.284756 -109.76864)
		)
		(stroke
			(width 0)
			(type solid)
		)
		(fill yes)
		(layer "F.Cu")
		(net "M_L_DQS_DN<5>")
	)
	(gr_poly
		(pts
			(xy 116.436648 -112.436402) (xy 116.472716 -112.400588) (xy 116.3828 -112.310672) (xy 116.346986 -112.34674)
			(xy 116.221256 -112.49025) (xy 116.293138 -112.562132)
		)
		(stroke
			(width 0)
			(type solid)
		)
		(fill yes)
		(layer "F.Cu")
		(net "M_L_DQ<45>")
	)
	(gr_poly
		(pts
			(xy 116.44249 -102.084378) (xy 116.44249 -101.863398) (xy 116.27231 -101.774498) (xy 116.22786 -101.774498)
			(xy 116.22786 -102.173278) (xy 116.27231 -102.173278)
		)
		(stroke
			(width 0)
			(type solid)
		)
		(fill yes)
		(layer "F.Cu")
		(net "M_L_DQ<46>")
	)
	(gr_poly
		(pts
			(xy 116.443506 -47.66564) (xy 116.407438 -47.629826) (xy 116.263928 -47.504096) (xy 116.192046 -47.575978)
			(xy 116.317776 -47.719488) (xy 116.35359 -47.755556)
		)
		(stroke
			(width 0)
			(type solid)
		)
		(fill yes)
		(layer "F.Cu")
		(net "M_H_DQ<42>")
	)
	(gr_poly
		(pts
			(xy 116.451888 -108.096304) (xy 116.401088 -108.096304) (xy 116.210588 -108.109004) (xy 116.210588 -108.210604)
			(xy 116.401088 -108.223304) (xy 116.451888 -108.223304)
		)
		(stroke
			(width 0)
			(type solid)
		)
		(fill yes)
		(layer "F.Cu")
		(net "M_L_DQ<46>")
	)
	(gr_poly
		(pts
			(xy 116.451888 -107.435904) (xy 116.401088 -107.435904) (xy 116.210588 -107.448604) (xy 116.210588 -107.550204)
			(xy 116.401088 -107.562904) (xy 116.451888 -107.562904)
		)
		(stroke
			(width 0)
			(type solid)
		)
		(fill yes)
		(layer "F.Cu")
		(net "M_L_DQ<46>")
	)
	(gr_poly
		(pts
			(xy 116.451888 -106.775504) (xy 116.401088 -106.775504) (xy 116.210588 -106.788204) (xy 116.210588 -106.889804)
			(xy 116.401088 -106.902504) (xy 116.451888 -106.902504)
		)
		(stroke
			(width 0)
			(type solid)
		)
		(fill yes)
		(layer "F.Cu")
		(net "M_L_DQ<46>")
	)
	(gr_poly
		(pts
			(xy 116.451888 -106.115104) (xy 116.401088 -106.115104) (xy 116.210588 -106.127804) (xy 116.210588 -106.229404)
			(xy 116.401088 -106.242104) (xy 116.451888 -106.242104)
		)
		(stroke
			(width 0)
			(type solid)
		)
		(fill yes)
		(layer "F.Cu")
		(net "M_L_DQ<46>")
	)
	(gr_poly
		(pts
			(xy 116.451888 -44.872148) (xy 116.41582 -44.836334) (xy 116.27231 -44.710604) (xy 116.200428 -44.782486)
			(xy 116.326158 -44.925996) (xy 116.361972 -44.962064)
		)
		(stroke
			(width 0)
			(type solid)
		)
		(fill yes)
		(layer "F.Cu")
		(net "M_H_DQS_DN<14>")
	)
	(gr_poly
		(pts
			(xy 116.45519 -110.083092) (xy 116.58092 -109.939328) (xy 116.509038 -109.8677) (xy 116.365274 -109.99343)
			(xy 116.32946 -110.029244) (xy 116.419376 -110.11916)
		)
		(stroke
			(width 0)
			(type solid)
		)
		(fill yes)
		(layer "F.Cu")
		(net "M_L_DQS_DN<14>")
	)
	(gr_poly
		(pts
			(xy 116.463572 -112.876584) (xy 116.589302 -112.73282) (xy 116.517674 -112.660938) (xy 116.37391 -112.786668)
			(xy 116.337842 -112.822482) (xy 116.427758 -112.912398)
		)
		(stroke
			(width 0)
			(type solid)
		)
		(fill yes)
		(layer "F.Cu")
		(net "M_L_DQ<44>")
	)
	(gr_poly
		(pts
			(xy 116.470176 -46.30928) (xy 116.344446 -46.165516) (xy 116.308378 -46.129702) (xy 116.218716 -46.219364)
			(xy 116.25453 -46.255432) (xy 116.398294 -46.381162)
		)
		(stroke
			(width 0)
			(type solid)
		)
		(fill yes)
		(layer "F.Cu")
		(net "M_H_DQS_DP<5>")
	)
	(gr_poly
		(pts
			(xy 116.526818 -111.412528) (xy 116.562632 -111.37646) (xy 116.47297 -111.286798) (xy 116.436902 -111.322612)
			(xy 116.311172 -111.466376) (xy 116.383054 -111.538258)
		)
		(stroke
			(width 0)
			(type solid)
		)
		(fill yes)
		(layer "F.Cu")
		(net "M_L_DQ<41>")
	)
	(gr_poly
		(pts
			(xy 116.541804 -45.896276) (xy 116.50599 -45.860208) (xy 116.362226 -45.734478) (xy 116.290344 -45.80636)
			(xy 116.416074 -45.950124) (xy 116.452142 -45.985938)
		)
		(stroke
			(width 0)
			(type solid)
		)
		(fill yes)
		(layer "F.Cu")
		(net "M_H_DQS_DP<5>")
	)
	(gr_poly
		(pts
			(xy 116.54536 -109.058964) (xy 116.67109 -108.9152) (xy 116.599208 -108.843572) (xy 116.455444 -108.969302)
			(xy 116.41963 -109.005116) (xy 116.509546 -109.095032)
		)
		(stroke
			(width 0)
			(type solid)
		)
		(fill yes)
		(layer "F.Cu")
		(net "M_L_DQS_DP<5>")
	)
	(gr_poly
		(pts
			(xy 116.54663 -105.235248) (xy 116.50218 -105.235248) (xy 116.30914 -105.324148) (xy 116.30914 -105.552748)
			(xy 116.50218 -105.641648) (xy 116.54663 -105.641648)
		)
		(stroke
			(width 0)
			(type solid)
		)
		(fill yes)
		(layer "F.Cu")
		(net "M_L_DQ<46>")
	)
	(gr_poly
		(pts
			(xy 116.54663 -104.244648) (xy 116.50218 -104.244648) (xy 116.30914 -104.333548) (xy 116.30914 -104.562148)
			(xy 116.50218 -104.651048) (xy 116.54663 -104.651048)
		)
		(stroke
			(width 0)
			(type solid)
		)
		(fill yes)
		(layer "F.Cu")
		(net "M_L_DQ<46>")
	)
	(gr_poly
		(pts
			(xy 116.553488 -111.85271) (xy 116.679218 -111.708946) (xy 116.60759 -111.637064) (xy 116.463826 -111.762794)
			(xy 116.427758 -111.798608) (xy 116.517674 -111.888524)
		)
		(stroke
			(width 0)
			(type solid)
		)
		(fill yes)
		(layer "F.Cu")
		(net "M_L_DQ<40>")
	)
	(gr_poly
		(pts
			(xy 116.560092 -47.333154) (xy 116.434362 -47.189644) (xy 116.398548 -47.153576) (xy 116.308632 -47.243492)
			(xy 116.344446 -47.279306) (xy 116.48821 -47.405036)
		)
		(stroke
			(width 0)
			(type solid)
		)
		(fill yes)
		(layer "F.Cu")
		(net "M_H_DQ<47>")
	)
	(gr_poly
		(pts
			(xy 116.568474 -44.539916) (xy 116.442744 -44.396152) (xy 116.40693 -44.360084) (xy 116.317014 -44.45)
			(xy 116.352828 -44.485814) (xy 116.496592 -44.611544)
		)
		(stroke
			(width 0)
			(type solid)
		)
		(fill yes)
		(layer "F.Cu")
		(net "M_H_DQS_DP<14>")
	)
	(gr_poly
		(pts
			(xy 116.583968 -42.882312) (xy 116.583968 -42.780712) (xy 116.393468 -42.768012) (xy 116.342668 -42.768012)
			(xy 116.342668 -42.895012) (xy 116.393468 -42.895012)
		)
		(stroke
			(width 0)
			(type solid)
		)
		(fill yes)
		(layer "F.Cu")
		(net "M_H_DQ<40>")
	)
	(gr_poly
		(pts
			(xy 116.583968 -42.221912) (xy 116.583968 -42.120312) (xy 116.393468 -42.107612) (xy 116.342668 -42.107612)
			(xy 116.342668 -42.234612) (xy 116.393468 -42.234612)
		)
		(stroke
			(width 0)
			(type solid)
		)
		(fill yes)
		(layer "F.Cu")
		(net "M_H_DQ<40>")
	)
	(gr_poly
		(pts
			(xy 116.616734 -110.3884) (xy 116.652802 -110.352586) (xy 116.562886 -110.26267) (xy 116.527072 -110.298738)
			(xy 116.401342 -110.442248) (xy 116.473224 -110.51413)
		)
		(stroke
			(width 0)
			(type solid)
		)
		(fill yes)
		(layer "F.Cu")
		(net "M_L_DQS_DN<14>")
	)
	(gr_poly
		(pts
			(xy 116.631974 -46.92015) (xy 116.595906 -46.884336) (xy 116.452396 -46.758606) (xy 116.380514 -46.830488)
			(xy 116.506244 -46.973998) (xy 116.542058 -47.010066)
		)
		(stroke
			(width 0)
			(type solid)
		)
		(fill yes)
		(layer "F.Cu")
		(net "M_H_DQ<47>")
	)
	(gr_poly
		(pts
			(xy 116.640356 -44.126658) (xy 116.604288 -44.090844) (xy 116.460778 -43.965114) (xy 116.388896 -44.036996)
			(xy 116.514626 -44.180506) (xy 116.55044 -44.216574)
		)
		(stroke
			(width 0)
			(type solid)
		)
		(fill yes)
		(layer "F.Cu")
		(net "M_H_DQS_DP<14>")
	)
	(gr_poly
		(pts
			(xy 116.643658 -110.828582) (xy 116.769388 -110.684818) (xy 116.697506 -110.61319) (xy 116.553742 -110.73892)
			(xy 116.517928 -110.774734) (xy 116.607844 -110.86465)
		)
		(stroke
			(width 0)
			(type solid)
		)
		(fill yes)
		(layer "F.Cu")
		(net "M_L_DQS_DP<14>")
	)
	(gr_poly
		(pts
			(xy 116.650262 -48.357282) (xy 116.524532 -48.213518) (xy 116.488464 -48.177704) (xy 116.398802 -48.267366)
			(xy 116.434616 -48.303434) (xy 116.57838 -48.429164)
		)
		(stroke
			(width 0)
			(type solid)
		)
		(fill yes)
		(layer "F.Cu")
		(net "M_H_DQ<43>")
	)
	(gr_poly
		(pts
			(xy 116.65839 -45.56379) (xy 116.532914 -45.420026) (xy 116.496846 -45.384212) (xy 116.407184 -45.473874)
			(xy 116.442998 -45.509942) (xy 116.586762 -45.635672)
		)
		(stroke
			(width 0)
			(type solid)
		)
		(fill yes)
		(layer "F.Cu")
		(net "M_H_DQS_DN<5>")
	)
	(gr_poly
		(pts
			(xy 116.693188 -107.880404) (xy 116.693188 -107.778804) (xy 116.502688 -107.766104) (xy 116.451888 -107.766104)
			(xy 116.451888 -107.893104) (xy 116.502688 -107.893104)
		)
		(stroke
			(width 0)
			(type solid)
		)
		(fill yes)
		(layer "F.Cu")
		(net "M_L_DQ<46>")
	)
	(gr_poly
		(pts
			(xy 116.693188 -107.220004) (xy 116.693188 -107.118404) (xy 116.502688 -107.105704) (xy 116.451888 -107.105704)
			(xy 116.451888 -107.232704) (xy 116.502688 -107.232704)
		)
		(stroke
			(width 0)
			(type solid)
		)
		(fill yes)
		(layer "F.Cu")
		(net "M_L_DQ<46>")
	)
	(gr_poly
		(pts
			(xy 116.693188 -106.559604) (xy 116.693188 -106.458004) (xy 116.502688 -106.445304) (xy 116.451888 -106.445304)
			(xy 116.451888 -106.572304) (xy 116.502688 -106.572304)
		)
		(stroke
			(width 0)
			(type solid)
		)
		(fill yes)
		(layer "F.Cu")
		(net "M_L_DQ<46>")
	)
	(gr_poly
		(pts
			(xy 116.706904 -109.364272) (xy 116.742972 -109.328458) (xy 116.653056 -109.238542) (xy 116.617242 -109.27461)
			(xy 116.491512 -109.41812) (xy 116.563394 -109.490002)
		)
		(stroke
			(width 0)
			(type solid)
		)
		(fill yes)
		(layer "F.Cu")
		(net "M_L_DQS_DP<5>")
	)
	(gr_poly
		(pts
			(xy 116.715286 -112.158018) (xy 116.7511 -112.12195) (xy 116.661438 -112.032288) (xy 116.62537 -112.068102)
			(xy 116.49964 -112.211866) (xy 116.571522 -112.283748)
		)
		(stroke
			(width 0)
			(type solid)
		)
		(fill yes)
		(layer "F.Cu")
		(net "M_L_DQ<40>")
	)
	(gr_poly
		(pts
			(xy 116.72189 -47.944278) (xy 116.686076 -47.90821) (xy 116.542312 -47.78248) (xy 116.47043 -47.854362)
			(xy 116.59616 -47.998126) (xy 116.632228 -48.03394)
		)
		(stroke
			(width 0)
			(type solid)
		)
		(fill yes)
		(layer "F.Cu")
		(net "M_H_DQ<43>")
	)
	(gr_poly
		(pts
			(xy 116.730272 -45.150786) (xy 116.694458 -45.114718) (xy 116.550694 -44.988988) (xy 116.478812 -45.06087)
			(xy 116.604542 -45.204634) (xy 116.64061 -45.240448)
		)
		(stroke
			(width 0)
			(type solid)
		)
		(fill yes)
		(layer "F.Cu")
		(net "M_H_DQS_DN<5>")
	)
	(gr_poly
		(pts
			(xy 116.733828 -109.804454) (xy 116.859558 -109.66069) (xy 116.787676 -109.589062) (xy 116.643912 -109.714792)
			(xy 116.608098 -109.750606) (xy 116.698014 -109.840522)
		)
		(stroke
			(width 0)
			(type solid)
		)
		(fill yes)
		(layer "F.Cu")
		(net "M_L_DQS_DN<5>")
	)
	(gr_poly
		(pts
			(xy 116.736368 -43.098212) (xy 116.685568 -43.098212) (xy 116.495068 -43.110912) (xy 116.495068 -43.212512)
			(xy 116.685568 -43.225212) (xy 116.736368 -43.225212)
		)
		(stroke
			(width 0)
			(type solid)
		)
		(fill yes)
		(layer "F.Cu")
		(net "M_H_DQ<41>")
	)
	(gr_poly
		(pts
			(xy 116.736368 -42.437812) (xy 116.685568 -42.437812) (xy 116.495068 -42.450512) (xy 116.495068 -42.552112)
			(xy 116.685568 -42.564812) (xy 116.736368 -42.564812)
		)
		(stroke
			(width 0)
			(type solid)
		)
		(fill yes)
		(layer "F.Cu")
		(net "M_H_DQ<41>")
	)
	(gr_poly
		(pts
			(xy 116.736368 -41.777412) (xy 116.685568 -41.777412) (xy 116.495068 -41.790112) (xy 116.495068 -41.891712)
			(xy 116.685568 -41.904412) (xy 116.736368 -41.904412)
		)
		(stroke
			(width 0)
			(type solid)
		)
		(fill yes)
		(layer "F.Cu")
		(net "M_H_DQ<41>")
	)
	(gr_poly
		(pts
			(xy 116.741956 -112.5982) (xy 116.867686 -112.454436) (xy 116.796058 -112.382554) (xy 116.652294 -112.508284)
			(xy 116.616226 -112.544098) (xy 116.706142 -112.634014)
		)
		(stroke
			(width 0)
			(type solid)
		)
		(fill yes)
		(layer "F.Cu")
		(net "M_L_DQ<45>")
	)
	(gr_poly
		(pts
			(xy 116.74856 -46.587918) (xy 116.62283 -46.444154) (xy 116.587016 -46.408086) (xy 116.4971 -46.498002)
			(xy 116.532914 -46.533816) (xy 116.676678 -46.659546)
		)
		(stroke
			(width 0)
			(type solid)
		)
		(fill yes)
		(layer "F.Cu")
		(net "M_H_DQ<46>")
	)
	(gr_poly
		(pts
			(xy 116.756942 -43.794426) (xy 116.631212 -43.650662) (xy 116.595398 -43.614594) (xy 116.505482 -43.70451)
			(xy 116.541296 -43.740324) (xy 116.68506 -43.866054)
		)
		(stroke
			(width 0)
			(type solid)
		)
		(fill yes)
		(layer "F.Cu")
		(net "M_H_DQ<41>")
	)
	(gr_poly
		(pts
			(xy 116.762784 -101.780086) (xy 116.718334 -101.780086) (xy 116.548154 -101.868986) (xy 116.548154 -102.089966)
			(xy 116.718334 -102.178866) (xy 116.762784 -102.178866)
		)
		(stroke
			(width 0)
			(type solid)
		)
		(fill yes)
		(layer "F.Cu")
		(net "M_L_DQ<42>")
	)
	(gr_poly
		(pts
			(xy 116.805202 -111.13389) (xy 116.84127 -111.098076) (xy 116.751354 -111.00816) (xy 116.71554 -111.044228)
			(xy 116.58981 -111.187738) (xy 116.661692 -111.25962)
		)
		(stroke
			(width 0)
			(type solid)
		)
		(fill yes)
		(layer "F.Cu")
		(net "M_L_DQS_DP<14>")
	)
	(gr_poly
		(pts
			(xy 116.820442 -46.17466) (xy 116.784374 -46.138846) (xy 116.640864 -46.013116) (xy 116.568982 -46.084998)
			(xy 116.694712 -46.228508) (xy 116.730526 -46.264576)
		)
		(stroke
			(width 0)
			(type solid)
		)
		(fill yes)
		(layer "F.Cu")
		(net "M_H_DQ<46>")
	)
	(gr_poly
		(pts
			(xy 116.823998 -108.780326) (xy 116.949728 -108.636562) (xy 116.877846 -108.564934) (xy 116.734082 -108.690664)
			(xy 116.698268 -108.726478) (xy 116.788184 -108.816394)
		)
		(stroke
			(width 0)
			(type solid)
		)
		(fill yes)
		(layer "F.Cu")
		(net "M_L_DQ<46>")
	)
	(gr_poly
		(pts
			(xy 116.832126 -111.574072) (xy 116.957856 -111.430308) (xy 116.885974 -111.35868) (xy 116.74221 -111.48441)
			(xy 116.706396 -111.520224) (xy 116.796312 -111.61014)
		)
		(stroke
			(width 0)
			(type solid)
		)
		(fill yes)
		(layer "F.Cu")
		(net "M_L_DQ<41>")
	)
	(gr_poly
		(pts
			(xy 116.83873 -47.611792) (xy 116.713 -47.468028) (xy 116.676932 -47.432214) (xy 116.58727 -47.521876)
			(xy 116.623084 -47.557944) (xy 116.766848 -47.683674)
		)
		(stroke
			(width 0)
			(type solid)
		)
		(fill yes)
		(layer "F.Cu")
		(net "M_H_DQ<42>")
	)
	(gr_poly
		(pts
			(xy 116.845588 -108.096304) (xy 116.794788 -108.096304) (xy 116.604288 -108.109004) (xy 116.604288 -108.210604)
			(xy 116.794788 -108.223304) (xy 116.845588 -108.223304)
		)
		(stroke
			(width 0)
			(type solid)
		)
		(fill yes)
		(layer "F.Cu")
		(net "M_L_DQ<47>")
	)
	(gr_poly
		(pts
			(xy 116.845588 -107.435904) (xy 116.794788 -107.435904) (xy 116.604288 -107.448604) (xy 116.604288 -107.550204)
			(xy 116.794788 -107.562904) (xy 116.845588 -107.562904)
		)
		(stroke
			(width 0)
			(type solid)
		)
		(fill yes)
		(layer "F.Cu")
		(net "M_L_DQ<47>")
	)
	(gr_poly
		(pts
			(xy 116.845588 -106.775504) (xy 116.794788 -106.775504) (xy 116.604288 -106.788204) (xy 116.604288 -106.889804)
			(xy 116.794788 -106.902504) (xy 116.845588 -106.902504)
		)
		(stroke
			(width 0)
			(type solid)
		)
		(fill yes)
		(layer "F.Cu")
		(net "M_L_DQ<47>")
	)
	(gr_poly
		(pts
			(xy 116.845588 -106.115104) (xy 116.794788 -106.115104) (xy 116.604288 -106.127804) (xy 116.604288 -106.229404)
			(xy 116.794788 -106.242104) (xy 116.845588 -106.242104)
		)
		(stroke
			(width 0)
			(type solid)
		)
		(fill yes)
		(layer "F.Cu")
		(net "M_L_DQ<47>")
	)
	(gr_poly
		(pts
			(xy 116.846858 -44.8183) (xy 116.721128 -44.674536) (xy 116.685314 -44.638722) (xy 116.595652 -44.728384)
			(xy 116.631466 -44.764452) (xy 116.77523 -44.890182)
		)
		(stroke
			(width 0)
			(type solid)
		)
		(fill yes)
		(layer "F.Cu")
		(net "M_H_DQS_DN<14>")
	)
	(gr_poly
		(pts
			(xy 116.895372 -110.109762) (xy 116.93144 -110.073948) (xy 116.841524 -109.984032) (xy 116.80571 -110.0201)
			(xy 116.67998 -110.16361) (xy 116.751862 -110.235492)
		)
		(stroke
			(width 0)
			(type solid)
		)
		(fill yes)
		(layer "F.Cu")
		(net "M_L_DQS_DN<5>")
	)
	(gr_poly
		(pts
			(xy 116.903754 -112.903254) (xy 116.939822 -112.86744) (xy 116.849906 -112.777524) (xy 116.814092 -112.813592)
			(xy 116.688362 -112.957102) (xy 116.760244 -113.028984)
		)
		(stroke
			(width 0)
			(type solid)
		)
		(fill yes)
		(layer "F.Cu")
		(net "M_L_DQ<45>")
	)
	(gr_poly
		(pts
			(xy 116.910358 -47.198788) (xy 116.874544 -47.16272) (xy 116.73078 -47.03699) (xy 116.658898 -47.108872)
			(xy 116.784628 -47.252636) (xy 116.820696 -47.28845)
		)
		(stroke
			(width 0)
			(type solid)
		)
		(fill yes)
		(layer "F.Cu")
		(net "M_H_DQ<42>")
	)
	(gr_poly
		(pts
			(xy 116.91874 -44.405296) (xy 116.882926 -44.369228) (xy 116.739162 -44.243498) (xy 116.66728 -44.31538)
			(xy 116.79301 -44.459144) (xy 116.829078 -44.494958)
		)
		(stroke
			(width 0)
			(type solid)
		)
		(fill yes)
		(layer "F.Cu")
		(net "M_H_DQS_DN<14>")
	)
	(gr_poly
		(pts
			(xy 116.922042 -110.550198) (xy 117.047772 -110.406434) (xy 116.976144 -110.334552) (xy 116.83238 -110.460282)
			(xy 116.796566 -110.49635) (xy 116.886228 -110.586012)
		)
		(stroke
			(width 0)
			(type solid)
		)
		(fill yes)
		(layer "F.Cu")
		(net "M_L_DQS_DN<14>")
	)
	(gr_poly
		(pts
			(xy 116.937028 -45.842428) (xy 116.811298 -45.698664) (xy 116.775484 -45.662596) (xy 116.685568 -45.752512)
			(xy 116.721382 -45.788326) (xy 116.865146 -45.914056)
		)
		(stroke
			(width 0)
			(type solid)
		)
		(fill yes)
		(layer "F.Cu")
		(net "M_H_DQS_DP<5>")
	)
	(gr_poly
		(pts
			(xy 116.97462 -105.552748) (xy 116.97462 -105.324148) (xy 116.78158 -105.235248) (xy 116.73713 -105.235248)
			(xy 116.73713 -105.641648) (xy 116.78158 -105.641648)
		)
		(stroke
			(width 0)
			(type solid)
		)
		(fill yes)
		(layer "F.Cu")
		(net "M_L_DQ<47>")
	)
	(gr_poly
		(pts
			(xy 116.97462 -104.562148) (xy 116.97462 -104.333548) (xy 116.78158 -104.244648) (xy 116.73713 -104.244648)
			(xy 116.73713 -104.651048) (xy 116.78158 -104.651048)
		)
		(stroke
			(width 0)
			(type solid)
		)
		(fill yes)
		(layer "F.Cu")
		(net "M_L_DQ<47>")
	)
	(gr_poly
		(pts
			(xy 116.977668 -42.882312) (xy 116.977668 -42.780712) (xy 116.787168 -42.768012) (xy 116.736368 -42.768012)
			(xy 116.736368 -42.895012) (xy 116.787168 -42.895012)
		)
		(stroke
			(width 0)
			(type solid)
		)
		(fill yes)
		(layer "F.Cu")
		(net "M_H_DQ<41>")
	)
	(gr_poly
		(pts
			(xy 116.977668 -42.221912) (xy 116.977668 -42.120312) (xy 116.787168 -42.107612) (xy 116.736368 -42.107612)
			(xy 116.736368 -42.234612) (xy 116.787168 -42.234612)
		)
		(stroke
			(width 0)
			(type solid)
		)
		(fill yes)
		(layer "F.Cu")
		(net "M_H_DQ<41>")
	)
	(gr_poly
		(pts
			(xy 116.985542 -109.085634) (xy 117.02161 -109.04982) (xy 116.931694 -108.959904) (xy 116.89588 -108.995972)
			(xy 116.77015 -109.139482) (xy 116.842032 -109.211364)
		)
		(stroke
			(width 0)
			(type solid)
		)
		(fill yes)
		(layer "F.Cu")
		(net "M_L_DQ<46>")
	)
	(gr_poly
		(pts
			(xy 116.99367 -111.87938) (xy 117.029738 -111.843566) (xy 116.939822 -111.75365) (xy 116.904008 -111.789718)
			(xy 116.778278 -111.933228) (xy 116.85016 -112.00511)
		)
		(stroke
			(width 0)
			(type solid)
		)
		(fill yes)
		(layer "F.Cu")
		(net "M_L_DQ<41>")
	)
	(gr_poly
		(pts
			(xy 117.00891 -45.42917) (xy 116.972842 -45.393356) (xy 116.829332 -45.267626) (xy 116.75745 -45.339508)
			(xy 116.88318 -45.483018) (xy 116.918994 -45.519086)
		)
		(stroke
			(width 0)
			(type solid)
		)
		(fill yes)
		(layer "F.Cu")
		(net "M_H_DQS_DP<5>")
	)
	(gr_poly
		(pts
			(xy 117.012466 -109.52607) (xy 117.137942 -109.382306) (xy 117.066314 -109.310424) (xy 116.92255 -109.436154)
			(xy 116.886736 -109.472222) (xy 116.976398 -109.561884)
		)
		(stroke
			(width 0)
			(type solid)
		)
		(fill yes)
		(layer "F.Cu")
		(net "M_L_DQS_DP<5>")
	)
	(gr_poly
		(pts
			(xy 117.020594 -112.319562) (xy 117.146324 -112.175798) (xy 117.074442 -112.10417) (xy 116.930678 -112.2299)
			(xy 116.894864 -112.265714) (xy 116.98478 -112.35563)
		)
		(stroke
			(width 0)
			(type solid)
		)
		(fill yes)
		(layer "F.Cu")
		(net "M_L_DQ<40>")
	)
	(gr_poly
		(pts
			(xy 117.027198 -46.866302) (xy 116.901468 -46.722538) (xy 116.8654 -46.686724) (xy 116.775738 -46.776386)
			(xy 116.811552 -46.812454) (xy 116.955316 -46.938184)
		)
		(stroke
			(width 0)
			(type solid)
		)
		(fill yes)
		(layer "F.Cu")
		(net "M_H_DQ<47>")
	)
	(gr_poly
		(pts
			(xy 117.035326 -44.07281) (xy 116.909596 -43.929046) (xy 116.873782 -43.893232) (xy 116.783866 -43.983148)
			(xy 116.819934 -44.018962) (xy 116.963698 -44.144692)
		)
		(stroke
			(width 0)
			(type solid)
		)
		(fill yes)
		(layer "F.Cu")
		(net "M_H_DQS_DP<14>")
	)
	(gr_poly
		(pts
			(xy 117.08384 -110.855506) (xy 117.119654 -110.819438) (xy 117.029992 -110.729776) (xy 116.993924 -110.76559)
			(xy 116.868194 -110.909354) (xy 116.940076 -110.981236)
		)
		(stroke
			(width 0)
			(type solid)
		)
		(fill yes)
		(layer "F.Cu")
		(net "M_L_DQS_DN<14>")
	)
	(gr_poly
		(pts
			(xy 117.086888 -107.880404) (xy 117.086888 -107.778804) (xy 116.896388 -107.766104) (xy 116.845588 -107.766104)
			(xy 116.845588 -107.893104) (xy 116.896388 -107.893104)
		)
		(stroke
			(width 0)
			(type solid)
		)
		(fill yes)
		(layer "F.Cu")
		(net "M_L_DQ<47>")
	)
	(gr_poly
		(pts
			(xy 117.086888 -107.220004) (xy 117.086888 -107.118404) (xy 116.896388 -107.105704) (xy 116.845588 -107.105704)
			(xy 116.845588 -107.232704) (xy 116.896388 -107.232704)
		)
		(stroke
			(width 0)
			(type solid)
		)
		(fill yes)
		(layer "F.Cu")
		(net "M_L_DQ<47>")
	)
	(gr_poly
		(pts
			(xy 117.086888 -106.559604) (xy 117.086888 -106.458004) (xy 116.896388 -106.445304) (xy 116.845588 -106.445304)
			(xy 116.845588 -106.572304) (xy 116.896388 -106.572304)
		)
		(stroke
			(width 0)
			(type solid)
		)
		(fill yes)
		(layer "F.Cu")
		(net "M_L_DQ<47>")
	)
	(gr_poly
		(pts
			(xy 117.098826 -46.453298) (xy 117.063012 -46.41723) (xy 116.919248 -46.2915) (xy 116.847366 -46.363382)
			(xy 116.973096 -46.507146) (xy 117.009164 -46.54296)
		)
		(stroke
			(width 0)
			(type solid)
		)
		(fill yes)
		(layer "F.Cu")
		(net "M_H_DQ<47>")
	)
	(gr_poly
		(pts
			(xy 117.102636 -108.501942) (xy 117.228366 -108.358178) (xy 117.156484 -108.286296) (xy 117.01272 -108.412026)
			(xy 116.976906 -108.448094) (xy 117.066568 -108.537756)
		)
		(stroke
			(width 0)
			(type solid)
		)
		(fill yes)
		(layer "F.Cu")
		(net "M_L_DQ<47>")
	)
	(gr_poly
		(pts
			(xy 117.11051 -111.295688) (xy 117.23624 -111.151924) (xy 117.164612 -111.080042) (xy 117.020848 -111.205772)
			(xy 116.98478 -111.241586) (xy 117.074696 -111.331502)
		)
		(stroke
			(width 0)
			(type solid)
		)
		(fill yes)
		(layer "F.Cu")
		(net "M_L_DQS_DP<14>")
	)
	(gr_poly
		(pts
			(xy 117.117114 -47.890176) (xy 116.991384 -47.746666) (xy 116.95557 -47.710598) (xy 116.865654 -47.800514)
			(xy 116.901468 -47.836328) (xy 117.045232 -47.962058)
		)
		(stroke
			(width 0)
			(type solid)
		)
		(fill yes)
		(layer "F.Cu")
		(net "M_H_DQ<43>")
	)
	(gr_poly
		(pts
			(xy 117.125496 -45.096938) (xy 116.999766 -44.953174) (xy 116.963952 -44.917106) (xy 116.874036 -45.007022)
			(xy 116.90985 -45.042836) (xy 117.053614 -45.168566)
		)
		(stroke
			(width 0)
			(type solid)
		)
		(fill yes)
		(layer "F.Cu")
		(net "M_H_DQS_DN<5>")
	)
	(gr_poly
		(pts
			(xy 117.13083 -49.591976) (xy 117.099334 -49.56048) (xy 116.9162 -49.503076) (xy 116.75999 -49.659286)
			(xy 116.817394 -49.84242) (xy 116.84889 -49.873916)
		)
		(stroke
			(width 0)
			(type solid)
		)
		(fill yes)
		(layer "F.Cu")
		(net "M_H_DQ<52>")
	)
	(gr_poly
		(pts
			(xy 117.17401 -109.831378) (xy 117.209824 -109.79531) (xy 117.120162 -109.705648) (xy 117.084094 -109.741462)
			(xy 116.958364 -109.885226) (xy 117.030246 -109.957108)
		)
		(stroke
			(width 0)
			(type solid)
		)
		(fill yes)
		(layer "F.Cu")
		(net "M_L_DQS_DP<5>")
	)
	(gr_poly
		(pts
			(xy 117.182138 -112.62487) (xy 117.218206 -112.589056) (xy 117.12829 -112.49914) (xy 117.092476 -112.535208)
			(xy 116.966746 -112.678718) (xy 117.038628 -112.7506)
		)
		(stroke
			(width 0)
			(type solid)
		)
		(fill yes)
		(layer "F.Cu")
		(net "M_L_DQ<40>")
	)
	(gr_poly
		(pts
			(xy 117.188996 -47.477172) (xy 117.152928 -47.441358) (xy 117.009418 -47.315628) (xy 116.937536 -47.38751)
			(xy 117.063266 -47.53102) (xy 117.09908 -47.567088)
		)
		(stroke
			(width 0)
			(type solid)
		)
		(fill yes)
		(layer "F.Cu")
		(net "M_H_DQ<43>")
	)
	(gr_poly
		(pts
			(xy 117.197378 -44.68368) (xy 117.16131 -44.647866) (xy 117.0178 -44.522136) (xy 116.945918 -44.594018)
			(xy 117.071648 -44.737528) (xy 117.107462 -44.773596)
		)
		(stroke
			(width 0)
			(type solid)
		)
		(fill yes)
		(layer "F.Cu")
		(net "M_H_DQS_DN<5>")
	)
	(gr_poly
		(pts
			(xy 117.20068 -110.27156) (xy 117.32641 -110.127796) (xy 117.254782 -110.055914) (xy 117.111018 -110.181644)
			(xy 117.075204 -110.217712) (xy 117.164866 -110.307374)
		)
		(stroke
			(width 0)
			(type solid)
		)
		(fill yes)
		(layer "F.Cu")
		(net "M_L_DQS_DN<5>")
	)
	(gr_poly
		(pts
			(xy 117.215412 -46.120812) (xy 117.089936 -45.977048) (xy 117.053868 -45.941234) (xy 116.964206 -46.030896)
			(xy 117.00002 -46.066964) (xy 117.143784 -46.192694)
		)
		(stroke
			(width 0)
			(type solid)
		)
		(fill yes)
		(layer "F.Cu")
		(net "M_H_DQ<46>")
	)
	(gr_poly
		(pts
			(xy 117.239288 -107.435904) (xy 117.188488 -107.435904) (xy 116.997988 -107.448604) (xy 116.997988 -107.550204)
			(xy 117.188488 -107.562904) (xy 117.239288 -107.562904)
		)
		(stroke
			(width 0)
			(type solid)
		)
		(fill yes)
		(layer "F.Cu")
		(net "M_L_DQ<42>")
	)
	(gr_poly
		(pts
			(xy 117.239288 -106.775504) (xy 117.188488 -106.775504) (xy 116.997988 -106.788204) (xy 116.997988 -106.889804)
			(xy 117.188488 -106.902504) (xy 117.239288 -106.902504)
		)
		(stroke
			(width 0)
			(type solid)
		)
		(fill yes)
		(layer "F.Cu")
		(net "M_L_DQ<42>")
	)
	(gr_poly
		(pts
			(xy 117.239288 -106.115104) (xy 117.188488 -106.115104) (xy 116.997988 -106.127804) (xy 116.997988 -106.229404)
			(xy 117.188488 -106.242104) (xy 117.239288 -106.242104)
		)
		(stroke
			(width 0)
			(type solid)
		)
		(fill yes)
		(layer "F.Cu")
		(net "M_L_DQ<42>")
	)
	(gr_poly
		(pts
			(xy 117.26418 -108.80725) (xy 117.299994 -108.771182) (xy 117.210332 -108.68152) (xy 117.174264 -108.717334)
			(xy 117.048534 -108.861098) (xy 117.120416 -108.93298)
		)
		(stroke
			(width 0)
			(type solid)
		)
		(fill yes)
		(layer "F.Cu")
		(net "M_L_DQ<47>")
	)
	(gr_poly
		(pts
			(xy 117.272308 -111.600996) (xy 117.308122 -111.564928) (xy 117.21846 -111.475266) (xy 117.182392 -111.51108)
			(xy 117.056662 -111.654844) (xy 117.128544 -111.726726)
		)
		(stroke
			(width 0)
			(type solid)
		)
		(fill yes)
		(layer "F.Cu")
		(net "M_L_DQS_DP<14>")
	)
	(gr_poly
		(pts
			(xy 117.287294 -45.707808) (xy 117.25148 -45.67174) (xy 117.107716 -45.54601) (xy 117.035834 -45.617892)
			(xy 117.161564 -45.761656) (xy 117.197632 -45.79747)
		)
		(stroke
			(width 0)
			(type solid)
		)
		(fill yes)
		(layer "F.Cu")
		(net "M_H_DQ<46>")
	)
	(gr_poly
		(pts
			(xy 117.291104 -109.247432) (xy 117.41658 -109.103668) (xy 117.344952 -109.031786) (xy 117.201188 -109.157516)
			(xy 117.165374 -109.193584) (xy 117.255036 -109.283246)
		)
		(stroke
			(width 0)
			(type solid)
		)
		(fill yes)
		(layer "F.Cu")
		(net "M_L_DQ<46>")
	)
	(gr_poly
		(pts
			(xy 117.298978 -112.041178) (xy 117.424708 -111.897414) (xy 117.35308 -111.825532) (xy 117.209316 -111.951262)
			(xy 117.173248 -111.987076) (xy 117.263164 -112.076992)
		)
		(stroke
			(width 0)
			(type solid)
		)
		(fill yes)
		(layer "F.Cu")
		(net "M_L_DQ<41>")
	)
	(gr_poly
		(pts
			(xy 117.30101 -52.051712) (xy 117.30101 -51.830732) (xy 117.13083 -51.741832) (xy 117.08638 -51.741832)
			(xy 117.08638 -52.140612) (xy 117.13083 -52.140612)
		)
		(stroke
			(width 0)
			(type solid)
		)
		(fill yes)
		(layer "F.Cu")
		(net "M_H_DQ<53>")
	)
	(gr_poly
		(pts
			(xy 117.305582 -47.14494) (xy 117.179852 -47.001176) (xy 117.144038 -46.965108) (xy 117.054122 -47.055024)
			(xy 117.089936 -47.090838) (xy 117.2337 -47.216568)
		)
		(stroke
			(width 0)
			(type solid)
		)
		(fill yes)
		(layer "F.Cu")
		(net "M_H_DQ<42>")
	)
	(gr_poly
		(pts
			(xy 117.313964 -44.351448) (xy 117.188234 -44.207684) (xy 117.15242 -44.171616) (xy 117.062504 -44.261532)
			(xy 117.098318 -44.297346) (xy 117.242082 -44.423076)
		)
		(stroke
			(width 0)
			(type solid)
		)
		(fill yes)
		(layer "F.Cu")
		(net "M_H_DQS_DN<14>")
	)
	(gr_poly
		(pts
			(xy 117.340888 -105.235248) (xy 117.296438 -105.235248) (xy 117.103398 -105.324148) (xy 117.103398 -105.552748)
			(xy 117.296438 -105.641648) (xy 117.340888 -105.641648)
		)
		(stroke
			(width 0)
			(type solid)
		)
		(fill yes)
		(layer "F.Cu")
		(net "M_L_DQ<42>")
	)
	(gr_poly
		(pts
			(xy 117.340888 -104.244648) (xy 117.296438 -104.244648) (xy 117.103398 -104.333548) (xy 117.103398 -104.562148)
			(xy 117.296438 -104.651048) (xy 117.340888 -104.651048)
		)
		(stroke
			(width 0)
			(type solid)
		)
		(fill yes)
		(layer "F.Cu")
		(net "M_L_DQ<42>")
	)
	(gr_poly
		(pts
			(xy 117.362478 -110.576868) (xy 117.398292 -110.5408) (xy 117.30863 -110.451138) (xy 117.272562 -110.486952)
			(xy 117.146832 -110.630716) (xy 117.218714 -110.702598)
		)
		(stroke
			(width 0)
			(type solid)
		)
		(fill yes)
		(layer "F.Cu")
		(net "M_L_DQS_DN<5>")
	)
	(gr_poly
		(pts
			(xy 117.377464 -46.731682) (xy 117.341396 -46.695868) (xy 117.197886 -46.570138) (xy 117.126004 -46.64202)
			(xy 117.251734 -46.78553) (xy 117.287548 -46.821598)
		)
		(stroke
			(width 0)
			(type solid)
		)
		(fill yes)
		(layer "F.Cu")
		(net "M_H_DQ<42>")
	)
	(gr_poly
		(pts
			(xy 117.385846 -43.93819) (xy 117.349778 -43.902376) (xy 117.206268 -43.776646) (xy 117.134386 -43.848528)
			(xy 117.260116 -43.992038) (xy 117.29593 -44.028106)
		)
		(stroke
			(width 0)
			(type solid)
		)
		(fill yes)
		(layer "F.Cu")
		(net "M_H_DQS_DN<14>")
	)
	(gr_poly
		(pts
			(xy 117.389148 -111.01705) (xy 117.514878 -110.873286) (xy 117.442996 -110.801658) (xy 117.299232 -110.927388)
			(xy 117.263418 -110.963202) (xy 117.353334 -111.053118)
		)
		(stroke
			(width 0)
			(type solid)
		)
		(fill yes)
		(layer "F.Cu")
		(net "M_L_DQS_DN<14>")
	)
	(gr_poly
		(pts
			(xy 117.40388 -45.375322) (xy 117.27815 -45.231558) (xy 117.242336 -45.195744) (xy 117.152674 -45.285406)
			(xy 117.188488 -45.321474) (xy 117.332252 -45.447204)
		)
		(stroke
			(width 0)
			(type solid)
		)
		(fill yes)
		(layer "F.Cu")
		(net "M_H_DQS_DP<5>")
	)
	(gr_poly
		(pts
			(xy 117.452648 -109.55274) (xy 117.488462 -109.516672) (xy 117.3988 -109.42701) (xy 117.362732 -109.462824)
			(xy 117.237002 -109.606588) (xy 117.308884 -109.67847)
		)
		(stroke
			(width 0)
			(type solid)
		)
		(fill yes)
		(layer "F.Cu")
		(net "M_L_DQ<46>")
	)
	(gr_poly
		(pts
			(xy 117.460776 -112.346486) (xy 117.49659 -112.310418) (xy 117.406928 -112.220756) (xy 117.37086 -112.25657)
			(xy 117.24513 -112.400334) (xy 117.317012 -112.472216)
		)
		(stroke
			(width 0)
			(type solid)
		)
		(fill yes)
		(layer "F.Cu")
		(net "M_L_DQ<41>")
	)
	(gr_poly
		(pts
			(xy 117.474238 -49.821846) (xy 117.416834 -49.638712) (xy 117.385338 -49.607216) (xy 117.103398 -49.889156)
			(xy 117.13464 -49.920652) (xy 117.318028 -49.978056)
		)
		(stroke
			(width 0)
			(type solid)
		)
		(fill yes)
		(layer "F.Cu")
		(net "M_H_DQ<53>")
	)
	(gr_poly
		(pts
			(xy 117.475762 -44.962318) (xy 117.439948 -44.92625) (xy 117.296184 -44.80052) (xy 117.224302 -44.872402)
			(xy 117.350032 -45.016166) (xy 117.3861 -45.05198)
		)
		(stroke
			(width 0)
			(type solid)
		)
		(fill yes)
		(layer "F.Cu")
		(net "M_H_DQS_DP<5>")
	)
	(gr_poly
		(pts
			(xy 117.479318 -109.992922) (xy 117.605048 -109.849158) (xy 117.533166 -109.77753) (xy 117.389402 -109.90326)
			(xy 117.353588 -109.939074) (xy 117.443504 -110.02899)
		)
		(stroke
			(width 0)
			(type solid)
		)
		(fill yes)
		(layer "F.Cu")
		(net "M_L_DQS_DP<5>")
	)
	(gr_poly
		(pts
			(xy 117.480588 -107.880404) (xy 117.480588 -107.778804) (xy 117.290088 -107.766104) (xy 117.239288 -107.766104)
			(xy 117.239288 -107.893104) (xy 117.290088 -107.893104)
		)
		(stroke
			(width 0)
			(type solid)
		)
		(fill yes)
		(layer "F.Cu")
		(net "M_L_DQ<42>")
	)
	(gr_poly
		(pts
			(xy 117.480588 -107.220004) (xy 117.480588 -107.118404) (xy 117.290088 -107.105704) (xy 117.239288 -107.105704)
			(xy 117.239288 -107.232704) (xy 117.290088 -107.232704)
		)
		(stroke
			(width 0)
			(type solid)
		)
		(fill yes)
		(layer "F.Cu")
		(net "M_L_DQ<42>")
	)
	(gr_poly
		(pts
			(xy 117.480588 -106.559604) (xy 117.480588 -106.458004) (xy 117.290088 -106.445304) (xy 117.239288 -106.445304)
			(xy 117.239288 -106.572304) (xy 117.290088 -106.572304)
		)
		(stroke
			(width 0)
			(type solid)
		)
		(fill yes)
		(layer "F.Cu")
		(net "M_L_DQ<42>")
	)
	(gr_poly
		(pts
			(xy 117.487446 -112.786668) (xy 117.613176 -112.642904) (xy 117.541294 -112.571276) (xy 117.39753 -112.697006)
			(xy 117.361716 -112.73282) (xy 117.451632 -112.822736)
		)
		(stroke
			(width 0)
			(type solid)
		)
		(fill yes)
		(layer "F.Cu")
		(net "M_L_DQ<40>")
	)
	(gr_poly
		(pts
			(xy 117.49405 -46.39945) (xy 117.36832 -46.255686) (xy 117.332506 -46.219618) (xy 117.24259 -46.309534)
			(xy 117.278404 -46.345348) (xy 117.422168 -46.471078)
		)
		(stroke
			(width 0)
			(type solid)
		)
		(fill yes)
		(layer "F.Cu")
		(net "M_H_DQ<47>")
	)
	(gr_poly
		(pts
			(xy 117.502432 -43.605958) (xy 117.376702 -43.462194) (xy 117.340888 -43.426126) (xy 117.250972 -43.516042)
			(xy 117.286786 -43.551856) (xy 117.43055 -43.677586)
		)
		(stroke
			(width 0)
			(type solid)
		)
		(fill yes)
		(layer "F.Cu")
		(net "M_H_DQS_DP<14>")
	)
	(gr_poly
		(pts
			(xy 117.542564 -108.528612) (xy 117.578632 -108.492798) (xy 117.488716 -108.402882) (xy 117.452902 -108.43895)
			(xy 117.327172 -108.58246) (xy 117.399054 -108.654342)
		)
		(stroke
			(width 0)
			(type solid)
		)
		(fill yes)
		(layer "F.Cu")
		(net "M_L_DQ<42>")
	)
	(gr_poly
		(pts
			(xy 117.550692 -111.322358) (xy 117.58676 -111.286544) (xy 117.496844 -111.196628) (xy 117.46103 -111.232696)
			(xy 117.3353 -111.376206) (xy 117.407182 -111.448088)
		)
		(stroke
			(width 0)
			(type solid)
		)
		(fill yes)
		(layer "F.Cu")
		(net "M_L_DQS_DN<14>")
	)
	(gr_poly
		(pts
			(xy 117.565932 -45.986192) (xy 117.529864 -45.950378) (xy 117.386354 -45.824648) (xy 117.314472 -45.89653)
			(xy 117.440202 -46.04004) (xy 117.476016 -46.076108)
		)
		(stroke
			(width 0)
			(type solid)
		)
		(fill yes)
		(layer "F.Cu")
		(net "M_H_DQ<47>")
	)
	(gr_poly
		(pts
			(xy 117.569488 -108.968794) (xy 117.695218 -108.82503) (xy 117.623336 -108.753402) (xy 117.479572 -108.879132)
			(xy 117.443758 -108.914946) (xy 117.533674 -109.004862)
		)
		(stroke
			(width 0)
			(type solid)
		)
		(fill yes)
		(layer "F.Cu")
		(net "M_L_DQ<47>")
	)
	(gr_poly
		(pts
			(xy 117.577616 -111.76254) (xy 117.703346 -111.618776) (xy 117.631464 -111.547148) (xy 117.4877 -111.672878)
			(xy 117.451886 -111.708692) (xy 117.541802 -111.798608)
		)
		(stroke
			(width 0)
			(type solid)
		)
		(fill yes)
		(layer "F.Cu")
		(net "M_L_DQS_DP<14>")
	)
	(gr_poly
		(pts
			(xy 117.58422 -47.423324) (xy 117.45849 -47.27956) (xy 117.422422 -47.243746) (xy 117.33276 -47.333408)
			(xy 117.368574 -47.369476) (xy 117.512338 -47.495206)
		)
		(stroke
			(width 0)
			(type solid)
		)
		(fill yes)
		(layer "F.Cu")
		(net "M_H_DQ<43>")
	)
	(gr_poly
		(pts
			(xy 117.592348 -44.629832) (xy 117.466618 -44.486068) (xy 117.430804 -44.450254) (xy 117.340888 -44.54017)
			(xy 117.376956 -44.575984) (xy 117.52072 -44.701714)
		)
		(stroke
			(width 0)
			(type solid)
		)
		(fill yes)
		(layer "F.Cu")
		(net "M_H_DQS_DN<5>")
	)
	(gr_poly
		(pts
			(xy 117.632988 -107.435904) (xy 117.582188 -107.435904) (xy 117.391688 -107.448604) (xy 117.391688 -107.550204)
			(xy 117.582188 -107.562904) (xy 117.632988 -107.562904)
		)
		(stroke
			(width 0)
			(type solid)
		)
		(fill yes)
		(layer "F.Cu")
		(net "M_L_DQ<43>")
	)
	(gr_poly
		(pts
			(xy 117.632988 -106.775504) (xy 117.582188 -106.775504) (xy 117.391688 -106.788204) (xy 117.391688 -106.889804)
			(xy 117.582188 -106.902504) (xy 117.632988 -106.902504)
		)
		(stroke
			(width 0)
			(type solid)
		)
		(fill yes)
		(layer "F.Cu")
		(net "M_L_DQ<43>")
	)
	(gr_poly
		(pts
			(xy 117.632988 -106.115104) (xy 117.582188 -106.115104) (xy 117.391688 -106.127804) (xy 117.391688 -106.229404)
			(xy 117.582188 -106.242104) (xy 117.632988 -106.242104)
		)
		(stroke
			(width 0)
			(type solid)
		)
		(fill yes)
		(layer "F.Cu")
		(net "M_L_DQ<43>")
	)
	(gr_poly
		(pts
			(xy 117.640862 -110.29823) (xy 117.67693 -110.262416) (xy 117.587014 -110.1725) (xy 117.5512 -110.208568)
			(xy 117.42547 -110.352078) (xy 117.497352 -110.42396)
		)
		(stroke
			(width 0)
			(type solid)
		)
		(fill yes)
		(layer "F.Cu")
		(net "M_L_DQS_DP<5>")
	)
	(gr_poly
		(pts
			(xy 117.655848 -47.01032) (xy 117.620034 -46.974252) (xy 117.47627 -46.848522) (xy 117.404388 -46.920404)
			(xy 117.530118 -47.064168) (xy 117.566186 -47.099982)
		)
		(stroke
			(width 0)
			(type solid)
		)
		(fill yes)
		(layer "F.Cu")
		(net "M_H_DQ<43>")
	)
	(gr_poly
		(pts
			(xy 117.66423 -44.216828) (xy 117.628416 -44.18076) (xy 117.484652 -44.05503) (xy 117.41277 -44.126912)
			(xy 117.5385 -44.270676) (xy 117.574568 -44.30649)
		)
		(stroke
			(width 0)
			(type solid)
		)
		(fill yes)
		(layer "F.Cu")
		(net "M_H_DQS_DN<5>")
	)
	(gr_poly
		(pts
			(xy 117.667786 -110.738412) (xy 117.793516 -110.594648) (xy 117.721634 -110.52302) (xy 117.57787 -110.64875)
			(xy 117.542056 -110.684564) (xy 117.631972 -110.77448)
		)
		(stroke
			(width 0)
			(type solid)
		)
		(fill yes)
		(layer "F.Cu")
		(net "M_L_DQS_DN<5>")
	)
	(gr_poly
		(pts
			(xy 117.682518 -45.65396) (xy 117.556788 -45.510196) (xy 117.520974 -45.474128) (xy 117.431058 -45.564044)
			(xy 117.466872 -45.599858) (xy 117.610636 -45.725588)
		)
		(stroke
			(width 0)
			(type solid)
		)
		(fill yes)
		(layer "F.Cu")
		(net "M_H_DQ<46>")
	)
	(gr_poly
		(pts
			(xy 117.731032 -109.274102) (xy 117.7671 -109.238288) (xy 117.677184 -109.148372) (xy 117.64137 -109.18444)
			(xy 117.51564 -109.32795) (xy 117.587522 -109.399832)
		)
		(stroke
			(width 0)
			(type solid)
		)
		(fill yes)
		(layer "F.Cu")
		(net "M_L_DQ<47>")
	)
	(gr_poly
		(pts
			(xy 117.73916 -112.067848) (xy 117.775228 -112.032034) (xy 117.685312 -111.942118) (xy 117.649498 -111.978186)
			(xy 117.523768 -112.121696) (xy 117.59565 -112.193578)
		)
		(stroke
			(width 0)
			(type solid)
		)
		(fill yes)
		(layer "F.Cu")
		(net "M_L_DQS_DP<14>")
	)
	(gr_poly
		(pts
			(xy 117.7544 -45.240702) (xy 117.718332 -45.204888) (xy 117.574822 -45.079158) (xy 117.50294 -45.15104)
			(xy 117.62867 -45.29455) (xy 117.664484 -45.330618)
		)
		(stroke
			(width 0)
			(type solid)
		)
		(fill yes)
		(layer "F.Cu")
		(net "M_H_DQ<46>")
	)
	(gr_poly
		(pts
			(xy 117.757956 -109.714284) (xy 117.883686 -109.57052) (xy 117.811804 -109.498892) (xy 117.66804 -109.624622)
			(xy 117.632226 -109.660436) (xy 117.722142 -109.750352)
		)
		(stroke
			(width 0)
			(type solid)
		)
		(fill yes)
		(layer "F.Cu")
		(net "M_L_DQ<46>")
	)
	(gr_poly
		(pts
			(xy 117.766084 -112.50803) (xy 117.891814 -112.364266) (xy 117.819932 -112.292638) (xy 117.676168 -112.418368)
			(xy 117.640354 -112.454182) (xy 117.730016 -112.543844)
		)
		(stroke
			(width 0)
			(type solid)
		)
		(fill yes)
		(layer "F.Cu")
		(net "M_L_DQ<41>")
	)
	(gr_poly
		(pts
			(xy 117.768878 -105.552748) (xy 117.768878 -105.324148) (xy 117.575838 -105.235248) (xy 117.531388 -105.235248)
			(xy 117.531388 -105.641648) (xy 117.575838 -105.641648)
		)
		(stroke
			(width 0)
			(type solid)
		)
		(fill yes)
		(layer "F.Cu")
		(net "M_L_DQ<43>")
	)
	(gr_poly
		(pts
			(xy 117.768878 -104.562148) (xy 117.768878 -104.333548) (xy 117.575838 -104.244648) (xy 117.531388 -104.244648)
			(xy 117.531388 -104.651048) (xy 117.575838 -104.651048)
		)
		(stroke
			(width 0)
			(type solid)
		)
		(fill yes)
		(layer "F.Cu")
		(net "M_L_DQ<43>")
	)
	(gr_poly
		(pts
			(xy 117.772434 -46.677834) (xy 117.646958 -46.53407) (xy 117.61089 -46.498256) (xy 117.521228 -46.587918)
			(xy 117.557042 -46.623986) (xy 117.700806 -46.749716)
		)
		(stroke
			(width 0)
			(type solid)
		)
		(fill yes)
		(layer "F.Cu")
		(net "M_H_DQ<42>")
	)
	(gr_poly
		(pts
			(xy 117.780816 -43.884342) (xy 117.655086 -43.740578) (xy 117.619272 -43.704764) (xy 117.529356 -43.79468)
			(xy 117.565424 -43.830494) (xy 117.709188 -43.956224)
		)
		(stroke
			(width 0)
			(type solid)
		)
		(fill yes)
		(layer "F.Cu")
		(net "M_H_DQS_DN<14>")
	)
	(gr_poly
		(pts
			(xy 117.821202 -108.250228) (xy 117.857016 -108.21416) (xy 117.767354 -108.124498) (xy 117.731286 -108.160312)
			(xy 117.605556 -108.304076) (xy 117.677438 -108.375958)
		)
		(stroke
			(width 0)
			(type solid)
		)
		(fill yes)
		(layer "F.Cu")
		(net "M_L_DQ<43>")
	)
	(gr_poly
		(pts
			(xy 117.823996 -48.74387) (xy 117.698266 -48.60036) (xy 117.662452 -48.564292) (xy 117.572536 -48.654208)
			(xy 117.60835 -48.690022) (xy 117.752114 -48.815752)
		)
		(stroke
			(width 0)
			(type solid)
		)
		(fill yes)
		(layer "F.Cu")
		(net "M_H_DQ<52>")
	)
	(gr_poly
		(pts
			(xy 117.82933 -111.04372) (xy 117.865398 -111.007906) (xy 117.775482 -110.91799) (xy 117.739668 -110.954058)
			(xy 117.613938 -111.097568) (xy 117.68582 -111.16945)
		)
		(stroke
			(width 0)
			(type solid)
		)
		(fill yes)
		(layer "F.Cu")
		(net "M_L_DQS_DN<5>")
	)
	(gr_poly
		(pts
			(xy 117.844316 -46.26483) (xy 117.808502 -46.228762) (xy 117.664738 -46.103032) (xy 117.592856 -46.174914)
			(xy 117.718586 -46.318678) (xy 117.754654 -46.354492)
		)
		(stroke
			(width 0)
			(type solid)
		)
		(fill yes)
		(layer "F.Cu")
		(net "M_H_DQ<42>")
	)
	(gr_poly
		(pts
			(xy 117.848126 -108.69041) (xy 117.973602 -108.546646) (xy 117.901974 -108.474764) (xy 117.75821 -108.600494)
			(xy 117.722396 -108.636562) (xy 117.812058 -108.726224)
		)
		(stroke
			(width 0)
			(type solid)
		)
		(fill yes)
		(layer "F.Cu")
		(net "M_L_DQ<42>")
	)
	(gr_poly
		(pts
			(xy 117.851936 -52.982114) (xy 117.860064 -52.790344) (xy 117.668802 -52.679854) (xy 117.50675 -52.782724)
			(xy 117.484398 -52.821078) (xy 117.829838 -53.020722)
		)
		(stroke
			(width 0)
			(type solid)
		)
		(fill yes)
		(layer "F.Cu")
		(net "M_H_DQ<53>")
	)
	(gr_poly
		(pts
			(xy 117.852698 -43.471338) (xy 117.816884 -43.43527) (xy 117.67312 -43.30954) (xy 117.601238 -43.381422)
			(xy 117.726968 -43.525186) (xy 117.763036 -43.561)
		)
		(stroke
			(width 0)
			(type solid)
		)
		(fill yes)
		(layer "F.Cu")
		(net "M_H_DQS_DN<14>")
	)
	(gr_poly
		(pts
			(xy 117.856 -111.484156) (xy 117.98173 -111.340392) (xy 117.910102 -111.26851) (xy 117.766338 -111.39424)
			(xy 117.73027 -111.430054) (xy 117.820186 -111.51997)
		)
		(stroke
			(width 0)
			(type solid)
		)
		(fill yes)
		(layer "F.Cu")
		(net "M_L_DQS_DN<14>")
	)
	(gr_poly
		(pts
			(xy 117.870986 -44.90847) (xy 117.745256 -44.764706) (xy 117.709442 -44.728638) (xy 117.619526 -44.818554)
			(xy 117.65534 -44.854368) (xy 117.799104 -44.980098)
		)
		(stroke
			(width 0)
			(type solid)
		)
		(fill yes)
		(layer "F.Cu")
		(net "M_H_DQS_DP<5>")
	)
	(gr_poly
		(pts
			(xy 117.874288 -107.880404) (xy 117.874288 -107.778804) (xy 117.683788 -107.766104) (xy 117.632988 -107.766104)
			(xy 117.632988 -107.893104) (xy 117.683788 -107.893104)
		)
		(stroke
			(width 0)
			(type solid)
		)
		(fill yes)
		(layer "F.Cu")
		(net "M_L_DQ<43>")
	)
	(gr_poly
		(pts
			(xy 117.874288 -107.220004) (xy 117.874288 -107.118404) (xy 117.683788 -107.105704) (xy 117.632988 -107.105704)
			(xy 117.632988 -107.232704) (xy 117.683788 -107.232704)
		)
		(stroke
			(width 0)
			(type solid)
		)
		(fill yes)
		(layer "F.Cu")
		(net "M_L_DQ<43>")
	)
	(gr_poly
		(pts
			(xy 117.874288 -106.559604) (xy 117.874288 -106.458004) (xy 117.683788 -106.445304) (xy 117.632988 -106.445304)
			(xy 117.632988 -106.572304) (xy 117.683788 -106.572304)
		)
		(stroke
			(width 0)
			(type solid)
		)
		(fill yes)
		(layer "F.Cu")
		(net "M_L_DQ<43>")
	)
	(gr_poly
		(pts
			(xy 117.895878 -48.330866) (xy 117.85981 -48.295052) (xy 117.7163 -48.169322) (xy 117.644418 -48.241204)
			(xy 117.770148 -48.384714) (xy 117.805962 -48.420782)
		)
		(stroke
			(width 0)
			(type solid)
		)
		(fill yes)
		(layer "F.Cu")
		(net "M_H_DQ<52>")
	)
	(gr_poly
		(pts
			(xy 117.907816 -42.104056) (xy 117.857016 -42.104056) (xy 117.666516 -42.116756) (xy 117.666516 -42.218356)
			(xy 117.857016 -42.231056) (xy 117.907816 -42.231056)
		)
		(stroke
			(width 0)
			(type solid)
		)
		(fill yes)
		(layer "F.Cu")
		(net "M_H_DQS_DP<14>")
	)
	(gr_poly
		(pts
			(xy 117.907816 -41.443656) (xy 117.857016 -41.443656) (xy 117.666516 -41.456356) (xy 117.666516 -41.557956)
			(xy 117.857016 -41.570656) (xy 117.907816 -41.570656)
		)
		(stroke
			(width 0)
			(type solid)
		)
		(fill yes)
		(layer "F.Cu")
		(net "M_H_DQS_DP<14>")
	)
	(gr_poly
		(pts
			(xy 117.918992 -50.802032) (xy 117.874542 -50.802032) (xy 117.704362 -50.890932) (xy 117.704362 -51.111912)
			(xy 117.874542 -51.200812) (xy 117.918992 -51.200812)
		)
		(stroke
			(width 0)
			(type solid)
		)
		(fill yes)
		(layer "F.Cu")
		(net "M_H_DQ<48>")
	)
	(gr_poly
		(pts
			(xy 117.918992 -49.811432) (xy 117.874542 -49.811432) (xy 117.704362 -49.900332) (xy 117.704362 -50.121312)
			(xy 117.874542 -50.210212) (xy 117.918992 -50.210212)
		)
		(stroke
			(width 0)
			(type solid)
		)
		(fill yes)
		(layer "F.Cu")
		(net "M_H_DQ<48>")
	)
	(gr_poly
		(pts
			(xy 117.9195 -110.019592) (xy 117.955568 -109.983778) (xy 117.865652 -109.893862) (xy 117.829838 -109.92993)
			(xy 117.704108 -110.07344) (xy 117.77599 -110.145322)
		)
		(stroke
			(width 0)
			(type solid)
		)
		(fill yes)
		(layer "F.Cu")
		(net "M_L_DQ<46>")
	)
	(gr_poly
		(pts
			(xy 117.927628 -112.813592) (xy 117.963442 -112.777524) (xy 117.87378 -112.687862) (xy 117.837712 -112.723676)
			(xy 117.711982 -112.86744) (xy 117.783864 -112.939322)
		)
		(stroke
			(width 0)
			(type solid)
		)
		(fill yes)
		(layer "F.Cu")
		(net "M_L_DQ<41>")
	)
	(gr_poly
		(pts
			(xy 117.942868 -44.495212) (xy 117.9068 -44.459398) (xy 117.76329 -44.333668) (xy 117.691408 -44.40555)
			(xy 117.817138 -44.54906) (xy 117.852952 -44.585128)
		)
		(stroke
			(width 0)
			(type solid)
		)
		(fill yes)
		(layer "F.Cu")
		(net "M_H_DQS_DP<5>")
	)
	(gr_poly
		(pts
			(xy 117.94617 -110.460028) (xy 118.0719 -110.316264) (xy 118.000272 -110.244382) (xy 117.856508 -110.370112)
			(xy 117.82044 -110.405926) (xy 117.910356 -110.495842)
		)
		(stroke
			(width 0)
			(type solid)
		)
		(fill yes)
		(layer "F.Cu")
		(net "M_L_DQS_DP<5>")
	)
	(gr_poly
		(pts
			(xy 117.960902 -45.932344) (xy 117.835172 -45.78858) (xy 117.799358 -45.752766) (xy 117.709696 -45.842428)
			(xy 117.74551 -45.878496) (xy 117.889274 -46.004226)
		)
		(stroke
			(width 0)
			(type solid)
		)
		(fill yes)
		(layer "F.Cu")
		(net "M_H_DQ<47>")
	)
	(gr_poly
		(pts
			(xy 117.969284 -43.138852) (xy 117.843554 -42.995088) (xy 117.80774 -42.959274) (xy 117.717824 -43.04919)
			(xy 117.753892 -43.085004) (xy 117.897656 -43.210734)
		)
		(stroke
			(width 0)
			(type solid)
		)
		(fill yes)
		(layer "F.Cu")
		(net "M_H_DQS_DP<14>")
	)
	(gr_poly
		(pts
			(xy 118.00967 -108.995718) (xy 118.045484 -108.95965) (xy 117.955822 -108.869988) (xy 117.919754 -108.905802)
			(xy 117.794024 -109.049566) (xy 117.865906 -109.121448)
		)
		(stroke
			(width 0)
			(type solid)
		)
		(fill yes)
		(layer "F.Cu")
		(net "M_L_DQ<42>")
	)
	(gr_poly
		(pts
			(xy 118.017798 -111.789464) (xy 118.053612 -111.753396) (xy 117.96395 -111.663734) (xy 117.927882 -111.699548)
			(xy 117.802152 -111.843312) (xy 117.874034 -111.915194)
		)
		(stroke
			(width 0)
			(type solid)
		)
		(fill yes)
		(layer "F.Cu")
		(net "M_L_DQS_DN<14>")
	)
	(gr_poly
		(pts
			(xy 118.032784 -45.51934) (xy 117.99697 -45.483272) (xy 117.853206 -45.357542) (xy 117.781324 -45.429424)
			(xy 117.907054 -45.573188) (xy 117.943122 -45.609002)
		)
		(stroke
			(width 0)
			(type solid)
		)
		(fill yes)
		(layer "F.Cu")
		(net "M_H_DQ<47>")
	)
	(gr_poly
		(pts
			(xy 118.03634 -109.4359) (xy 118.16207 -109.292136) (xy 118.090442 -109.220254) (xy 117.946678 -109.345984)
			(xy 117.910864 -109.382052) (xy 118.000526 -109.471714)
		)
		(stroke
			(width 0)
			(type solid)
		)
		(fill yes)
		(layer "F.Cu")
		(net "M_L_DQ<47>")
	)
	(gr_poly
		(pts
			(xy 118.044468 -112.229646) (xy 118.170198 -112.085882) (xy 118.09857 -112.014) (xy 117.954806 -112.13973)
			(xy 117.918738 -112.175544) (xy 118.008654 -112.26546)
		)
		(stroke
			(width 0)
			(type solid)
		)
		(fill yes)
		(layer "F.Cu")
		(net "M_L_DQS_DP<14>")
	)
	(gr_poly
		(pts
			(xy 118.051072 -46.956472) (xy 117.925342 -46.812708) (xy 117.889528 -46.77664) (xy 117.799612 -46.866556)
			(xy 117.835426 -46.90237) (xy 117.97919 -47.0281)
		)
		(stroke
			(width 0)
			(type solid)
		)
		(fill yes)
		(layer "F.Cu")
		(net "M_H_DQ<43>")
	)
	(gr_poly
		(pts
			(xy 118.059454 -44.16298) (xy 117.933724 -44.019216) (xy 117.89791 -43.983148) (xy 117.807994 -44.073064)
			(xy 117.843808 -44.108878) (xy 117.987572 -44.234608)
		)
		(stroke
			(width 0)
			(type solid)
		)
		(fill yes)
		(layer "F.Cu")
		(net "M_H_DQS_DN<5>")
	)
	(gr_poly
		(pts
			(xy 118.102634 -49.022508) (xy 117.976904 -48.878744) (xy 117.940836 -48.84293) (xy 117.851174 -48.932592)
			(xy 117.886988 -48.96866) (xy 118.030752 -49.09439)
		)
		(stroke
			(width 0)
			(type solid)
		)
		(fill yes)
		(layer "F.Cu")
		(net "M_H_DQ<53>")
	)
	(gr_poly
		(pts
			(xy 118.107968 -110.765336) (xy 118.143782 -110.729268) (xy 118.05412 -110.639606) (xy 118.018052 -110.67542)
			(xy 117.892322 -110.819184) (xy 117.964204 -110.891066)
		)
		(stroke
			(width 0)
			(type solid)
		)
		(fill yes)
		(layer "F.Cu")
		(net "M_L_DQS_DP<5>")
	)
	(gr_poly
		(pts
			(xy 118.122954 -46.543214) (xy 118.086886 -46.5074) (xy 117.943376 -46.38167) (xy 117.871494 -46.453552)
			(xy 117.997224 -46.597062) (xy 118.033038 -46.63313)
		)
		(stroke
			(width 0)
			(type solid)
		)
		(fill yes)
		(layer "F.Cu")
		(net "M_H_DQ<43>")
	)
	(gr_poly
		(pts
			(xy 118.12651 -108.411772) (xy 118.25224 -108.268008) (xy 118.180358 -108.19638) (xy 118.036594 -108.32211)
			(xy 118.00078 -108.357924) (xy 118.090696 -108.44784)
		)
		(stroke
			(width 0)
			(type solid)
		)
		(fill yes)
		(layer "F.Cu")
		(net "M_L_DQ<43>")
	)
	(gr_poly
		(pts
			(xy 118.131336 -43.749722) (xy 118.095268 -43.713908) (xy 117.951758 -43.588178) (xy 117.879876 -43.66006)
			(xy 118.005606 -43.80357) (xy 118.04142 -43.839638)
		)
		(stroke
			(width 0)
			(type solid)
		)
		(fill yes)
		(layer "F.Cu")
		(net "M_H_DQS_DN<5>")
	)
	(gr_poly
		(pts
			(xy 118.134638 -111.205518) (xy 118.260368 -111.061754) (xy 118.18874 -110.989872) (xy 118.044976 -111.115602)
			(xy 118.008908 -111.151416) (xy 118.098824 -111.241332)
		)
		(stroke
			(width 0)
			(type solid)
		)
		(fill yes)
		(layer "F.Cu")
		(net "M_L_DQS_DN<5>")
	)
	(gr_poly
		(pts
			(xy 118.149116 -42.548556) (xy 118.149116 -42.446956) (xy 117.958616 -42.434256) (xy 117.907816 -42.434256)
			(xy 117.907816 -42.561256) (xy 117.958616 -42.561256)
		)
		(stroke
			(width 0)
			(type solid)
		)
		(fill yes)
		(layer "F.Cu")
		(net "M_H_DQS_DP<14>")
	)
	(gr_poly
		(pts
			(xy 118.149116 -41.888156) (xy 118.149116 -41.786556) (xy 117.958616 -41.773856) (xy 117.907816 -41.773856)
			(xy 117.907816 -41.900856) (xy 117.958616 -41.900856)
		)
		(stroke
			(width 0)
			(type solid)
		)
		(fill yes)
		(layer "F.Cu")
		(net "M_H_DQS_DP<14>")
	)
	(gr_poly
		(pts
			(xy 118.14937 -45.186854) (xy 118.02364 -45.04309) (xy 117.987826 -45.007276) (xy 117.89791 -45.097192)
			(xy 117.933978 -45.133006) (xy 118.077742 -45.258736)
		)
		(stroke
			(width 0)
			(type solid)
		)
		(fill yes)
		(layer "F.Cu")
		(net "M_H_DQ<46>")
	)
	(gr_poly
		(pts
			(xy 118.174262 -48.609504) (xy 118.138448 -48.573436) (xy 117.994684 -48.447706) (xy 117.922802 -48.519588)
			(xy 118.048532 -48.663352) (xy 118.0846 -48.699166)
		)
		(stroke
			(width 0)
			(type solid)
		)
		(fill yes)
		(layer "F.Cu")
		(net "M_H_DQ<53>")
	)
	(gr_poly
		(pts
			(xy 118.198138 -109.741208) (xy 118.233952 -109.70514) (xy 118.14429 -109.615478) (xy 118.108222 -109.651292)
			(xy 117.982492 -109.795056) (xy 118.054374 -109.866938)
		)
		(stroke
			(width 0)
			(type solid)
		)
		(fill yes)
		(layer "F.Cu")
		(net "M_L_DQ<47>")
	)
	(gr_poly
		(pts
			(xy 118.206266 -112.534954) (xy 118.24208 -112.498886) (xy 118.152418 -112.409224) (xy 118.11635 -112.445038)
			(xy 117.99062 -112.588802) (xy 118.062502 -112.660684)
		)
		(stroke
			(width 0)
			(type solid)
		)
		(fill yes)
		(layer "F.Cu")
		(net "M_L_DQS_DP<14>")
	)
	(gr_poly
		(pts
			(xy 118.221252 -44.77385) (xy 118.185438 -44.737782) (xy 118.041674 -44.612052) (xy 117.969792 -44.683934)
			(xy 118.095522 -44.827698) (xy 118.13159 -44.863512)
		)
		(stroke
			(width 0)
			(type solid)
		)
		(fill yes)
		(layer "F.Cu")
		(net "M_H_DQ<46>")
	)
	(gr_poly
		(pts
			(xy 118.224808 -110.18139) (xy 118.350538 -110.037626) (xy 118.27891 -109.965744) (xy 118.135146 -110.091474)
			(xy 118.099078 -110.127288) (xy 118.188994 -110.217204)
		)
		(stroke
			(width 0)
			(type solid)
		)
		(fill yes)
		(layer "F.Cu")
		(net "M_L_DQ<46>")
	)
	(gr_poly
		(pts
			(xy 118.23954 -46.210982) (xy 118.11381 -46.067218) (xy 118.077996 -46.03115) (xy 117.98808 -46.121066)
			(xy 118.023894 -46.15688) (xy 118.167658 -46.28261)
		)
		(stroke
			(width 0)
			(type solid)
		)
		(fill yes)
		(layer "F.Cu")
		(net "M_H_DQ<42>")
	)
	(gr_poly
		(pts
			(xy 118.247922 -43.41749) (xy 118.122192 -43.273726) (xy 118.086124 -43.237912) (xy 117.996462 -43.327574)
			(xy 118.032276 -43.363388) (xy 118.17604 -43.489118)
		)
		(stroke
			(width 0)
			(type solid)
		)
		(fill yes)
		(layer "F.Cu")
		(net "M_H_DQS_DN<14>")
	)
	(gr_poly
		(pts
			(xy 118.288054 -108.71708) (xy 118.324122 -108.681266) (xy 118.234206 -108.59135) (xy 118.198392 -108.627418)
			(xy 118.072662 -108.770928) (xy 118.144544 -108.84281)
		)
		(stroke
			(width 0)
			(type solid)
		)
		(fill yes)
		(layer "F.Cu")
		(net "M_L_DQ<43>")
	)
	(gr_poly
		(pts
			(xy 118.291102 -48.277018) (xy 118.165372 -48.133254) (xy 118.129304 -48.09744) (xy 118.039642 -48.187102)
			(xy 118.075456 -48.22317) (xy 118.21922 -48.3489)
		)
		(stroke
			(width 0)
			(type solid)
		)
		(fill yes)
		(layer "F.Cu")
		(net "M_H_DQ<52>")
	)
	(gr_poly
		(pts
			(xy 118.296436 -111.510826) (xy 118.33225 -111.474758) (xy 118.242588 -111.385096) (xy 118.20652 -111.42091)
			(xy 118.08079 -111.564674) (xy 118.152672 -111.636556)
		)
		(stroke
			(width 0)
			(type solid)
		)
		(fill yes)
		(layer "F.Cu")
		(net "M_L_DQS_DN<5>")
	)
	(gr_poly
		(pts
			(xy 118.301516 -42.764456) (xy 118.250716 -42.764456) (xy 118.060216 -42.777156) (xy 118.060216 -42.878756)
			(xy 118.250716 -42.891456) (xy 118.301516 -42.891456)
		)
		(stroke
			(width 0)
			(type solid)
		)
		(fill yes)
		(layer "F.Cu")
		(net "M_H_DQS_DN<14>")
	)
	(gr_poly
		(pts
			(xy 118.301516 -42.104056) (xy 118.250716 -42.104056) (xy 118.060216 -42.116756) (xy 118.060216 -42.218356)
			(xy 118.250716 -42.231056) (xy 118.301516 -42.231056)
		)
		(stroke
			(width 0)
			(type solid)
		)
		(fill yes)
		(layer "F.Cu")
		(net "M_H_DQS_DN<14>")
	)
	(gr_poly
		(pts
			(xy 118.301516 -41.443656) (xy 118.250716 -41.443656) (xy 118.060216 -41.456356) (xy 118.060216 -41.557956)
			(xy 118.250716 -41.570656) (xy 118.301516 -41.570656)
		)
		(stroke
			(width 0)
			(type solid)
		)
		(fill yes)
		(layer "F.Cu")
		(net "M_H_DQS_DN<14>")
	)
	(gr_poly
		(pts
			(xy 118.311422 -45.797724) (xy 118.275354 -45.76191) (xy 118.131844 -45.63618) (xy 118.059962 -45.708062)
			(xy 118.185692 -45.851572) (xy 118.221506 -45.88764)
		)
		(stroke
			(width 0)
			(type solid)
		)
		(fill yes)
		(layer "F.Cu")
		(net "M_H_DQ<42>")
	)
	(gr_poly
		(pts
			(xy 118.314978 -109.157262) (xy 118.440708 -109.013498) (xy 118.368826 -108.94187) (xy 118.225062 -109.0676)
			(xy 118.189248 -109.103414) (xy 118.279164 -109.19333)
		)
		(stroke
			(width 0)
			(type solid)
		)
		(fill yes)
		(layer "F.Cu")
		(net "M_L_DQ<42>")
	)
	(gr_poly
		(pts
			(xy 118.323106 -111.951008) (xy 118.448836 -111.807244) (xy 118.376954 -111.735616) (xy 118.23319 -111.861346)
			(xy 118.197376 -111.89716) (xy 118.287038 -111.986822)
		)
		(stroke
			(width 0)
			(type solid)
		)
		(fill yes)
		(layer "F.Cu")
		(net "M_L_DQS_DN<14>")
	)
	(gr_poly
		(pts
			(xy 118.324122 -51.111912) (xy 118.324122 -50.890932) (xy 118.153942 -50.802032) (xy 118.109492 -50.802032)
			(xy 118.109492 -51.200812) (xy 118.153942 -51.200812)
		)
		(stroke
			(width 0)
			(type solid)
		)
		(fill yes)
		(layer "F.Cu")
		(net "M_H_DQ<49>")
	)
	(gr_poly
		(pts
			(xy 118.324122 -50.121312) (xy 118.324122 -49.900332) (xy 118.153942 -49.811432) (xy 118.109492 -49.811432)
			(xy 118.109492 -50.210212) (xy 118.153942 -50.210212)
		)
		(stroke
			(width 0)
			(type solid)
		)
		(fill yes)
		(layer "F.Cu")
		(net "M_H_DQ<49>")
	)
	(gr_poly
		(pts
			(xy 118.337838 -44.441364) (xy 118.212108 -44.2976) (xy 118.176294 -44.261786) (xy 118.086378 -44.351702)
			(xy 118.122446 -44.387516) (xy 118.26621 -44.513246)
		)
		(stroke
			(width 0)
			(type solid)
		)
		(fill yes)
		(layer "F.Cu")
		(net "M_H_DQS_DP<5>")
	)
	(gr_poly
		(pts
			(xy 118.36273 -47.864014) (xy 118.326916 -47.827946) (xy 118.183152 -47.702216) (xy 118.11127 -47.774098)
			(xy 118.237 -47.917862) (xy 118.273068 -47.953676)
		)
		(stroke
			(width 0)
			(type solid)
		)
		(fill yes)
		(layer "F.Cu")
		(net "M_H_DQ<52>")
	)
	(gr_poly
		(pts
			(xy 118.381018 -49.300892) (xy 118.255288 -49.157382) (xy 118.219474 -49.121314) (xy 118.129558 -49.21123)
			(xy 118.165372 -49.247044) (xy 118.309136 -49.372774)
		)
		(stroke
			(width 0)
			(type solid)
		)
		(fill yes)
		(layer "F.Cu")
		(net "M_H_DQ<48>")
	)
	(gr_poly
		(pts
			(xy 118.386606 -110.486698) (xy 118.42242 -110.45063) (xy 118.332758 -110.360968) (xy 118.29669 -110.396782)
			(xy 118.17096 -110.540546) (xy 118.242842 -110.612428)
		)
		(stroke
			(width 0)
			(type solid)
		)
		(fill yes)
		(layer "F.Cu")
		(net "M_L_DQ<46>")
	)
	(gr_poly
		(pts
			(xy 118.40972 -44.02836) (xy 118.373906 -43.992292) (xy 118.230142 -43.866562) (xy 118.15826 -43.938444)
			(xy 118.28399 -44.082208) (xy 118.320058 -44.118022)
		)
		(stroke
			(width 0)
			(type solid)
		)
		(fill yes)
		(layer "F.Cu")
		(net "M_H_DQS_DP<5>")
	)
	(gr_poly
		(pts
			(xy 118.413276 -110.92688) (xy 118.539006 -110.783116) (xy 118.467124 -110.711488) (xy 118.32336 -110.837218)
			(xy 118.287546 -110.873032) (xy 118.377462 -110.962948)
		)
		(stroke
			(width 0)
			(type solid)
		)
		(fill yes)
		(layer "F.Cu")
		(net "M_L_DQS_DP<5>")
	)
	(gr_poly
		(pts
			(xy 118.428008 -45.465492) (xy 118.302278 -45.321728) (xy 118.266464 -45.28566) (xy 118.176548 -45.375576)
			(xy 118.212362 -45.41139) (xy 118.356126 -45.53712)
		)
		(stroke
			(width 0)
			(type solid)
		)
		(fill yes)
		(layer "F.Cu")
		(net "M_H_DQ<47>")
	)
	(gr_poly
		(pts
			(xy 118.4529 -48.887888) (xy 118.416832 -48.852074) (xy 118.273322 -48.726344) (xy 118.20144 -48.798226)
			(xy 118.32717 -48.941736) (xy 118.362984 -48.977804)
		)
		(stroke
			(width 0)
			(type solid)
		)
		(fill yes)
		(layer "F.Cu")
		(net "M_H_DQ<48>")
	)
	(gr_poly
		(pts
			(xy 118.463568 -104.639872) (xy 118.412768 -104.639872) (xy 118.219728 -104.728772) (xy 118.219728 -104.957372)
			(xy 118.412768 -105.046272) (xy 118.463568 -105.046272)
		)
		(stroke
			(width 0)
			(type solid)
		)
		(fill yes)
		(layer "F.Cu")
		(net "M_L_DQ<52>")
	)
	(gr_poly
		(pts
			(xy 118.476522 -109.46257) (xy 118.51259 -109.426756) (xy 118.422674 -109.33684) (xy 118.38686 -109.372908)
			(xy 118.26113 -109.516418) (xy 118.333012 -109.5883)
		)
		(stroke
			(width 0)
			(type solid)
		)
		(fill yes)
		(layer "F.Cu")
		(net "M_L_DQ<42>")
	)
	(gr_poly
		(pts
			(xy 118.48465 -112.256316) (xy 118.520718 -112.220502) (xy 118.430802 -112.130586) (xy 118.394988 -112.166654)
			(xy 118.269258 -112.310164) (xy 118.34114 -112.382046)
		)
		(stroke
			(width 0)
			(type solid)
		)
		(fill yes)
		(layer "F.Cu")
		(net "M_L_DQS_DN<14>")
	)
	(gr_poly
		(pts
			(xy 118.49989 -45.052234) (xy 118.463822 -45.01642) (xy 118.320312 -44.89069) (xy 118.24843 -44.962572)
			(xy 118.37416 -45.106082) (xy 118.409974 -45.14215)
		)
		(stroke
			(width 0)
			(type solid)
		)
		(fill yes)
		(layer "F.Cu")
		(net "M_H_DQ<47>")
	)
	(gr_poly
		(pts
			(xy 118.503446 -109.902752) (xy 118.629176 -109.758988) (xy 118.557294 -109.68736) (xy 118.41353 -109.81309)
			(xy 118.377716 -109.848904) (xy 118.467632 -109.93882)
		)
		(stroke
			(width 0)
			(type solid)
		)
		(fill yes)
		(layer "F.Cu")
		(net "M_L_DQ<47>")
	)
	(gr_poly
		(pts
			(xy 118.511574 -112.696498) (xy 118.637304 -112.552734) (xy 118.565422 -112.481106) (xy 118.421658 -112.606582)
			(xy 118.385844 -112.64265) (xy 118.475506 -112.732312)
		)
		(stroke
			(width 0)
			(type solid)
		)
		(fill yes)
		(layer "F.Cu")
		(net "M_L_DQS_DP<14>")
	)
	(gr_poly
		(pts
			(xy 118.517924 -46.489366) (xy 118.392194 -46.345602) (xy 118.35638 -46.309788) (xy 118.266718 -46.39945)
			(xy 118.302532 -46.435518) (xy 118.446296 -46.561248)
		)
		(stroke
			(width 0)
			(type solid)
		)
		(fill yes)
		(layer "F.Cu")
		(net "M_H_DQ<43>")
	)
	(gr_poly
		(pts
			(xy 118.526306 -43.695874) (xy 118.400576 -43.55211) (xy 118.364762 -43.516296) (xy 118.274846 -43.606212)
			(xy 118.310914 -43.642026) (xy 118.454678 -43.767756)
		)
		(stroke
			(width 0)
			(type solid)
		)
		(fill yes)
		(layer "F.Cu")
		(net "M_H_DQS_DN<5>")
	)
	(gr_poly
		(pts
			(xy 118.542816 -42.548556) (xy 118.542816 -42.446956) (xy 118.352316 -42.434256) (xy 118.301516 -42.434256)
			(xy 118.301516 -42.561256) (xy 118.352316 -42.561256)
		)
		(stroke
			(width 0)
			(type solid)
		)
		(fill yes)
		(layer "F.Cu")
		(net "M_H_DQS_DN<14>")
	)
	(gr_poly
		(pts
			(xy 118.542816 -41.888156) (xy 118.542816 -41.786556) (xy 118.352316 -41.773856) (xy 118.301516 -41.773856)
			(xy 118.301516 -41.900856) (xy 118.352316 -41.900856)
		)
		(stroke
			(width 0)
			(type solid)
		)
		(fill yes)
		(layer "F.Cu")
		(net "M_H_DQS_DN<14>")
	)
	(gr_poly
		(pts
			(xy 118.569486 -48.555656) (xy 118.443756 -48.411892) (xy 118.407942 -48.375824) (xy 118.318026 -48.46574)
			(xy 118.35384 -48.501554) (xy 118.497604 -48.627284)
		)
		(stroke
			(width 0)
			(type solid)
		)
		(fill yes)
		(layer "F.Cu")
		(net "M_H_DQ<53>")
	)
	(gr_poly
		(pts
			(xy 118.57482 -111.232188) (xy 118.610888 -111.196374) (xy 118.520972 -111.106458) (xy 118.485158 -111.142526)
			(xy 118.359428 -111.286036) (xy 118.43131 -111.357918)
		)
		(stroke
			(width 0)
			(type solid)
		)
		(fill yes)
		(layer "F.Cu")
		(net "M_L_DQS_DP<5>")
	)
	(gr_poly
		(pts
			(xy 118.589806 -46.076362) (xy 118.553992 -46.040294) (xy 118.410228 -45.914564) (xy 118.338346 -45.986446)
			(xy 118.464076 -46.13021) (xy 118.500144 -46.166024)
		)
		(stroke
			(width 0)
			(type solid)
		)
		(fill yes)
		(layer "F.Cu")
		(net "M_H_DQ<43>")
	)
	(gr_poly
		(pts
			(xy 118.593362 -108.878878) (xy 118.719092 -108.735114) (xy 118.647464 -108.663232) (xy 118.5037 -108.788962)
			(xy 118.467886 -108.82503) (xy 118.557548 -108.914692)
		)
		(stroke
			(width 0)
			(type solid)
		)
		(fill yes)
		(layer "F.Cu")
		(net "M_L_DQ<43>")
	)
	(gr_poly
		(pts
			(xy 118.598188 -43.28287) (xy 118.562374 -43.246802) (xy 118.41861 -43.121072) (xy 118.346728 -43.192954)
			(xy 118.472458 -43.336718) (xy 118.508526 -43.372532)
		)
		(stroke
			(width 0)
			(type solid)
		)
		(fill yes)
		(layer "F.Cu")
		(net "M_H_DQS_DN<5>")
	)
	(gr_poly
		(pts
			(xy 118.601744 -111.67237) (xy 118.727474 -111.528606) (xy 118.655592 -111.456978) (xy 118.511828 -111.582708)
			(xy 118.476014 -111.618522) (xy 118.565676 -111.708184)
		)
		(stroke
			(width 0)
			(type solid)
		)
		(fill yes)
		(layer "F.Cu")
		(net "M_L_DQS_DN<5>")
	)
	(gr_poly
		(pts
			(xy 118.616476 -44.720002) (xy 118.490746 -44.576238) (xy 118.454932 -44.54017) (xy 118.365016 -44.630086)
			(xy 118.40083 -44.6659) (xy 118.544594 -44.79163)
		)
		(stroke
			(width 0)
			(type solid)
		)
		(fill yes)
		(layer "F.Cu")
		(net "M_H_DQ<46>")
	)
	(gr_poly
		(pts
			(xy 118.641368 -48.142398) (xy 118.6053 -48.106584) (xy 118.46179 -47.980854) (xy 118.389908 -48.052736)
			(xy 118.515638 -48.196246) (xy 118.551452 -48.232314)
		)
		(stroke
			(width 0)
			(type solid)
		)
		(fill yes)
		(layer "F.Cu")
		(net "M_H_DQ<53>")
	)
	(gr_poly
		(pts
			(xy 118.66499 -110.20806) (xy 118.701058 -110.172246) (xy 118.611142 -110.08233) (xy 118.575328 -110.118398)
			(xy 118.449598 -110.261908) (xy 118.52148 -110.33379)
		)
		(stroke
			(width 0)
			(type solid)
		)
		(fill yes)
		(layer "F.Cu")
		(net "M_L_DQ<47>")
	)
	(gr_poly
		(pts
			(xy 118.688358 -44.306744) (xy 118.65229 -44.27093) (xy 118.50878 -44.1452) (xy 118.436898 -44.217082)
			(xy 118.562628 -44.360592) (xy 118.598442 -44.39666)
		)
		(stroke
			(width 0)
			(type solid)
		)
		(fill yes)
		(layer "F.Cu")
		(net "M_H_DQ<46>")
	)
	(gr_poly
		(pts
			(xy 118.691914 -110.648242) (xy 118.817644 -110.504478) (xy 118.745762 -110.43285) (xy 118.601998 -110.55858)
			(xy 118.566184 -110.594394) (xy 118.6561 -110.68431)
		)
		(stroke
			(width 0)
			(type solid)
		)
		(fill yes)
		(layer "F.Cu")
		(net "M_L_DQ<46>")
	)
	(gr_poly
		(pts
			(xy 118.706392 -45.743876) (xy 118.580662 -45.600112) (xy 118.544848 -45.564298) (xy 118.454932 -45.654214)
			(xy 118.491 -45.690028) (xy 118.634764 -45.815758)
		)
		(stroke
			(width 0)
			(type solid)
		)
		(fill yes)
		(layer "F.Cu")
		(net "M_H_DQ<42>")
	)
	(gr_poly
		(pts
			(xy 118.731284 -49.166526) (xy 118.69547 -49.130458) (xy 118.551706 -49.004728) (xy 118.479824 -49.07661)
			(xy 118.605554 -49.220374) (xy 118.641622 -49.256188)
		)
		(stroke
			(width 0)
			(type solid)
		)
		(fill yes)
		(layer "F.Cu")
		(net "M_H_DQ<49>")
	)
	(gr_poly
		(pts
			(xy 118.75516 -109.184186) (xy 118.790974 -109.148118) (xy 118.701312 -109.058456) (xy 118.665244 -109.09427)
			(xy 118.539514 -109.238034) (xy 118.611396 -109.309916)
		)
		(stroke
			(width 0)
			(type solid)
		)
		(fill yes)
		(layer "F.Cu")
		(net "M_L_DQ<43>")
	)
	(gr_poly
		(pts
			(xy 118.757954 -47.810166) (xy 118.632224 -47.666402) (xy 118.59641 -47.630334) (xy 118.506494 -47.72025)
			(xy 118.542308 -47.756064) (xy 118.686072 -47.881794)
		)
		(stroke
			(width 0)
			(type solid)
		)
		(fill yes)
		(layer "F.Cu")
		(net "M_H_DQ<52>")
	)
	(gr_poly
		(pts
			(xy 118.763288 -111.977678) (xy 118.799356 -111.941864) (xy 118.70944 -111.851948) (xy 118.673626 -111.888016)
			(xy 118.547896 -112.031526) (xy 118.619778 -112.103408)
		)
		(stroke
			(width 0)
			(type solid)
		)
		(fill yes)
		(layer "F.Cu")
		(net "M_L_DQS_DN<5>")
	)
	(gr_poly
		(pts
			(xy 118.778274 -45.330872) (xy 118.74246 -45.294804) (xy 118.598696 -45.169074) (xy 118.526814 -45.240956)
			(xy 118.652544 -45.38472) (xy 118.688612 -45.420534)
		)
		(stroke
			(width 0)
			(type solid)
		)
		(fill yes)
		(layer "F.Cu")
		(net "M_H_DQ<42>")
	)
	(gr_poly
		(pts
			(xy 118.78183 -109.624368) (xy 118.90756 -109.480604) (xy 118.835932 -109.408722) (xy 118.692168 -109.534452)
			(xy 118.6561 -109.570266) (xy 118.746016 -109.660182)
		)
		(stroke
			(width 0)
			(type solid)
		)
		(fill yes)
		(layer "F.Cu")
		(net "M_L_DQ<42>")
	)
	(gr_poly
		(pts
			(xy 118.789958 -112.418114) (xy 118.915688 -112.27435) (xy 118.84406 -112.202468) (xy 118.700296 -112.328198)
			(xy 118.664228 -112.364012) (xy 118.754144 -112.453928)
		)
		(stroke
			(width 0)
			(type solid)
		)
		(fill yes)
		(layer "F.Cu")
		(net "M_L_DQS_DN<14>")
	)
	(gr_poly
		(pts
			(xy 118.804944 -43.974512) (xy 118.679214 -43.830748) (xy 118.643146 -43.794934) (xy 118.553484 -43.884596)
			(xy 118.589298 -43.92041) (xy 118.733062 -44.04614)
		)
		(stroke
			(width 0)
			(type solid)
		)
		(fill yes)
		(layer "F.Cu")
		(net "M_H_DQS_DP<5>")
	)
	(gr_poly
		(pts
			(xy 118.829836 -47.396908) (xy 118.793768 -47.361094) (xy 118.650258 -47.235364) (xy 118.578376 -47.307246)
			(xy 118.704106 -47.450756) (xy 118.73992 -47.486824)
		)
		(stroke
			(width 0)
			(type solid)
		)
		(fill yes)
		(layer "F.Cu")
		(net "M_H_DQ<52>")
	)
	(gr_poly
		(pts
			(xy 118.848124 -48.83404) (xy 118.722394 -48.690276) (xy 118.686326 -48.654462) (xy 118.596664 -48.744124)
			(xy 118.632478 -48.780192) (xy 118.776242 -48.905922)
		)
		(stroke
			(width 0)
			(type solid)
		)
		(fill yes)
		(layer "F.Cu")
		(net "M_H_DQ<48>")
	)
	(gr_poly
		(pts
			(xy 118.853458 -110.95355) (xy 118.889526 -110.917736) (xy 118.79961 -110.82782) (xy 118.763796 -110.863888)
			(xy 118.638066 -111.007398) (xy 118.709948 -111.07928)
		)
		(stroke
			(width 0)
			(type solid)
		)
		(fill yes)
		(layer "F.Cu")
		(net "M_L_DQ<46>")
	)
	(gr_poly
		(pts
			(xy 118.876826 -43.561254) (xy 118.840758 -43.52544) (xy 118.697248 -43.39971) (xy 118.625366 -43.471592)
			(xy 118.751096 -43.615102) (xy 118.78691 -43.65117)
		)
		(stroke
			(width 0)
			(type solid)
		)
		(fill yes)
		(layer "F.Cu")
		(net "M_H_DQS_DP<5>")
	)
	(gr_poly
		(pts
			(xy 118.880128 -111.393986) (xy 119.005858 -111.250222) (xy 118.93423 -111.17834) (xy 118.790466 -111.30407)
			(xy 118.754398 -111.339884) (xy 118.844314 -111.4298)
		)
		(stroke
			(width 0)
			(type solid)
		)
		(fill yes)
		(layer "F.Cu")
		(net "M_L_DQS_DP<5>")
	)
	(gr_poly
		(pts
			(xy 118.89486 -44.998386) (xy 118.76913 -44.854622) (xy 118.733316 -44.818808) (xy 118.6434 -44.908724)
			(xy 118.679468 -44.944538) (xy 118.823232 -45.070268)
		)
		(stroke
			(width 0)
			(type solid)
		)
		(fill yes)
		(layer "F.Cu")
		(net "M_H_DQ<47>")
	)
	(gr_poly
		(pts
			(xy 118.895114 -106.196384) (xy 119.020844 -106.05262) (xy 118.948962 -105.980992) (xy 118.805198 -106.106722)
			(xy 118.769384 -106.142536) (xy 118.8593 -106.232452)
		)
		(stroke
			(width 0)
			(type solid)
		)
		(fill yes)
		(layer "F.Cu")
		(net "M_L_DQ<52>")
	)
	(gr_poly
		(pts
			(xy 118.897908 -104.957372) (xy 118.897908 -104.728772) (xy 118.704868 -104.639872) (xy 118.654068 -104.639872)
			(xy 118.654068 -105.046272) (xy 118.704868 -105.046272)
		)
		(stroke
			(width 0)
			(type solid)
		)
		(fill yes)
		(layer "F.Cu")
		(net "M_L_DQ<53>")
	)
	(gr_poly
		(pts
			(xy 118.919752 -48.421036) (xy 118.883938 -48.384968) (xy 118.740174 -48.259238) (xy 118.668292 -48.33112)
			(xy 118.794022 -48.474884) (xy 118.83009 -48.510698)
		)
		(stroke
			(width 0)
			(type solid)
		)
		(fill yes)
		(layer "F.Cu")
		(net "M_H_DQ<48>")
	)
	(gr_poly
		(pts
			(xy 118.943628 -109.929676) (xy 118.979442 -109.893608) (xy 118.88978 -109.803946) (xy 118.853712 -109.83976)
			(xy 118.727982 -109.983524) (xy 118.799864 -110.055406)
		)
		(stroke
			(width 0)
			(type solid)
		)
		(fill yes)
		(layer "F.Cu")
		(net "M_L_DQ<42>")
	)
	(gr_poly
		(pts
			(xy 118.951756 -112.723422) (xy 118.98757 -112.687354) (xy 118.897908 -112.597692) (xy 118.86184 -112.633506)
			(xy 118.73611 -112.77727) (xy 118.807992 -112.849152)
		)
		(stroke
			(width 0)
			(type solid)
		)
		(fill yes)
		(layer "F.Cu")
		(net "M_L_DQS_DN<14>")
	)
	(gr_poly
		(pts
			(xy 118.966742 -44.585382) (xy 118.930928 -44.549314) (xy 118.787164 -44.423584) (xy 118.715282 -44.495466)
			(xy 118.841012 -44.63923) (xy 118.87708 -44.675044)
		)
		(stroke
			(width 0)
			(type solid)
		)
		(fill yes)
		(layer "F.Cu")
		(net "M_H_DQ<47>")
	)
	(gr_poly
		(pts
			(xy 118.970298 -110.369858) (xy 119.096028 -110.226094) (xy 119.0244 -110.154212) (xy 118.880636 -110.279942)
			(xy 118.844568 -110.315756) (xy 118.934484 -110.405672)
		)
		(stroke
			(width 0)
			(type solid)
		)
		(fill yes)
		(layer "F.Cu")
		(net "M_L_DQ<47>")
	)
	(gr_poly
		(pts
			(xy 118.978426 -113.163604) (xy 119.104156 -113.01984) (xy 119.032528 -112.947958) (xy 118.888764 -113.073688)
			(xy 118.852696 -113.109502) (xy 118.942612 -113.199418)
		)
		(stroke
			(width 0)
			(type solid)
		)
		(fill yes)
		(layer "F.Cu")
		(net "M_L_DQS_DP<14>")
	)
	(gr_poly
		(pts
			(xy 118.98503 -46.022514) (xy 118.8593 -45.87875) (xy 118.823486 -45.842682) (xy 118.73357 -45.932598)
			(xy 118.769384 -45.968412) (xy 118.913148 -46.094142)
		)
		(stroke
			(width 0)
			(type solid)
		)
		(fill yes)
		(layer "F.Cu")
		(net "M_H_DQ<43>")
	)
	(gr_poly
		(pts
			(xy 118.993412 -43.229022) (xy 118.867682 -43.085258) (xy 118.831614 -43.049444) (xy 118.741952 -43.139106)
			(xy 118.777766 -43.175174) (xy 118.92153 -43.30065)
		)
		(stroke
			(width 0)
			(type solid)
		)
		(fill yes)
		(layer "F.Cu")
		(net "M_H_DQS_DN<5>")
	)
	(gr_poly
		(pts
			(xy 119.000016 -42.104056) (xy 118.949216 -42.104056) (xy 118.758716 -42.116756) (xy 118.758716 -42.218356)
			(xy 118.949216 -42.231056) (xy 119.000016 -42.231056)
		)
		(stroke
			(width 0)
			(type solid)
		)
		(fill yes)
		(layer "F.Cu")
		(net "M_H_DQS_DN<5>")
	)
	(gr_poly
		(pts
			(xy 119.036338 -48.08855) (xy 118.910862 -47.944786) (xy 118.874794 -47.908972) (xy 118.785132 -47.998634)
			(xy 118.820946 -48.034702) (xy 118.96471 -48.160432)
		)
		(stroke
			(width 0)
			(type solid)
		)
		(fill yes)
		(layer "F.Cu")
		(net "M_H_DQ<53>")
	)
	(gr_poly
		(pts
			(xy 119.038624 -100.533454) (xy 119.016272 -100.494846) (xy 118.85422 -100.391976) (xy 118.662958 -100.502466)
			(xy 118.671086 -100.694236) (xy 118.693184 -100.73259)
		)
		(stroke
			(width 0)
			(type solid)
		)
		(fill yes)
		(layer "F.Cu")
		(net "M_L_DQ<52>")
	)
	(gr_poly
		(pts
			(xy 119.041926 -111.699294) (xy 119.07774 -111.663226) (xy 118.988078 -111.573564) (xy 118.95201 -111.609378)
			(xy 118.82628 -111.753142) (xy 118.898162 -111.825024)
		)
		(stroke
			(width 0)
			(type solid)
		)
		(fill yes)
		(layer "F.Cu")
		(net "M_L_DQS_DP<5>")
	)
	(gr_poly
		(pts
			(xy 119.056658 -106.501692) (xy 119.092726 -106.465878) (xy 119.00281 -106.375962) (xy 118.966996 -106.41203)
			(xy 118.841266 -106.55554) (xy 118.913148 -106.627422)
		)
		(stroke
			(width 0)
			(type solid)
		)
		(fill yes)
		(layer "F.Cu")
		(net "M_L_DQ<52>")
	)
	(gr_poly
		(pts
			(xy 119.056912 -45.609256) (xy 119.020844 -45.573442) (xy 118.877334 -45.447712) (xy 118.805452 -45.519594)
			(xy 118.931182 -45.663104) (xy 118.966996 -45.699172)
		)
		(stroke
			(width 0)
			(type solid)
		)
		(fill yes)
		(layer "F.Cu")
		(net "M_H_DQ<43>")
	)
	(gr_poly
		(pts
			(xy 119.060468 -109.34573) (xy 119.186198 -109.201966) (xy 119.114316 -109.130338) (xy 118.970552 -109.256068)
			(xy 118.934738 -109.291882) (xy 119.024654 -109.381798)
		)
		(stroke
			(width 0)
			(type solid)
		)
		(fill yes)
		(layer "F.Cu")
		(net "M_L_DQ<43>")
	)
	(gr_poly
		(pts
			(xy 119.068596 -112.139476) (xy 119.194326 -111.995712) (xy 119.122698 -111.92383) (xy 118.978934 -112.04956)
			(xy 118.942866 -112.085374) (xy 119.032782 -112.17529)
		)
		(stroke
			(width 0)
			(type solid)
		)
		(fill yes)
		(layer "F.Cu")
		(net "M_L_DQS_DN<5>")
	)
	(gr_poly
		(pts
			(xy 119.083328 -44.252896) (xy 118.957598 -44.109132) (xy 118.921784 -44.073318) (xy 118.831868 -44.163234)
			(xy 118.867936 -44.199048) (xy 119.0117 -44.324778)
		)
		(stroke
			(width 0)
			(type solid)
		)
		(fill yes)
		(layer "F.Cu")
		(net "M_H_DQ<46>")
	)
	(gr_poly
		(pts
			(xy 119.10822 -47.675546) (xy 119.072406 -47.639478) (xy 118.928642 -47.513748) (xy 118.85676 -47.58563)
			(xy 118.98249 -47.729394) (xy 119.018558 -47.765208)
		)
		(stroke
			(width 0)
			(type solid)
		)
		(fill yes)
		(layer "F.Cu")
		(net "M_H_DQ<53>")
	)
	(gr_poly
		(pts
			(xy 119.132096 -110.675166) (xy 119.16791 -110.639098) (xy 119.078248 -110.549436) (xy 119.04218 -110.58525)
			(xy 118.91645 -110.729014) (xy 118.988332 -110.800896)
		)
		(stroke
			(width 0)
			(type solid)
		)
		(fill yes)
		(layer "F.Cu")
		(net "M_L_DQ<47>")
	)
	(gr_poly
		(pts
			(xy 119.15521 -43.839892) (xy 119.119396 -43.803824) (xy 118.975632 -43.678094) (xy 118.90375 -43.749976)
			(xy 119.02948 -43.89374) (xy 119.065548 -43.929554)
		)
		(stroke
			(width 0)
			(type solid)
		)
		(fill yes)
		(layer "F.Cu")
		(net "M_H_DQ<46>")
	)
	(gr_poly
		(pts
			(xy 119.158766 -111.115348) (xy 119.284496 -110.971584) (xy 119.212868 -110.899702) (xy 119.069104 -111.025432)
			(xy 119.033036 -111.061246) (xy 119.122952 -111.151162)
		)
		(stroke
			(width 0)
			(type solid)
		)
		(fill yes)
		(layer "F.Cu")
		(net "M_L_DQ<46>")
	)
	(gr_poly
		(pts
			(xy 119.173498 -45.277024) (xy 119.047768 -45.13326) (xy 119.011954 -45.097192) (xy 118.922038 -45.187108)
			(xy 118.957852 -45.222922) (xy 119.101616 -45.348652)
		)
		(stroke
			(width 0)
			(type solid)
		)
		(fill yes)
		(layer "F.Cu")
		(net "M_H_DQ<42>")
	)
	(gr_poly
		(pts
			(xy 119.19839 -48.69942) (xy 119.162322 -48.663606) (xy 119.018812 -48.537876) (xy 118.94693 -48.609758)
			(xy 119.07266 -48.753268) (xy 119.108474 -48.789336)
		)
		(stroke
			(width 0)
			(type solid)
		)
		(fill yes)
		(layer "F.Cu")
		(net "M_H_DQ<49>")
	)
	(gr_poly
		(pts
			(xy 119.222012 -109.651038) (xy 119.25808 -109.615224) (xy 119.168164 -109.525308) (xy 119.13235 -109.561376)
			(xy 119.00662 -109.704886) (xy 119.078502 -109.776768)
		)
		(stroke
			(width 0)
			(type solid)
		)
		(fill yes)
		(layer "F.Cu")
		(net "M_L_DQ<43>")
	)
	(gr_poly
		(pts
			(xy 119.224806 -47.34306) (xy 119.099076 -47.199296) (xy 119.063262 -47.163482) (xy 118.9736 -47.253144)
			(xy 119.009414 -47.289212) (xy 119.153178 -47.414942)
		)
		(stroke
			(width 0)
			(type solid)
		)
		(fill yes)
		(layer "F.Cu")
		(net "M_H_DQ<52>")
	)
	(gr_poly
		(pts
			(xy 119.230394 -112.444784) (xy 119.266208 -112.408716) (xy 119.176546 -112.319054) (xy 119.140478 -112.354868)
			(xy 119.014748 -112.498632) (xy 119.08663 -112.570514)
		)
		(stroke
			(width 0)
			(type solid)
		)
		(fill yes)
		(layer "F.Cu")
		(net "M_L_DQS_DN<5>")
	)
	(gr_poly
		(pts
			(xy 119.241316 -42.548556) (xy 119.241316 -42.446956) (xy 119.050816 -42.434256) (xy 119.000016 -42.434256)
			(xy 119.000016 -42.561256) (xy 119.050816 -42.561256)
		)
		(stroke
			(width 0)
			(type solid)
		)
		(fill yes)
		(layer "F.Cu")
		(net "M_H_DQS_DN<5>")
	)
	(gr_poly
		(pts
			(xy 119.241316 -41.888156) (xy 119.241316 -41.786556) (xy 119.050816 -41.773856) (xy 119.000016 -41.773856)
			(xy 119.000016 -41.900856) (xy 119.050816 -41.900856)
		)
		(stroke
			(width 0)
			(type solid)
		)
		(fill yes)
		(layer "F.Cu")
		(net "M_H_DQS_DN<5>")
	)
	(gr_poly
		(pts
			(xy 119.24538 -44.863766) (xy 119.209312 -44.827952) (xy 119.065802 -44.702222) (xy 118.99392 -44.774104)
			(xy 119.11965 -44.917614) (xy 119.155464 -44.953682)
		)
		(stroke
			(width 0)
			(type solid)
		)
		(fill yes)
		(layer "F.Cu")
		(net "M_H_DQ<42>")
	)
	(gr_poly
		(pts
			(xy 119.245634 -49.343056) (xy 119.214138 -49.31156) (xy 119.031004 -49.254156) (xy 118.874794 -49.410366)
			(xy 118.932198 -49.5935) (xy 118.963694 -49.624996)
		)
		(stroke
			(width 0)
			(type solid)
		)
		(fill yes)
		(layer "F.Cu")
		(net "M_H_DQS_DP<15>")
	)
	(gr_poly
		(pts
			(xy 119.248936 -110.09122) (xy 119.374666 -109.947456) (xy 119.302784 -109.875828) (xy 119.15902 -110.001558)
			(xy 119.123206 -110.037372) (xy 119.213122 -110.127288)
		)
		(stroke
			(width 0)
			(type solid)
		)
		(fill yes)
		(layer "F.Cu")
		(net "M_L_DQ<42>")
	)
	(gr_poly
		(pts
			(xy 119.257064 -112.884966) (xy 119.382794 -112.741202) (xy 119.310912 -112.66932) (xy 119.167148 -112.79505)
			(xy 119.131334 -112.831118) (xy 119.220996 -112.92078)
		)
		(stroke
			(width 0)
			(type solid)
		)
		(fill yes)
		(layer "F.Cu")
		(net "M_L_DQS_DN<14>")
	)
	(gr_poly
		(pts
			(xy 119.271796 -43.507406) (xy 119.146066 -43.363642) (xy 119.110252 -43.327828) (xy 119.020336 -43.417744)
			(xy 119.056404 -43.453558) (xy 119.200168 -43.579288)
		)
		(stroke
			(width 0)
			(type solid)
		)
		(fill yes)
		(layer "F.Cu")
		(net "M_H_DQS_DP<5>")
	)
	(gr_poly
		(pts
			(xy 119.276368 -104.400096) (xy 119.225568 -104.400096) (xy 119.032528 -104.488996) (xy 119.032528 -104.717596)
			(xy 119.225568 -104.806496) (xy 119.276368 -104.806496)
		)
		(stroke
			(width 0)
			(type solid)
		)
		(fill yes)
		(layer "F.Cu")
		(net "M_L_DQ<48>")
	)
	(gr_poly
		(pts
			(xy 119.296688 -46.930056) (xy 119.260874 -46.893988) (xy 119.11711 -46.768258) (xy 119.045228 -46.84014)
			(xy 119.170958 -46.983904) (xy 119.207026 -47.019718)
		)
		(stroke
			(width 0)
			(type solid)
		)
		(fill yes)
		(layer "F.Cu")
		(net "M_H_DQ<52>")
	)
	(gr_poly
		(pts
			(xy 119.314976 -48.367188) (xy 119.189246 -48.223424) (xy 119.153432 -48.187356) (xy 119.063516 -48.277272)
			(xy 119.09933 -48.313086) (xy 119.243094 -48.438816)
		)
		(stroke
			(width 0)
			(type solid)
		)
		(fill yes)
		(layer "F.Cu")
		(net "M_H_DQ<48>")
	)
	(gr_poly
		(pts
			(xy 119.320564 -111.420656) (xy 119.356378 -111.384588) (xy 119.266716 -111.294926) (xy 119.230648 -111.33074)
			(xy 119.104918 -111.474504) (xy 119.1768 -111.546386)
		)
		(stroke
			(width 0)
			(type solid)
		)
		(fill yes)
		(layer "F.Cu")
		(net "M_L_DQ<46>")
	)
	(gr_poly
		(pts
			(xy 119.33047 -50.41392) (xy 119.28602 -50.41392) (xy 119.11584 -50.50282) (xy 119.11584 -50.7238)
			(xy 119.28602 -50.8127) (xy 119.33047 -50.8127)
		)
		(stroke
			(width 0)
			(type solid)
		)
		(fill yes)
		(layer "F.Cu")
		(net "M_H_DQS_DN<6>")
	)
	(gr_poly
		(pts
			(xy 119.335296 -106.223308) (xy 119.37111 -106.18724) (xy 119.281448 -106.097578) (xy 119.24538 -106.133392)
			(xy 119.11965 -106.277156) (xy 119.191532 -106.349038)
		)
		(stroke
			(width 0)
			(type solid)
		)
		(fill yes)
		(layer "F.Cu")
		(net "M_L_DQ<53>")
	)
	(gr_poly
		(pts
			(xy 119.347234 -111.860838) (xy 119.472964 -111.717074) (xy 119.401082 -111.645446) (xy 119.257318 -111.770922)
			(xy 119.221504 -111.80699) (xy 119.311166 -111.896652)
		)
		(stroke
			(width 0)
			(type solid)
		)
		(fill yes)
		(layer "F.Cu")
		(net "M_L_DQS_DP<5>")
	)
	(gr_poly
		(pts
			(xy 119.361966 -106.66349) (xy 119.487696 -106.519726) (xy 119.416068 -106.447844) (xy 119.272304 -106.573574)
			(xy 119.236236 -106.609388) (xy 119.326152 -106.699304)
		)
		(stroke
			(width 0)
			(type solid)
		)
		(fill yes)
		(layer "F.Cu")
		(net "M_L_DQ<52>")
	)
	(gr_poly
		(pts
			(xy 119.361966 -44.531534) (xy 119.236236 -44.38777) (xy 119.200168 -44.351956) (xy 119.110506 -44.441618)
			(xy 119.14632 -44.477432) (xy 119.290084 -44.603162)
		)
		(stroke
			(width 0)
			(type solid)
		)
		(fill yes)
		(layer "F.Cu")
		(net "M_H_DQ<47>")
	)
	(gr_poly
		(pts
			(xy 119.386858 -47.95393) (xy 119.35079 -47.918116) (xy 119.20728 -47.792386) (xy 119.135398 -47.864268)
			(xy 119.261128 -48.007778) (xy 119.296942 -48.043846)
		)
		(stroke
			(width 0)
			(type solid)
		)
		(fill yes)
		(layer "F.Cu")
		(net "M_H_DQ<48>")
	)
	(gr_poly
		(pts
			(xy 119.393716 -42.764456) (xy 119.342916 -42.764456) (xy 119.152416 -42.777156) (xy 119.152416 -42.878756)
			(xy 119.342916 -42.891456) (xy 119.393716 -42.891456)
		)
		(stroke
			(width 0)
			(type solid)
		)
		(fill yes)
		(layer "F.Cu")
		(net "M_H_DQS_DP<5>")
	)
	(gr_poly
		(pts
			(xy 119.393716 -42.104056) (xy 119.342916 -42.104056) (xy 119.152416 -42.116756) (xy 119.152416 -42.218356)
			(xy 119.342916 -42.231056) (xy 119.393716 -42.231056)
		)
		(stroke
			(width 0)
			(type solid)
		)
		(fill yes)
		(layer "F.Cu")
		(net "M_H_DQS_DP<5>")
	)
	(gr_poly
		(pts
			(xy 119.41048 -110.396528) (xy 119.446548 -110.360714) (xy 119.356632 -110.270798) (xy 119.320818 -110.306866)
			(xy 119.195088 -110.450376) (xy 119.26697 -110.522258)
		)
		(stroke
			(width 0)
			(type solid)
		)
		(fill yes)
		(layer "F.Cu")
		(net "M_L_DQ<42>")
	)
	(gr_poly
		(pts
			(xy 119.433848 -44.118276) (xy 119.39778 -44.082462) (xy 119.25427 -43.956732) (xy 119.182388 -44.028614)
			(xy 119.308118 -44.172124) (xy 119.343932 -44.208192)
		)
		(stroke
			(width 0)
			(type solid)
		)
		(fill yes)
		(layer "F.Cu")
		(net "M_H_DQ<47>")
	)
	(gr_poly
		(pts
			(xy 119.437404 -110.83671) (xy 119.563134 -110.692946) (xy 119.491252 -110.621318) (xy 119.347488 -110.747048)
			(xy 119.311674 -110.782862) (xy 119.401336 -110.872524)
		)
		(stroke
			(width 0)
			(type solid)
		)
		(fill yes)
		(layer "F.Cu")
		(net "M_L_DQ<47>")
	)
	(gr_poly
		(pts
			(xy 119.451882 -45.555408) (xy 119.326152 -45.411644) (xy 119.290338 -45.37583) (xy 119.200422 -45.465746)
			(xy 119.23649 -45.50156) (xy 119.380254 -45.62729)
		)
		(stroke
			(width 0)
			(type solid)
		)
		(fill yes)
		(layer "F.Cu")
		(net "M_H_DQ<43>")
	)
	(gr_poly
		(pts
			(xy 119.469408 -49.692306) (xy 119.41175 -49.509172) (xy 119.380508 -49.477676) (xy 119.098314 -49.75987)
			(xy 119.12981 -49.791112) (xy 119.312944 -49.84877)
		)
		(stroke
			(width 0)
			(type solid)
		)
		(fill yes)
		(layer "F.Cu")
		(net "M_H_DQS_DN<15>")
	)
	(gr_poly
		(pts
			(xy 119.503444 -47.621698) (xy 119.377714 -47.477934) (xy 119.3419 -47.441866) (xy 119.251984 -47.531782)
			(xy 119.287798 -47.567596) (xy 119.431562 -47.693326)
		)
		(stroke
			(width 0)
			(type solid)
		)
		(fill yes)
		(layer "F.Cu")
		(net "M_H_DQ<53>")
	)
	(gr_poly
		(pts
			(xy 119.508778 -112.166146) (xy 119.544846 -112.130332) (xy 119.45493 -112.040416) (xy 119.419116 -112.076484)
			(xy 119.293386 -112.219994) (xy 119.365268 -112.291876)
		)
		(stroke
			(width 0)
			(type solid)
		)
		(fill yes)
		(layer "F.Cu")
		(net "M_L_DQS_DP<5>")
	)
	(gr_poly
		(pts
			(xy 119.523764 -106.968798) (xy 119.559578 -106.93273) (xy 119.469916 -106.843068) (xy 119.433848 -106.878882)
			(xy 119.308118 -107.022646) (xy 119.38 -107.094528)
		)
		(stroke
			(width 0)
			(type solid)
		)
		(fill yes)
		(layer "F.Cu")
		(net "M_L_DQ<52>")
	)
	(gr_poly
		(pts
			(xy 119.523764 -45.142404) (xy 119.48795 -45.106336) (xy 119.344186 -44.980606) (xy 119.272304 -45.052488)
			(xy 119.398034 -45.196252) (xy 119.434102 -45.232066)
		)
		(stroke
			(width 0)
			(type solid)
		)
		(fill yes)
		(layer "F.Cu")
		(net "M_H_DQ<43>")
	)
	(gr_poly
		(pts
			(xy 119.52732 -109.812836) (xy 119.65305 -109.669072) (xy 119.581422 -109.59719) (xy 119.437658 -109.72292)
			(xy 119.40159 -109.758734) (xy 119.491506 -109.84865)
		)
		(stroke
			(width 0)
			(type solid)
		)
		(fill yes)
		(layer "F.Cu")
		(net "M_L_DQ<43>")
	)
	(gr_poly
		(pts
			(xy 119.535702 -112.606328) (xy 119.661432 -112.462564) (xy 119.58955 -112.390682) (xy 119.445786 -112.516412)
			(xy 119.409972 -112.55248) (xy 119.499634 -112.642142)
		)
		(stroke
			(width 0)
			(type solid)
		)
		(fill yes)
		(layer "F.Cu")
		(net "M_L_DQS_DN<5>")
	)
	(gr_poly
		(pts
			(xy 119.550434 -43.786044) (xy 119.424704 -43.64228) (xy 119.388636 -43.606466) (xy 119.298974 -43.696128)
			(xy 119.334788 -43.732196) (xy 119.478552 -43.857672)
		)
		(stroke
			(width 0)
			(type solid)
		)
		(fill yes)
		(layer "F.Cu")
		(net "M_H_DQ<46>")
	)
	(gr_poly
		(pts
			(xy 119.575326 -47.20844) (xy 119.539258 -47.172626) (xy 119.395748 -47.046896) (xy 119.323866 -47.118778)
			(xy 119.449596 -47.262288) (xy 119.48541 -47.298356)
		)
		(stroke
			(width 0)
			(type solid)
		)
		(fill yes)
		(layer "F.Cu")
		(net "M_H_DQ<53>")
	)
	(gr_poly
		(pts
			(xy 119.59336 -48.645572) (xy 119.467884 -48.501808) (xy 119.431816 -48.465994) (xy 119.342154 -48.555656)
			(xy 119.377968 -48.591724) (xy 119.521732 -48.717454)
		)
		(stroke
			(width 0)
			(type solid)
		)
		(fill yes)
		(layer "F.Cu")
		(net "M_H_DQ<49>")
	)
	(gr_poly
		(pts
			(xy 119.598948 -111.142018) (xy 119.635016 -111.106204) (xy 119.5451 -111.016288) (xy 119.509286 -111.052356)
			(xy 119.383556 -111.195866) (xy 119.455438 -111.267748)
		)
		(stroke
			(width 0)
			(type solid)
		)
		(fill yes)
		(layer "F.Cu")
		(net "M_L_DQ<47>")
	)
	(gr_poly
		(pts
			(xy 119.613934 -105.944416) (xy 119.650002 -105.908602) (xy 119.560086 -105.818686) (xy 119.524272 -105.854754)
			(xy 119.398542 -105.998264) (xy 119.470424 -106.070146)
		)
		(stroke
			(width 0)
			(type solid)
		)
		(fill yes)
		(layer "F.Cu")
		(net "M_L_DQ<48>")
	)
	(gr_poly
		(pts
			(xy 119.622316 -43.372786) (xy 119.586248 -43.336972) (xy 119.442738 -43.211242) (xy 119.370856 -43.283124)
			(xy 119.496586 -43.426634) (xy 119.5324 -43.462702)
		)
		(stroke
			(width 0)
			(type solid)
		)
		(fill yes)
		(layer "F.Cu")
		(net "M_H_DQ<46>")
	)
	(gr_poly
		(pts
			(xy 119.625872 -111.5822) (xy 119.751602 -111.438436) (xy 119.67972 -111.366808) (xy 119.535956 -111.492284)
			(xy 119.500142 -111.528352) (xy 119.589804 -111.618014)
		)
		(stroke
			(width 0)
			(type solid)
		)
		(fill yes)
		(layer "F.Cu")
		(net "M_L_DQ<46>")
	)
	(gr_poly
		(pts
			(xy 119.635016 -42.548556) (xy 119.635016 -42.446956) (xy 119.444516 -42.434256) (xy 119.393716 -42.434256)
			(xy 119.393716 -42.561256) (xy 119.444516 -42.561256)
		)
		(stroke
			(width 0)
			(type solid)
		)
		(fill yes)
		(layer "F.Cu")
		(net "M_H_DQS_DP<5>")
	)
	(gr_poly
		(pts
			(xy 119.635016 -41.888156) (xy 119.635016 -41.786556) (xy 119.444516 -41.773856) (xy 119.393716 -41.773856)
			(xy 119.393716 -41.900856) (xy 119.444516 -41.900856)
		)
		(stroke
			(width 0)
			(type solid)
		)
		(fill yes)
		(layer "F.Cu")
		(net "M_H_DQS_DP<5>")
	)
	(gr_poly
		(pts
			(xy 119.64035 -44.809918) (xy 119.51462 -44.666154) (xy 119.478806 -44.63034) (xy 119.38889 -44.720256)
			(xy 119.424958 -44.75607) (xy 119.568722 -44.8818)
		)
		(stroke
			(width 0)
			(type solid)
		)
		(fill yes)
		(layer "F.Cu")
		(net "M_H_DQ<42>")
	)
	(gr_poly
		(pts
			(xy 119.640604 -106.384852) (xy 119.766334 -106.241088) (xy 119.694452 -106.16946) (xy 119.550688 -106.29519)
			(xy 119.514874 -106.331004) (xy 119.60479 -106.42092)
		)
		(stroke
			(width 0)
			(type solid)
		)
		(fill yes)
		(layer "F.Cu")
		(net "M_L_DQ<53>")
	)
	(gr_poly
		(pts
			(xy 119.665242 -48.232568) (xy 119.629428 -48.1965) (xy 119.485664 -48.07077) (xy 119.413782 -48.142652)
			(xy 119.539512 -48.286416) (xy 119.57558 -48.32223)
		)
		(stroke
			(width 0)
			(type solid)
		)
		(fill yes)
		(layer "F.Cu")
		(net "M_H_DQ<49>")
	)
	(gr_poly
		(pts
			(xy 119.689118 -110.118144) (xy 119.724932 -110.082076) (xy 119.63527 -109.992414) (xy 119.599202 -110.028228)
			(xy 119.473472 -110.171992) (xy 119.545354 -110.243874)
		)
		(stroke
			(width 0)
			(type solid)
		)
		(fill yes)
		(layer "F.Cu")
		(net "M_L_DQ<43>")
	)
	(gr_poly
		(pts
			(xy 119.691912 -46.876208) (xy 119.566182 -46.732444) (xy 119.530368 -46.696376) (xy 119.440452 -46.786292)
			(xy 119.476266 -46.822106) (xy 119.62003 -46.947836)
		)
		(stroke
			(width 0)
			(type solid)
		)
		(fill yes)
		(layer "F.Cu")
		(net "M_H_DQ<52>")
	)
	(gr_poly
		(pts
			(xy 119.697246 -112.911636) (xy 119.733314 -112.875822) (xy 119.643398 -112.785906) (xy 119.607584 -112.821974)
			(xy 119.481854 -112.965484) (xy 119.553736 -113.037366)
		)
		(stroke
			(width 0)
			(type solid)
		)
		(fill yes)
		(layer "F.Cu")
		(net "M_L_DQS_DN<5>")
	)
	(gr_poly
		(pts
			(xy 119.706136 -52.625752) (xy 119.876316 -52.536852) (xy 119.876316 -52.315872) (xy 119.706136 -52.226972)
			(xy 119.66194 -52.226972) (xy 119.661686 -52.626006)
		)
		(stroke
			(width 0)
			(type solid)
		)
		(fill yes)
		(layer "F.Cu")
		(net "M_H_DQS_DP<6>")
	)
	(gr_poly
		(pts
			(xy 119.710708 -104.717596) (xy 119.710708 -104.488996) (xy 119.517668 -104.400096) (xy 119.466868 -104.400096)
			(xy 119.466868 -104.806496) (xy 119.517668 -104.806496)
		)
		(stroke
			(width 0)
			(type solid)
		)
		(fill yes)
		(layer "F.Cu")
		(net "M_L_DQ<49>")
	)
	(gr_poly
		(pts
			(xy 119.712232 -44.396914) (xy 119.676418 -44.360846) (xy 119.532654 -44.235116) (xy 119.460772 -44.306998)
			(xy 119.586502 -44.450762) (xy 119.62257 -44.486576)
		)
		(stroke
			(width 0)
			(type solid)
		)
		(fill yes)
		(layer "F.Cu")
		(net "M_H_DQ<42>")
	)
	(gr_poly
		(pts
			(xy 119.715788 -110.558326) (xy 119.841518 -110.414562) (xy 119.76989 -110.34268) (xy 119.626126 -110.46841)
			(xy 119.590058 -110.504224) (xy 119.679974 -110.59414)
		)
		(stroke
			(width 0)
			(type solid)
		)
		(fill yes)
		(layer "F.Cu")
		(net "M_L_DQ<42>")
	)
	(gr_poly
		(pts
			(xy 119.7356 -50.737516) (xy 119.7356 -50.516536) (xy 119.56542 -50.427636) (xy 119.52097 -50.427636)
			(xy 119.52097 -50.826416) (xy 119.56542 -50.826416)
		)
		(stroke
			(width 0)
			(type solid)
		)
		(fill yes)
		(layer "F.Cu")
		(net "M_H_DQS_DP<6>")
	)
	(gr_poly
		(pts
			(xy 119.763794 -46.46295) (xy 119.727726 -46.427136) (xy 119.584216 -46.301406) (xy 119.512334 -46.373288)
			(xy 119.638064 -46.516798) (xy 119.673878 -46.552866)
		)
		(stroke
			(width 0)
			(type solid)
		)
		(fill yes)
		(layer "F.Cu")
		(net "M_H_DQ<52>")
	)
	(gr_poly
		(pts
			(xy 119.781828 -47.900082) (xy 119.656098 -47.756318) (xy 119.620284 -47.720504) (xy 119.530622 -47.810166)
			(xy 119.566436 -47.846234) (xy 119.7102 -47.971964)
		)
		(stroke
			(width 0)
			(type solid)
		)
		(fill yes)
		(layer "F.Cu")
		(net "M_H_DQ<48>")
	)
	(gr_poly
		(pts
			(xy 119.787416 -111.887508) (xy 119.823484 -111.851694) (xy 119.733568 -111.761778) (xy 119.697754 -111.797846)
			(xy 119.572024 -111.941356) (xy 119.643906 -112.013238)
		)
		(stroke
			(width 0)
			(type solid)
		)
		(fill yes)
		(layer "F.Cu")
		(net "M_L_DQ<46>")
	)
	(gr_poly
		(pts
			(xy 119.802148 -106.69016) (xy 119.838216 -106.654346) (xy 119.7483 -106.56443) (xy 119.712486 -106.600498)
			(xy 119.586756 -106.744008) (xy 119.658638 -106.81589)
		)
		(stroke
			(width 0)
			(type solid)
		)
		(fill yes)
		(layer "F.Cu")
		(net "M_L_DQ<53>")
	)
	(gr_poly
		(pts
			(xy 119.814086 -112.327944) (xy 119.939816 -112.18418) (xy 119.868188 -112.112298) (xy 119.724424 -112.238028)
			(xy 119.688356 -112.273842) (xy 119.778272 -112.363758)
		)
		(stroke
			(width 0)
			(type solid)
		)
		(fill yes)
		(layer "F.Cu")
		(net "M_L_DQS_DP<5>")
	)
	(gr_poly
		(pts
			(xy 119.828818 -44.064428) (xy 119.703088 -43.920664) (xy 119.667274 -43.88485) (xy 119.577358 -43.974766)
			(xy 119.613426 -44.01058) (xy 119.75719 -44.13631)
		)
		(stroke
			(width 0)
			(type solid)
		)
		(fill yes)
		(layer "F.Cu")
		(net "M_H_DQ<47>")
	)
	(gr_poly
		(pts
			(xy 119.829072 -107.130342) (xy 119.954802 -106.986578) (xy 119.88292 -106.91495) (xy 119.739156 -107.04068)
			(xy 119.703342 -107.076494) (xy 119.793258 -107.16641)
		)
		(stroke
			(width 0)
			(type solid)
		)
		(fill yes)
		(layer "F.Cu")
		(net "M_L_DQ<52>")
	)
	(gr_poly
		(pts
			(xy 119.85371 -47.487078) (xy 119.817896 -47.45101) (xy 119.674132 -47.32528) (xy 119.60225 -47.397162)
			(xy 119.72798 -47.540926) (xy 119.764048 -47.57674)
		)
		(stroke
			(width 0)
			(type solid)
		)
		(fill yes)
		(layer "F.Cu")
		(net "M_H_DQ<48>")
	)
	(gr_poly
		(pts
			(xy 119.871744 -48.92421) (xy 119.746268 -48.780446) (xy 119.7102 -48.744632) (xy 119.620538 -48.834294)
			(xy 119.656352 -48.870362) (xy 119.800116 -48.996092)
		)
		(stroke
			(width 0)
			(type solid)
		)
		(fill yes)
		(layer "F.Cu")
		(net "M_H_DQS_DP<15>")
	)
	(gr_poly
		(pts
			(xy 119.877586 -110.863634) (xy 119.9134 -110.827566) (xy 119.823738 -110.737904) (xy 119.78767 -110.773718)
			(xy 119.66194 -110.917482) (xy 119.733822 -110.989364)
		)
		(stroke
			(width 0)
			(type solid)
		)
		(fill yes)
		(layer "F.Cu")
		(net "M_L_DQ<42>")
	)
	(gr_poly
		(pts
			(xy 119.883428 -51.542442) (xy 119.883428 -51.321462) (xy 119.713248 -51.232562) (xy 119.668798 -51.232562)
			(xy 119.668798 -51.631342) (xy 119.713248 -51.631342)
		)
		(stroke
			(width 0)
			(type solid)
		)
		(fill yes)
		(layer "F.Cu")
		(net "M_H_DQS_DP<6>")
	)
	(gr_poly
		(pts
			(xy 119.892572 -105.666032) (xy 119.928386 -105.629964) (xy 119.838724 -105.540302) (xy 119.802656 -105.576116)
			(xy 119.676926 -105.71988) (xy 119.748808 -105.791762)
		)
		(stroke
			(width 0)
			(type solid)
		)
		(fill yes)
		(layer "F.Cu")
		(net "M_L_DQ<49>")
	)
	(gr_poly
		(pts
			(xy 119.9007 -43.651424) (xy 119.864886 -43.615356) (xy 119.721122 -43.489626) (xy 119.64924 -43.561508)
			(xy 119.77497 -43.705272) (xy 119.811038 -43.741086)
		)
		(stroke
			(width 0)
			(type solid)
		)
		(fill yes)
		(layer "F.Cu")
		(net "M_H_DQ<47>")
	)
	(gr_poly
		(pts
			(xy 119.904256 -111.303816) (xy 120.029986 -111.160052) (xy 119.958358 -111.08817) (xy 119.814594 -111.2139)
			(xy 119.778526 -111.249714) (xy 119.868442 -111.33963)
		)
		(stroke
			(width 0)
			(type solid)
		)
		(fill yes)
		(layer "F.Cu")
		(net "M_L_DQ<47>")
	)
	(gr_poly
		(pts
			(xy 119.918988 -45.088556) (xy 119.793258 -44.944792) (xy 119.75719 -44.908978) (xy 119.667528 -44.99864)
			(xy 119.703342 -45.034454) (xy 119.847106 -45.160184)
		)
		(stroke
			(width 0)
			(type solid)
		)
		(fill yes)
		(layer "F.Cu")
		(net "M_H_DQ<43>")
	)
	(gr_poly
		(pts
			(xy 119.919242 -106.106214) (xy 120.044972 -105.96245) (xy 119.973344 -105.890568) (xy 119.82958 -106.016298)
			(xy 119.793512 -106.052112) (xy 119.883428 -106.142028)
		)
		(stroke
			(width 0)
			(type solid)
		)
		(fill yes)
		(layer "F.Cu")
		(net "M_L_DQ<48>")
	)
	(gr_poly
		(pts
			(xy 119.94388 -48.511206) (xy 119.908066 -48.475138) (xy 119.764302 -48.349408) (xy 119.69242 -48.42129)
			(xy 119.81815 -48.565054) (xy 119.854218 -48.600868)
		)
		(stroke
			(width 0)
			(type solid)
		)
		(fill yes)
		(layer "F.Cu")
		(net "M_H_DQS_DP<15>")
	)
	(gr_poly
		(pts
			(xy 119.970296 -47.154592) (xy 119.844566 -47.010828) (xy 119.808752 -46.975014) (xy 119.718836 -47.06493)
			(xy 119.754904 -47.100744) (xy 119.898668 -47.226474)
		)
		(stroke
			(width 0)
			(type solid)
		)
		(fill yes)
		(layer "F.Cu")
		(net "M_H_DQ<53>")
	)
	(gr_poly
		(pts
			(xy 119.97436 -49.516538) (xy 119.942864 -49.485042) (xy 119.75973 -49.427638) (xy 119.60352 -49.583848)
			(xy 119.660924 -49.766982) (xy 119.69242 -49.798478)
		)
		(stroke
			(width 0)
			(type solid)
		)
		(fill yes)
		(layer "F.Cu")
		(net "M_H_DQS_DN<6>")
	)
	(gr_poly
		(pts
			(xy 119.975884 -112.633252) (xy 120.011698 -112.597184) (xy 119.922036 -112.507522) (xy 119.885968 -112.543336)
			(xy 119.760238 -112.6871) (xy 119.83212 -112.758982)
		)
		(stroke
			(width 0)
			(type solid)
		)
		(fill yes)
		(layer "F.Cu")
		(net "M_L_DQS_DP<5>")
	)
	(gr_poly
		(pts
			(xy 119.990616 -107.43565) (xy 120.026684 -107.399836) (xy 119.936768 -107.30992) (xy 119.900954 -107.345988)
			(xy 119.775224 -107.489498) (xy 119.847106 -107.56138)
		)
		(stroke
			(width 0)
			(type solid)
		)
		(fill yes)
		(layer "F.Cu")
		(net "M_L_DQ<52>")
	)
	(gr_poly
		(pts
			(xy 119.99087 -44.675298) (xy 119.954802 -44.639484) (xy 119.811292 -44.513754) (xy 119.73941 -44.585636)
			(xy 119.86514 -44.729146) (xy 119.900954 -44.765214)
		)
		(stroke
			(width 0)
			(type solid)
		)
		(fill yes)
		(layer "F.Cu")
		(net "M_H_DQ<43>")
	)
	(gr_poly
		(pts
			(xy 119.994426 -110.279688) (xy 120.120156 -110.135924) (xy 120.048274 -110.064296) (xy 119.90451 -110.190026)
			(xy 119.868696 -110.22584) (xy 119.958358 -110.315502)
		)
		(stroke
			(width 0)
			(type solid)
		)
		(fill yes)
		(layer "F.Cu")
		(net "M_L_DQ<43>")
	)
	(gr_poly
		(pts
			(xy 120.017286 -43.318938) (xy 119.891556 -43.175174) (xy 119.855742 -43.13936) (xy 119.765826 -43.229276)
			(xy 119.801894 -43.26509) (xy 119.945658 -43.39082)
		)
		(stroke
			(width 0)
			(type solid)
		)
		(fill yes)
		(layer "F.Cu")
		(net "M_H_DQ<46>")
	)
	(gr_poly
		(pts
			(xy 120.042178 -46.741588) (xy 120.006364 -46.70552) (xy 119.8626 -46.57979) (xy 119.790718 -46.651672)
			(xy 119.916448 -46.795436) (xy 119.952516 -46.83125)
		)
		(stroke
			(width 0)
			(type solid)
		)
		(fill yes)
		(layer "F.Cu")
		(net "M_H_DQ<53>")
	)
	(gr_poly
		(pts
			(xy 120.060466 -48.17872) (xy 119.934736 -48.034956) (xy 119.898922 -47.998888) (xy 119.809006 -48.088804)
			(xy 119.84482 -48.124618) (xy 119.988584 -48.250348)
		)
		(stroke
			(width 0)
			(type solid)
		)
		(fill yes)
		(layer "F.Cu")
		(net "M_H_DQ<49>")
	)
	(gr_poly
		(pts
			(xy 120.066054 -111.609124) (xy 120.101868 -111.573056) (xy 120.012206 -111.483394) (xy 119.976138 -111.519208)
			(xy 119.850408 -111.662972) (xy 119.92229 -111.734854)
		)
		(stroke
			(width 0)
			(type solid)
		)
		(fill yes)
		(layer "F.Cu")
		(net "M_L_DQ<47>")
	)
	(gr_poly
		(pts
			(xy 120.08104 -106.411522) (xy 120.116854 -106.375454) (xy 120.027192 -106.285792) (xy 119.991124 -106.321606)
			(xy 119.865394 -106.46537) (xy 119.937276 -106.537252)
		)
		(stroke
			(width 0)
			(type solid)
		)
		(fill yes)
		(layer "F.Cu")
		(net "M_L_DQ<48>")
	)
	(gr_poly
		(pts
			(xy 120.089168 -104.30256) (xy 120.038368 -104.30256) (xy 119.845328 -104.39146) (xy 119.845328 -104.62006)
			(xy 120.038368 -104.70896) (xy 120.089168 -104.70896)
		)
		(stroke
			(width 0)
			(type solid)
		)
		(fill yes)
		(layer "F.Cu")
		(net "M_L_DQS_DP<15>")
	)
	(gr_poly
		(pts
			(xy 120.092724 -112.049306) (xy 120.218454 -111.905542) (xy 120.146826 -111.83366) (xy 120.003062 -111.95939)
			(xy 119.966994 -111.995204) (xy 120.05691 -112.08512)
		)
		(stroke
			(width 0)
			(type solid)
		)
		(fill yes)
		(layer "F.Cu")
		(net "M_L_DQ<46>")
	)
	(gr_poly
		(pts
			(xy 120.107456 -106.851958) (xy 120.233186 -106.708194) (xy 120.161558 -106.636312) (xy 120.017794 -106.762042)
			(xy 119.981726 -106.797856) (xy 120.071642 -106.887772)
		)
		(stroke
			(width 0)
			(type solid)
		)
		(fill yes)
		(layer "F.Cu")
		(net "M_L_DQ<53>")
	)
	(gr_poly
		(pts
			(xy 120.107456 -44.343066) (xy 119.981726 -44.199302) (xy 119.945658 -44.163488) (xy 119.855996 -44.25315)
			(xy 119.89181 -44.289218) (xy 120.035574 -44.414694)
		)
		(stroke
			(width 0)
			(type solid)
		)
		(fill yes)
		(layer "F.Cu")
		(net "M_H_DQ<42>")
	)
	(gr_poly
		(pts
			(xy 120.113552 -50.761138) (xy 120.069102 -50.761138) (xy 119.898922 -50.850038) (xy 119.898922 -51.071018)
			(xy 120.069102 -51.159918) (xy 120.113552 -51.159918)
		)
		(stroke
			(width 0)
			(type solid)
		)
		(fill yes)
		(layer "F.Cu")
		(net "M_H_DQ<54>")
	)
	(gr_poly
		(pts
			(xy 120.132348 -47.765462) (xy 120.09628 -47.729648) (xy 119.95277 -47.603918) (xy 119.880888 -47.6758)
			(xy 120.006618 -47.81931) (xy 120.042432 -47.855378)
		)
		(stroke
			(width 0)
			(type solid)
		)
		(fill yes)
		(layer "F.Cu")
		(net "M_H_DQ<49>")
	)
	(gr_poly
		(pts
			(xy 120.150382 -49.202594) (xy 120.024906 -49.05883) (xy 119.988838 -49.023016) (xy 119.899176 -49.112678)
			(xy 119.93499 -49.148746) (xy 120.078754 -49.274476)
		)
		(stroke
			(width 0)
			(type solid)
		)
		(fill yes)
		(layer "F.Cu")
		(net "M_H_DQS_DN<15>")
	)
	(gr_poly
		(pts
			(xy 120.15597 -110.584996) (xy 120.192038 -110.549182) (xy 120.102122 -110.459266) (xy 120.066308 -110.495334)
			(xy 119.940578 -110.638844) (xy 120.01246 -110.710726)
		)
		(stroke
			(width 0)
			(type solid)
		)
		(fill yes)
		(layer "F.Cu")
		(net "M_L_DQ<43>")
	)
	(gr_poly
		(pts
			(xy 120.158764 -46.409102) (xy 120.033034 -46.265338) (xy 119.99722 -46.229524) (xy 119.907304 -46.31944)
			(xy 119.943372 -46.355254) (xy 120.087136 -46.480984)
		)
		(stroke
			(width 0)
			(type solid)
		)
		(fill yes)
		(layer "F.Cu")
		(net "M_H_DQ<52>")
	)
	(gr_poly
		(pts
			(xy 120.179338 -43.929808) (xy 120.14327 -43.893994) (xy 119.99976 -43.768264) (xy 119.927878 -43.840146)
			(xy 120.053608 -43.983656) (xy 120.089422 -44.019724)
		)
		(stroke
			(width 0)
			(type solid)
		)
		(fill yes)
		(layer "F.Cu")
		(net "M_H_DQ<42>")
	)
	(gr_poly
		(pts
			(xy 120.182894 -111.025178) (xy 120.308624 -110.881414) (xy 120.236742 -110.809786) (xy 120.092978 -110.935262)
			(xy 120.057164 -110.97133) (xy 120.146826 -111.060992)
		)
		(stroke
			(width 0)
			(type solid)
		)
		(fill yes)
		(layer "F.Cu")
		(net "M_L_DQ<42>")
	)
	(gr_poly
		(pts
			(xy 120.196864 -100.76688) (xy 120.152414 -100.76688) (xy 119.982234 -100.85578) (xy 119.982234 -101.07676)
			(xy 120.152414 -101.165406) (xy 120.19661 -101.16566)
		)
		(stroke
			(width 0)
			(type solid)
		)
		(fill yes)
		(layer "F.Cu")
		(net "M_L_DQS_DP<15>")
	)
	(gr_poly
		(pts
			(xy 120.222518 -48.78959) (xy 120.186704 -48.753522) (xy 120.04294 -48.627792) (xy 119.971058 -48.699674)
			(xy 120.096788 -48.843438) (xy 120.132856 -48.879252)
		)
		(stroke
			(width 0)
			(type solid)
		)
		(fill yes)
		(layer "F.Cu")
		(net "M_H_DQS_DN<15>")
	)
	(gr_poly
		(pts
			(xy 120.230646 -45.996098) (xy 120.194832 -45.96003) (xy 120.051068 -45.8343) (xy 119.979186 -45.906182)
			(xy 120.104916 -46.049946) (xy 120.140984 -46.08576)
		)
		(stroke
			(width 0)
			(type solid)
		)
		(fill yes)
		(layer "F.Cu")
		(net "M_H_DQ<52>")
	)
	(gr_poly
		(pts
			(xy 120.248934 -47.43323) (xy 120.123204 -47.289466) (xy 120.08739 -47.253398) (xy 119.997474 -47.343314)
			(xy 120.033288 -47.379128) (xy 120.177052 -47.504858)
		)
		(stroke
			(width 0)
			(type solid)
		)
		(fill yes)
		(layer "F.Cu")
		(net "M_H_DQ<48>")
	)
	(gr_poly
		(pts
			(xy 120.269254 -107.157266) (xy 120.305068 -107.121198) (xy 120.215406 -107.031536) (xy 120.179338 -107.06735)
			(xy 120.053608 -107.211114) (xy 120.12549 -107.282996)
		)
		(stroke
			(width 0)
			(type solid)
		)
		(fill yes)
		(layer "F.Cu")
		(net "M_L_DQ<53>")
	)
	(gr_poly
		(pts
			(xy 120.295924 -107.597448) (xy 120.421654 -107.453684) (xy 120.350026 -107.381802) (xy 120.206262 -107.507532)
			(xy 120.170194 -107.543346) (xy 120.26011 -107.633262)
		)
		(stroke
			(width 0)
			(type solid)
		)
		(fill yes)
		(layer "F.Cu")
		(net "M_L_DQ<52>")
	)
	(gr_poly
		(pts
			(xy 120.295924 -43.597576) (xy 120.170194 -43.453812) (xy 120.134126 -43.417998) (xy 120.044464 -43.50766)
			(xy 120.080278 -43.543728) (xy 120.224042 -43.669458)
		)
		(stroke
			(width 0)
			(type solid)
		)
		(fill yes)
		(layer "F.Cu")
		(net "M_H_DQ<47>")
	)
	(gr_poly
		(pts
			(xy 120.320816 -47.019972) (xy 120.284748 -46.984158) (xy 120.141238 -46.858428) (xy 120.069356 -46.93031)
			(xy 120.195086 -47.07382) (xy 120.2309 -47.109888)
		)
		(stroke
			(width 0)
			(type solid)
		)
		(fill yes)
		(layer "F.Cu")
		(net "M_H_DQ<48>")
	)
	(gr_poly
		(pts
			(xy 120.33885 -48.457358) (xy 120.21312 -48.313594) (xy 120.177306 -48.277526) (xy 120.08739 -48.367442)
			(xy 120.123204 -48.403256) (xy 120.266968 -48.528986)
		)
		(stroke
			(width 0)
			(type solid)
		)
		(fill yes)
		(layer "F.Cu")
		(net "M_H_DQS_DP<15>")
	)
	(gr_poly
		(pts
			(xy 120.344438 -111.330486) (xy 120.380506 -111.294672) (xy 120.29059 -111.204756) (xy 120.254776 -111.240824)
			(xy 120.129046 -111.384334) (xy 120.200928 -111.456216)
		)
		(stroke
			(width 0)
			(type solid)
		)
		(fill yes)
		(layer "F.Cu")
		(net "M_L_DQ<42>")
	)
	(gr_poly
		(pts
			(xy 120.359424 -106.132884) (xy 120.395492 -106.09707) (xy 120.305576 -106.007154) (xy 120.269762 -106.043222)
			(xy 120.144032 -106.186732) (xy 120.215914 -106.258614)
		)
		(stroke
			(width 0)
			(type solid)
		)
		(fill yes)
		(layer "F.Cu")
		(net "M_L_DQ<49>")
	)
	(gr_poly
		(pts
			(xy 120.367806 -43.184318) (xy 120.331738 -43.148504) (xy 120.188228 -43.022774) (xy 120.116346 -43.094656)
			(xy 120.242076 -43.238166) (xy 120.27789 -43.274234)
		)
		(stroke
			(width 0)
			(type solid)
		)
		(fill yes)
		(layer "F.Cu")
		(net "M_H_DQ<47>")
	)
	(gr_poly
		(pts
			(xy 120.371362 -111.770668) (xy 120.497092 -111.626904) (xy 120.42521 -111.555022) (xy 120.281446 -111.680752)
			(xy 120.245632 -111.71682) (xy 120.335294 -111.806482)
		)
		(stroke
			(width 0)
			(type solid)
		)
		(fill yes)
		(layer "F.Cu")
		(net "M_L_DQ<47>")
	)
	(gr_poly
		(pts
			(xy 120.38584 -44.62145) (xy 120.26011 -44.477686) (xy 120.224296 -44.441872) (xy 120.13438 -44.531788)
			(xy 120.170448 -44.567602) (xy 120.314212 -44.693332)
		)
		(stroke
			(width 0)
			(type solid)
		)
		(fill yes)
		(layer "F.Cu")
		(net "M_H_DQ<43>")
	)
	(gr_poly
		(pts
			(xy 120.386348 -106.573066) (xy 120.512078 -106.429302) (xy 120.440196 -106.357674) (xy 120.296432 -106.483404)
			(xy 120.260618 -106.519218) (xy 120.350534 -106.609134)
		)
		(stroke
			(width 0)
			(type solid)
		)
		(fill yes)
		(layer "F.Cu")
		(net "M_L_DQ<48>")
	)
	(gr_poly
		(pts
			(xy 120.410986 -48.0441) (xy 120.374918 -48.008286) (xy 120.231408 -47.882556) (xy 120.159526 -47.954438)
			(xy 120.285256 -48.097948) (xy 120.32107 -48.134016)
		)
		(stroke
			(width 0)
			(type solid)
		)
		(fill yes)
		(layer "F.Cu")
		(net "M_H_DQS_DP<15>")
	)
	(gr_poly
		(pts
			(xy 120.437402 -46.68774) (xy 120.311672 -46.543976) (xy 120.275858 -46.507908) (xy 120.185942 -46.597824)
			(xy 120.221756 -46.633638) (xy 120.36552 -46.759368)
		)
		(stroke
			(width 0)
			(type solid)
		)
		(fill yes)
		(layer "F.Cu")
		(net "M_H_DQ<53>")
	)
	(gr_poly
		(pts
			(xy 120.457722 -107.902756) (xy 120.493536 -107.866688) (xy 120.403874 -107.777026) (xy 120.367806 -107.81284)
			(xy 120.242076 -107.956604) (xy 120.313958 -108.028486)
		)
		(stroke
			(width 0)
			(type solid)
		)
		(fill yes)
		(layer "F.Cu")
		(net "M_L_DQ<52>")
	)
	(gr_poly
		(pts
			(xy 120.457722 -44.208446) (xy 120.421908 -44.172378) (xy 120.278144 -44.046648) (xy 120.206262 -44.11853)
			(xy 120.331992 -44.262294) (xy 120.36806 -44.298108)
		)
		(stroke
			(width 0)
			(type solid)
		)
		(fill yes)
		(layer "F.Cu")
		(net "M_H_DQ<43>")
	)
	(gr_poly
		(pts
			(xy 120.461024 -50.079402) (xy 120.429528 -50.047906) (xy 120.246394 -49.990502) (xy 120.090184 -50.146712)
			(xy 120.147588 -50.329846) (xy 120.179084 -50.361342)
		)
		(stroke
			(width 0)
			(type solid)
		)
		(fill yes)
		(layer "F.Cu")
		(net "M_H_DQ<54>")
	)
	(gr_poly
		(pts
			(xy 120.461278 -110.746794) (xy 120.587008 -110.60303) (xy 120.51538 -110.531148) (xy 120.371616 -110.656878)
			(xy 120.335548 -110.692692) (xy 120.425464 -110.782608)
		)
		(stroke
			(width 0)
			(type solid)
		)
		(fill yes)
		(layer "F.Cu")
		(net "M_L_DQ<43>")
	)
	(gr_poly
		(pts
			(xy 120.484392 -42.852086) (xy 120.358662 -42.708322) (xy 120.322594 -42.672508) (xy 120.232932 -42.76217)
			(xy 120.268746 -42.798238) (xy 120.41251 -42.923968)
		)
		(stroke
			(width 0)
			(type solid)
		)
		(fill yes)
		(layer "F.Cu")
		(net "M_H_DQ<46>")
	)
	(gr_poly
		(pts
			(xy 120.500902 -49.067974) (xy 120.464834 -49.03216) (xy 120.321324 -48.90643) (xy 120.249442 -48.978312)
			(xy 120.375172 -49.121822) (xy 120.410986 -49.15789)
		)
		(stroke
			(width 0)
			(type solid)
		)
		(fill yes)
		(layer "F.Cu")
		(net "M_H_DQS_DN<6>")
	)
	(gr_poly
		(pts
			(xy 120.509284 -46.274482) (xy 120.473216 -46.238668) (xy 120.329706 -46.112938) (xy 120.257824 -46.18482)
			(xy 120.383554 -46.32833) (xy 120.419368 -46.364398)
		)
		(stroke
			(width 0)
			(type solid)
		)
		(fill yes)
		(layer "F.Cu")
		(net "M_H_DQ<53>")
	)
	(gr_poly
		(pts
			(xy 120.518682 -53.026818) (xy 120.518682 -52.805838) (xy 120.348502 -52.716938) (xy 120.304052 -52.716938)
			(xy 120.304052 -53.115718) (xy 120.348502 -53.115718)
		)
		(stroke
			(width 0)
			(type solid)
		)
		(fill yes)
		(layer "F.Cu")
		(net "M_H_DQ<55>")
	)
	(gr_poly
		(pts
			(xy 120.518682 -52.036218) (xy 120.518682 -51.815238) (xy 120.348502 -51.726338) (xy 120.304052 -51.726338)
			(xy 120.304052 -52.125118) (xy 120.348502 -52.125118)
		)
		(stroke
			(width 0)
			(type solid)
		)
		(fill yes)
		(layer "F.Cu")
		(net "M_H_DQ<55>")
	)
	(gr_poly
		(pts
			(xy 120.523508 -104.62006) (xy 120.523508 -104.39146) (xy 120.330468 -104.30256) (xy 120.279668 -104.30256)
			(xy 120.279668 -104.70896) (xy 120.330468 -104.70896)
		)
		(stroke
			(width 0)
			(type solid)
		)
		(fill yes)
		(layer "F.Cu")
		(net "M_L_DQS_DN<15>")
	)
	(gr_poly
		(pts
			(xy 120.527318 -47.711614) (xy 120.401588 -47.56785) (xy 120.365774 -47.532036) (xy 120.275858 -47.621952)
			(xy 120.311926 -47.657766) (xy 120.45569 -47.783496)
		)
		(stroke
			(width 0)
			(type solid)
		)
		(fill yes)
		(layer "F.Cu")
		(net "M_H_DQ<49>")
	)
	(gr_poly
		(pts
			(xy 120.547892 -106.878374) (xy 120.58396 -106.84256) (xy 120.494044 -106.752644) (xy 120.45823 -106.788712)
			(xy 120.3325 -106.932222) (xy 120.404382 -107.004104)
		)
		(stroke
			(width 0)
			(type solid)
		)
		(fill yes)
		(layer "F.Cu")
		(net "M_L_DQ<48>")
	)
	(gr_poly
		(pts
			(xy 120.574308 -43.87596) (xy 120.448578 -43.732196) (xy 120.412764 -43.696382) (xy 120.322848 -43.786298)
			(xy 120.358916 -43.822112) (xy 120.50268 -43.947842)
		)
		(stroke
			(width 0)
			(type solid)
		)
		(fill yes)
		(layer "F.Cu")
		(net "M_H_DQ<42>")
	)
	(gr_poly
		(pts
			(xy 120.574562 -107.31881) (xy 120.700292 -107.175046) (xy 120.62841 -107.103418) (xy 120.484646 -107.229148)
			(xy 120.448832 -107.264962) (xy 120.538494 -107.354624)
		)
		(stroke
			(width 0)
			(type solid)
		)
		(fill yes)
		(layer "F.Cu")
		(net "M_L_DQ<53>")
	)
	(gr_poly
		(pts
			(xy 120.5992 -47.29861) (xy 120.563386 -47.262542) (xy 120.419622 -47.136812) (xy 120.34774 -47.208694)
			(xy 120.47347 -47.352458) (xy 120.509538 -47.388272)
		)
		(stroke
			(width 0)
			(type solid)
		)
		(fill yes)
		(layer "F.Cu")
		(net "M_H_DQ<49>")
	)
	(gr_poly
		(pts
			(xy 120.617488 -48.735742) (xy 120.491758 -48.591978) (xy 120.455944 -48.55591) (xy 120.366028 -48.645826)
			(xy 120.401842 -48.68164) (xy 120.545606 -48.80737)
		)
		(stroke
			(width 0)
			(type solid)
		)
		(fill yes)
		(layer "F.Cu")
		(net "M_H_DQS_DN<15>")
	)
	(gr_poly
		(pts
			(xy 120.623076 -111.052102) (xy 120.65889 -111.016034) (xy 120.569228 -110.926372) (xy 120.53316 -110.962186)
			(xy 120.40743 -111.10595) (xy 120.479312 -111.177832)
		)
		(stroke
			(width 0)
			(type solid)
		)
		(fill yes)
		(layer "F.Cu")
		(net "M_L_DQ<43>")
	)
	(gr_poly
		(pts
			(xy 120.62587 -45.94225) (xy 120.50014 -45.798486) (xy 120.464072 -45.762672) (xy 120.37441 -45.852334)
			(xy 120.410224 -45.888148) (xy 120.553988 -46.013878)
		)
		(stroke
			(width 0)
			(type solid)
		)
		(fill yes)
		(layer "F.Cu")
		(net "M_H_DQ<52>")
	)
	(gr_poly
		(pts
			(xy 120.638062 -105.854246) (xy 120.67413 -105.818432) (xy 120.584214 -105.728516) (xy 120.5484 -105.764584)
			(xy 120.42267 -105.908094) (xy 120.494552 -105.979976)
		)
		(stroke
			(width 0)
			(type solid)
		)
		(fill yes)
		(layer "F.Cu")
		(net "M_L_DQS_DP<15>")
	)
	(gr_poly
		(pts
			(xy 120.64619 -43.462956) (xy 120.610376 -43.426888) (xy 120.466612 -43.301158) (xy 120.39473 -43.37304)
			(xy 120.52046 -43.516804) (xy 120.556528 -43.552618)
		)
		(stroke
			(width 0)
			(type solid)
		)
		(fill yes)
		(layer "F.Cu")
		(net "M_H_DQ<42>")
	)
	(gr_poly
		(pts
			(xy 120.664732 -106.294682) (xy 120.790462 -106.150918) (xy 120.718834 -106.079036) (xy 120.57507 -106.204766)
			(xy 120.539002 -106.24058) (xy 120.628918 -106.330496)
		)
		(stroke
			(width 0)
			(type solid)
		)
		(fill yes)
		(layer "F.Cu")
		(net "M_L_DQ<49>")
	)
	(gr_poly
		(pts
			(xy 120.687846 -112.3823) (xy 120.687846 -112.3315) (xy 120.560846 -112.3315) (xy 120.560846 -112.3823)
			(xy 120.573546 -112.5728) (xy 120.675146 -112.5728)
		)
		(stroke
			(width 0)
			(type solid)
		)
		(fill yes)
		(layer "F.Cu")
		(net "M_L_DQ<46>")
	)
	(gr_poly
		(pts
			(xy 120.687846 -111.9886) (xy 120.687846 -111.9378) (xy 120.560846 -111.9378) (xy 120.560846 -111.9886)
			(xy 120.573546 -112.1791) (xy 120.675146 -112.1791)
		)
		(stroke
			(width 0)
			(type solid)
		)
		(fill yes)
		(layer "F.Cu")
		(net "M_L_DQ<47>")
	)
	(gr_poly
		(pts
			(xy 120.68937 -48.322484) (xy 120.653302 -48.28667) (xy 120.509792 -48.16094) (xy 120.43791 -48.232822)
			(xy 120.56364 -48.376332) (xy 120.599454 -48.4124)
		)
		(stroke
			(width 0)
			(type solid)
		)
		(fill yes)
		(layer "F.Cu")
		(net "M_H_DQS_DN<15>")
	)
	(gr_poly
		(pts
			(xy 120.697752 -45.528992) (xy 120.661684 -45.493178) (xy 120.518174 -45.367448) (xy 120.446292 -45.43933)
			(xy 120.572022 -45.58284) (xy 120.607836 -45.618908)
		)
		(stroke
			(width 0)
			(type solid)
		)
		(fill yes)
		(layer "F.Cu")
		(net "M_H_DQ<52>")
	)
	(gr_poly
		(pts
			(xy 120.715786 -46.966124) (xy 120.590056 -46.82236) (xy 120.554242 -46.786546) (xy 120.464326 -46.876462)
			(xy 120.500394 -46.912276) (xy 120.644158 -47.038006)
		)
		(stroke
			(width 0)
			(type solid)
		)
		(fill yes)
		(layer "F.Cu")
		(net "M_H_DQ<48>")
	)
	(gr_poly
		(pts
			(xy 120.734582 -102.582218) (xy 120.734582 -102.361238) (xy 120.564402 -102.272338) (xy 120.519952 -102.272338)
			(xy 120.519952 -102.671118) (xy 120.564402 -102.671118)
		)
		(stroke
			(width 0)
			(type solid)
		)
		(fill yes)
		(layer "F.Cu")
		(net "M_L_DQS_DN<15>")
	)
	(gr_poly
		(pts
			(xy 120.736106 -107.624118) (xy 120.772174 -107.588304) (xy 120.682258 -107.498388) (xy 120.646444 -107.534456)
			(xy 120.520714 -107.677966) (xy 120.592596 -107.749848)
		)
		(stroke
			(width 0)
			(type solid)
		)
		(fill yes)
		(layer "F.Cu")
		(net "M_L_DQ<53>")
	)
	(gr_poly
		(pts
			(xy 120.762776 -43.13047) (xy 120.637046 -42.986706) (xy 120.601232 -42.950892) (xy 120.511316 -43.040808)
			(xy 120.547384 -43.076622) (xy 120.690894 -43.202352)
		)
		(stroke
			(width 0)
			(type solid)
		)
		(fill yes)
		(layer "F.Cu")
		(net "M_H_DQ<47>")
	)
	(gr_poly
		(pts
			(xy 120.76303 -108.0643) (xy 120.88876 -107.920536) (xy 120.816878 -107.848908) (xy 120.673114 -107.974384)
			(xy 120.6373 -108.010452) (xy 120.726962 -108.100114)
		)
		(stroke
			(width 0)
			(type solid)
		)
		(fill yes)
		(layer "F.Cu")
		(net "M_L_DQ<52>")
	)
	(gr_poly
		(pts
			(xy 120.779286 -49.346612) (xy 120.743472 -49.310544) (xy 120.599708 -49.184814) (xy 120.527826 -49.256696)
			(xy 120.653556 -49.40046) (xy 120.689624 -49.436274)
		)
		(stroke
			(width 0)
			(type solid)
		)
		(fill yes)
		(layer "F.Cu")
		(net "M_H_DQS_DP<6>")
	)
	(gr_poly
		(pts
			(xy 120.787668 -46.55312) (xy 120.751854 -46.517052) (xy 120.60809 -46.391322) (xy 120.536208 -46.463204)
			(xy 120.661938 -46.606968) (xy 120.698006 -46.642782)
		)
		(stroke
			(width 0)
			(type solid)
		)
		(fill yes)
		(layer "F.Cu")
		(net "M_H_DQ<48>")
	)
	(gr_poly
		(pts
			(xy 120.805702 -47.990252) (xy 120.679972 -47.846488) (xy 120.644158 -47.810674) (xy 120.554242 -47.90059)
			(xy 120.59031 -47.936404) (xy 120.734074 -48.062134)
		)
		(stroke
			(width 0)
			(type solid)
		)
		(fill yes)
		(layer "F.Cu")
		(net "M_H_DQS_DP<15>")
	)
	(gr_poly
		(pts
			(xy 120.82653 -106.59999) (xy 120.862344 -106.563922) (xy 120.772682 -106.47426) (xy 120.736614 -106.510074)
			(xy 120.610884 -106.653838) (xy 120.682766 -106.72572)
		)
		(stroke
			(width 0)
			(type solid)
		)
		(fill yes)
		(layer "F.Cu")
		(net "M_L_DQ<49>")
	)
	(gr_poly
		(pts
			(xy 120.834658 -42.717466) (xy 120.798844 -42.681398) (xy 120.65508 -42.555668) (xy 120.583198 -42.62755)
			(xy 120.708928 -42.771314) (xy 120.744996 -42.807128)
		)
		(stroke
			(width 0)
			(type solid)
		)
		(fill yes)
		(layer "F.Cu")
		(net "M_H_DQ<47>")
	)
	(gr_poly
		(pts
			(xy 120.852946 -44.154598) (xy 120.727216 -44.010834) (xy 120.691148 -43.97502) (xy 120.601486 -44.064682)
			(xy 120.6373 -44.10075) (xy 120.781064 -44.22648)
		)
		(stroke
			(width 0)
			(type solid)
		)
		(fill yes)
		(layer "F.Cu")
		(net "M_H_DQ<43>")
	)
	(gr_poly
		(pts
			(xy 120.8532 -107.040172) (xy 120.97893 -106.896408) (xy 120.907302 -106.824526) (xy 120.763538 -106.950256)
			(xy 120.72747 -106.98607) (xy 120.817386 -107.075986)
		)
		(stroke
			(width 0)
			(type solid)
		)
		(fill yes)
		(layer "F.Cu")
		(net "M_L_DQ<48>")
	)
	(gr_poly
		(pts
			(xy 120.877838 -47.577248) (xy 120.842024 -47.54118) (xy 120.69826 -47.41545) (xy 120.626378 -47.487332)
			(xy 120.752108 -47.631096) (xy 120.788176 -47.66691)
		)
		(stroke
			(width 0)
			(type solid)
		)
		(fill yes)
		(layer "F.Cu")
		(net "M_H_DQS_DP<15>")
	)
	(gr_poly
		(pts
			(xy 120.895872 -49.014126) (xy 120.770142 -48.870362) (xy 120.734328 -48.834548) (xy 120.644666 -48.92421)
			(xy 120.68048 -48.960278) (xy 120.824244 -49.086008)
		)
		(stroke
			(width 0)
			(type solid)
		)
		(fill yes)
		(layer "F.Cu")
		(net "M_H_DQS_DN<6>")
	)
	(gr_poly
		(pts
			(xy 120.904254 -46.220634) (xy 120.778524 -46.07687) (xy 120.74271 -46.041056) (xy 120.652794 -46.130972)
			(xy 120.688862 -46.166786) (xy 120.832626 -46.292516)
		)
		(stroke
			(width 0)
			(type solid)
		)
		(fill yes)
		(layer "F.Cu")
		(net "M_H_DQ<53>")
	)
	(gr_poly
		(pts
			(xy 120.9167 -105.575608) (xy 120.952768 -105.539794) (xy 120.862852 -105.449878) (xy 120.827038 -105.485946)
			(xy 120.701308 -105.629456) (xy 120.77319 -105.701338)
		)
		(stroke
			(width 0)
			(type solid)
		)
		(fill yes)
		(layer "F.Cu")
		(net "M_L_DQS_DN<15>")
	)
	(gr_poly
		(pts
			(xy 120.924574 -108.369608) (xy 120.960642 -108.333794) (xy 120.870726 -108.243878) (xy 120.834912 -108.279946)
			(xy 120.709182 -108.423456) (xy 120.781064 -108.495338)
		)
		(stroke
			(width 0)
			(type solid)
		)
		(fill yes)
		(layer "F.Cu")
		(net "M_L_DQ<52>")
	)
	(gr_poly
		(pts
			(xy 120.924828 -43.74134) (xy 120.88876 -43.705526) (xy 120.74525 -43.579796) (xy 120.673368 -43.651678)
			(xy 120.799098 -43.795188) (xy 120.834912 -43.831256)
		)
		(stroke
			(width 0)
			(type solid)
		)
		(fill yes)
		(layer "F.Cu")
		(net "M_H_DQ<43>")
	)
	(gr_poly
		(pts
			(xy 120.94337 -106.016044) (xy 121.0691 -105.87228) (xy 120.997472 -105.800398) (xy 120.853708 -105.926128)
			(xy 120.81764 -105.961942) (xy 120.907556 -106.051858)
		)
		(stroke
			(width 0)
			(type solid)
		)
		(fill yes)
		(layer "F.Cu")
		(net "M_L_DQS_DP<15>")
	)
	(gr_poly
		(pts
			(xy 120.951244 -42.38498) (xy 120.825514 -42.241216) (xy 120.789446 -42.205402) (xy 120.699784 -42.295064)
			(xy 120.735598 -42.331132) (xy 120.879362 -42.456862)
		)
		(stroke
			(width 0)
			(type solid)
		)
		(fill yes)
		(layer "F.Cu")
		(net "M_H_DQ<46>")
	)
	(gr_poly
		(pts
			(xy 120.967754 -48.601122) (xy 120.93194 -48.565054) (xy 120.788176 -48.439324) (xy 120.716294 -48.511206)
			(xy 120.842024 -48.65497) (xy 120.878092 -48.690784)
		)
		(stroke
			(width 0)
			(type solid)
		)
		(fill yes)
		(layer "F.Cu")
		(net "M_H_DQS_DN<6>")
	)
	(gr_poly
		(pts
			(xy 120.976136 -45.80763) (xy 120.940322 -45.771562) (xy 120.796558 -45.645832) (xy 120.724676 -45.717714)
			(xy 120.850406 -45.861478) (xy 120.886474 -45.897292)
		)
		(stroke
			(width 0)
			(type solid)
		)
		(fill yes)
		(layer "F.Cu")
		(net "M_H_DQ<53>")
	)
	(gr_poly
		(pts
			(xy 120.994424 -47.244762) (xy 120.868694 -47.100998) (xy 120.83288 -47.06493) (xy 120.742964 -47.154846)
			(xy 120.778778 -47.19066) (xy 120.922542 -47.31639)
		)
		(stroke
			(width 0)
			(type solid)
		)
		(fill yes)
		(layer "F.Cu")
		(net "M_H_DQ<49>")
	)
	(gr_poly
		(pts
			(xy 121.014998 -107.34548) (xy 121.050812 -107.309412) (xy 120.96115 -107.21975) (xy 120.925082 -107.255564)
			(xy 120.799352 -107.399328) (xy 120.871234 -107.47121)
		)
		(stroke
			(width 0)
			(type solid)
		)
		(fill yes)
		(layer "F.Cu")
		(net "M_L_DQ<48>")
	)
	(gr_poly
		(pts
			(xy 121.018046 -112.2807) (xy 121.005346 -112.0902) (xy 120.903746 -112.0902) (xy 120.891046 -112.2807)
			(xy 120.891046 -112.3315) (xy 121.018046 -112.3315)
		)
		(stroke
			(width 0)
			(type solid)
		)
		(fill yes)
		(layer "F.Cu")
		(net "M_L_DQ<46>")
	)
	(gr_poly
		(pts
			(xy 121.018046 -111.887) (xy 121.005346 -111.6965) (xy 120.903746 -111.6965) (xy 120.891046 -111.887)
			(xy 120.891046 -111.9378) (xy 121.018046 -111.9378)
		)
		(stroke
			(width 0)
			(type solid)
		)
		(fill yes)
		(layer "F.Cu")
		(net "M_L_DQ<47>")
	)
	(gr_poly
		(pts
			(xy 121.018046 -111.4933) (xy 121.005346 -111.3028) (xy 120.903746 -111.3028) (xy 120.891046 -111.4933)
			(xy 120.891046 -111.5441) (xy 121.018046 -111.5441)
		)
		(stroke
			(width 0)
			(type solid)
		)
		(fill yes)
		(layer "F.Cu")
		(net "M_L_DQ<42>")
	)
	(gr_poly
		(pts
			(xy 121.018046 -111.0996) (xy 121.005346 -110.9091) (xy 120.903746 -110.9091) (xy 120.891046 -111.0996)
			(xy 120.891046 -111.1504) (xy 121.018046 -111.1504)
		)
		(stroke
			(width 0)
			(type solid)
		)
		(fill yes)
		(layer "F.Cu")
		(net "M_L_DQ<43>")
	)
	(gr_poly
		(pts
			(xy 121.041414 -107.785916) (xy 121.167144 -107.642152) (xy 121.095516 -107.57027) (xy 120.951752 -107.696)
			(xy 120.915684 -107.731814) (xy 121.0056 -107.82173)
		)
		(stroke
			(width 0)
			(type solid)
		)
		(fill yes)
		(layer "F.Cu")
		(net "M_L_DQ<53>")
	)
	(gr_poly
		(pts
			(xy 121.041414 -43.409108) (xy 120.915684 -43.265344) (xy 120.879616 -43.22953) (xy 120.789954 -43.319192)
			(xy 120.825768 -43.35526) (xy 120.969532 -43.48099)
		)
		(stroke
			(width 0)
			(type solid)
		)
		(fill yes)
		(layer "F.Cu")
		(net "M_H_DQ<42>")
	)
	(gr_poly
		(pts
			(xy 121.057924 -49.624996) (xy 121.021856 -49.589182) (xy 120.878346 -49.463452) (xy 120.806464 -49.535334)
			(xy 120.932194 -49.678844) (xy 120.968008 -49.714912)
		)
		(stroke
			(width 0)
			(type solid)
		)
		(fill yes)
		(layer "F.Cu")
		(net "M_H_DQ<54>")
	)
	(gr_poly
		(pts
			(xy 121.066306 -46.831504) (xy 121.030238 -46.79569) (xy 120.886728 -46.66996) (xy 120.814846 -46.741842)
			(xy 120.940576 -46.885352) (xy 120.97639 -46.92142)
		)
		(stroke
			(width 0)
			(type solid)
		)
		(fill yes)
		(layer "F.Cu")
		(net "M_H_DQ<49>")
	)
	(gr_poly
		(pts
			(xy 121.08434 -48.268636) (xy 120.95861 -48.124872) (xy 120.922796 -48.089058) (xy 120.83288 -48.178974)
			(xy 120.868948 -48.214788) (xy 121.012712 -48.340518)
		)
		(stroke
			(width 0)
			(type solid)
		)
		(fill yes)
		(layer "F.Cu")
		(net "M_H_DQS_DN<15>")
	)
	(gr_poly
		(pts
			(xy 121.092722 -45.475144) (xy 120.966992 -45.33138) (xy 120.931178 -45.295566) (xy 120.841262 -45.385482)
			(xy 120.87733 -45.421296) (xy 121.021094 -45.547026)
		)
		(stroke
			(width 0)
			(type solid)
		)
		(fill yes)
		(layer "F.Cu")
		(net "M_H_DQ<52>")
	)
	(gr_poly
		(pts
			(xy 121.105168 -106.321352) (xy 121.140982 -106.285284) (xy 121.05132 -106.195622) (xy 121.015252 -106.231436)
			(xy 120.889522 -106.3752) (xy 120.961404 -106.447082)
		)
		(stroke
			(width 0)
			(type solid)
		)
		(fill yes)
		(layer "F.Cu")
		(net "M_L_DQS_DP<15>")
	)
	(gr_poly
		(pts
			(xy 121.113296 -42.99585) (xy 121.077228 -42.960036) (xy 120.933718 -42.834306) (xy 120.861836 -42.906188)
			(xy 120.987566 -43.049698) (xy 121.02338 -43.085766)
		)
		(stroke
			(width 0)
			(type solid)
		)
		(fill yes)
		(layer "F.Cu")
		(net "M_H_DQ<42>")
	)
	(gr_poly
		(pts
			(xy 121.131838 -106.761534) (xy 121.257568 -106.61777) (xy 121.185686 -106.546142) (xy 121.041922 -106.671872)
			(xy 121.006108 -106.707686) (xy 121.09577 -106.797348)
		)
		(stroke
			(width 0)
			(type solid)
		)
		(fill yes)
		(layer "F.Cu")
		(net "M_L_DQ<49>")
	)
	(gr_poly
		(pts
			(xy 121.156476 -47.855632) (xy 121.120662 -47.819564) (xy 120.976898 -47.693834) (xy 120.905016 -47.765716)
			(xy 121.030746 -47.90948) (xy 121.066814 -47.945294)
		)
		(stroke
			(width 0)
			(type solid)
		)
		(fill yes)
		(layer "F.Cu")
		(net "M_H_DQS_DN<15>")
	)
	(gr_poly
		(pts
			(xy 121.164604 -45.06214) (xy 121.12879 -45.026072) (xy 120.985026 -44.900342) (xy 120.913144 -44.972224)
			(xy 121.038874 -45.115988) (xy 121.074942 -45.151802)
		)
		(stroke
			(width 0)
			(type solid)
		)
		(fill yes)
		(layer "F.Cu")
		(net "M_H_DQ<52>")
	)
	(gr_poly
		(pts
			(xy 121.17451 -49.292764) (xy 121.04878 -49.149) (xy 121.012966 -49.112932) (xy 120.92305 -49.202848)
			(xy 120.958864 -49.238662) (xy 121.102628 -49.364392)
		)
		(stroke
			(width 0)
			(type solid)
		)
		(fill yes)
		(layer "F.Cu")
		(net "M_H_DQS_DP<6>")
	)
	(gr_poly
		(pts
			(xy 121.182892 -46.499272) (xy 121.057162 -46.355508) (xy 121.021094 -46.319694) (xy 120.931432 -46.409356)
			(xy 120.967246 -46.44517) (xy 121.11101 -46.5709)
		)
		(stroke
			(width 0)
			(type solid)
		)
		(fill yes)
		(layer "F.Cu")
		(net "M_H_DQ<48>")
	)
	(gr_poly
		(pts
			(xy 121.203212 -108.091224) (xy 121.239026 -108.055156) (xy 121.149364 -107.965494) (xy 121.113296 -108.001308)
			(xy 120.987566 -108.145072) (xy 121.059448 -108.216954)
		)
		(stroke
			(width 0)
			(type solid)
		)
		(fill yes)
		(layer "F.Cu")
		(net "M_L_DQ<53>")
	)
	(gr_poly
		(pts
			(xy 121.222008 -105.737406) (xy 121.347738 -105.593642) (xy 121.27611 -105.52176) (xy 121.132346 -105.64749)
			(xy 121.096278 -105.683304) (xy 121.186194 -105.77322)
		)
		(stroke
			(width 0)
			(type solid)
		)
		(fill yes)
		(layer "F.Cu")
		(net "M_L_DQS_DN<15>")
	)
	(gr_poly
		(pts
			(xy 121.229628 -42.663364) (xy 121.103898 -42.5196) (xy 121.068084 -42.483786) (xy 120.978168 -42.573702)
			(xy 121.014236 -42.609516) (xy 121.157746 -42.735246)
		)
		(stroke
			(width 0)
			(type solid)
		)
		(fill yes)
		(layer "F.Cu")
		(net "M_H_DQ<47>")
	)
	(gr_poly
		(pts
			(xy 121.232168 -52.631594) (xy 121.402348 -52.542694) (xy 121.402348 -52.321714) (xy 121.232168 -52.232814)
			(xy 121.187972 -52.232814) (xy 121.187718 -52.631848)
		)
		(stroke
			(width 0)
			(type solid)
		)
		(fill yes)
		(layer "F.Cu")
		(net "M_H_DQ<51>")
	)
	(gr_poly
		(pts
			(xy 121.245884 -101.277674) (xy 121.201434 -101.277674) (xy 121.031254 -101.366574) (xy 121.031254 -101.587554)
			(xy 121.201434 -101.676454) (xy 121.245884 -101.676454)
		)
		(stroke
			(width 0)
			(type solid)
		)
		(fill yes)
		(layer "F.Cu")
		(net "M_L_DQ<54>")
	)
	(gr_poly
		(pts
			(xy 121.246392 -48.879506) (xy 121.210324 -48.843692) (xy 121.066814 -48.717962) (xy 120.994932 -48.789844)
			(xy 121.120662 -48.933354) (xy 121.156476 -48.969422)
		)
		(stroke
			(width 0)
			(type solid)
		)
		(fill yes)
		(layer "F.Cu")
		(net "M_H_DQS_DP<6>")
	)
	(gr_poly
		(pts
			(xy 121.254774 -46.086014) (xy 121.218706 -46.0502) (xy 121.075196 -45.92447) (xy 121.003314 -45.996352)
			(xy 121.129044 -46.139862) (xy 121.164858 -46.17593)
		)
		(stroke
			(width 0)
			(type solid)
		)
		(fill yes)
		(layer "F.Cu")
		(net "M_H_DQ<48>")
	)
	(gr_poly
		(pts
			(xy 121.272808 -47.5234) (xy 121.147078 -47.379636) (xy 121.111264 -47.343568) (xy 121.021348 -47.433484)
			(xy 121.057162 -47.469298) (xy 121.200926 -47.595028)
		)
		(stroke
			(width 0)
			(type solid)
		)
		(fill yes)
		(layer "F.Cu")
		(net "M_H_DQS_DP<15>")
	)
	(gr_poly
		(pts
			(xy 121.293382 -107.066842) (xy 121.32945 -107.031028) (xy 121.239534 -106.941112) (xy 121.20372 -106.97718)
			(xy 121.07799 -107.12069) (xy 121.149872 -107.192572)
		)
		(stroke
			(width 0)
			(type solid)
		)
		(fill yes)
		(layer "F.Cu")
		(net "M_L_DQ<49>")
	)
	(gr_poly
		(pts
			(xy 121.319798 -43.687492) (xy 121.194068 -43.543728) (xy 121.158254 -43.507914) (xy 121.068338 -43.59783)
			(xy 121.104406 -43.633644) (xy 121.247916 -43.759374)
		)
		(stroke
			(width 0)
			(type solid)
		)
		(fill yes)
		(layer "F.Cu")
		(net "M_H_DQ<43>")
	)
	(gr_poly
		(pts
			(xy 121.320306 -107.507024) (xy 121.446036 -107.36326) (xy 121.374154 -107.291632) (xy 121.23039 -107.417108)
			(xy 121.194576 -107.453176) (xy 121.284238 -107.542838)
		)
		(stroke
			(width 0)
			(type solid)
		)
		(fill yes)
		(layer "F.Cu")
		(net "M_L_DQ<48>")
	)
	(gr_poly
		(pts
			(xy 121.344944 -47.110142) (xy 121.308876 -47.074328) (xy 121.165366 -46.948598) (xy 121.093484 -47.02048)
			(xy 121.219214 -47.16399) (xy 121.255028 -47.200058)
		)
		(stroke
			(width 0)
			(type solid)
		)
		(fill yes)
		(layer "F.Cu")
		(net "M_H_DQS_DP<15>")
	)
	(gr_poly
		(pts
			(xy 121.348246 -112.3823) (xy 121.348246 -112.3315) (xy 121.221246 -112.3315) (xy 121.221246 -112.3823)
			(xy 121.233946 -112.5728) (xy 121.335546 -112.5728)
		)
		(stroke
			(width 0)
			(type solid)
		)
		(fill yes)
		(layer "F.Cu")
		(net "M_L_DQ<46>")
	)
	(gr_poly
		(pts
			(xy 121.348246 -111.9886) (xy 121.348246 -111.9378) (xy 121.221246 -111.9378) (xy 121.221246 -111.9886)
			(xy 121.233946 -112.1791) (xy 121.335546 -112.1791)
		)
		(stroke
			(width 0)
			(type solid)
		)
		(fill yes)
		(layer "F.Cu")
		(net "M_L_DQ<47>")
	)
	(gr_poly
		(pts
			(xy 121.348246 -111.5949) (xy 121.348246 -111.5441) (xy 121.221246 -111.5441) (xy 121.221246 -111.5949)
			(xy 121.233946 -111.7854) (xy 121.335546 -111.7854)
		)
		(stroke
			(width 0)
			(type solid)
		)
		(fill yes)
		(layer "F.Cu")
		(net "M_L_DQ<42>")
	)
	(gr_poly
		(pts
			(xy 121.348246 -111.2012) (xy 121.348246 -111.1504) (xy 121.221246 -111.1504) (xy 121.221246 -111.2012)
			(xy 121.233946 -111.3917) (xy 121.335546 -111.3917)
		)
		(stroke
			(width 0)
			(type solid)
		)
		(fill yes)
		(layer "F.Cu")
		(net "M_L_DQ<43>")
	)
	(gr_poly
		(pts
			(xy 121.362978 -48.547274) (xy 121.237248 -48.40351) (xy 121.201434 -48.367442) (xy 121.111518 -48.457358)
			(xy 121.147332 -48.493172) (xy 121.291096 -48.618902)
		)
		(stroke
			(width 0)
			(type solid)
		)
		(fill yes)
		(layer "F.Cu")
		(net "M_H_DQS_DN<6>")
	)
	(gr_poly
		(pts
			(xy 121.37136 -45.753782) (xy 121.24563 -45.610018) (xy 121.209562 -45.574204) (xy 121.1199 -45.663866)
			(xy 121.155714 -45.699934) (xy 121.299478 -45.82541)
		)
		(stroke
			(width 0)
			(type solid)
		)
		(fill yes)
		(layer "F.Cu")
		(net "M_H_DQ<53>")
	)
	(gr_poly
		(pts
			(xy 121.383806 -106.042714) (xy 121.41962 -106.006646) (xy 121.329958 -105.916984) (xy 121.29389 -105.952798)
			(xy 121.16816 -106.096562) (xy 121.240042 -106.168444)
		)
		(stroke
			(width 0)
			(type solid)
		)
		(fill yes)
		(layer "F.Cu")
		(net "M_L_DQS_DN<15>")
	)
	(gr_poly
		(pts
			(xy 121.39168 -43.274488) (xy 121.355866 -43.23842) (xy 121.212102 -43.11269) (xy 121.14022 -43.184572)
			(xy 121.26595 -43.328336) (xy 121.302018 -43.36415)
		)
		(stroke
			(width 0)
			(type solid)
		)
		(fill yes)
		(layer "F.Cu")
		(net "M_H_DQ<43>")
	)
	(gr_poly
		(pts
			(xy 121.410476 -106.482896) (xy 121.536206 -106.339132) (xy 121.464324 -106.267504) (xy 121.32056 -106.393234)
			(xy 121.284746 -106.429048) (xy 121.374408 -106.51871)
		)
		(stroke
			(width 0)
			(type solid)
		)
		(fill yes)
		(layer "F.Cu")
		(net "M_L_DQS_DP<15>")
	)
	(gr_poly
		(pts
			(xy 121.43486 -48.134016) (xy 121.398792 -48.098202) (xy 121.255282 -47.972472) (xy 121.1834 -48.044354)
			(xy 121.30913 -48.187864) (xy 121.344944 -48.223932)
		)
		(stroke
			(width 0)
			(type solid)
		)
		(fill yes)
		(layer "F.Cu")
		(net "M_H_DQS_DN<6>")
	)
	(gr_poly
		(pts
			(xy 121.443242 -45.340524) (xy 121.407174 -45.30471) (xy 121.263664 -45.17898) (xy 121.191782 -45.250862)
			(xy 121.317512 -45.394372) (xy 121.353326 -45.43044)
		)
		(stroke
			(width 0)
			(type solid)
		)
		(fill yes)
		(layer "F.Cu")
		(net "M_H_DQ<53>")
	)
	(gr_poly
		(pts
			(xy 121.452894 -49.571148) (xy 121.327164 -49.427384) (xy 121.29135 -49.39157) (xy 121.201688 -49.481232)
			(xy 121.237502 -49.5173) (xy 121.381266 -49.64303)
		)
		(stroke
			(width 0)
			(type solid)
		)
		(fill yes)
		(layer "F.Cu")
		(net "M_H_DQ<54>")
	)
	(gr_poly
		(pts
			(xy 121.461276 -46.777656) (xy 121.335546 -46.633892) (xy 121.299732 -46.598078) (xy 121.209816 -46.687994)
			(xy 121.245884 -46.723808) (xy 121.389648 -46.849538)
		)
		(stroke
			(width 0)
			(type solid)
		)
		(fill yes)
		(layer "F.Cu")
		(net "M_H_DQ<49>")
	)
	(gr_poly
		(pts
			(xy 121.473976 -50.477166) (xy 121.429526 -50.477166) (xy 121.259346 -50.566066) (xy 121.259346 -50.787046)
			(xy 121.429526 -50.875946) (xy 121.473976 -50.875946)
		)
		(stroke
			(width 0)
			(type solid)
		)
		(fill yes)
		(layer "F.Cu")
		(net "M_H_DQ<50>")
	)
	(gr_poly
		(pts
			(xy 121.48185 -107.812332) (xy 121.517918 -107.776518) (xy 121.428002 -107.686602) (xy 121.392188 -107.72267)
			(xy 121.266458 -107.86618) (xy 121.33834 -107.938062)
		)
		(stroke
			(width 0)
			(type solid)
		)
		(fill yes)
		(layer "F.Cu")
		(net "M_L_DQ<48>")
	)
	(gr_poly
		(pts
			(xy 121.500646 -105.458768) (xy 121.626376 -105.315004) (xy 121.554748 -105.243122) (xy 121.410984 -105.368852)
			(xy 121.374916 -105.404666) (xy 121.464832 -105.494582)
		)
		(stroke
			(width 0)
			(type solid)
		)
		(fill yes)
		(layer "F.Cu")
		(net "M_L_DQS_DN<6>")
	)
	(gr_poly
		(pts
			(xy 121.508266 -42.942002) (xy 121.382536 -42.798492) (xy 121.346722 -42.762424) (xy 121.256806 -42.85234)
			(xy 121.292874 -42.888154) (xy 121.436384 -43.013884)
		)
		(stroke
			(width 0)
			(type solid)
		)
		(fill yes)
		(layer "F.Cu")
		(net "M_H_DQ<42>")
	)
	(gr_poly
		(pts
			(xy 121.509028 -108.572554) (xy 121.496328 -108.382054) (xy 121.394728 -108.382054) (xy 121.382028 -108.572554)
			(xy 121.382028 -108.623354) (xy 121.509028 -108.623354)
		)
		(stroke
			(width 0)
			(type solid)
		)
		(fill yes)
		(layer "F.Cu")
		(net "M_L_DQ<52>")
	)
	(gr_poly
		(pts
			(xy 121.524776 -49.158144) (xy 121.488962 -49.122076) (xy 121.345198 -48.996346) (xy 121.273316 -49.068228)
			(xy 121.399046 -49.211992) (xy 121.435114 -49.247806)
		)
		(stroke
			(width 0)
			(type solid)
		)
		(fill yes)
		(layer "F.Cu")
		(net "M_H_DQ<54>")
	)
	(gr_poly
		(pts
			(xy 121.533158 -46.364652) (xy 121.497344 -46.328584) (xy 121.35358 -46.202854) (xy 121.281698 -46.274736)
			(xy 121.407428 -46.4185) (xy 121.443496 -46.454314)
		)
		(stroke
			(width 0)
			(type solid)
		)
		(fill yes)
		(layer "F.Cu")
		(net "M_H_DQ<49>")
	)
	(gr_poly
		(pts
			(xy 121.551446 -47.801784) (xy 121.425716 -47.65802) (xy 121.389902 -47.621952) (xy 121.299986 -47.711868)
			(xy 121.3358 -47.747682) (xy 121.479564 -47.873412)
		)
		(stroke
			(width 0)
			(type solid)
		)
		(fill yes)
		(layer "F.Cu")
		(net "M_H_DQS_DN<15>")
	)
	(gr_poly
		(pts
			(xy 121.559828 -45.008292) (xy 121.434098 -44.864528) (xy 121.39803 -44.828714) (xy 121.308368 -44.918376)
			(xy 121.344182 -44.954444) (xy 121.487946 -45.080174)
		)
		(stroke
			(width 0)
			(type solid)
		)
		(fill yes)
		(layer "F.Cu")
		(net "M_H_DQ<52>")
	)
	(gr_poly
		(pts
			(xy 121.57202 -106.788204) (xy 121.608088 -106.75239) (xy 121.518172 -106.662474) (xy 121.482358 -106.698542)
			(xy 121.356628 -106.842052) (xy 121.42851 -106.913934)
		)
		(stroke
			(width 0)
			(type solid)
		)
		(fill yes)
		(layer "F.Cu")
		(net "M_L_DQS_DP<15>")
	)
	(gr_poly
		(pts
			(xy 121.580402 -42.528998) (xy 121.544334 -42.493184) (xy 121.400824 -42.367454) (xy 121.328942 -42.439336)
			(xy 121.454672 -42.582846) (xy 121.490486 -42.618914)
		)
		(stroke
			(width 0)
			(type solid)
		)
		(fill yes)
		(layer "F.Cu")
		(net "M_H_DQ<42>")
	)
	(gr_poly
		(pts
			(xy 121.593356 -102.071678) (xy 121.593356 -101.850698) (xy 121.423176 -101.761798) (xy 121.378726 -101.761798)
			(xy 121.378726 -102.160578) (xy 121.423176 -102.160578)
		)
		(stroke
			(width 0)
			(type solid)
		)
		(fill yes)
		(layer "F.Cu")
		(net "M_L_DQ<54>")
	)
	(gr_poly
		(pts
			(xy 121.59869 -107.22864) (xy 121.72442 -107.084876) (xy 121.652792 -107.012994) (xy 121.509028 -107.138724)
			(xy 121.47296 -107.174538) (xy 121.562876 -107.264454)
		)
		(stroke
			(width 0)
			(type solid)
		)
		(fill yes)
		(layer "F.Cu")
		(net "M_L_DQ<49>")
	)
	(gr_poly
		(pts
			(xy 121.623328 -47.388526) (xy 121.58726 -47.352712) (xy 121.44375 -47.226982) (xy 121.371868 -47.298864)
			(xy 121.497598 -47.442374) (xy 121.533412 -47.478442)
		)
		(stroke
			(width 0)
			(type solid)
		)
		(fill yes)
		(layer "F.Cu")
		(net "M_H_DQS_DN<15>")
	)
	(gr_poly
		(pts
			(xy 121.63171 -44.595034) (xy 121.595642 -44.55922) (xy 121.452132 -44.43349) (xy 121.38025 -44.505372)
			(xy 121.50598 -44.648882) (xy 121.541794 -44.68495)
		)
		(stroke
			(width 0)
			(type solid)
		)
		(fill yes)
		(layer "F.Cu")
		(net "M_H_DQ<52>")
	)
	(gr_poly
		(pts
			(xy 121.641362 -48.825658) (xy 121.515632 -48.681894) (xy 121.479818 -48.64608) (xy 121.389902 -48.735996)
			(xy 121.42597 -48.77181) (xy 121.569734 -48.89754)
		)
		(stroke
			(width 0)
			(type solid)
		)
		(fill yes)
		(layer "F.Cu")
		(net "M_H_DQS_DP<6>")
	)
	(gr_poly
		(pts
			(xy 121.649744 -46.032166) (xy 121.524014 -45.888402) (xy 121.4882 -45.852588) (xy 121.398284 -45.942504)
			(xy 121.434352 -45.978318) (xy 121.578116 -46.104048)
		)
		(stroke
			(width 0)
			(type solid)
		)
		(fill yes)
		(layer "F.Cu")
		(net "M_H_DQ<48>")
	)
	(gr_poly
		(pts
			(xy 121.662444 -105.764076) (xy 121.698258 -105.728008) (xy 121.608596 -105.638346) (xy 121.572528 -105.67416)
			(xy 121.446798 -105.817924) (xy 121.51868 -105.889806)
		)
		(stroke
			(width 0)
			(type solid)
		)
		(fill yes)
		(layer "F.Cu")
		(net "M_L_DQS_DN<6>")
	)
	(gr_poly
		(pts
			(xy 121.678446 -111.887) (xy 121.665746 -111.6965) (xy 121.564146 -111.6965) (xy 121.551446 -111.887)
			(xy 121.551446 -111.9378) (xy 121.678446 -111.9378)
		)
		(stroke
			(width 0)
			(type solid)
		)
		(fill yes)
		(layer "F.Cu")
		(net "M_L_DQ<47>")
	)
	(gr_poly
		(pts
			(xy 121.678446 -111.4933) (xy 121.665746 -111.3028) (xy 121.564146 -111.3028) (xy 121.551446 -111.4933)
			(xy 121.551446 -111.5441) (xy 121.678446 -111.5441)
		)
		(stroke
			(width 0)
			(type solid)
		)
		(fill yes)
		(layer "F.Cu")
		(net "M_L_DQ<42>")
	)
	(gr_poly
		(pts
			(xy 121.678446 -111.0996) (xy 121.665746 -110.9091) (xy 121.564146 -110.9091) (xy 121.551446 -111.0996)
			(xy 121.551446 -111.1504) (xy 121.678446 -111.1504)
		)
		(stroke
			(width 0)
			(type solid)
		)
		(fill yes)
		(layer "F.Cu")
		(net "M_L_DQ<43>")
	)
	(gr_poly
		(pts
			(xy 121.688098 -104.337358) (xy 121.813828 -104.193594) (xy 121.741946 -104.121966) (xy 121.598182 -104.247696)
			(xy 121.562368 -104.28351) (xy 121.652284 -104.373426)
		)
		(stroke
			(width 0)
			(type solid)
		)
		(fill yes)
		(layer "F.Cu")
		(net "M_L_DQ<54>")
	)
	(gr_poly
		(pts
			(xy 121.689114 -106.204258) (xy 121.814844 -106.060494) (xy 121.742962 -105.988866) (xy 121.599198 -106.114596)
			(xy 121.563384 -106.15041) (xy 121.653046 -106.240072)
		)
		(stroke
			(width 0)
			(type solid)
		)
		(fill yes)
		(layer "F.Cu")
		(net "M_L_DQS_DN<15>")
	)
	(gr_poly
		(pts
			(xy 121.713244 -48.412654) (xy 121.67743 -48.376586) (xy 121.533666 -48.250856) (xy 121.461784 -48.322738)
			(xy 121.587514 -48.466502) (xy 121.623582 -48.502316)
		)
		(stroke
			(width 0)
			(type solid)
		)
		(fill yes)
		(layer "F.Cu")
		(net "M_H_DQS_DP<6>")
	)
	(gr_poly
		(pts
			(xy 121.721626 -45.619162) (xy 121.685812 -45.583094) (xy 121.542048 -45.457364) (xy 121.470166 -45.529246)
			(xy 121.595896 -45.67301) (xy 121.631964 -45.708824)
		)
		(stroke
			(width 0)
			(type solid)
		)
		(fill yes)
		(layer "F.Cu")
		(net "M_H_DQ<48>")
	)
	(gr_poly
		(pts
			(xy 121.731532 -49.849786) (xy 121.605802 -49.706022) (xy 121.569988 -49.669954) (xy 121.480072 -49.75987)
			(xy 121.515886 -49.795684) (xy 121.65965 -49.921414)
		)
		(stroke
			(width 0)
			(type solid)
		)
		(fill yes)
		(layer "F.Cu")
		(net "M_H_DQ<55>")
	)
	(gr_poly
		(pts
			(xy 121.73966 -47.056294) (xy 121.61393 -46.91253) (xy 121.578116 -46.876716) (xy 121.4882 -46.966632)
			(xy 121.524268 -47.002446) (xy 121.668032 -47.128176)
		)
		(stroke
			(width 0)
			(type solid)
		)
		(fill yes)
		(layer "F.Cu")
		(net "M_H_DQS_DP<15>")
	)
	(gr_poly
		(pts
			(xy 121.779284 -105.18013) (xy 121.905014 -105.036366) (xy 121.833386 -104.964484) (xy 121.689622 -105.090214)
			(xy 121.653554 -105.126028) (xy 121.74347 -105.215944)
		)
		(stroke
			(width 0)
			(type solid)
		)
		(fill yes)
		(layer "F.Cu")
		(net "M_L_DQS_DP<6>")
	)
	(gr_poly
		(pts
			(xy 121.786904 -43.22064) (xy 121.661174 -43.076876) (xy 121.625106 -43.041062) (xy 121.535444 -43.130724)
			(xy 121.571258 -43.166792) (xy 121.715022 -43.292522)
		)
		(stroke
			(width 0)
			(type solid)
		)
		(fill yes)
		(layer "F.Cu")
		(net "M_H_DQ<43>")
	)
	(gr_poly
		(pts
			(xy 121.803414 -49.436528) (xy 121.767346 -49.400714) (xy 121.623836 -49.274984) (xy 121.551954 -49.346866)
			(xy 121.677684 -49.490376) (xy 121.713498 -49.526444)
		)
		(stroke
			(width 0)
			(type solid)
		)
		(fill yes)
		(layer "F.Cu")
		(net "M_H_DQ<55>")
	)
	(gr_poly
		(pts
			(xy 121.811796 -46.64329) (xy 121.775982 -46.607222) (xy 121.632218 -46.481492) (xy 121.560336 -46.553374)
			(xy 121.686066 -46.697138) (xy 121.722134 -46.732952)
		)
		(stroke
			(width 0)
			(type solid)
		)
		(fill yes)
		(layer "F.Cu")
		(net "M_H_DQS_DP<15>")
	)
	(gr_poly
		(pts
			(xy 121.82983 -48.080168) (xy 121.7041 -47.936404) (xy 121.668286 -47.90059) (xy 121.57837 -47.990506)
			(xy 121.614438 -48.02632) (xy 121.758202 -48.15205)
		)
		(stroke
			(width 0)
			(type solid)
		)
		(fill yes)
		(layer "F.Cu")
		(net "M_H_DQS_DN<6>")
	)
	(gr_poly
		(pts
			(xy 121.838212 -45.286676) (xy 121.712482 -45.142912) (xy 121.676668 -45.107098) (xy 121.586752 -45.197014)
			(xy 121.62282 -45.232828) (xy 121.766584 -45.358558)
		)
		(stroke
			(width 0)
			(type solid)
		)
		(fill yes)
		(layer "F.Cu")
		(net "M_H_DQ<53>")
	)
	(gr_poly
		(pts
			(xy 121.839228 -108.674154) (xy 121.839228 -108.623354) (xy 121.712228 -108.623354) (xy 121.712228 -108.674154)
			(xy 121.724928 -108.864654) (xy 121.826528 -108.864654)
		)
		(stroke
			(width 0)
			(type solid)
		)
		(fill yes)
		(layer "F.Cu")
		(net "M_L_DQ<52>")
	)
	(gr_poly
		(pts
			(xy 121.839228 -108.280454) (xy 121.839228 -108.229654) (xy 121.712228 -108.229654) (xy 121.712228 -108.280454)
			(xy 121.724928 -108.470954) (xy 121.826528 -108.470954)
		)
		(stroke
			(width 0)
			(type solid)
		)
		(fill yes)
		(layer "F.Cu")
		(net "M_L_DQ<53>")
	)
	(gr_poly
		(pts
			(xy 121.839228 -107.886754) (xy 121.839228 -107.835954) (xy 121.712228 -107.835954) (xy 121.712228 -107.886754)
			(xy 121.724928 -108.077254) (xy 121.826528 -108.077254)
		)
		(stroke
			(width 0)
			(type solid)
		)
		(fill yes)
		(layer "F.Cu")
		(net "M_L_DQ<48>")
	)
	(gr_poly
		(pts
			(xy 121.849642 -104.642666) (xy 121.88571 -104.606852) (xy 121.795794 -104.516936) (xy 121.75998 -104.553004)
			(xy 121.63425 -104.696514) (xy 121.706132 -104.768396)
		)
		(stroke
			(width 0)
			(type solid)
		)
		(fill yes)
		(layer "F.Cu")
		(net "M_L_DQ<54>")
	)
	(gr_poly
		(pts
			(xy 121.850658 -106.509566) (xy 121.886726 -106.473752) (xy 121.79681 -106.383836) (xy 121.760996 -106.419904)
			(xy 121.635266 -106.563414) (xy 121.707148 -106.635296)
		)
		(stroke
			(width 0)
			(type solid)
		)
		(fill yes)
		(layer "F.Cu")
		(net "M_L_DQS_DN<15>")
	)
	(gr_poly
		(pts
			(xy 121.858786 -42.807636) (xy 121.822972 -42.771568) (xy 121.679208 -42.645838) (xy 121.607326 -42.71772)
			(xy 121.733056 -42.861484) (xy 121.769124 -42.897298)
		)
		(stroke
			(width 0)
			(type solid)
		)
		(fill yes)
		(layer "F.Cu")
		(net "M_H_DQ<43>")
	)
	(gr_poly
		(pts
			(xy 121.879106 -51.009042) (xy 121.879106 -50.788062) (xy 121.708926 -50.699162) (xy 121.664476 -50.699162)
			(xy 121.664476 -51.097942) (xy 121.708926 -51.097942)
		)
		(stroke
			(width 0)
			(type solid)
		)
		(fill yes)
		(layer "F.Cu")
		(net "M_H_DQ<51>")
	)
	(gr_poly
		(pts
			(xy 121.901712 -47.667164) (xy 121.865898 -47.631096) (xy 121.722134 -47.505366) (xy 121.650252 -47.577248)
			(xy 121.775982 -47.721012) (xy 121.81205 -47.756826)
		)
		(stroke
			(width 0)
			(type solid)
		)
		(fill yes)
		(layer "F.Cu")
		(net "M_H_DQS_DN<6>")
	)
	(gr_poly
		(pts
			(xy 121.910094 -44.873672) (xy 121.87428 -44.837604) (xy 121.730516 -44.711874) (xy 121.658634 -44.783756)
			(xy 121.784364 -44.92752) (xy 121.820432 -44.963334)
		)
		(stroke
			(width 0)
			(type solid)
		)
		(fill yes)
		(layer "F.Cu")
		(net "M_H_DQ<53>")
	)
	(gr_poly
		(pts
			(xy 121.914158 -101.746812) (xy 121.869708 -101.746812) (xy 121.699528 -101.835712) (xy 121.699274 -102.056692)
			(xy 121.869708 -102.145338) (xy 121.913904 -102.145592)
		)
		(stroke
			(width 0)
			(type solid)
		)
		(fill yes)
		(layer "F.Cu")
		(net "M_L_DQ<50>")
	)
	(gr_poly
		(pts
			(xy 121.92 -49.104296) (xy 121.79427 -48.960532) (xy 121.758456 -48.924464) (xy 121.66854 -49.01438)
			(xy 121.704354 -49.050194) (xy 121.848118 -49.175924)
		)
		(stroke
			(width 0)
			(type solid)
		)
		(fill yes)
		(layer "F.Cu")
		(net "M_H_DQ<54>")
	)
	(gr_poly
		(pts
			(xy 121.928382 -46.310804) (xy 121.802652 -46.16704) (xy 121.766584 -46.131226) (xy 121.676922 -46.220888)
			(xy 121.712736 -46.256956) (xy 121.8565 -46.382432)
		)
		(stroke
			(width 0)
			(type solid)
		)
		(fill yes)
		(layer "F.Cu")
		(net "M_H_DQ<49>")
	)
	(gr_poly
		(pts
			(xy 121.941082 -105.485438) (xy 121.976896 -105.44937) (xy 121.887234 -105.359708) (xy 121.851166 -105.395522)
			(xy 121.725436 -105.539286) (xy 121.797318 -105.611168)
		)
		(stroke
			(width 0)
			(type solid)
		)
		(fill yes)
		(layer "F.Cu")
		(net "M_L_DQS_DP<6>")
	)
	(gr_poly
		(pts
			(xy 121.966482 -104.058974) (xy 122.092212 -103.91521) (xy 122.020584 -103.843328) (xy 121.87682 -103.969058)
			(xy 121.840752 -104.004872) (xy 121.930668 -104.094788)
		)
		(stroke
			(width 0)
			(type solid)
		)
		(fill yes)
		(layer "F.Cu")
		(net "M_L_DQ<55>")
	)
	(gr_poly
		(pts
			(xy 121.967752 -105.92562) (xy 122.093482 -105.781856) (xy 122.0216 -105.710228) (xy 121.877836 -105.835958)
			(xy 121.842022 -105.871772) (xy 121.931684 -105.961434)
		)
		(stroke
			(width 0)
			(type solid)
		)
		(fill yes)
		(layer "F.Cu")
		(net "M_L_DQS_DN<6>")
	)
	(gr_poly
		(pts
			(xy 121.975372 -42.47515) (xy 121.849642 -42.33164) (xy 121.813828 -42.295572) (xy 121.723912 -42.385488)
			(xy 121.75998 -42.421302) (xy 121.90349 -42.547032)
		)
		(stroke
			(width 0)
			(type solid)
		)
		(fill yes)
		(layer "F.Cu")
		(net "M_H_DQ<42>")
	)
	(gr_poly
		(pts
			(xy 121.991882 -48.691038) (xy 121.955814 -48.655224) (xy 121.812304 -48.529494) (xy 121.740422 -48.601376)
			(xy 121.866152 -48.744886) (xy 121.901966 -48.780954)
		)
		(stroke
			(width 0)
			(type solid)
		)
		(fill yes)
		(layer "F.Cu")
		(net "M_H_DQ<54>")
	)
	(gr_poly
		(pts
			(xy 122.000264 -45.897546) (xy 121.964196 -45.861732) (xy 121.820686 -45.736002) (xy 121.748804 -45.807884)
			(xy 121.874534 -45.951394) (xy 121.910348 -45.987462)
		)
		(stroke
			(width 0)
			(type solid)
		)
		(fill yes)
		(layer "F.Cu")
		(net "M_H_DQ<49>")
	)
	(gr_poly
		(pts
			(xy 122.00509 -44.451524) (xy 122.00509 -44.400724) (xy 121.87809 -44.400724) (xy 121.87809 -44.451524)
			(xy 121.89079 -44.642024) (xy 121.99239 -44.642024)
		)
		(stroke
			(width 0)
			(type solid)
		)
		(fill yes)
		(layer "F.Cu")
		(net "M_H_DQ<52>")
	)
	(gr_poly
		(pts
			(xy 122.009916 -50.12817) (xy 121.884186 -49.984406) (xy 121.848372 -49.948592) (xy 121.75871 -50.038254)
			(xy 121.794524 -50.074322) (xy 121.938288 -50.200052)
		)
		(stroke
			(width 0)
			(type solid)
		)
		(fill yes)
		(layer "F.Cu")
		(net "M_H_DQ<50>")
	)
	(gr_poly
		(pts
			(xy 122.018298 -47.334678) (xy 121.892568 -47.190914) (xy 121.856754 -47.1551) (xy 121.766838 -47.245016)
			(xy 121.802906 -47.28083) (xy 121.94667 -47.40656)
		)
		(stroke
			(width 0)
			(type solid)
		)
		(fill yes)
		(layer "F.Cu")
		(net "M_H_DQS_DN<15>")
	)
	(gr_poly
		(pts
			(xy 122.081798 -49.715166) (xy 122.045984 -49.679098) (xy 121.90222 -49.553368) (xy 121.830338 -49.62525)
			(xy 121.956068 -49.769014) (xy 121.992136 -49.804828)
		)
		(stroke
			(width 0)
			(type solid)
		)
		(fill yes)
		(layer "F.Cu")
		(net "M_H_DQ<50>")
	)
	(gr_poly
		(pts
			(xy 122.090434 -46.921674) (xy 122.05462 -46.885606) (xy 121.910856 -46.759876) (xy 121.838974 -46.831758)
			(xy 121.964704 -46.975522) (xy 122.000772 -47.011336)
		)
		(stroke
			(width 0)
			(type solid)
		)
		(fill yes)
		(layer "F.Cu")
		(net "M_H_DQS_DN<15>")
	)
	(gr_poly
		(pts
			(xy 122.108468 -48.358806) (xy 121.982738 -48.215042) (xy 121.946924 -48.178974) (xy 121.857008 -48.26889)
			(xy 121.892822 -48.304704) (xy 122.036586 -48.430434)
		)
		(stroke
			(width 0)
			(type solid)
		)
		(fill yes)
		(layer "F.Cu")
		(net "M_H_DQS_DP<6>")
	)
	(gr_poly
		(pts
			(xy 122.11685 -45.565314) (xy 121.99112 -45.42155) (xy 121.955052 -45.385736) (xy 121.86539 -45.475398)
			(xy 121.901204 -45.511466) (xy 122.044968 -45.637196)
		)
		(stroke
			(width 0)
			(type solid)
		)
		(fill yes)
		(layer "F.Cu")
		(net "M_H_DQ<48>")
	)
	(gr_poly
		(pts
			(xy 122.12828 -104.364282) (xy 122.164094 -104.328214) (xy 122.074432 -104.238552) (xy 122.038364 -104.274366)
			(xy 121.912634 -104.41813) (xy 121.984516 -104.490012)
		)
		(stroke
			(width 0)
			(type solid)
		)
		(fill yes)
		(layer "F.Cu")
		(net "M_L_DQ<55>")
	)
	(gr_poly
		(pts
			(xy 122.129296 -106.230928) (xy 122.165364 -106.195114) (xy 122.075448 -106.105198) (xy 122.039634 -106.141266)
			(xy 121.913904 -106.284776) (xy 121.985786 -106.356658)
		)
		(stroke
			(width 0)
			(type solid)
		)
		(fill yes)
		(layer "F.Cu")
		(net "M_L_DQS_DN<6>")
	)
	(gr_poly
		(pts
			(xy 122.15495 -104.804464) (xy 122.28068 -104.6607) (xy 122.209052 -104.588818) (xy 122.065288 -104.714548)
			(xy 122.02922 -104.750362) (xy 122.119136 -104.840278)
		)
		(stroke
			(width 0)
			(type solid)
		)
		(fill yes)
		(layer "F.Cu")
		(net "M_L_DQ<54>")
	)
	(gr_poly
		(pts
			(xy 122.169428 -108.572554) (xy 122.156728 -108.382054) (xy 122.055128 -108.382054) (xy 122.042428 -108.572554)
			(xy 122.042428 -108.623354) (xy 122.169428 -108.623354)
		)
		(stroke
			(width 0)
			(type solid)
		)
		(fill yes)
		(layer "F.Cu")
		(net "M_L_DQ<52>")
	)
	(gr_poly
		(pts
			(xy 122.169428 -108.178854) (xy 122.156728 -107.988354) (xy 122.055128 -107.988354) (xy 122.042428 -108.178854)
			(xy 122.042428 -108.229654) (xy 122.169428 -108.229654)
		)
		(stroke
			(width 0)
			(type solid)
		)
		(fill yes)
		(layer "F.Cu")
		(net "M_L_DQ<53>")
	)
	(gr_poly
		(pts
			(xy 122.169428 -107.785154) (xy 122.156728 -107.594654) (xy 122.055128 -107.594654) (xy 122.042428 -107.785154)
			(xy 122.042428 -107.835954) (xy 122.169428 -107.835954)
		)
		(stroke
			(width 0)
			(type solid)
		)
		(fill yes)
		(layer "F.Cu")
		(net "M_L_DQ<48>")
	)
	(gr_poly
		(pts
			(xy 122.169428 -107.391454) (xy 122.156728 -107.200954) (xy 122.055128 -107.200954) (xy 122.042428 -107.391454)
			(xy 122.042428 -107.442254) (xy 122.169428 -107.442254)
		)
		(stroke
			(width 0)
			(type solid)
		)
		(fill yes)
		(layer "F.Cu")
		(net "M_L_DQ<49>")
	)
	(gr_poly
		(pts
			(xy 122.169428 -106.997754) (xy 122.156728 -106.807254) (xy 122.055128 -106.807254) (xy 122.042428 -106.997754)
			(xy 122.042428 -107.048554) (xy 122.169428 -107.048554)
		)
		(stroke
			(width 0)
			(type solid)
		)
		(fill yes)
		(layer "F.Cu")
		(net "M_L_DQS_DP<15>")
	)
	(gr_poly
		(pts
			(xy 122.18035 -47.945548) (xy 122.144282 -47.909734) (xy 122.000772 -47.784004) (xy 121.92889 -47.855886)
			(xy 122.05462 -47.999396) (xy 122.090434 -48.035464)
		)
		(stroke
			(width 0)
			(type solid)
		)
		(fill yes)
		(layer "F.Cu")
		(net "M_H_DQS_DP<6>")
	)
	(gr_poly
		(pts
			(xy 122.198384 -49.38268) (xy 122.072654 -49.238916) (xy 122.03684 -49.203102) (xy 121.946924 -49.293018)
			(xy 121.982992 -49.328832) (xy 122.126756 -49.454562)
		)
		(stroke
			(width 0)
			(type solid)
		)
		(fill yes)
		(layer "F.Cu")
		(net "M_H_DQ<55>")
	)
	(gr_poly
		(pts
			(xy 122.206766 -46.589442) (xy 122.081036 -46.445678) (xy 122.044968 -46.409864) (xy 121.955306 -46.499526)
			(xy 121.99112 -46.535594) (xy 122.134884 -46.66107)
		)
		(stroke
			(width 0)
			(type solid)
		)
		(fill yes)
		(layer "F.Cu")
		(net "M_H_DQS_DP<15>")
	)
	(gr_poly
		(pts
			(xy 122.24512 -103.780336) (xy 122.37085 -103.636572) (xy 122.298968 -103.564944) (xy 122.155204 -103.690674)
			(xy 122.11939 -103.726488) (xy 122.209306 -103.816404)
		)
		(stroke
			(width 0)
			(type solid)
		)
		(fill yes)
		(layer "F.Cu")
		(net "M_L_DQ<50>")
	)
	(gr_poly
		(pts
			(xy 122.24639 -105.646982) (xy 122.37212 -105.503218) (xy 122.300238 -105.43159) (xy 122.156474 -105.55732)
			(xy 122.12066 -105.593134) (xy 122.210322 -105.682796)
		)
		(stroke
			(width 0)
			(type solid)
		)
		(fill yes)
		(layer "F.Cu")
		(net "M_L_DQS_DP<6>")
	)
	(gr_poly
		(pts
			(xy 122.25401 -42.753788) (xy 122.12828 -42.610024) (xy 122.092212 -42.57421) (xy 122.00255 -42.663872)
			(xy 122.038364 -42.69994) (xy 122.182128 -42.82567)
		)
		(stroke
			(width 0)
			(type solid)
		)
		(fill yes)
		(layer "F.Cu")
		(net "M_H_DQ<43>")
	)
	(gr_poly
		(pts
			(xy 122.270266 -48.969676) (xy 122.234452 -48.933608) (xy 122.090688 -48.807878) (xy 122.018806 -48.87976)
			(xy 122.144536 -49.023524) (xy 122.180604 -49.059338)
		)
		(stroke
			(width 0)
			(type solid)
		)
		(fill yes)
		(layer "F.Cu")
		(net "M_H_DQ<55>")
	)
	(gr_poly
		(pts
			(xy 122.278902 -46.176184) (xy 122.242834 -46.14037) (xy 122.099324 -46.01464) (xy 122.027442 -46.086522)
			(xy 122.153172 -46.230032) (xy 122.188986 -46.2661)
		)
		(stroke
			(width 0)
			(type solid)
		)
		(fill yes)
		(layer "F.Cu")
		(net "M_H_DQS_DP<15>")
	)
	(gr_poly
		(pts
			(xy 122.288554 -50.406808) (xy 122.162824 -50.263044) (xy 122.12701 -50.226976) (xy 122.037094 -50.316892)
			(xy 122.072908 -50.352706) (xy 122.216672 -50.478436)
		)
		(stroke
			(width 0)
			(type solid)
		)
		(fill yes)
		(layer "F.Cu")
		(net "M_H_DQ<51>")
	)
	(gr_poly
		(pts
			(xy 122.296936 -47.613316) (xy 122.171206 -47.469552) (xy 122.135138 -47.433738) (xy 122.045476 -47.5234)
			(xy 122.08129 -47.559214) (xy 122.225054 -47.684944)
		)
		(stroke
			(width 0)
			(type solid)
		)
		(fill yes)
		(layer "F.Cu")
		(net "M_H_DQS_DN<6>")
	)
	(gr_poly
		(pts
			(xy 122.316748 -105.109772) (xy 122.352562 -105.073704) (xy 122.2629 -104.984042) (xy 122.226832 -105.019856)
			(xy 122.101102 -105.16362) (xy 122.172984 -105.235502)
		)
		(stroke
			(width 0)
			(type solid)
		)
		(fill yes)
		(layer "F.Cu")
		(net "M_L_DQ<54>")
	)
	(gr_poly
		(pts
			(xy 122.323606 -111.45012) (xy 122.35942 -111.414052) (xy 122.269758 -111.32439) (xy 122.23369 -111.360204)
			(xy 122.10796 -111.503968) (xy 122.179842 -111.57585)
		)
		(stroke
			(width 0)
			(type solid)
		)
		(fill yes)
		(layer "F.Cu")
		(net "M_L_DQ<43>")
	)
	(gr_poly
		(pts
			(xy 122.33529 -44.743624) (xy 122.32259 -44.553124) (xy 122.22099 -44.553124) (xy 122.20829 -44.743624)
			(xy 122.20829 -44.794424) (xy 122.33529 -44.794424)
		)
		(stroke
			(width 0)
			(type solid)
		)
		(fill yes)
		(layer "F.Cu")
		(net "M_H_DQ<53>")
	)
	(gr_poly
		(pts
			(xy 122.33529 -44.349924) (xy 122.32259 -44.159424) (xy 122.22099 -44.159424) (xy 122.20829 -44.349924)
			(xy 122.20829 -44.400724) (xy 122.33529 -44.400724)
		)
		(stroke
			(width 0)
			(type solid)
		)
		(fill yes)
		(layer "F.Cu")
		(net "M_H_DQ<52>")
	)
	(gr_poly
		(pts
			(xy 122.350276 -111.890302) (xy 122.476006 -111.746538) (xy 122.404378 -111.674656) (xy 122.260614 -111.800386)
			(xy 122.224546 -111.8362) (xy 122.314462 -111.926116)
		)
		(stroke
			(width 0)
			(type solid)
		)
		(fill yes)
		(layer "F.Cu")
		(net "M_L_DQ<42>")
	)
	(gr_poly
		(pts
			(xy 122.360436 -49.99355) (xy 122.324368 -49.957736) (xy 122.180858 -49.832006) (xy 122.108976 -49.903888)
			(xy 122.234706 -50.047398) (xy 122.27052 -50.083466)
		)
		(stroke
			(width 0)
			(type solid)
		)
		(fill yes)
		(layer "F.Cu")
		(net "M_H_DQ<51>")
	)
	(gr_poly
		(pts
			(xy 122.368818 -47.200058) (xy 122.33275 -47.164244) (xy 122.18924 -47.038514) (xy 122.117358 -47.110396)
			(xy 122.243088 -47.253906) (xy 122.278902 -47.289974)
		)
		(stroke
			(width 0)
			(type solid)
		)
		(fill yes)
		(layer "F.Cu")
		(net "M_H_DQS_DN<6>")
	)
	(gr_poly
		(pts
			(xy 122.386852 -48.63719) (xy 122.261122 -48.493426) (xy 122.225308 -48.457612) (xy 122.135392 -48.547528)
			(xy 122.17146 -48.583342) (xy 122.315224 -48.709072)
		)
		(stroke
			(width 0)
			(type solid)
		)
		(fill yes)
		(layer "F.Cu")
		(net "M_H_DQ<54>")
	)
	(gr_poly
		(pts
			(xy 122.395234 -45.843698) (xy 122.269504 -45.699934) (xy 122.23369 -45.66412) (xy 122.143774 -45.754036)
			(xy 122.179842 -45.78985) (xy 122.323606 -45.91558)
		)
		(stroke
			(width 0)
			(type solid)
		)
		(fill yes)
		(layer "F.Cu")
		(net "M_H_DQ<49>")
	)
	(gr_poly
		(pts
			(xy 122.406664 -104.085644) (xy 122.442732 -104.04983) (xy 122.352816 -103.959914) (xy 122.317002 -103.995982)
			(xy 122.191272 -104.139492) (xy 122.263154 -104.211374)
		)
		(stroke
			(width 0)
			(type solid)
		)
		(fill yes)
		(layer "F.Cu")
		(net "M_L_DQ<50>")
	)
	(gr_poly
		(pts
			(xy 122.433588 -104.525826) (xy 122.559318 -104.382062) (xy 122.487436 -104.310434) (xy 122.343672 -104.436164)
			(xy 122.307858 -104.471978) (xy 122.397774 -104.561894)
		)
		(stroke
			(width 0)
			(type solid)
		)
		(fill yes)
		(layer "F.Cu")
		(net "M_L_DQ<55>")
	)
	(gr_poly
		(pts
			(xy 122.451876 -102.579424) (xy 122.451876 -102.358444) (xy 122.281696 -102.269544) (xy 122.237246 -102.269544)
			(xy 122.237246 -102.668324) (xy 122.281696 -102.668324)
		)
		(stroke
			(width 0)
			(type solid)
		)
		(fill yes)
		(layer "F.Cu")
		(net "M_L_DQ<51>")
	)
	(gr_poly
		(pts
			(xy 122.458734 -48.224186) (xy 122.42292 -48.188118) (xy 122.279156 -48.062388) (xy 122.207274 -48.13427)
			(xy 122.333004 -48.278034) (xy 122.369072 -48.313848)
		)
		(stroke
			(width 0)
			(type solid)
		)
		(fill yes)
		(layer "F.Cu")
		(net "M_H_DQ<54>")
	)
	(gr_poly
		(pts
			(xy 122.477022 -49.661318) (xy 122.351292 -49.517554) (xy 122.315478 -49.481486) (xy 122.225562 -49.571402)
			(xy 122.261376 -49.607216) (xy 122.40514 -49.732946)
		)
		(stroke
			(width 0)
			(type solid)
		)
		(fill yes)
		(layer "F.Cu")
		(net "M_H_DQ<50>")
	)
	(gr_poly
		(pts
			(xy 122.485404 -46.867826) (xy 122.359674 -46.724062) (xy 122.323606 -46.688248) (xy 122.233944 -46.77791)
			(xy 122.269758 -46.813978) (xy 122.413522 -46.939454)
		)
		(stroke
			(width 0)
			(type solid)
		)
		(fill yes)
		(layer "F.Cu")
		(net "M_H_DQS_DN<15>")
	)
	(gr_poly
		(pts
			(xy 122.499628 -108.674154) (xy 122.499628 -108.623354) (xy 122.372628 -108.623354) (xy 122.372628 -108.674154)
			(xy 122.385328 -108.864654) (xy 122.486928 -108.864654)
		)
		(stroke
			(width 0)
			(type solid)
		)
		(fill yes)
		(layer "F.Cu")
		(net "M_L_DQ<52>")
	)
	(gr_poly
		(pts
			(xy 122.499628 -108.280454) (xy 122.499628 -108.229654) (xy 122.372628 -108.229654) (xy 122.372628 -108.280454)
			(xy 122.385328 -108.470954) (xy 122.486928 -108.470954)
		)
		(stroke
			(width 0)
			(type solid)
		)
		(fill yes)
		(layer "F.Cu")
		(net "M_L_DQ<53>")
	)
	(gr_poly
		(pts
			(xy 122.499628 -107.886754) (xy 122.499628 -107.835954) (xy 122.372628 -107.835954) (xy 122.372628 -107.886754)
			(xy 122.385328 -108.077254) (xy 122.486928 -108.077254)
		)
		(stroke
			(width 0)
			(type solid)
		)
		(fill yes)
		(layer "F.Cu")
		(net "M_L_DQ<48>")
	)
	(gr_poly
		(pts
			(xy 122.499628 -107.493054) (xy 122.499628 -107.442254) (xy 122.372628 -107.442254) (xy 122.372628 -107.493054)
			(xy 122.385328 -107.683554) (xy 122.486928 -107.683554)
		)
		(stroke
			(width 0)
			(type solid)
		)
		(fill yes)
		(layer "F.Cu")
		(net "M_L_DQ<49>")
	)
	(gr_poly
		(pts
			(xy 122.499628 -107.099354) (xy 122.499628 -107.048554) (xy 122.372628 -107.048554) (xy 122.372628 -107.099354)
			(xy 122.385328 -107.289854) (xy 122.486928 -107.289854)
		)
		(stroke
			(width 0)
			(type solid)
		)
		(fill yes)
		(layer "F.Cu")
		(net "M_L_DQS_DP<15>")
	)
	(gr_poly
		(pts
			(xy 122.499628 -106.705654) (xy 122.499628 -106.654854) (xy 122.372628 -106.654854) (xy 122.372628 -106.705654)
			(xy 122.385328 -106.896154) (xy 122.486928 -106.896154)
		)
		(stroke
			(width 0)
			(type solid)
		)
		(fill yes)
		(layer "F.Cu")
		(net "M_L_DQS_DN<15>")
	)
	(gr_poly
		(pts
			(xy 122.499628 -106.311954) (xy 122.499628 -106.261154) (xy 122.372628 -106.261154) (xy 122.372628 -106.311954)
			(xy 122.385328 -106.502454) (xy 122.486928 -106.502454)
		)
		(stroke
			(width 0)
			(type solid)
		)
		(fill yes)
		(layer "F.Cu")
		(net "M_L_DQS_DN<6>")
	)
	(gr_poly
		(pts
			(xy 122.512074 -112.19561) (xy 122.547888 -112.159542) (xy 122.458226 -112.06988) (xy 122.422158 -112.105694)
			(xy 122.296428 -112.249458) (xy 122.36831 -112.32134)
		)
		(stroke
			(width 0)
			(type solid)
		)
		(fill yes)
		(layer "F.Cu")
		(net "M_L_DQ<42>")
	)
	(gr_poly
		(pts
			(xy 122.548904 -49.24806) (xy 122.512836 -49.212246) (xy 122.369326 -49.086516) (xy 122.297444 -49.158398)
			(xy 122.423174 -49.301908) (xy 122.458988 -49.337976)
		)
		(stroke
			(width 0)
			(type solid)
		)
		(fill yes)
		(layer "F.Cu")
		(net "M_H_DQ<50>")
	)
	(gr_poly
		(pts
			(xy 122.557286 -46.454568) (xy 122.521218 -46.418754) (xy 122.377708 -46.293024) (xy 122.305826 -46.364906)
			(xy 122.431556 -46.508416) (xy 122.46737 -46.544484)
		)
		(stroke
			(width 0)
			(type solid)
		)
		(fill yes)
		(layer "F.Cu")
		(net "M_H_DQS_DN<15>")
	)
	(gr_poly
		(pts
			(xy 122.57532 -47.8917) (xy 122.44959 -47.747936) (xy 122.413776 -47.712122) (xy 122.32386 -47.802038)
			(xy 122.359928 -47.837852) (xy 122.503692 -47.963582)
		)
		(stroke
			(width 0)
			(type solid)
		)
		(fill yes)
		(layer "F.Cu")
		(net "M_H_DQS_DP<6>")
	)
	(gr_poly
		(pts
			(xy 122.595132 -104.831134) (xy 122.6312 -104.79532) (xy 122.541284 -104.705404) (xy 122.50547 -104.741472)
			(xy 122.37974 -104.884982) (xy 122.451622 -104.956864)
		)
		(stroke
			(width 0)
			(type solid)
		)
		(fill yes)
		(layer "F.Cu")
		(net "M_L_DQ<55>")
	)
	(gr_poly
		(pts
			(xy 122.622056 -105.271316) (xy 122.747786 -105.127552) (xy 122.675904 -105.055924) (xy 122.53214 -105.181654)
			(xy 122.496326 -105.217468) (xy 122.585988 -105.30713)
		)
		(stroke
			(width 0)
			(type solid)
		)
		(fill yes)
		(layer "F.Cu")
		(net "M_L_DQ<54>")
	)
	(gr_poly
		(pts
			(xy 122.628914 -111.611664) (xy 122.754644 -111.4679) (xy 122.682762 -111.396272) (xy 122.538998 -111.522002)
			(xy 122.503184 -111.557816) (xy 122.5931 -111.647732)
		)
		(stroke
			(width 0)
			(type solid)
		)
		(fill yes)
		(layer "F.Cu")
		(net "M_L_DQ<43>")
	)
	(gr_poly
		(pts
			(xy 122.647202 -47.478696) (xy 122.611388 -47.442628) (xy 122.467624 -47.316898) (xy 122.395742 -47.38878)
			(xy 122.521472 -47.532544) (xy 122.55754 -47.568358)
		)
		(stroke
			(width 0)
			(type solid)
		)
		(fill yes)
		(layer "F.Cu")
		(net "M_H_DQS_DP<6>")
	)
	(gr_poly
		(pts
			(xy 122.66549 -48.915828) (xy 122.53976 -48.772064) (xy 122.503946 -48.735996) (xy 122.41403 -48.825912)
			(xy 122.449844 -48.861726) (xy 122.593608 -48.987456)
		)
		(stroke
			(width 0)
			(type solid)
		)
		(fill yes)
		(layer "F.Cu")
		(net "M_H_DQ<55>")
	)
	(gr_poly
		(pts
			(xy 122.66549 -45.632624) (xy 122.66549 -45.581824) (xy 122.53849 -45.581824) (xy 122.53849 -45.632624)
			(xy 122.55119 -45.823124) (xy 122.65279 -45.823124)
		)
		(stroke
			(width 0)
			(type solid)
		)
		(fill yes)
		(layer "F.Cu")
		(net "M_H_DQ<49>")
	)
	(gr_poly
		(pts
			(xy 122.66549 -45.238924) (xy 122.66549 -45.188124) (xy 122.53849 -45.188124) (xy 122.53849 -45.238924)
			(xy 122.55119 -45.429424) (xy 122.65279 -45.429424)
		)
		(stroke
			(width 0)
			(type solid)
		)
		(fill yes)
		(layer "F.Cu")
		(net "M_H_DQ<48>")
	)
	(gr_poly
		(pts
			(xy 122.66549 -44.845224) (xy 122.66549 -44.794424) (xy 122.53849 -44.794424) (xy 122.53849 -44.845224)
			(xy 122.55119 -45.035724) (xy 122.65279 -45.035724)
		)
		(stroke
			(width 0)
			(type solid)
		)
		(fill yes)
		(layer "F.Cu")
		(net "M_H_DQ<53>")
	)
	(gr_poly
		(pts
			(xy 122.66549 -44.451524) (xy 122.66549 -44.400724) (xy 122.53849 -44.400724) (xy 122.53849 -44.451524)
			(xy 122.55119 -44.642024) (xy 122.65279 -44.642024)
		)
		(stroke
			(width 0)
			(type solid)
		)
		(fill yes)
		(layer "F.Cu")
		(net "M_H_DQ<52>")
	)
	(gr_poly
		(pts
			(xy 122.685302 -103.807006) (xy 122.72137 -103.771192) (xy 122.631454 -103.681276) (xy 122.59564 -103.717344)
			(xy 122.46991 -103.860854) (xy 122.541792 -103.932736)
		)
		(stroke
			(width 0)
			(type solid)
		)
		(fill yes)
		(layer "F.Cu")
		(net "M_L_DQ<51>")
	)
	(gr_poly
		(pts
			(xy 122.711972 -104.247442) (xy 122.837702 -104.103678) (xy 122.766074 -104.031796) (xy 122.62231 -104.157526)
			(xy 122.586242 -104.19334) (xy 122.676158 -104.283256)
		)
		(stroke
			(width 0)
			(type solid)
		)
		(fill yes)
		(layer "F.Cu")
		(net "M_L_DQ<50>")
	)
	(gr_poly
		(pts
			(xy 122.737372 -48.50257) (xy 122.701304 -48.466756) (xy 122.557794 -48.341026) (xy 122.485912 -48.412908)
			(xy 122.611642 -48.556418) (xy 122.647456 -48.592486)
		)
		(stroke
			(width 0)
			(type solid)
		)
		(fill yes)
		(layer "F.Cu")
		(net "M_H_DQ<55>")
	)
	(gr_poly
		(pts
			(xy 122.755406 -49.939702) (xy 122.629676 -49.795938) (xy 122.593862 -49.760124) (xy 122.503946 -49.85004)
			(xy 122.540014 -49.885854) (xy 122.683778 -50.011584)
		)
		(stroke
			(width 0)
			(type solid)
		)
		(fill yes)
		(layer "F.Cu")
		(net "M_H_DQ<51>")
	)
	(gr_poly
		(pts
			(xy 122.763788 -47.14621) (xy 122.638058 -47.002446) (xy 122.602244 -46.966632) (xy 122.512328 -47.056548)
			(xy 122.548396 -47.092362) (xy 122.69216 -47.218092)
		)
		(stroke
			(width 0)
			(type solid)
		)
		(fill yes)
		(layer "F.Cu")
		(net "M_H_DQS_DN<6>")
	)
	(gr_poly
		(pts
			(xy 122.790458 -111.916972) (xy 122.826526 -111.881158) (xy 122.73661 -111.791242) (xy 122.700796 -111.82731)
			(xy 122.575066 -111.97082) (xy 122.646948 -112.042702)
		)
		(stroke
			(width 0)
			(type solid)
		)
		(fill yes)
		(layer "F.Cu")
		(net "M_L_DQ<43>")
	)
	(gr_poly
		(pts
			(xy 122.817382 -112.357154) (xy 122.943112 -112.21339) (xy 122.87123 -112.141762) (xy 122.727466 -112.267492)
			(xy 122.691652 -112.303306) (xy 122.781568 -112.393222)
		)
		(stroke
			(width 0)
			(type solid)
		)
		(fill yes)
		(layer "F.Cu")
		(net "M_L_DQ<42>")
	)
	(gr_poly
		(pts
			(xy 122.827288 -49.526698) (xy 122.791474 -49.49063) (xy 122.64771 -49.3649) (xy 122.575828 -49.436782)
			(xy 122.701558 -49.580546) (xy 122.737626 -49.61636)
		)
		(stroke
			(width 0)
			(type solid)
		)
		(fill yes)
		(layer "F.Cu")
		(net "M_H_DQ<51>")
	)
	(gr_poly
		(pts
			(xy 122.829828 -108.572554) (xy 122.817128 -108.382054) (xy 122.715528 -108.382054) (xy 122.702828 -108.572554)
			(xy 122.702828 -108.623354) (xy 122.829828 -108.623354)
		)
		(stroke
			(width 0)
			(type solid)
		)
		(fill yes)
		(layer "F.Cu")
		(net "M_L_DQ<52>")
	)
	(gr_poly
		(pts
			(xy 122.829828 -108.178854) (xy 122.817128 -107.988354) (xy 122.715528 -107.988354) (xy 122.702828 -108.178854)
			(xy 122.702828 -108.229654) (xy 122.829828 -108.229654)
		)
		(stroke
			(width 0)
			(type solid)
		)
		(fill yes)
		(layer "F.Cu")
		(net "M_L_DQ<53>")
	)
	(gr_poly
		(pts
			(xy 122.829828 -107.785154) (xy 122.817128 -107.594654) (xy 122.715528 -107.594654) (xy 122.702828 -107.785154)
			(xy 122.702828 -107.835954) (xy 122.829828 -107.835954)
		)
		(stroke
			(width 0)
			(type solid)
		)
		(fill yes)
		(layer "F.Cu")
		(net "M_L_DQ<48>")
	)
	(gr_poly
		(pts
			(xy 122.829828 -107.391454) (xy 122.817128 -107.200954) (xy 122.715528 -107.200954) (xy 122.702828 -107.391454)
			(xy 122.702828 -107.442254) (xy 122.829828 -107.442254)
		)
		(stroke
			(width 0)
			(type solid)
		)
		(fill yes)
		(layer "F.Cu")
		(net "M_L_DQ<49>")
	)
	(gr_poly
		(pts
			(xy 122.829828 -106.997754) (xy 122.817128 -106.807254) (xy 122.715528 -106.807254) (xy 122.702828 -106.997754)
			(xy 122.702828 -107.048554) (xy 122.829828 -107.048554)
		)
		(stroke
			(width 0)
			(type solid)
		)
		(fill yes)
		(layer "F.Cu")
		(net "M_L_DQS_DP<15>")
	)
	(gr_poly
		(pts
			(xy 122.829828 -106.604054) (xy 122.817128 -106.413554) (xy 122.715528 -106.413554) (xy 122.702828 -106.604054)
			(xy 122.702828 -106.654854) (xy 122.829828 -106.654854)
		)
		(stroke
			(width 0)
			(type solid)
		)
		(fill yes)
		(layer "F.Cu")
		(net "M_L_DQS_DN<15>")
	)
	(gr_poly
		(pts
			(xy 122.829828 -106.210354) (xy 122.817128 -106.019854) (xy 122.715528 -106.019854) (xy 122.702828 -106.210354)
			(xy 122.702828 -106.261154) (xy 122.829828 -106.261154)
		)
		(stroke
			(width 0)
			(type solid)
		)
		(fill yes)
		(layer "F.Cu")
		(net "M_L_DQS_DN<6>")
	)
	(gr_poly
		(pts
			(xy 122.829828 -105.816654) (xy 122.817128 -105.626154) (xy 122.715528 -105.626154) (xy 122.702828 -105.816654)
			(xy 122.702828 -105.867454) (xy 122.829828 -105.867454)
		)
		(stroke
			(width 0)
			(type solid)
		)
		(fill yes)
		(layer "F.Cu")
		(net "M_L_DQS_DP<6>")
	)
	(gr_poly
		(pts
			(xy 122.853958 -48.170338) (xy 122.728228 -48.026574) (xy 122.69216 -47.99076) (xy 122.602498 -48.080422)
			(xy 122.638312 -48.116236) (xy 122.782076 -48.241966)
		)
		(stroke
			(width 0)
			(type solid)
		)
		(fill yes)
		(layer "F.Cu")
		(net "M_H_DQ<54>")
	)
	(gr_poly
		(pts
			(xy 122.87377 -104.55275) (xy 122.909584 -104.516682) (xy 122.819922 -104.42702) (xy 122.783854 -104.462834)
			(xy 122.658124 -104.606598) (xy 122.730006 -104.67848)
		)
		(stroke
			(width 0)
			(type solid)
		)
		(fill yes)
		(layer "F.Cu")
		(net "M_L_DQ<50>")
	)
	(gr_poly
		(pts
			(xy 122.92584 -47.75708) (xy 122.889772 -47.721266) (xy 122.746262 -47.595536) (xy 122.67438 -47.667418)
			(xy 122.80011 -47.810928) (xy 122.835924 -47.846996)
		)
		(stroke
			(width 0)
			(type solid)
		)
		(fill yes)
		(layer "F.Cu")
		(net "M_H_DQ<54>")
	)
	(gr_poly
		(pts
			(xy 122.943874 -49.194212) (xy 122.818144 -49.050448) (xy 122.78233 -49.014634) (xy 122.692414 -49.10455)
			(xy 122.728482 -49.140364) (xy 122.872246 -49.266094)
		)
		(stroke
			(width 0)
			(type solid)
		)
		(fill yes)
		(layer "F.Cu")
		(net "M_H_DQ<50>")
	)
	(gr_poly
		(pts
			(xy 122.99061 -103.968804) (xy 123.11634 -103.82504) (xy 123.044712 -103.753158) (xy 122.900948 -103.878888)
			(xy 122.86488 -103.914702) (xy 122.954796 -104.004618)
		)
		(stroke
			(width 0)
			(type solid)
		)
		(fill yes)
		(layer "F.Cu")
		(net "M_L_DQ<51>")
	)
	(gr_poly
		(pts
			(xy 122.99569 -46.318424) (xy 122.98299 -46.127924) (xy 122.88139 -46.127924) (xy 122.86869 -46.318424)
			(xy 122.86869 -46.369224) (xy 122.99569 -46.369224)
		)
		(stroke
			(width 0)
			(type solid)
		)
		(fill yes)
		(layer "F.Cu")
		(net "M_H_DQS_DN<15>")
	)
	(gr_poly
		(pts
			(xy 122.99569 -45.924724) (xy 122.98299 -45.734224) (xy 122.88139 -45.734224) (xy 122.86869 -45.924724)
			(xy 122.86869 -45.975524) (xy 122.99569 -45.975524)
		)
		(stroke
			(width 0)
			(type solid)
		)
		(fill yes)
		(layer "F.Cu")
		(net "M_H_DQS_DP<15>")
	)
	(gr_poly
		(pts
			(xy 122.99569 -45.531024) (xy 122.98299 -45.340524) (xy 122.88139 -45.340524) (xy 122.86869 -45.531024)
			(xy 122.86869 -45.581824) (xy 122.99569 -45.581824)
		)
		(stroke
			(width 0)
			(type solid)
		)
		(fill yes)
		(layer "F.Cu")
		(net "M_H_DQ<49>")
	)
	(gr_poly
		(pts
			(xy 122.99569 -45.137324) (xy 122.98299 -44.946824) (xy 122.88139 -44.946824) (xy 122.86869 -45.137324)
			(xy 122.86869 -45.188124) (xy 122.99569 -45.188124)
		)
		(stroke
			(width 0)
			(type solid)
		)
		(fill yes)
		(layer "F.Cu")
		(net "M_H_DQ<48>")
	)
	(gr_poly
		(pts
			(xy 122.99569 -44.743624) (xy 122.98299 -44.553124) (xy 122.88139 -44.553124) (xy 122.86869 -44.743624)
			(xy 122.86869 -44.794424) (xy 122.99569 -44.794424)
		)
		(stroke
			(width 0)
			(type solid)
		)
		(fill yes)
		(layer "F.Cu")
		(net "M_H_DQ<53>")
	)
	(gr_poly
		(pts
			(xy 122.99569 -44.349924) (xy 122.98299 -44.159424) (xy 122.88139 -44.159424) (xy 122.86869 -44.349924)
			(xy 122.86869 -44.400724) (xy 122.99569 -44.400724)
		)
		(stroke
			(width 0)
			(type solid)
		)
		(fill yes)
		(layer "F.Cu")
		(net "M_H_DQ<52>")
	)
	(gr_poly
		(pts
			(xy 123.015756 -48.781208) (xy 122.979942 -48.74514) (xy 122.836178 -48.61941) (xy 122.764296 -48.691292)
			(xy 122.890026 -48.835056) (xy 122.926094 -48.87087)
		)
		(stroke
			(width 0)
			(type solid)
		)
		(fill yes)
		(layer "F.Cu")
		(net "M_H_DQ<50>")
	)
	(gr_poly
		(pts
			(xy 123.095766 -112.07877) (xy 123.221496 -111.935006) (xy 123.149868 -111.863124) (xy 123.006104 -111.988854)
			(xy 122.970036 -112.024668) (xy 123.059952 -112.114584)
		)
		(stroke
			(width 0)
			(type solid)
		)
		(fill yes)
		(layer "F.Cu")
		(net "M_L_DQ<43>")
	)
	(gr_poly
		(pts
			(xy 123.132342 -48.448722) (xy 123.006612 -48.304958) (xy 122.970798 -48.269144) (xy 122.880882 -48.35906)
			(xy 122.91695 -48.394874) (xy 123.060714 -48.520604)
		)
		(stroke
			(width 0)
			(type solid)
		)
		(fill yes)
		(layer "F.Cu")
		(net "M_H_DQ<55>")
	)
	(gr_poly
		(pts
			(xy 123.152408 -104.274112) (xy 123.188222 -104.238044) (xy 123.09856 -104.148382) (xy 123.062492 -104.184196)
			(xy 122.936762 -104.32796) (xy 123.008644 -104.399842)
		)
		(stroke
			(width 0)
			(type solid)
		)
		(fill yes)
		(layer "F.Cu")
		(net "M_L_DQ<51>")
	)
	(gr_poly
		(pts
			(xy 123.160028 -108.674154) (xy 123.160028 -108.623354) (xy 123.033028 -108.623354) (xy 123.033028 -108.674154)
			(xy 123.045728 -108.864654) (xy 123.147328 -108.864654)
		)
		(stroke
			(width 0)
			(type solid)
		)
		(fill yes)
		(layer "F.Cu")
		(net "M_L_DQ<52>")
	)
	(gr_poly
		(pts
			(xy 123.160028 -108.280454) (xy 123.160028 -108.229654) (xy 123.033028 -108.229654) (xy 123.033028 -108.280454)
			(xy 123.045728 -108.470954) (xy 123.147328 -108.470954)
		)
		(stroke
			(width 0)
			(type solid)
		)
		(fill yes)
		(layer "F.Cu")
		(net "M_L_DQ<53>")
	)
	(gr_poly
		(pts
			(xy 123.160028 -107.886754) (xy 123.160028 -107.835954) (xy 123.033028 -107.835954) (xy 123.033028 -107.886754)
			(xy 123.045728 -108.077254) (xy 123.147328 -108.077254)
		)
		(stroke
			(width 0)
			(type solid)
		)
		(fill yes)
		(layer "F.Cu")
		(net "M_L_DQ<48>")
	)
	(gr_poly
		(pts
			(xy 123.160028 -107.493054) (xy 123.160028 -107.442254) (xy 123.033028 -107.442254) (xy 123.033028 -107.493054)
			(xy 123.045728 -107.683554) (xy 123.147328 -107.683554)
		)
		(stroke
			(width 0)
			(type solid)
		)
		(fill yes)
		(layer "F.Cu")
		(net "M_L_DQ<49>")
	)
	(gr_poly
		(pts
			(xy 123.160028 -107.099354) (xy 123.160028 -107.048554) (xy 123.033028 -107.048554) (xy 123.033028 -107.099354)
			(xy 123.045728 -107.289854) (xy 123.147328 -107.289854)
		)
		(stroke
			(width 0)
			(type solid)
		)
		(fill yes)
		(layer "F.Cu")
		(net "M_L_DQS_DP<15>")
	)
	(gr_poly
		(pts
			(xy 123.160028 -106.705654) (xy 123.160028 -106.654854) (xy 123.033028 -106.654854) (xy 123.033028 -106.705654)
			(xy 123.045728 -106.896154) (xy 123.147328 -106.896154)
		)
		(stroke
			(width 0)
			(type solid)
		)
		(fill yes)
		(layer "F.Cu")
		(net "M_L_DQS_DN<15>")
	)
	(gr_poly
		(pts
			(xy 123.160028 -106.311954) (xy 123.160028 -106.261154) (xy 123.033028 -106.261154) (xy 123.033028 -106.311954)
			(xy 123.045728 -106.502454) (xy 123.147328 -106.502454)
		)
		(stroke
			(width 0)
			(type solid)
		)
		(fill yes)
		(layer "F.Cu")
		(net "M_L_DQS_DN<6>")
	)
	(gr_poly
		(pts
			(xy 123.160028 -105.918254) (xy 123.160028 -105.867454) (xy 123.033028 -105.867454) (xy 123.033028 -105.918254)
			(xy 123.045728 -106.108754) (xy 123.147328 -106.108754)
		)
		(stroke
			(width 0)
			(type solid)
		)
		(fill yes)
		(layer "F.Cu")
		(net "M_L_DQS_DP<6>")
	)
	(gr_poly
		(pts
			(xy 123.160028 -105.524554) (xy 123.160028 -105.473754) (xy 123.033028 -105.473754) (xy 123.033028 -105.524554)
			(xy 123.045728 -105.715054) (xy 123.147328 -105.715054)
		)
		(stroke
			(width 0)
			(type solid)
		)
		(fill yes)
		(layer "F.Cu")
		(net "M_L_DQ<54>")
	)
	(gr_poly
		(pts
			(xy 123.160028 -105.130854) (xy 123.160028 -105.080054) (xy 123.033028 -105.080054) (xy 123.033028 -105.130854)
			(xy 123.045728 -105.321354) (xy 123.147328 -105.321354)
		)
		(stroke
			(width 0)
			(type solid)
		)
		(fill yes)
		(layer "F.Cu")
		(net "M_L_DQ<55>")
	)
	(gr_poly
		(pts
			(xy 123.204224 -48.035718) (xy 123.16841 -47.99965) (xy 123.024646 -47.87392) (xy 122.952764 -47.945802)
			(xy 123.078494 -48.089566) (xy 123.114562 -48.12538)
		)
		(stroke
			(width 0)
			(type solid)
		)
		(fill yes)
		(layer "F.Cu")
		(net "M_H_DQ<55>")
	)
	(gr_poly
		(pts
			(xy 123.222512 -49.47285) (xy 123.096782 -49.329086) (xy 123.060968 -49.293018) (xy 122.971052 -49.382934)
			(xy 123.006866 -49.418748) (xy 123.15063 -49.544478)
		)
		(stroke
			(width 0)
			(type solid)
		)
		(fill yes)
		(layer "F.Cu")
		(net "M_H_DQ<51>")
	)
	(gr_poly
		(pts
			(xy 123.294394 -49.059592) (xy 123.258326 -49.023778) (xy 123.114816 -48.898048) (xy 123.042934 -48.96993)
			(xy 123.168664 -49.11344) (xy 123.204478 -49.149508)
		)
		(stroke
			(width 0)
			(type solid)
		)
		(fill yes)
		(layer "F.Cu")
		(net "M_H_DQ<51>")
	)
	(gr_poly
		(pts
			(xy 123.32589 -47.207424) (xy 123.32589 -47.156624) (xy 123.19889 -47.156624) (xy 123.19889 -47.207424)
			(xy 123.21159 -47.397924) (xy 123.31319 -47.397924)
		)
		(stroke
			(width 0)
			(type solid)
		)
		(fill yes)
		(layer "F.Cu")
		(net "M_H_DQS_DP<6>")
	)
	(gr_poly
		(pts
			(xy 123.32589 -46.813724) (xy 123.32589 -46.762924) (xy 123.19889 -46.762924) (xy 123.19889 -46.813724)
			(xy 123.21159 -47.004224) (xy 123.31319 -47.004224)
		)
		(stroke
			(width 0)
			(type solid)
		)
		(fill yes)
		(layer "F.Cu")
		(net "M_H_DQS_DN<6>")
	)
	(gr_poly
		(pts
			(xy 123.32589 -46.420024) (xy 123.32589 -46.369224) (xy 123.19889 -46.369224) (xy 123.19889 -46.420024)
			(xy 123.21159 -46.610524) (xy 123.31319 -46.610524)
		)
		(stroke
			(width 0)
			(type solid)
		)
		(fill yes)
		(layer "F.Cu")
		(net "M_H_DQS_DN<15>")
	)
	(gr_poly
		(pts
			(xy 123.32589 -46.026324) (xy 123.32589 -45.975524) (xy 123.19889 -45.975524) (xy 123.19889 -46.026324)
			(xy 123.21159 -46.216824) (xy 123.31319 -46.216824)
		)
		(stroke
			(width 0)
			(type solid)
		)
		(fill yes)
		(layer "F.Cu")
		(net "M_H_DQS_DP<15>")
	)
	(gr_poly
		(pts
			(xy 123.32589 -45.632624) (xy 123.32589 -45.581824) (xy 123.19889 -45.581824) (xy 123.19889 -45.632624)
			(xy 123.21159 -45.823124) (xy 123.31319 -45.823124)
		)
		(stroke
			(width 0)
			(type solid)
		)
		(fill yes)
		(layer "F.Cu")
		(net "M_H_DQ<49>")
	)
	(gr_poly
		(pts
			(xy 123.32589 -45.238924) (xy 123.32589 -45.188124) (xy 123.19889 -45.188124) (xy 123.19889 -45.238924)
			(xy 123.21159 -45.429424) (xy 123.31319 -45.429424)
		)
		(stroke
			(width 0)
			(type solid)
		)
		(fill yes)
		(layer "F.Cu")
		(net "M_H_DQ<48>")
	)
	(gr_poly
		(pts
			(xy 123.32589 -44.845224) (xy 123.32589 -44.794424) (xy 123.19889 -44.794424) (xy 123.19889 -44.845224)
			(xy 123.21159 -45.035724) (xy 123.31319 -45.035724)
		)
		(stroke
			(width 0)
			(type solid)
		)
		(fill yes)
		(layer "F.Cu")
		(net "M_H_DQ<53>")
	)
	(gr_poly
		(pts
			(xy 123.32589 -44.451524) (xy 123.32589 -44.400724) (xy 123.19889 -44.400724) (xy 123.19889 -44.451524)
			(xy 123.21159 -44.642024) (xy 123.31319 -44.642024)
		)
		(stroke
			(width 0)
			(type solid)
		)
		(fill yes)
		(layer "F.Cu")
		(net "M_H_DQ<52>")
	)
	(gr_poly
		(pts
			(xy 123.41098 -48.72736) (xy 123.28525 -48.583596) (xy 123.249182 -48.547782) (xy 123.15952 -48.637444)
			(xy 123.195334 -48.673258) (xy 123.339098 -48.798988)
		)
		(stroke
			(width 0)
			(type solid)
		)
		(fill yes)
		(layer "F.Cu")
		(net "M_H_DQ<50>")
	)
	(gr_poly
		(pts
			(xy 123.490228 -108.572554) (xy 123.477528 -108.382054) (xy 123.375928 -108.382054) (xy 123.363228 -108.572554)
			(xy 123.363228 -108.623354) (xy 123.490228 -108.623354)
		)
		(stroke
			(width 0)
			(type solid)
		)
		(fill yes)
		(layer "F.Cu")
		(net "M_L_DQ<52>")
	)
	(gr_poly
		(pts
			(xy 123.490228 -108.178854) (xy 123.477528 -107.988354) (xy 123.375928 -107.988354) (xy 123.363228 -108.178854)
			(xy 123.363228 -108.229654) (xy 123.490228 -108.229654)
		)
		(stroke
			(width 0)
			(type solid)
		)
		(fill yes)
		(layer "F.Cu")
		(net "M_L_DQ<53>")
	)
	(gr_poly
		(pts
			(xy 123.490228 -107.785154) (xy 123.477528 -107.594654) (xy 123.375928 -107.594654) (xy 123.363228 -107.785154)
			(xy 123.363228 -107.835954) (xy 123.490228 -107.835954)
		)
		(stroke
			(width 0)
			(type solid)
		)
		(fill yes)
		(layer "F.Cu")
		(net "M_L_DQ<48>")
	)
	(gr_poly
		(pts
			(xy 123.490228 -107.391454) (xy 123.477528 -107.200954) (xy 123.375928 -107.200954) (xy 123.363228 -107.391454)
			(xy 123.363228 -107.442254) (xy 123.490228 -107.442254)
		)
		(stroke
			(width 0)
			(type solid)
		)
		(fill yes)
		(layer "F.Cu")
		(net "M_L_DQ<49>")
	)
	(gr_poly
		(pts
			(xy 123.490228 -106.997754) (xy 123.477528 -106.807254) (xy 123.375928 -106.807254) (xy 123.363228 -106.997754)
			(xy 123.363228 -107.048554) (xy 123.490228 -107.048554)
		)
		(stroke
			(width 0)
			(type solid)
		)
		(fill yes)
		(layer "F.Cu")
		(net "M_L_DQS_DP<15>")
	)
	(gr_poly
		(pts
			(xy 123.490228 -106.604054) (xy 123.477528 -106.413554) (xy 123.375928 -106.413554) (xy 123.363228 -106.604054)
			(xy 123.363228 -106.654854) (xy 123.490228 -106.654854)
		)
		(stroke
			(width 0)
			(type solid)
		)
		(fill yes)
		(layer "F.Cu")
		(net "M_L_DQS_DN<15>")
	)
	(gr_poly
		(pts
			(xy 123.490228 -106.210354) (xy 123.477528 -106.019854) (xy 123.375928 -106.019854) (xy 123.363228 -106.210354)
			(xy 123.363228 -106.261154) (xy 123.490228 -106.261154)
		)
		(stroke
			(width 0)
			(type solid)
		)
		(fill yes)
		(layer "F.Cu")
		(net "M_L_DQS_DN<6>")
	)
	(gr_poly
		(pts
			(xy 123.490228 -105.816654) (xy 123.477528 -105.626154) (xy 123.375928 -105.626154) (xy 123.363228 -105.816654)
			(xy 123.363228 -105.867454) (xy 123.490228 -105.867454)
		)
		(stroke
			(width 0)
			(type solid)
		)
		(fill yes)
		(layer "F.Cu")
		(net "M_L_DQS_DP<6>")
	)
	(gr_poly
		(pts
			(xy 123.490228 -105.422954) (xy 123.477528 -105.232454) (xy 123.375928 -105.232454) (xy 123.363228 -105.422954)
			(xy 123.363228 -105.473754) (xy 123.490228 -105.473754)
		)
		(stroke
			(width 0)
			(type solid)
		)
		(fill yes)
		(layer "F.Cu")
		(net "M_L_DQ<54>")
	)
	(gr_poly
		(pts
			(xy 123.490228 -105.029254) (xy 123.477528 -104.838754) (xy 123.375928 -104.838754) (xy 123.363228 -105.029254)
			(xy 123.363228 -105.080054) (xy 123.490228 -105.080054)
		)
		(stroke
			(width 0)
			(type solid)
		)
		(fill yes)
		(layer "F.Cu")
		(net "M_L_DQ<55>")
	)
	(gr_poly
		(pts
			(xy 123.490228 -104.635554) (xy 123.477528 -104.445054) (xy 123.375928 -104.445054) (xy 123.363228 -104.635554)
			(xy 123.363228 -104.686354) (xy 123.490228 -104.686354)
		)
		(stroke
			(width 0)
			(type solid)
		)
		(fill yes)
		(layer "F.Cu")
		(net "M_L_DQ<50>")
	)
	(gr_poly
		(pts
			(xy 123.490228 -104.241854) (xy 123.477528 -104.051354) (xy 123.375928 -104.051354) (xy 123.363228 -104.241854)
			(xy 123.363228 -104.292654) (xy 123.490228 -104.292654)
		)
		(stroke
			(width 0)
			(type solid)
		)
		(fill yes)
		(layer "F.Cu")
		(net "M_L_DQ<51>")
	)
	(gr_poly
		(pts
			(xy 123.65609 -48.286924) (xy 123.64339 -48.096424) (xy 123.54179 -48.096424) (xy 123.52909 -48.286924)
			(xy 123.52909 -48.337724) (xy 123.65609 -48.337724)
		)
		(stroke
			(width 0)
			(type solid)
		)
		(fill yes)
		(layer "F.Cu")
		(net "M_H_DQ<50>")
	)
	(gr_poly
		(pts
			(xy 123.65609 -47.893224) (xy 123.64339 -47.702724) (xy 123.54179 -47.702724) (xy 123.52909 -47.893224)
			(xy 123.52909 -47.944024) (xy 123.65609 -47.944024)
		)
		(stroke
			(width 0)
			(type solid)
		)
		(fill yes)
		(layer "F.Cu")
		(net "M_H_DQ<55>")
	)
	(gr_poly
		(pts
			(xy 123.65609 -47.499524) (xy 123.64339 -47.309024) (xy 123.54179 -47.309024) (xy 123.52909 -47.499524)
			(xy 123.52909 -47.550324) (xy 123.65609 -47.550324)
		)
		(stroke
			(width 0)
			(type solid)
		)
		(fill yes)
		(layer "F.Cu")
		(net "M_H_DQ<54>")
	)
	(gr_poly
		(pts
			(xy 123.65609 -47.105824) (xy 123.64339 -46.915324) (xy 123.54179 -46.915324) (xy 123.52909 -47.105824)
			(xy 123.52909 -47.156624) (xy 123.65609 -47.156624)
		)
		(stroke
			(width 0)
			(type solid)
		)
		(fill yes)
		(layer "F.Cu")
		(net "M_H_DQS_DP<6>")
	)
	(gr_poly
		(pts
			(xy 123.65609 -46.712124) (xy 123.64339 -46.521624) (xy 123.54179 -46.521624) (xy 123.52909 -46.712124)
			(xy 123.52909 -46.762924) (xy 123.65609 -46.762924)
		)
		(stroke
			(width 0)
			(type solid)
		)
		(fill yes)
		(layer "F.Cu")
		(net "M_H_DQS_DN<6>")
	)
	(gr_poly
		(pts
			(xy 123.65609 -46.318424) (xy 123.64339 -46.127924) (xy 123.54179 -46.127924) (xy 123.52909 -46.318424)
			(xy 123.52909 -46.369224) (xy 123.65609 -46.369224)
		)
		(stroke
			(width 0)
			(type solid)
		)
		(fill yes)
		(layer "F.Cu")
		(net "M_H_DQS_DN<15>")
	)
	(gr_poly
		(pts
			(xy 123.65609 -45.924724) (xy 123.64339 -45.734224) (xy 123.54179 -45.734224) (xy 123.52909 -45.924724)
			(xy 123.52909 -45.975524) (xy 123.65609 -45.975524)
		)
		(stroke
			(width 0)
			(type solid)
		)
		(fill yes)
		(layer "F.Cu")
		(net "M_H_DQS_DP<15>")
	)
	(gr_poly
		(pts
			(xy 123.65609 -45.531024) (xy 123.64339 -45.340524) (xy 123.54179 -45.340524) (xy 123.52909 -45.531024)
			(xy 123.52909 -45.581824) (xy 123.65609 -45.581824)
		)
		(stroke
			(width 0)
			(type solid)
		)
		(fill yes)
		(layer "F.Cu")
		(net "M_H_DQ<49>")
	)
	(gr_poly
		(pts
			(xy 123.65609 -45.137324) (xy 123.64339 -44.946824) (xy 123.54179 -44.946824) (xy 123.52909 -45.137324)
			(xy 123.52909 -45.188124) (xy 123.65609 -45.188124)
		)
		(stroke
			(width 0)
			(type solid)
		)
		(fill yes)
		(layer "F.Cu")
		(net "M_H_DQ<48>")
	)
	(gr_poly
		(pts
			(xy 123.65609 -44.743624) (xy 123.64339 -44.553124) (xy 123.54179 -44.553124) (xy 123.52909 -44.743624)
			(xy 123.52909 -44.794424) (xy 123.65609 -44.794424)
		)
		(stroke
			(width 0)
			(type solid)
		)
		(fill yes)
		(layer "F.Cu")
		(net "M_H_DQ<53>")
	)
	(gr_poly
		(pts
			(xy 123.65609 -44.349924) (xy 123.64339 -44.159424) (xy 123.54179 -44.159424) (xy 123.52909 -44.349924)
			(xy 123.52909 -44.400724) (xy 123.65609 -44.400724)
		)
		(stroke
			(width 0)
			(type solid)
		)
		(fill yes)
		(layer "F.Cu")
		(net "M_H_DQ<52>")
	)
	(gr_poly
		(pts
			(xy 123.689364 -49.005744) (xy 123.563634 -48.86198) (xy 123.52782 -48.826166) (xy 123.437904 -48.916082)
			(xy 123.473972 -48.951896) (xy 123.617736 -49.077626)
		)
		(stroke
			(width 0)
			(type solid)
		)
		(fill yes)
		(layer "F.Cu")
		(net "M_H_DQ<51>")
	)
	(gr_poly
		(pts
			(xy 123.820428 -108.674154) (xy 123.820428 -108.623354) (xy 123.693428 -108.623354) (xy 123.693428 -108.674154)
			(xy 123.706128 -108.864654) (xy 123.807728 -108.864654)
		)
		(stroke
			(width 0)
			(type solid)
		)
		(fill yes)
		(layer "F.Cu")
		(net "M_L_DQ<52>")
	)
	(gr_poly
		(pts
			(xy 123.820428 -108.280454) (xy 123.820428 -108.229654) (xy 123.693428 -108.229654) (xy 123.693428 -108.280454)
			(xy 123.706128 -108.470954) (xy 123.807728 -108.470954)
		)
		(stroke
			(width 0)
			(type solid)
		)
		(fill yes)
		(layer "F.Cu")
		(net "M_L_DQ<53>")
	)
	(gr_poly
		(pts
			(xy 123.820428 -107.886754) (xy 123.820428 -107.835954) (xy 123.693428 -107.835954) (xy 123.693428 -107.886754)
			(xy 123.706128 -108.077254) (xy 123.807728 -108.077254)
		)
		(stroke
			(width 0)
			(type solid)
		)
		(fill yes)
		(layer "F.Cu")
		(net "M_L_DQ<48>")
	)
	(gr_poly
		(pts
			(xy 123.820428 -107.493054) (xy 123.820428 -107.442254) (xy 123.693428 -107.442254) (xy 123.693428 -107.493054)
			(xy 123.706128 -107.683554) (xy 123.807728 -107.683554)
		)
		(stroke
			(width 0)
			(type solid)
		)
		(fill yes)
		(layer "F.Cu")
		(net "M_L_DQ<49>")
	)
	(gr_poly
		(pts
			(xy 123.820428 -107.099354) (xy 123.820428 -107.048554) (xy 123.693428 -107.048554) (xy 123.693428 -107.099354)
			(xy 123.706128 -107.289854) (xy 123.807728 -107.289854)
		)
		(stroke
			(width 0)
			(type solid)
		)
		(fill yes)
		(layer "F.Cu")
		(net "M_L_DQS_DP<15>")
	)
	(gr_poly
		(pts
			(xy 123.820428 -106.705654) (xy 123.820428 -106.654854) (xy 123.693428 -106.654854) (xy 123.693428 -106.705654)
			(xy 123.706128 -106.896154) (xy 123.807728 -106.896154)
		)
		(stroke
			(width 0)
			(type solid)
		)
		(fill yes)
		(layer "F.Cu")
		(net "M_L_DQS_DN<15>")
	)
	(gr_poly
		(pts
			(xy 123.820428 -106.311954) (xy 123.820428 -106.261154) (xy 123.693428 -106.261154) (xy 123.693428 -106.311954)
			(xy 123.706128 -106.502454) (xy 123.807728 -106.502454)
		)
		(stroke
			(width 0)
			(type solid)
		)
		(fill yes)
		(layer "F.Cu")
		(net "M_L_DQS_DN<6>")
	)
	(gr_poly
		(pts
			(xy 123.820428 -105.918254) (xy 123.820428 -105.867454) (xy 123.693428 -105.867454) (xy 123.693428 -105.918254)
			(xy 123.706128 -106.108754) (xy 123.807728 -106.108754)
		)
		(stroke
			(width 0)
			(type solid)
		)
		(fill yes)
		(layer "F.Cu")
		(net "M_L_DQS_DP<6>")
	)
	(gr_poly
		(pts
			(xy 123.820428 -105.524554) (xy 123.820428 -105.473754) (xy 123.693428 -105.473754) (xy 123.693428 -105.524554)
			(xy 123.706128 -105.715054) (xy 123.807728 -105.715054)
		)
		(stroke
			(width 0)
			(type solid)
		)
		(fill yes)
		(layer "F.Cu")
		(net "M_L_DQ<54>")
	)
	(gr_poly
		(pts
			(xy 123.820428 -105.130854) (xy 123.820428 -105.080054) (xy 123.693428 -105.080054) (xy 123.693428 -105.130854)
			(xy 123.706128 -105.321354) (xy 123.807728 -105.321354)
		)
		(stroke
			(width 0)
			(type solid)
		)
		(fill yes)
		(layer "F.Cu")
		(net "M_L_DQ<55>")
	)
	(gr_poly
		(pts
			(xy 123.820428 -104.737154) (xy 123.820428 -104.686354) (xy 123.693428 -104.686354) (xy 123.693428 -104.737154)
			(xy 123.706128 -104.927654) (xy 123.807728 -104.927654)
		)
		(stroke
			(width 0)
			(type solid)
		)
		(fill yes)
		(layer "F.Cu")
		(net "M_L_DQ<50>")
	)
	(gr_poly
		(pts
			(xy 123.820428 -104.343454) (xy 123.820428 -104.292654) (xy 123.693428 -104.292654) (xy 123.693428 -104.343454)
			(xy 123.706128 -104.533954) (xy 123.807728 -104.533954)
		)
		(stroke
			(width 0)
			(type solid)
		)
		(fill yes)
		(layer "F.Cu")
		(net "M_L_DQ<51>")
	)
	(gr_poly
		(pts
			(xy 123.98629 -48.782224) (xy 123.98629 -48.731424) (xy 123.85929 -48.731424) (xy 123.85929 -48.782224)
			(xy 123.87199 -48.972724) (xy 123.97359 -48.972724)
		)
		(stroke
			(width 0)
			(type solid)
		)
		(fill yes)
		(layer "F.Cu")
		(net "M_H_DQ<51>")
	)
	(gr_poly
		(pts
			(xy 123.98629 -48.388524) (xy 123.98629 -48.337724) (xy 123.85929 -48.337724) (xy 123.85929 -48.388524)
			(xy 123.87199 -48.579024) (xy 123.97359 -48.579024)
		)
		(stroke
			(width 0)
			(type solid)
		)
		(fill yes)
		(layer "F.Cu")
		(net "M_H_DQ<50>")
	)
	(gr_poly
		(pts
			(xy 123.98629 -47.994824) (xy 123.98629 -47.944024) (xy 123.85929 -47.944024) (xy 123.85929 -47.994824)
			(xy 123.87199 -48.185324) (xy 123.97359 -48.185324)
		)
		(stroke
			(width 0)
			(type solid)
		)
		(fill yes)
		(layer "F.Cu")
		(net "M_H_DQ<55>")
	)
	(gr_poly
		(pts
			(xy 123.98629 -47.601124) (xy 123.98629 -47.550324) (xy 123.85929 -47.550324) (xy 123.85929 -47.601124)
			(xy 123.87199 -47.791624) (xy 123.97359 -47.791624)
		)
		(stroke
			(width 0)
			(type solid)
		)
		(fill yes)
		(layer "F.Cu")
		(net "M_H_DQ<54>")
	)
	(gr_poly
		(pts
			(xy 123.98629 -47.207424) (xy 123.98629 -47.156624) (xy 123.85929 -47.156624) (xy 123.85929 -47.207424)
			(xy 123.87199 -47.397924) (xy 123.97359 -47.397924)
		)
		(stroke
			(width 0)
			(type solid)
		)
		(fill yes)
		(layer "F.Cu")
		(net "M_H_DQS_DP<6>")
	)
	(gr_poly
		(pts
			(xy 123.98629 -46.813724) (xy 123.98629 -46.762924) (xy 123.85929 -46.762924) (xy 123.85929 -46.813724)
			(xy 123.87199 -47.004224) (xy 123.97359 -47.004224)
		)
		(stroke
			(width 0)
			(type solid)
		)
		(fill yes)
		(layer "F.Cu")
		(net "M_H_DQS_DN<6>")
	)
	(gr_poly
		(pts
			(xy 123.98629 -46.420024) (xy 123.98629 -46.369224) (xy 123.85929 -46.369224) (xy 123.85929 -46.420024)
			(xy 123.87199 -46.610524) (xy 123.97359 -46.610524)
		)
		(stroke
			(width 0)
			(type solid)
		)
		(fill yes)
		(layer "F.Cu")
		(net "M_H_DQS_DN<15>")
	)
	(gr_poly
		(pts
			(xy 123.98629 -46.026324) (xy 123.98629 -45.975524) (xy 123.85929 -45.975524) (xy 123.85929 -46.026324)
			(xy 123.87199 -46.216824) (xy 123.97359 -46.216824)
		)
		(stroke
			(width 0)
			(type solid)
		)
		(fill yes)
		(layer "F.Cu")
		(net "M_H_DQS_DP<15>")
	)
	(gr_poly
		(pts
			(xy 123.98629 -45.632624) (xy 123.98629 -45.581824) (xy 123.85929 -45.581824) (xy 123.85929 -45.632624)
			(xy 123.87199 -45.823124) (xy 123.97359 -45.823124)
		)
		(stroke
			(width 0)
			(type solid)
		)
		(fill yes)
		(layer "F.Cu")
		(net "M_H_DQ<49>")
	)
	(gr_poly
		(pts
			(xy 123.98629 -45.238924) (xy 123.98629 -45.188124) (xy 123.85929 -45.188124) (xy 123.85929 -45.238924)
			(xy 123.87199 -45.429424) (xy 123.97359 -45.429424)
		)
		(stroke
			(width 0)
			(type solid)
		)
		(fill yes)
		(layer "F.Cu")
		(net "M_H_DQ<48>")
	)
	(gr_poly
		(pts
			(xy 123.98629 -44.845224) (xy 123.98629 -44.794424) (xy 123.85929 -44.794424) (xy 123.85929 -44.845224)
			(xy 123.87199 -45.035724) (xy 123.97359 -45.035724)
		)
		(stroke
			(width 0)
			(type solid)
		)
		(fill yes)
		(layer "F.Cu")
		(net "M_H_DQ<53>")
	)
	(gr_poly
		(pts
			(xy 123.98629 -44.451524) (xy 123.98629 -44.400724) (xy 123.85929 -44.400724) (xy 123.85929 -44.451524)
			(xy 123.87199 -44.642024) (xy 123.97359 -44.642024)
		)
		(stroke
			(width 0)
			(type solid)
		)
		(fill yes)
		(layer "F.Cu")
		(net "M_H_DQ<52>")
	)
	(gr_poly
		(pts
			(xy 124.150628 -108.572554) (xy 124.137928 -108.382054) (xy 124.036328 -108.382054) (xy 124.023628 -108.572554)
			(xy 124.023628 -108.623354) (xy 124.150628 -108.623354)
		)
		(stroke
			(width 0)
			(type solid)
		)
		(fill yes)
		(layer "F.Cu")
		(net "M_L_DQ<52>")
	)
	(gr_poly
		(pts
			(xy 124.150628 -108.178854) (xy 124.137928 -107.988354) (xy 124.036328 -107.988354) (xy 124.023628 -108.178854)
			(xy 124.023628 -108.229654) (xy 124.150628 -108.229654)
		)
		(stroke
			(width 0)
			(type solid)
		)
		(fill yes)
		(layer "F.Cu")
		(net "M_L_DQ<53>")
	)
	(gr_poly
		(pts
			(xy 124.150628 -107.785154) (xy 124.137928 -107.594654) (xy 124.036328 -107.594654) (xy 124.023628 -107.785154)
			(xy 124.023628 -107.835954) (xy 124.150628 -107.835954)
		)
		(stroke
			(width 0)
			(type solid)
		)
		(fill yes)
		(layer "F.Cu")
		(net "M_L_DQ<48>")
	)
	(gr_poly
		(pts
			(xy 124.150628 -107.391454) (xy 124.137928 -107.200954) (xy 124.036328 -107.200954) (xy 124.023628 -107.391454)
			(xy 124.023628 -107.442254) (xy 124.150628 -107.442254)
		)
		(stroke
			(width 0)
			(type solid)
		)
		(fill yes)
		(layer "F.Cu")
		(net "M_L_DQ<49>")
	)
	(gr_poly
		(pts
			(xy 124.150628 -106.997754) (xy 124.137928 -106.807254) (xy 124.036328 -106.807254) (xy 124.023628 -106.997754)
			(xy 124.023628 -107.048554) (xy 124.150628 -107.048554)
		)
		(stroke
			(width 0)
			(type solid)
		)
		(fill yes)
		(layer "F.Cu")
		(net "M_L_DQS_DP<15>")
	)
	(gr_poly
		(pts
			(xy 124.150628 -106.604054) (xy 124.137928 -106.413554) (xy 124.036328 -106.413554) (xy 124.023628 -106.604054)
			(xy 124.023628 -106.654854) (xy 124.150628 -106.654854)
		)
		(stroke
			(width 0)
			(type solid)
		)
		(fill yes)
		(layer "F.Cu")
		(net "M_L_DQS_DN<15>")
	)
	(gr_poly
		(pts
			(xy 124.150628 -106.210354) (xy 124.137928 -106.019854) (xy 124.036328 -106.019854) (xy 124.023628 -106.210354)
			(xy 124.023628 -106.261154) (xy 124.150628 -106.261154)
		)
		(stroke
			(width 0)
			(type solid)
		)
		(fill yes)
		(layer "F.Cu")
		(net "M_L_DQS_DN<6>")
	)
	(gr_poly
		(pts
			(xy 124.150628 -105.816654) (xy 124.137928 -105.626154) (xy 124.036328 -105.626154) (xy 124.023628 -105.816654)
			(xy 124.023628 -105.867454) (xy 124.150628 -105.867454)
		)
		(stroke
			(width 0)
			(type solid)
		)
		(fill yes)
		(layer "F.Cu")
		(net "M_L_DQS_DP<6>")
	)
	(gr_poly
		(pts
			(xy 124.150628 -105.422954) (xy 124.137928 -105.232454) (xy 124.036328 -105.232454) (xy 124.023628 -105.422954)
			(xy 124.023628 -105.473754) (xy 124.150628 -105.473754)
		)
		(stroke
			(width 0)
			(type solid)
		)
		(fill yes)
		(layer "F.Cu")
		(net "M_L_DQ<54>")
	)
	(gr_poly
		(pts
			(xy 124.150628 -105.029254) (xy 124.137928 -104.838754) (xy 124.036328 -104.838754) (xy 124.023628 -105.029254)
			(xy 124.023628 -105.080054) (xy 124.150628 -105.080054)
		)
		(stroke
			(width 0)
			(type solid)
		)
		(fill yes)
		(layer "F.Cu")
		(net "M_L_DQ<55>")
	)
	(gr_poly
		(pts
			(xy 124.150628 -104.635554) (xy 124.137928 -104.445054) (xy 124.036328 -104.445054) (xy 124.023628 -104.635554)
			(xy 124.023628 -104.686354) (xy 124.150628 -104.686354)
		)
		(stroke
			(width 0)
			(type solid)
		)
		(fill yes)
		(layer "F.Cu")
		(net "M_L_DQ<50>")
	)
	(gr_poly
		(pts
			(xy 124.150628 -104.241854) (xy 124.137928 -104.051354) (xy 124.036328 -104.051354) (xy 124.023628 -104.241854)
			(xy 124.023628 -104.292654) (xy 124.150628 -104.292654)
		)
		(stroke
			(width 0)
			(type solid)
		)
		(fill yes)
		(layer "F.Cu")
		(net "M_L_DQ<51>")
	)
	(gr_poly
		(pts
			(xy 124.31649 -48.680624) (xy 124.30379 -48.490124) (xy 124.20219 -48.490124) (xy 124.18949 -48.680624)
			(xy 124.18949 -48.731424) (xy 124.31649 -48.731424)
		)
		(stroke
			(width 0)
			(type solid)
		)
		(fill yes)
		(layer "F.Cu")
		(net "M_H_DQ<51>")
	)
	(gr_poly
		(pts
			(xy 124.31649 -48.286924) (xy 124.30379 -48.096424) (xy 124.20219 -48.096424) (xy 124.18949 -48.286924)
			(xy 124.18949 -48.337724) (xy 124.31649 -48.337724)
		)
		(stroke
			(width 0)
			(type solid)
		)
		(fill yes)
		(layer "F.Cu")
		(net "M_H_DQ<50>")
	)
	(gr_poly
		(pts
			(xy 124.31649 -47.893224) (xy 124.30379 -47.702724) (xy 124.20219 -47.702724) (xy 124.18949 -47.893224)
			(xy 124.18949 -47.944024) (xy 124.31649 -47.944024)
		)
		(stroke
			(width 0)
			(type solid)
		)
		(fill yes)
		(layer "F.Cu")
		(net "M_H_DQ<55>")
	)
	(gr_poly
		(pts
			(xy 124.31649 -47.499524) (xy 124.30379 -47.309024) (xy 124.20219 -47.309024) (xy 124.18949 -47.499524)
			(xy 124.18949 -47.550324) (xy 124.31649 -47.550324)
		)
		(stroke
			(width 0)
			(type solid)
		)
		(fill yes)
		(layer "F.Cu")
		(net "M_H_DQ<54>")
	)
	(gr_poly
		(pts
			(xy 124.31649 -47.105824) (xy 124.30379 -46.915324) (xy 124.20219 -46.915324) (xy 124.18949 -47.105824)
			(xy 124.18949 -47.156624) (xy 124.31649 -47.156624)
		)
		(stroke
			(width 0)
			(type solid)
		)
		(fill yes)
		(layer "F.Cu")
		(net "M_H_DQS_DP<6>")
	)
	(gr_poly
		(pts
			(xy 124.31649 -46.712124) (xy 124.30379 -46.521624) (xy 124.20219 -46.521624) (xy 124.18949 -46.712124)
			(xy 124.18949 -46.762924) (xy 124.31649 -46.762924)
		)
		(stroke
			(width 0)
			(type solid)
		)
		(fill yes)
		(layer "F.Cu")
		(net "M_H_DQS_DN<6>")
	)
	(gr_poly
		(pts
			(xy 124.31649 -46.318424) (xy 124.30379 -46.127924) (xy 124.20219 -46.127924) (xy 124.18949 -46.318424)
			(xy 124.18949 -46.369224) (xy 124.31649 -46.369224)
		)
		(stroke
			(width 0)
			(type solid)
		)
		(fill yes)
		(layer "F.Cu")
		(net "M_H_DQS_DN<15>")
	)
	(gr_poly
		(pts
			(xy 124.31649 -45.924724) (xy 124.30379 -45.734224) (xy 124.20219 -45.734224) (xy 124.18949 -45.924724)
			(xy 124.18949 -45.975524) (xy 124.31649 -45.975524)
		)
		(stroke
			(width 0)
			(type solid)
		)
		(fill yes)
		(layer "F.Cu")
		(net "M_H_DQS_DP<15>")
	)
	(gr_poly
		(pts
			(xy 124.31649 -45.531024) (xy 124.30379 -45.340524) (xy 124.20219 -45.340524) (xy 124.18949 -45.531024)
			(xy 124.18949 -45.581824) (xy 124.31649 -45.581824)
		)
		(stroke
			(width 0)
			(type solid)
		)
		(fill yes)
		(layer "F.Cu")
		(net "M_H_DQ<49>")
	)
	(gr_poly
		(pts
			(xy 124.31649 -45.137324) (xy 124.30379 -44.946824) (xy 124.20219 -44.946824) (xy 124.18949 -45.137324)
			(xy 124.18949 -45.188124) (xy 124.31649 -45.188124)
		)
		(stroke
			(width 0)
			(type solid)
		)
		(fill yes)
		(layer "F.Cu")
		(net "M_H_DQ<48>")
	)
	(gr_poly
		(pts
			(xy 124.31649 -44.743624) (xy 124.30379 -44.553124) (xy 124.20219 -44.553124) (xy 124.18949 -44.743624)
			(xy 124.18949 -44.794424) (xy 124.31649 -44.794424)
		)
		(stroke
			(width 0)
			(type solid)
		)
		(fill yes)
		(layer "F.Cu")
		(net "M_H_DQ<53>")
	)
	(gr_poly
		(pts
			(xy 124.31649 -44.349924) (xy 124.30379 -44.159424) (xy 124.20219 -44.159424) (xy 124.18949 -44.349924)
			(xy 124.18949 -44.400724) (xy 124.31649 -44.400724)
		)
		(stroke
			(width 0)
			(type solid)
		)
		(fill yes)
		(layer "F.Cu")
		(net "M_H_DQ<52>")
	)
	(gr_poly
		(pts
			(xy 124.480828 -108.674154) (xy 124.480828 -108.623354) (xy 124.353828 -108.623354) (xy 124.353828 -108.674154)
			(xy 124.366528 -108.864654) (xy 124.468128 -108.864654)
		)
		(stroke
			(width 0)
			(type solid)
		)
		(fill yes)
		(layer "F.Cu")
		(net "M_L_DQ<52>")
	)
	(gr_poly
		(pts
			(xy 124.480828 -108.280454) (xy 124.480828 -108.229654) (xy 124.353828 -108.229654) (xy 124.353828 -108.280454)
			(xy 124.366528 -108.470954) (xy 124.468128 -108.470954)
		)
		(stroke
			(width 0)
			(type solid)
		)
		(fill yes)
		(layer "F.Cu")
		(net "M_L_DQ<53>")
	)
	(gr_poly
		(pts
			(xy 124.480828 -107.886754) (xy 124.480828 -107.835954) (xy 124.353828 -107.835954) (xy 124.353828 -107.886754)
			(xy 124.366528 -108.077254) (xy 124.468128 -108.077254)
		)
		(stroke
			(width 0)
			(type solid)
		)
		(fill yes)
		(layer "F.Cu")
		(net "M_L_DQ<48>")
	)
	(gr_poly
		(pts
			(xy 124.480828 -107.493054) (xy 124.480828 -107.442254) (xy 124.353828 -107.442254) (xy 124.353828 -107.493054)
			(xy 124.366528 -107.683554) (xy 124.468128 -107.683554)
		)
		(stroke
			(width 0)
			(type solid)
		)
		(fill yes)
		(layer "F.Cu")
		(net "M_L_DQ<49>")
	)
	(gr_poly
		(pts
			(xy 124.480828 -107.099354) (xy 124.480828 -107.048554) (xy 124.353828 -107.048554) (xy 124.353828 -107.099354)
			(xy 124.366528 -107.289854) (xy 124.468128 -107.289854)
		)
		(stroke
			(width 0)
			(type solid)
		)
		(fill yes)
		(layer "F.Cu")
		(net "M_L_DQS_DP<15>")
	)
	(gr_poly
		(pts
			(xy 124.480828 -106.705654) (xy 124.480828 -106.654854) (xy 124.353828 -106.654854) (xy 124.353828 -106.705654)
			(xy 124.366528 -106.896154) (xy 124.468128 -106.896154)
		)
		(stroke
			(width 0)
			(type solid)
		)
		(fill yes)
		(layer "F.Cu")
		(net "M_L_DQS_DN<15>")
	)
	(gr_poly
		(pts
			(xy 124.480828 -106.311954) (xy 124.480828 -106.261154) (xy 124.353828 -106.261154) (xy 124.353828 -106.311954)
			(xy 124.366528 -106.502454) (xy 124.468128 -106.502454)
		)
		(stroke
			(width 0)
			(type solid)
		)
		(fill yes)
		(layer "F.Cu")
		(net "M_L_DQS_DN<6>")
	)
	(gr_poly
		(pts
			(xy 124.480828 -105.918254) (xy 124.480828 -105.867454) (xy 124.353828 -105.867454) (xy 124.353828 -105.918254)
			(xy 124.366528 -106.108754) (xy 124.468128 -106.108754)
		)
		(stroke
			(width 0)
			(type solid)
		)
		(fill yes)
		(layer "F.Cu")
		(net "M_L_DQS_DP<6>")
	)
	(gr_poly
		(pts
			(xy 124.480828 -105.524554) (xy 124.480828 -105.473754) (xy 124.353828 -105.473754) (xy 124.353828 -105.524554)
			(xy 124.366528 -105.715054) (xy 124.468128 -105.715054)
		)
		(stroke
			(width 0)
			(type solid)
		)
		(fill yes)
		(layer "F.Cu")
		(net "M_L_DQ<54>")
	)
	(gr_poly
		(pts
			(xy 124.480828 -105.130854) (xy 124.480828 -105.080054) (xy 124.353828 -105.080054) (xy 124.353828 -105.130854)
			(xy 124.366528 -105.321354) (xy 124.468128 -105.321354)
		)
		(stroke
			(width 0)
			(type solid)
		)
		(fill yes)
		(layer "F.Cu")
		(net "M_L_DQ<55>")
	)
	(gr_poly
		(pts
			(xy 124.480828 -104.737154) (xy 124.480828 -104.686354) (xy 124.353828 -104.686354) (xy 124.353828 -104.737154)
			(xy 124.366528 -104.927654) (xy 124.468128 -104.927654)
		)
		(stroke
			(width 0)
			(type solid)
		)
		(fill yes)
		(layer "F.Cu")
		(net "M_L_DQ<50>")
	)
	(gr_poly
		(pts
			(xy 124.480828 -104.343454) (xy 124.480828 -104.292654) (xy 124.353828 -104.292654) (xy 124.353828 -104.343454)
			(xy 124.366528 -104.533954) (xy 124.468128 -104.533954)
		)
		(stroke
			(width 0)
			(type solid)
		)
		(fill yes)
		(layer "F.Cu")
		(net "M_L_DQ<51>")
	)
	(gr_poly
		(pts
			(xy 124.64669 -48.782224) (xy 124.64669 -48.731424) (xy 124.51969 -48.731424) (xy 124.51969 -48.782224)
			(xy 124.53239 -48.972724) (xy 124.63399 -48.972724)
		)
		(stroke
			(width 0)
			(type solid)
		)
		(fill yes)
		(layer "F.Cu")
		(net "M_H_DQ<51>")
	)
	(gr_poly
		(pts
			(xy 124.64669 -48.388524) (xy 124.64669 -48.337724) (xy 124.51969 -48.337724) (xy 124.51969 -48.388524)
			(xy 124.53239 -48.579024) (xy 124.63399 -48.579024)
		)
		(stroke
			(width 0)
			(type solid)
		)
		(fill yes)
		(layer "F.Cu")
		(net "M_H_DQ<50>")
	)
	(gr_poly
		(pts
			(xy 124.64669 -47.994824) (xy 124.64669 -47.944024) (xy 124.51969 -47.944024) (xy 124.51969 -47.994824)
			(xy 124.53239 -48.185324) (xy 124.63399 -48.185324)
		)
		(stroke
			(width 0)
			(type solid)
		)
		(fill yes)
		(layer "F.Cu")
		(net "M_H_DQ<55>")
	)
	(gr_poly
		(pts
			(xy 124.64669 -47.601124) (xy 124.64669 -47.550324) (xy 124.51969 -47.550324) (xy 124.51969 -47.601124)
			(xy 124.53239 -47.791624) (xy 124.63399 -47.791624)
		)
		(stroke
			(width 0)
			(type solid)
		)
		(fill yes)
		(layer "F.Cu")
		(net "M_H_DQ<54>")
	)
	(gr_poly
		(pts
			(xy 124.64669 -47.207424) (xy 124.64669 -47.156624) (xy 124.51969 -47.156624) (xy 124.51969 -47.207424)
			(xy 124.53239 -47.397924) (xy 124.63399 -47.397924)
		)
		(stroke
			(width 0)
			(type solid)
		)
		(fill yes)
		(layer "F.Cu")
		(net "M_H_DQS_DP<6>")
	)
	(gr_poly
		(pts
			(xy 124.64669 -46.813724) (xy 124.64669 -46.762924) (xy 124.51969 -46.762924) (xy 124.51969 -46.813724)
			(xy 124.53239 -47.004224) (xy 124.63399 -47.004224)
		)
		(stroke
			(width 0)
			(type solid)
		)
		(fill yes)
		(layer "F.Cu")
		(net "M_H_DQS_DN<6>")
	)
	(gr_poly
		(pts
			(xy 124.64669 -46.420024) (xy 124.64669 -46.369224) (xy 124.51969 -46.369224) (xy 124.51969 -46.420024)
			(xy 124.53239 -46.610524) (xy 124.63399 -46.610524)
		)
		(stroke
			(width 0)
			(type solid)
		)
		(fill yes)
		(layer "F.Cu")
		(net "M_H_DQS_DN<15>")
	)
	(gr_poly
		(pts
			(xy 124.64669 -46.026324) (xy 124.64669 -45.975524) (xy 124.51969 -45.975524) (xy 124.51969 -46.026324)
			(xy 124.53239 -46.216824) (xy 124.63399 -46.216824)
		)
		(stroke
			(width 0)
			(type solid)
		)
		(fill yes)
		(layer "F.Cu")
		(net "M_H_DQS_DP<15>")
	)
	(gr_poly
		(pts
			(xy 124.64669 -45.632624) (xy 124.64669 -45.581824) (xy 124.51969 -45.581824) (xy 124.51969 -45.632624)
			(xy 124.53239 -45.823124) (xy 124.63399 -45.823124)
		)
		(stroke
			(width 0)
			(type solid)
		)
		(fill yes)
		(layer "F.Cu")
		(net "M_H_DQ<49>")
	)
	(gr_poly
		(pts
			(xy 124.64669 -45.238924) (xy 124.64669 -45.188124) (xy 124.51969 -45.188124) (xy 124.51969 -45.238924)
			(xy 124.53239 -45.429424) (xy 124.63399 -45.429424)
		)
		(stroke
			(width 0)
			(type solid)
		)
		(fill yes)
		(layer "F.Cu")
		(net "M_H_DQ<48>")
	)
	(gr_poly
		(pts
			(xy 124.64669 -44.845224) (xy 124.64669 -44.794424) (xy 124.51969 -44.794424) (xy 124.51969 -44.845224)
			(xy 124.53239 -45.035724) (xy 124.63399 -45.035724)
		)
		(stroke
			(width 0)
			(type solid)
		)
		(fill yes)
		(layer "F.Cu")
		(net "M_H_DQ<53>")
	)
	(gr_poly
		(pts
			(xy 124.64669 -44.451524) (xy 124.64669 -44.400724) (xy 124.51969 -44.400724) (xy 124.51969 -44.451524)
			(xy 124.53239 -44.642024) (xy 124.63399 -44.642024)
		)
		(stroke
			(width 0)
			(type solid)
		)
		(fill yes)
		(layer "F.Cu")
		(net "M_H_DQ<52>")
	)
	(gr_poly
		(pts
			(xy 124.811028 -108.572554) (xy 124.798328 -108.382054) (xy 124.696728 -108.382054) (xy 124.684028 -108.572554)
			(xy 124.684028 -108.623354) (xy 124.811028 -108.623354)
		)
		(stroke
			(width 0)
			(type solid)
		)
		(fill yes)
		(layer "F.Cu")
		(net "M_L_DQ<52>")
	)
	(gr_poly
		(pts
			(xy 124.811028 -108.178854) (xy 124.798328 -107.988354) (xy 124.696728 -107.988354) (xy 124.684028 -108.178854)
			(xy 124.684028 -108.229654) (xy 124.811028 -108.229654)
		)
		(stroke
			(width 0)
			(type solid)
		)
		(fill yes)
		(layer "F.Cu")
		(net "M_L_DQ<53>")
	)
	(gr_poly
		(pts
			(xy 124.811028 -107.785154) (xy 124.798328 -107.594654) (xy 124.696728 -107.594654) (xy 124.684028 -107.785154)
			(xy 124.684028 -107.835954) (xy 124.811028 -107.835954)
		)
		(stroke
			(width 0)
			(type solid)
		)
		(fill yes)
		(layer "F.Cu")
		(net "M_L_DQ<48>")
	)
	(gr_poly
		(pts
			(xy 124.811028 -107.391454) (xy 124.798328 -107.200954) (xy 124.696728 -107.200954) (xy 124.684028 -107.391454)
			(xy 124.684028 -107.442254) (xy 124.811028 -107.442254)
		)
		(stroke
			(width 0)
			(type solid)
		)
		(fill yes)
		(layer "F.Cu")
		(net "M_L_DQ<49>")
	)
	(gr_poly
		(pts
			(xy 124.811028 -106.997754) (xy 124.798328 -106.807254) (xy 124.696728 -106.807254) (xy 124.684028 -106.997754)
			(xy 124.684028 -107.048554) (xy 124.811028 -107.048554)
		)
		(stroke
			(width 0)
			(type solid)
		)
		(fill yes)
		(layer "F.Cu")
		(net "M_L_DQS_DP<15>")
	)
	(gr_poly
		(pts
			(xy 124.811028 -106.604054) (xy 124.798328 -106.413554) (xy 124.696728 -106.413554) (xy 124.684028 -106.604054)
			(xy 124.684028 -106.654854) (xy 124.811028 -106.654854)
		)
		(stroke
			(width 0)
			(type solid)
		)
		(fill yes)
		(layer "F.Cu")
		(net "M_L_DQS_DN<15>")
	)
	(gr_poly
		(pts
			(xy 124.811028 -106.210354) (xy 124.798328 -106.019854) (xy 124.696728 -106.019854) (xy 124.684028 -106.210354)
			(xy 124.684028 -106.261154) (xy 124.811028 -106.261154)
		)
		(stroke
			(width 0)
			(type solid)
		)
		(fill yes)
		(layer "F.Cu")
		(net "M_L_DQS_DN<6>")
	)
	(gr_poly
		(pts
			(xy 124.811028 -105.816654) (xy 124.798328 -105.626154) (xy 124.696728 -105.626154) (xy 124.684028 -105.816654)
			(xy 124.684028 -105.867454) (xy 124.811028 -105.867454)
		)
		(stroke
			(width 0)
			(type solid)
		)
		(fill yes)
		(layer "F.Cu")
		(net "M_L_DQS_DP<6>")
	)
	(gr_poly
		(pts
			(xy 124.811028 -105.422954) (xy 124.798328 -105.232454) (xy 124.696728 -105.232454) (xy 124.684028 -105.422954)
			(xy 124.684028 -105.473754) (xy 124.811028 -105.473754)
		)
		(stroke
			(width 0)
			(type solid)
		)
		(fill yes)
		(layer "F.Cu")
		(net "M_L_DQ<54>")
	)
	(gr_poly
		(pts
			(xy 124.811028 -105.029254) (xy 124.798328 -104.838754) (xy 124.696728 -104.838754) (xy 124.684028 -105.029254)
			(xy 124.684028 -105.080054) (xy 124.811028 -105.080054)
		)
		(stroke
			(width 0)
			(type solid)
		)
		(fill yes)
		(layer "F.Cu")
		(net "M_L_DQ<55>")
	)
	(gr_poly
		(pts
			(xy 124.811028 -104.635554) (xy 124.798328 -104.445054) (xy 124.696728 -104.445054) (xy 124.684028 -104.635554)
			(xy 124.684028 -104.686354) (xy 124.811028 -104.686354)
		)
		(stroke
			(width 0)
			(type solid)
		)
		(fill yes)
		(layer "F.Cu")
		(net "M_L_DQ<50>")
	)
	(gr_poly
		(pts
			(xy 124.811028 -104.241854) (xy 124.798328 -104.051354) (xy 124.696728 -104.051354) (xy 124.684028 -104.241854)
			(xy 124.684028 -104.292654) (xy 124.811028 -104.292654)
		)
		(stroke
			(width 0)
			(type solid)
		)
		(fill yes)
		(layer "F.Cu")
		(net "M_L_DQ<51>")
	)
	(gr_poly
		(pts
			(xy 124.97689 -48.680624) (xy 124.96419 -48.490124) (xy 124.86259 -48.490124) (xy 124.84989 -48.680624)
			(xy 124.84989 -48.731424) (xy 124.97689 -48.731424)
		)
		(stroke
			(width 0)
			(type solid)
		)
		(fill yes)
		(layer "F.Cu")
		(net "M_H_DQ<51>")
	)
	(gr_poly
		(pts
			(xy 124.97689 -48.286924) (xy 124.96419 -48.096424) (xy 124.86259 -48.096424) (xy 124.84989 -48.286924)
			(xy 124.84989 -48.337724) (xy 124.97689 -48.337724)
		)
		(stroke
			(width 0)
			(type solid)
		)
		(fill yes)
		(layer "F.Cu")
		(net "M_H_DQ<50>")
	)
	(gr_poly
		(pts
			(xy 124.97689 -47.893224) (xy 124.96419 -47.702724) (xy 124.86259 -47.702724) (xy 124.84989 -47.893224)
			(xy 124.84989 -47.944024) (xy 124.97689 -47.944024)
		)
		(stroke
			(width 0)
			(type solid)
		)
		(fill yes)
		(layer "F.Cu")
		(net "M_H_DQ<55>")
	)
	(gr_poly
		(pts
			(xy 124.97689 -47.499524) (xy 124.96419 -47.309024) (xy 124.86259 -47.309024) (xy 124.84989 -47.499524)
			(xy 124.84989 -47.550324) (xy 124.97689 -47.550324)
		)
		(stroke
			(width 0)
			(type solid)
		)
		(fill yes)
		(layer "F.Cu")
		(net "M_H_DQ<54>")
	)
	(gr_poly
		(pts
			(xy 124.97689 -47.105824) (xy 124.96419 -46.915324) (xy 124.86259 -46.915324) (xy 124.84989 -47.105824)
			(xy 124.84989 -47.156624) (xy 124.97689 -47.156624)
		)
		(stroke
			(width 0)
			(type solid)
		)
		(fill yes)
		(layer "F.Cu")
		(net "M_H_DQS_DP<6>")
	)
	(gr_poly
		(pts
			(xy 124.97689 -46.712124) (xy 124.96419 -46.521624) (xy 124.86259 -46.521624) (xy 124.84989 -46.712124)
			(xy 124.84989 -46.762924) (xy 124.97689 -46.762924)
		)
		(stroke
			(width 0)
			(type solid)
		)
		(fill yes)
		(layer "F.Cu")
		(net "M_H_DQS_DN<6>")
	)
	(gr_poly
		(pts
			(xy 124.97689 -46.318424) (xy 124.96419 -46.127924) (xy 124.86259 -46.127924) (xy 124.84989 -46.318424)
			(xy 124.84989 -46.369224) (xy 124.97689 -46.369224)
		)
		(stroke
			(width 0)
			(type solid)
		)
		(fill yes)
		(layer "F.Cu")
		(net "M_H_DQS_DN<15>")
	)
	(gr_poly
		(pts
			(xy 124.97689 -45.924724) (xy 124.96419 -45.734224) (xy 124.86259 -45.734224) (xy 124.84989 -45.924724)
			(xy 124.84989 -45.975524) (xy 124.97689 -45.975524)
		)
		(stroke
			(width 0)
			(type solid)
		)
		(fill yes)
		(layer "F.Cu")
		(net "M_H_DQS_DP<15>")
	)
	(gr_poly
		(pts
			(xy 124.97689 -45.531024) (xy 124.96419 -45.340524) (xy 124.86259 -45.340524) (xy 124.84989 -45.531024)
			(xy 124.84989 -45.581824) (xy 124.97689 -45.581824)
		)
		(stroke
			(width 0)
			(type solid)
		)
		(fill yes)
		(layer "F.Cu")
		(net "M_H_DQ<49>")
	)
	(gr_poly
		(pts
			(xy 124.97689 -45.137324) (xy 124.96419 -44.946824) (xy 124.86259 -44.946824) (xy 124.84989 -45.137324)
			(xy 124.84989 -45.188124) (xy 124.97689 -45.188124)
		)
		(stroke
			(width 0)
			(type solid)
		)
		(fill yes)
		(layer "F.Cu")
		(net "M_H_DQ<48>")
	)
	(gr_poly
		(pts
			(xy 124.97689 -44.743624) (xy 124.96419 -44.553124) (xy 124.86259 -44.553124) (xy 124.84989 -44.743624)
			(xy 124.84989 -44.794424) (xy 124.97689 -44.794424)
		)
		(stroke
			(width 0)
			(type solid)
		)
		(fill yes)
		(layer "F.Cu")
		(net "M_H_DQ<53>")
	)
	(gr_poly
		(pts
			(xy 124.97689 -44.349924) (xy 124.96419 -44.159424) (xy 124.86259 -44.159424) (xy 124.84989 -44.349924)
			(xy 124.84989 -44.400724) (xy 124.97689 -44.400724)
		)
		(stroke
			(width 0)
			(type solid)
		)
		(fill yes)
		(layer "F.Cu")
		(net "M_H_DQ<52>")
	)
	(gr_poly
		(pts
			(xy 125.141228 -108.674154) (xy 125.141228 -108.623354) (xy 125.014228 -108.623354) (xy 125.014228 -108.674154)
			(xy 125.026928 -108.864654) (xy 125.128528 -108.864654)
		)
		(stroke
			(width 0)
			(type solid)
		)
		(fill yes)
		(layer "F.Cu")
		(net "M_L_DQ<52>")
	)
	(gr_poly
		(pts
			(xy 125.141228 -108.280454) (xy 125.141228 -108.229654) (xy 125.014228 -108.229654) (xy 125.014228 -108.280454)
			(xy 125.026928 -108.470954) (xy 125.128528 -108.470954)
		)
		(stroke
			(width 0)
			(type solid)
		)
		(fill yes)
		(layer "F.Cu")
		(net "M_L_DQ<53>")
	)
	(gr_poly
		(pts
			(xy 125.141228 -107.886754) (xy 125.141228 -107.835954) (xy 125.014228 -107.835954) (xy 125.014228 -107.886754)
			(xy 125.026928 -108.077254) (xy 125.128528 -108.077254)
		)
		(stroke
			(width 0)
			(type solid)
		)
		(fill yes)
		(layer "F.Cu")
		(net "M_L_DQ<48>")
	)
	(gr_poly
		(pts
			(xy 125.141228 -107.493054) (xy 125.141228 -107.442254) (xy 125.014228 -107.442254) (xy 125.014228 -107.493054)
			(xy 125.026928 -107.683554) (xy 125.128528 -107.683554)
		)
		(stroke
			(width 0)
			(type solid)
		)
		(fill yes)
		(layer "F.Cu")
		(net "M_L_DQ<49>")
	)
	(gr_poly
		(pts
			(xy 125.141228 -107.099354) (xy 125.141228 -107.048554) (xy 125.014228 -107.048554) (xy 125.014228 -107.099354)
			(xy 125.026928 -107.289854) (xy 125.128528 -107.289854)
		)
		(stroke
			(width 0)
			(type solid)
		)
		(fill yes)
		(layer "F.Cu")
		(net "M_L_DQS_DP<15>")
	)
	(gr_poly
		(pts
			(xy 125.141228 -106.705654) (xy 125.141228 -106.654854) (xy 125.014228 -106.654854) (xy 125.014228 -106.705654)
			(xy 125.026928 -106.896154) (xy 125.128528 -106.896154)
		)
		(stroke
			(width 0)
			(type solid)
		)
		(fill yes)
		(layer "F.Cu")
		(net "M_L_DQS_DN<15>")
	)
	(gr_poly
		(pts
			(xy 125.141228 -106.311954) (xy 125.141228 -106.261154) (xy 125.014228 -106.261154) (xy 125.014228 -106.311954)
			(xy 125.026928 -106.502454) (xy 125.128528 -106.502454)
		)
		(stroke
			(width 0)
			(type solid)
		)
		(fill yes)
		(layer "F.Cu")
		(net "M_L_DQS_DN<6>")
	)
	(gr_poly
		(pts
			(xy 125.141228 -105.918254) (xy 125.141228 -105.867454) (xy 125.014228 -105.867454) (xy 125.014228 -105.918254)
			(xy 125.026928 -106.108754) (xy 125.128528 -106.108754)
		)
		(stroke
			(width 0)
			(type solid)
		)
		(fill yes)
		(layer "F.Cu")
		(net "M_L_DQS_DP<6>")
	)
	(gr_poly
		(pts
			(xy 125.141228 -105.524554) (xy 125.141228 -105.473754) (xy 125.014228 -105.473754) (xy 125.014228 -105.524554)
			(xy 125.026928 -105.715054) (xy 125.128528 -105.715054)
		)
		(stroke
			(width 0)
			(type solid)
		)
		(fill yes)
		(layer "F.Cu")
		(net "M_L_DQ<54>")
	)
	(gr_poly
		(pts
			(xy 125.141228 -105.130854) (xy 125.141228 -105.080054) (xy 125.014228 -105.080054) (xy 125.014228 -105.130854)
			(xy 125.026928 -105.321354) (xy 125.128528 -105.321354)
		)
		(stroke
			(width 0)
			(type solid)
		)
		(fill yes)
		(layer "F.Cu")
		(net "M_L_DQ<55>")
	)
	(gr_poly
		(pts
			(xy 125.141228 -104.737154) (xy 125.141228 -104.686354) (xy 125.014228 -104.686354) (xy 125.014228 -104.737154)
			(xy 125.026928 -104.927654) (xy 125.128528 -104.927654)
		)
		(stroke
			(width 0)
			(type solid)
		)
		(fill yes)
		(layer "F.Cu")
		(net "M_L_DQ<50>")
	)
	(gr_poly
		(pts
			(xy 125.141228 -104.343454) (xy 125.141228 -104.292654) (xy 125.014228 -104.292654) (xy 125.014228 -104.343454)
			(xy 125.026928 -104.533954) (xy 125.128528 -104.533954)
		)
		(stroke
			(width 0)
			(type solid)
		)
		(fill yes)
		(layer "F.Cu")
		(net "M_L_DQ<51>")
	)
	(gr_poly
		(pts
			(xy 125.30709 -48.782224) (xy 125.30709 -48.731424) (xy 125.18009 -48.731424) (xy 125.18009 -48.782224)
			(xy 125.19279 -48.972724) (xy 125.29439 -48.972724)
		)
		(stroke
			(width 0)
			(type solid)
		)
		(fill yes)
		(layer "F.Cu")
		(net "M_H_DQ<51>")
	)
	(gr_poly
		(pts
			(xy 125.30709 -48.388524) (xy 125.30709 -48.337724) (xy 125.18009 -48.337724) (xy 125.18009 -48.388524)
			(xy 125.19279 -48.579024) (xy 125.29439 -48.579024)
		)
		(stroke
			(width 0)
			(type solid)
		)
		(fill yes)
		(layer "F.Cu")
		(net "M_H_DQ<50>")
	)
	(gr_poly
		(pts
			(xy 125.30709 -47.994824) (xy 125.30709 -47.944024) (xy 125.18009 -47.944024) (xy 125.18009 -47.994824)
			(xy 125.19279 -48.185324) (xy 125.29439 -48.185324)
		)
		(stroke
			(width 0)
			(type solid)
		)
		(fill yes)
		(layer "F.Cu")
		(net "M_H_DQ<55>")
	)
	(gr_poly
		(pts
			(xy 125.30709 -47.601124) (xy 125.30709 -47.550324) (xy 125.18009 -47.550324) (xy 125.18009 -47.601124)
			(xy 125.19279 -47.791624) (xy 125.29439 -47.791624)
		)
		(stroke
			(width 0)
			(type solid)
		)
		(fill yes)
		(layer "F.Cu")
		(net "M_H_DQ<54>")
	)
	(gr_poly
		(pts
			(xy 125.30709 -47.207424) (xy 125.30709 -47.156624) (xy 125.18009 -47.156624) (xy 125.18009 -47.207424)
			(xy 125.19279 -47.397924) (xy 125.29439 -47.397924)
		)
		(stroke
			(width 0)
			(type solid)
		)
		(fill yes)
		(layer "F.Cu")
		(net "M_H_DQS_DP<6>")
	)
	(gr_poly
		(pts
			(xy 125.30709 -46.813724) (xy 125.30709 -46.762924) (xy 125.18009 -46.762924) (xy 125.18009 -46.813724)
			(xy 125.19279 -47.004224) (xy 125.29439 -47.004224)
		)
		(stroke
			(width 0)
			(type solid)
		)
		(fill yes)
		(layer "F.Cu")
		(net "M_H_DQS_DN<6>")
	)
	(gr_poly
		(pts
			(xy 125.30709 -46.420024) (xy 125.30709 -46.369224) (xy 125.18009 -46.369224) (xy 125.18009 -46.420024)
			(xy 125.19279 -46.610524) (xy 125.29439 -46.610524)
		)
		(stroke
			(width 0)
			(type solid)
		)
		(fill yes)
		(layer "F.Cu")
		(net "M_H_DQS_DN<15>")
	)
	(gr_poly
		(pts
			(xy 125.30709 -46.026324) (xy 125.30709 -45.975524) (xy 125.18009 -45.975524) (xy 125.18009 -46.026324)
			(xy 125.19279 -46.216824) (xy 125.29439 -46.216824)
		)
		(stroke
			(width 0)
			(type solid)
		)
		(fill yes)
		(layer "F.Cu")
		(net "M_H_DQS_DP<15>")
	)
	(gr_poly
		(pts
			(xy 125.30709 -45.632624) (xy 125.30709 -45.581824) (xy 125.18009 -45.581824) (xy 125.18009 -45.632624)
			(xy 125.19279 -45.823124) (xy 125.29439 -45.823124)
		)
		(stroke
			(width 0)
			(type solid)
		)
		(fill yes)
		(layer "F.Cu")
		(net "M_H_DQ<49>")
	)
	(gr_poly
		(pts
			(xy 125.30709 -45.238924) (xy 125.30709 -45.188124) (xy 125.18009 -45.188124) (xy 125.18009 -45.238924)
			(xy 125.19279 -45.429424) (xy 125.29439 -45.429424)
		)
		(stroke
			(width 0)
			(type solid)
		)
		(fill yes)
		(layer "F.Cu")
		(net "M_H_DQ<48>")
	)
	(gr_poly
		(pts
			(xy 125.30709 -44.845224) (xy 125.30709 -44.794424) (xy 125.18009 -44.794424) (xy 125.18009 -44.845224)
			(xy 125.19279 -45.035724) (xy 125.29439 -45.035724)
		)
		(stroke
			(width 0)
			(type solid)
		)
		(fill yes)
		(layer "F.Cu")
		(net "M_H_DQ<53>")
	)
	(gr_poly
		(pts
			(xy 125.30709 -44.451524) (xy 125.30709 -44.400724) (xy 125.18009 -44.400724) (xy 125.18009 -44.451524)
			(xy 125.19279 -44.642024) (xy 125.29439 -44.642024)
		)
		(stroke
			(width 0)
			(type solid)
		)
		(fill yes)
		(layer "F.Cu")
		(net "M_H_DQ<52>")
	)
	(gr_poly
		(pts
			(xy 125.471428 -108.572554) (xy 125.458728 -108.382054) (xy 125.357128 -108.382054) (xy 125.344428 -108.572554)
			(xy 125.344428 -108.623354) (xy 125.471428 -108.623354)
		)
		(stroke
			(width 0)
			(type solid)
		)
		(fill yes)
		(layer "F.Cu")
		(net "M_L_DQ<52>")
	)
	(gr_poly
		(pts
			(xy 125.471428 -108.178854) (xy 125.458728 -107.988354) (xy 125.357128 -107.988354) (xy 125.344428 -108.178854)
			(xy 125.344428 -108.229654) (xy 125.471428 -108.229654)
		)
		(stroke
			(width 0)
			(type solid)
		)
		(fill yes)
		(layer "F.Cu")
		(net "M_L_DQ<53>")
	)
	(gr_poly
		(pts
			(xy 125.471428 -107.785154) (xy 125.458728 -107.594654) (xy 125.357128 -107.594654) (xy 125.344428 -107.785154)
			(xy 125.344428 -107.835954) (xy 125.471428 -107.835954)
		)
		(stroke
			(width 0)
			(type solid)
		)
		(fill yes)
		(layer "F.Cu")
		(net "M_L_DQ<48>")
	)
	(gr_poly
		(pts
			(xy 125.471428 -107.391454) (xy 125.458728 -107.200954) (xy 125.357128 -107.200954) (xy 125.344428 -107.391454)
			(xy 125.344428 -107.442254) (xy 125.471428 -107.442254)
		)
		(stroke
			(width 0)
			(type solid)
		)
		(fill yes)
		(layer "F.Cu")
		(net "M_L_DQ<49>")
	)
	(gr_poly
		(pts
			(xy 125.471428 -106.997754) (xy 125.458728 -106.807254) (xy 125.357128 -106.807254) (xy 125.344428 -106.997754)
			(xy 125.344428 -107.048554) (xy 125.471428 -107.048554)
		)
		(stroke
			(width 0)
			(type solid)
		)
		(fill yes)
		(layer "F.Cu")
		(net "M_L_DQS_DP<15>")
	)
	(gr_poly
		(pts
			(xy 125.471428 -106.604054) (xy 125.458728 -106.413554) (xy 125.357128 -106.413554) (xy 125.344428 -106.604054)
			(xy 125.344428 -106.654854) (xy 125.471428 -106.654854)
		)
		(stroke
			(width 0)
			(type solid)
		)
		(fill yes)
		(layer "F.Cu")
		(net "M_L_DQS_DN<15>")
	)
	(gr_poly
		(pts
			(xy 125.471428 -106.210354) (xy 125.458728 -106.019854) (xy 125.357128 -106.019854) (xy 125.344428 -106.210354)
			(xy 125.344428 -106.261154) (xy 125.471428 -106.261154)
		)
		(stroke
			(width 0)
			(type solid)
		)
		(fill yes)
		(layer "F.Cu")
		(net "M_L_DQS_DN<6>")
	)
	(gr_poly
		(pts
			(xy 125.471428 -105.816654) (xy 125.458728 -105.626154) (xy 125.357128 -105.626154) (xy 125.344428 -105.816654)
			(xy 125.344428 -105.867454) (xy 125.471428 -105.867454)
		)
		(stroke
			(width 0)
			(type solid)
		)
		(fill yes)
		(layer "F.Cu")
		(net "M_L_DQS_DP<6>")
	)
	(gr_poly
		(pts
			(xy 125.471428 -105.422954) (xy 125.458728 -105.232454) (xy 125.357128 -105.232454) (xy 125.344428 -105.422954)
			(xy 125.344428 -105.473754) (xy 125.471428 -105.473754)
		)
		(stroke
			(width 0)
			(type solid)
		)
		(fill yes)
		(layer "F.Cu")
		(net "M_L_DQ<54>")
	)
	(gr_poly
		(pts
			(xy 125.471428 -105.029254) (xy 125.458728 -104.838754) (xy 125.357128 -104.838754) (xy 125.344428 -105.029254)
			(xy 125.344428 -105.080054) (xy 125.471428 -105.080054)
		)
		(stroke
			(width 0)
			(type solid)
		)
		(fill yes)
		(layer "F.Cu")
		(net "M_L_DQ<55>")
	)
	(gr_poly
		(pts
			(xy 125.471428 -104.635554) (xy 125.458728 -104.445054) (xy 125.357128 -104.445054) (xy 125.344428 -104.635554)
			(xy 125.344428 -104.686354) (xy 125.471428 -104.686354)
		)
		(stroke
			(width 0)
			(type solid)
		)
		(fill yes)
		(layer "F.Cu")
		(net "M_L_DQ<50>")
	)
	(gr_poly
		(pts
			(xy 125.471428 -104.241854) (xy 125.458728 -104.051354) (xy 125.357128 -104.051354) (xy 125.344428 -104.241854)
			(xy 125.344428 -104.292654) (xy 125.471428 -104.292654)
		)
		(stroke
			(width 0)
			(type solid)
		)
		(fill yes)
		(layer "F.Cu")
		(net "M_L_DQ<51>")
	)
	(gr_poly
		(pts
			(xy 125.63729 -48.680624) (xy 125.62459 -48.490124) (xy 125.52299 -48.490124) (xy 125.51029 -48.680624)
			(xy 125.51029 -48.731424) (xy 125.63729 -48.731424)
		)
		(stroke
			(width 0)
			(type solid)
		)
		(fill yes)
		(layer "F.Cu")
		(net "M_H_DQ<51>")
	)
	(gr_poly
		(pts
			(xy 125.63729 -48.286924) (xy 125.62459 -48.096424) (xy 125.52299 -48.096424) (xy 125.51029 -48.286924)
			(xy 125.51029 -48.337724) (xy 125.63729 -48.337724)
		)
		(stroke
			(width 0)
			(type solid)
		)
		(fill yes)
		(layer "F.Cu")
		(net "M_H_DQ<50>")
	)
	(gr_poly
		(pts
			(xy 125.63729 -47.893224) (xy 125.62459 -47.702724) (xy 125.52299 -47.702724) (xy 125.51029 -47.893224)
			(xy 125.51029 -47.944024) (xy 125.63729 -47.944024)
		)
		(stroke
			(width 0)
			(type solid)
		)
		(fill yes)
		(layer "F.Cu")
		(net "M_H_DQ<55>")
	)
	(gr_poly
		(pts
			(xy 125.63729 -47.499524) (xy 125.62459 -47.309024) (xy 125.52299 -47.309024) (xy 125.51029 -47.499524)
			(xy 125.51029 -47.550324) (xy 125.63729 -47.550324)
		)
		(stroke
			(width 0)
			(type solid)
		)
		(fill yes)
		(layer "F.Cu")
		(net "M_H_DQ<54>")
	)
	(gr_poly
		(pts
			(xy 125.63729 -47.105824) (xy 125.62459 -46.915324) (xy 125.52299 -46.915324) (xy 125.51029 -47.105824)
			(xy 125.51029 -47.156624) (xy 125.63729 -47.156624)
		)
		(stroke
			(width 0)
			(type solid)
		)
		(fill yes)
		(layer "F.Cu")
		(net "M_H_DQS_DP<6>")
	)
	(gr_poly
		(pts
			(xy 125.63729 -46.712124) (xy 125.62459 -46.521624) (xy 125.52299 -46.521624) (xy 125.51029 -46.712124)
			(xy 125.51029 -46.762924) (xy 125.63729 -46.762924)
		)
		(stroke
			(width 0)
			(type solid)
		)
		(fill yes)
		(layer "F.Cu")
		(net "M_H_DQS_DN<6>")
	)
	(gr_poly
		(pts
			(xy 125.63729 -46.318424) (xy 125.62459 -46.127924) (xy 125.52299 -46.127924) (xy 125.51029 -46.318424)
			(xy 125.51029 -46.369224) (xy 125.63729 -46.369224)
		)
		(stroke
			(width 0)
			(type solid)
		)
		(fill yes)
		(layer "F.Cu")
		(net "M_H_DQS_DN<15>")
	)
	(gr_poly
		(pts
			(xy 125.63729 -45.924724) (xy 125.62459 -45.734224) (xy 125.52299 -45.734224) (xy 125.51029 -45.924724)
			(xy 125.51029 -45.975524) (xy 125.63729 -45.975524)
		)
		(stroke
			(width 0)
			(type solid)
		)
		(fill yes)
		(layer "F.Cu")
		(net "M_H_DQS_DP<15>")
	)
	(gr_poly
		(pts
			(xy 125.63729 -45.531024) (xy 125.62459 -45.340524) (xy 125.52299 -45.340524) (xy 125.51029 -45.531024)
			(xy 125.51029 -45.581824) (xy 125.63729 -45.581824)
		)
		(stroke
			(width 0)
			(type solid)
		)
		(fill yes)
		(layer "F.Cu")
		(net "M_H_DQ<49>")
	)
	(gr_poly
		(pts
			(xy 125.63729 -45.137324) (xy 125.62459 -44.946824) (xy 125.52299 -44.946824) (xy 125.51029 -45.137324)
			(xy 125.51029 -45.188124) (xy 125.63729 -45.188124)
		)
		(stroke
			(width 0)
			(type solid)
		)
		(fill yes)
		(layer "F.Cu")
		(net "M_H_DQ<48>")
	)
	(gr_poly
		(pts
			(xy 125.63729 -44.743624) (xy 125.62459 -44.553124) (xy 125.52299 -44.553124) (xy 125.51029 -44.743624)
			(xy 125.51029 -44.794424) (xy 125.63729 -44.794424)
		)
		(stroke
			(width 0)
			(type solid)
		)
		(fill yes)
		(layer "F.Cu")
		(net "M_H_DQ<53>")
	)
	(gr_poly
		(pts
			(xy 125.63729 -44.349924) (xy 125.62459 -44.159424) (xy 125.52299 -44.159424) (xy 125.51029 -44.349924)
			(xy 125.51029 -44.400724) (xy 125.63729 -44.400724)
		)
		(stroke
			(width 0)
			(type solid)
		)
		(fill yes)
		(layer "F.Cu")
		(net "M_H_DQ<52>")
	)
	(gr_poly
		(pts
			(xy 125.801628 -108.674154) (xy 125.801628 -108.623354) (xy 125.674628 -108.623354) (xy 125.674628 -108.674154)
			(xy 125.687328 -108.864654) (xy 125.788928 -108.864654)
		)
		(stroke
			(width 0)
			(type solid)
		)
		(fill yes)
		(layer "F.Cu")
		(net "M_L_DQ<52>")
	)
	(gr_poly
		(pts
			(xy 125.801628 -108.280454) (xy 125.801628 -108.229654) (xy 125.674628 -108.229654) (xy 125.674628 -108.280454)
			(xy 125.687328 -108.470954) (xy 125.788928 -108.470954)
		)
		(stroke
			(width 0)
			(type solid)
		)
		(fill yes)
		(layer "F.Cu")
		(net "M_L_DQ<53>")
	)
	(gr_poly
		(pts
			(xy 125.801628 -107.886754) (xy 125.801628 -107.835954) (xy 125.674628 -107.835954) (xy 125.674628 -107.886754)
			(xy 125.687328 -108.077254) (xy 125.788928 -108.077254)
		)
		(stroke
			(width 0)
			(type solid)
		)
		(fill yes)
		(layer "F.Cu")
		(net "M_L_DQ<48>")
	)
	(gr_poly
		(pts
			(xy 125.801628 -107.493054) (xy 125.801628 -107.442254) (xy 125.674628 -107.442254) (xy 125.674628 -107.493054)
			(xy 125.687328 -107.683554) (xy 125.788928 -107.683554)
		)
		(stroke
			(width 0)
			(type solid)
		)
		(fill yes)
		(layer "F.Cu")
		(net "M_L_DQ<49>")
	)
	(gr_poly
		(pts
			(xy 125.801628 -107.099354) (xy 125.801628 -107.048554) (xy 125.674628 -107.048554) (xy 125.674628 -107.099354)
			(xy 125.687328 -107.289854) (xy 125.788928 -107.289854)
		)
		(stroke
			(width 0)
			(type solid)
		)
		(fill yes)
		(layer "F.Cu")
		(net "M_L_DQS_DP<15>")
	)
	(gr_poly
		(pts
			(xy 125.801628 -106.705654) (xy 125.801628 -106.654854) (xy 125.674628 -106.654854) (xy 125.674628 -106.705654)
			(xy 125.687328 -106.896154) (xy 125.788928 -106.896154)
		)
		(stroke
			(width 0)
			(type solid)
		)
		(fill yes)
		(layer "F.Cu")
		(net "M_L_DQS_DN<15>")
	)
	(gr_poly
		(pts
			(xy 125.801628 -106.311954) (xy 125.801628 -106.261154) (xy 125.674628 -106.261154) (xy 125.674628 -106.311954)
			(xy 125.687328 -106.502454) (xy 125.788928 -106.502454)
		)
		(stroke
			(width 0)
			(type solid)
		)
		(fill yes)
		(layer "F.Cu")
		(net "M_L_DQS_DN<6>")
	)
	(gr_poly
		(pts
			(xy 125.801628 -105.918254) (xy 125.801628 -105.867454) (xy 125.674628 -105.867454) (xy 125.674628 -105.918254)
			(xy 125.687328 -106.108754) (xy 125.788928 -106.108754)
		)
		(stroke
			(width 0)
			(type solid)
		)
		(fill yes)
		(layer "F.Cu")
		(net "M_L_DQS_DP<6>")
	)
	(gr_poly
		(pts
			(xy 125.801628 -105.524554) (xy 125.801628 -105.473754) (xy 125.674628 -105.473754) (xy 125.674628 -105.524554)
			(xy 125.687328 -105.715054) (xy 125.788928 -105.715054)
		)
		(stroke
			(width 0)
			(type solid)
		)
		(fill yes)
		(layer "F.Cu")
		(net "M_L_DQ<54>")
	)
	(gr_poly
		(pts
			(xy 125.801628 -105.130854) (xy 125.801628 -105.080054) (xy 125.674628 -105.080054) (xy 125.674628 -105.130854)
			(xy 125.687328 -105.321354) (xy 125.788928 -105.321354)
		)
		(stroke
			(width 0)
			(type solid)
		)
		(fill yes)
		(layer "F.Cu")
		(net "M_L_DQ<55>")
	)
	(gr_poly
		(pts
			(xy 125.801628 -104.737154) (xy 125.801628 -104.686354) (xy 125.674628 -104.686354) (xy 125.674628 -104.737154)
			(xy 125.687328 -104.927654) (xy 125.788928 -104.927654)
		)
		(stroke
			(width 0)
			(type solid)
		)
		(fill yes)
		(layer "F.Cu")
		(net "M_L_DQ<50>")
	)
	(gr_poly
		(pts
			(xy 125.801628 -104.343454) (xy 125.801628 -104.292654) (xy 125.674628 -104.292654) (xy 125.674628 -104.343454)
			(xy 125.687328 -104.533954) (xy 125.788928 -104.533954)
		)
		(stroke
			(width 0)
			(type solid)
		)
		(fill yes)
		(layer "F.Cu")
		(net "M_L_DQ<51>")
	)
	(gr_poly
		(pts
			(xy 125.96749 -48.782224) (xy 125.96749 -48.731424) (xy 125.84049 -48.731424) (xy 125.84049 -48.782224)
			(xy 125.85319 -48.972724) (xy 125.95479 -48.972724)
		)
		(stroke
			(width 0)
			(type solid)
		)
		(fill yes)
		(layer "F.Cu")
		(net "M_H_DQ<51>")
	)
	(gr_poly
		(pts
			(xy 125.96749 -48.388524) (xy 125.96749 -48.337724) (xy 125.84049 -48.337724) (xy 125.84049 -48.388524)
			(xy 125.85319 -48.579024) (xy 125.95479 -48.579024)
		)
		(stroke
			(width 0)
			(type solid)
		)
		(fill yes)
		(layer "F.Cu")
		(net "M_H_DQ<50>")
	)
	(gr_poly
		(pts
			(xy 125.96749 -47.994824) (xy 125.96749 -47.944024) (xy 125.84049 -47.944024) (xy 125.84049 -47.994824)
			(xy 125.85319 -48.185324) (xy 125.95479 -48.185324)
		)
		(stroke
			(width 0)
			(type solid)
		)
		(fill yes)
		(layer "F.Cu")
		(net "M_H_DQ<55>")
	)
	(gr_poly
		(pts
			(xy 125.96749 -47.601124) (xy 125.96749 -47.550324) (xy 125.84049 -47.550324) (xy 125.84049 -47.601124)
			(xy 125.85319 -47.791624) (xy 125.95479 -47.791624)
		)
		(stroke
			(width 0)
			(type solid)
		)
		(fill yes)
		(layer "F.Cu")
		(net "M_H_DQ<54>")
	)
	(gr_poly
		(pts
			(xy 125.96749 -47.207424) (xy 125.96749 -47.156624) (xy 125.84049 -47.156624) (xy 125.84049 -47.207424)
			(xy 125.85319 -47.397924) (xy 125.95479 -47.397924)
		)
		(stroke
			(width 0)
			(type solid)
		)
		(fill yes)
		(layer "F.Cu")
		(net "M_H_DQS_DP<6>")
	)
	(gr_poly
		(pts
			(xy 125.96749 -46.813724) (xy 125.96749 -46.762924) (xy 125.84049 -46.762924) (xy 125.84049 -46.813724)
			(xy 125.85319 -47.004224) (xy 125.95479 -47.004224)
		)
		(stroke
			(width 0)
			(type solid)
		)
		(fill yes)
		(layer "F.Cu")
		(net "M_H_DQS_DN<6>")
	)
	(gr_poly
		(pts
			(xy 125.96749 -46.420024) (xy 125.96749 -46.369224) (xy 125.84049 -46.369224) (xy 125.84049 -46.420024)
			(xy 125.85319 -46.610524) (xy 125.95479 -46.610524)
		)
		(stroke
			(width 0)
			(type solid)
		)
		(fill yes)
		(layer "F.Cu")
		(net "M_H_DQS_DN<15>")
	)
	(gr_poly
		(pts
			(xy 125.96749 -46.026324) (xy 125.96749 -45.975524) (xy 125.84049 -45.975524) (xy 125.84049 -46.026324)
			(xy 125.85319 -46.216824) (xy 125.95479 -46.216824)
		)
		(stroke
			(width 0)
			(type solid)
		)
		(fill yes)
		(layer "F.Cu")
		(net "M_H_DQS_DP<15>")
	)
	(gr_poly
		(pts
			(xy 125.96749 -45.632624) (xy 125.96749 -45.581824) (xy 125.84049 -45.581824) (xy 125.84049 -45.632624)
			(xy 125.85319 -45.823124) (xy 125.95479 -45.823124)
		)
		(stroke
			(width 0)
			(type solid)
		)
		(fill yes)
		(layer "F.Cu")
		(net "M_H_DQ<49>")
	)
	(gr_poly
		(pts
			(xy 125.96749 -45.238924) (xy 125.96749 -45.188124) (xy 125.84049 -45.188124) (xy 125.84049 -45.238924)
			(xy 125.85319 -45.429424) (xy 125.95479 -45.429424)
		)
		(stroke
			(width 0)
			(type solid)
		)
		(fill yes)
		(layer "F.Cu")
		(net "M_H_DQ<48>")
	)
	(gr_poly
		(pts
			(xy 125.96749 -44.845224) (xy 125.96749 -44.794424) (xy 125.84049 -44.794424) (xy 125.84049 -44.845224)
			(xy 125.85319 -45.035724) (xy 125.95479 -45.035724)
		)
		(stroke
			(width 0)
			(type solid)
		)
		(fill yes)
		(layer "F.Cu")
		(net "M_H_DQ<53>")
	)
	(gr_poly
		(pts
			(xy 125.96749 -44.451524) (xy 125.96749 -44.400724) (xy 125.84049 -44.400724) (xy 125.84049 -44.451524)
			(xy 125.85319 -44.642024) (xy 125.95479 -44.642024)
		)
		(stroke
			(width 0)
			(type solid)
		)
		(fill yes)
		(layer "F.Cu")
		(net "M_H_DQ<52>")
	)
	(gr_poly
		(pts
			(xy 126.131828 -108.572554) (xy 126.119128 -108.382054) (xy 126.017528 -108.382054) (xy 126.004828 -108.572554)
			(xy 126.004828 -108.623354) (xy 126.131828 -108.623354)
		)
		(stroke
			(width 0)
			(type solid)
		)
		(fill yes)
		(layer "F.Cu")
		(net "M_L_DQ<52>")
	)
	(gr_poly
		(pts
			(xy 126.131828 -108.178854) (xy 126.119128 -107.988354) (xy 126.017528 -107.988354) (xy 126.004828 -108.178854)
			(xy 126.004828 -108.229654) (xy 126.131828 -108.229654)
		)
		(stroke
			(width 0)
			(type solid)
		)
		(fill yes)
		(layer "F.Cu")
		(net "M_L_DQ<53>")
	)
	(gr_poly
		(pts
			(xy 126.131828 -107.785154) (xy 126.119128 -107.594654) (xy 126.017528 -107.594654) (xy 126.004828 -107.785154)
			(xy 126.004828 -107.835954) (xy 126.131828 -107.835954)
		)
		(stroke
			(width 0)
			(type solid)
		)
		(fill yes)
		(layer "F.Cu")
		(net "M_L_DQ<48>")
	)
	(gr_poly
		(pts
			(xy 126.131828 -107.391454) (xy 126.119128 -107.200954) (xy 126.017528 -107.200954) (xy 126.004828 -107.391454)
			(xy 126.004828 -107.442254) (xy 126.131828 -107.442254)
		)
		(stroke
			(width 0)
			(type solid)
		)
		(fill yes)
		(layer "F.Cu")
		(net "M_L_DQ<49>")
	)
	(gr_poly
		(pts
			(xy 126.131828 -106.997754) (xy 126.119128 -106.807254) (xy 126.017528 -106.807254) (xy 126.004828 -106.997754)
			(xy 126.004828 -107.048554) (xy 126.131828 -107.048554)
		)
		(stroke
			(width 0)
			(type solid)
		)
		(fill yes)
		(layer "F.Cu")
		(net "M_L_DQS_DP<15>")
	)
	(gr_poly
		(pts
			(xy 126.131828 -106.604054) (xy 126.119128 -106.413554) (xy 126.017528 -106.413554) (xy 126.004828 -106.604054)
			(xy 126.004828 -106.654854) (xy 126.131828 -106.654854)
		)
		(stroke
			(width 0)
			(type solid)
		)
		(fill yes)
		(layer "F.Cu")
		(net "M_L_DQS_DN<15>")
	)
	(gr_poly
		(pts
			(xy 126.131828 -106.210354) (xy 126.119128 -106.019854) (xy 126.017528 -106.019854) (xy 126.004828 -106.210354)
			(xy 126.004828 -106.261154) (xy 126.131828 -106.261154)
		)
		(stroke
			(width 0)
			(type solid)
		)
		(fill yes)
		(layer "F.Cu")
		(net "M_L_DQS_DN<6>")
	)
	(gr_poly
		(pts
			(xy 126.131828 -105.816654) (xy 126.119128 -105.626154) (xy 126.017528 -105.626154) (xy 126.004828 -105.816654)
			(xy 126.004828 -105.867454) (xy 126.131828 -105.867454)
		)
		(stroke
			(width 0)
			(type solid)
		)
		(fill yes)
		(layer "F.Cu")
		(net "M_L_DQS_DP<6>")
	)
	(gr_poly
		(pts
			(xy 126.131828 -105.422954) (xy 126.119128 -105.232454) (xy 126.017528 -105.232454) (xy 126.004828 -105.422954)
			(xy 126.004828 -105.473754) (xy 126.131828 -105.473754)
		)
		(stroke
			(width 0)
			(type solid)
		)
		(fill yes)
		(layer "F.Cu")
		(net "M_L_DQ<54>")
	)
	(gr_poly
		(pts
			(xy 126.131828 -105.029254) (xy 126.119128 -104.838754) (xy 126.017528 -104.838754) (xy 126.004828 -105.029254)
			(xy 126.004828 -105.080054) (xy 126.131828 -105.080054)
		)
		(stroke
			(width 0)
			(type solid)
		)
		(fill yes)
		(layer "F.Cu")
		(net "M_L_DQ<55>")
	)
	(gr_poly
		(pts
			(xy 126.131828 -104.635554) (xy 126.119128 -104.445054) (xy 126.017528 -104.445054) (xy 126.004828 -104.635554)
			(xy 126.004828 -104.686354) (xy 126.131828 -104.686354)
		)
		(stroke
			(width 0)
			(type solid)
		)
		(fill yes)
		(layer "F.Cu")
		(net "M_L_DQ<50>")
	)
	(gr_poly
		(pts
			(xy 126.131828 -104.241854) (xy 126.119128 -104.051354) (xy 126.017528 -104.051354) (xy 126.004828 -104.241854)
			(xy 126.004828 -104.292654) (xy 126.131828 -104.292654)
		)
		(stroke
			(width 0)
			(type solid)
		)
		(fill yes)
		(layer "F.Cu")
		(net "M_L_DQ<51>")
	)
	(gr_poly
		(pts
			(xy 126.29769 -48.680624) (xy 126.28499 -48.490124) (xy 126.18339 -48.490124) (xy 126.17069 -48.680624)
			(xy 126.17069 -48.731424) (xy 126.29769 -48.731424)
		)
		(stroke
			(width 0)
			(type solid)
		)
		(fill yes)
		(layer "F.Cu")
		(net "M_H_DQ<51>")
	)
	(gr_poly
		(pts
			(xy 126.29769 -48.286924) (xy 126.28499 -48.096424) (xy 126.18339 -48.096424) (xy 126.17069 -48.286924)
			(xy 126.17069 -48.337724) (xy 126.29769 -48.337724)
		)
		(stroke
			(width 0)
			(type solid)
		)
		(fill yes)
		(layer "F.Cu")
		(net "M_H_DQ<50>")
	)
	(gr_poly
		(pts
			(xy 126.29769 -47.893224) (xy 126.28499 -47.702724) (xy 126.18339 -47.702724) (xy 126.17069 -47.893224)
			(xy 126.17069 -47.944024) (xy 126.29769 -47.944024)
		)
		(stroke
			(width 0)
			(type solid)
		)
		(fill yes)
		(layer "F.Cu")
		(net "M_H_DQ<55>")
	)
	(gr_poly
		(pts
			(xy 126.29769 -47.499524) (xy 126.28499 -47.309024) (xy 126.18339 -47.309024) (xy 126.17069 -47.499524)
			(xy 126.17069 -47.550324) (xy 126.29769 -47.550324)
		)
		(stroke
			(width 0)
			(type solid)
		)
		(fill yes)
		(layer "F.Cu")
		(net "M_H_DQ<54>")
	)
	(gr_poly
		(pts
			(xy 126.29769 -47.105824) (xy 126.28499 -46.915324) (xy 126.18339 -46.915324) (xy 126.17069 -47.105824)
			(xy 126.17069 -47.156624) (xy 126.29769 -47.156624)
		)
		(stroke
			(width 0)
			(type solid)
		)
		(fill yes)
		(layer "F.Cu")
		(net "M_H_DQS_DP<6>")
	)
	(gr_poly
		(pts
			(xy 126.29769 -46.712124) (xy 126.28499 -46.521624) (xy 126.18339 -46.521624) (xy 126.17069 -46.712124)
			(xy 126.17069 -46.762924) (xy 126.29769 -46.762924)
		)
		(stroke
			(width 0)
			(type solid)
		)
		(fill yes)
		(layer "F.Cu")
		(net "M_H_DQS_DN<6>")
	)
	(gr_poly
		(pts
			(xy 126.29769 -46.318424) (xy 126.28499 -46.127924) (xy 126.18339 -46.127924) (xy 126.17069 -46.318424)
			(xy 126.17069 -46.369224) (xy 126.29769 -46.369224)
		)
		(stroke
			(width 0)
			(type solid)
		)
		(fill yes)
		(layer "F.Cu")
		(net "M_H_DQS_DN<15>")
	)
	(gr_poly
		(pts
			(xy 126.29769 -45.924724) (xy 126.28499 -45.734224) (xy 126.18339 -45.734224) (xy 126.17069 -45.924724)
			(xy 126.17069 -45.975524) (xy 126.29769 -45.975524)
		)
		(stroke
			(width 0)
			(type solid)
		)
		(fill yes)
		(layer "F.Cu")
		(net "M_H_DQS_DP<15>")
	)
	(gr_poly
		(pts
			(xy 126.29769 -45.531024) (xy 126.28499 -45.340524) (xy 126.18339 -45.340524) (xy 126.17069 -45.531024)
			(xy 126.17069 -45.581824) (xy 126.29769 -45.581824)
		)
		(stroke
			(width 0)
			(type solid)
		)
		(fill yes)
		(layer "F.Cu")
		(net "M_H_DQ<49>")
	)
	(gr_poly
		(pts
			(xy 126.29769 -45.137324) (xy 126.28499 -44.946824) (xy 126.18339 -44.946824) (xy 126.17069 -45.137324)
			(xy 126.17069 -45.188124) (xy 126.29769 -45.188124)
		)
		(stroke
			(width 0)
			(type solid)
		)
		(fill yes)
		(layer "F.Cu")
		(net "M_H_DQ<48>")
	)
	(gr_poly
		(pts
			(xy 126.29769 -44.743624) (xy 126.28499 -44.553124) (xy 126.18339 -44.553124) (xy 126.17069 -44.743624)
			(xy 126.17069 -44.794424) (xy 126.29769 -44.794424)
		)
		(stroke
			(width 0)
			(type solid)
		)
		(fill yes)
		(layer "F.Cu")
		(net "M_H_DQ<53>")
	)
	(gr_poly
		(pts
			(xy 126.29769 -44.349924) (xy 126.28499 -44.159424) (xy 126.18339 -44.159424) (xy 126.17069 -44.349924)
			(xy 126.17069 -44.400724) (xy 126.29769 -44.400724)
		)
		(stroke
			(width 0)
			(type solid)
		)
		(fill yes)
		(layer "F.Cu")
		(net "M_H_DQ<52>")
	)
	(gr_poly
		(pts
			(xy 126.462028 -108.674154) (xy 126.462028 -108.623354) (xy 126.335028 -108.623354) (xy 126.335028 -108.674154)
			(xy 126.347728 -108.864654) (xy 126.449328 -108.864654)
		)
		(stroke
			(width 0)
			(type solid)
		)
		(fill yes)
		(layer "F.Cu")
		(net "M_L_DQ<52>")
	)
	(gr_poly
		(pts
			(xy 126.462028 -108.280454) (xy 126.462028 -108.229654) (xy 126.335028 -108.229654) (xy 126.335028 -108.280454)
			(xy 126.347728 -108.470954) (xy 126.449328 -108.470954)
		)
		(stroke
			(width 0)
			(type solid)
		)
		(fill yes)
		(layer "F.Cu")
		(net "M_L_DQ<53>")
	)
	(gr_poly
		(pts
			(xy 126.462028 -107.886754) (xy 126.462028 -107.835954) (xy 126.335028 -107.835954) (xy 126.335028 -107.886754)
			(xy 126.347728 -108.077254) (xy 126.449328 -108.077254)
		)
		(stroke
			(width 0)
			(type solid)
		)
		(fill yes)
		(layer "F.Cu")
		(net "M_L_DQ<48>")
	)
	(gr_poly
		(pts
			(xy 126.462028 -107.493054) (xy 126.462028 -107.442254) (xy 126.335028 -107.442254) (xy 126.335028 -107.493054)
			(xy 126.347728 -107.683554) (xy 126.449328 -107.683554)
		)
		(stroke
			(width 0)
			(type solid)
		)
		(fill yes)
		(layer "F.Cu")
		(net "M_L_DQ<49>")
	)
	(gr_poly
		(pts
			(xy 126.462028 -107.099354) (xy 126.462028 -107.048554) (xy 126.335028 -107.048554) (xy 126.335028 -107.099354)
			(xy 126.347728 -107.289854) (xy 126.449328 -107.289854)
		)
		(stroke
			(width 0)
			(type solid)
		)
		(fill yes)
		(layer "F.Cu")
		(net "M_L_DQS_DP<15>")
	)
	(gr_poly
		(pts
			(xy 126.462028 -106.705654) (xy 126.462028 -106.654854) (xy 126.335028 -106.654854) (xy 126.335028 -106.705654)
			(xy 126.347728 -106.896154) (xy 126.449328 -106.896154)
		)
		(stroke
			(width 0)
			(type solid)
		)
		(fill yes)
		(layer "F.Cu")
		(net "M_L_DQS_DN<15>")
	)
	(gr_poly
		(pts
			(xy 126.462028 -106.311954) (xy 126.462028 -106.261154) (xy 126.335028 -106.261154) (xy 126.335028 -106.311954)
			(xy 126.347728 -106.502454) (xy 126.449328 -106.502454)
		)
		(stroke
			(width 0)
			(type solid)
		)
		(fill yes)
		(layer "F.Cu")
		(net "M_L_DQS_DN<6>")
	)
	(gr_poly
		(pts
			(xy 126.462028 -105.918254) (xy 126.462028 -105.867454) (xy 126.335028 -105.867454) (xy 126.335028 -105.918254)
			(xy 126.347728 -106.108754) (xy 126.449328 -106.108754)
		)
		(stroke
			(width 0)
			(type solid)
		)
		(fill yes)
		(layer "F.Cu")
		(net "M_L_DQS_DP<6>")
	)
	(gr_poly
		(pts
			(xy 126.462028 -105.524554) (xy 126.462028 -105.473754) (xy 126.335028 -105.473754) (xy 126.335028 -105.524554)
			(xy 126.347728 -105.715054) (xy 126.449328 -105.715054)
		)
		(stroke
			(width 0)
			(type solid)
		)
		(fill yes)
		(layer "F.Cu")
		(net "M_L_DQ<54>")
	)
	(gr_poly
		(pts
			(xy 126.462028 -105.130854) (xy 126.462028 -105.080054) (xy 126.335028 -105.080054) (xy 126.335028 -105.130854)
			(xy 126.347728 -105.321354) (xy 126.449328 -105.321354)
		)
		(stroke
			(width 0)
			(type solid)
		)
		(fill yes)
		(layer "F.Cu")
		(net "M_L_DQ<55>")
	)
	(gr_poly
		(pts
			(xy 126.462028 -104.737154) (xy 126.462028 -104.686354) (xy 126.335028 -104.686354) (xy 126.335028 -104.737154)
			(xy 126.347728 -104.927654) (xy 126.449328 -104.927654)
		)
		(stroke
			(width 0)
			(type solid)
		)
		(fill yes)
		(layer "F.Cu")
		(net "M_L_DQ<50>")
	)
	(gr_poly
		(pts
			(xy 126.462028 -104.343454) (xy 126.462028 -104.292654) (xy 126.335028 -104.292654) (xy 126.335028 -104.343454)
			(xy 126.347728 -104.533954) (xy 126.449328 -104.533954)
		)
		(stroke
			(width 0)
			(type solid)
		)
		(fill yes)
		(layer "F.Cu")
		(net "M_L_DQ<51>")
	)
	(gr_poly
		(pts
			(xy 126.62789 -48.782224) (xy 126.62789 -48.731424) (xy 126.50089 -48.731424) (xy 126.50089 -48.782224)
			(xy 126.51359 -48.972724) (xy 126.61519 -48.972724)
		)
		(stroke
			(width 0)
			(type solid)
		)
		(fill yes)
		(layer "F.Cu")
		(net "M_H_DQ<51>")
	)
	(gr_poly
		(pts
			(xy 126.62789 -48.388524) (xy 126.62789 -48.337724) (xy 126.50089 -48.337724) (xy 126.50089 -48.388524)
			(xy 126.51359 -48.579024) (xy 126.61519 -48.579024)
		)
		(stroke
			(width 0)
			(type solid)
		)
		(fill yes)
		(layer "F.Cu")
		(net "M_H_DQ<50>")
	)
	(gr_poly
		(pts
			(xy 126.62789 -47.994824) (xy 126.62789 -47.944024) (xy 126.50089 -47.944024) (xy 126.50089 -47.994824)
			(xy 126.51359 -48.185324) (xy 126.61519 -48.185324)
		)
		(stroke
			(width 0)
			(type solid)
		)
		(fill yes)
		(layer "F.Cu")
		(net "M_H_DQ<55>")
	)
	(gr_poly
		(pts
			(xy 126.62789 -47.601124) (xy 126.62789 -47.550324) (xy 126.50089 -47.550324) (xy 126.50089 -47.601124)
			(xy 126.51359 -47.791624) (xy 126.61519 -47.791624)
		)
		(stroke
			(width 0)
			(type solid)
		)
		(fill yes)
		(layer "F.Cu")
		(net "M_H_DQ<54>")
	)
	(gr_poly
		(pts
			(xy 126.62789 -47.207424) (xy 126.62789 -47.156624) (xy 126.50089 -47.156624) (xy 126.50089 -47.207424)
			(xy 126.51359 -47.397924) (xy 126.61519 -47.397924)
		)
		(stroke
			(width 0)
			(type solid)
		)
		(fill yes)
		(layer "F.Cu")
		(net "M_H_DQS_DP<6>")
	)
	(gr_poly
		(pts
			(xy 126.62789 -46.813724) (xy 126.62789 -46.762924) (xy 126.50089 -46.762924) (xy 126.50089 -46.813724)
			(xy 126.51359 -47.004224) (xy 126.61519 -47.004224)
		)
		(stroke
			(width 0)
			(type solid)
		)
		(fill yes)
		(layer "F.Cu")
		(net "M_H_DQS_DN<6>")
	)
	(gr_poly
		(pts
			(xy 126.62789 -46.420024) (xy 126.62789 -46.369224) (xy 126.50089 -46.369224) (xy 126.50089 -46.420024)
			(xy 126.51359 -46.610524) (xy 126.61519 -46.610524)
		)
		(stroke
			(width 0)
			(type solid)
		)
		(fill yes)
		(layer "F.Cu")
		(net "M_H_DQS_DN<15>")
	)
	(gr_poly
		(pts
			(xy 126.62789 -46.026324) (xy 126.62789 -45.975524) (xy 126.50089 -45.975524) (xy 126.50089 -46.026324)
			(xy 126.51359 -46.216824) (xy 126.61519 -46.216824)
		)
		(stroke
			(width 0)
			(type solid)
		)
		(fill yes)
		(layer "F.Cu")
		(net "M_H_DQS_DP<15>")
	)
	(gr_poly
		(pts
			(xy 126.62789 -45.632624) (xy 126.62789 -45.581824) (xy 126.50089 -45.581824) (xy 126.50089 -45.632624)
			(xy 126.51359 -45.823124) (xy 126.61519 -45.823124)
		)
		(stroke
			(width 0)
			(type solid)
		)
		(fill yes)
		(layer "F.Cu")
		(net "M_H_DQ<49>")
	)
	(gr_poly
		(pts
			(xy 126.62789 -45.238924) (xy 126.62789 -45.188124) (xy 126.50089 -45.188124) (xy 126.50089 -45.238924)
			(xy 126.51359 -45.429424) (xy 126.61519 -45.429424)
		)
		(stroke
			(width 0)
			(type solid)
		)
		(fill yes)
		(layer "F.Cu")
		(net "M_H_DQ<48>")
	)
	(gr_poly
		(pts
			(xy 126.62789 -44.845224) (xy 126.62789 -44.794424) (xy 126.50089 -44.794424) (xy 126.50089 -44.845224)
			(xy 126.51359 -45.035724) (xy 126.61519 -45.035724)
		)
		(stroke
			(width 0)
			(type solid)
		)
		(fill yes)
		(layer "F.Cu")
		(net "M_H_DQ<53>")
	)
	(gr_poly
		(pts
			(xy 126.62789 -44.451524) (xy 126.62789 -44.400724) (xy 126.50089 -44.400724) (xy 126.50089 -44.451524)
			(xy 126.51359 -44.642024) (xy 126.61519 -44.642024)
		)
		(stroke
			(width 0)
			(type solid)
		)
		(fill yes)
		(layer "F.Cu")
		(net "M_H_DQ<52>")
	)
	(gr_poly
		(pts
			(xy 126.792228 -108.572554) (xy 126.779528 -108.382054) (xy 126.677928 -108.382054) (xy 126.665228 -108.572554)
			(xy 126.665228 -108.623354) (xy 126.792228 -108.623354)
		)
		(stroke
			(width 0)
			(type solid)
		)
		(fill yes)
		(layer "F.Cu")
		(net "M_L_DQ<52>")
	)
	(gr_poly
		(pts
			(xy 126.792228 -108.178854) (xy 126.779528 -107.988354) (xy 126.677928 -107.988354) (xy 126.665228 -108.178854)
			(xy 126.665228 -108.229654) (xy 126.792228 -108.229654)
		)
		(stroke
			(width 0)
			(type solid)
		)
		(fill yes)
		(layer "F.Cu")
		(net "M_L_DQ<53>")
	)
	(gr_poly
		(pts
			(xy 126.792228 -107.785154) (xy 126.779528 -107.594654) (xy 126.677928 -107.594654) (xy 126.665228 -107.785154)
			(xy 126.665228 -107.835954) (xy 126.792228 -107.835954)
		)
		(stroke
			(width 0)
			(type solid)
		)
		(fill yes)
		(layer "F.Cu")
		(net "M_L_DQ<48>")
	)
	(gr_poly
		(pts
			(xy 126.792228 -107.391454) (xy 126.779528 -107.200954) (xy 126.677928 -107.200954) (xy 126.665228 -107.391454)
			(xy 126.665228 -107.442254) (xy 126.792228 -107.442254)
		)
		(stroke
			(width 0)
			(type solid)
		)
		(fill yes)
		(layer "F.Cu")
		(net "M_L_DQ<49>")
	)
	(gr_poly
		(pts
			(xy 126.792228 -106.997754) (xy 126.779528 -106.807254) (xy 126.677928 -106.807254) (xy 126.665228 -106.997754)
			(xy 126.665228 -107.048554) (xy 126.792228 -107.048554)
		)
		(stroke
			(width 0)
			(type solid)
		)
		(fill yes)
		(layer "F.Cu")
		(net "M_L_DQS_DP<15>")
	)
	(gr_poly
		(pts
			(xy 126.792228 -106.604054) (xy 126.779528 -106.413554) (xy 126.677928 -106.413554) (xy 126.665228 -106.604054)
			(xy 126.665228 -106.654854) (xy 126.792228 -106.654854)
		)
		(stroke
			(width 0)
			(type solid)
		)
		(fill yes)
		(layer "F.Cu")
		(net "M_L_DQS_DN<15>")
	)
	(gr_poly
		(pts
			(xy 126.792228 -106.210354) (xy 126.779528 -106.019854) (xy 126.677928 -106.019854) (xy 126.665228 -106.210354)
			(xy 126.665228 -106.261154) (xy 126.792228 -106.261154)
		)
		(stroke
			(width 0)
			(type solid)
		)
		(fill yes)
		(layer "F.Cu")
		(net "M_L_DQS_DN<6>")
	)
	(gr_poly
		(pts
			(xy 126.792228 -105.816654) (xy 126.779528 -105.626154) (xy 126.677928 -105.626154) (xy 126.665228 -105.816654)
			(xy 126.665228 -105.867454) (xy 126.792228 -105.867454)
		)
		(stroke
			(width 0)
			(type solid)
		)
		(fill yes)
		(layer "F.Cu")
		(net "M_L_DQS_DP<6>")
	)
	(gr_poly
		(pts
			(xy 126.792228 -105.422954) (xy 126.779528 -105.232454) (xy 126.677928 -105.232454) (xy 126.665228 -105.422954)
			(xy 126.665228 -105.473754) (xy 126.792228 -105.473754)
		)
		(stroke
			(width 0)
			(type solid)
		)
		(fill yes)
		(layer "F.Cu")
		(net "M_L_DQ<54>")
	)
	(gr_poly
		(pts
			(xy 126.792228 -105.029254) (xy 126.779528 -104.838754) (xy 126.677928 -104.838754) (xy 126.665228 -105.029254)
			(xy 126.665228 -105.080054) (xy 126.792228 -105.080054)
		)
		(stroke
			(width 0)
			(type solid)
		)
		(fill yes)
		(layer "F.Cu")
		(net "M_L_DQ<55>")
	)
	(gr_poly
		(pts
			(xy 126.792228 -104.635554) (xy 126.779528 -104.445054) (xy 126.677928 -104.445054) (xy 126.665228 -104.635554)
			(xy 126.665228 -104.686354) (xy 126.792228 -104.686354)
		)
		(stroke
			(width 0)
			(type solid)
		)
		(fill yes)
		(layer "F.Cu")
		(net "M_L_DQ<50>")
	)
	(gr_poly
		(pts
			(xy 126.792228 -104.241854) (xy 126.779528 -104.051354) (xy 126.677928 -104.051354) (xy 126.665228 -104.241854)
			(xy 126.665228 -104.292654) (xy 126.792228 -104.292654)
		)
		(stroke
			(width 0)
			(type solid)
		)
		(fill yes)
		(layer "F.Cu")
		(net "M_L_DQ<51>")
	)
	(gr_poly
		(pts
			(xy 126.95809 -48.680624) (xy 126.94539 -48.490124) (xy 126.84379 -48.490124) (xy 126.83109 -48.680624)
			(xy 126.83109 -48.731424) (xy 126.95809 -48.731424)
		)
		(stroke
			(width 0)
			(type solid)
		)
		(fill yes)
		(layer "F.Cu")
		(net "M_H_DQ<51>")
	)
	(gr_poly
		(pts
			(xy 126.95809 -48.286924) (xy 126.94539 -48.096424) (xy 126.84379 -48.096424) (xy 126.83109 -48.286924)
			(xy 126.83109 -48.337724) (xy 126.95809 -48.337724)
		)
		(stroke
			(width 0)
			(type solid)
		)
		(fill yes)
		(layer "F.Cu")
		(net "M_H_DQ<50>")
	)
	(gr_poly
		(pts
			(xy 126.95809 -47.893224) (xy 126.94539 -47.702724) (xy 126.84379 -47.702724) (xy 126.83109 -47.893224)
			(xy 126.83109 -47.944024) (xy 126.95809 -47.944024)
		)
		(stroke
			(width 0)
			(type solid)
		)
		(fill yes)
		(layer "F.Cu")
		(net "M_H_DQ<55>")
	)
	(gr_poly
		(pts
			(xy 126.95809 -47.499524) (xy 126.94539 -47.309024) (xy 126.84379 -47.309024) (xy 126.83109 -47.499524)
			(xy 126.83109 -47.550324) (xy 126.95809 -47.550324)
		)
		(stroke
			(width 0)
			(type solid)
		)
		(fill yes)
		(layer "F.Cu")
		(net "M_H_DQ<54>")
	)
	(gr_poly
		(pts
			(xy 126.95809 -47.105824) (xy 126.94539 -46.915324) (xy 126.84379 -46.915324) (xy 126.83109 -47.105824)
			(xy 126.83109 -47.156624) (xy 126.95809 -47.156624)
		)
		(stroke
			(width 0)
			(type solid)
		)
		(fill yes)
		(layer "F.Cu")
		(net "M_H_DQS_DP<6>")
	)
	(gr_poly
		(pts
			(xy 126.95809 -46.712124) (xy 126.94539 -46.521624) (xy 126.84379 -46.521624) (xy 126.83109 -46.712124)
			(xy 126.83109 -46.762924) (xy 126.95809 -46.762924)
		)
		(stroke
			(width 0)
			(type solid)
		)
		(fill yes)
		(layer "F.Cu")
		(net "M_H_DQS_DN<6>")
	)
	(gr_poly
		(pts
			(xy 126.95809 -46.318424) (xy 126.94539 -46.127924) (xy 126.84379 -46.127924) (xy 126.83109 -46.318424)
			(xy 126.83109 -46.369224) (xy 126.95809 -46.369224)
		)
		(stroke
			(width 0)
			(type solid)
		)
		(fill yes)
		(layer "F.Cu")
		(net "M_H_DQS_DN<15>")
	)
	(gr_poly
		(pts
			(xy 126.95809 -45.924724) (xy 126.94539 -45.734224) (xy 126.84379 -45.734224) (xy 126.83109 -45.924724)
			(xy 126.83109 -45.975524) (xy 126.95809 -45.975524)
		)
		(stroke
			(width 0)
			(type solid)
		)
		(fill yes)
		(layer "F.Cu")
		(net "M_H_DQS_DP<15>")
	)
	(gr_poly
		(pts
			(xy 126.95809 -45.531024) (xy 126.94539 -45.340524) (xy 126.84379 -45.340524) (xy 126.83109 -45.531024)
			(xy 126.83109 -45.581824) (xy 126.95809 -45.581824)
		)
		(stroke
			(width 0)
			(type solid)
		)
		(fill yes)
		(layer "F.Cu")
		(net "M_H_DQ<49>")
	)
	(gr_poly
		(pts
			(xy 126.95809 -45.137324) (xy 126.94539 -44.946824) (xy 126.84379 -44.946824) (xy 126.83109 -45.137324)
			(xy 126.83109 -45.188124) (xy 126.95809 -45.188124)
		)
		(stroke
			(width 0)
			(type solid)
		)
		(fill yes)
		(layer "F.Cu")
		(net "M_H_DQ<48>")
	)
	(gr_poly
		(pts
			(xy 126.95809 -44.743624) (xy 126.94539 -44.553124) (xy 126.84379 -44.553124) (xy 126.83109 -44.743624)
			(xy 126.83109 -44.794424) (xy 126.95809 -44.794424)
		)
		(stroke
			(width 0)
			(type solid)
		)
		(fill yes)
		(layer "F.Cu")
		(net "M_H_DQ<53>")
	)
	(gr_poly
		(pts
			(xy 126.95809 -44.349924) (xy 126.94539 -44.159424) (xy 126.84379 -44.159424) (xy 126.83109 -44.349924)
			(xy 126.83109 -44.400724) (xy 126.95809 -44.400724)
		)
		(stroke
			(width 0)
			(type solid)
		)
		(fill yes)
		(layer "F.Cu")
		(net "M_H_DQ<52>")
	)
	(gr_poly
		(pts
			(xy 127.122428 -108.674154) (xy 127.122428 -108.623354) (xy 126.995428 -108.623354) (xy 126.995428 -108.674154)
			(xy 127.008128 -108.864654) (xy 127.109728 -108.864654)
		)
		(stroke
			(width 0)
			(type solid)
		)
		(fill yes)
		(layer "F.Cu")
		(net "M_L_DQ<52>")
	)
	(gr_poly
		(pts
			(xy 127.122428 -108.280454) (xy 127.122428 -108.229654) (xy 126.995428 -108.229654) (xy 126.995428 -108.280454)
			(xy 127.008128 -108.470954) (xy 127.109728 -108.470954)
		)
		(stroke
			(width 0)
			(type solid)
		)
		(fill yes)
		(layer "F.Cu")
		(net "M_L_DQ<53>")
	)
	(gr_poly
		(pts
			(xy 127.122428 -107.886754) (xy 127.122428 -107.835954) (xy 126.995428 -107.835954) (xy 126.995428 -107.886754)
			(xy 127.008128 -108.077254) (xy 127.109728 -108.077254)
		)
		(stroke
			(width 0)
			(type solid)
		)
		(fill yes)
		(layer "F.Cu")
		(net "M_L_DQ<48>")
	)
	(gr_poly
		(pts
			(xy 127.122428 -107.493054) (xy 127.122428 -107.442254) (xy 126.995428 -107.442254) (xy 126.995428 -107.493054)
			(xy 127.008128 -107.683554) (xy 127.109728 -107.683554)
		)
		(stroke
			(width 0)
			(type solid)
		)
		(fill yes)
		(layer "F.Cu")
		(net "M_L_DQ<49>")
	)
	(gr_poly
		(pts
			(xy 127.122428 -107.099354) (xy 127.122428 -107.048554) (xy 126.995428 -107.048554) (xy 126.995428 -107.099354)
			(xy 127.008128 -107.289854) (xy 127.109728 -107.289854)
		)
		(stroke
			(width 0)
			(type solid)
		)
		(fill yes)
		(layer "F.Cu")
		(net "M_L_DQS_DP<15>")
	)
	(gr_poly
		(pts
			(xy 127.122428 -106.705654) (xy 127.122428 -106.654854) (xy 126.995428 -106.654854) (xy 126.995428 -106.705654)
			(xy 127.008128 -106.896154) (xy 127.109728 -106.896154)
		)
		(stroke
			(width 0)
			(type solid)
		)
		(fill yes)
		(layer "F.Cu")
		(net "M_L_DQS_DN<15>")
	)
	(gr_poly
		(pts
			(xy 127.122428 -106.311954) (xy 127.122428 -106.261154) (xy 126.995428 -106.261154) (xy 126.995428 -106.311954)
			(xy 127.008128 -106.502454) (xy 127.109728 -106.502454)
		)
		(stroke
			(width 0)
			(type solid)
		)
		(fill yes)
		(layer "F.Cu")
		(net "M_L_DQS_DN<6>")
	)
	(gr_poly
		(pts
			(xy 127.122428 -105.918254) (xy 127.122428 -105.867454) (xy 126.995428 -105.867454) (xy 126.995428 -105.918254)
			(xy 127.008128 -106.108754) (xy 127.109728 -106.108754)
		)
		(stroke
			(width 0)
			(type solid)
		)
		(fill yes)
		(layer "F.Cu")
		(net "M_L_DQS_DP<6>")
	)
	(gr_poly
		(pts
			(xy 127.122428 -105.524554) (xy 127.122428 -105.473754) (xy 126.995428 -105.473754) (xy 126.995428 -105.524554)
			(xy 127.008128 -105.715054) (xy 127.109728 -105.715054)
		)
		(stroke
			(width 0)
			(type solid)
		)
		(fill yes)
		(layer "F.Cu")
		(net "M_L_DQ<54>")
	)
	(gr_poly
		(pts
			(xy 127.122428 -105.130854) (xy 127.122428 -105.080054) (xy 126.995428 -105.080054) (xy 126.995428 -105.130854)
			(xy 127.008128 -105.321354) (xy 127.109728 -105.321354)
		)
		(stroke
			(width 0)
			(type solid)
		)
		(fill yes)
		(layer "F.Cu")
		(net "M_L_DQ<55>")
	)
	(gr_poly
		(pts
			(xy 127.122428 -104.737154) (xy 127.122428 -104.686354) (xy 126.995428 -104.686354) (xy 126.995428 -104.737154)
			(xy 127.008128 -104.927654) (xy 127.109728 -104.927654)
		)
		(stroke
			(width 0)
			(type solid)
		)
		(fill yes)
		(layer "F.Cu")
		(net "M_L_DQ<50>")
	)
	(gr_poly
		(pts
			(xy 127.122428 -104.343454) (xy 127.122428 -104.292654) (xy 126.995428 -104.292654) (xy 126.995428 -104.343454)
			(xy 127.008128 -104.533954) (xy 127.109728 -104.533954)
		)
		(stroke
			(width 0)
			(type solid)
		)
		(fill yes)
		(layer "F.Cu")
		(net "M_L_DQ<51>")
	)
	(gr_poly
		(pts
			(xy 127.28829 -48.782224) (xy 127.28829 -48.731424) (xy 127.16129 -48.731424) (xy 127.16129 -48.782224)
			(xy 127.17399 -48.972724) (xy 127.27559 -48.972724)
		)
		(stroke
			(width 0)
			(type solid)
		)
		(fill yes)
		(layer "F.Cu")
		(net "M_H_DQ<51>")
	)
	(gr_poly
		(pts
			(xy 127.28829 -48.388524) (xy 127.28829 -48.337724) (xy 127.16129 -48.337724) (xy 127.16129 -48.388524)
			(xy 127.17399 -48.579024) (xy 127.27559 -48.579024)
		)
		(stroke
			(width 0)
			(type solid)
		)
		(fill yes)
		(layer "F.Cu")
		(net "M_H_DQ<50>")
	)
	(gr_poly
		(pts
			(xy 127.28829 -47.994824) (xy 127.28829 -47.944024) (xy 127.16129 -47.944024) (xy 127.16129 -47.994824)
			(xy 127.17399 -48.185324) (xy 127.27559 -48.185324)
		)
		(stroke
			(width 0)
			(type solid)
		)
		(fill yes)
		(layer "F.Cu")
		(net "M_H_DQ<55>")
	)
	(gr_poly
		(pts
			(xy 127.28829 -47.601124) (xy 127.28829 -47.550324) (xy 127.16129 -47.550324) (xy 127.16129 -47.601124)
			(xy 127.17399 -47.791624) (xy 127.27559 -47.791624)
		)
		(stroke
			(width 0)
			(type solid)
		)
		(fill yes)
		(layer "F.Cu")
		(net "M_H_DQ<54>")
	)
	(gr_poly
		(pts
			(xy 127.28829 -47.207424) (xy 127.28829 -47.156624) (xy 127.16129 -47.156624) (xy 127.16129 -47.207424)
			(xy 127.17399 -47.397924) (xy 127.27559 -47.397924)
		)
		(stroke
			(width 0)
			(type solid)
		)
		(fill yes)
		(layer "F.Cu")
		(net "M_H_DQS_DP<6>")
	)
	(gr_poly
		(pts
			(xy 127.28829 -46.813724) (xy 127.28829 -46.762924) (xy 127.16129 -46.762924) (xy 127.16129 -46.813724)
			(xy 127.17399 -47.004224) (xy 127.27559 -47.004224)
		)
		(stroke
			(width 0)
			(type solid)
		)
		(fill yes)
		(layer "F.Cu")
		(net "M_H_DQS_DN<6>")
	)
	(gr_poly
		(pts
			(xy 127.28829 -46.420024) (xy 127.28829 -46.369224) (xy 127.16129 -46.369224) (xy 127.16129 -46.420024)
			(xy 127.17399 -46.610524) (xy 127.27559 -46.610524)
		)
		(stroke
			(width 0)
			(type solid)
		)
		(fill yes)
		(layer "F.Cu")
		(net "M_H_DQS_DN<15>")
	)
	(gr_poly
		(pts
			(xy 127.28829 -46.026324) (xy 127.28829 -45.975524) (xy 127.16129 -45.975524) (xy 127.16129 -46.026324)
			(xy 127.17399 -46.216824) (xy 127.27559 -46.216824)
		)
		(stroke
			(width 0)
			(type solid)
		)
		(fill yes)
		(layer "F.Cu")
		(net "M_H_DQS_DP<15>")
	)
	(gr_poly
		(pts
			(xy 127.28829 -45.632624) (xy 127.28829 -45.581824) (xy 127.16129 -45.581824) (xy 127.16129 -45.632624)
			(xy 127.17399 -45.823124) (xy 127.27559 -45.823124)
		)
		(stroke
			(width 0)
			(type solid)
		)
		(fill yes)
		(layer "F.Cu")
		(net "M_H_DQ<49>")
	)
	(gr_poly
		(pts
			(xy 127.28829 -45.238924) (xy 127.28829 -45.188124) (xy 127.16129 -45.188124) (xy 127.16129 -45.238924)
			(xy 127.17399 -45.429424) (xy 127.27559 -45.429424)
		)
		(stroke
			(width 0)
			(type solid)
		)
		(fill yes)
		(layer "F.Cu")
		(net "M_H_DQ<48>")
	)
	(gr_poly
		(pts
			(xy 127.28829 -44.845224) (xy 127.28829 -44.794424) (xy 127.16129 -44.794424) (xy 127.16129 -44.845224)
			(xy 127.17399 -45.035724) (xy 127.27559 -45.035724)
		)
		(stroke
			(width 0)
			(type solid)
		)
		(fill yes)
		(layer "F.Cu")
		(net "M_H_DQ<53>")
	)
	(gr_poly
		(pts
			(xy 127.28829 -44.451524) (xy 127.28829 -44.400724) (xy 127.16129 -44.400724) (xy 127.16129 -44.451524)
			(xy 127.17399 -44.642024) (xy 127.27559 -44.642024)
		)
		(stroke
			(width 0)
			(type solid)
		)
		(fill yes)
		(layer "F.Cu")
		(net "M_H_DQ<52>")
	)
	(gr_poly
		(pts
			(xy 127.452628 -108.572554) (xy 127.439928 -108.382054) (xy 127.338328 -108.382054) (xy 127.325628 -108.572554)
			(xy 127.325628 -108.623354) (xy 127.452628 -108.623354)
		)
		(stroke
			(width 0)
			(type solid)
		)
		(fill yes)
		(layer "F.Cu")
		(net "M_L_DQ<52>")
	)
	(gr_poly
		(pts
			(xy 127.452628 -108.178854) (xy 127.439928 -107.988354) (xy 127.338328 -107.988354) (xy 127.325628 -108.178854)
			(xy 127.325628 -108.229654) (xy 127.452628 -108.229654)
		)
		(stroke
			(width 0)
			(type solid)
		)
		(fill yes)
		(layer "F.Cu")
		(net "M_L_DQ<53>")
	)
	(gr_poly
		(pts
			(xy 127.452628 -107.785154) (xy 127.439928 -107.594654) (xy 127.338328 -107.594654) (xy 127.325628 -107.785154)
			(xy 127.325628 -107.835954) (xy 127.452628 -107.835954)
		)
		(stroke
			(width 0)
			(type solid)
		)
		(fill yes)
		(layer "F.Cu")
		(net "M_L_DQ<48>")
	)
	(gr_poly
		(pts
			(xy 127.452628 -107.391454) (xy 127.439928 -107.200954) (xy 127.338328 -107.200954) (xy 127.325628 -107.391454)
			(xy 127.325628 -107.442254) (xy 127.452628 -107.442254)
		)
		(stroke
			(width 0)
			(type solid)
		)
		(fill yes)
		(layer "F.Cu")
		(net "M_L_DQ<49>")
	)
	(gr_poly
		(pts
			(xy 127.452628 -106.997754) (xy 127.439928 -106.807254) (xy 127.338328 -106.807254) (xy 127.325628 -106.997754)
			(xy 127.325628 -107.048554) (xy 127.452628 -107.048554)
		)
		(stroke
			(width 0)
			(type solid)
		)
		(fill yes)
		(layer "F.Cu")
		(net "M_L_DQS_DP<15>")
	)
	(gr_poly
		(pts
			(xy 127.452628 -106.604054) (xy 127.439928 -106.413554) (xy 127.338328 -106.413554) (xy 127.325628 -106.604054)
			(xy 127.325628 -106.654854) (xy 127.452628 -106.654854)
		)
		(stroke
			(width 0)
			(type solid)
		)
		(fill yes)
		(layer "F.Cu")
		(net "M_L_DQS_DN<15>")
	)
	(gr_poly
		(pts
			(xy 127.452628 -106.210354) (xy 127.439928 -106.019854) (xy 127.338328 -106.019854) (xy 127.325628 -106.210354)
			(xy 127.325628 -106.261154) (xy 127.452628 -106.261154)
		)
		(stroke
			(width 0)
			(type solid)
		)
		(fill yes)
		(layer "F.Cu")
		(net "M_L_DQS_DN<6>")
	)
	(gr_poly
		(pts
			(xy 127.452628 -105.816654) (xy 127.439928 -105.626154) (xy 127.338328 -105.626154) (xy 127.325628 -105.816654)
			(xy 127.325628 -105.867454) (xy 127.452628 -105.867454)
		)
		(stroke
			(width 0)
			(type solid)
		)
		(fill yes)
		(layer "F.Cu")
		(net "M_L_DQS_DP<6>")
	)
	(gr_poly
		(pts
			(xy 127.452628 -105.422954) (xy 127.439928 -105.232454) (xy 127.338328 -105.232454) (xy 127.325628 -105.422954)
			(xy 127.325628 -105.473754) (xy 127.452628 -105.473754)
		)
		(stroke
			(width 0)
			(type solid)
		)
		(fill yes)
		(layer "F.Cu")
		(net "M_L_DQ<54>")
	)
	(gr_poly
		(pts
			(xy 127.452628 -105.029254) (xy 127.439928 -104.838754) (xy 127.338328 -104.838754) (xy 127.325628 -105.029254)
			(xy 127.325628 -105.080054) (xy 127.452628 -105.080054)
		)
		(stroke
			(width 0)
			(type solid)
		)
		(fill yes)
		(layer "F.Cu")
		(net "M_L_DQ<55>")
	)
	(gr_poly
		(pts
			(xy 127.452628 -104.635554) (xy 127.439928 -104.445054) (xy 127.338328 -104.445054) (xy 127.325628 -104.635554)
			(xy 127.325628 -104.686354) (xy 127.452628 -104.686354)
		)
		(stroke
			(width 0)
			(type solid)
		)
		(fill yes)
		(layer "F.Cu")
		(net "M_L_DQ<50>")
	)
	(gr_poly
		(pts
			(xy 127.452628 -104.241854) (xy 127.439928 -104.051354) (xy 127.338328 -104.051354) (xy 127.325628 -104.241854)
			(xy 127.325628 -104.292654) (xy 127.452628 -104.292654)
		)
		(stroke
			(width 0)
			(type solid)
		)
		(fill yes)
		(layer "F.Cu")
		(net "M_L_DQ<51>")
	)
	(gr_poly
		(pts
			(xy 127.61849 -48.680624) (xy 127.60579 -48.490124) (xy 127.50419 -48.490124) (xy 127.49149 -48.680624)
			(xy 127.49149 -48.731424) (xy 127.61849 -48.731424)
		)
		(stroke
			(width 0)
			(type solid)
		)
		(fill yes)
		(layer "F.Cu")
		(net "M_H_DQ<51>")
	)
	(gr_poly
		(pts
			(xy 127.61849 -48.286924) (xy 127.60579 -48.096424) (xy 127.50419 -48.096424) (xy 127.49149 -48.286924)
			(xy 127.49149 -48.337724) (xy 127.61849 -48.337724)
		)
		(stroke
			(width 0)
			(type solid)
		)
		(fill yes)
		(layer "F.Cu")
		(net "M_H_DQ<50>")
	)
	(gr_poly
		(pts
			(xy 127.61849 -47.893224) (xy 127.60579 -47.702724) (xy 127.50419 -47.702724) (xy 127.49149 -47.893224)
			(xy 127.49149 -47.944024) (xy 127.61849 -47.944024)
		)
		(stroke
			(width 0)
			(type solid)
		)
		(fill yes)
		(layer "F.Cu")
		(net "M_H_DQ<55>")
	)
	(gr_poly
		(pts
			(xy 127.61849 -47.499524) (xy 127.60579 -47.309024) (xy 127.50419 -47.309024) (xy 127.49149 -47.499524)
			(xy 127.49149 -47.550324) (xy 127.61849 -47.550324)
		)
		(stroke
			(width 0)
			(type solid)
		)
		(fill yes)
		(layer "F.Cu")
		(net "M_H_DQ<54>")
	)
	(gr_poly
		(pts
			(xy 127.61849 -47.105824) (xy 127.60579 -46.915324) (xy 127.50419 -46.915324) (xy 127.49149 -47.105824)
			(xy 127.49149 -47.156624) (xy 127.61849 -47.156624)
		)
		(stroke
			(width 0)
			(type solid)
		)
		(fill yes)
		(layer "F.Cu")
		(net "M_H_DQS_DP<6>")
	)
	(gr_poly
		(pts
			(xy 127.61849 -46.712124) (xy 127.60579 -46.521624) (xy 127.50419 -46.521624) (xy 127.49149 -46.712124)
			(xy 127.49149 -46.762924) (xy 127.61849 -46.762924)
		)
		(stroke
			(width 0)
			(type solid)
		)
		(fill yes)
		(layer "F.Cu")
		(net "M_H_DQS_DN<6>")
	)
	(gr_poly
		(pts
			(xy 127.61849 -46.318424) (xy 127.60579 -46.127924) (xy 127.50419 -46.127924) (xy 127.49149 -46.318424)
			(xy 127.49149 -46.369224) (xy 127.61849 -46.369224)
		)
		(stroke
			(width 0)
			(type solid)
		)
		(fill yes)
		(layer "F.Cu")
		(net "M_H_DQS_DN<15>")
	)
	(gr_poly
		(pts
			(xy 127.61849 -45.924724) (xy 127.60579 -45.734224) (xy 127.50419 -45.734224) (xy 127.49149 -45.924724)
			(xy 127.49149 -45.975524) (xy 127.61849 -45.975524)
		)
		(stroke
			(width 0)
			(type solid)
		)
		(fill yes)
		(layer "F.Cu")
		(net "M_H_DQS_DP<15>")
	)
	(gr_poly
		(pts
			(xy 127.61849 -45.531024) (xy 127.60579 -45.340524) (xy 127.50419 -45.340524) (xy 127.49149 -45.531024)
			(xy 127.49149 -45.581824) (xy 127.61849 -45.581824)
		)
		(stroke
			(width 0)
			(type solid)
		)
		(fill yes)
		(layer "F.Cu")
		(net "M_H_DQ<49>")
	)
	(gr_poly
		(pts
			(xy 127.61849 -45.137324) (xy 127.60579 -44.946824) (xy 127.50419 -44.946824) (xy 127.49149 -45.137324)
			(xy 127.49149 -45.188124) (xy 127.61849 -45.188124)
		)
		(stroke
			(width 0)
			(type solid)
		)
		(fill yes)
		(layer "F.Cu")
		(net "M_H_DQ<48>")
	)
	(gr_poly
		(pts
			(xy 127.61849 -44.743624) (xy 127.60579 -44.553124) (xy 127.50419 -44.553124) (xy 127.49149 -44.743624)
			(xy 127.49149 -44.794424) (xy 127.61849 -44.794424)
		)
		(stroke
			(width 0)
			(type solid)
		)
		(fill yes)
		(layer "F.Cu")
		(net "M_H_DQ<53>")
	)
	(gr_poly
		(pts
			(xy 127.61849 -44.349924) (xy 127.60579 -44.159424) (xy 127.50419 -44.159424) (xy 127.49149 -44.349924)
			(xy 127.49149 -44.400724) (xy 127.61849 -44.400724)
		)
		(stroke
			(width 0)
			(type solid)
		)
		(fill yes)
		(layer "F.Cu")
		(net "M_H_DQ<52>")
	)
	(gr_poly
		(pts
			(xy 127.782828 -108.674154) (xy 127.782828 -108.623354) (xy 127.655828 -108.623354) (xy 127.655828 -108.674154)
			(xy 127.668528 -108.864654) (xy 127.770128 -108.864654)
		)
		(stroke
			(width 0)
			(type solid)
		)
		(fill yes)
		(layer "F.Cu")
		(net "M_L_DQ<52>")
	)
	(gr_poly
		(pts
			(xy 127.782828 -108.280454) (xy 127.782828 -108.229654) (xy 127.655828 -108.229654) (xy 127.655828 -108.280454)
			(xy 127.668528 -108.470954) (xy 127.770128 -108.470954)
		)
		(stroke
			(width 0)
			(type solid)
		)
		(fill yes)
		(layer "F.Cu")
		(net "M_L_DQ<53>")
	)
	(gr_poly
		(pts
			(xy 127.782828 -107.886754) (xy 127.782828 -107.835954) (xy 127.655828 -107.835954) (xy 127.655828 -107.886754)
			(xy 127.668528 -108.077254) (xy 127.770128 -108.077254)
		)
		(stroke
			(width 0)
			(type solid)
		)
		(fill yes)
		(layer "F.Cu")
		(net "M_L_DQ<48>")
	)
	(gr_poly
		(pts
			(xy 127.782828 -107.493054) (xy 127.782828 -107.442254) (xy 127.655828 -107.442254) (xy 127.655828 -107.493054)
			(xy 127.668528 -107.683554) (xy 127.770128 -107.683554)
		)
		(stroke
			(width 0)
			(type solid)
		)
		(fill yes)
		(layer "F.Cu")
		(net "M_L_DQ<49>")
	)
	(gr_poly
		(pts
			(xy 127.782828 -107.099354) (xy 127.782828 -107.048554) (xy 127.655828 -107.048554) (xy 127.655828 -107.099354)
			(xy 127.668528 -107.289854) (xy 127.770128 -107.289854)
		)
		(stroke
			(width 0)
			(type solid)
		)
		(fill yes)
		(layer "F.Cu")
		(net "M_L_DQS_DP<15>")
	)
	(gr_poly
		(pts
			(xy 127.782828 -106.705654) (xy 127.782828 -106.654854) (xy 127.655828 -106.654854) (xy 127.655828 -106.705654)
			(xy 127.668528 -106.896154) (xy 127.770128 -106.896154)
		)
		(stroke
			(width 0)
			(type solid)
		)
		(fill yes)
		(layer "F.Cu")
		(net "M_L_DQS_DN<15>")
	)
	(gr_poly
		(pts
			(xy 127.782828 -106.311954) (xy 127.782828 -106.261154) (xy 127.655828 -106.261154) (xy 127.655828 -106.311954)
			(xy 127.668528 -106.502454) (xy 127.770128 -106.502454)
		)
		(stroke
			(width 0)
			(type solid)
		)
		(fill yes)
		(layer "F.Cu")
		(net "M_L_DQS_DN<6>")
	)
	(gr_poly
		(pts
			(xy 127.782828 -105.918254) (xy 127.782828 -105.867454) (xy 127.655828 -105.867454) (xy 127.655828 -105.918254)
			(xy 127.668528 -106.108754) (xy 127.770128 -106.108754)
		)
		(stroke
			(width 0)
			(type solid)
		)
		(fill yes)
		(layer "F.Cu")
		(net "M_L_DQS_DP<6>")
	)
	(gr_poly
		(pts
			(xy 127.782828 -105.524554) (xy 127.782828 -105.473754) (xy 127.655828 -105.473754) (xy 127.655828 -105.524554)
			(xy 127.668528 -105.715054) (xy 127.770128 -105.715054)
		)
		(stroke
			(width 0)
			(type solid)
		)
		(fill yes)
		(layer "F.Cu")
		(net "M_L_DQ<54>")
	)
	(gr_poly
		(pts
			(xy 127.782828 -105.130854) (xy 127.782828 -105.080054) (xy 127.655828 -105.080054) (xy 127.655828 -105.130854)
			(xy 127.668528 -105.321354) (xy 127.770128 -105.321354)
		)
		(stroke
			(width 0)
			(type solid)
		)
		(fill yes)
		(layer "F.Cu")
		(net "M_L_DQ<55>")
	)
	(gr_poly
		(pts
			(xy 127.782828 -104.737154) (xy 127.782828 -104.686354) (xy 127.655828 -104.686354) (xy 127.655828 -104.737154)
			(xy 127.668528 -104.927654) (xy 127.770128 -104.927654)
		)
		(stroke
			(width 0)
			(type solid)
		)
		(fill yes)
		(layer "F.Cu")
		(net "M_L_DQ<50>")
	)
	(gr_poly
		(pts
			(xy 127.782828 -104.343454) (xy 127.782828 -104.292654) (xy 127.655828 -104.292654) (xy 127.655828 -104.343454)
			(xy 127.668528 -104.533954) (xy 127.770128 -104.533954)
		)
		(stroke
			(width 0)
			(type solid)
		)
		(fill yes)
		(layer "F.Cu")
		(net "M_L_DQ<51>")
	)
	(gr_poly
		(pts
			(xy 127.94869 -48.782224) (xy 127.94869 -48.731424) (xy 127.82169 -48.731424) (xy 127.82169 -48.782224)
			(xy 127.83439 -48.972724) (xy 127.93599 -48.972724)
		)
		(stroke
			(width 0)
			(type solid)
		)
		(fill yes)
		(layer "F.Cu")
		(net "M_H_DQ<51>")
	)
	(gr_poly
		(pts
			(xy 127.94869 -48.388524) (xy 127.94869 -48.337724) (xy 127.82169 -48.337724) (xy 127.82169 -48.388524)
			(xy 127.83439 -48.579024) (xy 127.93599 -48.579024)
		)
		(stroke
			(width 0)
			(type solid)
		)
		(fill yes)
		(layer "F.Cu")
		(net "M_H_DQ<50>")
	)
	(gr_poly
		(pts
			(xy 127.94869 -47.994824) (xy 127.94869 -47.944024) (xy 127.82169 -47.944024) (xy 127.82169 -47.994824)
			(xy 127.83439 -48.185324) (xy 127.93599 -48.185324)
		)
		(stroke
			(width 0)
			(type solid)
		)
		(fill yes)
		(layer "F.Cu")
		(net "M_H_DQ<55>")
	)
	(gr_poly
		(pts
			(xy 127.94869 -47.601124) (xy 127.94869 -47.550324) (xy 127.82169 -47.550324) (xy 127.82169 -47.601124)
			(xy 127.83439 -47.791624) (xy 127.93599 -47.791624)
		)
		(stroke
			(width 0)
			(type solid)
		)
		(fill yes)
		(layer "F.Cu")
		(net "M_H_DQ<54>")
	)
	(gr_poly
		(pts
			(xy 127.94869 -47.207424) (xy 127.94869 -47.156624) (xy 127.82169 -47.156624) (xy 127.82169 -47.207424)
			(xy 127.83439 -47.397924) (xy 127.93599 -47.397924)
		)
		(stroke
			(width 0)
			(type solid)
		)
		(fill yes)
		(layer "F.Cu")
		(net "M_H_DQS_DP<6>")
	)
	(gr_poly
		(pts
			(xy 127.94869 -46.813724) (xy 127.94869 -46.762924) (xy 127.82169 -46.762924) (xy 127.82169 -46.813724)
			(xy 127.83439 -47.004224) (xy 127.93599 -47.004224)
		)
		(stroke
			(width 0)
			(type solid)
		)
		(fill yes)
		(layer "F.Cu")
		(net "M_H_DQS_DN<6>")
	)
	(gr_poly
		(pts
			(xy 127.94869 -46.420024) (xy 127.94869 -46.369224) (xy 127.82169 -46.369224) (xy 127.82169 -46.420024)
			(xy 127.83439 -46.610524) (xy 127.93599 -46.610524)
		)
		(stroke
			(width 0)
			(type solid)
		)
		(fill yes)
		(layer "F.Cu")
		(net "M_H_DQS_DN<15>")
	)
	(gr_poly
		(pts
			(xy 127.94869 -46.026324) (xy 127.94869 -45.975524) (xy 127.82169 -45.975524) (xy 127.82169 -46.026324)
			(xy 127.83439 -46.216824) (xy 127.93599 -46.216824)
		)
		(stroke
			(width 0)
			(type solid)
		)
		(fill yes)
		(layer "F.Cu")
		(net "M_H_DQS_DP<15>")
	)
	(gr_poly
		(pts
			(xy 127.94869 -45.632624) (xy 127.94869 -45.581824) (xy 127.82169 -45.581824) (xy 127.82169 -45.632624)
			(xy 127.83439 -45.823124) (xy 127.93599 -45.823124)
		)
		(stroke
			(width 0)
			(type solid)
		)
		(fill yes)
		(layer "F.Cu")
		(net "M_H_DQ<49>")
	)
	(gr_poly
		(pts
			(xy 127.94869 -45.238924) (xy 127.94869 -45.188124) (xy 127.82169 -45.188124) (xy 127.82169 -45.238924)
			(xy 127.83439 -45.429424) (xy 127.93599 -45.429424)
		)
		(stroke
			(width 0)
			(type solid)
		)
		(fill yes)
		(layer "F.Cu")
		(net "M_H_DQ<48>")
	)
	(gr_poly
		(pts
			(xy 127.94869 -44.845224) (xy 127.94869 -44.794424) (xy 127.82169 -44.794424) (xy 127.82169 -44.845224)
			(xy 127.83439 -45.035724) (xy 127.93599 -45.035724)
		)
		(stroke
			(width 0)
			(type solid)
		)
		(fill yes)
		(layer "F.Cu")
		(net "M_H_DQ<53>")
	)
	(gr_poly
		(pts
			(xy 127.94869 -44.451524) (xy 127.94869 -44.400724) (xy 127.82169 -44.400724) (xy 127.82169 -44.451524)
			(xy 127.83439 -44.642024) (xy 127.93599 -44.642024)
		)
		(stroke
			(width 0)
			(type solid)
		)
		(fill yes)
		(layer "F.Cu")
		(net "M_H_DQ<52>")
	)
	(gr_poly
		(pts
			(xy 128.113028 -108.572554) (xy 128.100328 -108.382054) (xy 127.998728 -108.382054) (xy 127.986028 -108.572554)
			(xy 127.986028 -108.623354) (xy 128.113028 -108.623354)
		)
		(stroke
			(width 0)
			(type solid)
		)
		(fill yes)
		(layer "F.Cu")
		(net "M_L_DQ<52>")
	)
	(gr_poly
		(pts
			(xy 128.113028 -108.178854) (xy 128.100328 -107.988354) (xy 127.998728 -107.988354) (xy 127.986028 -108.178854)
			(xy 127.986028 -108.229654) (xy 128.113028 -108.229654)
		)
		(stroke
			(width 0)
			(type solid)
		)
		(fill yes)
		(layer "F.Cu")
		(net "M_L_DQ<53>")
	)
	(gr_poly
		(pts
			(xy 128.113028 -107.785154) (xy 128.100328 -107.594654) (xy 127.998728 -107.594654) (xy 127.986028 -107.785154)
			(xy 127.986028 -107.835954) (xy 128.113028 -107.835954)
		)
		(stroke
			(width 0)
			(type solid)
		)
		(fill yes)
		(layer "F.Cu")
		(net "M_L_DQ<48>")
	)
	(gr_poly
		(pts
			(xy 128.113028 -107.391454) (xy 128.100328 -107.200954) (xy 127.998728 -107.200954) (xy 127.986028 -107.391454)
			(xy 127.986028 -107.442254) (xy 128.113028 -107.442254)
		)
		(stroke
			(width 0)
			(type solid)
		)
		(fill yes)
		(layer "F.Cu")
		(net "M_L_DQ<49>")
	)
	(gr_poly
		(pts
			(xy 128.113028 -106.997754) (xy 128.100328 -106.807254) (xy 127.998728 -106.807254) (xy 127.986028 -106.997754)
			(xy 127.986028 -107.048554) (xy 128.113028 -107.048554)
		)
		(stroke
			(width 0)
			(type solid)
		)
		(fill yes)
		(layer "F.Cu")
		(net "M_L_DQS_DP<15>")
	)
	(gr_poly
		(pts
			(xy 128.113028 -106.604054) (xy 128.100328 -106.413554) (xy 127.998728 -106.413554) (xy 127.986028 -106.604054)
			(xy 127.986028 -106.654854) (xy 128.113028 -106.654854)
		)
		(stroke
			(width 0)
			(type solid)
		)
		(fill yes)
		(layer "F.Cu")
		(net "M_L_DQS_DN<15>")
	)
	(gr_poly
		(pts
			(xy 128.113028 -106.210354) (xy 128.100328 -106.019854) (xy 127.998728 -106.019854) (xy 127.986028 -106.210354)
			(xy 127.986028 -106.261154) (xy 128.113028 -106.261154)
		)
		(stroke
			(width 0)
			(type solid)
		)
		(fill yes)
		(layer "F.Cu")
		(net "M_L_DQS_DN<6>")
	)
	(gr_poly
		(pts
			(xy 128.113028 -105.816654) (xy 128.100328 -105.626154) (xy 127.998728 -105.626154) (xy 127.986028 -105.816654)
			(xy 127.986028 -105.867454) (xy 128.113028 -105.867454)
		)
		(stroke
			(width 0)
			(type solid)
		)
		(fill yes)
		(layer "F.Cu")
		(net "M_L_DQS_DP<6>")
	)
	(gr_poly
		(pts
			(xy 128.113028 -105.422954) (xy 128.100328 -105.232454) (xy 127.998728 -105.232454) (xy 127.986028 -105.422954)
			(xy 127.986028 -105.473754) (xy 128.113028 -105.473754)
		)
		(stroke
			(width 0)
			(type solid)
		)
		(fill yes)
		(layer "F.Cu")
		(net "M_L_DQ<54>")
	)
	(gr_poly
		(pts
			(xy 128.113028 -105.029254) (xy 128.100328 -104.838754) (xy 127.998728 -104.838754) (xy 127.986028 -105.029254)
			(xy 127.986028 -105.080054) (xy 128.113028 -105.080054)
		)
		(stroke
			(width 0)
			(type solid)
		)
		(fill yes)
		(layer "F.Cu")
		(net "M_L_DQ<55>")
	)
	(gr_poly
		(pts
			(xy 128.113028 -104.635554) (xy 128.100328 -104.445054) (xy 127.998728 -104.445054) (xy 127.986028 -104.635554)
			(xy 127.986028 -104.686354) (xy 128.113028 -104.686354)
		)
		(stroke
			(width 0)
			(type solid)
		)
		(fill yes)
		(layer "F.Cu")
		(net "M_L_DQ<50>")
	)
	(gr_poly
		(pts
			(xy 128.113028 -104.241854) (xy 128.100328 -104.051354) (xy 127.998728 -104.051354) (xy 127.986028 -104.241854)
			(xy 127.986028 -104.292654) (xy 128.113028 -104.292654)
		)
		(stroke
			(width 0)
			(type solid)
		)
		(fill yes)
		(layer "F.Cu")
		(net "M_L_DQ<51>")
	)
	(gr_poly
		(pts
			(xy 128.27889 -48.680624) (xy 128.26619 -48.490124) (xy 128.16459 -48.490124) (xy 128.15189 -48.680624)
			(xy 128.15189 -48.731424) (xy 128.27889 -48.731424)
		)
		(stroke
			(width 0)
			(type solid)
		)
		(fill yes)
		(layer "F.Cu")
		(net "M_H_DQ<51>")
	)
	(gr_poly
		(pts
			(xy 128.27889 -48.286924) (xy 128.26619 -48.096424) (xy 128.16459 -48.096424) (xy 128.15189 -48.286924)
			(xy 128.15189 -48.337724) (xy 128.27889 -48.337724)
		)
		(stroke
			(width 0)
			(type solid)
		)
		(fill yes)
		(layer "F.Cu")
		(net "M_H_DQ<50>")
	)
	(gr_poly
		(pts
			(xy 128.27889 -47.893224) (xy 128.26619 -47.702724) (xy 128.16459 -47.702724) (xy 128.15189 -47.893224)
			(xy 128.15189 -47.944024) (xy 128.27889 -47.944024)
		)
		(stroke
			(width 0)
			(type solid)
		)
		(fill yes)
		(layer "F.Cu")
		(net "M_H_DQ<55>")
	)
	(gr_poly
		(pts
			(xy 128.27889 -47.499524) (xy 128.26619 -47.309024) (xy 128.16459 -47.309024) (xy 128.15189 -47.499524)
			(xy 128.15189 -47.550324) (xy 128.27889 -47.550324)
		)
		(stroke
			(width 0)
			(type solid)
		)
		(fill yes)
		(layer "F.Cu")
		(net "M_H_DQ<54>")
	)
	(gr_poly
		(pts
			(xy 128.27889 -47.105824) (xy 128.26619 -46.915324) (xy 128.16459 -46.915324) (xy 128.15189 -47.105824)
			(xy 128.15189 -47.156624) (xy 128.27889 -47.156624)
		)
		(stroke
			(width 0)
			(type solid)
		)
		(fill yes)
		(layer "F.Cu")
		(net "M_H_DQS_DP<6>")
	)
	(gr_poly
		(pts
			(xy 128.27889 -46.712124) (xy 128.26619 -46.521624) (xy 128.16459 -46.521624) (xy 128.15189 -46.712124)
			(xy 128.15189 -46.762924) (xy 128.27889 -46.762924)
		)
		(stroke
			(width 0)
			(type solid)
		)
		(fill yes)
		(layer "F.Cu")
		(net "M_H_DQS_DN<6>")
	)
	(gr_poly
		(pts
			(xy 128.27889 -46.318424) (xy 128.26619 -46.127924) (xy 128.16459 -46.127924) (xy 128.15189 -46.318424)
			(xy 128.15189 -46.369224) (xy 128.27889 -46.369224)
		)
		(stroke
			(width 0)
			(type solid)
		)
		(fill yes)
		(layer "F.Cu")
		(net "M_H_DQS_DN<15>")
	)
	(gr_poly
		(pts
			(xy 128.27889 -45.924724) (xy 128.26619 -45.734224) (xy 128.16459 -45.734224) (xy 128.15189 -45.924724)
			(xy 128.15189 -45.975524) (xy 128.27889 -45.975524)
		)
		(stroke
			(width 0)
			(type solid)
		)
		(fill yes)
		(layer "F.Cu")
		(net "M_H_DQS_DP<15>")
	)
	(gr_poly
		(pts
			(xy 128.27889 -45.531024) (xy 128.26619 -45.340524) (xy 128.16459 -45.340524) (xy 128.15189 -45.531024)
			(xy 128.15189 -45.581824) (xy 128.27889 -45.581824)
		)
		(stroke
			(width 0)
			(type solid)
		)
		(fill yes)
		(layer "F.Cu")
		(net "M_H_DQ<49>")
	)
	(gr_poly
		(pts
			(xy 128.27889 -45.137324) (xy 128.26619 -44.946824) (xy 128.16459 -44.946824) (xy 128.15189 -45.137324)
			(xy 128.15189 -45.188124) (xy 128.27889 -45.188124)
		)
		(stroke
			(width 0)
			(type solid)
		)
		(fill yes)
		(layer "F.Cu")
		(net "M_H_DQ<48>")
	)
	(gr_poly
		(pts
			(xy 128.27889 -44.743624) (xy 128.26619 -44.553124) (xy 128.16459 -44.553124) (xy 128.15189 -44.743624)
			(xy 128.15189 -44.794424) (xy 128.27889 -44.794424)
		)
		(stroke
			(width 0)
			(type solid)
		)
		(fill yes)
		(layer "F.Cu")
		(net "M_H_DQ<53>")
	)
	(gr_poly
		(pts
			(xy 128.27889 -44.349924) (xy 128.26619 -44.159424) (xy 128.16459 -44.159424) (xy 128.15189 -44.349924)
			(xy 128.15189 -44.400724) (xy 128.27889 -44.400724)
		)
		(stroke
			(width 0)
			(type solid)
		)
		(fill yes)
		(layer "F.Cu")
		(net "M_H_DQ<52>")
	)
	(gr_poly
		(pts
			(xy 128.443228 -108.674154) (xy 128.443228 -108.623354) (xy 128.316228 -108.623354) (xy 128.316228 -108.674154)
			(xy 128.328928 -108.864654) (xy 128.430528 -108.864654)
		)
		(stroke
			(width 0)
			(type solid)
		)
		(fill yes)
		(layer "F.Cu")
		(net "M_L_DQ<52>")
	)
	(gr_poly
		(pts
			(xy 128.443228 -108.280454) (xy 128.443228 -108.229654) (xy 128.316228 -108.229654) (xy 128.316228 -108.280454)
			(xy 128.328928 -108.470954) (xy 128.430528 -108.470954)
		)
		(stroke
			(width 0)
			(type solid)
		)
		(fill yes)
		(layer "F.Cu")
		(net "M_L_DQ<53>")
	)
	(gr_poly
		(pts
			(xy 128.443228 -107.886754) (xy 128.443228 -107.835954) (xy 128.316228 -107.835954) (xy 128.316228 -107.886754)
			(xy 128.328928 -108.077254) (xy 128.430528 -108.077254)
		)
		(stroke
			(width 0)
			(type solid)
		)
		(fill yes)
		(layer "F.Cu")
		(net "M_L_DQ<48>")
	)
	(gr_poly
		(pts
			(xy 128.443228 -107.493054) (xy 128.443228 -107.442254) (xy 128.316228 -107.442254) (xy 128.316228 -107.493054)
			(xy 128.328928 -107.683554) (xy 128.430528 -107.683554)
		)
		(stroke
			(width 0)
			(type solid)
		)
		(fill yes)
		(layer "F.Cu")
		(net "M_L_DQ<49>")
	)
	(gr_poly
		(pts
			(xy 128.443228 -107.099354) (xy 128.443228 -107.048554) (xy 128.316228 -107.048554) (xy 128.316228 -107.099354)
			(xy 128.328928 -107.289854) (xy 128.430528 -107.289854)
		)
		(stroke
			(width 0)
			(type solid)
		)
		(fill yes)
		(layer "F.Cu")
		(net "M_L_DQS_DP<15>")
	)
	(gr_poly
		(pts
			(xy 128.443228 -106.705654) (xy 128.443228 -106.654854) (xy 128.316228 -106.654854) (xy 128.316228 -106.705654)
			(xy 128.328928 -106.896154) (xy 128.430528 -106.896154)
		)
		(stroke
			(width 0)
			(type solid)
		)
		(fill yes)
		(layer "F.Cu")
		(net "M_L_DQS_DN<15>")
	)
	(gr_poly
		(pts
			(xy 128.443228 -106.311954) (xy 128.443228 -106.261154) (xy 128.316228 -106.261154) (xy 128.316228 -106.311954)
			(xy 128.328928 -106.502454) (xy 128.430528 -106.502454)
		)
		(stroke
			(width 0)
			(type solid)
		)
		(fill yes)
		(layer "F.Cu")
		(net "M_L_DQS_DN<6>")
	)
	(gr_poly
		(pts
			(xy 128.443228 -105.918254) (xy 128.443228 -105.867454) (xy 128.316228 -105.867454) (xy 128.316228 -105.918254)
			(xy 128.328928 -106.108754) (xy 128.430528 -106.108754)
		)
		(stroke
			(width 0)
			(type solid)
		)
		(fill yes)
		(layer "F.Cu")
		(net "M_L_DQS_DP<6>")
	)
	(gr_poly
		(pts
			(xy 128.443228 -105.524554) (xy 128.443228 -105.473754) (xy 128.316228 -105.473754) (xy 128.316228 -105.524554)
			(xy 128.328928 -105.715054) (xy 128.430528 -105.715054)
		)
		(stroke
			(width 0)
			(type solid)
		)
		(fill yes)
		(layer "F.Cu")
		(net "M_L_DQ<54>")
	)
	(gr_poly
		(pts
			(xy 128.443228 -105.130854) (xy 128.443228 -105.080054) (xy 128.316228 -105.080054) (xy 128.316228 -105.130854)
			(xy 128.328928 -105.321354) (xy 128.430528 -105.321354)
		)
		(stroke
			(width 0)
			(type solid)
		)
		(fill yes)
		(layer "F.Cu")
		(net "M_L_DQ<55>")
	)
	(gr_poly
		(pts
			(xy 128.443228 -104.737154) (xy 128.443228 -104.686354) (xy 128.316228 -104.686354) (xy 128.316228 -104.737154)
			(xy 128.328928 -104.927654) (xy 128.430528 -104.927654)
		)
		(stroke
			(width 0)
			(type solid)
		)
		(fill yes)
		(layer "F.Cu")
		(net "M_L_DQ<50>")
	)
	(gr_poly
		(pts
			(xy 128.443228 -104.343454) (xy 128.443228 -104.292654) (xy 128.316228 -104.292654) (xy 128.316228 -104.343454)
			(xy 128.328928 -104.533954) (xy 128.430528 -104.533954)
		)
		(stroke
			(width 0)
			(type solid)
		)
		(fill yes)
		(layer "F.Cu")
		(net "M_L_DQ<51>")
	)
	(gr_poly
		(pts
			(xy 128.60909 -48.782224) (xy 128.60909 -48.731424) (xy 128.48209 -48.731424) (xy 128.48209 -48.782224)
			(xy 128.49479 -48.972724) (xy 128.59639 -48.972724)
		)
		(stroke
			(width 0)
			(type solid)
		)
		(fill yes)
		(layer "F.Cu")
		(net "M_H_DQ<51>")
	)
	(gr_poly
		(pts
			(xy 128.60909 -48.388524) (xy 128.60909 -48.337724) (xy 128.48209 -48.337724) (xy 128.48209 -48.388524)
			(xy 128.49479 -48.579024) (xy 128.59639 -48.579024)
		)
		(stroke
			(width 0)
			(type solid)
		)
		(fill yes)
		(layer "F.Cu")
		(net "M_H_DQ<50>")
	)
	(gr_poly
		(pts
			(xy 128.60909 -47.994824) (xy 128.60909 -47.944024) (xy 128.48209 -47.944024) (xy 128.48209 -47.994824)
			(xy 128.49479 -48.185324) (xy 128.59639 -48.185324)
		)
		(stroke
			(width 0)
			(type solid)
		)
		(fill yes)
		(layer "F.Cu")
		(net "M_H_DQ<55>")
	)
	(gr_poly
		(pts
			(xy 128.60909 -47.601124) (xy 128.60909 -47.550324) (xy 128.48209 -47.550324) (xy 128.48209 -47.601124)
			(xy 128.49479 -47.791624) (xy 128.59639 -47.791624)
		)
		(stroke
			(width 0)
			(type solid)
		)
		(fill yes)
		(layer "F.Cu")
		(net "M_H_DQ<54>")
	)
	(gr_poly
		(pts
			(xy 128.60909 -47.207424) (xy 128.60909 -47.156624) (xy 128.48209 -47.156624) (xy 128.48209 -47.207424)
			(xy 128.49479 -47.397924) (xy 128.59639 -47.397924)
		)
		(stroke
			(width 0)
			(type solid)
		)
		(fill yes)
		(layer "F.Cu")
		(net "M_H_DQS_DP<6>")
	)
	(gr_poly
		(pts
			(xy 128.60909 -46.813724) (xy 128.60909 -46.762924) (xy 128.48209 -46.762924) (xy 128.48209 -46.813724)
			(xy 128.49479 -47.004224) (xy 128.59639 -47.004224)
		)
		(stroke
			(width 0)
			(type solid)
		)
		(fill yes)
		(layer "F.Cu")
		(net "M_H_DQS_DN<6>")
	)
	(gr_poly
		(pts
			(xy 128.60909 -46.420024) (xy 128.60909 -46.369224) (xy 128.48209 -46.369224) (xy 128.48209 -46.420024)
			(xy 128.49479 -46.610524) (xy 128.59639 -46.610524)
		)
		(stroke
			(width 0)
			(type solid)
		)
		(fill yes)
		(layer "F.Cu")
		(net "M_H_DQS_DN<15>")
	)
	(gr_poly
		(pts
			(xy 128.60909 -46.026324) (xy 128.60909 -45.975524) (xy 128.48209 -45.975524) (xy 128.48209 -46.026324)
			(xy 128.49479 -46.216824) (xy 128.59639 -46.216824)
		)
		(stroke
			(width 0)
			(type solid)
		)
		(fill yes)
		(layer "F.Cu")
		(net "M_H_DQS_DP<15>")
	)
	(gr_poly
		(pts
			(xy 128.60909 -45.632624) (xy 128.60909 -45.581824) (xy 128.48209 -45.581824) (xy 128.48209 -45.632624)
			(xy 128.49479 -45.823124) (xy 128.59639 -45.823124)
		)
		(stroke
			(width 0)
			(type solid)
		)
		(fill yes)
		(layer "F.Cu")
		(net "M_H_DQ<49>")
	)
	(gr_poly
		(pts
			(xy 128.60909 -45.238924) (xy 128.60909 -45.188124) (xy 128.48209 -45.188124) (xy 128.48209 -45.238924)
			(xy 128.49479 -45.429424) (xy 128.59639 -45.429424)
		)
		(stroke
			(width 0)
			(type solid)
		)
		(fill yes)
		(layer "F.Cu")
		(net "M_H_DQ<48>")
	)
	(gr_poly
		(pts
			(xy 128.60909 -44.845224) (xy 128.60909 -44.794424) (xy 128.48209 -44.794424) (xy 128.48209 -44.845224)
			(xy 128.49479 -45.035724) (xy 128.59639 -45.035724)
		)
		(stroke
			(width 0)
			(type solid)
		)
		(fill yes)
		(layer "F.Cu")
		(net "M_H_DQ<53>")
	)
	(gr_poly
		(pts
			(xy 128.60909 -44.451524) (xy 128.60909 -44.400724) (xy 128.48209 -44.400724) (xy 128.48209 -44.451524)
			(xy 128.49479 -44.642024) (xy 128.59639 -44.642024)
		)
		(stroke
			(width 0)
			(type solid)
		)
		(fill yes)
		(layer "F.Cu")
		(net "M_H_DQ<52>")
	)
	(gr_poly
		(pts
			(xy 128.773428 -108.572554) (xy 128.760728 -108.382054) (xy 128.659128 -108.382054) (xy 128.646428 -108.572554)
			(xy 128.646428 -108.623354) (xy 128.773428 -108.623354)
		)
		(stroke
			(width 0)
			(type solid)
		)
		(fill yes)
		(layer "F.Cu")
		(net "M_L_DQ<52>")
	)
	(gr_poly
		(pts
			(xy 128.773428 -108.178854) (xy 128.760728 -107.988354) (xy 128.659128 -107.988354) (xy 128.646428 -108.178854)
			(xy 128.646428 -108.229654) (xy 128.773428 -108.229654)
		)
		(stroke
			(width 0)
			(type solid)
		)
		(fill yes)
		(layer "F.Cu")
		(net "M_L_DQ<53>")
	)
	(gr_poly
		(pts
			(xy 128.773428 -107.785154) (xy 128.760728 -107.594654) (xy 128.659128 -107.594654) (xy 128.646428 -107.785154)
			(xy 128.646428 -107.835954) (xy 128.773428 -107.835954)
		)
		(stroke
			(width 0)
			(type solid)
		)
		(fill yes)
		(layer "F.Cu")
		(net "M_L_DQ<48>")
	)
	(gr_poly
		(pts
			(xy 128.773428 -107.391454) (xy 128.760728 -107.200954) (xy 128.659128 -107.200954) (xy 128.646428 -107.391454)
			(xy 128.646428 -107.442254) (xy 128.773428 -107.442254)
		)
		(stroke
			(width 0)
			(type solid)
		)
		(fill yes)
		(layer "F.Cu")
		(net "M_L_DQ<49>")
	)
	(gr_poly
		(pts
			(xy 128.773428 -106.997754) (xy 128.760728 -106.807254) (xy 128.659128 -106.807254) (xy 128.646428 -106.997754)
			(xy 128.646428 -107.048554) (xy 128.773428 -107.048554)
		)
		(stroke
			(width 0)
			(type solid)
		)
		(fill yes)
		(layer "F.Cu")
		(net "M_L_DQS_DP<15>")
	)
	(gr_poly
		(pts
			(xy 128.773428 -106.604054) (xy 128.760728 -106.413554) (xy 128.659128 -106.413554) (xy 128.646428 -106.604054)
			(xy 128.646428 -106.654854) (xy 128.773428 -106.654854)
		)
		(stroke
			(width 0)
			(type solid)
		)
		(fill yes)
		(layer "F.Cu")
		(net "M_L_DQS_DN<15>")
	)
	(gr_poly
		(pts
			(xy 128.773428 -106.210354) (xy 128.760728 -106.019854) (xy 128.659128 -106.019854) (xy 128.646428 -106.210354)
			(xy 128.646428 -106.261154) (xy 128.773428 -106.261154)
		)
		(stroke
			(width 0)
			(type solid)
		)
		(fill yes)
		(layer "F.Cu")
		(net "M_L_DQS_DN<6>")
	)
	(gr_poly
		(pts
			(xy 128.773428 -105.816654) (xy 128.760728 -105.626154) (xy 128.659128 -105.626154) (xy 128.646428 -105.816654)
			(xy 128.646428 -105.867454) (xy 128.773428 -105.867454)
		)
		(stroke
			(width 0)
			(type solid)
		)
		(fill yes)
		(layer "F.Cu")
		(net "M_L_DQS_DP<6>")
	)
	(gr_poly
		(pts
			(xy 128.773428 -105.422954) (xy 128.760728 -105.232454) (xy 128.659128 -105.232454) (xy 128.646428 -105.422954)
			(xy 128.646428 -105.473754) (xy 128.773428 -105.473754)
		)
		(stroke
			(width 0)
			(type solid)
		)
		(fill yes)
		(layer "F.Cu")
		(net "M_L_DQ<54>")
	)
	(gr_poly
		(pts
			(xy 128.773428 -105.029254) (xy 128.760728 -104.838754) (xy 128.659128 -104.838754) (xy 128.646428 -105.029254)
			(xy 128.646428 -105.080054) (xy 128.773428 -105.080054)
		)
		(stroke
			(width 0)
			(type solid)
		)
		(fill yes)
		(layer "F.Cu")
		(net "M_L_DQ<55>")
	)
	(gr_poly
		(pts
			(xy 128.773428 -104.635554) (xy 128.760728 -104.445054) (xy 128.659128 -104.445054) (xy 128.646428 -104.635554)
			(xy 128.646428 -104.686354) (xy 128.773428 -104.686354)
		)
		(stroke
			(width 0)
			(type solid)
		)
		(fill yes)
		(layer "F.Cu")
		(net "M_L_DQ<50>")
	)
	(gr_poly
		(pts
			(xy 128.773428 -104.241854) (xy 128.760728 -104.051354) (xy 128.659128 -104.051354) (xy 128.646428 -104.241854)
			(xy 128.646428 -104.292654) (xy 128.773428 -104.292654)
		)
		(stroke
			(width 0)
			(type solid)
		)
		(fill yes)
		(layer "F.Cu")
		(net "M_L_DQ<51>")
	)
	(gr_poly
		(pts
			(xy 128.93929 -48.680624) (xy 128.92659 -48.490124) (xy 128.82499 -48.490124) (xy 128.81229 -48.680624)
			(xy 128.81229 -48.731424) (xy 128.93929 -48.731424)
		)
		(stroke
			(width 0)
			(type solid)
		)
		(fill yes)
		(layer "F.Cu")
		(net "M_H_DQ<51>")
	)
	(gr_poly
		(pts
			(xy 128.93929 -48.286924) (xy 128.92659 -48.096424) (xy 128.82499 -48.096424) (xy 128.81229 -48.286924)
			(xy 128.81229 -48.337724) (xy 128.93929 -48.337724)
		)
		(stroke
			(width 0)
			(type solid)
		)
		(fill yes)
		(layer "F.Cu")
		(net "M_H_DQ<50>")
	)
	(gr_poly
		(pts
			(xy 128.93929 -47.893224) (xy 128.92659 -47.702724) (xy 128.82499 -47.702724) (xy 128.81229 -47.893224)
			(xy 128.81229 -47.944024) (xy 128.93929 -47.944024)
		)
		(stroke
			(width 0)
			(type solid)
		)
		(fill yes)
		(layer "F.Cu")
		(net "M_H_DQ<55>")
	)
	(gr_poly
		(pts
			(xy 128.93929 -47.499524) (xy 128.92659 -47.309024) (xy 128.82499 -47.309024) (xy 128.81229 -47.499524)
			(xy 128.81229 -47.550324) (xy 128.93929 -47.550324)
		)
		(stroke
			(width 0)
			(type solid)
		)
		(fill yes)
		(layer "F.Cu")
		(net "M_H_DQ<54>")
	)
	(gr_poly
		(pts
			(xy 128.93929 -47.105824) (xy 128.92659 -46.915324) (xy 128.82499 -46.915324) (xy 128.81229 -47.105824)
			(xy 128.81229 -47.156624) (xy 128.93929 -47.156624)
		)
		(stroke
			(width 0)
			(type solid)
		)
		(fill yes)
		(layer "F.Cu")
		(net "M_H_DQS_DP<6>")
	)
	(gr_poly
		(pts
			(xy 128.93929 -46.712124) (xy 128.92659 -46.521624) (xy 128.82499 -46.521624) (xy 128.81229 -46.712124)
			(xy 128.81229 -46.762924) (xy 128.93929 -46.762924)
		)
		(stroke
			(width 0)
			(type solid)
		)
		(fill yes)
		(layer "F.Cu")
		(net "M_H_DQS_DN<6>")
	)
	(gr_poly
		(pts
			(xy 128.93929 -46.318424) (xy 128.92659 -46.127924) (xy 128.82499 -46.127924) (xy 128.81229 -46.318424)
			(xy 128.81229 -46.369224) (xy 128.93929 -46.369224)
		)
		(stroke
			(width 0)
			(type solid)
		)
		(fill yes)
		(layer "F.Cu")
		(net "M_H_DQS_DN<15>")
	)
	(gr_poly
		(pts
			(xy 128.93929 -45.924724) (xy 128.92659 -45.734224) (xy 128.82499 -45.734224) (xy 128.81229 -45.924724)
			(xy 128.81229 -45.975524) (xy 128.93929 -45.975524)
		)
		(stroke
			(width 0)
			(type solid)
		)
		(fill yes)
		(layer "F.Cu")
		(net "M_H_DQS_DP<15>")
	)
	(gr_poly
		(pts
			(xy 128.93929 -45.531024) (xy 128.92659 -45.340524) (xy 128.82499 -45.340524) (xy 128.81229 -45.531024)
			(xy 128.81229 -45.581824) (xy 128.93929 -45.581824)
		)
		(stroke
			(width 0)
			(type solid)
		)
		(fill yes)
		(layer "F.Cu")
		(net "M_H_DQ<49>")
	)
	(gr_poly
		(pts
			(xy 129.003298 -44.615608) (xy 128.967484 -44.57954) (xy 128.82372 -44.45381) (xy 128.751838 -44.525692)
			(xy 128.877568 -44.669456) (xy 128.913636 -44.70527)
		)
		(stroke
			(width 0)
			(type solid)
		)
		(fill yes)
		(layer "F.Cu")
		(net "M_H_DQ<53>")
	)
	(gr_poly
		(pts
			(xy 129.103628 -108.674154) (xy 129.103628 -108.623354) (xy 128.976628 -108.623354) (xy 128.976628 -108.674154)
			(xy 128.989328 -108.864654) (xy 129.090928 -108.864654)
		)
		(stroke
			(width 0)
			(type solid)
		)
		(fill yes)
		(layer "F.Cu")
		(net "M_L_DQ<52>")
	)
	(gr_poly
		(pts
			(xy 129.103628 -108.280454) (xy 129.103628 -108.229654) (xy 128.976628 -108.229654) (xy 128.976628 -108.280454)
			(xy 128.989328 -108.470954) (xy 129.090928 -108.470954)
		)
		(stroke
			(width 0)
			(type solid)
		)
		(fill yes)
		(layer "F.Cu")
		(net "M_L_DQ<53>")
	)
	(gr_poly
		(pts
			(xy 129.103628 -107.886754) (xy 129.103628 -107.835954) (xy 128.976628 -107.835954) (xy 128.976628 -107.886754)
			(xy 128.989328 -108.077254) (xy 129.090928 -108.077254)
		)
		(stroke
			(width 0)
			(type solid)
		)
		(fill yes)
		(layer "F.Cu")
		(net "M_L_DQ<48>")
	)
	(gr_poly
		(pts
			(xy 129.103628 -107.493054) (xy 129.103628 -107.442254) (xy 128.976628 -107.442254) (xy 128.976628 -107.493054)
			(xy 128.989328 -107.683554) (xy 129.090928 -107.683554)
		)
		(stroke
			(width 0)
			(type solid)
		)
		(fill yes)
		(layer "F.Cu")
		(net "M_L_DQ<49>")
	)
	(gr_poly
		(pts
			(xy 129.103628 -107.099354) (xy 129.103628 -107.048554) (xy 128.976628 -107.048554) (xy 128.976628 -107.099354)
			(xy 128.989328 -107.289854) (xy 129.090928 -107.289854)
		)
		(stroke
			(width 0)
			(type solid)
		)
		(fill yes)
		(layer "F.Cu")
		(net "M_L_DQS_DP<15>")
	)
	(gr_poly
		(pts
			(xy 129.103628 -106.705654) (xy 129.103628 -106.654854) (xy 128.976628 -106.654854) (xy 128.976628 -106.705654)
			(xy 128.989328 -106.896154) (xy 129.090928 -106.896154)
		)
		(stroke
			(width 0)
			(type solid)
		)
		(fill yes)
		(layer "F.Cu")
		(net "M_L_DQS_DN<15>")
	)
	(gr_poly
		(pts
			(xy 129.103628 -106.311954) (xy 129.103628 -106.261154) (xy 128.976628 -106.261154) (xy 128.976628 -106.311954)
			(xy 128.989328 -106.502454) (xy 129.090928 -106.502454)
		)
		(stroke
			(width 0)
			(type solid)
		)
		(fill yes)
		(layer "F.Cu")
		(net "M_L_DQS_DN<6>")
	)
	(gr_poly
		(pts
			(xy 129.103628 -105.918254) (xy 129.103628 -105.867454) (xy 128.976628 -105.867454) (xy 128.976628 -105.918254)
			(xy 128.989328 -106.108754) (xy 129.090928 -106.108754)
		)
		(stroke
			(width 0)
			(type solid)
		)
		(fill yes)
		(layer "F.Cu")
		(net "M_L_DQS_DP<6>")
	)
	(gr_poly
		(pts
			(xy 129.103628 -105.524554) (xy 129.103628 -105.473754) (xy 128.976628 -105.473754) (xy 128.976628 -105.524554)
			(xy 128.989328 -105.715054) (xy 129.090928 -105.715054)
		)
		(stroke
			(width 0)
			(type solid)
		)
		(fill yes)
		(layer "F.Cu")
		(net "M_L_DQ<54>")
	)
	(gr_poly
		(pts
			(xy 129.103628 -105.130854) (xy 129.103628 -105.080054) (xy 128.976628 -105.080054) (xy 128.976628 -105.130854)
			(xy 128.989328 -105.321354) (xy 129.090928 -105.321354)
		)
		(stroke
			(width 0)
			(type solid)
		)
		(fill yes)
		(layer "F.Cu")
		(net "M_L_DQ<55>")
	)
	(gr_poly
		(pts
			(xy 129.103628 -104.737154) (xy 129.103628 -104.686354) (xy 128.976628 -104.686354) (xy 128.976628 -104.737154)
			(xy 128.989328 -104.927654) (xy 129.090928 -104.927654)
		)
		(stroke
			(width 0)
			(type solid)
		)
		(fill yes)
		(layer "F.Cu")
		(net "M_L_DQ<50>")
	)
	(gr_poly
		(pts
			(xy 129.103628 -104.343454) (xy 129.103628 -104.292654) (xy 128.976628 -104.292654) (xy 128.976628 -104.343454)
			(xy 128.989328 -104.533954) (xy 129.090928 -104.533954)
		)
		(stroke
			(width 0)
			(type solid)
		)
		(fill yes)
		(layer "F.Cu")
		(net "M_L_DQ<51>")
	)
	(gr_poly
		(pts
			(xy 129.119884 -44.283122) (xy 128.994408 -44.139358) (xy 128.95834 -44.103544) (xy 128.868678 -44.193206)
			(xy 128.904492 -44.229274) (xy 129.048256 -44.355004)
		)
		(stroke
			(width 0)
			(type solid)
		)
		(fill yes)
		(layer "F.Cu")
		(net "M_H_DQ<52>")
	)
	(gr_poly
		(pts
			(xy 129.191766 -43.870118) (xy 129.155952 -43.83405) (xy 129.012188 -43.70832) (xy 128.940306 -43.780202)
			(xy 129.066036 -43.923966) (xy 129.102104 -43.95978)
		)
		(stroke
			(width 0)
			(type solid)
		)
		(fill yes)
		(layer "F.Cu")
		(net "M_H_DQ<52>")
	)
	(gr_poly
		(pts
			(xy 129.26949 -48.782224) (xy 129.26949 -48.731424) (xy 129.14249 -48.731424) (xy 129.14249 -48.782224)
			(xy 129.15519 -48.972724) (xy 129.25679 -48.972724)
		)
		(stroke
			(width 0)
			(type solid)
		)
		(fill yes)
		(layer "F.Cu")
		(net "M_H_DQ<51>")
	)
	(gr_poly
		(pts
			(xy 129.26949 -48.388524) (xy 129.26949 -48.337724) (xy 129.14249 -48.337724) (xy 129.14249 -48.388524)
			(xy 129.15519 -48.579024) (xy 129.25679 -48.579024)
		)
		(stroke
			(width 0)
			(type solid)
		)
		(fill yes)
		(layer "F.Cu")
		(net "M_H_DQ<50>")
	)
	(gr_poly
		(pts
			(xy 129.26949 -47.994824) (xy 129.26949 -47.944024) (xy 129.14249 -47.944024) (xy 129.14249 -47.994824)
			(xy 129.15519 -48.185324) (xy 129.25679 -48.185324)
		)
		(stroke
			(width 0)
			(type solid)
		)
		(fill yes)
		(layer "F.Cu")
		(net "M_H_DQ<55>")
	)
	(gr_poly
		(pts
			(xy 129.26949 -47.601124) (xy 129.26949 -47.550324) (xy 129.14249 -47.550324) (xy 129.14249 -47.601124)
			(xy 129.15519 -47.791624) (xy 129.25679 -47.791624)
		)
		(stroke
			(width 0)
			(type solid)
		)
		(fill yes)
		(layer "F.Cu")
		(net "M_H_DQ<54>")
	)
	(gr_poly
		(pts
			(xy 129.26949 -47.207424) (xy 129.26949 -47.156624) (xy 129.14249 -47.156624) (xy 129.14249 -47.207424)
			(xy 129.15519 -47.397924) (xy 129.25679 -47.397924)
		)
		(stroke
			(width 0)
			(type solid)
		)
		(fill yes)
		(layer "F.Cu")
		(net "M_H_DQS_DP<6>")
	)
	(gr_poly
		(pts
			(xy 129.26949 -46.813724) (xy 129.26949 -46.762924) (xy 129.14249 -46.762924) (xy 129.14249 -46.813724)
			(xy 129.15519 -47.004224) (xy 129.25679 -47.004224)
		)
		(stroke
			(width 0)
			(type solid)
		)
		(fill yes)
		(layer "F.Cu")
		(net "M_H_DQS_DN<6>")
	)
	(gr_poly
		(pts
			(xy 129.26949 -46.420024) (xy 129.26949 -46.369224) (xy 129.14249 -46.369224) (xy 129.14249 -46.420024)
			(xy 129.15519 -46.610524) (xy 129.25679 -46.610524)
		)
		(stroke
			(width 0)
			(type solid)
		)
		(fill yes)
		(layer "F.Cu")
		(net "M_H_DQS_DN<15>")
	)
	(gr_poly
		(pts
			(xy 129.26949 -46.026324) (xy 129.26949 -45.975524) (xy 129.14249 -45.975524) (xy 129.14249 -46.026324)
			(xy 129.15519 -46.216824) (xy 129.25679 -46.216824)
		)
		(stroke
			(width 0)
			(type solid)
		)
		(fill yes)
		(layer "F.Cu")
		(net "M_H_DQS_DP<15>")
	)
	(gr_poly
		(pts
			(xy 129.281936 -44.893992) (xy 129.245868 -44.858178) (xy 129.102358 -44.732448) (xy 129.030476 -44.80433)
			(xy 129.156206 -44.94784) (xy 129.19202 -44.983908)
		)
		(stroke
			(width 0)
			(type solid)
		)
		(fill yes)
		(layer "F.Cu")
		(net "M_H_DQ<48>")
	)
	(gr_poly
		(pts
			(xy 129.398522 -44.56176) (xy 129.272792 -44.417996) (xy 129.236978 -44.381928) (xy 129.147062 -44.471844)
			(xy 129.182876 -44.507658) (xy 129.32664 -44.633388)
		)
		(stroke
			(width 0)
			(type solid)
		)
		(fill yes)
		(layer "F.Cu")
		(net "M_H_DQ<53>")
	)
	(gr_poly
		(pts
			(xy 129.433828 -108.572554) (xy 129.421128 -108.382054) (xy 129.319528 -108.382054) (xy 129.306828 -108.572554)
			(xy 129.306828 -108.623354) (xy 129.433828 -108.623354)
		)
		(stroke
			(width 0)
			(type solid)
		)
		(fill yes)
		(layer "F.Cu")
		(net "M_L_DQ<52>")
	)
	(gr_poly
		(pts
			(xy 129.433828 -108.178854) (xy 129.421128 -107.988354) (xy 129.319528 -107.988354) (xy 129.306828 -108.178854)
			(xy 129.306828 -108.229654) (xy 129.433828 -108.229654)
		)
		(stroke
			(width 0)
			(type solid)
		)
		(fill yes)
		(layer "F.Cu")
		(net "M_L_DQ<53>")
	)
	(gr_poly
		(pts
			(xy 129.433828 -107.785154) (xy 129.421128 -107.594654) (xy 129.319528 -107.594654) (xy 129.306828 -107.785154)
			(xy 129.306828 -107.835954) (xy 129.433828 -107.835954)
		)
		(stroke
			(width 0)
			(type solid)
		)
		(fill yes)
		(layer "F.Cu")
		(net "M_L_DQ<48>")
	)
	(gr_poly
		(pts
			(xy 129.433828 -107.391454) (xy 129.421128 -107.200954) (xy 129.319528 -107.200954) (xy 129.306828 -107.391454)
			(xy 129.306828 -107.442254) (xy 129.433828 -107.442254)
		)
		(stroke
			(width 0)
			(type solid)
		)
		(fill yes)
		(layer "F.Cu")
		(net "M_L_DQ<49>")
	)
	(gr_poly
		(pts
			(xy 129.433828 -106.997754) (xy 129.421128 -106.807254) (xy 129.319528 -106.807254) (xy 129.306828 -106.997754)
			(xy 129.306828 -107.048554) (xy 129.433828 -107.048554)
		)
		(stroke
			(width 0)
			(type solid)
		)
		(fill yes)
		(layer "F.Cu")
		(net "M_L_DQS_DP<15>")
	)
	(gr_poly
		(pts
			(xy 129.433828 -106.604054) (xy 129.421128 -106.413554) (xy 129.319528 -106.413554) (xy 129.306828 -106.604054)
			(xy 129.306828 -106.654854) (xy 129.433828 -106.654854)
		)
		(stroke
			(width 0)
			(type solid)
		)
		(fill yes)
		(layer "F.Cu")
		(net "M_L_DQS_DN<15>")
	)
	(gr_poly
		(pts
			(xy 129.433828 -106.210354) (xy 129.421128 -106.019854) (xy 129.319528 -106.019854) (xy 129.306828 -106.210354)
			(xy 129.306828 -106.261154) (xy 129.433828 -106.261154)
		)
		(stroke
			(width 0)
			(type solid)
		)
		(fill yes)
		(layer "F.Cu")
		(net "M_L_DQS_DN<6>")
	)
	(gr_poly
		(pts
			(xy 129.433828 -105.816654) (xy 129.421128 -105.626154) (xy 129.319528 -105.626154) (xy 129.306828 -105.816654)
			(xy 129.306828 -105.867454) (xy 129.433828 -105.867454)
		)
		(stroke
			(width 0)
			(type solid)
		)
		(fill yes)
		(layer "F.Cu")
		(net "M_L_DQS_DP<6>")
	)
	(gr_poly
		(pts
			(xy 129.433828 -105.422954) (xy 129.421128 -105.232454) (xy 129.319528 -105.232454) (xy 129.306828 -105.422954)
			(xy 129.306828 -105.473754) (xy 129.433828 -105.473754)
		)
		(stroke
			(width 0)
			(type solid)
		)
		(fill yes)
		(layer "F.Cu")
		(net "M_L_DQ<54>")
	)
	(gr_poly
		(pts
			(xy 129.433828 -105.029254) (xy 129.421128 -104.838754) (xy 129.319528 -104.838754) (xy 129.306828 -105.029254)
			(xy 129.306828 -105.080054) (xy 129.433828 -105.080054)
		)
		(stroke
			(width 0)
			(type solid)
		)
		(fill yes)
		(layer "F.Cu")
		(net "M_L_DQ<55>")
	)
	(gr_poly
		(pts
			(xy 129.433828 -104.635554) (xy 129.421128 -104.445054) (xy 129.319528 -104.445054) (xy 129.306828 -104.635554)
			(xy 129.306828 -104.686354) (xy 129.433828 -104.686354)
		)
		(stroke
			(width 0)
			(type solid)
		)
		(fill yes)
		(layer "F.Cu")
		(net "M_L_DQ<50>")
	)
	(gr_poly
		(pts
			(xy 129.433828 -104.241854) (xy 129.421128 -104.051354) (xy 129.319528 -104.051354) (xy 129.306828 -104.241854)
			(xy 129.306828 -104.292654) (xy 129.433828 -104.292654)
		)
		(stroke
			(width 0)
			(type solid)
		)
		(fill yes)
		(layer "F.Cu")
		(net "M_L_DQ<51>")
	)
	(gr_poly
		(pts
			(xy 129.470404 -44.148502) (xy 129.434336 -44.112688) (xy 129.290826 -43.986958) (xy 129.218944 -44.05884)
			(xy 129.344674 -44.20235) (xy 129.380488 -44.238418)
		)
		(stroke
			(width 0)
			(type solid)
		)
		(fill yes)
		(layer "F.Cu")
		(net "M_H_DQ<53>")
	)
	(gr_poly
		(pts
			(xy 129.488692 -45.585634) (xy 129.362962 -45.44187) (xy 129.326894 -45.406056) (xy 129.237232 -45.495718)
			(xy 129.273046 -45.531786) (xy 129.41681 -45.657516)
		)
		(stroke
			(width 0)
			(type solid)
		)
		(fill yes)
		(layer "F.Cu")
		(net "M_H_DQ<49>")
	)
	(gr_poly
		(pts
			(xy 129.56032 -45.17263) (xy 129.524506 -45.136562) (xy 129.380742 -45.010832) (xy 129.30886 -45.082714)
			(xy 129.43459 -45.226478) (xy 129.470658 -45.262292)
		)
		(stroke
			(width 0)
			(type solid)
		)
		(fill yes)
		(layer "F.Cu")
		(net "M_H_DQ<49>")
	)
	(gr_poly
		(pts
			(xy 129.58699 -43.81627) (xy 129.46126 -43.672506) (xy 129.425446 -43.636438) (xy 129.33553 -43.726354)
			(xy 129.371344 -43.762168) (xy 129.515108 -43.887898)
		)
		(stroke
			(width 0)
			(type solid)
		)
		(fill yes)
		(layer "F.Cu")
		(net "M_H_DQ<52>")
	)
	(gr_poly
		(pts
			(xy 129.59969 -48.680624) (xy 129.58699 -48.490124) (xy 129.48539 -48.490124) (xy 129.47269 -48.680624)
			(xy 129.47269 -48.731424) (xy 129.59969 -48.731424)
		)
		(stroke
			(width 0)
			(type solid)
		)
		(fill yes)
		(layer "F.Cu")
		(net "M_H_DQ<51>")
	)
	(gr_poly
		(pts
			(xy 129.59969 -48.286924) (xy 129.58699 -48.096424) (xy 129.48539 -48.096424) (xy 129.47269 -48.286924)
			(xy 129.47269 -48.337724) (xy 129.59969 -48.337724)
		)
		(stroke
			(width 0)
			(type solid)
		)
		(fill yes)
		(layer "F.Cu")
		(net "M_H_DQ<50>")
	)
	(gr_poly
		(pts
			(xy 129.59969 -47.893224) (xy 129.58699 -47.702724) (xy 129.48539 -47.702724) (xy 129.47269 -47.893224)
			(xy 129.47269 -47.944024) (xy 129.59969 -47.944024)
		)
		(stroke
			(width 0)
			(type solid)
		)
		(fill yes)
		(layer "F.Cu")
		(net "M_H_DQ<55>")
	)
	(gr_poly
		(pts
			(xy 129.59969 -47.499524) (xy 129.58699 -47.309024) (xy 129.48539 -47.309024) (xy 129.47269 -47.499524)
			(xy 129.47269 -47.550324) (xy 129.59969 -47.550324)
		)
		(stroke
			(width 0)
			(type solid)
		)
		(fill yes)
		(layer "F.Cu")
		(net "M_H_DQ<54>")
	)
	(gr_poly
		(pts
			(xy 129.59969 -47.105824) (xy 129.58699 -46.915324) (xy 129.48539 -46.915324) (xy 129.47269 -47.105824)
			(xy 129.47269 -47.156624) (xy 129.59969 -47.156624)
		)
		(stroke
			(width 0)
			(type solid)
		)
		(fill yes)
		(layer "F.Cu")
		(net "M_H_DQS_DP<6>")
	)
	(gr_poly
		(pts
			(xy 129.65049 -46.196504) (xy 129.614422 -46.16069) (xy 129.470912 -46.03496) (xy 129.39903 -46.106842)
			(xy 129.52476 -46.250352) (xy 129.560574 -46.28642)
		)
		(stroke
			(width 0)
			(type solid)
		)
		(fill yes)
		(layer "F.Cu")
		(net "M_H_DQS_DN<15>")
	)
	(gr_poly
		(pts
			(xy 129.658872 -43.403012) (xy 129.622804 -43.367198) (xy 129.479294 -43.241468) (xy 129.407412 -43.31335)
			(xy 129.533142 -43.45686) (xy 129.568956 -43.492928)
		)
		(stroke
			(width 0)
			(type solid)
		)
		(fill yes)
		(layer "F.Cu")
		(net "M_H_DQ<52>")
	)
	(gr_poly
		(pts
			(xy 129.676906 -44.840144) (xy 129.55143 -44.69638) (xy 129.515362 -44.660566) (xy 129.4257 -44.750228)
			(xy 129.461514 -44.786296) (xy 129.605278 -44.912026)
		)
		(stroke
			(width 0)
			(type solid)
		)
		(fill yes)
		(layer "F.Cu")
		(net "M_H_DQ<48>")
	)
	(gr_poly
		(pts
			(xy 129.748788 -44.42714) (xy 129.712974 -44.391072) (xy 129.56921 -44.265342) (xy 129.497328 -44.337224)
			(xy 129.623058 -44.480988) (xy 129.659126 -44.516802)
		)
		(stroke
			(width 0)
			(type solid)
		)
		(fill yes)
		(layer "F.Cu")
		(net "M_H_DQ<48>")
	)
	(gr_poly
		(pts
			(xy 129.758948 -108.744766) (xy 129.884678 -108.601002) (xy 129.812796 -108.529374) (xy 129.669032 -108.655104)
			(xy 129.633218 -108.690918) (xy 129.723134 -108.780834)
		)
		(stroke
			(width 0)
			(type solid)
		)
		(fill yes)
		(layer "F.Cu")
		(net "M_L_DQ<52>")
	)
	(gr_poly
		(pts
			(xy 129.764028 -107.886754) (xy 129.764028 -107.835954) (xy 129.637028 -107.835954) (xy 129.637028 -107.886754)
			(xy 129.649728 -108.077254) (xy 129.751328 -108.077254)
		)
		(stroke
			(width 0)
			(type solid)
		)
		(fill yes)
		(layer "F.Cu")
		(net "M_L_DQ<48>")
	)
	(gr_poly
		(pts
			(xy 129.764028 -107.493054) (xy 129.764028 -107.442254) (xy 129.637028 -107.442254) (xy 129.637028 -107.493054)
			(xy 129.649728 -107.683554) (xy 129.751328 -107.683554)
		)
		(stroke
			(width 0)
			(type solid)
		)
		(fill yes)
		(layer "F.Cu")
		(net "M_L_DQ<49>")
	)
	(gr_poly
		(pts
			(xy 129.764028 -107.099354) (xy 129.764028 -107.048554) (xy 129.637028 -107.048554) (xy 129.637028 -107.099354)
			(xy 129.649728 -107.289854) (xy 129.751328 -107.289854)
		)
		(stroke
			(width 0)
			(type solid)
		)
		(fill yes)
		(layer "F.Cu")
		(net "M_L_DQS_DP<15>")
	)
	(gr_poly
		(pts
			(xy 129.764028 -106.705654) (xy 129.764028 -106.654854) (xy 129.637028 -106.654854) (xy 129.637028 -106.705654)
			(xy 129.649728 -106.896154) (xy 129.751328 -106.896154)
		)
		(stroke
			(width 0)
			(type solid)
		)
		(fill yes)
		(layer "F.Cu")
		(net "M_L_DQS_DN<15>")
	)
	(gr_poly
		(pts
			(xy 129.764028 -106.311954) (xy 129.764028 -106.261154) (xy 129.637028 -106.261154) (xy 129.637028 -106.311954)
			(xy 129.649728 -106.502454) (xy 129.751328 -106.502454)
		)
		(stroke
			(width 0)
			(type solid)
		)
		(fill yes)
		(layer "F.Cu")
		(net "M_L_DQS_DN<6>")
	)
	(gr_poly
		(pts
			(xy 129.764028 -105.918254) (xy 129.764028 -105.867454) (xy 129.637028 -105.867454) (xy 129.637028 -105.918254)
			(xy 129.649728 -106.108754) (xy 129.751328 -106.108754)
		)
		(stroke
			(width 0)
			(type solid)
		)
		(fill yes)
		(layer "F.Cu")
		(net "M_L_DQS_DP<6>")
	)
	(gr_poly
		(pts
			(xy 129.764028 -105.524554) (xy 129.764028 -105.473754) (xy 129.637028 -105.473754) (xy 129.637028 -105.524554)
			(xy 129.649728 -105.715054) (xy 129.751328 -105.715054)
		)
		(stroke
			(width 0)
			(type solid)
		)
		(fill yes)
		(layer "F.Cu")
		(net "M_L_DQ<54>")
	)
	(gr_poly
		(pts
			(xy 129.764028 -105.130854) (xy 129.764028 -105.080054) (xy 129.637028 -105.080054) (xy 129.637028 -105.130854)
			(xy 129.649728 -105.321354) (xy 129.751328 -105.321354)
		)
		(stroke
			(width 0)
			(type solid)
		)
		(fill yes)
		(layer "F.Cu")
		(net "M_L_DQ<55>")
	)
	(gr_poly
		(pts
			(xy 129.764028 -104.737154) (xy 129.764028 -104.686354) (xy 129.637028 -104.686354) (xy 129.637028 -104.737154)
			(xy 129.649728 -104.927654) (xy 129.751328 -104.927654)
		)
		(stroke
			(width 0)
			(type solid)
		)
		(fill yes)
		(layer "F.Cu")
		(net "M_L_DQ<50>")
	)
	(gr_poly
		(pts
			(xy 129.764028 -104.343454) (xy 129.764028 -104.292654) (xy 129.637028 -104.292654) (xy 129.637028 -104.343454)
			(xy 129.649728 -104.533954) (xy 129.751328 -104.533954)
		)
		(stroke
			(width 0)
			(type solid)
		)
		(fill yes)
		(layer "F.Cu")
		(net "M_L_DQ<51>")
	)
	(gr_poly
		(pts
			(xy 129.767076 -45.864272) (xy 129.641346 -45.720508) (xy 129.605532 -45.68444) (xy 129.515616 -45.774356)
			(xy 129.55143 -45.81017) (xy 129.695194 -45.9359)
		)
		(stroke
			(width 0)
			(type solid)
		)
		(fill yes)
		(layer "F.Cu")
		(net "M_H_DQS_DP<15>")
	)
	(gr_poly
		(pts
			(xy 129.838958 -45.451014) (xy 129.80289 -45.4152) (xy 129.65938 -45.28947) (xy 129.587498 -45.361352)
			(xy 129.713228 -45.504862) (xy 129.749042 -45.54093)
		)
		(stroke
			(width 0)
			(type solid)
		)
		(fill yes)
		(layer "F.Cu")
		(net "M_H_DQS_DP<15>")
	)
	(gr_poly
		(pts
			(xy 129.865374 -44.094654) (xy 129.739644 -43.95089) (xy 129.70383 -43.915076) (xy 129.614168 -44.004738)
			(xy 129.649982 -44.040806) (xy 129.793746 -44.166536)
		)
		(stroke
			(width 0)
			(type solid)
		)
		(fill yes)
		(layer "F.Cu")
		(net "M_H_DQ<53>")
	)
	(gr_poly
		(pts
			(xy 129.920492 -109.050074) (xy 129.95656 -109.01426) (xy 129.866644 -108.924344) (xy 129.83083 -108.960412)
			(xy 129.7051 -109.103922) (xy 129.776982 -109.175804)
		)
		(stroke
			(width 0)
			(type solid)
		)
		(fill yes)
		(layer "F.Cu")
		(net "M_L_DQ<52>")
	)
	(gr_poly
		(pts
			(xy 129.928874 -46.475142) (xy 129.89306 -46.439074) (xy 129.749296 -46.313344) (xy 129.677414 -46.385226)
			(xy 129.803144 -46.52899) (xy 129.839212 -46.564804)
		)
		(stroke
			(width 0)
			(type solid)
		)
		(fill yes)
		(layer "F.Cu")
		(net "M_H_DQS_DN<6>")
	)
	(gr_poly
		(pts
			(xy 129.92989 -48.782224) (xy 129.92989 -48.731424) (xy 129.80289 -48.731424) (xy 129.80289 -48.782224)
			(xy 129.81559 -48.972724) (xy 129.91719 -48.972724)
		)
		(stroke
			(width 0)
			(type solid)
		)
		(fill yes)
		(layer "F.Cu")
		(net "M_H_DQ<51>")
	)
	(gr_poly
		(pts
			(xy 129.92989 -48.388524) (xy 129.92989 -48.337724) (xy 129.80289 -48.337724) (xy 129.80289 -48.388524)
			(xy 129.81559 -48.579024) (xy 129.91719 -48.579024)
		)
		(stroke
			(width 0)
			(type solid)
		)
		(fill yes)
		(layer "F.Cu")
		(net "M_H_DQ<50>")
	)
	(gr_poly
		(pts
			(xy 129.937256 -43.68165) (xy 129.901442 -43.645582) (xy 129.757678 -43.519852) (xy 129.685796 -43.591734)
			(xy 129.811526 -43.735498) (xy 129.847594 -43.771312)
		)
		(stroke
			(width 0)
			(type solid)
		)
		(fill yes)
		(layer "F.Cu")
		(net "M_H_DQ<53>")
	)
	(gr_poly
		(pts
			(xy 129.955544 -45.118782) (xy 129.829814 -44.975018) (xy 129.794 -44.93895) (xy 129.704084 -45.028866)
			(xy 129.739898 -45.06468) (xy 129.883662 -45.19041)
		)
		(stroke
			(width 0)
			(type solid)
		)
		(fill yes)
		(layer "F.Cu")
		(net "M_H_DQ<49>")
	)
	(gr_poly
		(pts
			(xy 130.027426 -44.705524) (xy 129.991358 -44.66971) (xy 129.847848 -44.54398) (xy 129.775966 -44.615862)
			(xy 129.901696 -44.759372) (xy 129.93751 -44.79544)
		)
		(stroke
			(width 0)
			(type solid)
		)
		(fill yes)
		(layer "F.Cu")
		(net "M_H_DQ<49>")
	)
	(gr_poly
		(pts
			(xy 130.037332 -108.466382) (xy 130.163062 -108.322618) (xy 130.091434 -108.250736) (xy 129.94767 -108.376466)
			(xy 129.911602 -108.41228) (xy 130.001518 -108.502196)
		)
		(stroke
			(width 0)
			(type solid)
		)
		(fill yes)
		(layer "F.Cu")
		(net "M_L_DQ<53>")
	)
	(gr_poly
		(pts
			(xy 130.045714 -46.142656) (xy 129.919984 -45.998892) (xy 129.883916 -45.963078) (xy 129.794254 -46.05274)
			(xy 129.830068 -46.088808) (xy 129.973832 -46.214538)
		)
		(stroke
			(width 0)
			(type solid)
		)
		(fill yes)
		(layer "F.Cu")
		(net "M_H_DQS_DN<15>")
	)
	(gr_poly
		(pts
			(xy 130.094228 -106.997754) (xy 130.081528 -106.807254) (xy 129.979928 -106.807254) (xy 129.967228 -106.997754)
			(xy 129.967228 -107.048554) (xy 130.094228 -107.048554)
		)
		(stroke
			(width 0)
			(type solid)
		)
		(fill yes)
		(layer "F.Cu")
		(net "M_L_DQS_DP<15>")
	)
	(gr_poly
		(pts
			(xy 130.094228 -106.604054) (xy 130.081528 -106.413554) (xy 129.979928 -106.413554) (xy 129.967228 -106.604054)
			(xy 129.967228 -106.654854) (xy 130.094228 -106.654854)
		)
		(stroke
			(width 0)
			(type solid)
		)
		(fill yes)
		(layer "F.Cu")
		(net "M_L_DQS_DN<15>")
	)
	(gr_poly
		(pts
			(xy 130.094228 -106.210354) (xy 130.081528 -106.019854) (xy 129.979928 -106.019854) (xy 129.967228 -106.210354)
			(xy 129.967228 -106.261154) (xy 130.094228 -106.261154)
		)
		(stroke
			(width 0)
			(type solid)
		)
		(fill yes)
		(layer "F.Cu")
		(net "M_L_DQS_DN<6>")
	)
	(gr_poly
		(pts
			(xy 130.094228 -105.816654) (xy 130.081528 -105.626154) (xy 129.979928 -105.626154) (xy 129.967228 -105.816654)
			(xy 129.967228 -105.867454) (xy 130.094228 -105.867454)
		)
		(stroke
			(width 0)
			(type solid)
		)
		(fill yes)
		(layer "F.Cu")
		(net "M_L_DQS_DP<6>")
	)
	(gr_poly
		(pts
			(xy 130.094228 -105.422954) (xy 130.081528 -105.232454) (xy 129.979928 -105.232454) (xy 129.967228 -105.422954)
			(xy 129.967228 -105.473754) (xy 130.094228 -105.473754)
		)
		(stroke
			(width 0)
			(type solid)
		)
		(fill yes)
		(layer "F.Cu")
		(net "M_L_DQ<54>")
	)
	(gr_poly
		(pts
			(xy 130.094228 -105.029254) (xy 130.081528 -104.838754) (xy 129.979928 -104.838754) (xy 129.967228 -105.029254)
			(xy 129.967228 -105.080054) (xy 130.094228 -105.080054)
		)
		(stroke
			(width 0)
			(type solid)
		)
		(fill yes)
		(layer "F.Cu")
		(net "M_L_DQ<55>")
	)
	(gr_poly
		(pts
			(xy 130.094228 -104.635554) (xy 130.081528 -104.445054) (xy 129.979928 -104.445054) (xy 129.967228 -104.635554)
			(xy 129.967228 -104.686354) (xy 130.094228 -104.686354)
		)
		(stroke
			(width 0)
			(type solid)
		)
		(fill yes)
		(layer "F.Cu")
		(net "M_L_DQ<50>")
	)
	(gr_poly
		(pts
			(xy 130.094228 -104.241854) (xy 130.081528 -104.051354) (xy 129.979928 -104.051354) (xy 129.967228 -104.241854)
			(xy 129.967228 -104.292654) (xy 130.094228 -104.292654)
		)
		(stroke
			(width 0)
			(type solid)
		)
		(fill yes)
		(layer "F.Cu")
		(net "M_L_DQ<51>")
	)
	(gr_poly
		(pts
			(xy 130.117342 -45.729652) (xy 130.081528 -45.693584) (xy 129.937764 -45.567854) (xy 129.865882 -45.639736)
			(xy 129.991612 -45.7835) (xy 130.02768 -45.819314)
		)
		(stroke
			(width 0)
			(type solid)
		)
		(fill yes)
		(layer "F.Cu")
		(net "M_H_DQS_DN<15>")
	)
	(gr_poly
		(pts
			(xy 130.13563 -47.16653) (xy 130.0099 -47.02302) (xy 129.974086 -46.986952) (xy 129.88417 -47.076868)
			(xy 129.919984 -47.112682) (xy 130.063748 -47.238412)
		)
		(stroke
			(width 0)
			(type solid)
		)
		(fill yes)
		(layer "F.Cu")
		(net "M_H_DQS_DP<6>")
	)
	(gr_poly
		(pts
			(xy 130.144012 -44.373292) (xy 130.018282 -44.229528) (xy 129.982468 -44.19346) (xy 129.892552 -44.283376)
			(xy 129.928366 -44.31919) (xy 130.07213 -44.44492)
		)
		(stroke
			(width 0)
			(type solid)
		)
		(fill yes)
		(layer "F.Cu")
		(net "M_H_DQ<48>")
	)
	(gr_poly
		(pts
			(xy 130.19913 -108.77169) (xy 130.234944 -108.735622) (xy 130.145282 -108.64596) (xy 130.109214 -108.681774)
			(xy 129.983484 -108.825538) (xy 130.055366 -108.89742)
		)
		(stroke
			(width 0)
			(type solid)
		)
		(fill yes)
		(layer "F.Cu")
		(net "M_L_DQ<53>")
	)
	(gr_poly
		(pts
			(xy 130.207512 -46.753526) (xy 130.171444 -46.717712) (xy 130.027934 -46.591982) (xy 129.956052 -46.663864)
			(xy 130.081782 -46.807374) (xy 130.117596 -46.843442)
		)
		(stroke
			(width 0)
			(type solid)
		)
		(fill yes)
		(layer "F.Cu")
		(net "M_H_DQS_DP<6>")
	)
	(gr_poly
		(pts
			(xy 130.215894 -43.960034) (xy 130.179826 -43.92422) (xy 130.036316 -43.79849) (xy 129.964434 -43.870372)
			(xy 130.090164 -44.013882) (xy 130.125978 -44.04995)
		)
		(stroke
			(width 0)
			(type solid)
		)
		(fill yes)
		(layer "F.Cu")
		(net "M_H_DQ<48>")
	)
	(gr_poly
		(pts
			(xy 130.2258 -109.211872) (xy 130.35153 -109.068108) (xy 130.279902 -108.996226) (xy 130.136138 -109.121956)
			(xy 130.10007 -109.15777) (xy 130.189986 -109.247686)
		)
		(stroke
			(width 0)
			(type solid)
		)
		(fill yes)
		(layer "F.Cu")
		(net "M_L_DQ<52>")
	)
	(gr_poly
		(pts
			(xy 130.233928 -45.397166) (xy 130.108452 -45.253402) (xy 130.072384 -45.217588) (xy 129.982722 -45.30725)
			(xy 130.018536 -45.343318) (xy 130.1623 -45.469048)
		)
		(stroke
			(width 0)
			(type solid)
		)
		(fill yes)
		(layer "F.Cu")
		(net "M_H_DQS_DP<15>")
	)
	(gr_poly
		(pts
			(xy 130.289046 -107.747562) (xy 130.325114 -107.711748) (xy 130.235198 -107.621832) (xy 130.199384 -107.6579)
			(xy 130.073654 -107.80141) (xy 130.145536 -107.873292)
		)
		(stroke
			(width 0)
			(type solid)
		)
		(fill yes)
		(layer "F.Cu")
		(net "M_L_DQ<49>")
	)
	(gr_poly
		(pts
			(xy 130.297428 -47.777654) (xy 130.261614 -47.741586) (xy 130.11785 -47.615856) (xy 130.045968 -47.687738)
			(xy 130.171698 -47.831502) (xy 130.207766 -47.867316)
		)
		(stroke
			(width 0)
			(type solid)
		)
		(fill yes)
		(layer "F.Cu")
		(net "M_H_DQ<55>")
	)
	(gr_poly
		(pts
			(xy 130.30581 -44.984162) (xy 130.269996 -44.948094) (xy 130.126232 -44.822364) (xy 130.05435 -44.894246)
			(xy 130.18008 -45.03801) (xy 130.216148 -45.073824)
		)
		(stroke
			(width 0)
			(type solid)
		)
		(fill yes)
		(layer "F.Cu")
		(net "M_H_DQS_DP<15>")
	)
	(gr_poly
		(pts
			(xy 130.31597 -108.187744) (xy 130.4417 -108.04398) (xy 130.369818 -107.972352) (xy 130.226054 -108.098082)
			(xy 130.19024 -108.133896) (xy 130.280156 -108.223812)
		)
		(stroke
			(width 0)
			(type solid)
		)
		(fill yes)
		(layer "F.Cu")
		(net "M_L_DQ<48>")
	)
	(gr_poly
		(pts
			(xy 130.324098 -46.421294) (xy 130.198368 -46.27753) (xy 130.162554 -46.241462) (xy 130.072638 -46.331378)
			(xy 130.108452 -46.367192) (xy 130.252216 -46.492922)
		)
		(stroke
			(width 0)
			(type solid)
		)
		(fill yes)
		(layer "F.Cu")
		(net "M_H_DQS_DN<6>")
	)
	(gr_poly
		(pts
			(xy 130.33248 -43.627802) (xy 130.20675 -43.484038) (xy 130.170936 -43.44797) (xy 130.08102 -43.537886)
			(xy 130.116834 -43.5737) (xy 130.260598 -43.69943)
		)
		(stroke
			(width 0)
			(type solid)
		)
		(fill yes)
		(layer "F.Cu")
		(net "M_H_DQ<53>")
	)
	(gr_poly
		(pts
			(xy 130.387598 -109.51718) (xy 130.423412 -109.481112) (xy 130.33375 -109.39145) (xy 130.297682 -109.427264)
			(xy 130.171952 -109.571028) (xy 130.243834 -109.64291)
		)
		(stroke
			(width 0)
			(type solid)
		)
		(fill yes)
		(layer "F.Cu")
		(net "M_L_DQ<52>")
	)
	(gr_poly
		(pts
			(xy 130.39598 -46.008036) (xy 130.359912 -45.972222) (xy 130.216402 -45.846492) (xy 130.14452 -45.918374)
			(xy 130.27025 -46.061884) (xy 130.306064 -46.097952)
		)
		(stroke
			(width 0)
			(type solid)
		)
		(fill yes)
		(layer "F.Cu")
		(net "M_H_DQS_DN<6>")
	)
	(gr_poly
		(pts
			(xy 130.405886 -107.16387) (xy 130.531616 -107.020106) (xy 130.459988 -106.948224) (xy 130.316224 -107.073954)
			(xy 130.28041 -107.110022) (xy 130.370072 -107.199684)
		)
		(stroke
			(width 0)
			(type solid)
		)
		(fill yes)
		(layer "F.Cu")
		(net "M_L_DQS_DP<15>")
	)
	(gr_poly
		(pts
			(xy 130.414268 -47.445168) (xy 130.288538 -47.301404) (xy 130.25247 -47.26559) (xy 130.162808 -47.355252)
			(xy 130.198622 -47.39132) (xy 130.342386 -47.51705)
		)
		(stroke
			(width 0)
			(type solid)
		)
		(fill yes)
		(layer "F.Cu")
		(net "M_H_DQ<54>")
	)
	(gr_poly
		(pts
			(xy 130.422396 -44.651676) (xy 130.296666 -44.507912) (xy 130.260852 -44.472098) (xy 130.17119 -44.56176)
			(xy 130.207004 -44.597828) (xy 130.350768 -44.723558)
		)
		(stroke
			(width 0)
			(type solid)
		)
		(fill yes)
		(layer "F.Cu")
		(net "M_H_DQ<49>")
	)
	(gr_poly
		(pts
			(xy 130.424428 -106.311954) (xy 130.424428 -106.261154) (xy 130.297428 -106.261154) (xy 130.297428 -106.311954)
			(xy 130.310128 -106.502454) (xy 130.411728 -106.502454)
		)
		(stroke
			(width 0)
			(type solid)
		)
		(fill yes)
		(layer "F.Cu")
		(net "M_L_DQS_DN<6>")
	)
	(gr_poly
		(pts
			(xy 130.424428 -105.918254) (xy 130.424428 -105.867454) (xy 130.297428 -105.867454) (xy 130.297428 -105.918254)
			(xy 130.310128 -106.108754) (xy 130.411728 -106.108754)
		)
		(stroke
			(width 0)
			(type solid)
		)
		(fill yes)
		(layer "F.Cu")
		(net "M_L_DQS_DP<6>")
	)
	(gr_poly
		(pts
			(xy 130.424428 -105.524554) (xy 130.424428 -105.473754) (xy 130.297428 -105.473754) (xy 130.297428 -105.524554)
			(xy 130.310128 -105.715054) (xy 130.411728 -105.715054)
		)
		(stroke
			(width 0)
			(type solid)
		)
		(fill yes)
		(layer "F.Cu")
		(net "M_L_DQ<54>")
	)
	(gr_poly
		(pts
			(xy 130.424428 -105.130854) (xy 130.424428 -105.080054) (xy 130.297428 -105.080054) (xy 130.297428 -105.130854)
			(xy 130.310128 -105.321354) (xy 130.411728 -105.321354)
		)
		(stroke
			(width 0)
			(type solid)
		)
		(fill yes)
		(layer "F.Cu")
		(net "M_L_DQ<55>")
	)
	(gr_poly
		(pts
			(xy 130.424428 -104.737154) (xy 130.424428 -104.686354) (xy 130.297428 -104.686354) (xy 130.297428 -104.737154)
			(xy 130.310128 -104.927654) (xy 130.411728 -104.927654)
		)
		(stroke
			(width 0)
			(type solid)
		)
		(fill yes)
		(layer "F.Cu")
		(net "M_L_DQ<50>")
	)
	(gr_poly
		(pts
			(xy 130.424428 -104.343454) (xy 130.424428 -104.292654) (xy 130.297428 -104.292654) (xy 130.297428 -104.343454)
			(xy 130.310128 -104.533954) (xy 130.411728 -104.533954)
		)
		(stroke
			(width 0)
			(type solid)
		)
		(fill yes)
		(layer "F.Cu")
		(net "M_L_DQ<51>")
	)
	(gr_poly
		(pts
			(xy 130.477514 -108.493052) (xy 130.513582 -108.457238) (xy 130.423666 -108.367322) (xy 130.387852 -108.40339)
			(xy 130.262122 -108.5469) (xy 130.334004 -108.618782)
		)
		(stroke
			(width 0)
			(type solid)
		)
		(fill yes)
		(layer "F.Cu")
		(net "M_L_DQ<48>")
	)
	(gr_poly
		(pts
			(xy 130.485896 -47.032164) (xy 130.450082 -46.996096) (xy 130.306318 -46.870366) (xy 130.234436 -46.942248)
			(xy 130.360166 -47.086012) (xy 130.396234 -47.121826)
		)
		(stroke
			(width 0)
			(type solid)
		)
		(fill yes)
		(layer "F.Cu")
		(net "M_H_DQ<54>")
	)
	(gr_poly
		(pts
			(xy 130.494278 -44.238672) (xy 130.458464 -44.202604) (xy 130.3147 -44.076874) (xy 130.242818 -44.148756)
			(xy 130.368548 -44.29252) (xy 130.404616 -44.328334)
		)
		(stroke
			(width 0)
			(type solid)
		)
		(fill yes)
		(layer "F.Cu")
		(net "M_H_DQ<49>")
	)
	(gr_poly
		(pts
			(xy 130.504438 -108.933234) (xy 130.630168 -108.78947) (xy 130.558286 -108.717842) (xy 130.414522 -108.843572)
			(xy 130.378708 -108.879386) (xy 130.468624 -108.969302)
		)
		(stroke
			(width 0)
			(type solid)
		)
		(fill yes)
		(layer "F.Cu")
		(net "M_L_DQ<53>")
	)
	(gr_poly
		(pts
			(xy 130.512566 -45.675804) (xy 130.386836 -45.53204) (xy 130.351022 -45.495972) (xy 130.261106 -45.585888)
			(xy 130.29692 -45.621702) (xy 130.440684 -45.747432)
		)
		(stroke
			(width 0)
			(type solid)
		)
		(fill yes)
		(layer "F.Cu")
		(net "M_H_DQS_DN<15>")
	)
	(gr_poly
		(pts
			(xy 130.567684 -107.469178) (xy 130.603498 -107.43311) (xy 130.513836 -107.343448) (xy 130.477768 -107.379262)
			(xy 130.352038 -107.523026) (xy 130.42392 -107.594908)
		)
		(stroke
			(width 0)
			(type solid)
		)
		(fill yes)
		(layer "F.Cu")
		(net "M_L_DQS_DP<15>")
	)
	(gr_poly
		(pts
			(xy 130.576066 -48.056038) (xy 130.539998 -48.020224) (xy 130.396488 -47.894494) (xy 130.324606 -47.966376)
			(xy 130.450336 -48.109886) (xy 130.48615 -48.145954)
		)
		(stroke
			(width 0)
			(type solid)
		)
		(fill yes)
		(layer "F.Cu")
		(net "M_H_DQ<50>")
	)
	(gr_poly
		(pts
			(xy 130.584448 -45.262546) (xy 130.54838 -45.226732) (xy 130.40487 -45.101002) (xy 130.332988 -45.172884)
			(xy 130.458718 -45.316394) (xy 130.494532 -45.352462)
		)
		(stroke
			(width 0)
			(type solid)
		)
		(fill yes)
		(layer "F.Cu")
		(net "M_H_DQS_DN<15>")
	)
	(gr_poly
		(pts
			(xy 130.594354 -107.90936) (xy 130.720084 -107.765596) (xy 130.648456 -107.693714) (xy 130.504692 -107.819444)
			(xy 130.468624 -107.855258) (xy 130.55854 -107.945174)
		)
		(stroke
			(width 0)
			(type solid)
		)
		(fill yes)
		(layer "F.Cu")
		(net "M_L_DQ<49>")
	)
	(gr_poly
		(pts
			(xy 130.602736 -46.699678) (xy 130.477006 -46.555914) (xy 130.440938 -46.5201) (xy 130.351276 -46.609762)
			(xy 130.38709 -46.64583) (xy 130.530854 -46.77156)
		)
		(stroke
			(width 0)
			(type solid)
		)
		(fill yes)
		(layer "F.Cu")
		(net "M_H_DQS_DP<6>")
	)
	(gr_poly
		(pts
			(xy 130.610864 -43.906186) (xy 130.485134 -43.762422) (xy 130.44932 -43.726608) (xy 130.359404 -43.816524)
			(xy 130.395472 -43.852338) (xy 130.539236 -43.978068)
		)
		(stroke
			(width 0)
			(type solid)
		)
		(fill yes)
		(layer "F.Cu")
		(net "M_H_DQ<48>")
	)
	(gr_poly
		(pts
			(xy 130.665982 -109.238542) (xy 130.70205 -109.202728) (xy 130.612134 -109.112812) (xy 130.57632 -109.14888)
			(xy 130.45059 -109.29239) (xy 130.522472 -109.364272)
		)
		(stroke
			(width 0)
			(type solid)
		)
		(fill yes)
		(layer "F.Cu")
		(net "M_L_DQ<53>")
	)
	(gr_poly
		(pts
			(xy 130.674364 -46.286674) (xy 130.63855 -46.250606) (xy 130.494786 -46.124876) (xy 130.422904 -46.196758)
			(xy 130.548634 -46.340522) (xy 130.584702 -46.376336)
		)
		(stroke
			(width 0)
			(type solid)
		)
		(fill yes)
		(layer "F.Cu")
		(net "M_H_DQS_DP<6>")
	)
	(gr_poly
		(pts
			(xy 130.682746 -43.493182) (xy 130.646932 -43.457114) (xy 130.503168 -43.331384) (xy 130.431286 -43.403266)
			(xy 130.557016 -43.54703) (xy 130.593084 -43.582844)
		)
		(stroke
			(width 0)
			(type solid)
		)
		(fill yes)
		(layer "F.Cu")
		(net "M_H_DQ<48>")
	)
	(gr_poly
		(pts
			(xy 130.684524 -106.885232) (xy 130.810254 -106.741468) (xy 130.738372 -106.66984) (xy 130.594608 -106.79557)
			(xy 130.558794 -106.831384) (xy 130.64871 -106.9213)
		)
		(stroke
			(width 0)
			(type solid)
		)
		(fill yes)
		(layer "F.Cu")
		(net "M_L_DQS_DN<15>")
	)
	(gr_poly
		(pts
			(xy 130.692652 -47.723552) (xy 130.566922 -47.580042) (xy 130.531108 -47.543974) (xy 130.441192 -47.63389)
			(xy 130.477006 -47.669704) (xy 130.62077 -47.795434)
		)
		(stroke
			(width 0)
			(type solid)
		)
		(fill yes)
		(layer "F.Cu")
		(net "M_H_DQ<55>")
	)
	(gr_poly
		(pts
			(xy 130.692906 -109.678724) (xy 130.818636 -109.53496) (xy 130.746754 -109.463332) (xy 130.60299 -109.589062)
			(xy 130.567176 -109.624876) (xy 130.656838 -109.714538)
		)
		(stroke
			(width 0)
			(type solid)
		)
		(fill yes)
		(layer "F.Cu")
		(net "M_L_DQ<52>")
	)
	(gr_poly
		(pts
			(xy 130.701034 -44.930314) (xy 130.575304 -44.78655) (xy 130.53949 -44.750482) (xy 130.449574 -44.840398)
			(xy 130.485388 -44.876212) (xy 130.629152 -45.001942)
		)
		(stroke
			(width 0)
			(type solid)
		)
		(fill yes)
		(layer "F.Cu")
		(net "M_H_DQS_DP<15>")
	)
	(gr_poly
		(pts
			(xy 130.754628 -105.422954) (xy 130.741928 -105.232454) (xy 130.640328 -105.232454) (xy 130.627628 -105.422954)
			(xy 130.627628 -105.473754) (xy 130.754628 -105.473754)
		)
		(stroke
			(width 0)
			(type solid)
		)
		(fill yes)
		(layer "F.Cu")
		(net "M_L_DQ<54>")
	)
	(gr_poly
		(pts
			(xy 130.754628 -105.029254) (xy 130.741928 -104.838754) (xy 130.640328 -104.838754) (xy 130.627628 -105.029254)
			(xy 130.627628 -105.080054) (xy 130.754628 -105.080054)
		)
		(stroke
			(width 0)
			(type solid)
		)
		(fill yes)
		(layer "F.Cu")
		(net "M_L_DQ<55>")
	)
	(gr_poly
		(pts
			(xy 130.754628 -104.635554) (xy 130.741928 -104.445054) (xy 130.640328 -104.445054) (xy 130.627628 -104.635554)
			(xy 130.627628 -104.686354) (xy 130.754628 -104.686354)
		)
		(stroke
			(width 0)
			(type solid)
		)
		(fill yes)
		(layer "F.Cu")
		(net "M_L_DQ<50>")
	)
	(gr_poly
		(pts
			(xy 130.754628 -104.241854) (xy 130.741928 -104.051354) (xy 130.640328 -104.051354) (xy 130.627628 -104.241854)
			(xy 130.627628 -104.292654) (xy 130.754628 -104.292654)
		)
		(stroke
			(width 0)
			(type solid)
		)
		(fill yes)
		(layer "F.Cu")
		(net "M_L_DQ<51>")
	)
	(gr_poly
		(pts
			(xy 130.756152 -108.214668) (xy 130.791966 -108.1786) (xy 130.702304 -108.088938) (xy 130.666236 -108.124752)
			(xy 130.540506 -108.268516) (xy 130.612388 -108.340398)
		)
		(stroke
			(width 0)
			(type solid)
		)
		(fill yes)
		(layer "F.Cu")
		(net "M_L_DQ<49>")
	)
	(gr_poly
		(pts
			(xy 130.764534 -47.310548) (xy 130.728466 -47.274734) (xy 130.584956 -47.149004) (xy 130.513074 -47.220886)
			(xy 130.638804 -47.364396) (xy 130.674618 -47.400464)
		)
		(stroke
			(width 0)
			(type solid)
		)
		(fill yes)
		(layer "F.Cu")
		(net "M_H_DQ<55>")
	)
	(gr_poly
		(pts
			(xy 130.772916 -44.517056) (xy 130.736848 -44.481242) (xy 130.593338 -44.355512) (xy 130.521456 -44.427394)
			(xy 130.647186 -44.570904) (xy 130.683 -44.606972)
		)
		(stroke
			(width 0)
			(type solid)
		)
		(fill yes)
		(layer "F.Cu")
		(net "M_H_DQS_DP<15>")
	)
	(gr_poly
		(pts
			(xy 130.782822 -108.65485) (xy 130.908552 -108.511086) (xy 130.836924 -108.439204) (xy 130.69316 -108.564934)
			(xy 130.657092 -108.600748) (xy 130.747008 -108.690664)
		)
		(stroke
			(width 0)
			(type solid)
		)
		(fill yes)
		(layer "F.Cu")
		(net "M_L_DQ<48>")
	)
	(gr_poly
		(pts
			(xy 130.782822 -48.74768) (xy 130.657092 -48.603916) (xy 130.621024 -48.568102) (xy 130.531362 -48.657764)
			(xy 130.567176 -48.693832) (xy 130.71094 -48.819562)
		)
		(stroke
			(width 0)
			(type solid)
		)
		(fill yes)
		(layer "F.Cu")
		(net "M_H_DQ<51>")
	)
	(gr_poly
		(pts
			(xy 130.79095 -45.954188) (xy 130.665474 -45.810424) (xy 130.629406 -45.77461) (xy 130.539744 -45.864272)
			(xy 130.575558 -45.90034) (xy 130.719322 -46.02607)
		)
		(stroke
			(width 0)
			(type solid)
		)
		(fill yes)
		(layer "F.Cu")
		(net "M_H_DQS_DN<6>")
	)
	(gr_poly
		(pts
			(xy 130.846068 -107.19054) (xy 130.882136 -107.154726) (xy 130.79222 -107.06481) (xy 130.756406 -107.100878)
			(xy 130.630676 -107.244388) (xy 130.702558 -107.31627)
		)
		(stroke
			(width 0)
			(type solid)
		)
		(fill yes)
		(layer "F.Cu")
		(net "M_L_DQS_DN<15>")
	)
	(gr_poly
		(pts
			(xy 130.85445 -109.984032) (xy 130.890518 -109.948218) (xy 130.800602 -109.858302) (xy 130.764788 -109.89437)
			(xy 130.639058 -110.03788) (xy 130.71094 -110.109762)
		)
		(stroke
			(width 0)
			(type solid)
		)
		(fill yes)
		(layer "F.Cu")
		(net "M_L_DQ<52>")
	)
	(gr_poly
		(pts
			(xy 130.85445 -48.334676) (xy 130.818636 -48.298608) (xy 130.674872 -48.172878) (xy 130.60299 -48.24476)
			(xy 130.72872 -48.388524) (xy 130.764788 -48.424338)
		)
		(stroke
			(width 0)
			(type solid)
		)
		(fill yes)
		(layer "F.Cu")
		(net "M_H_DQ<51>")
	)
	(gr_poly
		(pts
			(xy 130.862832 -45.541184) (xy 130.827018 -45.505116) (xy 130.683254 -45.379386) (xy 130.611372 -45.451268)
			(xy 130.737102 -45.595032) (xy 130.77317 -45.630846)
		)
		(stroke
			(width 0)
			(type solid)
		)
		(fill yes)
		(layer "F.Cu")
		(net "M_H_DQS_DN<6>")
	)
	(gr_poly
		(pts
			(xy 130.872992 -107.630722) (xy 130.998722 -107.486958) (xy 130.92684 -107.41533) (xy 130.783076 -107.54106)
			(xy 130.747262 -107.576874) (xy 130.837178 -107.66679)
		)
		(stroke
			(width 0)
			(type solid)
		)
		(fill yes)
		(layer "F.Cu")
		(net "M_L_DQS_DP<15>")
	)
	(gr_poly
		(pts
			(xy 130.88112 -46.978316) (xy 130.75539 -46.834552) (xy 130.719576 -46.798484) (xy 130.62966 -46.8884)
			(xy 130.665474 -46.924214) (xy 130.809238 -47.049944)
		)
		(stroke
			(width 0)
			(type solid)
		)
		(fill yes)
		(layer "F.Cu")
		(net "M_H_DQ<54>")
	)
	(gr_poly
		(pts
			(xy 130.889502 -44.184824) (xy 130.763772 -44.04106) (xy 130.727958 -44.004992) (xy 130.638042 -44.094908)
			(xy 130.673856 -44.130722) (xy 130.81762 -44.256452)
		)
		(stroke
			(width 0)
			(type solid)
		)
		(fill yes)
		(layer "F.Cu")
		(net "M_H_DQ<49>")
	)
	(gr_poly
		(pts
			(xy 130.936238 -106.166412) (xy 130.972306 -106.130598) (xy 130.88239 -106.040682) (xy 130.846576 -106.07675)
			(xy 130.720846 -106.22026) (xy 130.792728 -106.292142)
		)
		(stroke
			(width 0)
			(type solid)
		)
		(fill yes)
		(layer "F.Cu")
		(net "M_L_DQS_DP<6>")
	)
	(gr_poly
		(pts
			(xy 130.94462 -108.960158) (xy 130.980434 -108.92409) (xy 130.890772 -108.834428) (xy 130.854704 -108.870242)
			(xy 130.728974 -109.014006) (xy 130.800856 -109.085888)
		)
		(stroke
			(width 0)
			(type solid)
		)
		(fill yes)
		(layer "F.Cu")
		(net "M_L_DQ<48>")
	)
	(gr_poly
		(pts
			(xy 130.953002 -46.565058) (xy 130.916934 -46.529244) (xy 130.773424 -46.403514) (xy 130.701542 -46.475396)
			(xy 130.827272 -46.618906) (xy 130.863086 -46.654974)
		)
		(stroke
			(width 0)
			(type solid)
		)
		(fill yes)
		(layer "F.Cu")
		(net "M_H_DQ<54>")
	)
	(gr_poly
		(pts
			(xy 130.961384 -43.771566) (xy 130.925316 -43.735752) (xy 130.781806 -43.610022) (xy 130.709924 -43.681904)
			(xy 130.835654 -43.825414) (xy 130.871468 -43.861482)
		)
		(stroke
			(width 0)
			(type solid)
		)
		(fill yes)
		(layer "F.Cu")
		(net "M_H_DQ<49>")
	)
	(gr_poly
		(pts
			(xy 130.963162 -106.606594) (xy 131.088892 -106.46283) (xy 131.01701 -106.391202) (xy 130.873246 -106.516932)
			(xy 130.837432 -106.552746) (xy 130.927348 -106.642662)
		)
		(stroke
			(width 0)
			(type solid)
		)
		(fill yes)
		(layer "F.Cu")
		(net "M_L_DQS_DN<6>")
	)
	(gr_poly
		(pts
			(xy 130.97129 -109.40034) (xy 131.09702 -109.256576) (xy 131.025392 -109.184694) (xy 130.881628 -109.310424)
			(xy 130.84556 -109.346238) (xy 130.935476 -109.436154)
		)
		(stroke
			(width 0)
			(type solid)
		)
		(fill yes)
		(layer "F.Cu")
		(net "M_L_DQ<53>")
	)
	(gr_poly
		(pts
			(xy 130.97129 -48.00219) (xy 130.84556 -47.858426) (xy 130.809492 -47.822612) (xy 130.71983 -47.912274)
			(xy 130.755644 -47.948342) (xy 130.899408 -48.074072)
		)
		(stroke
			(width 0)
			(type solid)
		)
		(fill yes)
		(layer "F.Cu")
		(net "M_H_DQ<50>")
	)
	(gr_poly
		(pts
			(xy 130.979418 -45.208698) (xy 130.853688 -45.064934) (xy 130.817874 -45.02912) (xy 130.728212 -45.118782)
			(xy 130.764026 -45.15485) (xy 130.90779 -45.28058)
		)
		(stroke
			(width 0)
			(type solid)
		)
		(fill yes)
		(layer "F.Cu")
		(net "M_H_DQS_DN<15>")
	)
	(gr_poly
		(pts
			(xy 131.034536 -107.93603) (xy 131.070604 -107.900216) (xy 130.980688 -107.8103) (xy 130.944874 -107.846368)
			(xy 130.819144 -107.989878) (xy 130.891026 -108.06176)
		)
		(stroke
			(width 0)
			(type solid)
		)
		(fill yes)
		(layer "F.Cu")
		(net "M_L_DQS_DP<15>")
	)
	(gr_poly
		(pts
			(xy 131.042918 -47.589186) (xy 131.007104 -47.553118) (xy 130.86334 -47.427388) (xy 130.791458 -47.49927)
			(xy 130.917188 -47.643034) (xy 130.953256 -47.678848)
		)
		(stroke
			(width 0)
			(type solid)
		)
		(fill yes)
		(layer "F.Cu")
		(net "M_H_DQ<50>")
	)
	(gr_poly
		(pts
			(xy 131.0513 -44.795694) (xy 131.015486 -44.759626) (xy 130.871722 -44.633896) (xy 130.79984 -44.705778)
			(xy 130.92557 -44.849542) (xy 130.961638 -44.885356)
		)
		(stroke
			(width 0)
			(type solid)
		)
		(fill yes)
		(layer "F.Cu")
		(net "M_H_DQS_DN<15>")
	)
	(gr_poly
		(pts
			(xy 131.053332 -105.582466) (xy 131.179062 -105.438702) (xy 131.10718 -105.367074) (xy 130.963416 -105.492804)
			(xy 130.927602 -105.528618) (xy 131.017518 -105.618534)
		)
		(stroke
			(width 0)
			(type solid)
		)
		(fill yes)
		(layer "F.Cu")
		(net "M_L_DQ<54>")
	)
	(gr_poly
		(pts
			(xy 131.06146 -108.376212) (xy 131.18719 -108.232448) (xy 131.115308 -108.16082) (xy 130.971544 -108.28655)
			(xy 130.93573 -108.322364) (xy 131.025646 -108.41228)
		)
		(stroke
			(width 0)
			(type solid)
		)
		(fill yes)
		(layer "F.Cu")
		(net "M_L_DQ<49>")
	)
	(gr_poly
		(pts
			(xy 131.069588 -46.232826) (xy 130.943858 -46.089062) (xy 130.908044 -46.052994) (xy 130.818128 -46.14291)
			(xy 130.853942 -46.178724) (xy 130.997706 -46.304454)
		)
		(stroke
			(width 0)
			(type solid)
		)
		(fill yes)
		(layer "F.Cu")
		(net "M_H_DQS_DP<6>")
	)
	(gr_poly
		(pts
			(xy 131.07797 -43.439334) (xy 130.95224 -43.29557) (xy 130.916426 -43.259502) (xy 130.82651 -43.349418)
			(xy 130.862324 -43.385232) (xy 131.006088 -43.510962)
		)
		(stroke
			(width 0)
			(type solid)
		)
		(fill yes)
		(layer "F.Cu")
		(net "M_H_DQ<48>")
	)
	(gr_poly
		(pts
			(xy 131.084828 -104.737154) (xy 131.084828 -104.686354) (xy 130.957828 -104.686354) (xy 130.957828 -104.737154)
			(xy 130.970528 -104.927654) (xy 131.072128 -104.927654)
		)
		(stroke
			(width 0)
			(type solid)
		)
		(fill yes)
		(layer "F.Cu")
		(net "M_L_DQ<50>")
	)
	(gr_poly
		(pts
			(xy 131.084828 -104.343454) (xy 131.084828 -104.292654) (xy 130.957828 -104.292654) (xy 130.957828 -104.343454)
			(xy 130.970528 -104.533954) (xy 131.072128 -104.533954)
		)
		(stroke
			(width 0)
			(type solid)
		)
		(fill yes)
		(layer "F.Cu")
		(net "M_L_DQ<51>")
	)
	(gr_poly
		(pts
			(xy 131.124706 -106.911902) (xy 131.160774 -106.876088) (xy 131.070858 -106.786172) (xy 131.035044 -106.82224)
			(xy 130.909314 -106.96575) (xy 130.981196 -107.037632)
		)
		(stroke
			(width 0)
			(type solid)
		)
		(fill yes)
		(layer "F.Cu")
		(net "M_L_DQS_DN<6>")
	)
	(gr_poly
		(pts
			(xy 131.133088 -109.705648) (xy 131.168902 -109.66958) (xy 131.07924 -109.579918) (xy 131.043172 -109.615732)
			(xy 130.917442 -109.759496) (xy 130.989324 -109.831378)
		)
		(stroke
			(width 0)
			(type solid)
		)
		(fill yes)
		(layer "F.Cu")
		(net "M_L_DQ<53>")
	)
	(gr_poly
		(pts
			(xy 131.14147 -45.819568) (xy 131.105402 -45.783754) (xy 130.961892 -45.658024) (xy 130.89001 -45.729906)
			(xy 131.01574 -45.873416) (xy 131.051554 -45.909484)
		)
		(stroke
			(width 0)
			(type solid)
		)
		(fill yes)
		(layer "F.Cu")
		(net "M_H_DQS_DP<6>")
	)
	(gr_poly
		(pts
			(xy 131.151376 -107.352338) (xy 131.277106 -107.208574) (xy 131.205478 -107.136692) (xy 131.061714 -107.262422)
			(xy 131.025646 -107.298236) (xy 131.115562 -107.388152)
		)
		(stroke
			(width 0)
			(type solid)
		)
		(fill yes)
		(layer "F.Cu")
		(net "M_L_DQS_DN<15>")
	)
	(gr_poly
		(pts
			(xy 131.159758 -47.2567) (xy 131.034028 -47.112936) (xy 130.99796 -47.077122) (xy 130.908298 -47.166784)
			(xy 130.944112 -47.202852) (xy 131.087876 -47.328582)
		)
		(stroke
			(width 0)
			(type solid)
		)
		(fill yes)
		(layer "F.Cu")
		(net "M_H_DQ<55>")
	)
	(gr_poly
		(pts
			(xy 131.167886 -44.463208) (xy 131.042156 -44.319444) (xy 131.006342 -44.28363) (xy 130.916426 -44.373546)
			(xy 130.952494 -44.40936) (xy 131.096258 -44.53509)
		)
		(stroke
			(width 0)
			(type solid)
		)
		(fill yes)
		(layer "F.Cu")
		(net "M_H_DQS_DP<15>")
	)
	(gr_poly
		(pts
			(xy 131.214876 -105.887774) (xy 131.250944 -105.85196) (xy 131.161028 -105.762044) (xy 131.125214 -105.798112)
			(xy 130.999484 -105.941622) (xy 131.071366 -106.013504)
		)
		(stroke
			(width 0)
			(type solid)
		)
		(fill yes)
		(layer "F.Cu")
		(net "M_L_DQ<54>")
	)
	(gr_poly
		(pts
			(xy 131.223004 -108.68152) (xy 131.259072 -108.645706) (xy 131.169156 -108.55579) (xy 131.133342 -108.591858)
			(xy 131.007612 -108.735368) (xy 131.079494 -108.80725)
		)
		(stroke
			(width 0)
			(type solid)
		)
		(fill yes)
		(layer "F.Cu")
		(net "M_L_DQ<49>")
	)
	(gr_poly
		(pts
			(xy 131.231386 -46.843696) (xy 131.195572 -46.807628) (xy 131.051808 -46.681898) (xy 130.979926 -46.75378)
			(xy 131.105656 -46.897544) (xy 131.141724 -46.933358)
		)
		(stroke
			(width 0)
			(type solid)
		)
		(fill yes)
		(layer "F.Cu")
		(net "M_H_DQ<55>")
	)
	(gr_poly
		(pts
			(xy 131.239768 -44.050204) (xy 131.203954 -44.014136) (xy 131.06019 -43.888406) (xy 130.988308 -43.960288)
			(xy 131.114038 -44.104052) (xy 131.150106 -44.139866)
		)
		(stroke
			(width 0)
			(type solid)
		)
		(fill yes)
		(layer "F.Cu")
		(net "M_H_DQS_DP<15>")
	)
	(gr_poly
		(pts
			(xy 131.241546 -106.32821) (xy 131.367276 -106.184446) (xy 131.295648 -106.112564) (xy 131.151884 -106.238294)
			(xy 131.11607 -106.274362) (xy 131.205732 -106.364024)
		)
		(stroke
			(width 0)
			(type solid)
		)
		(fill yes)
		(layer "F.Cu")
		(net "M_L_DQS_DP<6>")
	)
	(gr_poly
		(pts
			(xy 131.249674 -48.280574) (xy 131.123944 -48.137064) (xy 131.08813 -48.100996) (xy 130.998214 -48.190912)
			(xy 131.034028 -48.226726) (xy 131.177792 -48.352456)
		)
		(stroke
			(width 0)
			(type solid)
		)
		(fill yes)
		(layer "F.Cu")
		(net "M_H_DQ<51>")
	)
	(gr_poly
		(pts
			(xy 131.249928 -109.121702) (xy 131.375658 -108.977938) (xy 131.303776 -108.90631) (xy 131.160012 -109.03204)
			(xy 131.124198 -109.067854) (xy 131.21386 -109.157516)
		)
		(stroke
			(width 0)
			(type solid)
		)
		(fill yes)
		(layer "F.Cu")
		(net "M_L_DQ<48>")
	)
	(gr_poly
		(pts
			(xy 131.258056 -45.487336) (xy 131.132326 -45.343572) (xy 131.096512 -45.307504) (xy 131.006596 -45.39742)
			(xy 131.04241 -45.433234) (xy 131.186174 -45.558964)
		)
		(stroke
			(width 0)
			(type solid)
		)
		(fill yes)
		(layer "F.Cu")
		(net "M_H_DQS_DN<6>")
	)
	(gr_poly
		(pts
			(xy 131.313174 -107.657646) (xy 131.348988 -107.621578) (xy 131.259326 -107.531916) (xy 131.223258 -107.56773)
			(xy 131.097528 -107.711494) (xy 131.16941 -107.783376)
		)
		(stroke
			(width 0)
			(type solid)
		)
		(fill yes)
		(layer "F.Cu")
		(net "M_L_DQS_DN<15>")
	)
	(gr_poly
		(pts
			(xy 131.321556 -47.86757) (xy 131.285488 -47.831756) (xy 131.141978 -47.706026) (xy 131.070096 -47.777908)
			(xy 131.195826 -47.921418) (xy 131.23164 -47.957486)
		)
		(stroke
			(width 0)
			(type solid)
		)
		(fill yes)
		(layer "F.Cu")
		(net "M_H_DQ<51>")
	)
	(gr_poly
		(pts
			(xy 131.329938 -45.074078) (xy 131.29387 -45.038264) (xy 131.15036 -44.912534) (xy 131.078478 -44.984416)
			(xy 131.204208 -45.127926) (xy 131.240022 -45.163994)
		)
		(stroke
			(width 0)
			(type solid)
		)
		(fill yes)
		(layer "F.Cu")
		(net "M_H_DQS_DN<6>")
	)
	(gr_poly
		(pts
			(xy 131.33197 -105.304082) (xy 131.457446 -105.160318) (xy 131.385818 -105.088436) (xy 131.242054 -105.214166)
			(xy 131.20624 -105.250234) (xy 131.295902 -105.339896)
		)
		(stroke
			(width 0)
			(type solid)
		)
		(fill yes)
		(layer "F.Cu")
		(net "M_L_DQ<55>")
	)
	(gr_poly
		(pts
			(xy 131.339844 -108.097828) (xy 131.465574 -107.954064) (xy 131.393946 -107.882182) (xy 131.250182 -108.007912)
			(xy 131.214114 -108.043726) (xy 131.30403 -108.133642)
		)
		(stroke
			(width 0)
			(type solid)
		)
		(fill yes)
		(layer "F.Cu")
		(net "M_L_DQS_DP<15>")
	)
	(gr_poly
		(pts
			(xy 131.347972 -46.51121) (xy 131.222496 -46.367446) (xy 131.186428 -46.331632) (xy 131.096766 -46.421294)
			(xy 131.13258 -46.457362) (xy 131.276344 -46.583092)
		)
		(stroke
			(width 0)
			(type solid)
		)
		(fill yes)
		(layer "F.Cu")
		(net "M_H_DQ<54>")
	)
	(gr_poly
		(pts
			(xy 131.356354 -43.717718) (xy 131.230624 -43.573954) (xy 131.19481 -43.53814) (xy 131.104894 -43.628056)
			(xy 131.140962 -43.66387) (xy 131.284726 -43.7896)
		)
		(stroke
			(width 0)
			(type solid)
		)
		(fill yes)
		(layer "F.Cu")
		(net "M_H_DQ<49>")
	)
	(gr_poly
		(pts
			(xy 131.403344 -106.633518) (xy 131.439158 -106.59745) (xy 131.349496 -106.507788) (xy 131.313428 -106.543602)
			(xy 131.187698 -106.687366) (xy 131.25958 -106.759248)
		)
		(stroke
			(width 0)
			(type solid)
		)
		(fill yes)
		(layer "F.Cu")
		(net "M_L_DQS_DP<6>")
	)
	(gr_poly
		(pts
			(xy 131.411472 -109.42701) (xy 131.44754 -109.391196) (xy 131.357624 -109.30128) (xy 131.32181 -109.337348)
			(xy 131.19608 -109.480858) (xy 131.267962 -109.55274)
		)
		(stroke
			(width 0)
			(type solid)
		)
		(fill yes)
		(layer "F.Cu")
		(net "M_L_DQ<48>")
	)
	(gr_poly
		(pts
			(xy 131.419854 -46.098206) (xy 131.38404 -46.062138) (xy 131.240276 -45.936408) (xy 131.168394 -46.00829)
			(xy 131.294124 -46.152054) (xy 131.330192 -46.187868)
		)
		(stroke
			(width 0)
			(type solid)
		)
		(fill yes)
		(layer "F.Cu")
		(net "M_H_DQ<54>")
	)
	(gr_poly
		(pts
			(xy 131.430014 -107.0737) (xy 131.555744 -106.929936) (xy 131.484116 -106.858054) (xy 131.340352 -106.983784)
			(xy 131.304284 -107.019598) (xy 131.3942 -107.109514)
		)
		(stroke
			(width 0)
			(type solid)
		)
		(fill yes)
		(layer "F.Cu")
		(net "M_L_DQS_DN<6>")
	)
	(gr_poly
		(pts
			(xy 131.438142 -47.535338) (xy 131.312412 -47.391574) (xy 131.276598 -47.355506) (xy 131.186682 -47.445422)
			(xy 131.222496 -47.481236) (xy 131.36626 -47.606966)
		)
		(stroke
			(width 0)
			(type solid)
		)
		(fill yes)
		(layer "F.Cu")
		(net "M_H_DQ<50>")
	)
	(gr_poly
		(pts
			(xy 131.438396 -109.867192) (xy 131.564126 -109.723428) (xy 131.492244 -109.6518) (xy 131.34848 -109.777276)
			(xy 131.312666 -109.813344) (xy 131.402328 -109.903006)
		)
		(stroke
			(width 0)
			(type solid)
		)
		(fill yes)
		(layer "F.Cu")
		(net "M_L_DQ<53>")
	)
	(gr_poly
		(pts
			(xy 131.446524 -44.741846) (xy 131.320794 -44.598082) (xy 131.28498 -44.562014) (xy 131.195064 -44.65193)
			(xy 131.230878 -44.687744) (xy 131.374642 -44.813474)
		)
		(stroke
			(width 0)
			(type solid)
		)
		(fill yes)
		(layer "F.Cu")
		(net "M_H_DQS_DN<15>")
	)
	(gr_poly
		(pts
			(xy 131.493514 -105.60939) (xy 131.529328 -105.573322) (xy 131.439666 -105.48366) (xy 131.403598 -105.519474)
			(xy 131.277868 -105.663238) (xy 131.34975 -105.73512)
		)
		(stroke
			(width 0)
			(type solid)
		)
		(fill yes)
		(layer "F.Cu")
		(net "M_L_DQ<55>")
	)
	(gr_poly
		(pts
			(xy 131.501642 -108.403136) (xy 131.537456 -108.367068) (xy 131.447794 -108.277406) (xy 131.411726 -108.31322)
			(xy 131.285996 -108.456984) (xy 131.357878 -108.528866)
		)
		(stroke
			(width 0)
			(type solid)
		)
		(fill yes)
		(layer "F.Cu")
		(net "M_L_DQS_DP<15>")
	)
	(gr_poly
		(pts
			(xy 131.510024 -47.12208) (xy 131.473956 -47.086266) (xy 131.330446 -46.960536) (xy 131.258564 -47.032418)
			(xy 131.384294 -47.175928) (xy 131.420108 -47.211996)
		)
		(stroke
			(width 0)
			(type solid)
		)
		(fill yes)
		(layer "F.Cu")
		(net "M_H_DQ<50>")
	)
	(gr_poly
		(pts
			(xy 131.518406 -44.328588) (xy 131.482338 -44.292774) (xy 131.338828 -44.167044) (xy 131.266946 -44.238926)
			(xy 131.392676 -44.382436) (xy 131.42849 -44.418504)
		)
		(stroke
			(width 0)
			(type solid)
		)
		(fill yes)
		(layer "F.Cu")
		(net "M_H_DQS_DN<15>")
	)
	(gr_poly
		(pts
			(xy 131.520184 -106.049572) (xy 131.645914 -105.905808) (xy 131.574286 -105.833926) (xy 131.430522 -105.959656)
			(xy 131.394708 -105.995724) (xy 131.48437 -106.085386)
		)
		(stroke
			(width 0)
			(type solid)
		)
		(fill yes)
		(layer "F.Cu")
		(net "M_L_DQ<54>")
	)
	(gr_poly
		(pts
			(xy 131.528312 -108.843318) (xy 131.654042 -108.699554) (xy 131.582414 -108.627672) (xy 131.43865 -108.753402)
			(xy 131.402582 -108.789216) (xy 131.492498 -108.879132)
		)
		(stroke
			(width 0)
			(type solid)
		)
		(fill yes)
		(layer "F.Cu")
		(net "M_L_DQ<49>")
	)
	(gr_poly
		(pts
			(xy 131.53644 -45.76572) (xy 131.41071 -45.621956) (xy 131.374896 -45.586142) (xy 131.285234 -45.675804)
			(xy 131.321048 -45.711872) (xy 131.464812 -45.837602)
		)
		(stroke
			(width 0)
			(type solid)
		)
		(fill yes)
		(layer "F.Cu")
		(net "M_H_DQS_DP<6>")
	)
	(gr_poly
		(pts
			(xy 131.58343 -104.585262) (xy 131.619498 -104.549448) (xy 131.529582 -104.459532) (xy 131.493768 -104.4956)
			(xy 131.368038 -104.63911) (xy 131.43992 -104.710992)
		)
		(stroke
			(width 0)
			(type solid)
		)
		(fill yes)
		(layer "F.Cu")
		(net "M_L_DQ<51>")
	)
	(gr_poly
		(pts
			(xy 131.591812 -107.379008) (xy 131.627626 -107.34294) (xy 131.537964 -107.253278) (xy 131.501896 -107.289092)
			(xy 131.376166 -107.432856) (xy 131.448048 -107.504738)
		)
		(stroke
			(width 0)
			(type solid)
		)
		(fill yes)
		(layer "F.Cu")
		(net "M_L_DQS_DN<6>")
	)
	(gr_poly
		(pts
			(xy 131.608322 -45.352716) (xy 131.572508 -45.316648) (xy 131.428744 -45.190918) (xy 131.356862 -45.2628)
			(xy 131.482592 -45.406564) (xy 131.51866 -45.442378)
		)
		(stroke
			(width 0)
			(type solid)
		)
		(fill yes)
		(layer "F.Cu")
		(net "M_H_DQS_DP<6>")
	)
	(gr_poly
		(pts
			(xy 131.610354 -105.025444) (xy 131.736084 -104.88168) (xy 131.664202 -104.810052) (xy 131.520438 -104.935782)
			(xy 131.484624 -104.971596) (xy 131.57454 -105.061512)
		)
		(stroke
			(width 0)
			(type solid)
		)
		(fill yes)
		(layer "F.Cu")
		(net "M_L_DQ<50>")
	)
	(gr_poly
		(pts
			(xy 131.618482 -107.81919) (xy 131.744212 -107.675426) (xy 131.67233 -107.603798) (xy 131.528566 -107.729528)
			(xy 131.492752 -107.765342) (xy 131.582668 -107.855258)
		)
		(stroke
			(width 0)
			(type solid)
		)
		(fill yes)
		(layer "F.Cu")
		(net "M_L_DQS_DN<15>")
	)
	(gr_poly
		(pts
			(xy 131.62661 -46.789848) (xy 131.50088 -46.646084) (xy 131.465066 -46.610016) (xy 131.37515 -46.699932)
			(xy 131.410964 -46.735746) (xy 131.554728 -46.861476)
		)
		(stroke
			(width 0)
			(type solid)
		)
		(fill yes)
		(layer "F.Cu")
		(net "M_H_DQ<55>")
	)
	(gr_poly
		(pts
			(xy 131.634992 -43.996356) (xy 131.509262 -43.852592) (xy 131.473448 -43.816524) (xy 131.383532 -43.90644)
			(xy 131.419346 -43.942254) (xy 131.56311 -44.067984)
		)
		(stroke
			(width 0)
			(type solid)
		)
		(fill yes)
		(layer "F.Cu")
		(net "M_H_DQS_DP<15>")
	)
	(gr_poly
		(pts
			(xy 131.681982 -106.35488) (xy 131.717796 -106.318812) (xy 131.628134 -106.22915) (xy 131.592066 -106.264964)
			(xy 131.466336 -106.408728) (xy 131.538218 -106.48061)
		)
		(stroke
			(width 0)
			(type solid)
		)
		(fill yes)
		(layer "F.Cu")
		(net "M_L_DQ<54>")
	)
	(gr_poly
		(pts
			(xy 131.69011 -109.148626) (xy 131.725924 -109.112558) (xy 131.636262 -109.022896) (xy 131.600194 -109.05871)
			(xy 131.474464 -109.202474) (xy 131.546346 -109.274356)
		)
		(stroke
			(width 0)
			(type solid)
		)
		(fill yes)
		(layer "F.Cu")
		(net "M_L_DQ<49>")
	)
	(gr_poly
		(pts
			(xy 131.698492 -46.37659) (xy 131.662424 -46.340776) (xy 131.518914 -46.215046) (xy 131.447032 -46.286928)
			(xy 131.572762 -46.430438) (xy 131.608576 -46.466506)
		)
		(stroke
			(width 0)
			(type solid)
		)
		(fill yes)
		(layer "F.Cu")
		(net "M_H_DQ<55>")
	)
	(gr_poly
		(pts
			(xy 131.706874 -43.583098) (xy 131.670806 -43.547284) (xy 131.527296 -43.421554) (xy 131.455414 -43.493436)
			(xy 131.581144 -43.636946) (xy 131.616958 -43.673014)
		)
		(stroke
			(width 0)
			(type solid)
		)
		(fill yes)
		(layer "F.Cu")
		(net "M_H_DQS_DP<15>")
	)
	(gr_poly
		(pts
			(xy 131.708652 -106.795062) (xy 131.834382 -106.651298) (xy 131.7625 -106.57967) (xy 131.618736 -106.7054)
			(xy 131.582922 -106.741214) (xy 131.672838 -106.83113)
		)
		(stroke
			(width 0)
			(type solid)
		)
		(fill yes)
		(layer "F.Cu")
		(net "M_L_DQS_DP<6>")
	)
	(gr_poly
		(pts
			(xy 131.71678 -109.588808) (xy 131.84251 -109.445044) (xy 131.770882 -109.373162) (xy 131.627118 -109.498892)
			(xy 131.59105 -109.534706) (xy 131.680966 -109.624622)
		)
		(stroke
			(width 0)
			(type solid)
		)
		(fill yes)
		(layer "F.Cu")
		(net "M_L_DQ<48>")
	)
	(gr_poly
		(pts
			(xy 131.71678 -47.813722) (xy 131.59105 -47.669958) (xy 131.554982 -47.634144) (xy 131.46532 -47.723806)
			(xy 131.501134 -47.759874) (xy 131.644898 -47.885604)
		)
		(stroke
			(width 0)
			(type solid)
		)
		(fill yes)
		(layer "F.Cu")
		(net "M_H_DQ<51>")
	)
	(gr_poly
		(pts
			(xy 131.724908 -45.02023) (xy 131.599178 -44.876466) (xy 131.563364 -44.840652) (xy 131.473448 -44.930568)
			(xy 131.509516 -44.966382) (xy 131.65328 -45.092112)
		)
		(stroke
			(width 0)
			(type solid)
		)
		(fill yes)
		(layer "F.Cu")
		(net "M_H_DQS_DN<6>")
	)
	(gr_poly
		(pts
			(xy 131.771898 -105.330752) (xy 131.807966 -105.294938) (xy 131.71805 -105.205022) (xy 131.682236 -105.24109)
			(xy 131.556506 -105.3846) (xy 131.628388 -105.456482)
		)
		(stroke
			(width 0)
			(type solid)
		)
		(fill yes)
		(layer "F.Cu")
		(net "M_L_DQ<50>")
	)
	(gr_poly
		(pts
			(xy 131.780026 -108.124498) (xy 131.816094 -108.088684) (xy 131.726178 -107.998768) (xy 131.690364 -108.034836)
			(xy 131.564634 -108.178346) (xy 131.636516 -108.250228)
		)
		(stroke
			(width 0)
			(type solid)
		)
		(fill yes)
		(layer "F.Cu")
		(net "M_L_DQS_DN<15>")
	)
	(gr_poly
		(pts
			(xy 131.788408 -47.400718) (xy 131.752594 -47.36465) (xy 131.60883 -47.23892) (xy 131.536948 -47.310802)
			(xy 131.662678 -47.454566) (xy 131.698746 -47.49038)
		)
		(stroke
			(width 0)
			(type solid)
		)
		(fill yes)
		(layer "F.Cu")
		(net "M_H_DQ<51>")
	)
	(gr_poly
		(pts
			(xy 131.79679 -44.607226) (xy 131.760976 -44.571158) (xy 131.617212 -44.445428) (xy 131.54533 -44.51731)
			(xy 131.67106 -44.661074) (xy 131.707128 -44.696888)
		)
		(stroke
			(width 0)
			(type solid)
		)
		(fill yes)
		(layer "F.Cu")
		(net "M_H_DQS_DN<6>")
	)
	(gr_poly
		(pts
			(xy 131.798822 -105.770934) (xy 131.924552 -105.62717) (xy 131.85267 -105.555542) (xy 131.708906 -105.681272)
			(xy 131.673092 -105.717086) (xy 131.763008 -105.807002)
		)
		(stroke
			(width 0)
			(type solid)
		)
		(fill yes)
		(layer "F.Cu")
		(net "M_L_DQ<55>")
	)
	(gr_poly
		(pts
			(xy 131.80695 -108.56468) (xy 131.93268 -108.420916) (xy 131.860798 -108.349288) (xy 131.717034 -108.475018)
			(xy 131.68122 -108.510832) (xy 131.770882 -108.600494)
		)
		(stroke
			(width 0)
			(type solid)
		)
		(fill yes)
		(layer "F.Cu")
		(net "M_L_DQS_DP<15>")
	)
	(gr_poly
		(pts
			(xy 131.815078 -46.044358) (xy 131.689348 -45.900594) (xy 131.653534 -45.864526) (xy 131.563618 -45.954442)
			(xy 131.599432 -45.990256) (xy 131.743196 -46.115986)
		)
		(stroke
			(width 0)
			(type solid)
		)
		(fill yes)
		(layer "F.Cu")
		(net "M_H_DQ<54>")
	)
	(gr_poly
		(pts
			(xy 131.82346 -43.250866) (xy 131.69773 -43.107102) (xy 131.661662 -43.071288) (xy 131.572 -43.16095)
			(xy 131.607814 -43.196764) (xy 131.751578 -43.322494)
		)
		(stroke
			(width 0)
			(type solid)
		)
		(fill yes)
		(layer "F.Cu")
		(net "M_H_DQ<49>")
	)
	(gr_poly
		(pts
			(xy 131.870196 -107.10037) (xy 131.906264 -107.064556) (xy 131.816348 -106.97464) (xy 131.780534 -107.010708)
			(xy 131.654804 -107.154218) (xy 131.726686 -107.2261)
		)
		(stroke
			(width 0)
			(type solid)
		)
		(fill yes)
		(layer "F.Cu")
		(net "M_L_DQS_DP<6>")
	)
	(gr_poly
		(pts
			(xy 131.878578 -109.894116) (xy 131.914392 -109.858048) (xy 131.82473 -109.768386) (xy 131.788662 -109.8042)
			(xy 131.662932 -109.947964) (xy 131.734814 -110.019846)
		)
		(stroke
			(width 0)
			(type solid)
		)
		(fill yes)
		(layer "F.Cu")
		(net "M_L_DQ<48>")
	)
	(gr_poly
		(pts
			(xy 131.88696 -45.6311) (xy 131.850892 -45.595286) (xy 131.707382 -45.469556) (xy 131.6355 -45.541438)
			(xy 131.76123 -45.684948) (xy 131.797044 -45.721016)
		)
		(stroke
			(width 0)
			(type solid)
		)
		(fill yes)
		(layer "F.Cu")
		(net "M_H_DQ<54>")
	)
	(gr_poly
		(pts
			(xy 131.888992 -104.74706) (xy 132.014468 -104.603296) (xy 131.94284 -104.531414) (xy 131.799076 -104.657144)
			(xy 131.763262 -104.693212) (xy 131.852924 -104.782874)
		)
		(stroke
			(width 0)
			(type solid)
		)
		(fill yes)
		(layer "F.Cu")
		(net "M_L_DQ<51>")
	)
	(gr_poly
		(pts
			(xy 131.89712 -107.540552) (xy 132.02285 -107.396788) (xy 131.950968 -107.32516) (xy 131.807204 -107.45089)
			(xy 131.77139 -107.486704) (xy 131.861306 -107.57662)
		)
		(stroke
			(width 0)
			(type solid)
		)
		(fill yes)
		(layer "F.Cu")
		(net "M_L_DQS_DN<6>")
	)
	(gr_poly
		(pts
			(xy 131.904994 -47.068232) (xy 131.779518 -46.924468) (xy 131.74345 -46.888654) (xy 131.653788 -46.978316)
			(xy 131.689602 -47.014384) (xy 131.833366 -47.140114)
		)
		(stroke
			(width 0)
			(type solid)
		)
		(fill yes)
		(layer "F.Cu")
		(net "M_H_DQ<50>")
	)
	(gr_poly
		(pts
			(xy 131.913376 -44.27474) (xy 131.787646 -44.130976) (xy 131.751832 -44.095162) (xy 131.661916 -44.185078)
			(xy 131.697984 -44.220892) (xy 131.841748 -44.346622)
		)
		(stroke
			(width 0)
			(type solid)
		)
		(fill yes)
		(layer "F.Cu")
		(net "M_H_DQS_DN<15>")
	)
	(gr_poly
		(pts
			(xy 131.960366 -106.076242) (xy 131.996434 -106.040428) (xy 131.906518 -105.950512) (xy 131.870704 -105.98658)
			(xy 131.744974 -106.13009) (xy 131.816856 -106.201972)
		)
		(stroke
			(width 0)
			(type solid)
		)
		(fill yes)
		(layer "F.Cu")
		(net "M_L_DQ<55>")
	)
	(gr_poly
		(pts
			(xy 131.968494 -108.869988) (xy 132.004562 -108.834174) (xy 131.914646 -108.744258) (xy 131.878832 -108.780326)
			(xy 131.753102 -108.923836) (xy 131.824984 -108.995718)
		)
		(stroke
			(width 0)
			(type solid)
		)
		(fill yes)
		(layer "F.Cu")
		(net "M_L_DQS_DP<15>")
	)
	(gr_poly
		(pts
			(xy 131.976876 -46.655228) (xy 131.941062 -46.61916) (xy 131.797298 -46.49343) (xy 131.725416 -46.565312)
			(xy 131.851146 -46.709076) (xy 131.887214 -46.74489)
		)
		(stroke
			(width 0)
			(type solid)
		)
		(fill yes)
		(layer "F.Cu")
		(net "M_H_DQ<50>")
	)
	(gr_poly
		(pts
			(xy 131.985258 -43.861736) (xy 131.949444 -43.825668) (xy 131.80568 -43.699938) (xy 131.733798 -43.77182)
			(xy 131.859528 -43.915584) (xy 131.895596 -43.951398)
		)
		(stroke
			(width 0)
			(type solid)
		)
		(fill yes)
		(layer "F.Cu")
		(net "M_H_DQS_DN<15>")
	)
	(gr_poly
		(pts
			(xy 131.98729 -106.516424) (xy 132.11302 -106.37266) (xy 132.041138 -106.301032) (xy 131.897374 -106.426762)
			(xy 131.86156 -106.462576) (xy 131.951476 -106.552492)
		)
		(stroke
			(width 0)
			(type solid)
		)
		(fill yes)
		(layer "F.Cu")
		(net "M_L_DQ<54>")
	)
	(gr_poly
		(pts
			(xy 131.995418 -109.31017) (xy 132.121148 -109.166406) (xy 132.049266 -109.094778) (xy 131.905502 -109.220254)
			(xy 131.869688 -109.256322) (xy 131.95935 -109.345984)
		)
		(stroke
			(width 0)
			(type solid)
		)
		(fill yes)
		(layer "F.Cu")
		(net "M_L_DQ<49>")
	)
	(gr_poly
		(pts
			(xy 132.003546 -45.298868) (xy 131.877816 -45.155104) (xy 131.842002 -45.119036) (xy 131.752086 -45.208952)
			(xy 131.7879 -45.244766) (xy 131.931664 -45.370496)
		)
		(stroke
			(width 0)
			(type solid)
		)
		(fill yes)
		(layer "F.Cu")
		(net "M_H_DQS_DP<6>")
	)
	(gr_poly
		(pts
			(xy 132.050536 -105.052368) (xy 132.08635 -105.0163) (xy 131.996688 -104.926638) (xy 131.96062 -104.962452)
			(xy 131.83489 -105.106216) (xy 131.906772 -105.178098)
		)
		(stroke
			(width 0)
			(type solid)
		)
		(fill yes)
		(layer "F.Cu")
		(net "M_L_DQ<51>")
	)
	(gr_poly
		(pts
			(xy 132.058664 -107.84586) (xy 132.094732 -107.810046) (xy 132.004816 -107.72013) (xy 131.969002 -107.756198)
			(xy 131.843272 -107.899708) (xy 131.915154 -107.97159)
		)
		(stroke
			(width 0)
			(type solid)
		)
		(fill yes)
		(layer "F.Cu")
		(net "M_L_DQS_DN<6>")
	)
	(gr_poly
		(pts
			(xy 132.075428 -44.88561) (xy 132.03936 -44.849796) (xy 131.89585 -44.724066) (xy 131.823968 -44.795948)
			(xy 131.949698 -44.939458) (xy 131.985512 -44.975526)
		)
		(stroke
			(width 0)
			(type solid)
		)
		(fill yes)
		(layer "F.Cu")
		(net "M_H_DQS_DP<6>")
	)
	(gr_poly
		(pts
			(xy 132.077206 -105.49255) (xy 132.202936 -105.348786) (xy 132.131308 -105.276904) (xy 131.987544 -105.402634)
			(xy 131.95173 -105.438702) (xy 132.041392 -105.528364)
		)
		(stroke
			(width 0)
			(type solid)
		)
		(fill yes)
		(layer "F.Cu")
		(net "M_L_DQ<50>")
	)
	(gr_poly
		(pts
			(xy 132.085334 -108.286296) (xy 132.211064 -108.142532) (xy 132.139436 -108.07065) (xy 131.995672 -108.19638)
			(xy 131.959604 -108.232194) (xy 132.04952 -108.32211)
		)
		(stroke
			(width 0)
			(type solid)
		)
		(fill yes)
		(layer "F.Cu")
		(net "M_L_DQS_DN<15>")
	)
	(gr_poly
		(pts
			(xy 132.093462 -46.322742) (xy 131.967732 -46.178978) (xy 131.931918 -46.143164) (xy 131.842256 -46.232826)
			(xy 131.87807 -46.268894) (xy 132.021834 -46.394624)
		)
		(stroke
			(width 0)
			(type solid)
		)
		(fill yes)
		(layer "F.Cu")
		(net "M_H_DQ<55>")
	)
	(gr_poly
		(pts
			(xy 132.101844 -43.52925) (xy 131.976114 -43.385486) (xy 131.9403 -43.349672) (xy 131.850384 -43.439588)
			(xy 131.886452 -43.475402) (xy 132.030216 -43.601132)
		)
		(stroke
			(width 0)
			(type solid)
		)
		(fill yes)
		(layer "F.Cu")
		(net "M_H_DQS_DP<15>")
	)
	(gr_poly
		(pts
			(xy 132.148834 -106.821732) (xy 132.184902 -106.785918) (xy 132.094986 -106.696002) (xy 132.059172 -106.73207)
			(xy 131.933442 -106.87558) (xy 132.005324 -106.947462)
		)
		(stroke
			(width 0)
			(type solid)
		)
		(fill yes)
		(layer "F.Cu")
		(net "M_L_DQ<54>")
	)
	(gr_poly
		(pts
			(xy 132.156962 -109.615478) (xy 132.19303 -109.579664) (xy 132.103114 -109.489748) (xy 132.0673 -109.525816)
			(xy 131.94157 -109.669326) (xy 132.013452 -109.741208)
		)
		(stroke
			(width 0)
			(type solid)
		)
		(fill yes)
		(layer "F.Cu")
		(net "M_L_DQ<49>")
	)
	(gr_poly
		(pts
			(xy 132.165344 -45.909738) (xy 132.12953 -45.87367) (xy 131.985766 -45.74794) (xy 131.913884 -45.819822)
			(xy 132.039614 -45.963586) (xy 132.075682 -45.9994)
		)
		(stroke
			(width 0)
			(type solid)
		)
		(fill yes)
		(layer "F.Cu")
		(net "M_H_DQ<55>")
	)
	(gr_poly
		(pts
			(xy 132.17398 -43.116246) (xy 132.137912 -43.080432) (xy 131.994402 -42.954702) (xy 131.92252 -43.026584)
			(xy 132.04825 -43.170094) (xy 132.084064 -43.206162)
		)
		(stroke
			(width 0)
			(type solid)
		)
		(fill yes)
		(layer "F.Cu")
		(net "M_H_DQS_DP<15>")
	)
	(gr_poly
		(pts
			(xy 132.175504 -107.262168) (xy 132.301234 -107.118404) (xy 132.229606 -107.046522) (xy 132.085842 -107.172252)
			(xy 132.049774 -107.208066) (xy 132.13969 -107.297982)
		)
		(stroke
			(width 0)
			(type solid)
		)
		(fill yes)
		(layer "F.Cu")
		(net "M_L_DQS_DP<6>")
	)
	(gr_poly
		(pts
			(xy 132.183632 -47.34687) (xy 132.057902 -47.203106) (xy 132.022088 -47.167038) (xy 131.932172 -47.256954)
			(xy 131.967986 -47.292768) (xy 132.11175 -47.418498)
		)
		(stroke
			(width 0)
			(type solid)
		)
		(fill yes)
		(layer "F.Cu")
		(net "M_H_DQ<51>")
	)
	(gr_poly
		(pts
			(xy 132.192014 -44.553378) (xy 132.066284 -44.409614) (xy 132.03047 -44.373546) (xy 131.940554 -44.463462)
			(xy 131.976368 -44.499276) (xy 132.120132 -44.625006)
		)
		(stroke
			(width 0)
			(type solid)
		)
		(fill yes)
		(layer "F.Cu")
		(net "M_H_DQS_DN<6>")
	)
	(gr_poly
		(pts
			(xy 132.239004 -105.797858) (xy 132.274818 -105.76179) (xy 132.185156 -105.672128) (xy 132.149088 -105.707942)
			(xy 132.023358 -105.851706) (xy 132.09524 -105.923588)
		)
		(stroke
			(width 0)
			(type solid)
		)
		(fill yes)
		(layer "F.Cu")
		(net "M_L_DQ<50>")
	)
	(gr_poly
		(pts
			(xy 132.247132 -108.591604) (xy 132.282946 -108.555536) (xy 132.193284 -108.465874) (xy 132.157216 -108.501688)
			(xy 132.031486 -108.645452) (xy 132.103368 -108.717334)
		)
		(stroke
			(width 0)
			(type solid)
		)
		(fill yes)
		(layer "F.Cu")
		(net "M_L_DQS_DN<15>")
	)
	(gr_poly
		(pts
			(xy 132.255514 -46.933612) (xy 132.219446 -46.897798) (xy 132.075936 -46.772068) (xy 132.004054 -46.84395)
			(xy 132.129784 -46.98746) (xy 132.165598 -47.023528)
		)
		(stroke
			(width 0)
			(type solid)
		)
		(fill yes)
		(layer "F.Cu")
		(net "M_H_DQ<51>")
	)
	(gr_poly
		(pts
			(xy 132.263896 -44.14012) (xy 132.227828 -44.104306) (xy 132.084318 -43.978576) (xy 132.012436 -44.050458)
			(xy 132.138166 -44.193968) (xy 132.17398 -44.230036)
		)
		(stroke
			(width 0)
			(type solid)
		)
		(fill yes)
		(layer "F.Cu")
		(net "M_H_DQS_DN<6>")
	)
	(gr_poly
		(pts
			(xy 132.265674 -106.23804) (xy 132.391404 -106.094276) (xy 132.319776 -106.022394) (xy 132.176012 -106.148124)
			(xy 132.139944 -106.183938) (xy 132.22986 -106.273854)
		)
		(stroke
			(width 0)
			(type solid)
		)
		(fill yes)
		(layer "F.Cu")
		(net "M_L_DQ<55>")
	)
	(gr_poly
		(pts
			(xy 132.273802 -109.031786) (xy 132.399532 -108.888022) (xy 132.327904 -108.81614) (xy 132.18414 -108.94187)
			(xy 132.148072 -108.977684) (xy 132.237988 -109.0676)
		)
		(stroke
			(width 0)
			(type solid)
		)
		(fill yes)
		(layer "F.Cu")
		(net "M_L_DQS_DP<15>")
	)
	(gr_poly
		(pts
			(xy 132.28193 -45.577252) (xy 132.1562 -45.433488) (xy 132.120386 -45.397674) (xy 132.03047 -45.48759)
			(xy 132.066538 -45.523404) (xy 132.210302 -45.649134)
		)
		(stroke
			(width 0)
			(type solid)
		)
		(fill yes)
		(layer "F.Cu")
		(net "M_H_DQ<54>")
	)
	(gr_poly
		(pts
			(xy 132.337302 -107.567476) (xy 132.373116 -107.531408) (xy 132.283454 -107.441746) (xy 132.247386 -107.47756)
			(xy 132.121656 -107.621324) (xy 132.193538 -107.693206)
		)
		(stroke
			(width 0)
			(type solid)
		)
		(fill yes)
		(layer "F.Cu")
		(net "M_L_DQS_DP<6>")
	)
	(gr_poly
		(pts
			(xy 132.353812 -45.164248) (xy 132.317998 -45.12818) (xy 132.174234 -45.00245) (xy 132.102352 -45.074332)
			(xy 132.228082 -45.218096) (xy 132.26415 -45.25391)
		)
		(stroke
			(width 0)
			(type solid)
		)
		(fill yes)
		(layer "F.Cu")
		(net "M_H_DQ<54>")
	)
	(gr_poly
		(pts
			(xy 132.355844 -105.213912) (xy 132.481574 -105.070148) (xy 132.409692 -104.99852) (xy 132.265928 -105.12425)
			(xy 132.230114 -105.160064) (xy 132.32003 -105.24998)
		)
		(stroke
			(width 0)
			(type solid)
		)
		(fill yes)
		(layer "F.Cu")
		(net "M_L_DQ<51>")
	)
	(gr_poly
		(pts
			(xy 132.363972 -108.007658) (xy 132.489702 -107.863894) (xy 132.418074 -107.792012) (xy 132.27431 -107.917742)
			(xy 132.238242 -107.953556) (xy 132.328158 -108.043472)
		)
		(stroke
			(width 0)
			(type solid)
		)
		(fill yes)
		(layer "F.Cu")
		(net "M_L_DQS_DN<6>")
	)
	(gr_poly
		(pts
			(xy 132.3721 -46.60138) (xy 132.24637 -46.457616) (xy 132.210556 -46.421548) (xy 132.12064 -46.511464)
			(xy 132.156454 -46.547278) (xy 132.300218 -46.673008)
		)
		(stroke
			(width 0)
			(type solid)
		)
		(fill yes)
		(layer "F.Cu")
		(net "M_H_DQ<50>")
	)
	(gr_poly
		(pts
			(xy 132.380482 -43.807888) (xy 132.254752 -43.664124) (xy 132.218684 -43.62831) (xy 132.129022 -43.717972)
			(xy 132.164836 -43.753786) (xy 132.3086 -43.879516)
		)
		(stroke
			(width 0)
			(type solid)
		)
		(fill yes)
		(layer "F.Cu")
		(net "M_H_DQS_DN<15>")
	)
	(gr_poly
		(pts
			(xy 132.427472 -106.543348) (xy 132.463286 -106.50728) (xy 132.373624 -106.417618) (xy 132.337556 -106.453432)
			(xy 132.211826 -106.597196) (xy 132.283708 -106.669078)
		)
		(stroke
			(width 0)
			(type solid)
		)
		(fill yes)
		(layer "F.Cu")
		(net "M_L_DQ<55>")
	)
	(gr_poly
		(pts
			(xy 132.4356 -109.337094) (xy 132.471414 -109.301026) (xy 132.381752 -109.211364) (xy 132.345684 -109.247178)
			(xy 132.219954 -109.390942) (xy 132.291836 -109.462824)
		)
		(stroke
			(width 0)
			(type solid)
		)
		(fill yes)
		(layer "F.Cu")
		(net "M_L_DQS_DP<15>")
	)
	(gr_poly
		(pts
			(xy 132.443982 -46.188122) (xy 132.407914 -46.152308) (xy 132.264404 -46.026578) (xy 132.192522 -46.09846)
			(xy 132.318252 -46.24197) (xy 132.354066 -46.278038)
		)
		(stroke
			(width 0)
			(type solid)
		)
		(fill yes)
		(layer "F.Cu")
		(net "M_H_DQ<50>")
	)
	(gr_poly
		(pts
			(xy 132.452364 -43.39463) (xy 132.416296 -43.358816) (xy 132.272786 -43.233086) (xy 132.200904 -43.304968)
			(xy 132.326634 -43.448478) (xy 132.362448 -43.484546)
		)
		(stroke
			(width 0)
			(type solid)
		)
		(fill yes)
		(layer "F.Cu")
		(net "M_H_DQS_DN<15>")
	)
	(gr_poly
		(pts
			(xy 132.454142 -106.98353) (xy 132.579872 -106.839766) (xy 132.508244 -106.767884) (xy 132.36448 -106.893614)
			(xy 132.328412 -106.929428) (xy 132.418328 -107.019344)
		)
		(stroke
			(width 0)
			(type solid)
		)
		(fill yes)
		(layer "F.Cu")
		(net "M_L_DQ<54>")
	)
	(gr_poly
		(pts
			(xy 132.46227 -109.777276) (xy 132.588 -109.633512) (xy 132.516372 -109.56163) (xy 132.372608 -109.68736)
			(xy 132.33654 -109.723174) (xy 132.426456 -109.81309)
		)
		(stroke
			(width 0)
			(type solid)
		)
		(fill yes)
		(layer "F.Cu")
		(net "M_L_DQ<49>")
	)
	(gr_poly
		(pts
			(xy 132.470398 -44.831762) (xy 132.344668 -44.687998) (xy 132.308854 -44.652184) (xy 132.218938 -44.7421)
			(xy 132.255006 -44.777914) (xy 132.39877 -44.903644)
		)
		(stroke
			(width 0)
			(type solid)
		)
		(fill yes)
		(layer "F.Cu")
		(net "M_H_DQS_DP<6>")
	)
	(gr_poly
		(pts
			(xy 132.517388 -105.51922) (xy 132.553456 -105.483406) (xy 132.46354 -105.39349) (xy 132.427726 -105.429558)
			(xy 132.301996 -105.573068) (xy 132.373878 -105.64495)
		)
		(stroke
			(width 0)
			(type solid)
		)
		(fill yes)
		(layer "F.Cu")
		(net "M_L_DQ<51>")
	)
	(gr_poly
		(pts
			(xy 132.52577 -108.312966) (xy 132.561584 -108.276898) (xy 132.471922 -108.187236) (xy 132.435854 -108.22305)
			(xy 132.310124 -108.366814) (xy 132.382006 -108.438696)
		)
		(stroke
			(width 0)
			(type solid)
		)
		(fill yes)
		(layer "F.Cu")
		(net "M_L_DQS_DN<6>")
	)
	(gr_poly
		(pts
			(xy 132.54228 -44.418758) (xy 132.506466 -44.38269) (xy 132.362702 -44.25696) (xy 132.29082 -44.328842)
			(xy 132.41655 -44.472606) (xy 132.452618 -44.50842)
		)
		(stroke
			(width 0)
			(type solid)
		)
		(fill yes)
		(layer "F.Cu")
		(net "M_H_DQS_DP<6>")
	)
	(gr_poly
		(pts
			(xy 132.544312 -105.959402) (xy 132.670042 -105.815638) (xy 132.59816 -105.74401) (xy 132.454396 -105.86974)
			(xy 132.418582 -105.905554) (xy 132.508498 -105.99547)
		)
		(stroke
			(width 0)
			(type solid)
		)
		(fill yes)
		(layer "F.Cu")
		(net "M_L_DQ<50>")
	)
	(gr_poly
		(pts
			(xy 132.55244 -108.753148) (xy 132.67817 -108.609384) (xy 132.606288 -108.537756) (xy 132.462524 -108.663232)
			(xy 132.42671 -108.6993) (xy 132.516372 -108.788962)
		)
		(stroke
			(width 0)
			(type solid)
		)
		(fill yes)
		(layer "F.Cu")
		(net "M_L_DQS_DN<15>")
	)
	(gr_poly
		(pts
			(xy 132.560568 -45.85589) (xy 132.434838 -45.712126) (xy 132.399024 -45.676058) (xy 132.309108 -45.765974)
			(xy 132.344922 -45.801788) (xy 132.488686 -45.927518)
		)
		(stroke
			(width 0)
			(type solid)
		)
		(fill yes)
		(layer "F.Cu")
		(net "M_H_DQ<55>")
	)
	(gr_poly
		(pts
			(xy 132.61594 -107.288838) (xy 132.651754 -107.25277) (xy 132.562092 -107.163108) (xy 132.526024 -107.198922)
			(xy 132.400294 -107.342686) (xy 132.472176 -107.414568)
		)
		(stroke
			(width 0)
			(type solid)
		)
		(fill yes)
		(layer "F.Cu")
		(net "M_L_DQ<54>")
	)
	(gr_poly
		(pts
			(xy 132.63245 -45.442632) (xy 132.596382 -45.406818) (xy 132.452872 -45.281088) (xy 132.38099 -45.35297)
			(xy 132.50672 -45.49648) (xy 132.542534 -45.532548)
		)
		(stroke
			(width 0)
			(type solid)
		)
		(fill yes)
		(layer "F.Cu")
		(net "M_H_DQ<55>")
	)
	(gr_poly
		(pts
			(xy 132.64261 -107.72902) (xy 132.76834 -107.585256) (xy 132.696458 -107.513628) (xy 132.552694 -107.639358)
			(xy 132.51688 -107.675172) (xy 132.606542 -107.764834)
		)
		(stroke
			(width 0)
			(type solid)
		)
		(fill yes)
		(layer "F.Cu")
		(net "M_L_DQS_DP<6>")
	)
	(gr_poly
		(pts
			(xy 132.650484 -46.879764) (xy 132.524754 -46.736) (xy 132.48894 -46.700186) (xy 132.399278 -46.789848)
			(xy 132.435092 -46.825916) (xy 132.578856 -46.951646)
		)
		(stroke
			(width 0)
			(type solid)
		)
		(fill yes)
		(layer "F.Cu")
		(net "M_H_DQ<51>")
	)
	(gr_poly
		(pts
			(xy 132.658866 -44.086272) (xy 132.533136 -43.942508) (xy 132.497322 -43.906694) (xy 132.407406 -43.99661)
			(xy 132.443474 -44.032424) (xy 132.587238 -44.158154)
		)
		(stroke
			(width 0)
			(type solid)
		)
		(fill yes)
		(layer "F.Cu")
		(net "M_H_DQS_DN<6>")
	)
	(gr_poly
		(pts
			(xy 132.705856 -106.26471) (xy 132.741924 -106.228896) (xy 132.652008 -106.13898) (xy 132.616194 -106.175048)
			(xy 132.490464 -106.318558) (xy 132.562346 -106.39044)
		)
		(stroke
			(width 0)
			(type solid)
		)
		(fill yes)
		(layer "F.Cu")
		(net "M_L_DQ<50>")
	)
	(gr_poly
		(pts
			(xy 132.713984 -109.058456) (xy 132.750052 -109.022642) (xy 132.660136 -108.932726) (xy 132.624322 -108.968794)
			(xy 132.498592 -109.112304) (xy 132.570474 -109.184186)
		)
		(stroke
			(width 0)
			(type solid)
		)
		(fill yes)
		(layer "F.Cu")
		(net "M_L_DQS_DN<15>")
	)
	(gr_poly
		(pts
			(xy 132.722366 -46.46676) (xy 132.686552 -46.430692) (xy 132.542788 -46.304962) (xy 132.470906 -46.376844)
			(xy 132.596636 -46.520608) (xy 132.632704 -46.556422)
		)
		(stroke
			(width 0)
			(type solid)
		)
		(fill yes)
		(layer "F.Cu")
		(net "M_H_DQ<51>")
	)
	(gr_poly
		(pts
			(xy 132.730748 -43.673268) (xy 132.694934 -43.6372) (xy 132.55117 -43.51147) (xy 132.479288 -43.583352)
			(xy 132.605018 -43.727116) (xy 132.641086 -43.76293)
		)
		(stroke
			(width 0)
			(type solid)
		)
		(fill yes)
		(layer "F.Cu")
		(net "M_H_DQS_DN<6>")
	)
	(gr_poly
		(pts
			(xy 132.73278 -106.704892) (xy 132.85851 -106.561128) (xy 132.786628 -106.4895) (xy 132.642864 -106.61523)
			(xy 132.60705 -106.651044) (xy 132.696966 -106.74096)
		)
		(stroke
			(width 0)
			(type solid)
		)
		(fill yes)
		(layer "F.Cu")
		(net "M_L_DQ<55>")
	)
	(gr_poly
		(pts
			(xy 132.740908 -109.498638) (xy 132.866638 -109.354874) (xy 132.794756 -109.282992) (xy 132.650992 -109.408722)
			(xy 132.615178 -109.44479) (xy 132.70484 -109.534452)
		)
		(stroke
			(width 0)
			(type solid)
		)
		(fill yes)
		(layer "F.Cu")
		(net "M_L_DQS_DP<15>")
	)
	(gr_poly
		(pts
			(xy 132.749036 -45.1104) (xy 132.623306 -44.966636) (xy 132.587492 -44.930568) (xy 132.497576 -45.020484)
			(xy 132.53339 -45.056298) (xy 132.677154 -45.182028)
		)
		(stroke
			(width 0)
			(type solid)
		)
		(fill yes)
		(layer "F.Cu")
		(net "M_H_DQ<54>")
	)
	(gr_poly
		(pts
			(xy 132.804154 -108.034328) (xy 132.840222 -107.998514) (xy 132.750306 -107.908598) (xy 132.714492 -107.944666)
			(xy 132.588762 -108.088176) (xy 132.660644 -108.160058)
		)
		(stroke
			(width 0)
			(type solid)
		)
		(fill yes)
		(layer "F.Cu")
		(net "M_L_DQS_DP<6>")
	)
	(gr_poly
		(pts
			(xy 132.820918 -44.697142) (xy 132.78485 -44.661328) (xy 132.64134 -44.535598) (xy 132.569458 -44.60748)
			(xy 132.695188 -44.75099) (xy 132.731002 -44.787058)
		)
		(stroke
			(width 0)
			(type solid)
		)
		(fill yes)
		(layer "F.Cu")
		(net "M_H_DQ<54>")
	)
	(gr_poly
		(pts
			(xy 132.822696 -105.681018) (xy 132.948426 -105.537254) (xy 132.876798 -105.465372) (xy 132.733034 -105.591102)
			(xy 132.696966 -105.626916) (xy 132.786882 -105.716832)
		)
		(stroke
			(width 0)
			(type solid)
		)
		(fill yes)
		(layer "F.Cu")
		(net "M_L_DQ<51>")
	)
	(gr_poly
		(pts
			(xy 132.831078 -108.47451) (xy 132.956808 -108.330746) (xy 132.884926 -108.259118) (xy 132.741162 -108.384594)
			(xy 132.705348 -108.420662) (xy 132.79501 -108.510324)
		)
		(stroke
			(width 0)
			(type solid)
		)
		(fill yes)
		(layer "F.Cu")
		(net "M_L_DQS_DN<6>")
	)
	(gr_poly
		(pts
			(xy 132.838952 -46.134274) (xy 132.713222 -45.99051) (xy 132.677408 -45.954696) (xy 132.587492 -46.044612)
			(xy 132.62356 -46.080426) (xy 132.767324 -46.206156)
		)
		(stroke
			(width 0)
			(type solid)
		)
		(fill yes)
		(layer "F.Cu")
		(net "M_H_DQ<50>")
	)
	(gr_poly
		(pts
			(xy 132.894324 -107.0102) (xy 132.930392 -106.974386) (xy 132.840476 -106.88447) (xy 132.804662 -106.920538)
			(xy 132.678932 -107.064048) (xy 132.750814 -107.13593)
		)
		(stroke
			(width 0)
			(type solid)
		)
		(fill yes)
		(layer "F.Cu")
		(net "M_L_DQ<55>")
	)
	(gr_poly
		(pts
			(xy 132.902452 -109.803946) (xy 132.93852 -109.768132) (xy 132.848604 -109.678216) (xy 132.81279 -109.714284)
			(xy 132.68706 -109.857794) (xy 132.758942 -109.929676)
		)
		(stroke
			(width 0)
			(type solid)
		)
		(fill yes)
		(layer "F.Cu")
		(net "M_L_DQS_DP<15>")
	)
	(gr_poly
		(pts
			(xy 132.910834 -45.72127) (xy 132.87502 -45.685202) (xy 132.731256 -45.559472) (xy 132.659374 -45.631354)
			(xy 132.785104 -45.775118) (xy 132.821172 -45.810932)
		)
		(stroke
			(width 0)
			(type solid)
		)
		(fill yes)
		(layer "F.Cu")
		(net "M_H_DQ<50>")
	)
	(gr_poly
		(pts
			(xy 132.921248 -107.450382) (xy 133.046978 -107.306618) (xy 132.975096 -107.23499) (xy 132.831332 -107.36072)
			(xy 132.795518 -107.396534) (xy 132.88518 -107.486196)
		)
		(stroke
			(width 0)
			(type solid)
		)
		(fill yes)
		(layer "F.Cu")
		(net "M_L_DQ<54>")
	)
	(gr_poly
		(pts
			(xy 132.937504 -44.36491) (xy 132.811774 -44.221146) (xy 132.775706 -44.185332) (xy 132.686044 -44.274994)
			(xy 132.721858 -44.310808) (xy 132.865622 -44.436538)
		)
		(stroke
			(width 0)
			(type solid)
		)
		(fill yes)
		(layer "F.Cu")
		(net "M_H_DQS_DP<6>")
	)
	(gr_poly
		(pts
			(xy 132.984494 -105.986326) (xy 133.020308 -105.950258) (xy 132.930646 -105.860596) (xy 132.894578 -105.89641)
			(xy 132.768848 -106.040174) (xy 132.84073 -106.112056)
		)
		(stroke
			(width 0)
			(type solid)
		)
		(fill yes)
		(layer "F.Cu")
		(net "M_L_DQ<51>")
	)
	(gr_poly
		(pts
			(xy 132.992622 -108.779818) (xy 133.02869 -108.744004) (xy 132.938774 -108.654088) (xy 132.90296 -108.690156)
			(xy 132.77723 -108.833666) (xy 132.849112 -108.905548)
		)
		(stroke
			(width 0)
			(type solid)
		)
		(fill yes)
		(layer "F.Cu")
		(net "M_L_DQS_DN<6>")
	)
	(gr_poly
		(pts
			(xy 133.009386 -43.951652) (xy 132.973318 -43.915838) (xy 132.829808 -43.790108) (xy 132.757926 -43.86199)
			(xy 132.883656 -44.0055) (xy 132.91947 -44.041568)
		)
		(stroke
			(width 0)
			(type solid)
		)
		(fill yes)
		(layer "F.Cu")
		(net "M_H_DQS_DP<6>")
	)
	(gr_poly
		(pts
			(xy 133.011164 -106.426508) (xy 133.136894 -106.282744) (xy 133.065266 -106.210862) (xy 132.921502 -106.336592)
			(xy 132.885434 -106.372406) (xy 132.97535 -106.462322)
		)
		(stroke
			(width 0)
			(type solid)
		)
		(fill yes)
		(layer "F.Cu")
		(net "M_L_DQ<50>")
	)
	(gr_poly
		(pts
			(xy 133.019292 -109.220254) (xy 133.145022 -109.07649) (xy 133.073394 -109.004608) (xy 132.92963 -109.130338)
			(xy 132.893562 -109.166152) (xy 132.983478 -109.256068)
		)
		(stroke
			(width 0)
			(type solid)
		)
		(fill yes)
		(layer "F.Cu")
		(net "M_L_DQS_DN<15>")
	)
	(gr_poly
		(pts
			(xy 133.02742 -45.388784) (xy 132.90169 -45.24502) (xy 132.865876 -45.209206) (xy 132.77596 -45.299122)
			(xy 132.812028 -45.334936) (xy 132.955792 -45.460666)
		)
		(stroke
			(width 0)
			(type solid)
		)
		(fill yes)
		(layer "F.Cu")
		(net "M_H_DQ<55>")
	)
	(gr_poly
		(pts
			(xy 133.082792 -107.75569) (xy 133.11886 -107.719876) (xy 133.028944 -107.62996) (xy 132.99313 -107.666028)
			(xy 132.8674 -107.809538) (xy 132.939282 -107.88142)
		)
		(stroke
			(width 0)
			(type solid)
		)
		(fill yes)
		(layer "F.Cu")
		(net "M_L_DQ<54>")
	)
	(gr_poly
		(pts
			(xy 133.099302 -44.97578) (xy 133.063488 -44.939712) (xy 132.919724 -44.813982) (xy 132.847842 -44.885864)
			(xy 132.973572 -45.029628) (xy 133.00964 -45.065442)
		)
		(stroke
			(width 0)
			(type solid)
		)
		(fill yes)
		(layer "F.Cu")
		(net "M_H_DQ<55>")
	)
	(gr_poly
		(pts
			(xy 133.109462 -108.196126) (xy 133.235192 -108.052362) (xy 133.163564 -107.98048) (xy 133.0198 -108.10621)
			(xy 132.983732 -108.142024) (xy 133.073648 -108.23194)
		)
		(stroke
			(width 0)
			(type solid)
		)
		(fill yes)
		(layer "F.Cu")
		(net "M_L_DQS_DP<6>")
	)
	(gr_poly
		(pts
			(xy 133.11759 -46.412912) (xy 132.99186 -46.269148) (xy 132.956046 -46.23308) (xy 132.86613 -46.322996)
			(xy 132.901944 -46.35881) (xy 133.045708 -46.48454)
		)
		(stroke
			(width 0)
			(type solid)
		)
		(fill yes)
		(layer "F.Cu")
		(net "M_H_DQ<51>")
	)
	(gr_poly
		(pts
			(xy 133.125972 -43.61942) (xy 133.000242 -43.475656) (xy 132.964174 -43.439842) (xy 132.874512 -43.529504)
			(xy 132.910326 -43.565572) (xy 133.05409 -43.691048)
		)
		(stroke
			(width 0)
			(type solid)
		)
		(fill yes)
		(layer "F.Cu")
		(net "M_H_DQS_DN<6>")
	)
	(gr_poly
		(pts
			(xy 133.172962 -106.731816) (xy 133.208776 -106.695748) (xy 133.119114 -106.606086) (xy 133.083046 -106.6419)
			(xy 132.957316 -106.785664) (xy 133.029198 -106.857546)
		)
		(stroke
			(width 0)
			(type solid)
		)
		(fill yes)
		(layer "F.Cu")
		(net "M_L_DQ<50>")
	)
	(gr_poly
		(pts
			(xy 133.18109 -109.525562) (xy 133.216904 -109.489494) (xy 133.127242 -109.399832) (xy 133.091174 -109.435646)
			(xy 132.965444 -109.57941) (xy 133.037326 -109.651292)
		)
		(stroke
			(width 0)
			(type solid)
		)
		(fill yes)
		(layer "F.Cu")
		(net "M_L_DQS_DN<15>")
	)
	(gr_poly
		(pts
			(xy 133.189472 -45.999654) (xy 133.153404 -45.96384) (xy 133.009894 -45.83811) (xy 132.938012 -45.909992)
			(xy 133.063742 -46.053502) (xy 133.099556 -46.08957)
		)
		(stroke
			(width 0)
			(type solid)
		)
		(fill yes)
		(layer "F.Cu")
		(net "M_H_DQ<51>")
	)
	(gr_poly
		(pts
			(xy 133.197854 -43.206416) (xy 133.16204 -43.170348) (xy 133.018276 -43.044618) (xy 132.946394 -43.1165)
			(xy 133.072124 -43.260264) (xy 133.108192 -43.296078)
		)
		(stroke
			(width 0)
			(type solid)
		)
		(fill yes)
		(layer "F.Cu")
		(net "M_H_DQS_DN<6>")
	)
	(gr_poly
		(pts
			(xy 133.199632 -107.171998) (xy 133.325362 -107.028234) (xy 133.253734 -106.956352) (xy 133.10997 -107.082082)
			(xy 133.073902 -107.117896) (xy 133.163818 -107.207812)
		)
		(stroke
			(width 0)
			(type solid)
		)
		(fill yes)
		(layer "F.Cu")
		(net "M_L_DQ<55>")
	)
	(gr_poly
		(pts
			(xy 133.215888 -44.643294) (xy 133.090158 -44.49953) (xy 133.054344 -44.463716) (xy 132.964428 -44.553632)
			(xy 133.000496 -44.589446) (xy 133.14426 -44.715176)
		)
		(stroke
			(width 0)
			(type solid)
		)
		(fill yes)
		(layer "F.Cu")
		(net "M_H_DQ<54>")
	)
	(gr_poly
		(pts
			(xy 133.27126 -108.501434) (xy 133.307074 -108.465366) (xy 133.217412 -108.375704) (xy 133.181344 -108.411518)
			(xy 133.055614 -108.555282) (xy 133.127496 -108.627164)
		)
		(stroke
			(width 0)
			(type solid)
		)
		(fill yes)
		(layer "F.Cu")
		(net "M_L_DQS_DP<6>")
	)
	(gr_poly
		(pts
			(xy 133.28777 -44.23029) (xy 133.251956 -44.194222) (xy 133.108192 -44.068492) (xy 133.03631 -44.140374)
			(xy 133.16204 -44.284138) (xy 133.198108 -44.319952)
		)
		(stroke
			(width 0)
			(type solid)
		)
		(fill yes)
		(layer "F.Cu")
		(net "M_H_DQ<54>")
	)
	(gr_poly
		(pts
			(xy 133.289802 -106.14787) (xy 133.415532 -106.004106) (xy 133.34365 -105.932478) (xy 133.199886 -106.058208)
			(xy 133.164072 -106.094022) (xy 133.253988 -106.183938)
		)
		(stroke
			(width 0)
			(type solid)
		)
		(fill yes)
		(layer "F.Cu")
		(net "M_L_DQ<51>")
	)
	(gr_poly
		(pts
			(xy 133.29793 -108.941616) (xy 133.42366 -108.797852) (xy 133.352032 -108.72597) (xy 133.208268 -108.8517)
			(xy 133.1722 -108.887514) (xy 133.262116 -108.97743)
		)
		(stroke
			(width 0)
			(type solid)
		)
		(fill yes)
		(layer "F.Cu")
		(net "M_L_DQS_DN<6>")
	)
	(gr_poly
		(pts
			(xy 133.306058 -45.667422) (xy 133.180328 -45.523658) (xy 133.144514 -45.48759) (xy 133.054598 -45.577506)
			(xy 133.090412 -45.61332) (xy 133.234176 -45.73905)
		)
		(stroke
			(width 0)
			(type solid)
		)
		(fill yes)
		(layer "F.Cu")
		(net "M_H_DQ<50>")
	)
	(gr_poly
		(pts
			(xy 133.36143 -107.477306) (xy 133.397244 -107.441238) (xy 133.307582 -107.351576) (xy 133.271514 -107.38739)
			(xy 133.145784 -107.531154) (xy 133.217666 -107.603036)
		)
		(stroke
			(width 0)
			(type solid)
		)
		(fill yes)
		(layer "F.Cu")
		(net "M_L_DQ<55>")
	)
	(gr_poly
		(pts
			(xy 133.37794 -45.254164) (xy 133.341872 -45.21835) (xy 133.198362 -45.09262) (xy 133.12648 -45.164502)
			(xy 133.25221 -45.308012) (xy 133.288024 -45.34408)
		)
		(stroke
			(width 0)
			(type solid)
		)
		(fill yes)
		(layer "F.Cu")
		(net "M_H_DQ<50>")
	)
	(gr_poly
		(pts
			(xy 133.3881 -107.917488) (xy 133.51383 -107.773724) (xy 133.442202 -107.701842) (xy 133.298438 -107.827572)
			(xy 133.26237 -107.863386) (xy 133.352286 -107.953302)
		)
		(stroke
			(width 0)
			(type solid)
		)
		(fill yes)
		(layer "F.Cu")
		(net "M_L_DQ<54>")
	)
	(gr_poly
		(pts
			(xy 133.404356 -43.897804) (xy 133.278626 -43.75404) (xy 133.242812 -43.718226) (xy 133.152896 -43.808142)
			(xy 133.188964 -43.843956) (xy 133.332728 -43.969686)
		)
		(stroke
			(width 0)
			(type solid)
		)
		(fill yes)
		(layer "F.Cu")
		(net "M_H_DQS_DP<6>")
	)
	(gr_poly
		(pts
			(xy 133.451346 -106.453178) (xy 133.487414 -106.417364) (xy 133.397498 -106.327448) (xy 133.361684 -106.363516)
			(xy 133.235954 -106.507026) (xy 133.307836 -106.578908)
		)
		(stroke
			(width 0)
			(type solid)
		)
		(fill yes)
		(layer "F.Cu")
		(net "M_L_DQ<51>")
	)
	(gr_poly
		(pts
			(xy 133.459728 -109.246924) (xy 133.495542 -109.210856) (xy 133.40588 -109.121194) (xy 133.369812 -109.157008)
			(xy 133.244082 -109.300772) (xy 133.315964 -109.372654)
		)
		(stroke
			(width 0)
			(type solid)
		)
		(fill yes)
		(layer "F.Cu")
		(net "M_L_DQS_DN<6>")
	)
	(gr_poly
		(pts
			(xy 133.476238 -43.4848) (xy 133.440424 -43.448732) (xy 133.29666 -43.323002) (xy 133.224778 -43.394884)
			(xy 133.350508 -43.538648) (xy 133.386576 -43.574462)
		)
		(stroke
			(width 0)
			(type solid)
		)
		(fill yes)
		(layer "F.Cu")
		(net "M_H_DQS_DP<6>")
	)
	(gr_poly
		(pts
			(xy 133.47827 -106.89336) (xy 133.604 -106.749596) (xy 133.532118 -106.677968) (xy 133.388354 -106.803698)
			(xy 133.35254 -106.839512) (xy 133.442202 -106.929174)
		)
		(stroke
			(width 0)
			(type solid)
		)
		(fill yes)
		(layer "F.Cu")
		(net "M_L_DQ<50>")
	)
	(gr_poly
		(pts
			(xy 133.494526 -44.921932) (xy 133.368796 -44.778168) (xy 133.332728 -44.742354) (xy 133.243066 -44.832016)
			(xy 133.27888 -44.86783) (xy 133.422644 -44.99356)
		)
		(stroke
			(width 0)
			(type solid)
		)
		(fill yes)
		(layer "F.Cu")
		(net "M_H_DQ<55>")
	)
	(gr_poly
		(pts
			(xy 133.549898 -108.222796) (xy 133.585712 -108.186728) (xy 133.49605 -108.097066) (xy 133.459982 -108.13288)
			(xy 133.334252 -108.276644) (xy 133.406134 -108.348526)
		)
		(stroke
			(width 0)
			(type solid)
		)
		(fill yes)
		(layer "F.Cu")
		(net "M_L_DQ<54>")
	)
	(gr_poly
		(pts
			(xy 133.566408 -44.508674) (xy 133.53034 -44.47286) (xy 133.38683 -44.34713) (xy 133.314948 -44.419012)
			(xy 133.440678 -44.562522) (xy 133.476492 -44.59859)
		)
		(stroke
			(width 0)
			(type solid)
		)
		(fill yes)
		(layer "F.Cu")
		(net "M_H_DQ<55>")
	)
	(gr_poly
		(pts
			(xy 133.576568 -108.662978) (xy 133.702298 -108.519214) (xy 133.630416 -108.447332) (xy 133.486652 -108.573062)
			(xy 133.450838 -108.60913) (xy 133.5405 -108.698792)
		)
		(stroke
			(width 0)
			(type solid)
		)
		(fill yes)
		(layer "F.Cu")
		(net "M_L_DQS_DP<6>")
	)
	(gr_poly
		(pts
			(xy 133.584442 -45.945806) (xy 133.458712 -45.802042) (xy 133.422898 -45.766228) (xy 133.332982 -45.856144)
			(xy 133.36905 -45.891958) (xy 133.512814 -46.017688)
		)
		(stroke
			(width 0)
			(type solid)
		)
		(fill yes)
		(layer "F.Cu")
		(net "M_H_DQ<51>")
	)
	(gr_poly
		(pts
			(xy 133.592824 -43.152568) (xy 133.467094 -43.008804) (xy 133.431026 -42.97299) (xy 133.341364 -43.062652)
			(xy 133.377178 -43.09872) (xy 133.520942 -43.224196)
		)
		(stroke
			(width 0)
			(type solid)
		)
		(fill yes)
		(layer "F.Cu")
		(net "M_H_DQS_DN<6>")
	)
	(gr_poly
		(pts
			(xy 133.639814 -107.198668) (xy 133.675882 -107.162854) (xy 133.585966 -107.072938) (xy 133.550152 -107.109006)
			(xy 133.424422 -107.252516) (xy 133.496304 -107.324398)
		)
		(stroke
			(width 0)
			(type solid)
		)
		(fill yes)
		(layer "F.Cu")
		(net "M_L_DQ<50>")
	)
	(gr_poly
		(pts
			(xy 133.656324 -45.532802) (xy 133.62051 -45.496734) (xy 133.476746 -45.371004) (xy 133.404864 -45.442886)
			(xy 133.530594 -45.58665) (xy 133.566662 -45.622464)
		)
		(stroke
			(width 0)
			(type solid)
		)
		(fill yes)
		(layer "F.Cu")
		(net "M_H_DQ<51>")
	)
	(gr_poly
		(pts
			(xy 133.666484 -107.63885) (xy 133.792214 -107.495086) (xy 133.720586 -107.423204) (xy 133.576822 -107.548934)
			(xy 133.540754 -107.584748) (xy 133.63067 -107.674664)
		)
		(stroke
			(width 0)
			(type solid)
		)
		(fill yes)
		(layer "F.Cu")
		(net "M_L_DQ<55>")
	)
	(gr_poly
		(pts
			(xy 133.682994 -44.176442) (xy 133.557264 -44.032678) (xy 133.521196 -43.996864) (xy 133.431534 -44.086526)
			(xy 133.467348 -44.122594) (xy 133.611112 -44.24807)
		)
		(stroke
			(width 0)
			(type solid)
		)
		(fill yes)
		(layer "F.Cu")
		(net "M_H_DQ<54>")
	)
	(gr_poly
		(pts
			(xy 133.738112 -108.968286) (xy 133.77418 -108.932472) (xy 133.684264 -108.842556) (xy 133.64845 -108.878624)
			(xy 133.52272 -109.022134) (xy 133.594602 -109.094016)
		)
		(stroke
			(width 0)
			(type solid)
		)
		(fill yes)
		(layer "F.Cu")
		(net "M_L_DQS_DP<6>")
	)
	(gr_poly
		(pts
			(xy 133.754876 -43.763184) (xy 133.718808 -43.72737) (xy 133.575298 -43.60164) (xy 133.503416 -43.673522)
			(xy 133.629146 -43.817032) (xy 133.66496 -43.8531)
		)
		(stroke
			(width 0)
			(type solid)
		)
		(fill yes)
		(layer "F.Cu")
		(net "M_H_DQ<54>")
	)
	(gr_poly
		(pts
			(xy 133.756908 -106.614976) (xy 133.882638 -106.471212) (xy 133.810756 -106.399584) (xy 133.666992 -106.525314)
			(xy 133.631178 -106.561128) (xy 133.721094 -106.651044)
		)
		(stroke
			(width 0)
			(type solid)
		)
		(fill yes)
		(layer "F.Cu")
		(net "M_L_DQ<51>")
	)
	(gr_poly
		(pts
			(xy 133.77291 -45.200316) (xy 133.64718 -45.056552) (xy 133.611366 -45.020738) (xy 133.52145 -45.110654)
			(xy 133.557518 -45.146468) (xy 133.701282 -45.272198)
		)
		(stroke
			(width 0)
			(type solid)
		)
		(fill yes)
		(layer "F.Cu")
		(net "M_H_DQ<50>")
	)
	(gr_poly
		(pts
			(xy 133.828282 -107.944158) (xy 133.864096 -107.90809) (xy 133.774434 -107.818428) (xy 133.738366 -107.854242)
			(xy 133.612636 -107.998006) (xy 133.684518 -108.069888)
		)
		(stroke
			(width 0)
			(type solid)
		)
		(fill yes)
		(layer "F.Cu")
		(net "M_L_DQ<55>")
	)
	(gr_poly
		(pts
			(xy 133.844792 -44.787312) (xy 133.808978 -44.751244) (xy 133.665214 -44.625514) (xy 133.593332 -44.697396)
			(xy 133.719062 -44.84116) (xy 133.75513 -44.876974)
		)
		(stroke
			(width 0)
			(type solid)
		)
		(fill yes)
		(layer "F.Cu")
		(net "M_H_DQ<50>")
	)
	(gr_poly
		(pts
			(xy 133.918452 -106.920284) (xy 133.95452 -106.88447) (xy 133.864604 -106.794554) (xy 133.82879 -106.830622)
			(xy 133.70306 -106.974132) (xy 133.774942 -107.046014)
		)
		(stroke
			(width 0)
			(type solid)
		)
		(fill yes)
		(layer "F.Cu")
		(net "M_L_DQ<51>")
	)
	(gr_poly
		(pts
			(xy 133.945376 -107.360466) (xy 134.071106 -107.216702) (xy 133.999224 -107.145074) (xy 133.85546 -107.270804)
			(xy 133.819646 -107.306618) (xy 133.909308 -107.39628)
		)
		(stroke
			(width 0)
			(type solid)
		)
		(fill yes)
		(layer "F.Cu")
		(net "M_L_DQ<50>")
	)
	(gr_poly
		(pts
			(xy 133.961378 -44.454826) (xy 133.835648 -44.311062) (xy 133.799834 -44.275248) (xy 133.709918 -44.365164)
			(xy 133.745986 -44.400978) (xy 133.88975 -44.526708)
		)
		(stroke
			(width 0)
			(type solid)
		)
		(fill yes)
		(layer "F.Cu")
		(net "M_H_DQ<55>")
	)
	(gr_poly
		(pts
			(xy 134.03326 -44.041822) (xy 133.997446 -44.005754) (xy 133.853682 -43.880024) (xy 133.7818 -43.951906)
			(xy 133.90753 -44.09567) (xy 133.943598 -44.131484)
		)
		(stroke
			(width 0)
			(type solid)
		)
		(fill yes)
		(layer "F.Cu")
		(net "M_H_DQ<55>")
	)
	(gr_poly
		(pts
			(xy 134.051548 -45.478954) (xy 133.925818 -45.33519) (xy 133.88975 -45.299376) (xy 133.800088 -45.389038)
			(xy 133.835902 -45.424852) (xy 133.979666 -45.550582)
		)
		(stroke
			(width 0)
			(type solid)
		)
		(fill yes)
		(layer "F.Cu")
		(net "M_H_DQ<51>")
	)
	(gr_poly
		(pts
			(xy 134.10692 -107.665774) (xy 134.142988 -107.62996) (xy 134.053072 -107.540044) (xy 134.017258 -107.576112)
			(xy 133.891528 -107.719622) (xy 133.96341 -107.791504)
		)
		(stroke
			(width 0)
			(type solid)
		)
		(fill yes)
		(layer "F.Cu")
		(net "M_L_DQ<50>")
	)
	(gr_poly
		(pts
			(xy 134.12343 -45.065696) (xy 134.087362 -45.029882) (xy 133.943852 -44.904152) (xy 133.87197 -44.976034)
			(xy 133.9977 -45.119544) (xy 134.033514 -45.155612)
		)
		(stroke
			(width 0)
			(type solid)
		)
		(fill yes)
		(layer "F.Cu")
		(net "M_H_DQ<51>")
	)
	(gr_poly
		(pts
			(xy 134.149846 -43.709336) (xy 134.024116 -43.565572) (xy 133.988302 -43.529758) (xy 133.898386 -43.619674)
			(xy 133.934454 -43.655488) (xy 134.078218 -43.781218)
		)
		(stroke
			(width 0)
			(type solid)
		)
		(fill yes)
		(layer "F.Cu")
		(net "M_H_DQ<54>")
	)
	(gr_poly
		(pts
			(xy 134.224014 -107.082082) (xy 134.349744 -106.938318) (xy 134.277862 -106.86669) (xy 134.134098 -106.99242)
			(xy 134.098284 -107.028234) (xy 134.1882 -107.11815)
		)
		(stroke
			(width 0)
			(type solid)
		)
		(fill yes)
		(layer "F.Cu")
		(net "M_L_DQ<51>")
	)
	(gr_poly
		(pts
			(xy 134.240016 -44.733464) (xy 134.114286 -44.5897) (xy 134.078218 -44.553886) (xy 133.988556 -44.643548)
			(xy 134.02437 -44.679616) (xy 134.168134 -44.805092)
		)
		(stroke
			(width 0)
			(type solid)
		)
		(fill yes)
		(layer "F.Cu")
		(net "M_H_DQ<50>")
	)
	(gr_poly
		(pts
			(xy 134.311898 -44.320206) (xy 134.27583 -44.284392) (xy 134.13232 -44.158662) (xy 134.060438 -44.230544)
			(xy 134.186168 -44.374054) (xy 134.221982 -44.410122)
		)
		(stroke
			(width 0)
			(type solid)
		)
		(fill yes)
		(layer "F.Cu")
		(net "M_H_DQ<50>")
	)
	(gr_poly
		(pts
			(xy 134.385558 -107.38739) (xy 134.421626 -107.351576) (xy 134.33171 -107.26166) (xy 134.295896 -107.297728)
			(xy 134.170166 -107.441238) (xy 134.242048 -107.51312)
		)
		(stroke
			(width 0)
			(type solid)
		)
		(fill yes)
		(layer "F.Cu")
		(net "M_L_DQ<51>")
	)
	(gr_poly
		(pts
			(xy 134.428484 -43.987974) (xy 134.302754 -43.84421) (xy 134.266686 -43.808396) (xy 134.177024 -43.898058)
			(xy 134.212838 -43.934126) (xy 134.356602 -44.059856)
		)
		(stroke
			(width 0)
			(type solid)
		)
		(fill yes)
		(layer "F.Cu")
		(net "M_H_DQ<55>")
	)
	(gr_poly
		(pts
			(xy 134.5184 -45.011848) (xy 134.39267 -44.868084) (xy 134.356856 -44.83227) (xy 134.26694 -44.922186)
			(xy 134.303008 -44.958) (xy 134.446772 -45.08373)
		)
		(stroke
			(width 0)
			(type solid)
		)
		(fill yes)
		(layer "F.Cu")
		(net "M_H_DQ<51>")
	)
	(gr_poly
		(pts
			(xy 134.590282 -44.598844) (xy 134.554468 -44.562776) (xy 134.410704 -44.437046) (xy 134.338822 -44.508928)
			(xy 134.464552 -44.652692) (xy 134.50062 -44.688506)
		)
		(stroke
			(width 0)
			(type solid)
		)
		(fill yes)
		(layer "F.Cu")
		(net "M_H_DQ<51>")
	)
	(gr_poly
		(pts
			(xy 134.706868 -44.266358) (xy 134.581138 -44.122594) (xy 134.545324 -44.08678) (xy 134.455408 -44.176696)
			(xy 134.491476 -44.21251) (xy 134.63524 -44.33824)
		)
		(stroke
			(width 0)
			(type solid)
		)
		(fill yes)
		(layer "F.Cu")
		(net "M_H_DQ<50>")
	)
	(gr_poly
		(pts
			(xy 134.985506 -44.544996) (xy 134.859776 -44.401232) (xy 134.823708 -44.365418) (xy 134.734046 -44.45508)
			(xy 134.76986 -44.491148) (xy 134.913624 -44.616878)
		)
		(stroke
			(width 0)
			(type solid)
		)
		(fill yes)
		(layer "F.Cu")
		(net "M_H_DQ<51>")
	)
	(gr_poly
		(pts
			(xy 230.168196 -48.283114) (xy 230.155496 -48.092614) (xy 230.053896 -48.092614) (xy 230.041196 -48.283114)
			(xy 230.041196 -48.346614) (xy 230.168196 -48.346614)
		)
		(stroke
			(width 0)
			(type solid)
		)
		(fill yes)
		(layer "F.Cu")
		(net "M_B_DQ<28>")
	)
	(gr_poly
		(pts
			(xy 230.498396 -47.991014) (xy 230.498396 -47.940214) (xy 230.371396 -47.940214) (xy 230.371396 -47.991014)
			(xy 230.384096 -48.181514) (xy 230.485696 -48.181514)
		)
		(stroke
			(width 0)
			(type solid)
		)
		(fill yes)
		(layer "F.Cu")
		(net "M_B_DQ<29>")
	)
	(gr_poly
		(pts
			(xy 230.828596 -48.283114) (xy 230.815896 -48.092614) (xy 230.714296 -48.092614) (xy 230.701596 -48.283114)
			(xy 230.701596 -48.346614) (xy 230.828596 -48.346614)
		)
		(stroke
			(width 0)
			(type solid)
		)
		(fill yes)
		(layer "F.Cu")
		(net "M_B_DQ<28>")
	)
	(gr_poly
		(pts
			(xy 230.828596 -47.889414) (xy 230.815896 -47.698914) (xy 230.714296 -47.698914) (xy 230.701596 -47.889414)
			(xy 230.701596 -47.940214) (xy 230.828596 -47.940214)
		)
		(stroke
			(width 0)
			(type solid)
		)
		(fill yes)
		(layer "F.Cu")
		(net "M_B_DQ<29>")
	)
	(gr_poly
		(pts
			(xy 231.158796 -47.991014) (xy 231.158796 -47.940214) (xy 231.031796 -47.940214) (xy 231.031796 -47.991014)
			(xy 231.044496 -48.181514) (xy 231.146096 -48.181514)
		)
		(stroke
			(width 0)
			(type solid)
		)
		(fill yes)
		(layer "F.Cu")
		(net "M_B_DQ<29>")
	)
	(gr_poly
		(pts
			(xy 231.158796 -47.597314) (xy 231.158796 -47.546514) (xy 231.031796 -47.546514) (xy 231.031796 -47.597314)
			(xy 231.044496 -47.787814) (xy 231.146096 -47.787814)
		)
		(stroke
			(width 0)
			(type solid)
		)
		(fill yes)
		(layer "F.Cu")
		(net "M_B_DQ<24>")
	)
	(gr_poly
		(pts
			(xy 231.488996 -48.283114) (xy 231.476296 -48.092614) (xy 231.374696 -48.092614) (xy 231.361996 -48.283114)
			(xy 231.361996 -48.346614) (xy 231.488996 -48.346614)
		)
		(stroke
			(width 0)
			(type solid)
		)
		(fill yes)
		(layer "F.Cu")
		(net "M_B_DQ<28>")
	)
	(gr_poly
		(pts
			(xy 231.488996 -47.889414) (xy 231.476296 -47.698914) (xy 231.374696 -47.698914) (xy 231.361996 -47.889414)
			(xy 231.361996 -47.940214) (xy 231.488996 -47.940214)
		)
		(stroke
			(width 0)
			(type solid)
		)
		(fill yes)
		(layer "F.Cu")
		(net "M_B_DQ<29>")
	)
	(gr_poly
		(pts
			(xy 231.488996 -47.495714) (xy 231.476296 -47.305214) (xy 231.374696 -47.305214) (xy 231.361996 -47.495714)
			(xy 231.361996 -47.546514) (xy 231.488996 -47.546514)
		)
		(stroke
			(width 0)
			(type solid)
		)
		(fill yes)
		(layer "F.Cu")
		(net "M_B_DQ<24>")
	)
	(gr_poly
		(pts
			(xy 231.75722 -48.37811) (xy 231.88295 -48.234346) (xy 231.811068 -48.162464) (xy 231.667558 -48.288194)
			(xy 231.6226 -48.333152) (xy 231.712262 -48.422814)
		)
		(stroke
			(width 0)
			(type solid)
		)
		(fill yes)
		(layer "F.Cu")
		(net "M_B_DQ<28>")
	)
	(gr_poly
		(pts
			(xy 231.819196 -47.597314) (xy 231.819196 -47.546514) (xy 231.692196 -47.546514) (xy 231.692196 -47.597314)
			(xy 231.704896 -47.787814) (xy 231.806496 -47.787814)
		)
		(stroke
			(width 0)
			(type solid)
		)
		(fill yes)
		(layer "F.Cu")
		(net "M_B_DQ<24>")
	)
	(gr_poly
		(pts
			(xy 231.819196 -47.203614) (xy 231.819196 -47.152814) (xy 231.692196 -47.152814) (xy 231.692196 -47.203614)
			(xy 231.704896 -47.394114) (xy 231.806496 -47.394114)
		)
		(stroke
			(width 0)
			(type solid)
		)
		(fill yes)
		(layer "F.Cu")
		(net "M_B_DQ<25>")
	)
	(gr_poly
		(pts
			(xy 232.035604 -48.099726) (xy 232.161334 -47.955962) (xy 232.089706 -47.88408) (xy 231.945942 -48.00981)
			(xy 231.909874 -48.045624) (xy 231.99979 -48.13554)
		)
		(stroke
			(width 0)
			(type solid)
		)
		(fill yes)
		(layer "F.Cu")
		(net "M_B_DQ<29>")
	)
	(gr_poly
		(pts
			(xy 232.149396 -47.102014) (xy 232.136696 -46.911514) (xy 232.035096 -46.911514) (xy 232.022396 -47.102014)
			(xy 232.022396 -47.152814) (xy 232.149396 -47.152814)
		)
		(stroke
			(width 0)
			(type solid)
		)
		(fill yes)
		(layer "F.Cu")
		(net "M_B_DQ<25>")
	)
	(gr_poly
		(pts
			(xy 232.197656 -48.405288) (xy 232.233724 -48.369474) (xy 232.143808 -48.279558) (xy 232.107994 -48.315626)
			(xy 231.982264 -48.459136) (xy 232.054146 -48.531018)
		)
		(stroke
			(width 0)
			(type solid)
		)
		(fill yes)
		(layer "F.Cu")
		(net "M_B_DQ<29>")
	)
	(gr_poly
		(pts
			(xy 232.22458 -48.84547) (xy 232.35031 -48.701706) (xy 232.278428 -48.629824) (xy 232.134918 -48.755554)
			(xy 232.08996 -48.800512) (xy 232.179622 -48.890174)
		)
		(stroke
			(width 0)
			(type solid)
		)
		(fill yes)
		(layer "F.Cu")
		(net "M_B_DQ<28>")
	)
	(gr_poly
		(pts
			(xy 232.287318 -47.380906) (xy 232.323386 -47.345092) (xy 232.23347 -47.255176) (xy 232.197656 -47.291244)
			(xy 232.071926 -47.434754) (xy 232.143808 -47.506636)
		)
		(stroke
			(width 0)
			(type solid)
		)
		(fill yes)
		(layer "F.Cu")
		(net "M_B_DQ<25>")
	)
	(gr_poly
		(pts
			(xy 232.314496 -47.821596) (xy 232.440226 -47.677832) (xy 232.368598 -47.60595) (xy 232.224834 -47.73168)
			(xy 232.188766 -47.767494) (xy 232.278682 -47.85741)
		)
		(stroke
			(width 0)
			(type solid)
		)
		(fill yes)
		(layer "F.Cu")
		(net "M_B_DQ<24>")
	)
	(gr_poly
		(pts
			(xy 232.404158 -46.797214) (xy 232.529888 -46.65345) (xy 232.45826 -46.581568) (xy 232.314496 -46.707298)
			(xy 232.278428 -46.743112) (xy 232.368344 -46.833028)
		)
		(stroke
			(width 0)
			(type solid)
		)
		(fill yes)
		(layer "F.Cu")
		(net "M_B_DQS_DP<12>")
	)
	(gr_poly
		(pts
			(xy 232.476294 -48.126904) (xy 232.512108 -48.090836) (xy 232.422446 -48.001174) (xy 232.386378 -48.036988)
			(xy 232.260648 -48.180752) (xy 232.33253 -48.252634)
		)
		(stroke
			(width 0)
			(type solid)
		)
		(fill yes)
		(layer "F.Cu")
		(net "M_B_DQ<24>")
	)
	(gr_poly
		(pts
			(xy 232.502964 -48.567086) (xy 232.628694 -48.423322) (xy 232.557066 -48.35144) (xy 232.413302 -48.47717)
			(xy 232.377234 -48.512984) (xy 232.46715 -48.6029)
		)
		(stroke
			(width 0)
			(type solid)
		)
		(fill yes)
		(layer "F.Cu")
		(net "M_B_DQ<29>")
	)
	(gr_poly
		(pts
			(xy 232.56621 -47.102776) (xy 232.602278 -47.066962) (xy 232.512362 -46.977046) (xy 232.476548 -47.013114)
			(xy 232.350818 -47.156624) (xy 232.4227 -47.228506)
		)
		(stroke
			(width 0)
			(type solid)
		)
		(fill yes)
		(layer "F.Cu")
		(net "M_B_DQS_DP<12>")
	)
	(gr_poly
		(pts
			(xy 232.593134 -47.542958) (xy 232.718864 -47.399194) (xy 232.646982 -47.327566) (xy 232.503218 -47.453296)
			(xy 232.467404 -47.48911) (xy 232.55732 -47.579026)
		)
		(stroke
			(width 0)
			(type solid)
		)
		(fill yes)
		(layer "F.Cu")
		(net "M_B_DQ<25>")
	)
	(gr_poly
		(pts
			(xy 232.655872 -46.078394) (xy 232.69194 -46.04258) (xy 232.602024 -45.952664) (xy 232.56621 -45.988732)
			(xy 232.44048 -46.132242) (xy 232.512362 -46.204124)
		)
		(stroke
			(width 0)
			(type solid)
		)
		(fill yes)
		(layer "F.Cu")
		(net "M_B_DQS_DN<3>")
	)
	(gr_poly
		(pts
			(xy 232.664762 -48.872394) (xy 232.700576 -48.836326) (xy 232.610914 -48.746664) (xy 232.574846 -48.782478)
			(xy 232.449116 -48.926242) (xy 232.520998 -48.998124)
		)
		(stroke
			(width 0)
			(type solid)
		)
		(fill yes)
		(layer "F.Cu")
		(net "M_B_DQ<29>")
	)
	(gr_poly
		(pts
			(xy 232.682796 -46.518576) (xy 232.808526 -46.374812) (xy 232.736644 -46.303184) (xy 232.59288 -46.428914)
			(xy 232.557066 -46.464728) (xy 232.646982 -46.554644)
		)
		(stroke
			(width 0)
			(type solid)
		)
		(fill yes)
		(layer "F.Cu")
		(net "M_B_DQS_DN<12>")
	)
	(gr_poly
		(pts
			(xy 232.69194 -49.31283) (xy 232.81767 -49.169066) (xy 232.745788 -49.097184) (xy 232.602278 -49.222914)
			(xy 232.55732 -49.267872) (xy 232.646982 -49.357534)
		)
		(stroke
			(width 0)
			(type solid)
		)
		(fill yes)
		(layer "F.Cu")
		(net "M_B_DQ<28>")
	)
	(gr_poly
		(pts
			(xy 232.754678 -47.848266) (xy 232.790746 -47.812452) (xy 232.70083 -47.722536) (xy 232.665016 -47.758604)
			(xy 232.539286 -47.902114) (xy 232.611168 -47.973996)
		)
		(stroke
			(width 0)
			(type solid)
		)
		(fill yes)
		(layer "F.Cu")
		(net "M_B_DQ<25>")
	)
	(gr_poly
		(pts
			(xy 232.781602 -48.288448) (xy 232.907332 -48.144684) (xy 232.83545 -48.073056) (xy 232.691686 -48.198786)
			(xy 232.655872 -48.2346) (xy 232.745534 -48.324262)
		)
		(stroke
			(width 0)
			(type solid)
		)
		(fill yes)
		(layer "F.Cu")
		(net "M_B_DQ<24>")
	)
	(gr_poly
		(pts
			(xy 232.844848 -46.824392) (xy 232.880662 -46.788324) (xy 232.791 -46.698662) (xy 232.754932 -46.734476)
			(xy 232.629202 -46.87824) (xy 232.701084 -46.950122)
		)
		(stroke
			(width 0)
			(type solid)
		)
		(fill yes)
		(layer "F.Cu")
		(net "M_B_DQS_DN<12>")
	)
	(gr_poly
		(pts
			(xy 232.871518 -47.264574) (xy 232.997248 -47.12081) (xy 232.92562 -47.048928) (xy 232.781856 -47.174658)
			(xy 232.745788 -47.210472) (xy 232.835704 -47.300388)
		)
		(stroke
			(width 0)
			(type solid)
		)
		(fill yes)
		(layer "F.Cu")
		(net "M_B_DQS_DP<12>")
	)
	(gr_poly
		(pts
			(xy 232.93451 -45.80001) (xy 232.970324 -45.763942) (xy 232.880662 -45.67428) (xy 232.844594 -45.710094)
			(xy 232.718864 -45.853858) (xy 232.790746 -45.92574)
		)
		(stroke
			(width 0)
			(type solid)
		)
		(fill yes)
		(layer "F.Cu")
		(net "M_B_DQS_DP<3>")
	)
	(gr_poly
		(pts
			(xy 232.943654 -48.594264) (xy 232.979468 -48.558196) (xy 232.889806 -48.468534) (xy 232.853738 -48.504348)
			(xy 232.728008 -48.648112) (xy 232.79989 -48.719994)
		)
		(stroke
			(width 0)
			(type solid)
		)
		(fill yes)
		(layer "F.Cu")
		(net "M_B_DQ<24>")
	)
	(gr_poly
		(pts
			(xy 232.961688 -46.240446) (xy 233.087418 -46.096682) (xy 233.015536 -46.025054) (xy 232.871772 -46.150784)
			(xy 232.835958 -46.186598) (xy 232.925874 -46.276514)
		)
		(stroke
			(width 0)
			(type solid)
		)
		(fill yes)
		(layer "F.Cu")
		(net "M_B_DQS_DN<3>")
	)
	(gr_poly
		(pts
			(xy 232.970324 -49.034446) (xy 233.096054 -48.890682) (xy 233.024426 -48.8188) (xy 232.880662 -48.94453)
			(xy 232.844594 -48.980344) (xy 232.93451 -49.07026)
		)
		(stroke
			(width 0)
			(type solid)
		)
		(fill yes)
		(layer "F.Cu")
		(net "M_B_DQ<29>")
	)
	(gr_poly
		(pts
			(xy 233.033316 -47.569882) (xy 233.06913 -47.533814) (xy 232.979468 -47.444152) (xy 232.9434 -47.479966)
			(xy 232.81767 -47.62373) (xy 232.889552 -47.695612)
		)
		(stroke
			(width 0)
			(type solid)
		)
		(fill yes)
		(layer "F.Cu")
		(net "M_B_DQS_DP<12>")
	)
	(gr_poly
		(pts
			(xy 233.060494 -48.010318) (xy 233.186224 -47.866554) (xy 233.114342 -47.794926) (xy 232.970578 -47.920656)
			(xy 232.934764 -47.95647) (xy 233.02468 -48.046386)
		)
		(stroke
			(width 0)
			(type solid)
		)
		(fill yes)
		(layer "F.Cu")
		(net "M_B_DQ<25>")
	)
	(gr_poly
		(pts
			(xy 233.123232 -46.545754) (xy 233.1593 -46.50994) (xy 233.069384 -46.420024) (xy 233.03357 -46.456092)
			(xy 232.90784 -46.599602) (xy 232.979722 -46.671484)
		)
		(stroke
			(width 0)
			(type solid)
		)
		(fill yes)
		(layer "F.Cu")
		(net "M_B_DQS_DN<3>")
	)
	(gr_poly
		(pts
			(xy 233.13136 -49.17059) (xy 233.13136 -49.11979) (xy 233.00436 -49.11979) (xy 233.00436 -49.17059)
			(xy 233.01706 -49.36109) (xy 233.11866 -49.36109)
		)
		(stroke
			(width 0)
			(type solid)
		)
		(fill yes)
		(layer "F.Cu")
		(net "M_B_DQ<29>")
	)
	(gr_poly
		(pts
			(xy 233.150156 -46.985936) (xy 233.275886 -46.842172) (xy 233.204004 -46.770544) (xy 233.06024 -46.896274)
			(xy 233.024426 -46.932088) (xy 233.114342 -47.022004)
		)
		(stroke
			(width 0)
			(type solid)
		)
		(fill yes)
		(layer "F.Cu")
		(net "M_B_DQS_DN<12>")
	)
	(gr_poly
		(pts
			(xy 233.212894 -45.521372) (xy 233.248962 -45.485558) (xy 233.159046 -45.395642) (xy 233.123232 -45.43171)
			(xy 232.997502 -45.57522) (xy 233.069384 -45.647102)
		)
		(stroke
			(width 0)
			(type solid)
		)
		(fill yes)
		(layer "F.Cu")
		(net "M_B_DQ<30>")
	)
	(gr_poly
		(pts
			(xy 233.222038 -48.315626) (xy 233.258106 -48.279812) (xy 233.16819 -48.189896) (xy 233.132376 -48.225964)
			(xy 233.006646 -48.369474) (xy 233.078528 -48.441356)
		)
		(stroke
			(width 0)
			(type solid)
		)
		(fill yes)
		(layer "F.Cu")
		(net "M_B_DQ<25>")
	)
	(gr_poly
		(pts
			(xy 233.240072 -45.962062) (xy 233.365802 -45.818298) (xy 233.294174 -45.746416) (xy 233.15041 -45.872146)
			(xy 233.114342 -45.90796) (xy 233.204258 -45.997876)
		)
		(stroke
			(width 0)
			(type solid)
		)
		(fill yes)
		(layer "F.Cu")
		(net "M_B_DQS_DP<3>")
	)
	(gr_poly
		(pts
			(xy 233.3117 -47.291244) (xy 233.347768 -47.25543) (xy 233.257852 -47.165514) (xy 233.222038 -47.201582)
			(xy 233.096308 -47.345092) (xy 233.16819 -47.416974)
		)
		(stroke
			(width 0)
			(type solid)
		)
		(fill yes)
		(layer "F.Cu")
		(net "M_B_DQS_DN<12>")
	)
	(gr_poly
		(pts
			(xy 233.338878 -47.731934) (xy 233.464608 -47.58817) (xy 233.39298 -47.516288) (xy 233.249216 -47.642018)
			(xy 233.213148 -47.677832) (xy 233.303064 -47.767748)
		)
		(stroke
			(width 0)
			(type solid)
		)
		(fill yes)
		(layer "F.Cu")
		(net "M_B_DQS_DP<12>")
	)
	(gr_poly
		(pts
			(xy 233.40187 -46.26737) (xy 233.437684 -46.231302) (xy 233.348022 -46.14164) (xy 233.311954 -46.177454)
			(xy 233.186224 -46.321218) (xy 233.258106 -46.3931)
		)
		(stroke
			(width 0)
			(type solid)
		)
		(fill yes)
		(layer "F.Cu")
		(net "M_B_DQS_DP<3>")
	)
	(gr_poly
		(pts
			(xy 233.42854 -46.707552) (xy 233.55427 -46.563788) (xy 233.482642 -46.491906) (xy 233.338878 -46.617636)
			(xy 233.30281 -46.65345) (xy 233.392726 -46.743366)
		)
		(stroke
			(width 0)
			(type solid)
		)
		(fill yes)
		(layer "F.Cu")
		(net "M_B_DQS_DN<3>")
	)
	(gr_poly
		(pts
			(xy 233.46156 -49.46269) (xy 233.44886 -49.27219) (xy 233.34726 -49.27219) (xy 233.33456 -49.46269)
			(xy 233.33456 -49.52619) (xy 233.46156 -49.52619)
		)
		(stroke
			(width 0)
			(type solid)
		)
		(fill yes)
		(layer "F.Cu")
		(net "M_B_DQ<28>")
	)
	(gr_poly
		(pts
			(xy 233.46156 -49.06899) (xy 233.44886 -48.87849) (xy 233.34726 -48.87849) (xy 233.33456 -49.06899)
			(xy 233.33456 -49.11979) (xy 233.46156 -49.11979)
		)
		(stroke
			(width 0)
			(type solid)
		)
		(fill yes)
		(layer "F.Cu")
		(net "M_B_DQ<29>")
	)
	(gr_poly
		(pts
			(xy 233.46156 -48.67529) (xy 233.44886 -48.48479) (xy 233.34726 -48.48479) (xy 233.33456 -48.67529)
			(xy 233.33456 -48.72609) (xy 233.46156 -48.72609)
		)
		(stroke
			(width 0)
			(type solid)
		)
		(fill yes)
		(layer "F.Cu")
		(net "M_B_DQ<24>")
	)
	(gr_poly
		(pts
			(xy 233.51871 -45.683424) (xy 233.64444 -45.53966) (xy 233.572812 -45.467778) (xy 233.429048 -45.593508)
			(xy 233.39298 -45.629322) (xy 233.482896 -45.719238)
		)
		(stroke
			(width 0)
			(type solid)
		)
		(fill yes)
		(layer "F.Cu")
		(net "M_B_DQ<30>")
	)
	(gr_poly
		(pts
			(xy 233.590592 -47.013114) (xy 233.62666 -46.9773) (xy 233.536744 -46.887384) (xy 233.50093 -46.923452)
			(xy 233.3752 -47.066962) (xy 233.447082 -47.138844)
		)
		(stroke
			(width 0)
			(type solid)
		)
		(fill yes)
		(layer "F.Cu")
		(net "M_B_DQS_DN<3>")
	)
	(gr_poly
		(pts
			(xy 233.617516 -47.453296) (xy 233.743246 -47.309532) (xy 233.671364 -47.237904) (xy 233.5276 -47.363634)
			(xy 233.491786 -47.399448) (xy 233.581702 -47.489364)
		)
		(stroke
			(width 0)
			(type solid)
		)
		(fill yes)
		(layer "F.Cu")
		(net "M_B_DQS_DN<12>")
	)
	(gr_poly
		(pts
			(xy 233.680254 -45.988732) (xy 233.716322 -45.952918) (xy 233.626406 -45.863002) (xy 233.590592 -45.89907)
			(xy 233.464862 -46.04258) (xy 233.536744 -46.114462)
		)
		(stroke
			(width 0)
			(type solid)
		)
		(fill yes)
		(layer "F.Cu")
		(net "M_B_DQ<30>")
	)
	(gr_poly
		(pts
			(xy 233.707432 -46.429422) (xy 233.833162 -46.285658) (xy 233.761534 -46.213776) (xy 233.61777 -46.339506)
			(xy 233.581702 -46.37532) (xy 233.671618 -46.465236)
		)
		(stroke
			(width 0)
			(type solid)
		)
		(fill yes)
		(layer "F.Cu")
		(net "M_B_DQS_DP<3>")
	)
	(gr_poly
		(pts
			(xy 233.79176 -49.17059) (xy 233.79176 -49.11979) (xy 233.66476 -49.11979) (xy 233.66476 -49.17059)
			(xy 233.67746 -49.36109) (xy 233.77906 -49.36109)
		)
		(stroke
			(width 0)
			(type solid)
		)
		(fill yes)
		(layer "F.Cu")
		(net "M_B_DQ<29>")
	)
	(gr_poly
		(pts
			(xy 233.79176 -48.77689) (xy 233.79176 -48.72609) (xy 233.66476 -48.72609) (xy 233.66476 -48.77689)
			(xy 233.67746 -48.96739) (xy 233.77906 -48.96739)
		)
		(stroke
			(width 0)
			(type solid)
		)
		(fill yes)
		(layer "F.Cu")
		(net "M_B_DQ<24>")
	)
	(gr_poly
		(pts
			(xy 233.79176 -48.38319) (xy 233.79176 -48.33239) (xy 233.66476 -48.33239) (xy 233.66476 -48.38319)
			(xy 233.67746 -48.57369) (xy 233.77906 -48.57369)
		)
		(stroke
			(width 0)
			(type solid)
		)
		(fill yes)
		(layer "F.Cu")
		(net "M_B_DQ<25>")
	)
	(gr_poly
		(pts
			(xy 233.79176 -47.98949) (xy 233.79176 -47.93869) (xy 233.66476 -47.93869) (xy 233.66476 -47.98949)
			(xy 233.67746 -48.17999) (xy 233.77906 -48.17999)
		)
		(stroke
			(width 0)
			(type solid)
		)
		(fill yes)
		(layer "F.Cu")
		(net "M_B_DQS_DP<12>")
	)
	(gr_poly
		(pts
			(xy 233.79176 -47.59579) (xy 233.79176 -47.54499) (xy 233.66476 -47.54499) (xy 233.66476 -47.59579)
			(xy 233.67746 -47.78629) (xy 233.77906 -47.78629)
		)
		(stroke
			(width 0)
			(type solid)
		)
		(fill yes)
		(layer "F.Cu")
		(net "M_B_DQS_DN<12>")
	)
	(gr_poly
		(pts
			(xy 233.797348 -45.404786) (xy 233.923078 -45.261022) (xy 233.85145 -45.18914) (xy 233.707686 -45.31487)
			(xy 233.671618 -45.350684) (xy 233.761534 -45.4406)
		)
		(stroke
			(width 0)
			(type solid)
		)
		(fill yes)
		(layer "F.Cu")
		(net "M_B_DQ<31>")
	)
	(gr_poly
		(pts
			(xy 233.86923 -46.73473) (xy 233.905044 -46.698662) (xy 233.815382 -46.609) (xy 233.779314 -46.644814)
			(xy 233.653584 -46.788578) (xy 233.725466 -46.86046)
		)
		(stroke
			(width 0)
			(type solid)
		)
		(fill yes)
		(layer "F.Cu")
		(net "M_B_DQS_DP<3>")
	)
	(gr_poly
		(pts
			(xy 233.958892 -45.710348) (xy 233.994706 -45.67428) (xy 233.905044 -45.584618) (xy 233.868976 -45.620432)
			(xy 233.743246 -45.764196) (xy 233.815128 -45.836078)
		)
		(stroke
			(width 0)
			(type solid)
		)
		(fill yes)
		(layer "F.Cu")
		(net "M_B_DQ<31>")
	)
	(gr_poly
		(pts
			(xy 233.98607 -46.150784) (xy 234.1118 -46.00702) (xy 234.040172 -45.935138) (xy 233.896408 -46.060868)
			(xy 233.86034 -46.096682) (xy 233.950256 -46.186598)
		)
		(stroke
			(width 0)
			(type solid)
		)
		(fill yes)
		(layer "F.Cu")
		(net "M_B_DQ<30>")
	)
	(gr_poly
		(pts
			(xy 234.002834 -44.810934) (xy 233.939334 -44.810934) (xy 233.748834 -44.823634) (xy 233.748834 -44.925234)
			(xy 233.939334 -44.937934) (xy 234.002834 -44.937934)
		)
		(stroke
			(width 0)
			(type solid)
		)
		(fill yes)
		(layer "F.Cu")
		(net "M_B_DQ<26>")
	)
	(gr_poly
		(pts
			(xy 234.12196 -49.46269) (xy 234.10926 -49.27219) (xy 234.00766 -49.27219) (xy 233.99496 -49.46269)
			(xy 233.99496 -49.52619) (xy 234.12196 -49.52619)
		)
		(stroke
			(width 0)
			(type solid)
		)
		(fill yes)
		(layer "F.Cu")
		(net "M_B_DQ<28>")
	)
	(gr_poly
		(pts
			(xy 234.12196 -49.06899) (xy 234.10926 -48.87849) (xy 234.00766 -48.87849) (xy 233.99496 -49.06899)
			(xy 233.99496 -49.11979) (xy 234.12196 -49.11979)
		)
		(stroke
			(width 0)
			(type solid)
		)
		(fill yes)
		(layer "F.Cu")
		(net "M_B_DQ<29>")
	)
	(gr_poly
		(pts
			(xy 234.12196 -48.67529) (xy 234.10926 -48.48479) (xy 234.00766 -48.48479) (xy 233.99496 -48.67529)
			(xy 233.99496 -48.72609) (xy 234.12196 -48.72609)
		)
		(stroke
			(width 0)
			(type solid)
		)
		(fill yes)
		(layer "F.Cu")
		(net "M_B_DQ<24>")
	)
	(gr_poly
		(pts
			(xy 234.12196 -48.28159) (xy 234.10926 -48.09109) (xy 234.00766 -48.09109) (xy 233.99496 -48.28159)
			(xy 233.99496 -48.33239) (xy 234.12196 -48.33239)
		)
		(stroke
			(width 0)
			(type solid)
		)
		(fill yes)
		(layer "F.Cu")
		(net "M_B_DQ<25>")
	)
	(gr_poly
		(pts
			(xy 234.12196 -47.88789) (xy 234.10926 -47.69739) (xy 234.00766 -47.69739) (xy 233.99496 -47.88789)
			(xy 233.99496 -47.93869) (xy 234.12196 -47.93869)
		)
		(stroke
			(width 0)
			(type solid)
		)
		(fill yes)
		(layer "F.Cu")
		(net "M_B_DQS_DP<12>")
	)
	(gr_poly
		(pts
			(xy 234.12196 -47.49419) (xy 234.10926 -47.30369) (xy 234.00766 -47.30369) (xy 233.99496 -47.49419)
			(xy 233.99496 -47.54499) (xy 234.12196 -47.54499)
		)
		(stroke
			(width 0)
			(type solid)
		)
		(fill yes)
		(layer "F.Cu")
		(net "M_B_DQS_DN<12>")
	)
	(gr_poly
		(pts
			(xy 234.12196 -47.10049) (xy 234.10926 -46.90999) (xy 234.00766 -46.90999) (xy 233.99496 -47.10049)
			(xy 233.99496 -47.15129) (xy 234.12196 -47.15129)
		)
		(stroke
			(width 0)
			(type solid)
		)
		(fill yes)
		(layer "F.Cu")
		(net "M_B_DQS_DN<3>")
	)
	(gr_poly
		(pts
			(xy 234.147614 -46.456092) (xy 234.183682 -46.420278) (xy 234.093766 -46.330362) (xy 234.057952 -46.36643)
			(xy 233.932222 -46.50994) (xy 234.004104 -46.581822)
		)
		(stroke
			(width 0)
			(type solid)
		)
		(fill yes)
		(layer "F.Cu")
		(net "M_B_DQ<30>")
	)
	(gr_poly
		(pts
			(xy 234.23753 -45.43171) (xy 234.273344 -45.395642) (xy 234.183682 -45.30598) (xy 234.147614 -45.341794)
			(xy 234.021884 -45.485558) (xy 234.093766 -45.55744)
		)
		(stroke
			(width 0)
			(type solid)
		)
		(fill yes)
		(layer "F.Cu")
		(net "M_B_DQ<26>")
	)
	(gr_poly
		(pts
			(xy 234.244134 -44.595034) (xy 234.244134 -44.493434) (xy 234.053634 -44.480734) (xy 233.990134 -44.480734)
			(xy 233.990134 -44.607734) (xy 234.053634 -44.607734)
		)
		(stroke
			(width 0)
			(type solid)
		)
		(fill yes)
		(layer "F.Cu")
		(net "M_B_DQ<26>")
	)
	(gr_poly
		(pts
			(xy 234.264454 -45.872146) (xy 234.390184 -45.728382) (xy 234.318556 -45.6565) (xy 234.174792 -45.78223)
			(xy 234.138724 -45.818044) (xy 234.22864 -45.90796)
		)
		(stroke
			(width 0)
			(type solid)
		)
		(fill yes)
		(layer "F.Cu")
		(net "M_B_DQ<31>")
	)
	(gr_poly
		(pts
			(xy 234.409234 -44.810934) (xy 234.345734 -44.810934) (xy 234.155234 -44.823634) (xy 234.155234 -44.925234)
			(xy 234.345734 -44.937934) (xy 234.409234 -44.937934)
		)
		(stroke
			(width 0)
			(type solid)
		)
		(fill yes)
		(layer "F.Cu")
		(net "M_B_DQ<27>")
	)
	(gr_poly
		(pts
			(xy 234.409234 -44.150534) (xy 234.345734 -44.150534) (xy 234.155234 -44.163234) (xy 234.155234 -44.264834)
			(xy 234.345734 -44.277534) (xy 234.409234 -44.277534)
		)
		(stroke
			(width 0)
			(type solid)
		)
		(fill yes)
		(layer "F.Cu")
		(net "M_B_DQ<27>")
	)
	(gr_poly
		(pts
			(xy 234.45216 -49.17059) (xy 234.45216 -49.11979) (xy 234.32516 -49.11979) (xy 234.32516 -49.17059)
			(xy 234.33786 -49.36109) (xy 234.43946 -49.36109)
		)
		(stroke
			(width 0)
			(type solid)
		)
		(fill yes)
		(layer "F.Cu")
		(net "M_B_DQ<29>")
	)
	(gr_poly
		(pts
			(xy 234.45216 -48.77689) (xy 234.45216 -48.72609) (xy 234.32516 -48.72609) (xy 234.32516 -48.77689)
			(xy 234.33786 -48.96739) (xy 234.43946 -48.96739)
		)
		(stroke
			(width 0)
			(type solid)
		)
		(fill yes)
		(layer "F.Cu")
		(net "M_B_DQ<24>")
	)
	(gr_poly
		(pts
			(xy 234.45216 -48.38319) (xy 234.45216 -48.33239) (xy 234.32516 -48.33239) (xy 234.32516 -48.38319)
			(xy 234.33786 -48.57369) (xy 234.43946 -48.57369)
		)
		(stroke
			(width 0)
			(type solid)
		)
		(fill yes)
		(layer "F.Cu")
		(net "M_B_DQ<25>")
	)
	(gr_poly
		(pts
			(xy 234.45216 -47.98949) (xy 234.45216 -47.93869) (xy 234.32516 -47.93869) (xy 234.32516 -47.98949)
			(xy 234.33786 -48.17999) (xy 234.43946 -48.17999)
		)
		(stroke
			(width 0)
			(type solid)
		)
		(fill yes)
		(layer "F.Cu")
		(net "M_B_DQS_DP<12>")
	)
	(gr_poly
		(pts
			(xy 234.45216 -47.59579) (xy 234.45216 -47.54499) (xy 234.32516 -47.54499) (xy 234.32516 -47.59579)
			(xy 234.33786 -47.78629) (xy 234.43946 -47.78629)
		)
		(stroke
			(width 0)
			(type solid)
		)
		(fill yes)
		(layer "F.Cu")
		(net "M_B_DQS_DN<12>")
	)
	(gr_poly
		(pts
			(xy 234.45216 -47.20209) (xy 234.45216 -47.15129) (xy 234.32516 -47.15129) (xy 234.32516 -47.20209)
			(xy 234.33786 -47.39259) (xy 234.43946 -47.39259)
		)
		(stroke
			(width 0)
			(type solid)
		)
		(fill yes)
		(layer "F.Cu")
		(net "M_B_DQS_DN<3>")
	)
	(gr_poly
		(pts
			(xy 234.45216 -46.80839) (xy 234.45216 -46.75759) (xy 234.32516 -46.75759) (xy 234.32516 -46.80839)
			(xy 234.33786 -46.99889) (xy 234.43946 -46.99889)
		)
		(stroke
			(width 0)
			(type solid)
		)
		(fill yes)
		(layer "F.Cu")
		(net "M_B_DQS_DP<3>")
	)
	(gr_poly
		(pts
			(xy 234.45216 -46.41469) (xy 234.45216 -46.36389) (xy 234.32516 -46.36389) (xy 234.32516 -46.41469)
			(xy 234.33786 -46.60519) (xy 234.43946 -46.60519)
		)
		(stroke
			(width 0)
			(type solid)
		)
		(fill yes)
		(layer "F.Cu")
		(net "M_B_DQ<30>")
	)
	(gr_poly
		(pts
			(xy 234.45216 -46.02099) (xy 234.45216 -45.97019) (xy 234.32516 -45.97019) (xy 234.32516 -46.02099)
			(xy 234.33786 -46.21149) (xy 234.43946 -46.21149)
		)
		(stroke
			(width 0)
			(type solid)
		)
		(fill yes)
		(layer "F.Cu")
		(net "M_B_DQ<31>")
	)
	(gr_poly
		(pts
			(xy 234.516168 -45.153072) (xy 234.551982 -45.117004) (xy 234.46232 -45.027342) (xy 234.426252 -45.063156)
			(xy 234.300522 -45.20692) (xy 234.372404 -45.278802)
		)
		(stroke
			(width 0)
			(type solid)
		)
		(fill yes)
		(layer "F.Cu")
		(net "M_B_DQ<27>")
	)
	(gr_poly
		(pts
			(xy 234.78236 -49.46269) (xy 234.76966 -49.27219) (xy 234.66806 -49.27219) (xy 234.65536 -49.46269)
			(xy 234.65536 -49.52619) (xy 234.78236 -49.52619)
		)
		(stroke
			(width 0)
			(type solid)
		)
		(fill yes)
		(layer "F.Cu")
		(net "M_B_DQ<28>")
	)
	(gr_poly
		(pts
			(xy 234.78236 -49.06899) (xy 234.76966 -48.87849) (xy 234.66806 -48.87849) (xy 234.65536 -49.06899)
			(xy 234.65536 -49.11979) (xy 234.78236 -49.11979)
		)
		(stroke
			(width 0)
			(type solid)
		)
		(fill yes)
		(layer "F.Cu")
		(net "M_B_DQ<29>")
	)
	(gr_poly
		(pts
			(xy 234.78236 -48.67529) (xy 234.76966 -48.48479) (xy 234.66806 -48.48479) (xy 234.65536 -48.67529)
			(xy 234.65536 -48.72609) (xy 234.78236 -48.72609)
		)
		(stroke
			(width 0)
			(type solid)
		)
		(fill yes)
		(layer "F.Cu")
		(net "M_B_DQ<24>")
	)
	(gr_poly
		(pts
			(xy 234.78236 -48.28159) (xy 234.76966 -48.09109) (xy 234.66806 -48.09109) (xy 234.65536 -48.28159)
			(xy 234.65536 -48.33239) (xy 234.78236 -48.33239)
		)
		(stroke
			(width 0)
			(type solid)
		)
		(fill yes)
		(layer "F.Cu")
		(net "M_B_DQ<25>")
	)
	(gr_poly
		(pts
			(xy 234.78236 -47.88789) (xy 234.76966 -47.69739) (xy 234.66806 -47.69739) (xy 234.65536 -47.88789)
			(xy 234.65536 -47.93869) (xy 234.78236 -47.93869)
		)
		(stroke
			(width 0)
			(type solid)
		)
		(fill yes)
		(layer "F.Cu")
		(net "M_B_DQS_DP<12>")
	)
	(gr_poly
		(pts
			(xy 234.78236 -47.49419) (xy 234.76966 -47.30369) (xy 234.66806 -47.30369) (xy 234.65536 -47.49419)
			(xy 234.65536 -47.54499) (xy 234.78236 -47.54499)
		)
		(stroke
			(width 0)
			(type solid)
		)
		(fill yes)
		(layer "F.Cu")
		(net "M_B_DQS_DN<12>")
	)
	(gr_poly
		(pts
			(xy 234.78236 -47.10049) (xy 234.76966 -46.90999) (xy 234.66806 -46.90999) (xy 234.65536 -47.10049)
			(xy 234.65536 -47.15129) (xy 234.78236 -47.15129)
		)
		(stroke
			(width 0)
			(type solid)
		)
		(fill yes)
		(layer "F.Cu")
		(net "M_B_DQS_DN<3>")
	)
	(gr_poly
		(pts
			(xy 234.78236 -46.70679) (xy 234.76966 -46.51629) (xy 234.66806 -46.51629) (xy 234.65536 -46.70679)
			(xy 234.65536 -46.75759) (xy 234.78236 -46.75759)
		)
		(stroke
			(width 0)
			(type solid)
		)
		(fill yes)
		(layer "F.Cu")
		(net "M_B_DQS_DP<3>")
	)
	(gr_poly
		(pts
			(xy 234.78236 -46.31309) (xy 234.76966 -46.12259) (xy 234.66806 -46.12259) (xy 234.65536 -46.31309)
			(xy 234.65536 -46.36389) (xy 234.78236 -46.36389)
		)
		(stroke
			(width 0)
			(type solid)
		)
		(fill yes)
		(layer "F.Cu")
		(net "M_B_DQ<30>")
	)
	(gr_poly
		(pts
			(xy 234.78236 -45.91939) (xy 234.76966 -45.72889) (xy 234.66806 -45.72889) (xy 234.65536 -45.91939)
			(xy 234.65536 -45.97019) (xy 234.78236 -45.97019)
		)
		(stroke
			(width 0)
			(type solid)
		)
		(fill yes)
		(layer "F.Cu")
		(net "M_B_DQ<31>")
	)
	(gr_poly
		(pts
			(xy 234.78236 -45.52569) (xy 234.76966 -45.33519) (xy 234.66806 -45.33519) (xy 234.65536 -45.52569)
			(xy 234.65536 -45.57649) (xy 234.78236 -45.57649)
		)
		(stroke
			(width 0)
			(type solid)
		)
		(fill yes)
		(layer "F.Cu")
		(net "M_B_DQ<26>")
	)
	(gr_poly
		(pts
			(xy 235.11256 -49.17059) (xy 235.11256 -49.11979) (xy 234.98556 -49.11979) (xy 234.98556 -49.17059)
			(xy 234.99826 -49.36109) (xy 235.09986 -49.36109)
		)
		(stroke
			(width 0)
			(type solid)
		)
		(fill yes)
		(layer "F.Cu")
		(net "M_B_DQ<29>")
	)
	(gr_poly
		(pts
			(xy 235.11256 -48.77689) (xy 235.11256 -48.72609) (xy 234.98556 -48.72609) (xy 234.98556 -48.77689)
			(xy 234.99826 -48.96739) (xy 235.09986 -48.96739)
		)
		(stroke
			(width 0)
			(type solid)
		)
		(fill yes)
		(layer "F.Cu")
		(net "M_B_DQ<24>")
	)
	(gr_poly
		(pts
			(xy 235.11256 -48.38319) (xy 235.11256 -48.33239) (xy 234.98556 -48.33239) (xy 234.98556 -48.38319)
			(xy 234.99826 -48.57369) (xy 235.09986 -48.57369)
		)
		(stroke
			(width 0)
			(type solid)
		)
		(fill yes)
		(layer "F.Cu")
		(net "M_B_DQ<25>")
	)
	(gr_poly
		(pts
			(xy 235.11256 -47.98949) (xy 235.11256 -47.93869) (xy 234.98556 -47.93869) (xy 234.98556 -47.98949)
			(xy 234.99826 -48.17999) (xy 235.09986 -48.17999)
		)
		(stroke
			(width 0)
			(type solid)
		)
		(fill yes)
		(layer "F.Cu")
		(net "M_B_DQS_DP<12>")
	)
	(gr_poly
		(pts
			(xy 235.11256 -47.59579) (xy 235.11256 -47.54499) (xy 234.98556 -47.54499) (xy 234.98556 -47.59579)
			(xy 234.99826 -47.78629) (xy 235.09986 -47.78629)
		)
		(stroke
			(width 0)
			(type solid)
		)
		(fill yes)
		(layer "F.Cu")
		(net "M_B_DQS_DN<12>")
	)
	(gr_poly
		(pts
			(xy 235.11256 -47.20209) (xy 235.11256 -47.15129) (xy 234.98556 -47.15129) (xy 234.98556 -47.20209)
			(xy 234.99826 -47.39259) (xy 235.09986 -47.39259)
		)
		(stroke
			(width 0)
			(type solid)
		)
		(fill yes)
		(layer "F.Cu")
		(net "M_B_DQS_DN<3>")
	)
	(gr_poly
		(pts
			(xy 235.11256 -46.80839) (xy 235.11256 -46.75759) (xy 234.98556 -46.75759) (xy 234.98556 -46.80839)
			(xy 234.99826 -46.99889) (xy 235.09986 -46.99889)
		)
		(stroke
			(width 0)
			(type solid)
		)
		(fill yes)
		(layer "F.Cu")
		(net "M_B_DQS_DP<3>")
	)
	(gr_poly
		(pts
			(xy 235.11256 -46.41469) (xy 235.11256 -46.36389) (xy 234.98556 -46.36389) (xy 234.98556 -46.41469)
			(xy 234.99826 -46.60519) (xy 235.09986 -46.60519)
		)
		(stroke
			(width 0)
			(type solid)
		)
		(fill yes)
		(layer "F.Cu")
		(net "M_B_DQ<30>")
	)
	(gr_poly
		(pts
			(xy 235.11256 -46.02099) (xy 235.11256 -45.97019) (xy 234.98556 -45.97019) (xy 234.98556 -46.02099)
			(xy 234.99826 -46.21149) (xy 235.09986 -46.21149)
		)
		(stroke
			(width 0)
			(type solid)
		)
		(fill yes)
		(layer "F.Cu")
		(net "M_B_DQ<31>")
	)
	(gr_poly
		(pts
			(xy 235.11256 -45.62729) (xy 235.11256 -45.57649) (xy 234.98556 -45.57649) (xy 234.98556 -45.62729)
			(xy 234.99826 -45.81779) (xy 235.09986 -45.81779)
		)
		(stroke
			(width 0)
			(type solid)
		)
		(fill yes)
		(layer "F.Cu")
		(net "M_B_DQ<26>")
	)
	(gr_poly
		(pts
			(xy 235.11256 -45.23359) (xy 235.11256 -45.17009) (xy 234.98556 -45.17009) (xy 234.98556 -45.23359)
			(xy 234.99826 -45.42409) (xy 235.09986 -45.42409)
		)
		(stroke
			(width 0)
			(type solid)
		)
		(fill yes)
		(layer "F.Cu")
		(net "M_B_DQ<27>")
	)
	(gr_poly
		(pts
			(xy 235.44276 -49.46269) (xy 235.43006 -49.27219) (xy 235.32846 -49.27219) (xy 235.31576 -49.46269)
			(xy 235.31576 -49.52619) (xy 235.44276 -49.52619)
		)
		(stroke
			(width 0)
			(type solid)
		)
		(fill yes)
		(layer "F.Cu")
		(net "M_B_DQ<28>")
	)
	(gr_poly
		(pts
			(xy 235.44276 -49.06899) (xy 235.43006 -48.87849) (xy 235.32846 -48.87849) (xy 235.31576 -49.06899)
			(xy 235.31576 -49.11979) (xy 235.44276 -49.11979)
		)
		(stroke
			(width 0)
			(type solid)
		)
		(fill yes)
		(layer "F.Cu")
		(net "M_B_DQ<29>")
	)
	(gr_poly
		(pts
			(xy 235.44276 -48.67529) (xy 235.43006 -48.48479) (xy 235.32846 -48.48479) (xy 235.31576 -48.67529)
			(xy 235.31576 -48.72609) (xy 235.44276 -48.72609)
		)
		(stroke
			(width 0)
			(type solid)
		)
		(fill yes)
		(layer "F.Cu")
		(net "M_B_DQ<24>")
	)
	(gr_poly
		(pts
			(xy 235.44276 -48.28159) (xy 235.43006 -48.09109) (xy 235.32846 -48.09109) (xy 235.31576 -48.28159)
			(xy 235.31576 -48.33239) (xy 235.44276 -48.33239)
		)
		(stroke
			(width 0)
			(type solid)
		)
		(fill yes)
		(layer "F.Cu")
		(net "M_B_DQ<25>")
	)
	(gr_poly
		(pts
			(xy 235.44276 -47.88789) (xy 235.43006 -47.69739) (xy 235.32846 -47.69739) (xy 235.31576 -47.88789)
			(xy 235.31576 -47.93869) (xy 235.44276 -47.93869)
		)
		(stroke
			(width 0)
			(type solid)
		)
		(fill yes)
		(layer "F.Cu")
		(net "M_B_DQS_DP<12>")
	)
	(gr_poly
		(pts
			(xy 235.44276 -47.49419) (xy 235.43006 -47.30369) (xy 235.32846 -47.30369) (xy 235.31576 -47.49419)
			(xy 235.31576 -47.54499) (xy 235.44276 -47.54499)
		)
		(stroke
			(width 0)
			(type solid)
		)
		(fill yes)
		(layer "F.Cu")
		(net "M_B_DQS_DN<12>")
	)
	(gr_poly
		(pts
			(xy 235.44276 -47.10049) (xy 235.43006 -46.90999) (xy 235.32846 -46.90999) (xy 235.31576 -47.10049)
			(xy 235.31576 -47.15129) (xy 235.44276 -47.15129)
		)
		(stroke
			(width 0)
			(type solid)
		)
		(fill yes)
		(layer "F.Cu")
		(net "M_B_DQS_DN<3>")
	)
	(gr_poly
		(pts
			(xy 235.44276 -46.70679) (xy 235.43006 -46.51629) (xy 235.32846 -46.51629) (xy 235.31576 -46.70679)
			(xy 235.31576 -46.75759) (xy 235.44276 -46.75759)
		)
		(stroke
			(width 0)
			(type solid)
		)
		(fill yes)
		(layer "F.Cu")
		(net "M_B_DQS_DP<3>")
	)
	(gr_poly
		(pts
			(xy 235.44276 -46.31309) (xy 235.43006 -46.12259) (xy 235.32846 -46.12259) (xy 235.31576 -46.31309)
			(xy 235.31576 -46.36389) (xy 235.44276 -46.36389)
		)
		(stroke
			(width 0)
			(type solid)
		)
		(fill yes)
		(layer "F.Cu")
		(net "M_B_DQ<30>")
	)
	(gr_poly
		(pts
			(xy 235.44276 -45.91939) (xy 235.43006 -45.72889) (xy 235.32846 -45.72889) (xy 235.31576 -45.91939)
			(xy 235.31576 -45.97019) (xy 235.44276 -45.97019)
		)
		(stroke
			(width 0)
			(type solid)
		)
		(fill yes)
		(layer "F.Cu")
		(net "M_B_DQ<31>")
	)
	(gr_poly
		(pts
			(xy 235.44276 -45.52569) (xy 235.43006 -45.33519) (xy 235.32846 -45.33519) (xy 235.31576 -45.52569)
			(xy 235.31576 -45.57649) (xy 235.44276 -45.57649)
		)
		(stroke
			(width 0)
			(type solid)
		)
		(fill yes)
		(layer "F.Cu")
		(net "M_B_DQ<26>")
	)
	(gr_poly
		(pts
			(xy 235.77296 -49.17059) (xy 235.77296 -49.11979) (xy 235.64596 -49.11979) (xy 235.64596 -49.17059)
			(xy 235.65866 -49.36109) (xy 235.76026 -49.36109)
		)
		(stroke
			(width 0)
			(type solid)
		)
		(fill yes)
		(layer "F.Cu")
		(net "M_B_DQ<29>")
	)
	(gr_poly
		(pts
			(xy 235.77296 -48.77689) (xy 235.77296 -48.72609) (xy 235.64596 -48.72609) (xy 235.64596 -48.77689)
			(xy 235.65866 -48.96739) (xy 235.76026 -48.96739)
		)
		(stroke
			(width 0)
			(type solid)
		)
		(fill yes)
		(layer "F.Cu")
		(net "M_B_DQ<24>")
	)
	(gr_poly
		(pts
			(xy 235.77296 -48.38319) (xy 235.77296 -48.33239) (xy 235.64596 -48.33239) (xy 235.64596 -48.38319)
			(xy 235.65866 -48.57369) (xy 235.76026 -48.57369)
		)
		(stroke
			(width 0)
			(type solid)
		)
		(fill yes)
		(layer "F.Cu")
		(net "M_B_DQ<25>")
	)
	(gr_poly
		(pts
			(xy 235.77296 -47.98949) (xy 235.77296 -47.93869) (xy 235.64596 -47.93869) (xy 235.64596 -47.98949)
			(xy 235.65866 -48.17999) (xy 235.76026 -48.17999)
		)
		(stroke
			(width 0)
			(type solid)
		)
		(fill yes)
		(layer "F.Cu")
		(net "M_B_DQS_DP<12>")
	)
	(gr_poly
		(pts
			(xy 235.77296 -47.59579) (xy 235.77296 -47.54499) (xy 235.64596 -47.54499) (xy 235.64596 -47.59579)
			(xy 235.65866 -47.78629) (xy 235.76026 -47.78629)
		)
		(stroke
			(width 0)
			(type solid)
		)
		(fill yes)
		(layer "F.Cu")
		(net "M_B_DQS_DN<12>")
	)
	(gr_poly
		(pts
			(xy 235.77296 -47.20209) (xy 235.77296 -47.15129) (xy 235.64596 -47.15129) (xy 235.64596 -47.20209)
			(xy 235.65866 -47.39259) (xy 235.76026 -47.39259)
		)
		(stroke
			(width 0)
			(type solid)
		)
		(fill yes)
		(layer "F.Cu")
		(net "M_B_DQS_DN<3>")
	)
	(gr_poly
		(pts
			(xy 235.77296 -46.80839) (xy 235.77296 -46.75759) (xy 235.64596 -46.75759) (xy 235.64596 -46.80839)
			(xy 235.65866 -46.99889) (xy 235.76026 -46.99889)
		)
		(stroke
			(width 0)
			(type solid)
		)
		(fill yes)
		(layer "F.Cu")
		(net "M_B_DQS_DP<3>")
	)
	(gr_poly
		(pts
			(xy 235.77296 -46.41469) (xy 235.77296 -46.36389) (xy 235.64596 -46.36389) (xy 235.64596 -46.41469)
			(xy 235.65866 -46.60519) (xy 235.76026 -46.60519)
		)
		(stroke
			(width 0)
			(type solid)
		)
		(fill yes)
		(layer "F.Cu")
		(net "M_B_DQ<30>")
	)
	(gr_poly
		(pts
			(xy 235.77296 -46.02099) (xy 235.77296 -45.97019) (xy 235.64596 -45.97019) (xy 235.64596 -46.02099)
			(xy 235.65866 -46.21149) (xy 235.76026 -46.21149)
		)
		(stroke
			(width 0)
			(type solid)
		)
		(fill yes)
		(layer "F.Cu")
		(net "M_B_DQ<31>")
	)
	(gr_poly
		(pts
			(xy 235.77296 -45.62729) (xy 235.77296 -45.57649) (xy 235.64596 -45.57649) (xy 235.64596 -45.62729)
			(xy 235.65866 -45.81779) (xy 235.76026 -45.81779)
		)
		(stroke
			(width 0)
			(type solid)
		)
		(fill yes)
		(layer "F.Cu")
		(net "M_B_DQ<26>")
	)
	(gr_poly
		(pts
			(xy 235.77296 -45.23359) (xy 235.77296 -45.17009) (xy 235.64596 -45.17009) (xy 235.64596 -45.23359)
			(xy 235.65866 -45.42409) (xy 235.76026 -45.42409)
		)
		(stroke
			(width 0)
			(type solid)
		)
		(fill yes)
		(layer "F.Cu")
		(net "M_B_DQ<27>")
	)
	(gr_poly
		(pts
			(xy 236.10316 -49.46269) (xy 236.09046 -49.27219) (xy 235.98886 -49.27219) (xy 235.97616 -49.46269)
			(xy 235.97616 -49.52619) (xy 236.10316 -49.52619)
		)
		(stroke
			(width 0)
			(type solid)
		)
		(fill yes)
		(layer "F.Cu")
		(net "M_B_DQ<28>")
	)
	(gr_poly
		(pts
			(xy 236.10316 -49.06899) (xy 236.09046 -48.87849) (xy 235.98886 -48.87849) (xy 235.97616 -49.06899)
			(xy 235.97616 -49.11979) (xy 236.10316 -49.11979)
		)
		(stroke
			(width 0)
			(type solid)
		)
		(fill yes)
		(layer "F.Cu")
		(net "M_B_DQ<29>")
	)
	(gr_poly
		(pts
			(xy 236.10316 -48.67529) (xy 236.09046 -48.48479) (xy 235.98886 -48.48479) (xy 235.97616 -48.67529)
			(xy 235.97616 -48.72609) (xy 236.10316 -48.72609)
		)
		(stroke
			(width 0)
			(type solid)
		)
		(fill yes)
		(layer "F.Cu")
		(net "M_B_DQ<24>")
	)
	(gr_poly
		(pts
			(xy 236.10316 -48.28159) (xy 236.09046 -48.09109) (xy 235.98886 -48.09109) (xy 235.97616 -48.28159)
			(xy 235.97616 -48.33239) (xy 236.10316 -48.33239)
		)
		(stroke
			(width 0)
			(type solid)
		)
		(fill yes)
		(layer "F.Cu")
		(net "M_B_DQ<25>")
	)
	(gr_poly
		(pts
			(xy 236.10316 -47.88789) (xy 236.09046 -47.69739) (xy 235.98886 -47.69739) (xy 235.97616 -47.88789)
			(xy 235.97616 -47.93869) (xy 236.10316 -47.93869)
		)
		(stroke
			(width 0)
			(type solid)
		)
		(fill yes)
		(layer "F.Cu")
		(net "M_B_DQS_DP<12>")
	)
	(gr_poly
		(pts
			(xy 236.10316 -47.49419) (xy 236.09046 -47.30369) (xy 235.98886 -47.30369) (xy 235.97616 -47.49419)
			(xy 235.97616 -47.54499) (xy 236.10316 -47.54499)
		)
		(stroke
			(width 0)
			(type solid)
		)
		(fill yes)
		(layer "F.Cu")
		(net "M_B_DQS_DN<12>")
	)
	(gr_poly
		(pts
			(xy 236.10316 -47.10049) (xy 236.09046 -46.90999) (xy 235.98886 -46.90999) (xy 235.97616 -47.10049)
			(xy 235.97616 -47.15129) (xy 236.10316 -47.15129)
		)
		(stroke
			(width 0)
			(type solid)
		)
		(fill yes)
		(layer "F.Cu")
		(net "M_B_DQS_DN<3>")
	)
	(gr_poly
		(pts
			(xy 236.10316 -46.70679) (xy 236.09046 -46.51629) (xy 235.98886 -46.51629) (xy 235.97616 -46.70679)
			(xy 235.97616 -46.75759) (xy 236.10316 -46.75759)
		)
		(stroke
			(width 0)
			(type solid)
		)
		(fill yes)
		(layer "F.Cu")
		(net "M_B_DQS_DP<3>")
	)
	(gr_poly
		(pts
			(xy 236.10316 -46.31309) (xy 236.09046 -46.12259) (xy 235.98886 -46.12259) (xy 235.97616 -46.31309)
			(xy 235.97616 -46.36389) (xy 236.10316 -46.36389)
		)
		(stroke
			(width 0)
			(type solid)
		)
		(fill yes)
		(layer "F.Cu")
		(net "M_B_DQ<30>")
	)
	(gr_poly
		(pts
			(xy 236.10316 -45.91939) (xy 236.09046 -45.72889) (xy 235.98886 -45.72889) (xy 235.97616 -45.91939)
			(xy 235.97616 -45.97019) (xy 236.10316 -45.97019)
		)
		(stroke
			(width 0)
			(type solid)
		)
		(fill yes)
		(layer "F.Cu")
		(net "M_B_DQ<31>")
	)
	(gr_poly
		(pts
			(xy 236.10316 -45.52569) (xy 236.09046 -45.33519) (xy 235.98886 -45.33519) (xy 235.97616 -45.52569)
			(xy 235.97616 -45.57649) (xy 236.10316 -45.57649)
		)
		(stroke
			(width 0)
			(type solid)
		)
		(fill yes)
		(layer "F.Cu")
		(net "M_B_DQ<26>")
	)
	(gr_poly
		(pts
			(xy 236.43336 -49.17059) (xy 236.43336 -49.11979) (xy 236.30636 -49.11979) (xy 236.30636 -49.17059)
			(xy 236.31906 -49.36109) (xy 236.42066 -49.36109)
		)
		(stroke
			(width 0)
			(type solid)
		)
		(fill yes)
		(layer "F.Cu")
		(net "M_B_DQ<29>")
	)
	(gr_poly
		(pts
			(xy 236.43336 -48.77689) (xy 236.43336 -48.72609) (xy 236.30636 -48.72609) (xy 236.30636 -48.77689)
			(xy 236.31906 -48.96739) (xy 236.42066 -48.96739)
		)
		(stroke
			(width 0)
			(type solid)
		)
		(fill yes)
		(layer "F.Cu")
		(net "M_B_DQ<24>")
	)
	(gr_poly
		(pts
			(xy 236.43336 -48.38319) (xy 236.43336 -48.33239) (xy 236.30636 -48.33239) (xy 236.30636 -48.38319)
			(xy 236.31906 -48.57369) (xy 236.42066 -48.57369)
		)
		(stroke
			(width 0)
			(type solid)
		)
		(fill yes)
		(layer "F.Cu")
		(net "M_B_DQ<25>")
	)
	(gr_poly
		(pts
			(xy 236.43336 -47.98949) (xy 236.43336 -47.93869) (xy 236.30636 -47.93869) (xy 236.30636 -47.98949)
			(xy 236.31906 -48.17999) (xy 236.42066 -48.17999)
		)
		(stroke
			(width 0)
			(type solid)
		)
		(fill yes)
		(layer "F.Cu")
		(net "M_B_DQS_DP<12>")
	)
	(gr_poly
		(pts
			(xy 236.43336 -47.59579) (xy 236.43336 -47.54499) (xy 236.30636 -47.54499) (xy 236.30636 -47.59579)
			(xy 236.31906 -47.78629) (xy 236.42066 -47.78629)
		)
		(stroke
			(width 0)
			(type solid)
		)
		(fill yes)
		(layer "F.Cu")
		(net "M_B_DQS_DN<12>")
	)
	(gr_poly
		(pts
			(xy 236.43336 -47.20209) (xy 236.43336 -47.15129) (xy 236.30636 -47.15129) (xy 236.30636 -47.20209)
			(xy 236.31906 -47.39259) (xy 236.42066 -47.39259)
		)
		(stroke
			(width 0)
			(type solid)
		)
		(fill yes)
		(layer "F.Cu")
		(net "M_B_DQS_DN<3>")
	)
	(gr_poly
		(pts
			(xy 236.43336 -46.80839) (xy 236.43336 -46.75759) (xy 236.30636 -46.75759) (xy 236.30636 -46.80839)
			(xy 236.31906 -46.99889) (xy 236.42066 -46.99889)
		)
		(stroke
			(width 0)
			(type solid)
		)
		(fill yes)
		(layer "F.Cu")
		(net "M_B_DQS_DP<3>")
	)
	(gr_poly
		(pts
			(xy 236.43336 -46.41469) (xy 236.43336 -46.36389) (xy 236.30636 -46.36389) (xy 236.30636 -46.41469)
			(xy 236.31906 -46.60519) (xy 236.42066 -46.60519)
		)
		(stroke
			(width 0)
			(type solid)
		)
		(fill yes)
		(layer "F.Cu")
		(net "M_B_DQ<30>")
	)
	(gr_poly
		(pts
			(xy 236.43336 -46.02099) (xy 236.43336 -45.97019) (xy 236.30636 -45.97019) (xy 236.30636 -46.02099)
			(xy 236.31906 -46.21149) (xy 236.42066 -46.21149)
		)
		(stroke
			(width 0)
			(type solid)
		)
		(fill yes)
		(layer "F.Cu")
		(net "M_B_DQ<31>")
	)
	(gr_poly
		(pts
			(xy 236.43336 -45.62729) (xy 236.43336 -45.57649) (xy 236.30636 -45.57649) (xy 236.30636 -45.62729)
			(xy 236.31906 -45.81779) (xy 236.42066 -45.81779)
		)
		(stroke
			(width 0)
			(type solid)
		)
		(fill yes)
		(layer "F.Cu")
		(net "M_B_DQ<26>")
	)
	(gr_poly
		(pts
			(xy 236.43336 -45.23359) (xy 236.43336 -45.17009) (xy 236.30636 -45.17009) (xy 236.30636 -45.23359)
			(xy 236.31906 -45.42409) (xy 236.42066 -45.42409)
		)
		(stroke
			(width 0)
			(type solid)
		)
		(fill yes)
		(layer "F.Cu")
		(net "M_B_DQ<27>")
	)
	(gr_poly
		(pts
			(xy 236.597444 -103.027988) (xy 236.642402 -102.983284) (xy 236.516672 -102.857554) (xy 236.471714 -102.902258)
			(xy 236.424978 -102.999286) (xy 236.500416 -103.074724)
		)
		(stroke
			(width 0)
			(type solid)
		)
		(fill yes)
		(layer "F.Cu")
		(net "M_E_DQ<29>")
	)
	(gr_poly
		(pts
			(xy 236.76356 -49.46269) (xy 236.75086 -49.27219) (xy 236.64926 -49.27219) (xy 236.63656 -49.46269)
			(xy 236.63656 -49.52619) (xy 236.76356 -49.52619)
		)
		(stroke
			(width 0)
			(type solid)
		)
		(fill yes)
		(layer "F.Cu")
		(net "M_B_DQ<28>")
	)
	(gr_poly
		(pts
			(xy 236.76356 -49.06899) (xy 236.75086 -48.87849) (xy 236.64926 -48.87849) (xy 236.63656 -49.06899)
			(xy 236.63656 -49.11979) (xy 236.76356 -49.11979)
		)
		(stroke
			(width 0)
			(type solid)
		)
		(fill yes)
		(layer "F.Cu")
		(net "M_B_DQ<29>")
	)
	(gr_poly
		(pts
			(xy 236.76356 -48.67529) (xy 236.75086 -48.48479) (xy 236.64926 -48.48479) (xy 236.63656 -48.67529)
			(xy 236.63656 -48.72609) (xy 236.76356 -48.72609)
		)
		(stroke
			(width 0)
			(type solid)
		)
		(fill yes)
		(layer "F.Cu")
		(net "M_B_DQ<24>")
	)
	(gr_poly
		(pts
			(xy 236.76356 -48.28159) (xy 236.75086 -48.09109) (xy 236.64926 -48.09109) (xy 236.63656 -48.28159)
			(xy 236.63656 -48.33239) (xy 236.76356 -48.33239)
		)
		(stroke
			(width 0)
			(type solid)
		)
		(fill yes)
		(layer "F.Cu")
		(net "M_B_DQ<25>")
	)
	(gr_poly
		(pts
			(xy 236.76356 -47.88789) (xy 236.75086 -47.69739) (xy 236.64926 -47.69739) (xy 236.63656 -47.88789)
			(xy 236.63656 -47.93869) (xy 236.76356 -47.93869)
		)
		(stroke
			(width 0)
			(type solid)
		)
		(fill yes)
		(layer "F.Cu")
		(net "M_B_DQS_DP<12>")
	)
	(gr_poly
		(pts
			(xy 236.76356 -47.49419) (xy 236.75086 -47.30369) (xy 236.64926 -47.30369) (xy 236.63656 -47.49419)
			(xy 236.63656 -47.54499) (xy 236.76356 -47.54499)
		)
		(stroke
			(width 0)
			(type solid)
		)
		(fill yes)
		(layer "F.Cu")
		(net "M_B_DQS_DN<12>")
	)
	(gr_poly
		(pts
			(xy 236.76356 -47.10049) (xy 236.75086 -46.90999) (xy 236.64926 -46.90999) (xy 236.63656 -47.10049)
			(xy 236.63656 -47.15129) (xy 236.76356 -47.15129)
		)
		(stroke
			(width 0)
			(type solid)
		)
		(fill yes)
		(layer "F.Cu")
		(net "M_B_DQS_DN<3>")
	)
	(gr_poly
		(pts
			(xy 236.76356 -46.70679) (xy 236.75086 -46.51629) (xy 236.64926 -46.51629) (xy 236.63656 -46.70679)
			(xy 236.63656 -46.75759) (xy 236.76356 -46.75759)
		)
		(stroke
			(width 0)
			(type solid)
		)
		(fill yes)
		(layer "F.Cu")
		(net "M_B_DQS_DP<3>")
	)
	(gr_poly
		(pts
			(xy 236.76356 -46.31309) (xy 236.75086 -46.12259) (xy 236.64926 -46.12259) (xy 236.63656 -46.31309)
			(xy 236.63656 -46.36389) (xy 236.76356 -46.36389)
		)
		(stroke
			(width 0)
			(type solid)
		)
		(fill yes)
		(layer "F.Cu")
		(net "M_B_DQ<30>")
	)
	(gr_poly
		(pts
			(xy 236.76356 -45.91939) (xy 236.75086 -45.72889) (xy 236.64926 -45.72889) (xy 236.63656 -45.91939)
			(xy 236.63656 -45.97019) (xy 236.76356 -45.97019)
		)
		(stroke
			(width 0)
			(type solid)
		)
		(fill yes)
		(layer "F.Cu")
		(net "M_B_DQ<31>")
	)
	(gr_poly
		(pts
			(xy 236.76356 -45.52569) (xy 236.75086 -45.33519) (xy 236.64926 -45.33519) (xy 236.63656 -45.52569)
			(xy 236.63656 -45.57649) (xy 236.76356 -45.57649)
		)
		(stroke
			(width 0)
			(type solid)
		)
		(fill yes)
		(layer "F.Cu")
		(net "M_B_DQ<26>")
	)
	(gr_poly
		(pts
			(xy 236.796072 -104.190546) (xy 236.796072 -104.139746) (xy 236.618272 -104.139746) (xy 236.618272 -104.190546)
			(xy 236.653832 -104.292146) (xy 236.760512 -104.292146)
		)
		(stroke
			(width 0)
			(type solid)
		)
		(fill yes)
		(layer "F.Cu")
		(net "M_E_DQ<25>")
	)
	(gr_poly
		(pts
			(xy 236.81309 -102.812342) (xy 236.857794 -102.767384) (xy 236.732318 -102.641908) (xy 236.68736 -102.686612)
			(xy 236.640624 -102.78364) (xy 236.716062 -102.859078)
		)
		(stroke
			(width 0)
			(type solid)
		)
		(fill yes)
		(layer "F.Cu")
		(net "M_E_DQ<28>")
	)
	(gr_poly
		(pts
			(xy 236.82198 -103.10876) (xy 236.868716 -103.011732) (xy 236.793278 -102.936294) (xy 236.69625 -102.98303)
			(xy 236.660436 -103.019098) (xy 236.786166 -103.144828)
		)
		(stroke
			(width 0)
			(type solid)
		)
		(fill yes)
		(layer "F.Cu")
		(net "M_E_DQ<29>")
	)
	(gr_poly
		(pts
			(xy 236.902752 -103.333296) (xy 236.94771 -103.288592) (xy 236.82198 -103.162862) (xy 236.777022 -103.207566)
			(xy 236.730286 -103.304594) (xy 236.805724 -103.380032)
		)
		(stroke
			(width 0)
			(type solid)
		)
		(fill yes)
		(layer "F.Cu")
		(net "M_E_DQ<29>")
	)
	(gr_poly
		(pts
			(xy 237.011972 -104.088946) (xy 236.976412 -103.987346) (xy 236.869732 -103.987346) (xy 236.834172 -104.088946)
			(xy 236.834172 -104.139746) (xy 237.011972 -104.139746)
		)
		(stroke
			(width 0)
			(type solid)
		)
		(fill yes)
		(layer "F.Cu")
		(net "M_E_DQ<25>")
	)
	(gr_poly
		(pts
			(xy 237.09376 -49.17059) (xy 237.09376 -49.11979) (xy 236.96676 -49.11979) (xy 236.96676 -49.17059)
			(xy 236.97946 -49.36109) (xy 237.08106 -49.36109)
		)
		(stroke
			(width 0)
			(type solid)
		)
		(fill yes)
		(layer "F.Cu")
		(net "M_B_DQ<29>")
	)
	(gr_poly
		(pts
			(xy 237.09376 -48.77689) (xy 237.09376 -48.72609) (xy 236.96676 -48.72609) (xy 236.96676 -48.77689)
			(xy 236.97946 -48.96739) (xy 237.08106 -48.96739)
		)
		(stroke
			(width 0)
			(type solid)
		)
		(fill yes)
		(layer "F.Cu")
		(net "M_B_DQ<24>")
	)
	(gr_poly
		(pts
			(xy 237.09376 -48.38319) (xy 237.09376 -48.33239) (xy 236.96676 -48.33239) (xy 236.96676 -48.38319)
			(xy 236.97946 -48.57369) (xy 237.08106 -48.57369)
		)
		(stroke
			(width 0)
			(type solid)
		)
		(fill yes)
		(layer "F.Cu")
		(net "M_B_DQ<25>")
	)
	(gr_poly
		(pts
			(xy 237.09376 -47.98949) (xy 237.09376 -47.93869) (xy 236.96676 -47.93869) (xy 236.96676 -47.98949)
			(xy 236.97946 -48.17999) (xy 237.08106 -48.17999)
		)
		(stroke
			(width 0)
			(type solid)
		)
		(fill yes)
		(layer "F.Cu")
		(net "M_B_DQS_DP<12>")
	)
	(gr_poly
		(pts
			(xy 237.09376 -47.59579) (xy 237.09376 -47.54499) (xy 236.96676 -47.54499) (xy 236.96676 -47.59579)
			(xy 236.97946 -47.78629) (xy 237.08106 -47.78629)
		)
		(stroke
			(width 0)
			(type solid)
		)
		(fill yes)
		(layer "F.Cu")
		(net "M_B_DQS_DN<12>")
	)
	(gr_poly
		(pts
			(xy 237.09376 -47.20209) (xy 237.09376 -47.15129) (xy 236.96676 -47.15129) (xy 236.96676 -47.20209)
			(xy 236.97946 -47.39259) (xy 237.08106 -47.39259)
		)
		(stroke
			(width 0)
			(type solid)
		)
		(fill yes)
		(layer "F.Cu")
		(net "M_B_DQS_DN<3>")
	)
	(gr_poly
		(pts
			(xy 237.09376 -46.80839) (xy 237.09376 -46.75759) (xy 236.96676 -46.75759) (xy 236.96676 -46.80839)
			(xy 236.97946 -46.99889) (xy 237.08106 -46.99889)
		)
		(stroke
			(width 0)
			(type solid)
		)
		(fill yes)
		(layer "F.Cu")
		(net "M_B_DQS_DP<3>")
	)
	(gr_poly
		(pts
			(xy 237.09376 -46.41469) (xy 237.09376 -46.36389) (xy 236.96676 -46.36389) (xy 236.96676 -46.41469)
			(xy 236.97946 -46.60519) (xy 237.08106 -46.60519)
		)
		(stroke
			(width 0)
			(type solid)
		)
		(fill yes)
		(layer "F.Cu")
		(net "M_B_DQ<30>")
	)
	(gr_poly
		(pts
			(xy 237.09376 -46.02099) (xy 237.09376 -45.97019) (xy 236.96676 -45.97019) (xy 236.96676 -46.02099)
			(xy 236.97946 -46.21149) (xy 237.08106 -46.21149)
		)
		(stroke
			(width 0)
			(type solid)
		)
		(fill yes)
		(layer "F.Cu")
		(net "M_B_DQ<31>")
	)
	(gr_poly
		(pts
			(xy 237.09376 -45.62729) (xy 237.09376 -45.57649) (xy 236.96676 -45.57649) (xy 236.96676 -45.62729)
			(xy 236.97946 -45.81779) (xy 237.08106 -45.81779)
		)
		(stroke
			(width 0)
			(type solid)
		)
		(fill yes)
		(layer "F.Cu")
		(net "M_B_DQ<26>")
	)
	(gr_poly
		(pts
			(xy 237.09376 -45.23359) (xy 237.09376 -45.17009) (xy 236.96676 -45.17009) (xy 236.96676 -45.23359)
			(xy 236.97946 -45.42409) (xy 237.08106 -45.42409)
		)
		(stroke
			(width 0)
			(type solid)
		)
		(fill yes)
		(layer "F.Cu")
		(net "M_B_DQ<27>")
	)
	(gr_poly
		(pts
			(xy 237.118398 -103.11765) (xy 237.163356 -103.072946) (xy 237.037626 -102.947216) (xy 236.992668 -102.99192)
			(xy 236.945932 -103.088948) (xy 237.02137 -103.164386)
		)
		(stroke
			(width 0)
			(type solid)
		)
		(fill yes)
		(layer "F.Cu")
		(net "M_E_DQ<28>")
	)
	(gr_poly
		(pts
			(xy 237.127288 -103.414068) (xy 237.174024 -103.31704) (xy 237.098586 -103.241602) (xy 237.001558 -103.288338)
			(xy 236.965744 -103.324406) (xy 237.091474 -103.450136)
		)
		(stroke
			(width 0)
			(type solid)
		)
		(fill yes)
		(layer "F.Cu")
		(net "M_E_DQ<29>")
	)
	(gr_poly
		(pts
			(xy 237.227872 -104.190546) (xy 237.227872 -104.139746) (xy 237.050072 -104.139746) (xy 237.050072 -104.190546)
			(xy 237.085632 -104.292146) (xy 237.192312 -104.292146)
		)
		(stroke
			(width 0)
			(type solid)
		)
		(fill yes)
		(layer "F.Cu")
		(net "M_E_DQ<25>")
	)
	(gr_poly
		(pts
			(xy 237.227872 -103.885746) (xy 237.227872 -103.834946) (xy 237.050072 -103.834946) (xy 237.050072 -103.885746)
			(xy 237.085632 -103.987346) (xy 237.192312 -103.987346)
		)
		(stroke
			(width 0)
			(type solid)
		)
		(fill yes)
		(layer "F.Cu")
		(net "M_E_DQ<24>")
	)
	(gr_poly
		(pts
			(xy 237.42396 -49.06899) (xy 237.41126 -48.87849) (xy 237.30966 -48.87849) (xy 237.29696 -49.06899)
			(xy 237.29696 -49.11979) (xy 237.42396 -49.11979)
		)
		(stroke
			(width 0)
			(type solid)
		)
		(fill yes)
		(layer "F.Cu")
		(net "M_B_DQ<29>")
	)
	(gr_poly
		(pts
			(xy 237.42396 -48.28159) (xy 237.41126 -48.09109) (xy 237.30966 -48.09109) (xy 237.29696 -48.28159)
			(xy 237.29696 -48.33239) (xy 237.42396 -48.33239)
		)
		(stroke
			(width 0)
			(type solid)
		)
		(fill yes)
		(layer "F.Cu")
		(net "M_B_DQ<25>")
	)
	(gr_poly
		(pts
			(xy 237.42396 -47.88789) (xy 237.41126 -47.69739) (xy 237.30966 -47.69739) (xy 237.29696 -47.88789)
			(xy 237.29696 -47.93869) (xy 237.42396 -47.93869)
		)
		(stroke
			(width 0)
			(type solid)
		)
		(fill yes)
		(layer "F.Cu")
		(net "M_B_DQS_DP<12>")
	)
	(gr_poly
		(pts
			(xy 237.42396 -47.49419) (xy 237.41126 -47.30369) (xy 237.30966 -47.30369) (xy 237.29696 -47.49419)
			(xy 237.29696 -47.54499) (xy 237.42396 -47.54499)
		)
		(stroke
			(width 0)
			(type solid)
		)
		(fill yes)
		(layer "F.Cu")
		(net "M_B_DQS_DN<12>")
	)
	(gr_poly
		(pts
			(xy 237.42396 -47.10049) (xy 237.41126 -46.90999) (xy 237.30966 -46.90999) (xy 237.29696 -47.10049)
			(xy 237.29696 -47.15129) (xy 237.42396 -47.15129)
		)
		(stroke
			(width 0)
			(type solid)
		)
		(fill yes)
		(layer "F.Cu")
		(net "M_B_DQS_DN<3>")
	)
	(gr_poly
		(pts
			(xy 237.42396 -46.70679) (xy 237.41126 -46.51629) (xy 237.30966 -46.51629) (xy 237.29696 -46.70679)
			(xy 237.29696 -46.75759) (xy 237.42396 -46.75759)
		)
		(stroke
			(width 0)
			(type solid)
		)
		(fill yes)
		(layer "F.Cu")
		(net "M_B_DQS_DP<3>")
	)
	(gr_poly
		(pts
			(xy 237.42396 -46.31309) (xy 237.41126 -46.12259) (xy 237.30966 -46.12259) (xy 237.29696 -46.31309)
			(xy 237.29696 -46.36389) (xy 237.42396 -46.36389)
		)
		(stroke
			(width 0)
			(type solid)
		)
		(fill yes)
		(layer "F.Cu")
		(net "M_B_DQ<30>")
	)
	(gr_poly
		(pts
			(xy 237.42396 -45.91939) (xy 237.41126 -45.72889) (xy 237.30966 -45.72889) (xy 237.29696 -45.91939)
			(xy 237.29696 -45.97019) (xy 237.42396 -45.97019)
		)
		(stroke
			(width 0)
			(type solid)
		)
		(fill yes)
		(layer "F.Cu")
		(net "M_B_DQ<31>")
	)
	(gr_poly
		(pts
			(xy 237.42396 -45.52569) (xy 237.41126 -45.33519) (xy 237.30966 -45.33519) (xy 237.29696 -45.52569)
			(xy 237.29696 -45.57649) (xy 237.42396 -45.57649)
		)
		(stroke
			(width 0)
			(type solid)
		)
		(fill yes)
		(layer "F.Cu")
		(net "M_B_DQ<26>")
	)
	(gr_poly
		(pts
			(xy 237.443772 -104.088946) (xy 237.408212 -103.987346) (xy 237.301532 -103.987346) (xy 237.265972 -104.088946)
			(xy 237.265972 -104.139746) (xy 237.443772 -104.139746)
		)
		(stroke
			(width 0)
			(type solid)
		)
		(fill yes)
		(layer "F.Cu")
		(net "M_E_DQ<25>")
	)
	(gr_poly
		(pts
			(xy 237.443772 -103.784146) (xy 237.408212 -103.682546) (xy 237.301532 -103.682546) (xy 237.265972 -103.784146)
			(xy 237.265972 -103.834946) (xy 237.443772 -103.834946)
		)
		(stroke
			(width 0)
			(type solid)
		)
		(fill yes)
		(layer "F.Cu")
		(net "M_E_DQ<24>")
	)
	(gr_poly
		(pts
			(xy 237.443772 -103.479346) (xy 237.408212 -103.377746) (xy 237.301532 -103.377746) (xy 237.265972 -103.479346)
			(xy 237.265972 -103.530146) (xy 237.443772 -103.530146)
		)
		(stroke
			(width 0)
			(type solid)
		)
		(fill yes)
		(layer "F.Cu")
		(net "M_E_DQ<29>")
	)
	(gr_poly
		(pts
			(xy 237.58779 -108.245148) (xy 237.542832 -108.200444) (xy 237.445804 -108.153708) (xy 237.370366 -108.229146)
			(xy 237.417102 -108.326174) (xy 237.46206 -108.370878)
		)
		(stroke
			(width 0)
			(type solid)
		)
		(fill yes)
		(layer "F.Cu")
		(net "M_E_DQ<27>")
	)
	(gr_poly
		(pts
			(xy 237.598458 -108.001054) (xy 237.551722 -107.904026) (xy 237.515908 -107.867958) (xy 237.390178 -107.993688)
			(xy 237.425992 -108.029756) (xy 237.52302 -108.076238)
		)
		(stroke
			(width 0)
			(type solid)
		)
		(fill yes)
		(layer "F.Cu")
		(net "M_E_DQ<26>")
	)
	(gr_poly
		(pts
			(xy 237.65256 -49.46269) (xy 237.617 -49.36109) (xy 237.51032 -49.36109) (xy 237.47476 -49.46269)
			(xy 237.47476 -49.52619) (xy 237.65256 -49.52619)
		)
		(stroke
			(width 0)
			(type solid)
		)
		(fill yes)
		(layer "F.Cu")
		(net "M_B_DQ<28>")
	)
	(gr_poly
		(pts
			(xy 237.659672 -104.190546) (xy 237.659672 -104.139746) (xy 237.481872 -104.139746) (xy 237.481872 -104.190546)
			(xy 237.517432 -104.292146) (xy 237.624112 -104.292146)
		)
		(stroke
			(width 0)
			(type solid)
		)
		(fill yes)
		(layer "F.Cu")
		(net "M_E_DQ<25>")
	)
	(gr_poly
		(pts
			(xy 237.659672 -103.885746) (xy 237.659672 -103.834946) (xy 237.481872 -103.834946) (xy 237.481872 -103.885746)
			(xy 237.517432 -103.987346) (xy 237.624112 -103.987346)
		)
		(stroke
			(width 0)
			(type solid)
		)
		(fill yes)
		(layer "F.Cu")
		(net "M_E_DQ<24>")
	)
	(gr_poly
		(pts
			(xy 237.659672 -103.580946) (xy 237.659672 -103.530146) (xy 237.481872 -103.530146) (xy 237.481872 -103.580946)
			(xy 237.517432 -103.682546) (xy 237.624112 -103.682546)
		)
		(stroke
			(width 0)
			(type solid)
		)
		(fill yes)
		(layer "F.Cu")
		(net "M_E_DQ<29>")
	)
	(gr_poly
		(pts
			(xy 237.659672 -103.276146) (xy 237.659672 -103.212646) (xy 237.481872 -103.212646) (xy 237.481872 -103.276146)
			(xy 237.517432 -103.377746) (xy 237.624112 -103.377746)
		)
		(stroke
			(width 0)
			(type solid)
		)
		(fill yes)
		(layer "F.Cu")
		(net "M_E_DQ<28>")
	)
	(gr_poly
		(pts
			(xy 237.668308 -48.545496) (xy 237.704122 -48.509428) (xy 237.578392 -48.383698) (xy 237.542578 -48.419766)
			(xy 237.495842 -48.516794) (xy 237.57128 -48.592232)
		)
		(stroke
			(width 0)
			(type solid)
		)
		(fill yes)
		(layer "F.Cu")
		(net "M_B_DQ<25>")
	)
	(gr_poly
		(pts
			(xy 237.668562 -107.715304) (xy 237.632494 -107.67949) (xy 237.53572 -107.632754) (xy 237.460282 -107.708192)
			(xy 237.506764 -107.80522) (xy 237.542832 -107.841034)
		)
		(stroke
			(width 0)
			(type solid)
		)
		(fill yes)
		(layer "F.Cu")
		(net "M_E_DQ<26>")
	)
	(gr_poly
		(pts
			(xy 237.677198 -48.841914) (xy 237.723934 -48.744886) (xy 237.648496 -48.669448) (xy 237.551468 -48.716184)
			(xy 237.5154 -48.751998) (xy 237.64113 -48.877728)
		)
		(stroke
			(width 0)
			(type solid)
		)
		(fill yes)
		(layer "F.Cu")
		(net "M_B_DQ<24>")
	)
	(gr_poly
		(pts
			(xy 237.71352 -47.58436) (xy 237.760256 -47.487332) (xy 237.684818 -47.411894) (xy 237.58779 -47.45863)
			(xy 237.551722 -47.494444) (xy 237.677452 -47.620174)
		)
		(stroke
			(width 0)
			(type solid)
		)
		(fill yes)
		(layer "F.Cu")
		(net "M_B_DQS_DN<12>")
	)
	(gr_poly
		(pts
			(xy 237.75416 -45.23359) (xy 237.75416 -45.17009) (xy 237.62716 -45.17009) (xy 237.62716 -45.23359)
			(xy 237.63986 -45.42409) (xy 237.74146 -45.42409)
		)
		(stroke
			(width 0)
			(type solid)
		)
		(fill yes)
		(layer "F.Cu")
		(net "M_B_DQ<27>")
	)
	(gr_poly
		(pts
			(xy 237.794292 -47.808896) (xy 237.830106 -47.772828) (xy 237.704376 -47.647098) (xy 237.668562 -47.683166)
			(xy 237.621826 -47.780194) (xy 237.697264 -47.855632)
		)
		(stroke
			(width 0)
			(type solid)
		)
		(fill yes)
		(layer "F.Cu")
		(net "M_B_DQS_DN<12>")
	)
	(gr_poly
		(pts
			(xy 237.803182 -48.105314) (xy 237.849918 -48.008286) (xy 237.77448 -47.932848) (xy 237.677452 -47.979584)
			(xy 237.641384 -48.015398) (xy 237.767114 -48.141128)
		)
		(stroke
			(width 0)
			(type solid)
		)
		(fill yes)
		(layer "F.Cu")
		(net "M_B_DQS_DP<12>")
	)
	(gr_poly
		(pts
			(xy 237.839504 -46.84776) (xy 237.88624 -46.750732) (xy 237.810802 -46.675294) (xy 237.713774 -46.72203)
			(xy 237.677706 -46.757844) (xy 237.803436 -46.883574)
		)
		(stroke
			(width 0)
			(type solid)
		)
		(fill yes)
		(layer "F.Cu")
		(net "M_B_DQS_DP<3>")
	)
	(gr_poly
		(pts
			(xy 237.86846 -49.25949) (xy 237.86846 -49.20869) (xy 237.69066 -49.20869) (xy 237.69066 -49.25949)
			(xy 237.72622 -49.36109) (xy 237.8329 -49.36109)
		)
		(stroke
			(width 0)
			(type solid)
		)
		(fill yes)
		(layer "F.Cu")
		(net "M_B_DQ<29>")
	)
	(gr_poly
		(pts
			(xy 237.875572 -104.088946) (xy 237.840012 -103.987346) (xy 237.733332 -103.987346) (xy 237.697772 -104.088946)
			(xy 237.697772 -104.139746) (xy 237.875572 -104.139746)
		)
		(stroke
			(width 0)
			(type solid)
		)
		(fill yes)
		(layer "F.Cu")
		(net "M_E_DQ<25>")
	)
	(gr_poly
		(pts
			(xy 237.875572 -103.784146) (xy 237.840012 -103.682546) (xy 237.733332 -103.682546) (xy 237.697772 -103.784146)
			(xy 237.697772 -103.834946) (xy 237.875572 -103.834946)
		)
		(stroke
			(width 0)
			(type solid)
		)
		(fill yes)
		(layer "F.Cu")
		(net "M_E_DQ<24>")
	)
	(gr_poly
		(pts
			(xy 237.875572 -103.479346) (xy 237.840012 -103.377746) (xy 237.733332 -103.377746) (xy 237.697772 -103.479346)
			(xy 237.697772 -103.530146) (xy 237.875572 -103.530146)
		)
		(stroke
			(width 0)
			(type solid)
		)
		(fill yes)
		(layer "F.Cu")
		(net "M_E_DQ<29>")
	)
	(gr_poly
		(pts
			(xy 237.883954 -48.32985) (xy 237.919768 -48.293782) (xy 237.794038 -48.168052) (xy 237.758224 -48.20412)
			(xy 237.711488 -48.301148) (xy 237.786926 -48.376586)
		)
		(stroke
			(width 0)
			(type solid)
		)
		(fill yes)
		(layer "F.Cu")
		(net "M_B_DQS_DP<12>")
	)
	(gr_poly
		(pts
			(xy 237.893098 -107.93984) (xy 237.84814 -107.895136) (xy 237.751112 -107.8484) (xy 237.675674 -107.923838)
			(xy 237.72241 -108.020612) (xy 237.767368 -108.06557)
		)
		(stroke
			(width 0)
			(type solid)
		)
		(fill yes)
		(layer "F.Cu")
		(net "M_E_DQ<27>")
	)
	(gr_poly
		(pts
			(xy 237.903766 -107.695746) (xy 237.85703 -107.598718) (xy 237.821216 -107.56265) (xy 237.695486 -107.68838)
			(xy 237.7313 -107.724448) (xy 237.828328 -107.77093)
		)
		(stroke
			(width 0)
			(type solid)
		)
		(fill yes)
		(layer "F.Cu")
		(net "M_E_DQ<26>")
	)
	(gr_poly
		(pts
			(xy 237.920276 -47.072296) (xy 237.95609 -47.036228) (xy 237.83036 -46.910498) (xy 237.794546 -46.946566)
			(xy 237.74781 -47.043594) (xy 237.823248 -47.119032)
		)
		(stroke
			(width 0)
			(type solid)
		)
		(fill yes)
		(layer "F.Cu")
		(net "M_B_DQS_DP<3>")
	)
	(gr_poly
		(pts
			(xy 237.929166 -47.368714) (xy 237.975902 -47.271686) (xy 237.900464 -47.196248) (xy 237.803436 -47.242984)
			(xy 237.767368 -47.278798) (xy 237.893098 -47.404528)
		)
		(stroke
			(width 0)
			(type solid)
		)
		(fill yes)
		(layer "F.Cu")
		(net "M_B_DQS_DN<3>")
	)
	(gr_poly
		(pts
			(xy 237.956598 -45.814742) (xy 237.992412 -45.778674) (xy 237.866682 -45.652944) (xy 237.830868 -45.689012)
			(xy 237.784132 -45.785786) (xy 237.85957 -45.861224)
		)
		(stroke
			(width 0)
			(type solid)
		)
		(fill yes)
		(layer "F.Cu")
		(net "M_B_DQ<26>")
	)
	(gr_poly
		(pts
			(xy 237.965488 -46.11116) (xy 238.012224 -46.014132) (xy 237.936786 -45.938694) (xy 237.839758 -45.98543)
			(xy 237.80369 -46.021244) (xy 237.92942 -46.146974)
		)
		(stroke
			(width 0)
			(type solid)
		)
		(fill yes)
		(layer "F.Cu")
		(net "M_B_DQ<31>")
	)
	(gr_poly
		(pts
			(xy 237.97387 -107.409996) (xy 237.937802 -107.374182) (xy 237.841028 -107.327446) (xy 237.76559 -107.402884)
			(xy 237.812072 -107.499912) (xy 237.84814 -107.535726)
		)
		(stroke
			(width 0)
			(type solid)
		)
		(fill yes)
		(layer "F.Cu")
		(net "M_E_DQ<26>")
	)
	(gr_poly
		(pts
			(xy 237.993428 -107.174538) (xy 237.946692 -107.077764) (xy 237.910878 -107.041696) (xy 237.785148 -107.167426)
			(xy 237.820962 -107.203494) (xy 237.91799 -107.249976)
		)
		(stroke
			(width 0)
			(type solid)
		)
		(fill yes)
		(layer "F.Cu")
		(net "M_E_DQ<31>")
	)
	(gr_poly
		(pts
			(xy 238.009938 -47.59325) (xy 238.045752 -47.557182) (xy 237.920022 -47.431452) (xy 237.884208 -47.46752)
			(xy 237.837472 -47.564548) (xy 237.91291 -47.639986)
		)
		(stroke
			(width 0)
			(type solid)
		)
		(fill yes)
		(layer "F.Cu")
		(net "M_B_DQS_DN<3>")
	)
	(gr_poly
		(pts
			(xy 238.018828 -47.889668) (xy 238.065564 -47.79264) (xy 237.990126 -47.717202) (xy 237.893098 -47.763938)
			(xy 237.85703 -47.799752) (xy 237.98276 -47.925482)
		)
		(stroke
			(width 0)
			(type solid)
		)
		(fill yes)
		(layer "F.Cu")
		(net "M_B_DQS_DN<12>")
	)
	(gr_poly
		(pts
			(xy 238.04626 -46.335696) (xy 238.082074 -46.299628) (xy 237.956344 -46.173898) (xy 237.92053 -46.209966)
			(xy 237.873794 -46.306994) (xy 237.949232 -46.382432)
		)
		(stroke
			(width 0)
			(type solid)
		)
		(fill yes)
		(layer "F.Cu")
		(net "M_B_DQ<31>")
	)
	(gr_poly
		(pts
			(xy 238.05515 -46.632114) (xy 238.101886 -46.535086) (xy 238.026448 -46.459648) (xy 237.92942 -46.506384)
			(xy 237.893352 -46.542198) (xy 238.019082 -46.667928)
		)
		(stroke
			(width 0)
			(type solid)
		)
		(fill yes)
		(layer "F.Cu")
		(net "M_B_DQ<30>")
	)
	(gr_poly
		(pts
			(xy 238.063532 -106.889042) (xy 238.027464 -106.853228) (xy 237.93069 -106.806492) (xy 237.855252 -106.88193)
			(xy 237.901734 -106.978958) (xy 237.937802 -107.014772)
		)
		(stroke
			(width 0)
			(type solid)
		)
		(fill yes)
		(layer "F.Cu")
		(net "M_E_DQ<31>")
	)
	(gr_poly
		(pts
			(xy 238.08309 -106.653584) (xy 238.036354 -106.556556) (xy 238.00054 -106.520742) (xy 237.87481 -106.646472)
			(xy 237.910624 -106.682286) (xy 238.007652 -106.729022)
		)
		(stroke
			(width 0)
			(type solid)
		)
		(fill yes)
		(layer "F.Cu")
		(net "M_E_DQ<30>")
	)
	(gr_poly
		(pts
			(xy 238.08436 -49.46269) (xy 238.0488 -49.36109) (xy 237.94212 -49.36109) (xy 237.90656 -49.46269)
			(xy 237.90656 -49.52619) (xy 238.08436 -49.52619)
		)
		(stroke
			(width 0)
			(type solid)
		)
		(fill yes)
		(layer "F.Cu")
		(net "M_B_DQ<28>")
	)
	(gr_poly
		(pts
			(xy 238.08436 -49.15789) (xy 238.0488 -49.05629) (xy 237.94212 -49.05629) (xy 237.90656 -49.15789)
			(xy 237.90656 -49.20869) (xy 238.08436 -49.20869)
		)
		(stroke
			(width 0)
			(type solid)
		)
		(fill yes)
		(layer "F.Cu")
		(net "M_B_DQ<29>")
	)
	(gr_poly
		(pts
			(xy 238.08436 -48.85309) (xy 238.0488 -48.75149) (xy 237.94212 -48.75149) (xy 237.90656 -48.85309)
			(xy 237.90656 -48.90389) (xy 238.08436 -48.90389)
		)
		(stroke
			(width 0)
			(type solid)
		)
		(fill yes)
		(layer "F.Cu")
		(net "M_B_DQ<24>")
	)
	(gr_poly
		(pts
			(xy 238.091472 -104.190546) (xy 238.091472 -104.139746) (xy 237.913672 -104.139746) (xy 237.913672 -104.190546)
			(xy 237.949232 -104.292146) (xy 238.055912 -104.292146)
		)
		(stroke
			(width 0)
			(type solid)
		)
		(fill yes)
		(layer "F.Cu")
		(net "M_E_DQ<25>")
	)
	(gr_poly
		(pts
			(xy 238.091472 -103.885746) (xy 238.091472 -103.834946) (xy 237.913672 -103.834946) (xy 237.913672 -103.885746)
			(xy 237.949232 -103.987346) (xy 238.055912 -103.987346)
		)
		(stroke
			(width 0)
			(type solid)
		)
		(fill yes)
		(layer "F.Cu")
		(net "M_E_DQ<24>")
	)
	(gr_poly
		(pts
			(xy 238.135922 -46.85665) (xy 238.171736 -46.820582) (xy 238.046006 -46.694852) (xy 238.010192 -46.73092)
			(xy 237.963456 -46.827948) (xy 238.038894 -46.903386)
		)
		(stroke
			(width 0)
			(type solid)
		)
		(fill yes)
		(layer "F.Cu")
		(net "M_B_DQ<30>")
	)
	(gr_poly
		(pts
			(xy 238.144812 -47.153068) (xy 238.191548 -47.05604) (xy 238.11611 -46.980602) (xy 238.019082 -47.027338)
			(xy 237.983014 -47.063152) (xy 238.108744 -47.188882)
		)
		(stroke
			(width 0)
			(type solid)
		)
		(fill yes)
		(layer "F.Cu")
		(net "M_B_DQS_DP<3>")
	)
	(gr_poly
		(pts
			(xy 238.153194 -106.368088) (xy 238.11738 -106.332274) (xy 238.020352 -106.285538) (xy 237.944914 -106.360976)
			(xy 237.99165 -106.458004) (xy 238.027464 -106.493818)
		)
		(stroke
			(width 0)
			(type solid)
		)
		(fill yes)
		(layer "F.Cu")
		(net "M_E_DQ<30>")
	)
	(gr_poly
		(pts
			(xy 238.169196 -103.33101) (xy 238.133382 -103.294942) (xy 238.036354 -103.248206) (xy 237.960916 -103.323644)
			(xy 238.007652 -103.420672) (xy 238.043466 -103.45674)
		)
		(stroke
			(width 0)
			(type solid)
		)
		(fill yes)
		(layer "F.Cu")
		(net "M_E_DQ<29>")
	)
	(gr_poly
		(pts
			(xy 238.17199 -45.599096) (xy 238.216948 -45.554138) (xy 238.091218 -45.428408) (xy 238.04626 -45.473366)
			(xy 237.999778 -45.570394) (xy 238.075216 -45.645832)
		)
		(stroke
			(width 0)
			(type solid)
		)
		(fill yes)
		(layer "F.Cu")
		(net "M_B_DQ<27>")
	)
	(gr_poly
		(pts
			(xy 238.181134 -45.895514) (xy 238.227616 -45.798486) (xy 238.152178 -45.723048) (xy 238.055404 -45.769784)
			(xy 238.019336 -45.805598) (xy 238.145066 -45.931328)
		)
		(stroke
			(width 0)
			(type solid)
		)
		(fill yes)
		(layer "F.Cu")
		(net "M_B_DQ<26>")
	)
	(gr_poly
		(pts
			(xy 238.189008 -103.095552) (xy 238.142272 -102.998524) (xy 238.097314 -102.95382) (xy 237.971584 -103.07955)
			(xy 238.016542 -103.124254) (xy 238.11357 -103.17099)
		)
		(stroke
			(width 0)
			(type solid)
		)
		(fill yes)
		(layer "F.Cu")
		(net "M_E_DQ<28>")
	)
	(gr_poly
		(pts
			(xy 238.198406 -107.634532) (xy 238.153448 -107.589574) (xy 238.05642 -107.543092) (xy 237.980982 -107.61853)
			(xy 238.027718 -107.715304) (xy 238.072676 -107.760262)
		)
		(stroke
			(width 0)
			(type solid)
		)
		(fill yes)
		(layer "F.Cu")
		(net "M_E_DQ<27>")
	)
	(gr_poly
		(pts
			(xy 238.206534 -104.58958) (xy 238.17072 -104.553512) (xy 238.073692 -104.506776) (xy 237.998254 -104.582214)
			(xy 238.04499 -104.679242) (xy 238.080804 -104.71531)
		)
		(stroke
			(width 0)
			(type solid)
		)
		(fill yes)
		(layer "F.Cu")
		(net "M_E_DQS_DP<12>")
	)
	(gr_poly
		(pts
			(xy 238.209074 -107.390184) (xy 238.162338 -107.29341) (xy 238.126524 -107.257342) (xy 238.000794 -107.383072)
			(xy 238.036608 -107.41914) (xy 238.133636 -107.465622)
		)
		(stroke
			(width 0)
			(type solid)
		)
		(fill yes)
		(layer "F.Cu")
		(net "M_E_DQ<26>")
	)
	(gr_poly
		(pts
			(xy 238.225584 -47.377604) (xy 238.261398 -47.341536) (xy 238.135668 -47.215806) (xy 238.099854 -47.251874)
			(xy 238.053118 -47.348902) (xy 238.128556 -47.42434)
		)
		(stroke
			(width 0)
			(type solid)
		)
		(fill yes)
		(layer "F.Cu")
		(net "M_B_DQS_DP<3>")
	)
	(gr_poly
		(pts
			(xy 238.242856 -105.847134) (xy 238.207042 -105.811066) (xy 238.110014 -105.764584) (xy 238.034576 -105.840022)
			(xy 238.081312 -105.936796) (xy 238.117126 -105.972864)
		)
		(stroke
			(width 0)
			(type solid)
		)
		(fill yes)
		(layer "F.Cu")
		(net "M_E_DQS_DP<3>")
	)
	(gr_poly
		(pts
			(xy 238.261906 -46.12005) (xy 238.29772 -46.083982) (xy 238.17199 -45.958252) (xy 238.136176 -45.99432)
			(xy 238.08944 -46.091094) (xy 238.164878 -46.166532)
		)
		(stroke
			(width 0)
			(type solid)
		)
		(fill yes)
		(layer "F.Cu")
		(net "M_B_DQ<26>")
	)
	(gr_poly
		(pts
			(xy 238.262414 -105.611676) (xy 238.215932 -105.514648) (xy 238.179864 -105.478834) (xy 238.054134 -105.604564)
			(xy 238.090202 -105.640378) (xy 238.186976 -105.687114)
		)
		(stroke
			(width 0)
			(type solid)
		)
		(fill yes)
		(layer "F.Cu")
		(net "M_E_DQS_DN<3>")
	)
	(gr_poly
		(pts
			(xy 238.270796 -46.416468) (xy 238.317532 -46.31944) (xy 238.242094 -46.244002) (xy 238.145066 -46.290738)
			(xy 238.108998 -46.326552) (xy 238.234728 -46.452282)
		)
		(stroke
			(width 0)
			(type solid)
		)
		(fill yes)
		(layer "F.Cu")
		(net "M_B_DQ<31>")
	)
	(gr_poly
		(pts
			(xy 238.279178 -107.104688) (xy 238.24311 -107.068874) (xy 238.146336 -107.022138) (xy 238.070898 -107.097576)
			(xy 238.11738 -107.194604) (xy 238.153448 -107.230418)
		)
		(stroke
			(width 0)
			(type solid)
		)
		(fill yes)
		(layer "F.Cu")
		(net "M_E_DQ<26>")
	)
	(gr_poly
		(pts
			(xy 238.298736 -106.86923) (xy 238.252 -106.772456) (xy 238.216186 -106.736388) (xy 238.090456 -106.862118)
			(xy 238.12627 -106.897932) (xy 238.223298 -106.944668)
		)
		(stroke
			(width 0)
			(type solid)
		)
		(fill yes)
		(layer "F.Cu")
		(net "M_E_DQ<31>")
	)
	(gr_poly
		(pts
			(xy 238.30026 -49.25949) (xy 238.30026 -49.20869) (xy 238.12246 -49.20869) (xy 238.12246 -49.25949)
			(xy 238.15802 -49.36109) (xy 238.2647 -49.36109)
		)
		(stroke
			(width 0)
			(type solid)
		)
		(fill yes)
		(layer "F.Cu")
		(net "M_B_DQ<29>")
	)
	(gr_poly
		(pts
			(xy 238.30026 -48.95469) (xy 238.30026 -48.90389) (xy 238.12246 -48.90389) (xy 238.12246 -48.95469)
			(xy 238.15802 -49.05629) (xy 238.2647 -49.05629)
		)
		(stroke
			(width 0)
			(type solid)
		)
		(fill yes)
		(layer "F.Cu")
		(net "M_B_DQ<24>")
	)
	(gr_poly
		(pts
			(xy 238.30026 -48.64989) (xy 238.30026 -48.59909) (xy 238.12246 -48.59909) (xy 238.12246 -48.64989)
			(xy 238.15802 -48.75149) (xy 238.2647 -48.75149)
		)
		(stroke
			(width 0)
			(type solid)
		)
		(fill yes)
		(layer "F.Cu")
		(net "M_B_DQ<25>")
	)
	(gr_poly
		(pts
			(xy 238.30026 -48.34509) (xy 238.30026 -48.29429) (xy 238.12246 -48.29429) (xy 238.12246 -48.34509)
			(xy 238.15802 -48.44669) (xy 238.2647 -48.44669)
		)
		(stroke
			(width 0)
			(type solid)
		)
		(fill yes)
		(layer "F.Cu")
		(net "M_B_DQS_DP<12>")
	)
	(gr_poly
		(pts
			(xy 238.314992 -103.832152) (xy 238.268256 -103.735124) (xy 238.232188 -103.69931) (xy 238.106458 -103.82504)
			(xy 238.142526 -103.860854) (xy 238.239554 -103.90759)
		)
		(stroke
			(width 0)
			(type solid)
		)
		(fill yes)
		(layer "F.Cu")
		(net "M_E_DQ<24>")
	)
	(gr_poly
		(pts
			(xy 238.332518 -105.32618) (xy 238.296704 -105.290112) (xy 238.199676 -105.24363) (xy 238.124238 -105.319068)
			(xy 238.170974 -105.415842) (xy 238.206788 -105.45191)
		)
		(stroke
			(width 0)
			(type solid)
		)
		(fill yes)
		(layer "F.Cu")
		(net "M_E_DQS_DN<3>")
	)
	(gr_poly
		(pts
			(xy 238.351568 -46.641004) (xy 238.387382 -46.604936) (xy 238.261652 -46.479206) (xy 238.225838 -46.515274)
			(xy 238.179102 -46.612302) (xy 238.25454 -46.68774)
		)
		(stroke
			(width 0)
			(type solid)
		)
		(fill yes)
		(layer "F.Cu")
		(net "M_B_DQ<31>")
	)
	(gr_poly
		(pts
			(xy 238.360458 -46.937422) (xy 238.407194 -46.840394) (xy 238.331756 -46.764956) (xy 238.234728 -46.811692)
			(xy 238.19866 -46.847506) (xy 238.32439 -46.973236)
		)
		(stroke
			(width 0)
			(type solid)
		)
		(fill yes)
		(layer "F.Cu")
		(net "M_B_DQ<30>")
	)
	(gr_poly
		(pts
			(xy 238.36884 -106.583734) (xy 238.333026 -106.54792) (xy 238.235998 -106.501184) (xy 238.16056 -106.576622)
			(xy 238.207296 -106.67365) (xy 238.24311 -106.709464)
		)
		(stroke
			(width 0)
			(type solid)
		)
		(fill yes)
		(layer "F.Cu")
		(net "M_E_DQ<31>")
	)
	(gr_poly
		(pts
			(xy 238.384842 -103.546656) (xy 238.349028 -103.510588) (xy 238.252 -103.463852) (xy 238.176562 -103.53929)
			(xy 238.223298 -103.636318) (xy 238.259112 -103.672386)
		)
		(stroke
			(width 0)
			(type solid)
		)
		(fill yes)
		(layer "F.Cu")
		(net "M_E_DQ<24>")
	)
	(gr_poly
		(pts
			(xy 238.388398 -106.348276) (xy 238.341662 -106.251248) (xy 238.305848 -106.215434) (xy 238.180118 -106.341164)
			(xy 238.215932 -106.376978) (xy 238.31296 -106.423714)
		)
		(stroke
			(width 0)
			(type solid)
		)
		(fill yes)
		(layer "F.Cu")
		(net "M_E_DQ<30>")
	)
	(gr_poly
		(pts
			(xy 238.404654 -103.311198) (xy 238.357918 -103.21417) (xy 238.32185 -103.178356) (xy 238.19612 -103.304086)
			(xy 238.232188 -103.3399) (xy 238.329216 -103.386636)
		)
		(stroke
			(width 0)
			(type solid)
		)
		(fill yes)
		(layer "F.Cu")
		(net "M_E_DQ<29>")
	)
	(gr_poly
		(pts
			(xy 238.42218 -104.805226) (xy 238.386366 -104.769158) (xy 238.289338 -104.722676) (xy 238.2139 -104.798114)
			(xy 238.260636 -104.894888) (xy 238.29645 -104.930956)
		)
		(stroke
			(width 0)
			(type solid)
		)
		(fill yes)
		(layer "F.Cu")
		(net "M_E_DQS_DN<12>")
	)
	(gr_poly
		(pts
			(xy 238.44123 -47.161958) (xy 238.477044 -47.12589) (xy 238.351314 -47.00016) (xy 238.3155 -47.036228)
			(xy 238.268764 -47.133256) (xy 238.344202 -47.208694)
		)
		(stroke
			(width 0)
			(type solid)
		)
		(fill yes)
		(layer "F.Cu")
		(net "M_B_DQ<30>")
	)
	(gr_poly
		(pts
			(xy 238.441992 -104.569768) (xy 238.395256 -104.47274) (xy 238.359188 -104.436926) (xy 238.233458 -104.562656)
			(xy 238.269526 -104.59847) (xy 238.366554 -104.645206)
		)
		(stroke
			(width 0)
			(type solid)
		)
		(fill yes)
		(layer "F.Cu")
		(net "M_E_DQS_DP<12>")
	)
	(gr_poly
		(pts
			(xy 238.458502 -106.06278) (xy 238.422688 -106.026966) (xy 238.32566 -105.98023) (xy 238.250222 -106.055668)
			(xy 238.296958 -106.152696) (xy 238.332772 -106.18851)
		)
		(stroke
			(width 0)
			(type solid)
		)
		(fill yes)
		(layer "F.Cu")
		(net "M_E_DQ<30>")
	)
	(gr_poly
		(pts
			(xy 238.474504 -103.025702) (xy 238.43869 -102.989634) (xy 238.341662 -102.942898) (xy 238.266224 -103.018336)
			(xy 238.31296 -103.115364) (xy 238.348774 -103.151432)
		)
		(stroke
			(width 0)
			(type solid)
		)
		(fill yes)
		(layer "F.Cu")
		(net "M_E_DQ<29>")
	)
	(gr_poly
		(pts
			(xy 238.477298 -45.904404) (xy 238.522256 -45.859446) (xy 238.396526 -45.733716) (xy 238.351568 -45.778674)
			(xy 238.305086 -45.875702) (xy 238.380524 -45.95114)
		)
		(stroke
			(width 0)
			(type solid)
		)
		(fill yes)
		(layer "F.Cu")
		(net "M_B_DQ<27>")
	)
	(gr_poly
		(pts
			(xy 238.47806 -105.827322) (xy 238.431578 -105.730294) (xy 238.39551 -105.69448) (xy 238.26978 -105.82021)
			(xy 238.305848 -105.856024) (xy 238.402622 -105.90276)
		)
		(stroke
			(width 0)
			(type solid)
		)
		(fill yes)
		(layer "F.Cu")
		(net "M_E_DQS_DP<3>")
	)
	(gr_poly
		(pts
			(xy 238.486442 -46.200822) (xy 238.533178 -46.103794) (xy 238.45774 -46.028356) (xy 238.360712 -46.075092)
			(xy 238.324644 -46.110906) (xy 238.450374 -46.236636)
		)
		(stroke
			(width 0)
			(type solid)
		)
		(fill yes)
		(layer "F.Cu")
		(net "M_B_DQ<26>")
	)
	(gr_poly
		(pts
			(xy 238.494316 -102.790244) (xy 238.44758 -102.693216) (xy 238.402622 -102.648512) (xy 238.277146 -102.773988)
			(xy 238.32185 -102.818946) (xy 238.418878 -102.865682)
		)
		(stroke
			(width 0)
			(type solid)
		)
		(fill yes)
		(layer "F.Cu")
		(net "M_E_DQ<28>")
	)
	(gr_poly
		(pts
			(xy 238.503714 -107.329224) (xy 238.458756 -107.284266) (xy 238.361728 -107.23753) (xy 238.28629 -107.312968)
			(xy 238.333026 -107.409996) (xy 238.377984 -107.454954)
		)
		(stroke
			(width 0)
			(type solid)
		)
		(fill yes)
		(layer "F.Cu")
		(net "M_E_DQ<27>")
	)
	(gr_poly
		(pts
			(xy 238.511842 -104.284272) (xy 238.476028 -104.248204) (xy 238.379 -104.201468) (xy 238.303562 -104.276906)
			(xy 238.350298 -104.373934) (xy 238.386112 -104.410002)
		)
		(stroke
			(width 0)
			(type solid)
		)
		(fill yes)
		(layer "F.Cu")
		(net "M_E_DQS_DP<12>")
	)
	(gr_poly
		(pts
			(xy 238.514382 -107.084876) (xy 238.467646 -106.988102) (xy 238.431832 -106.952034) (xy 238.306102 -107.077764)
			(xy 238.341916 -107.113578) (xy 238.438944 -107.160314)
		)
		(stroke
			(width 0)
			(type solid)
		)
		(fill yes)
		(layer "F.Cu")
		(net "M_E_DQ<26>")
	)
	(gr_poly
		(pts
			(xy 238.51616 -49.46269) (xy 238.4806 -49.36109) (xy 238.37392 -49.36109) (xy 238.33836 -49.46269)
			(xy 238.33836 -49.52619) (xy 238.51616 -49.52619)
		)
		(stroke
			(width 0)
			(type solid)
		)
		(fill yes)
		(layer "F.Cu")
		(net "M_B_DQ<28>")
	)
	(gr_poly
		(pts
			(xy 238.51616 -49.15789) (xy 238.4806 -49.05629) (xy 238.37392 -49.05629) (xy 238.33836 -49.15789)
			(xy 238.33836 -49.20869) (xy 238.51616 -49.20869)
		)
		(stroke
			(width 0)
			(type solid)
		)
		(fill yes)
		(layer "F.Cu")
		(net "M_B_DQ<29>")
	)
	(gr_poly
		(pts
			(xy 238.51616 -48.85309) (xy 238.4806 -48.75149) (xy 238.37392 -48.75149) (xy 238.33836 -48.85309)
			(xy 238.33836 -48.90389) (xy 238.51616 -48.90389)
		)
		(stroke
			(width 0)
			(type solid)
		)
		(fill yes)
		(layer "F.Cu")
		(net "M_B_DQ<24>")
	)
	(gr_poly
		(pts
			(xy 238.51616 -48.54829) (xy 238.4806 -48.44669) (xy 238.37392 -48.44669) (xy 238.33836 -48.54829)
			(xy 238.33836 -48.59909) (xy 238.51616 -48.59909)
		)
		(stroke
			(width 0)
			(type solid)
		)
		(fill yes)
		(layer "F.Cu")
		(net "M_B_DQ<25>")
	)
	(gr_poly
		(pts
			(xy 238.51616 -48.24349) (xy 238.4806 -48.14189) (xy 238.37392 -48.14189) (xy 238.33836 -48.24349)
			(xy 238.33836 -48.29429) (xy 238.51616 -48.29429)
		)
		(stroke
			(width 0)
			(type solid)
		)
		(fill yes)
		(layer "F.Cu")
		(net "M_B_DQS_DP<12>")
	)
	(gr_poly
		(pts
			(xy 238.51616 -47.93869) (xy 238.4806 -47.83709) (xy 238.37392 -47.83709) (xy 238.33836 -47.93869)
			(xy 238.33836 -47.98949) (xy 238.51616 -47.98949)
		)
		(stroke
			(width 0)
			(type solid)
		)
		(fill yes)
		(layer "F.Cu")
		(net "M_B_DQS_DN<12>")
	)
	(gr_poly
		(pts
			(xy 238.51616 -47.63389) (xy 238.4806 -47.53229) (xy 238.37392 -47.53229) (xy 238.33836 -47.63389)
			(xy 238.33836 -47.68469) (xy 238.51616 -47.68469)
		)
		(stroke
			(width 0)
			(type solid)
		)
		(fill yes)
		(layer "F.Cu")
		(net "M_B_DQS_DN<3>")
	)
	(gr_poly
		(pts
			(xy 238.530638 -104.047798) (xy 238.483902 -103.95077) (xy 238.447834 -103.914956) (xy 238.322104 -104.040686)
			(xy 238.358172 -104.0765) (xy 238.4552 -104.123236)
		)
		(stroke
			(width 0)
			(type solid)
		)
		(fill yes)
		(layer "F.Cu")
		(net "M_E_DQ<25>")
	)
	(gr_poly
		(pts
			(xy 238.548164 -105.541826) (xy 238.51235 -105.505758) (xy 238.415322 -105.459276) (xy 238.339884 -105.534714)
			(xy 238.38662 -105.631488) (xy 238.422434 -105.667556)
		)
		(stroke
			(width 0)
			(type solid)
		)
		(fill yes)
		(layer "F.Cu")
		(net "M_E_DQS_DP<3>")
	)
	(gr_poly
		(pts
			(xy 238.567214 -46.425358) (xy 238.603028 -46.38929) (xy 238.477298 -46.26356) (xy 238.441484 -46.299628)
			(xy 238.394748 -46.396402) (xy 238.470186 -46.47184)
		)
		(stroke
			(width 0)
			(type solid)
		)
		(fill yes)
		(layer "F.Cu")
		(net "M_B_DQ<26>")
	)
	(gr_poly
		(pts
			(xy 238.567722 -105.306368) (xy 238.52124 -105.20934) (xy 238.485172 -105.173526) (xy 238.359442 -105.299256)
			(xy 238.39551 -105.33507) (xy 238.492284 -105.381806)
		)
		(stroke
			(width 0)
			(type solid)
		)
		(fill yes)
		(layer "F.Cu")
		(net "M_E_DQS_DN<3>")
	)
	(gr_poly
		(pts
			(xy 238.576104 -46.721776) (xy 238.62284 -46.624748) (xy 238.547402 -46.54931) (xy 238.450374 -46.596046)
			(xy 238.414306 -46.63186) (xy 238.540036 -46.75759)
		)
		(stroke
			(width 0)
			(type solid)
		)
		(fill yes)
		(layer "F.Cu")
		(net "M_B_DQ<31>")
	)
	(gr_poly
		(pts
			(xy 238.584486 -106.79938) (xy 238.548672 -106.763566) (xy 238.451644 -106.71683) (xy 238.376206 -106.792268)
			(xy 238.422942 -106.889296) (xy 238.458756 -106.92511)
		)
		(stroke
			(width 0)
			(type solid)
		)
		(fill yes)
		(layer "F.Cu")
		(net "M_E_DQ<26>")
	)
	(gr_poly
		(pts
			(xy 238.600488 -103.762302) (xy 238.564674 -103.726234) (xy 238.467646 -103.679498) (xy 238.392208 -103.754936)
			(xy 238.438944 -103.851964) (xy 238.474758 -103.888032)
		)
		(stroke
			(width 0)
			(type solid)
		)
		(fill yes)
		(layer "F.Cu")
		(net "M_E_DQ<25>")
	)
	(gr_poly
		(pts
			(xy 238.604044 -106.563922) (xy 238.557308 -106.466894) (xy 238.521494 -106.43108) (xy 238.395764 -106.55681)
			(xy 238.431578 -106.592624) (xy 238.528606 -106.63936)
		)
		(stroke
			(width 0)
			(type solid)
		)
		(fill yes)
		(layer "F.Cu")
		(net "M_E_DQ<31>")
	)
	(gr_poly
		(pts
			(xy 238.6203 -103.526844) (xy 238.573564 -103.429816) (xy 238.537496 -103.394002) (xy 238.411766 -103.519732)
			(xy 238.447834 -103.555546) (xy 238.544862 -103.602282)
		)
		(stroke
			(width 0)
			(type solid)
		)
		(fill yes)
		(layer "F.Cu")
		(net "M_E_DQ<24>")
	)
	(gr_poly
		(pts
			(xy 238.637826 -105.020872) (xy 238.602012 -104.984804) (xy 238.504984 -104.938322) (xy 238.429546 -105.01376)
			(xy 238.476282 -105.110534) (xy 238.512096 -105.146602)
		)
		(stroke
			(width 0)
			(type solid)
		)
		(fill yes)
		(layer "F.Cu")
		(net "M_E_DQS_DN<3>")
	)
	(gr_poly
		(pts
			(xy 238.657638 -104.785414) (xy 238.610902 -104.688386) (xy 238.574834 -104.652572) (xy 238.449104 -104.778302)
			(xy 238.485172 -104.814116) (xy 238.5822 -104.860852)
		)
		(stroke
			(width 0)
			(type solid)
		)
		(fill yes)
		(layer "F.Cu")
		(net "M_E_DQS_DN<12>")
	)
	(gr_poly
		(pts
			(xy 238.674148 -106.278426) (xy 238.638334 -106.242612) (xy 238.541306 -106.195876) (xy 238.465868 -106.271314)
			(xy 238.512604 -106.368342) (xy 238.548418 -106.404156)
		)
		(stroke
			(width 0)
			(type solid)
		)
		(fill yes)
		(layer "F.Cu")
		(net "M_E_DQ<31>")
	)
	(gr_poly
		(pts
			(xy 238.69015 -103.241348) (xy 238.654336 -103.20528) (xy 238.557308 -103.158544) (xy 238.48187 -103.233982)
			(xy 238.528606 -103.33101) (xy 238.56442 -103.367078)
		)
		(stroke
			(width 0)
			(type solid)
		)
		(fill yes)
		(layer "F.Cu")
		(net "M_E_DQ<24>")
	)
	(gr_poly
		(pts
			(xy 238.693706 -106.042968) (xy 238.647224 -105.94594) (xy 238.611156 -105.910126) (xy 238.485426 -106.035856)
			(xy 238.521494 -106.07167) (xy 238.618268 -106.118406)
		)
		(stroke
			(width 0)
			(type solid)
		)
		(fill yes)
		(layer "F.Cu")
		(net "M_E_DQ<30>")
	)
	(gr_poly
		(pts
			(xy 238.709962 -103.00589) (xy 238.663226 -102.908862) (xy 238.627158 -102.873048) (xy 238.501682 -102.998524)
			(xy 238.537496 -103.034592) (xy 238.634524 -103.081328)
		)
		(stroke
			(width 0)
			(type solid)
		)
		(fill yes)
		(layer "F.Cu")
		(net "M_E_DQ<29>")
	)
	(gr_poly
		(pts
			(xy 238.727488 -104.499918) (xy 238.691674 -104.46385) (xy 238.594646 -104.417114) (xy 238.519208 -104.492552)
			(xy 238.565944 -104.58958) (xy 238.601758 -104.625648)
		)
		(stroke
			(width 0)
			(type solid)
		)
		(fill yes)
		(layer "F.Cu")
		(net "M_E_DQS_DN<12>")
	)
	(gr_poly
		(pts
			(xy 238.73206 -49.25949) (xy 238.73206 -49.20869) (xy 238.55426 -49.20869) (xy 238.55426 -49.25949)
			(xy 238.58982 -49.36109) (xy 238.6965 -49.36109)
		)
		(stroke
			(width 0)
			(type solid)
		)
		(fill yes)
		(layer "F.Cu")
		(net "M_B_DQ<29>")
	)
	(gr_poly
		(pts
			(xy 238.73206 -48.95469) (xy 238.73206 -48.90389) (xy 238.55426 -48.90389) (xy 238.55426 -48.95469)
			(xy 238.58982 -49.05629) (xy 238.6965 -49.05629)
		)
		(stroke
			(width 0)
			(type solid)
		)
		(fill yes)
		(layer "F.Cu")
		(net "M_B_DQ<24>")
	)
	(gr_poly
		(pts
			(xy 238.73206 -48.64989) (xy 238.73206 -48.59909) (xy 238.55426 -48.59909) (xy 238.55426 -48.64989)
			(xy 238.58982 -48.75149) (xy 238.6965 -48.75149)
		)
		(stroke
			(width 0)
			(type solid)
		)
		(fill yes)
		(layer "F.Cu")
		(net "M_B_DQ<25>")
	)
	(gr_poly
		(pts
			(xy 238.73206 -48.34509) (xy 238.73206 -48.29429) (xy 238.55426 -48.29429) (xy 238.55426 -48.34509)
			(xy 238.58982 -48.44669) (xy 238.6965 -48.44669)
		)
		(stroke
			(width 0)
			(type solid)
		)
		(fill yes)
		(layer "F.Cu")
		(net "M_B_DQS_DP<12>")
	)
	(gr_poly
		(pts
			(xy 238.73206 -48.04029) (xy 238.73206 -47.98949) (xy 238.55426 -47.98949) (xy 238.55426 -48.04029)
			(xy 238.58982 -48.14189) (xy 238.6965 -48.14189)
		)
		(stroke
			(width 0)
			(type solid)
		)
		(fill yes)
		(layer "F.Cu")
		(net "M_B_DQS_DN<12>")
	)
	(gr_poly
		(pts
			(xy 238.73206 -47.73549) (xy 238.73206 -47.68469) (xy 238.55426 -47.68469) (xy 238.55426 -47.73549)
			(xy 238.58982 -47.83709) (xy 238.6965 -47.83709)
		)
		(stroke
			(width 0)
			(type solid)
		)
		(fill yes)
		(layer "F.Cu")
		(net "M_B_DQS_DN<3>")
	)
	(gr_poly
		(pts
			(xy 238.73206 -47.43069) (xy 238.73206 -47.37989) (xy 238.55426 -47.37989) (xy 238.55426 -47.43069)
			(xy 238.58982 -47.53229) (xy 238.6965 -47.53229)
		)
		(stroke
			(width 0)
			(type solid)
		)
		(fill yes)
		(layer "F.Cu")
		(net "M_B_DQS_DP<3>")
	)
	(gr_poly
		(pts
			(xy 238.73206 -47.12589) (xy 238.73206 -47.07509) (xy 238.55426 -47.07509) (xy 238.55426 -47.12589)
			(xy 238.58982 -47.22749) (xy 238.6965 -47.22749)
		)
		(stroke
			(width 0)
			(type solid)
		)
		(fill yes)
		(layer "F.Cu")
		(net "M_B_DQ<30>")
	)
	(gr_poly
		(pts
			(xy 238.7473 -104.26446) (xy 238.700564 -104.167432) (xy 238.664496 -104.131618) (xy 238.538766 -104.257348)
			(xy 238.574834 -104.293162) (xy 238.671862 -104.339898)
		)
		(stroke
			(width 0)
			(type solid)
		)
		(fill yes)
		(layer "F.Cu")
		(net "M_E_DQS_DP<12>")
	)
	(gr_poly
		(pts
			(xy 238.76381 -105.757472) (xy 238.727996 -105.721404) (xy 238.630968 -105.674922) (xy 238.55553 -105.75036)
			(xy 238.602266 -105.847134) (xy 238.63808 -105.883202)
		)
		(stroke
			(width 0)
			(type solid)
		)
		(fill yes)
		(layer "F.Cu")
		(net "M_E_DQ<30>")
	)
	(gr_poly
		(pts
			(xy 238.780066 -102.72014) (xy 238.743998 -102.684326) (xy 238.64697 -102.63759) (xy 238.571532 -102.713028)
			(xy 238.618268 -102.810056) (xy 238.654336 -102.84587)
		)
		(stroke
			(width 0)
			(type solid)
		)
		(fill yes)
		(layer "F.Cu")
		(net "M_E_DQ<29>")
	)
	(gr_poly
		(pts
			(xy 238.782606 -46.209712) (xy 238.827564 -46.164754) (xy 238.701834 -46.039024) (xy 238.656876 -46.083982)
			(xy 238.610394 -46.18101) (xy 238.685832 -46.256448)
		)
		(stroke
			(width 0)
			(type solid)
		)
		(fill yes)
		(layer "F.Cu")
		(net "M_B_DQ<27>")
	)
	(gr_poly
		(pts
			(xy 238.783368 -105.522014) (xy 238.736886 -105.424986) (xy 238.700818 -105.389172) (xy 238.575088 -105.514902)
			(xy 238.611156 -105.550716) (xy 238.70793 -105.597452)
		)
		(stroke
			(width 0)
			(type solid)
		)
		(fill yes)
		(layer "F.Cu")
		(net "M_E_DQS_DP<3>")
	)
	(gr_poly
		(pts
			(xy 238.799624 -102.484936) (xy 238.752888 -102.387908) (xy 238.70793 -102.343204) (xy 238.582454 -102.46868)
			(xy 238.627158 -102.513638) (xy 238.724186 -102.560374)
		)
		(stroke
			(width 0)
			(type solid)
		)
		(fill yes)
		(layer "F.Cu")
		(net "M_E_DQ<28>")
	)
	(gr_poly
		(pts
			(xy 238.809022 -107.023916) (xy 238.764064 -106.978958) (xy 238.667036 -106.932222) (xy 238.591598 -107.00766)
			(xy 238.638334 -107.104688) (xy 238.683292 -107.149646)
		)
		(stroke
			(width 0)
			(type solid)
		)
		(fill yes)
		(layer "F.Cu")
		(net "M_E_DQ<27>")
	)
	(gr_poly
		(pts
			(xy 238.81715 -103.978964) (xy 238.781336 -103.942896) (xy 238.684308 -103.89616) (xy 238.60887 -103.971598)
			(xy 238.655606 -104.068626) (xy 238.69142 -104.104694)
		)
		(stroke
			(width 0)
			(type solid)
		)
		(fill yes)
		(layer "F.Cu")
		(net "M_E_DQS_DP<12>")
	)
	(gr_poly
		(pts
			(xy 238.81969 -106.779568) (xy 238.772954 -106.68254) (xy 238.73714 -106.646726) (xy 238.61141 -106.772456)
			(xy 238.647224 -106.80827) (xy 238.744252 -106.855006)
		)
		(stroke
			(width 0)
			(type solid)
		)
		(fill yes)
		(layer "F.Cu")
		(net "M_E_DQ<26>")
	)
	(gr_poly
		(pts
			(xy 238.835946 -103.74249) (xy 238.78921 -103.645462) (xy 238.753142 -103.609648) (xy 238.627412 -103.735378)
			(xy 238.66348 -103.771192) (xy 238.760508 -103.817928)
		)
		(stroke
			(width 0)
			(type solid)
		)
		(fill yes)
		(layer "F.Cu")
		(net "M_E_DQ<25>")
	)
	(gr_poly
		(pts
			(xy 238.853472 -105.236518) (xy 238.817658 -105.20045) (xy 238.72063 -105.153968) (xy 238.645192 -105.229406)
			(xy 238.691928 -105.32618) (xy 238.727742 -105.362248)
		)
		(stroke
			(width 0)
			(type solid)
		)
		(fill yes)
		(layer "F.Cu")
		(net "M_E_DQS_DP<3>")
	)
	(gr_poly
		(pts
			(xy 238.873284 -105.00106) (xy 238.826548 -104.904032) (xy 238.79048 -104.868218) (xy 238.66475 -104.993948)
			(xy 238.700818 -105.029762) (xy 238.797846 -105.076498)
		)
		(stroke
			(width 0)
			(type solid)
		)
		(fill yes)
		(layer "F.Cu")
		(net "M_E_DQS_DN<3>")
	)
	(gr_poly
		(pts
			(xy 238.889794 -106.494072) (xy 238.85398 -106.458258) (xy 238.756952 -106.411522) (xy 238.681514 -106.48696)
			(xy 238.72825 -106.583988) (xy 238.764064 -106.619802)
		)
		(stroke
			(width 0)
			(type solid)
		)
		(fill yes)
		(layer "F.Cu")
		(net "M_E_DQ<26>")
	)
	(gr_poly
		(pts
			(xy 238.905796 -103.456994) (xy 238.869982 -103.420926) (xy 238.772954 -103.37419) (xy 238.697516 -103.449628)
			(xy 238.744252 -103.546656) (xy 238.780066 -103.582724)
		)
		(stroke
			(width 0)
			(type solid)
		)
		(fill yes)
		(layer "F.Cu")
		(net "M_E_DQ<25>")
	)
	(gr_poly
		(pts
			(xy 238.909352 -106.258614) (xy 238.86287 -106.161586) (xy 238.826802 -106.125772) (xy 238.701072 -106.251502)
			(xy 238.73714 -106.287316) (xy 238.833914 -106.334052)
		)
		(stroke
			(width 0)
			(type solid)
		)
		(fill yes)
		(layer "F.Cu")
		(net "M_E_DQ<31>")
	)
	(gr_poly
		(pts
			(xy 238.925608 -103.221536) (xy 238.878872 -103.124508) (xy 238.842804 -103.088694) (xy 238.717328 -103.21417)
			(xy 238.753142 -103.250238) (xy 238.85017 -103.296974)
		)
		(stroke
			(width 0)
			(type solid)
		)
		(fill yes)
		(layer "F.Cu")
		(net "M_E_DQ<24>")
	)
	(gr_poly
		(pts
			(xy 238.943134 -104.715564) (xy 238.90732 -104.679496) (xy 238.810292 -104.63276) (xy 238.734854 -104.708198)
			(xy 238.78159 -104.805226) (xy 238.817404 -104.841294)
		)
		(stroke
			(width 0)
			(type solid)
		)
		(fill yes)
		(layer "F.Cu")
		(net "M_E_DQS_DN<3>")
	)
	(gr_poly
		(pts
			(xy 238.94796 -49.46269) (xy 238.9124 -49.36109) (xy 238.80572 -49.36109) (xy 238.77016 -49.46269)
			(xy 238.77016 -49.52619) (xy 238.94796 -49.52619)
		)
		(stroke
			(width 0)
			(type solid)
		)
		(fill yes)
		(layer "F.Cu")
		(net "M_B_DQ<28>")
	)
	(gr_poly
		(pts
			(xy 238.94796 -49.15789) (xy 238.9124 -49.05629) (xy 238.80572 -49.05629) (xy 238.77016 -49.15789)
			(xy 238.77016 -49.20869) (xy 238.94796 -49.20869)
		)
		(stroke
			(width 0)
			(type solid)
		)
		(fill yes)
		(layer "F.Cu")
		(net "M_B_DQ<29>")
	)
	(gr_poly
		(pts
			(xy 238.94796 -48.85309) (xy 238.9124 -48.75149) (xy 238.80572 -48.75149) (xy 238.77016 -48.85309)
			(xy 238.77016 -48.90389) (xy 238.94796 -48.90389)
		)
		(stroke
			(width 0)
			(type solid)
		)
		(fill yes)
		(layer "F.Cu")
		(net "M_B_DQ<24>")
	)
	(gr_poly
		(pts
			(xy 238.94796 -48.54829) (xy 238.9124 -48.44669) (xy 238.80572 -48.44669) (xy 238.77016 -48.54829)
			(xy 238.77016 -48.59909) (xy 238.94796 -48.59909)
		)
		(stroke
			(width 0)
			(type solid)
		)
		(fill yes)
		(layer "F.Cu")
		(net "M_B_DQ<25>")
	)
	(gr_poly
		(pts
			(xy 238.94796 -48.24349) (xy 238.9124 -48.14189) (xy 238.80572 -48.14189) (xy 238.77016 -48.24349)
			(xy 238.77016 -48.29429) (xy 238.94796 -48.29429)
		)
		(stroke
			(width 0)
			(type solid)
		)
		(fill yes)
		(layer "F.Cu")
		(net "M_B_DQS_DP<12>")
	)
	(gr_poly
		(pts
			(xy 238.94796 -47.93869) (xy 238.9124 -47.83709) (xy 238.80572 -47.83709) (xy 238.77016 -47.93869)
			(xy 238.77016 -47.98949) (xy 238.94796 -47.98949)
		)
		(stroke
			(width 0)
			(type solid)
		)
		(fill yes)
		(layer "F.Cu")
		(net "M_B_DQS_DN<12>")
	)
	(gr_poly
		(pts
			(xy 238.94796 -47.63389) (xy 238.9124 -47.53229) (xy 238.80572 -47.53229) (xy 238.77016 -47.63389)
			(xy 238.77016 -47.68469) (xy 238.94796 -47.68469)
		)
		(stroke
			(width 0)
			(type solid)
		)
		(fill yes)
		(layer "F.Cu")
		(net "M_B_DQS_DN<3>")
	)
	(gr_poly
		(pts
			(xy 238.94796 -47.32909) (xy 238.9124 -47.22749) (xy 238.80572 -47.22749) (xy 238.77016 -47.32909)
			(xy 238.77016 -47.37989) (xy 238.94796 -47.37989)
		)
		(stroke
			(width 0)
			(type solid)
		)
		(fill yes)
		(layer "F.Cu")
		(net "M_B_DQS_DP<3>")
	)
	(gr_poly
		(pts
			(xy 238.94796 -47.02429) (xy 238.9124 -46.92269) (xy 238.80572 -46.92269) (xy 238.77016 -47.02429)
			(xy 238.77016 -47.07509) (xy 238.94796 -47.07509)
		)
		(stroke
			(width 0)
			(type solid)
		)
		(fill yes)
		(layer "F.Cu")
		(net "M_B_DQ<30>")
	)
	(gr_poly
		(pts
			(xy 238.94796 -46.71949) (xy 238.9124 -46.61789) (xy 238.80572 -46.61789) (xy 238.77016 -46.71949)
			(xy 238.77016 -46.77029) (xy 238.94796 -46.77029)
		)
		(stroke
			(width 0)
			(type solid)
		)
		(fill yes)
		(layer "F.Cu")
		(net "M_B_DQ<31>")
	)
	(gr_poly
		(pts
			(xy 238.962946 -104.480106) (xy 238.91621 -104.383078) (xy 238.880142 -104.347264) (xy 238.754412 -104.472994)
			(xy 238.79048 -104.508808) (xy 238.887508 -104.555544)
		)
		(stroke
			(width 0)
			(type solid)
		)
		(fill yes)
		(layer "F.Cu")
		(net "M_E_DQS_DN<12>")
	)
	(gr_poly
		(pts
			(xy 238.979456 -105.973118) (xy 238.943642 -105.93705) (xy 238.846614 -105.890568) (xy 238.771176 -105.966006)
			(xy 238.817912 -106.06278) (xy 238.853726 -106.098848)
		)
		(stroke
			(width 0)
			(type solid)
		)
		(fill yes)
		(layer "F.Cu")
		(net "M_E_DQ<31>")
	)
	(gr_poly
		(pts
			(xy 238.995712 -102.935786) (xy 238.959644 -102.899972) (xy 238.862616 -102.853236) (xy 238.787178 -102.928674)
			(xy 238.833914 -103.025702) (xy 238.869982 -103.061516)
		)
		(stroke
			(width 0)
			(type solid)
		)
		(fill yes)
		(layer "F.Cu")
		(net "M_E_DQ<24>")
	)
	(gr_poly
		(pts
			(xy 238.999014 -105.73766) (xy 238.952532 -105.640632) (xy 238.916464 -105.604818) (xy 238.790734 -105.730548)
			(xy 238.826802 -105.766362) (xy 238.923576 -105.813098)
		)
		(stroke
			(width 0)
			(type solid)
		)
		(fill yes)
		(layer "F.Cu")
		(net "M_E_DQ<30>")
	)
	(gr_poly
		(pts
			(xy 239.01527 -102.700582) (xy 238.968534 -102.603554) (xy 238.932466 -102.56774) (xy 238.80699 -102.693216)
			(xy 238.842804 -102.729284) (xy 238.939832 -102.77602)
		)
		(stroke
			(width 0)
			(type solid)
		)
		(fill yes)
		(layer "F.Cu")
		(net "M_E_DQ<29>")
	)
	(gr_poly
		(pts
			(xy 239.032796 -104.19461) (xy 238.996982 -104.158542) (xy 238.899954 -104.111806) (xy 238.824516 -104.187244)
			(xy 238.871252 -104.284272) (xy 238.907066 -104.32034)
		)
		(stroke
			(width 0)
			(type solid)
		)
		(fill yes)
		(layer "F.Cu")
		(net "M_E_DQS_DN<12>")
	)
	(gr_poly
		(pts
			(xy 239.052608 -103.959152) (xy 239.005872 -103.862124) (xy 238.969804 -103.82631) (xy 238.844074 -103.95204)
			(xy 238.880142 -103.987854) (xy 238.97717 -104.03459)
		)
		(stroke
			(width 0)
			(type solid)
		)
		(fill yes)
		(layer "F.Cu")
		(net "M_E_DQS_DP<12>")
	)
	(gr_poly
		(pts
			(xy 239.069118 -105.452164) (xy 239.033304 -105.416096) (xy 238.936276 -105.369614) (xy 238.860838 -105.445052)
			(xy 238.907574 -105.541826) (xy 238.943388 -105.577894)
		)
		(stroke
			(width 0)
			(type solid)
		)
		(fill yes)
		(layer "F.Cu")
		(net "M_E_DQ<30>")
	)
	(gr_poly
		(pts
			(xy 239.08893 -105.216706) (xy 239.042194 -105.119678) (xy 239.006126 -105.083864) (xy 238.880396 -105.209594)
			(xy 238.916464 -105.245408) (xy 239.013492 -105.292144)
		)
		(stroke
			(width 0)
			(type solid)
		)
		(fill yes)
		(layer "F.Cu")
		(net "M_E_DQS_DP<3>")
	)
	(gr_poly
		(pts
			(xy 239.11433 -106.718608) (xy 239.069372 -106.67365) (xy 238.972344 -106.626914) (xy 238.896906 -106.702352)
			(xy 238.943642 -106.79938) (xy 238.9886 -106.844338)
		)
		(stroke
			(width 0)
			(type solid)
		)
		(fill yes)
		(layer "F.Cu")
		(net "M_E_DQ<27>")
	)
	(gr_poly
		(pts
			(xy 239.122458 -103.673656) (xy 239.086644 -103.637588) (xy 238.989616 -103.590852) (xy 238.914178 -103.66629)
			(xy 238.960914 -103.763318) (xy 238.996728 -103.799386)
		)
		(stroke
			(width 0)
			(type solid)
		)
		(fill yes)
		(layer "F.Cu")
		(net "M_E_DQS_DP<12>")
	)
	(gr_poly
		(pts
			(xy 239.124998 -106.47426) (xy 239.078516 -106.377232) (xy 239.042448 -106.341418) (xy 238.916718 -106.467148)
			(xy 238.952786 -106.502962) (xy 239.04956 -106.549698)
		)
		(stroke
			(width 0)
			(type solid)
		)
		(fill yes)
		(layer "F.Cu")
		(net "M_E_DQ<26>")
	)
	(gr_poly
		(pts
			(xy 239.141254 -103.437182) (xy 239.094518 -103.340154) (xy 239.05845 -103.30434) (xy 238.93272 -103.43007)
			(xy 238.968788 -103.465884) (xy 239.065816 -103.51262)
		)
		(stroke
			(width 0)
			(type solid)
		)
		(fill yes)
		(layer "F.Cu")
		(net "M_E_DQ<25>")
	)
	(gr_poly
		(pts
			(xy 239.15878 -104.93121) (xy 239.122966 -104.895142) (xy 239.025938 -104.848406) (xy 238.9505 -104.923844)
			(xy 238.997236 -105.020872) (xy 239.03305 -105.05694)
		)
		(stroke
			(width 0)
			(type solid)
		)
		(fill yes)
		(layer "F.Cu")
		(net "M_E_DQS_DP<3>")
	)
	(gr_poly
		(pts
			(xy 239.16386 -49.25949) (xy 239.16386 -49.20869) (xy 238.98606 -49.20869) (xy 238.98606 -49.25949)
			(xy 239.02162 -49.36109) (xy 239.1283 -49.36109)
		)
		(stroke
			(width 0)
			(type solid)
		)
		(fill yes)
		(layer "F.Cu")
		(net "M_B_DQ<29>")
	)
	(gr_poly
		(pts
			(xy 239.16386 -48.95469) (xy 239.16386 -48.90389) (xy 238.98606 -48.90389) (xy 238.98606 -48.95469)
			(xy 239.02162 -49.05629) (xy 239.1283 -49.05629)
		)
		(stroke
			(width 0)
			(type solid)
		)
		(fill yes)
		(layer "F.Cu")
		(net "M_B_DQ<24>")
	)
	(gr_poly
		(pts
			(xy 239.16386 -48.64989) (xy 239.16386 -48.59909) (xy 238.98606 -48.59909) (xy 238.98606 -48.64989)
			(xy 239.02162 -48.75149) (xy 239.1283 -48.75149)
		)
		(stroke
			(width 0)
			(type solid)
		)
		(fill yes)
		(layer "F.Cu")
		(net "M_B_DQ<25>")
	)
	(gr_poly
		(pts
			(xy 239.16386 -48.34509) (xy 239.16386 -48.29429) (xy 238.98606 -48.29429) (xy 238.98606 -48.34509)
			(xy 239.02162 -48.44669) (xy 239.1283 -48.44669)
		)
		(stroke
			(width 0)
			(type solid)
		)
		(fill yes)
		(layer "F.Cu")
		(net "M_B_DQS_DP<12>")
	)
	(gr_poly
		(pts
			(xy 239.16386 -48.04029) (xy 239.16386 -47.98949) (xy 238.98606 -47.98949) (xy 238.98606 -48.04029)
			(xy 239.02162 -48.14189) (xy 239.1283 -48.14189)
		)
		(stroke
			(width 0)
			(type solid)
		)
		(fill yes)
		(layer "F.Cu")
		(net "M_B_DQS_DN<12>")
	)
	(gr_poly
		(pts
			(xy 239.16386 -47.73549) (xy 239.16386 -47.68469) (xy 238.98606 -47.68469) (xy 238.98606 -47.73549)
			(xy 239.02162 -47.83709) (xy 239.1283 -47.83709)
		)
		(stroke
			(width 0)
			(type solid)
		)
		(fill yes)
		(layer "F.Cu")
		(net "M_B_DQS_DN<3>")
	)
	(gr_poly
		(pts
			(xy 239.16386 -47.43069) (xy 239.16386 -47.37989) (xy 238.98606 -47.37989) (xy 238.98606 -47.43069)
			(xy 239.02162 -47.53229) (xy 239.1283 -47.53229)
		)
		(stroke
			(width 0)
			(type solid)
		)
		(fill yes)
		(layer "F.Cu")
		(net "M_B_DQS_DP<3>")
	)
	(gr_poly
		(pts
			(xy 239.16386 -47.12589) (xy 239.16386 -47.07509) (xy 238.98606 -47.07509) (xy 238.98606 -47.12589)
			(xy 239.02162 -47.22749) (xy 239.1283 -47.22749)
		)
		(stroke
			(width 0)
			(type solid)
		)
		(fill yes)
		(layer "F.Cu")
		(net "M_B_DQ<30>")
	)
	(gr_poly
		(pts
			(xy 239.16386 -46.82109) (xy 239.16386 -46.77029) (xy 238.98606 -46.77029) (xy 238.98606 -46.82109)
			(xy 239.02162 -46.92269) (xy 239.1283 -46.92269)
		)
		(stroke
			(width 0)
			(type solid)
		)
		(fill yes)
		(layer "F.Cu")
		(net "M_B_DQ<31>")
	)
	(gr_poly
		(pts
			(xy 239.16386 -46.51629) (xy 239.16386 -46.46549) (xy 238.98606 -46.46549) (xy 238.98606 -46.51629)
			(xy 239.02162 -46.61789) (xy 239.1283 -46.61789)
		)
		(stroke
			(width 0)
			(type solid)
		)
		(fill yes)
		(layer "F.Cu")
		(net "M_B_DQ<26>")
	)
	(gr_poly
		(pts
			(xy 239.16386 -46.21149) (xy 239.16386 -46.14799) (xy 238.98606 -46.14799) (xy 238.98606 -46.21149)
			(xy 239.02162 -46.31309) (xy 239.1283 -46.31309)
		)
		(stroke
			(width 0)
			(type solid)
		)
		(fill yes)
		(layer "F.Cu")
		(net "M_B_DQ<27>")
	)
	(gr_poly
		(pts
			(xy 239.178592 -104.695752) (xy 239.131856 -104.598724) (xy 239.095788 -104.56291) (xy 238.970058 -104.68864)
			(xy 239.006126 -104.724454) (xy 239.103154 -104.77119)
		)
		(stroke
			(width 0)
			(type solid)
		)
		(fill yes)
		(layer "F.Cu")
		(net "M_E_DQS_DN<3>")
	)
	(gr_poly
		(pts
			(xy 239.195102 -106.188764) (xy 239.159288 -106.152696) (xy 239.06226 -106.106214) (xy 238.986822 -106.181652)
			(xy 239.033558 -106.278426) (xy 239.069372 -106.314494)
		)
		(stroke
			(width 0)
			(type solid)
		)
		(fill yes)
		(layer "F.Cu")
		(net "M_E_DQ<26>")
	)
	(gr_poly
		(pts
			(xy 239.211104 -103.151686) (xy 239.17529 -103.115618) (xy 239.078262 -103.068882) (xy 239.002824 -103.14432)
			(xy 239.04956 -103.241348) (xy 239.085374 -103.277416)
		)
		(stroke
			(width 0)
			(type solid)
		)
		(fill yes)
		(layer "F.Cu")
		(net "M_E_DQ<25>")
	)
	(gr_poly
		(pts
			(xy 239.21466 -105.953306) (xy 239.168178 -105.856278) (xy 239.13211 -105.820464) (xy 239.00638 -105.946194)
			(xy 239.042448 -105.982008) (xy 239.139222 -106.028744)
		)
		(stroke
			(width 0)
			(type solid)
		)
		(fill yes)
		(layer "F.Cu")
		(net "M_E_DQ<31>")
	)
	(gr_poly
		(pts
			(xy 239.248442 -104.410256) (xy 239.212628 -104.374188) (xy 239.1156 -104.327452) (xy 239.040162 -104.40289)
			(xy 239.086898 -104.499918) (xy 239.122712 -104.535986)
		)
		(stroke
			(width 0)
			(type solid)
		)
		(fill yes)
		(layer "F.Cu")
		(net "M_E_DQS_DN<3>")
	)
	(gr_poly
		(pts
			(xy 239.268254 -104.174798) (xy 239.221518 -104.07777) (xy 239.18545 -104.041956) (xy 239.05972 -104.167686)
			(xy 239.095788 -104.2035) (xy 239.192816 -104.250236)
		)
		(stroke
			(width 0)
			(type solid)
		)
		(fill yes)
		(layer "F.Cu")
		(net "M_E_DQS_DN<12>")
	)
	(gr_poly
		(pts
			(xy 239.284764 -105.66781) (xy 239.24895 -105.631742) (xy 239.151922 -105.58526) (xy 239.076484 -105.660698)
			(xy 239.12322 -105.757472) (xy 239.159034 -105.79354)
		)
		(stroke
			(width 0)
			(type solid)
		)
		(fill yes)
		(layer "F.Cu")
		(net "M_E_DQ<31>")
	)
	(gr_poly
		(pts
			(xy 239.304576 -105.432352) (xy 239.25784 -105.335324) (xy 239.221772 -105.29951) (xy 239.096042 -105.42524)
			(xy 239.13211 -105.461054) (xy 239.229138 -105.50779)
		)
		(stroke
			(width 0)
			(type solid)
		)
		(fill yes)
		(layer "F.Cu")
		(net "M_E_DQ<30>")
	)
	(gr_poly
		(pts
			(xy 239.336834 -102.882954) (xy 239.336834 -102.832154) (xy 239.159034 -102.832154) (xy 239.159034 -102.882954)
			(xy 239.194594 -102.984554) (xy 239.301274 -102.984554)
		)
		(stroke
			(width 0)
			(type solid)
		)
		(fill yes)
		(layer "F.Cu")
		(net "M_E_DQ<24>")
	)
	(gr_poly
		(pts
			(xy 239.336834 -102.578154) (xy 239.336834 -102.527354) (xy 239.159034 -102.527354) (xy 239.159034 -102.578154)
			(xy 239.194594 -102.679754) (xy 239.301274 -102.679754)
		)
		(stroke
			(width 0)
			(type solid)
		)
		(fill yes)
		(layer "F.Cu")
		(net "M_E_DQ<29>")
	)
	(gr_poly
		(pts
			(xy 239.336834 -102.273354) (xy 239.336834 -102.209854) (xy 239.159034 -102.209854) (xy 239.159034 -102.273354)
			(xy 239.194594 -102.374954) (xy 239.301274 -102.374954)
		)
		(stroke
			(width 0)
			(type solid)
		)
		(fill yes)
		(layer "F.Cu")
		(net "M_E_DQ<28>")
	)
	(gr_poly
		(pts
			(xy 239.338104 -103.889302) (xy 239.30229 -103.853234) (xy 239.205262 -103.806498) (xy 239.129824 -103.881936)
			(xy 239.17656 -103.978964) (xy 239.212374 -104.015032)
		)
		(stroke
			(width 0)
			(type solid)
		)
		(fill yes)
		(layer "F.Cu")
		(net "M_E_DQS_DN<12>")
	)
	(gr_poly
		(pts
			(xy 239.357916 -103.653844) (xy 239.31118 -103.556816) (xy 239.275112 -103.521002) (xy 239.149382 -103.646732)
			(xy 239.18545 -103.682546) (xy 239.282478 -103.729282)
		)
		(stroke
			(width 0)
			(type solid)
		)
		(fill yes)
		(layer "F.Cu")
		(net "M_E_DQS_DP<12>")
	)
	(gr_poly
		(pts
			(xy 239.374426 -105.146856) (xy 239.338612 -105.110788) (xy 239.241584 -105.064052) (xy 239.166146 -105.13949)
			(xy 239.212882 -105.236518) (xy 239.248696 -105.272586)
		)
		(stroke
			(width 0)
			(type solid)
		)
		(fill yes)
		(layer "F.Cu")
		(net "M_E_DQ<30>")
	)
	(gr_poly
		(pts
			(xy 239.37976 -49.46269) (xy 239.3442 -49.36109) (xy 239.23752 -49.36109) (xy 239.20196 -49.46269)
			(xy 239.20196 -49.52619) (xy 239.37976 -49.52619)
		)
		(stroke
			(width 0)
			(type solid)
		)
		(fill yes)
		(layer "F.Cu")
		(net "M_B_DQ<28>")
	)
	(gr_poly
		(pts
			(xy 239.37976 -49.15789) (xy 239.3442 -49.05629) (xy 239.23752 -49.05629) (xy 239.20196 -49.15789)
			(xy 239.20196 -49.20869) (xy 239.37976 -49.20869)
		)
		(stroke
			(width 0)
			(type solid)
		)
		(fill yes)
		(layer "F.Cu")
		(net "M_B_DQ<29>")
	)
	(gr_poly
		(pts
			(xy 239.37976 -48.85309) (xy 239.3442 -48.75149) (xy 239.23752 -48.75149) (xy 239.20196 -48.85309)
			(xy 239.20196 -48.90389) (xy 239.37976 -48.90389)
		)
		(stroke
			(width 0)
			(type solid)
		)
		(fill yes)
		(layer "F.Cu")
		(net "M_B_DQ<24>")
	)
	(gr_poly
		(pts
			(xy 239.37976 -48.54829) (xy 239.3442 -48.44669) (xy 239.23752 -48.44669) (xy 239.20196 -48.54829)
			(xy 239.20196 -48.59909) (xy 239.37976 -48.59909)
		)
		(stroke
			(width 0)
			(type solid)
		)
		(fill yes)
		(layer "F.Cu")
		(net "M_B_DQ<25>")
	)
	(gr_poly
		(pts
			(xy 239.37976 -48.24349) (xy 239.3442 -48.14189) (xy 239.23752 -48.14189) (xy 239.20196 -48.24349)
			(xy 239.20196 -48.29429) (xy 239.37976 -48.29429)
		)
		(stroke
			(width 0)
			(type solid)
		)
		(fill yes)
		(layer "F.Cu")
		(net "M_B_DQS_DP<12>")
	)
	(gr_poly
		(pts
			(xy 239.37976 -47.93869) (xy 239.3442 -47.83709) (xy 239.23752 -47.83709) (xy 239.20196 -47.93869)
			(xy 239.20196 -47.98949) (xy 239.37976 -47.98949)
		)
		(stroke
			(width 0)
			(type solid)
		)
		(fill yes)
		(layer "F.Cu")
		(net "M_B_DQS_DN<12>")
	)
	(gr_poly
		(pts
			(xy 239.37976 -47.63389) (xy 239.3442 -47.53229) (xy 239.23752 -47.53229) (xy 239.20196 -47.63389)
			(xy 239.20196 -47.68469) (xy 239.37976 -47.68469)
		)
		(stroke
			(width 0)
			(type solid)
		)
		(fill yes)
		(layer "F.Cu")
		(net "M_B_DQS_DN<3>")
	)
	(gr_poly
		(pts
			(xy 239.37976 -47.32909) (xy 239.3442 -47.22749) (xy 239.23752 -47.22749) (xy 239.20196 -47.32909)
			(xy 239.20196 -47.37989) (xy 239.37976 -47.37989)
		)
		(stroke
			(width 0)
			(type solid)
		)
		(fill yes)
		(layer "F.Cu")
		(net "M_B_DQS_DP<3>")
	)
	(gr_poly
		(pts
			(xy 239.37976 -47.02429) (xy 239.3442 -46.92269) (xy 239.23752 -46.92269) (xy 239.20196 -47.02429)
			(xy 239.20196 -47.07509) (xy 239.37976 -47.07509)
		)
		(stroke
			(width 0)
			(type solid)
		)
		(fill yes)
		(layer "F.Cu")
		(net "M_B_DQ<30>")
	)
	(gr_poly
		(pts
			(xy 239.37976 -46.71949) (xy 239.3442 -46.61789) (xy 239.23752 -46.61789) (xy 239.20196 -46.71949)
			(xy 239.20196 -46.77029) (xy 239.37976 -46.77029)
		)
		(stroke
			(width 0)
			(type solid)
		)
		(fill yes)
		(layer "F.Cu")
		(net "M_B_DQ<31>")
	)
	(gr_poly
		(pts
			(xy 239.37976 -46.41469) (xy 239.3442 -46.31309) (xy 239.23752 -46.31309) (xy 239.20196 -46.41469)
			(xy 239.20196 -46.46549) (xy 239.37976 -46.46549)
		)
		(stroke
			(width 0)
			(type solid)
		)
		(fill yes)
		(layer "F.Cu")
		(net "M_B_DQ<26>")
	)
	(gr_poly
		(pts
			(xy 239.394238 -104.911398) (xy 239.347502 -104.81437) (xy 239.311434 -104.778556) (xy 239.185704 -104.904286)
			(xy 239.221772 -104.9401) (xy 239.3188 -104.986836)
		)
		(stroke
			(width 0)
			(type solid)
		)
		(fill yes)
		(layer "F.Cu")
		(net "M_E_DQS_DP<3>")
	)
	(gr_poly
		(pts
			(xy 239.419638 -106.4133) (xy 239.37468 -106.368342) (xy 239.277906 -106.321606) (xy 239.202468 -106.397044)
			(xy 239.24895 -106.494072) (xy 239.293908 -106.53903)
		)
		(stroke
			(width 0)
			(type solid)
		)
		(fill yes)
		(layer "F.Cu")
		(net "M_E_DQ<27>")
	)
	(gr_poly
		(pts
			(xy 239.430306 -106.168952) (xy 239.383824 -106.071924) (xy 239.347756 -106.03611) (xy 239.222026 -106.16184)
			(xy 239.258094 -106.197654) (xy 239.354868 -106.24439)
		)
		(stroke
			(width 0)
			(type solid)
		)
		(fill yes)
		(layer "F.Cu")
		(net "M_E_DQ<26>")
	)
	(gr_poly
		(pts
			(xy 239.464088 -104.625902) (xy 239.428274 -104.589834) (xy 239.331246 -104.543098) (xy 239.255808 -104.618536)
			(xy 239.302544 -104.715564) (xy 239.338358 -104.751632)
		)
		(stroke
			(width 0)
			(type solid)
		)
		(fill yes)
		(layer "F.Cu")
		(net "M_E_DQS_DP<3>")
	)
	(gr_poly
		(pts
			(xy 239.4839 -104.390444) (xy 239.437164 -104.293416) (xy 239.401096 -104.257602) (xy 239.275366 -104.383332)
			(xy 239.311434 -104.419146) (xy 239.408462 -104.465882)
		)
		(stroke
			(width 0)
			(type solid)
		)
		(fill yes)
		(layer "F.Cu")
		(net "M_E_DQS_DN<3>")
	)
	(gr_poly
		(pts
			(xy 239.50041 -105.883456) (xy 239.464596 -105.847388) (xy 239.367568 -105.800906) (xy 239.29213 -105.876344)
			(xy 239.338866 -105.973118) (xy 239.37468 -106.009186)
		)
		(stroke
			(width 0)
			(type solid)
		)
		(fill yes)
		(layer "F.Cu")
		(net "M_E_DQ<26>")
	)
	(gr_poly
		(pts
			(xy 239.520222 -105.647998) (xy 239.473486 -105.55097) (xy 239.437418 -105.515156) (xy 239.311688 -105.640886)
			(xy 239.347756 -105.6767) (xy 239.444784 -105.723436)
		)
		(stroke
			(width 0)
			(type solid)
		)
		(fill yes)
		(layer "F.Cu")
		(net "M_E_DQ<31>")
	)
	(gr_poly
		(pts
			(xy 239.552734 -103.390954) (xy 239.517174 -103.289354) (xy 239.410494 -103.289354) (xy 239.374934 -103.390954)
			(xy 239.374934 -103.441754) (xy 239.552734 -103.441754)
		)
		(stroke
			(width 0)
			(type solid)
		)
		(fill yes)
		(layer "F.Cu")
		(net "M_E_DQS_DP<12>")
	)
	(gr_poly
		(pts
			(xy 239.552734 -103.086154) (xy 239.517174 -102.984554) (xy 239.410494 -102.984554) (xy 239.374934 -103.086154)
			(xy 239.374934 -103.136954) (xy 239.552734 -103.136954)
		)
		(stroke
			(width 0)
			(type solid)
		)
		(fill yes)
		(layer "F.Cu")
		(net "M_E_DQ<25>")
	)
	(gr_poly
		(pts
			(xy 239.552734 -102.781354) (xy 239.517174 -102.679754) (xy 239.410494 -102.679754) (xy 239.374934 -102.781354)
			(xy 239.374934 -102.832154) (xy 239.552734 -102.832154)
		)
		(stroke
			(width 0)
			(type solid)
		)
		(fill yes)
		(layer "F.Cu")
		(net "M_E_DQ<24>")
	)
	(gr_poly
		(pts
			(xy 239.552734 -102.476554) (xy 239.517174 -102.374954) (xy 239.410494 -102.374954) (xy 239.374934 -102.476554)
			(xy 239.374934 -102.527354) (xy 239.552734 -102.527354)
		)
		(stroke
			(width 0)
			(type solid)
		)
		(fill yes)
		(layer "F.Cu")
		(net "M_E_DQ<29>")
	)
	(gr_poly
		(pts
			(xy 239.55375 -104.104948) (xy 239.517936 -104.06888) (xy 239.420908 -104.022144) (xy 239.34547 -104.097582)
			(xy 239.392206 -104.19461) (xy 239.42802 -104.230678)
		)
		(stroke
			(width 0)
			(type solid)
		)
		(fill yes)
		(layer "F.Cu")
		(net "M_E_DQS_DN<3>")
	)
	(gr_poly
		(pts
			(xy 239.590072 -105.362502) (xy 239.554258 -105.326434) (xy 239.45723 -105.279698) (xy 239.381792 -105.355136)
			(xy 239.428528 -105.452164) (xy 239.464342 -105.488232)
		)
		(stroke
			(width 0)
			(type solid)
		)
		(fill yes)
		(layer "F.Cu")
		(net "M_E_DQ<31>")
	)
	(gr_poly
		(pts
			(xy 239.59566 -49.25949) (xy 239.59566 -49.20869) (xy 239.41786 -49.20869) (xy 239.41786 -49.25949)
			(xy 239.45342 -49.36109) (xy 239.5601 -49.36109)
		)
		(stroke
			(width 0)
			(type solid)
		)
		(fill yes)
		(layer "F.Cu")
		(net "M_B_DQ<29>")
	)
	(gr_poly
		(pts
			(xy 239.59566 -48.95469) (xy 239.59566 -48.90389) (xy 239.41786 -48.90389) (xy 239.41786 -48.95469)
			(xy 239.45342 -49.05629) (xy 239.5601 -49.05629)
		)
		(stroke
			(width 0)
			(type solid)
		)
		(fill yes)
		(layer "F.Cu")
		(net "M_B_DQ<24>")
	)
	(gr_poly
		(pts
			(xy 239.59566 -48.64989) (xy 239.59566 -48.59909) (xy 239.41786 -48.59909) (xy 239.41786 -48.64989)
			(xy 239.45342 -48.75149) (xy 239.5601 -48.75149)
		)
		(stroke
			(width 0)
			(type solid)
		)
		(fill yes)
		(layer "F.Cu")
		(net "M_B_DQ<25>")
	)
	(gr_poly
		(pts
			(xy 239.59566 -48.34509) (xy 239.59566 -48.29429) (xy 239.41786 -48.29429) (xy 239.41786 -48.34509)
			(xy 239.45342 -48.44669) (xy 239.5601 -48.44669)
		)
		(stroke
			(width 0)
			(type solid)
		)
		(fill yes)
		(layer "F.Cu")
		(net "M_B_DQS_DP<12>")
	)
	(gr_poly
		(pts
			(xy 239.59566 -48.04029) (xy 239.59566 -47.98949) (xy 239.41786 -47.98949) (xy 239.41786 -48.04029)
			(xy 239.45342 -48.14189) (xy 239.5601 -48.14189)
		)
		(stroke
			(width 0)
			(type solid)
		)
		(fill yes)
		(layer "F.Cu")
		(net "M_B_DQS_DN<12>")
	)
	(gr_poly
		(pts
			(xy 239.59566 -47.73549) (xy 239.59566 -47.68469) (xy 239.41786 -47.68469) (xy 239.41786 -47.73549)
			(xy 239.45342 -47.83709) (xy 239.5601 -47.83709)
		)
		(stroke
			(width 0)
			(type solid)
		)
		(fill yes)
		(layer "F.Cu")
		(net "M_B_DQS_DN<3>")
	)
	(gr_poly
		(pts
			(xy 239.59566 -47.43069) (xy 239.59566 -47.37989) (xy 239.41786 -47.37989) (xy 239.41786 -47.43069)
			(xy 239.45342 -47.53229) (xy 239.5601 -47.53229)
		)
		(stroke
			(width 0)
			(type solid)
		)
		(fill yes)
		(layer "F.Cu")
		(net "M_B_DQS_DP<3>")
	)
	(gr_poly
		(pts
			(xy 239.59566 -47.12589) (xy 239.59566 -47.07509) (xy 239.41786 -47.07509) (xy 239.41786 -47.12589)
			(xy 239.45342 -47.22749) (xy 239.5601 -47.22749)
		)
		(stroke
			(width 0)
			(type solid)
		)
		(fill yes)
		(layer "F.Cu")
		(net "M_B_DQ<30>")
	)
	(gr_poly
		(pts
			(xy 239.59566 -46.82109) (xy 239.59566 -46.77029) (xy 239.41786 -46.77029) (xy 239.41786 -46.82109)
			(xy 239.45342 -46.92269) (xy 239.5601 -46.92269)
		)
		(stroke
			(width 0)
			(type solid)
		)
		(fill yes)
		(layer "F.Cu")
		(net "M_B_DQ<31>")
	)
	(gr_poly
		(pts
			(xy 239.59566 -46.51629) (xy 239.59566 -46.46549) (xy 239.41786 -46.46549) (xy 239.41786 -46.51629)
			(xy 239.45342 -46.61789) (xy 239.5601 -46.61789)
		)
		(stroke
			(width 0)
			(type solid)
		)
		(fill yes)
		(layer "F.Cu")
		(net "M_B_DQ<26>")
	)
	(gr_poly
		(pts
			(xy 239.59566 -46.21149) (xy 239.59566 -46.14799) (xy 239.41786 -46.14799) (xy 239.41786 -46.21149)
			(xy 239.45342 -46.31309) (xy 239.5601 -46.31309)
		)
		(stroke
			(width 0)
			(type solid)
		)
		(fill yes)
		(layer "F.Cu")
		(net "M_B_DQ<27>")
	)
	(gr_poly
		(pts
			(xy 239.609884 -105.127044) (xy 239.563148 -105.030016) (xy 239.52708 -104.994202) (xy 239.40135 -105.119932)
			(xy 239.437418 -105.155746) (xy 239.534446 -105.202482)
		)
		(stroke
			(width 0)
			(type solid)
		)
		(fill yes)
		(layer "F.Cu")
		(net "M_E_DQ<30>")
	)
	(gr_poly
		(pts
			(xy 239.679734 -104.841548) (xy 239.64392 -104.80548) (xy 239.546892 -104.758744) (xy 239.471454 -104.834182)
			(xy 239.51819 -104.93121) (xy 239.554004 -104.967278)
		)
		(stroke
			(width 0)
			(type solid)
		)
		(fill yes)
		(layer "F.Cu")
		(net "M_E_DQ<30>")
	)
	(gr_poly
		(pts
			(xy 239.699546 -104.60609) (xy 239.65281 -104.509062) (xy 239.616742 -104.473248) (xy 239.491012 -104.598978)
			(xy 239.52708 -104.634792) (xy 239.624108 -104.681528)
		)
		(stroke
			(width 0)
			(type solid)
		)
		(fill yes)
		(layer "F.Cu")
		(net "M_E_DQS_DP<3>")
	)
	(gr_poly
		(pts
			(xy 239.724946 -106.107992) (xy 239.679988 -106.063034) (xy 239.583214 -106.016298) (xy 239.507776 -106.091736)
			(xy 239.554258 -106.188764) (xy 239.599216 -106.233722)
		)
		(stroke
			(width 0)
			(type solid)
		)
		(fill yes)
		(layer "F.Cu")
		(net "M_E_DQ<27>")
	)
	(gr_poly
		(pts
			(xy 239.735868 -105.863644) (xy 239.689132 -105.766616) (xy 239.653064 -105.730802) (xy 239.527334 -105.856532)
			(xy 239.563402 -105.892346) (xy 239.66043 -105.939082)
		)
		(stroke
			(width 0)
			(type solid)
		)
		(fill yes)
		(layer "F.Cu")
		(net "M_E_DQ<26>")
	)
	(gr_poly
		(pts
			(xy 239.737392 -45.146468) (xy 239.724692 -44.955968) (xy 239.623092 -44.955968) (xy 239.610392 -45.146468)
			(xy 239.610392 -45.209968) (xy 239.737392 -45.209968)
		)
		(stroke
			(width 0)
			(type solid)
		)
		(fill yes)
		(layer "F.Cu")
		(net "M_B_ECC<4>")
	)
	(gr_poly
		(pts
			(xy 239.737392 -44.752768) (xy 239.724692 -44.562268) (xy 239.623092 -44.562268) (xy 239.610392 -44.752768)
			(xy 239.610392 -44.803568) (xy 239.737392 -44.803568)
		)
		(stroke
			(width 0)
			(type solid)
		)
		(fill yes)
		(layer "F.Cu")
		(net "M_B_ECC<5>")
	)
	(gr_poly
		(pts
			(xy 239.768634 -103.797354) (xy 239.768634 -103.746554) (xy 239.590834 -103.746554) (xy 239.590834 -103.797354)
			(xy 239.626394 -103.898954) (xy 239.733074 -103.898954)
		)
		(stroke
			(width 0)
			(type solid)
		)
		(fill yes)
		(layer "F.Cu")
		(net "M_E_DQS_DN<12>")
	)
	(gr_poly
		(pts
			(xy 239.768634 -103.492554) (xy 239.768634 -103.441754) (xy 239.590834 -103.441754) (xy 239.590834 -103.492554)
			(xy 239.626394 -103.594154) (xy 239.733074 -103.594154)
		)
		(stroke
			(width 0)
			(type solid)
		)
		(fill yes)
		(layer "F.Cu")
		(net "M_E_DQS_DP<12>")
	)
	(gr_poly
		(pts
			(xy 239.768634 -103.187754) (xy 239.768634 -103.136954) (xy 239.590834 -103.136954) (xy 239.590834 -103.187754)
			(xy 239.626394 -103.289354) (xy 239.733074 -103.289354)
		)
		(stroke
			(width 0)
			(type solid)
		)
		(fill yes)
		(layer "F.Cu")
		(net "M_E_DQ<25>")
	)
	(gr_poly
		(pts
			(xy 239.768634 -102.882954) (xy 239.768634 -102.832154) (xy 239.590834 -102.832154) (xy 239.590834 -102.882954)
			(xy 239.626394 -102.984554) (xy 239.733074 -102.984554)
		)
		(stroke
			(width 0)
			(type solid)
		)
		(fill yes)
		(layer "F.Cu")
		(net "M_E_DQ<24>")
	)
	(gr_poly
		(pts
			(xy 239.768634 -102.578154) (xy 239.768634 -102.527354) (xy 239.590834 -102.527354) (xy 239.590834 -102.578154)
			(xy 239.626394 -102.679754) (xy 239.733074 -102.679754)
		)
		(stroke
			(width 0)
			(type solid)
		)
		(fill yes)
		(layer "F.Cu")
		(net "M_E_DQ<29>")
	)
	(gr_poly
		(pts
			(xy 239.768634 -102.273354) (xy 239.768634 -102.209854) (xy 239.590834 -102.209854) (xy 239.590834 -102.273354)
			(xy 239.626394 -102.374954) (xy 239.733074 -102.374954)
		)
		(stroke
			(width 0)
			(type solid)
		)
		(fill yes)
		(layer "F.Cu")
		(net "M_E_DQ<28>")
	)
	(gr_poly
		(pts
			(xy 239.805718 -105.578148) (xy 239.769904 -105.54208) (xy 239.672876 -105.495344) (xy 239.597438 -105.570782)
			(xy 239.644174 -105.66781) (xy 239.679988 -105.703878)
		)
		(stroke
			(width 0)
			(type solid)
		)
		(fill yes)
		(layer "F.Cu")
		(net "M_E_DQ<26>")
	)
	(gr_poly
		(pts
			(xy 239.81156 -49.46269) (xy 239.776 -49.36109) (xy 239.66932 -49.36109) (xy 239.63376 -49.46269)
			(xy 239.63376 -49.52619) (xy 239.81156 -49.52619)
		)
		(stroke
			(width 0)
			(type solid)
		)
		(fill yes)
		(layer "F.Cu")
		(net "M_B_DQ<28>")
	)
	(gr_poly
		(pts
			(xy 239.81156 -49.15789) (xy 239.776 -49.05629) (xy 239.66932 -49.05629) (xy 239.63376 -49.15789)
			(xy 239.63376 -49.20869) (xy 239.81156 -49.20869)
		)
		(stroke
			(width 0)
			(type solid)
		)
		(fill yes)
		(layer "F.Cu")
		(net "M_B_DQ<29>")
	)
	(gr_poly
		(pts
			(xy 239.81156 -48.85309) (xy 239.776 -48.75149) (xy 239.66932 -48.75149) (xy 239.63376 -48.85309)
			(xy 239.63376 -48.90389) (xy 239.81156 -48.90389)
		)
		(stroke
			(width 0)
			(type solid)
		)
		(fill yes)
		(layer "F.Cu")
		(net "M_B_DQ<24>")
	)
	(gr_poly
		(pts
			(xy 239.81156 -48.54829) (xy 239.776 -48.44669) (xy 239.66932 -48.44669) (xy 239.63376 -48.54829)
			(xy 239.63376 -48.59909) (xy 239.81156 -48.59909)
		)
		(stroke
			(width 0)
			(type solid)
		)
		(fill yes)
		(layer "F.Cu")
		(net "M_B_DQ<25>")
	)
	(gr_poly
		(pts
			(xy 239.81156 -48.24349) (xy 239.776 -48.14189) (xy 239.66932 -48.14189) (xy 239.63376 -48.24349)
			(xy 239.63376 -48.29429) (xy 239.81156 -48.29429)
		)
		(stroke
			(width 0)
			(type solid)
		)
		(fill yes)
		(layer "F.Cu")
		(net "M_B_DQS_DP<12>")
	)
	(gr_poly
		(pts
			(xy 239.81156 -47.93869) (xy 239.776 -47.83709) (xy 239.66932 -47.83709) (xy 239.63376 -47.93869)
			(xy 239.63376 -47.98949) (xy 239.81156 -47.98949)
		)
		(stroke
			(width 0)
			(type solid)
		)
		(fill yes)
		(layer "F.Cu")
		(net "M_B_DQS_DN<12>")
	)
	(gr_poly
		(pts
			(xy 239.81156 -47.63389) (xy 239.776 -47.53229) (xy 239.66932 -47.53229) (xy 239.63376 -47.63389)
			(xy 239.63376 -47.68469) (xy 239.81156 -47.68469)
		)
		(stroke
			(width 0)
			(type solid)
		)
		(fill yes)
		(layer "F.Cu")
		(net "M_B_DQS_DN<3>")
	)
	(gr_poly
		(pts
			(xy 239.81156 -47.32909) (xy 239.776 -47.22749) (xy 239.66932 -47.22749) (xy 239.63376 -47.32909)
			(xy 239.63376 -47.37989) (xy 239.81156 -47.37989)
		)
		(stroke
			(width 0)
			(type solid)
		)
		(fill yes)
		(layer "F.Cu")
		(net "M_B_DQS_DP<3>")
	)
	(gr_poly
		(pts
			(xy 239.81156 -47.02429) (xy 239.776 -46.92269) (xy 239.66932 -46.92269) (xy 239.63376 -47.02429)
			(xy 239.63376 -47.07509) (xy 239.81156 -47.07509)
		)
		(stroke
			(width 0)
			(type solid)
		)
		(fill yes)
		(layer "F.Cu")
		(net "M_B_DQ<30>")
	)
	(gr_poly
		(pts
			(xy 239.81156 -46.71949) (xy 239.776 -46.61789) (xy 239.66932 -46.61789) (xy 239.63376 -46.71949)
			(xy 239.63376 -46.77029) (xy 239.81156 -46.77029)
		)
		(stroke
			(width 0)
			(type solid)
		)
		(fill yes)
		(layer "F.Cu")
		(net "M_B_DQ<31>")
	)
	(gr_poly
		(pts
			(xy 239.81156 -46.41469) (xy 239.776 -46.31309) (xy 239.66932 -46.31309) (xy 239.63376 -46.41469)
			(xy 239.63376 -46.46549) (xy 239.81156 -46.46549)
		)
		(stroke
			(width 0)
			(type solid)
		)
		(fill yes)
		(layer "F.Cu")
		(net "M_B_DQ<26>")
	)
	(gr_poly
		(pts
			(xy 239.82553 -105.34269) (xy 239.778794 -105.245662) (xy 239.742726 -105.209848) (xy 239.616996 -105.335578)
			(xy 239.653064 -105.371392) (xy 239.750092 -105.418128)
		)
		(stroke
			(width 0)
			(type solid)
		)
		(fill yes)
		(layer "F.Cu")
		(net "M_E_DQ<31>")
	)
	(gr_poly
		(pts
			(xy 239.89538 -105.057194) (xy 239.859566 -105.021126) (xy 239.762538 -104.97439) (xy 239.6871 -105.049828)
			(xy 239.733836 -105.146856) (xy 239.76965 -105.182924)
		)
		(stroke
			(width 0)
			(type solid)
		)
		(fill yes)
		(layer "F.Cu")
		(net "M_E_DQ<31>")
	)
	(gr_poly
		(pts
			(xy 239.915192 -104.821736) (xy 239.868456 -104.724708) (xy 239.832388 -104.688894) (xy 239.706658 -104.814624)
			(xy 239.742726 -104.850438) (xy 239.839754 -104.897174)
		)
		(stroke
			(width 0)
			(type solid)
		)
		(fill yes)
		(layer "F.Cu")
		(net "M_E_DQ<30>")
	)
	(gr_poly
		(pts
			(xy 239.984534 -104.305354) (xy 239.948974 -104.203754) (xy 239.842294 -104.203754) (xy 239.806734 -104.305354)
			(xy 239.806734 -104.356154) (xy 239.984534 -104.356154)
		)
		(stroke
			(width 0)
			(type solid)
		)
		(fill yes)
		(layer "F.Cu")
		(net "M_E_DQS_DP<3>")
	)
	(gr_poly
		(pts
			(xy 239.984534 -104.000554) (xy 239.948974 -103.898954) (xy 239.842294 -103.898954) (xy 239.806734 -104.000554)
			(xy 239.806734 -104.051354) (xy 239.984534 -104.051354)
		)
		(stroke
			(width 0)
			(type solid)
		)
		(fill yes)
		(layer "F.Cu")
		(net "M_E_DQS_DN<3>")
	)
	(gr_poly
		(pts
			(xy 239.984534 -103.695754) (xy 239.948974 -103.594154) (xy 239.842294 -103.594154) (xy 239.806734 -103.695754)
			(xy 239.806734 -103.746554) (xy 239.984534 -103.746554)
		)
		(stroke
			(width 0)
			(type solid)
		)
		(fill yes)
		(layer "F.Cu")
		(net "M_E_DQS_DN<12>")
	)
	(gr_poly
		(pts
			(xy 239.984534 -103.390954) (xy 239.948974 -103.289354) (xy 239.842294 -103.289354) (xy 239.806734 -103.390954)
			(xy 239.806734 -103.441754) (xy 239.984534 -103.441754)
		)
		(stroke
			(width 0)
			(type solid)
		)
		(fill yes)
		(layer "F.Cu")
		(net "M_E_DQS_DP<12>")
	)
	(gr_poly
		(pts
			(xy 239.984534 -103.086154) (xy 239.948974 -102.984554) (xy 239.842294 -102.984554) (xy 239.806734 -103.086154)
			(xy 239.806734 -103.136954) (xy 239.984534 -103.136954)
		)
		(stroke
			(width 0)
			(type solid)
		)
		(fill yes)
		(layer "F.Cu")
		(net "M_E_DQ<25>")
	)
	(gr_poly
		(pts
			(xy 239.984534 -102.781354) (xy 239.948974 -102.679754) (xy 239.842294 -102.679754) (xy 239.806734 -102.781354)
			(xy 239.806734 -102.832154) (xy 239.984534 -102.832154)
		)
		(stroke
			(width 0)
			(type solid)
		)
		(fill yes)
		(layer "F.Cu")
		(net "M_E_DQ<24>")
	)
	(gr_poly
		(pts
			(xy 239.984534 -102.476554) (xy 239.948974 -102.374954) (xy 239.842294 -102.374954) (xy 239.806734 -102.476554)
			(xy 239.806734 -102.527354) (xy 239.984534 -102.527354)
		)
		(stroke
			(width 0)
			(type solid)
		)
		(fill yes)
		(layer "F.Cu")
		(net "M_E_DQ<29>")
	)
	(gr_poly
		(pts
			(xy 240.02746 -49.25949) (xy 240.02746 -49.20869) (xy 239.84966 -49.20869) (xy 239.84966 -49.25949)
			(xy 239.88522 -49.36109) (xy 239.9919 -49.36109)
		)
		(stroke
			(width 0)
			(type solid)
		)
		(fill yes)
		(layer "F.Cu")
		(net "M_B_DQ<29>")
	)
	(gr_poly
		(pts
			(xy 240.02746 -48.95469) (xy 240.02746 -48.90389) (xy 239.84966 -48.90389) (xy 239.84966 -48.95469)
			(xy 239.88522 -49.05629) (xy 239.9919 -49.05629)
		)
		(stroke
			(width 0)
			(type solid)
		)
		(fill yes)
		(layer "F.Cu")
		(net "M_B_DQ<24>")
	)
	(gr_poly
		(pts
			(xy 240.02746 -48.64989) (xy 240.02746 -48.59909) (xy 239.84966 -48.59909) (xy 239.84966 -48.64989)
			(xy 239.88522 -48.75149) (xy 239.9919 -48.75149)
		)
		(stroke
			(width 0)
			(type solid)
		)
		(fill yes)
		(layer "F.Cu")
		(net "M_B_DQ<25>")
	)
	(gr_poly
		(pts
			(xy 240.02746 -48.34509) (xy 240.02746 -48.29429) (xy 239.84966 -48.29429) (xy 239.84966 -48.34509)
			(xy 239.88522 -48.44669) (xy 239.9919 -48.44669)
		)
		(stroke
			(width 0)
			(type solid)
		)
		(fill yes)
		(layer "F.Cu")
		(net "M_B_DQS_DP<12>")
	)
	(gr_poly
		(pts
			(xy 240.02746 -48.04029) (xy 240.02746 -47.98949) (xy 239.84966 -47.98949) (xy 239.84966 -48.04029)
			(xy 239.88522 -48.14189) (xy 239.9919 -48.14189)
		)
		(stroke
			(width 0)
			(type solid)
		)
		(fill yes)
		(layer "F.Cu")
		(net "M_B_DQS_DN<12>")
	)
	(gr_poly
		(pts
			(xy 240.02746 -47.73549) (xy 240.02746 -47.68469) (xy 239.84966 -47.68469) (xy 239.84966 -47.73549)
			(xy 239.88522 -47.83709) (xy 239.9919 -47.83709)
		)
		(stroke
			(width 0)
			(type solid)
		)
		(fill yes)
		(layer "F.Cu")
		(net "M_B_DQS_DN<3>")
	)
	(gr_poly
		(pts
			(xy 240.02746 -47.43069) (xy 240.02746 -47.37989) (xy 239.84966 -47.37989) (xy 239.84966 -47.43069)
			(xy 239.88522 -47.53229) (xy 239.9919 -47.53229)
		)
		(stroke
			(width 0)
			(type solid)
		)
		(fill yes)
		(layer "F.Cu")
		(net "M_B_DQS_DP<3>")
	)
	(gr_poly
		(pts
			(xy 240.02746 -47.12589) (xy 240.02746 -47.07509) (xy 239.84966 -47.07509) (xy 239.84966 -47.12589)
			(xy 239.88522 -47.22749) (xy 239.9919 -47.22749)
		)
		(stroke
			(width 0)
			(type solid)
		)
		(fill yes)
		(layer "F.Cu")
		(net "M_B_DQ<30>")
	)
	(gr_poly
		(pts
			(xy 240.02746 -46.82109) (xy 240.02746 -46.77029) (xy 239.84966 -46.77029) (xy 239.84966 -46.82109)
			(xy 239.88522 -46.92269) (xy 239.9919 -46.92269)
		)
		(stroke
			(width 0)
			(type solid)
		)
		(fill yes)
		(layer "F.Cu")
		(net "M_B_DQ<31>")
	)
	(gr_poly
		(pts
			(xy 240.02746 -46.51629) (xy 240.02746 -46.46549) (xy 239.84966 -46.46549) (xy 239.84966 -46.51629)
			(xy 239.88522 -46.61789) (xy 239.9919 -46.61789)
		)
		(stroke
			(width 0)
			(type solid)
		)
		(fill yes)
		(layer "F.Cu")
		(net "M_B_DQ<26>")
	)
	(gr_poly
		(pts
			(xy 240.02746 -46.21149) (xy 240.02746 -46.14799) (xy 239.84966 -46.14799) (xy 239.84966 -46.21149)
			(xy 239.88522 -46.31309) (xy 239.9919 -46.31309)
		)
		(stroke
			(width 0)
			(type solid)
		)
		(fill yes)
		(layer "F.Cu")
		(net "M_B_DQ<27>")
	)
	(gr_poly
		(pts
			(xy 240.030254 -105.802684) (xy 239.98555 -105.757726) (xy 239.888522 -105.71099) (xy 239.813084 -105.786428)
			(xy 239.85982 -105.883456) (xy 239.904524 -105.928414)
		)
		(stroke
			(width 0)
			(type solid)
		)
		(fill yes)
		(layer "F.Cu")
		(net "M_E_DQ<27>")
	)
	(gr_poly
		(pts
			(xy 240.041176 -105.558336) (xy 239.99444 -105.461308) (xy 239.958372 -105.425494) (xy 239.832642 -105.551224)
			(xy 239.86871 -105.587038) (xy 239.965738 -105.633774)
		)
		(stroke
			(width 0)
			(type solid)
		)
		(fill yes)
		(layer "F.Cu")
		(net "M_E_DQ<26>")
	)
	(gr_poly
		(pts
			(xy 240.092992 -44.854368) (xy 240.092992 -44.803568) (xy 239.965992 -44.803568) (xy 239.965992 -44.854368)
			(xy 239.978692 -45.044868) (xy 240.080292 -45.044868)
		)
		(stroke
			(width 0)
			(type solid)
		)
		(fill yes)
		(layer "F.Cu")
		(net "M_B_ECC<5>")
	)
	(gr_poly
		(pts
			(xy 240.200434 -105.016554) (xy 240.200434 -104.965754) (xy 240.022634 -104.965754) (xy 240.022634 -105.016554)
			(xy 240.058194 -105.118154) (xy 240.164874 -105.118154)
		)
		(stroke
			(width 0)
			(type solid)
		)
		(fill yes)
		(layer "F.Cu")
		(net "M_E_DQ<31>")
	)
	(gr_poly
		(pts
			(xy 240.200434 -104.711754) (xy 240.200434 -104.660954) (xy 240.022634 -104.660954) (xy 240.022634 -104.711754)
			(xy 240.058194 -104.813354) (xy 240.164874 -104.813354)
		)
		(stroke
			(width 0)
			(type solid)
		)
		(fill yes)
		(layer "F.Cu")
		(net "M_E_DQ<30>")
	)
	(gr_poly
		(pts
			(xy 240.200434 -104.406954) (xy 240.200434 -104.356154) (xy 240.022634 -104.356154) (xy 240.022634 -104.406954)
			(xy 240.058194 -104.508554) (xy 240.164874 -104.508554)
		)
		(stroke
			(width 0)
			(type solid)
		)
		(fill yes)
		(layer "F.Cu")
		(net "M_E_DQS_DP<3>")
	)
	(gr_poly
		(pts
			(xy 240.200434 -104.102154) (xy 240.200434 -104.051354) (xy 240.022634 -104.051354) (xy 240.022634 -104.102154)
			(xy 240.058194 -104.203754) (xy 240.164874 -104.203754)
		)
		(stroke
			(width 0)
			(type solid)
		)
		(fill yes)
		(layer "F.Cu")
		(net "M_E_DQS_DN<3>")
	)
	(gr_poly
		(pts
			(xy 240.200434 -103.797354) (xy 240.200434 -103.746554) (xy 240.022634 -103.746554) (xy 240.022634 -103.797354)
			(xy 240.058194 -103.898954) (xy 240.164874 -103.898954)
		)
		(stroke
			(width 0)
			(type solid)
		)
		(fill yes)
		(layer "F.Cu")
		(net "M_E_DQS_DN<12>")
	)
	(gr_poly
		(pts
			(xy 240.200434 -103.492554) (xy 240.200434 -103.441754) (xy 240.022634 -103.441754) (xy 240.022634 -103.492554)
			(xy 240.058194 -103.594154) (xy 240.164874 -103.594154)
		)
		(stroke
			(width 0)
			(type solid)
		)
		(fill yes)
		(layer "F.Cu")
		(net "M_E_DQS_DP<12>")
	)
	(gr_poly
		(pts
			(xy 240.200434 -103.187754) (xy 240.200434 -103.136954) (xy 240.022634 -103.136954) (xy 240.022634 -103.187754)
			(xy 240.058194 -103.289354) (xy 240.164874 -103.289354)
		)
		(stroke
			(width 0)
			(type solid)
		)
		(fill yes)
		(layer "F.Cu")
		(net "M_E_DQ<25>")
	)
	(gr_poly
		(pts
			(xy 240.200434 -102.882954) (xy 240.200434 -102.832154) (xy 240.022634 -102.832154) (xy 240.022634 -102.882954)
			(xy 240.058194 -102.984554) (xy 240.164874 -102.984554)
		)
		(stroke
			(width 0)
			(type solid)
		)
		(fill yes)
		(layer "F.Cu")
		(net "M_E_DQ<24>")
	)
	(gr_poly
		(pts
			(xy 240.200434 -102.578154) (xy 240.200434 -102.527354) (xy 240.022634 -102.527354) (xy 240.022634 -102.578154)
			(xy 240.058194 -102.679754) (xy 240.164874 -102.679754)
		)
		(stroke
			(width 0)
			(type solid)
		)
		(fill yes)
		(layer "F.Cu")
		(net "M_E_DQ<29>")
	)
	(gr_poly
		(pts
			(xy 240.200434 -102.273354) (xy 240.200434 -102.209854) (xy 240.022634 -102.209854) (xy 240.022634 -102.273354)
			(xy 240.058194 -102.374954) (xy 240.164874 -102.374954)
		)
		(stroke
			(width 0)
			(type solid)
		)
		(fill yes)
		(layer "F.Cu")
		(net "M_E_DQ<28>")
	)
	(gr_poly
		(pts
			(xy 240.24336 -49.46269) (xy 240.2078 -49.36109) (xy 240.10112 -49.36109) (xy 240.06556 -49.46269)
			(xy 240.06556 -49.52619) (xy 240.24336 -49.52619)
		)
		(stroke
			(width 0)
			(type solid)
		)
		(fill yes)
		(layer "F.Cu")
		(net "M_B_DQ<28>")
	)
	(gr_poly
		(pts
			(xy 240.24336 -49.15789) (xy 240.2078 -49.05629) (xy 240.10112 -49.05629) (xy 240.06556 -49.15789)
			(xy 240.06556 -49.20869) (xy 240.24336 -49.20869)
		)
		(stroke
			(width 0)
			(type solid)
		)
		(fill yes)
		(layer "F.Cu")
		(net "M_B_DQ<29>")
	)
	(gr_poly
		(pts
			(xy 240.24336 -48.85309) (xy 240.2078 -48.75149) (xy 240.10112 -48.75149) (xy 240.06556 -48.85309)
			(xy 240.06556 -48.90389) (xy 240.24336 -48.90389)
		)
		(stroke
			(width 0)
			(type solid)
		)
		(fill yes)
		(layer "F.Cu")
		(net "M_B_DQ<24>")
	)
	(gr_poly
		(pts
			(xy 240.24336 -48.54829) (xy 240.2078 -48.44669) (xy 240.10112 -48.44669) (xy 240.06556 -48.54829)
			(xy 240.06556 -48.59909) (xy 240.24336 -48.59909)
		)
		(stroke
			(width 0)
			(type solid)
		)
		(fill yes)
		(layer "F.Cu")
		(net "M_B_DQ<25>")
	)
	(gr_poly
		(pts
			(xy 240.24336 -48.24349) (xy 240.2078 -48.14189) (xy 240.10112 -48.14189) (xy 240.06556 -48.24349)
			(xy 240.06556 -48.29429) (xy 240.24336 -48.29429)
		)
		(stroke
			(width 0)
			(type solid)
		)
		(fill yes)
		(layer "F.Cu")
		(net "M_B_DQS_DP<12>")
	)
	(gr_poly
		(pts
			(xy 240.24336 -47.93869) (xy 240.2078 -47.83709) (xy 240.10112 -47.83709) (xy 240.06556 -47.93869)
			(xy 240.06556 -47.98949) (xy 240.24336 -47.98949)
		)
		(stroke
			(width 0)
			(type solid)
		)
		(fill yes)
		(layer "F.Cu")
		(net "M_B_DQS_DN<12>")
	)
	(gr_poly
		(pts
			(xy 240.24336 -47.63389) (xy 240.2078 -47.53229) (xy 240.10112 -47.53229) (xy 240.06556 -47.63389)
			(xy 240.06556 -47.68469) (xy 240.24336 -47.68469)
		)
		(stroke
			(width 0)
			(type solid)
		)
		(fill yes)
		(layer "F.Cu")
		(net "M_B_DQS_DN<3>")
	)
	(gr_poly
		(pts
			(xy 240.24336 -47.32909) (xy 240.2078 -47.22749) (xy 240.10112 -47.22749) (xy 240.06556 -47.32909)
			(xy 240.06556 -47.37989) (xy 240.24336 -47.37989)
		)
		(stroke
			(width 0)
			(type solid)
		)
		(fill yes)
		(layer "F.Cu")
		(net "M_B_DQS_DP<3>")
	)
	(gr_poly
		(pts
			(xy 240.24336 -47.02429) (xy 240.2078 -46.92269) (xy 240.10112 -46.92269) (xy 240.06556 -47.02429)
			(xy 240.06556 -47.07509) (xy 240.24336 -47.07509)
		)
		(stroke
			(width 0)
			(type solid)
		)
		(fill yes)
		(layer "F.Cu")
		(net "M_B_DQ<30>")
	)
	(gr_poly
		(pts
			(xy 240.24336 -46.71949) (xy 240.2078 -46.61789) (xy 240.10112 -46.61789) (xy 240.06556 -46.71949)
			(xy 240.06556 -46.77029) (xy 240.24336 -46.77029)
		)
		(stroke
			(width 0)
			(type solid)
		)
		(fill yes)
		(layer "F.Cu")
		(net "M_B_DQ<31>")
	)
	(gr_poly
		(pts
			(xy 240.24336 -46.41469) (xy 240.2078 -46.31309) (xy 240.10112 -46.31309) (xy 240.06556 -46.41469)
			(xy 240.06556 -46.46549) (xy 240.24336 -46.46549)
		)
		(stroke
			(width 0)
			(type solid)
		)
		(fill yes)
		(layer "F.Cu")
		(net "M_B_DQ<26>")
	)
	(gr_poly
		(pts
			(xy 240.397792 -44.359068) (xy 240.385092 -44.168568) (xy 240.283492 -44.168568) (xy 240.270792 -44.359068)
			(xy 240.270792 -44.409868) (xy 240.397792 -44.409868)
		)
		(stroke
			(width 0)
			(type solid)
		)
		(fill yes)
		(layer "F.Cu")
		(net "M_B_ECC<0>")
	)
	(gr_poly
		(pts
			(xy 240.416334 -105.524554) (xy 240.380774 -105.422954) (xy 240.274094 -105.422954) (xy 240.238534 -105.524554)
			(xy 240.238534 -105.588054) (xy 240.416334 -105.588054)
		)
		(stroke
			(width 0)
			(type solid)
		)
		(fill yes)
		(layer "F.Cu")
		(net "M_E_DQ<27>")
	)
	(gr_poly
		(pts
			(xy 240.416334 -105.219754) (xy 240.380774 -105.118154) (xy 240.274094 -105.118154) (xy 240.238534 -105.219754)
			(xy 240.238534 -105.270554) (xy 240.416334 -105.270554)
		)
		(stroke
			(width 0)
			(type solid)
		)
		(fill yes)
		(layer "F.Cu")
		(net "M_E_DQ<26>")
	)
	(gr_poly
		(pts
			(xy 240.416334 -104.914954) (xy 240.380774 -104.813354) (xy 240.274094 -104.813354) (xy 240.238534 -104.914954)
			(xy 240.238534 -104.965754) (xy 240.416334 -104.965754)
		)
		(stroke
			(width 0)
			(type solid)
		)
		(fill yes)
		(layer "F.Cu")
		(net "M_E_DQ<31>")
	)
	(gr_poly
		(pts
			(xy 240.416334 -104.610154) (xy 240.380774 -104.508554) (xy 240.274094 -104.508554) (xy 240.238534 -104.610154)
			(xy 240.238534 -104.660954) (xy 240.416334 -104.660954)
		)
		(stroke
			(width 0)
			(type solid)
		)
		(fill yes)
		(layer "F.Cu")
		(net "M_E_DQ<30>")
	)
	(gr_poly
		(pts
			(xy 240.416334 -104.305354) (xy 240.380774 -104.203754) (xy 240.274094 -104.203754) (xy 240.238534 -104.305354)
			(xy 240.238534 -104.356154) (xy 240.416334 -104.356154)
		)
		(stroke
			(width 0)
			(type solid)
		)
		(fill yes)
		(layer "F.Cu")
		(net "M_E_DQS_DP<3>")
	)
	(gr_poly
		(pts
			(xy 240.416334 -104.000554) (xy 240.380774 -103.898954) (xy 240.274094 -103.898954) (xy 240.238534 -104.000554)
			(xy 240.238534 -104.051354) (xy 240.416334 -104.051354)
		)
		(stroke
			(width 0)
			(type solid)
		)
		(fill yes)
		(layer "F.Cu")
		(net "M_E_DQS_DN<3>")
	)
	(gr_poly
		(pts
			(xy 240.416334 -103.695754) (xy 240.380774 -103.594154) (xy 240.274094 -103.594154) (xy 240.238534 -103.695754)
			(xy 240.238534 -103.746554) (xy 240.416334 -103.746554)
		)
		(stroke
			(width 0)
			(type solid)
		)
		(fill yes)
		(layer "F.Cu")
		(net "M_E_DQS_DN<12>")
	)
	(gr_poly
		(pts
			(xy 240.416334 -103.390954) (xy 240.380774 -103.289354) (xy 240.274094 -103.289354) (xy 240.238534 -103.390954)
			(xy 240.238534 -103.441754) (xy 240.416334 -103.441754)
		)
		(stroke
			(width 0)
			(type solid)
		)
		(fill yes)
		(layer "F.Cu")
		(net "M_E_DQS_DP<12>")
	)
	(gr_poly
		(pts
			(xy 240.416334 -103.086154) (xy 240.380774 -102.984554) (xy 240.274094 -102.984554) (xy 240.238534 -103.086154)
			(xy 240.238534 -103.136954) (xy 240.416334 -103.136954)
		)
		(stroke
			(width 0)
			(type solid)
		)
		(fill yes)
		(layer "F.Cu")
		(net "M_E_DQ<25>")
	)
	(gr_poly
		(pts
			(xy 240.416334 -102.781354) (xy 240.380774 -102.679754) (xy 240.274094 -102.679754) (xy 240.238534 -102.781354)
			(xy 240.238534 -102.832154) (xy 240.416334 -102.832154)
		)
		(stroke
			(width 0)
			(type solid)
		)
		(fill yes)
		(layer "F.Cu")
		(net "M_E_DQ<24>")
	)
	(gr_poly
		(pts
			(xy 240.416334 -102.476554) (xy 240.380774 -102.374954) (xy 240.274094 -102.374954) (xy 240.238534 -102.476554)
			(xy 240.238534 -102.527354) (xy 240.416334 -102.527354)
		)
		(stroke
			(width 0)
			(type solid)
		)
		(fill yes)
		(layer "F.Cu")
		(net "M_E_DQ<29>")
	)
	(gr_poly
		(pts
			(xy 240.423192 -45.146468) (xy 240.410492 -44.955968) (xy 240.308892 -44.955968) (xy 240.296192 -45.146468)
			(xy 240.296192 -45.209968) (xy 240.423192 -45.209968)
		)
		(stroke
			(width 0)
			(type solid)
		)
		(fill yes)
		(layer "F.Cu")
		(net "M_B_ECC<4>")
	)
	(gr_poly
		(pts
			(xy 240.423192 -44.752768) (xy 240.410492 -44.562268) (xy 240.308892 -44.562268) (xy 240.296192 -44.752768)
			(xy 240.296192 -44.803568) (xy 240.423192 -44.803568)
		)
		(stroke
			(width 0)
			(type solid)
		)
		(fill yes)
		(layer "F.Cu")
		(net "M_B_ECC<5>")
	)
	(gr_poly
		(pts
			(xy 240.45926 -49.25949) (xy 240.45926 -49.20869) (xy 240.28146 -49.20869) (xy 240.28146 -49.25949)
			(xy 240.31702 -49.36109) (xy 240.4237 -49.36109)
		)
		(stroke
			(width 0)
			(type solid)
		)
		(fill yes)
		(layer "F.Cu")
		(net "M_B_DQ<29>")
	)
	(gr_poly
		(pts
			(xy 240.45926 -48.95469) (xy 240.45926 -48.90389) (xy 240.28146 -48.90389) (xy 240.28146 -48.95469)
			(xy 240.31702 -49.05629) (xy 240.4237 -49.05629)
		)
		(stroke
			(width 0)
			(type solid)
		)
		(fill yes)
		(layer "F.Cu")
		(net "M_B_DQ<24>")
	)
	(gr_poly
		(pts
			(xy 240.45926 -48.64989) (xy 240.45926 -48.59909) (xy 240.28146 -48.59909) (xy 240.28146 -48.64989)
			(xy 240.31702 -48.75149) (xy 240.4237 -48.75149)
		)
		(stroke
			(width 0)
			(type solid)
		)
		(fill yes)
		(layer "F.Cu")
		(net "M_B_DQ<25>")
	)
	(gr_poly
		(pts
			(xy 240.45926 -48.34509) (xy 240.45926 -48.29429) (xy 240.28146 -48.29429) (xy 240.28146 -48.34509)
			(xy 240.31702 -48.44669) (xy 240.4237 -48.44669)
		)
		(stroke
			(width 0)
			(type solid)
		)
		(fill yes)
		(layer "F.Cu")
		(net "M_B_DQS_DP<12>")
	)
	(gr_poly
		(pts
			(xy 240.45926 -48.04029) (xy 240.45926 -47.98949) (xy 240.28146 -47.98949) (xy 240.28146 -48.04029)
			(xy 240.31702 -48.14189) (xy 240.4237 -48.14189)
		)
		(stroke
			(width 0)
			(type solid)
		)
		(fill yes)
		(layer "F.Cu")
		(net "M_B_DQS_DN<12>")
	)
	(gr_poly
		(pts
			(xy 240.45926 -47.73549) (xy 240.45926 -47.68469) (xy 240.28146 -47.68469) (xy 240.28146 -47.73549)
			(xy 240.31702 -47.83709) (xy 240.4237 -47.83709)
		)
		(stroke
			(width 0)
			(type solid)
		)
		(fill yes)
		(layer "F.Cu")
		(net "M_B_DQS_DN<3>")
	)
	(gr_poly
		(pts
			(xy 240.45926 -47.43069) (xy 240.45926 -47.37989) (xy 240.28146 -47.37989) (xy 240.28146 -47.43069)
			(xy 240.31702 -47.53229) (xy 240.4237 -47.53229)
		)
		(stroke
			(width 0)
			(type solid)
		)
		(fill yes)
		(layer "F.Cu")
		(net "M_B_DQS_DP<3>")
	)
	(gr_poly
		(pts
			(xy 240.45926 -47.12589) (xy 240.45926 -47.07509) (xy 240.28146 -47.07509) (xy 240.28146 -47.12589)
			(xy 240.31702 -47.22749) (xy 240.4237 -47.22749)
		)
		(stroke
			(width 0)
			(type solid)
		)
		(fill yes)
		(layer "F.Cu")
		(net "M_B_DQ<30>")
	)
	(gr_poly
		(pts
			(xy 240.45926 -46.82109) (xy 240.45926 -46.77029) (xy 240.28146 -46.77029) (xy 240.28146 -46.82109)
			(xy 240.31702 -46.92269) (xy 240.4237 -46.92269)
		)
		(stroke
			(width 0)
			(type solid)
		)
		(fill yes)
		(layer "F.Cu")
		(net "M_B_DQ<31>")
	)
	(gr_poly
		(pts
			(xy 240.45926 -46.51629) (xy 240.45926 -46.46549) (xy 240.28146 -46.46549) (xy 240.28146 -46.51629)
			(xy 240.31702 -46.61789) (xy 240.4237 -46.61789)
		)
		(stroke
			(width 0)
			(type solid)
		)
		(fill yes)
		(layer "F.Cu")
		(net "M_B_DQ<26>")
	)
	(gr_poly
		(pts
			(xy 240.45926 -46.21149) (xy 240.45926 -46.14799) (xy 240.28146 -46.14799) (xy 240.28146 -46.21149)
			(xy 240.31702 -46.31309) (xy 240.4237 -46.31309)
		)
		(stroke
			(width 0)
			(type solid)
		)
		(fill yes)
		(layer "F.Cu")
		(net "M_B_DQ<27>")
	)
	(gr_poly
		(pts
			(xy 240.632234 -105.321354) (xy 240.632234 -105.270554) (xy 240.454434 -105.270554) (xy 240.454434 -105.321354)
			(xy 240.489994 -105.422954) (xy 240.596674 -105.422954)
		)
		(stroke
			(width 0)
			(type solid)
		)
		(fill yes)
		(layer "F.Cu")
		(net "M_E_DQ<26>")
	)
	(gr_poly
		(pts
			(xy 240.632234 -105.016554) (xy 240.632234 -104.965754) (xy 240.454434 -104.965754) (xy 240.454434 -105.016554)
			(xy 240.489994 -105.118154) (xy 240.596674 -105.118154)
		)
		(stroke
			(width 0)
			(type solid)
		)
		(fill yes)
		(layer "F.Cu")
		(net "M_E_DQ<31>")
	)
	(gr_poly
		(pts
			(xy 240.632234 -104.711754) (xy 240.632234 -104.660954) (xy 240.454434 -104.660954) (xy 240.454434 -104.711754)
			(xy 240.489994 -104.813354) (xy 240.596674 -104.813354)
		)
		(stroke
			(width 0)
			(type solid)
		)
		(fill yes)
		(layer "F.Cu")
		(net "M_E_DQ<30>")
	)
	(gr_poly
		(pts
			(xy 240.632234 -104.406954) (xy 240.632234 -104.356154) (xy 240.454434 -104.356154) (xy 240.454434 -104.406954)
			(xy 240.489994 -104.508554) (xy 240.596674 -104.508554)
		)
		(stroke
			(width 0)
			(type solid)
		)
		(fill yes)
		(layer "F.Cu")
		(net "M_E_DQS_DP<3>")
	)
	(gr_poly
		(pts
			(xy 240.632234 -104.102154) (xy 240.632234 -104.051354) (xy 240.454434 -104.051354) (xy 240.454434 -104.102154)
			(xy 240.489994 -104.203754) (xy 240.596674 -104.203754)
		)
		(stroke
			(width 0)
			(type solid)
		)
		(fill yes)
		(layer "F.Cu")
		(net "M_E_DQS_DN<3>")
	)
	(gr_poly
		(pts
			(xy 240.632234 -103.797354) (xy 240.632234 -103.746554) (xy 240.454434 -103.746554) (xy 240.454434 -103.797354)
			(xy 240.489994 -103.898954) (xy 240.596674 -103.898954)
		)
		(stroke
			(width 0)
			(type solid)
		)
		(fill yes)
		(layer "F.Cu")
		(net "M_E_DQS_DN<12>")
	)
	(gr_poly
		(pts
			(xy 240.632234 -103.492554) (xy 240.632234 -103.441754) (xy 240.454434 -103.441754) (xy 240.454434 -103.492554)
			(xy 240.489994 -103.594154) (xy 240.596674 -103.594154)
		)
		(stroke
			(width 0)
			(type solid)
		)
		(fill yes)
		(layer "F.Cu")
		(net "M_E_DQS_DP<12>")
	)
	(gr_poly
		(pts
			(xy 240.632234 -103.187754) (xy 240.632234 -103.136954) (xy 240.454434 -103.136954) (xy 240.454434 -103.187754)
			(xy 240.489994 -103.289354) (xy 240.596674 -103.289354)
		)
		(stroke
			(width 0)
			(type solid)
		)
		(fill yes)
		(layer "F.Cu")
		(net "M_E_DQ<25>")
	)
	(gr_poly
		(pts
			(xy 240.632234 -102.882954) (xy 240.632234 -102.832154) (xy 240.454434 -102.832154) (xy 240.454434 -102.882954)
			(xy 240.489994 -102.984554) (xy 240.596674 -102.984554)
		)
		(stroke
			(width 0)
			(type solid)
		)
		(fill yes)
		(layer "F.Cu")
		(net "M_E_DQ<24>")
	)
	(gr_poly
		(pts
			(xy 240.632234 -102.578154) (xy 240.632234 -102.527354) (xy 240.454434 -102.527354) (xy 240.454434 -102.578154)
			(xy 240.489994 -102.679754) (xy 240.596674 -102.679754)
		)
		(stroke
			(width 0)
			(type solid)
		)
		(fill yes)
		(layer "F.Cu")
		(net "M_E_DQ<29>")
	)
	(gr_poly
		(pts
			(xy 240.632234 -102.273354) (xy 240.632234 -102.209854) (xy 240.454434 -102.209854) (xy 240.454434 -102.273354)
			(xy 240.489994 -102.374954) (xy 240.596674 -102.374954)
		)
		(stroke
			(width 0)
			(type solid)
		)
		(fill yes)
		(layer "F.Cu")
		(net "M_E_DQ<28>")
	)
	(gr_poly
		(pts
			(xy 240.67516 -49.15789) (xy 240.6396 -49.05629) (xy 240.53292 -49.05629) (xy 240.49736 -49.15789)
			(xy 240.49736 -49.20869) (xy 240.67516 -49.20869)
		)
		(stroke
			(width 0)
			(type solid)
		)
		(fill yes)
		(layer "F.Cu")
		(net "M_B_DQ<29>")
	)
	(gr_poly
		(pts
			(xy 240.67516 -48.85309) (xy 240.6396 -48.75149) (xy 240.53292 -48.75149) (xy 240.49736 -48.85309)
			(xy 240.49736 -48.90389) (xy 240.67516 -48.90389)
		)
		(stroke
			(width 0)
			(type solid)
		)
		(fill yes)
		(layer "F.Cu")
		(net "M_B_DQ<24>")
	)
	(gr_poly
		(pts
			(xy 240.67516 -48.54829) (xy 240.6396 -48.44669) (xy 240.53292 -48.44669) (xy 240.49736 -48.54829)
			(xy 240.49736 -48.59909) (xy 240.67516 -48.59909)
		)
		(stroke
			(width 0)
			(type solid)
		)
		(fill yes)
		(layer "F.Cu")
		(net "M_B_DQ<25>")
	)
	(gr_poly
		(pts
			(xy 240.67516 -48.24349) (xy 240.6396 -48.14189) (xy 240.53292 -48.14189) (xy 240.49736 -48.24349)
			(xy 240.49736 -48.29429) (xy 240.67516 -48.29429)
		)
		(stroke
			(width 0)
			(type solid)
		)
		(fill yes)
		(layer "F.Cu")
		(net "M_B_DQS_DP<12>")
	)
	(gr_poly
		(pts
			(xy 240.67516 -47.93869) (xy 240.6396 -47.83709) (xy 240.53292 -47.83709) (xy 240.49736 -47.93869)
			(xy 240.49736 -47.98949) (xy 240.67516 -47.98949)
		)
		(stroke
			(width 0)
			(type solid)
		)
		(fill yes)
		(layer "F.Cu")
		(net "M_B_DQS_DN<12>")
	)
	(gr_poly
		(pts
			(xy 240.67516 -47.63389) (xy 240.6396 -47.53229) (xy 240.53292 -47.53229) (xy 240.49736 -47.63389)
			(xy 240.49736 -47.68469) (xy 240.67516 -47.68469)
		)
		(stroke
			(width 0)
			(type solid)
		)
		(fill yes)
		(layer "F.Cu")
		(net "M_B_DQS_DN<3>")
	)
	(gr_poly
		(pts
			(xy 240.67516 -47.32909) (xy 240.6396 -47.22749) (xy 240.53292 -47.22749) (xy 240.49736 -47.32909)
			(xy 240.49736 -47.37989) (xy 240.67516 -47.37989)
		)
		(stroke
			(width 0)
			(type solid)
		)
		(fill yes)
		(layer "F.Cu")
		(net "M_B_DQS_DP<3>")
	)
	(gr_poly
		(pts
			(xy 240.67516 -47.02429) (xy 240.6396 -46.92269) (xy 240.53292 -46.92269) (xy 240.49736 -47.02429)
			(xy 240.49736 -47.07509) (xy 240.67516 -47.07509)
		)
		(stroke
			(width 0)
			(type solid)
		)
		(fill yes)
		(layer "F.Cu")
		(net "M_B_DQ<30>")
	)
	(gr_poly
		(pts
			(xy 240.67516 -46.71949) (xy 240.6396 -46.61789) (xy 240.53292 -46.61789) (xy 240.49736 -46.71949)
			(xy 240.49736 -46.77029) (xy 240.67516 -46.77029)
		)
		(stroke
			(width 0)
			(type solid)
		)
		(fill yes)
		(layer "F.Cu")
		(net "M_B_DQ<31>")
	)
	(gr_poly
		(pts
			(xy 240.67516 -46.41469) (xy 240.6396 -46.31309) (xy 240.53292 -46.31309) (xy 240.49736 -46.41469)
			(xy 240.49736 -46.46549) (xy 240.67516 -46.46549)
		)
		(stroke
			(width 0)
			(type solid)
		)
		(fill yes)
		(layer "F.Cu")
		(net "M_B_DQ<26>")
	)
	(gr_poly
		(pts
			(xy 240.727992 -44.066968) (xy 240.727992 -44.016168) (xy 240.600992 -44.016168) (xy 240.600992 -44.066968)
			(xy 240.613692 -44.257468) (xy 240.715292 -44.257468)
		)
		(stroke
			(width 0)
			(type solid)
		)
		(fill yes)
		(layer "F.Cu")
		(net "M_B_ECC<1>")
	)
	(gr_poly
		(pts
			(xy 240.753392 -44.854368) (xy 240.753392 -44.803568) (xy 240.626392 -44.803568) (xy 240.626392 -44.854368)
			(xy 240.639092 -45.044868) (xy 240.740692 -45.044868)
		)
		(stroke
			(width 0)
			(type solid)
		)
		(fill yes)
		(layer "F.Cu")
		(net "M_B_ECC<5>")
	)
	(gr_poly
		(pts
			(xy 240.753392 -44.460668) (xy 240.753392 -44.409868) (xy 240.626392 -44.409868) (xy 240.626392 -44.460668)
			(xy 240.639092 -44.651168) (xy 240.740692 -44.651168)
		)
		(stroke
			(width 0)
			(type solid)
		)
		(fill yes)
		(layer "F.Cu")
		(net "M_B_ECC<0>")
	)
	(gr_poly
		(pts
			(xy 240.848134 -105.524554) (xy 240.812574 -105.422954) (xy 240.705894 -105.422954) (xy 240.670334 -105.524554)
			(xy 240.670334 -105.588054) (xy 240.848134 -105.588054)
		)
		(stroke
			(width 0)
			(type solid)
		)
		(fill yes)
		(layer "F.Cu")
		(net "M_E_DQ<27>")
	)
	(gr_poly
		(pts
			(xy 240.848134 -105.219754) (xy 240.812574 -105.118154) (xy 240.705894 -105.118154) (xy 240.670334 -105.219754)
			(xy 240.670334 -105.270554) (xy 240.848134 -105.270554)
		)
		(stroke
			(width 0)
			(type solid)
		)
		(fill yes)
		(layer "F.Cu")
		(net "M_E_DQ<26>")
	)
	(gr_poly
		(pts
			(xy 240.848134 -104.914954) (xy 240.812574 -104.813354) (xy 240.705894 -104.813354) (xy 240.670334 -104.914954)
			(xy 240.670334 -104.965754) (xy 240.848134 -104.965754)
		)
		(stroke
			(width 0)
			(type solid)
		)
		(fill yes)
		(layer "F.Cu")
		(net "M_E_DQ<31>")
	)
	(gr_poly
		(pts
			(xy 240.848134 -104.610154) (xy 240.812574 -104.508554) (xy 240.705894 -104.508554) (xy 240.670334 -104.610154)
			(xy 240.670334 -104.660954) (xy 240.848134 -104.660954)
		)
		(stroke
			(width 0)
			(type solid)
		)
		(fill yes)
		(layer "F.Cu")
		(net "M_E_DQ<30>")
	)
	(gr_poly
		(pts
			(xy 240.848134 -104.305354) (xy 240.812574 -104.203754) (xy 240.705894 -104.203754) (xy 240.670334 -104.305354)
			(xy 240.670334 -104.356154) (xy 240.848134 -104.356154)
		)
		(stroke
			(width 0)
			(type solid)
		)
		(fill yes)
		(layer "F.Cu")
		(net "M_E_DQS_DP<3>")
	)
	(gr_poly
		(pts
			(xy 240.848134 -104.000554) (xy 240.812574 -103.898954) (xy 240.705894 -103.898954) (xy 240.670334 -104.000554)
			(xy 240.670334 -104.051354) (xy 240.848134 -104.051354)
		)
		(stroke
			(width 0)
			(type solid)
		)
		(fill yes)
		(layer "F.Cu")
		(net "M_E_DQS_DN<3>")
	)
	(gr_poly
		(pts
			(xy 240.848134 -103.695754) (xy 240.812574 -103.594154) (xy 240.705894 -103.594154) (xy 240.670334 -103.695754)
			(xy 240.670334 -103.746554) (xy 240.848134 -103.746554)
		)
		(stroke
			(width 0)
			(type solid)
		)
		(fill yes)
		(layer "F.Cu")
		(net "M_E_DQS_DN<12>")
	)
	(gr_poly
		(pts
			(xy 240.848134 -103.390954) (xy 240.812574 -103.289354) (xy 240.705894 -103.289354) (xy 240.670334 -103.390954)
			(xy 240.670334 -103.441754) (xy 240.848134 -103.441754)
		)
		(stroke
			(width 0)
			(type solid)
		)
		(fill yes)
		(layer "F.Cu")
		(net "M_E_DQS_DP<12>")
	)
	(gr_poly
		(pts
			(xy 240.848134 -103.086154) (xy 240.812574 -102.984554) (xy 240.705894 -102.984554) (xy 240.670334 -103.086154)
			(xy 240.670334 -103.136954) (xy 240.848134 -103.136954)
		)
		(stroke
			(width 0)
			(type solid)
		)
		(fill yes)
		(layer "F.Cu")
		(net "M_E_DQ<25>")
	)
	(gr_poly
		(pts
			(xy 240.848134 -102.781354) (xy 240.812574 -102.679754) (xy 240.705894 -102.679754) (xy 240.670334 -102.781354)
			(xy 240.670334 -102.832154) (xy 240.848134 -102.832154)
		)
		(stroke
			(width 0)
			(type solid)
		)
		(fill yes)
		(layer "F.Cu")
		(net "M_E_DQ<24>")
	)
	(gr_poly
		(pts
			(xy 240.8682 -49.432718) (xy 240.904014 -49.396904) (xy 240.778284 -49.271174) (xy 240.74247 -49.306988)
			(xy 240.695734 -49.404016) (xy 240.771172 -49.479454)
		)
		(stroke
			(width 0)
			(type solid)
		)
		(fill yes)
		(layer "F.Cu")
		(net "M_B_DQ<29>")
	)
	(gr_poly
		(pts
			(xy 240.87709 -49.729136) (xy 240.923826 -49.632108) (xy 240.848388 -49.55667) (xy 240.75136 -49.603406)
			(xy 240.715546 -49.639474) (xy 240.841276 -49.765204)
		)
		(stroke
			(width 0)
			(type solid)
		)
		(fill yes)
		(layer "F.Cu")
		(net "M_B_DQ<28>")
	)
	(gr_poly
		(pts
			(xy 240.89106 -48.95469) (xy 240.89106 -48.90389) (xy 240.71326 -48.90389) (xy 240.71326 -48.95469)
			(xy 240.74882 -49.05629) (xy 240.8555 -49.05629)
		)
		(stroke
			(width 0)
			(type solid)
		)
		(fill yes)
		(layer "F.Cu")
		(net "M_B_DQ<24>")
	)
	(gr_poly
		(pts
			(xy 240.89106 -48.64989) (xy 240.89106 -48.59909) (xy 240.71326 -48.59909) (xy 240.71326 -48.64989)
			(xy 240.74882 -48.75149) (xy 240.8555 -48.75149)
		)
		(stroke
			(width 0)
			(type solid)
		)
		(fill yes)
		(layer "F.Cu")
		(net "M_B_DQ<25>")
	)
	(gr_poly
		(pts
			(xy 240.89106 -48.34509) (xy 240.89106 -48.29429) (xy 240.71326 -48.29429) (xy 240.71326 -48.34509)
			(xy 240.74882 -48.44669) (xy 240.8555 -48.44669)
		)
		(stroke
			(width 0)
			(type solid)
		)
		(fill yes)
		(layer "F.Cu")
		(net "M_B_DQS_DP<12>")
	)
	(gr_poly
		(pts
			(xy 240.89106 -48.04029) (xy 240.89106 -47.98949) (xy 240.71326 -47.98949) (xy 240.71326 -48.04029)
			(xy 240.74882 -48.14189) (xy 240.8555 -48.14189)
		)
		(stroke
			(width 0)
			(type solid)
		)
		(fill yes)
		(layer "F.Cu")
		(net "M_B_DQS_DN<12>")
	)
	(gr_poly
		(pts
			(xy 240.89106 -47.73549) (xy 240.89106 -47.68469) (xy 240.71326 -47.68469) (xy 240.71326 -47.73549)
			(xy 240.74882 -47.83709) (xy 240.8555 -47.83709)
		)
		(stroke
			(width 0)
			(type solid)
		)
		(fill yes)
		(layer "F.Cu")
		(net "M_B_DQS_DN<3>")
	)
	(gr_poly
		(pts
			(xy 240.89106 -47.43069) (xy 240.89106 -47.37989) (xy 240.71326 -47.37989) (xy 240.71326 -47.43069)
			(xy 240.74882 -47.53229) (xy 240.8555 -47.53229)
		)
		(stroke
			(width 0)
			(type solid)
		)
		(fill yes)
		(layer "F.Cu")
		(net "M_B_DQS_DP<3>")
	)
	(gr_poly
		(pts
			(xy 240.89106 -47.12589) (xy 240.89106 -47.07509) (xy 240.71326 -47.07509) (xy 240.71326 -47.12589)
			(xy 240.74882 -47.22749) (xy 240.8555 -47.22749)
		)
		(stroke
			(width 0)
			(type solid)
		)
		(fill yes)
		(layer "F.Cu")
		(net "M_B_DQ<30>")
	)
	(gr_poly
		(pts
			(xy 240.89106 -46.82109) (xy 240.89106 -46.77029) (xy 240.71326 -46.77029) (xy 240.71326 -46.82109)
			(xy 240.74882 -46.92269) (xy 240.8555 -46.92269)
		)
		(stroke
			(width 0)
			(type solid)
		)
		(fill yes)
		(layer "F.Cu")
		(net "M_B_DQ<31>")
	)
	(gr_poly
		(pts
			(xy 240.89106 -46.51629) (xy 240.89106 -46.46549) (xy 240.71326 -46.46549) (xy 240.71326 -46.51629)
			(xy 240.74882 -46.61789) (xy 240.8555 -46.61789)
		)
		(stroke
			(width 0)
			(type solid)
		)
		(fill yes)
		(layer "F.Cu")
		(net "M_B_DQ<26>")
	)
	(gr_poly
		(pts
			(xy 240.89106 -46.21149) (xy 240.89106 -46.14799) (xy 240.71326 -46.14799) (xy 240.71326 -46.21149)
			(xy 240.74882 -46.31309) (xy 240.8555 -46.31309)
		)
		(stroke
			(width 0)
			(type solid)
		)
		(fill yes)
		(layer "F.Cu")
		(net "M_B_DQ<27>")
	)
	(gr_poly
		(pts
			(xy 241.064034 -105.321354) (xy 241.064034 -105.270554) (xy 240.886234 -105.270554) (xy 240.886234 -105.321354)
			(xy 240.921794 -105.422954) (xy 241.028474 -105.422954)
		)
		(stroke
			(width 0)
			(type solid)
		)
		(fill yes)
		(layer "F.Cu")
		(net "M_E_DQ<26>")
	)
	(gr_poly
		(pts
			(xy 241.064034 -105.016554) (xy 241.064034 -104.965754) (xy 240.886234 -104.965754) (xy 240.886234 -105.016554)
			(xy 240.921794 -105.118154) (xy 241.028474 -105.118154)
		)
		(stroke
			(width 0)
			(type solid)
		)
		(fill yes)
		(layer "F.Cu")
		(net "M_E_DQ<31>")
	)
	(gr_poly
		(pts
			(xy 241.064034 -104.711754) (xy 241.064034 -104.660954) (xy 240.886234 -104.660954) (xy 240.886234 -104.711754)
			(xy 240.921794 -104.813354) (xy 241.028474 -104.813354)
		)
		(stroke
			(width 0)
			(type solid)
		)
		(fill yes)
		(layer "F.Cu")
		(net "M_E_DQ<30>")
	)
	(gr_poly
		(pts
			(xy 241.064034 -104.406954) (xy 241.064034 -104.356154) (xy 240.886234 -104.356154) (xy 240.886234 -104.406954)
			(xy 240.921794 -104.508554) (xy 241.028474 -104.508554)
		)
		(stroke
			(width 0)
			(type solid)
		)
		(fill yes)
		(layer "F.Cu")
		(net "M_E_DQS_DP<3>")
	)
	(gr_poly
		(pts
			(xy 241.064034 -104.102154) (xy 241.064034 -104.051354) (xy 240.886234 -104.051354) (xy 240.886234 -104.102154)
			(xy 240.921794 -104.203754) (xy 241.028474 -104.203754)
		)
		(stroke
			(width 0)
			(type solid)
		)
		(fill yes)
		(layer "F.Cu")
		(net "M_E_DQS_DN<3>")
	)
	(gr_poly
		(pts
			(xy 241.064034 -103.797354) (xy 241.064034 -103.746554) (xy 240.886234 -103.746554) (xy 240.886234 -103.797354)
			(xy 240.921794 -103.898954) (xy 241.028474 -103.898954)
		)
		(stroke
			(width 0)
			(type solid)
		)
		(fill yes)
		(layer "F.Cu")
		(net "M_E_DQS_DN<12>")
	)
	(gr_poly
		(pts
			(xy 241.064034 -103.492554) (xy 241.064034 -103.441754) (xy 240.886234 -103.441754) (xy 240.886234 -103.492554)
			(xy 240.921794 -103.594154) (xy 241.028474 -103.594154)
		)
		(stroke
			(width 0)
			(type solid)
		)
		(fill yes)
		(layer "F.Cu")
		(net "M_E_DQS_DP<12>")
	)
	(gr_poly
		(pts
			(xy 241.064034 -103.187754) (xy 241.064034 -103.136954) (xy 240.886234 -103.136954) (xy 240.886234 -103.187754)
			(xy 240.921794 -103.289354) (xy 241.028474 -103.289354)
		)
		(stroke
			(width 0)
			(type solid)
		)
		(fill yes)
		(layer "F.Cu")
		(net "M_E_DQ<25>")
	)
	(gr_poly
		(pts
			(xy 241.064034 -102.882954) (xy 241.064034 -102.832154) (xy 240.886234 -102.832154) (xy 240.886234 -102.882954)
			(xy 240.921794 -102.984554) (xy 241.028474 -102.984554)
		)
		(stroke
			(width 0)
			(type solid)
		)
		(fill yes)
		(layer "F.Cu")
		(net "M_E_DQ<24>")
	)
	(gr_poly
		(pts
			(xy 241.064034 -102.578154) (xy 241.064034 -102.527354) (xy 240.886234 -102.527354) (xy 240.886234 -102.578154)
			(xy 240.921794 -102.679754) (xy 241.028474 -102.679754)
		)
		(stroke
			(width 0)
			(type solid)
		)
		(fill yes)
		(layer "F.Cu")
		(net "M_E_DQ<29>")
	)
	(gr_poly
		(pts
			(xy 241.083592 -45.146468) (xy 241.070892 -44.955968) (xy 240.969292 -44.955968) (xy 240.956592 -45.146468)
			(xy 240.956592 -45.209968) (xy 241.083592 -45.209968)
		)
		(stroke
			(width 0)
			(type solid)
		)
		(fill yes)
		(layer "F.Cu")
		(net "M_B_ECC<4>")
	)
	(gr_poly
		(pts
			(xy 241.083592 -44.752768) (xy 241.070892 -44.562268) (xy 240.969292 -44.562268) (xy 240.956592 -44.752768)
			(xy 240.956592 -44.803568) (xy 241.083592 -44.803568)
		)
		(stroke
			(width 0)
			(type solid)
		)
		(fill yes)
		(layer "F.Cu")
		(net "M_B_ECC<5>")
	)
	(gr_poly
		(pts
			(xy 241.083592 -44.359068) (xy 241.070892 -44.168568) (xy 240.969292 -44.168568) (xy 240.956592 -44.359068)
			(xy 240.956592 -44.409868) (xy 241.083592 -44.409868)
		)
		(stroke
			(width 0)
			(type solid)
		)
		(fill yes)
		(layer "F.Cu")
		(net "M_B_ECC<0>")
	)
	(gr_poly
		(pts
			(xy 241.083592 -43.965368) (xy 241.070892 -43.774868) (xy 240.969292 -43.774868) (xy 240.956592 -43.965368)
			(xy 240.956592 -44.016168) (xy 241.083592 -44.016168)
		)
		(stroke
			(width 0)
			(type solid)
		)
		(fill yes)
		(layer "F.Cu")
		(net "M_B_ECC<1>")
	)
	(gr_poly
		(pts
			(xy 241.092736 -49.513744) (xy 241.139472 -49.416716) (xy 241.064034 -49.341278) (xy 240.967006 -49.388014)
			(xy 240.931192 -49.423828) (xy 241.056922 -49.549558)
		)
		(stroke
			(width 0)
			(type solid)
		)
		(fill yes)
		(layer "F.Cu")
		(net "M_B_DQ<29>")
	)
	(gr_poly
		(pts
			(xy 241.10696 -48.85309) (xy 241.0714 -48.75149) (xy 240.96472 -48.75149) (xy 240.92916 -48.85309)
			(xy 240.92916 -48.90389) (xy 241.10696 -48.90389)
		)
		(stroke
			(width 0)
			(type solid)
		)
		(fill yes)
		(layer "F.Cu")
		(net "M_B_DQ<24>")
	)
	(gr_poly
		(pts
			(xy 241.10696 -48.54829) (xy 241.0714 -48.44669) (xy 240.96472 -48.44669) (xy 240.92916 -48.54829)
			(xy 240.92916 -48.59909) (xy 241.10696 -48.59909)
		)
		(stroke
			(width 0)
			(type solid)
		)
		(fill yes)
		(layer "F.Cu")
		(net "M_B_DQ<25>")
	)
	(gr_poly
		(pts
			(xy 241.10696 -48.24349) (xy 241.0714 -48.14189) (xy 240.96472 -48.14189) (xy 240.92916 -48.24349)
			(xy 240.92916 -48.29429) (xy 241.10696 -48.29429)
		)
		(stroke
			(width 0)
			(type solid)
		)
		(fill yes)
		(layer "F.Cu")
		(net "M_B_DQS_DP<12>")
	)
	(gr_poly
		(pts
			(xy 241.10696 -47.93869) (xy 241.0714 -47.83709) (xy 240.96472 -47.83709) (xy 240.92916 -47.93869)
			(xy 240.92916 -47.98949) (xy 241.10696 -47.98949)
		)
		(stroke
			(width 0)
			(type solid)
		)
		(fill yes)
		(layer "F.Cu")
		(net "M_B_DQS_DN<12>")
	)
	(gr_poly
		(pts
			(xy 241.10696 -47.63389) (xy 241.0714 -47.53229) (xy 240.96472 -47.53229) (xy 240.92916 -47.63389)
			(xy 240.92916 -47.68469) (xy 241.10696 -47.68469)
		)
		(stroke
			(width 0)
			(type solid)
		)
		(fill yes)
		(layer "F.Cu")
		(net "M_B_DQS_DN<3>")
	)
	(gr_poly
		(pts
			(xy 241.10696 -47.32909) (xy 241.0714 -47.22749) (xy 240.96472 -47.22749) (xy 240.92916 -47.32909)
			(xy 240.92916 -47.37989) (xy 241.10696 -47.37989)
		)
		(stroke
			(width 0)
			(type solid)
		)
		(fill yes)
		(layer "F.Cu")
		(net "M_B_DQS_DP<3>")
	)
	(gr_poly
		(pts
			(xy 241.10696 -47.02429) (xy 241.0714 -46.92269) (xy 240.96472 -46.92269) (xy 240.92916 -47.02429)
			(xy 240.92916 -47.07509) (xy 241.10696 -47.07509)
		)
		(stroke
			(width 0)
			(type solid)
		)
		(fill yes)
		(layer "F.Cu")
		(net "M_B_DQ<30>")
	)
	(gr_poly
		(pts
			(xy 241.10696 -46.71949) (xy 241.0714 -46.61789) (xy 240.96472 -46.61789) (xy 240.92916 -46.71949)
			(xy 240.92916 -46.77029) (xy 241.10696 -46.77029)
		)
		(stroke
			(width 0)
			(type solid)
		)
		(fill yes)
		(layer "F.Cu")
		(net "M_B_DQ<31>")
	)
	(gr_poly
		(pts
			(xy 241.10696 -46.41469) (xy 241.0714 -46.31309) (xy 240.96472 -46.31309) (xy 240.92916 -46.41469)
			(xy 240.92916 -46.46549) (xy 241.10696 -46.46549)
		)
		(stroke
			(width 0)
			(type solid)
		)
		(fill yes)
		(layer "F.Cu")
		(net "M_B_DQ<26>")
	)
	(gr_poly
		(pts
			(xy 241.173508 -49.738026) (xy 241.209322 -49.702212) (xy 241.083592 -49.576482) (xy 241.047778 -49.612296)
			(xy 241.001042 -49.709324) (xy 241.07648 -49.784762)
		)
		(stroke
			(width 0)
			(type solid)
		)
		(fill yes)
		(layer "F.Cu")
		(net "M_B_DQ<29>")
	)
	(gr_poly
		(pts
			(xy 241.279934 -105.524554) (xy 241.244374 -105.422954) (xy 241.137694 -105.422954) (xy 241.102134 -105.524554)
			(xy 241.102134 -105.588054) (xy 241.279934 -105.588054)
		)
		(stroke
			(width 0)
			(type solid)
		)
		(fill yes)
		(layer "F.Cu")
		(net "M_E_DQ<27>")
	)
	(gr_poly
		(pts
			(xy 241.279934 -105.219754) (xy 241.244374 -105.118154) (xy 241.137694 -105.118154) (xy 241.102134 -105.219754)
			(xy 241.102134 -105.270554) (xy 241.279934 -105.270554)
		)
		(stroke
			(width 0)
			(type solid)
		)
		(fill yes)
		(layer "F.Cu")
		(net "M_E_DQ<26>")
	)
	(gr_poly
		(pts
			(xy 241.279934 -104.914954) (xy 241.244374 -104.813354) (xy 241.137694 -104.813354) (xy 241.102134 -104.914954)
			(xy 241.102134 -104.965754) (xy 241.279934 -104.965754)
		)
		(stroke
			(width 0)
			(type solid)
		)
		(fill yes)
		(layer "F.Cu")
		(net "M_E_DQ<31>")
	)
	(gr_poly
		(pts
			(xy 241.279934 -104.610154) (xy 241.244374 -104.508554) (xy 241.137694 -104.508554) (xy 241.102134 -104.610154)
			(xy 241.102134 -104.660954) (xy 241.279934 -104.660954)
		)
		(stroke
			(width 0)
			(type solid)
		)
		(fill yes)
		(layer "F.Cu")
		(net "M_E_DQ<30>")
	)
	(gr_poly
		(pts
			(xy 241.279934 -104.305354) (xy 241.244374 -104.203754) (xy 241.137694 -104.203754) (xy 241.102134 -104.305354)
			(xy 241.102134 -104.356154) (xy 241.279934 -104.356154)
		)
		(stroke
			(width 0)
			(type solid)
		)
		(fill yes)
		(layer "F.Cu")
		(net "M_E_DQS_DP<3>")
	)
	(gr_poly
		(pts
			(xy 241.279934 -104.000554) (xy 241.244374 -103.898954) (xy 241.137694 -103.898954) (xy 241.102134 -104.000554)
			(xy 241.102134 -104.051354) (xy 241.279934 -104.051354)
		)
		(stroke
			(width 0)
			(type solid)
		)
		(fill yes)
		(layer "F.Cu")
		(net "M_E_DQS_DN<3>")
	)
	(gr_poly
		(pts
			(xy 241.279934 -103.695754) (xy 241.244374 -103.594154) (xy 241.137694 -103.594154) (xy 241.102134 -103.695754)
			(xy 241.102134 -103.746554) (xy 241.279934 -103.746554)
		)
		(stroke
			(width 0)
			(type solid)
		)
		(fill yes)
		(layer "F.Cu")
		(net "M_E_DQS_DN<12>")
	)
	(gr_poly
		(pts
			(xy 241.279934 -103.390954) (xy 241.244374 -103.289354) (xy 241.137694 -103.289354) (xy 241.102134 -103.390954)
			(xy 241.102134 -103.441754) (xy 241.279934 -103.441754)
		)
		(stroke
			(width 0)
			(type solid)
		)
		(fill yes)
		(layer "F.Cu")
		(net "M_E_DQS_DP<12>")
	)
	(gr_poly
		(pts
			(xy 241.279934 -103.086154) (xy 241.244374 -102.984554) (xy 241.137694 -102.984554) (xy 241.102134 -103.086154)
			(xy 241.102134 -103.136954) (xy 241.279934 -103.136954)
		)
		(stroke
			(width 0)
			(type solid)
		)
		(fill yes)
		(layer "F.Cu")
		(net "M_E_DQ<25>")
	)
	(gr_poly
		(pts
			(xy 241.279934 -102.781354) (xy 241.244374 -102.679754) (xy 241.137694 -102.679754) (xy 241.102134 -102.781354)
			(xy 241.102134 -102.832154) (xy 241.279934 -102.832154)
		)
		(stroke
			(width 0)
			(type solid)
		)
		(fill yes)
		(layer "F.Cu")
		(net "M_E_DQ<24>")
	)
	(gr_poly
		(pts
			(xy 241.32286 -48.95469) (xy 241.32286 -48.90389) (xy 241.14506 -48.90389) (xy 241.14506 -48.95469)
			(xy 241.18062 -49.05629) (xy 241.2873 -49.05629)
		)
		(stroke
			(width 0)
			(type solid)
		)
		(fill yes)
		(layer "F.Cu")
		(net "M_B_DQ<24>")
	)
	(gr_poly
		(pts
			(xy 241.32286 -48.64989) (xy 241.32286 -48.59909) (xy 241.14506 -48.59909) (xy 241.14506 -48.64989)
			(xy 241.18062 -48.75149) (xy 241.2873 -48.75149)
		)
		(stroke
			(width 0)
			(type solid)
		)
		(fill yes)
		(layer "F.Cu")
		(net "M_B_DQ<25>")
	)
	(gr_poly
		(pts
			(xy 241.32286 -48.34509) (xy 241.32286 -48.29429) (xy 241.14506 -48.29429) (xy 241.14506 -48.34509)
			(xy 241.18062 -48.44669) (xy 241.2873 -48.44669)
		)
		(stroke
			(width 0)
			(type solid)
		)
		(fill yes)
		(layer "F.Cu")
		(net "M_B_DQS_DP<12>")
	)
	(gr_poly
		(pts
			(xy 241.32286 -48.04029) (xy 241.32286 -47.98949) (xy 241.14506 -47.98949) (xy 241.14506 -48.04029)
			(xy 241.18062 -48.14189) (xy 241.2873 -48.14189)
		)
		(stroke
			(width 0)
			(type solid)
		)
		(fill yes)
		(layer "F.Cu")
		(net "M_B_DQS_DN<12>")
	)
	(gr_poly
		(pts
			(xy 241.32286 -47.73549) (xy 241.32286 -47.68469) (xy 241.14506 -47.68469) (xy 241.14506 -47.73549)
			(xy 241.18062 -47.83709) (xy 241.2873 -47.83709)
		)
		(stroke
			(width 0)
			(type solid)
		)
		(fill yes)
		(layer "F.Cu")
		(net "M_B_DQS_DN<3>")
	)
	(gr_poly
		(pts
			(xy 241.32286 -47.43069) (xy 241.32286 -47.37989) (xy 241.14506 -47.37989) (xy 241.14506 -47.43069)
			(xy 241.18062 -47.53229) (xy 241.2873 -47.53229)
		)
		(stroke
			(width 0)
			(type solid)
		)
		(fill yes)
		(layer "F.Cu")
		(net "M_B_DQS_DP<3>")
	)
	(gr_poly
		(pts
			(xy 241.32286 -47.12589) (xy 241.32286 -47.07509) (xy 241.14506 -47.07509) (xy 241.14506 -47.12589)
			(xy 241.18062 -47.22749) (xy 241.2873 -47.22749)
		)
		(stroke
			(width 0)
			(type solid)
		)
		(fill yes)
		(layer "F.Cu")
		(net "M_B_DQ<30>")
	)
	(gr_poly
		(pts
			(xy 241.32286 -46.82109) (xy 241.32286 -46.77029) (xy 241.14506 -46.77029) (xy 241.14506 -46.82109)
			(xy 241.18062 -46.92269) (xy 241.2873 -46.92269)
		)
		(stroke
			(width 0)
			(type solid)
		)
		(fill yes)
		(layer "F.Cu")
		(net "M_B_DQ<31>")
	)
	(gr_poly
		(pts
			(xy 241.32286 -46.51629) (xy 241.32286 -46.46549) (xy 241.14506 -46.46549) (xy 241.14506 -46.51629)
			(xy 241.18062 -46.61789) (xy 241.2873 -46.61789)
		)
		(stroke
			(width 0)
			(type solid)
		)
		(fill yes)
		(layer "F.Cu")
		(net "M_B_DQ<26>")
	)
	(gr_poly
		(pts
			(xy 241.32286 -46.21149) (xy 241.32286 -46.14799) (xy 241.14506 -46.14799) (xy 241.14506 -46.21149)
			(xy 241.18062 -46.31309) (xy 241.2873 -46.31309)
		)
		(stroke
			(width 0)
			(type solid)
		)
		(fill yes)
		(layer "F.Cu")
		(net "M_B_DQ<27>")
	)
	(gr_poly
		(pts
			(xy 241.388392 -43.279568) (xy 241.388392 -43.228768) (xy 241.261392 -43.228768) (xy 241.261392 -43.279568)
			(xy 241.274092 -43.470068) (xy 241.375692 -43.470068)
		)
		(stroke
			(width 0)
			(type solid)
		)
		(fill yes)
		(layer "F.Cu")
		(net "M_B_DQS_DN<17>")
	)
	(gr_poly
		(pts
			(xy 241.413792 -44.854368) (xy 241.413792 -44.803568) (xy 241.286792 -44.803568) (xy 241.286792 -44.854368)
			(xy 241.299492 -45.044868) (xy 241.401092 -45.044868)
		)
		(stroke
			(width 0)
			(type solid)
		)
		(fill yes)
		(layer "F.Cu")
		(net "M_B_ECC<5>")
	)
	(gr_poly
		(pts
			(xy 241.413792 -44.460668) (xy 241.413792 -44.409868) (xy 241.286792 -44.409868) (xy 241.286792 -44.460668)
			(xy 241.299492 -44.651168) (xy 241.401092 -44.651168)
		)
		(stroke
			(width 0)
			(type solid)
		)
		(fill yes)
		(layer "F.Cu")
		(net "M_B_ECC<0>")
	)
	(gr_poly
		(pts
			(xy 241.413792 -44.066968) (xy 241.413792 -44.016168) (xy 241.286792 -44.016168) (xy 241.286792 -44.066968)
			(xy 241.299492 -44.257468) (xy 241.401092 -44.257468)
		)
		(stroke
			(width 0)
			(type solid)
		)
		(fill yes)
		(layer "F.Cu")
		(net "M_B_ECC<1>")
	)
	(gr_poly
		(pts
			(xy 241.413792 -43.673268) (xy 241.413792 -43.622468) (xy 241.286792 -43.622468) (xy 241.286792 -43.673268)
			(xy 241.299492 -43.863768) (xy 241.401092 -43.863768)
		)
		(stroke
			(width 0)
			(type solid)
		)
		(fill yes)
		(layer "F.Cu")
		(net "M_B_DQS_DP<17>")
	)
	(gr_poly
		(pts
			(xy 241.495834 -105.321354) (xy 241.495834 -105.270554) (xy 241.318034 -105.270554) (xy 241.318034 -105.321354)
			(xy 241.353594 -105.422954) (xy 241.460274 -105.422954)
		)
		(stroke
			(width 0)
			(type solid)
		)
		(fill yes)
		(layer "F.Cu")
		(net "M_E_DQ<26>")
	)
	(gr_poly
		(pts
			(xy 241.495834 -105.016554) (xy 241.495834 -104.965754) (xy 241.318034 -104.965754) (xy 241.318034 -105.016554)
			(xy 241.353594 -105.118154) (xy 241.460274 -105.118154)
		)
		(stroke
			(width 0)
			(type solid)
		)
		(fill yes)
		(layer "F.Cu")
		(net "M_E_DQ<31>")
	)
	(gr_poly
		(pts
			(xy 241.495834 -104.711754) (xy 241.495834 -104.660954) (xy 241.318034 -104.660954) (xy 241.318034 -104.711754)
			(xy 241.353594 -104.813354) (xy 241.460274 -104.813354)
		)
		(stroke
			(width 0)
			(type solid)
		)
		(fill yes)
		(layer "F.Cu")
		(net "M_E_DQ<30>")
	)
	(gr_poly
		(pts
			(xy 241.495834 -104.406954) (xy 241.495834 -104.356154) (xy 241.318034 -104.356154) (xy 241.318034 -104.406954)
			(xy 241.353594 -104.508554) (xy 241.460274 -104.508554)
		)
		(stroke
			(width 0)
			(type solid)
		)
		(fill yes)
		(layer "F.Cu")
		(net "M_E_DQS_DP<3>")
	)
	(gr_poly
		(pts
			(xy 241.495834 -104.102154) (xy 241.495834 -104.051354) (xy 241.318034 -104.051354) (xy 241.318034 -104.102154)
			(xy 241.353594 -104.203754) (xy 241.460274 -104.203754)
		)
		(stroke
			(width 0)
			(type solid)
		)
		(fill yes)
		(layer "F.Cu")
		(net "M_E_DQS_DN<3>")
	)
	(gr_poly
		(pts
			(xy 241.495834 -103.797354) (xy 241.495834 -103.746554) (xy 241.318034 -103.746554) (xy 241.318034 -103.797354)
			(xy 241.353594 -103.898954) (xy 241.460274 -103.898954)
		)
		(stroke
			(width 0)
			(type solid)
		)
		(fill yes)
		(layer "F.Cu")
		(net "M_E_DQS_DN<12>")
	)
	(gr_poly
		(pts
			(xy 241.495834 -103.492554) (xy 241.495834 -103.441754) (xy 241.318034 -103.441754) (xy 241.318034 -103.492554)
			(xy 241.353594 -103.594154) (xy 241.460274 -103.594154)
		)
		(stroke
			(width 0)
			(type solid)
		)
		(fill yes)
		(layer "F.Cu")
		(net "M_E_DQS_DP<12>")
	)
	(gr_poly
		(pts
			(xy 241.495834 -103.187754) (xy 241.495834 -103.136954) (xy 241.318034 -103.136954) (xy 241.318034 -103.187754)
			(xy 241.353594 -103.289354) (xy 241.460274 -103.289354)
		)
		(stroke
			(width 0)
			(type solid)
		)
		(fill yes)
		(layer "F.Cu")
		(net "M_E_DQ<25>")
	)
	(gr_poly
		(pts
			(xy 241.495834 -102.882954) (xy 241.495834 -102.832154) (xy 241.318034 -102.832154) (xy 241.318034 -102.882954)
			(xy 241.353594 -102.984554) (xy 241.460274 -102.984554)
		)
		(stroke
			(width 0)
			(type solid)
		)
		(fill yes)
		(layer "F.Cu")
		(net "M_E_DQ<24>")
	)
	(gr_poly
		(pts
			(xy 241.53876 -48.85309) (xy 241.5032 -48.75149) (xy 241.39652 -48.75149) (xy 241.36096 -48.85309)
			(xy 241.36096 -48.90389) (xy 241.53876 -48.90389)
		)
		(stroke
			(width 0)
			(type solid)
		)
		(fill yes)
		(layer "F.Cu")
		(net "M_B_DQ<24>")
	)
	(gr_poly
		(pts
			(xy 241.53876 -48.54829) (xy 241.5032 -48.44669) (xy 241.39652 -48.44669) (xy 241.36096 -48.54829)
			(xy 241.36096 -48.59909) (xy 241.53876 -48.59909)
		)
		(stroke
			(width 0)
			(type solid)
		)
		(fill yes)
		(layer "F.Cu")
		(net "M_B_DQ<25>")
	)
	(gr_poly
		(pts
			(xy 241.53876 -48.24349) (xy 241.5032 -48.14189) (xy 241.39652 -48.14189) (xy 241.36096 -48.24349)
			(xy 241.36096 -48.29429) (xy 241.53876 -48.29429)
		)
		(stroke
			(width 0)
			(type solid)
		)
		(fill yes)
		(layer "F.Cu")
		(net "M_B_DQS_DP<12>")
	)
	(gr_poly
		(pts
			(xy 241.53876 -47.93869) (xy 241.5032 -47.83709) (xy 241.39652 -47.83709) (xy 241.36096 -47.93869)
			(xy 241.36096 -47.98949) (xy 241.53876 -47.98949)
		)
		(stroke
			(width 0)
			(type solid)
		)
		(fill yes)
		(layer "F.Cu")
		(net "M_B_DQS_DN<12>")
	)
	(gr_poly
		(pts
			(xy 241.53876 -47.63389) (xy 241.5032 -47.53229) (xy 241.39652 -47.53229) (xy 241.36096 -47.63389)
			(xy 241.36096 -47.68469) (xy 241.53876 -47.68469)
		)
		(stroke
			(width 0)
			(type solid)
		)
		(fill yes)
		(layer "F.Cu")
		(net "M_B_DQS_DN<3>")
	)
	(gr_poly
		(pts
			(xy 241.53876 -47.32909) (xy 241.5032 -47.22749) (xy 241.39652 -47.22749) (xy 241.36096 -47.32909)
			(xy 241.36096 -47.37989) (xy 241.53876 -47.37989)
		)
		(stroke
			(width 0)
			(type solid)
		)
		(fill yes)
		(layer "F.Cu")
		(net "M_B_DQS_DP<3>")
	)
	(gr_poly
		(pts
			(xy 241.53876 -47.02429) (xy 241.5032 -46.92269) (xy 241.39652 -46.92269) (xy 241.36096 -47.02429)
			(xy 241.36096 -47.07509) (xy 241.53876 -47.07509)
		)
		(stroke
			(width 0)
			(type solid)
		)
		(fill yes)
		(layer "F.Cu")
		(net "M_B_DQ<30>")
	)
	(gr_poly
		(pts
			(xy 241.53876 -46.71949) (xy 241.5032 -46.61789) (xy 241.39652 -46.61789) (xy 241.36096 -46.71949)
			(xy 241.36096 -46.77029) (xy 241.53876 -46.77029)
		)
		(stroke
			(width 0)
			(type solid)
		)
		(fill yes)
		(layer "F.Cu")
		(net "M_B_DQ<31>")
	)
	(gr_poly
		(pts
			(xy 241.53876 -46.41469) (xy 241.5032 -46.31309) (xy 241.39652 -46.31309) (xy 241.36096 -46.41469)
			(xy 241.36096 -46.46549) (xy 241.53876 -46.46549)
		)
		(stroke
			(width 0)
			(type solid)
		)
		(fill yes)
		(layer "F.Cu")
		(net "M_B_DQ<26>")
	)
	(gr_poly
		(pts
			(xy 241.545872 -106.404664) (xy 241.545872 -106.341164) (xy 241.418872 -106.341164) (xy 241.418872 -106.404664)
			(xy 241.431572 -106.595164) (xy 241.533172 -106.595164)
		)
		(stroke
			(width 0)
			(type solid)
		)
		(fill yes)
		(layer "F.Cu")
		(net "M_E_ECC<4>")
	)
	(gr_poly
		(pts
			(xy 241.621564 -51.361848) (xy 241.58702 -50.964592) (xy 241.54257 -50.968402) (xy 241.380772 -51.07178)
			(xy 241.400076 -51.291998) (xy 241.577368 -51.365658)
		)
		(stroke
			(width 0)
			(type solid)
		)
		(fill yes)
		(layer "F.Cu")
		(net "M_B_DQ<28>")
	)
	(gr_poly
		(pts
			(xy 241.711734 -105.524554) (xy 241.676174 -105.422954) (xy 241.569494 -105.422954) (xy 241.533934 -105.524554)
			(xy 241.533934 -105.588054) (xy 241.711734 -105.588054)
		)
		(stroke
			(width 0)
			(type solid)
		)
		(fill yes)
		(layer "F.Cu")
		(net "M_E_DQ<27>")
	)
	(gr_poly
		(pts
			(xy 241.711734 -105.219754) (xy 241.676174 -105.118154) (xy 241.569494 -105.118154) (xy 241.533934 -105.219754)
			(xy 241.533934 -105.270554) (xy 241.711734 -105.270554)
		)
		(stroke
			(width 0)
			(type solid)
		)
		(fill yes)
		(layer "F.Cu")
		(net "M_E_DQ<26>")
	)
	(gr_poly
		(pts
			(xy 241.711734 -104.914954) (xy 241.676174 -104.813354) (xy 241.569494 -104.813354) (xy 241.533934 -104.914954)
			(xy 241.533934 -104.965754) (xy 241.711734 -104.965754)
		)
		(stroke
			(width 0)
			(type solid)
		)
		(fill yes)
		(layer "F.Cu")
		(net "M_E_DQ<31>")
	)
	(gr_poly
		(pts
			(xy 241.711734 -104.610154) (xy 241.676174 -104.508554) (xy 241.569494 -104.508554) (xy 241.533934 -104.610154)
			(xy 241.533934 -104.660954) (xy 241.711734 -104.660954)
		)
		(stroke
			(width 0)
			(type solid)
		)
		(fill yes)
		(layer "F.Cu")
		(net "M_E_DQ<30>")
	)
	(gr_poly
		(pts
			(xy 241.711734 -104.305354) (xy 241.676174 -104.203754) (xy 241.569494 -104.203754) (xy 241.533934 -104.305354)
			(xy 241.533934 -104.356154) (xy 241.711734 -104.356154)
		)
		(stroke
			(width 0)
			(type solid)
		)
		(fill yes)
		(layer "F.Cu")
		(net "M_E_DQS_DP<3>")
	)
	(gr_poly
		(pts
			(xy 241.711734 -104.000554) (xy 241.676174 -103.898954) (xy 241.569494 -103.898954) (xy 241.533934 -104.000554)
			(xy 241.533934 -104.051354) (xy 241.711734 -104.051354)
		)
		(stroke
			(width 0)
			(type solid)
		)
		(fill yes)
		(layer "F.Cu")
		(net "M_E_DQS_DN<3>")
	)
	(gr_poly
		(pts
			(xy 241.711734 -103.695754) (xy 241.676174 -103.594154) (xy 241.569494 -103.594154) (xy 241.533934 -103.695754)
			(xy 241.533934 -103.746554) (xy 241.711734 -103.746554)
		)
		(stroke
			(width 0)
			(type solid)
		)
		(fill yes)
		(layer "F.Cu")
		(net "M_E_DQS_DN<12>")
	)
	(gr_poly
		(pts
			(xy 241.711734 -103.390954) (xy 241.676174 -103.289354) (xy 241.569494 -103.289354) (xy 241.533934 -103.390954)
			(xy 241.533934 -103.441754) (xy 241.711734 -103.441754)
		)
		(stroke
			(width 0)
			(type solid)
		)
		(fill yes)
		(layer "F.Cu")
		(net "M_E_DQS_DP<12>")
	)
	(gr_poly
		(pts
			(xy 241.711734 -103.086154) (xy 241.676174 -102.984554) (xy 241.569494 -102.984554) (xy 241.533934 -103.086154)
			(xy 241.533934 -103.136954) (xy 241.711734 -103.136954)
		)
		(stroke
			(width 0)
			(type solid)
		)
		(fill yes)
		(layer "F.Cu")
		(net "M_E_DQ<25>")
	)
	(gr_poly
		(pts
			(xy 241.711734 -102.781354) (xy 241.676174 -102.679754) (xy 241.569494 -102.679754) (xy 241.533934 -102.781354)
			(xy 241.533934 -102.832154) (xy 241.711734 -102.832154)
		)
		(stroke
			(width 0)
			(type solid)
		)
		(fill yes)
		(layer "F.Cu")
		(net "M_E_DQ<24>")
	)
	(gr_poly
		(pts
			(xy 241.743992 -45.146468) (xy 241.731292 -44.955968) (xy 241.629692 -44.955968) (xy 241.616992 -45.146468)
			(xy 241.616992 -45.209968) (xy 241.743992 -45.209968)
		)
		(stroke
			(width 0)
			(type solid)
		)
		(fill yes)
		(layer "F.Cu")
		(net "M_B_ECC<4>")
	)
	(gr_poly
		(pts
			(xy 241.743992 -44.752768) (xy 241.731292 -44.562268) (xy 241.629692 -44.562268) (xy 241.616992 -44.752768)
			(xy 241.616992 -44.803568) (xy 241.743992 -44.803568)
		)
		(stroke
			(width 0)
			(type solid)
		)
		(fill yes)
		(layer "F.Cu")
		(net "M_B_ECC<5>")
	)
	(gr_poly
		(pts
			(xy 241.743992 -44.359068) (xy 241.731292 -44.168568) (xy 241.629692 -44.168568) (xy 241.616992 -44.359068)
			(xy 241.616992 -44.409868) (xy 241.743992 -44.409868)
		)
		(stroke
			(width 0)
			(type solid)
		)
		(fill yes)
		(layer "F.Cu")
		(net "M_B_ECC<0>")
	)
	(gr_poly
		(pts
			(xy 241.743992 -43.965368) (xy 241.731292 -43.774868) (xy 241.629692 -43.774868) (xy 241.616992 -43.965368)
			(xy 241.616992 -44.016168) (xy 241.743992 -44.016168)
		)
		(stroke
			(width 0)
			(type solid)
		)
		(fill yes)
		(layer "F.Cu")
		(net "M_B_ECC<1>")
	)
	(gr_poly
		(pts
			(xy 241.743992 -43.571668) (xy 241.731292 -43.381168) (xy 241.629692 -43.381168) (xy 241.616992 -43.571668)
			(xy 241.616992 -43.622468) (xy 241.743992 -43.622468)
		)
		(stroke
			(width 0)
			(type solid)
		)
		(fill yes)
		(layer "F.Cu")
		(net "M_B_DQS_DP<17>")
	)
	(gr_poly
		(pts
			(xy 241.743992 -43.177968) (xy 241.731292 -42.987468) (xy 241.629692 -42.987468) (xy 241.616992 -43.177968)
			(xy 241.616992 -43.228768) (xy 241.743992 -43.228768)
		)
		(stroke
			(width 0)
			(type solid)
		)
		(fill yes)
		(layer "F.Cu")
		(net "M_B_DQS_DN<17>")
	)
	(gr_poly
		(pts
			(xy 241.743992 -42.784268) (xy 241.731292 -42.593768) (xy 241.629692 -42.593768) (xy 241.616992 -42.784268)
			(xy 241.616992 -42.835068) (xy 241.743992 -42.835068)
		)
		(stroke
			(width 0)
			(type solid)
		)
		(fill yes)
		(layer "F.Cu")
		(net "M_B_DQS_DN<8>")
	)
	(gr_poly
		(pts
			(xy 241.75466 -48.34509) (xy 241.75466 -48.29429) (xy 241.57686 -48.29429) (xy 241.57686 -48.34509)
			(xy 241.61242 -48.44669) (xy 241.7191 -48.44669)
		)
		(stroke
			(width 0)
			(type solid)
		)
		(fill yes)
		(layer "F.Cu")
		(net "M_B_DQS_DP<12>")
	)
	(gr_poly
		(pts
			(xy 241.75466 -48.04029) (xy 241.75466 -47.98949) (xy 241.57686 -47.98949) (xy 241.57686 -48.04029)
			(xy 241.61242 -48.14189) (xy 241.7191 -48.14189)
		)
		(stroke
			(width 0)
			(type solid)
		)
		(fill yes)
		(layer "F.Cu")
		(net "M_B_DQS_DN<12>")
	)
	(gr_poly
		(pts
			(xy 241.75466 -47.73549) (xy 241.75466 -47.68469) (xy 241.57686 -47.68469) (xy 241.57686 -47.73549)
			(xy 241.61242 -47.83709) (xy 241.7191 -47.83709)
		)
		(stroke
			(width 0)
			(type solid)
		)
		(fill yes)
		(layer "F.Cu")
		(net "M_B_DQS_DN<3>")
	)
	(gr_poly
		(pts
			(xy 241.75466 -47.43069) (xy 241.75466 -47.37989) (xy 241.57686 -47.37989) (xy 241.57686 -47.43069)
			(xy 241.61242 -47.53229) (xy 241.7191 -47.53229)
		)
		(stroke
			(width 0)
			(type solid)
		)
		(fill yes)
		(layer "F.Cu")
		(net "M_B_DQS_DP<3>")
	)
	(gr_poly
		(pts
			(xy 241.75466 -47.12589) (xy 241.75466 -47.07509) (xy 241.57686 -47.07509) (xy 241.57686 -47.12589)
			(xy 241.61242 -47.22749) (xy 241.7191 -47.22749)
		)
		(stroke
			(width 0)
			(type solid)
		)
		(fill yes)
		(layer "F.Cu")
		(net "M_B_DQ<30>")
	)
	(gr_poly
		(pts
			(xy 241.75466 -46.82109) (xy 241.75466 -46.77029) (xy 241.57686 -46.77029) (xy 241.57686 -46.82109)
			(xy 241.61242 -46.92269) (xy 241.7191 -46.92269)
		)
		(stroke
			(width 0)
			(type solid)
		)
		(fill yes)
		(layer "F.Cu")
		(net "M_B_DQ<31>")
	)
	(gr_poly
		(pts
			(xy 241.75466 -46.51629) (xy 241.75466 -46.46549) (xy 241.57686 -46.46549) (xy 241.57686 -46.51629)
			(xy 241.61242 -46.61789) (xy 241.7191 -46.61789)
		)
		(stroke
			(width 0)
			(type solid)
		)
		(fill yes)
		(layer "F.Cu")
		(net "M_B_DQ<26>")
	)
	(gr_poly
		(pts
			(xy 241.75466 -46.21149) (xy 241.75466 -46.14799) (xy 241.57686 -46.14799) (xy 241.57686 -46.21149)
			(xy 241.61242 -46.31309) (xy 241.7191 -46.31309)
		)
		(stroke
			(width 0)
			(type solid)
		)
		(fill yes)
		(layer "F.Cu")
		(net "M_B_DQ<27>")
	)
	(gr_poly
		(pts
			(xy 241.876072 -106.696764) (xy 241.863372 -106.506264) (xy 241.761772 -106.506264) (xy 241.749072 -106.696764)
			(xy 241.749072 -106.747564) (xy 241.876072 -106.747564)
		)
		(stroke
			(width 0)
			(type solid)
		)
		(fill yes)
		(layer "F.Cu")
		(net "M_E_ECC<5>")
	)
	(gr_poly
		(pts
			(xy 241.91468 -48.804068) (xy 241.950494 -48.768) (xy 241.825018 -48.642524) (xy 241.78895 -48.678338)
			(xy 241.742214 -48.775366) (xy 241.817652 -48.850804)
		)
		(stroke
			(width 0)
			(type solid)
		)
		(fill yes)
		(layer "F.Cu")
		(net "M_B_DQ<25>")
	)
	(gr_poly
		(pts
			(xy 241.92357 -49.100486) (xy 241.970306 -49.003458) (xy 241.894868 -48.92802) (xy 241.79784 -48.974756)
			(xy 241.761772 -49.01057) (xy 241.887502 -49.1363)
		)
		(stroke
			(width 0)
			(type solid)
		)
		(fill yes)
		(layer "F.Cu")
		(net "M_B_DQ<24>")
	)
	(gr_poly
		(pts
			(xy 241.927634 -105.321354) (xy 241.927634 -105.270554) (xy 241.749834 -105.270554) (xy 241.749834 -105.321354)
			(xy 241.785394 -105.422954) (xy 241.892074 -105.422954)
		)
		(stroke
			(width 0)
			(type solid)
		)
		(fill yes)
		(layer "F.Cu")
		(net "M_E_DQ<26>")
	)
	(gr_poly
		(pts
			(xy 241.927634 -105.016554) (xy 241.927634 -104.965754) (xy 241.749834 -104.965754) (xy 241.749834 -105.016554)
			(xy 241.785394 -105.118154) (xy 241.892074 -105.118154)
		)
		(stroke
			(width 0)
			(type solid)
		)
		(fill yes)
		(layer "F.Cu")
		(net "M_E_DQ<31>")
	)
	(gr_poly
		(pts
			(xy 241.927634 -104.711754) (xy 241.927634 -104.660954) (xy 241.749834 -104.660954) (xy 241.749834 -104.711754)
			(xy 241.785394 -104.813354) (xy 241.892074 -104.813354)
		)
		(stroke
			(width 0)
			(type solid)
		)
		(fill yes)
		(layer "F.Cu")
		(net "M_E_DQ<30>")
	)
	(gr_poly
		(pts
			(xy 241.927634 -104.406954) (xy 241.927634 -104.356154) (xy 241.749834 -104.356154) (xy 241.749834 -104.406954)
			(xy 241.785394 -104.508554) (xy 241.892074 -104.508554)
		)
		(stroke
			(width 0)
			(type solid)
		)
		(fill yes)
		(layer "F.Cu")
		(net "M_E_DQS_DP<3>")
	)
	(gr_poly
		(pts
			(xy 241.927634 -104.102154) (xy 241.927634 -104.051354) (xy 241.749834 -104.051354) (xy 241.749834 -104.102154)
			(xy 241.785394 -104.203754) (xy 241.892074 -104.203754)
		)
		(stroke
			(width 0)
			(type solid)
		)
		(fill yes)
		(layer "F.Cu")
		(net "M_E_DQS_DN<3>")
	)
	(gr_poly
		(pts
			(xy 241.927634 -103.797354) (xy 241.927634 -103.746554) (xy 241.749834 -103.746554) (xy 241.749834 -103.797354)
			(xy 241.785394 -103.898954) (xy 241.892074 -103.898954)
		)
		(stroke
			(width 0)
			(type solid)
		)
		(fill yes)
		(layer "F.Cu")
		(net "M_E_DQS_DN<12>")
	)
	(gr_poly
		(pts
			(xy 241.927634 -103.492554) (xy 241.927634 -103.441754) (xy 241.749834 -103.441754) (xy 241.749834 -103.492554)
			(xy 241.785394 -103.594154) (xy 241.892074 -103.594154)
		)
		(stroke
			(width 0)
			(type solid)
		)
		(fill yes)
		(layer "F.Cu")
		(net "M_E_DQS_DP<12>")
	)
	(gr_poly
		(pts
			(xy 241.927634 -103.187754) (xy 241.927634 -103.136954) (xy 241.749834 -103.136954) (xy 241.749834 -103.187754)
			(xy 241.785394 -103.289354) (xy 241.892074 -103.289354)
		)
		(stroke
			(width 0)
			(type solid)
		)
		(fill yes)
		(layer "F.Cu")
		(net "M_E_DQ<25>")
	)
	(gr_poly
		(pts
			(xy 241.97056 -47.93869) (xy 241.935 -47.83709) (xy 241.82832 -47.83709) (xy 241.79276 -47.93869)
			(xy 241.79276 -47.98949) (xy 241.97056 -47.98949)
		)
		(stroke
			(width 0)
			(type solid)
		)
		(fill yes)
		(layer "F.Cu")
		(net "M_B_DQS_DN<12>")
	)
	(gr_poly
		(pts
			(xy 241.97056 -47.63389) (xy 241.935 -47.53229) (xy 241.82832 -47.53229) (xy 241.79276 -47.63389)
			(xy 241.79276 -47.68469) (xy 241.97056 -47.68469)
		)
		(stroke
			(width 0)
			(type solid)
		)
		(fill yes)
		(layer "F.Cu")
		(net "M_B_DQS_DN<3>")
	)
	(gr_poly
		(pts
			(xy 241.97056 -47.32909) (xy 241.935 -47.22749) (xy 241.82832 -47.22749) (xy 241.79276 -47.32909)
			(xy 241.79276 -47.37989) (xy 241.97056 -47.37989)
		)
		(stroke
			(width 0)
			(type solid)
		)
		(fill yes)
		(layer "F.Cu")
		(net "M_B_DQS_DP<3>")
	)
	(gr_poly
		(pts
			(xy 241.97056 -47.02429) (xy 241.935 -46.92269) (xy 241.82832 -46.92269) (xy 241.79276 -47.02429)
			(xy 241.79276 -47.07509) (xy 241.97056 -47.07509)
		)
		(stroke
			(width 0)
			(type solid)
		)
		(fill yes)
		(layer "F.Cu")
		(net "M_B_DQ<30>")
	)
	(gr_poly
		(pts
			(xy 241.97056 -46.71949) (xy 241.935 -46.61789) (xy 241.82832 -46.61789) (xy 241.79276 -46.71949)
			(xy 241.79276 -46.77029) (xy 241.97056 -46.77029)
		)
		(stroke
			(width 0)
			(type solid)
		)
		(fill yes)
		(layer "F.Cu")
		(net "M_B_DQ<31>")
	)
	(gr_poly
		(pts
			(xy 241.97056 -46.41469) (xy 241.935 -46.31309) (xy 241.82832 -46.31309) (xy 241.79276 -46.41469)
			(xy 241.79276 -46.46549) (xy 241.97056 -46.46549)
		)
		(stroke
			(width 0)
			(type solid)
		)
		(fill yes)
		(layer "F.Cu")
		(net "M_B_DQ<26>")
	)
	(gr_poly
		(pts
			(xy 242.049554 -48.363886) (xy 242.09629 -48.266858) (xy 242.020852 -48.19142) (xy 241.923824 -48.238156)
			(xy 241.887756 -48.27397) (xy 242.013486 -48.3997)
		)
		(stroke
			(width 0)
			(type solid)
		)
		(fill yes)
		(layer "F.Cu")
		(net "M_B_DQS_DP<12>")
	)
	(gr_poly
		(pts
			(xy 242.064032 -102.841044) (xy 242.017296 -102.744016) (xy 241.981228 -102.708202) (xy 241.855752 -102.833678)
			(xy 241.891566 -102.869746) (xy 241.988594 -102.916482)
		)
		(stroke
			(width 0)
			(type solid)
		)
		(fill yes)
		(layer "F.Cu")
		(net "M_E_DQ<24>")
	)
	(gr_poly
		(pts
			(xy 242.071652 -44.96816) (xy 242.107466 -44.932092) (xy 242.017804 -44.84243) (xy 241.981736 -44.878244)
			(xy 241.856006 -45.022008) (xy 241.927888 -45.09389)
		)
		(stroke
			(width 0)
			(type solid)
		)
		(fill yes)
		(layer "F.Cu")
		(net "M_B_ECC<5>")
	)
	(gr_poly
		(pts
			(xy 242.074192 -44.460668) (xy 242.074192 -44.409868) (xy 241.947192 -44.409868) (xy 241.947192 -44.460668)
			(xy 241.959892 -44.651168) (xy 242.061492 -44.651168)
		)
		(stroke
			(width 0)
			(type solid)
		)
		(fill yes)
		(layer "F.Cu")
		(net "M_B_ECC<0>")
	)
	(gr_poly
		(pts
			(xy 242.074192 -44.066968) (xy 242.074192 -44.016168) (xy 241.947192 -44.016168) (xy 241.947192 -44.066968)
			(xy 241.959892 -44.257468) (xy 242.061492 -44.257468)
		)
		(stroke
			(width 0)
			(type solid)
		)
		(fill yes)
		(layer "F.Cu")
		(net "M_B_ECC<1>")
	)
	(gr_poly
		(pts
			(xy 242.074192 -43.673268) (xy 242.074192 -43.622468) (xy 241.947192 -43.622468) (xy 241.947192 -43.673268)
			(xy 241.959892 -43.863768) (xy 242.061492 -43.863768)
		)
		(stroke
			(width 0)
			(type solid)
		)
		(fill yes)
		(layer "F.Cu")
		(net "M_B_DQS_DP<17>")
	)
	(gr_poly
		(pts
			(xy 242.074192 -43.279568) (xy 242.074192 -43.228768) (xy 241.947192 -43.228768) (xy 241.947192 -43.279568)
			(xy 241.959892 -43.470068) (xy 242.061492 -43.470068)
		)
		(stroke
			(width 0)
			(type solid)
		)
		(fill yes)
		(layer "F.Cu")
		(net "M_B_DQS_DN<17>")
	)
	(gr_poly
		(pts
			(xy 242.074192 -42.885868) (xy 242.074192 -42.835068) (xy 241.947192 -42.835068) (xy 241.947192 -42.885868)
			(xy 241.959892 -43.076368) (xy 242.061492 -43.076368)
		)
		(stroke
			(width 0)
			(type solid)
		)
		(fill yes)
		(layer "F.Cu")
		(net "M_B_DQS_DN<8>")
	)
	(gr_poly
		(pts
			(xy 242.074192 -42.492168) (xy 242.074192 -42.441368) (xy 241.947192 -42.441368) (xy 241.947192 -42.492168)
			(xy 241.959892 -42.682668) (xy 242.061492 -42.682668)
		)
		(stroke
			(width 0)
			(type solid)
		)
		(fill yes)
		(layer "F.Cu")
		(net "M_B_DQS_DP<8>")
	)
	(gr_poly
		(pts
			(xy 242.098576 -45.40885) (xy 242.224306 -45.265086) (xy 242.152424 -45.193458) (xy 242.00866 -45.319188)
			(xy 241.972846 -45.355002) (xy 242.062762 -45.444918)
		)
		(stroke
			(width 0)
			(type solid)
		)
		(fill yes)
		(layer "F.Cu")
		(net "M_B_ECC<4>")
	)
	(gr_poly
		(pts
			(xy 242.130326 -48.588422) (xy 242.16614 -48.552354) (xy 242.040664 -48.426878) (xy 242.004596 -48.462692)
			(xy 241.95786 -48.55972) (xy 242.033298 -48.635158)
		)
		(stroke
			(width 0)
			(type solid)
		)
		(fill yes)
		(layer "F.Cu")
		(net "M_B_DQS_DP<12>")
	)
	(gr_poly
		(pts
			(xy 242.139216 -48.88484) (xy 242.185952 -48.787812) (xy 242.110514 -48.712374) (xy 242.013486 -48.75911)
			(xy 241.977418 -48.794924) (xy 242.103148 -48.920654)
		)
		(stroke
			(width 0)
			(type solid)
		)
		(fill yes)
		(layer "F.Cu")
		(net "M_B_DQ<25>")
	)
	(gr_poly
		(pts
			(xy 242.140486 -50.74158) (xy 242.140486 -50.5206) (xy 241.970306 -50.4317) (xy 241.925856 -50.4317)
			(xy 241.925856 -50.83048) (xy 241.970306 -50.83048)
		)
		(stroke
			(width 0)
			(type solid)
		)
		(fill yes)
		(layer "F.Cu")
		(net "M_B_DQ<29>")
	)
	(gr_poly
		(pts
			(xy 242.143534 -105.524554) (xy 242.107974 -105.422954) (xy 242.001294 -105.422954) (xy 241.965734 -105.524554)
			(xy 241.965734 -105.588054) (xy 242.143534 -105.588054)
		)
		(stroke
			(width 0)
			(type solid)
		)
		(fill yes)
		(layer "F.Cu")
		(net "M_E_DQ<27>")
	)
	(gr_poly
		(pts
			(xy 242.143534 -105.219754) (xy 242.107974 -105.118154) (xy 242.001294 -105.118154) (xy 241.965734 -105.219754)
			(xy 241.965734 -105.270554) (xy 242.143534 -105.270554)
		)
		(stroke
			(width 0)
			(type solid)
		)
		(fill yes)
		(layer "F.Cu")
		(net "M_E_DQ<26>")
	)
	(gr_poly
		(pts
			(xy 242.143534 -104.914954) (xy 242.107974 -104.813354) (xy 242.001294 -104.813354) (xy 241.965734 -104.914954)
			(xy 241.965734 -104.965754) (xy 242.143534 -104.965754)
		)
		(stroke
			(width 0)
			(type solid)
		)
		(fill yes)
		(layer "F.Cu")
		(net "M_E_DQ<31>")
	)
	(gr_poly
		(pts
			(xy 242.143534 -104.610154) (xy 242.107974 -104.508554) (xy 242.001294 -104.508554) (xy 241.965734 -104.610154)
			(xy 241.965734 -104.660954) (xy 242.143534 -104.660954)
		)
		(stroke
			(width 0)
			(type solid)
		)
		(fill yes)
		(layer "F.Cu")
		(net "M_E_DQ<30>")
	)
	(gr_poly
		(pts
			(xy 242.143534 -104.305354) (xy 242.107974 -104.203754) (xy 242.001294 -104.203754) (xy 241.965734 -104.305354)
			(xy 241.965734 -104.356154) (xy 242.143534 -104.356154)
		)
		(stroke
			(width 0)
			(type solid)
		)
		(fill yes)
		(layer "F.Cu")
		(net "M_E_DQS_DP<3>")
	)
	(gr_poly
		(pts
			(xy 242.143534 -104.000554) (xy 242.107974 -103.898954) (xy 242.001294 -103.898954) (xy 241.965734 -104.000554)
			(xy 241.965734 -104.051354) (xy 242.143534 -104.051354)
		)
		(stroke
			(width 0)
			(type solid)
		)
		(fill yes)
		(layer "F.Cu")
		(net "M_E_DQS_DN<3>")
	)
	(gr_poly
		(pts
			(xy 242.143534 -103.695754) (xy 242.107974 -103.594154) (xy 242.001294 -103.594154) (xy 241.965734 -103.695754)
			(xy 241.965734 -103.746554) (xy 242.143534 -103.746554)
		)
		(stroke
			(width 0)
			(type solid)
		)
		(fill yes)
		(layer "F.Cu")
		(net "M_E_DQS_DN<12>")
	)
	(gr_poly
		(pts
			(xy 242.18646 -47.43069) (xy 242.18646 -47.37989) (xy 242.00866 -47.37989) (xy 242.00866 -47.43069)
			(xy 242.04422 -47.53229) (xy 242.1509 -47.53229)
		)
		(stroke
			(width 0)
			(type solid)
		)
		(fill yes)
		(layer "F.Cu")
		(net "M_B_DQS_DP<3>")
	)
	(gr_poly
		(pts
			(xy 242.18646 -47.12589) (xy 242.18646 -47.07509) (xy 242.00866 -47.07509) (xy 242.00866 -47.12589)
			(xy 242.04422 -47.22749) (xy 242.1509 -47.22749)
		)
		(stroke
			(width 0)
			(type solid)
		)
		(fill yes)
		(layer "F.Cu")
		(net "M_B_DQ<30>")
	)
	(gr_poly
		(pts
			(xy 242.18646 -46.82109) (xy 242.18646 -46.77029) (xy 242.00866 -46.77029) (xy 242.00866 -46.82109)
			(xy 242.04422 -46.92269) (xy 242.1509 -46.92269)
		)
		(stroke
			(width 0)
			(type solid)
		)
		(fill yes)
		(layer "F.Cu")
		(net "M_B_DQ<31>")
	)
	(gr_poly
		(pts
			(xy 242.18646 -46.51629) (xy 242.18646 -46.46549) (xy 242.00866 -46.46549) (xy 242.00866 -46.51629)
			(xy 242.04422 -46.61789) (xy 242.1509 -46.61789)
		)
		(stroke
			(width 0)
			(type solid)
		)
		(fill yes)
		(layer "F.Cu")
		(net "M_B_DQ<26>")
	)
	(gr_poly
		(pts
			(xy 242.18646 -46.21149) (xy 242.18646 -46.14799) (xy 242.00866 -46.14799) (xy 242.00866 -46.21149)
			(xy 242.04422 -46.31309) (xy 242.1509 -46.31309)
		)
		(stroke
			(width 0)
			(type solid)
		)
		(fill yes)
		(layer "F.Cu")
		(net "M_B_DQ<27>")
	)
	(gr_poly
		(pts
			(xy 242.206272 -107.19181) (xy 242.206272 -107.14101) (xy 242.079272 -107.14101) (xy 242.079272 -107.19181)
			(xy 242.091972 -107.38231) (xy 242.193572 -107.38231)
		)
		(stroke
			(width 0)
			(type solid)
		)
		(fill yes)
		(layer "F.Cu")
		(net "M_E_ECC<0>")
	)
	(gr_poly
		(pts
			(xy 242.206272 -106.798364) (xy 242.206272 -106.747564) (xy 242.079272 -106.747564) (xy 242.079272 -106.798364)
			(xy 242.091972 -106.988864) (xy 242.193572 -106.988864)
		)
		(stroke
			(width 0)
			(type solid)
		)
		(fill yes)
		(layer "F.Cu")
		(net "M_E_ECC<5>")
	)
	(gr_poly
		(pts
			(xy 242.206272 -106.404664) (xy 242.206272 -106.341164) (xy 242.079272 -106.341164) (xy 242.079272 -106.404664)
			(xy 242.091972 -106.595164) (xy 242.193572 -106.595164)
		)
		(stroke
			(width 0)
			(type solid)
		)
		(fill yes)
		(layer "F.Cu")
		(net "M_E_ECC<4>")
	)
	(gr_poly
		(pts
			(xy 242.219988 -49.109376) (xy 242.255802 -49.073308) (xy 242.130326 -48.947832) (xy 242.094258 -48.983646)
			(xy 242.047522 -49.080674) (xy 242.12296 -49.156112)
		)
		(stroke
			(width 0)
			(type solid)
		)
		(fill yes)
		(layer "F.Cu")
		(net "M_B_DQ<25>")
	)
	(gr_poly
		(pts
			(xy 242.228878 -49.405794) (xy 242.275614 -49.308766) (xy 242.200176 -49.233328) (xy 242.103148 -49.280064)
			(xy 242.067334 -49.316132) (xy 242.193064 -49.441862)
		)
		(stroke
			(width 0)
			(type solid)
		)
		(fill yes)
		(layer "F.Cu")
		(net "M_B_DQ<24>")
	)
	(gr_poly
		(pts
			(xy 242.259866 -103.292148) (xy 242.224052 -103.25608) (xy 242.127024 -103.209344) (xy 242.051586 -103.284782)
			(xy 242.098322 -103.38181) (xy 242.134136 -103.417878)
		)
		(stroke
			(width 0)
			(type solid)
		)
		(fill yes)
		(layer "F.Cu")
		(net "M_E_DQS_DP<12>")
	)
	(gr_poly
		(pts
			(xy 242.2652 -48.14824) (xy 242.311936 -48.051212) (xy 242.236498 -47.975774) (xy 242.13947 -48.02251)
			(xy 242.103402 -48.058324) (xy 242.229132 -48.184054)
		)
		(stroke
			(width 0)
			(type solid)
		)
		(fill yes)
		(layer "F.Cu")
		(net "M_B_DQS_DN<12>")
	)
	(gr_poly
		(pts
			(xy 242.279678 -103.05669) (xy 242.232942 -102.959662) (xy 242.196874 -102.923848) (xy 242.071398 -103.049324)
			(xy 242.107212 -103.085392) (xy 242.20424 -103.132128)
		)
		(stroke
			(width 0)
			(type solid)
		)
		(fill yes)
		(layer "F.Cu")
		(net "M_E_DQ<25>")
	)
	(gr_poly
		(pts
			(xy 242.345972 -48.372776) (xy 242.381786 -48.336708) (xy 242.256056 -48.210978) (xy 242.220242 -48.247046)
			(xy 242.173506 -48.344074) (xy 242.248944 -48.419512)
		)
		(stroke
			(width 0)
			(type solid)
		)
		(fill yes)
		(layer "F.Cu")
		(net "M_B_DQS_DN<12>")
	)
	(gr_poly
		(pts
			(xy 242.349528 -102.771194) (xy 242.313714 -102.735126) (xy 242.216686 -102.68839) (xy 242.141248 -102.763828)
			(xy 242.187984 -102.860856) (xy 242.223798 -102.896924)
		)
		(stroke
			(width 0)
			(type solid)
		)
		(fill yes)
		(layer "F.Cu")
		(net "M_E_DQ<25>")
	)
	(gr_poly
		(pts
			(xy 242.35029 -44.689522) (xy 242.386104 -44.653454) (xy 242.296442 -44.563792) (xy 242.260374 -44.599606)
			(xy 242.134644 -44.74337) (xy 242.206526 -44.815252)
		)
		(stroke
			(width 0)
			(type solid)
		)
		(fill yes)
		(layer "F.Cu")
		(net "M_B_ECC<0>")
	)
	(gr_poly
		(pts
			(xy 242.354862 -48.669194) (xy 242.401598 -48.572166) (xy 242.32616 -48.496728) (xy 242.229132 -48.543464)
			(xy 242.193064 -48.579278) (xy 242.318794 -48.705008)
		)
		(stroke
			(width 0)
			(type solid)
		)
		(fill yes)
		(layer "F.Cu")
		(net "M_B_DQS_DP<12>")
	)
	(gr_poly
		(pts
			(xy 242.359434 -105.321354) (xy 242.359434 -105.270554) (xy 242.181634 -105.270554) (xy 242.181634 -105.321354)
			(xy 242.217194 -105.422954) (xy 242.323874 -105.422954)
		)
		(stroke
			(width 0)
			(type solid)
		)
		(fill yes)
		(layer "F.Cu")
		(net "M_E_DQ<26>")
	)
	(gr_poly
		(pts
			(xy 242.359434 -105.016554) (xy 242.359434 -104.965754) (xy 242.181634 -104.965754) (xy 242.181634 -105.016554)
			(xy 242.217194 -105.118154) (xy 242.323874 -105.118154)
		)
		(stroke
			(width 0)
			(type solid)
		)
		(fill yes)
		(layer "F.Cu")
		(net "M_E_DQ<31>")
	)
	(gr_poly
		(pts
			(xy 242.359434 -104.711754) (xy 242.359434 -104.660954) (xy 242.181634 -104.660954) (xy 242.181634 -104.711754)
			(xy 242.217194 -104.813354) (xy 242.323874 -104.813354)
		)
		(stroke
			(width 0)
			(type solid)
		)
		(fill yes)
		(layer "F.Cu")
		(net "M_E_DQ<30>")
	)
	(gr_poly
		(pts
			(xy 242.359434 -104.406954) (xy 242.359434 -104.356154) (xy 242.181634 -104.356154) (xy 242.181634 -104.406954)
			(xy 242.217194 -104.508554) (xy 242.323874 -104.508554)
		)
		(stroke
			(width 0)
			(type solid)
		)
		(fill yes)
		(layer "F.Cu")
		(net "M_E_DQS_DP<3>")
	)
	(gr_poly
		(pts
			(xy 242.359434 -104.102154) (xy 242.359434 -104.051354) (xy 242.181634 -104.051354) (xy 242.181634 -104.102154)
			(xy 242.217194 -104.203754) (xy 242.323874 -104.203754)
		)
		(stroke
			(width 0)
			(type solid)
		)
		(fill yes)
		(layer "F.Cu")
		(net "M_E_DQS_DN<3>")
	)
	(gr_poly
		(pts
			(xy 242.36934 -102.535736) (xy 242.322604 -102.438708) (xy 242.286536 -102.402894) (xy 242.16106 -102.52837)
			(xy 242.196874 -102.564438) (xy 242.293902 -102.611174)
		)
		(stroke
			(width 0)
			(type solid)
		)
		(fill yes)
		(layer "F.Cu")
		(net "M_E_DQ<24>")
	)
	(gr_poly
		(pts
			(xy 242.377214 -45.130212) (xy 242.502944 -44.986448) (xy 242.431062 -44.91482) (xy 242.287298 -45.04055)
			(xy 242.251484 -45.076364) (xy 242.3414 -45.16628)
		)
		(stroke
			(width 0)
			(type solid)
		)
		(fill yes)
		(layer "F.Cu")
		(net "M_B_ECC<5>")
	)
	(gr_poly
		(pts
			(xy 242.40236 -47.02429) (xy 242.3668 -46.92269) (xy 242.26012 -46.92269) (xy 242.22456 -47.02429)
			(xy 242.22456 -47.07509) (xy 242.40236 -47.07509)
		)
		(stroke
			(width 0)
			(type solid)
		)
		(fill yes)
		(layer "F.Cu")
		(net "M_B_DQ<30>")
	)
	(gr_poly
		(pts
			(xy 242.40236 -46.71949) (xy 242.3668 -46.61789) (xy 242.26012 -46.61789) (xy 242.22456 -46.71949)
			(xy 242.22456 -46.77029) (xy 242.40236 -46.77029)
		)
		(stroke
			(width 0)
			(type solid)
		)
		(fill yes)
		(layer "F.Cu")
		(net "M_B_DQ<31>")
	)
	(gr_poly
		(pts
			(xy 242.40236 -46.41469) (xy 242.3668 -46.31309) (xy 242.26012 -46.31309) (xy 242.22456 -46.41469)
			(xy 242.22456 -46.46549) (xy 242.40236 -46.46549)
		)
		(stroke
			(width 0)
			(type solid)
		)
		(fill yes)
		(layer "F.Cu")
		(net "M_B_DQ<26>")
	)
	(gr_poly
		(pts
			(xy 242.404392 -43.571668) (xy 242.391692 -43.381168) (xy 242.290092 -43.381168) (xy 242.277392 -43.571668)
			(xy 242.277392 -43.622468) (xy 242.404392 -43.622468)
		)
		(stroke
			(width 0)
			(type solid)
		)
		(fill yes)
		(layer "F.Cu")
		(net "M_B_DQS_DP<17>")
	)
	(gr_poly
		(pts
			(xy 242.404392 -43.177968) (xy 242.391692 -42.987468) (xy 242.290092 -42.987468) (xy 242.277392 -43.177968)
			(xy 242.277392 -43.228768) (xy 242.404392 -43.228768)
		)
		(stroke
			(width 0)
			(type solid)
		)
		(fill yes)
		(layer "F.Cu")
		(net "M_B_DQS_DN<17>")
	)
	(gr_poly
		(pts
			(xy 242.404392 -42.784268) (xy 242.391692 -42.593768) (xy 242.290092 -42.593768) (xy 242.277392 -42.784268)
			(xy 242.277392 -42.835068) (xy 242.404392 -42.835068)
		)
		(stroke
			(width 0)
			(type solid)
		)
		(fill yes)
		(layer "F.Cu")
		(net "M_B_DQS_DN<8>")
	)
	(gr_poly
		(pts
			(xy 242.404392 -42.390568) (xy 242.391692 -42.200068) (xy 242.290092 -42.200068) (xy 242.277392 -42.390568)
			(xy 242.277392 -42.441368) (xy 242.404392 -42.441368)
		)
		(stroke
			(width 0)
			(type solid)
		)
		(fill yes)
		(layer "F.Cu")
		(net "M_B_DQS_DP<8>")
	)
	(gr_poly
		(pts
			(xy 242.404392 -41.996868) (xy 242.391692 -41.806368) (xy 242.290092 -41.806368) (xy 242.277392 -41.996868)
			(xy 242.277392 -42.047668) (xy 242.404392 -42.047668)
		)
		(stroke
			(width 0)
			(type solid)
		)
		(fill yes)
		(layer "F.Cu")
		(net "M_B_ECC<6>")
	)
	(gr_poly
		(pts
			(xy 242.435634 -48.89373) (xy 242.471448 -48.857662) (xy 242.345972 -48.732186) (xy 242.309904 -48.768)
			(xy 242.263168 -48.865028) (xy 242.338606 -48.940466)
		)
		(stroke
			(width 0)
			(type solid)
		)
		(fill yes)
		(layer "F.Cu")
		(net "M_B_DQS_DP<12>")
	)
	(gr_poly
		(pts
			(xy 242.439444 -102.249986) (xy 242.403376 -102.214172) (xy 242.306348 -102.167436) (xy 242.23091 -102.242874)
			(xy 242.277646 -102.339902) (xy 242.313714 -102.375716)
		)
		(stroke
			(width 0)
			(type solid)
		)
		(fill yes)
		(layer "F.Cu")
		(net "M_E_DQ<24>")
	)
	(gr_poly
		(pts
			(xy 242.444524 -49.190148) (xy 242.49126 -49.09312) (xy 242.415822 -49.017682) (xy 242.318794 -49.064418)
			(xy 242.28298 -49.100486) (xy 242.40871 -49.226216)
		)
		(stroke
			(width 0)
			(type solid)
		)
		(fill yes)
		(layer "F.Cu")
		(net "M_B_DQ<25>")
	)
	(gr_poly
		(pts
			(xy 242.46713 -44.105576) (xy 242.59286 -43.961812) (xy 242.520978 -43.890184) (xy 242.377214 -44.015914)
			(xy 242.3414 -44.051728) (xy 242.431316 -44.141644)
		)
		(stroke
			(width 0)
			(type solid)
		)
		(fill yes)
		(layer "F.Cu")
		(net "M_B_ECC<1>")
	)
	(gr_poly
		(pts
			(xy 242.471956 -47.636176) (xy 242.50777 -47.600108) (xy 242.38204 -47.474378) (xy 242.346226 -47.510446)
			(xy 242.29949 -47.607474) (xy 242.374928 -47.682912)
		)
		(stroke
			(width 0)
			(type solid)
		)
		(fill yes)
		(layer "F.Cu")
		(net "M_B_DQS_DP<3>")
	)
	(gr_poly
		(pts
			(xy 242.475512 -103.507794) (xy 242.439698 -103.471726) (xy 242.34267 -103.42499) (xy 242.267232 -103.500428)
			(xy 242.313968 -103.597456) (xy 242.349782 -103.633524)
		)
		(stroke
			(width 0)
			(type solid)
		)
		(fill yes)
		(layer "F.Cu")
		(net "M_E_DQS_DN<12>")
	)
	(gr_poly
		(pts
			(xy 242.480846 -47.932594) (xy 242.527582 -47.835566) (xy 242.452144 -47.760128) (xy 242.355116 -47.806864)
			(xy 242.319048 -47.842678) (xy 242.444778 -47.968408)
		)
		(stroke
			(width 0)
			(type solid)
		)
		(fill yes)
		(layer "F.Cu")
		(net "M_B_DQS_DN<3>")
	)
	(gr_poly
		(pts
			(xy 242.495324 -103.272336) (xy 242.448588 -103.175308) (xy 242.41252 -103.139494) (xy 242.28679 -103.265224)
			(xy 242.322858 -103.301038) (xy 242.419886 -103.347774)
		)
		(stroke
			(width 0)
			(type solid)
		)
		(fill yes)
		(layer "F.Cu")
		(net "M_E_DQS_DP<12>")
	)
	(gr_poly
		(pts
			(xy 242.525296 -49.414684) (xy 242.561364 -49.37887) (xy 242.435634 -49.25314) (xy 242.399566 -49.288954)
			(xy 242.35283 -49.385982) (xy 242.428268 -49.46142)
		)
		(stroke
			(width 0)
			(type solid)
		)
		(fill yes)
		(layer "F.Cu")
		(net "M_B_DQ<25>")
	)
	(gr_poly
		(pts
			(xy 242.536472 -107.09021) (xy 242.523772 -106.89971) (xy 242.422172 -106.89971) (xy 242.409472 -107.09021)
			(xy 242.409472 -107.14101) (xy 242.536472 -107.14101)
		)
		(stroke
			(width 0)
			(type solid)
		)
		(fill yes)
		(layer "F.Cu")
		(net "M_E_ECC<0>")
	)
	(gr_poly
		(pts
			(xy 242.536472 -106.696764) (xy 242.523772 -106.506264) (xy 242.422172 -106.506264) (xy 242.409472 -106.696764)
			(xy 242.409472 -106.747564) (xy 242.536472 -106.747564)
		)
		(stroke
			(width 0)
			(type solid)
		)
		(fill yes)
		(layer "F.Cu")
		(net "M_E_ECC<5>")
	)
	(gr_poly
		(pts
			(xy 242.561618 -48.15713) (xy 242.597432 -48.121062) (xy 242.471702 -47.995332) (xy 242.435888 -48.0314)
			(xy 242.389152 -48.128428) (xy 242.46459 -48.203866)
		)
		(stroke
			(width 0)
			(type solid)
		)
		(fill yes)
		(layer "F.Cu")
		(net "M_B_DQS_DN<3>")
	)
	(gr_poly
		(pts
			(xy 242.565174 -102.98684) (xy 242.52936 -102.950772) (xy 242.432332 -102.904036) (xy 242.356894 -102.979474)
			(xy 242.40363 -103.076502) (xy 242.439444 -103.11257)
		)
		(stroke
			(width 0)
			(type solid)
		)
		(fill yes)
		(layer "F.Cu")
		(net "M_E_DQS_DP<12>")
	)
	(gr_poly
		(pts
			(xy 242.570508 -48.453548) (xy 242.617244 -48.35652) (xy 242.541806 -48.281082) (xy 242.444778 -48.327818)
			(xy 242.40871 -48.363632) (xy 242.53444 -48.489362)
		)
		(stroke
			(width 0)
			(type solid)
		)
		(fill yes)
		(layer "F.Cu")
		(net "M_B_DQS_DN<12>")
	)
	(gr_poly
		(pts
			(xy 242.575334 -105.524554) (xy 242.539774 -105.422954) (xy 242.433094 -105.422954) (xy 242.397534 -105.524554)
			(xy 242.397534 -105.588054) (xy 242.575334 -105.588054)
		)
		(stroke
			(width 0)
			(type solid)
		)
		(fill yes)
		(layer "F.Cu")
		(net "M_E_DQ<27>")
	)
	(gr_poly
		(pts
			(xy 242.575334 -105.219754) (xy 242.539774 -105.118154) (xy 242.433094 -105.118154) (xy 242.397534 -105.219754)
			(xy 242.397534 -105.270554) (xy 242.575334 -105.270554)
		)
		(stroke
			(width 0)
			(type solid)
		)
		(fill yes)
		(layer "F.Cu")
		(net "M_E_DQ<26>")
	)
	(gr_poly
		(pts
			(xy 242.575334 -104.914954) (xy 242.539774 -104.813354) (xy 242.433094 -104.813354) (xy 242.397534 -104.914954)
			(xy 242.397534 -104.965754) (xy 242.575334 -104.965754)
		)
		(stroke
			(width 0)
			(type solid)
		)
		(fill yes)
		(layer "F.Cu")
		(net "M_E_DQ<31>")
	)
	(gr_poly
		(pts
			(xy 242.584986 -102.751382) (xy 242.53825 -102.654354) (xy 242.502182 -102.61854) (xy 242.376706 -102.744016)
			(xy 242.41252 -102.780084) (xy 242.509548 -102.82682)
		)
		(stroke
			(width 0)
			(type solid)
		)
		(fill yes)
		(layer "F.Cu")
		(net "M_E_DQ<25>")
	)
	(gr_poly
		(pts
			(xy 242.60683 -47.195994) (xy 242.653566 -47.098966) (xy 242.578128 -47.023528) (xy 242.4811 -47.070264)
			(xy 242.445032 -47.106078) (xy 242.570762 -47.231808)
		)
		(stroke
			(width 0)
			(type solid)
		)
		(fill yes)
		(layer "F.Cu")
		(net "M_B_DQ<30>")
	)
	(gr_poly
		(pts
			(xy 242.61826 -46.21149) (xy 242.61826 -46.14799) (xy 242.44046 -46.14799) (xy 242.44046 -46.21149)
			(xy 242.47602 -46.31309) (xy 242.5827 -46.31309)
		)
		(stroke
			(width 0)
			(type solid)
		)
		(fill yes)
		(layer "F.Cu")
		(net "M_B_DQ<27>")
	)
	(gr_poly
		(pts
			(xy 242.621308 -104.008936) (xy 242.574572 -103.911908) (xy 242.538504 -103.876094) (xy 242.412774 -104.001824)
			(xy 242.448842 -104.037638) (xy 242.54587 -104.084374)
		)
		(stroke
			(width 0)
			(type solid)
		)
		(fill yes)
		(layer "F.Cu")
		(net "M_E_DQS_DN<3>")
	)
	(gr_poly
		(pts
			(xy 242.628928 -44.410884) (xy 242.664742 -44.374816) (xy 242.57508 -44.285154) (xy 242.539012 -44.320968)
			(xy 242.413282 -44.464732) (xy 242.485164 -44.536614)
		)
		(stroke
			(width 0)
			(type solid)
		)
		(fill yes)
		(layer "F.Cu")
		(net "M_B_ECC<1>")
	)
	(gr_poly
		(pts
			(xy 242.65128 -48.678084) (xy 242.687094 -48.642016) (xy 242.561618 -48.51654) (xy 242.52555 -48.552354)
			(xy 242.478814 -48.649382) (xy 242.554252 -48.72482)
		)
		(stroke
			(width 0)
			(type solid)
		)
		(fill yes)
		(layer "F.Cu")
		(net "M_B_DQS_DN<12>")
	)
	(gr_poly
		(pts
			(xy 242.65509 -102.465632) (xy 242.619022 -102.429818) (xy 242.521994 -102.383082) (xy 242.446556 -102.45852)
			(xy 242.493292 -102.555548) (xy 242.52936 -102.591362)
		)
		(stroke
			(width 0)
			(type solid)
		)
		(fill yes)
		(layer "F.Cu")
		(net "M_E_DQ<25>")
	)
	(gr_poly
		(pts
			(xy 242.655852 -44.851574) (xy 242.781582 -44.70781) (xy 242.7097 -44.636182) (xy 242.565936 -44.761912)
			(xy 242.530122 -44.797726) (xy 242.620038 -44.887642)
		)
		(stroke
			(width 0)
			(type solid)
		)
		(fill yes)
		(layer "F.Cu")
		(net "M_B_ECC<0>")
	)
	(gr_poly
		(pts
			(xy 242.66017 -48.974502) (xy 242.706906 -48.877474) (xy 242.631468 -48.802036) (xy 242.53444 -48.848772)
			(xy 242.498626 -48.88484) (xy 242.624356 -49.01057)
		)
		(stroke
			(width 0)
			(type solid)
		)
		(fill yes)
		(layer "F.Cu")
		(net "M_B_DQS_DP<12>")
	)
	(gr_poly
		(pts
			(xy 242.687602 -47.42053) (xy 242.723416 -47.384462) (xy 242.597686 -47.258732) (xy 242.561872 -47.2948)
			(xy 242.515136 -47.391828) (xy 242.590574 -47.467266)
		)
		(stroke
			(width 0)
			(type solid)
		)
		(fill yes)
		(layer "F.Cu")
		(net "M_B_DQ<30>")
	)
	(gr_poly
		(pts
			(xy 242.691158 -103.72344) (xy 242.655344 -103.687372) (xy 242.558316 -103.640636) (xy 242.482878 -103.716074)
			(xy 242.529614 -103.813102) (xy 242.565428 -103.84917)
		)
		(stroke
			(width 0)
			(type solid)
		)
		(fill yes)
		(layer "F.Cu")
		(net "M_E_DQS_DN<3>")
	)
	(gr_poly
		(pts
			(xy 242.691412 -51.677316) (xy 242.69954 -51.485546) (xy 242.508278 -51.375056) (xy 242.346226 -51.477926)
			(xy 242.323874 -51.516534) (xy 242.669314 -51.715924)
		)
		(stroke
			(width 0)
			(type solid)
		)
		(fill yes)
		(layer "F.Cu")
		(net "M_B_DQ<29>")
	)
	(gr_poly
		(pts
			(xy 242.696492 -47.716948) (xy 242.743228 -47.61992) (xy 242.66779 -47.544482) (xy 242.570762 -47.591218)
			(xy 242.534694 -47.627032) (xy 242.660424 -47.752762)
		)
		(stroke
			(width 0)
			(type solid)
		)
		(fill yes)
		(layer "F.Cu")
		(net "M_B_DQS_DP<3>")
	)
	(gr_poly
		(pts
			(xy 242.706652 -45.514514) (xy 242.671092 -45.412914) (xy 242.564412 -45.412914) (xy 242.528852 -45.514514)
			(xy 242.528852 -45.578014) (xy 242.706652 -45.578014)
		)
		(stroke
			(width 0)
			(type solid)
		)
		(fill yes)
		(layer "F.Cu")
		(net "M_B_ECC<4>")
	)
	(gr_poly
		(pts
			(xy 242.706652 -45.209714) (xy 242.671092 -45.108114) (xy 242.564412 -45.108114) (xy 242.528852 -45.209714)
			(xy 242.528852 -45.260514) (xy 242.706652 -45.260514)
		)
		(stroke
			(width 0)
			(type solid)
		)
		(fill yes)
		(layer "F.Cu")
		(net "M_B_ECC<5>")
	)
	(gr_poly
		(pts
			(xy 242.71097 -103.487982) (xy 242.664234 -103.390954) (xy 242.628166 -103.35514) (xy 242.502436 -103.48087)
			(xy 242.538504 -103.516684) (xy 242.635532 -103.56342)
		)
		(stroke
			(width 0)
			(type solid)
		)
		(fill yes)
		(layer "F.Cu")
		(net "M_E_DQS_DN<12>")
	)
	(gr_poly
		(pts
			(xy 242.719098 -43.386756) (xy 242.754912 -43.350688) (xy 242.66525 -43.261026) (xy 242.629182 -43.29684)
			(xy 242.503452 -43.440604) (xy 242.575334 -43.512486)
		)
		(stroke
			(width 0)
			(type solid)
		)
		(fill yes)
		(layer "F.Cu")
		(net "M_B_DQS_DN<17>")
	)
	(gr_poly
		(pts
			(xy 242.734592 -42.885868) (xy 242.734592 -42.835068) (xy 242.607592 -42.835068) (xy 242.607592 -42.885868)
			(xy 242.620292 -43.076368) (xy 242.721892 -43.076368)
		)
		(stroke
			(width 0)
			(type solid)
		)
		(fill yes)
		(layer "F.Cu")
		(net "M_B_DQS_DN<8>")
	)
	(gr_poly
		(pts
			(xy 242.734592 -42.492168) (xy 242.734592 -42.441368) (xy 242.607592 -42.441368) (xy 242.607592 -42.492168)
			(xy 242.620292 -42.682668) (xy 242.721892 -42.682668)
		)
		(stroke
			(width 0)
			(type solid)
		)
		(fill yes)
		(layer "F.Cu")
		(net "M_B_DQS_DP<8>")
	)
	(gr_poly
		(pts
			(xy 242.734592 -42.098468) (xy 242.734592 -42.047668) (xy 242.607592 -42.047668) (xy 242.607592 -42.098468)
			(xy 242.620292 -42.288968) (xy 242.721892 -42.288968)
		)
		(stroke
			(width 0)
			(type solid)
		)
		(fill yes)
		(layer "F.Cu")
		(net "M_B_ECC<6>")
	)
	(gr_poly
		(pts
			(xy 242.734592 -41.704768) (xy 242.734592 -41.653968) (xy 242.607592 -41.653968) (xy 242.607592 -41.704768)
			(xy 242.620292 -41.895268) (xy 242.721892 -41.895268)
		)
		(stroke
			(width 0)
			(type solid)
		)
		(fill yes)
		(layer "F.Cu")
		(net "M_B_ECC<7>")
	)
	(gr_poly
		(pts
			(xy 242.740942 -49.199038) (xy 242.77701 -49.163224) (xy 242.65128 -49.037494) (xy 242.615212 -49.073308)
			(xy 242.568476 -49.170336) (xy 242.643914 -49.245774)
		)
		(stroke
			(width 0)
			(type solid)
		)
		(fill yes)
		(layer "F.Cu")
		(net "M_B_DQS_DP<12>")
	)
	(gr_poly
		(pts
			(xy 242.745768 -43.826938) (xy 242.871498 -43.683174) (xy 242.799616 -43.611546) (xy 242.655852 -43.737276)
			(xy 242.620038 -43.77309) (xy 242.709954 -43.863006)
		)
		(stroke
			(width 0)
			(type solid)
		)
		(fill yes)
		(layer "F.Cu")
		(net "M_B_DQS_DP<17>")
	)
	(gr_poly
		(pts
			(xy 242.749832 -49.495456) (xy 242.796568 -49.398428) (xy 242.72113 -49.32299) (xy 242.624102 -49.369726)
			(xy 242.588288 -49.405794) (xy 242.714018 -49.531524)
		)
		(stroke
			(width 0)
			(type solid)
		)
		(fill yes)
		(layer "F.Cu")
		(net "M_B_DQ<25>")
	)
	(gr_poly
		(pts
			(xy 242.777264 -47.941484) (xy 242.813078 -47.905416) (xy 242.687348 -47.779686) (xy 242.651534 -47.815754)
			(xy 242.604798 -47.912782) (xy 242.680236 -47.98822)
		)
		(stroke
			(width 0)
			(type solid)
		)
		(fill yes)
		(layer "F.Cu")
		(net "M_B_DQS_DP<3>")
	)
	(gr_poly
		(pts
			(xy 242.78082 -103.202486) (xy 242.745006 -103.166418) (xy 242.647978 -103.119682) (xy 242.57254 -103.19512)
			(xy 242.619276 -103.292148) (xy 242.65509 -103.328216)
		)
		(stroke
			(width 0)
			(type solid)
		)
		(fill yes)
		(layer "F.Cu")
		(net "M_E_DQS_DN<12>")
	)
	(gr_poly
		(pts
			(xy 242.786154 -48.237902) (xy 242.83289 -48.140874) (xy 242.757452 -48.065436) (xy 242.660424 -48.112172)
			(xy 242.624356 -48.147986) (xy 242.750086 -48.273716)
		)
		(stroke
			(width 0)
			(type solid)
		)
		(fill yes)
		(layer "F.Cu")
		(net "M_B_DQS_DN<3>")
	)
	(gr_poly
		(pts
			(xy 242.791234 -105.321354) (xy 242.791234 -105.270554) (xy 242.613434 -105.270554) (xy 242.613434 -105.321354)
			(xy 242.648994 -105.422954) (xy 242.755674 -105.422954)
		)
		(stroke
			(width 0)
			(type solid)
		)
		(fill yes)
		(layer "F.Cu")
		(net "M_E_DQ<26>")
	)
	(gr_poly
		(pts
			(xy 242.800632 -102.967028) (xy 242.753896 -102.87) (xy 242.717828 -102.834186) (xy 242.592352 -102.959662)
			(xy 242.628166 -102.99573) (xy 242.725194 -103.042466)
		)
		(stroke
			(width 0)
			(type solid)
		)
		(fill yes)
		(layer "F.Cu")
		(net "M_E_DQS_DP<12>")
	)
	(gr_poly
		(pts
			(xy 242.813586 -46.68393) (xy 242.8494 -46.647862) (xy 242.72367 -46.522132) (xy 242.687856 -46.5582)
			(xy 242.64112 -46.655228) (xy 242.716558 -46.730666)
		)
		(stroke
			(width 0)
			(type solid)
		)
		(fill yes)
		(layer "F.Cu")
		(net "M_B_DQ<26>")
	)
	(gr_poly
		(pts
			(xy 242.817142 -104.46004) (xy 242.781328 -104.423972) (xy 242.6843 -104.377236) (xy 242.608862 -104.452674)
			(xy 242.655598 -104.549702) (xy 242.691412 -104.58577)
		)
		(stroke
			(width 0)
			(type solid)
		)
		(fill yes)
		(layer "F.Cu")
		(net "M_E_DQ<30>")
	)
	(gr_poly
		(pts
			(xy 242.822476 -46.980348) (xy 242.869212 -46.88332) (xy 242.793774 -46.807882) (xy 242.696746 -46.854618)
			(xy 242.660678 -46.890432) (xy 242.786408 -47.016162)
		)
		(stroke
			(width 0)
			(type solid)
		)
		(fill yes)
		(layer "F.Cu")
		(net "M_B_DQ<31>")
	)
	(gr_poly
		(pts
			(xy 242.830604 -49.719992) (xy 242.866672 -49.684178) (xy 242.740942 -49.558448) (xy 242.704874 -49.594262)
			(xy 242.658138 -49.69129) (xy 242.733576 -49.766728)
		)
		(stroke
			(width 0)
			(type solid)
		)
		(fill yes)
		(layer "F.Cu")
		(net "M_B_DQ<25>")
	)
	(gr_poly
		(pts
			(xy 242.836954 -104.224582) (xy 242.790218 -104.127554) (xy 242.75415 -104.09174) (xy 242.62842 -104.21747)
			(xy 242.664488 -104.253284) (xy 242.761516 -104.30002)
		)
		(stroke
			(width 0)
			(type solid)
		)
		(fill yes)
		(layer "F.Cu")
		(net "M_E_DQS_DP<3>")
	)
	(gr_poly
		(pts
			(xy 242.866672 -107.585256) (xy 242.866672 -107.534456) (xy 242.739672 -107.534456) (xy 242.739672 -107.585256)
			(xy 242.752372 -107.775756) (xy 242.853972 -107.775756)
		)
		(stroke
			(width 0)
			(type solid)
		)
		(fill yes)
		(layer "F.Cu")
		(net "M_E_ECC<1>")
	)
	(gr_poly
		(pts
			(xy 242.866672 -107.19181) (xy 242.866672 -107.14101) (xy 242.739672 -107.14101) (xy 242.739672 -107.19181)
			(xy 242.752372 -107.38231) (xy 242.853972 -107.38231)
		)
		(stroke
			(width 0)
			(type solid)
		)
		(fill yes)
		(layer "F.Cu")
		(net "M_E_ECC<0>")
	)
	(gr_poly
		(pts
			(xy 242.866672 -106.798364) (xy 242.866672 -106.747564) (xy 242.739672 -106.747564) (xy 242.739672 -106.798364)
			(xy 242.752372 -106.988864) (xy 242.853972 -106.988864)
		)
		(stroke
			(width 0)
			(type solid)
		)
		(fill yes)
		(layer "F.Cu")
		(net "M_E_ECC<5>")
	)
	(gr_poly
		(pts
			(xy 242.866672 -106.404664) (xy 242.866672 -106.341164) (xy 242.739672 -106.341164) (xy 242.739672 -106.404664)
			(xy 242.752372 -106.595164) (xy 242.853972 -106.595164)
		)
		(stroke
			(width 0)
			(type solid)
		)
		(fill yes)
		(layer "F.Cu")
		(net "M_E_ECC<4>")
	)
	(gr_poly
		(pts
			(xy 242.866926 -48.462438) (xy 242.90274 -48.42637) (xy 242.777264 -48.300894) (xy 242.741196 -48.336708)
			(xy 242.69446 -48.433736) (xy 242.769898 -48.509174)
		)
		(stroke
			(width 0)
			(type solid)
		)
		(fill yes)
		(layer "F.Cu")
		(net "M_B_DQS_DN<3>")
	)
	(gr_poly
		(pts
			(xy 242.870736 -102.681278) (xy 242.834668 -102.645464) (xy 242.73764 -102.598728) (xy 242.662202 -102.674166)
			(xy 242.708938 -102.771194) (xy 242.745006 -102.807008)
		)
		(stroke
			(width 0)
			(type solid)
		)
		(fill yes)
		(layer "F.Cu")
		(net "M_E_DQS_DP<12>")
	)
	(gr_poly
		(pts
			(xy 242.875816 -48.758856) (xy 242.922552 -48.661828) (xy 242.847114 -48.58639) (xy 242.750086 -48.633126)
			(xy 242.714272 -48.669194) (xy 242.840002 -48.794924)
		)
		(stroke
			(width 0)
			(type solid)
		)
		(fill yes)
		(layer "F.Cu")
		(net "M_B_DQS_DN<12>")
	)
	(gr_poly
		(pts
			(xy 242.890294 -102.446074) (xy 242.843558 -102.349046) (xy 242.807744 -102.312978) (xy 242.682014 -102.438708)
			(xy 242.717828 -102.474776) (xy 242.814856 -102.521512)
		)
		(stroke
			(width 0)
			(type solid)
		)
		(fill yes)
		(layer "F.Cu")
		(net "M_E_DQ<25>")
	)
	(gr_poly
		(pts
			(xy 242.903248 -47.204884) (xy 242.939062 -47.168816) (xy 242.813332 -47.043086) (xy 242.777518 -47.079154)
			(xy 242.730782 -47.176182) (xy 242.80622 -47.25162)
		)
		(stroke
			(width 0)
			(type solid)
		)
		(fill yes)
		(layer "F.Cu")
		(net "M_B_DQ<31>")
	)
	(gr_poly
		(pts
			(xy 242.906804 -103.939086) (xy 242.87099 -103.903018) (xy 242.773962 -103.856282) (xy 242.698524 -103.93172)
			(xy 242.74526 -104.028748) (xy 242.781074 -104.064816)
		)
		(stroke
			(width 0)
			(type solid)
		)
		(fill yes)
		(layer "F.Cu")
		(net "M_E_DQS_DP<3>")
	)
	(gr_poly
		(pts
			(xy 242.907566 -44.132246) (xy 242.94338 -44.096178) (xy 242.853718 -44.006516) (xy 242.81765 -44.04233)
			(xy 242.69192 -44.186094) (xy 242.763802 -44.257976)
		)
		(stroke
			(width 0)
			(type solid)
		)
		(fill yes)
		(layer "F.Cu")
		(net "M_B_DQS_DP<17>")
	)
	(gr_poly
		(pts
			(xy 242.912138 -47.501302) (xy 242.958874 -47.404274) (xy 242.883436 -47.328836) (xy 242.786408 -47.375572)
			(xy 242.75034 -47.411386) (xy 242.87607 -47.537116)
		)
		(stroke
			(width 0)
			(type solid)
		)
		(fill yes)
		(layer "F.Cu")
		(net "M_B_DQ<30>")
	)
	(gr_poly
		(pts
			(xy 242.922552 -45.311314) (xy 242.922552 -45.260514) (xy 242.744752 -45.260514) (xy 242.744752 -45.311314)
			(xy 242.780312 -45.412914) (xy 242.886992 -45.412914)
		)
		(stroke
			(width 0)
			(type solid)
		)
		(fill yes)
		(layer "F.Cu")
		(net "M_B_ECC<5>")
	)
	(gr_poly
		(pts
			(xy 242.922552 -45.006514) (xy 242.922552 -44.955714) (xy 242.744752 -44.955714) (xy 242.744752 -45.006514)
			(xy 242.780312 -45.108114) (xy 242.886992 -45.108114)
		)
		(stroke
			(width 0)
			(type solid)
		)
		(fill yes)
		(layer "F.Cu")
		(net "M_B_ECC<0>")
	)
	(gr_poly
		(pts
			(xy 242.926616 -103.703628) (xy 242.87988 -103.6066) (xy 242.843812 -103.570786) (xy 242.718082 -103.696516)
			(xy 242.75415 -103.73233) (xy 242.851178 -103.779066)
		)
		(stroke
			(width 0)
			(type solid)
		)
		(fill yes)
		(layer "F.Cu")
		(net "M_E_DQS_DN<3>")
	)
	(gr_poly
		(pts
			(xy 242.93449 -44.572936) (xy 243.06022 -44.429172) (xy 242.988338 -44.357544) (xy 242.844574 -44.483274)
			(xy 242.80876 -44.519088) (xy 242.898676 -44.609004)
		)
		(stroke
			(width 0)
			(type solid)
		)
		(fill yes)
		(layer "F.Cu")
		(net "M_B_ECC<1>")
	)
	(gr_poly
		(pts
			(xy 242.956588 -48.983392) (xy 242.992656 -48.947578) (xy 242.866926 -48.821848) (xy 242.830858 -48.857662)
			(xy 242.784122 -48.95469) (xy 242.85956 -49.030128)
		)
		(stroke
			(width 0)
			(type solid)
		)
		(fill yes)
		(layer "F.Cu")
		(net "M_B_DQS_DN<12>")
	)
	(gr_poly
		(pts
			(xy 242.962938 -104.961182) (xy 242.916202 -104.864154) (xy 242.880134 -104.82834) (xy 242.754404 -104.95407)
			(xy 242.790472 -104.989884) (xy 242.8875 -105.03662)
		)
		(stroke
			(width 0)
			(type solid)
		)
		(fill yes)
		(layer "F.Cu")
		(net "M_E_DQ<31>")
	)
	(gr_poly
		(pts
			(xy 242.965478 -49.27981) (xy 243.012214 -49.182782) (xy 242.936776 -49.107344) (xy 242.839748 -49.15408)
			(xy 242.803934 -49.190148) (xy 242.929664 -49.315878)
		)
		(stroke
			(width 0)
			(type solid)
		)
		(fill yes)
		(layer "F.Cu")
		(net "M_B_DQS_DP<12>")
	)
	(gr_poly
		(pts
			(xy 242.99291 -47.725838) (xy 243.028724 -47.68977) (xy 242.902994 -47.56404) (xy 242.86718 -47.600108)
			(xy 242.820444 -47.697136) (xy 242.895882 -47.772574)
		)
		(stroke
			(width 0)
			(type solid)
		)
		(fill yes)
		(layer "F.Cu")
		(net "M_B_DQ<30>")
	)
	(gr_poly
		(pts
			(xy 242.996466 -103.418132) (xy 242.960652 -103.382064) (xy 242.863624 -103.335328) (xy 242.788186 -103.410766)
			(xy 242.834922 -103.507794) (xy 242.870736 -103.543862)
		)
		(stroke
			(width 0)
			(type solid)
		)
		(fill yes)
		(layer "F.Cu")
		(net "M_E_DQS_DN<3>")
	)
	(gr_poly
		(pts
			(xy 242.997482 -43.108372) (xy 243.033296 -43.072304) (xy 242.943634 -42.982642) (xy 242.907566 -43.018456)
			(xy 242.781836 -43.16222) (xy 242.853718 -43.234102)
		)
		(stroke
			(width 0)
			(type solid)
		)
		(fill yes)
		(layer "F.Cu")
		(net "M_B_DQS_DN<8>")
	)
	(gr_poly
		(pts
			(xy 243.0018 -48.022256) (xy 243.048536 -47.925228) (xy 242.973098 -47.84979) (xy 242.87607 -47.896526)
			(xy 242.840002 -47.93234) (xy 242.965732 -48.05807)
		)
		(stroke
			(width 0)
			(type solid)
		)
		(fill yes)
		(layer "F.Cu")
		(net "M_B_DQS_DP<3>")
	)
	(gr_poly
		(pts
			(xy 243.016278 -103.182674) (xy 242.969542 -103.085646) (xy 242.933474 -103.049832) (xy 242.807998 -103.175308)
			(xy 242.843812 -103.211376) (xy 242.94084 -103.258112)
		)
		(stroke
			(width 0)
			(type solid)
		)
		(fill yes)
		(layer "F.Cu")
		(net "M_E_DQS_DN<12>")
	)
	(gr_poly
		(pts
			(xy 243.024406 -43.5483) (xy 243.150136 -43.404536) (xy 243.078254 -43.332908) (xy 242.93449 -43.458638)
			(xy 242.898676 -43.494452) (xy 242.988592 -43.584368)
		)
		(stroke
			(width 0)
			(type solid)
		)
		(fill yes)
		(layer "F.Cu")
		(net "M_B_DQS_DN<17>")
	)
	(gr_poly
		(pts
			(xy 243.028978 -46.468284) (xy 243.073936 -46.423326) (xy 242.948206 -46.297596) (xy 242.903248 -46.342554)
			(xy 242.856766 -46.439582) (xy 242.932204 -46.51502)
		)
		(stroke
			(width 0)
			(type solid)
		)
		(fill yes)
		(layer "F.Cu")
		(net "M_B_DQ<27>")
	)
	(gr_poly
		(pts
			(xy 243.032788 -104.675686) (xy 242.996974 -104.639618) (xy 242.899946 -104.592882) (xy 242.824508 -104.66832)
			(xy 242.871244 -104.765348) (xy 242.907058 -104.801416)
		)
		(stroke
			(width 0)
			(type solid)
		)
		(fill yes)
		(layer "F.Cu")
		(net "M_E_DQ<31>")
	)
	(gr_poly
		(pts
			(xy 243.038122 -46.764702) (xy 243.084858 -46.667674) (xy 243.00942 -46.592236) (xy 242.912392 -46.638972)
			(xy 242.876324 -46.674786) (xy 243.002054 -46.800516)
		)
		(stroke
			(width 0)
			(type solid)
		)
		(fill yes)
		(layer "F.Cu")
		(net "M_B_DQ<26>")
	)
	(gr_poly
		(pts
			(xy 243.0526 -104.440228) (xy 243.005864 -104.3432) (xy 242.969796 -104.307386) (xy 242.844066 -104.433116)
			(xy 242.880134 -104.46893) (xy 242.977162 -104.515666)
		)
		(stroke
			(width 0)
			(type solid)
		)
		(fill yes)
		(layer "F.Cu")
		(net "M_E_DQ<30>")
	)
	(gr_poly
		(pts
			(xy 243.057172 -41.996868) (xy 243.044472 -41.806368) (xy 242.942872 -41.806368) (xy 242.930172 -41.996868)
			(xy 242.930172 -42.047668) (xy 243.057172 -42.047668)
		)
		(stroke
			(width 0)
			(type solid)
		)
		(fill yes)
		(layer "F.Cu")
		(net "M_B_ECC<6>")
	)
	(gr_poly
		(pts
			(xy 243.064792 -41.603168) (xy 243.052092 -41.412668) (xy 242.950492 -41.412668) (xy 242.937792 -41.603168)
			(xy 242.937792 -41.653968) (xy 243.064792 -41.653968)
		)
		(stroke
			(width 0)
			(type solid)
		)
		(fill yes)
		(layer "F.Cu")
		(net "M_B_ECC<7>")
	)
	(gr_poly
		(pts
			(xy 243.082572 -48.246792) (xy 243.118386 -48.210724) (xy 242.99291 -48.085248) (xy 242.956842 -48.121062)
			(xy 242.910106 -48.21809) (xy 242.985544 -48.293528)
		)
		(stroke
			(width 0)
			(type solid)
		)
		(fill yes)
		(layer "F.Cu")
		(net "M_B_DQS_DP<3>")
	)
	(gr_poly
		(pts
			(xy 243.086382 -102.896924) (xy 243.050314 -102.86111) (xy 242.953286 -102.814374) (xy 242.877848 -102.889812)
			(xy 242.924584 -102.98684) (xy 242.960652 -103.022654)
		)
		(stroke
			(width 0)
			(type solid)
		)
		(fill yes)
		(layer "F.Cu")
		(net "M_E_DQS_DN<12>")
	)
	(gr_poly
		(pts
			(xy 243.091462 -48.54321) (xy 243.138198 -48.446182) (xy 243.06276 -48.370744) (xy 242.965732 -48.41748)
			(xy 242.929918 -48.453548) (xy 243.055648 -48.579278)
		)
		(stroke
			(width 0)
			(type solid)
		)
		(fill yes)
		(layer "F.Cu")
		(net "M_B_DQS_DN<3>")
	)
	(gr_poly
		(pts
			(xy 243.10594 -102.66172) (xy 243.059204 -102.564692) (xy 243.02339 -102.528624) (xy 242.89766 -102.654354)
			(xy 242.933474 -102.690422) (xy 243.030502 -102.737158)
		)
		(stroke
			(width 0)
			(type solid)
		)
		(fill yes)
		(layer "F.Cu")
		(net "M_E_DQS_DP<12>")
	)
	(gr_poly
		(pts
			(xy 243.113814 -42.524172) (xy 243.239544 -42.380408) (xy 243.167916 -42.308526) (xy 243.024152 -42.434256)
			(xy 242.988084 -42.47007) (xy 243.078 -42.559986)
		)
		(stroke
			(width 0)
			(type solid)
		)
		(fill yes)
		(layer "F.Cu")
		(net "M_B_DQS_DP<8>")
	)
	(gr_poly
		(pts
			(xy 243.118894 -46.989238) (xy 243.154708 -46.95317) (xy 243.028978 -46.82744) (xy 242.993164 -46.863508)
			(xy 242.946428 -46.960536) (xy 243.021866 -47.035974)
		)
		(stroke
			(width 0)
			(type solid)
		)
		(fill yes)
		(layer "F.Cu")
		(net "M_B_DQ<26>")
	)
	(gr_poly
		(pts
			(xy 243.12245 -104.154732) (xy 243.086636 -104.118664) (xy 242.989608 -104.071928) (xy 242.91417 -104.147366)
			(xy 242.960906 -104.244394) (xy 242.99672 -104.280462)
		)
		(stroke
			(width 0)
			(type solid)
		)
		(fill yes)
		(layer "F.Cu")
		(net "M_E_DQ<30>")
	)
	(gr_poly
		(pts
			(xy 243.127784 -47.285656) (xy 243.17452 -47.188628) (xy 243.099082 -47.11319) (xy 243.002054 -47.159926)
			(xy 242.965986 -47.19574) (xy 243.091716 -47.32147)
		)
		(stroke
			(width 0)
			(type solid)
		)
		(fill yes)
		(layer "F.Cu")
		(net "M_B_DQ<31>")
	)
	(gr_poly
		(pts
			(xy 243.138452 -45.514514) (xy 243.102892 -45.412914) (xy 242.996212 -45.412914) (xy 242.960652 -45.514514)
			(xy 242.960652 -45.578014) (xy 243.138452 -45.578014)
		)
		(stroke
			(width 0)
			(type solid)
		)
		(fill yes)
		(layer "F.Cu")
		(net "M_B_ECC<4>")
	)
	(gr_poly
		(pts
			(xy 243.138452 -45.209714) (xy 243.102892 -45.108114) (xy 242.996212 -45.108114) (xy 242.960652 -45.209714)
			(xy 242.960652 -45.260514) (xy 243.138452 -45.260514)
		)
		(stroke
			(width 0)
			(type solid)
		)
		(fill yes)
		(layer "F.Cu")
		(net "M_B_ECC<5>")
	)
	(gr_poly
		(pts
			(xy 243.138452 -44.904914) (xy 243.102892 -44.803314) (xy 242.996212 -44.803314) (xy 242.960652 -44.904914)
			(xy 242.960652 -44.955714) (xy 243.138452 -44.955714)
		)
		(stroke
			(width 0)
			(type solid)
		)
		(fill yes)
		(layer "F.Cu")
		(net "M_B_ECC<0>")
	)
	(gr_poly
		(pts
			(xy 243.142262 -103.919274) (xy 243.095526 -103.822246) (xy 243.059458 -103.786432) (xy 242.933728 -103.912162)
			(xy 242.969796 -103.947976) (xy 243.066824 -103.994712)
		)
		(stroke
			(width 0)
			(type solid)
		)
		(fill yes)
		(layer "F.Cu")
		(net "M_E_DQS_DP<3>")
	)
	(gr_poly
		(pts
			(xy 243.167662 -105.421176) (xy 243.122958 -105.376218) (xy 243.02593 -105.329482) (xy 242.950492 -105.40492)
			(xy 242.997228 -105.501948) (xy 243.041932 -105.546906)
		)
		(stroke
			(width 0)
			(type solid)
		)
		(fill yes)
		(layer "F.Cu")
		(net "M_E_DQ<27>")
	)
	(gr_poly
		(pts
			(xy 243.172234 -48.767746) (xy 243.208302 -48.731932) (xy 243.082572 -48.606202) (xy 243.046504 -48.642016)
			(xy 242.999768 -48.739044) (xy 243.075206 -48.814482)
		)
		(stroke
			(width 0)
			(type solid)
		)
		(fill yes)
		(layer "F.Cu")
		(net "M_B_DQS_DN<3>")
	)
	(gr_poly
		(pts
			(xy 243.178584 -105.176828) (xy 243.131848 -105.0798) (xy 243.09578 -105.043986) (xy 242.97005 -105.169716)
			(xy 243.006118 -105.20553) (xy 243.103146 -105.252266)
		)
		(stroke
			(width 0)
			(type solid)
		)
		(fill yes)
		(layer "F.Cu")
		(net "M_E_DQ<26>")
	)
	(gr_poly
		(pts
			(xy 243.181124 -49.064164) (xy 243.22786 -48.967136) (xy 243.152422 -48.891698) (xy 243.055394 -48.938434)
			(xy 243.01958 -48.974502) (xy 243.14531 -49.100232)
		)
		(stroke
			(width 0)
			(type solid)
		)
		(fill yes)
		(layer "F.Cu")
		(net "M_B_DQS_DN<12>")
	)
	(gr_poly
		(pts
			(xy 243.18595 -43.853608) (xy 243.222018 -43.817794) (xy 243.132102 -43.727878) (xy 243.096288 -43.763946)
			(xy 242.970558 -43.907456) (xy 243.04244 -43.979338)
		)
		(stroke
			(width 0)
			(type solid)
		)
		(fill yes)
		(layer "F.Cu")
		(net "M_B_DQS_DN<17>")
	)
	(gr_poly
		(pts
			(xy 243.196872 -107.483656) (xy 243.184172 -107.293156) (xy 243.082572 -107.293156) (xy 243.069872 -107.483656)
			(xy 243.069872 -107.534456) (xy 243.196872 -107.534456)
		)
		(stroke
			(width 0)
			(type solid)
		)
		(fill yes)
		(layer "F.Cu")
		(net "M_E_ECC<1>")
	)
	(gr_poly
		(pts
			(xy 243.196872 -107.09021) (xy 243.184172 -106.89971) (xy 243.082572 -106.89971) (xy 243.069872 -107.09021)
			(xy 243.069872 -107.14101) (xy 243.196872 -107.14101)
		)
		(stroke
			(width 0)
			(type solid)
		)
		(fill yes)
		(layer "F.Cu")
		(net "M_E_ECC<0>")
	)
	(gr_poly
		(pts
			(xy 243.196872 -106.696764) (xy 243.184172 -106.506264) (xy 243.082572 -106.506264) (xy 243.069872 -106.696764)
			(xy 243.069872 -106.747564) (xy 243.196872 -106.747564)
		)
		(stroke
			(width 0)
			(type solid)
		)
		(fill yes)
		(layer "F.Cu")
		(net "M_E_ECC<5>")
	)
	(gr_poly
		(pts
			(xy 243.208556 -47.510192) (xy 243.24437 -47.474124) (xy 243.11864 -47.348394) (xy 243.082826 -47.384462)
			(xy 243.03609 -47.48149) (xy 243.111528 -47.556928)
		)
		(stroke
			(width 0)
			(type solid)
		)
		(fill yes)
		(layer "F.Cu")
		(net "M_B_DQ<31>")
	)
	(gr_poly
		(pts
			(xy 243.212112 -103.633778) (xy 243.176298 -103.59771) (xy 243.07927 -103.550974) (xy 243.003832 -103.626412)
			(xy 243.050568 -103.72344) (xy 243.086382 -103.759508)
		)
		(stroke
			(width 0)
			(type solid)
		)
		(fill yes)
		(layer "F.Cu")
		(net "M_E_DQS_DP<3>")
	)
	(gr_poly
		(pts
			(xy 243.217446 -47.80661) (xy 243.264182 -47.709582) (xy 243.188744 -47.634144) (xy 243.091716 -47.68088)
			(xy 243.055648 -47.716694) (xy 243.181378 -47.842424)
		)
		(stroke
			(width 0)
			(type solid)
		)
		(fill yes)
		(layer "F.Cu")
		(net "M_B_DQ<30>")
	)
	(gr_poly
		(pts
			(xy 243.231924 -103.39832) (xy 243.185188 -103.301292) (xy 243.14912 -103.265478) (xy 243.023644 -103.390954)
			(xy 243.059458 -103.427022) (xy 243.156486 -103.473758)
		)
		(stroke
			(width 0)
			(type solid)
		)
		(fill yes)
		(layer "F.Cu")
		(net "M_E_DQS_DN<3>")
	)
	(gr_poly
		(pts
			(xy 243.248434 -104.891332) (xy 243.21262 -104.855264) (xy 243.115592 -104.808528) (xy 243.040154 -104.883966)
			(xy 243.08689 -104.980994) (xy 243.122704 -105.017062)
		)
		(stroke
			(width 0)
			(type solid)
		)
		(fill yes)
		(layer "F.Cu")
		(net "M_E_DQ<26>")
	)
	(gr_poly
		(pts
			(xy 243.268246 -104.655874) (xy 243.22151 -104.558846) (xy 243.185442 -104.523032) (xy 243.059712 -104.648762)
			(xy 243.09578 -104.684576) (xy 243.192808 -104.731312)
		)
		(stroke
			(width 0)
			(type solid)
		)
		(fill yes)
		(layer "F.Cu")
		(net "M_E_DQ<31>")
	)
	(gr_poly
		(pts
			(xy 243.275866 -42.829734) (xy 243.311934 -42.79392) (xy 243.222018 -42.704004) (xy 243.186204 -42.740072)
			(xy 243.060474 -42.883582) (xy 243.132356 -42.955464)
		)
		(stroke
			(width 0)
			(type solid)
		)
		(fill yes)
		(layer "F.Cu")
		(net "M_B_DQS_DP<8>")
	)
	(gr_poly
		(pts
			(xy 243.298218 -48.031146) (xy 243.334032 -47.995078) (xy 243.208556 -47.869602) (xy 243.172488 -47.905416)
			(xy 243.125752 -48.002444) (xy 243.20119 -48.077882)
		)
		(stroke
			(width 0)
			(type solid)
		)
		(fill yes)
		(layer "F.Cu")
		(net "M_B_DQ<30>")
	)
	(gr_poly
		(pts
			(xy 243.302028 -103.11257) (xy 243.26596 -103.076756) (xy 243.168932 -103.03002) (xy 243.093494 -103.105458)
			(xy 243.14023 -103.202486) (xy 243.176298 -103.2383)
		)
		(stroke
			(width 0)
			(type solid)
		)
		(fill yes)
		(layer "F.Cu")
		(net "M_E_DQS_DN<3>")
	)
	(gr_poly
		(pts
			(xy 243.30279 -43.269916) (xy 243.42852 -43.126152) (xy 243.356638 -43.054524) (xy 243.212874 -43.180254)
			(xy 243.17706 -43.216068) (xy 243.266976 -43.305984)
		)
		(stroke
			(width 0)
			(type solid)
		)
		(fill yes)
		(layer "F.Cu")
		(net "M_B_DQS_DN<8>")
	)
	(gr_poly
		(pts
			(xy 243.307108 -48.327564) (xy 243.353844 -48.230536) (xy 243.278406 -48.155098) (xy 243.181378 -48.201834)
			(xy 243.145564 -48.237902) (xy 243.271294 -48.363632)
		)
		(stroke
			(width 0)
			(type solid)
		)
		(fill yes)
		(layer "F.Cu")
		(net "M_B_DQS_DP<3>")
	)
	(gr_poly
		(pts
			(xy 243.321586 -102.877366) (xy 243.27485 -102.780338) (xy 243.239036 -102.74427) (xy 243.113306 -102.87)
			(xy 243.14912 -102.906068) (xy 243.246148 -102.952804)
		)
		(stroke
			(width 0)
			(type solid)
		)
		(fill yes)
		(layer "F.Cu")
		(net "M_E_DQS_DN<12>")
	)
	(gr_poly
		(pts
			(xy 243.33454 -46.773592) (xy 243.379244 -46.728634) (xy 243.253514 -46.602904) (xy 243.20881 -46.647862)
			(xy 243.162074 -46.74489) (xy 243.237512 -46.820328)
		)
		(stroke
			(width 0)
			(type solid)
		)
		(fill yes)
		(layer "F.Cu")
		(net "M_B_DQ<27>")
	)
	(gr_poly
		(pts
			(xy 243.338096 -104.370378) (xy 243.302282 -104.33431) (xy 243.205254 -104.287574) (xy 243.129816 -104.363012)
			(xy 243.176552 -104.46004) (xy 243.212366 -104.496108)
		)
		(stroke
			(width 0)
			(type solid)
		)
		(fill yes)
		(layer "F.Cu")
		(net "M_E_DQ<31>")
	)
	(gr_poly
		(pts
			(xy 243.339112 -51.893724) (xy 243.294916 -51.889914) (xy 243.117624 -51.963574) (xy 243.09832 -52.183792)
			(xy 243.260118 -52.28717) (xy 243.304568 -52.29098)
		)
		(stroke
			(width 0)
			(type solid)
		)
		(fill yes)
		(layer "F.Cu")
		(net "M_B_DQS_DN<3>")
	)
	(gr_poly
		(pts
			(xy 243.34343 -47.07001) (xy 243.390166 -46.972982) (xy 243.314728 -46.897544) (xy 243.2177 -46.94428)
			(xy 243.181632 -46.980094) (xy 243.307362 -47.105824)
		)
		(stroke
			(width 0)
			(type solid)
		)
		(fill yes)
		(layer "F.Cu")
		(net "M_B_DQ<26>")
	)
	(gr_poly
		(pts
			(xy 243.354352 -45.311314) (xy 243.354352 -45.260514) (xy 243.176552 -45.260514) (xy 243.176552 -45.311314)
			(xy 243.212112 -45.412914) (xy 243.318792 -45.412914)
		)
		(stroke
			(width 0)
			(type solid)
		)
		(fill yes)
		(layer "F.Cu")
		(net "M_B_ECC<5>")
	)
	(gr_poly
		(pts
			(xy 243.354352 -45.006514) (xy 243.354352 -44.955714) (xy 243.176552 -44.955714) (xy 243.176552 -45.006514)
			(xy 243.212112 -45.108114) (xy 243.318792 -45.108114)
		)
		(stroke
			(width 0)
			(type solid)
		)
		(fill yes)
		(layer "F.Cu")
		(net "M_B_ECC<0>")
	)
	(gr_poly
		(pts
			(xy 243.354352 -44.701714) (xy 243.354352 -44.650914) (xy 243.176552 -44.650914) (xy 243.176552 -44.701714)
			(xy 243.212112 -44.803314) (xy 243.318792 -44.803314)
		)
		(stroke
			(width 0)
			(type solid)
		)
		(fill yes)
		(layer "F.Cu")
		(net "M_B_ECC<1>")
	)
	(gr_poly
		(pts
			(xy 243.354352 -44.396914) (xy 243.354352 -44.346114) (xy 243.176552 -44.346114) (xy 243.176552 -44.396914)
			(xy 243.212112 -44.498514) (xy 243.318792 -44.498514)
		)
		(stroke
			(width 0)
			(type solid)
		)
		(fill yes)
		(layer "F.Cu")
		(net "M_B_DQS_DP<17>")
	)
	(gr_poly
		(pts
			(xy 243.357908 -104.13492) (xy 243.311172 -104.037892) (xy 243.275104 -104.002078) (xy 243.149374 -104.127808)
			(xy 243.185442 -104.163622) (xy 243.28247 -104.210358)
		)
		(stroke
			(width 0)
			(type solid)
		)
		(fill yes)
		(layer "F.Cu")
		(net "M_E_DQ<30>")
	)
	(gr_poly
		(pts
			(xy 243.365528 -41.805352) (xy 243.401596 -41.769538) (xy 243.31168 -41.679622) (xy 243.275866 -41.71569)
			(xy 243.150136 -41.8592) (xy 243.222018 -41.931082)
		)
		(stroke
			(width 0)
			(type solid)
		)
		(fill yes)
		(layer "F.Cu")
		(net "M_B_ECC<7>")
	)
	(gr_poly
		(pts
			(xy 243.38788 -48.5521) (xy 243.423948 -48.516286) (xy 243.298218 -48.390556) (xy 243.26215 -48.42637)
			(xy 243.215414 -48.523398) (xy 243.290852 -48.598836)
		)
		(stroke
			(width 0)
			(type solid)
		)
		(fill yes)
		(layer "F.Cu")
		(net "M_B_DQS_DP<3>")
	)
	(gr_poly
		(pts
			(xy 243.392452 -42.245534) (xy 243.518182 -42.10177) (xy 243.446554 -42.029888) (xy 243.30279 -42.155618)
			(xy 243.266722 -42.191432) (xy 243.356638 -42.281348)
		)
		(stroke
			(width 0)
			(type solid)
		)
		(fill yes)
		(layer "F.Cu")
		(net "M_B_ECC<6>")
	)
	(gr_poly
		(pts
			(xy 243.39677 -48.848518) (xy 243.443506 -48.75149) (xy 243.368068 -48.676052) (xy 243.27104 -48.722788)
			(xy 243.235226 -48.758856) (xy 243.360956 -48.884586)
		)
		(stroke
			(width 0)
			(type solid)
		)
		(fill yes)
		(layer "F.Cu")
		(net "M_B_DQS_DN<3>")
	)
	(gr_poly
		(pts
			(xy 243.424202 -47.294546) (xy 243.460016 -47.258478) (xy 243.334286 -47.132748) (xy 243.298472 -47.168816)
			(xy 243.251736 -47.265844) (xy 243.327174 -47.341282)
		)
		(stroke
			(width 0)
			(type solid)
		)
		(fill yes)
		(layer "F.Cu")
		(net "M_B_DQ<26>")
	)
	(gr_poly
		(pts
			(xy 243.427758 -103.849424) (xy 243.391944 -103.813356) (xy 243.294916 -103.76662) (xy 243.219478 -103.842058)
			(xy 243.266214 -103.939086) (xy 243.302028 -103.975154)
		)
		(stroke
			(width 0)
			(type solid)
		)
		(fill yes)
		(layer "F.Cu")
		(net "M_E_DQ<30>")
	)
	(gr_poly
		(pts
			(xy 243.433092 -47.590964) (xy 243.479828 -47.493936) (xy 243.40439 -47.418498) (xy 243.307362 -47.465234)
			(xy 243.271294 -47.501048) (xy 243.397024 -47.626778)
		)
		(stroke
			(width 0)
			(type solid)
		)
		(fill yes)
		(layer "F.Cu")
		(net "M_B_DQ<31>")
	)
	(gr_poly
		(pts
			(xy 243.44757 -103.613966) (xy 243.400834 -103.516938) (xy 243.364766 -103.481124) (xy 243.23929 -103.6066)
			(xy 243.275104 -103.642668) (xy 243.372132 -103.689404)
		)
		(stroke
			(width 0)
			(type solid)
		)
		(fill yes)
		(layer "F.Cu")
		(net "M_E_DQS_DP<3>")
	)
	(gr_poly
		(pts
			(xy 243.464334 -43.575224) (xy 243.500402 -43.53941) (xy 243.410486 -43.449494) (xy 243.374672 -43.485562)
			(xy 243.248942 -43.629072) (xy 243.320824 -43.700954)
		)
		(stroke
			(width 0)
			(type solid)
		)
		(fill yes)
		(layer "F.Cu")
		(net "M_B_DQS_DN<8>")
	)
	(gr_poly
		(pts
			(xy 243.47297 -105.115868) (xy 243.428266 -105.07091) (xy 243.331238 -105.024174) (xy 243.2558 -105.099612)
			(xy 243.302536 -105.19664) (xy 243.34724 -105.241598)
		)
		(stroke
			(width 0)
			(type solid)
		)
		(fill yes)
		(layer "F.Cu")
		(net "M_E_DQ<27>")
	)
	(gr_poly
		(pts
			(xy 243.477542 -49.073054) (xy 243.51361 -49.03724) (xy 243.38788 -48.91151) (xy 243.351812 -48.947324)
			(xy 243.305076 -49.044352) (xy 243.380514 -49.11979)
		)
		(stroke
			(width 0)
			(type solid)
		)
		(fill yes)
		(layer "F.Cu")
		(net "M_B_DQS_DN<3>")
	)
	(gr_poly
		(pts
			(xy 243.482368 -41.22166) (xy 243.608098 -41.077896) (xy 243.53647 -41.006014) (xy 243.392706 -41.131744)
			(xy 243.356638 -41.167558) (xy 243.446554 -41.257474)
		)
		(stroke
			(width 0)
			(type solid)
		)
		(fill yes)
		(layer "F.Cu")
		(net "M_B_ECC<2>")
	)
	(gr_poly
		(pts
			(xy 243.483892 -104.87152) (xy 243.437156 -104.774492) (xy 243.401088 -104.738678) (xy 243.275358 -104.864408)
			(xy 243.311426 -104.900222) (xy 243.408454 -104.946958)
		)
		(stroke
			(width 0)
			(type solid)
		)
		(fill yes)
		(layer "F.Cu")
		(net "M_E_DQ<26>")
	)
	(gr_poly
		(pts
			(xy 243.513864 -47.8155) (xy 243.549678 -47.779432) (xy 243.424202 -47.653956) (xy 243.388134 -47.68977)
			(xy 243.341398 -47.786798) (xy 243.416836 -47.862236)
		)
		(stroke
			(width 0)
			(type solid)
		)
		(fill yes)
		(layer "F.Cu")
		(net "M_B_DQ<31>")
	)
	(gr_poly
		(pts
			(xy 243.517674 -103.328216) (xy 243.481606 -103.292402) (xy 243.384578 -103.245666) (xy 243.30914 -103.321104)
			(xy 243.355876 -103.418132) (xy 243.391944 -103.453946)
		)
		(stroke
			(width 0)
			(type solid)
		)
		(fill yes)
		(layer "F.Cu")
		(net "M_E_DQS_DP<3>")
	)
	(gr_poly
		(pts
			(xy 243.522754 -48.111918) (xy 243.56949 -48.01489) (xy 243.494052 -47.939452) (xy 243.397024 -47.986188)
			(xy 243.36121 -48.022256) (xy 243.48694 -48.147986)
		)
		(stroke
			(width 0)
			(type solid)
		)
		(fill yes)
		(layer "F.Cu")
		(net "M_B_DQ<30>")
	)
	(gr_poly
		(pts
			(xy 243.527072 -108.372402) (xy 243.527072 -108.321602) (xy 243.400072 -108.321602) (xy 243.400072 -108.372402)
			(xy 243.412772 -108.562902) (xy 243.514372 -108.562902)
		)
		(stroke
			(width 0)
			(type solid)
		)
		(fill yes)
		(layer "F.Cu")
		(net "M_E_DQS_DN<17>")
	)
	(gr_poly
		(pts
			(xy 243.527072 -107.978702) (xy 243.527072 -107.927902) (xy 243.400072 -107.927902) (xy 243.400072 -107.978702)
			(xy 243.412772 -108.169202) (xy 243.514372 -108.169202)
		)
		(stroke
			(width 0)
			(type solid)
		)
		(fill yes)
		(layer "F.Cu")
		(net "M_E_DQS_DP<17>")
	)
	(gr_poly
		(pts
			(xy 243.527072 -107.585256) (xy 243.527072 -107.534456) (xy 243.400072 -107.534456) (xy 243.400072 -107.585256)
			(xy 243.412772 -107.775756) (xy 243.514372 -107.775756)
		)
		(stroke
			(width 0)
			(type solid)
		)
		(fill yes)
		(layer "F.Cu")
		(net "M_E_ECC<1>")
	)
	(gr_poly
		(pts
			(xy 243.527072 -107.19181) (xy 243.527072 -107.14101) (xy 243.400072 -107.14101) (xy 243.400072 -107.19181)
			(xy 243.412772 -107.38231) (xy 243.514372 -107.38231)
		)
		(stroke
			(width 0)
			(type solid)
		)
		(fill yes)
		(layer "F.Cu")
		(net "M_E_ECC<0>")
	)
	(gr_poly
		(pts
			(xy 243.537232 -103.093012) (xy 243.490496 -102.995984) (xy 243.454682 -102.959916) (xy 243.328952 -103.085646)
			(xy 243.364766 -103.121714) (xy 243.461794 -103.16845)
		)
		(stroke
			(width 0)
			(type solid)
		)
		(fill yes)
		(layer "F.Cu")
		(net "M_E_DQS_DN<3>")
	)
	(gr_poly
		(pts
			(xy 243.553742 -104.586024) (xy 243.517928 -104.549956) (xy 243.4209 -104.50322) (xy 243.345462 -104.578658)
			(xy 243.392198 -104.675686) (xy 243.428012 -104.711754)
		)
		(stroke
			(width 0)
			(type solid)
		)
		(fill yes)
		(layer "F.Cu")
		(net "M_E_DQ<26>")
	)
	(gr_poly
		(pts
			(xy 243.554504 -42.551096) (xy 243.590572 -42.515282) (xy 243.500656 -42.425366) (xy 243.464842 -42.461434)
			(xy 243.339112 -42.604944) (xy 243.410994 -42.676826)
		)
		(stroke
			(width 0)
			(type solid)
		)
		(fill yes)
		(layer "F.Cu")
		(net "M_B_ECC<6>")
	)
	(gr_poly
		(pts
			(xy 243.570252 -45.209714) (xy 243.534692 -45.108114) (xy 243.428012 -45.108114) (xy 243.392452 -45.209714)
			(xy 243.392452 -45.260514) (xy 243.570252 -45.260514)
		)
		(stroke
			(width 0)
			(type solid)
		)
		(fill yes)
		(layer "F.Cu")
		(net "M_B_ECC<5>")
	)
	(gr_poly
		(pts
			(xy 243.570252 -44.904914) (xy 243.534692 -44.803314) (xy 243.428012 -44.803314) (xy 243.392452 -44.904914)
			(xy 243.392452 -44.955714) (xy 243.570252 -44.955714)
		)
		(stroke
			(width 0)
			(type solid)
		)
		(fill yes)
		(layer "F.Cu")
		(net "M_B_ECC<0>")
	)
	(gr_poly
		(pts
			(xy 243.570252 -44.600114) (xy 243.534692 -44.498514) (xy 243.428012 -44.498514) (xy 243.392452 -44.600114)
			(xy 243.392452 -44.650914) (xy 243.570252 -44.650914)
		)
		(stroke
			(width 0)
			(type solid)
		)
		(fill yes)
		(layer "F.Cu")
		(net "M_B_ECC<1>")
	)
	(gr_poly
		(pts
			(xy 243.570252 -44.295314) (xy 243.534692 -44.193714) (xy 243.428012 -44.193714) (xy 243.392452 -44.295314)
			(xy 243.392452 -44.346114) (xy 243.570252 -44.346114)
		)
		(stroke
			(width 0)
			(type solid)
		)
		(fill yes)
		(layer "F.Cu")
		(net "M_B_DQS_DP<17>")
	)
	(gr_poly
		(pts
			(xy 243.573554 -104.350566) (xy 243.526818 -104.253538) (xy 243.49075 -104.217724) (xy 243.36502 -104.343454)
			(xy 243.401088 -104.379268) (xy 243.498116 -104.426004)
		)
		(stroke
			(width 0)
			(type solid)
		)
		(fill yes)
		(layer "F.Cu")
		(net "M_E_DQ<31>")
	)
	(gr_poly
		(pts
			(xy 243.581174 -42.991532) (xy 243.706904 -42.847768) (xy 243.635276 -42.775886) (xy 243.491512 -42.901616)
			(xy 243.455444 -42.93743) (xy 243.54536 -43.027346)
		)
		(stroke
			(width 0)
			(type solid)
		)
		(fill yes)
		(layer "F.Cu")
		(net "M_B_DQS_DP<8>")
	)
	(gr_poly
		(pts
			(xy 243.603526 -48.336454) (xy 243.639594 -48.30064) (xy 243.513864 -48.17491) (xy 243.477796 -48.210724)
			(xy 243.43106 -48.307752) (xy 243.506498 -48.38319)
		)
		(stroke
			(width 0)
			(type solid)
		)
		(fill yes)
		(layer "F.Cu")
		(net "M_B_DQ<30>")
	)
	(gr_poly
		(pts
			(xy 243.607336 -102.807262) (xy 243.571268 -102.771448) (xy 243.47424 -102.724712) (xy 243.398802 -102.80015)
			(xy 243.445538 -102.897178) (xy 243.481606 -102.932992)
		)
		(stroke
			(width 0)
			(type solid)
		)
		(fill yes)
		(layer "F.Cu")
		(net "M_E_DQS_DN<3>")
	)
	(gr_poly
		(pts
			(xy 243.612416 -48.632872) (xy 243.659152 -48.535844) (xy 243.583714 -48.460406) (xy 243.486686 -48.507142)
			(xy 243.450872 -48.54321) (xy 243.576602 -48.66894)
		)
		(stroke
			(width 0)
			(type solid)
		)
		(fill yes)
		(layer "F.Cu")
		(net "M_B_DQS_DP<3>")
	)
	(gr_poly
		(pts
			(xy 243.639848 -47.0789) (xy 243.684552 -47.033942) (xy 243.558822 -46.908212) (xy 243.514118 -46.95317)
			(xy 243.467382 -47.050198) (xy 243.54282 -47.125636)
		)
		(stroke
			(width 0)
			(type solid)
		)
		(fill yes)
		(layer "F.Cu")
		(net "M_B_DQ<27>")
	)
	(gr_poly
		(pts
			(xy 243.643404 -104.06507) (xy 243.60759 -104.029002) (xy 243.510562 -103.982266) (xy 243.435124 -104.057704)
			(xy 243.48186 -104.154732) (xy 243.517674 -104.1908)
		)
		(stroke
			(width 0)
			(type solid)
		)
		(fill yes)
		(layer "F.Cu")
		(net "M_E_DQ<31>")
	)
	(gr_poly
		(pts
			(xy 243.644166 -41.526968) (xy 243.67998 -41.4909) (xy 243.590318 -41.401238) (xy 243.55425 -41.437052)
			(xy 243.42852 -41.580816) (xy 243.500402 -41.652698)
		)
		(stroke
			(width 0)
			(type solid)
		)
		(fill yes)
		(layer "F.Cu")
		(net "M_B_ECC<2>")
	)
	(gr_poly
		(pts
			(xy 243.648738 -47.375318) (xy 243.695474 -47.27829) (xy 243.620036 -47.202852) (xy 243.523008 -47.249588)
			(xy 243.48694 -47.285402) (xy 243.61267 -47.411132)
		)
		(stroke
			(width 0)
			(type solid)
		)
		(fill yes)
		(layer "F.Cu")
		(net "M_B_DQ<26>")
	)
	(gr_poly
		(pts
			(xy 243.663216 -103.829612) (xy 243.61648 -103.732584) (xy 243.580412 -103.69677) (xy 243.454936 -103.822246)
			(xy 243.49075 -103.858314) (xy 243.587778 -103.90505)
		)
		(stroke
			(width 0)
			(type solid)
		)
		(fill yes)
		(layer "F.Cu")
		(net "M_E_DQ<30>")
	)
	(gr_poly
		(pts
			(xy 243.671344 -41.967404) (xy 243.797074 -41.82364) (xy 243.725192 -41.752012) (xy 243.581428 -41.877742)
			(xy 243.545614 -41.913556) (xy 243.63553 -42.003472)
		)
		(stroke
			(width 0)
			(type solid)
		)
		(fill yes)
		(layer "F.Cu")
		(net "M_B_ECC<7>")
	)
	(gr_poly
		(pts
			(xy 243.689378 -106.82478) (xy 243.563648 -106.68127) (xy 243.527834 -106.645202) (xy 243.437918 -106.735118)
			(xy 243.473986 -106.770932) (xy 243.617496 -106.896662)
		)
		(stroke
			(width 0)
			(type solid)
		)
		(fill yes)
		(layer "F.Cu")
		(net "M_E_ECC<5>")
	)
	(gr_poly
		(pts
			(xy 243.693188 -48.857408) (xy 243.729256 -48.821594) (xy 243.603526 -48.695864) (xy 243.567458 -48.731678)
			(xy 243.520722 -48.828706) (xy 243.59616 -48.904144)
		)
		(stroke
			(width 0)
			(type solid)
		)
		(fill yes)
		(layer "F.Cu")
		(net "M_B_DQS_DP<3>")
	)
	(gr_poly
		(pts
			(xy 243.69649 -45.660818) (xy 243.743226 -45.56379) (xy 243.667788 -45.488352) (xy 243.57076 -45.535088)
			(xy 243.526056 -45.580046) (xy 243.651786 -45.705776)
		)
		(stroke
			(width 0)
			(type solid)
		)
		(fill yes)
		(layer "F.Cu")
		(net "M_B_ECC<4>")
	)
	(gr_poly
		(pts
			(xy 243.72951 -47.599854) (xy 243.765324 -47.563786) (xy 243.639848 -47.43831) (xy 243.60378 -47.474124)
			(xy 243.557044 -47.571152) (xy 243.632482 -47.64659)
		)
		(stroke
			(width 0)
			(type solid)
		)
		(fill yes)
		(layer "F.Cu")
		(net "M_B_DQ<26>")
	)
	(gr_poly
		(pts
			(xy 243.73332 -103.543862) (xy 243.697252 -103.508048) (xy 243.600224 -103.461312) (xy 243.524786 -103.53675)
			(xy 243.571522 -103.633778) (xy 243.60759 -103.669592)
		)
		(stroke
			(width 0)
			(type solid)
		)
		(fill yes)
		(layer "F.Cu")
		(net "M_E_DQ<30>")
	)
	(gr_poly
		(pts
			(xy 243.7384 -47.896272) (xy 243.785136 -47.799244) (xy 243.709698 -47.723806) (xy 243.61267 -47.770542)
			(xy 243.576856 -47.80661) (xy 243.702586 -47.93234)
		)
		(stroke
			(width 0)
			(type solid)
		)
		(fill yes)
		(layer "F.Cu")
		(net "M_B_DQ<31>")
	)
	(gr_poly
		(pts
			(xy 243.743226 -43.297094) (xy 243.779294 -43.26128) (xy 243.689378 -43.171364) (xy 243.653564 -43.207432)
			(xy 243.527834 -43.350942) (xy 243.599716 -43.422824)
		)
		(stroke
			(width 0)
			(type solid)
		)
		(fill yes)
		(layer "F.Cu")
		(net "M_B_DQS_DP<8>")
	)
	(gr_poly
		(pts
			(xy 243.752878 -103.308658) (xy 243.706142 -103.21163) (xy 243.670328 -103.175562) (xy 243.544598 -103.301292)
			(xy 243.580412 -103.33736) (xy 243.67744 -103.384096)
		)
		(stroke
			(width 0)
			(type solid)
		)
		(fill yes)
		(layer "F.Cu")
		(net "M_E_DQS_DP<3>")
	)
	(gr_poly
		(pts
			(xy 243.761768 -106.411268) (xy 243.7257 -106.375454) (xy 243.581936 -106.249724) (xy 243.510308 -106.321606)
			(xy 243.636038 -106.46537) (xy 243.671852 -106.501184)
		)
		(stroke
			(width 0)
			(type solid)
		)
		(fill yes)
		(layer "F.Cu")
		(net "M_E_ECC<5>")
	)
	(gr_poly
		(pts
			(xy 243.778278 -104.81056) (xy 243.733574 -104.765602) (xy 243.636546 -104.718866) (xy 243.561108 -104.794304)
			(xy 243.607844 -104.891332) (xy 243.652548 -104.93629)
		)
		(stroke
			(width 0)
			(type solid)
		)
		(fill yes)
		(layer "F.Cu")
		(net "M_E_DQ<27>")
	)
	(gr_poly
		(pts
			(xy 243.786152 -44.701714) (xy 243.786152 -44.650914) (xy 243.608352 -44.650914) (xy 243.608352 -44.701714)
			(xy 243.643912 -44.803314) (xy 243.750592 -44.803314)
		)
		(stroke
			(width 0)
			(type solid)
		)
		(fill yes)
		(layer "F.Cu")
		(net "M_B_ECC<1>")
	)
	(gr_poly
		(pts
			(xy 243.786152 -44.396914) (xy 243.786152 -44.346114) (xy 243.608352 -44.346114) (xy 243.608352 -44.396914)
			(xy 243.643912 -44.498514) (xy 243.750592 -44.498514)
		)
		(stroke
			(width 0)
			(type solid)
		)
		(fill yes)
		(layer "F.Cu")
		(net "M_B_DQS_DP<17>")
	)
	(gr_poly
		(pts
			(xy 243.786152 -44.092114) (xy 243.786152 -44.041314) (xy 243.608352 -44.041314) (xy 243.608352 -44.092114)
			(xy 243.643912 -44.193714) (xy 243.750592 -44.193714)
		)
		(stroke
			(width 0)
			(type solid)
		)
		(fill yes)
		(layer "F.Cu")
		(net "M_B_DQS_DN<17>")
	)
	(gr_poly
		(pts
			(xy 243.7892 -104.566212) (xy 243.742464 -104.469184) (xy 243.706396 -104.43337) (xy 243.580666 -104.5591)
			(xy 243.616734 -104.594914) (xy 243.713762 -104.64165)
		)
		(stroke
			(width 0)
			(type solid)
		)
		(fill yes)
		(layer "F.Cu")
		(net "M_E_DQ<26>")
	)
	(gr_poly
		(pts
			(xy 243.819172 -48.120808) (xy 243.85524 -48.084994) (xy 243.72951 -47.959264) (xy 243.693442 -47.995078)
			(xy 243.646706 -48.092106) (xy 243.722144 -48.167544)
		)
		(stroke
			(width 0)
			(type solid)
		)
		(fill yes)
		(layer "F.Cu")
		(net "M_B_DQ<31>")
	)
	(gr_poly
		(pts
			(xy 243.822982 -103.022908) (xy 243.786914 -102.987094) (xy 243.689886 -102.940358) (xy 243.614448 -103.015796)
			(xy 243.661184 -103.112824) (xy 243.697252 -103.148638)
		)
		(stroke
			(width 0)
			(type solid)
		)
		(fill yes)
		(layer "F.Cu")
		(net "M_E_DQS_DP<3>")
	)
	(gr_poly
		(pts
			(xy 243.828062 -48.417226) (xy 243.874798 -48.320198) (xy 243.79936 -48.24476) (xy 243.702332 -48.291496)
			(xy 243.666518 -48.327564) (xy 243.792248 -48.453294)
		)
		(stroke
			(width 0)
			(type solid)
		)
		(fill yes)
		(layer "F.Cu")
		(net "M_B_DQ<30>")
	)
	(gr_poly
		(pts
			(xy 243.832888 -42.272712) (xy 243.868956 -42.236898) (xy 243.77904 -42.146982) (xy 243.743226 -42.18305)
			(xy 243.617496 -42.32656) (xy 243.689378 -42.398442)
		)
		(stroke
			(width 0)
			(type solid)
		)
		(fill yes)
		(layer "F.Cu")
		(net "M_B_ECC<7>")
	)
	(gr_poly
		(pts
			(xy 243.84254 -102.787704) (xy 243.795804 -102.690676) (xy 243.75999 -102.654608) (xy 243.63426 -102.780338)
			(xy 243.670074 -102.816406) (xy 243.767102 -102.863142)
		)
		(stroke
			(width 0)
			(type solid)
		)
		(fill yes)
		(layer "F.Cu")
		(net "M_E_DQS_DN<3>")
	)
	(gr_poly
		(pts
			(xy 243.857272 -108.271056) (xy 243.844572 -108.080556) (xy 243.742972 -108.080556) (xy 243.730272 -108.271056)
			(xy 243.730272 -108.321856) (xy 243.857272 -108.321856)
		)
		(stroke
			(width 0)
			(type solid)
		)
		(fill yes)
		(layer "F.Cu")
		(net "M_E_DQS_DN<17>")
	)
	(gr_poly
		(pts
			(xy 243.85905 -104.280716) (xy 243.823236 -104.244648) (xy 243.726208 -104.197912) (xy 243.65077 -104.27335)
			(xy 243.697506 -104.370378) (xy 243.73332 -104.406446)
		)
		(stroke
			(width 0)
			(type solid)
		)
		(fill yes)
		(layer "F.Cu")
		(net "M_E_DQ<26>")
	)
	(gr_poly
		(pts
			(xy 243.859812 -42.712894) (xy 243.985542 -42.56913) (xy 243.913914 -42.497248) (xy 243.77015 -42.622978)
			(xy 243.734082 -42.658792) (xy 243.823998 -42.748708)
		)
		(stroke
			(width 0)
			(type solid)
		)
		(fill yes)
		(layer "F.Cu")
		(net "M_B_ECC<6>")
	)
	(gr_poly
		(pts
			(xy 243.878354 -106.079036) (xy 243.752624 -105.935272) (xy 243.707666 -105.890568) (xy 243.618004 -105.98023)
			(xy 243.662962 -106.025188) (xy 243.806472 -106.150918)
		)
		(stroke
			(width 0)
			(type solid)
		)
		(fill yes)
		(layer "F.Cu")
		(net "M_E_ECC<4>")
	)
	(gr_poly
		(pts
			(xy 243.878862 -104.045258) (xy 243.832126 -103.94823) (xy 243.796058 -103.912416) (xy 243.670582 -104.037892)
			(xy 243.706396 -104.07396) (xy 243.803424 -104.120696)
		)
		(stroke
			(width 0)
			(type solid)
		)
		(fill yes)
		(layer "F.Cu")
		(net "M_E_DQ<31>")
	)
	(gr_poly
		(pts
			(xy 243.908834 -48.641762) (xy 243.944902 -48.605948) (xy 243.819172 -48.480218) (xy 243.783104 -48.516032)
			(xy 243.736368 -48.61306) (xy 243.811806 -48.688498)
		)
		(stroke
			(width 0)
			(type solid)
		)
		(fill yes)
		(layer "F.Cu")
		(net "M_B_DQ<30>")
	)
	(gr_poly
		(pts
			(xy 243.912136 -45.445172) (xy 243.958872 -45.348144) (xy 243.883434 -45.272706) (xy 243.786406 -45.319442)
			(xy 243.750592 -45.35551) (xy 243.876322 -45.48124)
		)
		(stroke
			(width 0)
			(type solid)
		)
		(fill yes)
		(layer "F.Cu")
		(net "M_B_ECC<5>")
	)
	(gr_poly
		(pts
			(xy 243.922804 -41.24833) (xy 243.967508 -41.203372) (xy 243.877846 -41.11371) (xy 243.832888 -41.158668)
			(xy 243.707158 -41.302178) (xy 243.77904 -41.37406)
		)
		(stroke
			(width 0)
			(type solid)
		)
		(fill yes)
		(layer "F.Cu")
		(net "M_B_ECC<3>")
	)
	(gr_poly
		(pts
			(xy 243.945156 -47.384208) (xy 243.98986 -47.33925) (xy 243.864384 -47.213774) (xy 243.819426 -47.258478)
			(xy 243.77269 -47.355506) (xy 243.848128 -47.430944)
		)
		(stroke
			(width 0)
			(type solid)
		)
		(fill yes)
		(layer "F.Cu")
		(net "M_B_DQ<27>")
	)
	(gr_poly
		(pts
			(xy 243.948966 -103.759508) (xy 243.912898 -103.723694) (xy 243.81587 -103.676958) (xy 243.740432 -103.752396)
			(xy 243.787168 -103.849424) (xy 243.823236 -103.885238)
		)
		(stroke
			(width 0)
			(type solid)
		)
		(fill yes)
		(layer "F.Cu")
		(net "M_E_DQ<31>")
	)
	(gr_poly
		(pts
			(xy 243.949728 -41.68902) (xy 244.075458 -41.545256) (xy 244.00383 -41.473374) (xy 243.860066 -41.599104)
			(xy 243.823998 -41.634918) (xy 243.913914 -41.724834)
		)
		(stroke
			(width 0)
			(type solid)
		)
		(fill yes)
		(layer "F.Cu")
		(net "M_B_ECC<2>")
	)
	(gr_poly
		(pts
			(xy 243.954046 -47.680626) (xy 244.000782 -47.583598) (xy 243.925344 -47.50816) (xy 243.828316 -47.554896)
			(xy 243.792502 -47.590964) (xy 243.918232 -47.716694)
		)
		(stroke
			(width 0)
			(type solid)
		)
		(fill yes)
		(layer "F.Cu")
		(net "M_B_DQ<26>")
	)
	(gr_poly
		(pts
			(xy 243.96827 -107.10291) (xy 243.84254 -106.9594) (xy 243.806726 -106.923332) (xy 243.71681 -107.013248)
			(xy 243.752878 -107.049062) (xy 243.896388 -107.174792)
		)
		(stroke
			(width 0)
			(type solid)
		)
		(fill yes)
		(layer "F.Cu")
		(net "M_E_ECC<0>")
	)
	(gr_poly
		(pts
			(xy 243.968524 -103.524304) (xy 243.921788 -103.427276) (xy 243.885974 -103.391208) (xy 243.760244 -103.516938)
			(xy 243.796058 -103.553006) (xy 243.893086 -103.599742)
		)
		(stroke
			(width 0)
			(type solid)
		)
		(fill yes)
		(layer "F.Cu")
		(net "M_E_DQ<30>")
	)
	(gr_poly
		(pts
			(xy 243.992908 -45.669708) (xy 244.028976 -45.633894) (xy 243.903246 -45.508164) (xy 243.867178 -45.543978)
			(xy 243.820442 -45.641006) (xy 243.89588 -45.716444)
		)
		(stroke
			(width 0)
			(type solid)
		)
		(fill yes)
		(layer "F.Cu")
		(net "M_B_ECC<5>")
	)
	(gr_poly
		(pts
			(xy 244.001798 -45.966126) (xy 244.048534 -45.869098) (xy 243.973096 -45.79366) (xy 243.876068 -45.840396)
			(xy 243.831364 -45.885354) (xy 243.957094 -46.011084)
		)
		(stroke
			(width 0)
			(type solid)
		)
		(fill yes)
		(layer "F.Cu")
		(net "M_B_ECC<4>")
	)
	(gr_poly
		(pts
			(xy 244.002052 -44.295314) (xy 243.966492 -44.193714) (xy 243.859812 -44.193714) (xy 243.824252 -44.295314)
			(xy 243.824252 -44.346114) (xy 244.002052 -44.346114)
		)
		(stroke
			(width 0)
			(type solid)
		)
		(fill yes)
		(layer "F.Cu")
		(net "M_B_DQS_DP<17>")
	)
	(gr_poly
		(pts
			(xy 244.002052 -43.990514) (xy 243.966492 -43.888914) (xy 243.859812 -43.888914) (xy 243.824252 -43.990514)
			(xy 243.824252 -44.041314) (xy 244.002052 -44.041314)
		)
		(stroke
			(width 0)
			(type solid)
		)
		(fill yes)
		(layer "F.Cu")
		(net "M_B_DQS_DN<17>")
	)
	(gr_poly
		(pts
			(xy 244.002052 -43.685714) (xy 243.966492 -43.584114) (xy 243.859812 -43.584114) (xy 243.824252 -43.685714)
			(xy 243.824252 -43.736514) (xy 244.002052 -43.736514)
		)
		(stroke
			(width 0)
			(type solid)
		)
		(fill yes)
		(layer "F.Cu")
		(net "M_B_DQS_DN<8>")
	)
	(gr_poly
		(pts
			(xy 244.021864 -43.018456) (xy 244.057932 -42.982642) (xy 243.968016 -42.892726) (xy 243.932202 -42.928794)
			(xy 243.806472 -43.072304) (xy 243.878354 -43.144186)
		)
		(stroke
			(width 0)
			(type solid)
		)
		(fill yes)
		(layer "F.Cu")
		(net "M_B_ECC<6>")
	)
	(gr_poly
		(pts
			(xy 244.034818 -47.905162) (xy 244.070886 -47.869348) (xy 243.945156 -47.743618) (xy 243.909088 -47.779432)
			(xy 243.862352 -47.87646) (xy 243.93779 -47.951898)
		)
		(stroke
			(width 0)
			(type solid)
		)
		(fill yes)
		(layer "F.Cu")
		(net "M_B_DQ<26>")
	)
	(gr_poly
		(pts
			(xy 244.03812 -44.708572) (xy 244.084856 -44.611544) (xy 244.009418 -44.536106) (xy 243.91239 -44.582842)
			(xy 243.876576 -44.61891) (xy 244.002306 -44.74464)
		)
		(stroke
			(width 0)
			(type solid)
		)
		(fill yes)
		(layer "F.Cu")
		(net "M_B_ECC<1>")
	)
	(gr_poly
		(pts
			(xy 244.038628 -103.238554) (xy 244.00256 -103.20274) (xy 243.905532 -103.156004) (xy 243.830094 -103.231442)
			(xy 243.87683 -103.32847) (xy 243.912898 -103.364284)
		)
		(stroke
			(width 0)
			(type solid)
		)
		(fill yes)
		(layer "F.Cu")
		(net "M_E_DQ<30>")
	)
	(gr_poly
		(pts
			(xy 244.040152 -106.689906) (xy 244.004338 -106.653838) (xy 243.860574 -106.528108) (xy 243.788692 -106.59999)
			(xy 243.914422 -106.743754) (xy 243.95049 -106.779568)
		)
		(stroke
			(width 0)
			(type solid)
		)
		(fill yes)
		(layer "F.Cu")
		(net "M_E_ECC<0>")
	)
	(gr_poly
		(pts
			(xy 244.043708 -48.20158) (xy 244.090444 -48.104552) (xy 244.015006 -48.029114) (xy 243.917978 -48.07585)
			(xy 243.882164 -48.111918) (xy 244.007894 -48.237648)
		)
		(stroke
			(width 0)
			(type solid)
		)
		(fill yes)
		(layer "F.Cu")
		(net "M_B_DQ<31>")
	)
	(gr_poly
		(pts
			(xy 244.058186 -103.00335) (xy 244.01145 -102.906322) (xy 243.975636 -102.870254) (xy 243.849906 -102.995984)
			(xy 243.88572 -103.032052) (xy 243.982748 -103.078788)
		)
		(stroke
			(width 0)
			(type solid)
		)
		(fill yes)
		(layer "F.Cu")
		(net "M_E_DQS_DP<3>")
	)
	(gr_poly
		(pts
			(xy 244.083586 -104.505252) (xy 244.038882 -104.460294) (xy 243.941854 -104.413558) (xy 243.866416 -104.488996)
			(xy 243.913152 -104.586024) (xy 243.957856 -104.630982)
		)
		(stroke
			(width 0)
			(type solid)
		)
		(fill yes)
		(layer "F.Cu")
		(net "M_E_DQ<27>")
	)
	(gr_poly
		(pts
			(xy 244.094508 -104.260904) (xy 244.047772 -104.163876) (xy 244.011704 -104.128062) (xy 243.886228 -104.253538)
			(xy 243.922042 -104.289606) (xy 244.01907 -104.336342)
		)
		(stroke
			(width 0)
			(type solid)
		)
		(fill yes)
		(layer "F.Cu")
		(net "M_E_DQ<26>")
	)
	(gr_poly
		(pts
			(xy 244.111526 -41.994328) (xy 244.14734 -41.95826) (xy 244.057678 -41.868598) (xy 244.02161 -41.904412)
			(xy 243.89588 -42.048176) (xy 243.967762 -42.120058)
		)
		(stroke
			(width 0)
			(type solid)
		)
		(fill yes)
		(layer "F.Cu")
		(net "M_B_ECC<2>")
	)
	(gr_poly
		(pts
			(xy 244.118892 -44.933108) (xy 244.15496 -44.897294) (xy 244.02923 -44.771564) (xy 243.993162 -44.807378)
			(xy 243.946426 -44.904406) (xy 244.021864 -44.979844)
		)
		(stroke
			(width 0)
			(type solid)
		)
		(fill yes)
		(layer "F.Cu")
		(net "M_B_ECC<1>")
	)
	(gr_poly
		(pts
			(xy 244.12448 -48.426116) (xy 244.160548 -48.390302) (xy 244.034818 -48.264572) (xy 243.99875 -48.300386)
			(xy 243.952014 -48.397414) (xy 244.027452 -48.472852)
		)
		(stroke
			(width 0)
			(type solid)
		)
		(fill yes)
		(layer "F.Cu")
		(net "M_B_DQ<31>")
	)
	(gr_poly
		(pts
			(xy 244.127782 -45.229526) (xy 244.174518 -45.132498) (xy 244.09908 -45.05706) (xy 244.002052 -45.103796)
			(xy 243.966238 -45.139864) (xy 244.091968 -45.265594)
		)
		(stroke
			(width 0)
			(type solid)
		)
		(fill yes)
		(layer "F.Cu")
		(net "M_B_ECC<0>")
	)
	(gr_poly
		(pts
			(xy 244.130068 -107.713526) (xy 244.094 -107.677712) (xy 243.95049 -107.551982) (xy 243.878608 -107.623864)
			(xy 244.004338 -107.767628) (xy 244.040152 -107.803442)
		)
		(stroke
			(width 0)
			(type solid)
		)
		(fill yes)
		(layer "F.Cu")
		(net "M_E_DQS_DP<17>")
	)
	(gr_poly
		(pts
			(xy 244.13337 -48.722534) (xy 244.180106 -48.625506) (xy 244.104668 -48.550068) (xy 244.00764 -48.596804)
			(xy 243.971826 -48.632872) (xy 244.097556 -48.758602)
		)
		(stroke
			(width 0)
			(type solid)
		)
		(fill yes)
		(layer "F.Cu")
		(net "M_B_DQ<30>")
	)
	(gr_poly
		(pts
			(xy 244.138196 -42.43451) (xy 244.263926 -42.290746) (xy 244.192298 -42.218864) (xy 244.048534 -42.344594)
			(xy 244.012466 -42.380408) (xy 244.102382 -42.470324)
		)
		(stroke
			(width 0)
			(type solid)
		)
		(fill yes)
		(layer "F.Cu")
		(net "M_B_ECC<7>")
	)
	(gr_poly
		(pts
			(xy 244.156738 -106.35742) (xy 244.031008 -106.21391) (xy 243.995194 -106.177842) (xy 243.905278 -106.267758)
			(xy 243.941346 -106.303572) (xy 244.084856 -106.429302)
		)
		(stroke
			(width 0)
			(type solid)
		)
		(fill yes)
		(layer "F.Cu")
		(net "M_E_ECC<5>")
	)
	(gr_poly
		(pts
			(xy 244.164612 -103.975154) (xy 244.128544 -103.93934) (xy 244.031516 -103.892604) (xy 243.956078 -103.968042)
			(xy 244.002814 -104.06507) (xy 244.038882 -104.100884)
		)
		(stroke
			(width 0)
			(type solid)
		)
		(fill yes)
		(layer "F.Cu")
		(net "M_E_DQ<26>")
	)
	(gr_poly
		(pts
			(xy 244.18417 -103.73995) (xy 244.137434 -103.642922) (xy 244.10162 -103.606854) (xy 243.97589 -103.732584)
			(xy 244.011704 -103.768652) (xy 244.108732 -103.815388)
		)
		(stroke
			(width 0)
			(type solid)
		)
		(fill yes)
		(layer "F.Cu")
		(net "M_E_DQ<31>")
	)
	(gr_poly
		(pts
			(xy 244.208554 -45.454062) (xy 244.244622 -45.418248) (xy 244.118892 -45.292518) (xy 244.082824 -45.328332)
			(xy 244.036088 -45.42536) (xy 244.111526 -45.500798)
		)
		(stroke
			(width 0)
			(type solid)
		)
		(fill yes)
		(layer "F.Cu")
		(net "M_B_ECC<0>")
	)
	(gr_poly
		(pts
			(xy 244.214142 -48.94707) (xy 244.25021 -48.911256) (xy 244.12448 -48.785526) (xy 244.088412 -48.82134)
			(xy 244.041676 -48.918368) (xy 244.117114 -48.993806)
		)
		(stroke
			(width 0)
			(type solid)
		)
		(fill yes)
		(layer "F.Cu")
		(net "M_B_DQ<30>")
	)
	(gr_poly
		(pts
			(xy 244.217444 -45.75048) (xy 244.26418 -45.653452) (xy 244.188742 -45.578014) (xy 244.091714 -45.62475)
			(xy 244.0559 -45.660818) (xy 244.18163 -45.786548)
		)
		(stroke
			(width 0)
			(type solid)
		)
		(fill yes)
		(layer "F.Cu")
		(net "M_B_ECC<5>")
	)
	(gr_poly
		(pts
			(xy 244.217952 -43.787314) (xy 244.217952 -43.736514) (xy 244.040152 -43.736514) (xy 244.040152 -43.787314)
			(xy 244.075712 -43.888914) (xy 244.182392 -43.888914)
		)
		(stroke
			(width 0)
			(type solid)
		)
		(fill yes)
		(layer "F.Cu")
		(net "M_B_DQS_DN<8>")
	)
	(gr_poly
		(pts
			(xy 244.217952 -43.482514) (xy 244.217952 -43.431714) (xy 244.040152 -43.431714) (xy 244.040152 -43.482514)
			(xy 244.075712 -43.584114) (xy 244.182392 -43.584114)
		)
		(stroke
			(width 0)
			(type solid)
		)
		(fill yes)
		(layer "F.Cu")
		(net "M_B_DQS_DP<8>")
	)
	(gr_poly
		(pts
			(xy 244.22862 -105.944416) (xy 244.192806 -105.908348) (xy 244.049042 -105.782872) (xy 243.97716 -105.8545)
			(xy 244.10289 -105.998264) (xy 244.138958 -106.034078)
		)
		(stroke
			(width 0)
			(type solid)
		)
		(fill yes)
		(layer "F.Cu")
		(net "M_E_ECC<5>")
	)
	(gr_poly
		(pts
			(xy 244.246654 -107.381294) (xy 244.120924 -107.237784) (xy 244.08511 -107.201716) (xy 243.995194 -107.291632)
			(xy 244.031262 -107.327446) (xy 244.174772 -107.453176)
		)
		(stroke
			(width 0)
			(type solid)
		)
		(fill yes)
		(layer "F.Cu")
		(net "M_E_ECC<1>")
	)
	(gr_poly
		(pts
			(xy 244.250464 -47.689516) (xy 244.295422 -47.644812) (xy 244.169692 -47.519082) (xy 244.124734 -47.563786)
			(xy 244.077998 -47.660814) (xy 244.153436 -47.736252)
		)
		(stroke
			(width 0)
			(type solid)
		)
		(fill yes)
		(layer "F.Cu")
		(net "M_B_DQ<27>")
	)
	(gr_poly
		(pts
			(xy 244.254274 -103.4542) (xy 244.218206 -103.418386) (xy 244.121178 -103.37165) (xy 244.04574 -103.447088)
			(xy 244.092476 -103.544116) (xy 244.128544 -103.57993)
		)
		(stroke
			(width 0)
			(type solid)
		)
		(fill yes)
		(layer "F.Cu")
		(net "M_E_DQ<31>")
	)
	(gr_poly
		(pts
			(xy 244.259354 -47.985934) (xy 244.30609 -47.888906) (xy 244.230652 -47.813468) (xy 244.133624 -47.860204)
			(xy 244.09781 -47.896272) (xy 244.22354 -48.022002)
		)
		(stroke
			(width 0)
			(type solid)
		)
		(fill yes)
		(layer "F.Cu")
		(net "M_B_DQ<26>")
	)
	(gr_poly
		(pts
			(xy 244.273832 -103.218996) (xy 244.227096 -103.121968) (xy 244.191282 -103.0859) (xy 244.065552 -103.21163)
			(xy 244.101366 -103.247698) (xy 244.198394 -103.294434)
		)
		(stroke
			(width 0)
			(type solid)
		)
		(fill yes)
		(layer "F.Cu")
		(net "M_E_DQ<30>")
	)
	(gr_poly
		(pts
			(xy 244.298216 -45.975016) (xy 244.334284 -45.939202) (xy 244.208554 -45.813472) (xy 244.172486 -45.849286)
			(xy 244.12575 -45.946314) (xy 244.201188 -46.021752)
		)
		(stroke
			(width 0)
			(type solid)
		)
		(fill yes)
		(layer "F.Cu")
		(net "M_B_ECC<5>")
	)
	(gr_poly
		(pts
			(xy 244.300248 -42.740072) (xy 244.336316 -42.704258) (xy 244.2464 -42.614342) (xy 244.210586 -42.65041)
			(xy 244.084856 -42.79392) (xy 244.156738 -42.865802)
		)
		(stroke
			(width 0)
			(type solid)
		)
		(fill yes)
		(layer "F.Cu")
		(net "M_B_ECC<7>")
	)
	(gr_poly
		(pts
			(xy 244.30736 -46.271434) (xy 244.353842 -46.174406) (xy 244.278404 -46.098968) (xy 244.18163 -46.145704)
			(xy 244.136672 -46.190662) (xy 244.262402 -46.316392)
		)
		(stroke
			(width 0)
			(type solid)
		)
		(fill yes)
		(layer "F.Cu")
		(net "M_B_ECC<4>")
	)
	(gr_poly
		(pts
			(xy 244.318536 -106.96829) (xy 244.282722 -106.932222) (xy 244.138958 -106.806492) (xy 244.067076 -106.878374)
			(xy 244.192806 -107.022138) (xy 244.228874 -107.057952)
		)
		(stroke
			(width 0)
			(type solid)
		)
		(fill yes)
		(layer "F.Cu")
		(net "M_E_ECC<1>")
	)
	(gr_poly
		(pts
			(xy 244.334538 -44.717462) (xy 244.370606 -44.681648) (xy 244.244876 -44.555918) (xy 244.208808 -44.591732)
			(xy 244.162072 -44.68876) (xy 244.23751 -44.764198)
		)
		(stroke
			(width 0)
			(type solid)
		)
		(fill yes)
		(layer "F.Cu")
		(net "M_B_DQS_DP<17>")
	)
	(gr_poly
		(pts
			(xy 244.336062 -108.405422) (xy 244.210332 -108.261912) (xy 244.174518 -108.225844) (xy 244.084602 -108.31576)
			(xy 244.12067 -108.351574) (xy 244.26418 -108.477304)
		)
		(stroke
			(width 0)
			(type solid)
		)
		(fill yes)
		(layer "F.Cu")
		(net "M_E_DQS_DN<17>")
	)
	(gr_poly
		(pts
			(xy 244.340126 -48.21047) (xy 244.376194 -48.174656) (xy 244.250464 -48.048926) (xy 244.214396 -48.08474)
			(xy 244.16766 -48.181768) (xy 244.243098 -48.257206)
		)
		(stroke
			(width 0)
			(type solid)
		)
		(fill yes)
		(layer "F.Cu")
		(net "M_B_DQ<26>")
	)
	(gr_poly
		(pts
			(xy 244.343428 -45.01388) (xy 244.390164 -44.916852) (xy 244.314726 -44.841414) (xy 244.217698 -44.88815)
			(xy 244.181884 -44.924218) (xy 244.307614 -45.049948)
		)
		(stroke
			(width 0)
			(type solid)
		)
		(fill yes)
		(layer "F.Cu")
		(net "M_B_ECC<1>")
	)
	(gr_poly
		(pts
			(xy 244.34546 -105.612184) (xy 244.21973 -105.46842) (xy 244.174772 -105.423462) (xy 244.084856 -105.513378)
			(xy 244.129814 -105.558336) (xy 244.273578 -105.683812)
		)
		(stroke
			(width 0)
			(type solid)
		)
		(fill yes)
		(layer "F.Cu")
		(net "M_E_ECC<4>")
	)
	(gr_poly
		(pts
			(xy 244.349016 -48.506888) (xy 244.395752 -48.40986) (xy 244.320314 -48.334422) (xy 244.223286 -48.381158)
			(xy 244.187472 -48.417226) (xy 244.313202 -48.542956)
		)
		(stroke
			(width 0)
			(type solid)
		)
		(fill yes)
		(layer "F.Cu")
		(net "M_B_DQ<31>")
	)
	(gr_poly
		(pts
			(xy 244.389148 -104.19969) (xy 244.34419 -104.154986) (xy 244.247162 -104.10825) (xy 244.171724 -104.183688)
			(xy 244.21846 -104.280716) (xy 244.263418 -104.32542)
		)
		(stroke
			(width 0)
			(type solid)
		)
		(fill yes)
		(layer "F.Cu")
		(net "M_E_DQ<27>")
	)
	(gr_poly
		(pts
			(xy 244.390164 -41.71569) (xy 244.434868 -41.670732) (xy 244.345206 -41.58107) (xy 244.300248 -41.626028)
			(xy 244.174518 -41.769538) (xy 244.2464 -41.84142)
		)
		(stroke
			(width 0)
			(type solid)
		)
		(fill yes)
		(layer "F.Cu")
		(net "M_B_ECC<3>")
	)
	(gr_poly
		(pts
			(xy 244.399816 -103.955596) (xy 244.35308 -103.858568) (xy 244.317266 -103.8225) (xy 244.191536 -103.94823)
			(xy 244.22735 -103.984298) (xy 244.324378 -104.031034)
		)
		(stroke
			(width 0)
			(type solid)
		)
		(fill yes)
		(layer "F.Cu")
		(net "M_E_DQ<26>")
	)
	(gr_poly
		(pts
			(xy 244.408452 -107.99191) (xy 244.372384 -107.956096) (xy 244.228874 -107.830366) (xy 244.156992 -107.902248)
			(xy 244.282722 -108.046012) (xy 244.318536 -108.081826)
		)
		(stroke
			(width 0)
			(type solid)
		)
		(fill yes)
		(layer "F.Cu")
		(net "M_E_DQS_DN<17>")
	)
	(gr_poly
		(pts
			(xy 244.416834 -42.155872) (xy 244.542564 -42.012108) (xy 244.470682 -41.94048) (xy 244.326918 -42.06621)
			(xy 244.291104 -42.102024) (xy 244.38102 -42.19194)
		)
		(stroke
			(width 0)
			(type solid)
		)
		(fill yes)
		(layer "F.Cu")
		(net "M_B_ECC<2>")
	)
	(gr_poly
		(pts
			(xy 244.4242 -45.238416) (xy 244.460268 -45.202602) (xy 244.334538 -45.076872) (xy 244.29847 -45.112686)
			(xy 244.251734 -45.209714) (xy 244.327172 -45.285152)
		)
		(stroke
			(width 0)
			(type solid)
		)
		(fill yes)
		(layer "F.Cu")
		(net "M_B_ECC<1>")
	)
	(gr_poly
		(pts
			(xy 244.429788 -48.731424) (xy 244.465856 -48.69561) (xy 244.340126 -48.56988) (xy 244.304058 -48.605694)
			(xy 244.257322 -48.702722) (xy 244.33276 -48.77816)
		)
		(stroke
			(width 0)
			(type solid)
		)
		(fill yes)
		(layer "F.Cu")
		(net "M_B_DQ<31>")
	)
	(gr_poly
		(pts
			(xy 244.43309 -45.534834) (xy 244.479826 -45.437806) (xy 244.404388 -45.362368) (xy 244.30736 -45.409104)
			(xy 244.271546 -45.445172) (xy 244.397276 -45.570902)
		)
		(stroke
			(width 0)
			(type solid)
		)
		(fill yes)
		(layer "F.Cu")
		(net "M_B_ECC<0>")
	)
	(gr_poly
		(pts
			(xy 244.433852 -43.076114) (xy 244.398292 -42.974514) (xy 244.291612 -42.974514) (xy 244.256052 -43.076114)
			(xy 244.256052 -43.126914) (xy 244.433852 -43.126914)
		)
		(stroke
			(width 0)
			(type solid)
		)
		(fill yes)
		(layer "F.Cu")
		(net "M_B_ECC<6>")
	)
	(gr_poly
		(pts
			(xy 244.435376 -106.636058) (xy 244.309646 -106.492294) (xy 244.273578 -106.45648) (xy 244.183916 -106.546142)
			(xy 244.21973 -106.58221) (xy 244.363494 -106.70794)
		)
		(stroke
			(width 0)
			(type solid)
		)
		(fill yes)
		(layer "F.Cu")
		(net "M_E_ECC<0>")
	)
	(gr_poly
		(pts
			(xy 244.438678 -49.027842) (xy 244.485414 -48.931068) (xy 244.409976 -48.85563) (xy 244.312948 -48.902112)
			(xy 244.277134 -48.93818) (xy 244.402864 -49.06391)
		)
		(stroke
			(width 0)
			(type solid)
		)
		(fill yes)
		(layer "F.Cu")
		(net "M_B_DQ<30>")
	)
	(gr_poly
		(pts
			(xy 244.460522 -43.980862) (xy 244.49659 -43.945048) (xy 244.37086 -43.819318) (xy 244.334792 -43.855132)
			(xy 244.288056 -43.95216) (xy 244.363494 -44.027598)
		)
		(stroke
			(width 0)
			(type solid)
		)
		(fill yes)
		(layer "F.Cu")
		(net "M_B_DQS_DN<8>")
	)
	(gr_poly
		(pts
			(xy 244.469412 -44.27728) (xy 244.516148 -44.180252) (xy 244.44071 -44.104814) (xy 244.343682 -44.15155)
			(xy 244.307868 -44.187618) (xy 244.433598 -44.313348)
		)
		(stroke
			(width 0)
			(type solid)
		)
		(fill yes)
		(layer "F.Cu")
		(net "M_B_DQS_DN<17>")
	)
	(gr_poly
		(pts
			(xy 244.46992 -103.669846) (xy 244.433852 -103.634032) (xy 244.336824 -103.587296) (xy 244.261386 -103.662734)
			(xy 244.308122 -103.759762) (xy 244.34419 -103.795576)
		)
		(stroke
			(width 0)
			(type solid)
		)
		(fill yes)
		(layer "F.Cu")
		(net "M_E_DQ<26>")
	)
	(gr_poly
		(pts
			(xy 244.489478 -103.434642) (xy 244.442742 -103.337614) (xy 244.406928 -103.301546) (xy 244.281198 -103.427276)
			(xy 244.317012 -103.463344) (xy 244.41404 -103.51008)
		)
		(stroke
			(width 0)
			(type solid)
		)
		(fill yes)
		(layer "F.Cu")
		(net "M_E_DQ<31>")
	)
	(gr_poly
		(pts
			(xy 244.49786 -109.016038) (xy 244.461792 -108.980224) (xy 244.318282 -108.854494) (xy 244.2464 -108.926376)
			(xy 244.37213 -109.07014) (xy 244.407944 -109.105954)
		)
		(stroke
			(width 0)
			(type solid)
		)
		(fill yes)
		(layer "F.Cu")
		(net "M_E_DQS_DP<8>")
	)
	(gr_poly
		(pts
			(xy 244.507258 -106.2228) (xy 244.47119 -106.186986) (xy 244.327426 -106.061256) (xy 244.255798 -106.133138)
			(xy 244.381528 -106.276902) (xy 244.417342 -106.312716)
		)
		(stroke
			(width 0)
			(type solid)
		)
		(fill yes)
		(layer "F.Cu")
		(net "M_E_ECC<0>")
	)
	(gr_poly
		(pts
			(xy 244.513862 -45.75937) (xy 244.54993 -45.723556) (xy 244.4242 -45.597826) (xy 244.388132 -45.63364)
			(xy 244.341396 -45.730668) (xy 244.416834 -45.806106)
		)
		(stroke
			(width 0)
			(type solid)
		)
		(fill yes)
		(layer "F.Cu")
		(net "M_B_ECC<0>")
	)
	(gr_poly
		(pts
			(xy 244.51945 -49.252378) (xy 244.555518 -49.216564) (xy 244.429788 -49.090834) (xy 244.39372 -49.126648)
			(xy 244.346984 -49.223676) (xy 244.422422 -49.299114)
		)
		(stroke
			(width 0)
			(type solid)
		)
		(fill yes)
		(layer "F.Cu")
		(net "M_B_DQ<30>")
	)
	(gr_poly
		(pts
			(xy 244.522752 -46.055788) (xy 244.569488 -45.95876) (xy 244.49405 -45.883322) (xy 244.397022 -45.930058)
			(xy 244.361208 -45.966126) (xy 244.486938 -46.091856)
		)
		(stroke
			(width 0)
			(type solid)
		)
		(fill yes)
		(layer "F.Cu")
		(net "M_B_ECC<5>")
	)
	(gr_poly
		(pts
			(xy 244.525038 -107.659678) (xy 244.399308 -107.516168) (xy 244.363494 -107.4801) (xy 244.273578 -107.570016)
			(xy 244.309646 -107.60583) (xy 244.453156 -107.73156)
		)
		(stroke
			(width 0)
			(type solid)
		)
		(fill yes)
		(layer "F.Cu")
		(net "M_E_DQS_DP<17>")
	)
	(gr_poly
		(pts
			(xy 244.550184 -44.501816) (xy 244.586252 -44.466002) (xy 244.460522 -44.340272) (xy 244.424454 -44.376086)
			(xy 244.377718 -44.473114) (xy 244.453156 -44.548552)
		)
		(stroke
			(width 0)
			(type solid)
		)
		(fill yes)
		(layer "F.Cu")
		(net "M_B_DQS_DN<17>")
	)
	(gr_poly
		(pts
			(xy 244.555772 -47.994824) (xy 244.60073 -47.95012) (xy 244.475 -47.82439) (xy 244.430042 -47.869094)
			(xy 244.383306 -47.966122) (xy 244.458744 -48.04156)
		)
		(stroke
			(width 0)
			(type solid)
		)
		(fill yes)
		(layer "F.Cu")
		(net "M_B_DQ<27>")
	)
	(gr_poly
		(pts
			(xy 244.559074 -44.798234) (xy 244.60581 -44.701206) (xy 244.530372 -44.625768) (xy 244.433344 -44.672504)
			(xy 244.39753 -44.708572) (xy 244.52326 -44.834302)
		)
		(stroke
			(width 0)
			(type solid)
		)
		(fill yes)
		(layer "F.Cu")
		(net "M_B_DQS_DP<17>")
	)
	(gr_poly
		(pts
			(xy 244.559582 -103.148892) (xy 244.523514 -103.113078) (xy 244.426486 -103.066342) (xy 244.351048 -103.14178)
			(xy 244.397784 -103.238808) (xy 244.433852 -103.274622)
		)
		(stroke
			(width 0)
			(type solid)
		)
		(fill yes)
		(layer "F.Cu")
		(net "M_E_DQ<31>")
	)
	(gr_poly
		(pts
			(xy 244.564662 -48.291242) (xy 244.611398 -48.194214) (xy 244.53596 -48.118776) (xy 244.438932 -48.165512)
			(xy 244.403118 -48.20158) (xy 244.528848 -48.32731)
		)
		(stroke
			(width 0)
			(type solid)
		)
		(fill yes)
		(layer "F.Cu")
		(net "M_B_DQ<26>")
	)
	(gr_poly
		(pts
			(xy 244.578886 -42.461688) (xy 244.6147 -42.42562) (xy 244.525038 -42.335958) (xy 244.48897 -42.371772)
			(xy 244.36324 -42.515536) (xy 244.435122 -42.587418)
		)
		(stroke
			(width 0)
			(type solid)
		)
		(fill yes)
		(layer "F.Cu")
		(net "M_B_ECC<2>")
	)
	(gr_poly
		(pts
			(xy 244.595396 -43.54068) (xy 244.642132 -43.443652) (xy 244.566694 -43.368214) (xy 244.469666 -43.41495)
			(xy 244.433852 -43.451018) (xy 244.559328 -43.576494)
		)
		(stroke
			(width 0)
			(type solid)
		)
		(fill yes)
		(layer "F.Cu")
		(net "M_B_DQS_DP<8>")
	)
	(gr_poly
		(pts
			(xy 244.59692 -107.246674) (xy 244.561106 -107.210606) (xy 244.417342 -107.084876) (xy 244.34546 -107.156758)
			(xy 244.47119 -107.300522) (xy 244.507258 -107.336336)
		)
		(stroke
			(width 0)
			(type solid)
		)
		(fill yes)
		(layer "F.Cu")
		(net "M_E_DQS_DP<17>")
	)
	(gr_poly
		(pts
			(xy 244.603524 -46.280324) (xy 244.639592 -46.24451) (xy 244.513862 -46.11878) (xy 244.477794 -46.154594)
			(xy 244.431312 -46.251622) (xy 244.50675 -46.32706)
		)
		(stroke
			(width 0)
			(type solid)
		)
		(fill yes)
		(layer "F.Cu")
		(net "M_B_ECC<5>")
	)
	(gr_poly
		(pts
			(xy 244.612668 -46.576742) (xy 244.65915 -46.479714) (xy 244.583712 -46.404276) (xy 244.486938 -46.451012)
			(xy 244.44198 -46.49597) (xy 244.56771 -46.6217)
		)
		(stroke
			(width 0)
			(type solid)
		)
		(fill yes)
		(layer "F.Cu")
		(net "M_B_ECC<4>")
	)
	(gr_poly
		(pts
			(xy 244.614954 -108.683552) (xy 244.489224 -108.539788) (xy 244.453156 -108.503974) (xy 244.363494 -108.593636)
			(xy 244.399308 -108.629704) (xy 244.543072 -108.755434)
		)
		(stroke
			(width 0)
			(type solid)
		)
		(fill yes)
		(layer "F.Cu")
		(net "M_E_DQS_DN<8>")
	)
	(gr_poly
		(pts
			(xy 244.623844 -105.890568) (xy 244.498114 -105.746804) (xy 244.462046 -105.71099) (xy 244.372384 -105.800652)
			(xy 244.408198 -105.83672) (xy 244.551962 -105.96245)
		)
		(stroke
			(width 0)
			(type solid)
		)
		(fill yes)
		(layer "F.Cu")
		(net "M_E_ECC<5>")
	)
	(gr_poly
		(pts
			(xy 244.639846 -45.02277) (xy 244.675914 -44.986956) (xy 244.550184 -44.861226) (xy 244.514116 -44.89704)
			(xy 244.46738 -44.994068) (xy 244.542818 -45.069506)
		)
		(stroke
			(width 0)
			(type solid)
		)
		(fill yes)
		(layer "F.Cu")
		(net "M_B_DQS_DP<17>")
	)
	(gr_poly
		(pts
			(xy 244.645434 -48.515778) (xy 244.681502 -48.479964) (xy 244.555772 -48.354234) (xy 244.519704 -48.390048)
			(xy 244.472968 -48.487076) (xy 244.548406 -48.562514)
		)
		(stroke
			(width 0)
			(type solid)
		)
		(fill yes)
		(layer "F.Cu")
		(net "M_B_DQ<26>")
	)
	(gr_poly
		(pts
			(xy 244.648736 -45.319188) (xy 244.695472 -45.22216) (xy 244.620034 -45.146722) (xy 244.523006 -45.193458)
			(xy 244.487192 -45.229526) (xy 244.612922 -45.355256)
		)
		(stroke
			(width 0)
			(type solid)
		)
		(fill yes)
		(layer "F.Cu")
		(net "M_B_ECC<1>")
	)
	(gr_poly
		(pts
			(xy 244.649752 -42.872914) (xy 244.649752 -42.822114) (xy 244.471952 -42.822114) (xy 244.471952 -42.872914)
			(xy 244.507512 -42.974514) (xy 244.614192 -42.974514)
		)
		(stroke
			(width 0)
			(type solid)
		)
		(fill yes)
		(layer "F.Cu")
		(net "M_B_ECC<7>")
	)
	(gr_poly
		(pts
			(xy 244.654324 -48.812196) (xy 244.70106 -48.715422) (xy 244.625622 -48.639984) (xy 244.528594 -48.686466)
			(xy 244.49278 -48.722534) (xy 244.61851 -48.848264)
		)
		(stroke
			(width 0)
			(type solid)
		)
		(fill yes)
		(layer "F.Cu")
		(net "M_B_DQ<31>")
	)
	(gr_poly
		(pts
			(xy 244.676168 -43.765216) (xy 244.711982 -43.729148) (xy 244.586252 -43.603418) (xy 244.550438 -43.639486)
			(xy 244.503702 -43.736514) (xy 244.57914 -43.811952)
		)
		(stroke
			(width 0)
			(type solid)
		)
		(fill yes)
		(layer "F.Cu")
		(net "M_B_DQS_DP<8>")
	)
	(gr_poly
		(pts
			(xy 244.685058 -44.061634) (xy 244.731794 -43.964606) (xy 244.656356 -43.889168) (xy 244.559328 -43.935904)
			(xy 244.523514 -43.971972) (xy 244.64899 -44.097448)
		)
		(stroke
			(width 0)
			(type solid)
		)
		(fill yes)
		(layer "F.Cu")
		(net "M_B_DQS_DN<8>")
	)
	(gr_poly
		(pts
			(xy 244.686836 -108.270294) (xy 244.650768 -108.23448) (xy 244.507258 -108.10875) (xy 244.435376 -108.180632)
			(xy 244.561106 -108.324396) (xy 244.59692 -108.36021)
		)
		(stroke
			(width 0)
			(type solid)
		)
		(fill yes)
		(layer "F.Cu")
		(net "M_E_DQS_DN<8>")
	)
	(gr_poly
		(pts
			(xy 244.694456 -103.894382) (xy 244.649498 -103.849678) (xy 244.55247 -103.802942) (xy 244.477032 -103.87838)
			(xy 244.523768 -103.975408) (xy 244.568726 -104.020112)
		)
		(stroke
			(width 0)
			(type solid)
		)
		(fill yes)
		(layer "F.Cu")
		(net "M_E_DQ<27>")
	)
	(gr_poly
		(pts
			(xy 244.695726 -105.47731) (xy 244.659658 -105.441496) (xy 244.515894 -105.315766) (xy 244.444266 -105.387648)
			(xy 244.569996 -105.531412) (xy 244.60581 -105.567226)
		)
		(stroke
			(width 0)
			(type solid)
		)
		(fill yes)
		(layer "F.Cu")
		(net "M_E_ECC<5>")
	)
	(gr_poly
		(pts
			(xy 244.705124 -103.650288) (xy 244.658388 -103.55326) (xy 244.622574 -103.517192) (xy 244.496844 -103.642922)
			(xy 244.532658 -103.67899) (xy 244.629686 -103.725726)
		)
		(stroke
			(width 0)
			(type solid)
		)
		(fill yes)
		(layer "F.Cu")
		(net "M_E_DQ<26>")
	)
	(gr_poly
		(pts
			(xy 244.71376 -106.914442) (xy 244.58803 -106.770678) (xy 244.551962 -106.734864) (xy 244.4623 -106.824526)
			(xy 244.498114 -106.860594) (xy 244.641878 -106.986324)
		)
		(stroke
			(width 0)
			(type solid)
		)
		(fill yes)
		(layer "F.Cu")
		(net "M_E_ECC<1>")
	)
	(gr_poly
		(pts
			(xy 244.716046 -51.241452) (xy 244.715792 -51.020472) (xy 244.545358 -50.931826) (xy 244.501162 -50.931826)
			(xy 244.501924 -51.330606) (xy 244.54612 -51.330606)
		)
		(stroke
			(width 0)
			(type solid)
		)
		(fill yes)
		(layer "F.Cu")
		(net "M_B_DQS_DP<3>")
	)
	(gr_poly
		(pts
			(xy 244.729508 -45.543724) (xy 244.765576 -45.50791) (xy 244.639846 -45.38218) (xy 244.603778 -45.417994)
			(xy 244.557042 -45.515022) (xy 244.63248 -45.59046)
		)
		(stroke
			(width 0)
			(type solid)
		)
		(fill yes)
		(layer "F.Cu")
		(net "M_B_ECC<1>")
	)
	(gr_poly
		(pts
			(xy 244.735096 -49.036732) (xy 244.771164 -49.000918) (xy 244.645434 -48.875188) (xy 244.609366 -48.911002)
			(xy 244.562884 -49.00803) (xy 244.638322 -49.083468)
		)
		(stroke
			(width 0)
			(type solid)
		)
		(fill yes)
		(layer "F.Cu")
		(net "M_B_DQ<31>")
	)
	(gr_poly
		(pts
			(xy 244.738398 -45.840142) (xy 244.785134 -45.743114) (xy 244.709696 -45.667676) (xy 244.612668 -45.714412)
			(xy 244.576854 -45.75048) (xy 244.702584 -45.87621)
		)
		(stroke
			(width 0)
			(type solid)
		)
		(fill yes)
		(layer "F.Cu")
		(net "M_B_ECC<0>")
	)
	(gr_poly
		(pts
			(xy 244.743986 -49.33315) (xy 244.790722 -49.236376) (xy 244.715284 -49.160938) (xy 244.618256 -49.20742)
			(xy 244.582442 -49.243488) (xy 244.708172 -49.369218)
		)
		(stroke
			(width 0)
			(type solid)
		)
		(fill yes)
		(layer "F.Cu")
		(net "M_B_DQ<30>")
	)
	(gr_poly
		(pts
			(xy 244.76583 -44.28617) (xy 244.801898 -44.250356) (xy 244.676168 -44.124626) (xy 244.6401 -44.16044)
			(xy 244.593364 -44.257468) (xy 244.668802 -44.332906)
		)
		(stroke
			(width 0)
			(type solid)
		)
		(fill yes)
		(layer "F.Cu")
		(net "M_B_DQS_DN<8>")
	)
	(gr_poly
		(pts
			(xy 244.77472 -44.582588) (xy 244.821456 -44.48556) (xy 244.746018 -44.410122) (xy 244.64899 -44.456858)
			(xy 244.613176 -44.492926) (xy 244.738906 -44.618656)
		)
		(stroke
			(width 0)
			(type solid)
		)
		(fill yes)
		(layer "F.Cu")
		(net "M_B_DQS_DN<17>")
	)
	(gr_poly
		(pts
			(xy 244.775228 -103.364538) (xy 244.73916 -103.328724) (xy 244.642132 -103.281988) (xy 244.566694 -103.357426)
			(xy 244.61343 -103.454454) (xy 244.649498 -103.490268)
		)
		(stroke
			(width 0)
			(type solid)
		)
		(fill yes)
		(layer "F.Cu")
		(net "M_E_DQ<26>")
	)
	(gr_poly
		(pts
			(xy 244.776498 -109.294168) (xy 244.740684 -109.2581) (xy 244.59692 -109.13237) (xy 244.525038 -109.204252)
			(xy 244.650768 -109.348016) (xy 244.686836 -109.38383)
		)
		(stroke
			(width 0)
			(type solid)
		)
		(fill yes)
		(layer "F.Cu")
		(net "M_E_ECC<6>")
	)
	(gr_poly
		(pts
			(xy 244.785642 -106.501184) (xy 244.749574 -106.46537) (xy 244.60581 -106.33964) (xy 244.534182 -106.411522)
			(xy 244.659912 -106.555286) (xy 244.695726 -106.5911)
		)
		(stroke
			(width 0)
			(type solid)
		)
		(fill yes)
		(layer "F.Cu")
		(net "M_E_ECC<1>")
	)
	(gr_poly
		(pts
			(xy 244.803422 -107.938062) (xy 244.677692 -107.794552) (xy 244.641878 -107.758484) (xy 244.551962 -107.8484)
			(xy 244.58803 -107.884214) (xy 244.73154 -108.009944)
		)
		(stroke
			(width 0)
			(type solid)
		)
		(fill yes)
		(layer "F.Cu")
		(net "M_E_DQS_DN<17>")
	)
	(gr_poly
		(pts
			(xy 244.811042 -43.325034) (xy 244.857778 -43.228006) (xy 244.78234 -43.152568) (xy 244.685312 -43.199304)
			(xy 244.649498 -43.235372) (xy 244.774974 -43.360848)
		)
		(stroke
			(width 0)
			(type solid)
		)
		(fill yes)
		(layer "F.Cu")
		(net "M_B_ECC<6>")
	)
	(gr_poly
		(pts
			(xy 244.812312 -105.145078) (xy 244.686582 -105.001314) (xy 244.641624 -104.95661) (xy 244.551962 -105.046272)
			(xy 244.59692 -105.09123) (xy 244.74043 -105.21696)
		)
		(stroke
			(width 0)
			(type solid)
		)
		(fill yes)
		(layer "F.Cu")
		(net "M_E_ECC<4>")
	)
	(gr_poly
		(pts
			(xy 244.81917 -46.064678) (xy 244.855238 -46.028864) (xy 244.729508 -45.903134) (xy 244.69344 -45.938948)
			(xy 244.646958 -46.035976) (xy 244.722396 -46.111414)
		)
		(stroke
			(width 0)
			(type solid)
		)
		(fill yes)
		(layer "F.Cu")
		(net "M_B_ECC<0>")
	)
	(gr_poly
		(pts
			(xy 244.82806 -46.361096) (xy 244.874796 -46.264322) (xy 244.799358 -46.188884) (xy 244.70233 -46.235366)
			(xy 244.666516 -46.271434) (xy 244.792246 -46.397164)
		)
		(stroke
			(width 0)
			(type solid)
		)
		(fill yes)
		(layer "F.Cu")
		(net "M_B_ECC<5>")
	)
	(gr_poly
		(pts
			(xy 244.855492 -44.807124) (xy 244.89156 -44.77131) (xy 244.76583 -44.64558) (xy 244.729762 -44.681394)
			(xy 244.683026 -44.778422) (xy 244.758464 -44.85386)
		)
		(stroke
			(width 0)
			(type solid)
		)
		(fill yes)
		(layer "F.Cu")
		(net "M_B_DQS_DN<17>")
	)
	(gr_poly
		(pts
			(xy 244.857524 -42.18305) (xy 244.902228 -42.138092) (xy 244.812566 -42.04843) (xy 244.767608 -42.093388)
			(xy 244.641878 -42.236898) (xy 244.71376 -42.30878)
		)
		(stroke
			(width 0)
			(type solid)
		)
		(fill yes)
		(layer "F.Cu")
		(net "M_B_ECC<3>")
	)
	(gr_poly
		(pts
			(xy 244.86108 -48.300386) (xy 244.906038 -48.255428) (xy 244.780308 -48.129698) (xy 244.73535 -48.174656)
			(xy 244.688614 -48.27143) (xy 244.764052 -48.346868)
		)
		(stroke
			(width 0)
			(type solid)
		)
		(fill yes)
		(layer "F.Cu")
		(net "M_B_DQ<27>")
	)
	(gr_poly
		(pts
			(xy 244.864382 -45.103542) (xy 244.911118 -45.006514) (xy 244.83568 -44.931076) (xy 244.738652 -44.977812)
			(xy 244.702838 -45.01388) (xy 244.828568 -45.13961)
		)
		(stroke
			(width 0)
			(type solid)
		)
		(fill yes)
		(layer "F.Cu")
		(net "M_B_DQS_DP<17>")
	)
	(gr_poly
		(pts
			(xy 244.86997 -48.59655) (xy 244.916706 -48.499776) (xy 244.841268 -48.424338) (xy 244.74424 -48.47082)
			(xy 244.708426 -48.506888) (xy 244.834156 -48.632618)
		)
		(stroke
			(width 0)
			(type solid)
		)
		(fill yes)
		(layer "F.Cu")
		(net "M_B_DQ<26>")
	)
	(gr_poly
		(pts
			(xy 244.875304 -107.525058) (xy 244.83949 -107.48899) (xy 244.695726 -107.36326) (xy 244.623844 -107.435142)
			(xy 244.749574 -107.578906) (xy 244.785642 -107.61472)
		)
		(stroke
			(width 0)
			(type solid)
		)
		(fill yes)
		(layer "F.Cu")
		(net "M_E_DQS_DN<17>")
	)
	(gr_poly
		(pts
			(xy 244.891814 -43.54957) (xy 244.927628 -43.513502) (xy 244.801898 -43.387772) (xy 244.766084 -43.42384)
			(xy 244.719348 -43.520868) (xy 244.794786 -43.596306)
		)
		(stroke
			(width 0)
			(type solid)
		)
		(fill yes)
		(layer "F.Cu")
		(net "M_B_ECC<6>")
	)
	(gr_poly
		(pts
			(xy 244.893338 -108.961936) (xy 244.767608 -108.818172) (xy 244.73154 -108.782358) (xy 244.641878 -108.87202)
			(xy 244.677692 -108.908088) (xy 244.821456 -109.033818)
		)
		(stroke
			(width 0)
			(type solid)
		)
		(fill yes)
		(layer "F.Cu")
		(net "M_E_DQS_DP<8>")
	)
	(gr_poly
		(pts
			(xy 244.900704 -43.845988) (xy 244.94744 -43.74896) (xy 244.872002 -43.673522) (xy 244.774974 -43.720258)
			(xy 244.73916 -43.756326) (xy 244.864636 -43.881802)
		)
		(stroke
			(width 0)
			(type solid)
		)
		(fill yes)
		(layer "F.Cu")
		(net "M_B_DQS_DP<8>")
	)
	(gr_poly
		(pts
			(xy 244.902228 -106.168952) (xy 244.776498 -106.025442) (xy 244.740684 -105.989374) (xy 244.650768 -106.07929)
			(xy 244.686836 -106.115104) (xy 244.830346 -106.240834)
		)
		(stroke
			(width 0)
			(type solid)
		)
		(fill yes)
		(layer "F.Cu")
		(net "M_E_ECC<0>")
	)
	(gr_poly
		(pts
			(xy 244.908832 -46.585632) (xy 244.9449 -46.549818) (xy 244.81917 -46.424088) (xy 244.783102 -46.459902)
			(xy 244.73662 -46.55693) (xy 244.812058 -46.632368)
		)
		(stroke
			(width 0)
			(type solid)
		)
		(fill yes)
		(layer "F.Cu")
		(net "M_B_ECC<5>")
	)
	(gr_poly
		(pts
			(xy 244.917976 -46.88205) (xy 244.964712 -46.785022) (xy 244.889274 -46.709584) (xy 244.792246 -46.75632)
			(xy 244.747288 -46.801278) (xy 244.873018 -46.927008)
		)
		(stroke
			(width 0)
			(type solid)
		)
		(fill yes)
		(layer "F.Cu")
		(net "M_B_ECC<4>")
	)
	(gr_poly
		(pts
			(xy 244.945154 -45.328078) (xy 244.981222 -45.292264) (xy 244.855492 -45.166534) (xy 244.819424 -45.202348)
			(xy 244.772688 -45.299376) (xy 244.848126 -45.374814)
		)
		(stroke
			(width 0)
			(type solid)
		)
		(fill yes)
		(layer "F.Cu")
		(net "M_B_DQS_DP<17>")
	)
	(gr_poly
		(pts
			(xy 244.954044 -45.624496) (xy 245.00078 -45.527468) (xy 244.925342 -45.45203) (xy 244.828314 -45.498766)
			(xy 244.7925 -45.534834) (xy 244.91823 -45.660564)
		)
		(stroke
			(width 0)
			(type solid)
		)
		(fill yes)
		(layer "F.Cu")
		(net "M_B_ECC<1>")
	)
	(gr_poly
		(pts
			(xy 244.959632 -49.117504) (xy 245.006368 -49.02073) (xy 244.93093 -48.945292) (xy 244.833902 -48.991774)
			(xy 244.798088 -49.027842) (xy 244.923818 -49.153572)
		)
		(stroke
			(width 0)
			(type solid)
		)
		(fill yes)
		(layer "F.Cu")
		(net "M_B_DQ<31>")
	)
	(gr_poly
		(pts
			(xy 244.96522 -108.548678) (xy 244.929152 -108.512864) (xy 244.785642 -108.387134) (xy 244.71376 -108.459016)
			(xy 244.83949 -108.60278) (xy 244.875304 -108.638594)
		)
		(stroke
			(width 0)
			(type solid)
		)
		(fill yes)
		(layer "F.Cu")
		(net "M_E_DQS_DP<8>")
	)
	(gr_poly
		(pts
			(xy 244.97411 -105.755948) (xy 244.938296 -105.720134) (xy 244.794532 -105.594404) (xy 244.72265 -105.666032)
			(xy 244.84838 -105.809796) (xy 244.884448 -105.84561)
		)
		(stroke
			(width 0)
			(type solid)
		)
		(fill yes)
		(layer "F.Cu")
		(net "M_E_ECC<0>")
	)
	(gr_poly
		(pts
			(xy 244.981476 -44.070524) (xy 245.017544 -44.03471) (xy 244.891814 -43.90898) (xy 244.855746 -43.944794)
			(xy 244.80901 -44.041822) (xy 244.884448 -44.11726)
		)
		(stroke
			(width 0)
			(type solid)
		)
		(fill yes)
		(layer "F.Cu")
		(net "M_B_DQS_DP<8>")
	)
	(gr_poly
		(pts
			(xy 244.983 -109.985556) (xy 244.85727 -109.842046) (xy 244.821456 -109.805978) (xy 244.73154 -109.895894)
			(xy 244.767608 -109.931708) (xy 244.911118 -110.057438)
		)
		(stroke
			(width 0)
			(type solid)
		)
		(fill yes)
		(layer "F.Cu")
		(net "M_E_ECC<7>")
	)
	(gr_poly
		(pts
			(xy 244.990366 -44.366942) (xy 245.037102 -44.269914) (xy 244.961664 -44.194476) (xy 244.864636 -44.241212)
			(xy 244.828822 -44.27728) (xy 244.954552 -44.40301)
		)
		(stroke
			(width 0)
			(type solid)
		)
		(fill yes)
		(layer "F.Cu")
		(net "M_B_DQS_DN<8>")
	)
	(gr_poly
		(pts
			(xy 244.992144 -107.192826) (xy 244.866414 -107.049062) (xy 244.830346 -107.013248) (xy 244.740684 -107.10291)
			(xy 244.776498 -107.138978) (xy 244.920262 -107.264708)
		)
		(stroke
			(width 0)
			(type solid)
		)
		(fill yes)
		(layer "F.Cu")
		(net "M_E_DQS_DP<17>")
	)
	(gr_poly
		(pts
			(xy 244.999764 -103.589074) (xy 244.954806 -103.54437) (xy 244.857778 -103.497634) (xy 244.78234 -103.573072)
			(xy 244.829076 -103.6701) (xy 244.874034 -103.714804)
		)
		(stroke
			(width 0)
			(type solid)
		)
		(fill yes)
		(layer "F.Cu")
		(net "M_E_DQ<27>")
	)
	(gr_poly
		(pts
			(xy 245.017798 -42.81297) (xy 245.053612 -42.776902) (xy 244.927882 -42.651172) (xy 244.892068 -42.68724)
			(xy 244.845332 -42.784268) (xy 244.92077 -42.859706)
		)
		(stroke
			(width 0)
			(type solid)
		)
		(fill yes)
		(layer "F.Cu")
		(net "M_B_ECC<2>")
	)
	(gr_poly
		(pts
			(xy 245.026688 -43.109388) (xy 245.073424 -43.01236) (xy 244.997986 -42.936922) (xy 244.900958 -42.983658)
			(xy 244.86489 -43.019472) (xy 244.99062 -43.145202)
		)
		(stroke
			(width 0)
			(type solid)
		)
		(fill yes)
		(layer "F.Cu")
		(net "M_B_ECC<7>")
	)
	(gr_poly
		(pts
			(xy 245.034816 -45.849032) (xy 245.070884 -45.813218) (xy 244.945154 -45.687488) (xy 244.909086 -45.723302)
			(xy 244.862604 -45.82033) (xy 244.938042 -45.895768)
		)
		(stroke
			(width 0)
			(type solid)
		)
		(fill yes)
		(layer "F.Cu")
		(net "M_B_ECC<1>")
	)
	(gr_poly
		(pts
			(xy 245.040404 -49.34204) (xy 245.076472 -49.306226) (xy 244.950742 -49.180496) (xy 244.914674 -49.21631)
			(xy 244.868192 -49.313338) (xy 244.94363 -49.388776)
		)
		(stroke
			(width 0)
			(type solid)
		)
		(fill yes)
		(layer "F.Cu")
		(net "M_B_DQ<31>")
	)
	(gr_poly
		(pts
			(xy 245.043706 -46.14545) (xy 245.090442 -46.048676) (xy 245.015004 -45.973238) (xy 244.917976 -46.01972)
			(xy 244.882162 -46.055788) (xy 245.007892 -46.181518)
		)
		(stroke
			(width 0)
			(type solid)
		)
		(fill yes)
		(layer "F.Cu")
		(net "M_B_ECC<0>")
	)
	(gr_poly
		(pts
			(xy 245.054882 -109.572552) (xy 245.019068 -109.536484) (xy 244.875304 -109.410754) (xy 244.803422 -109.482636)
			(xy 244.929152 -109.6264) (xy 244.96522 -109.662214)
		)
		(stroke
			(width 0)
			(type solid)
		)
		(fill yes)
		(layer "F.Cu")
		(net "M_E_ECC<7>")
	)
	(gr_poly
		(pts
			(xy 245.064026 -106.779568) (xy 245.027958 -106.743754) (xy 244.884194 -106.618024) (xy 244.812566 -106.689906)
			(xy 244.938296 -106.83367) (xy 244.97411 -106.869484)
		)
		(stroke
			(width 0)
			(type solid)
		)
		(fill yes)
		(layer "F.Cu")
		(net "M_E_DQS_DP<17>")
	)
	(gr_poly
		(pts
			(xy 245.071138 -44.591478) (xy 245.107206 -44.555664) (xy 244.981476 -44.429934) (xy 244.945408 -44.465748)
			(xy 244.898672 -44.562776) (xy 244.97411 -44.638214)
		)
		(stroke
			(width 0)
			(type solid)
		)
		(fill yes)
		(layer "F.Cu")
		(net "M_B_DQS_DN<8>")
	)
	(gr_poly
		(pts
			(xy 245.080028 -44.887896) (xy 245.126764 -44.790868) (xy 245.051326 -44.71543) (xy 244.954298 -44.762166)
			(xy 244.918484 -44.798234) (xy 245.044214 -44.923964)
		)
		(stroke
			(width 0)
			(type solid)
		)
		(fill yes)
		(layer "F.Cu")
		(net "M_B_DQS_DN<17>")
	)
	(gr_poly
		(pts
			(xy 245.081806 -108.216446) (xy 244.956076 -108.072936) (xy 244.920262 -108.036868) (xy 244.830346 -108.126784)
			(xy 244.866414 -108.162598) (xy 245.009924 -108.288328)
		)
		(stroke
			(width 0)
			(type solid)
		)
		(fill yes)
		(layer "F.Cu")
		(net "M_E_DQS_DN<8>")
	)
	(gr_poly
		(pts
			(xy 245.090696 -105.423462) (xy 244.964966 -105.279952) (xy 244.929152 -105.243884) (xy 244.839236 -105.3338)
			(xy 244.875304 -105.369614) (xy 245.018814 -105.495344)
		)
		(stroke
			(width 0)
			(type solid)
		)
		(fill yes)
		(layer "F.Cu")
		(net "M_E_ECC<5>")
	)
	(gr_poly
		(pts
			(xy 245.10746 -43.333924) (xy 245.143274 -43.297856) (xy 245.017544 -43.172126) (xy 244.98173 -43.208194)
			(xy 244.934994 -43.305222) (xy 245.010432 -43.38066)
		)
		(stroke
			(width 0)
			(type solid)
		)
		(fill yes)
		(layer "F.Cu")
		(net "M_B_ECC<7>")
	)
	(gr_poly
		(pts
			(xy 245.11635 -43.630342) (xy 245.163086 -43.533314) (xy 245.087648 -43.457876) (xy 244.99062 -43.504612)
			(xy 244.954806 -43.54068) (xy 245.080282 -43.666156)
		)
		(stroke
			(width 0)
			(type solid)
		)
		(fill yes)
		(layer "F.Cu")
		(net "M_B_ECC<6>")
	)
	(gr_poly
		(pts
			(xy 245.124478 -46.369986) (xy 245.160546 -46.334172) (xy 245.034816 -46.208442) (xy 244.998748 -46.244256)
			(xy 244.952266 -46.341284) (xy 245.027704 -46.416722)
		)
		(stroke
			(width 0)
			(type solid)
		)
		(fill yes)
		(layer "F.Cu")
		(net "M_B_ECC<0>")
	)
	(gr_poly
		(pts
			(xy 245.133368 -46.666404) (xy 245.180104 -46.56963) (xy 245.104666 -46.494192) (xy 245.007638 -46.540928)
			(xy 244.971824 -46.576742) (xy 245.097554 -46.702472)
		)
		(stroke
			(width 0)
			(type solid)
		)
		(fill yes)
		(layer "F.Cu")
		(net "M_B_ECC<5>")
	)
	(gr_poly
		(pts
			(xy 245.153688 -107.803442) (xy 245.117874 -107.767374) (xy 244.97411 -107.641644) (xy 244.902228 -107.713526)
			(xy 245.027958 -107.85729) (xy 245.064026 -107.893104)
		)
		(stroke
			(width 0)
			(type solid)
		)
		(fill yes)
		(layer "F.Cu")
		(net "M_E_DQS_DN<8>")
	)
	(gr_poly
		(pts
			(xy 245.1608 -45.112432) (xy 245.196868 -45.076618) (xy 245.071138 -44.950888) (xy 245.03507 -44.986702)
			(xy 244.988334 -45.08373) (xy 245.063772 -45.159168)
		)
		(stroke
			(width 0)
			(type solid)
		)
		(fill yes)
		(layer "F.Cu")
		(net "M_B_DQS_DN<17>")
	)
	(gr_poly
		(pts
			(xy 245.162578 -105.010458) (xy 245.126764 -104.974644) (xy 244.983 -104.848914) (xy 244.911118 -104.920542)
			(xy 245.036848 -105.064306) (xy 245.072662 -105.100374)
		)
		(stroke
			(width 0)
			(type solid)
		)
		(fill yes)
		(layer "F.Cu")
		(net "M_E_ECC<5>")
	)
	(gr_poly
		(pts
			(xy 245.16969 -45.40885) (xy 245.216426 -45.311822) (xy 245.140988 -45.236384) (xy 245.04396 -45.28312)
			(xy 245.008146 -45.319188) (xy 245.133876 -45.444918)
		)
		(stroke
			(width 0)
			(type solid)
		)
		(fill yes)
		(layer "F.Cu")
		(net "M_B_DQS_DP<17>")
	)
	(gr_poly
		(pts
			(xy 245.171722 -109.24032) (xy 245.045992 -109.096556) (xy 245.009924 -109.060742) (xy 244.920262 -109.150404)
			(xy 244.956076 -109.186472) (xy 245.09984 -109.312202)
		)
		(stroke
			(width 0)
			(type solid)
		)
		(fill yes)
		(layer "F.Cu")
		(net "M_E_ECC<6>")
	)
	(gr_poly
		(pts
			(xy 245.180612 -106.447336) (xy 245.054882 -106.303826) (xy 245.019068 -106.267758) (xy 244.929152 -106.357674)
			(xy 244.96522 -106.393488) (xy 245.10873 -106.519218)
		)
		(stroke
			(width 0)
			(type solid)
		)
		(fill yes)
		(layer "F.Cu")
		(net "M_E_ECC<1>")
	)
	(gr_poly
		(pts
			(xy 245.197122 -43.854878) (xy 245.23319 -43.819064) (xy 245.10746 -43.693334) (xy 245.071392 -43.729148)
			(xy 245.024656 -43.826176) (xy 245.100094 -43.901614)
		)
		(stroke
			(width 0)
			(type solid)
		)
		(fill yes)
		(layer "F.Cu")
		(net "M_B_ECC<6>")
	)
	(gr_poly
		(pts
			(xy 245.206012 -44.151296) (xy 245.252748 -44.054268) (xy 245.17731 -43.97883) (xy 245.080282 -44.025566)
			(xy 245.044468 -44.061634) (xy 245.170198 -44.187364)
		)
		(stroke
			(width 0)
			(type solid)
		)
		(fill yes)
		(layer "F.Cu")
		(net "M_B_DQS_DP<8>")
	)
	(gr_poly
		(pts
			(xy 245.214394 -46.89094) (xy 245.250208 -46.855126) (xy 245.124478 -46.729396) (xy 245.088664 -46.76521)
			(xy 245.041928 -46.862238) (xy 245.117366 -46.937676)
		)
		(stroke
			(width 0)
			(type solid)
		)
		(fill yes)
		(layer "F.Cu")
		(net "M_B_ECC<5>")
	)
	(gr_poly
		(pts
			(xy 245.223284 -47.187358) (xy 245.27002 -47.09033) (xy 245.194582 -47.014892) (xy 245.097554 -47.061628)
			(xy 245.052596 -47.106586) (xy 245.178326 -47.232316)
		)
		(stroke
			(width 0)
			(type solid)
		)
		(fill yes)
		(layer "F.Cu")
		(net "M_B_ECC<4>")
	)
	(gr_poly
		(pts
			(xy 245.233444 -42.597324) (xy 245.278148 -42.552366) (xy 245.152418 -42.426636) (xy 245.107714 -42.471594)
			(xy 245.060978 -42.568622) (xy 245.136416 -42.64406)
		)
		(stroke
			(width 0)
			(type solid)
		)
		(fill yes)
		(layer "F.Cu")
		(net "M_B_ECC<3>")
	)
	(gr_poly
		(pts
			(xy 245.242334 -42.893742) (xy 245.28907 -42.796714) (xy 245.213632 -42.721276) (xy 245.116604 -42.768012)
			(xy 245.080536 -42.803826) (xy 245.206266 -42.929556)
		)
		(stroke
			(width 0)
			(type solid)
		)
		(fill yes)
		(layer "F.Cu")
		(net "M_B_ECC<2>")
	)
	(gr_poly
		(pts
			(xy 245.243604 -108.827062) (xy 245.207536 -108.791248) (xy 245.064026 -108.665518) (xy 244.992144 -108.7374)
			(xy 245.117874 -108.881164) (xy 245.153688 -108.916978)
		)
		(stroke
			(width 0)
			(type solid)
		)
		(fill yes)
		(layer "F.Cu")
		(net "M_E_ECC<6>")
	)
	(gr_poly
		(pts
			(xy 245.250462 -45.633386) (xy 245.28653 -45.597572) (xy 245.1608 -45.471842) (xy 245.124732 -45.507656)
			(xy 245.07825 -45.604684) (xy 245.153688 -45.680122)
		)
		(stroke
			(width 0)
			(type solid)
		)
		(fill yes)
		(layer "F.Cu")
		(net "M_B_DQS_DP<17>")
	)
	(gr_poly
		(pts
			(xy 245.252494 -106.034332) (xy 245.21668 -105.998518) (xy 245.072916 -105.872788) (xy 245.001034 -105.944416)
			(xy 245.126764 -106.08818) (xy 245.162832 -106.123994)
		)
		(stroke
			(width 0)
			(type solid)
		)
		(fill yes)
		(layer "F.Cu")
		(net "M_E_ECC<1>")
	)
	(gr_poly
		(pts
			(xy 245.259352 -45.929804) (xy 245.306088 -45.83303) (xy 245.23065 -45.757592) (xy 245.133622 -45.804074)
			(xy 245.097808 -45.840142) (xy 245.223538 -45.965872)
		)
		(stroke
			(width 0)
			(type solid)
		)
		(fill yes)
		(layer "F.Cu")
		(net "M_B_ECC<1>")
	)
	(gr_poly
		(pts
			(xy 245.270528 -107.47121) (xy 245.144798 -107.327446) (xy 245.10873 -107.291632) (xy 245.019068 -107.381294)
			(xy 245.054882 -107.417362) (xy 245.198646 -107.543092)
		)
		(stroke
			(width 0)
			(type solid)
		)
		(fill yes)
		(layer "F.Cu")
		(net "M_E_DQS_DN<17>")
	)
	(gr_poly
		(pts
			(xy 245.279418 -104.678226) (xy 245.153688 -104.534462) (xy 245.10873 -104.489504) (xy 245.018814 -104.57942)
			(xy 245.063772 -104.624378) (xy 245.207536 -104.750108)
		)
		(stroke
			(width 0)
			(type solid)
		)
		(fill yes)
		(layer "F.Cu")
		(net "M_E_ECC<4>")
	)
	(gr_poly
		(pts
			(xy 245.286784 -44.375832) (xy 245.322852 -44.340018) (xy 245.197122 -44.214288) (xy 245.161054 -44.250102)
			(xy 245.114318 -44.34713) (xy 245.189756 -44.422568)
		)
		(stroke
			(width 0)
			(type solid)
		)
		(fill yes)
		(layer "F.Cu")
		(net "M_B_DQS_DP<8>")
	)
	(gr_poly
		(pts
			(xy 245.295674 -44.67225) (xy 245.34241 -44.575222) (xy 245.266972 -44.499784) (xy 245.169944 -44.54652)
			(xy 245.13413 -44.582588) (xy 245.25986 -44.708318)
		)
		(stroke
			(width 0)
			(type solid)
		)
		(fill yes)
		(layer "F.Cu")
		(net "M_B_DQS_DN<8>")
	)
	(gr_poly
		(pts
			(xy 245.323106 -43.118278) (xy 245.35892 -43.08221) (xy 245.23319 -42.95648) (xy 245.197376 -42.992548)
			(xy 245.15064 -43.089576) (xy 245.226078 -43.165014)
		)
		(stroke
			(width 0)
			(type solid)
		)
		(fill yes)
		(layer "F.Cu")
		(net "M_B_ECC<2>")
	)
	(gr_poly
		(pts
			(xy 245.331996 -43.414696) (xy 245.378732 -43.317668) (xy 245.303294 -43.24223) (xy 245.206266 -43.288966)
			(xy 245.170452 -43.325034) (xy 245.295928 -43.45051)
		)
		(stroke
			(width 0)
			(type solid)
		)
		(fill yes)
		(layer "F.Cu")
		(net "M_B_ECC<7>")
	)
	(gr_poly
		(pts
			(xy 245.333266 -109.850936) (xy 245.297452 -109.814868) (xy 245.153688 -109.689138) (xy 245.081806 -109.76102)
			(xy 245.207536 -109.904784) (xy 245.243604 -109.940598)
		)
		(stroke
			(width 0)
			(type solid)
		)
		(fill yes)
		(layer "F.Cu")
		(net "M_E_ECC<2>")
	)
	(gr_poly
		(pts
			(xy 245.340124 -46.15434) (xy 245.376192 -46.118526) (xy 245.250462 -45.992796) (xy 245.214394 -46.02861)
			(xy 245.167912 -46.125638) (xy 245.24335 -46.201076)
		)
		(stroke
			(width 0)
			(type solid)
		)
		(fill yes)
		(layer "F.Cu")
		(net "M_B_ECC<1>")
	)
	(gr_poly
		(pts
			(xy 245.34241 -107.057952) (xy 245.306342 -107.022138) (xy 245.162578 -106.896408) (xy 245.09095 -106.96829)
			(xy 245.21668 -107.112054) (xy 245.252494 -107.147868)
		)
		(stroke
			(width 0)
			(type solid)
		)
		(fill yes)
		(layer "F.Cu")
		(net "M_E_DQS_DN<17>")
	)
	(gr_poly
		(pts
			(xy 245.349014 -46.450758) (xy 245.39575 -46.353984) (xy 245.320312 -46.278546) (xy 245.223284 -46.325282)
			(xy 245.18747 -46.361096) (xy 245.3132 -46.486826)
		)
		(stroke
			(width 0)
			(type solid)
		)
		(fill yes)
		(layer "F.Cu")
		(net "M_B_ECC<0>")
	)
	(gr_poly
		(pts
			(xy 245.36019 -108.49483) (xy 245.23446 -108.35132) (xy 245.198646 -108.315252) (xy 245.10873 -108.405168)
			(xy 245.144798 -108.440982) (xy 245.288308 -108.566712)
		)
		(stroke
			(width 0)
			(type solid)
		)
		(fill yes)
		(layer "F.Cu")
		(net "M_E_DQS_DP<8>")
	)
	(gr_poly
		(pts
			(xy 245.369334 -105.7021) (xy 245.243604 -105.558336) (xy 245.207536 -105.522522) (xy 245.117874 -105.612184)
			(xy 245.153688 -105.648252) (xy 245.297452 -105.773982)
		)
		(stroke
			(width 0)
			(type solid)
		)
		(fill yes)
		(layer "F.Cu")
		(net "M_E_ECC<0>")
	)
	(gr_poly
		(pts
			(xy 245.376446 -44.896786) (xy 245.412514 -44.860972) (xy 245.286784 -44.735242) (xy 245.250716 -44.771056)
			(xy 245.20398 -44.868084) (xy 245.279418 -44.943522)
		)
		(stroke
			(width 0)
			(type solid)
		)
		(fill yes)
		(layer "F.Cu")
		(net "M_B_DQS_DN<8>")
	)
	(gr_poly
		(pts
			(xy 245.385336 -45.193204) (xy 245.432072 -45.096176) (xy 245.356634 -45.020738) (xy 245.259606 -45.067474)
			(xy 245.223792 -45.103542) (xy 245.349522 -45.229272)
		)
		(stroke
			(width 0)
			(type solid)
		)
		(fill yes)
		(layer "F.Cu")
		(net "M_B_DQS_DN<17>")
	)
	(gr_poly
		(pts
			(xy 245.412768 -43.639232) (xy 245.448836 -43.603418) (xy 245.323106 -43.477688) (xy 245.287038 -43.513502)
			(xy 245.240302 -43.61053) (xy 245.31574 -43.685968)
		)
		(stroke
			(width 0)
			(type solid)
		)
		(fill yes)
		(layer "F.Cu")
		(net "M_B_ECC<7>")
	)
	(gr_poly
		(pts
			(xy 245.421658 -43.93565) (xy 245.468394 -43.838622) (xy 245.392956 -43.763184) (xy 245.295928 -43.80992)
			(xy 245.260114 -43.845988) (xy 245.385844 -43.971718)
		)
		(stroke
			(width 0)
			(type solid)
		)
		(fill yes)
		(layer "F.Cu")
		(net "M_B_ECC<6>")
	)
	(gr_poly
		(pts
			(xy 245.43004 -46.675294) (xy 245.465854 -46.63948) (xy 245.340124 -46.51375) (xy 245.30431 -46.549564)
			(xy 245.257574 -46.646592) (xy 245.333012 -46.72203)
		)
		(stroke
			(width 0)
			(type solid)
		)
		(fill yes)
		(layer "F.Cu")
		(net "M_B_ECC<0>")
	)
	(gr_poly
		(pts
			(xy 245.432072 -108.081826) (xy 245.396258 -108.045758) (xy 245.252494 -107.920028) (xy 245.180612 -107.99191)
			(xy 245.306342 -108.135674) (xy 245.34241 -108.171488)
		)
		(stroke
			(width 0)
			(type solid)
		)
		(fill yes)
		(layer "F.Cu")
		(net "M_E_DQS_DP<8>")
	)
	(gr_poly
		(pts
			(xy 245.438676 -46.971966) (xy 245.485412 -46.874938) (xy 245.409974 -46.7995) (xy 245.312946 -46.846236)
			(xy 245.277132 -46.88205) (xy 245.402862 -47.00778)
		)
		(stroke
			(width 0)
			(type solid)
		)
		(fill yes)
		(layer "F.Cu")
		(net "M_B_ECC<5>")
	)
	(gr_poly
		(pts
			(xy 245.441216 -105.288842) (xy 245.405148 -105.253028) (xy 245.261384 -105.127298) (xy 245.189756 -105.19918)
			(xy 245.315486 -105.342944) (xy 245.3513 -105.378758)
		)
		(stroke
			(width 0)
			(type solid)
		)
		(fill yes)
		(layer "F.Cu")
		(net "M_E_ECC<0>")
	)
	(gr_poly
		(pts
			(xy 245.450106 -109.518704) (xy 245.324376 -109.37494) (xy 245.288308 -109.339126) (xy 245.198646 -109.428788)
			(xy 245.23446 -109.464856) (xy 245.378224 -109.590586)
		)
		(stroke
			(width 0)
			(type solid)
		)
		(fill yes)
		(layer "F.Cu")
		(net "M_E_ECC<7>")
	)
	(gr_poly
		(pts
			(xy 245.458996 -106.72572) (xy 245.333266 -106.58221) (xy 245.297452 -106.546142) (xy 245.207536 -106.636058)
			(xy 245.243604 -106.671872) (xy 245.387114 -106.797602)
		)
		(stroke
			(width 0)
			(type solid)
		)
		(fill yes)
		(layer "F.Cu")
		(net "M_E_DQS_DP<17>")
	)
	(gr_poly
		(pts
			(xy 245.466108 -45.41774) (xy 245.502176 -45.381926) (xy 245.376446 -45.256196) (xy 245.340378 -45.29201)
			(xy 245.293896 -45.389038) (xy 245.369334 -45.464476)
		)
		(stroke
			(width 0)
			(type solid)
		)
		(fill yes)
		(layer "F.Cu")
		(net "M_B_DQS_DN<17>")
	)
	(gr_poly
		(pts
			(xy 245.474998 -45.714158) (xy 245.521734 -45.617384) (xy 245.446296 -45.541946) (xy 245.349268 -45.588428)
			(xy 245.313454 -45.624496) (xy 245.439184 -45.750226)
		)
		(stroke
			(width 0)
			(type solid)
		)
		(fill yes)
		(layer "F.Cu")
		(net "M_B_DQS_DP<17>")
	)
	(gr_poly
		(pts
			(xy 245.50243 -44.160186) (xy 245.538498 -44.124372) (xy 245.412768 -43.998642) (xy 245.3767 -44.034456)
			(xy 245.329964 -44.131484) (xy 245.405402 -44.206922)
		)
		(stroke
			(width 0)
			(type solid)
		)
		(fill yes)
		(layer "F.Cu")
		(net "M_B_ECC<6>")
	)
	(gr_poly
		(pts
			(xy 245.51132 -44.456604) (xy 245.558056 -44.359576) (xy 245.482618 -44.284138) (xy 245.38559 -44.330874)
			(xy 245.349776 -44.366942) (xy 245.475506 -44.492672)
		)
		(stroke
			(width 0)
			(type solid)
		)
		(fill yes)
		(layer "F.Cu")
		(net "M_B_DQS_DP<8>")
	)
	(gr_poly
		(pts
			(xy 245.519702 -47.196248) (xy 245.555516 -47.160434) (xy 245.429786 -47.034704) (xy 245.393972 -47.070518)
			(xy 245.347236 -47.167546) (xy 245.422674 -47.242984)
		)
		(stroke
			(width 0)
			(type solid)
		)
		(fill yes)
		(layer "F.Cu")
		(net "M_B_ECC<5>")
	)
	(gr_poly
		(pts
			(xy 245.521988 -109.105446) (xy 245.48592 -109.069632) (xy 245.34241 -108.943902) (xy 245.270528 -109.015784)
			(xy 245.396258 -109.159548) (xy 245.432072 -109.195362)
		)
		(stroke
			(width 0)
			(type solid)
		)
		(fill yes)
		(layer "F.Cu")
		(net "M_E_ECC<7>")
	)
	(gr_poly
		(pts
			(xy 245.528592 -47.492666) (xy 245.575328 -47.395638) (xy 245.49989 -47.3202) (xy 245.402862 -47.366936)
			(xy 245.357904 -47.411894) (xy 245.483634 -47.537624)
		)
		(stroke
			(width 0)
			(type solid)
		)
		(fill yes)
		(layer "F.Cu")
		(net "M_B_ECC<4>")
	)
	(gr_poly
		(pts
			(xy 245.530878 -106.312716) (xy 245.495064 -106.276902) (xy 245.3513 -106.151172) (xy 245.279418 -106.2228)
			(xy 245.405148 -106.366564) (xy 245.441216 -106.402378)
		)
		(stroke
			(width 0)
			(type solid)
		)
		(fill yes)
		(layer "F.Cu")
		(net "M_E_DQS_DP<17>")
	)
	(gr_poly
		(pts
			(xy 245.538752 -42.902632) (xy 245.583456 -42.857674) (xy 245.457726 -42.731944) (xy 245.413022 -42.776902)
			(xy 245.366286 -42.87393) (xy 245.441724 -42.949368)
		)
		(stroke
			(width 0)
			(type solid)
		)
		(fill yes)
		(layer "F.Cu")
		(net "M_B_ECC<3>")
	)
	(gr_poly
		(pts
			(xy 245.547642 -43.19905) (xy 245.594378 -43.102022) (xy 245.51894 -43.026584) (xy 245.421912 -43.07332)
			(xy 245.386098 -43.109388) (xy 245.511574 -43.234864)
		)
		(stroke
			(width 0)
			(type solid)
		)
		(fill yes)
		(layer "F.Cu")
		(net "M_B_ECC<2>")
	)
	(gr_poly
		(pts
			(xy 245.548912 -107.749594) (xy 245.423182 -107.60583) (xy 245.387114 -107.570016) (xy 245.297452 -107.659678)
			(xy 245.333266 -107.695746) (xy 245.47703 -107.821476)
		)
		(stroke
			(width 0)
			(type solid)
		)
		(fill yes)
		(layer "F.Cu")
		(net "M_E_DQS_DN<8>")
	)
	(gr_poly
		(pts
			(xy 245.55577 -45.938694) (xy 245.591838 -45.90288) (xy 245.466108 -45.77715) (xy 245.43004 -45.812964)
			(xy 245.383558 -45.909992) (xy 245.458996 -45.98543)
		)
		(stroke
			(width 0)
			(type solid)
		)
		(fill yes)
		(layer "F.Cu")
		(net "M_B_DQS_DP<17>")
	)
	(gr_poly
		(pts
			(xy 245.557802 -104.95661) (xy 245.432072 -104.812846) (xy 245.396004 -104.777032) (xy 245.306342 -104.866694)
			(xy 245.342156 -104.902762) (xy 245.48592 -105.028492)
		)
		(stroke
			(width 0)
			(type solid)
		)
		(fill yes)
		(layer "F.Cu")
		(net "M_E_ECC<5>")
	)
	(gr_poly
		(pts
			(xy 245.56466 -46.235112) (xy 245.611396 -46.138338) (xy 245.535958 -46.0629) (xy 245.43893 -46.109636)
			(xy 245.403116 -46.14545) (xy 245.528846 -46.27118)
		)
		(stroke
			(width 0)
			(type solid)
		)
		(fill yes)
		(layer "F.Cu")
		(net "M_B_ECC<1>")
	)
	(gr_poly
		(pts
			(xy 245.592092 -44.68114) (xy 245.62816 -44.645326) (xy 245.50243 -44.519596) (xy 245.466362 -44.55541)
			(xy 245.419626 -44.652438) (xy 245.495064 -44.727876)
		)
		(stroke
			(width 0)
			(type solid)
		)
		(fill yes)
		(layer "F.Cu")
		(net "M_B_DQS_DP<8>")
	)
	(gr_poly
		(pts
			(xy 245.600982 -44.977558) (xy 245.647718 -44.88053) (xy 245.57228 -44.805092) (xy 245.475252 -44.851828)
			(xy 245.439438 -44.887896) (xy 245.565168 -45.013626)
		)
		(stroke
			(width 0)
			(type solid)
		)
		(fill yes)
		(layer "F.Cu")
		(net "M_B_DQS_DN<8>")
	)
	(gr_poly
		(pts
			(xy 245.620794 -110.137956) (xy 245.575836 -110.092998) (xy 245.432326 -109.967268) (xy 245.360444 -110.03915)
			(xy 245.486174 -110.182914) (xy 245.531132 -110.227618)
		)
		(stroke
			(width 0)
			(type solid)
		)
		(fill yes)
		(layer "F.Cu")
		(net "M_E_ECC<3>")
	)
	(gr_poly
		(pts
			(xy 245.620794 -107.336336) (xy 245.584726 -107.300522) (xy 245.440962 -107.174792) (xy 245.369334 -107.246674)
			(xy 245.495064 -107.390438) (xy 245.530878 -107.426252)
		)
		(stroke
			(width 0)
			(type solid)
		)
		(fill yes)
		(layer "F.Cu")
		(net "M_E_DQS_DN<8>")
	)
	(gr_poly
		(pts
			(xy 245.628414 -43.423586) (xy 245.664482 -43.387772) (xy 245.538752 -43.262042) (xy 245.502684 -43.297856)
			(xy 245.455948 -43.394884) (xy 245.531386 -43.470322)
		)
		(stroke
			(width 0)
			(type solid)
		)
		(fill yes)
		(layer "F.Cu")
		(net "M_B_ECC<2>")
	)
	(gr_poly
		(pts
			(xy 245.629684 -104.543352) (xy 245.593616 -104.507538) (xy 245.449852 -104.381808) (xy 245.378224 -104.45369)
			(xy 245.503954 -104.597454) (xy 245.539768 -104.633268)
		)
		(stroke
			(width 0)
			(type solid)
		)
		(fill yes)
		(layer "F.Cu")
		(net "M_E_ECC<5>")
	)
	(gr_poly
		(pts
			(xy 245.637304 -43.720004) (xy 245.68404 -43.622976) (xy 245.608602 -43.547538) (xy 245.511574 -43.594274)
			(xy 245.47576 -43.630342) (xy 245.60149 -43.756072)
		)
		(stroke
			(width 0)
			(type solid)
		)
		(fill yes)
		(layer "F.Cu")
		(net "M_B_ECC<7>")
	)
	(gr_poly
		(pts
			(xy 245.638574 -108.773214) (xy 245.512844 -108.629704) (xy 245.47703 -108.593636) (xy 245.387114 -108.683552)
			(xy 245.423182 -108.719366) (xy 245.566692 -108.845096)
		)
		(stroke
			(width 0)
			(type solid)
		)
		(fill yes)
		(layer "F.Cu")
		(net "M_E_ECC<6>")
	)
	(gr_poly
		(pts
			(xy 245.645686 -46.459648) (xy 245.6815 -46.423834) (xy 245.55577 -46.298104) (xy 245.519956 -46.333918)
			(xy 245.47322 -46.430946) (xy 245.548658 -46.506384)
		)
		(stroke
			(width 0)
			(type solid)
		)
		(fill yes)
		(layer "F.Cu")
		(net "M_B_ECC<1>")
	)
	(gr_poly
		(pts
			(xy 245.647718 -105.980484) (xy 245.521988 -105.83672) (xy 245.48592 -105.800906) (xy 245.396258 -105.890568)
			(xy 245.432072 -105.926636) (xy 245.575836 -106.052366)
		)
		(stroke
			(width 0)
			(type solid)
		)
		(fill yes)
		(layer "F.Cu")
		(net "M_E_ECC<1>")
	)
	(gr_poly
		(pts
			(xy 245.654322 -46.75632) (xy 245.701058 -46.659292) (xy 245.62562 -46.583854) (xy 245.528592 -46.63059)
			(xy 245.492778 -46.666404) (xy 245.618508 -46.792134)
		)
		(stroke
			(width 0)
			(type solid)
		)
		(fill yes)
		(layer "F.Cu")
		(net "M_B_ECC<0>")
	)
	(gr_poly
		(pts
			(xy 245.681754 -45.202094) (xy 245.717822 -45.16628) (xy 245.592092 -45.04055) (xy 245.556024 -45.076364)
			(xy 245.509542 -45.173392) (xy 245.58498 -45.24883)
		)
		(stroke
			(width 0)
			(type solid)
		)
		(fill yes)
		(layer "F.Cu")
		(net "M_B_DQS_DN<8>")
	)
	(gr_poly
		(pts
			(xy 245.690644 -45.498512) (xy 245.73738 -45.401738) (xy 245.661942 -45.3263) (xy 245.564914 -45.372782)
			(xy 245.5291 -45.40885) (xy 245.65483 -45.53458)
		)
		(stroke
			(width 0)
			(type solid)
		)
		(fill yes)
		(layer "F.Cu")
		(net "M_B_DQS_DN<17>")
	)
	(gr_poly
		(pts
			(xy 245.710456 -108.36021) (xy 245.674642 -108.324142) (xy 245.530878 -108.198412) (xy 245.458996 -108.270294)
			(xy 245.584726 -108.414058) (xy 245.620794 -108.449872)
		)
		(stroke
			(width 0)
			(type solid)
		)
		(fill yes)
		(layer "F.Cu")
		(net "M_E_ECC<6>")
	)
	(gr_poly
		(pts
			(xy 245.718076 -43.94454) (xy 245.754144 -43.908726) (xy 245.628414 -43.782996) (xy 245.592346 -43.81881)
			(xy 245.54561 -43.915838) (xy 245.621048 -43.991276)
		)
		(stroke
			(width 0)
			(type solid)
		)
		(fill yes)
		(layer "F.Cu")
		(net "M_B_ECC<7>")
	)
	(gr_poly
		(pts
			(xy 245.7196 -105.567226) (xy 245.683532 -105.531412) (xy 245.539768 -105.405682) (xy 245.46814 -105.477564)
			(xy 245.59387 -105.621328) (xy 245.629684 -105.657142)
		)
		(stroke
			(width 0)
			(type solid)
		)
		(fill yes)
		(layer "F.Cu")
		(net "M_E_ECC<1>")
	)
	(gr_poly
		(pts
			(xy 245.726966 -44.240958) (xy 245.773702 -44.14393) (xy 245.698264 -44.068492) (xy 245.601236 -44.115228)
			(xy 245.565422 -44.151296) (xy 245.691152 -44.277026)
		)
		(stroke
			(width 0)
			(type solid)
		)
		(fill yes)
		(layer "F.Cu")
		(net "M_B_ECC<6>")
	)
	(gr_poly
		(pts
			(xy 245.72849 -109.797088) (xy 245.60276 -109.653324) (xy 245.566692 -109.61751) (xy 245.47703 -109.707172)
			(xy 245.512844 -109.74324) (xy 245.656608 -109.86897)
		)
		(stroke
			(width 0)
			(type solid)
		)
		(fill yes)
		(layer "F.Cu")
		(net "M_E_ECC<2>")
	)
	(gr_poly
		(pts
			(xy 245.735348 -46.980602) (xy 245.771162 -46.944788) (xy 245.645432 -46.819058) (xy 245.609618 -46.854872)
			(xy 245.562882 -46.9519) (xy 245.63832 -47.027338)
		)
		(stroke
			(width 0)
			(type solid)
		)
		(fill yes)
		(layer "F.Cu")
		(net "M_B_ECC<0>")
	)
	(gr_poly
		(pts
			(xy 245.73738 -107.004104) (xy 245.61165 -106.860594) (xy 245.575836 -106.824526) (xy 245.48592 -106.914442)
			(xy 245.521988 -106.950256) (xy 245.665498 -107.075986)
		)
		(stroke
			(width 0)
			(type solid)
		)
		(fill yes)
		(layer "F.Cu")
		(net "M_E_DQS_DN<17>")
	)
	(gr_poly
		(pts
			(xy 245.743984 -47.277274) (xy 245.79072 -47.180246) (xy 245.715282 -47.104808) (xy 245.618508 -47.151544)
			(xy 245.58244 -47.187358) (xy 245.70817 -47.313088)
		)
		(stroke
			(width 0)
			(type solid)
		)
		(fill yes)
		(layer "F.Cu")
		(net "M_B_ECC<5>")
	)
	(gr_poly
		(pts
			(xy 245.74627 -104.21112) (xy 245.62054 -104.06761) (xy 245.575582 -104.022652) (xy 245.48592 -104.112314)
			(xy 245.530624 -104.157272) (xy 245.674388 -104.283002)
		)
		(stroke
			(width 0)
			(type solid)
		)
		(fill yes)
		(layer "F.Cu")
		(net "M_E_ECC<4>")
	)
	(gr_poly
		(pts
			(xy 245.771416 -45.723048) (xy 245.807484 -45.687234) (xy 245.681754 -45.561504) (xy 245.645686 -45.597318)
			(xy 245.599204 -45.694346) (xy 245.674642 -45.769784)
		)
		(stroke
			(width 0)
			(type solid)
		)
		(fill yes)
		(layer "F.Cu")
		(net "M_B_DQS_DN<17>")
	)
	(gr_poly
		(pts
			(xy 245.780306 -46.019466) (xy 245.827042 -45.922692) (xy 245.751604 -45.847254) (xy 245.654576 -45.89399)
			(xy 245.618762 -45.929804) (xy 245.744492 -46.055534)
		)
		(stroke
			(width 0)
			(type solid)
		)
		(fill yes)
		(layer "F.Cu")
		(net "M_B_DQS_DP<17>")
	)
	(gr_poly
		(pts
			(xy 245.800372 -109.38383) (xy 245.764304 -109.348016) (xy 245.620794 -109.222286) (xy 245.548912 -109.294168)
			(xy 245.674642 -109.437932) (xy 245.710456 -109.473746)
		)
		(stroke
			(width 0)
			(type solid)
		)
		(fill yes)
		(layer "F.Cu")
		(net "M_E_ECC<2>")
	)
	(gr_poly
		(pts
			(xy 245.807738 -44.465494) (xy 245.843806 -44.42968) (xy 245.718076 -44.30395) (xy 245.682008 -44.339764)
			(xy 245.635272 -44.436792) (xy 245.71071 -44.51223)
		)
		(stroke
			(width 0)
			(type solid)
		)
		(fill yes)
		(layer "F.Cu")
		(net "M_B_ECC<6>")
	)
	(gr_poly
		(pts
			(xy 245.809262 -106.5911) (xy 245.773448 -106.555286) (xy 245.629684 -106.429556) (xy 245.557802 -106.501184)
			(xy 245.683532 -106.644948) (xy 245.7196 -106.680762)
		)
		(stroke
			(width 0)
			(type solid)
		)
		(fill yes)
		(layer "F.Cu")
		(net "M_E_DQS_DN<17>")
	)
	(gr_poly
		(pts
			(xy 245.816628 -44.761912) (xy 245.863364 -44.664884) (xy 245.787926 -44.589446) (xy 245.690898 -44.636182)
			(xy 245.655084 -44.67225) (xy 245.780814 -44.79798)
		)
		(stroke
			(width 0)
			(type solid)
		)
		(fill yes)
		(layer "F.Cu")
		(net "M_B_DQS_DP<8>")
	)
	(gr_poly
		(pts
			(xy 245.82501 -47.50181) (xy 245.860824 -47.465742) (xy 245.735094 -47.340012) (xy 245.69928 -47.37608)
			(xy 245.652544 -47.472854) (xy 245.727982 -47.548292)
		)
		(stroke
			(width 0)
			(type solid)
		)
		(fill yes)
		(layer "F.Cu")
		(net "M_B_ECC<5>")
	)
	(gr_poly
		(pts
			(xy 245.827296 -108.027978) (xy 245.701566 -107.884214) (xy 245.665498 -107.8484) (xy 245.575836 -107.938062)
			(xy 245.61165 -107.97413) (xy 245.755414 -108.09986)
		)
		(stroke
			(width 0)
			(type solid)
		)
		(fill yes)
		(layer "F.Cu")
		(net "M_E_DQS_DP<8>")
	)
	(gr_poly
		(pts
			(xy 245.8339 -47.797974) (xy 245.880636 -47.7012) (xy 245.805198 -47.625762) (xy 245.70817 -47.672244)
			(xy 245.663212 -47.717202) (xy 245.788942 -47.842932)
		)
		(stroke
			(width 0)
			(type solid)
		)
		(fill yes)
		(layer "F.Cu")
		(net "M_B_ECC<4>")
	)
	(gr_poly
		(pts
			(xy 245.836186 -105.234994) (xy 245.710456 -105.091484) (xy 245.674642 -105.055416) (xy 245.584726 -105.145332)
			(xy 245.620794 -105.181146) (xy 245.764304 -105.306876)
		)
		(stroke
			(width 0)
			(type solid)
		)
		(fill yes)
		(layer "F.Cu")
		(net "M_E_ECC<0>")
	)
	(gr_poly
		(pts
			(xy 245.84406 -43.20794) (xy 245.889018 -43.163236) (xy 245.763288 -43.037506) (xy 245.71833 -43.08221)
			(xy 245.671594 -43.179238) (xy 245.747032 -43.254676)
		)
		(stroke
			(width 0)
			(type solid)
		)
		(fill yes)
		(layer "F.Cu")
		(net "M_B_ECC<3>")
	)
	(gr_poly
		(pts
			(xy 245.85295 -43.504358) (xy 245.899686 -43.40733) (xy 245.824248 -43.331892) (xy 245.72722 -43.378628)
			(xy 245.691406 -43.414696) (xy 245.817136 -43.540426)
		)
		(stroke
			(width 0)
			(type solid)
		)
		(fill yes)
		(layer "F.Cu")
		(net "M_B_ECC<2>")
	)
	(gr_poly
		(pts
			(xy 245.861332 -46.244002) (xy 245.897146 -46.208188) (xy 245.771416 -46.082458) (xy 245.735602 -46.118272)
			(xy 245.688866 -46.2153) (xy 245.764304 -46.290738)
		)
		(stroke
			(width 0)
			(type solid)
		)
		(fill yes)
		(layer "F.Cu")
		(net "M_B_DQS_DP<17>")
	)
	(gr_poly
		(pts
			(xy 245.869968 -46.540674) (xy 245.916704 -46.443646) (xy 245.841266 -46.368208) (xy 245.744238 -46.414944)
			(xy 245.708424 -46.450758) (xy 245.834154 -46.576488)
		)
		(stroke
			(width 0)
			(type solid)
		)
		(fill yes)
		(layer "F.Cu")
		(net "M_B_ECC<1>")
	)
	(gr_poly
		(pts
			(xy 245.894606 -53.4035) (xy 245.850156 -53.4035) (xy 245.679976 -53.4924) (xy 245.679976 -53.71338)
			(xy 245.850156 -53.80228) (xy 245.894606 -53.80228)
		)
		(stroke
			(width 0)
			(type solid)
		)
		(fill yes)
		(layer "F.Cu")
		(net "M_B_ECC<4>")
	)
	(gr_poly
		(pts
			(xy 245.8974 -44.986448) (xy 245.933468 -44.950634) (xy 245.807738 -44.824904) (xy 245.77167 -44.860718)
			(xy 245.725188 -44.957746) (xy 245.800626 -45.033184)
		)
		(stroke
			(width 0)
			(type solid)
		)
		(fill yes)
		(layer "F.Cu")
		(net "M_B_DQS_DP<8>")
	)
	(gr_poly
		(pts
			(xy 245.899178 -107.61472) (xy 245.86311 -107.578906) (xy 245.719346 -107.453176) (xy 245.647718 -107.525058)
			(xy 245.773448 -107.668822) (xy 245.809262 -107.704636)
		)
		(stroke
			(width 0)
			(type solid)
		)
		(fill yes)
		(layer "F.Cu")
		(net "M_E_DQS_DP<8>")
	)
	(gr_poly
		(pts
			(xy 245.90629 -45.282866) (xy 245.953026 -45.186092) (xy 245.877588 -45.110654) (xy 245.78056 -45.157136)
			(xy 245.744746 -45.193204) (xy 245.870476 -45.318934)
		)
		(stroke
			(width 0)
			(type solid)
		)
		(fill yes)
		(layer "F.Cu")
		(net "M_B_DQS_DN<8>")
	)
	(gr_poly
		(pts
			(xy 245.908068 -104.82199) (xy 245.872254 -104.786176) (xy 245.72849 -104.660446) (xy 245.656608 -104.732074)
			(xy 245.782338 -104.875838) (xy 245.818152 -104.911906)
		)
		(stroke
			(width 0)
			(type solid)
		)
		(fill yes)
		(layer "F.Cu")
		(net "M_E_ECC<0>")
	)
	(gr_poly
		(pts
			(xy 245.916958 -109.051598) (xy 245.791228 -108.908088) (xy 245.755414 -108.87202) (xy 245.665498 -108.961936)
			(xy 245.701566 -108.99775) (xy 245.845076 -109.12348)
		)
		(stroke
			(width 0)
			(type solid)
		)
		(fill yes)
		(layer "F.Cu")
		(net "M_E_ECC<7>")
	)
	(gr_poly
		(pts
			(xy 245.926102 -106.258868) (xy 245.800372 -106.115104) (xy 245.764304 -106.07929) (xy 245.674642 -106.168952)
			(xy 245.710456 -106.20502) (xy 245.85422 -106.33075)
		)
		(stroke
			(width 0)
			(type solid)
		)
		(fill yes)
		(layer "F.Cu")
		(net "M_E_DQS_DP<17>")
	)
	(gr_poly
		(pts
			(xy 245.933722 -43.728894) (xy 245.96979 -43.69308) (xy 245.84406 -43.56735) (xy 245.807992 -43.603164)
			(xy 245.761256 -43.700192) (xy 245.836694 -43.77563)
		)
		(stroke
			(width 0)
			(type solid)
		)
		(fill yes)
		(layer "F.Cu")
		(net "M_B_ECC<2>")
	)
	(gr_poly
		(pts
			(xy 245.942612 -44.025312) (xy 245.989348 -43.928284) (xy 245.91391 -43.852846) (xy 245.816882 -43.899582)
			(xy 245.781068 -43.93565) (xy 245.906798 -44.06138)
		)
		(stroke
			(width 0)
			(type solid)
		)
		(fill yes)
		(layer "F.Cu")
		(net "M_B_ECC<7>")
	)
	(gr_poly
		(pts
			(xy 245.950994 -46.764956) (xy 245.986808 -46.729142) (xy 245.861078 -46.603412) (xy 245.825264 -46.639226)
			(xy 245.778528 -46.736254) (xy 245.853966 -46.811692)
		)
		(stroke
			(width 0)
			(type solid)
		)
		(fill yes)
		(layer "F.Cu")
		(net "M_B_ECC<1>")
	)
	(gr_poly
		(pts
			(xy 245.95963 -47.061628) (xy 246.006366 -46.9646) (xy 245.930928 -46.889162) (xy 245.834154 -46.935898)
			(xy 245.798086 -46.971712) (xy 245.923816 -47.097442)
		)
		(stroke
			(width 0)
			(type solid)
		)
		(fill yes)
		(layer "F.Cu")
		(net "M_B_ECC<0>")
	)
	(gr_poly
		(pts
			(xy 245.987062 -45.507402) (xy 246.02313 -45.471588) (xy 245.8974 -45.345858) (xy 245.861332 -45.381672)
			(xy 245.81485 -45.4787) (xy 245.890288 -45.554138)
		)
		(stroke
			(width 0)
			(type solid)
		)
		(fill yes)
		(layer "F.Cu")
		(net "M_B_DQS_DN<8>")
	)
	(gr_poly
		(pts
			(xy 245.98884 -108.638594) (xy 245.953026 -108.602526) (xy 245.809262 -108.476796) (xy 245.73738 -108.548678)
			(xy 245.86311 -108.692442) (xy 245.899178 -108.728256)
		)
		(stroke
			(width 0)
			(type solid)
		)
		(fill yes)
		(layer "F.Cu")
		(net "M_E_ECC<7>")
	)
	(gr_poly
		(pts
			(xy 245.995952 -45.80382) (xy 246.042688 -45.707046) (xy 245.96725 -45.631608) (xy 245.870222 -45.678344)
			(xy 245.834408 -45.714158) (xy 245.960138 -45.839888)
		)
		(stroke
			(width 0)
			(type solid)
		)
		(fill yes)
		(layer "F.Cu")
		(net "M_B_DQS_DN<17>")
	)
	(gr_poly
		(pts
			(xy 245.997984 -105.84561) (xy 245.961916 -105.809796) (xy 245.818152 -105.684066) (xy 245.746524 -105.755948)
			(xy 245.872254 -105.899712) (xy 245.908068 -105.935526)
		)
		(stroke
			(width 0)
			(type solid)
		)
		(fill yes)
		(layer "F.Cu")
		(net "M_E_DQS_DP<17>")
	)
	(gr_poly
		(pts
			(xy 246.015764 -107.282488) (xy 245.890034 -107.138978) (xy 245.85422 -107.10291) (xy 245.764304 -107.192826)
			(xy 245.800372 -107.22864) (xy 245.943882 -107.35437)
		)
		(stroke
			(width 0)
			(type solid)
		)
		(fill yes)
		(layer "F.Cu")
		(net "M_E_DQS_DN<8>")
	)
	(gr_poly
		(pts
			(xy 246.023384 -44.249848) (xy 246.059452 -44.214034) (xy 245.933722 -44.088304) (xy 245.897654 -44.124118)
			(xy 245.850918 -44.221146) (xy 245.926356 -44.296584)
		)
		(stroke
			(width 0)
			(type solid)
		)
		(fill yes)
		(layer "F.Cu")
		(net "M_B_ECC<7>")
	)
	(gr_poly
		(pts
			(xy 246.024654 -104.489504) (xy 245.898924 -104.345994) (xy 245.86311 -104.309926) (xy 245.773194 -104.399842)
			(xy 245.809262 -104.435656) (xy 245.952772 -104.561386)
		)
		(stroke
			(width 0)
			(type solid)
		)
		(fill yes)
		(layer "F.Cu")
		(net "M_E_ECC<5>")
	)
	(gr_poly
		(pts
			(xy 246.032274 -44.546266) (xy 246.07901 -44.449238) (xy 246.003572 -44.3738) (xy 245.906544 -44.420536)
			(xy 245.87073 -44.456604) (xy 245.99646 -44.582334)
		)
		(stroke
			(width 0)
			(type solid)
		)
		(fill yes)
		(layer "F.Cu")
		(net "M_B_ECC<6>")
	)
	(gr_poly
		(pts
			(xy 246.040656 -47.286164) (xy 246.07647 -47.250096) (xy 245.95074 -47.124366) (xy 245.914926 -47.160434)
			(xy 245.86819 -47.257208) (xy 245.943628 -47.332646)
		)
		(stroke
			(width 0)
			(type solid)
		)
		(fill yes)
		(layer "F.Cu")
		(net "M_B_ECC<0>")
	)
	(gr_poly
		(pts
			(xy 246.049546 -47.582582) (xy 246.096028 -47.485554) (xy 246.02059 -47.410116) (xy 245.923816 -47.456852)
			(xy 245.887748 -47.492666) (xy 246.013478 -47.618396)
		)
		(stroke
			(width 0)
			(type solid)
		)
		(fill yes)
		(layer "F.Cu")
		(net "M_B_ECC<5>")
	)
	(gr_poly
		(pts
			(xy 246.076978 -46.028356) (xy 246.112792 -45.992542) (xy 245.987062 -45.866812) (xy 245.951248 -45.902626)
			(xy 245.904512 -45.999654) (xy 245.97995 -46.075092)
		)
		(stroke
			(width 0)
			(type solid)
		)
		(fill yes)
		(layer "F.Cu")
		(net "M_B_DQS_DN<17>")
	)
	(gr_poly
		(pts
			(xy 246.085614 -46.325028) (xy 246.13235 -46.228) (xy 246.056912 -46.152562) (xy 245.959884 -46.199298)
			(xy 245.92407 -46.235112) (xy 246.0498 -46.360842)
		)
		(stroke
			(width 0)
			(type solid)
		)
		(fill yes)
		(layer "F.Cu")
		(net "M_B_DQS_DP<17>")
	)
	(gr_poly
		(pts
			(xy 246.087646 -109.671104) (xy 246.042688 -109.626146) (xy 245.899178 -109.500416) (xy 245.827296 -109.572298)
			(xy 245.953026 -109.716062) (xy 245.997984 -109.760766)
		)
		(stroke
			(width 0)
			(type solid)
		)
		(fill yes)
		(layer "F.Cu")
		(net "M_E_ECC<3>")
	)
	(gr_poly
		(pts
			(xy 246.087646 -106.869484) (xy 246.051832 -106.83367) (xy 245.908068 -106.70794) (xy 245.836186 -106.779568)
			(xy 245.961916 -106.923332) (xy 245.997984 -106.959146)
		)
		(stroke
			(width 0)
			(type solid)
		)
		(fill yes)
		(layer "F.Cu")
		(net "M_E_DQS_DN<8>")
	)
	(gr_poly
		(pts
			(xy 246.096536 -104.0765) (xy 246.060722 -104.040686) (xy 245.916958 -103.914956) (xy 245.845076 -103.986584)
			(xy 245.970806 -104.130348) (xy 246.00662 -104.166416)
		)
		(stroke
			(width 0)
			(type solid)
		)
		(fill yes)
		(layer "F.Cu")
		(net "M_E_ECC<5>")
	)
	(gr_poly
		(pts
			(xy 246.10568 -108.306362) (xy 245.97995 -108.162598) (xy 245.943882 -108.126784) (xy 245.85422 -108.216446)
			(xy 245.890034 -108.252514) (xy 246.033798 -108.378244)
		)
		(stroke
			(width 0)
			(type solid)
		)
		(fill yes)
		(layer "F.Cu")
		(net "M_E_ECC<6>")
	)
	(gr_poly
		(pts
			(xy 246.113046 -44.770802) (xy 246.149114 -44.734988) (xy 246.023384 -44.609258) (xy 245.987316 -44.645072)
			(xy 245.940834 -44.7421) (xy 246.016272 -44.817538)
		)
		(stroke
			(width 0)
			(type solid)
		)
		(fill yes)
		(layer "F.Cu")
		(net "M_B_ECC<6>")
	)
	(gr_poly
		(pts
			(xy 246.11457 -105.513378) (xy 245.98884 -105.369868) (xy 245.953026 -105.3338) (xy 245.86311 -105.423716)
			(xy 245.899178 -105.45953) (xy 246.042688 -105.58526)
		)
		(stroke
			(width 0)
			(type solid)
		)
		(fill yes)
		(layer "F.Cu")
		(net "M_E_ECC<1>")
	)
	(gr_poly
		(pts
			(xy 246.121936 -45.06722) (xy 246.168672 -44.970446) (xy 246.093234 -44.895008) (xy 245.996206 -44.94149)
			(xy 245.960392 -44.977558) (xy 246.086122 -45.103288)
		)
		(stroke
			(width 0)
			(type solid)
		)
		(fill yes)
		(layer "F.Cu")
		(net "M_B_DQS_DP<8>")
	)
	(gr_poly
		(pts
			(xy 246.130318 -47.807118) (xy 246.166132 -47.77105) (xy 246.040402 -47.64532) (xy 246.004588 -47.681388)
			(xy 245.957852 -47.778162) (xy 246.03329 -47.8536)
		)
		(stroke
			(width 0)
			(type solid)
		)
		(fill yes)
		(layer "F.Cu")
		(net "M_B_ECC<5>")
	)
	(gr_poly
		(pts
			(xy 246.139208 -48.103282) (xy 246.185944 -48.006508) (xy 246.110506 -47.93107) (xy 246.013478 -47.977552)
			(xy 245.96852 -48.02251) (xy 246.09425 -48.14824)
		)
		(stroke
			(width 0)
			(type solid)
		)
		(fill yes)
		(layer "F.Cu")
		(net "M_B_ECC<4>")
	)
	(gr_poly
		(pts
			(xy 246.149368 -43.513248) (xy 246.194326 -43.468544) (xy 246.068596 -43.342814) (xy 246.023638 -43.387518)
			(xy 245.976902 -43.484546) (xy 246.05234 -43.559984)
		)
		(stroke
			(width 0)
			(type solid)
		)
		(fill yes)
		(layer "F.Cu")
		(net "M_B_ECC<3>")
	)
	(gr_poly
		(pts
			(xy 246.158258 -43.809666) (xy 246.204994 -43.712638) (xy 246.129556 -43.6372) (xy 246.032528 -43.683936)
			(xy 245.996714 -43.720004) (xy 246.122444 -43.845734)
		)
		(stroke
			(width 0)
			(type solid)
		)
		(fill yes)
		(layer "F.Cu")
		(net "M_B_ECC<2>")
	)
	(gr_poly
		(pts
			(xy 246.16664 -46.54931) (xy 246.202454 -46.513496) (xy 246.076724 -46.387766) (xy 246.04091 -46.42358)
			(xy 245.994174 -46.520608) (xy 246.069612 -46.596046)
		)
		(stroke
			(width 0)
			(type solid)
		)
		(fill yes)
		(layer "F.Cu")
		(net "M_B_DQS_DP<17>")
	)
	(gr_poly
		(pts
			(xy 246.175276 -46.845982) (xy 246.222012 -46.748954) (xy 246.146574 -46.673516) (xy 246.0498 -46.720252)
			(xy 246.013732 -46.756066) (xy 246.139462 -46.881796)
		)
		(stroke
			(width 0)
			(type solid)
		)
		(fill yes)
		(layer "F.Cu")
		(net "M_B_ECC<1>")
	)
	(gr_poly
		(pts
			(xy 246.177562 -107.893104) (xy 246.141494 -107.85729) (xy 245.99773 -107.73156) (xy 245.926102 -107.803442)
			(xy 246.051832 -107.947206) (xy 246.087646 -107.98302)
		)
		(stroke
			(width 0)
			(type solid)
		)
		(fill yes)
		(layer "F.Cu")
		(net "M_E_ECC<6>")
	)
	(gr_poly
		(pts
			(xy 246.186452 -105.100374) (xy 246.150638 -105.06456) (xy 246.006874 -104.93883) (xy 245.934992 -105.010458)
			(xy 246.060722 -105.154222) (xy 246.096536 -105.19029)
		)
		(stroke
			(width 0)
			(type solid)
		)
		(fill yes)
		(layer "F.Cu")
		(net "M_E_ECC<1>")
	)
	(gr_poly
		(pts
			(xy 246.195342 -109.329982) (xy 246.069612 -109.186472) (xy 246.033798 -109.150404) (xy 245.943882 -109.24032)
			(xy 245.97995 -109.276134) (xy 246.12346 -109.401864)
		)
		(stroke
			(width 0)
			(type solid)
		)
		(fill yes)
		(layer "F.Cu")
		(net "M_E_ECC<2>")
	)
	(gr_poly
		(pts
			(xy 246.202708 -45.291756) (xy 246.238776 -45.255942) (xy 246.113046 -45.130212) (xy 246.076978 -45.166026)
			(xy 246.030496 -45.263054) (xy 246.105934 -45.338492)
		)
		(stroke
			(width 0)
			(type solid)
		)
		(fill yes)
		(layer "F.Cu")
		(net "M_B_DQS_DP<8>")
	)
	(gr_poly
		(pts
			(xy 246.204486 -106.537252) (xy 246.078756 -106.393488) (xy 246.042688 -106.357674) (xy 245.953026 -106.447336)
			(xy 245.98884 -106.483404) (xy 246.132604 -106.609134)
		)
		(stroke
			(width 0)
			(type solid)
		)
		(fill yes)
		(layer "F.Cu")
		(net "M_E_DQS_DN<17>")
	)
	(gr_poly
		(pts
			(xy 246.211598 -45.588174) (xy 246.258334 -45.4914) (xy 246.182896 -45.415962) (xy 246.085868 -45.462698)
			(xy 246.050054 -45.498512) (xy 246.175784 -45.624242)
		)
		(stroke
			(width 0)
			(type solid)
		)
		(fill yes)
		(layer "F.Cu")
		(net "M_B_DQS_DN<8>")
	)
	(gr_poly
		(pts
			(xy 246.213122 -103.744268) (xy 246.087646 -103.600504) (xy 246.042688 -103.555546) (xy 245.952772 -103.645462)
			(xy 245.99773 -103.69042) (xy 246.141494 -103.81615)
		)
		(stroke
			(width 0)
			(type solid)
		)
		(fill yes)
		(layer "F.Cu")
		(net "M_E_ECC<4>")
	)
	(gr_poly
		(pts
			(xy 246.23903 -44.034202) (xy 246.275098 -43.998388) (xy 246.149368 -43.872658) (xy 246.1133 -43.908472)
			(xy 246.066564 -44.0055) (xy 246.142002 -44.080938)
		)
		(stroke
			(width 0)
			(type solid)
		)
		(fill yes)
		(layer "F.Cu")
		(net "M_B_ECC<2>")
	)
	(gr_poly
		(pts
			(xy 246.24792 -44.33062) (xy 246.294656 -44.233592) (xy 246.219218 -44.158154) (xy 246.12219 -44.20489)
			(xy 246.086376 -44.240958) (xy 246.212106 -44.366688)
		)
		(stroke
			(width 0)
			(type solid)
		)
		(fill yes)
		(layer "F.Cu")
		(net "M_B_ECC<7>")
	)
	(gr_poly
		(pts
			(xy 246.256302 -47.070518) (xy 246.292116 -47.03445) (xy 246.166386 -46.90872) (xy 246.130572 -46.944788)
			(xy 246.083836 -47.041562) (xy 246.159274 -47.117)
		)
		(stroke
			(width 0)
			(type solid)
		)
		(fill yes)
		(layer "F.Cu")
		(net "M_B_ECC<1>")
	)
	(gr_poly
		(pts
			(xy 246.265192 -47.366936) (xy 246.311674 -47.269908) (xy 246.236236 -47.19447) (xy 246.139462 -47.241206)
			(xy 246.103394 -47.27702) (xy 246.229124 -47.40275)
		)
		(stroke
			(width 0)
			(type solid)
		)
		(fill yes)
		(layer "F.Cu")
		(net "M_B_ECC<0>")
	)
	(gr_poly
		(pts
			(xy 246.267224 -108.916978) (xy 246.23141 -108.88091) (xy 246.087646 -108.75518) (xy 246.015764 -108.827062)
			(xy 246.141494 -108.970826) (xy 246.177562 -109.00664)
		)
		(stroke
			(width 0)
			(type solid)
		)
		(fill yes)
		(layer "F.Cu")
		(net "M_E_ECC<2>")
	)
	(gr_poly
		(pts
			(xy 246.276368 -106.123994) (xy 246.2403 -106.08818) (xy 246.096536 -105.96245) (xy 246.024908 -106.034332)
			(xy 246.150638 -106.178096) (xy 246.186452 -106.21391)
		)
		(stroke
			(width 0)
			(type solid)
		)
		(fill yes)
		(layer "F.Cu")
		(net "M_E_DQS_DN<17>")
	)
	(gr_poly
		(pts
			(xy 246.292624 -45.81271) (xy 246.328438 -45.776896) (xy 246.202708 -45.651166) (xy 246.166894 -45.68698)
			(xy 246.120158 -45.784008) (xy 246.195596 -45.859446)
		)
		(stroke
			(width 0)
			(type solid)
		)
		(fill yes)
		(layer "F.Cu")
		(net "M_B_DQS_DN<8>")
	)
	(gr_poly
		(pts
			(xy 246.294148 -107.560872) (xy 246.168418 -107.417362) (xy 246.132604 -107.381294) (xy 246.042688 -107.47121)
			(xy 246.078756 -107.507024) (xy 246.222266 -107.632754)
		)
		(stroke
			(width 0)
			(type solid)
		)
		(fill yes)
		(layer "F.Cu")
		(net "M_E_DQS_DP<8>")
	)
	(gr_poly
		(pts
			(xy 246.30126 -46.109382) (xy 246.347996 -46.012354) (xy 246.272558 -45.936916) (xy 246.17553 -45.983652)
			(xy 246.139716 -46.019466) (xy 246.265446 -46.145196)
		)
		(stroke
			(width 0)
			(type solid)
		)
		(fill yes)
		(layer "F.Cu")
		(net "M_B_DQS_DN<17>")
	)
	(gr_poly
		(pts
			(xy 246.303292 -104.768142) (xy 246.177562 -104.624378) (xy 246.141494 -104.588564) (xy 246.051832 -104.678226)
			(xy 246.087646 -104.714294) (xy 246.23141 -104.840024)
		)
		(stroke
			(width 0)
			(type solid)
		)
		(fill yes)
		(layer "F.Cu")
		(net "M_E_ECC<0>")
	)
	(gr_poly
		(pts
			(xy 246.328692 -44.555156) (xy 246.36476 -44.519342) (xy 246.23903 -44.393612) (xy 246.202962 -44.429426)
			(xy 246.15648 -44.526454) (xy 246.231918 -44.601892)
		)
		(stroke
			(width 0)
			(type solid)
		)
		(fill yes)
		(layer "F.Cu")
		(net "M_B_ECC<7>")
	)
	(gr_poly
		(pts
			(xy 246.337582 -44.851574) (xy 246.384318 -44.7548) (xy 246.30888 -44.679362) (xy 246.211852 -44.725844)
			(xy 246.176038 -44.761912) (xy 246.301768 -44.887642)
		)
		(stroke
			(width 0)
			(type solid)
		)
		(fill yes)
		(layer "F.Cu")
		(net "M_B_ECC<6>")
	)
	(gr_poly
		(pts
			(xy 246.345964 -47.591472) (xy 246.381778 -47.555404) (xy 246.256048 -47.429674) (xy 246.220234 -47.465742)
			(xy 246.173498 -47.562516) (xy 246.248936 -47.637954)
		)
		(stroke
			(width 0)
			(type solid)
		)
		(fill yes)
		(layer "F.Cu")
		(net "M_B_ECC<0>")
	)
	(gr_poly
		(pts
			(xy 246.354854 -47.88789) (xy 246.40159 -47.790862) (xy 246.326152 -47.715424) (xy 246.229124 -47.76216)
			(xy 246.193056 -47.797974) (xy 246.318786 -47.923704)
		)
		(stroke
			(width 0)
			(type solid)
		)
		(fill yes)
		(layer "F.Cu")
		(net "M_B_ECC<5>")
	)
	(gr_poly
		(pts
			(xy 246.36603 -107.147868) (xy 246.330216 -107.112054) (xy 246.186452 -106.986324) (xy 246.11457 -107.057952)
			(xy 246.2403 -107.201716) (xy 246.276368 -107.23753)
		)
		(stroke
			(width 0)
			(type solid)
		)
		(fill yes)
		(layer "F.Cu")
		(net "M_E_DQS_DP<8>")
	)
	(gr_poly
		(pts
			(xy 246.37492 -104.355138) (xy 246.339106 -104.31907) (xy 246.195342 -104.19334) (xy 246.123714 -104.265222)
			(xy 246.249444 -104.408986) (xy 246.285258 -104.4448)
		)
		(stroke
			(width 0)
			(type solid)
		)
		(fill yes)
		(layer "F.Cu")
		(net "M_E_ECC<0>")
	)
	(gr_poly
		(pts
			(xy 246.382286 -46.333664) (xy 246.4181 -46.29785) (xy 246.29237 -46.17212) (xy 246.256556 -46.207934)
			(xy 246.20982 -46.304962) (xy 246.285258 -46.3804)
		)
		(stroke
			(width 0)
			(type solid)
		)
		(fill yes)
		(layer "F.Cu")
		(net "M_B_DQS_DN<17>")
	)
	(gr_poly
		(pts
			(xy 246.384064 -108.584746) (xy 246.258334 -108.440982) (xy 246.222266 -108.405168) (xy 246.132604 -108.49483)
			(xy 246.168418 -108.530898) (xy 246.312182 -108.656628)
		)
		(stroke
			(width 0)
			(type solid)
		)
		(fill yes)
		(layer "F.Cu")
		(net "M_E_ECC<7>")
	)
	(gr_poly
		(pts
			(xy 246.390922 -46.630336) (xy 246.437658 -46.533308) (xy 246.36222 -46.45787) (xy 246.265446 -46.504606)
			(xy 246.229378 -46.54042) (xy 246.355108 -46.66615)
		)
		(stroke
			(width 0)
			(type solid)
		)
		(fill yes)
		(layer "F.Cu")
		(net "M_B_DQS_DP<17>")
	)
	(gr_poly
		(pts
			(xy 246.392954 -105.791762) (xy 246.267224 -105.648252) (xy 246.23141 -105.612184) (xy 246.141494 -105.7021)
			(xy 246.177562 -105.737914) (xy 246.321072 -105.863644)
		)
		(stroke
			(width 0)
			(type solid)
		)
		(fill yes)
		(layer "F.Cu")
		(net "M_E_DQS_DP<17>")
	)
	(gr_poly
		(pts
			(xy 246.418354 -45.07611) (xy 246.454422 -45.040296) (xy 246.328692 -44.914566) (xy 246.292624 -44.95038)
			(xy 246.246142 -45.047408) (xy 246.32158 -45.122846)
		)
		(stroke
			(width 0)
			(type solid)
		)
		(fill yes)
		(layer "F.Cu")
		(net "M_B_ECC<6>")
	)
	(gr_poly
		(pts
			(xy 246.427244 -45.372528) (xy 246.47398 -45.275754) (xy 246.398542 -45.200316) (xy 246.301514 -45.247052)
			(xy 246.2657 -45.282866) (xy 246.39143 -45.408596)
		)
		(stroke
			(width 0)
			(type solid)
		)
		(fill yes)
		(layer "F.Cu")
		(net "M_B_DQS_DP<8>")
	)
	(gr_poly
		(pts
			(xy 246.435626 -48.112426) (xy 246.47144 -48.076358) (xy 246.34571 -47.950628) (xy 246.309896 -47.986696)
			(xy 246.26316 -48.083724) (xy 246.338598 -48.159162)
		)
		(stroke
			(width 0)
			(type solid)
		)
		(fill yes)
		(layer "F.Cu")
		(net "M_B_ECC<5>")
	)
	(gr_poly
		(pts
			(xy 246.444516 -48.408844) (xy 246.491252 -48.311816) (xy 246.415814 -48.236378) (xy 246.318786 -48.283114)
			(xy 246.273828 -48.327818) (xy 246.399558 -48.453548)
		)
		(stroke
			(width 0)
			(type solid)
		)
		(fill yes)
		(layer "F.Cu")
		(net "M_B_ECC<4>")
	)
	(gr_poly
		(pts
			(xy 246.454676 -43.818556) (xy 246.499634 -43.773852) (xy 246.373904 -43.648122) (xy 246.328946 -43.69308)
			(xy 246.28221 -43.789854) (xy 246.357648 -43.865292)
		)
		(stroke
			(width 0)
			(type solid)
		)
		(fill yes)
		(layer "F.Cu")
		(net "M_B_ECC<3>")
	)
	(gr_poly
		(pts
			(xy 246.455946 -108.171488) (xy 246.419878 -108.135674) (xy 246.276114 -108.009944) (xy 246.204486 -108.081826)
			(xy 246.330216 -108.22559) (xy 246.36603 -108.261404)
		)
		(stroke
			(width 0)
			(type solid)
		)
		(fill yes)
		(layer "F.Cu")
		(net "M_E_ECC<7>")
	)
	(gr_poly
		(pts
			(xy 246.463566 -44.114974) (xy 246.510302 -44.017946) (xy 246.434864 -43.942508) (xy 246.337836 -43.989244)
			(xy 246.302022 -44.025312) (xy 246.427752 -44.151042)
		)
		(stroke
			(width 0)
			(type solid)
		)
		(fill yes)
		(layer "F.Cu")
		(net "M_B_ECC<2>")
	)
	(gr_poly
		(pts
			(xy 246.464836 -105.378758) (xy 246.429022 -105.342944) (xy 246.285258 -105.217214) (xy 246.213376 -105.288842)
			(xy 246.339106 -105.432606) (xy 246.37492 -105.468674)
		)
		(stroke
			(width 0)
			(type solid)
		)
		(fill yes)
		(layer "F.Cu")
		(net "M_E_DQS_DP<17>")
	)
	(gr_poly
		(pts
			(xy 246.471948 -46.854872) (xy 246.507762 -46.818804) (xy 246.382032 -46.693074) (xy 246.346218 -46.729142)
			(xy 246.299482 -46.825916) (xy 246.37492 -46.901354)
		)
		(stroke
			(width 0)
			(type solid)
		)
		(fill yes)
		(layer "F.Cu")
		(net "M_B_DQS_DP<17>")
	)
	(gr_poly
		(pts
			(xy 246.480838 -47.15129) (xy 246.52732 -47.054262) (xy 246.451882 -46.978824) (xy 246.355108 -47.02556)
			(xy 246.31904 -47.061374) (xy 246.44477 -47.187104)
		)
		(stroke
			(width 0)
			(type solid)
		)
		(fill yes)
		(layer "F.Cu")
		(net "M_B_ECC<1>")
	)
	(gr_poly
		(pts
			(xy 246.48287 -106.815636) (xy 246.35714 -106.671872) (xy 246.321072 -106.636058) (xy 246.23141 -106.72572)
			(xy 246.267224 -106.761788) (xy 246.410988 -106.887518)
		)
		(stroke
			(width 0)
			(type solid)
		)
		(fill yes)
		(layer "F.Cu")
		(net "M_E_DQS_DN<8>")
	)
	(gr_poly
		(pts
			(xy 246.49176 -104.022652) (xy 246.36603 -103.878888) (xy 246.329962 -103.843074) (xy 246.2403 -103.932736)
			(xy 246.276114 -103.968804) (xy 246.419878 -104.094534)
		)
		(stroke
			(width 0)
			(type solid)
		)
		(fill yes)
		(layer "F.Cu")
		(net "M_E_ECC<5>")
	)
	(gr_poly
		(pts
			(xy 246.50827 -45.597064) (xy 246.544084 -45.56125) (xy 246.418354 -45.43552) (xy 246.38254 -45.471334)
			(xy 246.335804 -45.568362) (xy 246.411242 -45.6438)
		)
		(stroke
			(width 0)
			(type solid)
		)
		(fill yes)
		(layer "F.Cu")
		(net "M_B_DQS_DP<8>")
	)
	(gr_poly
		(pts
			(xy 246.516906 -45.893736) (xy 246.563642 -45.796708) (xy 246.488204 -45.72127) (xy 246.391176 -45.768006)
			(xy 246.355362 -45.80382) (xy 246.481092 -45.92955)
		)
		(stroke
			(width 0)
			(type solid)
		)
		(fill yes)
		(layer "F.Cu")
		(net "M_B_DQS_DN<8>")
	)
	(gr_poly
		(pts
			(xy 246.544338 -44.33951) (xy 246.580406 -44.303696) (xy 246.454676 -44.177966) (xy 246.418608 -44.21378)
			(xy 246.372126 -44.310808) (xy 246.447564 -44.386246)
		)
		(stroke
			(width 0)
			(type solid)
		)
		(fill yes)
		(layer "F.Cu")
		(net "M_B_ECC<2>")
	)
	(gr_poly
		(pts
			(xy 246.553228 -44.635928) (xy 246.599964 -44.539154) (xy 246.524526 -44.463716) (xy 246.427498 -44.510198)
			(xy 246.391684 -44.546266) (xy 246.517414 -44.671996)
		)
		(stroke
			(width 0)
			(type solid)
		)
		(fill yes)
		(layer "F.Cu")
		(net "M_B_ECC<7>")
	)
	(gr_poly
		(pts
			(xy 246.554498 -109.204252) (xy 246.50954 -109.159294) (xy 246.36603 -109.033564) (xy 246.294148 -109.105446)
			(xy 246.419878 -109.24921) (xy 246.464836 -109.293914)
		)
		(stroke
			(width 0)
			(type solid)
		)
		(fill yes)
		(layer "F.Cu")
		(net "M_E_ECC<3>")
	)
	(gr_poly
		(pts
			(xy 246.554752 -106.402378) (xy 246.518684 -106.366564) (xy 246.37492 -106.240834) (xy 246.303292 -106.312716)
			(xy 246.429022 -106.45648) (xy 246.464836 -106.492294)
		)
		(stroke
			(width 0)
			(type solid)
		)
		(fill yes)
		(layer "F.Cu")
		(net "M_E_DQS_DN<8>")
	)
	(gr_poly
		(pts
			(xy 246.56161 -47.375826) (xy 246.597424 -47.339758) (xy 246.471694 -47.214028) (xy 246.43588 -47.250096)
			(xy 246.389144 -47.34687) (xy 246.464582 -47.422308)
		)
		(stroke
			(width 0)
			(type solid)
		)
		(fill yes)
		(layer "F.Cu")
		(net "M_B_ECC<1>")
	)
	(gr_poly
		(pts
			(xy 246.563388 -103.609648) (xy 246.527574 -103.57358) (xy 246.38381 -103.44785) (xy 246.312182 -103.519732)
			(xy 246.437658 -103.663496) (xy 246.473726 -103.69931)
		)
		(stroke
			(width 0)
			(type solid)
		)
		(fill yes)
		(layer "F.Cu")
		(net "M_E_ECC<5>")
	)
	(gr_poly
		(pts
			(xy 246.5705 -47.672244) (xy 246.617236 -47.575216) (xy 246.541798 -47.499778) (xy 246.44477 -47.546514)
			(xy 246.408702 -47.582328) (xy 246.534432 -47.708058)
		)
		(stroke
			(width 0)
			(type solid)
		)
		(fill yes)
		(layer "F.Cu")
		(net "M_B_ECC<0>")
	)
	(gr_poly
		(pts
			(xy 246.572532 -107.839256) (xy 246.446802 -107.695746) (xy 246.410988 -107.659678) (xy 246.321072 -107.749594)
			(xy 246.35714 -107.785408) (xy 246.50065 -107.911138)
		)
		(stroke
			(width 0)
			(type solid)
		)
		(fill yes)
		(layer "F.Cu")
		(net "M_E_ECC<6>")
	)
	(gr_poly
		(pts
			(xy 246.581676 -105.046526) (xy 246.455946 -104.902762) (xy 246.419878 -104.866948) (xy 246.330216 -104.95661)
			(xy 246.36603 -104.992678) (xy 246.509794 -105.118408)
		)
		(stroke
			(width 0)
			(type solid)
		)
		(fill yes)
		(layer "F.Cu")
		(net "M_E_ECC<1>")
	)
	(gr_poly
		(pts
			(xy 246.597932 -46.118018) (xy 246.633746 -46.082204) (xy 246.508016 -45.956474) (xy 246.472202 -45.992288)
			(xy 246.425466 -46.089316) (xy 246.500904 -46.164754)
		)
		(stroke
			(width 0)
			(type solid)
		)
		(fill yes)
		(layer "F.Cu")
		(net "M_B_DQS_DN<8>")
	)
	(gr_poly
		(pts
			(xy 246.606568 -46.41469) (xy 246.653304 -46.317662) (xy 246.577866 -46.242224) (xy 246.481092 -46.28896)
			(xy 246.445024 -46.324774) (xy 246.570754 -46.450504)
		)
		(stroke
			(width 0)
			(type solid)
		)
		(fill yes)
		(layer "F.Cu")
		(net "M_B_DQS_DN<17>")
	)
	(gr_poly
		(pts
			(xy 246.634 -44.860464) (xy 246.670068 -44.82465) (xy 246.544338 -44.69892) (xy 246.50827 -44.734734)
			(xy 246.461788 -44.831762) (xy 246.537226 -44.9072)
		)
		(stroke
			(width 0)
			(type solid)
		)
		(fill yes)
		(layer "F.Cu")
		(net "M_B_ECC<7>")
	)
	(gr_poly
		(pts
			(xy 246.639588 -53.16474) (xy 246.627396 -53.122322) (xy 246.495316 -52.982876) (xy 246.282718 -53.043074)
			(xy 246.243602 -53.231034) (xy 246.256048 -53.27396)
		)
		(stroke
			(width 0)
			(type solid)
		)
		(fill yes)
		(layer "F.Cu")
		(net "M_B_ECC<5>")
	)
	(gr_poly
		(pts
			(xy 246.64289 -45.156882) (xy 246.689626 -45.060108) (xy 246.614188 -44.98467) (xy 246.51716 -45.031406)
			(xy 246.481346 -45.06722) (xy 246.607076 -45.19295)
		)
		(stroke
			(width 0)
			(type solid)
		)
		(fill yes)
		(layer "F.Cu")
		(net "M_B_ECC<6>")
	)
	(gr_poly
		(pts
			(xy 246.644414 -107.426252) (xy 246.6086 -107.390438) (xy 246.464836 -107.264708) (xy 246.392954 -107.336336)
			(xy 246.518684 -107.4801) (xy 246.554752 -107.515914)
		)
		(stroke
			(width 0)
			(type solid)
		)
		(fill yes)
		(layer "F.Cu")
		(net "M_E_ECC<6>")
	)
	(gr_poly
		(pts
			(xy 246.651272 -47.89678) (xy 246.687086 -47.860712) (xy 246.561356 -47.734982) (xy 246.525542 -47.77105)
			(xy 246.478806 -47.868078) (xy 246.554244 -47.943516)
		)
		(stroke
			(width 0)
			(type solid)
		)
		(fill yes)
		(layer "F.Cu")
		(net "M_B_ECC<0>")
	)
	(gr_poly
		(pts
			(xy 246.653304 -104.633522) (xy 246.61749 -104.597454) (xy 246.473726 -104.471724) (xy 246.402098 -104.543606)
			(xy 246.527828 -104.68737) (xy 246.563642 -104.723184)
		)
		(stroke
			(width 0)
			(type solid)
		)
		(fill yes)
		(layer "F.Cu")
		(net "M_E_ECC<1>")
	)
	(gr_poly
		(pts
			(xy 246.660162 -48.193198) (xy 246.706898 -48.09617) (xy 246.63146 -48.020732) (xy 246.534432 -48.067468)
			(xy 246.498364 -48.103282) (xy 246.624094 -48.229012)
		)
		(stroke
			(width 0)
			(type solid)
		)
		(fill yes)
		(layer "F.Cu")
		(net "M_B_ECC<5>")
	)
	(gr_poly
		(pts
			(xy 246.662448 -108.86313) (xy 246.536718 -108.719366) (xy 246.50065 -108.683552) (xy 246.410988 -108.773214)
			(xy 246.446802 -108.809282) (xy 246.590566 -108.935012)
		)
		(stroke
			(width 0)
			(type solid)
		)
		(fill yes)
		(layer "F.Cu")
		(net "M_E_ECC<2>")
	)
	(gr_poly
		(pts
			(xy 246.671338 -106.070146) (xy 246.545608 -105.926636) (xy 246.509794 -105.890568) (xy 246.419878 -105.980484)
			(xy 246.455946 -106.016298) (xy 246.599456 -106.142028)
		)
		(stroke
			(width 0)
			(type solid)
		)
		(fill yes)
		(layer "F.Cu")
		(net "M_E_DQS_DN<17>")
	)
	(gr_poly
		(pts
			(xy 246.680228 -103.277162) (xy 246.554498 -103.133652) (xy 246.50954 -103.088694) (xy 246.419878 -103.178356)
			(xy 246.464582 -103.223314) (xy 246.608346 -103.349044)
		)
		(stroke
			(width 0)
			(type solid)
		)
		(fill yes)
		(layer "F.Cu")
		(net "M_E_ECC<4>")
	)
	(gr_poly
		(pts
			(xy 246.687594 -46.639226) (xy 246.723408 -46.603158) (xy 246.597678 -46.477428) (xy 246.561864 -46.513496)
			(xy 246.515128 -46.61027) (xy 246.590566 -46.685708)
		)
		(stroke
			(width 0)
			(type solid)
		)
		(fill yes)
		(layer "F.Cu")
		(net "M_B_DQS_DN<17>")
	)
	(gr_poly
		(pts
			(xy 246.696484 -46.935644) (xy 246.742966 -46.838616) (xy 246.667528 -46.763178) (xy 246.570754 -46.809914)
			(xy 246.534686 -46.845728) (xy 246.660416 -46.971458)
		)
		(stroke
			(width 0)
			(type solid)
		)
		(fill yes)
		(layer "F.Cu")
		(net "M_B_DQS_DP<17>")
	)
	(gr_poly
		(pts
			(xy 246.723916 -45.381418) (xy 246.75973 -45.345604) (xy 246.634 -45.219874) (xy 246.598186 -45.255688)
			(xy 246.55145 -45.352716) (xy 246.626888 -45.428154)
		)
		(stroke
			(width 0)
			(type solid)
		)
		(fill yes)
		(layer "F.Cu")
		(net "M_B_ECC<6>")
	)
	(gr_poly
		(pts
			(xy 246.732552 -45.67809) (xy 246.779288 -45.581062) (xy 246.70385 -45.505624) (xy 246.606822 -45.55236)
			(xy 246.571008 -45.588174) (xy 246.696738 -45.713904)
		)
		(stroke
			(width 0)
			(type solid)
		)
		(fill yes)
		(layer "F.Cu")
		(net "M_B_DQS_DP<8>")
	)
	(gr_poly
		(pts
			(xy 246.73433 -108.449872) (xy 246.698262 -108.414058) (xy 246.554498 -108.288328) (xy 246.48287 -108.36021)
			(xy 246.6086 -108.503974) (xy 246.644414 -108.539788)
		)
		(stroke
			(width 0)
			(type solid)
		)
		(fill yes)
		(layer "F.Cu")
		(net "M_E_ECC<2>")
	)
	(gr_poly
		(pts
			(xy 246.740934 -48.417734) (xy 246.776748 -48.381666) (xy 246.651018 -48.255936) (xy 246.615204 -48.292004)
			(xy 246.568468 -48.389032) (xy 246.643906 -48.46447)
		)
		(stroke
			(width 0)
			(type solid)
		)
		(fill yes)
		(layer "F.Cu")
		(net "M_B_ECC<5>")
	)
	(gr_poly
		(pts
			(xy 246.74322 -105.657142) (xy 246.707406 -105.621328) (xy 246.563642 -105.495598) (xy 246.49176 -105.567226)
			(xy 246.61749 -105.71099) (xy 246.653304 -105.747058)
		)
		(stroke
			(width 0)
			(type solid)
		)
		(fill yes)
		(layer "F.Cu")
		(net "M_E_DQS_DN<17>")
	)
	(gr_poly
		(pts
			(xy 246.749824 -48.714152) (xy 246.79656 -48.617124) (xy 246.721122 -48.541686) (xy 246.624094 -48.588422)
			(xy 246.579136 -48.633126) (xy 246.704866 -48.758856)
		)
		(stroke
			(width 0)
			(type solid)
		)
		(fill yes)
		(layer "F.Cu")
		(net "M_B_ECC<4>")
	)
	(gr_poly
		(pts
			(xy 246.753126 -98.488246) (xy 246.708676 -98.488246) (xy 246.538496 -98.577146) (xy 246.538496 -98.798126)
			(xy 246.708676 -98.887026) (xy 246.753126 -98.887026)
		)
		(stroke
			(width 0)
			(type solid)
		)
		(fill yes)
		(layer "F.Cu")
		(net "M_E_ECC<4>")
	)
	(gr_poly
		(pts
			(xy 246.759984 -44.124118) (xy 246.804942 -44.07916) (xy 246.679212 -43.95343) (xy 246.634254 -43.998388)
			(xy 246.587518 -44.095162) (xy 246.662956 -44.1706)
		)
		(stroke
			(width 0)
			(type solid)
		)
		(fill yes)
		(layer "F.Cu")
		(net "M_B_ECC<3>")
	)
	(gr_poly
		(pts
			(xy 246.761254 -107.09402) (xy 246.635524 -106.950256) (xy 246.599456 -106.914442) (xy 246.509794 -107.004104)
			(xy 246.545608 -107.040172) (xy 246.689372 -107.165902)
		)
		(stroke
			(width 0)
			(type solid)
		)
		(fill yes)
		(layer "F.Cu")
		(net "M_E_DQS_DP<8>")
	)
	(gr_poly
		(pts
			(xy 246.768874 -44.420282) (xy 246.81561 -44.323508) (xy 246.740172 -44.24807) (xy 246.643144 -44.294552)
			(xy 246.60733 -44.33062) (xy 246.73306 -44.45635)
		)
		(stroke
			(width 0)
			(type solid)
		)
		(fill yes)
		(layer "F.Cu")
		(net "M_B_ECC<2>")
	)
	(gr_poly
		(pts
			(xy 246.770144 -104.301036) (xy 246.644414 -104.157526) (xy 246.6086 -104.121458) (xy 246.518684 -104.211374)
			(xy 246.554752 -104.247188) (xy 246.698262 -104.372918)
		)
		(stroke
			(width 0)
			(type solid)
		)
		(fill yes)
		(layer "F.Cu")
		(net "M_E_ECC<0>")
	)
	(gr_poly
		(pts
			(xy 246.777256 -47.16018) (xy 246.81307 -47.124112) (xy 246.68734 -46.998382) (xy 246.651526 -47.03445)
			(xy 246.60479 -47.131224) (xy 246.680228 -47.206662)
		)
		(stroke
			(width 0)
			(type solid)
		)
		(fill yes)
		(layer "F.Cu")
		(net "M_B_DQS_DP<17>")
	)
	(gr_poly
		(pts
			(xy 246.786146 -47.456598) (xy 246.832882 -47.35957) (xy 246.757444 -47.284132) (xy 246.660416 -47.330868)
			(xy 246.624348 -47.366682) (xy 246.750078 -47.492412)
		)
		(stroke
			(width 0)
			(type solid)
		)
		(fill yes)
		(layer "F.Cu")
		(net "M_B_ECC<1>")
	)
	(gr_poly
		(pts
			(xy 246.813578 -45.902372) (xy 246.849392 -45.866558) (xy 246.723662 -45.740828) (xy 246.687848 -45.776642)
			(xy 246.641112 -45.87367) (xy 246.71655 -45.949108)
		)
		(stroke
			(width 0)
			(type solid)
		)
		(fill yes)
		(layer "F.Cu")
		(net "M_B_DQS_DP<8>")
	)
	(gr_poly
		(pts
			(xy 246.822214 -46.199044) (xy 246.86895 -46.102016) (xy 246.793512 -46.026578) (xy 246.696738 -46.073314)
			(xy 246.66067 -46.109128) (xy 246.7864 -46.234858)
		)
		(stroke
			(width 0)
			(type solid)
		)
		(fill yes)
		(layer "F.Cu")
		(net "M_B_DQS_DN<8>")
	)
	(gr_poly
		(pts
			(xy 246.833136 -106.680762) (xy 246.797068 -106.644948) (xy 246.653304 -106.519218) (xy 246.581676 -106.5911)
			(xy 246.707406 -106.734864) (xy 246.74322 -106.770678)
		)
		(stroke
			(width 0)
			(type solid)
		)
		(fill yes)
		(layer "F.Cu")
		(net "M_E_DQS_DP<8>")
	)
	(gr_poly
		(pts
			(xy 246.842026 -103.888032) (xy 246.806212 -103.852218) (xy 246.662448 -103.726488) (xy 246.590566 -103.798116)
			(xy 246.716296 -103.94188) (xy 246.75211 -103.977948)
		)
		(stroke
			(width 0)
			(type solid)
		)
		(fill yes)
		(layer "F.Cu")
		(net "M_E_ECC<0>")
	)
	(gr_poly
		(pts
			(xy 246.849646 -44.644818) (xy 246.885714 -44.609004) (xy 246.759984 -44.483274) (xy 246.723916 -44.519088)
			(xy 246.677434 -44.616116) (xy 246.752872 -44.691554)
		)
		(stroke
			(width 0)
			(type solid)
		)
		(fill yes)
		(layer "F.Cu")
		(net "M_B_ECC<2>")
	)
	(gr_poly
		(pts
			(xy 246.850916 -108.11764) (xy 246.725186 -107.97413) (xy 246.689372 -107.938062) (xy 246.599456 -108.027978)
			(xy 246.635524 -108.063792) (xy 246.779034 -108.189522)
		)
		(stroke
			(width 0)
			(type solid)
		)
		(fill yes)
		(layer "F.Cu")
		(net "M_E_ECC<7>")
	)
	(gr_poly
		(pts
			(xy 246.858536 -44.941236) (xy 246.905272 -44.844462) (xy 246.829834 -44.769024) (xy 246.732806 -44.81576)
			(xy 246.696992 -44.851574) (xy 246.822722 -44.977304)
		)
		(stroke
			(width 0)
			(type solid)
		)
		(fill yes)
		(layer "F.Cu")
		(net "M_B_ECC<7>")
	)
	(gr_poly
		(pts
			(xy 246.86006 -105.32491) (xy 246.73433 -105.181146) (xy 246.698262 -105.145332) (xy 246.6086 -105.234994)
			(xy 246.644414 -105.271062) (xy 246.788178 -105.396792)
		)
		(stroke
			(width 0)
			(type solid)
		)
		(fill yes)
		(layer "F.Cu")
		(net "M_E_DQS_DP<17>")
	)
	(gr_poly
		(pts
			(xy 246.866918 -47.681134) (xy 246.902732 -47.645066) (xy 246.777002 -47.519336) (xy 246.741188 -47.555404)
			(xy 246.694452 -47.652432) (xy 246.76989 -47.72787)
		)
		(stroke
			(width 0)
			(type solid)
		)
		(fill yes)
		(layer "F.Cu")
		(net "M_B_ECC<1>")
	)
	(gr_poly
		(pts
			(xy 246.871998 -49.608232) (xy 246.871998 -49.501298) (xy 246.770398 -49.465992) (xy 246.706898 -49.465992)
			(xy 246.706898 -49.643792) (xy 246.770398 -49.643792)
		)
		(stroke
			(width 0)
			(type solid)
		)
		(fill yes)
		(layer "F.Cu")
		(net "M_B_ECC<4>")
	)
	(gr_poly
		(pts
			(xy 246.871998 -49.176432) (xy 246.871998 -49.069498) (xy 246.770398 -49.034192) (xy 246.706898 -49.034192)
			(xy 246.706898 -49.211992) (xy 246.770398 -49.211992)
		)
		(stroke
			(width 0)
			(type solid)
		)
		(fill yes)
		(layer "F.Cu")
		(net "M_B_ECC<4>")
	)
	(gr_poly
		(pts
			(xy 246.875808 -47.977552) (xy 246.922544 -47.880524) (xy 246.847106 -47.805086) (xy 246.750078 -47.851822)
			(xy 246.71401 -47.887636) (xy 246.83974 -48.013366)
		)
		(stroke
			(width 0)
			(type solid)
		)
		(fill yes)
		(layer "F.Cu")
		(net "M_B_ECC<0>")
	)
	(gr_poly
		(pts
			(xy 246.90324 -46.42358) (xy 246.939054 -46.387512) (xy 246.813324 -46.261782) (xy 246.77751 -46.29785)
			(xy 246.730774 -46.394624) (xy 246.806212 -46.470062)
		)
		(stroke
			(width 0)
			(type solid)
		)
		(fill yes)
		(layer "F.Cu")
		(net "M_B_DQS_DN<8>")
	)
	(gr_poly
		(pts
			(xy 246.91213 -46.719998) (xy 246.958612 -46.62297) (xy 246.883174 -46.547532) (xy 246.7864 -46.594268)
			(xy 246.750332 -46.630082) (xy 246.876062 -46.755812)
		)
		(stroke
			(width 0)
			(type solid)
		)
		(fill yes)
		(layer "F.Cu")
		(net "M_B_DQS_DN<17>")
	)
	(gr_poly
		(pts
			(xy 246.922798 -107.704636) (xy 246.886984 -107.668822) (xy 246.74322 -107.543092) (xy 246.671338 -107.61472)
			(xy 246.797068 -107.758484) (xy 246.833136 -107.794298)
		)
		(stroke
			(width 0)
			(type solid)
		)
		(fill yes)
		(layer "F.Cu")
		(net "M_E_ECC<7>")
	)
	(gr_poly
		(pts
			(xy 246.931688 -104.911906) (xy 246.895874 -104.875838) (xy 246.75211 -104.750108) (xy 246.680482 -104.82199)
			(xy 246.806212 -104.965754) (xy 246.842026 -105.001568)
		)
		(stroke
			(width 0)
			(type solid)
		)
		(fill yes)
		(layer "F.Cu")
		(net "M_E_DQS_DP<17>")
	)
	(gr_poly
		(pts
			(xy 246.939562 -45.165772) (xy 246.975376 -45.129958) (xy 246.849646 -45.004228) (xy 246.813832 -45.040042)
			(xy 246.767096 -45.13707) (xy 246.842534 -45.212508)
		)
		(stroke
			(width 0)
			(type solid)
		)
		(fill yes)
		(layer "F.Cu")
		(net "M_B_ECC<7>")
	)
	(gr_poly
		(pts
			(xy 246.948198 -45.462444) (xy 246.994934 -45.365416) (xy 246.919496 -45.289978) (xy 246.822468 -45.336714)
			(xy 246.786654 -45.372528) (xy 246.912384 -45.498258)
		)
		(stroke
			(width 0)
			(type solid)
		)
		(fill yes)
		(layer "F.Cu")
		(net "M_B_ECC<6>")
	)
	(gr_poly
		(pts
			(xy 246.949722 -106.34853) (xy 246.823992 -106.20502) (xy 246.788178 -106.168952) (xy 246.698262 -106.258868)
			(xy 246.73433 -106.294682) (xy 246.87784 -106.420412)
		)
		(stroke
			(width 0)
			(type solid)
		)
		(fill yes)
		(layer "F.Cu")
		(net "M_E_DQS_DN<8>")
	)
	(gr_poly
		(pts
			(xy 246.95658 -48.202088) (xy 246.992394 -48.16602) (xy 246.866664 -48.04029) (xy 246.83085 -48.076358)
			(xy 246.784114 -48.173386) (xy 246.859552 -48.248824)
		)
		(stroke
			(width 0)
			(type solid)
		)
		(fill yes)
		(layer "F.Cu")
		(net "M_B_ECC<0>")
	)
	(gr_poly
		(pts
			(xy 246.958612 -103.555546) (xy 246.832882 -103.412036) (xy 246.797068 -103.375968) (xy 246.707152 -103.465884)
			(xy 246.74322 -103.501698) (xy 246.88673 -103.627428)
		)
		(stroke
			(width 0)
			(type solid)
		)
		(fill yes)
		(layer "F.Cu")
		(net "M_E_ECC<5>")
	)
	(gr_poly
		(pts
			(xy 246.96547 -48.498506) (xy 247.012206 -48.401478) (xy 246.936768 -48.32604) (xy 246.83974 -48.372776)
			(xy 246.803672 -48.40859) (xy 246.929402 -48.53432)
		)
		(stroke
			(width 0)
			(type solid)
		)
		(fill yes)
		(layer "F.Cu")
		(net "M_B_ECC<5>")
	)
	(gr_poly
		(pts
			(xy 246.992902 -46.944534) (xy 247.028716 -46.908466) (xy 246.902986 -46.782736) (xy 246.867172 -46.818804)
			(xy 246.820436 -46.915578) (xy 246.895874 -46.991016)
		)
		(stroke
			(width 0)
			(type solid)
		)
		(fill yes)
		(layer "F.Cu")
		(net "M_B_DQS_DN<17>")
	)
	(gr_poly
		(pts
			(xy 247.001792 -47.240952) (xy 247.048528 -47.143924) (xy 246.97309 -47.068486) (xy 246.876062 -47.115222)
			(xy 246.839994 -47.151036) (xy 246.965724 -47.276766)
		)
		(stroke
			(width 0)
			(type solid)
		)
		(fill yes)
		(layer "F.Cu")
		(net "M_B_DQS_DP<17>")
	)
	(gr_poly
		(pts
			(xy 247.021604 -108.737146) (xy 246.976646 -108.692442) (xy 246.832882 -108.566712) (xy 246.761 -108.638594)
			(xy 246.88673 -108.782104) (xy 246.931688 -108.827062)
		)
		(stroke
			(width 0)
			(type solid)
		)
		(fill yes)
		(layer "F.Cu")
		(net "M_E_ECC<3>")
	)
	(gr_poly
		(pts
			(xy 247.021604 -105.935526) (xy 246.98579 -105.899712) (xy 246.842026 -105.773982) (xy 246.770144 -105.84561)
			(xy 246.895874 -105.989374) (xy 246.931688 -106.025442)
		)
		(stroke
			(width 0)
			(type solid)
		)
		(fill yes)
		(layer "F.Cu")
		(net "M_E_DQS_DN<8>")
	)
	(gr_poly
		(pts
			(xy 247.024398 -49.681892) (xy 246.973598 -49.681892) (xy 246.871998 -49.717198) (xy 246.871998 -49.824132)
			(xy 246.973598 -49.859692) (xy 247.024398 -49.859692)
		)
		(stroke
			(width 0)
			(type solid)
		)
		(fill yes)
		(layer "F.Cu")
		(net "M_B_ECC<5>")
	)
	(gr_poly
		(pts
			(xy 247.024398 -49.250092) (xy 246.973598 -49.250092) (xy 246.871998 -49.285398) (xy 246.871998 -49.392332)
			(xy 246.973598 -49.427892) (xy 247.024398 -49.427892)
		)
		(stroke
			(width 0)
			(type solid)
		)
		(fill yes)
		(layer "F.Cu")
		(net "M_B_ECC<5>")
	)
	(gr_poly
		(pts
			(xy 247.024398 -48.818292) (xy 246.973598 -48.818292) (xy 246.871998 -48.853598) (xy 246.871998 -48.960532)
			(xy 246.973598 -48.996092) (xy 247.024398 -48.996092)
		)
		(stroke
			(width 0)
			(type solid)
		)
		(fill yes)
		(layer "F.Cu")
		(net "M_B_ECC<5>")
	)
	(gr_poly
		(pts
			(xy 247.029224 -45.686726) (xy 247.065038 -45.650912) (xy 246.939308 -45.525182) (xy 246.903494 -45.560996)
			(xy 246.856758 -45.658024) (xy 246.932196 -45.733462)
		)
		(stroke
			(width 0)
			(type solid)
		)
		(fill yes)
		(layer "F.Cu")
		(net "M_B_ECC<6>")
	)
	(gr_poly
		(pts
			(xy 247.030494 -103.142542) (xy 246.99468 -103.106728) (xy 246.850916 -102.980998) (xy 246.779034 -103.052626)
			(xy 246.904764 -103.19639) (xy 246.940578 -103.232458)
		)
		(stroke
			(width 0)
			(type solid)
		)
		(fill yes)
		(layer "F.Cu")
		(net "M_E_ECC<5>")
	)
	(gr_poly
		(pts
			(xy 247.03786 -45.983398) (xy 247.084596 -45.88637) (xy 247.009158 -45.810932) (xy 246.912384 -45.857668)
			(xy 246.876316 -45.893482) (xy 247.002046 -46.019212)
		)
		(stroke
			(width 0)
			(type solid)
		)
		(fill yes)
		(layer "F.Cu")
		(net "M_B_DQS_DP<8>")
	)
	(gr_poly
		(pts
			(xy 247.039638 -107.372404) (xy 246.913908 -107.22864) (xy 246.87784 -107.192826) (xy 246.788178 -107.282488)
			(xy 246.823992 -107.318556) (xy 246.967756 -107.444286)
		)
		(stroke
			(width 0)
			(type solid)
		)
		(fill yes)
		(layer "F.Cu")
		(net "M_E_ECC<6>")
	)
	(gr_poly
		(pts
			(xy 247.048528 -104.57942) (xy 246.922798 -104.43591) (xy 246.886984 -104.399842) (xy 246.797068 -104.489758)
			(xy 246.833136 -104.525572) (xy 246.976646 -104.651302)
		)
		(stroke
			(width 0)
			(type solid)
		)
		(fill yes)
		(layer "F.Cu")
		(net "M_E_ECC<1>")
	)
	(gr_poly
		(pts
			(xy 247.065292 -44.429426) (xy 247.11025 -44.384468) (xy 246.98452 -44.258738) (xy 246.939562 -44.303696)
			(xy 246.892826 -44.400724) (xy 246.968264 -44.475908)
		)
		(stroke
			(width 0)
			(type solid)
		)
		(fill yes)
		(layer "F.Cu")
		(net "M_B_ECC<3>")
	)
	(gr_poly
		(pts
			(xy 247.074182 -44.72559) (xy 247.120918 -44.628816) (xy 247.04548 -44.553378) (xy 246.948452 -44.600114)
			(xy 246.912638 -44.635928) (xy 247.038368 -44.761658)
		)
		(stroke
			(width 0)
			(type solid)
		)
		(fill yes)
		(layer "F.Cu")
		(net "M_B_ECC<2>")
	)
	(gr_poly
		(pts
			(xy 247.082564 -47.465488) (xy 247.118378 -47.42942) (xy 246.992648 -47.30369) (xy 246.956834 -47.339758)
			(xy 246.910098 -47.436786) (xy 246.985536 -47.512224)
		)
		(stroke
			(width 0)
			(type solid)
		)
		(fill yes)
		(layer "F.Cu")
		(net "M_B_DQS_DP<17>")
	)
	(gr_poly
		(pts
			(xy 247.091454 -47.761906) (xy 247.13819 -47.664878) (xy 247.062752 -47.58944) (xy 246.965724 -47.636176)
			(xy 246.929656 -47.67199) (xy 247.055386 -47.79772)
		)
		(stroke
			(width 0)
			(type solid)
		)
		(fill yes)
		(layer "F.Cu")
		(net "M_B_ECC<1>")
	)
	(gr_poly
		(pts
			(xy 247.11152 -106.959146) (xy 247.075452 -106.923332) (xy 246.931688 -106.797602) (xy 246.86006 -106.869484)
			(xy 246.98579 -107.013248) (xy 247.021604 -107.049062)
		)
		(stroke
			(width 0)
			(type solid)
		)
		(fill yes)
		(layer "F.Cu")
		(net "M_E_ECC<6>")
	)
	(gr_poly
		(pts
			(xy 247.118886 -46.207934) (xy 247.1547 -46.171866) (xy 247.02897 -46.046136) (xy 246.993156 -46.082204)
			(xy 246.94642 -46.178978) (xy 247.021858 -46.254416)
		)
		(stroke
			(width 0)
			(type solid)
		)
		(fill yes)
		(layer "F.Cu")
		(net "M_B_DQS_DP<8>")
	)
	(gr_poly
		(pts
			(xy 247.12041 -104.166416) (xy 247.084596 -104.130602) (xy 246.940832 -104.004872) (xy 246.86895 -104.0765)
			(xy 246.99468 -104.220264) (xy 247.030494 -104.256332)
		)
		(stroke
			(width 0)
			(type solid)
		)
		(fill yes)
		(layer "F.Cu")
		(net "M_E_ECC<1>")
	)
	(gr_poly
		(pts
			(xy 247.127776 -46.504352) (xy 247.174258 -46.407324) (xy 247.09882 -46.331886) (xy 247.002046 -46.378622)
			(xy 246.965978 -46.414436) (xy 247.091708 -46.540166)
		)
		(stroke
			(width 0)
			(type solid)
		)
		(fill yes)
		(layer "F.Cu")
		(net "M_B_DQS_DN<8>")
	)
	(gr_poly
		(pts
			(xy 247.1293 -108.396024) (xy 247.00357 -108.252514) (xy 246.967756 -108.216446) (xy 246.87784 -108.306362)
			(xy 246.913908 -108.342176) (xy 247.057418 -108.467906)
		)
		(stroke
			(width 0)
			(type solid)
		)
		(fill yes)
		(layer "F.Cu")
		(net "M_E_ECC<2>")
	)
	(gr_poly
		(pts
			(xy 247.138444 -105.603294) (xy 247.012714 -105.45953) (xy 246.976646 -105.423716) (xy 246.886984 -105.513378)
			(xy 246.922798 -105.549446) (xy 247.066562 -105.675176)
		)
		(stroke
			(width 0)
			(type solid)
		)
		(fill yes)
		(layer "F.Cu")
		(net "M_E_DQS_DN<17>")
	)
	(gr_poly
		(pts
			(xy 247.155208 -44.950126) (xy 247.191022 -44.914312) (xy 247.065292 -44.788582) (xy 247.029478 -44.824396)
			(xy 246.982742 -44.921424) (xy 247.05818 -44.996862)
		)
		(stroke
			(width 0)
			(type solid)
		)
		(fill yes)
		(layer "F.Cu")
		(net "M_B_ECC<2>")
	)
	(gr_poly
		(pts
			(xy 247.163844 -45.246798) (xy 247.21058 -45.14977) (xy 247.135142 -45.074332) (xy 247.038114 -45.121068)
			(xy 247.0023 -45.156882) (xy 247.12803 -45.282612)
		)
		(stroke
			(width 0)
			(type solid)
		)
		(fill yes)
		(layer "F.Cu")
		(net "M_B_ECC<7>")
	)
	(gr_poly
		(pts
			(xy 247.172226 -47.986442) (xy 247.20804 -47.950374) (xy 247.08231 -47.824644) (xy 247.046496 -47.860712)
			(xy 246.99976 -47.95774) (xy 247.075198 -48.033178)
		)
		(stroke
			(width 0)
			(type solid)
		)
		(fill yes)
		(layer "F.Cu")
		(net "M_B_ECC<1>")
	)
	(gr_poly
		(pts
			(xy 247.176798 -49.608232) (xy 247.176798 -49.501298) (xy 247.075198 -49.465992) (xy 247.024398 -49.465992)
			(xy 247.024398 -49.643792) (xy 247.075198 -49.643792)
		)
		(stroke
			(width 0)
			(type solid)
		)
		(fill yes)
		(layer "F.Cu")
		(net "M_B_ECC<5>")
	)
	(gr_poly
		(pts
			(xy 247.176798 -49.176432) (xy 247.176798 -49.069498) (xy 247.075198 -49.034192) (xy 247.024398 -49.034192)
			(xy 247.024398 -49.211992) (xy 247.075198 -49.211992)
		)
		(stroke
			(width 0)
			(type solid)
		)
		(fill yes)
		(layer "F.Cu")
		(net "M_B_ECC<5>")
	)
	(gr_poly
		(pts
			(xy 247.176798 -48.744632) (xy 247.176798 -48.637698) (xy 247.075198 -48.602392) (xy 247.024398 -48.602392)
			(xy 247.024398 -48.780192) (xy 247.075198 -48.780192)
		)
		(stroke
			(width 0)
			(type solid)
		)
		(fill yes)
		(layer "F.Cu")
		(net "M_B_ECC<5>")
	)
	(gr_poly
		(pts
			(xy 247.181116 -48.28286) (xy 247.227852 -48.185832) (xy 247.152414 -48.110394) (xy 247.055386 -48.15713)
			(xy 247.019318 -48.192944) (xy 247.145048 -48.318674)
		)
		(stroke
			(width 0)
			(type solid)
		)
		(fill yes)
		(layer "F.Cu")
		(net "M_B_ECC<0>")
	)
	(gr_poly
		(pts
			(xy 247.183656 -54.743604) (xy 247.019064 -54.380384) (xy 246.978932 -54.398672) (xy 246.860314 -54.549802)
			(xy 246.951246 -54.751224) (xy 247.143016 -54.762146)
		)
		(stroke
			(width 0)
			(type solid)
		)
		(fill yes)
		(layer "F.Cu")
		(net "M_B_ECC<5>")
	)
	(gr_poly
		(pts
			(xy 247.201182 -107.98302) (xy 247.165368 -107.947206) (xy 247.021604 -107.821476) (xy 246.949722 -107.893104)
			(xy 247.075452 -108.036868) (xy 247.11152 -108.072682)
		)
		(stroke
			(width 0)
			(type solid)
		)
		(fill yes)
		(layer "F.Cu")
		(net "M_E_ECC<2>")
	)
	(gr_poly
		(pts
			(xy 247.208548 -46.728888) (xy 247.244362 -46.69282) (xy 247.118632 -46.56709) (xy 247.082818 -46.603158)
			(xy 247.036082 -46.699932) (xy 247.11152 -46.77537)
		)
		(stroke
			(width 0)
			(type solid)
		)
		(fill yes)
		(layer "F.Cu")
		(net "M_B_DQS_DN<8>")
	)
	(gr_poly
		(pts
			(xy 247.210072 -105.19029) (xy 247.174258 -105.154222) (xy 247.030494 -105.028492) (xy 246.958866 -105.100374)
			(xy 247.084596 -105.244138) (xy 247.12041 -105.279952)
		)
		(stroke
			(width 0)
			(type solid)
		)
		(fill yes)
		(layer "F.Cu")
		(net "M_E_DQS_DN<17>")
	)
	(gr_poly
		(pts
			(xy 247.217438 -47.025306) (xy 247.264174 -46.928278) (xy 247.188736 -46.85284) (xy 247.091708 -46.899576)
			(xy 247.05564 -46.93539) (xy 247.18137 -47.06112)
		)
		(stroke
			(width 0)
			(type solid)
		)
		(fill yes)
		(layer "F.Cu")
		(net "M_B_DQS_DN<17>")
	)
	(gr_poly
		(pts
			(xy 247.228106 -106.626914) (xy 247.102376 -106.483404) (xy 247.066562 -106.447336) (xy 246.976646 -106.537252)
			(xy 247.012714 -106.573066) (xy 247.156224 -106.698796)
		)
		(stroke
			(width 0)
			(type solid)
		)
		(fill yes)
		(layer "F.Cu")
		(net "M_E_DQS_DP<8>")
	)
	(gr_poly
		(pts
			(xy 247.23725 -103.834184) (xy 247.11152 -103.69042) (xy 247.075452 -103.654606) (xy 246.98579 -103.744268)
			(xy 247.021604 -103.780336) (xy 247.165368 -103.906066)
		)
		(stroke
			(width 0)
			(type solid)
		)
		(fill yes)
		(layer "F.Cu")
		(net "M_E_ECC<0>")
	)
	(gr_poly
		(pts
			(xy 247.24487 -45.47108) (xy 247.280684 -45.435266) (xy 247.154954 -45.309536) (xy 247.11914 -45.34535)
			(xy 247.072404 -45.442378) (xy 247.147842 -45.517816)
		)
		(stroke
			(width 0)
			(type solid)
		)
		(fill yes)
		(layer "F.Cu")
		(net "M_B_ECC<7>")
	)
	(gr_poly
		(pts
			(xy 247.253506 -45.767752) (xy 247.300242 -45.670724) (xy 247.224804 -45.595286) (xy 247.12803 -45.642022)
			(xy 247.091962 -45.677836) (xy 247.217692 -45.803566)
		)
		(stroke
			(width 0)
			(type solid)
		)
		(fill yes)
		(layer "F.Cu")
		(net "M_B_ECC<6>")
	)
	(gr_poly
		(pts
			(xy 247.29821 -47.249842) (xy 247.334024 -47.213774) (xy 247.208294 -47.088044) (xy 247.17248 -47.124112)
			(xy 247.125744 -47.22114) (xy 247.201182 -47.296578)
		)
		(stroke
			(width 0)
			(type solid)
		)
		(fill yes)
		(layer "F.Cu")
		(net "M_B_DQS_DN<17>")
	)
	(gr_poly
		(pts
			(xy 247.299988 -106.21391) (xy 247.264174 -106.178096) (xy 247.12041 -106.052366) (xy 247.048528 -106.123994)
			(xy 247.174258 -106.267758) (xy 247.210072 -106.303826)
		)
		(stroke
			(width 0)
			(type solid)
		)
		(fill yes)
		(layer "F.Cu")
		(net "M_E_DQS_DP<8>")
	)
	(gr_poly
		(pts
			(xy 247.305068 -52.724812) (xy 247.304306 -52.504086) (xy 247.133872 -52.415694) (xy 247.089168 -52.415948)
			(xy 247.090692 -52.814474) (xy 247.135142 -52.814474)
		)
		(stroke
			(width 0)
			(type solid)
		)
		(fill yes)
		(layer "F.Cu")
		(net "M_B_ECC<0>")
	)
	(gr_poly
		(pts
			(xy 247.3071 -47.54626) (xy 247.353836 -47.449232) (xy 247.278398 -47.373794) (xy 247.18137 -47.42053)
			(xy 247.145302 -47.456344) (xy 247.271032 -47.582074)
		)
		(stroke
			(width 0)
			(type solid)
		)
		(fill yes)
		(layer "F.Cu")
		(net "M_B_DQS_DP<17>")
	)
	(gr_poly
		(pts
			(xy 247.311926 -97.247202) (xy 247.289574 -97.208848) (xy 247.127522 -97.105978) (xy 246.93626 -97.216468)
			(xy 246.944388 -97.408238) (xy 246.966486 -97.446846)
		)
		(stroke
			(width 0)
			(type solid)
		)
		(fill yes)
		(layer "F.Cu")
		(net "M_E_ECC<4>")
	)
	(gr_poly
		(pts
			(xy 247.318022 -107.650788) (xy 247.192292 -107.507024) (xy 247.156224 -107.47121) (xy 247.066562 -107.560872)
			(xy 247.102376 -107.59694) (xy 247.24614 -107.72267)
		)
		(stroke
			(width 0)
			(type solid)
		)
		(fill yes)
		(layer "F.Cu")
		(net "M_E_ECC<7>")
	)
	(gr_poly
		(pts
			(xy 247.326912 -104.857804) (xy 247.201182 -104.714294) (xy 247.165368 -104.678226) (xy 247.075452 -104.768142)
			(xy 247.11152 -104.803956) (xy 247.25503 -104.929686)
		)
		(stroke
			(width 0)
			(type solid)
		)
		(fill yes)
		(layer "F.Cu")
		(net "M_E_DQS_DP<17>")
	)
	(gr_poly
		(pts
			(xy 247.329198 -49.681892) (xy 247.278398 -49.681892) (xy 247.176798 -49.717198) (xy 247.176798 -49.824132)
			(xy 247.278398 -49.859692) (xy 247.329198 -49.859692)
		)
		(stroke
			(width 0)
			(type solid)
		)
		(fill yes)
		(layer "F.Cu")
		(net "M_B_ECC<0>")
	)
	(gr_poly
		(pts
			(xy 247.329198 -49.250092) (xy 247.278398 -49.250092) (xy 247.176798 -49.285398) (xy 247.176798 -49.392332)
			(xy 247.278398 -49.427892) (xy 247.329198 -49.427892)
		)
		(stroke
			(width 0)
			(type solid)
		)
		(fill yes)
		(layer "F.Cu")
		(net "M_B_ECC<0>")
	)
	(gr_poly
		(pts
			(xy 247.329198 -48.818292) (xy 247.278398 -48.818292) (xy 247.176798 -48.853598) (xy 247.176798 -48.960532)
			(xy 247.278398 -48.996092) (xy 247.329198 -48.996092)
		)
		(stroke
			(width 0)
			(type solid)
		)
		(fill yes)
		(layer "F.Cu")
		(net "M_B_ECC<0>")
	)
	(gr_poly
		(pts
			(xy 247.334532 -45.992288) (xy 247.370346 -45.95622) (xy 247.244616 -45.83049) (xy 247.208802 -45.866558)
			(xy 247.162066 -45.963332) (xy 247.237504 -46.03877)
		)
		(stroke
			(width 0)
			(type solid)
		)
		(fill yes)
		(layer "F.Cu")
		(net "M_B_ECC<6>")
	)
	(gr_poly
		(pts
			(xy 247.343422 -46.288706) (xy 247.389904 -46.191678) (xy 247.314466 -46.11624) (xy 247.217692 -46.162976)
			(xy 247.181624 -46.19879) (xy 247.307354 -46.32452)
		)
		(stroke
			(width 0)
			(type solid)
		)
		(fill yes)
		(layer "F.Cu")
		(net "M_B_DQS_DP<8>")
	)
	(gr_poly
		(pts
			(xy 247.3706 -44.734734) (xy 247.415558 -44.689776) (xy 247.289828 -44.564046) (xy 247.24487 -44.609004)
			(xy 247.198134 -44.706032) (xy 247.273572 -44.78147)
		)
		(stroke
			(width 0)
			(type solid)
		)
		(fill yes)
		(layer "F.Cu")
		(net "M_B_ECC<3>")
	)
	(gr_poly
		(pts
			(xy 247.376188 -103.569262) (xy 247.329452 -103.472488) (xy 247.293638 -103.43642) (xy 247.167908 -103.56215)
			(xy 247.203722 -103.598218) (xy 247.30075 -103.6447)
		)
		(stroke
			(width 0)
			(type solid)
		)
		(fill yes)
		(layer "F.Cu")
		(net "M_E_ECC<0>")
	)
	(gr_poly
		(pts
			(xy 247.37949 -45.031152) (xy 247.426226 -44.934124) (xy 247.350788 -44.858686) (xy 247.25376 -44.905422)
			(xy 247.217946 -44.941236) (xy 247.343676 -45.066966)
		)
		(stroke
			(width 0)
			(type solid)
		)
		(fill yes)
		(layer "F.Cu")
		(net "M_B_ECC<2>")
	)
	(gr_poly
		(pts
			(xy 247.387872 -47.770796) (xy 247.423686 -47.734728) (xy 247.297956 -47.608998) (xy 247.262142 -47.645066)
			(xy 247.215406 -47.742094) (xy 247.290844 -47.817532)
		)
		(stroke
			(width 0)
			(type solid)
		)
		(fill yes)
		(layer "F.Cu")
		(net "M_B_DQS_DP<17>")
	)
	(gr_poly
		(pts
			(xy 247.389904 -107.23753) (xy 247.353836 -107.201716) (xy 247.210072 -107.075986) (xy 247.138444 -107.147868)
			(xy 247.264174 -107.291632) (xy 247.299988 -107.327446)
		)
		(stroke
			(width 0)
			(type solid)
		)
		(fill yes)
		(layer "F.Cu")
		(net "M_E_ECC<7>")
	)
	(gr_poly
		(pts
			(xy 247.396762 -48.067214) (xy 247.443498 -47.970186) (xy 247.36806 -47.894748) (xy 247.271032 -47.941484)
			(xy 247.234964 -47.977298) (xy 247.360694 -48.103028)
		)
		(stroke
			(width 0)
			(type solid)
		)
		(fill yes)
		(layer "F.Cu")
		(net "M_B_ECC<1>")
	)
	(gr_poly
		(pts
			(xy 247.398794 -104.4448) (xy 247.36298 -104.408986) (xy 247.219216 -104.283256) (xy 247.147334 -104.354884)
			(xy 247.273064 -104.498648) (xy 247.308878 -104.534716)
		)
		(stroke
			(width 0)
			(type solid)
		)
		(fill yes)
		(layer "F.Cu")
		(net "M_E_DQS_DP<17>")
	)
	(gr_poly
		(pts
			(xy 247.416828 -105.881678) (xy 247.291098 -105.737914) (xy 247.25503 -105.7021) (xy 247.165368 -105.791762)
			(xy 247.201182 -105.82783) (xy 247.344946 -105.95356)
		)
		(stroke
			(width 0)
			(type solid)
		)
		(fill yes)
		(layer "F.Cu")
		(net "M_E_DQS_DN<8>")
	)
	(gr_poly
		(pts
			(xy 247.424194 -46.513242) (xy 247.460008 -46.477174) (xy 247.334278 -46.351444) (xy 247.298464 -46.387512)
			(xy 247.251728 -46.484286) (xy 247.327166 -46.559724)
		)
		(stroke
			(width 0)
			(type solid)
		)
		(fill yes)
		(layer "F.Cu")
		(net "M_B_DQS_DP<8>")
	)
	(gr_poly
		(pts
			(xy 247.433084 -46.80966) (xy 247.47982 -46.712632) (xy 247.404382 -46.637194) (xy 247.307354 -46.68393)
			(xy 247.271286 -46.719744) (xy 247.397016 -46.845474)
		)
		(stroke
			(width 0)
			(type solid)
		)
		(fill yes)
		(layer "F.Cu")
		(net "M_B_DQS_DN<8>")
	)
	(gr_poly
		(pts
			(xy 247.446292 -103.283766) (xy 247.410478 -103.247952) (xy 247.31345 -103.201216) (xy 247.238012 -103.276654)
			(xy 247.284748 -103.373682) (xy 247.320562 -103.409496)
		)
		(stroke
			(width 0)
			(type solid)
		)
		(fill yes)
		(layer "F.Cu")
		(net "M_E_ECC<0>")
	)
	(gr_poly
		(pts
			(xy 247.460516 -45.255434) (xy 247.49633 -45.21962) (xy 247.3706 -45.09389) (xy 247.334786 -45.129704)
			(xy 247.28805 -45.226732) (xy 247.363488 -45.30217)
		)
		(stroke
			(width 0)
			(type solid)
		)
		(fill yes)
		(layer "F.Cu")
		(net "M_B_ECC<2>")
	)
	(gr_poly
		(pts
			(xy 247.469152 -45.552106) (xy 247.515888 -45.455078) (xy 247.44045 -45.37964) (xy 247.343676 -45.426376)
			(xy 247.307608 -45.46219) (xy 247.433338 -45.58792)
		)
		(stroke
			(width 0)
			(type solid)
		)
		(fill yes)
		(layer "F.Cu")
		(net "M_B_ECC<7>")
	)
	(gr_poly
		(pts
			(xy 247.477534 -48.29175) (xy 247.513348 -48.255682) (xy 247.387618 -48.129952) (xy 247.351804 -48.16602)
			(xy 247.305068 -48.263048) (xy 247.380506 -48.338486)
		)
		(stroke
			(width 0)
			(type solid)
		)
		(fill yes)
		(layer "F.Cu")
		(net "M_B_ECC<1>")
	)
	(gr_poly
		(pts
			(xy 247.481598 -49.608232) (xy 247.481598 -49.501298) (xy 247.379998 -49.465992) (xy 247.329198 -49.465992)
			(xy 247.329198 -49.643792) (xy 247.379998 -49.643792)
		)
		(stroke
			(width 0)
			(type solid)
		)
		(fill yes)
		(layer "F.Cu")
		(net "M_B_ECC<0>")
	)
	(gr_poly
		(pts
			(xy 247.481598 -49.176432) (xy 247.481598 -49.069498) (xy 247.379998 -49.034192) (xy 247.329198 -49.034192)
			(xy 247.329198 -49.211992) (xy 247.379998 -49.211992)
		)
		(stroke
			(width 0)
			(type solid)
		)
		(fill yes)
		(layer "F.Cu")
		(net "M_B_ECC<0>")
	)
	(gr_poly
		(pts
			(xy 247.481598 -48.744632) (xy 247.481598 -48.637698) (xy 247.379998 -48.602392) (xy 247.329198 -48.602392)
			(xy 247.329198 -48.780192) (xy 247.379998 -48.780192)
		)
		(stroke
			(width 0)
			(type solid)
		)
		(fill yes)
		(layer "F.Cu")
		(net "M_B_ECC<0>")
	)
	(gr_poly
		(pts
			(xy 247.488456 -108.270294) (xy 247.443498 -108.225336) (xy 247.299988 -108.099606) (xy 247.228106 -108.171488)
			(xy 247.353836 -108.315252) (xy 247.398794 -108.359956)
		)
		(stroke
			(width 0)
			(type solid)
		)
		(fill yes)
		(layer "F.Cu")
		(net "M_E_ECC<3>")
	)
	(gr_poly
		(pts
			(xy 247.488456 -105.468674) (xy 247.452642 -105.432606) (xy 247.308878 -105.306876) (xy 247.23725 -105.378758)
			(xy 247.36298 -105.522522) (xy 247.398794 -105.558336)
		)
		(stroke
			(width 0)
			(type solid)
		)
		(fill yes)
		(layer "F.Cu")
		(net "M_E_DQS_DN<8>")
	)
	(gr_poly
		(pts
			(xy 247.50649 -106.905298) (xy 247.38076 -106.761788) (xy 247.344946 -106.72572) (xy 247.25503 -106.815636)
			(xy 247.291098 -106.85145) (xy 247.434608 -106.97718)
		)
		(stroke
			(width 0)
			(type solid)
		)
		(fill yes)
		(layer "F.Cu")
		(net "M_E_ECC<6>")
	)
	(gr_poly
		(pts
			(xy 247.513856 -47.034196) (xy 247.54967 -46.998128) (xy 247.42394 -46.872398) (xy 247.388126 -46.908466)
			(xy 247.34139 -47.005494) (xy 247.416828 -47.080932)
		)
		(stroke
			(width 0)
			(type solid)
		)
		(fill yes)
		(layer "F.Cu")
		(net "M_B_DQS_DN<8>")
	)
	(gr_poly
		(pts
			(xy 247.515888 -104.11206) (xy 247.390158 -103.96855) (xy 247.354344 -103.932482) (xy 247.264428 -104.022398)
			(xy 247.300496 -104.058212) (xy 247.444006 -104.183942)
		)
		(stroke
			(width 0)
			(type solid)
		)
		(fill yes)
		(layer "F.Cu")
		(net "M_E_ECC<1>")
	)
	(gr_poly
		(pts
			(xy 247.522746 -47.330614) (xy 247.569482 -47.233586) (xy 247.494044 -47.158148) (xy 247.397016 -47.204884)
			(xy 247.360948 -47.240698) (xy 247.486678 -47.366428)
		)
		(stroke
			(width 0)
			(type solid)
		)
		(fill yes)
		(layer "F.Cu")
		(net "M_B_DQS_DN<17>")
	)
	(gr_poly
		(pts
			(xy 247.550178 -45.776642) (xy 247.585992 -45.740574) (xy 247.460262 -45.614844) (xy 247.424448 -45.650912)
			(xy 247.377712 -45.747686) (xy 247.45315 -45.823124)
		)
		(stroke
			(width 0)
			(type solid)
		)
		(fill yes)
		(layer "F.Cu")
		(net "M_B_ECC<7>")
	)
	(gr_poly
		(pts
			(xy 247.559068 -46.07306) (xy 247.60555 -45.976032) (xy 247.530112 -45.900594) (xy 247.433338 -45.94733)
			(xy 247.39727 -45.983144) (xy 247.523 -46.108874)
		)
		(stroke
			(width 0)
			(type solid)
		)
		(fill yes)
		(layer "F.Cu")
		(net "M_B_ECC<6>")
	)
	(gr_poly
		(pts
			(xy 247.578372 -106.492294) (xy 247.542558 -106.45648) (xy 247.398794 -106.33075) (xy 247.326912 -106.402378)
			(xy 247.452642 -106.546142) (xy 247.488456 -106.58221)
		)
		(stroke
			(width 0)
			(type solid)
		)
		(fill yes)
		(layer "F.Cu")
		(net "M_E_ECC<6>")
	)
	(gr_poly
		(pts
			(xy 247.596406 -107.929172) (xy 247.470676 -107.785408) (xy 247.434608 -107.749594) (xy 247.344946 -107.839256)
			(xy 247.38076 -107.875324) (xy 247.524524 -108.001054)
		)
		(stroke
			(width 0)
			(type solid)
		)
		(fill yes)
		(layer "F.Cu")
		(net "M_E_ECC<2>")
	)
	(gr_poly
		(pts
			(xy 247.603518 -47.55515) (xy 247.639332 -47.519082) (xy 247.513602 -47.393352) (xy 247.477788 -47.42942)
			(xy 247.431052 -47.526448) (xy 247.50649 -47.601886)
		)
		(stroke
			(width 0)
			(type solid)
		)
		(fill yes)
		(layer "F.Cu")
		(net "M_B_DQS_DN<17>")
	)
	(gr_poly
		(pts
			(xy 247.605296 -105.136188) (xy 247.479566 -104.992678) (xy 247.443752 -104.95661) (xy 247.353836 -105.046526)
			(xy 247.389904 -105.08234) (xy 247.533414 -105.20807)
		)
		(stroke
			(width 0)
			(type solid)
		)
		(fill yes)
		(layer "F.Cu")
		(net "M_E_DQS_DN<17>")
	)
	(gr_poly
		(pts
			(xy 247.612154 -54.415436) (xy 247.567704 -54.415436) (xy 247.397524 -54.504082) (xy 247.39727 -54.725062)
			(xy 247.567196 -54.814216) (xy 247.6119 -54.814216)
		)
		(stroke
			(width 0)
			(type solid)
		)
		(fill yes)
		(layer "F.Cu")
		(net "M_B_DQS_DN<8>")
	)
	(gr_poly
		(pts
			(xy 247.612408 -47.851568) (xy 247.659144 -47.75454) (xy 247.583706 -47.679102) (xy 247.486678 -47.725838)
			(xy 247.45061 -47.761652) (xy 247.57634 -47.887382)
		)
		(stroke
			(width 0)
			(type solid)
		)
		(fill yes)
		(layer "F.Cu")
		(net "M_B_DQS_DP<17>")
	)
	(gr_poly
		(pts
			(xy 247.633998 -49.681892) (xy 247.583198 -49.681892) (xy 247.481598 -49.717198) (xy 247.481598 -49.824132)
			(xy 247.583198 -49.859692) (xy 247.633998 -49.859692)
		)
		(stroke
			(width 0)
			(type solid)
		)
		(fill yes)
		(layer "F.Cu")
		(net "M_B_ECC<1>")
	)
	(gr_poly
		(pts
			(xy 247.633998 -49.250092) (xy 247.583198 -49.250092) (xy 247.481598 -49.285398) (xy 247.481598 -49.392332)
			(xy 247.583198 -49.427892) (xy 247.633998 -49.427892)
		)
		(stroke
			(width 0)
			(type solid)
		)
		(fill yes)
		(layer "F.Cu")
		(net "M_B_ECC<1>")
	)
	(gr_poly
		(pts
			(xy 247.633998 -48.818292) (xy 247.583198 -48.818292) (xy 247.481598 -48.853598) (xy 247.481598 -48.960532)
			(xy 247.583198 -48.996092) (xy 247.633998 -48.996092)
		)
		(stroke
			(width 0)
			(type solid)
		)
		(fill yes)
		(layer "F.Cu")
		(net "M_B_ECC<1>")
	)
	(gr_poly
		(pts
			(xy 247.633998 -48.386492) (xy 247.583198 -48.386492) (xy 247.481598 -48.421798) (xy 247.481598 -48.528732)
			(xy 247.583198 -48.564292) (xy 247.633998 -48.564292)
		)
		(stroke
			(width 0)
			(type solid)
		)
		(fill yes)
		(layer "F.Cu")
		(net "M_B_ECC<1>")
	)
	(gr_poly
		(pts
			(xy 247.63984 -46.297596) (xy 247.675654 -46.261528) (xy 247.549924 -46.135798) (xy 247.51411 -46.171866)
			(xy 247.467374 -46.26864) (xy 247.542812 -46.344078)
		)
		(stroke
			(width 0)
			(type solid)
		)
		(fill yes)
		(layer "F.Cu")
		(net "M_B_ECC<6>")
	)
	(gr_poly
		(pts
			(xy 247.64873 -46.594014) (xy 247.695466 -46.496986) (xy 247.620028 -46.421548) (xy 247.523 -46.468284)
			(xy 247.486932 -46.504098) (xy 247.612662 -46.629828)
		)
		(stroke
			(width 0)
			(type solid)
		)
		(fill yes)
		(layer "F.Cu")
		(net "M_B_DQS_DP<8>")
	)
	(gr_poly
		(pts
			(xy 247.661938 -103.499412) (xy 247.626124 -103.463598) (xy 247.529096 -103.416862) (xy 247.453658 -103.4923)
			(xy 247.500394 -103.589328) (xy 247.536208 -103.625142)
		)
		(stroke
			(width 0)
			(type solid)
		)
		(fill yes)
		(layer "F.Cu")
		(net "M_E_ECC<1>")
	)
	(gr_poly
		(pts
			(xy 247.668288 -107.515914) (xy 247.63222 -107.4801) (xy 247.488456 -107.35437) (xy 247.416828 -107.426252)
			(xy 247.542558 -107.570016) (xy 247.578372 -107.60583)
		)
		(stroke
			(width 0)
			(type solid)
		)
		(fill yes)
		(layer "F.Cu")
		(net "M_E_ECC<2>")
	)
	(gr_poly
		(pts
			(xy 247.675908 -45.040042) (xy 247.720866 -44.995084) (xy 247.595136 -44.869354) (xy 247.550178 -44.914312)
			(xy 247.503442 -45.01134) (xy 247.57888 -45.086778)
		)
		(stroke
			(width 0)
			(type solid)
		)
		(fill yes)
		(layer "F.Cu")
		(net "M_B_ECC<3>")
	)
	(gr_poly
		(pts
			(xy 247.677178 -104.723184) (xy 247.641364 -104.68737) (xy 247.4976 -104.56164) (xy 247.425718 -104.633268)
			(xy 247.551448 -104.777032) (xy 247.587262 -104.8131)
		)
		(stroke
			(width 0)
			(type solid)
		)
		(fill yes)
		(layer "F.Cu")
		(net "M_E_DQS_DN<17>")
	)
	(gr_poly
		(pts
			(xy 247.681496 -103.263954) (xy 247.63476 -103.166926) (xy 247.598946 -103.131112) (xy 247.473216 -103.256842)
			(xy 247.50903 -103.292656) (xy 247.606058 -103.339392)
		)
		(stroke
			(width 0)
			(type solid)
		)
		(fill yes)
		(layer "F.Cu")
		(net "M_E_ECC<0>")
	)
	(gr_poly
		(pts
			(xy 247.684798 -45.33646) (xy 247.731534 -45.239432) (xy 247.656096 -45.163994) (xy 247.559322 -45.21073)
			(xy 247.523254 -45.246544) (xy 247.648984 -45.372274)
		)
		(stroke
			(width 0)
			(type solid)
		)
		(fill yes)
		(layer "F.Cu")
		(net "M_B_ECC<2>")
	)
	(gr_poly
		(pts
			(xy 247.69318 -48.076104) (xy 247.728994 -48.040036) (xy 247.603264 -47.914306) (xy 247.56745 -47.950374)
			(xy 247.520714 -48.047402) (xy 247.596152 -48.12284)
		)
		(stroke
			(width 0)
			(type solid)
		)
		(fill yes)
		(layer "F.Cu")
		(net "M_B_DQS_DP<17>")
	)
	(gr_poly
		(pts
			(xy 247.695212 -106.160062) (xy 247.569482 -106.016298) (xy 247.533414 -105.980484) (xy 247.443752 -106.070146)
			(xy 247.479566 -106.106214) (xy 247.62333 -106.231944)
		)
		(stroke
			(width 0)
			(type solid)
		)
		(fill yes)
		(layer "F.Cu")
		(net "M_E_DQS_DP<8>")
	)
	(gr_poly
		(pts
			(xy 247.729502 -46.81855) (xy 247.765316 -46.782482) (xy 247.639586 -46.656752) (xy 247.603772 -46.69282)
			(xy 247.557036 -46.789848) (xy 247.632474 -46.865286)
		)
		(stroke
			(width 0)
			(type solid)
		)
		(fill yes)
		(layer "F.Cu")
		(net "M_B_DQS_DP<8>")
	)
	(gr_poly
		(pts
			(xy 247.738392 -47.114968) (xy 247.785128 -47.01794) (xy 247.70969 -46.942502) (xy 247.612662 -46.989238)
			(xy 247.576594 -47.025052) (xy 247.702324 -47.150782)
		)
		(stroke
			(width 0)
			(type solid)
		)
		(fill yes)
		(layer "F.Cu")
		(net "M_B_DQS_DN<8>")
	)
	(gr_poly
		(pts
			(xy 247.7516 -102.978458) (xy 247.715786 -102.942644) (xy 247.618758 -102.895908) (xy 247.54332 -102.971346)
			(xy 247.590056 -103.068374) (xy 247.62587 -103.104188)
		)
		(stroke
			(width 0)
			(type solid)
		)
		(fill yes)
		(layer "F.Cu")
		(net "M_E_ECC<0>")
	)
	(gr_poly
		(pts
			(xy 247.765824 -45.560996) (xy 247.801638 -45.524928) (xy 247.675908 -45.399198) (xy 247.640094 -45.435266)
			(xy 247.593358 -45.53204) (xy 247.668796 -45.607478)
		)
		(stroke
			(width 0)
			(type solid)
		)
		(fill yes)
		(layer "F.Cu")
		(net "M_B_ECC<2>")
	)
	(gr_poly
		(pts
			(xy 247.76684 -105.747058) (xy 247.731026 -105.71099) (xy 247.587262 -105.58526) (xy 247.515634 -105.657142)
			(xy 247.641364 -105.800906) (xy 247.677178 -105.83672)
		)
		(stroke
			(width 0)
			(type solid)
		)
		(fill yes)
		(layer "F.Cu")
		(net "M_E_DQS_DP<8>")
	)
	(gr_poly
		(pts
			(xy 247.774714 -45.857414) (xy 247.821196 -45.760386) (xy 247.745758 -45.684948) (xy 247.648984 -45.731684)
			(xy 247.612916 -45.767498) (xy 247.738646 -45.893228)
		)
		(stroke
			(width 0)
			(type solid)
		)
		(fill yes)
		(layer "F.Cu")
		(net "M_B_ECC<7>")
	)
	(gr_poly
		(pts
			(xy 247.784874 -107.183682) (xy 247.659144 -107.040172) (xy 247.62333 -107.004104) (xy 247.533414 -107.09402)
			(xy 247.569482 -107.129834) (xy 247.712992 -107.255564)
		)
		(stroke
			(width 0)
			(type solid)
		)
		(fill yes)
		(layer "F.Cu")
		(net "M_E_ECC<7>")
	)
	(gr_poly
		(pts
			(xy 247.786398 -49.608232) (xy 247.786398 -49.501298) (xy 247.684798 -49.465992) (xy 247.633998 -49.465992)
			(xy 247.633998 -49.643792) (xy 247.684798 -49.643792)
		)
		(stroke
			(width 0)
			(type solid)
		)
		(fill yes)
		(layer "F.Cu")
		(net "M_B_ECC<1>")
	)
	(gr_poly
		(pts
			(xy 247.786398 -49.176432) (xy 247.786398 -49.069498) (xy 247.684798 -49.034192) (xy 247.633998 -49.034192)
			(xy 247.633998 -49.211992) (xy 247.684798 -49.211992)
		)
		(stroke
			(width 0)
			(type solid)
		)
		(fill yes)
		(layer "F.Cu")
		(net "M_B_ECC<1>")
	)
	(gr_poly
		(pts
			(xy 247.786398 -48.744632) (xy 247.786398 -48.637698) (xy 247.684798 -48.602392) (xy 247.633998 -48.602392)
			(xy 247.633998 -48.780192) (xy 247.684798 -48.780192)
		)
		(stroke
			(width 0)
			(type solid)
		)
		(fill yes)
		(layer "F.Cu")
		(net "M_B_ECC<1>")
	)
	(gr_poly
		(pts
			(xy 247.794018 -104.390952) (xy 247.668288 -104.247188) (xy 247.63222 -104.211374) (xy 247.542558 -104.301036)
			(xy 247.578372 -104.337104) (xy 247.722136 -104.462834)
		)
		(stroke
			(width 0)
			(type solid)
		)
		(fill yes)
		(layer "F.Cu")
		(net "M_E_DQS_DP<17>")
	)
	(gr_poly
		(pts
			(xy 247.819164 -102.260654) (xy 247.768364 -102.260654) (xy 247.666764 -102.296214) (xy 247.666764 -102.402894)
			(xy 247.768364 -102.438454) (xy 247.819164 -102.438454)
		)
		(stroke
			(width 0)
			(type solid)
		)
		(fill yes)
		(layer "F.Cu")
		(net "M_E_ECC<0>")
	)
	(gr_poly
		(pts
			(xy 247.819164 -101.828854) (xy 247.768364 -101.828854) (xy 247.666764 -101.864414) (xy 247.666764 -101.971094)
			(xy 247.768364 -102.006654) (xy 247.819164 -102.006654)
		)
		(stroke
			(width 0)
			(type solid)
		)
		(fill yes)
		(layer "F.Cu")
		(net "M_E_ECC<0>")
	)
	(gr_poly
		(pts
			(xy 247.819164 -100.965254) (xy 247.768364 -100.965254) (xy 247.666764 -101.000814) (xy 247.666764 -101.107494)
			(xy 247.768364 -101.143054) (xy 247.819164 -101.143054)
		)
		(stroke
			(width 0)
			(type solid)
		)
		(fill yes)
		(layer "F.Cu")
		(net "M_E_ECC<0>")
	)
	(gr_poly
		(pts
			(xy 247.819164 -47.339504) (xy 247.854978 -47.303436) (xy 247.729248 -47.177706) (xy 247.693434 -47.213774)
			(xy 247.646698 -47.310802) (xy 247.722136 -47.38624)
		)
		(stroke
			(width 0)
			(type solid)
		)
		(fill yes)
		(layer "F.Cu")
		(net "M_B_DQS_DN<8>")
	)
	(gr_poly
		(pts
			(xy 247.828054 -47.635922) (xy 247.87479 -47.538894) (xy 247.799352 -47.463456) (xy 247.702324 -47.510192)
			(xy 247.666256 -47.546006) (xy 247.791986 -47.671736)
		)
		(stroke
			(width 0)
			(type solid)
		)
		(fill yes)
		(layer "F.Cu")
		(net "M_B_DQS_DN<17>")
	)
	(gr_poly
		(pts
			(xy 247.855486 -46.08195) (xy 247.8913 -46.045882) (xy 247.76557 -45.920152) (xy 247.729756 -45.95622)
			(xy 247.68302 -46.052994) (xy 247.758458 -46.128432)
		)
		(stroke
			(width 0)
			(type solid)
		)
		(fill yes)
		(layer "F.Cu")
		(net "M_B_ECC<7>")
	)
	(gr_poly
		(pts
			(xy 247.856756 -106.770678) (xy 247.820942 -106.734864) (xy 247.677178 -106.609134) (xy 247.605296 -106.680762)
			(xy 247.731026 -106.824526) (xy 247.76684 -106.860594)
		)
		(stroke
			(width 0)
			(type solid)
		)
		(fill yes)
		(layer "F.Cu")
		(net "M_E_ECC<7>")
	)
	(gr_poly
		(pts
			(xy 247.864376 -46.378368) (xy 247.911112 -46.28134) (xy 247.835674 -46.205902) (xy 247.738646 -46.252638)
			(xy 247.702578 -46.288452) (xy 247.828308 -46.414182)
		)
		(stroke
			(width 0)
			(type solid)
		)
		(fill yes)
		(layer "F.Cu")
		(net "M_B_ECC<6>")
	)
	(gr_poly
		(pts
			(xy 247.877584 -103.715058) (xy 247.84177 -103.679244) (xy 247.744742 -103.632508) (xy 247.669304 -103.707946)
			(xy 247.71604 -103.804974) (xy 247.751854 -103.840788)
		)
		(stroke
			(width 0)
			(type solid)
		)
		(fill yes)
		(layer "F.Cu")
		(net "M_E_DQS_DP<17>")
	)
	(gr_poly
		(pts
			(xy 247.88368 -105.414572) (xy 247.75795 -105.271062) (xy 247.722136 -105.234994) (xy 247.63222 -105.32491)
			(xy 247.668288 -105.360724) (xy 247.811798 -105.486454)
		)
		(stroke
			(width 0)
			(type solid)
		)
		(fill yes)
		(layer "F.Cu")
		(net "M_E_DQS_DN<8>")
	)
	(gr_poly
		(pts
			(xy 247.892824 -104.031034) (xy 247.892824 -103.924354) (xy 247.791224 -103.888794) (xy 247.740424 -103.888794)
			(xy 247.740424 -104.066594) (xy 247.791224 -104.066594)
		)
		(stroke
			(width 0)
			(type solid)
		)
		(fill yes)
		(layer "F.Cu")
		(net "M_E_DQS_DP<17>")
	)
	(gr_poly
		(pts
			(xy 247.897142 -103.4796) (xy 247.850406 -103.382572) (xy 247.814592 -103.346758) (xy 247.688862 -103.472488)
			(xy 247.724676 -103.508302) (xy 247.821704 -103.555038)
		)
		(stroke
			(width 0)
			(type solid)
		)
		(fill yes)
		(layer "F.Cu")
		(net "M_E_ECC<1>")
	)
	(gr_poly
		(pts
			(xy 247.908826 -47.860458) (xy 247.94464 -47.82439) (xy 247.81891 -47.69866) (xy 247.783096 -47.734728)
			(xy 247.73636 -47.831756) (xy 247.811798 -47.907194)
		)
		(stroke
			(width 0)
			(type solid)
		)
		(fill yes)
		(layer "F.Cu")
		(net "M_B_DQS_DN<17>")
	)
	(gr_poly
		(pts
			(xy 247.917716 -48.156876) (xy 247.964452 -48.059848) (xy 247.889014 -47.98441) (xy 247.791986 -48.031146)
			(xy 247.755918 -48.06696) (xy 247.881648 -48.19269)
		)
		(stroke
			(width 0)
			(type solid)
		)
		(fill yes)
		(layer "F.Cu")
		(net "M_B_DQS_DP<17>")
	)
	(gr_poly
		(pts
			(xy 247.938798 -49.681892) (xy 247.887998 -49.681892) (xy 247.786398 -49.717198) (xy 247.786398 -49.824132)
			(xy 247.887998 -49.859692) (xy 247.938798 -49.859692)
		)
		(stroke
			(width 0)
			(type solid)
		)
		(fill yes)
		(layer "F.Cu")
		(net "M_B_DQS_DP<17>")
	)
	(gr_poly
		(pts
			(xy 247.938798 -49.250092) (xy 247.887998 -49.250092) (xy 247.786398 -49.285398) (xy 247.786398 -49.392332)
			(xy 247.887998 -49.427892) (xy 247.938798 -49.427892)
		)
		(stroke
			(width 0)
			(type solid)
		)
		(fill yes)
		(layer "F.Cu")
		(net "M_B_DQS_DP<17>")
	)
	(gr_poly
		(pts
			(xy 247.938798 -48.818292) (xy 247.887998 -48.818292) (xy 247.786398 -48.853598) (xy 247.786398 -48.960532)
			(xy 247.887998 -48.996092) (xy 247.938798 -48.996092)
		)
		(stroke
			(width 0)
			(type solid)
		)
		(fill yes)
		(layer "F.Cu")
		(net "M_B_DQS_DP<17>")
	)
	(gr_poly
		(pts
			(xy 247.938798 -48.386492) (xy 247.887998 -48.386492) (xy 247.786398 -48.421798) (xy 247.786398 -48.528732)
			(xy 247.887998 -48.564292) (xy 247.938798 -48.564292)
		)
		(stroke
			(width 0)
			(type solid)
		)
		(fill yes)
		(layer "F.Cu")
		(net "M_B_DQS_DP<17>")
	)
	(gr_poly
		(pts
			(xy 247.945148 -46.602904) (xy 247.980962 -46.566836) (xy 247.855232 -46.441106) (xy 247.819418 -46.477174)
			(xy 247.772682 -46.574202) (xy 247.84812 -46.64964)
		)
		(stroke
			(width 0)
			(type solid)
		)
		(fill yes)
		(layer "F.Cu")
		(net "M_B_ECC<6>")
	)
	(gr_poly
		(pts
			(xy 247.954038 -46.899322) (xy 248.000774 -46.802294) (xy 247.925336 -46.726856) (xy 247.828308 -46.773592)
			(xy 247.79224 -46.809406) (xy 247.91797 -46.935136)
		)
		(stroke
			(width 0)
			(type solid)
		)
		(fill yes)
		(layer "F.Cu")
		(net "M_B_DQS_DP<8>")
	)
	(gr_poly
		(pts
			(xy 247.955562 -107.803188) (xy 247.910604 -107.758484) (xy 247.76684 -107.632754) (xy 247.694958 -107.704636)
			(xy 247.820688 -107.848146) (xy 247.865646 -107.893104)
		)
		(stroke
			(width 0)
			(type solid)
		)
		(fill yes)
		(layer "F.Cu")
		(net "M_E_ECC<3>")
	)
	(gr_poly
		(pts
			(xy 247.955562 -105.001568) (xy 247.919748 -104.965754) (xy 247.775984 -104.840024) (xy 247.704102 -104.911652)
			(xy 247.829832 -105.055416) (xy 247.865646 -105.091484)
		)
		(stroke
			(width 0)
			(type solid)
		)
		(fill yes)
		(layer "F.Cu")
		(net "M_E_DQS_DN<8>")
	)
	(gr_poly
		(pts
			(xy 247.967246 -103.194104) (xy 247.931432 -103.15829) (xy 247.834404 -103.111554) (xy 247.758966 -103.186992)
			(xy 247.805702 -103.28402) (xy 247.841516 -103.319834)
		)
		(stroke
			(width 0)
			(type solid)
		)
		(fill yes)
		(layer "F.Cu")
		(net "M_E_ECC<1>")
	)
	(gr_poly
		(pts
			(xy 247.971564 -102.618794) (xy 247.971564 -102.512114) (xy 247.869964 -102.476554) (xy 247.819164 -102.476554)
			(xy 247.819164 -102.654354) (xy 247.869964 -102.654354)
		)
		(stroke
			(width 0)
			(type solid)
		)
		(fill yes)
		(layer "F.Cu")
		(net "M_E_ECC<0>")
	)
	(gr_poly
		(pts
			(xy 247.971564 -102.186994) (xy 247.971564 -102.080314) (xy 247.869964 -102.044754) (xy 247.819164 -102.044754)
			(xy 247.819164 -102.222554) (xy 247.869964 -102.222554)
		)
		(stroke
			(width 0)
			(type solid)
		)
		(fill yes)
		(layer "F.Cu")
		(net "M_E_ECC<0>")
	)
	(gr_poly
		(pts
			(xy 247.971564 -101.755194) (xy 247.971564 -101.648514) (xy 247.869964 -101.612954) (xy 247.819164 -101.612954)
			(xy 247.819164 -101.790754) (xy 247.869964 -101.790754)
		)
		(stroke
			(width 0)
			(type solid)
		)
		(fill yes)
		(layer "F.Cu")
		(net "M_E_ECC<0>")
	)
	(gr_poly
		(pts
			(xy 247.971564 -101.323394) (xy 247.971564 -101.216714) (xy 247.869964 -101.181154) (xy 247.819164 -101.181154)
			(xy 247.819164 -101.358954) (xy 247.869964 -101.358954)
		)
		(stroke
			(width 0)
			(type solid)
		)
		(fill yes)
		(layer "F.Cu")
		(net "M_E_ECC<0>")
	)
	(gr_poly
		(pts
			(xy 247.971564 -100.891594) (xy 247.971564 -100.784914) (xy 247.869964 -100.749354) (xy 247.819164 -100.749354)
			(xy 247.819164 -100.927154) (xy 247.869964 -100.927154)
		)
		(stroke
			(width 0)
			(type solid)
		)
		(fill yes)
		(layer "F.Cu")
		(net "M_E_ECC<0>")
	)
	(gr_poly
		(pts
			(xy 247.973596 -106.438446) (xy 247.847866 -106.294682) (xy 247.811798 -106.258868) (xy 247.722136 -106.34853)
			(xy 247.75795 -106.384598) (xy 247.901714 -106.510328)
		)
		(stroke
			(width 0)
			(type solid)
		)
		(fill yes)
		(layer "F.Cu")
		(net "M_E_ECC<6>")
	)
	(gr_poly
		(pts
			(xy 247.981216 -45.34535) (xy 248.026174 -45.300392) (xy 247.900444 -45.174662) (xy 247.855486 -45.21962)
			(xy 247.809004 -45.316648) (xy 247.884188 -45.392086)
		)
		(stroke
			(width 0)
			(type solid)
		)
		(fill yes)
		(layer "F.Cu")
		(net "M_B_ECC<3>")
	)
	(gr_poly
		(pts
			(xy 247.99036 -45.641768) (xy 248.036842 -45.54474) (xy 247.961404 -45.469302) (xy 247.86463 -45.516038)
			(xy 247.828562 -45.551852) (xy 247.954292 -45.677582)
		)
		(stroke
			(width 0)
			(type solid)
		)
		(fill yes)
		(layer "F.Cu")
		(net "M_B_ECC<2>")
	)
	(gr_poly
		(pts
			(xy 248.03481 -47.123858) (xy 248.070624 -47.08779) (xy 247.944894 -46.96206) (xy 247.90908 -46.998128)
			(xy 247.862344 -47.095156) (xy 247.937782 -47.170594)
		)
		(stroke
			(width 0)
			(type solid)
		)
		(fill yes)
		(layer "F.Cu")
		(net "M_B_DQS_DP<8>")
	)
	(gr_poly
		(pts
			(xy 248.0437 -47.420276) (xy 248.090436 -47.323248) (xy 248.014998 -47.24781) (xy 247.91797 -47.294546)
			(xy 247.881902 -47.33036) (xy 248.007632 -47.45609)
		)
		(stroke
			(width 0)
			(type solid)
		)
		(fill yes)
		(layer "F.Cu")
		(net "M_B_DQS_DN<8>")
	)
	(gr_poly
		(pts
			(xy 248.045224 -106.025442) (xy 248.00941 -105.989374) (xy 247.865646 -105.863644) (xy 247.794018 -105.935526)
			(xy 247.919748 -106.07929) (xy 247.955562 -106.115104)
		)
		(stroke
			(width 0)
			(type solid)
		)
		(fill yes)
		(layer "F.Cu")
		(net "M_E_ECC<6>")
	)
	(gr_poly
		(pts
			(xy 248.045224 -104.104694) (xy 247.994424 -104.104694) (xy 247.892824 -104.140254) (xy 247.892824 -104.246934)
			(xy 247.994424 -104.282494) (xy 248.045224 -104.282494)
		)
		(stroke
			(width 0)
			(type solid)
		)
		(fill yes)
		(layer "F.Cu")
		(net "M_E_DQS_DN<17>")
	)
	(gr_poly
		(pts
			(xy 248.063258 -107.462066) (xy 247.937528 -107.318556) (xy 247.901714 -107.282488) (xy 247.811798 -107.372404)
			(xy 247.847866 -107.408218) (xy 247.991376 -107.533948)
		)
		(stroke
			(width 0)
			(type solid)
		)
		(fill yes)
		(layer "F.Cu")
		(net "M_E_ECC<2>")
	)
	(gr_poly
		(pts
			(xy 248.071132 -45.866304) (xy 248.106946 -45.830236) (xy 247.981216 -45.704506) (xy 247.945402 -45.740574)
			(xy 247.898666 -45.837348) (xy 247.974104 -45.912786)
		)
		(stroke
			(width 0)
			(type solid)
		)
		(fill yes)
		(layer "F.Cu")
		(net "M_B_ECC<2>")
	)
	(gr_poly
		(pts
			(xy 248.072402 -104.669336) (xy 247.946672 -104.525572) (xy 247.910604 -104.489758) (xy 247.820942 -104.57942)
			(xy 247.856756 -104.615488) (xy 248.00052 -104.741218)
		)
		(stroke
			(width 0)
			(type solid)
		)
		(fill yes)
		(layer "F.Cu")
		(net "M_E_DQS_DN<17>")
	)
	(gr_poly
		(pts
			(xy 248.080022 -46.162722) (xy 248.126758 -46.065694) (xy 248.05132 -45.990256) (xy 247.954292 -46.036992)
			(xy 247.918224 -46.072806) (xy 248.043954 -46.198536)
		)
		(stroke
			(width 0)
			(type solid)
		)
		(fill yes)
		(layer "F.Cu")
		(net "M_B_ECC<7>")
	)
	(gr_poly
		(pts
			(xy 248.091198 -49.608232) (xy 248.091198 -49.501298) (xy 247.989598 -49.465992) (xy 247.938798 -49.465992)
			(xy 247.938798 -49.643792) (xy 247.989598 -49.643792)
		)
		(stroke
			(width 0)
			(type solid)
		)
		(fill yes)
		(layer "F.Cu")
		(net "M_B_DQS_DP<17>")
	)
	(gr_poly
		(pts
			(xy 248.091198 -49.176432) (xy 248.091198 -49.069498) (xy 247.989598 -49.034192) (xy 247.938798 -49.034192)
			(xy 247.938798 -49.211992) (xy 247.989598 -49.211992)
		)
		(stroke
			(width 0)
			(type solid)
		)
		(fill yes)
		(layer "F.Cu")
		(net "M_B_DQS_DP<17>")
	)
	(gr_poly
		(pts
			(xy 248.091198 -48.744632) (xy 248.091198 -48.637698) (xy 247.989598 -48.602392) (xy 247.938798 -48.602392)
			(xy 247.938798 -48.780192) (xy 247.989598 -48.780192)
		)
		(stroke
			(width 0)
			(type solid)
		)
		(fill yes)
		(layer "F.Cu")
		(net "M_B_DQS_DP<17>")
	)
	(gr_poly
		(pts
			(xy 248.112788 -103.695246) (xy 248.066052 -103.598218) (xy 248.030238 -103.562404) (xy 247.904508 -103.688134)
			(xy 247.940322 -103.723948) (xy 248.03735 -103.770684)
		)
		(stroke
			(width 0)
			(type solid)
		)
		(fill yes)
		(layer "F.Cu")
		(net "M_E_DQS_DP<17>")
	)
	(gr_poly
		(pts
			(xy 248.123964 -102.692454) (xy 248.073164 -102.692454) (xy 247.971564 -102.728014) (xy 247.971564 -102.834694)
			(xy 248.073164 -102.870254) (xy 248.123964 -102.870254)
		)
		(stroke
			(width 0)
			(type solid)
		)
		(fill yes)
		(layer "F.Cu")
		(net "M_E_ECC<1>")
	)
	(gr_poly
		(pts
			(xy 248.123964 -102.260654) (xy 248.073164 -102.260654) (xy 247.971564 -102.296214) (xy 247.971564 -102.402894)
			(xy 248.073164 -102.438454) (xy 248.123964 -102.438454)
		)
		(stroke
			(width 0)
			(type solid)
		)
		(fill yes)
		(layer "F.Cu")
		(net "M_E_ECC<1>")
	)
	(gr_poly
		(pts
			(xy 248.123964 -101.828854) (xy 248.073164 -101.828854) (xy 247.971564 -101.864414) (xy 247.971564 -101.971094)
			(xy 248.073164 -102.006654) (xy 248.123964 -102.006654)
		)
		(stroke
			(width 0)
			(type solid)
		)
		(fill yes)
		(layer "F.Cu")
		(net "M_E_ECC<1>")
	)
	(gr_poly
		(pts
			(xy 248.123964 -101.397054) (xy 248.073164 -101.397054) (xy 247.971564 -101.432614) (xy 247.971564 -101.539294)
			(xy 248.073164 -101.574854) (xy 248.123964 -101.574854)
		)
		(stroke
			(width 0)
			(type solid)
		)
		(fill yes)
		(layer "F.Cu")
		(net "M_E_ECC<1>")
	)
	(gr_poly
		(pts
			(xy 248.123964 -100.965254) (xy 248.073164 -100.965254) (xy 247.971564 -101.000814) (xy 247.971564 -101.107494)
			(xy 248.073164 -101.143054) (xy 248.123964 -101.143054)
		)
		(stroke
			(width 0)
			(type solid)
		)
		(fill yes)
		(layer "F.Cu")
		(net "M_E_ECC<1>")
	)
	(gr_poly
		(pts
			(xy 248.123964 -100.533454) (xy 248.073164 -100.533454) (xy 247.971564 -100.569014) (xy 247.971564 -100.675694)
			(xy 248.073164 -100.711254) (xy 248.123964 -100.711254)
		)
		(stroke
			(width 0)
			(type solid)
		)
		(fill yes)
		(layer "F.Cu")
		(net "M_E_ECC<1>")
	)
	(gr_poly
		(pts
			(xy 248.124472 -47.644812) (xy 248.160286 -47.608744) (xy 248.034556 -47.483014) (xy 247.998742 -47.519082)
			(xy 247.952006 -47.61611) (xy 248.027444 -47.691548)
		)
		(stroke
			(width 0)
			(type solid)
		)
		(fill yes)
		(layer "F.Cu")
		(net "M_B_DQS_DN<8>")
	)
	(gr_poly
		(pts
			(xy 248.133362 -47.94123) (xy 248.180098 -47.844202) (xy 248.10466 -47.768764) (xy 248.007632 -47.8155)
			(xy 247.971564 -47.851314) (xy 248.097294 -47.977044)
		)
		(stroke
			(width 0)
			(type solid)
		)
		(fill yes)
		(layer "F.Cu")
		(net "M_B_DQS_DN<17>")
	)
	(gr_poly
		(pts
			(xy 248.13514 -107.049062) (xy 248.099326 -107.013248) (xy 247.955562 -106.887518) (xy 247.88368 -106.959146)
			(xy 248.00941 -107.10291) (xy 248.045224 -107.138978)
		)
		(stroke
			(width 0)
			(type solid)
		)
		(fill yes)
		(layer "F.Cu")
		(net "M_E_ECC<2>")
	)
	(gr_poly
		(pts
			(xy 248.160794 -46.387258) (xy 248.196608 -46.35119) (xy 248.070878 -46.22546) (xy 248.035064 -46.261528)
			(xy 247.988328 -46.358556) (xy 248.063766 -46.433994)
		)
		(stroke
			(width 0)
			(type solid)
		)
		(fill yes)
		(layer "F.Cu")
		(net "M_B_ECC<7>")
	)
	(gr_poly
		(pts
			(xy 248.162064 -105.692956) (xy 248.036334 -105.549446) (xy 248.00052 -105.513378) (xy 247.910604 -105.603294)
			(xy 247.946672 -105.639108) (xy 248.090182 -105.764838)
		)
		(stroke
			(width 0)
			(type solid)
		)
		(fill yes)
		(layer "F.Cu")
		(net "M_E_DQS_DP<8>")
	)
	(gr_poly
		(pts
			(xy 248.169684 -46.683676) (xy 248.21642 -46.586648) (xy 248.140982 -46.51121) (xy 248.043954 -46.557946)
			(xy 248.007886 -46.59376) (xy 248.133616 -46.71949)
		)
		(stroke
			(width 0)
			(type solid)
		)
		(fill yes)
		(layer "F.Cu")
		(net "M_B_ECC<6>")
	)
	(gr_poly
		(pts
			(xy 248.182892 -103.40975) (xy 248.147078 -103.373936) (xy 248.05005 -103.3272) (xy 247.974612 -103.402638)
			(xy 248.021348 -103.499666) (xy 248.057162 -103.53548)
		)
		(stroke
			(width 0)
			(type solid)
		)
		(fill yes)
		(layer "F.Cu")
		(net "M_E_DQS_DP<17>")
	)
	(gr_poly
		(pts
			(xy 248.20245 -103.174292) (xy 248.155714 -103.077264) (xy 248.1199 -103.04145) (xy 247.99417 -103.16718)
			(xy 248.029984 -103.202994) (xy 248.127012 -103.24973)
		)
		(stroke
			(width 0)
			(type solid)
		)
		(fill yes)
		(layer "F.Cu")
		(net "M_E_ECC<1>")
	)
	(gr_poly
		(pts
			(xy 248.233946 -105.279952) (xy 248.198132 -105.244138) (xy 248.054368 -105.118408) (xy 247.982486 -105.190036)
			(xy 248.108216 -105.3338) (xy 248.14403 -105.369868)
		)
		(stroke
			(width 0)
			(type solid)
		)
		(fill yes)
		(layer "F.Cu")
		(net "M_E_DQS_DP<8>")
	)
	(gr_poly
		(pts
			(xy 248.243598 -49.681892) (xy 248.192798 -49.681892) (xy 248.091198 -49.717198) (xy 248.091198 -49.824132)
			(xy 248.192798 -49.859692) (xy 248.243598 -49.859692)
		)
		(stroke
			(width 0)
			(type solid)
		)
		(fill yes)
		(layer "F.Cu")
		(net "M_B_DQS_DN<17>")
	)
	(gr_poly
		(pts
			(xy 248.243598 -49.250092) (xy 248.192798 -49.250092) (xy 248.091198 -49.285398) (xy 248.091198 -49.392332)
			(xy 248.192798 -49.427892) (xy 248.243598 -49.427892)
		)
		(stroke
			(width 0)
			(type solid)
		)
		(fill yes)
		(layer "F.Cu")
		(net "M_B_DQS_DN<17>")
	)
	(gr_poly
		(pts
			(xy 248.243598 -48.818292) (xy 248.192798 -48.818292) (xy 248.091198 -48.853598) (xy 248.091198 -48.960532)
			(xy 248.192798 -48.996092) (xy 248.243598 -48.996092)
		)
		(stroke
			(width 0)
			(type solid)
		)
		(fill yes)
		(layer "F.Cu")
		(net "M_B_DQS_DN<17>")
	)
	(gr_poly
		(pts
			(xy 248.243598 -48.386492) (xy 248.192798 -48.386492) (xy 248.091198 -48.421798) (xy 248.091198 -48.528732)
			(xy 248.192798 -48.564292) (xy 248.243598 -48.564292)
		)
		(stroke
			(width 0)
			(type solid)
		)
		(fill yes)
		(layer "F.Cu")
		(net "M_B_DQS_DN<17>")
	)
	(gr_poly
		(pts
			(xy 248.250456 -46.908212) (xy 248.28627 -46.872144) (xy 248.16054 -46.746414) (xy 248.124726 -46.782482)
			(xy 248.07799 -46.87951) (xy 248.153428 -46.954948)
		)
		(stroke
			(width 0)
			(type solid)
		)
		(fill yes)
		(layer "F.Cu")
		(net "M_B_ECC<6>")
	)
	(gr_poly
		(pts
			(xy 248.25198 -106.71683) (xy 248.12625 -106.573066) (xy 248.090182 -106.537252) (xy 248.00052 -106.626914)
			(xy 248.036334 -106.662982) (xy 248.180098 -106.788712)
		)
		(stroke
			(width 0)
			(type solid)
		)
		(fill yes)
		(layer "F.Cu")
		(net "M_E_ECC<7>")
	)
	(gr_poly
		(pts
			(xy 248.259346 -47.20463) (xy 248.306082 -47.107602) (xy 248.230644 -47.032164) (xy 248.133616 -47.0789)
			(xy 248.097548 -47.114714) (xy 248.223278 -47.240444)
		)
		(stroke
			(width 0)
			(type solid)
		)
		(fill yes)
		(layer "F.Cu")
		(net "M_B_DQS_DP<8>")
	)
	(gr_poly
		(pts
			(xy 248.276364 -102.618794) (xy 248.276364 -102.512114) (xy 248.174764 -102.476554) (xy 248.123964 -102.476554)
			(xy 248.123964 -102.654354) (xy 248.174764 -102.654354)
		)
		(stroke
			(width 0)
			(type solid)
		)
		(fill yes)
		(layer "F.Cu")
		(net "M_E_ECC<1>")
	)
	(gr_poly
		(pts
			(xy 248.276364 -102.186994) (xy 248.276364 -102.080314) (xy 248.174764 -102.044754) (xy 248.123964 -102.044754)
			(xy 248.123964 -102.222554) (xy 248.174764 -102.222554)
		)
		(stroke
			(width 0)
			(type solid)
		)
		(fill yes)
		(layer "F.Cu")
		(net "M_E_ECC<1>")
	)
	(gr_poly
		(pts
			(xy 248.276364 -101.755194) (xy 248.276364 -101.648514) (xy 248.174764 -101.612954) (xy 248.123964 -101.612954)
			(xy 248.123964 -101.790754) (xy 248.174764 -101.790754)
		)
		(stroke
			(width 0)
			(type solid)
		)
		(fill yes)
		(layer "F.Cu")
		(net "M_E_ECC<1>")
	)
	(gr_poly
		(pts
			(xy 248.276364 -101.323394) (xy 248.276364 -101.216714) (xy 248.174764 -101.181154) (xy 248.123964 -101.181154)
			(xy 248.123964 -101.358954) (xy 248.174764 -101.358954)
		)
		(stroke
			(width 0)
			(type solid)
		)
		(fill yes)
		(layer "F.Cu")
		(net "M_E_ECC<1>")
	)
	(gr_poly
		(pts
			(xy 248.276364 -100.891594) (xy 248.276364 -100.784914) (xy 248.174764 -100.749354) (xy 248.123964 -100.749354)
			(xy 248.123964 -100.927154) (xy 248.174764 -100.927154)
		)
		(stroke
			(width 0)
			(type solid)
		)
		(fill yes)
		(layer "F.Cu")
		(net "M_E_ECC<1>")
	)
	(gr_poly
		(pts
			(xy 248.286524 -45.650658) (xy 248.331482 -45.6057) (xy 248.205752 -45.47997) (xy 248.160794 -45.524928)
			(xy 248.114312 -45.621956) (xy 248.18975 -45.697394)
		)
		(stroke
			(width 0)
			(type solid)
		)
		(fill yes)
		(layer "F.Cu")
		(net "M_B_ECC<3>")
	)
	(gr_poly
		(pts
			(xy 248.295668 -45.947076) (xy 248.342404 -45.850048) (xy 248.266966 -45.77461) (xy 248.169938 -45.821346)
			(xy 248.13387 -45.85716) (xy 248.2596 -45.98289)
		)
		(stroke
			(width 0)
			(type solid)
		)
		(fill yes)
		(layer "F.Cu")
		(net "M_B_ECC<2>")
	)
	(gr_poly
		(pts
			(xy 248.323608 -106.303826) (xy 248.287794 -106.267758) (xy 248.14403 -106.142028) (xy 248.072402 -106.21391)
			(xy 248.198132 -106.357674) (xy 248.233946 -106.393488)
		)
		(stroke
			(width 0)
			(type solid)
		)
		(fill yes)
		(layer "F.Cu")
		(net "M_E_ECC<7>")
	)
	(gr_poly
		(pts
			(xy 248.328434 -103.910892) (xy 248.281698 -103.813864) (xy 248.245884 -103.77805) (xy 248.120154 -103.90378)
			(xy 248.155968 -103.939594) (xy 248.252996 -103.98633)
		)
		(stroke
			(width 0)
			(type solid)
		)
		(fill yes)
		(layer "F.Cu")
		(net "M_E_DQS_DN<17>")
	)
	(gr_poly
		(pts
			(xy 248.340118 -47.429166) (xy 248.375932 -47.393098) (xy 248.250202 -47.267368) (xy 248.214388 -47.303436)
			(xy 248.167652 -47.400464) (xy 248.24309 -47.475902)
		)
		(stroke
			(width 0)
			(type solid)
		)
		(fill yes)
		(layer "F.Cu")
		(net "M_B_DQS_DP<8>")
	)
	(gr_poly
		(pts
			(xy 248.349008 -47.725584) (xy 248.395744 -47.628556) (xy 248.320306 -47.553118) (xy 248.223278 -47.599854)
			(xy 248.187464 -47.635922) (xy 248.31294 -47.761398)
		)
		(stroke
			(width 0)
			(type solid)
		)
		(fill yes)
		(layer "F.Cu")
		(net "M_B_DQS_DN<8>")
	)
	(gr_poly
		(pts
			(xy 248.350024 -104.104694) (xy 248.299224 -104.104694) (xy 248.197624 -104.140254) (xy 248.197624 -104.246934)
			(xy 248.299224 -104.282494) (xy 248.350024 -104.282494)
		)
		(stroke
			(width 0)
			(type solid)
		)
		(fill yes)
		(layer "F.Cu")
		(net "M_E_DQS_DN<8>")
	)
	(gr_poly
		(pts
			(xy 248.350786 -104.94772) (xy 248.225056 -104.803956) (xy 248.188988 -104.768142) (xy 248.099326 -104.857804)
			(xy 248.13514 -104.893872) (xy 248.278904 -105.019602)
		)
		(stroke
			(width 0)
			(type solid)
		)
		(fill yes)
		(layer "F.Cu")
		(net "M_E_DQS_DN<8>")
	)
	(gr_poly
		(pts
			(xy 248.37644 -46.171612) (xy 248.412254 -46.135544) (xy 248.286524 -46.009814) (xy 248.25071 -46.045882)
			(xy 248.203974 -46.14291) (xy 248.279412 -46.218348)
		)
		(stroke
			(width 0)
			(type solid)
		)
		(fill yes)
		(layer "F.Cu")
		(net "M_B_ECC<2>")
	)
	(gr_poly
		(pts
			(xy 248.38533 -46.46803) (xy 248.432066 -46.371002) (xy 248.356628 -46.295564) (xy 248.2596 -46.3423)
			(xy 248.223532 -46.378114) (xy 248.349262 -46.503844)
		)
		(stroke
			(width 0)
			(type solid)
		)
		(fill yes)
		(layer "F.Cu")
		(net "M_B_ECC<7>")
	)
	(gr_poly
		(pts
			(xy 248.395998 -49.608232) (xy 248.395998 -49.501298) (xy 248.294398 -49.465992) (xy 248.243598 -49.465992)
			(xy 248.243598 -49.643792) (xy 248.294398 -49.643792)
		)
		(stroke
			(width 0)
			(type solid)
		)
		(fill yes)
		(layer "F.Cu")
		(net "M_B_DQS_DN<17>")
	)
	(gr_poly
		(pts
			(xy 248.395998 -49.176432) (xy 248.395998 -49.069498) (xy 248.294398 -49.034192) (xy 248.243598 -49.034192)
			(xy 248.243598 -49.211992) (xy 248.294398 -49.211992)
		)
		(stroke
			(width 0)
			(type solid)
		)
		(fill yes)
		(layer "F.Cu")
		(net "M_B_DQS_DN<17>")
	)
	(gr_poly
		(pts
			(xy 248.395998 -48.744632) (xy 248.395998 -48.637698) (xy 248.294398 -48.602392) (xy 248.243598 -48.602392)
			(xy 248.243598 -48.780192) (xy 248.294398 -48.780192)
		)
		(stroke
			(width 0)
			(type solid)
		)
		(fill yes)
		(layer "F.Cu")
		(net "M_B_DQS_DN<17>")
	)
	(gr_poly
		(pts
			(xy 248.395998 -48.312832) (xy 248.395998 -48.205898) (xy 248.294398 -48.170592) (xy 248.243598 -48.170592)
			(xy 248.243598 -48.348392) (xy 248.294398 -48.348392)
		)
		(stroke
			(width 0)
			(type solid)
		)
		(fill yes)
		(layer "F.Cu")
		(net "M_B_DQS_DN<17>")
	)
	(gr_poly
		(pts
			(xy 248.398538 -103.625396) (xy 248.362724 -103.589582) (xy 248.265696 -103.542846) (xy 248.190258 -103.618284)
			(xy 248.236994 -103.715312) (xy 248.272808 -103.751126)
		)
		(stroke
			(width 0)
			(type solid)
		)
		(fill yes)
		(layer "F.Cu")
		(net "M_E_DQS_DN<17>")
	)
	(gr_poly
		(pts
			(xy 248.418096 -103.389938) (xy 248.37136 -103.29291) (xy 248.335546 -103.257096) (xy 248.209816 -103.382826)
			(xy 248.245884 -103.41864) (xy 248.342658 -103.465376)
		)
		(stroke
			(width 0)
			(type solid)
		)
		(fill yes)
		(layer "F.Cu")
		(net "M_E_DQS_DP<17>")
	)
	(gr_poly
		(pts
			(xy 248.422414 -107.336336) (xy 248.377456 -107.291378) (xy 248.233946 -107.165648) (xy 248.162064 -107.23753)
			(xy 248.287794 -107.381294) (xy 248.332498 -107.426252)
		)
		(stroke
			(width 0)
			(type solid)
		)
		(fill yes)
		(layer "F.Cu")
		(net "M_E_ECC<3>")
	)
	(gr_poly
		(pts
			(xy 248.428764 -102.692454) (xy 248.377964 -102.692454) (xy 248.276364 -102.728014) (xy 248.276364 -102.834694)
			(xy 248.377964 -102.870254) (xy 248.428764 -102.870254)
		)
		(stroke
			(width 0)
			(type solid)
		)
		(fill yes)
		(layer "F.Cu")
		(net "M_E_DQS_DP<17>")
	)
	(gr_poly
		(pts
			(xy 248.428764 -102.260654) (xy 248.377964 -102.260654) (xy 248.276364 -102.296214) (xy 248.276364 -102.402894)
			(xy 248.377964 -102.438454) (xy 248.428764 -102.438454)
		)
		(stroke
			(width 0)
			(type solid)
		)
		(fill yes)
		(layer "F.Cu")
		(net "M_E_DQS_DP<17>")
	)
	(gr_poly
		(pts
			(xy 248.428764 -101.828854) (xy 248.377964 -101.828854) (xy 248.276364 -101.864414) (xy 248.276364 -101.971094)
			(xy 248.377964 -102.006654) (xy 248.428764 -102.006654)
		)
		(stroke
			(width 0)
			(type solid)
		)
		(fill yes)
		(layer "F.Cu")
		(net "M_E_DQS_DP<17>")
	)
	(gr_poly
		(pts
			(xy 248.428764 -101.397054) (xy 248.377964 -101.397054) (xy 248.276364 -101.432614) (xy 248.276364 -101.539294)
			(xy 248.377964 -101.574854) (xy 248.428764 -101.574854)
		)
		(stroke
			(width 0)
			(type solid)
		)
		(fill yes)
		(layer "F.Cu")
		(net "M_E_DQS_DP<17>")
	)
	(gr_poly
		(pts
			(xy 248.428764 -100.965254) (xy 248.377964 -100.965254) (xy 248.276364 -101.000814) (xy 248.276364 -101.107494)
			(xy 248.377964 -101.143054) (xy 248.428764 -101.143054)
		)
		(stroke
			(width 0)
			(type solid)
		)
		(fill yes)
		(layer "F.Cu")
		(net "M_E_DQS_DP<17>")
	)
	(gr_poly
		(pts
			(xy 248.428764 -100.533454) (xy 248.377964 -100.533454) (xy 248.276364 -100.569014) (xy 248.276364 -100.675694)
			(xy 248.377964 -100.711254) (xy 248.428764 -100.711254)
		)
		(stroke
			(width 0)
			(type solid)
		)
		(fill yes)
		(layer "F.Cu")
		(net "M_E_DQS_DP<17>")
	)
	(gr_poly
		(pts
			(xy 248.42978 -47.95012) (xy 248.465594 -47.914052) (xy 248.339864 -47.788322) (xy 248.30405 -47.82439)
			(xy 248.257314 -47.921418) (xy 248.332752 -47.996856)
		)
		(stroke
			(width 0)
			(type solid)
		)
		(fill yes)
		(layer "F.Cu")
		(net "M_B_DQS_DN<8>")
	)
	(gr_poly
		(pts
			(xy 248.440448 -105.97134) (xy 248.314718 -105.82783) (xy 248.278904 -105.791762) (xy 248.188988 -105.881678)
			(xy 248.225056 -105.917492) (xy 248.368566 -106.043222)
		)
		(stroke
			(width 0)
			(type solid)
		)
		(fill yes)
		(layer "F.Cu")
		(net "M_E_ECC<6>")
	)
	(gr_poly
		(pts
			(xy 248.466102 -46.692566) (xy 248.501916 -46.656498) (xy 248.376186 -46.530768) (xy 248.340372 -46.566836)
			(xy 248.293636 -46.663864) (xy 248.369074 -46.739302)
		)
		(stroke
			(width 0)
			(type solid)
		)
		(fill yes)
		(layer "F.Cu")
		(net "M_B_ECC<7>")
	)
	(gr_poly
		(pts
			(xy 248.470166 -52.914296) (xy 248.425716 -52.914296) (xy 248.255536 -53.003196) (xy 248.255536 -53.224176)
			(xy 248.425716 -53.313076) (xy 248.470166 -53.313076)
		)
		(stroke
			(width 0)
			(type solid)
		)
		(fill yes)
		(layer "F.Cu")
		(net "M_B_DQS_DN<8>")
	)
	(gr_poly
		(pts
			(xy 248.474992 -46.988984) (xy 248.521728 -46.891956) (xy 248.44629 -46.816518) (xy 248.349262 -46.863254)
			(xy 248.313194 -46.899068) (xy 248.438924 -47.024798)
		)
		(stroke
			(width 0)
			(type solid)
		)
		(fill yes)
		(layer "F.Cu")
		(net "M_B_ECC<6>")
	)
	(gr_poly
		(pts
			(xy 248.502424 -104.462834) (xy 248.502424 -104.356154) (xy 248.400824 -104.320594) (xy 248.350024 -104.320594)
			(xy 248.350024 -104.498394) (xy 248.400824 -104.498394)
		)
		(stroke
			(width 0)
			(type solid)
		)
		(fill yes)
		(layer "F.Cu")
		(net "M_E_DQS_DN<8>")
	)
	(gr_poly
		(pts
			(xy 248.51233 -105.558336) (xy 248.476516 -105.522522) (xy 248.332752 -105.396792) (xy 248.26087 -105.46842)
			(xy 248.3866 -105.612184) (xy 248.422414 -105.648252)
		)
		(stroke
			(width 0)
			(type solid)
		)
		(fill yes)
		(layer "F.Cu")
		(net "M_E_ECC<6>")
	)
	(gr_poly
		(pts
			(xy 248.530364 -106.995214) (xy 248.404634 -106.85145) (xy 248.368566 -106.815636) (xy 248.278904 -106.905298)
			(xy 248.314718 -106.941366) (xy 248.458482 -107.067096)
		)
		(stroke
			(width 0)
			(type solid)
		)
		(fill yes)
		(layer "F.Cu")
		(net "M_E_ECC<2>")
	)
	(gr_poly
		(pts
			(xy 248.548398 -49.681892) (xy 248.497598 -49.681892) (xy 248.395998 -49.717198) (xy 248.395998 -49.824132)
			(xy 248.497598 -49.859692) (xy 248.548398 -49.859692)
		)
		(stroke
			(width 0)
			(type solid)
		)
		(fill yes)
		(layer "F.Cu")
		(net "M_B_DQS_DN<8>")
	)
	(gr_poly
		(pts
			(xy 248.548398 -49.250092) (xy 248.497598 -49.250092) (xy 248.395998 -49.285398) (xy 248.395998 -49.392332)
			(xy 248.497598 -49.427892) (xy 248.548398 -49.427892)
		)
		(stroke
			(width 0)
			(type solid)
		)
		(fill yes)
		(layer "F.Cu")
		(net "M_B_DQS_DN<8>")
	)
	(gr_poly
		(pts
			(xy 248.548398 -48.818292) (xy 248.497598 -48.818292) (xy 248.395998 -48.853598) (xy 248.395998 -48.960532)
			(xy 248.497598 -48.996092) (xy 248.548398 -48.996092)
		)
		(stroke
			(width 0)
			(type solid)
		)
		(fill yes)
		(layer "F.Cu")
		(net "M_B_DQS_DN<8>")
	)
	(gr_poly
		(pts
			(xy 248.548398 -48.386492) (xy 248.497598 -48.386492) (xy 248.395998 -48.421798) (xy 248.395998 -48.528732)
			(xy 248.497598 -48.564292) (xy 248.548398 -48.564292)
		)
		(stroke
			(width 0)
			(type solid)
		)
		(fill yes)
		(layer "F.Cu")
		(net "M_B_DQS_DN<8>")
	)
	(gr_poly
		(pts
			(xy 248.555764 -47.21352) (xy 248.591578 -47.177452) (xy 248.465848 -47.051722) (xy 248.430034 -47.08779)
			(xy 248.383298 -47.184818) (xy 248.458736 -47.260256)
		)
		(stroke
			(width 0)
			(type solid)
		)
		(fill yes)
		(layer "F.Cu")
		(net "M_B_ECC<6>")
	)
	(gr_poly
		(pts
			(xy 248.564654 -47.509938) (xy 248.61139 -47.41291) (xy 248.535952 -47.337472) (xy 248.438924 -47.384208)
			(xy 248.40311 -47.420276) (xy 248.528586 -47.545752)
		)
		(stroke
			(width 0)
			(type solid)
		)
		(fill yes)
		(layer "F.Cu")
		(net "M_B_DQS_DP<8>")
	)
	(gr_poly
		(pts
			(xy 248.581164 -103.050594) (xy 248.581164 -102.943914) (xy 248.479564 -102.908354) (xy 248.428764 -102.908354)
			(xy 248.428764 -103.086154) (xy 248.479564 -103.086154)
		)
		(stroke
			(width 0)
			(type solid)
		)
		(fill yes)
		(layer "F.Cu")
		(net "M_E_DQS_DP<17>")
	)
	(gr_poly
		(pts
			(xy 248.581164 -102.618794) (xy 248.581164 -102.512114) (xy 248.479564 -102.476554) (xy 248.428764 -102.476554)
			(xy 248.428764 -102.654354) (xy 248.479564 -102.654354)
		)
		(stroke
			(width 0)
			(type solid)
		)
		(fill yes)
		(layer "F.Cu")
		(net "M_E_DQS_DP<17>")
	)
	(gr_poly
		(pts
			(xy 248.581164 -102.186994) (xy 248.581164 -102.080314) (xy 248.479564 -102.044754) (xy 248.428764 -102.044754)
			(xy 248.428764 -102.222554) (xy 248.479564 -102.222554)
		)
		(stroke
			(width 0)
			(type solid)
		)
		(fill yes)
		(layer "F.Cu")
		(net "M_E_DQS_DP<17>")
	)
	(gr_poly
		(pts
			(xy 248.581164 -101.755194) (xy 248.581164 -101.648514) (xy 248.479564 -101.612954) (xy 248.428764 -101.612954)
			(xy 248.428764 -101.790754) (xy 248.479564 -101.790754)
		)
		(stroke
			(width 0)
			(type solid)
		)
		(fill yes)
		(layer "F.Cu")
		(net "M_E_DQS_DP<17>")
	)
	(gr_poly
		(pts
			(xy 248.581164 -101.323394) (xy 248.581164 -101.216714) (xy 248.479564 -101.181154) (xy 248.428764 -101.181154)
			(xy 248.428764 -101.358954) (xy 248.479564 -101.358954)
		)
		(stroke
			(width 0)
			(type solid)
		)
		(fill yes)
		(layer "F.Cu")
		(net "M_E_DQS_DP<17>")
	)
	(gr_poly
		(pts
			(xy 248.581164 -100.891594) (xy 248.581164 -100.784914) (xy 248.479564 -100.749354) (xy 248.428764 -100.749354)
			(xy 248.428764 -100.927154) (xy 248.479564 -100.927154)
		)
		(stroke
			(width 0)
			(type solid)
		)
		(fill yes)
		(layer "F.Cu")
		(net "M_E_DQS_DP<17>")
	)
	(gr_poly
		(pts
			(xy 248.591832 -45.955966) (xy 248.63679 -45.911008) (xy 248.51106 -45.785278) (xy 248.466356 -45.830236)
			(xy 248.41962 -45.927264) (xy 248.495058 -46.002702)
		)
		(stroke
			(width 0)
			(type solid)
		)
		(fill yes)
		(layer "F.Cu")
		(net "M_B_ECC<3>")
	)
	(gr_poly
		(pts
			(xy 248.600976 -46.252384) (xy 248.647712 -46.155356) (xy 248.572274 -46.079918) (xy 248.475246 -46.126654)
			(xy 248.439178 -46.162468) (xy 248.564908 -46.288198)
		)
		(stroke
			(width 0)
			(type solid)
		)
		(fill yes)
		(layer "F.Cu")
		(net "M_B_ECC<2>")
	)
	(gr_poly
		(pts
			(xy 248.601992 -106.58221) (xy 248.566178 -106.546142) (xy 248.422414 -106.420412) (xy 248.350786 -106.492294)
			(xy 248.476516 -106.636058) (xy 248.51233 -106.671872)
		)
		(stroke
			(width 0)
			(type solid)
		)
		(fill yes)
		(layer "F.Cu")
		(net "M_E_ECC<2>")
	)
	(gr_poly
		(pts
			(xy 248.614184 -103.841042) (xy 248.57837 -103.805228) (xy 248.481342 -103.758492) (xy 248.405904 -103.83393)
			(xy 248.45264 -103.930958) (xy 248.488454 -103.966772)
		)
		(stroke
			(width 0)
			(type solid)
		)
		(fill yes)
		(layer "F.Cu")
		(net "M_E_DQS_DN<8>")
	)
	(gr_poly
		(pts
			(xy 248.62917 -105.226104) (xy 248.50344 -105.08234) (xy 248.467372 -105.046526) (xy 248.37771 -105.136188)
			(xy 248.413524 -105.172256) (xy 248.557288 -105.297986)
		)
		(stroke
			(width 0)
			(type solid)
		)
		(fill yes)
		(layer "F.Cu")
		(net "M_E_DQS_DP<8>")
	)
	(gr_poly
		(pts
			(xy 248.633742 -103.605584) (xy 248.587006 -103.508556) (xy 248.551192 -103.472742) (xy 248.425462 -103.598472)
			(xy 248.46153 -103.634286) (xy 248.558304 -103.681022)
		)
		(stroke
			(width 0)
			(type solid)
		)
		(fill yes)
		(layer "F.Cu")
		(net "M_E_DQS_DN<17>")
	)
	(gr_poly
		(pts
			(xy 248.645426 -47.734474) (xy 248.681494 -47.69866) (xy 248.555764 -47.57293) (xy 248.519696 -47.608744)
			(xy 248.47296 -47.705772) (xy 248.548398 -47.78121)
		)
		(stroke
			(width 0)
			(type solid)
		)
		(fill yes)
		(layer "F.Cu")
		(net "M_B_DQS_DP<8>")
	)
	(gr_poly
		(pts
			(xy 248.654824 -104.536494) (xy 248.604024 -104.536494) (xy 248.502424 -104.572054) (xy 248.502424 -104.678734)
			(xy 248.604024 -104.714294) (xy 248.654824 -104.714294)
		)
		(stroke
			(width 0)
			(type solid)
		)
		(fill yes)
		(layer "F.Cu")
		(net "M_E_DQS_DP<8>")
	)
	(gr_poly
		(pts
			(xy 248.681748 -46.47692) (xy 248.717562 -46.440852) (xy 248.591832 -46.315122) (xy 248.556018 -46.35119)
			(xy 248.509282 -46.448218) (xy 248.58472 -46.523656)
		)
		(stroke
			(width 0)
			(type solid)
		)
		(fill yes)
		(layer "F.Cu")
		(net "M_B_ECC<2>")
	)
	(gr_poly
		(pts
			(xy 248.690638 -46.773338) (xy 248.737374 -46.67631) (xy 248.661936 -46.600872) (xy 248.564908 -46.647608)
			(xy 248.52884 -46.683422) (xy 248.65457 -46.809152)
		)
		(stroke
			(width 0)
			(type solid)
		)
		(fill yes)
		(layer "F.Cu")
		(net "M_B_ECC<7>")
	)
	(gr_poly
		(pts
			(xy 248.700798 -49.608232) (xy 248.700798 -49.501298) (xy 248.599198 -49.465992) (xy 248.548398 -49.465992)
			(xy 248.548398 -49.643792) (xy 248.599198 -49.643792)
		)
		(stroke
			(width 0)
			(type solid)
		)
		(fill yes)
		(layer "F.Cu")
		(net "M_B_DQS_DN<8>")
	)
	(gr_poly
		(pts
			(xy 248.700798 -49.176432) (xy 248.700798 -49.069498) (xy 248.599198 -49.034192) (xy 248.548398 -49.034192)
			(xy 248.548398 -49.211992) (xy 248.599198 -49.211992)
		)
		(stroke
			(width 0)
			(type solid)
		)
		(fill yes)
		(layer "F.Cu")
		(net "M_B_DQS_DN<8>")
	)
	(gr_poly
		(pts
			(xy 248.700798 -48.744632) (xy 248.700798 -48.637698) (xy 248.599198 -48.602392) (xy 248.548398 -48.602392)
			(xy 248.548398 -48.780192) (xy 248.599198 -48.780192)
		)
		(stroke
			(width 0)
			(type solid)
		)
		(fill yes)
		(layer "F.Cu")
		(net "M_B_DQS_DN<8>")
	)
	(gr_poly
		(pts
			(xy 248.700798 -48.312832) (xy 248.700798 -48.205898) (xy 248.599198 -48.170592) (xy 248.548398 -48.170592)
			(xy 248.548398 -48.348392) (xy 248.599198 -48.348392)
		)
		(stroke
			(width 0)
			(type solid)
		)
		(fill yes)
		(layer "F.Cu")
		(net "M_B_DQS_DN<8>")
	)
	(gr_poly
		(pts
			(xy 248.718832 -106.249724) (xy 248.593102 -106.106214) (xy 248.557288 -106.070146) (xy 248.467372 -106.160062)
			(xy 248.50344 -106.195876) (xy 248.64695 -106.321606)
		)
		(stroke
			(width 0)
			(type solid)
		)
		(fill yes)
		(layer "F.Cu")
		(net "M_E_ECC<7>")
	)
	(gr_poly
		(pts
			(xy 248.733564 -102.692454) (xy 248.682764 -102.692454) (xy 248.581164 -102.728014) (xy 248.581164 -102.834694)
			(xy 248.682764 -102.870254) (xy 248.733564 -102.870254)
		)
		(stroke
			(width 0)
			(type solid)
		)
		(fill yes)
		(layer "F.Cu")
		(net "M_E_DQS_DN<17>")
	)
	(gr_poly
		(pts
			(xy 248.733564 -102.260654) (xy 248.682764 -102.260654) (xy 248.581164 -102.296214) (xy 248.581164 -102.402894)
			(xy 248.682764 -102.438454) (xy 248.733564 -102.438454)
		)
		(stroke
			(width 0)
			(type solid)
		)
		(fill yes)
		(layer "F.Cu")
		(net "M_E_DQS_DN<17>")
	)
	(gr_poly
		(pts
			(xy 248.733564 -101.828854) (xy 248.682764 -101.828854) (xy 248.581164 -101.864414) (xy 248.581164 -101.971094)
			(xy 248.682764 -102.006654) (xy 248.733564 -102.006654)
		)
		(stroke
			(width 0)
			(type solid)
		)
		(fill yes)
		(layer "F.Cu")
		(net "M_E_DQS_DN<17>")
	)
	(gr_poly
		(pts
			(xy 248.733564 -101.397054) (xy 248.682764 -101.397054) (xy 248.581164 -101.432614) (xy 248.581164 -101.539294)
			(xy 248.682764 -101.574854) (xy 248.733564 -101.574854)
		)
		(stroke
			(width 0)
			(type solid)
		)
		(fill yes)
		(layer "F.Cu")
		(net "M_E_DQS_DN<17>")
	)
	(gr_poly
		(pts
			(xy 248.733564 -100.965254) (xy 248.682764 -100.965254) (xy 248.581164 -101.000814) (xy 248.581164 -101.107494)
			(xy 248.682764 -101.143054) (xy 248.733564 -101.143054)
		)
		(stroke
			(width 0)
			(type solid)
		)
		(fill yes)
		(layer "F.Cu")
		(net "M_E_DQS_DN<17>")
	)
	(gr_poly
		(pts
			(xy 248.733564 -100.533454) (xy 248.682764 -100.533454) (xy 248.581164 -100.569014) (xy 248.581164 -100.675694)
			(xy 248.682764 -100.711254) (xy 248.733564 -100.711254)
		)
		(stroke
			(width 0)
			(type solid)
		)
		(fill yes)
		(layer "F.Cu")
		(net "M_E_DQS_DN<17>")
	)
	(gr_poly
		(pts
			(xy 248.77141 -46.997874) (xy 248.807224 -46.961806) (xy 248.681494 -46.836076) (xy 248.64568 -46.872144)
			(xy 248.598944 -46.969172) (xy 248.674382 -47.04461)
		)
		(stroke
			(width 0)
			(type solid)
		)
		(fill yes)
		(layer "F.Cu")
		(net "M_B_ECC<7>")
	)
	(gr_poly
		(pts
			(xy 248.7803 -47.294292) (xy 248.827036 -47.197264) (xy 248.751598 -47.121826) (xy 248.65457 -47.168562)
			(xy 248.618756 -47.20463) (xy 248.744232 -47.330106)
		)
		(stroke
			(width 0)
			(type solid)
		)
		(fill yes)
		(layer "F.Cu")
		(net "M_B_ECC<6>")
	)
	(gr_poly
		(pts
			(xy 248.790714 -105.83672) (xy 248.7549 -105.800906) (xy 248.611136 -105.675176) (xy 248.539254 -105.746804)
			(xy 248.664984 -105.890568) (xy 248.700798 -105.926636)
		)
		(stroke
			(width 0)
			(type solid)
		)
		(fill yes)
		(layer "F.Cu")
		(net "M_E_ECC<7>")
	)
	(gr_poly
		(pts
			(xy 248.807224 -104.462834) (xy 248.807224 -104.356154) (xy 248.705624 -104.320594) (xy 248.654824 -104.320594)
			(xy 248.654824 -104.498394) (xy 248.705624 -104.498394)
		)
		(stroke
			(width 0)
			(type solid)
		)
		(fill yes)
		(layer "F.Cu")
		(net "M_E_DQS_DP<8>")
	)
	(gr_poly
		(pts
			(xy 248.82983 -104.056688) (xy 248.794016 -104.02062) (xy 248.696988 -103.974138) (xy 248.62155 -104.049576)
			(xy 248.668286 -104.14635) (xy 248.7041 -104.182418)
		)
		(stroke
			(width 0)
			(type solid)
		)
		(fill yes)
		(layer "F.Cu")
		(net "M_E_DQS_DP<8>")
	)
	(gr_poly
		(pts
			(xy 248.849388 -103.82123) (xy 248.802652 -103.724202) (xy 248.766838 -103.688388) (xy 248.641108 -103.814118)
			(xy 248.677176 -103.849932) (xy 248.77395 -103.896668)
		)
		(stroke
			(width 0)
			(type solid)
		)
		(fill yes)
		(layer "F.Cu")
		(net "M_E_DQS_DN<8>")
	)
	(gr_poly
		(pts
			(xy 248.853198 -49.681892) (xy 248.802398 -49.681892) (xy 248.700798 -49.717198) (xy 248.700798 -49.824132)
			(xy 248.802398 -49.859692) (xy 248.853198 -49.859692)
		)
		(stroke
			(width 0)
			(type solid)
		)
		(fill yes)
		(layer "F.Cu")
		(net "M_B_DQS_DP<8>")
	)
	(gr_poly
		(pts
			(xy 248.853198 -49.250092) (xy 248.802398 -49.250092) (xy 248.700798 -49.285398) (xy 248.700798 -49.392332)
			(xy 248.802398 -49.427892) (xy 248.853198 -49.427892)
		)
		(stroke
			(width 0)
			(type solid)
		)
		(fill yes)
		(layer "F.Cu")
		(net "M_B_DQS_DP<8>")
	)
	(gr_poly
		(pts
			(xy 248.853198 -48.818292) (xy 248.802398 -48.818292) (xy 248.700798 -48.853598) (xy 248.700798 -48.960532)
			(xy 248.802398 -48.996092) (xy 248.853198 -48.996092)
		)
		(stroke
			(width 0)
			(type solid)
		)
		(fill yes)
		(layer "F.Cu")
		(net "M_B_DQS_DP<8>")
	)
	(gr_poly
		(pts
			(xy 248.853198 -48.386492) (xy 248.802398 -48.386492) (xy 248.700798 -48.421798) (xy 248.700798 -48.528732)
			(xy 248.802398 -48.564292) (xy 248.853198 -48.564292)
		)
		(stroke
			(width 0)
			(type solid)
		)
		(fill yes)
		(layer "F.Cu")
		(net "M_B_DQS_DP<8>")
	)
	(gr_poly
		(pts
			(xy 248.853198 -47.954692) (xy 248.802398 -47.954692) (xy 248.700798 -47.989998) (xy 248.700798 -48.096932)
			(xy 248.802398 -48.132492) (xy 248.853198 -48.132492)
		)
		(stroke
			(width 0)
			(type solid)
		)
		(fill yes)
		(layer "F.Cu")
		(net "M_B_DQS_DP<8>")
	)
	(gr_poly
		(pts
			(xy 248.861072 -47.518828) (xy 248.89714 -47.483014) (xy 248.77141 -47.357284) (xy 248.735342 -47.393098)
			(xy 248.688606 -47.490126) (xy 248.764044 -47.565564)
		)
		(stroke
			(width 0)
			(type solid)
		)
		(fill yes)
		(layer "F.Cu")
		(net "M_B_ECC<6>")
	)
	(gr_poly
		(pts
			(xy 248.869962 -47.815246) (xy 248.916698 -47.718218) (xy 248.84126 -47.64278) (xy 248.744232 -47.689516)
			(xy 248.708418 -47.725584) (xy 248.833894 -47.85106)
		)
		(stroke
			(width 0)
			(type solid)
		)
		(fill yes)
		(layer "F.Cu")
		(net "M_B_DQS_DP<8>")
	)
	(gr_poly
		(pts
			(xy 248.885964 -103.050594) (xy 248.885964 -102.943914) (xy 248.784364 -102.908354) (xy 248.733564 -102.908354)
			(xy 248.733564 -103.086154) (xy 248.784364 -103.086154)
		)
		(stroke
			(width 0)
			(type solid)
		)
		(fill yes)
		(layer "F.Cu")
		(net "M_E_DQS_DN<17>")
	)
	(gr_poly
		(pts
			(xy 248.885964 -102.618794) (xy 248.885964 -102.512114) (xy 248.784364 -102.476554) (xy 248.733564 -102.476554)
			(xy 248.733564 -102.654354) (xy 248.784364 -102.654354)
		)
		(stroke
			(width 0)
			(type solid)
		)
		(fill yes)
		(layer "F.Cu")
		(net "M_E_DQS_DN<17>")
	)
	(gr_poly
		(pts
			(xy 248.885964 -102.186994) (xy 248.885964 -102.080314) (xy 248.784364 -102.044754) (xy 248.733564 -102.044754)
			(xy 248.733564 -102.222554) (xy 248.784364 -102.222554)
		)
		(stroke
			(width 0)
			(type solid)
		)
		(fill yes)
		(layer "F.Cu")
		(net "M_E_DQS_DN<17>")
	)
	(gr_poly
		(pts
			(xy 248.885964 -101.755194) (xy 248.885964 -101.648514) (xy 248.784364 -101.612954) (xy 248.733564 -101.612954)
			(xy 248.733564 -101.790754) (xy 248.784364 -101.790754)
		)
		(stroke
			(width 0)
			(type solid)
		)
		(fill yes)
		(layer "F.Cu")
		(net "M_E_DQS_DN<17>")
	)
	(gr_poly
		(pts
			(xy 248.885964 -101.323394) (xy 248.885964 -101.216714) (xy 248.784364 -101.181154) (xy 248.733564 -101.181154)
			(xy 248.733564 -101.358954) (xy 248.784364 -101.358954)
		)
		(stroke
			(width 0)
			(type solid)
		)
		(fill yes)
		(layer "F.Cu")
		(net "M_E_DQS_DN<17>")
	)
	(gr_poly
		(pts
			(xy 248.885964 -100.891594) (xy 248.885964 -100.784914) (xy 248.784364 -100.749354) (xy 248.733564 -100.749354)
			(xy 248.733564 -100.927154) (xy 248.784364 -100.927154)
		)
		(stroke
			(width 0)
			(type solid)
		)
		(fill yes)
		(layer "F.Cu")
		(net "M_E_DQS_DN<17>")
	)
	(gr_poly
		(pts
			(xy 248.889266 -106.869484) (xy 248.844562 -106.824526) (xy 248.700798 -106.698796) (xy 248.628916 -106.770678)
			(xy 248.754646 -106.914188) (xy 248.799604 -106.959146)
		)
		(stroke
			(width 0)
			(type solid)
		)
		(fill yes)
		(layer "F.Cu")
		(net "M_E_ECC<3>")
	)
	(gr_poly
		(pts
			(xy 248.897394 -46.261274) (xy 248.942098 -46.216316) (xy 248.816368 -46.090586) (xy 248.771664 -46.135544)
			(xy 248.724928 -46.232572) (xy 248.800366 -46.30801)
		)
		(stroke
			(width 0)
			(type solid)
		)
		(fill yes)
		(layer "F.Cu")
		(net "M_B_ECC<3>")
	)
	(gr_poly
		(pts
			(xy 248.906284 -46.557692) (xy 248.95302 -46.460664) (xy 248.877582 -46.385226) (xy 248.780554 -46.431962)
			(xy 248.744486 -46.467776) (xy 248.870216 -46.593506)
		)
		(stroke
			(width 0)
			(type solid)
		)
		(fill yes)
		(layer "F.Cu")
		(net "M_B_ECC<2>")
	)
	(gr_poly
		(pts
			(xy 248.907554 -105.504488) (xy 248.781824 -105.360724) (xy 248.745756 -105.32491) (xy 248.656094 -105.414572)
			(xy 248.691908 -105.45064) (xy 248.835672 -105.57637)
		)
		(stroke
			(width 0)
			(type solid)
		)
		(fill yes)
		(layer "F.Cu")
		(net "M_E_ECC<6>")
	)
	(gr_poly
		(pts
			(xy 248.919492 -103.535734) (xy 248.883678 -103.49992) (xy 248.78665 -103.453184) (xy 248.711212 -103.528622)
			(xy 248.757948 -103.62565) (xy 248.793762 -103.661464)
		)
		(stroke
			(width 0)
			(type solid)
		)
		(fill yes)
		(layer "F.Cu")
		(net "M_E_DQS_DN<8>")
	)
	(gr_poly
		(pts
			(xy 248.959624 -104.536494) (xy 248.908824 -104.536494) (xy 248.807224 -104.572054) (xy 248.807224 -104.678734)
			(xy 248.908824 -104.714294) (xy 248.959624 -104.714294)
		)
		(stroke
			(width 0)
			(type solid)
		)
		(fill yes)
		(layer "F.Cu")
		(net "M_E_ECC<6>")
	)
	(gr_poly
		(pts
			(xy 248.987056 -46.782228) (xy 249.02287 -46.74616) (xy 248.89714 -46.62043) (xy 248.861326 -46.656498)
			(xy 248.81459 -46.753526) (xy 248.890028 -46.828964)
		)
		(stroke
			(width 0)
			(type solid)
		)
		(fill yes)
		(layer "F.Cu")
		(net "M_B_ECC<2>")
	)
	(gr_poly
		(pts
			(xy 248.995946 -47.078646) (xy 249.042682 -46.981618) (xy 248.967244 -46.90618) (xy 248.870216 -46.952916)
			(xy 248.834402 -46.988984) (xy 248.959878 -47.11446)
		)
		(stroke
			(width 0)
			(type solid)
		)
		(fill yes)
		(layer "F.Cu")
		(net "M_B_ECC<7>")
	)
	(gr_poly
		(pts
			(xy 248.997216 -106.528108) (xy 248.871486 -106.384598) (xy 248.835672 -106.34853) (xy 248.745756 -106.438446)
			(xy 248.781824 -106.47426) (xy 248.925334 -106.59999)
		)
		(stroke
			(width 0)
			(type solid)
		)
		(fill yes)
		(layer "F.Cu")
		(net "M_E_ECC<2>")
	)
	(gr_poly
		(pts
			(xy 249.005598 -49.608232) (xy 249.005598 -49.501298) (xy 248.903998 -49.465992) (xy 248.853198 -49.465992)
			(xy 248.853198 -49.643792) (xy 248.903998 -49.643792)
		)
		(stroke
			(width 0)
			(type solid)
		)
		(fill yes)
		(layer "F.Cu")
		(net "M_B_DQS_DP<8>")
	)
	(gr_poly
		(pts
			(xy 249.005598 -49.176432) (xy 249.005598 -49.069498) (xy 248.903998 -49.034192) (xy 248.853198 -49.034192)
			(xy 248.853198 -49.211992) (xy 248.903998 -49.211992)
		)
		(stroke
			(width 0)
			(type solid)
		)
		(fill yes)
		(layer "F.Cu")
		(net "M_B_DQS_DP<8>")
	)
	(gr_poly
		(pts
			(xy 249.005598 -48.744632) (xy 249.005598 -48.637698) (xy 248.903998 -48.602392) (xy 248.853198 -48.602392)
			(xy 248.853198 -48.780192) (xy 248.903998 -48.780192)
		)
		(stroke
			(width 0)
			(type solid)
		)
		(fill yes)
		(layer "F.Cu")
		(net "M_B_DQS_DP<8>")
	)
	(gr_poly
		(pts
			(xy 249.005598 -48.312832) (xy 249.005598 -48.205898) (xy 248.903998 -48.170592) (xy 248.853198 -48.170592)
			(xy 248.853198 -48.348392) (xy 248.903998 -48.348392)
		)
		(stroke
			(width 0)
			(type solid)
		)
		(fill yes)
		(layer "F.Cu")
		(net "M_B_DQS_DP<8>")
	)
	(gr_poly
		(pts
			(xy 249.008392 -53.725826) (xy 249.008392 -53.504846) (xy 248.838212 -53.415946) (xy 248.793762 -53.415946)
			(xy 248.793762 -53.814726) (xy 248.838212 -53.814726)
		)
		(stroke
			(width 0)
			(type solid)
		)
		(fill yes)
		(layer "F.Cu")
		(net "M_B_DQS_DP<8>")
	)
	(gr_poly
		(pts
			(xy 249.008392 -52.735226) (xy 249.008392 -52.514246) (xy 248.838212 -52.425346) (xy 248.793762 -52.425346)
			(xy 248.793762 -52.824126) (xy 248.838212 -52.824126)
		)
		(stroke
			(width 0)
			(type solid)
		)
		(fill yes)
		(layer "F.Cu")
		(net "M_B_DQS_DP<8>")
	)
	(gr_poly
		(pts
			(xy 249.038364 -103.124254) (xy 248.987564 -103.124254) (xy 248.885964 -103.159814) (xy 248.885964 -103.266494)
			(xy 248.987564 -103.302054) (xy 249.038364 -103.302054)
		)
		(stroke
			(width 0)
			(type solid)
		)
		(fill yes)
		(layer "F.Cu")
		(net "M_E_DQS_DN<8>")
	)
	(gr_poly
		(pts
			(xy 249.038364 -102.692454) (xy 248.987564 -102.692454) (xy 248.885964 -102.728014) (xy 248.885964 -102.834694)
			(xy 248.987564 -102.870254) (xy 249.038364 -102.870254)
		)
		(stroke
			(width 0)
			(type solid)
		)
		(fill yes)
		(layer "F.Cu")
		(net "M_E_DQS_DN<8>")
	)
	(gr_poly
		(pts
			(xy 249.038364 -102.260654) (xy 248.987564 -102.260654) (xy 248.885964 -102.296214) (xy 248.885964 -102.402894)
			(xy 248.987564 -102.438454) (xy 249.038364 -102.438454)
		)
		(stroke
			(width 0)
			(type solid)
		)
		(fill yes)
		(layer "F.Cu")
		(net "M_E_DQS_DN<8>")
	)
	(gr_poly
		(pts
			(xy 249.038364 -101.828854) (xy 248.987564 -101.828854) (xy 248.885964 -101.864414) (xy 248.885964 -101.971094)
			(xy 248.987564 -102.006654) (xy 249.038364 -102.006654)
		)
		(stroke
			(width 0)
			(type solid)
		)
		(fill yes)
		(layer "F.Cu")
		(net "M_E_DQS_DN<8>")
	)
	(gr_poly
		(pts
			(xy 249.038364 -101.397054) (xy 248.987564 -101.397054) (xy 248.885964 -101.432614) (xy 248.885964 -101.539294)
			(xy 248.987564 -101.574854) (xy 249.038364 -101.574854)
		)
		(stroke
			(width 0)
			(type solid)
		)
		(fill yes)
		(layer "F.Cu")
		(net "M_E_DQS_DN<8>")
	)
	(gr_poly
		(pts
			(xy 249.038364 -100.965254) (xy 248.987564 -100.965254) (xy 248.885964 -101.000814) (xy 248.885964 -101.107494)
			(xy 248.987564 -101.143054) (xy 249.038364 -101.143054)
		)
		(stroke
			(width 0)
			(type solid)
		)
		(fill yes)
		(layer "F.Cu")
		(net "M_E_DQS_DN<8>")
	)
	(gr_poly
		(pts
			(xy 249.038364 -100.533454) (xy 248.987564 -100.533454) (xy 248.885964 -100.569014) (xy 248.885964 -100.675694)
			(xy 248.987564 -100.711254) (xy 249.038364 -100.711254)
		)
		(stroke
			(width 0)
			(type solid)
		)
		(fill yes)
		(layer "F.Cu")
		(net "M_E_DQS_DN<8>")
	)
	(gr_poly
		(pts
			(xy 249.065034 -104.036876) (xy 249.018298 -103.939848) (xy 248.982484 -103.904034) (xy 248.856754 -104.029764)
			(xy 248.892822 -104.065578) (xy 248.989596 -104.112314)
		)
		(stroke
			(width 0)
			(type solid)
		)
		(fill yes)
		(layer "F.Cu")
		(net "M_E_DQS_DP<8>")
	)
	(gr_poly
		(pts
			(xy 249.069098 -106.115104) (xy 249.033284 -106.07929) (xy 248.88952 -105.95356) (xy 248.817638 -106.025188)
			(xy 248.943368 -106.168952) (xy 248.979182 -106.20502)
		)
		(stroke
			(width 0)
			(type solid)
		)
		(fill yes)
		(layer "F.Cu")
		(net "M_E_ECC<2>")
	)
	(gr_poly
		(pts
			(xy 249.076718 -47.303182) (xy 249.112786 -47.267368) (xy 248.987056 -47.141638) (xy 248.950988 -47.177452)
			(xy 248.904252 -47.27448) (xy 248.97969 -47.349918)
		)
		(stroke
			(width 0)
			(type solid)
		)
		(fill yes)
		(layer "F.Cu")
		(net "M_B_ECC<7>")
	)
	(gr_poly
		(pts
			(xy 249.085608 -47.5996) (xy 249.132344 -47.502572) (xy 249.056906 -47.427134) (xy 248.959878 -47.47387)
			(xy 248.924064 -47.509938) (xy 249.04954 -47.635414)
		)
		(stroke
			(width 0)
			(type solid)
		)
		(fill yes)
		(layer "F.Cu")
		(net "M_B_ECC<6>")
	)
	(gr_poly
		(pts
			(xy 249.112024 -104.894634) (xy 249.112024 -104.787954) (xy 249.010424 -104.752394) (xy 248.959624 -104.752394)
			(xy 248.959624 -104.930194) (xy 249.010424 -104.930194)
		)
		(stroke
			(width 0)
			(type solid)
		)
		(fill yes)
		(layer "F.Cu")
		(net "M_E_ECC<6>")
	)
	(gr_poly
		(pts
			(xy 249.135138 -103.75138) (xy 249.099324 -103.715312) (xy 249.002296 -103.66883) (xy 248.926858 -103.744268)
			(xy 248.973594 -103.841042) (xy 249.009408 -103.87711)
		)
		(stroke
			(width 0)
			(type solid)
		)
		(fill yes)
		(layer "F.Cu")
		(net "M_E_DQS_DP<8>")
	)
	(gr_poly
		(pts
			(xy 249.154696 -103.515922) (xy 249.10796 -103.418894) (xy 249.072146 -103.38308) (xy 248.946416 -103.50881)
			(xy 248.982484 -103.544624) (xy 249.079258 -103.59136)
		)
		(stroke
			(width 0)
			(type solid)
		)
		(fill yes)
		(layer "F.Cu")
		(net "M_E_DQS_DN<8>")
	)
	(gr_poly
		(pts
			(xy 249.157998 -49.681892) (xy 249.107198 -49.681892) (xy 249.005598 -49.717198) (xy 249.005598 -49.824132)
			(xy 249.107198 -49.859692) (xy 249.157998 -49.859692)
		)
		(stroke
			(width 0)
			(type solid)
		)
		(fill yes)
		(layer "F.Cu")
		(net "M_B_ECC<6>")
	)
	(gr_poly
		(pts
			(xy 249.157998 -49.250092) (xy 249.107198 -49.250092) (xy 249.005598 -49.285398) (xy 249.005598 -49.392332)
			(xy 249.107198 -49.427892) (xy 249.157998 -49.427892)
		)
		(stroke
			(width 0)
			(type solid)
		)
		(fill yes)
		(layer "F.Cu")
		(net "M_B_ECC<6>")
	)
	(gr_poly
		(pts
			(xy 249.157998 -48.818292) (xy 249.107198 -48.818292) (xy 249.005598 -48.853598) (xy 249.005598 -48.960532)
			(xy 249.107198 -48.996092) (xy 249.157998 -48.996092)
		)
		(stroke
			(width 0)
			(type solid)
		)
		(fill yes)
		(layer "F.Cu")
		(net "M_B_ECC<6>")
	)
	(gr_poly
		(pts
			(xy 249.157998 -48.386492) (xy 249.107198 -48.386492) (xy 249.005598 -48.421798) (xy 249.005598 -48.528732)
			(xy 249.107198 -48.564292) (xy 249.157998 -48.564292)
		)
		(stroke
			(width 0)
			(type solid)
		)
		(fill yes)
		(layer "F.Cu")
		(net "M_B_ECC<6>")
	)
	(gr_poly
		(pts
			(xy 249.157998 -47.954692) (xy 249.107198 -47.954692) (xy 249.005598 -47.989998) (xy 249.005598 -48.096932)
			(xy 249.107198 -48.132492) (xy 249.157998 -48.132492)
		)
		(stroke
			(width 0)
			(type solid)
		)
		(fill yes)
		(layer "F.Cu")
		(net "M_B_ECC<6>")
	)
	(gr_poly
		(pts
			(xy 249.185938 -105.782872) (xy 249.060208 -105.639108) (xy 249.02414 -105.603294) (xy 248.934478 -105.692956)
			(xy 248.970292 -105.729024) (xy 249.114056 -105.854754)
		)
		(stroke
			(width 0)
			(type solid)
		)
		(fill yes)
		(layer "F.Cu")
		(net "M_E_ECC<7>")
	)
	(gr_poly
		(pts
			(xy 249.190764 -103.050594) (xy 249.190764 -102.943914) (xy 249.089164 -102.908354) (xy 249.038364 -102.908354)
			(xy 249.038364 -103.086154) (xy 249.089164 -103.086154)
		)
		(stroke
			(width 0)
			(type solid)
		)
		(fill yes)
		(layer "F.Cu")
		(net "M_E_DQS_DN<8>")
	)
	(gr_poly
		(pts
			(xy 249.190764 -102.618794) (xy 249.190764 -102.512114) (xy 249.089164 -102.476554) (xy 249.038364 -102.476554)
			(xy 249.038364 -102.654354) (xy 249.089164 -102.654354)
		)
		(stroke
			(width 0)
			(type solid)
		)
		(fill yes)
		(layer "F.Cu")
		(net "M_E_DQS_DN<8>")
	)
	(gr_poly
		(pts
			(xy 249.190764 -102.186994) (xy 249.190764 -102.080314) (xy 249.089164 -102.044754) (xy 249.038364 -102.044754)
			(xy 249.038364 -102.222554) (xy 249.089164 -102.222554)
		)
		(stroke
			(width 0)
			(type solid)
		)
		(fill yes)
		(layer "F.Cu")
		(net "M_E_DQS_DN<8>")
	)
	(gr_poly
		(pts
			(xy 249.190764 -101.755194) (xy 249.190764 -101.648514) (xy 249.089164 -101.612954) (xy 249.038364 -101.612954)
			(xy 249.038364 -101.790754) (xy 249.089164 -101.790754)
		)
		(stroke
			(width 0)
			(type solid)
		)
		(fill yes)
		(layer "F.Cu")
		(net "M_E_DQS_DN<8>")
	)
	(gr_poly
		(pts
			(xy 249.190764 -101.323394) (xy 249.190764 -101.216714) (xy 249.089164 -101.181154) (xy 249.038364 -101.181154)
			(xy 249.038364 -101.358954) (xy 249.089164 -101.358954)
		)
		(stroke
			(width 0)
			(type solid)
		)
		(fill yes)
		(layer "F.Cu")
		(net "M_E_DQS_DN<8>")
	)
	(gr_poly
		(pts
			(xy 249.190764 -100.891594) (xy 249.190764 -100.784914) (xy 249.089164 -100.749354) (xy 249.038364 -100.749354)
			(xy 249.038364 -100.927154) (xy 249.089164 -100.927154)
		)
		(stroke
			(width 0)
			(type solid)
		)
		(fill yes)
		(layer "F.Cu")
		(net "M_E_DQS_DN<8>")
	)
	(gr_poly
		(pts
			(xy 249.202702 -46.566582) (xy 249.247406 -46.521624) (xy 249.121676 -46.395894) (xy 249.076972 -46.440852)
			(xy 249.030236 -46.53788) (xy 249.105674 -46.613318)
		)
		(stroke
			(width 0)
			(type solid)
		)
		(fill yes)
		(layer "F.Cu")
		(net "M_B_ECC<3>")
	)
	(gr_poly
		(pts
			(xy 249.211592 -46.863) (xy 249.258328 -46.765972) (xy 249.18289 -46.690534) (xy 249.085862 -46.73727)
			(xy 249.050048 -46.773338) (xy 249.175524 -46.898814)
		)
		(stroke
			(width 0)
			(type solid)
		)
		(fill yes)
		(layer "F.Cu")
		(net "M_B_ECC<2>")
	)
	(gr_poly
		(pts
			(xy 249.264424 -104.968294) (xy 249.213624 -104.968294) (xy 249.112024 -105.003854) (xy 249.112024 -105.110534)
			(xy 249.213624 -105.146094) (xy 249.264424 -105.146094)
		)
		(stroke
			(width 0)
			(type solid)
		)
		(fill yes)
		(layer "F.Cu")
		(net "M_E_ECC<7>")
	)
	(gr_poly
		(pts
			(xy 249.264424 -104.536494) (xy 249.213624 -104.536494) (xy 249.112024 -104.572054) (xy 249.112024 -104.678734)
			(xy 249.213624 -104.714294) (xy 249.264424 -104.714294)
		)
		(stroke
			(width 0)
			(type solid)
		)
		(fill yes)
		(layer "F.Cu")
		(net "M_E_ECC<7>")
	)
	(gr_poly
		(pts
			(xy 249.28068 -104.252522) (xy 249.233944 -104.155494) (xy 249.19813 -104.11968) (xy 249.0724 -104.24541)
			(xy 249.108468 -104.281224) (xy 249.205242 -104.32796)
		)
		(stroke
			(width 0)
			(type solid)
		)
		(fill yes)
		(layer "F.Cu")
		(net "M_E_ECC<6>")
	)
	(gr_poly
		(pts
			(xy 249.292364 -47.087536) (xy 249.328432 -47.051722) (xy 249.202702 -46.925992) (xy 249.166634 -46.961806)
			(xy 249.119898 -47.058834) (xy 249.195336 -47.134272)
		)
		(stroke
			(width 0)
			(type solid)
		)
		(fill yes)
		(layer "F.Cu")
		(net "M_B_ECC<2>")
	)
	(gr_poly
		(pts
			(xy 249.301254 -47.383954) (xy 249.34799 -47.286926) (xy 249.272552 -47.211488) (xy 249.175524 -47.258224)
			(xy 249.13971 -47.294292) (xy 249.26544 -47.420022)
		)
		(stroke
			(width 0)
			(type solid)
		)
		(fill yes)
		(layer "F.Cu")
		(net "M_B_ECC<7>")
	)
	(gr_poly
		(pts
			(xy 249.310398 -49.608232) (xy 249.310398 -49.501298) (xy 249.208798 -49.465992) (xy 249.157998 -49.465992)
			(xy 249.157998 -49.643792) (xy 249.208798 -49.643792)
		)
		(stroke
			(width 0)
			(type solid)
		)
		(fill yes)
		(layer "F.Cu")
		(net "M_B_ECC<6>")
	)
	(gr_poly
		(pts
			(xy 249.310398 -49.176432) (xy 249.310398 -49.069498) (xy 249.208798 -49.034192) (xy 249.157998 -49.034192)
			(xy 249.157998 -49.211992) (xy 249.208798 -49.211992)
		)
		(stroke
			(width 0)
			(type solid)
		)
		(fill yes)
		(layer "F.Cu")
		(net "M_B_ECC<6>")
	)
	(gr_poly
		(pts
			(xy 249.310398 -48.744632) (xy 249.310398 -48.637698) (xy 249.208798 -48.602392) (xy 249.157998 -48.602392)
			(xy 249.157998 -48.780192) (xy 249.208798 -48.780192)
		)
		(stroke
			(width 0)
			(type solid)
		)
		(fill yes)
		(layer "F.Cu")
		(net "M_B_ECC<6>")
	)
	(gr_poly
		(pts
			(xy 249.310398 -48.312832) (xy 249.310398 -48.205898) (xy 249.208798 -48.170592) (xy 249.157998 -48.170592)
			(xy 249.157998 -48.348392) (xy 249.208798 -48.348392)
		)
		(stroke
			(width 0)
			(type solid)
		)
		(fill yes)
		(layer "F.Cu")
		(net "M_B_ECC<6>")
	)
	(gr_poly
		(pts
			(xy 249.310398 -47.881032) (xy 249.310398 -47.774098) (xy 249.208798 -47.738792) (xy 249.157998 -47.738792)
			(xy 249.157998 -47.916592) (xy 249.208798 -47.916592)
		)
		(stroke
			(width 0)
			(type solid)
		)
		(fill yes)
		(layer "F.Cu")
		(net "M_B_ECC<6>")
	)
	(gr_poly
		(pts
			(xy 249.331734 -52.829206) (xy 249.330718 -52.43068) (xy 249.286268 -52.43068) (xy 249.116088 -52.520088)
			(xy 249.11685 -52.741068) (xy 249.287284 -52.82946)
		)
		(stroke
			(width 0)
			(type solid)
		)
		(fill yes)
		(layer "F.Cu")
		(net "M_B_ECC<6>")
	)
	(gr_poly
		(pts
			(xy 249.343164 -103.124254) (xy 249.292364 -103.124254) (xy 249.190764 -103.159814) (xy 249.190764 -103.266494)
			(xy 249.292364 -103.302054) (xy 249.343164 -103.302054)
		)
		(stroke
			(width 0)
			(type solid)
		)
		(fill yes)
		(layer "F.Cu")
		(net "M_E_DQS_DP<8>")
	)
	(gr_poly
		(pts
			(xy 249.343164 -102.692454) (xy 249.292364 -102.692454) (xy 249.190764 -102.728014) (xy 249.190764 -102.834694)
			(xy 249.292364 -102.870254) (xy 249.343164 -102.870254)
		)
		(stroke
			(width 0)
			(type solid)
		)
		(fill yes)
		(layer "F.Cu")
		(net "M_E_DQS_DP<8>")
	)
	(gr_poly
		(pts
			(xy 249.343164 -102.260654) (xy 249.292364 -102.260654) (xy 249.190764 -102.296214) (xy 249.190764 -102.402894)
			(xy 249.292364 -102.438454) (xy 249.343164 -102.438454)
		)
		(stroke
			(width 0)
			(type solid)
		)
		(fill yes)
		(layer "F.Cu")
		(net "M_E_DQS_DP<8>")
	)
	(gr_poly
		(pts
			(xy 249.343164 -101.828854) (xy 249.292364 -101.828854) (xy 249.190764 -101.864414) (xy 249.190764 -101.971094)
			(xy 249.292364 -102.006654) (xy 249.343164 -102.006654)
		)
		(stroke
			(width 0)
			(type solid)
		)
		(fill yes)
		(layer "F.Cu")
		(net "M_E_DQS_DP<8>")
	)
	(gr_poly
		(pts
			(xy 249.343164 -101.397054) (xy 249.292364 -101.397054) (xy 249.190764 -101.432614) (xy 249.190764 -101.539294)
			(xy 249.292364 -101.574854) (xy 249.343164 -101.574854)
		)
		(stroke
			(width 0)
			(type solid)
		)
		(fill yes)
		(layer "F.Cu")
		(net "M_E_DQS_DP<8>")
	)
	(gr_poly
		(pts
			(xy 249.343164 -100.965254) (xy 249.292364 -100.965254) (xy 249.190764 -101.000814) (xy 249.190764 -101.107494)
			(xy 249.292364 -101.143054) (xy 249.343164 -101.143054)
		)
		(stroke
			(width 0)
			(type solid)
		)
		(fill yes)
		(layer "F.Cu")
		(net "M_E_DQS_DP<8>")
	)
	(gr_poly
		(pts
			(xy 249.343164 -100.533454) (xy 249.292364 -100.533454) (xy 249.190764 -100.569014) (xy 249.190764 -100.675694)
			(xy 249.292364 -100.711254) (xy 249.343164 -100.711254)
		)
		(stroke
			(width 0)
			(type solid)
		)
		(fill yes)
		(layer "F.Cu")
		(net "M_E_DQS_DP<8>")
	)
	(gr_poly
		(pts
			(xy 249.350784 -103.967026) (xy 249.31497 -103.930958) (xy 249.217942 -103.884476) (xy 249.142504 -103.959914)
			(xy 249.18924 -104.056688) (xy 249.225054 -104.092756)
		)
		(stroke
			(width 0)
			(type solid)
		)
		(fill yes)
		(layer "F.Cu")
		(net "M_E_ECC<6>")
	)
	(gr_poly
		(pts
			(xy 249.356372 -106.402378) (xy 249.311414 -106.35742) (xy 249.167904 -106.23169) (xy 249.096022 -106.303572)
			(xy 249.221752 -106.447336) (xy 249.266456 -106.492294)
		)
		(stroke
			(width 0)
			(type solid)
		)
		(fill yes)
		(layer "F.Cu")
		(net "M_E_ECC<3>")
	)
	(gr_poly
		(pts
			(xy 249.370342 -103.731568) (xy 249.323606 -103.63454) (xy 249.287792 -103.598726) (xy 249.162062 -103.724456)
			(xy 249.19813 -103.76027) (xy 249.294904 -103.807006)
		)
		(stroke
			(width 0)
			(type solid)
		)
		(fill yes)
		(layer "F.Cu")
		(net "M_E_DQS_DP<8>")
	)
	(gr_poly
		(pts
			(xy 249.382026 -47.60849) (xy 249.418094 -47.572676) (xy 249.292364 -47.446946) (xy 249.256296 -47.48276)
			(xy 249.20956 -47.579788) (xy 249.284998 -47.655226)
		)
		(stroke
			(width 0)
			(type solid)
		)
		(fill yes)
		(layer "F.Cu")
		(net "M_B_ECC<7>")
	)
	(gr_poly
		(pts
			(xy 249.416824 -105.326434) (xy 249.416824 -105.219754) (xy 249.315224 -105.184194) (xy 249.264424 -105.184194)
			(xy 249.264424 -105.361994) (xy 249.315224 -105.361994)
		)
		(stroke
			(width 0)
			(type solid)
		)
		(fill yes)
		(layer "F.Cu")
		(net "M_E_ECC<7>")
	)
	(gr_poly
		(pts
			(xy 249.416824 -104.894634) (xy 249.416824 -104.787954) (xy 249.315224 -104.752394) (xy 249.264424 -104.752394)
			(xy 249.264424 -104.930194) (xy 249.315224 -104.930194)
		)
		(stroke
			(width 0)
			(type solid)
		)
		(fill yes)
		(layer "F.Cu")
		(net "M_E_ECC<7>")
	)
	(gr_poly
		(pts
			(xy 249.462798 -49.681892) (xy 249.411998 -49.681892) (xy 249.310398 -49.717198) (xy 249.310398 -49.824132)
			(xy 249.411998 -49.859692) (xy 249.462798 -49.859692)
		)
		(stroke
			(width 0)
			(type solid)
		)
		(fill yes)
		(layer "F.Cu")
		(net "M_B_ECC<7>")
	)
	(gr_poly
		(pts
			(xy 249.462798 -49.250092) (xy 249.411998 -49.250092) (xy 249.310398 -49.285398) (xy 249.310398 -49.392332)
			(xy 249.411998 -49.427892) (xy 249.462798 -49.427892)
		)
		(stroke
			(width 0)
			(type solid)
		)
		(fill yes)
		(layer "F.Cu")
		(net "M_B_ECC<7>")
	)
	(gr_poly
		(pts
			(xy 249.462798 -48.818292) (xy 249.411998 -48.818292) (xy 249.310398 -48.853598) (xy 249.310398 -48.960532)
			(xy 249.411998 -48.996092) (xy 249.462798 -48.996092)
		)
		(stroke
			(width 0)
			(type solid)
		)
		(fill yes)
		(layer "F.Cu")
		(net "M_B_ECC<7>")
	)
	(gr_poly
		(pts
			(xy 249.462798 -48.386492) (xy 249.411998 -48.386492) (xy 249.310398 -48.421798) (xy 249.310398 -48.528732)
			(xy 249.411998 -48.564292) (xy 249.462798 -48.564292)
		)
		(stroke
			(width 0)
			(type solid)
		)
		(fill yes)
		(layer "F.Cu")
		(net "M_B_ECC<7>")
	)
	(gr_poly
		(pts
			(xy 249.462798 -47.954692) (xy 249.411998 -47.954692) (xy 249.310398 -47.989998) (xy 249.310398 -48.096932)
			(xy 249.411998 -48.132492) (xy 249.462798 -48.132492)
		)
		(stroke
			(width 0)
			(type solid)
		)
		(fill yes)
		(layer "F.Cu")
		(net "M_B_ECC<7>")
	)
	(gr_poly
		(pts
			(xy 249.464322 -106.061256) (xy 249.338592 -105.917492) (xy 249.302524 -105.881678) (xy 249.212862 -105.97134)
			(xy 249.248676 -106.007408) (xy 249.39244 -106.133138)
		)
		(stroke
			(width 0)
			(type solid)
		)
		(fill yes)
		(layer "F.Cu")
		(net "M_E_ECC<2>")
	)
	(gr_poly
		(pts
			(xy 249.495564 -103.481378) (xy 249.495564 -103.374698) (xy 249.393964 -103.339138) (xy 249.343164 -103.339138)
			(xy 249.343164 -103.516938) (xy 249.393964 -103.516938)
		)
		(stroke
			(width 0)
			(type solid)
		)
		(fill yes)
		(layer "F.Cu")
		(net "M_E_DQS_DP<8>")
	)
	(gr_poly
		(pts
			(xy 249.495564 -103.050594) (xy 249.495564 -102.943914) (xy 249.393964 -102.908354) (xy 249.343164 -102.908354)
			(xy 249.343164 -103.086154) (xy 249.393964 -103.086154)
		)
		(stroke
			(width 0)
			(type solid)
		)
		(fill yes)
		(layer "F.Cu")
		(net "M_E_DQS_DP<8>")
	)
	(gr_poly
		(pts
			(xy 249.495564 -102.618794) (xy 249.495564 -102.512114) (xy 249.393964 -102.476554) (xy 249.343164 -102.476554)
			(xy 249.343164 -102.654354) (xy 249.393964 -102.654354)
		)
		(stroke
			(width 0)
			(type solid)
		)
		(fill yes)
		(layer "F.Cu")
		(net "M_E_DQS_DP<8>")
	)
	(gr_poly
		(pts
			(xy 249.495564 -102.186994) (xy 249.495564 -102.080314) (xy 249.393964 -102.044754) (xy 249.343164 -102.044754)
			(xy 249.343164 -102.222554) (xy 249.393964 -102.222554)
		)
		(stroke
			(width 0)
			(type solid)
		)
		(fill yes)
		(layer "F.Cu")
		(net "M_E_DQS_DP<8>")
	)
	(gr_poly
		(pts
			(xy 249.495564 -101.755194) (xy 249.495564 -101.648514) (xy 249.393964 -101.612954) (xy 249.343164 -101.612954)
			(xy 249.343164 -101.790754) (xy 249.393964 -101.790754)
		)
		(stroke
			(width 0)
			(type solid)
		)
		(fill yes)
		(layer "F.Cu")
		(net "M_E_DQS_DP<8>")
	)
	(gr_poly
		(pts
			(xy 249.495564 -101.323394) (xy 249.495564 -101.216714) (xy 249.393964 -101.181154) (xy 249.343164 -101.181154)
			(xy 249.343164 -101.358954) (xy 249.393964 -101.358954)
		)
		(stroke
			(width 0)
			(type solid)
		)
		(fill yes)
		(layer "F.Cu")
		(net "M_E_DQS_DP<8>")
	)
	(gr_poly
		(pts
			(xy 249.495564 -100.891594) (xy 249.495564 -100.784914) (xy 249.393964 -100.749354) (xy 249.343164 -100.749354)
			(xy 249.343164 -100.927154) (xy 249.393964 -100.927154)
		)
		(stroke
			(width 0)
			(type solid)
		)
		(fill yes)
		(layer "F.Cu")
		(net "M_E_DQS_DP<8>")
	)
	(gr_poly
		(pts
			(xy 249.496326 -104.468168) (xy 249.44959 -104.37114) (xy 249.413776 -104.335326) (xy 249.288046 -104.461056)
			(xy 249.324114 -104.49687) (xy 249.420888 -104.543606)
		)
		(stroke
			(width 0)
			(type solid)
		)
		(fill yes)
		(layer "F.Cu")
		(net "M_E_ECC<7>")
	)
	(gr_poly
		(pts
			(xy 249.50801 -46.87189) (xy 249.552968 -46.827186) (xy 249.427238 -46.701456) (xy 249.38228 -46.74616)
			(xy 249.335544 -46.843188) (xy 249.410982 -46.918626)
		)
		(stroke
			(width 0)
			(type solid)
		)
		(fill yes)
		(layer "F.Cu")
		(net "M_B_ECC<3>")
	)
	(gr_poly
		(pts
			(xy 249.5169 -47.168308) (xy 249.563636 -47.07128) (xy 249.488198 -46.995842) (xy 249.39117 -47.042578)
			(xy 249.355356 -47.078646) (xy 249.481086 -47.204376)
		)
		(stroke
			(width 0)
			(type solid)
		)
		(fill yes)
		(layer "F.Cu")
		(net "M_B_ECC<2>")
	)
	(gr_poly
		(pts
			(xy 249.536458 -105.647744) (xy 249.500644 -105.61193) (xy 249.35688 -105.4862) (xy 249.284998 -105.557828)
			(xy 249.410728 -105.701592) (xy 249.446542 -105.73766)
		)
		(stroke
			(width 0)
			(type solid)
		)
		(fill yes)
		(layer "F.Cu")
		(net "M_E_ECC<2>")
	)
	(gr_poly
		(pts
			(xy 249.56643 -104.182672) (xy 249.530616 -104.146604) (xy 249.433588 -104.100122) (xy 249.35815 -104.17556)
			(xy 249.404886 -104.272334) (xy 249.4407 -104.308402)
		)
		(stroke
			(width 0)
			(type solid)
		)
		(fill yes)
		(layer "F.Cu")
		(net "M_E_ECC<7>")
	)
	(gr_poly
		(pts
			(xy 249.569224 -104.968294) (xy 249.518424 -104.968294) (xy 249.416824 -105.003854) (xy 249.416824 -105.110534)
			(xy 249.518424 -105.146094) (xy 249.569224 -105.146094)
		)
		(stroke
			(width 0)
			(type solid)
		)
		(fill yes)
		(layer "F.Cu")
		(net "M_E_ECC<2>")
	)
	(gr_poly
		(pts
			(xy 249.585988 -103.947214) (xy 249.539506 -103.850186) (xy 249.503438 -103.814372) (xy 249.377708 -103.940102)
			(xy 249.413776 -103.975916) (xy 249.51055 -104.022652)
		)
		(stroke
			(width 0)
			(type solid)
		)
		(fill yes)
		(layer "F.Cu")
		(net "M_E_ECC<6>")
	)
	(gr_poly
		(pts
			(xy 249.597672 -47.392844) (xy 249.63374 -47.35703) (xy 249.50801 -47.2313) (xy 249.471942 -47.267114)
			(xy 249.425206 -47.364142) (xy 249.500644 -47.43958)
		)
		(stroke
			(width 0)
			(type solid)
		)
		(fill yes)
		(layer "F.Cu")
		(net "M_B_ECC<2>")
	)
	(gr_poly
		(pts
			(xy 249.615198 -49.608232) (xy 249.615198 -49.501298) (xy 249.513598 -49.465992) (xy 249.462798 -49.465992)
			(xy 249.462798 -49.643792) (xy 249.513598 -49.643792)
		)
		(stroke
			(width 0)
			(type solid)
		)
		(fill yes)
		(layer "F.Cu")
		(net "M_B_ECC<7>")
	)
	(gr_poly
		(pts
			(xy 249.615198 -49.176432) (xy 249.615198 -49.069498) (xy 249.513598 -49.034192) (xy 249.462798 -49.034192)
			(xy 249.462798 -49.211992) (xy 249.513598 -49.211992)
		)
		(stroke
			(width 0)
			(type solid)
		)
		(fill yes)
		(layer "F.Cu")
		(net "M_B_ECC<7>")
	)
	(gr_poly
		(pts
			(xy 249.615198 -48.744632) (xy 249.615198 -48.637698) (xy 249.513598 -48.602392) (xy 249.462798 -48.602392)
			(xy 249.462798 -48.780192) (xy 249.513598 -48.780192)
		)
		(stroke
			(width 0)
			(type solid)
		)
		(fill yes)
		(layer "F.Cu")
		(net "M_B_ECC<7>")
	)
	(gr_poly
		(pts
			(xy 249.615198 -48.312832) (xy 249.615198 -48.205898) (xy 249.513598 -48.170592) (xy 249.462798 -48.170592)
			(xy 249.462798 -48.348392) (xy 249.513598 -48.348392)
		)
		(stroke
			(width 0)
			(type solid)
		)
		(fill yes)
		(layer "F.Cu")
		(net "M_B_ECC<7>")
	)
	(gr_poly
		(pts
			(xy 249.615198 -47.881032) (xy 249.615198 -47.774098) (xy 249.513598 -47.738792) (xy 249.462798 -47.738792)
			(xy 249.462798 -47.916592) (xy 249.513598 -47.916592)
		)
		(stroke
			(width 0)
			(type solid)
		)
		(fill yes)
		(layer "F.Cu")
		(net "M_B_ECC<7>")
	)
	(gr_poly
		(pts
			(xy 249.647964 -103.124254) (xy 249.597164 -103.124254) (xy 249.495564 -103.159814) (xy 249.495564 -103.266494)
			(xy 249.597164 -103.302054) (xy 249.647964 -103.302054)
		)
		(stroke
			(width 0)
			(type solid)
		)
		(fill yes)
		(layer "F.Cu")
		(net "M_E_ECC<6>")
	)
	(gr_poly
		(pts
			(xy 249.647964 -102.692454) (xy 249.597164 -102.692454) (xy 249.495564 -102.728014) (xy 249.495564 -102.834694)
			(xy 249.597164 -102.870254) (xy 249.647964 -102.870254)
		)
		(stroke
			(width 0)
			(type solid)
		)
		(fill yes)
		(layer "F.Cu")
		(net "M_E_ECC<6>")
	)
	(gr_poly
		(pts
			(xy 249.647964 -102.260654) (xy 249.597164 -102.260654) (xy 249.495564 -102.296214) (xy 249.495564 -102.402894)
			(xy 249.597164 -102.438454) (xy 249.647964 -102.438454)
		)
		(stroke
			(width 0)
			(type solid)
		)
		(fill yes)
		(layer "F.Cu")
		(net "M_E_ECC<6>")
	)
	(gr_poly
		(pts
			(xy 249.647964 -101.828854) (xy 249.597164 -101.828854) (xy 249.495564 -101.864414) (xy 249.495564 -101.971094)
			(xy 249.597164 -102.006654) (xy 249.647964 -102.006654)
		)
		(stroke
			(width 0)
			(type solid)
		)
		(fill yes)
		(layer "F.Cu")
		(net "M_E_ECC<6>")
	)
	(gr_poly
		(pts
			(xy 249.647964 -101.397054) (xy 249.597164 -101.397054) (xy 249.495564 -101.432614) (xy 249.495564 -101.539294)
			(xy 249.597164 -101.574854) (xy 249.647964 -101.574854)
		)
		(stroke
			(width 0)
			(type solid)
		)
		(fill yes)
		(layer "F.Cu")
		(net "M_E_ECC<6>")
	)
	(gr_poly
		(pts
			(xy 249.647964 -100.965254) (xy 249.597164 -100.965254) (xy 249.495564 -101.000814) (xy 249.495564 -101.107494)
			(xy 249.597164 -101.143054) (xy 249.647964 -101.143054)
		)
		(stroke
			(width 0)
			(type solid)
		)
		(fill yes)
		(layer "F.Cu")
		(net "M_E_ECC<6>")
	)
	(gr_poly
		(pts
			(xy 249.647964 -100.533454) (xy 249.597164 -100.533454) (xy 249.495564 -100.569014) (xy 249.495564 -100.675694)
			(xy 249.597164 -100.711254) (xy 249.647964 -100.711254)
		)
		(stroke
			(width 0)
			(type solid)
		)
		(fill yes)
		(layer "F.Cu")
		(net "M_E_ECC<6>")
	)
	(gr_poly
		(pts
			(xy 249.676158 -54.219856) (xy 249.676158 -53.998876) (xy 249.505978 -53.909976) (xy 249.461528 -53.909976)
			(xy 249.461528 -54.308756) (xy 249.505978 -54.308756)
		)
		(stroke
			(width 0)
			(type solid)
		)
		(fill yes)
		(layer "F.Cu")
		(net "M_B_ECC<7>")
	)
	(gr_poly
		(pts
			(xy 249.721624 -105.326434) (xy 249.721624 -105.219754) (xy 249.620024 -105.184194) (xy 249.569224 -105.184194)
			(xy 249.569224 -105.361994) (xy 249.620024 -105.361994)
		)
		(stroke
			(width 0)
			(type solid)
		)
		(fill yes)
		(layer "F.Cu")
		(net "M_E_ECC<2>")
	)
	(gr_poly
		(pts
			(xy 249.721624 -104.894634) (xy 249.721624 -104.787954) (xy 249.620024 -104.752394) (xy 249.569224 -104.752394)
			(xy 249.569224 -104.930194) (xy 249.620024 -104.930194)
		)
		(stroke
			(width 0)
			(type solid)
		)
		(fill yes)
		(layer "F.Cu")
		(net "M_E_ECC<2>")
	)
	(gr_poly
		(pts
			(xy 249.767598 -49.250092) (xy 249.716798 -49.250092) (xy 249.615198 -49.285398) (xy 249.615198 -49.392332)
			(xy 249.716798 -49.427892) (xy 249.767598 -49.427892)
		)
		(stroke
			(width 0)
			(type solid)
		)
		(fill yes)
		(layer "F.Cu")
		(net "M_B_ECC<2>")
	)
	(gr_poly
		(pts
			(xy 249.767598 -48.818292) (xy 249.716798 -48.818292) (xy 249.615198 -48.853598) (xy 249.615198 -48.960532)
			(xy 249.716798 -48.996092) (xy 249.767598 -48.996092)
		)
		(stroke
			(width 0)
			(type solid)
		)
		(fill yes)
		(layer "F.Cu")
		(net "M_B_ECC<2>")
	)
	(gr_poly
		(pts
			(xy 249.767598 -48.386492) (xy 249.716798 -48.386492) (xy 249.615198 -48.421798) (xy 249.615198 -48.528732)
			(xy 249.716798 -48.564292) (xy 249.767598 -48.564292)
		)
		(stroke
			(width 0)
			(type solid)
		)
		(fill yes)
		(layer "F.Cu")
		(net "M_B_ECC<2>")
	)
	(gr_poly
		(pts
			(xy 249.767598 -47.954692) (xy 249.716798 -47.954692) (xy 249.615198 -47.989998) (xy 249.615198 -48.096932)
			(xy 249.716798 -48.132492) (xy 249.767598 -48.132492)
		)
		(stroke
			(width 0)
			(type solid)
		)
		(fill yes)
		(layer "F.Cu")
		(net "M_B_ECC<2>")
	)
	(gr_poly
		(pts
			(xy 249.767598 -47.522892) (xy 249.716798 -47.522892) (xy 249.615198 -47.558198) (xy 249.615198 -47.665132)
			(xy 249.716798 -47.700692) (xy 249.767598 -47.700692)
		)
		(stroke
			(width 0)
			(type solid)
		)
		(fill yes)
		(layer "F.Cu")
		(net "M_B_ECC<2>")
	)
	(gr_poly
		(pts
			(xy 249.782076 -104.398318) (xy 249.746262 -104.36225) (xy 249.649234 -104.315768) (xy 249.573796 -104.391206)
			(xy 249.620532 -104.48798) (xy 249.656346 -104.524048)
		)
		(stroke
			(width 0)
			(type solid)
		)
		(fill yes)
		(layer "F.Cu")
		(net "M_E_ECC<2>")
	)
	(gr_poly
		(pts
			(xy 249.800364 -103.482394) (xy 249.800364 -103.375714) (xy 249.698764 -103.340154) (xy 249.647964 -103.340154)
			(xy 249.647964 -103.517954) (xy 249.698764 -103.517954)
		)
		(stroke
			(width 0)
			(type solid)
		)
		(fill yes)
		(layer "F.Cu")
		(net "M_E_ECC<6>")
	)
	(gr_poly
		(pts
			(xy 249.800364 -103.050594) (xy 249.800364 -102.943914) (xy 249.698764 -102.908354) (xy 249.647964 -102.908354)
			(xy 249.647964 -103.086154) (xy 249.698764 -103.086154)
		)
		(stroke
			(width 0)
			(type solid)
		)
		(fill yes)
		(layer "F.Cu")
		(net "M_E_ECC<6>")
	)
	(gr_poly
		(pts
			(xy 249.800364 -102.618794) (xy 249.800364 -102.512114) (xy 249.698764 -102.476554) (xy 249.647964 -102.476554)
			(xy 249.647964 -102.654354) (xy 249.698764 -102.654354)
		)
		(stroke
			(width 0)
			(type solid)
		)
		(fill yes)
		(layer "F.Cu")
		(net "M_E_ECC<6>")
	)
	(gr_poly
		(pts
			(xy 249.800364 -102.186994) (xy 249.800364 -102.080314) (xy 249.698764 -102.044754) (xy 249.647964 -102.044754)
			(xy 249.647964 -102.222554) (xy 249.698764 -102.222554)
		)
		(stroke
			(width 0)
			(type solid)
		)
		(fill yes)
		(layer "F.Cu")
		(net "M_E_ECC<6>")
	)
	(gr_poly
		(pts
			(xy 249.800364 -101.755194) (xy 249.800364 -101.648514) (xy 249.698764 -101.612954) (xy 249.647964 -101.612954)
			(xy 249.647964 -101.790754) (xy 249.698764 -101.790754)
		)
		(stroke
			(width 0)
			(type solid)
		)
		(fill yes)
		(layer "F.Cu")
		(net "M_E_ECC<6>")
	)
	(gr_poly
		(pts
			(xy 249.800364 -101.323394) (xy 249.800364 -101.216714) (xy 249.698764 -101.181154) (xy 249.647964 -101.181154)
			(xy 249.647964 -101.358954) (xy 249.698764 -101.358954)
		)
		(stroke
			(width 0)
			(type solid)
		)
		(fill yes)
		(layer "F.Cu")
		(net "M_E_ECC<6>")
	)
	(gr_poly
		(pts
			(xy 249.800364 -100.891594) (xy 249.800364 -100.784914) (xy 249.698764 -100.749354) (xy 249.647964 -100.749354)
			(xy 249.647964 -100.927154) (xy 249.698764 -100.927154)
		)
		(stroke
			(width 0)
			(type solid)
		)
		(fill yes)
		(layer "F.Cu")
		(net "M_E_ECC<6>")
	)
	(gr_poly
		(pts
			(xy 249.801634 -104.16286) (xy 249.755152 -104.065832) (xy 249.719084 -104.030018) (xy 249.593354 -104.155748)
			(xy 249.629422 -104.191562) (xy 249.726196 -104.238298)
		)
		(stroke
			(width 0)
			(type solid)
		)
		(fill yes)
		(layer "F.Cu")
		(net "M_E_ECC<7>")
	)
	(gr_poly
		(pts
			(xy 249.813318 -47.177198) (xy 249.858276 -47.132494) (xy 249.732546 -47.006764) (xy 249.687588 -47.051468)
			(xy 249.640852 -47.148496) (xy 249.71629 -47.223934)
		)
		(stroke
			(width 0)
			(type solid)
		)
		(fill yes)
		(layer "F.Cu")
		(net "M_B_ECC<3>")
	)
	(gr_poly
		(pts
			(xy 249.822208 -47.473616) (xy 249.868944 -47.376588) (xy 249.793506 -47.30115) (xy 249.696478 -47.347886)
			(xy 249.660664 -47.383954) (xy 249.786394 -47.509684)
		)
		(stroke
			(width 0)
			(type solid)
		)
		(fill yes)
		(layer "F.Cu")
		(net "M_B_ECC<2>")
	)
	(gr_poly
		(pts
			(xy 249.823732 -105.935018) (xy 249.778774 -105.89006) (xy 249.635264 -105.76433) (xy 249.563382 -105.836212)
			(xy 249.689112 -105.979976) (xy 249.733816 -106.024934)
		)
		(stroke
			(width 0)
			(type solid)
		)
		(fill yes)
		(layer "F.Cu")
		(net "M_E_ECC<3>")
	)
	(gr_poly
		(pts
			(xy 249.866912 -53.224176) (xy 249.866912 -53.003196) (xy 249.696732 -52.914296) (xy 249.652282 -52.914296)
			(xy 249.652282 -53.313076) (xy 249.696732 -53.313076)
		)
		(stroke
			(width 0)
			(type solid)
		)
		(fill yes)
		(layer "F.Cu")
		(net "M_B_ECC<7>")
	)
	(gr_poly
		(pts
			(xy 249.871738 -103.877364) (xy 249.835924 -103.841296) (xy 249.738896 -103.794814) (xy 249.663458 -103.870252)
			(xy 249.710194 -103.967026) (xy 249.746008 -104.003094)
		)
		(stroke
			(width 0)
			(type solid)
		)
		(fill yes)
		(layer "F.Cu")
		(net "M_E_ECC<7>")
	)
	(gr_poly
		(pts
			(xy 249.886724 -105.400094) (xy 249.823224 -105.400094) (xy 249.721624 -105.435654) (xy 249.721624 -105.542334)
			(xy 249.823224 -105.577894) (xy 249.886724 -105.577894)
		)
		(stroke
			(width 0)
			(type solid)
		)
		(fill yes)
		(layer "F.Cu")
		(net "M_E_ECC<3>")
	)
	(gr_poly
		(pts
			(xy 249.886724 -104.968294) (xy 249.823224 -104.968294) (xy 249.721624 -105.003854) (xy 249.721624 -105.110534)
			(xy 249.823224 -105.146094) (xy 249.886724 -105.146094)
		)
		(stroke
			(width 0)
			(type solid)
		)
		(fill yes)
		(layer "F.Cu")
		(net "M_E_ECC<3>")
	)
	(gr_poly
		(pts
			(xy 249.919998 -49.176432) (xy 249.919998 -49.069498) (xy 249.818398 -49.034192) (xy 249.767598 -49.034192)
			(xy 249.767598 -49.211992) (xy 249.818398 -49.211992)
		)
		(stroke
			(width 0)
			(type solid)
		)
		(fill yes)
		(layer "F.Cu")
		(net "M_B_ECC<2>")
	)
	(gr_poly
		(pts
			(xy 249.919998 -48.744632) (xy 249.919998 -48.637698) (xy 249.818398 -48.602392) (xy 249.767598 -48.602392)
			(xy 249.767598 -48.780192) (xy 249.818398 -48.780192)
		)
		(stroke
			(width 0)
			(type solid)
		)
		(fill yes)
		(layer "F.Cu")
		(net "M_B_ECC<2>")
	)
	(gr_poly
		(pts
			(xy 249.919998 -48.312832) (xy 249.919998 -48.205898) (xy 249.818398 -48.170592) (xy 249.767598 -48.170592)
			(xy 249.767598 -48.348392) (xy 249.818398 -48.348392)
		)
		(stroke
			(width 0)
			(type solid)
		)
		(fill yes)
		(layer "F.Cu")
		(net "M_B_ECC<2>")
	)
	(gr_poly
		(pts
			(xy 249.919998 -47.881032) (xy 249.919998 -47.774098) (xy 249.818398 -47.738792) (xy 249.767598 -47.738792)
			(xy 249.767598 -47.916592) (xy 249.818398 -47.916592)
		)
		(stroke
			(width 0)
			(type solid)
		)
		(fill yes)
		(layer "F.Cu")
		(net "M_B_ECC<2>")
	)
	(gr_poly
		(pts
			(xy 249.952764 -103.556054) (xy 249.901964 -103.556054) (xy 249.800364 -103.591614) (xy 249.800364 -103.698294)
			(xy 249.901964 -103.733854) (xy 249.952764 -103.733854)
		)
		(stroke
			(width 0)
			(type solid)
		)
		(fill yes)
		(layer "F.Cu")
		(net "M_E_ECC<7>")
	)
	(gr_poly
		(pts
			(xy 249.952764 -103.124254) (xy 249.901964 -103.124254) (xy 249.800364 -103.159814) (xy 249.800364 -103.266494)
			(xy 249.901964 -103.302054) (xy 249.952764 -103.302054)
		)
		(stroke
			(width 0)
			(type solid)
		)
		(fill yes)
		(layer "F.Cu")
		(net "M_E_ECC<7>")
	)
	(gr_poly
		(pts
			(xy 249.952764 -102.692454) (xy 249.901964 -102.692454) (xy 249.800364 -102.728014) (xy 249.800364 -102.834694)
			(xy 249.901964 -102.870254) (xy 249.952764 -102.870254)
		)
		(stroke
			(width 0)
			(type solid)
		)
		(fill yes)
		(layer "F.Cu")
		(net "M_E_ECC<7>")
	)
	(gr_poly
		(pts
			(xy 249.952764 -102.260654) (xy 249.901964 -102.260654) (xy 249.800364 -102.296214) (xy 249.800364 -102.402894)
			(xy 249.901964 -102.438454) (xy 249.952764 -102.438454)
		)
		(stroke
			(width 0)
			(type solid)
		)
		(fill yes)
		(layer "F.Cu")
		(net "M_E_ECC<7>")
	)
	(gr_poly
		(pts
			(xy 249.952764 -101.828854) (xy 249.901964 -101.828854) (xy 249.800364 -101.864414) (xy 249.800364 -101.971094)
			(xy 249.901964 -102.006654) (xy 249.952764 -102.006654)
		)
		(stroke
			(width 0)
			(type solid)
		)
		(fill yes)
		(layer "F.Cu")
		(net "M_E_ECC<7>")
	)
	(gr_poly
		(pts
			(xy 249.952764 -101.397054) (xy 249.901964 -101.397054) (xy 249.800364 -101.432614) (xy 249.800364 -101.539294)
			(xy 249.901964 -101.574854) (xy 249.952764 -101.574854)
		)
		(stroke
			(width 0)
			(type solid)
		)
		(fill yes)
		(layer "F.Cu")
		(net "M_E_ECC<7>")
	)
	(gr_poly
		(pts
			(xy 249.952764 -100.965254) (xy 249.901964 -100.965254) (xy 249.800364 -101.000814) (xy 249.800364 -101.107494)
			(xy 249.901964 -101.143054) (xy 249.952764 -101.143054)
		)
		(stroke
			(width 0)
			(type solid)
		)
		(fill yes)
		(layer "F.Cu")
		(net "M_E_ECC<7>")
	)
	(gr_poly
		(pts
			(xy 249.952764 -100.533454) (xy 249.901964 -100.533454) (xy 249.800364 -100.569014) (xy 249.800364 -100.675694)
			(xy 249.901964 -100.711254) (xy 249.952764 -100.711254)
		)
		(stroke
			(width 0)
			(type solid)
		)
		(fill yes)
		(layer "F.Cu")
		(net "M_E_ECC<7>")
	)
	(gr_poly
		(pts
			(xy 250.006612 -104.622854) (xy 249.961654 -104.577896) (xy 249.86488 -104.53116) (xy 249.789442 -104.606598)
			(xy 249.835924 -104.703626) (xy 249.880882 -104.748584)
		)
		(stroke
			(width 0)
			(type solid)
		)
		(fill yes)
		(layer "F.Cu")
		(net "M_E_ECC<3>")
	)
	(gr_poly
		(pts
			(xy 250.01728 -104.378506) (xy 249.970798 -104.281478) (xy 249.93473 -104.245664) (xy 249.809 -104.371394)
			(xy 249.845068 -104.407208) (xy 249.941842 -104.453944)
		)
		(stroke
			(width 0)
			(type solid)
		)
		(fill yes)
		(layer "F.Cu")
		(net "M_E_ECC<2>")
	)
	(gr_poly
		(pts
			(xy 250.085098 -49.250092) (xy 250.021598 -49.250092) (xy 249.919998 -49.285398) (xy 249.919998 -49.392332)
			(xy 250.021598 -49.427892) (xy 250.085098 -49.427892)
		)
		(stroke
			(width 0)
			(type solid)
		)
		(fill yes)
		(layer "F.Cu")
		(net "M_B_ECC<3>")
	)
	(gr_poly
		(pts
			(xy 250.085098 -48.818292) (xy 250.021598 -48.818292) (xy 249.919998 -48.853598) (xy 249.919998 -48.960532)
			(xy 250.021598 -48.996092) (xy 250.085098 -48.996092)
		)
		(stroke
			(width 0)
			(type solid)
		)
		(fill yes)
		(layer "F.Cu")
		(net "M_B_ECC<3>")
	)
	(gr_poly
		(pts
			(xy 250.085098 -48.386492) (xy 250.021598 -48.386492) (xy 249.919998 -48.421798) (xy 249.919998 -48.528732)
			(xy 250.021598 -48.564292) (xy 250.085098 -48.564292)
		)
		(stroke
			(width 0)
			(type solid)
		)
		(fill yes)
		(layer "F.Cu")
		(net "M_B_ECC<3>")
	)
	(gr_poly
		(pts
			(xy 250.085098 -47.954692) (xy 250.021598 -47.954692) (xy 249.919998 -47.989998) (xy 249.919998 -48.096932)
			(xy 250.021598 -48.132492) (xy 250.085098 -48.132492)
		)
		(stroke
			(width 0)
			(type solid)
		)
		(fill yes)
		(layer "F.Cu")
		(net "M_B_ECC<3>")
	)
	(gr_poly
		(pts
			(xy 250.085098 -47.522892) (xy 250.021598 -47.522892) (xy 249.919998 -47.558198) (xy 249.919998 -47.665132)
			(xy 250.021598 -47.700692) (xy 250.085098 -47.700692)
		)
		(stroke
			(width 0)
			(type solid)
		)
		(fill yes)
		(layer "F.Cu")
		(net "M_B_ECC<3>")
	)
	(gr_poly
		(pts
			(xy 250.087384 -104.09301) (xy 250.05157 -104.056942) (xy 249.954542 -104.01046) (xy 249.879104 -104.085898)
			(xy 249.92584 -104.182672) (xy 249.961654 -104.21874)
		)
		(stroke
			(width 0)
			(type solid)
		)
		(fill yes)
		(layer "F.Cu")
		(net "M_E_ECC<2>")
	)
	(gr_poly
		(pts
			(xy 250.105164 -103.482394) (xy 250.105164 -103.375714) (xy 250.003564 -103.340154) (xy 249.952764 -103.340154)
			(xy 249.952764 -103.517954) (xy 250.003564 -103.517954)
		)
		(stroke
			(width 0)
			(type solid)
		)
		(fill yes)
		(layer "F.Cu")
		(net "M_E_ECC<7>")
	)
	(gr_poly
		(pts
			(xy 250.105164 -103.050594) (xy 250.105164 -102.943914) (xy 250.003564 -102.908354) (xy 249.952764 -102.908354)
			(xy 249.952764 -103.086154) (xy 250.003564 -103.086154)
		)
		(stroke
			(width 0)
			(type solid)
		)
		(fill yes)
		(layer "F.Cu")
		(net "M_E_ECC<7>")
	)
	(gr_poly
		(pts
			(xy 250.105164 -102.618794) (xy 250.105164 -102.512114) (xy 250.003564 -102.476554) (xy 249.952764 -102.476554)
			(xy 249.952764 -102.654354) (xy 250.003564 -102.654354)
		)
		(stroke
			(width 0)
			(type solid)
		)
		(fill yes)
		(layer "F.Cu")
		(net "M_E_ECC<7>")
	)
	(gr_poly
		(pts
			(xy 250.105164 -102.186994) (xy 250.105164 -102.080314) (xy 250.003564 -102.044754) (xy 249.952764 -102.044754)
			(xy 249.952764 -102.222554) (xy 250.003564 -102.222554)
		)
		(stroke
			(width 0)
			(type solid)
		)
		(fill yes)
		(layer "F.Cu")
		(net "M_E_ECC<7>")
	)
	(gr_poly
		(pts
			(xy 250.105164 -101.755194) (xy 250.105164 -101.648514) (xy 250.003564 -101.612954) (xy 249.952764 -101.612954)
			(xy 249.952764 -101.790754) (xy 250.003564 -101.790754)
		)
		(stroke
			(width 0)
			(type solid)
		)
		(fill yes)
		(layer "F.Cu")
		(net "M_E_ECC<7>")
	)
	(gr_poly
		(pts
			(xy 250.105164 -101.323394) (xy 250.105164 -101.216714) (xy 250.003564 -101.181154) (xy 249.952764 -101.181154)
			(xy 249.952764 -101.358954) (xy 250.003564 -101.358954)
		)
		(stroke
			(width 0)
			(type solid)
		)
		(fill yes)
		(layer "F.Cu")
		(net "M_E_ECC<7>")
	)
	(gr_poly
		(pts
			(xy 250.105164 -100.891594) (xy 250.105164 -100.784914) (xy 250.003564 -100.749354) (xy 249.952764 -100.749354)
			(xy 249.952764 -100.927154) (xy 250.003564 -100.927154)
		)
		(stroke
			(width 0)
			(type solid)
		)
		(fill yes)
		(layer "F.Cu")
		(net "M_E_ECC<7>")
	)
	(gr_poly
		(pts
			(xy 250.187206 -52.914296) (xy 250.142756 -52.914296) (xy 249.972576 -53.003196) (xy 249.972576 -53.224176)
			(xy 250.142756 -53.313076) (xy 250.187206 -53.313076)
		)
		(stroke
			(width 0)
			(type solid)
		)
		(fill yes)
		(layer "F.Cu")
		(net "M_B_ECC<2>")
	)
	(gr_poly
		(pts
			(xy 250.257564 -103.556054) (xy 250.206764 -103.556054) (xy 250.105164 -103.591614) (xy 250.105164 -103.698294)
			(xy 250.206764 -103.733854) (xy 250.257564 -103.733854)
		)
		(stroke
			(width 0)
			(type solid)
		)
		(fill yes)
		(layer "F.Cu")
		(net "M_E_ECC<2>")
	)
	(gr_poly
		(pts
			(xy 250.257564 -103.124254) (xy 250.206764 -103.124254) (xy 250.105164 -103.159814) (xy 250.105164 -103.266494)
			(xy 250.206764 -103.302054) (xy 250.257564 -103.302054)
		)
		(stroke
			(width 0)
			(type solid)
		)
		(fill yes)
		(layer "F.Cu")
		(net "M_E_ECC<2>")
	)
	(gr_poly
		(pts
			(xy 250.257564 -102.692454) (xy 250.206764 -102.692454) (xy 250.105164 -102.728014) (xy 250.105164 -102.834694)
			(xy 250.206764 -102.870254) (xy 250.257564 -102.870254)
		)
		(stroke
			(width 0)
			(type solid)
		)
		(fill yes)
		(layer "F.Cu")
		(net "M_E_ECC<2>")
	)
	(gr_poly
		(pts
			(xy 250.257564 -102.260654) (xy 250.206764 -102.260654) (xy 250.105164 -102.296214) (xy 250.105164 -102.402894)
			(xy 250.206764 -102.438454) (xy 250.257564 -102.438454)
		)
		(stroke
			(width 0)
			(type solid)
		)
		(fill yes)
		(layer "F.Cu")
		(net "M_E_ECC<2>")
	)
	(gr_poly
		(pts
			(xy 250.257564 -101.828854) (xy 250.206764 -101.828854) (xy 250.105164 -101.864414) (xy 250.105164 -101.971094)
			(xy 250.206764 -102.006654) (xy 250.257564 -102.006654)
		)
		(stroke
			(width 0)
			(type solid)
		)
		(fill yes)
		(layer "F.Cu")
		(net "M_E_ECC<2>")
	)
	(gr_poly
		(pts
			(xy 250.257564 -101.397054) (xy 250.206764 -101.397054) (xy 250.105164 -101.432614) (xy 250.105164 -101.539294)
			(xy 250.206764 -101.574854) (xy 250.257564 -101.574854)
		)
		(stroke
			(width 0)
			(type solid)
		)
		(fill yes)
		(layer "F.Cu")
		(net "M_E_ECC<2>")
	)
	(gr_poly
		(pts
			(xy 250.257564 -100.965254) (xy 250.206764 -100.965254) (xy 250.105164 -101.000814) (xy 250.105164 -101.107494)
			(xy 250.206764 -101.143054) (xy 250.257564 -101.143054)
		)
		(stroke
			(width 0)
			(type solid)
		)
		(fill yes)
		(layer "F.Cu")
		(net "M_E_ECC<2>")
	)
	(gr_poly
		(pts
			(xy 250.257564 -100.533454) (xy 250.206764 -100.533454) (xy 250.105164 -100.569014) (xy 250.105164 -100.675694)
			(xy 250.206764 -100.711254) (xy 250.257564 -100.711254)
		)
		(stroke
			(width 0)
			(type solid)
		)
		(fill yes)
		(layer "F.Cu")
		(net "M_E_ECC<2>")
	)
	(gr_poly
		(pts
			(xy 250.31192 -104.317546) (xy 250.266962 -104.272588) (xy 250.170188 -104.225852) (xy 250.09475 -104.30129)
			(xy 250.141232 -104.398318) (xy 250.18619 -104.443276)
		)
		(stroke
			(width 0)
			(type solid)
		)
		(fill yes)
		(layer "F.Cu")
		(net "M_E_ECC<3>")
	)
	(gr_poly
		(pts
			(xy 250.322588 -104.073198) (xy 250.276106 -103.97617) (xy 250.240038 -103.940356) (xy 250.114308 -104.066086)
			(xy 250.150376 -104.1019) (xy 250.24715 -104.148636)
		)
		(stroke
			(width 0)
			(type solid)
		)
		(fill yes)
		(layer "F.Cu")
		(net "M_E_ECC<2>")
	)
	(gr_poly
		(pts
			(xy 250.409964 -103.482394) (xy 250.409964 -103.375714) (xy 250.308364 -103.340154) (xy 250.257564 -103.340154)
			(xy 250.257564 -103.517954) (xy 250.308364 -103.517954)
		)
		(stroke
			(width 0)
			(type solid)
		)
		(fill yes)
		(layer "F.Cu")
		(net "M_E_ECC<2>")
	)
	(gr_poly
		(pts
			(xy 250.409964 -103.050594) (xy 250.409964 -102.943914) (xy 250.308364 -102.908354) (xy 250.257564 -102.908354)
			(xy 250.257564 -103.086154) (xy 250.308364 -103.086154)
		)
		(stroke
			(width 0)
			(type solid)
		)
		(fill yes)
		(layer "F.Cu")
		(net "M_E_ECC<2>")
	)
	(gr_poly
		(pts
			(xy 250.409964 -102.618794) (xy 250.409964 -102.512114) (xy 250.308364 -102.476554) (xy 250.257564 -102.476554)
			(xy 250.257564 -102.654354) (xy 250.308364 -102.654354)
		)
		(stroke
			(width 0)
			(type solid)
		)
		(fill yes)
		(layer "F.Cu")
		(net "M_E_ECC<2>")
	)
	(gr_poly
		(pts
			(xy 250.409964 -102.186994) (xy 250.409964 -102.080314) (xy 250.308364 -102.044754) (xy 250.257564 -102.044754)
			(xy 250.257564 -102.222554) (xy 250.308364 -102.222554)
		)
		(stroke
			(width 0)
			(type solid)
		)
		(fill yes)
		(layer "F.Cu")
		(net "M_E_ECC<2>")
	)
	(gr_poly
		(pts
			(xy 250.409964 -101.755194) (xy 250.409964 -101.648514) (xy 250.308364 -101.612954) (xy 250.257564 -101.612954)
			(xy 250.257564 -101.790754) (xy 250.308364 -101.790754)
		)
		(stroke
			(width 0)
			(type solid)
		)
		(fill yes)
		(layer "F.Cu")
		(net "M_E_ECC<2>")
	)
	(gr_poly
		(pts
			(xy 250.409964 -101.323394) (xy 250.409964 -101.216714) (xy 250.308364 -101.181154) (xy 250.257564 -101.181154)
			(xy 250.257564 -101.358954) (xy 250.308364 -101.358954)
		)
		(stroke
			(width 0)
			(type solid)
		)
		(fill yes)
		(layer "F.Cu")
		(net "M_E_ECC<2>")
	)
	(gr_poly
		(pts
			(xy 250.409964 -100.891594) (xy 250.409964 -100.784914) (xy 250.308364 -100.749354) (xy 250.257564 -100.749354)
			(xy 250.257564 -100.927154) (xy 250.308364 -100.927154)
		)
		(stroke
			(width 0)
			(type solid)
		)
		(fill yes)
		(layer "F.Cu")
		(net "M_E_ECC<2>")
	)
	(gr_poly
		(pts
			(xy 250.44273 -54.231286) (xy 250.428506 -54.03977) (xy 250.404884 -54.001924) (xy 250.066048 -54.212236)
			(xy 250.08967 -54.250082) (xy 250.25477 -54.347872)
		)
		(stroke
			(width 0)
			(type solid)
		)
		(fill yes)
		(layer "F.Cu")
		(net "M_B_ECC<3>")
	)
	(gr_poly
		(pts
			(xy 250.575064 -103.556054) (xy 250.511564 -103.556054) (xy 250.409964 -103.591614) (xy 250.409964 -103.698294)
			(xy 250.511564 -103.733854) (xy 250.575064 -103.733854)
		)
		(stroke
			(width 0)
			(type solid)
		)
		(fill yes)
		(layer "F.Cu")
		(net "M_E_ECC<3>")
	)
	(gr_poly
		(pts
			(xy 250.575064 -103.124254) (xy 250.511564 -103.124254) (xy 250.409964 -103.159814) (xy 250.409964 -103.266494)
			(xy 250.511564 -103.302054) (xy 250.575064 -103.302054)
		)
		(stroke
			(width 0)
			(type solid)
		)
		(fill yes)
		(layer "F.Cu")
		(net "M_E_ECC<3>")
	)
	(gr_poly
		(pts
			(xy 250.575064 -102.692454) (xy 250.511564 -102.692454) (xy 250.409964 -102.728014) (xy 250.409964 -102.834694)
			(xy 250.511564 -102.870254) (xy 250.575064 -102.870254)
		)
		(stroke
			(width 0)
			(type solid)
		)
		(fill yes)
		(layer "F.Cu")
		(net "M_E_ECC<3>")
	)
	(gr_poly
		(pts
			(xy 250.575064 -102.260654) (xy 250.511564 -102.260654) (xy 250.409964 -102.296214) (xy 250.409964 -102.402894)
			(xy 250.511564 -102.438454) (xy 250.575064 -102.438454)
		)
		(stroke
			(width 0)
			(type solid)
		)
		(fill yes)
		(layer "F.Cu")
		(net "M_E_ECC<3>")
	)
	(gr_poly
		(pts
			(xy 250.575064 -101.828854) (xy 250.511564 -101.828854) (xy 250.409964 -101.864414) (xy 250.409964 -101.971094)
			(xy 250.511564 -102.006654) (xy 250.575064 -102.006654)
		)
		(stroke
			(width 0)
			(type solid)
		)
		(fill yes)
		(layer "F.Cu")
		(net "M_E_ECC<3>")
	)
	(gr_poly
		(pts
			(xy 250.575064 -101.397054) (xy 250.511564 -101.397054) (xy 250.409964 -101.432614) (xy 250.409964 -101.539294)
			(xy 250.511564 -101.574854) (xy 250.575064 -101.574854)
		)
		(stroke
			(width 0)
			(type solid)
		)
		(fill yes)
		(layer "F.Cu")
		(net "M_E_ECC<3>")
	)
	(gr_poly
		(pts
			(xy 250.575064 -100.965254) (xy 250.511564 -100.965254) (xy 250.409964 -101.000814) (xy 250.409964 -101.107494)
			(xy 250.511564 -101.143054) (xy 250.575064 -101.143054)
		)
		(stroke
			(width 0)
			(type solid)
		)
		(fill yes)
		(layer "F.Cu")
		(net "M_E_ECC<3>")
	)
	(gr_poly
		(pts
			(xy 250.575064 -100.533454) (xy 250.511564 -100.533454) (xy 250.409964 -100.569014) (xy 250.409964 -100.675694)
			(xy 250.511564 -100.711254) (xy 250.575064 -100.711254)
		)
		(stroke
			(width 0)
			(type solid)
		)
		(fill yes)
		(layer "F.Cu")
		(net "M_E_ECC<3>")
	)
	(gr_poly
		(pts
			(xy 271.622774 -49.306988) (xy 271.571974 -49.306988) (xy 271.381474 -49.319688) (xy 271.381474 -49.421288)
			(xy 271.571974 -49.433988) (xy 271.622774 -49.433988)
		)
		(stroke
			(width 0)
			(type solid)
		)
		(fill yes)
		(layer "F.Cu")
		(net "M_A_DQ<36>")
	)
	(gr_poly
		(pts
			(xy 271.622774 -48.646588) (xy 271.571974 -48.646588) (xy 271.381474 -48.659288) (xy 271.381474 -48.760888)
			(xy 271.571974 -48.773588) (xy 271.622774 -48.773588)
		)
		(stroke
			(width 0)
			(type solid)
		)
		(fill yes)
		(layer "F.Cu")
		(net "M_A_DQ<36>")
	)
	(gr_poly
		(pts
			(xy 271.622774 -47.986188) (xy 271.571974 -47.986188) (xy 271.381474 -47.998888) (xy 271.381474 -48.100488)
			(xy 271.571974 -48.113188) (xy 271.622774 -48.113188)
		)
		(stroke
			(width 0)
			(type solid)
		)
		(fill yes)
		(layer "F.Cu")
		(net "M_A_DQ<36>")
	)
	(gr_poly
		(pts
			(xy 271.622774 -47.325788) (xy 271.571974 -47.325788) (xy 271.381474 -47.338488) (xy 271.381474 -47.440088)
			(xy 271.571974 -47.452788) (xy 271.622774 -47.452788)
		)
		(stroke
			(width 0)
			(type solid)
		)
		(fill yes)
		(layer "F.Cu")
		(net "M_A_DQ<36>")
	)
	(gr_poly
		(pts
			(xy 271.622774 -46.665388) (xy 271.571974 -46.665388) (xy 271.381474 -46.678088) (xy 271.381474 -46.779688)
			(xy 271.571974 -46.792388) (xy 271.622774 -46.792388)
		)
		(stroke
			(width 0)
			(type solid)
		)
		(fill yes)
		(layer "F.Cu")
		(net "M_A_DQ<36>")
	)
	(gr_poly
		(pts
			(xy 271.622774 -46.004988) (xy 271.571974 -46.004988) (xy 271.381474 -46.017688) (xy 271.381474 -46.119288)
			(xy 271.571974 -46.131988) (xy 271.622774 -46.131988)
		)
		(stroke
			(width 0)
			(type solid)
		)
		(fill yes)
		(layer "F.Cu")
		(net "M_A_DQ<36>")
	)
	(gr_poly
		(pts
			(xy 271.622774 -45.344588) (xy 271.571974 -45.344588) (xy 271.381474 -45.357288) (xy 271.381474 -45.458888)
			(xy 271.571974 -45.471588) (xy 271.622774 -45.471588)
		)
		(stroke
			(width 0)
			(type solid)
		)
		(fill yes)
		(layer "F.Cu")
		(net "M_A_DQ<36>")
	)
	(gr_poly
		(pts
			(xy 271.622774 -44.684188) (xy 271.571974 -44.684188) (xy 271.381474 -44.696888) (xy 271.381474 -44.798488)
			(xy 271.571974 -44.811188) (xy 271.622774 -44.811188)
		)
		(stroke
			(width 0)
			(type solid)
		)
		(fill yes)
		(layer "F.Cu")
		(net "M_A_DQ<36>")
	)
	(gr_poly
		(pts
			(xy 271.622774 -44.023788) (xy 271.571974 -44.023788) (xy 271.381474 -44.036488) (xy 271.381474 -44.138088)
			(xy 271.571974 -44.150788) (xy 271.622774 -44.150788)
		)
		(stroke
			(width 0)
			(type solid)
		)
		(fill yes)
		(layer "F.Cu")
		(net "M_A_DQ<36>")
	)
	(gr_poly
		(pts
			(xy 271.622774 -43.363388) (xy 271.571974 -43.363388) (xy 271.381474 -43.376088) (xy 271.381474 -43.477688)
			(xy 271.571974 -43.490388) (xy 271.622774 -43.490388)
		)
		(stroke
			(width 0)
			(type solid)
		)
		(fill yes)
		(layer "F.Cu")
		(net "M_A_DQ<36>")
	)
	(gr_poly
		(pts
			(xy 271.622774 -42.702988) (xy 271.571974 -42.702988) (xy 271.381474 -42.715688) (xy 271.381474 -42.817288)
			(xy 271.571974 -42.829988) (xy 271.622774 -42.829988)
		)
		(stroke
			(width 0)
			(type solid)
		)
		(fill yes)
		(layer "F.Cu")
		(net "M_A_DQ<36>")
	)
	(gr_poly
		(pts
			(xy 271.622774 -42.042588) (xy 271.571974 -42.042588) (xy 271.381474 -42.055288) (xy 271.381474 -42.156888)
			(xy 271.571974 -42.169588) (xy 271.622774 -42.169588)
		)
		(stroke
			(width 0)
			(type solid)
		)
		(fill yes)
		(layer "F.Cu")
		(net "M_A_DQ<36>")
	)
	(gr_poly
		(pts
			(xy 271.864074 -49.091088) (xy 271.864074 -48.989488) (xy 271.673574 -48.976788) (xy 271.622774 -48.976788)
			(xy 271.622774 -49.103788) (xy 271.673574 -49.103788)
		)
		(stroke
			(width 0)
			(type solid)
		)
		(fill yes)
		(layer "F.Cu")
		(net "M_A_DQ<36>")
	)
	(gr_poly
		(pts
			(xy 271.864074 -48.430688) (xy 271.864074 -48.329088) (xy 271.673574 -48.316388) (xy 271.622774 -48.316388)
			(xy 271.622774 -48.443388) (xy 271.673574 -48.443388)
		)
		(stroke
			(width 0)
			(type solid)
		)
		(fill yes)
		(layer "F.Cu")
		(net "M_A_DQ<36>")
	)
	(gr_poly
		(pts
			(xy 271.864074 -47.770288) (xy 271.864074 -47.668688) (xy 271.673574 -47.655988) (xy 271.622774 -47.655988)
			(xy 271.622774 -47.782988) (xy 271.673574 -47.782988)
		)
		(stroke
			(width 0)
			(type solid)
		)
		(fill yes)
		(layer "F.Cu")
		(net "M_A_DQ<36>")
	)
	(gr_poly
		(pts
			(xy 271.864074 -47.109888) (xy 271.864074 -47.008288) (xy 271.673574 -46.995588) (xy 271.622774 -46.995588)
			(xy 271.622774 -47.122588) (xy 271.673574 -47.122588)
		)
		(stroke
			(width 0)
			(type solid)
		)
		(fill yes)
		(layer "F.Cu")
		(net "M_A_DQ<36>")
	)
	(gr_poly
		(pts
			(xy 271.864074 -46.449488) (xy 271.864074 -46.347888) (xy 271.673574 -46.335188) (xy 271.622774 -46.335188)
			(xy 271.622774 -46.462188) (xy 271.673574 -46.462188)
		)
		(stroke
			(width 0)
			(type solid)
		)
		(fill yes)
		(layer "F.Cu")
		(net "M_A_DQ<36>")
	)
	(gr_poly
		(pts
			(xy 271.864074 -45.789088) (xy 271.864074 -45.687488) (xy 271.673574 -45.674788) (xy 271.622774 -45.674788)
			(xy 271.622774 -45.801788) (xy 271.673574 -45.801788)
		)
		(stroke
			(width 0)
			(type solid)
		)
		(fill yes)
		(layer "F.Cu")
		(net "M_A_DQ<36>")
	)
	(gr_poly
		(pts
			(xy 271.864074 -45.128688) (xy 271.864074 -45.027088) (xy 271.673574 -45.014388) (xy 271.622774 -45.014388)
			(xy 271.622774 -45.141388) (xy 271.673574 -45.141388)
		)
		(stroke
			(width 0)
			(type solid)
		)
		(fill yes)
		(layer "F.Cu")
		(net "M_A_DQ<36>")
	)
	(gr_poly
		(pts
			(xy 271.864074 -44.468288) (xy 271.864074 -44.366688) (xy 271.673574 -44.353988) (xy 271.622774 -44.353988)
			(xy 271.622774 -44.480988) (xy 271.673574 -44.480988)
		)
		(stroke
			(width 0)
			(type solid)
		)
		(fill yes)
		(layer "F.Cu")
		(net "M_A_DQ<36>")
	)
	(gr_poly
		(pts
			(xy 271.864074 -43.807888) (xy 271.864074 -43.706288) (xy 271.673574 -43.693588) (xy 271.622774 -43.693588)
			(xy 271.622774 -43.820588) (xy 271.673574 -43.820588)
		)
		(stroke
			(width 0)
			(type solid)
		)
		(fill yes)
		(layer "F.Cu")
		(net "M_A_DQ<36>")
	)
	(gr_poly
		(pts
			(xy 271.864074 -43.147488) (xy 271.864074 -43.045888) (xy 271.673574 -43.033188) (xy 271.622774 -43.033188)
			(xy 271.622774 -43.160188) (xy 271.673574 -43.160188)
		)
		(stroke
			(width 0)
			(type solid)
		)
		(fill yes)
		(layer "F.Cu")
		(net "M_A_DQ<36>")
	)
	(gr_poly
		(pts
			(xy 271.864074 -42.487088) (xy 271.864074 -42.385488) (xy 271.673574 -42.372788) (xy 271.622774 -42.372788)
			(xy 271.622774 -42.499788) (xy 271.673574 -42.499788)
		)
		(stroke
			(width 0)
			(type solid)
		)
		(fill yes)
		(layer "F.Cu")
		(net "M_A_DQ<36>")
	)
	(gr_poly
		(pts
			(xy 272.001996 -52.065936) (xy 272.001996 -51.844956) (xy 271.831816 -51.756056) (xy 271.787366 -51.756056)
			(xy 271.787366 -52.154836) (xy 271.831816 -52.154836)
		)
		(stroke
			(width 0)
			(type solid)
		)
		(fill yes)
		(layer "F.Cu")
		(net "M_A_DQ<37>")
	)
	(gr_poly
		(pts
			(xy 272.016474 -49.306988) (xy 271.965674 -49.306988) (xy 271.775174 -49.319688) (xy 271.775174 -49.421288)
			(xy 271.965674 -49.433988) (xy 272.016474 -49.433988)
		)
		(stroke
			(width 0)
			(type solid)
		)
		(fill yes)
		(layer "F.Cu")
		(net "M_A_DQ<37>")
	)
	(gr_poly
		(pts
			(xy 272.016474 -48.646588) (xy 271.965674 -48.646588) (xy 271.775174 -48.659288) (xy 271.775174 -48.760888)
			(xy 271.965674 -48.773588) (xy 272.016474 -48.773588)
		)
		(stroke
			(width 0)
			(type solid)
		)
		(fill yes)
		(layer "F.Cu")
		(net "M_A_DQ<37>")
	)
	(gr_poly
		(pts
			(xy 272.016474 -47.986188) (xy 271.965674 -47.986188) (xy 271.775174 -47.998888) (xy 271.775174 -48.100488)
			(xy 271.965674 -48.113188) (xy 272.016474 -48.113188)
		)
		(stroke
			(width 0)
			(type solid)
		)
		(fill yes)
		(layer "F.Cu")
		(net "M_A_DQ<37>")
	)
	(gr_poly
		(pts
			(xy 272.016474 -47.325788) (xy 271.965674 -47.325788) (xy 271.775174 -47.338488) (xy 271.775174 -47.440088)
			(xy 271.965674 -47.452788) (xy 272.016474 -47.452788)
		)
		(stroke
			(width 0)
			(type solid)
		)
		(fill yes)
		(layer "F.Cu")
		(net "M_A_DQ<37>")
	)
	(gr_poly
		(pts
			(xy 272.016474 -46.665388) (xy 271.965674 -46.665388) (xy 271.775174 -46.678088) (xy 271.775174 -46.779688)
			(xy 271.965674 -46.792388) (xy 272.016474 -46.792388)
		)
		(stroke
			(width 0)
			(type solid)
		)
		(fill yes)
		(layer "F.Cu")
		(net "M_A_DQ<37>")
	)
	(gr_poly
		(pts
			(xy 272.016474 -46.004988) (xy 271.965674 -46.004988) (xy 271.775174 -46.017688) (xy 271.775174 -46.119288)
			(xy 271.965674 -46.131988) (xy 272.016474 -46.131988)
		)
		(stroke
			(width 0)
			(type solid)
		)
		(fill yes)
		(layer "F.Cu")
		(net "M_A_DQ<37>")
	)
	(gr_poly
		(pts
			(xy 272.016474 -45.344588) (xy 271.965674 -45.344588) (xy 271.775174 -45.357288) (xy 271.775174 -45.458888)
			(xy 271.965674 -45.471588) (xy 272.016474 -45.471588)
		)
		(stroke
			(width 0)
			(type solid)
		)
		(fill yes)
		(layer "F.Cu")
		(net "M_A_DQ<37>")
	)
	(gr_poly
		(pts
			(xy 272.016474 -44.684188) (xy 271.965674 -44.684188) (xy 271.775174 -44.696888) (xy 271.775174 -44.798488)
			(xy 271.965674 -44.811188) (xy 272.016474 -44.811188)
		)
		(stroke
			(width 0)
			(type solid)
		)
		(fill yes)
		(layer "F.Cu")
		(net "M_A_DQ<37>")
	)
	(gr_poly
		(pts
			(xy 272.016474 -44.023788) (xy 271.965674 -44.023788) (xy 271.775174 -44.036488) (xy 271.775174 -44.138088)
			(xy 271.965674 -44.150788) (xy 272.016474 -44.150788)
		)
		(stroke
			(width 0)
			(type solid)
		)
		(fill yes)
		(layer "F.Cu")
		(net "M_A_DQ<37>")
	)
	(gr_poly
		(pts
			(xy 272.016474 -43.363388) (xy 271.965674 -43.363388) (xy 271.775174 -43.376088) (xy 271.775174 -43.477688)
			(xy 271.965674 -43.490388) (xy 272.016474 -43.490388)
		)
		(stroke
			(width 0)
			(type solid)
		)
		(fill yes)
		(layer "F.Cu")
		(net "M_A_DQ<37>")
	)
	(gr_poly
		(pts
			(xy 272.016474 -42.702988) (xy 271.965674 -42.702988) (xy 271.775174 -42.715688) (xy 271.775174 -42.817288)
			(xy 271.965674 -42.829988) (xy 272.016474 -42.829988)
		)
		(stroke
			(width 0)
			(type solid)
		)
		(fill yes)
		(layer "F.Cu")
		(net "M_A_DQ<37>")
	)
	(gr_poly
		(pts
			(xy 272.016474 -42.042588) (xy 271.965674 -42.042588) (xy 271.775174 -42.055288) (xy 271.775174 -42.156888)
			(xy 271.965674 -42.169588) (xy 272.016474 -42.169588)
		)
		(stroke
			(width 0)
			(type solid)
		)
		(fill yes)
		(layer "F.Cu")
		(net "M_A_DQ<37>")
	)
	(gr_poly
		(pts
			(xy 272.257774 -49.091088) (xy 272.257774 -48.989488) (xy 272.067274 -48.976788) (xy 272.016474 -48.976788)
			(xy 272.016474 -49.103788) (xy 272.067274 -49.103788)
		)
		(stroke
			(width 0)
			(type solid)
		)
		(fill yes)
		(layer "F.Cu")
		(net "M_A_DQ<37>")
	)
	(gr_poly
		(pts
			(xy 272.257774 -48.430688) (xy 272.257774 -48.329088) (xy 272.067274 -48.316388) (xy 272.016474 -48.316388)
			(xy 272.016474 -48.443388) (xy 272.067274 -48.443388)
		)
		(stroke
			(width 0)
			(type solid)
		)
		(fill yes)
		(layer "F.Cu")
		(net "M_A_DQ<37>")
	)
	(gr_poly
		(pts
			(xy 272.257774 -47.770288) (xy 272.257774 -47.668688) (xy 272.067274 -47.655988) (xy 272.016474 -47.655988)
			(xy 272.016474 -47.782988) (xy 272.067274 -47.782988)
		)
		(stroke
			(width 0)
			(type solid)
		)
		(fill yes)
		(layer "F.Cu")
		(net "M_A_DQ<37>")
	)
	(gr_poly
		(pts
			(xy 272.257774 -47.109888) (xy 272.257774 -47.008288) (xy 272.067274 -46.995588) (xy 272.016474 -46.995588)
			(xy 272.016474 -47.122588) (xy 272.067274 -47.122588)
		)
		(stroke
			(width 0)
			(type solid)
		)
		(fill yes)
		(layer "F.Cu")
		(net "M_A_DQ<37>")
	)
	(gr_poly
		(pts
			(xy 272.257774 -46.449488) (xy 272.257774 -46.347888) (xy 272.067274 -46.335188) (xy 272.016474 -46.335188)
			(xy 272.016474 -46.462188) (xy 272.067274 -46.462188)
		)
		(stroke
			(width 0)
			(type solid)
		)
		(fill yes)
		(layer "F.Cu")
		(net "M_A_DQ<37>")
	)
	(gr_poly
		(pts
			(xy 272.257774 -45.789088) (xy 272.257774 -45.687488) (xy 272.067274 -45.674788) (xy 272.016474 -45.674788)
			(xy 272.016474 -45.801788) (xy 272.067274 -45.801788)
		)
		(stroke
			(width 0)
			(type solid)
		)
		(fill yes)
		(layer "F.Cu")
		(net "M_A_DQ<37>")
	)
	(gr_poly
		(pts
			(xy 272.257774 -45.128688) (xy 272.257774 -45.027088) (xy 272.067274 -45.014388) (xy 272.016474 -45.014388)
			(xy 272.016474 -45.141388) (xy 272.067274 -45.141388)
		)
		(stroke
			(width 0)
			(type solid)
		)
		(fill yes)
		(layer "F.Cu")
		(net "M_A_DQ<37>")
	)
	(gr_poly
		(pts
			(xy 272.257774 -44.468288) (xy 272.257774 -44.366688) (xy 272.067274 -44.353988) (xy 272.016474 -44.353988)
			(xy 272.016474 -44.480988) (xy 272.067274 -44.480988)
		)
		(stroke
			(width 0)
			(type solid)
		)
		(fill yes)
		(layer "F.Cu")
		(net "M_A_DQ<37>")
	)
	(gr_poly
		(pts
			(xy 272.257774 -43.807888) (xy 272.257774 -43.706288) (xy 272.067274 -43.693588) (xy 272.016474 -43.693588)
			(xy 272.016474 -43.820588) (xy 272.067274 -43.820588)
		)
		(stroke
			(width 0)
			(type solid)
		)
		(fill yes)
		(layer "F.Cu")
		(net "M_A_DQ<37>")
	)
	(gr_poly
		(pts
			(xy 272.257774 -43.147488) (xy 272.257774 -43.045888) (xy 272.067274 -43.033188) (xy 272.016474 -43.033188)
			(xy 272.016474 -43.160188) (xy 272.067274 -43.160188)
		)
		(stroke
			(width 0)
			(type solid)
		)
		(fill yes)
		(layer "F.Cu")
		(net "M_A_DQ<37>")
	)
	(gr_poly
		(pts
			(xy 272.257774 -42.487088) (xy 272.257774 -42.385488) (xy 272.067274 -42.372788) (xy 272.016474 -42.372788)
			(xy 272.016474 -42.499788) (xy 272.067274 -42.499788)
		)
		(stroke
			(width 0)
			(type solid)
		)
		(fill yes)
		(layer "F.Cu")
		(net "M_A_DQ<37>")
	)
	(gr_poly
		(pts
			(xy 272.397474 -111.565436) (xy 272.346674 -111.565436) (xy 272.156174 -111.578136) (xy 272.156174 -111.679736)
			(xy 272.346674 -111.692436) (xy 272.397474 -111.692436)
		)
		(stroke
			(width 0)
			(type solid)
		)
		(fill yes)
		(layer "F.Cu")
		(net "M_D_DQ<36>")
	)
	(gr_poly
		(pts
			(xy 272.397474 -110.905036) (xy 272.346674 -110.905036) (xy 272.156174 -110.917736) (xy 272.156174 -111.019336)
			(xy 272.346674 -111.032036) (xy 272.397474 -111.032036)
		)
		(stroke
			(width 0)
			(type solid)
		)
		(fill yes)
		(layer "F.Cu")
		(net "M_D_DQ<36>")
	)
	(gr_poly
		(pts
			(xy 272.397474 -110.244636) (xy 272.346674 -110.244636) (xy 272.156174 -110.257336) (xy 272.156174 -110.358936)
			(xy 272.346674 -110.371636) (xy 272.397474 -110.371636)
		)
		(stroke
			(width 0)
			(type solid)
		)
		(fill yes)
		(layer "F.Cu")
		(net "M_D_DQ<36>")
	)
	(gr_poly
		(pts
			(xy 272.397474 -109.584236) (xy 272.346674 -109.584236) (xy 272.156174 -109.596936) (xy 272.156174 -109.698536)
			(xy 272.346674 -109.711236) (xy 272.397474 -109.711236)
		)
		(stroke
			(width 0)
			(type solid)
		)
		(fill yes)
		(layer "F.Cu")
		(net "M_D_DQ<36>")
	)
	(gr_poly
		(pts
			(xy 272.397474 -108.923836) (xy 272.346674 -108.923836) (xy 272.156174 -108.936536) (xy 272.156174 -109.038136)
			(xy 272.346674 -109.050836) (xy 272.397474 -109.050836)
		)
		(stroke
			(width 0)
			(type solid)
		)
		(fill yes)
		(layer "F.Cu")
		(net "M_D_DQ<36>")
	)
	(gr_poly
		(pts
			(xy 272.397474 -108.263436) (xy 272.346674 -108.263436) (xy 272.156174 -108.276136) (xy 272.156174 -108.377736)
			(xy 272.346674 -108.390436) (xy 272.397474 -108.390436)
		)
		(stroke
			(width 0)
			(type solid)
		)
		(fill yes)
		(layer "F.Cu")
		(net "M_D_DQ<36>")
	)
	(gr_poly
		(pts
			(xy 272.397474 -107.603036) (xy 272.346674 -107.603036) (xy 272.156174 -107.615736) (xy 272.156174 -107.717336)
			(xy 272.346674 -107.730036) (xy 272.397474 -107.730036)
		)
		(stroke
			(width 0)
			(type solid)
		)
		(fill yes)
		(layer "F.Cu")
		(net "M_D_DQ<36>")
	)
	(gr_poly
		(pts
			(xy 272.397474 -106.942636) (xy 272.346674 -106.942636) (xy 272.156174 -106.955336) (xy 272.156174 -107.056936)
			(xy 272.346674 -107.069636) (xy 272.397474 -107.069636)
		)
		(stroke
			(width 0)
			(type solid)
		)
		(fill yes)
		(layer "F.Cu")
		(net "M_D_DQ<36>")
	)
	(gr_poly
		(pts
			(xy 272.410174 -49.306988) (xy 272.359374 -49.306988) (xy 272.168874 -49.319688) (xy 272.168874 -49.421288)
			(xy 272.359374 -49.433988) (xy 272.410174 -49.433988)
		)
		(stroke
			(width 0)
			(type solid)
		)
		(fill yes)
		(layer "F.Cu")
		(net "M_A_DQ<32>")
	)
	(gr_poly
		(pts
			(xy 272.410174 -48.646588) (xy 272.359374 -48.646588) (xy 272.168874 -48.659288) (xy 272.168874 -48.760888)
			(xy 272.359374 -48.773588) (xy 272.410174 -48.773588)
		)
		(stroke
			(width 0)
			(type solid)
		)
		(fill yes)
		(layer "F.Cu")
		(net "M_A_DQ<32>")
	)
	(gr_poly
		(pts
			(xy 272.410174 -47.986188) (xy 272.359374 -47.986188) (xy 272.168874 -47.998888) (xy 272.168874 -48.100488)
			(xy 272.359374 -48.113188) (xy 272.410174 -48.113188)
		)
		(stroke
			(width 0)
			(type solid)
		)
		(fill yes)
		(layer "F.Cu")
		(net "M_A_DQ<32>")
	)
	(gr_poly
		(pts
			(xy 272.410174 -47.325788) (xy 272.359374 -47.325788) (xy 272.168874 -47.338488) (xy 272.168874 -47.440088)
			(xy 272.359374 -47.452788) (xy 272.410174 -47.452788)
		)
		(stroke
			(width 0)
			(type solid)
		)
		(fill yes)
		(layer "F.Cu")
		(net "M_A_DQ<32>")
	)
	(gr_poly
		(pts
			(xy 272.410174 -46.665388) (xy 272.359374 -46.665388) (xy 272.168874 -46.678088) (xy 272.168874 -46.779688)
			(xy 272.359374 -46.792388) (xy 272.410174 -46.792388)
		)
		(stroke
			(width 0)
			(type solid)
		)
		(fill yes)
		(layer "F.Cu")
		(net "M_A_DQ<32>")
	)
	(gr_poly
		(pts
			(xy 272.410174 -46.004988) (xy 272.359374 -46.004988) (xy 272.168874 -46.017688) (xy 272.168874 -46.119288)
			(xy 272.359374 -46.131988) (xy 272.410174 -46.131988)
		)
		(stroke
			(width 0)
			(type solid)
		)
		(fill yes)
		(layer "F.Cu")
		(net "M_A_DQ<32>")
	)
	(gr_poly
		(pts
			(xy 272.410174 -45.344588) (xy 272.359374 -45.344588) (xy 272.168874 -45.357288) (xy 272.168874 -45.458888)
			(xy 272.359374 -45.471588) (xy 272.410174 -45.471588)
		)
		(stroke
			(width 0)
			(type solid)
		)
		(fill yes)
		(layer "F.Cu")
		(net "M_A_DQ<32>")
	)
	(gr_poly
		(pts
			(xy 272.410174 -44.684188) (xy 272.359374 -44.684188) (xy 272.168874 -44.696888) (xy 272.168874 -44.798488)
			(xy 272.359374 -44.811188) (xy 272.410174 -44.811188)
		)
		(stroke
			(width 0)
			(type solid)
		)
		(fill yes)
		(layer "F.Cu")
		(net "M_A_DQ<32>")
	)
	(gr_poly
		(pts
			(xy 272.410174 -44.023788) (xy 272.359374 -44.023788) (xy 272.168874 -44.036488) (xy 272.168874 -44.138088)
			(xy 272.359374 -44.150788) (xy 272.410174 -44.150788)
		)
		(stroke
			(width 0)
			(type solid)
		)
		(fill yes)
		(layer "F.Cu")
		(net "M_A_DQ<32>")
	)
	(gr_poly
		(pts
			(xy 272.410174 -43.363388) (xy 272.359374 -43.363388) (xy 272.168874 -43.376088) (xy 272.168874 -43.477688)
			(xy 272.359374 -43.490388) (xy 272.410174 -43.490388)
		)
		(stroke
			(width 0)
			(type solid)
		)
		(fill yes)
		(layer "F.Cu")
		(net "M_A_DQ<32>")
	)
	(gr_poly
		(pts
			(xy 272.410174 -42.702988) (xy 272.359374 -42.702988) (xy 272.168874 -42.715688) (xy 272.168874 -42.817288)
			(xy 272.359374 -42.829988) (xy 272.410174 -42.829988)
		)
		(stroke
			(width 0)
			(type solid)
		)
		(fill yes)
		(layer "F.Cu")
		(net "M_A_DQ<32>")
	)
	(gr_poly
		(pts
			(xy 272.410174 -42.042588) (xy 272.359374 -42.042588) (xy 272.168874 -42.055288) (xy 272.168874 -42.156888)
			(xy 272.359374 -42.169588) (xy 272.410174 -42.169588)
		)
		(stroke
			(width 0)
			(type solid)
		)
		(fill yes)
		(layer "F.Cu")
		(net "M_A_DQ<32>")
	)
	(gr_poly
		(pts
			(xy 272.499074 -105.205784) (xy 272.454624 -105.205784) (xy 272.261584 -105.294684) (xy 272.261584 -105.523284)
			(xy 272.454624 -105.612184) (xy 272.499074 -105.612184)
		)
		(stroke
			(width 0)
			(type solid)
		)
		(fill yes)
		(layer "F.Cu")
		(net "M_D_DQ<36>")
	)
	(gr_poly
		(pts
			(xy 272.499074 -104.215184) (xy 272.454624 -104.215184) (xy 272.261584 -104.304084) (xy 272.261584 -104.532684)
			(xy 272.454624 -104.621584) (xy 272.499074 -104.621584)
		)
		(stroke
			(width 0)
			(type solid)
		)
		(fill yes)
		(layer "F.Cu")
		(net "M_D_DQ<36>")
	)
	(gr_poly
		(pts
			(xy 272.546572 -52.982622) (xy 272.548604 -52.790852) (xy 272.35404 -52.686204) (xy 272.19529 -52.794154)
			(xy 272.174208 -52.833524) (xy 272.52549 -53.021992)
		)
		(stroke
			(width 0)
			(type solid)
		)
		(fill yes)
		(layer "F.Cu")
		(net "M_A_DQ<37>")
	)
	(gr_poly
		(pts
			(xy 272.638774 -111.349536) (xy 272.638774 -111.247936) (xy 272.448274 -111.235236) (xy 272.397474 -111.235236)
			(xy 272.397474 -111.362236) (xy 272.448274 -111.362236)
		)
		(stroke
			(width 0)
			(type solid)
		)
		(fill yes)
		(layer "F.Cu")
		(net "M_D_DQ<36>")
	)
	(gr_poly
		(pts
			(xy 272.638774 -110.689136) (xy 272.638774 -110.587536) (xy 272.448274 -110.574836) (xy 272.397474 -110.574836)
			(xy 272.397474 -110.701836) (xy 272.448274 -110.701836)
		)
		(stroke
			(width 0)
			(type solid)
		)
		(fill yes)
		(layer "F.Cu")
		(net "M_D_DQ<36>")
	)
	(gr_poly
		(pts
			(xy 272.638774 -110.028736) (xy 272.638774 -109.927136) (xy 272.448274 -109.914436) (xy 272.397474 -109.914436)
			(xy 272.397474 -110.041436) (xy 272.448274 -110.041436)
		)
		(stroke
			(width 0)
			(type solid)
		)
		(fill yes)
		(layer "F.Cu")
		(net "M_D_DQ<36>")
	)
	(gr_poly
		(pts
			(xy 272.638774 -109.368336) (xy 272.638774 -109.266736) (xy 272.448274 -109.254036) (xy 272.397474 -109.254036)
			(xy 272.397474 -109.381036) (xy 272.448274 -109.381036)
		)
		(stroke
			(width 0)
			(type solid)
		)
		(fill yes)
		(layer "F.Cu")
		(net "M_D_DQ<36>")
	)
	(gr_poly
		(pts
			(xy 272.638774 -108.707936) (xy 272.638774 -108.606336) (xy 272.448274 -108.593636) (xy 272.397474 -108.593636)
			(xy 272.397474 -108.720636) (xy 272.448274 -108.720636)
		)
		(stroke
			(width 0)
			(type solid)
		)
		(fill yes)
		(layer "F.Cu")
		(net "M_D_DQ<36>")
	)
	(gr_poly
		(pts
			(xy 272.638774 -108.047536) (xy 272.638774 -107.945936) (xy 272.448274 -107.933236) (xy 272.397474 -107.933236)
			(xy 272.397474 -108.060236) (xy 272.448274 -108.060236)
		)
		(stroke
			(width 0)
			(type solid)
		)
		(fill yes)
		(layer "F.Cu")
		(net "M_D_DQ<36>")
	)
	(gr_poly
		(pts
			(xy 272.638774 -107.387136) (xy 272.638774 -107.285536) (xy 272.448274 -107.272836) (xy 272.397474 -107.272836)
			(xy 272.397474 -107.399836) (xy 272.448274 -107.399836)
		)
		(stroke
			(width 0)
			(type solid)
		)
		(fill yes)
		(layer "F.Cu")
		(net "M_D_DQ<36>")
	)
	(gr_poly
		(pts
			(xy 272.651474 -49.091088) (xy 272.651474 -48.989488) (xy 272.460974 -48.976788) (xy 272.410174 -48.976788)
			(xy 272.410174 -49.103788) (xy 272.460974 -49.103788)
		)
		(stroke
			(width 0)
			(type solid)
		)
		(fill yes)
		(layer "F.Cu")
		(net "M_A_DQ<32>")
	)
	(gr_poly
		(pts
			(xy 272.651474 -48.430688) (xy 272.651474 -48.329088) (xy 272.460974 -48.316388) (xy 272.410174 -48.316388)
			(xy 272.410174 -48.443388) (xy 272.460974 -48.443388)
		)
		(stroke
			(width 0)
			(type solid)
		)
		(fill yes)
		(layer "F.Cu")
		(net "M_A_DQ<32>")
	)
	(gr_poly
		(pts
			(xy 272.651474 -47.770288) (xy 272.651474 -47.668688) (xy 272.460974 -47.655988) (xy 272.410174 -47.655988)
			(xy 272.410174 -47.782988) (xy 272.460974 -47.782988)
		)
		(stroke
			(width 0)
			(type solid)
		)
		(fill yes)
		(layer "F.Cu")
		(net "M_A_DQ<32>")
	)
	(gr_poly
		(pts
			(xy 272.651474 -47.109888) (xy 272.651474 -47.008288) (xy 272.460974 -46.995588) (xy 272.410174 -46.995588)
			(xy 272.410174 -47.122588) (xy 272.460974 -47.122588)
		)
		(stroke
			(width 0)
			(type solid)
		)
		(fill yes)
		(layer "F.Cu")
		(net "M_A_DQ<32>")
	)
	(gr_poly
		(pts
			(xy 272.651474 -46.449488) (xy 272.651474 -46.347888) (xy 272.460974 -46.335188) (xy 272.410174 -46.335188)
			(xy 272.410174 -46.462188) (xy 272.460974 -46.462188)
		)
		(stroke
			(width 0)
			(type solid)
		)
		(fill yes)
		(layer "F.Cu")
		(net "M_A_DQ<32>")
	)
	(gr_poly
		(pts
			(xy 272.651474 -45.789088) (xy 272.651474 -45.687488) (xy 272.460974 -45.674788) (xy 272.410174 -45.674788)
			(xy 272.410174 -45.801788) (xy 272.460974 -45.801788)
		)
		(stroke
			(width 0)
			(type solid)
		)
		(fill yes)
		(layer "F.Cu")
		(net "M_A_DQ<32>")
	)
	(gr_poly
		(pts
			(xy 272.651474 -45.128688) (xy 272.651474 -45.027088) (xy 272.460974 -45.014388) (xy 272.410174 -45.014388)
			(xy 272.410174 -45.141388) (xy 272.460974 -45.141388)
		)
		(stroke
			(width 0)
			(type solid)
		)
		(fill yes)
		(layer "F.Cu")
		(net "M_A_DQ<32>")
	)
	(gr_poly
		(pts
			(xy 272.651474 -44.468288) (xy 272.651474 -44.366688) (xy 272.460974 -44.353988) (xy 272.410174 -44.353988)
			(xy 272.410174 -44.480988) (xy 272.460974 -44.480988)
		)
		(stroke
			(width 0)
			(type solid)
		)
		(fill yes)
		(layer "F.Cu")
		(net "M_A_DQ<32>")
	)
	(gr_poly
		(pts
			(xy 272.651474 -43.807888) (xy 272.651474 -43.706288) (xy 272.460974 -43.693588) (xy 272.410174 -43.693588)
			(xy 272.410174 -43.820588) (xy 272.460974 -43.820588)
		)
		(stroke
			(width 0)
			(type solid)
		)
		(fill yes)
		(layer "F.Cu")
		(net "M_A_DQ<32>")
	)
	(gr_poly
		(pts
			(xy 272.651474 -43.147488) (xy 272.651474 -43.045888) (xy 272.460974 -43.033188) (xy 272.410174 -43.033188)
			(xy 272.410174 -43.160188) (xy 272.460974 -43.160188)
		)
		(stroke
			(width 0)
			(type solid)
		)
		(fill yes)
		(layer "F.Cu")
		(net "M_A_DQ<32>")
	)
	(gr_poly
		(pts
			(xy 272.651474 -42.487088) (xy 272.651474 -42.385488) (xy 272.460974 -42.372788) (xy 272.410174 -42.372788)
			(xy 272.410174 -42.499788) (xy 272.460974 -42.499788)
		)
		(stroke
			(width 0)
			(type solid)
		)
		(fill yes)
		(layer "F.Cu")
		(net "M_A_DQ<32>")
	)
	(gr_poly
		(pts
			(xy 272.791174 -111.565436) (xy 272.740374 -111.565436) (xy 272.549874 -111.578136) (xy 272.549874 -111.679736)
			(xy 272.740374 -111.692436) (xy 272.791174 -111.692436)
		)
		(stroke
			(width 0)
			(type solid)
		)
		(fill yes)
		(layer "F.Cu")
		(net "M_D_DQ<37>")
	)
	(gr_poly
		(pts
			(xy 272.791174 -110.905036) (xy 272.740374 -110.905036) (xy 272.549874 -110.917736) (xy 272.549874 -111.019336)
			(xy 272.740374 -111.032036) (xy 272.791174 -111.032036)
		)
		(stroke
			(width 0)
			(type solid)
		)
		(fill yes)
		(layer "F.Cu")
		(net "M_D_DQ<37>")
	)
	(gr_poly
		(pts
			(xy 272.791174 -110.244636) (xy 272.740374 -110.244636) (xy 272.549874 -110.257336) (xy 272.549874 -110.358936)
			(xy 272.740374 -110.371636) (xy 272.791174 -110.371636)
		)
		(stroke
			(width 0)
			(type solid)
		)
		(fill yes)
		(layer "F.Cu")
		(net "M_D_DQ<37>")
	)
	(gr_poly
		(pts
			(xy 272.791174 -109.584236) (xy 272.740374 -109.584236) (xy 272.549874 -109.596936) (xy 272.549874 -109.698536)
			(xy 272.740374 -109.711236) (xy 272.791174 -109.711236)
		)
		(stroke
			(width 0)
			(type solid)
		)
		(fill yes)
		(layer "F.Cu")
		(net "M_D_DQ<37>")
	)
	(gr_poly
		(pts
			(xy 272.791174 -108.923836) (xy 272.740374 -108.923836) (xy 272.549874 -108.936536) (xy 272.549874 -109.038136)
			(xy 272.740374 -109.050836) (xy 272.791174 -109.050836)
		)
		(stroke
			(width 0)
			(type solid)
		)
		(fill yes)
		(layer "F.Cu")
		(net "M_D_DQ<37>")
	)
	(gr_poly
		(pts
			(xy 272.791174 -108.263436) (xy 272.740374 -108.263436) (xy 272.549874 -108.276136) (xy 272.549874 -108.377736)
			(xy 272.740374 -108.390436) (xy 272.791174 -108.390436)
		)
		(stroke
			(width 0)
			(type solid)
		)
		(fill yes)
		(layer "F.Cu")
		(net "M_D_DQ<37>")
	)
	(gr_poly
		(pts
			(xy 272.791174 -107.603036) (xy 272.740374 -107.603036) (xy 272.549874 -107.615736) (xy 272.549874 -107.717336)
			(xy 272.740374 -107.730036) (xy 272.791174 -107.730036)
		)
		(stroke
			(width 0)
			(type solid)
		)
		(fill yes)
		(layer "F.Cu")
		(net "M_D_DQ<37>")
	)
	(gr_poly
		(pts
			(xy 272.791174 -106.942636) (xy 272.740374 -106.942636) (xy 272.549874 -106.955336) (xy 272.549874 -107.056936)
			(xy 272.740374 -107.069636) (xy 272.791174 -107.069636)
		)
		(stroke
			(width 0)
			(type solid)
		)
		(fill yes)
		(layer "F.Cu")
		(net "M_D_DQ<37>")
	)
	(gr_poly
		(pts
			(xy 272.803874 -49.306988) (xy 272.753074 -49.306988) (xy 272.562574 -49.319688) (xy 272.562574 -49.421288)
			(xy 272.753074 -49.433988) (xy 272.803874 -49.433988)
		)
		(stroke
			(width 0)
			(type solid)
		)
		(fill yes)
		(layer "F.Cu")
		(net "M_A_DQ<33>")
	)
	(gr_poly
		(pts
			(xy 272.803874 -48.646588) (xy 272.753074 -48.646588) (xy 272.562574 -48.659288) (xy 272.562574 -48.760888)
			(xy 272.753074 -48.773588) (xy 272.803874 -48.773588)
		)
		(stroke
			(width 0)
			(type solid)
		)
		(fill yes)
		(layer "F.Cu")
		(net "M_A_DQ<33>")
	)
	(gr_poly
		(pts
			(xy 272.803874 -47.986188) (xy 272.753074 -47.986188) (xy 272.562574 -47.998888) (xy 272.562574 -48.100488)
			(xy 272.753074 -48.113188) (xy 272.803874 -48.113188)
		)
		(stroke
			(width 0)
			(type solid)
		)
		(fill yes)
		(layer "F.Cu")
		(net "M_A_DQ<33>")
	)
	(gr_poly
		(pts
			(xy 272.803874 -47.325788) (xy 272.753074 -47.325788) (xy 272.562574 -47.338488) (xy 272.562574 -47.440088)
			(xy 272.753074 -47.452788) (xy 272.803874 -47.452788)
		)
		(stroke
			(width 0)
			(type solid)
		)
		(fill yes)
		(layer "F.Cu")
		(net "M_A_DQ<33>")
	)
	(gr_poly
		(pts
			(xy 272.803874 -46.665388) (xy 272.753074 -46.665388) (xy 272.562574 -46.678088) (xy 272.562574 -46.779688)
			(xy 272.753074 -46.792388) (xy 272.803874 -46.792388)
		)
		(stroke
			(width 0)
			(type solid)
		)
		(fill yes)
		(layer "F.Cu")
		(net "M_A_DQ<33>")
	)
	(gr_poly
		(pts
			(xy 272.803874 -46.004988) (xy 272.753074 -46.004988) (xy 272.562574 -46.017688) (xy 272.562574 -46.119288)
			(xy 272.753074 -46.131988) (xy 272.803874 -46.131988)
		)
		(stroke
			(width 0)
			(type solid)
		)
		(fill yes)
		(layer "F.Cu")
		(net "M_A_DQ<33>")
	)
	(gr_poly
		(pts
			(xy 272.803874 -45.344588) (xy 272.753074 -45.344588) (xy 272.562574 -45.357288) (xy 272.562574 -45.458888)
			(xy 272.753074 -45.471588) (xy 272.803874 -45.471588)
		)
		(stroke
			(width 0)
			(type solid)
		)
		(fill yes)
		(layer "F.Cu")
		(net "M_A_DQ<33>")
	)
	(gr_poly
		(pts
			(xy 272.803874 -44.684188) (xy 272.753074 -44.684188) (xy 272.562574 -44.696888) (xy 272.562574 -44.798488)
			(xy 272.753074 -44.811188) (xy 272.803874 -44.811188)
		)
		(stroke
			(width 0)
			(type solid)
		)
		(fill yes)
		(layer "F.Cu")
		(net "M_A_DQ<33>")
	)
	(gr_poly
		(pts
			(xy 272.803874 -44.023788) (xy 272.753074 -44.023788) (xy 272.562574 -44.036488) (xy 272.562574 -44.138088)
			(xy 272.753074 -44.150788) (xy 272.803874 -44.150788)
		)
		(stroke
			(width 0)
			(type solid)
		)
		(fill yes)
		(layer "F.Cu")
		(net "M_A_DQ<33>")
	)
	(gr_poly
		(pts
			(xy 272.803874 -43.363388) (xy 272.753074 -43.363388) (xy 272.562574 -43.376088) (xy 272.562574 -43.477688)
			(xy 272.753074 -43.490388) (xy 272.803874 -43.490388)
		)
		(stroke
			(width 0)
			(type solid)
		)
		(fill yes)
		(layer "F.Cu")
		(net "M_A_DQ<33>")
	)
	(gr_poly
		(pts
			(xy 272.803874 -42.702988) (xy 272.753074 -42.702988) (xy 272.562574 -42.715688) (xy 272.562574 -42.817288)
			(xy 272.753074 -42.829988) (xy 272.803874 -42.829988)
		)
		(stroke
			(width 0)
			(type solid)
		)
		(fill yes)
		(layer "F.Cu")
		(net "M_A_DQ<33>")
	)
	(gr_poly
		(pts
			(xy 272.803874 -42.042588) (xy 272.753074 -42.042588) (xy 272.562574 -42.055288) (xy 272.562574 -42.156888)
			(xy 272.753074 -42.169588) (xy 272.803874 -42.169588)
		)
		(stroke
			(width 0)
			(type solid)
		)
		(fill yes)
		(layer "F.Cu")
		(net "M_A_DQ<33>")
	)
	(gr_poly
		(pts
			(xy 272.863564 -103.062532) (xy 272.832068 -103.03129) (xy 272.632678 -102.95763) (xy 272.471134 -103.119174)
			(xy 272.544794 -103.318564) (xy 272.576036 -103.35006)
		)
		(stroke
			(width 0)
			(type solid)
		)
		(fill yes)
		(layer "F.Cu")
		(net "M_D_DQ<36>")
	)
	(gr_poly
		(pts
			(xy 272.927064 -105.523284) (xy 272.927064 -105.294684) (xy 272.734024 -105.205784) (xy 272.689574 -105.205784)
			(xy 272.689574 -105.612184) (xy 272.734024 -105.612184)
		)
		(stroke
			(width 0)
			(type solid)
		)
		(fill yes)
		(layer "F.Cu")
		(net "M_D_DQ<37>")
	)
	(gr_poly
		(pts
			(xy 272.927064 -104.532684) (xy 272.927064 -104.304084) (xy 272.734024 -104.215184) (xy 272.689574 -104.215184)
			(xy 272.689574 -104.621584) (xy 272.734024 -104.621584)
		)
		(stroke
			(width 0)
			(type solid)
		)
		(fill yes)
		(layer "F.Cu")
		(net "M_D_DQ<37>")
	)
	(gr_poly
		(pts
			(xy 273.032474 -111.349536) (xy 273.032474 -111.247936) (xy 272.841974 -111.235236) (xy 272.791174 -111.235236)
			(xy 272.791174 -111.362236) (xy 272.841974 -111.362236)
		)
		(stroke
			(width 0)
			(type solid)
		)
		(fill yes)
		(layer "F.Cu")
		(net "M_D_DQ<37>")
	)
	(gr_poly
		(pts
			(xy 273.032474 -110.689136) (xy 273.032474 -110.587536) (xy 272.841974 -110.574836) (xy 272.791174 -110.574836)
			(xy 272.791174 -110.701836) (xy 272.841974 -110.701836)
		)
		(stroke
			(width 0)
			(type solid)
		)
		(fill yes)
		(layer "F.Cu")
		(net "M_D_DQ<37>")
	)
	(gr_poly
		(pts
			(xy 273.032474 -110.028736) (xy 273.032474 -109.927136) (xy 272.841974 -109.914436) (xy 272.791174 -109.914436)
			(xy 272.791174 -110.041436) (xy 272.841974 -110.041436)
		)
		(stroke
			(width 0)
			(type solid)
		)
		(fill yes)
		(layer "F.Cu")
		(net "M_D_DQ<37>")
	)
	(gr_poly
		(pts
			(xy 273.032474 -109.368336) (xy 273.032474 -109.266736) (xy 272.841974 -109.254036) (xy 272.791174 -109.254036)
			(xy 272.791174 -109.381036) (xy 272.841974 -109.381036)
		)
		(stroke
			(width 0)
			(type solid)
		)
		(fill yes)
		(layer "F.Cu")
		(net "M_D_DQ<37>")
	)
	(gr_poly
		(pts
			(xy 273.032474 -108.707936) (xy 273.032474 -108.606336) (xy 272.841974 -108.593636) (xy 272.791174 -108.593636)
			(xy 272.791174 -108.720636) (xy 272.841974 -108.720636)
		)
		(stroke
			(width 0)
			(type solid)
		)
		(fill yes)
		(layer "F.Cu")
		(net "M_D_DQ<37>")
	)
	(gr_poly
		(pts
			(xy 273.032474 -108.047536) (xy 273.032474 -107.945936) (xy 272.841974 -107.933236) (xy 272.791174 -107.933236)
			(xy 272.791174 -108.060236) (xy 272.841974 -108.060236)
		)
		(stroke
			(width 0)
			(type solid)
		)
		(fill yes)
		(layer "F.Cu")
		(net "M_D_DQ<37>")
	)
	(gr_poly
		(pts
			(xy 273.032474 -107.387136) (xy 273.032474 -107.285536) (xy 272.841974 -107.272836) (xy 272.791174 -107.272836)
			(xy 272.791174 -107.399836) (xy 272.841974 -107.399836)
		)
		(stroke
			(width 0)
			(type solid)
		)
		(fill yes)
		(layer "F.Cu")
		(net "M_D_DQ<37>")
	)
	(gr_poly
		(pts
			(xy 273.045174 -49.091088) (xy 273.045174 -48.989488) (xy 272.854674 -48.976788) (xy 272.803874 -48.976788)
			(xy 272.803874 -49.103788) (xy 272.854674 -49.103788)
		)
		(stroke
			(width 0)
			(type solid)
		)
		(fill yes)
		(layer "F.Cu")
		(net "M_A_DQ<33>")
	)
	(gr_poly
		(pts
			(xy 273.045174 -48.430688) (xy 273.045174 -48.329088) (xy 272.854674 -48.316388) (xy 272.803874 -48.316388)
			(xy 272.803874 -48.443388) (xy 272.854674 -48.443388)
		)
		(stroke
			(width 0)
			(type solid)
		)
		(fill yes)
		(layer "F.Cu")
		(net "M_A_DQ<33>")
	)
	(gr_poly
		(pts
			(xy 273.045174 -47.770288) (xy 273.045174 -47.668688) (xy 272.854674 -47.655988) (xy 272.803874 -47.655988)
			(xy 272.803874 -47.782988) (xy 272.854674 -47.782988)
		)
		(stroke
			(width 0)
			(type solid)
		)
		(fill yes)
		(layer "F.Cu")
		(net "M_A_DQ<33>")
	)
	(gr_poly
		(pts
			(xy 273.045174 -47.109888) (xy 273.045174 -47.008288) (xy 272.854674 -46.995588) (xy 272.803874 -46.995588)
			(xy 272.803874 -47.122588) (xy 272.854674 -47.122588)
		)
		(stroke
			(width 0)
			(type solid)
		)
		(fill yes)
		(layer "F.Cu")
		(net "M_A_DQ<33>")
	)
	(gr_poly
		(pts
			(xy 273.045174 -46.449488) (xy 273.045174 -46.347888) (xy 272.854674 -46.335188) (xy 272.803874 -46.335188)
			(xy 272.803874 -46.462188) (xy 272.854674 -46.462188)
		)
		(stroke
			(width 0)
			(type solid)
		)
		(fill yes)
		(layer "F.Cu")
		(net "M_A_DQ<33>")
	)
	(gr_poly
		(pts
			(xy 273.045174 -45.789088) (xy 273.045174 -45.687488) (xy 272.854674 -45.674788) (xy 272.803874 -45.674788)
			(xy 272.803874 -45.801788) (xy 272.854674 -45.801788)
		)
		(stroke
			(width 0)
			(type solid)
		)
		(fill yes)
		(layer "F.Cu")
		(net "M_A_DQ<33>")
	)
	(gr_poly
		(pts
			(xy 273.045174 -45.128688) (xy 273.045174 -45.027088) (xy 272.854674 -45.014388) (xy 272.803874 -45.014388)
			(xy 272.803874 -45.141388) (xy 272.854674 -45.141388)
		)
		(stroke
			(width 0)
			(type solid)
		)
		(fill yes)
		(layer "F.Cu")
		(net "M_A_DQ<33>")
	)
	(gr_poly
		(pts
			(xy 273.045174 -44.468288) (xy 273.045174 -44.366688) (xy 272.854674 -44.353988) (xy 272.803874 -44.353988)
			(xy 272.803874 -44.480988) (xy 272.854674 -44.480988)
		)
		(stroke
			(width 0)
			(type solid)
		)
		(fill yes)
		(layer "F.Cu")
		(net "M_A_DQ<33>")
	)
	(gr_poly
		(pts
			(xy 273.045174 -43.807888) (xy 273.045174 -43.706288) (xy 272.854674 -43.693588) (xy 272.803874 -43.693588)
			(xy 272.803874 -43.820588) (xy 272.854674 -43.820588)
		)
		(stroke
			(width 0)
			(type solid)
		)
		(fill yes)
		(layer "F.Cu")
		(net "M_A_DQ<33>")
	)
	(gr_poly
		(pts
			(xy 273.045174 -43.147488) (xy 273.045174 -43.045888) (xy 272.854674 -43.033188) (xy 272.803874 -43.033188)
			(xy 272.803874 -43.160188) (xy 272.854674 -43.160188)
		)
		(stroke
			(width 0)
			(type solid)
		)
		(fill yes)
		(layer "F.Cu")
		(net "M_A_DQ<33>")
	)
	(gr_poly
		(pts
			(xy 273.045174 -42.487088) (xy 273.045174 -42.385488) (xy 272.854674 -42.372788) (xy 272.803874 -42.372788)
			(xy 272.803874 -42.499788) (xy 272.854674 -42.499788)
		)
		(stroke
			(width 0)
			(type solid)
		)
		(fill yes)
		(layer "F.Cu")
		(net "M_A_DQ<33>")
	)
	(gr_poly
		(pts
			(xy 273.106134 -103.431086) (xy 273.032474 -103.231696) (xy 273.001232 -103.2002) (xy 272.713704 -103.487728)
			(xy 272.7452 -103.51897) (xy 272.94459 -103.59263)
		)
		(stroke
			(width 0)
			(type solid)
		)
		(fill yes)
		(layer "F.Cu")
		(net "M_D_DQ<37>")
	)
	(gr_poly
		(pts
			(xy 273.184874 -111.565436) (xy 273.134074 -111.565436) (xy 272.943574 -111.578136) (xy 272.943574 -111.679736)
			(xy 273.134074 -111.692436) (xy 273.184874 -111.692436)
		)
		(stroke
			(width 0)
			(type solid)
		)
		(fill yes)
		(layer "F.Cu")
		(net "M_D_DQ<32>")
	)
	(gr_poly
		(pts
			(xy 273.184874 -110.905036) (xy 273.134074 -110.905036) (xy 272.943574 -110.917736) (xy 272.943574 -111.019336)
			(xy 273.134074 -111.032036) (xy 273.184874 -111.032036)
		)
		(stroke
			(width 0)
			(type solid)
		)
		(fill yes)
		(layer "F.Cu")
		(net "M_D_DQ<32>")
	)
	(gr_poly
		(pts
			(xy 273.184874 -110.244636) (xy 273.134074 -110.244636) (xy 272.943574 -110.257336) (xy 272.943574 -110.358936)
			(xy 273.134074 -110.371636) (xy 273.184874 -110.371636)
		)
		(stroke
			(width 0)
			(type solid)
		)
		(fill yes)
		(layer "F.Cu")
		(net "M_D_DQ<32>")
	)
	(gr_poly
		(pts
			(xy 273.184874 -109.584236) (xy 273.134074 -109.584236) (xy 272.943574 -109.596936) (xy 272.943574 -109.698536)
			(xy 273.134074 -109.711236) (xy 273.184874 -109.711236)
		)
		(stroke
			(width 0)
			(type solid)
		)
		(fill yes)
		(layer "F.Cu")
		(net "M_D_DQ<32>")
	)
	(gr_poly
		(pts
			(xy 273.184874 -108.923836) (xy 273.134074 -108.923836) (xy 272.943574 -108.936536) (xy 272.943574 -109.038136)
			(xy 273.134074 -109.050836) (xy 273.184874 -109.050836)
		)
		(stroke
			(width 0)
			(type solid)
		)
		(fill yes)
		(layer "F.Cu")
		(net "M_D_DQ<32>")
	)
	(gr_poly
		(pts
			(xy 273.184874 -108.263436) (xy 273.134074 -108.263436) (xy 272.943574 -108.276136) (xy 272.943574 -108.377736)
			(xy 273.134074 -108.390436) (xy 273.184874 -108.390436)
		)
		(stroke
			(width 0)
			(type solid)
		)
		(fill yes)
		(layer "F.Cu")
		(net "M_D_DQ<32>")
	)
	(gr_poly
		(pts
			(xy 273.184874 -107.603036) (xy 273.134074 -107.603036) (xy 272.943574 -107.615736) (xy 272.943574 -107.717336)
			(xy 273.134074 -107.730036) (xy 273.184874 -107.730036)
		)
		(stroke
			(width 0)
			(type solid)
		)
		(fill yes)
		(layer "F.Cu")
		(net "M_D_DQ<32>")
	)
	(gr_poly
		(pts
			(xy 273.184874 -106.942636) (xy 273.134074 -106.942636) (xy 272.943574 -106.955336) (xy 272.943574 -107.056936)
			(xy 273.134074 -107.069636) (xy 273.184874 -107.069636)
		)
		(stroke
			(width 0)
			(type solid)
		)
		(fill yes)
		(layer "F.Cu")
		(net "M_D_DQ<32>")
	)
	(gr_poly
		(pts
			(xy 273.197574 -49.306988) (xy 273.146774 -49.306988) (xy 272.956274 -49.319688) (xy 272.956274 -49.421288)
			(xy 273.146774 -49.433988) (xy 273.197574 -49.433988)
		)
		(stroke
			(width 0)
			(type solid)
		)
		(fill yes)
		(layer "F.Cu")
		(net "M_A_DQS_DP<13>")
	)
	(gr_poly
		(pts
			(xy 273.197574 -48.646588) (xy 273.146774 -48.646588) (xy 272.956274 -48.659288) (xy 272.956274 -48.760888)
			(xy 273.146774 -48.773588) (xy 273.197574 -48.773588)
		)
		(stroke
			(width 0)
			(type solid)
		)
		(fill yes)
		(layer "F.Cu")
		(net "M_A_DQS_DP<13>")
	)
	(gr_poly
		(pts
			(xy 273.197574 -47.986188) (xy 273.146774 -47.986188) (xy 272.956274 -47.998888) (xy 272.956274 -48.100488)
			(xy 273.146774 -48.113188) (xy 273.197574 -48.113188)
		)
		(stroke
			(width 0)
			(type solid)
		)
		(fill yes)
		(layer "F.Cu")
		(net "M_A_DQS_DP<13>")
	)
	(gr_poly
		(pts
			(xy 273.197574 -47.325788) (xy 273.146774 -47.325788) (xy 272.956274 -47.338488) (xy 272.956274 -47.440088)
			(xy 273.146774 -47.452788) (xy 273.197574 -47.452788)
		)
		(stroke
			(width 0)
			(type solid)
		)
		(fill yes)
		(layer "F.Cu")
		(net "M_A_DQS_DP<13>")
	)
	(gr_poly
		(pts
			(xy 273.197574 -46.665388) (xy 273.146774 -46.665388) (xy 272.956274 -46.678088) (xy 272.956274 -46.779688)
			(xy 273.146774 -46.792388) (xy 273.197574 -46.792388)
		)
		(stroke
			(width 0)
			(type solid)
		)
		(fill yes)
		(layer "F.Cu")
		(net "M_A_DQS_DP<13>")
	)
	(gr_poly
		(pts
			(xy 273.197574 -46.004988) (xy 273.146774 -46.004988) (xy 272.956274 -46.017688) (xy 272.956274 -46.119288)
			(xy 273.146774 -46.131988) (xy 273.197574 -46.131988)
		)
		(stroke
			(width 0)
			(type solid)
		)
		(fill yes)
		(layer "F.Cu")
		(net "M_A_DQS_DP<13>")
	)
	(gr_poly
		(pts
			(xy 273.197574 -45.344588) (xy 273.146774 -45.344588) (xy 272.956274 -45.357288) (xy 272.956274 -45.458888)
			(xy 273.146774 -45.471588) (xy 273.197574 -45.471588)
		)
		(stroke
			(width 0)
			(type solid)
		)
		(fill yes)
		(layer "F.Cu")
		(net "M_A_DQS_DP<13>")
	)
	(gr_poly
		(pts
			(xy 273.197574 -44.684188) (xy 273.146774 -44.684188) (xy 272.956274 -44.696888) (xy 272.956274 -44.798488)
			(xy 273.146774 -44.811188) (xy 273.197574 -44.811188)
		)
		(stroke
			(width 0)
			(type solid)
		)
		(fill yes)
		(layer "F.Cu")
		(net "M_A_DQS_DP<13>")
	)
	(gr_poly
		(pts
			(xy 273.197574 -44.023788) (xy 273.146774 -44.023788) (xy 272.956274 -44.036488) (xy 272.956274 -44.138088)
			(xy 273.146774 -44.150788) (xy 273.197574 -44.150788)
		)
		(stroke
			(width 0)
			(type solid)
		)
		(fill yes)
		(layer "F.Cu")
		(net "M_A_DQS_DP<13>")
	)
	(gr_poly
		(pts
			(xy 273.197574 -43.363388) (xy 273.146774 -43.363388) (xy 272.956274 -43.376088) (xy 272.956274 -43.477688)
			(xy 273.146774 -43.490388) (xy 273.197574 -43.490388)
		)
		(stroke
			(width 0)
			(type solid)
		)
		(fill yes)
		(layer "F.Cu")
		(net "M_A_DQS_DP<13>")
	)
	(gr_poly
		(pts
			(xy 273.197574 -42.702988) (xy 273.146774 -42.702988) (xy 272.956274 -42.715688) (xy 272.956274 -42.817288)
			(xy 273.146774 -42.829988) (xy 273.197574 -42.829988)
		)
		(stroke
			(width 0)
			(type solid)
		)
		(fill yes)
		(layer "F.Cu")
		(net "M_A_DQS_DP<13>")
	)
	(gr_poly
		(pts
			(xy 273.197574 -42.042588) (xy 273.146774 -42.042588) (xy 272.956274 -42.055288) (xy 272.956274 -42.156888)
			(xy 273.146774 -42.169588) (xy 273.197574 -42.169588)
		)
		(stroke
			(width 0)
			(type solid)
		)
		(fill yes)
		(layer "F.Cu")
		(net "M_A_DQS_DP<13>")
	)
	(gr_poly
		(pts
			(xy 273.286474 -105.949242) (xy 273.242024 -105.949242) (xy 273.048984 -106.038142) (xy 273.048984 -106.266742)
			(xy 273.242024 -106.355642) (xy 273.286474 -106.355642)
		)
		(stroke
			(width 0)
			(type solid)
		)
		(fill yes)
		(layer "F.Cu")
		(net "M_D_DQ<32>")
	)
	(gr_poly
		(pts
			(xy 273.286474 -105.060242) (xy 273.242024 -105.060242) (xy 273.048984 -105.149142) (xy 273.048984 -105.377742)
			(xy 273.242024 -105.466642) (xy 273.286474 -105.466642)
		)
		(stroke
			(width 0)
			(type solid)
		)
		(fill yes)
		(layer "F.Cu")
		(net "M_D_DQ<32>")
	)
	(gr_poly
		(pts
			(xy 273.426174 -111.349536) (xy 273.426174 -111.247936) (xy 273.235674 -111.235236) (xy 273.184874 -111.235236)
			(xy 273.184874 -111.362236) (xy 273.235674 -111.362236)
		)
		(stroke
			(width 0)
			(type solid)
		)
		(fill yes)
		(layer "F.Cu")
		(net "M_D_DQ<32>")
	)
	(gr_poly
		(pts
			(xy 273.426174 -110.689136) (xy 273.426174 -110.587536) (xy 273.235674 -110.574836) (xy 273.184874 -110.574836)
			(xy 273.184874 -110.701836) (xy 273.235674 -110.701836)
		)
		(stroke
			(width 0)
			(type solid)
		)
		(fill yes)
		(layer "F.Cu")
		(net "M_D_DQ<32>")
	)
	(gr_poly
		(pts
			(xy 273.426174 -110.028736) (xy 273.426174 -109.927136) (xy 273.235674 -109.914436) (xy 273.184874 -109.914436)
			(xy 273.184874 -110.041436) (xy 273.235674 -110.041436)
		)
		(stroke
			(width 0)
			(type solid)
		)
		(fill yes)
		(layer "F.Cu")
		(net "M_D_DQ<32>")
	)
	(gr_poly
		(pts
			(xy 273.426174 -109.368336) (xy 273.426174 -109.266736) (xy 273.235674 -109.254036) (xy 273.184874 -109.254036)
			(xy 273.184874 -109.381036) (xy 273.235674 -109.381036)
		)
		(stroke
			(width 0)
			(type solid)
		)
		(fill yes)
		(layer "F.Cu")
		(net "M_D_DQ<32>")
	)
	(gr_poly
		(pts
			(xy 273.426174 -108.707936) (xy 273.426174 -108.606336) (xy 273.235674 -108.593636) (xy 273.184874 -108.593636)
			(xy 273.184874 -108.720636) (xy 273.235674 -108.720636)
		)
		(stroke
			(width 0)
			(type solid)
		)
		(fill yes)
		(layer "F.Cu")
		(net "M_D_DQ<32>")
	)
	(gr_poly
		(pts
			(xy 273.426174 -108.047536) (xy 273.426174 -107.945936) (xy 273.235674 -107.933236) (xy 273.184874 -107.933236)
			(xy 273.184874 -108.060236) (xy 273.235674 -108.060236)
		)
		(stroke
			(width 0)
			(type solid)
		)
		(fill yes)
		(layer "F.Cu")
		(net "M_D_DQ<32>")
	)
	(gr_poly
		(pts
			(xy 273.426174 -107.387136) (xy 273.426174 -107.285536) (xy 273.235674 -107.272836) (xy 273.184874 -107.272836)
			(xy 273.184874 -107.399836) (xy 273.235674 -107.399836)
		)
		(stroke
			(width 0)
			(type solid)
		)
		(fill yes)
		(layer "F.Cu")
		(net "M_D_DQ<32>")
	)
	(gr_poly
		(pts
			(xy 273.438874 -49.091088) (xy 273.438874 -48.989488) (xy 273.248374 -48.976788) (xy 273.197574 -48.976788)
			(xy 273.197574 -49.103788) (xy 273.248374 -49.103788)
		)
		(stroke
			(width 0)
			(type solid)
		)
		(fill yes)
		(layer "F.Cu")
		(net "M_A_DQS_DP<13>")
	)
	(gr_poly
		(pts
			(xy 273.438874 -48.430688) (xy 273.438874 -48.329088) (xy 273.248374 -48.316388) (xy 273.197574 -48.316388)
			(xy 273.197574 -48.443388) (xy 273.248374 -48.443388)
		)
		(stroke
			(width 0)
			(type solid)
		)
		(fill yes)
		(layer "F.Cu")
		(net "M_A_DQS_DP<13>")
	)
	(gr_poly
		(pts
			(xy 273.438874 -47.770288) (xy 273.438874 -47.668688) (xy 273.248374 -47.655988) (xy 273.197574 -47.655988)
			(xy 273.197574 -47.782988) (xy 273.248374 -47.782988)
		)
		(stroke
			(width 0)
			(type solid)
		)
		(fill yes)
		(layer "F.Cu")
		(net "M_A_DQS_DP<13>")
	)
	(gr_poly
		(pts
			(xy 273.438874 -47.109888) (xy 273.438874 -47.008288) (xy 273.248374 -46.995588) (xy 273.197574 -46.995588)
			(xy 273.197574 -47.122588) (xy 273.248374 -47.122588)
		)
		(stroke
			(width 0)
			(type solid)
		)
		(fill yes)
		(layer "F.Cu")
		(net "M_A_DQS_DP<13>")
	)
	(gr_poly
		(pts
			(xy 273.438874 -46.449488) (xy 273.438874 -46.347888) (xy 273.248374 -46.335188) (xy 273.197574 -46.335188)
			(xy 273.197574 -46.462188) (xy 273.248374 -46.462188)
		)
		(stroke
			(width 0)
			(type solid)
		)
		(fill yes)
		(layer "F.Cu")
		(net "M_A_DQS_DP<13>")
	)
	(gr_poly
		(pts
			(xy 273.438874 -45.789088) (xy 273.438874 -45.687488) (xy 273.248374 -45.674788) (xy 273.197574 -45.674788)
			(xy 273.197574 -45.801788) (xy 273.248374 -45.801788)
		)
		(stroke
			(width 0)
			(type solid)
		)
		(fill yes)
		(layer "F.Cu")
		(net "M_A_DQS_DP<13>")
	)
	(gr_poly
		(pts
			(xy 273.438874 -45.128688) (xy 273.438874 -45.027088) (xy 273.248374 -45.014388) (xy 273.197574 -45.014388)
			(xy 273.197574 -45.141388) (xy 273.248374 -45.141388)
		)
		(stroke
			(width 0)
			(type solid)
		)
		(fill yes)
		(layer "F.Cu")
		(net "M_A_DQS_DP<13>")
	)
	(gr_poly
		(pts
			(xy 273.438874 -44.468288) (xy 273.438874 -44.366688) (xy 273.248374 -44.353988) (xy 273.197574 -44.353988)
			(xy 273.197574 -44.480988) (xy 273.248374 -44.480988)
		)
		(stroke
			(width 0)
			(type solid)
		)
		(fill yes)
		(layer "F.Cu")
		(net "M_A_DQS_DP<13>")
	)
	(gr_poly
		(pts
			(xy 273.438874 -43.807888) (xy 273.438874 -43.706288) (xy 273.248374 -43.693588) (xy 273.197574 -43.693588)
			(xy 273.197574 -43.820588) (xy 273.248374 -43.820588)
		)
		(stroke
			(width 0)
			(type solid)
		)
		(fill yes)
		(layer "F.Cu")
		(net "M_A_DQS_DP<13>")
	)
	(gr_poly
		(pts
			(xy 273.438874 -43.147488) (xy 273.438874 -43.045888) (xy 273.248374 -43.033188) (xy 273.197574 -43.033188)
			(xy 273.197574 -43.160188) (xy 273.248374 -43.160188)
		)
		(stroke
			(width 0)
			(type solid)
		)
		(fill yes)
		(layer "F.Cu")
		(net "M_A_DQS_DP<13>")
	)
	(gr_poly
		(pts
			(xy 273.438874 -42.487088) (xy 273.438874 -42.385488) (xy 273.248374 -42.372788) (xy 273.197574 -42.372788)
			(xy 273.197574 -42.499788) (xy 273.248374 -42.499788)
		)
		(stroke
			(width 0)
			(type solid)
		)
		(fill yes)
		(layer "F.Cu")
		(net "M_A_DQS_DP<13>")
	)
	(gr_poly
		(pts
			(xy 273.578574 -111.565436) (xy 273.527774 -111.565436) (xy 273.337274 -111.578136) (xy 273.337274 -111.679736)
			(xy 273.527774 -111.692436) (xy 273.578574 -111.692436)
		)
		(stroke
			(width 0)
			(type solid)
		)
		(fill yes)
		(layer "F.Cu")
		(net "M_D_DQ<33>")
	)
	(gr_poly
		(pts
			(xy 273.578574 -110.905036) (xy 273.527774 -110.905036) (xy 273.337274 -110.917736) (xy 273.337274 -111.019336)
			(xy 273.527774 -111.032036) (xy 273.578574 -111.032036)
		)
		(stroke
			(width 0)
			(type solid)
		)
		(fill yes)
		(layer "F.Cu")
		(net "M_D_DQ<33>")
	)
	(gr_poly
		(pts
			(xy 273.578574 -110.244636) (xy 273.527774 -110.244636) (xy 273.337274 -110.257336) (xy 273.337274 -110.358936)
			(xy 273.527774 -110.371636) (xy 273.578574 -110.371636)
		)
		(stroke
			(width 0)
			(type solid)
		)
		(fill yes)
		(layer "F.Cu")
		(net "M_D_DQ<33>")
	)
	(gr_poly
		(pts
			(xy 273.578574 -109.584236) (xy 273.527774 -109.584236) (xy 273.337274 -109.596936) (xy 273.337274 -109.698536)
			(xy 273.527774 -109.711236) (xy 273.578574 -109.711236)
		)
		(stroke
			(width 0)
			(type solid)
		)
		(fill yes)
		(layer "F.Cu")
		(net "M_D_DQ<33>")
	)
	(gr_poly
		(pts
			(xy 273.578574 -108.923836) (xy 273.527774 -108.923836) (xy 273.337274 -108.936536) (xy 273.337274 -109.038136)
			(xy 273.527774 -109.050836) (xy 273.578574 -109.050836)
		)
		(stroke
			(width 0)
			(type solid)
		)
		(fill yes)
		(layer "F.Cu")
		(net "M_D_DQ<33>")
	)
	(gr_poly
		(pts
			(xy 273.578574 -108.263436) (xy 273.527774 -108.263436) (xy 273.337274 -108.276136) (xy 273.337274 -108.377736)
			(xy 273.527774 -108.390436) (xy 273.578574 -108.390436)
		)
		(stroke
			(width 0)
			(type solid)
		)
		(fill yes)
		(layer "F.Cu")
		(net "M_D_DQ<33>")
	)
	(gr_poly
		(pts
			(xy 273.578574 -107.603036) (xy 273.527774 -107.603036) (xy 273.337274 -107.615736) (xy 273.337274 -107.717336)
			(xy 273.527774 -107.730036) (xy 273.578574 -107.730036)
		)
		(stroke
			(width 0)
			(type solid)
		)
		(fill yes)
		(layer "F.Cu")
		(net "M_D_DQ<33>")
	)
	(gr_poly
		(pts
			(xy 273.578574 -106.942636) (xy 273.527774 -106.942636) (xy 273.337274 -106.955336) (xy 273.337274 -107.056936)
			(xy 273.527774 -107.069636) (xy 273.578574 -107.069636)
		)
		(stroke
			(width 0)
			(type solid)
		)
		(fill yes)
		(layer "F.Cu")
		(net "M_D_DQ<33>")
	)
	(gr_poly
		(pts
			(xy 273.591274 -49.306988) (xy 273.540474 -49.306988) (xy 273.349974 -49.319688) (xy 273.349974 -49.421288)
			(xy 273.540474 -49.433988) (xy 273.591274 -49.433988)
		)
		(stroke
			(width 0)
			(type solid)
		)
		(fill yes)
		(layer "F.Cu")
		(net "M_A_DQS_DN<13>")
	)
	(gr_poly
		(pts
			(xy 273.591274 -48.646588) (xy 273.540474 -48.646588) (xy 273.349974 -48.659288) (xy 273.349974 -48.760888)
			(xy 273.540474 -48.773588) (xy 273.591274 -48.773588)
		)
		(stroke
			(width 0)
			(type solid)
		)
		(fill yes)
		(layer "F.Cu")
		(net "M_A_DQS_DN<13>")
	)
	(gr_poly
		(pts
			(xy 273.591274 -47.986188) (xy 273.540474 -47.986188) (xy 273.349974 -47.998888) (xy 273.349974 -48.100488)
			(xy 273.540474 -48.113188) (xy 273.591274 -48.113188)
		)
		(stroke
			(width 0)
			(type solid)
		)
		(fill yes)
		(layer "F.Cu")
		(net "M_A_DQS_DN<13>")
	)
	(gr_poly
		(pts
			(xy 273.591274 -47.325788) (xy 273.540474 -47.325788) (xy 273.349974 -47.338488) (xy 273.349974 -47.440088)
			(xy 273.540474 -47.452788) (xy 273.591274 -47.452788)
		)
		(stroke
			(width 0)
			(type solid)
		)
		(fill yes)
		(layer "F.Cu")
		(net "M_A_DQS_DN<13>")
	)
	(gr_poly
		(pts
			(xy 273.591274 -46.665388) (xy 273.540474 -46.665388) (xy 273.349974 -46.678088) (xy 273.349974 -46.779688)
			(xy 273.540474 -46.792388) (xy 273.591274 -46.792388)
		)
		(stroke
			(width 0)
			(type solid)
		)
		(fill yes)
		(layer "F.Cu")
		(net "M_A_DQS_DN<13>")
	)
	(gr_poly
		(pts
			(xy 273.591274 -46.004988) (xy 273.540474 -46.004988) (xy 273.349974 -46.017688) (xy 273.349974 -46.119288)
			(xy 273.540474 -46.131988) (xy 273.591274 -46.131988)
		)
		(stroke
			(width 0)
			(type solid)
		)
		(fill yes)
		(layer "F.Cu")
		(net "M_A_DQS_DN<13>")
	)
	(gr_poly
		(pts
			(xy 273.591274 -45.344588) (xy 273.540474 -45.344588) (xy 273.349974 -45.357288) (xy 273.349974 -45.458888)
			(xy 273.540474 -45.471588) (xy 273.591274 -45.471588)
		)
		(stroke
			(width 0)
			(type solid)
		)
		(fill yes)
		(layer "F.Cu")
		(net "M_A_DQS_DN<13>")
	)
	(gr_poly
		(pts
			(xy 273.591274 -44.684188) (xy 273.540474 -44.684188) (xy 273.349974 -44.696888) (xy 273.349974 -44.798488)
			(xy 273.540474 -44.811188) (xy 273.591274 -44.811188)
		)
		(stroke
			(width 0)
			(type solid)
		)
		(fill yes)
		(layer "F.Cu")
		(net "M_A_DQS_DN<13>")
	)
	(gr_poly
		(pts
			(xy 273.591274 -44.023788) (xy 273.540474 -44.023788) (xy 273.349974 -44.036488) (xy 273.349974 -44.138088)
			(xy 273.540474 -44.150788) (xy 273.591274 -44.150788)
		)
		(stroke
			(width 0)
			(type solid)
		)
		(fill yes)
		(layer "F.Cu")
		(net "M_A_DQS_DN<13>")
	)
	(gr_poly
		(pts
			(xy 273.591274 -43.363388) (xy 273.540474 -43.363388) (xy 273.349974 -43.376088) (xy 273.349974 -43.477688)
			(xy 273.540474 -43.490388) (xy 273.591274 -43.490388)
		)
		(stroke
			(width 0)
			(type solid)
		)
		(fill yes)
		(layer "F.Cu")
		(net "M_A_DQS_DN<13>")
	)
	(gr_poly
		(pts
			(xy 273.591274 -42.702988) (xy 273.540474 -42.702988) (xy 273.349974 -42.715688) (xy 273.349974 -42.817288)
			(xy 273.540474 -42.829988) (xy 273.591274 -42.829988)
		)
		(stroke
			(width 0)
			(type solid)
		)
		(fill yes)
		(layer "F.Cu")
		(net "M_A_DQS_DN<13>")
	)
	(gr_poly
		(pts
			(xy 273.591274 -42.042588) (xy 273.540474 -42.042588) (xy 273.349974 -42.055288) (xy 273.349974 -42.156888)
			(xy 273.540474 -42.169588) (xy 273.591274 -42.169588)
		)
		(stroke
			(width 0)
			(type solid)
		)
		(fill yes)
		(layer "F.Cu")
		(net "M_A_DQS_DN<13>")
	)
	(gr_poly
		(pts
			(xy 273.638772 -100.369624) (xy 273.616674 -100.33127) (xy 273.454622 -100.2284) (xy 273.26336 -100.338636)
			(xy 273.271488 -100.530406) (xy 273.293586 -100.569268)
		)
		(stroke
			(width 0)
			(type solid)
		)
		(fill yes)
		(layer "F.Cu")
		(net "M_D_DQ<36>")
	)
	(gr_poly
		(pts
			(xy 273.714464 -106.266742) (xy 273.714464 -106.038142) (xy 273.521424 -105.949242) (xy 273.476974 -105.949242)
			(xy 273.476974 -106.355642) (xy 273.521424 -106.355642)
		)
		(stroke
			(width 0)
			(type solid)
		)
		(fill yes)
		(layer "F.Cu")
		(net "M_D_DQ<33>")
	)
	(gr_poly
		(pts
			(xy 273.714464 -105.377742) (xy 273.714464 -105.149142) (xy 273.521424 -105.060242) (xy 273.476974 -105.060242)
			(xy 273.476974 -105.466642) (xy 273.521424 -105.466642)
		)
		(stroke
			(width 0)
			(type solid)
		)
		(fill yes)
		(layer "F.Cu")
		(net "M_D_DQ<33>")
	)
	(gr_poly
		(pts
			(xy 273.716242 -102.567232) (xy 273.716242 -102.346252) (xy 273.546062 -102.257352) (xy 273.501612 -102.257352)
			(xy 273.501612 -102.656132) (xy 273.546062 -102.656132)
		)
		(stroke
			(width 0)
			(type solid)
		)
		(fill yes)
		(layer "F.Cu")
		(net "M_D_DQ<37>")
	)
	(gr_poly
		(pts
			(xy 273.819874 -111.349536) (xy 273.819874 -111.247936) (xy 273.629374 -111.235236) (xy 273.578574 -111.235236)
			(xy 273.578574 -111.362236) (xy 273.629374 -111.362236)
		)
		(stroke
			(width 0)
			(type solid)
		)
		(fill yes)
		(layer "F.Cu")
		(net "M_D_DQ<33>")
	)
	(gr_poly
		(pts
			(xy 273.819874 -110.689136) (xy 273.819874 -110.587536) (xy 273.629374 -110.574836) (xy 273.578574 -110.574836)
			(xy 273.578574 -110.701836) (xy 273.629374 -110.701836)
		)
		(stroke
			(width 0)
			(type solid)
		)
		(fill yes)
		(layer "F.Cu")
		(net "M_D_DQ<33>")
	)
	(gr_poly
		(pts
			(xy 273.819874 -110.028736) (xy 273.819874 -109.927136) (xy 273.629374 -109.914436) (xy 273.578574 -109.914436)
			(xy 273.578574 -110.041436) (xy 273.629374 -110.041436)
		)
		(stroke
			(width 0)
			(type solid)
		)
		(fill yes)
		(layer "F.Cu")
		(net "M_D_DQ<33>")
	)
	(gr_poly
		(pts
			(xy 273.819874 -109.368336) (xy 273.819874 -109.266736) (xy 273.629374 -109.254036) (xy 273.578574 -109.254036)
			(xy 273.578574 -109.381036) (xy 273.629374 -109.381036)
		)
		(stroke
			(width 0)
			(type solid)
		)
		(fill yes)
		(layer "F.Cu")
		(net "M_D_DQ<33>")
	)
	(gr_poly
		(pts
			(xy 273.819874 -108.707936) (xy 273.819874 -108.606336) (xy 273.629374 -108.593636) (xy 273.578574 -108.593636)
			(xy 273.578574 -108.720636) (xy 273.629374 -108.720636)
		)
		(stroke
			(width 0)
			(type solid)
		)
		(fill yes)
		(layer "F.Cu")
		(net "M_D_DQ<33>")
	)
	(gr_poly
		(pts
			(xy 273.819874 -108.047536) (xy 273.819874 -107.945936) (xy 273.629374 -107.933236) (xy 273.578574 -107.933236)
			(xy 273.578574 -108.060236) (xy 273.629374 -108.060236)
		)
		(stroke
			(width 0)
			(type solid)
		)
		(fill yes)
		(layer "F.Cu")
		(net "M_D_DQ<33>")
	)
	(gr_poly
		(pts
			(xy 273.819874 -107.387136) (xy 273.819874 -107.285536) (xy 273.629374 -107.272836) (xy 273.578574 -107.272836)
			(xy 273.578574 -107.399836) (xy 273.629374 -107.399836)
		)
		(stroke
			(width 0)
			(type solid)
		)
		(fill yes)
		(layer "F.Cu")
		(net "M_D_DQ<33>")
	)
	(gr_poly
		(pts
			(xy 273.832574 -49.091088) (xy 273.832574 -48.989488) (xy 273.642074 -48.976788) (xy 273.591274 -48.976788)
			(xy 273.591274 -49.103788) (xy 273.642074 -49.103788)
		)
		(stroke
			(width 0)
			(type solid)
		)
		(fill yes)
		(layer "F.Cu")
		(net "M_A_DQS_DN<13>")
	)
	(gr_poly
		(pts
			(xy 273.832574 -48.430688) (xy 273.832574 -48.329088) (xy 273.642074 -48.316388) (xy 273.591274 -48.316388)
			(xy 273.591274 -48.443388) (xy 273.642074 -48.443388)
		)
		(stroke
			(width 0)
			(type solid)
		)
		(fill yes)
		(layer "F.Cu")
		(net "M_A_DQS_DN<13>")
	)
	(gr_poly
		(pts
			(xy 273.832574 -47.770288) (xy 273.832574 -47.668688) (xy 273.642074 -47.655988) (xy 273.591274 -47.655988)
			(xy 273.591274 -47.782988) (xy 273.642074 -47.782988)
		)
		(stroke
			(width 0)
			(type solid)
		)
		(fill yes)
		(layer "F.Cu")
		(net "M_A_DQS_DN<13>")
	)
	(gr_poly
		(pts
			(xy 273.832574 -47.109888) (xy 273.832574 -47.008288) (xy 273.642074 -46.995588) (xy 273.591274 -46.995588)
			(xy 273.591274 -47.122588) (xy 273.642074 -47.122588)
		)
		(stroke
			(width 0)
			(type solid)
		)
		(fill yes)
		(layer "F.Cu")
		(net "M_A_DQS_DN<13>")
	)
	(gr_poly
		(pts
			(xy 273.832574 -46.449488) (xy 273.832574 -46.347888) (xy 273.642074 -46.335188) (xy 273.591274 -46.335188)
			(xy 273.591274 -46.462188) (xy 273.642074 -46.462188)
		)
		(stroke
			(width 0)
			(type solid)
		)
		(fill yes)
		(layer "F.Cu")
		(net "M_A_DQS_DN<13>")
	)
	(gr_poly
		(pts
			(xy 273.832574 -45.789088) (xy 273.832574 -45.687488) (xy 273.642074 -45.674788) (xy 273.591274 -45.674788)
			(xy 273.591274 -45.801788) (xy 273.642074 -45.801788)
		)
		(stroke
			(width 0)
			(type solid)
		)
		(fill yes)
		(layer "F.Cu")
		(net "M_A_DQS_DN<13>")
	)
	(gr_poly
		(pts
			(xy 273.832574 -45.128688) (xy 273.832574 -45.027088) (xy 273.642074 -45.014388) (xy 273.591274 -45.014388)
			(xy 273.591274 -45.141388) (xy 273.642074 -45.141388)
		)
		(stroke
			(width 0)
			(type solid)
		)
		(fill yes)
		(layer "F.Cu")
		(net "M_A_DQS_DN<13>")
	)
	(gr_poly
		(pts
			(xy 273.832574 -44.468288) (xy 273.832574 -44.366688) (xy 273.642074 -44.353988) (xy 273.591274 -44.353988)
			(xy 273.591274 -44.480988) (xy 273.642074 -44.480988)
		)
		(stroke
			(width 0)
			(type solid)
		)
		(fill yes)
		(layer "F.Cu")
		(net "M_A_DQS_DN<13>")
	)
	(gr_poly
		(pts
			(xy 273.832574 -43.807888) (xy 273.832574 -43.706288) (xy 273.642074 -43.693588) (xy 273.591274 -43.693588)
			(xy 273.591274 -43.820588) (xy 273.642074 -43.820588)
		)
		(stroke
			(width 0)
			(type solid)
		)
		(fill yes)
		(layer "F.Cu")
		(net "M_A_DQS_DN<13>")
	)
	(gr_poly
		(pts
			(xy 273.832574 -43.147488) (xy 273.832574 -43.045888) (xy 273.642074 -43.033188) (xy 273.591274 -43.033188)
			(xy 273.591274 -43.160188) (xy 273.642074 -43.160188)
		)
		(stroke
			(width 0)
			(type solid)
		)
		(fill yes)
		(layer "F.Cu")
		(net "M_A_DQS_DN<13>")
	)
	(gr_poly
		(pts
			(xy 273.832574 -42.487088) (xy 273.832574 -42.385488) (xy 273.642074 -42.372788) (xy 273.591274 -42.372788)
			(xy 273.591274 -42.499788) (xy 273.642074 -42.499788)
		)
		(stroke
			(width 0)
			(type solid)
		)
		(fill yes)
		(layer "F.Cu")
		(net "M_A_DQS_DN<13>")
	)
	(gr_poly
		(pts
			(xy 273.87804 -104.21747) (xy 273.846544 -104.186228) (xy 273.647154 -104.112568) (xy 273.48561 -104.274112)
			(xy 273.55927 -104.473502) (xy 273.590512 -104.504998)
		)
		(stroke
			(width 0)
			(type solid)
		)
		(fill yes)
		(layer "F.Cu")
		(net "M_D_DQ<32>")
	)
	(gr_poly
		(pts
			(xy 273.972274 -111.565436) (xy 273.921474 -111.565436) (xy 273.730974 -111.578136) (xy 273.730974 -111.679736)
			(xy 273.921474 -111.692436) (xy 273.972274 -111.692436)
		)
		(stroke
			(width 0)
			(type solid)
		)
		(fill yes)
		(layer "F.Cu")
		(net "M_D_DQS_DP<13>")
	)
	(gr_poly
		(pts
			(xy 273.972274 -110.905036) (xy 273.921474 -110.905036) (xy 273.730974 -110.917736) (xy 273.730974 -111.019336)
			(xy 273.921474 -111.032036) (xy 273.972274 -111.032036)
		)
		(stroke
			(width 0)
			(type solid)
		)
		(fill yes)
		(layer "F.Cu")
		(net "M_D_DQS_DP<13>")
	)
	(gr_poly
		(pts
			(xy 273.972274 -110.244636) (xy 273.921474 -110.244636) (xy 273.730974 -110.257336) (xy 273.730974 -110.358936)
			(xy 273.921474 -110.371636) (xy 273.972274 -110.371636)
		)
		(stroke
			(width 0)
			(type solid)
		)
		(fill yes)
		(layer "F.Cu")
		(net "M_D_DQS_DP<13>")
	)
	(gr_poly
		(pts
			(xy 273.972274 -109.584236) (xy 273.921474 -109.584236) (xy 273.730974 -109.596936) (xy 273.730974 -109.698536)
			(xy 273.921474 -109.711236) (xy 273.972274 -109.711236)
		)
		(stroke
			(width 0)
			(type solid)
		)
		(fill yes)
		(layer "F.Cu")
		(net "M_D_DQS_DP<13>")
	)
	(gr_poly
		(pts
			(xy 273.972274 -108.923836) (xy 273.921474 -108.923836) (xy 273.730974 -108.936536) (xy 273.730974 -109.038136)
			(xy 273.921474 -109.050836) (xy 273.972274 -109.050836)
		)
		(stroke
			(width 0)
			(type solid)
		)
		(fill yes)
		(layer "F.Cu")
		(net "M_D_DQS_DP<13>")
	)
	(gr_poly
		(pts
			(xy 273.972274 -108.263436) (xy 273.921474 -108.263436) (xy 273.730974 -108.276136) (xy 273.730974 -108.377736)
			(xy 273.921474 -108.390436) (xy 273.972274 -108.390436)
		)
		(stroke
			(width 0)
			(type solid)
		)
		(fill yes)
		(layer "F.Cu")
		(net "M_D_DQS_DP<13>")
	)
	(gr_poly
		(pts
			(xy 273.972274 -107.603036) (xy 273.921474 -107.603036) (xy 273.730974 -107.615736) (xy 273.730974 -107.717336)
			(xy 273.921474 -107.730036) (xy 273.972274 -107.730036)
		)
		(stroke
			(width 0)
			(type solid)
		)
		(fill yes)
		(layer "F.Cu")
		(net "M_D_DQS_DP<13>")
	)
	(gr_poly
		(pts
			(xy 273.972274 -106.942636) (xy 273.921474 -106.942636) (xy 273.730974 -106.955336) (xy 273.730974 -107.056936)
			(xy 273.921474 -107.069636) (xy 273.972274 -107.069636)
		)
		(stroke
			(width 0)
			(type solid)
		)
		(fill yes)
		(layer "F.Cu")
		(net "M_D_DQS_DP<13>")
	)
	(gr_poly
		(pts
			(xy 273.984974 -49.306988) (xy 273.934174 -49.306988) (xy 273.743674 -49.319688) (xy 273.743674 -49.421288)
			(xy 273.934174 -49.433988) (xy 273.984974 -49.433988)
		)
		(stroke
			(width 0)
			(type solid)
		)
		(fill yes)
		(layer "F.Cu")
		(net "M_A_DQS_DN<4>")
	)
	(gr_poly
		(pts
			(xy 273.984974 -48.646588) (xy 273.934174 -48.646588) (xy 273.743674 -48.659288) (xy 273.743674 -48.760888)
			(xy 273.934174 -48.773588) (xy 273.984974 -48.773588)
		)
		(stroke
			(width 0)
			(type solid)
		)
		(fill yes)
		(layer "F.Cu")
		(net "M_A_DQS_DN<4>")
	)
	(gr_poly
		(pts
			(xy 273.984974 -47.986188) (xy 273.934174 -47.986188) (xy 273.743674 -47.998888) (xy 273.743674 -48.100488)
			(xy 273.934174 -48.113188) (xy 273.984974 -48.113188)
		)
		(stroke
			(width 0)
			(type solid)
		)
		(fill yes)
		(layer "F.Cu")
		(net "M_A_DQS_DN<4>")
	)
	(gr_poly
		(pts
			(xy 273.984974 -47.325788) (xy 273.934174 -47.325788) (xy 273.743674 -47.338488) (xy 273.743674 -47.440088)
			(xy 273.934174 -47.452788) (xy 273.984974 -47.452788)
		)
		(stroke
			(width 0)
			(type solid)
		)
		(fill yes)
		(layer "F.Cu")
		(net "M_A_DQS_DN<4>")
	)
	(gr_poly
		(pts
			(xy 273.984974 -46.665388) (xy 273.934174 -46.665388) (xy 273.743674 -46.678088) (xy 273.743674 -46.779688)
			(xy 273.934174 -46.792388) (xy 273.984974 -46.792388)
		)
		(stroke
			(width 0)
			(type solid)
		)
		(fill yes)
		(layer "F.Cu")
		(net "M_A_DQS_DN<4>")
	)
	(gr_poly
		(pts
			(xy 273.984974 -46.004988) (xy 273.934174 -46.004988) (xy 273.743674 -46.017688) (xy 273.743674 -46.119288)
			(xy 273.934174 -46.131988) (xy 273.984974 -46.131988)
		)
		(stroke
			(width 0)
			(type solid)
		)
		(fill yes)
		(layer "F.Cu")
		(net "M_A_DQS_DN<4>")
	)
	(gr_poly
		(pts
			(xy 273.984974 -45.344588) (xy 273.934174 -45.344588) (xy 273.743674 -45.357288) (xy 273.743674 -45.458888)
			(xy 273.934174 -45.471588) (xy 273.984974 -45.471588)
		)
		(stroke
			(width 0)
			(type solid)
		)
		(fill yes)
		(layer "F.Cu")
		(net "M_A_DQS_DN<4>")
	)
	(gr_poly
		(pts
			(xy 273.984974 -44.684188) (xy 273.934174 -44.684188) (xy 273.743674 -44.696888) (xy 273.743674 -44.798488)
			(xy 273.934174 -44.811188) (xy 273.984974 -44.811188)
		)
		(stroke
			(width 0)
			(type solid)
		)
		(fill yes)
		(layer "F.Cu")
		(net "M_A_DQS_DN<4>")
	)
	(gr_poly
		(pts
			(xy 273.984974 -44.023788) (xy 273.934174 -44.023788) (xy 273.743674 -44.036488) (xy 273.743674 -44.138088)
			(xy 273.934174 -44.150788) (xy 273.984974 -44.150788)
		)
		(stroke
			(width 0)
			(type solid)
		)
		(fill yes)
		(layer "F.Cu")
		(net "M_A_DQS_DN<4>")
	)
	(gr_poly
		(pts
			(xy 273.984974 -43.363388) (xy 273.934174 -43.363388) (xy 273.743674 -43.376088) (xy 273.743674 -43.477688)
			(xy 273.934174 -43.490388) (xy 273.984974 -43.490388)
		)
		(stroke
			(width 0)
			(type solid)
		)
		(fill yes)
		(layer "F.Cu")
		(net "M_A_DQS_DN<4>")
	)
	(gr_poly
		(pts
			(xy 273.984974 -42.702988) (xy 273.934174 -42.702988) (xy 273.743674 -42.715688) (xy 273.743674 -42.817288)
			(xy 273.934174 -42.829988) (xy 273.984974 -42.829988)
		)
		(stroke
			(width 0)
			(type solid)
		)
		(fill yes)
		(layer "F.Cu")
		(net "M_A_DQS_DN<4>")
	)
	(gr_poly
		(pts
			(xy 273.984974 -42.042588) (xy 273.934174 -42.042588) (xy 273.743674 -42.055288) (xy 273.743674 -42.156888)
			(xy 273.934174 -42.169588) (xy 273.984974 -42.169588)
		)
		(stroke
			(width 0)
			(type solid)
		)
		(fill yes)
		(layer "F.Cu")
		(net "M_A_DQS_DN<4>")
	)
	(gr_poly
		(pts
			(xy 274.073874 -105.64622) (xy 274.029424 -105.64622) (xy 273.836384 -105.73512) (xy 273.836384 -105.96372)
			(xy 274.029424 -106.05262) (xy 274.073874 -106.05262)
		)
		(stroke
			(width 0)
			(type solid)
		)
		(fill yes)
		(layer "F.Cu")
		(net "M_D_DQS_DP<13>")
	)
	(gr_poly
		(pts
			(xy 274.117816 -104.58323) (xy 274.044156 -104.38384) (xy 274.012914 -104.352344) (xy 273.725386 -104.639872)
			(xy 273.756882 -104.671114) (xy 273.956272 -104.744774)
		)
		(stroke
			(width 0)
			(type solid)
		)
		(fill yes)
		(layer "F.Cu")
		(net "M_D_DQ<33>")
	)
	(gr_poly
		(pts
			(xy 274.182078 -102.33533) (xy 274.137628 -102.33533) (xy 273.944588 -102.42423) (xy 273.944588 -102.65283)
			(xy 274.137628 -102.74173) (xy 274.182078 -102.74173)
		)
		(stroke
			(width 0)
			(type solid)
		)
		(fill yes)
		(layer "F.Cu")
		(net "M_D_DQ<32>")
	)
	(gr_poly
		(pts
			(xy 274.213574 -111.349536) (xy 274.213574 -111.247936) (xy 274.023074 -111.235236) (xy 273.972274 -111.235236)
			(xy 273.972274 -111.362236) (xy 274.023074 -111.362236)
		)
		(stroke
			(width 0)
			(type solid)
		)
		(fill yes)
		(layer "F.Cu")
		(net "M_D_DQS_DP<13>")
	)
	(gr_poly
		(pts
			(xy 274.213574 -110.689136) (xy 274.213574 -110.587536) (xy 274.023074 -110.574836) (xy 273.972274 -110.574836)
			(xy 273.972274 -110.701836) (xy 274.023074 -110.701836)
		)
		(stroke
			(width 0)
			(type solid)
		)
		(fill yes)
		(layer "F.Cu")
		(net "M_D_DQS_DP<13>")
	)
	(gr_poly
		(pts
			(xy 274.213574 -110.028736) (xy 274.213574 -109.927136) (xy 274.023074 -109.914436) (xy 273.972274 -109.914436)
			(xy 273.972274 -110.041436) (xy 274.023074 -110.041436)
		)
		(stroke
			(width 0)
			(type solid)
		)
		(fill yes)
		(layer "F.Cu")
		(net "M_D_DQS_DP<13>")
	)
	(gr_poly
		(pts
			(xy 274.213574 -109.368336) (xy 274.213574 -109.266736) (xy 274.023074 -109.254036) (xy 273.972274 -109.254036)
			(xy 273.972274 -109.381036) (xy 274.023074 -109.381036)
		)
		(stroke
			(width 0)
			(type solid)
		)
		(fill yes)
		(layer "F.Cu")
		(net "M_D_DQS_DP<13>")
	)
	(gr_poly
		(pts
			(xy 274.213574 -108.707936) (xy 274.213574 -108.606336) (xy 274.023074 -108.593636) (xy 273.972274 -108.593636)
			(xy 273.972274 -108.720636) (xy 274.023074 -108.720636)
		)
		(stroke
			(width 0)
			(type solid)
		)
		(fill yes)
		(layer "F.Cu")
		(net "M_D_DQS_DP<13>")
	)
	(gr_poly
		(pts
			(xy 274.213574 -108.047536) (xy 274.213574 -107.945936) (xy 274.023074 -107.933236) (xy 273.972274 -107.933236)
			(xy 273.972274 -108.060236) (xy 274.023074 -108.060236)
		)
		(stroke
			(width 0)
			(type solid)
		)
		(fill yes)
		(layer "F.Cu")
		(net "M_D_DQS_DP<13>")
	)
	(gr_poly
		(pts
			(xy 274.213574 -107.387136) (xy 274.213574 -107.285536) (xy 274.023074 -107.272836) (xy 273.972274 -107.272836)
			(xy 273.972274 -107.399836) (xy 274.023074 -107.399836)
		)
		(stroke
			(width 0)
			(type solid)
		)
		(fill yes)
		(layer "F.Cu")
		(net "M_D_DQS_DP<13>")
	)
	(gr_poly
		(pts
			(xy 274.226274 -49.091088) (xy 274.226274 -48.989488) (xy 274.035774 -48.976788) (xy 273.984974 -48.976788)
			(xy 273.984974 -49.103788) (xy 274.035774 -49.103788)
		)
		(stroke
			(width 0)
			(type solid)
		)
		(fill yes)
		(layer "F.Cu")
		(net "M_A_DQS_DN<4>")
	)
	(gr_poly
		(pts
			(xy 274.226274 -48.430688) (xy 274.226274 -48.329088) (xy 274.035774 -48.316388) (xy 273.984974 -48.316388)
			(xy 273.984974 -48.443388) (xy 274.035774 -48.443388)
		)
		(stroke
			(width 0)
			(type solid)
		)
		(fill yes)
		(layer "F.Cu")
		(net "M_A_DQS_DN<4>")
	)
	(gr_poly
		(pts
			(xy 274.226274 -47.770288) (xy 274.226274 -47.668688) (xy 274.035774 -47.655988) (xy 273.984974 -47.655988)
			(xy 273.984974 -47.782988) (xy 274.035774 -47.782988)
		)
		(stroke
			(width 0)
			(type solid)
		)
		(fill yes)
		(layer "F.Cu")
		(net "M_A_DQS_DN<4>")
	)
	(gr_poly
		(pts
			(xy 274.226274 -47.109888) (xy 274.226274 -47.008288) (xy 274.035774 -46.995588) (xy 273.984974 -46.995588)
			(xy 273.984974 -47.122588) (xy 274.035774 -47.122588)
		)
		(stroke
			(width 0)
			(type solid)
		)
		(fill yes)
		(layer "F.Cu")
		(net "M_A_DQS_DN<4>")
	)
	(gr_poly
		(pts
			(xy 274.226274 -46.449488) (xy 274.226274 -46.347888) (xy 274.035774 -46.335188) (xy 273.984974 -46.335188)
			(xy 273.984974 -46.462188) (xy 274.035774 -46.462188)
		)
		(stroke
			(width 0)
			(type solid)
		)
		(fill yes)
		(layer "F.Cu")
		(net "M_A_DQS_DN<4>")
	)
	(gr_poly
		(pts
			(xy 274.226274 -45.789088) (xy 274.226274 -45.687488) (xy 274.035774 -45.674788) (xy 273.984974 -45.674788)
			(xy 273.984974 -45.801788) (xy 274.035774 -45.801788)
		)
		(stroke
			(width 0)
			(type solid)
		)
		(fill yes)
		(layer "F.Cu")
		(net "M_A_DQS_DN<4>")
	)
	(gr_poly
		(pts
			(xy 274.226274 -45.128688) (xy 274.226274 -45.027088) (xy 274.035774 -45.014388) (xy 273.984974 -45.014388)
			(xy 273.984974 -45.141388) (xy 274.035774 -45.141388)
		)
		(stroke
			(width 0)
			(type solid)
		)
		(fill yes)
		(layer "F.Cu")
		(net "M_A_DQS_DN<4>")
	)
	(gr_poly
		(pts
			(xy 274.226274 -44.468288) (xy 274.226274 -44.366688) (xy 274.035774 -44.353988) (xy 273.984974 -44.353988)
			(xy 273.984974 -44.480988) (xy 274.035774 -44.480988)
		)
		(stroke
			(width 0)
			(type solid)
		)
		(fill yes)
		(layer "F.Cu")
		(net "M_A_DQS_DN<4>")
	)
	(gr_poly
		(pts
			(xy 274.226274 -43.807888) (xy 274.226274 -43.706288) (xy 274.035774 -43.693588) (xy 273.984974 -43.693588)
			(xy 273.984974 -43.820588) (xy 274.035774 -43.820588)
		)
		(stroke
			(width 0)
			(type solid)
		)
		(fill yes)
		(layer "F.Cu")
		(net "M_A_DQS_DN<4>")
	)
	(gr_poly
		(pts
			(xy 274.226274 -43.147488) (xy 274.226274 -43.045888) (xy 274.035774 -43.033188) (xy 273.984974 -43.033188)
			(xy 273.984974 -43.160188) (xy 274.035774 -43.160188)
		)
		(stroke
			(width 0)
			(type solid)
		)
		(fill yes)
		(layer "F.Cu")
		(net "M_A_DQS_DN<4>")
	)
	(gr_poly
		(pts
			(xy 274.226274 -42.487088) (xy 274.226274 -42.385488) (xy 274.035774 -42.372788) (xy 273.984974 -42.372788)
			(xy 273.984974 -42.499788) (xy 274.035774 -42.499788)
		)
		(stroke
			(width 0)
			(type solid)
		)
		(fill yes)
		(layer "F.Cu")
		(net "M_A_DQS_DN<4>")
	)
	(gr_poly
		(pts
			(xy 274.365974 -111.565436) (xy 274.315174 -111.565436) (xy 274.124674 -111.578136) (xy 274.124674 -111.679736)
			(xy 274.315174 -111.692436) (xy 274.365974 -111.692436)
		)
		(stroke
			(width 0)
			(type solid)
		)
		(fill yes)
		(layer "F.Cu")
		(net "M_D_DQS_DN<13>")
	)
	(gr_poly
		(pts
			(xy 274.365974 -110.905036) (xy 274.315174 -110.905036) (xy 274.124674 -110.917736) (xy 274.124674 -111.019336)
			(xy 274.315174 -111.032036) (xy 274.365974 -111.032036)
		)
		(stroke
			(width 0)
			(type solid)
		)
		(fill yes)
		(layer "F.Cu")
		(net "M_D_DQS_DN<13>")
	)
	(gr_poly
		(pts
			(xy 274.365974 -110.244636) (xy 274.315174 -110.244636) (xy 274.124674 -110.257336) (xy 274.124674 -110.358936)
			(xy 274.315174 -110.371636) (xy 274.365974 -110.371636)
		)
		(stroke
			(width 0)
			(type solid)
		)
		(fill yes)
		(layer "F.Cu")
		(net "M_D_DQS_DN<13>")
	)
	(gr_poly
		(pts
			(xy 274.365974 -109.584236) (xy 274.315174 -109.584236) (xy 274.124674 -109.596936) (xy 274.124674 -109.698536)
			(xy 274.315174 -109.711236) (xy 274.365974 -109.711236)
		)
		(stroke
			(width 0)
			(type solid)
		)
		(fill yes)
		(layer "F.Cu")
		(net "M_D_DQS_DN<13>")
	)
	(gr_poly
		(pts
			(xy 274.365974 -108.923836) (xy 274.315174 -108.923836) (xy 274.124674 -108.936536) (xy 274.124674 -109.038136)
			(xy 274.315174 -109.050836) (xy 274.365974 -109.050836)
		)
		(stroke
			(width 0)
			(type solid)
		)
		(fill yes)
		(layer "F.Cu")
		(net "M_D_DQS_DN<13>")
	)
	(gr_poly
		(pts
			(xy 274.365974 -108.263436) (xy 274.315174 -108.263436) (xy 274.124674 -108.276136) (xy 274.124674 -108.377736)
			(xy 274.315174 -108.390436) (xy 274.365974 -108.390436)
		)
		(stroke
			(width 0)
			(type solid)
		)
		(fill yes)
		(layer "F.Cu")
		(net "M_D_DQS_DN<13>")
	)
	(gr_poly
		(pts
			(xy 274.365974 -107.603036) (xy 274.315174 -107.603036) (xy 274.124674 -107.615736) (xy 274.124674 -107.717336)
			(xy 274.315174 -107.730036) (xy 274.365974 -107.730036)
		)
		(stroke
			(width 0)
			(type solid)
		)
		(fill yes)
		(layer "F.Cu")
		(net "M_D_DQS_DN<13>")
	)
	(gr_poly
		(pts
			(xy 274.365974 -106.942636) (xy 274.315174 -106.942636) (xy 274.124674 -106.955336) (xy 274.124674 -107.056936)
			(xy 274.315174 -107.069636) (xy 274.365974 -107.069636)
		)
		(stroke
			(width 0)
			(type solid)
		)
		(fill yes)
		(layer "F.Cu")
		(net "M_D_DQS_DN<13>")
	)
	(gr_poly
		(pts
			(xy 274.378674 -49.306988) (xy 274.327874 -49.306988) (xy 274.137374 -49.319688) (xy 274.137374 -49.421288)
			(xy 274.327874 -49.433988) (xy 274.378674 -49.433988)
		)
		(stroke
			(width 0)
			(type solid)
		)
		(fill yes)
		(layer "F.Cu")
		(net "M_A_DQS_DP<4>")
	)
	(gr_poly
		(pts
			(xy 274.378674 -48.646588) (xy 274.327874 -48.646588) (xy 274.137374 -48.659288) (xy 274.137374 -48.760888)
			(xy 274.327874 -48.773588) (xy 274.378674 -48.773588)
		)
		(stroke
			(width 0)
			(type solid)
		)
		(fill yes)
		(layer "F.Cu")
		(net "M_A_DQS_DP<4>")
	)
	(gr_poly
		(pts
			(xy 274.378674 -47.986188) (xy 274.327874 -47.986188) (xy 274.137374 -47.998888) (xy 274.137374 -48.100488)
			(xy 274.327874 -48.113188) (xy 274.378674 -48.113188)
		)
		(stroke
			(width 0)
			(type solid)
		)
		(fill yes)
		(layer "F.Cu")
		(net "M_A_DQS_DP<4>")
	)
	(gr_poly
		(pts
			(xy 274.378674 -47.325788) (xy 274.327874 -47.325788) (xy 274.137374 -47.338488) (xy 274.137374 -47.440088)
			(xy 274.327874 -47.452788) (xy 274.378674 -47.452788)
		)
		(stroke
			(width 0)
			(type solid)
		)
		(fill yes)
		(layer "F.Cu")
		(net "M_A_DQS_DP<4>")
	)
	(gr_poly
		(pts
			(xy 274.378674 -46.665388) (xy 274.327874 -46.665388) (xy 274.137374 -46.678088) (xy 274.137374 -46.779688)
			(xy 274.327874 -46.792388) (xy 274.378674 -46.792388)
		)
		(stroke
			(width 0)
			(type solid)
		)
		(fill yes)
		(layer "F.Cu")
		(net "M_A_DQS_DP<4>")
	)
	(gr_poly
		(pts
			(xy 274.378674 -46.004988) (xy 274.327874 -46.004988) (xy 274.137374 -46.017688) (xy 274.137374 -46.119288)
			(xy 274.327874 -46.131988) (xy 274.378674 -46.131988)
		)
		(stroke
			(width 0)
			(type solid)
		)
		(fill yes)
		(layer "F.Cu")
		(net "M_A_DQS_DP<4>")
	)
	(gr_poly
		(pts
			(xy 274.378674 -45.344588) (xy 274.327874 -45.344588) (xy 274.137374 -45.357288) (xy 274.137374 -45.458888)
			(xy 274.327874 -45.471588) (xy 274.378674 -45.471588)
		)
		(stroke
			(width 0)
			(type solid)
		)
		(fill yes)
		(layer "F.Cu")
		(net "M_A_DQS_DP<4>")
	)
	(gr_poly
		(pts
			(xy 274.378674 -44.684188) (xy 274.327874 -44.684188) (xy 274.137374 -44.696888) (xy 274.137374 -44.798488)
			(xy 274.327874 -44.811188) (xy 274.378674 -44.811188)
		)
		(stroke
			(width 0)
			(type solid)
		)
		(fill yes)
		(layer "F.Cu")
		(net "M_A_DQS_DP<4>")
	)
	(gr_poly
		(pts
			(xy 274.378674 -44.023788) (xy 274.327874 -44.023788) (xy 274.137374 -44.036488) (xy 274.137374 -44.138088)
			(xy 274.327874 -44.150788) (xy 274.378674 -44.150788)
		)
		(stroke
			(width 0)
			(type solid)
		)
		(fill yes)
		(layer "F.Cu")
		(net "M_A_DQS_DP<4>")
	)
	(gr_poly
		(pts
			(xy 274.378674 -43.363388) (xy 274.327874 -43.363388) (xy 274.137374 -43.376088) (xy 274.137374 -43.477688)
			(xy 274.327874 -43.490388) (xy 274.378674 -43.490388)
		)
		(stroke
			(width 0)
			(type solid)
		)
		(fill yes)
		(layer "F.Cu")
		(net "M_A_DQS_DP<4>")
	)
	(gr_poly
		(pts
			(xy 274.378674 -42.702988) (xy 274.327874 -42.702988) (xy 274.137374 -42.715688) (xy 274.137374 -42.817288)
			(xy 274.327874 -42.829988) (xy 274.378674 -42.829988)
		)
		(stroke
			(width 0)
			(type solid)
		)
		(fill yes)
		(layer "F.Cu")
		(net "M_A_DQS_DP<4>")
	)
	(gr_poly
		(pts
			(xy 274.378674 -42.042588) (xy 274.327874 -42.042588) (xy 274.137374 -42.055288) (xy 274.137374 -42.156888)
			(xy 274.327874 -42.169588) (xy 274.378674 -42.169588)
		)
		(stroke
			(width 0)
			(type solid)
		)
		(fill yes)
		(layer "F.Cu")
		(net "M_A_DQS_DP<4>")
	)
	(gr_poly
		(pts
			(xy 274.501864 -105.96372) (xy 274.501864 -105.73512) (xy 274.308824 -105.64622) (xy 274.264374 -105.64622)
			(xy 274.264374 -106.05262) (xy 274.308824 -106.05262)
		)
		(stroke
			(width 0)
			(type solid)
		)
		(fill yes)
		(layer "F.Cu")
		(net "M_D_DQS_DN<13>")
	)
	(gr_poly
		(pts
			(xy 274.607274 -111.349536) (xy 274.607274 -111.247936) (xy 274.416774 -111.235236) (xy 274.365974 -111.235236)
			(xy 274.365974 -111.362236) (xy 274.416774 -111.362236)
		)
		(stroke
			(width 0)
			(type solid)
		)
		(fill yes)
		(layer "F.Cu")
		(net "M_D_DQS_DN<13>")
	)
	(gr_poly
		(pts
			(xy 274.607274 -110.689136) (xy 274.607274 -110.587536) (xy 274.416774 -110.574836) (xy 274.365974 -110.574836)
			(xy 274.365974 -110.701836) (xy 274.416774 -110.701836)
		)
		(stroke
			(width 0)
			(type solid)
		)
		(fill yes)
		(layer "F.Cu")
		(net "M_D_DQS_DN<13>")
	)
	(gr_poly
		(pts
			(xy 274.607274 -110.028736) (xy 274.607274 -109.927136) (xy 274.416774 -109.914436) (xy 274.365974 -109.914436)
			(xy 274.365974 -110.041436) (xy 274.416774 -110.041436)
		)
		(stroke
			(width 0)
			(type solid)
		)
		(fill yes)
		(layer "F.Cu")
		(net "M_D_DQS_DN<13>")
	)
	(gr_poly
		(pts
			(xy 274.607274 -109.368336) (xy 274.607274 -109.266736) (xy 274.416774 -109.254036) (xy 274.365974 -109.254036)
			(xy 274.365974 -109.381036) (xy 274.416774 -109.381036)
		)
		(stroke
			(width 0)
			(type solid)
		)
		(fill yes)
		(layer "F.Cu")
		(net "M_D_DQS_DN<13>")
	)
	(gr_poly
		(pts
			(xy 274.607274 -108.707936) (xy 274.607274 -108.606336) (xy 274.416774 -108.593636) (xy 274.365974 -108.593636)
			(xy 274.365974 -108.720636) (xy 274.416774 -108.720636)
		)
		(stroke
			(width 0)
			(type solid)
		)
		(fill yes)
		(layer "F.Cu")
		(net "M_D_DQS_DN<13>")
	)
	(gr_poly
		(pts
			(xy 274.607274 -108.047536) (xy 274.607274 -107.945936) (xy 274.416774 -107.933236) (xy 274.365974 -107.933236)
			(xy 274.365974 -108.060236) (xy 274.416774 -108.060236)
		)
		(stroke
			(width 0)
			(type solid)
		)
		(fill yes)
		(layer "F.Cu")
		(net "M_D_DQS_DN<13>")
	)
	(gr_poly
		(pts
			(xy 274.607274 -107.387136) (xy 274.607274 -107.285536) (xy 274.416774 -107.272836) (xy 274.365974 -107.272836)
			(xy 274.365974 -107.399836) (xy 274.416774 -107.399836)
		)
		(stroke
			(width 0)
			(type solid)
		)
		(fill yes)
		(layer "F.Cu")
		(net "M_D_DQS_DN<13>")
	)
	(gr_poly
		(pts
			(xy 274.610068 -103.41483) (xy 274.610068 -103.18623) (xy 274.417028 -103.09733) (xy 274.372578 -103.09733)
			(xy 274.372578 -103.50373) (xy 274.417028 -103.50373)
		)
		(stroke
			(width 0)
			(type solid)
		)
		(fill yes)
		(layer "F.Cu")
		(net "M_D_DQ<33>")
	)
	(gr_poly
		(pts
			(xy 274.619974 -49.091088) (xy 274.619974 -48.989488) (xy 274.429474 -48.976788) (xy 274.378674 -48.976788)
			(xy 274.378674 -49.103788) (xy 274.429474 -49.103788)
		)
		(stroke
			(width 0)
			(type solid)
		)
		(fill yes)
		(layer "F.Cu")
		(net "M_A_DQS_DP<4>")
	)
	(gr_poly
		(pts
			(xy 274.619974 -48.430688) (xy 274.619974 -48.329088) (xy 274.429474 -48.316388) (xy 274.378674 -48.316388)
			(xy 274.378674 -48.443388) (xy 274.429474 -48.443388)
		)
		(stroke
			(width 0)
			(type solid)
		)
		(fill yes)
		(layer "F.Cu")
		(net "M_A_DQS_DP<4>")
	)
	(gr_poly
		(pts
			(xy 274.619974 -47.770288) (xy 274.619974 -47.668688) (xy 274.429474 -47.655988) (xy 274.378674 -47.655988)
			(xy 274.378674 -47.782988) (xy 274.429474 -47.782988)
		)
		(stroke
			(width 0)
			(type solid)
		)
		(fill yes)
		(layer "F.Cu")
		(net "M_A_DQS_DP<4>")
	)
	(gr_poly
		(pts
			(xy 274.619974 -47.109888) (xy 274.619974 -47.008288) (xy 274.429474 -46.995588) (xy 274.378674 -46.995588)
			(xy 274.378674 -47.122588) (xy 274.429474 -47.122588)
		)
		(stroke
			(width 0)
			(type solid)
		)
		(fill yes)
		(layer "F.Cu")
		(net "M_A_DQS_DP<4>")
	)
	(gr_poly
		(pts
			(xy 274.619974 -46.449488) (xy 274.619974 -46.347888) (xy 274.429474 -46.335188) (xy 274.378674 -46.335188)
			(xy 274.378674 -46.462188) (xy 274.429474 -46.462188)
		)
		(stroke
			(width 0)
			(type solid)
		)
		(fill yes)
		(layer "F.Cu")
		(net "M_A_DQS_DP<4>")
	)
	(gr_poly
		(pts
			(xy 274.619974 -45.789088) (xy 274.619974 -45.687488) (xy 274.429474 -45.674788) (xy 274.378674 -45.674788)
			(xy 274.378674 -45.801788) (xy 274.429474 -45.801788)
		)
		(stroke
			(width 0)
			(type solid)
		)
		(fill yes)
		(layer "F.Cu")
		(net "M_A_DQS_DP<4>")
	)
	(gr_poly
		(pts
			(xy 274.619974 -45.128688) (xy 274.619974 -45.027088) (xy 274.429474 -45.014388) (xy 274.378674 -45.014388)
			(xy 274.378674 -45.141388) (xy 274.429474 -45.141388)
		)
		(stroke
			(width 0)
			(type solid)
		)
		(fill yes)
		(layer "F.Cu")
		(net "M_A_DQS_DP<4>")
	)
	(gr_poly
		(pts
			(xy 274.619974 -44.468288) (xy 274.619974 -44.366688) (xy 274.429474 -44.353988) (xy 274.378674 -44.353988)
			(xy 274.378674 -44.480988) (xy 274.429474 -44.480988)
		)
		(stroke
			(width 0)
			(type solid)
		)
		(fill yes)
		(layer "F.Cu")
		(net "M_A_DQS_DP<4>")
	)
	(gr_poly
		(pts
			(xy 274.619974 -43.807888) (xy 274.619974 -43.706288) (xy 274.429474 -43.693588) (xy 274.378674 -43.693588)
			(xy 274.378674 -43.820588) (xy 274.429474 -43.820588)
		)
		(stroke
			(width 0)
			(type solid)
		)
		(fill yes)
		(layer "F.Cu")
		(net "M_A_DQS_DP<4>")
	)
	(gr_poly
		(pts
			(xy 274.619974 -43.147488) (xy 274.619974 -43.045888) (xy 274.429474 -43.033188) (xy 274.378674 -43.033188)
			(xy 274.378674 -43.160188) (xy 274.429474 -43.160188)
		)
		(stroke
			(width 0)
			(type solid)
		)
		(fill yes)
		(layer "F.Cu")
		(net "M_A_DQS_DP<4>")
	)
	(gr_poly
		(pts
			(xy 274.619974 -42.487088) (xy 274.619974 -42.385488) (xy 274.429474 -42.372788) (xy 274.378674 -42.372788)
			(xy 274.378674 -42.499788) (xy 274.429474 -42.499788)
		)
		(stroke
			(width 0)
			(type solid)
		)
		(fill yes)
		(layer "F.Cu")
		(net "M_A_DQS_DP<4>")
	)
	(gr_poly
		(pts
			(xy 274.688046 -104.533446) (xy 274.65655 -104.502204) (xy 274.45716 -104.428544) (xy 274.295616 -104.590088)
			(xy 274.369276 -104.789478) (xy 274.400518 -104.820974)
		)
		(stroke
			(width 0)
			(type solid)
		)
		(fill yes)
		(layer "F.Cu")
		(net "M_D_DQS_DP<13>")
	)
	(gr_poly
		(pts
			(xy 274.759674 -111.565436) (xy 274.708874 -111.565436) (xy 274.518374 -111.578136) (xy 274.518374 -111.679736)
			(xy 274.708874 -111.692436) (xy 274.759674 -111.692436)
		)
		(stroke
			(width 0)
			(type solid)
		)
		(fill yes)
		(layer "F.Cu")
		(net "M_D_DQS_DN<4>")
	)
	(gr_poly
		(pts
			(xy 274.759674 -110.905036) (xy 274.708874 -110.905036) (xy 274.518374 -110.917736) (xy 274.518374 -111.019336)
			(xy 274.708874 -111.032036) (xy 274.759674 -111.032036)
		)
		(stroke
			(width 0)
			(type solid)
		)
		(fill yes)
		(layer "F.Cu")
		(net "M_D_DQS_DN<4>")
	)
	(gr_poly
		(pts
			(xy 274.759674 -110.244636) (xy 274.708874 -110.244636) (xy 274.518374 -110.257336) (xy 274.518374 -110.358936)
			(xy 274.708874 -110.371636) (xy 274.759674 -110.371636)
		)
		(stroke
			(width 0)
			(type solid)
		)
		(fill yes)
		(layer "F.Cu")
		(net "M_D_DQS_DN<4>")
	)
	(gr_poly
		(pts
			(xy 274.759674 -109.584236) (xy 274.708874 -109.584236) (xy 274.518374 -109.596936) (xy 274.518374 -109.698536)
			(xy 274.708874 -109.711236) (xy 274.759674 -109.711236)
		)
		(stroke
			(width 0)
			(type solid)
		)
		(fill yes)
		(layer "F.Cu")
		(net "M_D_DQS_DN<4>")
	)
	(gr_poly
		(pts
			(xy 274.759674 -108.923836) (xy 274.708874 -108.923836) (xy 274.518374 -108.936536) (xy 274.518374 -109.038136)
			(xy 274.708874 -109.050836) (xy 274.759674 -109.050836)
		)
		(stroke
			(width 0)
			(type solid)
		)
		(fill yes)
		(layer "F.Cu")
		(net "M_D_DQS_DN<4>")
	)
	(gr_poly
		(pts
			(xy 274.759674 -108.263436) (xy 274.708874 -108.263436) (xy 274.518374 -108.276136) (xy 274.518374 -108.377736)
			(xy 274.708874 -108.390436) (xy 274.759674 -108.390436)
		)
		(stroke
			(width 0)
			(type solid)
		)
		(fill yes)
		(layer "F.Cu")
		(net "M_D_DQS_DN<4>")
	)
	(gr_poly
		(pts
			(xy 274.759674 -107.603036) (xy 274.708874 -107.603036) (xy 274.518374 -107.615736) (xy 274.518374 -107.717336)
			(xy 274.708874 -107.730036) (xy 274.759674 -107.730036)
		)
		(stroke
			(width 0)
			(type solid)
		)
		(fill yes)
		(layer "F.Cu")
		(net "M_D_DQS_DN<4>")
	)
	(gr_poly
		(pts
			(xy 274.759674 -106.942636) (xy 274.708874 -106.942636) (xy 274.518374 -106.955336) (xy 274.518374 -107.056936)
			(xy 274.708874 -107.069636) (xy 274.759674 -107.069636)
		)
		(stroke
			(width 0)
			(type solid)
		)
		(fill yes)
		(layer "F.Cu")
		(net "M_D_DQS_DN<4>")
	)
	(gr_poly
		(pts
			(xy 274.772374 -49.306988) (xy 274.721574 -49.306988) (xy 274.531074 -49.319688) (xy 274.531074 -49.421288)
			(xy 274.721574 -49.433988) (xy 274.772374 -49.433988)
		)
		(stroke
			(width 0)
			(type solid)
		)
		(fill yes)
		(layer "F.Cu")
		(net "M_A_DQ<38>")
	)
	(gr_poly
		(pts
			(xy 274.772374 -48.646588) (xy 274.721574 -48.646588) (xy 274.531074 -48.659288) (xy 274.531074 -48.760888)
			(xy 274.721574 -48.773588) (xy 274.772374 -48.773588)
		)
		(stroke
			(width 0)
			(type solid)
		)
		(fill yes)
		(layer "F.Cu")
		(net "M_A_DQ<38>")
	)
	(gr_poly
		(pts
			(xy 274.772374 -47.986188) (xy 274.721574 -47.986188) (xy 274.531074 -47.998888) (xy 274.531074 -48.100488)
			(xy 274.721574 -48.113188) (xy 274.772374 -48.113188)
		)
		(stroke
			(width 0)
			(type solid)
		)
		(fill yes)
		(layer "F.Cu")
		(net "M_A_DQ<38>")
	)
	(gr_poly
		(pts
			(xy 274.772374 -47.325788) (xy 274.721574 -47.325788) (xy 274.531074 -47.338488) (xy 274.531074 -47.440088)
			(xy 274.721574 -47.452788) (xy 274.772374 -47.452788)
		)
		(stroke
			(width 0)
			(type solid)
		)
		(fill yes)
		(layer "F.Cu")
		(net "M_A_DQ<38>")
	)
	(gr_poly
		(pts
			(xy 274.772374 -46.665388) (xy 274.721574 -46.665388) (xy 274.531074 -46.678088) (xy 274.531074 -46.779688)
			(xy 274.721574 -46.792388) (xy 274.772374 -46.792388)
		)
		(stroke
			(width 0)
			(type solid)
		)
		(fill yes)
		(layer "F.Cu")
		(net "M_A_DQ<38>")
	)
	(gr_poly
		(pts
			(xy 274.772374 -46.004988) (xy 274.721574 -46.004988) (xy 274.531074 -46.017688) (xy 274.531074 -46.119288)
			(xy 274.721574 -46.131988) (xy 274.772374 -46.131988)
		)
		(stroke
			(width 0)
			(type solid)
		)
		(fill yes)
		(layer "F.Cu")
		(net "M_A_DQ<38>")
	)
	(gr_poly
		(pts
			(xy 274.772374 -45.344588) (xy 274.721574 -45.344588) (xy 274.531074 -45.357288) (xy 274.531074 -45.458888)
			(xy 274.721574 -45.471588) (xy 274.772374 -45.471588)
		)
		(stroke
			(width 0)
			(type solid)
		)
		(fill yes)
		(layer "F.Cu")
		(net "M_A_DQ<38>")
	)
	(gr_poly
		(pts
			(xy 274.772374 -44.684188) (xy 274.721574 -44.684188) (xy 274.531074 -44.696888) (xy 274.531074 -44.798488)
			(xy 274.721574 -44.811188) (xy 274.772374 -44.811188)
		)
		(stroke
			(width 0)
			(type solid)
		)
		(fill yes)
		(layer "F.Cu")
		(net "M_A_DQ<38>")
	)
	(gr_poly
		(pts
			(xy 274.772374 -44.023788) (xy 274.721574 -44.023788) (xy 274.531074 -44.036488) (xy 274.531074 -44.138088)
			(xy 274.721574 -44.150788) (xy 274.772374 -44.150788)
		)
		(stroke
			(width 0)
			(type solid)
		)
		(fill yes)
		(layer "F.Cu")
		(net "M_A_DQ<38>")
	)
	(gr_poly
		(pts
			(xy 274.772374 -43.363388) (xy 274.721574 -43.363388) (xy 274.531074 -43.376088) (xy 274.531074 -43.477688)
			(xy 274.721574 -43.490388) (xy 274.772374 -43.490388)
		)
		(stroke
			(width 0)
			(type solid)
		)
		(fill yes)
		(layer "F.Cu")
		(net "M_A_DQ<38>")
	)
	(gr_poly
		(pts
			(xy 274.772374 -42.702988) (xy 274.721574 -42.702988) (xy 274.531074 -42.715688) (xy 274.531074 -42.817288)
			(xy 274.721574 -42.829988) (xy 274.772374 -42.829988)
		)
		(stroke
			(width 0)
			(type solid)
		)
		(fill yes)
		(layer "F.Cu")
		(net "M_A_DQ<38>")
	)
	(gr_poly
		(pts
			(xy 274.772374 -42.042588) (xy 274.721574 -42.042588) (xy 274.531074 -42.055288) (xy 274.531074 -42.156888)
			(xy 274.721574 -42.169588) (xy 274.772374 -42.169588)
		)
		(stroke
			(width 0)
			(type solid)
		)
		(fill yes)
		(layer "F.Cu")
		(net "M_A_DQ<38>")
	)
	(gr_poly
		(pts
			(xy 274.861274 -105.79862) (xy 274.816824 -105.79862) (xy 274.623784 -105.88752) (xy 274.623784 -106.11612)
			(xy 274.816824 -106.20502) (xy 274.861274 -106.20502)
		)
		(stroke
			(width 0)
			(type solid)
		)
		(fill yes)
		(layer "F.Cu")
		(net "M_D_DQS_DN<4>")
	)
	(gr_poly
		(pts
			(xy 274.895056 -101.761798) (xy 274.850606 -101.761798) (xy 274.680426 -101.850698) (xy 274.680426 -102.071678)
			(xy 274.850606 -102.160578) (xy 274.895056 -102.160578)
		)
		(stroke
			(width 0)
			(type solid)
		)
		(fill yes)
		(layer "F.Cu")
		(net "M_D_DQS_DP<13>")
	)
	(gr_poly
		(pts
			(xy 274.903184 -103.459534) (xy 274.858734 -103.459534) (xy 274.665694 -103.548434) (xy 274.665694 -103.777034)
			(xy 274.858734 -103.865934) (xy 274.903184 -103.865934)
		)
		(stroke
			(width 0)
			(type solid)
		)
		(fill yes)
		(layer "F.Cu")
		(net "M_D_DQS_DP<13>")
	)
	(gr_poly
		(pts
			(xy 274.9169 -101.184202) (xy 274.882356 -100.7872) (xy 274.837906 -100.79101) (xy 274.676108 -100.894388)
			(xy 274.695412 -101.114352) (xy 274.872704 -101.188012)
		)
		(stroke
			(width 0)
			(type solid)
		)
		(fill yes)
		(layer "F.Cu")
		(net "M_D_DQS_DP<13>")
	)
	(gr_poly
		(pts
			(xy 274.927822 -104.898952) (xy 274.854162 -104.699816) (xy 274.822666 -104.66832) (xy 274.535392 -104.955594)
			(xy 274.566888 -104.98709) (xy 274.766024 -105.06075)
		)
		(stroke
			(width 0)
			(type solid)
		)
		(fill yes)
		(layer "F.Cu")
		(net "M_D_DQS_DN<13>")
	)
	(gr_poly
		(pts
			(xy 275.000974 -111.349536) (xy 275.000974 -111.247936) (xy 274.810474 -111.235236) (xy 274.759674 -111.235236)
			(xy 274.759674 -111.362236) (xy 274.810474 -111.362236)
		)
		(stroke
			(width 0)
			(type solid)
		)
		(fill yes)
		(layer "F.Cu")
		(net "M_D_DQS_DN<4>")
	)
	(gr_poly
		(pts
			(xy 275.000974 -110.689136) (xy 275.000974 -110.587536) (xy 274.810474 -110.574836) (xy 274.759674 -110.574836)
			(xy 274.759674 -110.701836) (xy 274.810474 -110.701836)
		)
		(stroke
			(width 0)
			(type solid)
		)
		(fill yes)
		(layer "F.Cu")
		(net "M_D_DQS_DN<4>")
	)
	(gr_poly
		(pts
			(xy 275.000974 -110.028736) (xy 275.000974 -109.927136) (xy 274.810474 -109.914436) (xy 274.759674 -109.914436)
			(xy 274.759674 -110.041436) (xy 274.810474 -110.041436)
		)
		(stroke
			(width 0)
			(type solid)
		)
		(fill yes)
		(layer "F.Cu")
		(net "M_D_DQS_DN<4>")
	)
	(gr_poly
		(pts
			(xy 275.000974 -109.368336) (xy 275.000974 -109.266736) (xy 274.810474 -109.254036) (xy 274.759674 -109.254036)
			(xy 274.759674 -109.381036) (xy 274.810474 -109.381036)
		)
		(stroke
			(width 0)
			(type solid)
		)
		(fill yes)
		(layer "F.Cu")
		(net "M_D_DQS_DN<4>")
	)
	(gr_poly
		(pts
			(xy 275.000974 -108.707936) (xy 275.000974 -108.606336) (xy 274.810474 -108.593636) (xy 274.759674 -108.593636)
			(xy 274.759674 -108.720636) (xy 274.810474 -108.720636)
		)
		(stroke
			(width 0)
			(type solid)
		)
		(fill yes)
		(layer "F.Cu")
		(net "M_D_DQS_DN<4>")
	)
	(gr_poly
		(pts
			(xy 275.000974 -108.047536) (xy 275.000974 -107.945936) (xy 274.810474 -107.933236) (xy 274.759674 -107.933236)
			(xy 274.759674 -108.060236) (xy 274.810474 -108.060236)
		)
		(stroke
			(width 0)
			(type solid)
		)
		(fill yes)
		(layer "F.Cu")
		(net "M_D_DQS_DN<4>")
	)
	(gr_poly
		(pts
			(xy 275.000974 -107.387136) (xy 275.000974 -107.285536) (xy 274.810474 -107.272836) (xy 274.759674 -107.272836)
			(xy 274.759674 -107.399836) (xy 274.810474 -107.399836)
		)
		(stroke
			(width 0)
			(type solid)
		)
		(fill yes)
		(layer "F.Cu")
		(net "M_D_DQS_DN<4>")
	)
	(gr_poly
		(pts
			(xy 275.013674 -49.091088) (xy 275.013674 -48.989488) (xy 274.823174 -48.976788) (xy 274.772374 -48.976788)
			(xy 274.772374 -49.103788) (xy 274.823174 -49.103788)
		)
		(stroke
			(width 0)
			(type solid)
		)
		(fill yes)
		(layer "F.Cu")
		(net "M_A_DQ<38>")
	)
	(gr_poly
		(pts
			(xy 275.013674 -48.430688) (xy 275.013674 -48.329088) (xy 274.823174 -48.316388) (xy 274.772374 -48.316388)
			(xy 274.772374 -48.443388) (xy 274.823174 -48.443388)
		)
		(stroke
			(width 0)
			(type solid)
		)
		(fill yes)
		(layer "F.Cu")
		(net "M_A_DQ<38>")
	)
	(gr_poly
		(pts
			(xy 275.013674 -47.770288) (xy 275.013674 -47.668688) (xy 274.823174 -47.655988) (xy 274.772374 -47.655988)
			(xy 274.772374 -47.782988) (xy 274.823174 -47.782988)
		)
		(stroke
			(width 0)
			(type solid)
		)
		(fill yes)
		(layer "F.Cu")
		(net "M_A_DQ<38>")
	)
	(gr_poly
		(pts
			(xy 275.013674 -47.109888) (xy 275.013674 -47.008288) (xy 274.823174 -46.995588) (xy 274.772374 -46.995588)
			(xy 274.772374 -47.122588) (xy 274.823174 -47.122588)
		)
		(stroke
			(width 0)
			(type solid)
		)
		(fill yes)
		(layer "F.Cu")
		(net "M_A_DQ<38>")
	)
	(gr_poly
		(pts
			(xy 275.013674 -46.449488) (xy 275.013674 -46.347888) (xy 274.823174 -46.335188) (xy 274.772374 -46.335188)
			(xy 274.772374 -46.462188) (xy 274.823174 -46.462188)
		)
		(stroke
			(width 0)
			(type solid)
		)
		(fill yes)
		(layer "F.Cu")
		(net "M_A_DQ<38>")
	)
	(gr_poly
		(pts
			(xy 275.013674 -45.789088) (xy 275.013674 -45.687488) (xy 274.823174 -45.674788) (xy 274.772374 -45.674788)
			(xy 274.772374 -45.801788) (xy 274.823174 -45.801788)
		)
		(stroke
			(width 0)
			(type solid)
		)
		(fill yes)
		(layer "F.Cu")
		(net "M_A_DQ<38>")
	)
	(gr_poly
		(pts
			(xy 275.013674 -45.128688) (xy 275.013674 -45.027088) (xy 274.823174 -45.014388) (xy 274.772374 -45.014388)
			(xy 274.772374 -45.141388) (xy 274.823174 -45.141388)
		)
		(stroke
			(width 0)
			(type solid)
		)
		(fill yes)
		(layer "F.Cu")
		(net "M_A_DQ<38>")
	)
	(gr_poly
		(pts
			(xy 275.013674 -44.468288) (xy 275.013674 -44.366688) (xy 274.823174 -44.353988) (xy 274.772374 -44.353988)
			(xy 274.772374 -44.480988) (xy 274.823174 -44.480988)
		)
		(stroke
			(width 0)
			(type solid)
		)
		(fill yes)
		(layer "F.Cu")
		(net "M_A_DQ<38>")
	)
	(gr_poly
		(pts
			(xy 275.013674 -43.807888) (xy 275.013674 -43.706288) (xy 274.823174 -43.693588) (xy 274.772374 -43.693588)
			(xy 274.772374 -43.820588) (xy 274.823174 -43.820588)
		)
		(stroke
			(width 0)
			(type solid)
		)
		(fill yes)
		(layer "F.Cu")
		(net "M_A_DQ<38>")
	)
	(gr_poly
		(pts
			(xy 275.013674 -43.147488) (xy 275.013674 -43.045888) (xy 274.823174 -43.033188) (xy 274.772374 -43.033188)
			(xy 274.772374 -43.160188) (xy 274.823174 -43.160188)
		)
		(stroke
			(width 0)
			(type solid)
		)
		(fill yes)
		(layer "F.Cu")
		(net "M_A_DQ<38>")
	)
	(gr_poly
		(pts
			(xy 275.013674 -42.487088) (xy 275.013674 -42.385488) (xy 274.823174 -42.372788) (xy 274.772374 -42.372788)
			(xy 274.772374 -42.499788) (xy 274.823174 -42.499788)
		)
		(stroke
			(width 0)
			(type solid)
		)
		(fill yes)
		(layer "F.Cu")
		(net "M_A_DQ<38>")
	)
	(gr_poly
		(pts
			(xy 275.153374 -111.565436) (xy 275.102574 -111.565436) (xy 274.912074 -111.578136) (xy 274.912074 -111.679736)
			(xy 275.102574 -111.692436) (xy 275.153374 -111.692436)
		)
		(stroke
			(width 0)
			(type solid)
		)
		(fill yes)
		(layer "F.Cu")
		(net "M_D_DQS_DP<4>")
	)
	(gr_poly
		(pts
			(xy 275.153374 -110.905036) (xy 275.102574 -110.905036) (xy 274.912074 -110.917736) (xy 274.912074 -111.019336)
			(xy 275.102574 -111.032036) (xy 275.153374 -111.032036)
		)
		(stroke
			(width 0)
			(type solid)
		)
		(fill yes)
		(layer "F.Cu")
		(net "M_D_DQS_DP<4>")
	)
	(gr_poly
		(pts
			(xy 275.153374 -110.244636) (xy 275.102574 -110.244636) (xy 274.912074 -110.257336) (xy 274.912074 -110.358936)
			(xy 275.102574 -110.371636) (xy 275.153374 -110.371636)
		)
		(stroke
			(width 0)
			(type solid)
		)
		(fill yes)
		(layer "F.Cu")
		(net "M_D_DQS_DP<4>")
	)
	(gr_poly
		(pts
			(xy 275.153374 -109.584236) (xy 275.102574 -109.584236) (xy 274.912074 -109.596936) (xy 274.912074 -109.698536)
			(xy 275.102574 -109.711236) (xy 275.153374 -109.711236)
		)
		(stroke
			(width 0)
			(type solid)
		)
		(fill yes)
		(layer "F.Cu")
		(net "M_D_DQS_DP<4>")
	)
	(gr_poly
		(pts
			(xy 275.153374 -108.923836) (xy 275.102574 -108.923836) (xy 274.912074 -108.936536) (xy 274.912074 -109.038136)
			(xy 275.102574 -109.050836) (xy 275.153374 -109.050836)
		)
		(stroke
			(width 0)
			(type solid)
		)
		(fill yes)
		(layer "F.Cu")
		(net "M_D_DQS_DP<4>")
	)
	(gr_poly
		(pts
			(xy 275.153374 -108.263436) (xy 275.102574 -108.263436) (xy 274.912074 -108.276136) (xy 274.912074 -108.377736)
			(xy 275.102574 -108.390436) (xy 275.153374 -108.390436)
		)
		(stroke
			(width 0)
			(type solid)
		)
		(fill yes)
		(layer "F.Cu")
		(net "M_D_DQS_DP<4>")
	)
	(gr_poly
		(pts
			(xy 275.153374 -107.603036) (xy 275.102574 -107.603036) (xy 274.912074 -107.615736) (xy 274.912074 -107.717336)
			(xy 275.102574 -107.730036) (xy 275.153374 -107.730036)
		)
		(stroke
			(width 0)
			(type solid)
		)
		(fill yes)
		(layer "F.Cu")
		(net "M_D_DQS_DP<4>")
	)
	(gr_poly
		(pts
			(xy 275.153374 -106.942636) (xy 275.102574 -106.942636) (xy 274.912074 -106.955336) (xy 274.912074 -107.056936)
			(xy 275.102574 -107.069636) (xy 275.153374 -107.069636)
		)
		(stroke
			(width 0)
			(type solid)
		)
		(fill yes)
		(layer "F.Cu")
		(net "M_D_DQS_DP<4>")
	)
	(gr_poly
		(pts
			(xy 275.166074 -49.306988) (xy 275.115274 -49.306988) (xy 274.924774 -49.319688) (xy 274.924774 -49.421288)
			(xy 275.115274 -49.433988) (xy 275.166074 -49.433988)
		)
		(stroke
			(width 0)
			(type solid)
		)
		(fill yes)
		(layer "F.Cu")
		(net "M_A_DQ<39>")
	)
	(gr_poly
		(pts
			(xy 275.166074 -48.646588) (xy 275.115274 -48.646588) (xy 274.924774 -48.659288) (xy 274.924774 -48.760888)
			(xy 275.115274 -48.773588) (xy 275.166074 -48.773588)
		)
		(stroke
			(width 0)
			(type solid)
		)
		(fill yes)
		(layer "F.Cu")
		(net "M_A_DQ<39>")
	)
	(gr_poly
		(pts
			(xy 275.166074 -47.986188) (xy 275.115274 -47.986188) (xy 274.924774 -47.998888) (xy 274.924774 -48.100488)
			(xy 275.115274 -48.113188) (xy 275.166074 -48.113188)
		)
		(stroke
			(width 0)
			(type solid)
		)
		(fill yes)
		(layer "F.Cu")
		(net "M_A_DQ<39>")
	)
	(gr_poly
		(pts
			(xy 275.166074 -47.325788) (xy 275.115274 -47.325788) (xy 274.924774 -47.338488) (xy 274.924774 -47.440088)
			(xy 275.115274 -47.452788) (xy 275.166074 -47.452788)
		)
		(stroke
			(width 0)
			(type solid)
		)
		(fill yes)
		(layer "F.Cu")
		(net "M_A_DQ<39>")
	)
	(gr_poly
		(pts
			(xy 275.166074 -46.665388) (xy 275.115274 -46.665388) (xy 274.924774 -46.678088) (xy 274.924774 -46.779688)
			(xy 275.115274 -46.792388) (xy 275.166074 -46.792388)
		)
		(stroke
			(width 0)
			(type solid)
		)
		(fill yes)
		(layer "F.Cu")
		(net "M_A_DQ<39>")
	)
	(gr_poly
		(pts
			(xy 275.166074 -46.004988) (xy 275.115274 -46.004988) (xy 274.924774 -46.017688) (xy 274.924774 -46.119288)
			(xy 275.115274 -46.131988) (xy 275.166074 -46.131988)
		)
		(stroke
			(width 0)
			(type solid)
		)
		(fill yes)
		(layer "F.Cu")
		(net "M_A_DQ<39>")
	)
	(gr_poly
		(pts
			(xy 275.166074 -45.344588) (xy 275.115274 -45.344588) (xy 274.924774 -45.357288) (xy 274.924774 -45.458888)
			(xy 275.115274 -45.471588) (xy 275.166074 -45.471588)
		)
		(stroke
			(width 0)
			(type solid)
		)
		(fill yes)
		(layer "F.Cu")
		(net "M_A_DQ<39>")
	)
	(gr_poly
		(pts
			(xy 275.166074 -44.684188) (xy 275.115274 -44.684188) (xy 274.924774 -44.696888) (xy 274.924774 -44.798488)
			(xy 275.115274 -44.811188) (xy 275.166074 -44.811188)
		)
		(stroke
			(width 0)
			(type solid)
		)
		(fill yes)
		(layer "F.Cu")
		(net "M_A_DQ<39>")
	)
	(gr_poly
		(pts
			(xy 275.166074 -44.023788) (xy 275.115274 -44.023788) (xy 274.924774 -44.036488) (xy 274.924774 -44.138088)
			(xy 275.115274 -44.150788) (xy 275.166074 -44.150788)
		)
		(stroke
			(width 0)
			(type solid)
		)
		(fill yes)
		(layer "F.Cu")
		(net "M_A_DQ<39>")
	)
	(gr_poly
		(pts
			(xy 275.166074 -43.363388) (xy 275.115274 -43.363388) (xy 274.924774 -43.376088) (xy 274.924774 -43.477688)
			(xy 275.115274 -43.490388) (xy 275.166074 -43.490388)
		)
		(stroke
			(width 0)
			(type solid)
		)
		(fill yes)
		(layer "F.Cu")
		(net "M_A_DQ<39>")
	)
	(gr_poly
		(pts
			(xy 275.166074 -42.702988) (xy 275.115274 -42.702988) (xy 274.924774 -42.715688) (xy 274.924774 -42.817288)
			(xy 275.115274 -42.829988) (xy 275.166074 -42.829988)
		)
		(stroke
			(width 0)
			(type solid)
		)
		(fill yes)
		(layer "F.Cu")
		(net "M_A_DQ<39>")
	)
	(gr_poly
		(pts
			(xy 275.166074 -42.042588) (xy 275.115274 -42.042588) (xy 274.924774 -42.055288) (xy 274.924774 -42.156888)
			(xy 275.115274 -42.169588) (xy 275.166074 -42.169588)
		)
		(stroke
			(width 0)
			(type solid)
		)
		(fill yes)
		(layer "F.Cu")
		(net "M_A_DQ<39>")
	)
	(gr_poly
		(pts
			(xy 275.289264 -106.11612) (xy 275.289264 -105.88752) (xy 275.096224 -105.79862) (xy 275.051774 -105.79862)
			(xy 275.051774 -106.20502) (xy 275.096224 -106.20502)
		)
		(stroke
			(width 0)
			(type solid)
		)
		(fill yes)
		(layer "F.Cu")
		(net "M_D_DQS_DP<4>")
	)
	(gr_poly
		(pts
			(xy 275.331174 -104.208834) (xy 275.331174 -103.980234) (xy 275.138134 -103.891334) (xy 275.093684 -103.891334)
			(xy 275.093684 -104.297734) (xy 275.138134 -104.297734)
		)
		(stroke
			(width 0)
			(type solid)
		)
		(fill yes)
		(layer "F.Cu")
		(net "M_D_DQS_DN<13>")
	)
	(gr_poly
		(pts
			(xy 275.33854 -104.97566) (xy 275.307044 -104.944418) (xy 275.107654 -104.870758) (xy 274.94611 -105.032302)
			(xy 275.01977 -105.231692) (xy 275.051012 -105.263188)
		)
		(stroke
			(width 0)
			(type solid)
		)
		(fill yes)
		(layer "F.Cu")
		(net "M_D_DQS_DN<4>")
	)
	(gr_poly
		(pts
			(xy 275.394674 -111.349536) (xy 275.394674 -111.247936) (xy 275.204174 -111.235236) (xy 275.153374 -111.235236)
			(xy 275.153374 -111.362236) (xy 275.204174 -111.362236)
		)
		(stroke
			(width 0)
			(type solid)
		)
		(fill yes)
		(layer "F.Cu")
		(net "M_D_DQS_DP<4>")
	)
	(gr_poly
		(pts
			(xy 275.394674 -110.689136) (xy 275.394674 -110.587536) (xy 275.204174 -110.574836) (xy 275.153374 -110.574836)
			(xy 275.153374 -110.701836) (xy 275.204174 -110.701836)
		)
		(stroke
			(width 0)
			(type solid)
		)
		(fill yes)
		(layer "F.Cu")
		(net "M_D_DQS_DP<4>")
	)
	(gr_poly
		(pts
			(xy 275.394674 -110.028736) (xy 275.394674 -109.927136) (xy 275.204174 -109.914436) (xy 275.153374 -109.914436)
			(xy 275.153374 -110.041436) (xy 275.204174 -110.041436)
		)
		(stroke
			(width 0)
			(type solid)
		)
		(fill yes)
		(layer "F.Cu")
		(net "M_D_DQS_DP<4>")
	)
	(gr_poly
		(pts
			(xy 275.394674 -109.368336) (xy 275.394674 -109.266736) (xy 275.204174 -109.254036) (xy 275.153374 -109.254036)
			(xy 275.153374 -109.381036) (xy 275.204174 -109.381036)
		)
		(stroke
			(width 0)
			(type solid)
		)
		(fill yes)
		(layer "F.Cu")
		(net "M_D_DQS_DP<4>")
	)
	(gr_poly
		(pts
			(xy 275.394674 -108.707936) (xy 275.394674 -108.606336) (xy 275.204174 -108.593636) (xy 275.153374 -108.593636)
			(xy 275.153374 -108.720636) (xy 275.204174 -108.720636)
		)
		(stroke
			(width 0)
			(type solid)
		)
		(fill yes)
		(layer "F.Cu")
		(net "M_D_DQS_DP<4>")
	)
	(gr_poly
		(pts
			(xy 275.394674 -108.047536) (xy 275.394674 -107.945936) (xy 275.204174 -107.933236) (xy 275.153374 -107.933236)
			(xy 275.153374 -108.060236) (xy 275.204174 -108.060236)
		)
		(stroke
			(width 0)
			(type solid)
		)
		(fill yes)
		(layer "F.Cu")
		(net "M_D_DQS_DP<4>")
	)
	(gr_poly
		(pts
			(xy 275.394674 -107.387136) (xy 275.394674 -107.285536) (xy 275.204174 -107.272836) (xy 275.153374 -107.272836)
			(xy 275.153374 -107.399836) (xy 275.204174 -107.399836)
		)
		(stroke
			(width 0)
			(type solid)
		)
		(fill yes)
		(layer "F.Cu")
		(net "M_D_DQS_DP<4>")
	)
	(gr_poly
		(pts
			(xy 275.407374 -49.091088) (xy 275.407374 -48.989488) (xy 275.216874 -48.976788) (xy 275.166074 -48.976788)
			(xy 275.166074 -49.103788) (xy 275.216874 -49.103788)
		)
		(stroke
			(width 0)
			(type solid)
		)
		(fill yes)
		(layer "F.Cu")
		(net "M_A_DQ<39>")
	)
	(gr_poly
		(pts
			(xy 275.407374 -48.430688) (xy 275.407374 -48.329088) (xy 275.216874 -48.316388) (xy 275.166074 -48.316388)
			(xy 275.166074 -48.443388) (xy 275.216874 -48.443388)
		)
		(stroke
			(width 0)
			(type solid)
		)
		(fill yes)
		(layer "F.Cu")
		(net "M_A_DQ<39>")
	)
	(gr_poly
		(pts
			(xy 275.407374 -47.770288) (xy 275.407374 -47.668688) (xy 275.216874 -47.655988) (xy 275.166074 -47.655988)
			(xy 275.166074 -47.782988) (xy 275.216874 -47.782988)
		)
		(stroke
			(width 0)
			(type solid)
		)
		(fill yes)
		(layer "F.Cu")
		(net "M_A_DQ<39>")
	)
	(gr_poly
		(pts
			(xy 275.407374 -47.109888) (xy 275.407374 -47.008288) (xy 275.216874 -46.995588) (xy 275.166074 -46.995588)
			(xy 275.166074 -47.122588) (xy 275.216874 -47.122588)
		)
		(stroke
			(width 0)
			(type solid)
		)
		(fill yes)
		(layer "F.Cu")
		(net "M_A_DQ<39>")
	)
	(gr_poly
		(pts
			(xy 275.407374 -46.449488) (xy 275.407374 -46.347888) (xy 275.216874 -46.335188) (xy 275.166074 -46.335188)
			(xy 275.166074 -46.462188) (xy 275.216874 -46.462188)
		)
		(stroke
			(width 0)
			(type solid)
		)
		(fill yes)
		(layer "F.Cu")
		(net "M_A_DQ<39>")
	)
	(gr_poly
		(pts
			(xy 275.407374 -45.789088) (xy 275.407374 -45.687488) (xy 275.216874 -45.674788) (xy 275.166074 -45.674788)
			(xy 275.166074 -45.801788) (xy 275.216874 -45.801788)
		)
		(stroke
			(width 0)
			(type solid)
		)
		(fill yes)
		(layer "F.Cu")
		(net "M_A_DQ<39>")
	)
	(gr_poly
		(pts
			(xy 275.407374 -45.128688) (xy 275.407374 -45.027088) (xy 275.216874 -45.014388) (xy 275.166074 -45.014388)
			(xy 275.166074 -45.141388) (xy 275.216874 -45.141388)
		)
		(stroke
			(width 0)
			(type solid)
		)
		(fill yes)
		(layer "F.Cu")
		(net "M_A_DQ<39>")
	)
	(gr_poly
		(pts
			(xy 275.407374 -44.468288) (xy 275.407374 -44.366688) (xy 275.216874 -44.353988) (xy 275.166074 -44.353988)
			(xy 275.166074 -44.480988) (xy 275.216874 -44.480988)
		)
		(stroke
			(width 0)
			(type solid)
		)
		(fill yes)
		(layer "F.Cu")
		(net "M_A_DQ<39>")
	)
	(gr_poly
		(pts
			(xy 275.407374 -43.807888) (xy 275.407374 -43.706288) (xy 275.216874 -43.693588) (xy 275.166074 -43.693588)
			(xy 275.166074 -43.820588) (xy 275.216874 -43.820588)
		)
		(stroke
			(width 0)
			(type solid)
		)
		(fill yes)
		(layer "F.Cu")
		(net "M_A_DQ<39>")
	)
	(gr_poly
		(pts
			(xy 275.407374 -43.147488) (xy 275.407374 -43.045888) (xy 275.216874 -43.033188) (xy 275.166074 -43.033188)
			(xy 275.166074 -43.160188) (xy 275.216874 -43.160188)
		)
		(stroke
			(width 0)
			(type solid)
		)
		(fill yes)
		(layer "F.Cu")
		(net "M_A_DQ<39>")
	)
	(gr_poly
		(pts
			(xy 275.407374 -42.487088) (xy 275.407374 -42.385488) (xy 275.216874 -42.372788) (xy 275.166074 -42.372788)
			(xy 275.166074 -42.499788) (xy 275.216874 -42.499788)
		)
		(stroke
			(width 0)
			(type solid)
		)
		(fill yes)
		(layer "F.Cu")
		(net "M_A_DQ<39>")
	)
	(gr_poly
		(pts
			(xy 275.433028 -102.579932) (xy 275.433028 -102.358952) (xy 275.262848 -102.270052) (xy 275.218398 -102.270052)
			(xy 275.218398 -102.668832) (xy 275.262848 -102.668832)
		)
		(stroke
			(width 0)
			(type solid)
		)
		(fill yes)
		(layer "F.Cu")
		(net "M_D_DQS_DN<13>")
	)
	(gr_poly
		(pts
			(xy 275.433282 -101.582474) (xy 275.433282 -101.361494) (xy 275.263102 -101.272594) (xy 275.218652 -101.272594)
			(xy 275.218652 -101.671374) (xy 275.263102 -101.671374)
		)
		(stroke
			(width 0)
			(type solid)
		)
		(fill yes)
		(layer "F.Cu")
		(net "M_D_DQS_DN<13>")
	)
	(gr_poly
		(pts
			(xy 275.528024 -103.449374) (xy 275.483574 -103.449374) (xy 275.290534 -103.538274) (xy 275.290534 -103.766874)
			(xy 275.483574 -103.855774) (xy 275.528024 -103.855774)
		)
		(stroke
			(width 0)
			(type solid)
		)
		(fill yes)
		(layer "F.Cu")
		(net "M_D_DQS_DN<4>")
	)
	(gr_poly
		(pts
			(xy 275.547074 -111.565436) (xy 275.496274 -111.565436) (xy 275.305774 -111.578136) (xy 275.305774 -111.679736)
			(xy 275.496274 -111.692436) (xy 275.547074 -111.692436)
		)
		(stroke
			(width 0)
			(type solid)
		)
		(fill yes)
		(layer "F.Cu")
		(net "M_D_DQ<38>")
	)
	(gr_poly
		(pts
			(xy 275.547074 -110.905036) (xy 275.496274 -110.905036) (xy 275.305774 -110.917736) (xy 275.305774 -111.019336)
			(xy 275.496274 -111.032036) (xy 275.547074 -111.032036)
		)
		(stroke
			(width 0)
			(type solid)
		)
		(fill yes)
		(layer "F.Cu")
		(net "M_D_DQ<38>")
	)
	(gr_poly
		(pts
			(xy 275.547074 -110.244636) (xy 275.496274 -110.244636) (xy 275.305774 -110.257336) (xy 275.305774 -110.358936)
			(xy 275.496274 -110.371636) (xy 275.547074 -110.371636)
		)
		(stroke
			(width 0)
			(type solid)
		)
		(fill yes)
		(layer "F.Cu")
		(net "M_D_DQ<38>")
	)
	(gr_poly
		(pts
			(xy 275.547074 -109.584236) (xy 275.496274 -109.584236) (xy 275.305774 -109.596936) (xy 275.305774 -109.698536)
			(xy 275.496274 -109.711236) (xy 275.547074 -109.711236)
		)
		(stroke
			(width 0)
			(type solid)
		)
		(fill yes)
		(layer "F.Cu")
		(net "M_D_DQ<38>")
	)
	(gr_poly
		(pts
			(xy 275.547074 -108.923836) (xy 275.496274 -108.923836) (xy 275.305774 -108.936536) (xy 275.305774 -109.038136)
			(xy 275.496274 -109.050836) (xy 275.547074 -109.050836)
		)
		(stroke
			(width 0)
			(type solid)
		)
		(fill yes)
		(layer "F.Cu")
		(net "M_D_DQ<38>")
	)
	(gr_poly
		(pts
			(xy 275.547074 -108.263436) (xy 275.496274 -108.263436) (xy 275.305774 -108.276136) (xy 275.305774 -108.377736)
			(xy 275.496274 -108.390436) (xy 275.547074 -108.390436)
		)
		(stroke
			(width 0)
			(type solid)
		)
		(fill yes)
		(layer "F.Cu")
		(net "M_D_DQ<38>")
	)
	(gr_poly
		(pts
			(xy 275.547074 -107.603036) (xy 275.496274 -107.603036) (xy 275.305774 -107.615736) (xy 275.305774 -107.717336)
			(xy 275.496274 -107.730036) (xy 275.547074 -107.730036)
		)
		(stroke
			(width 0)
			(type solid)
		)
		(fill yes)
		(layer "F.Cu")
		(net "M_D_DQ<38>")
	)
	(gr_poly
		(pts
			(xy 275.547074 -106.942636) (xy 275.496274 -106.942636) (xy 275.305774 -106.955336) (xy 275.305774 -107.056936)
			(xy 275.496274 -107.069636) (xy 275.547074 -107.069636)
		)
		(stroke
			(width 0)
			(type solid)
		)
		(fill yes)
		(layer "F.Cu")
		(net "M_D_DQ<38>")
	)
	(gr_poly
		(pts
			(xy 275.559774 -49.306988) (xy 275.508974 -49.306988) (xy 275.318474 -49.319688) (xy 275.318474 -49.421288)
			(xy 275.508974 -49.433988) (xy 275.559774 -49.433988)
		)
		(stroke
			(width 0)
			(type solid)
		)
		(fill yes)
		(layer "F.Cu")
		(net "M_A_DQ<34>")
	)
	(gr_poly
		(pts
			(xy 275.559774 -48.646588) (xy 275.508974 -48.646588) (xy 275.318474 -48.659288) (xy 275.318474 -48.760888)
			(xy 275.508974 -48.773588) (xy 275.559774 -48.773588)
		)
		(stroke
			(width 0)
			(type solid)
		)
		(fill yes)
		(layer "F.Cu")
		(net "M_A_DQ<34>")
	)
	(gr_poly
		(pts
			(xy 275.559774 -47.986188) (xy 275.508974 -47.986188) (xy 275.318474 -47.998888) (xy 275.318474 -48.100488)
			(xy 275.508974 -48.113188) (xy 275.559774 -48.113188)
		)
		(stroke
			(width 0)
			(type solid)
		)
		(fill yes)
		(layer "F.Cu")
		(net "M_A_DQ<34>")
	)
	(gr_poly
		(pts
			(xy 275.559774 -47.325788) (xy 275.508974 -47.325788) (xy 275.318474 -47.338488) (xy 275.318474 -47.440088)
			(xy 275.508974 -47.452788) (xy 275.559774 -47.452788)
		)
		(stroke
			(width 0)
			(type solid)
		)
		(fill yes)
		(layer "F.Cu")
		(net "M_A_DQ<34>")
	)
	(gr_poly
		(pts
			(xy 275.559774 -46.665388) (xy 275.508974 -46.665388) (xy 275.318474 -46.678088) (xy 275.318474 -46.779688)
			(xy 275.508974 -46.792388) (xy 275.559774 -46.792388)
		)
		(stroke
			(width 0)
			(type solid)
		)
		(fill yes)
		(layer "F.Cu")
		(net "M_A_DQ<34>")
	)
	(gr_poly
		(pts
			(xy 275.559774 -46.004988) (xy 275.508974 -46.004988) (xy 275.318474 -46.017688) (xy 275.318474 -46.119288)
			(xy 275.508974 -46.131988) (xy 275.559774 -46.131988)
		)
		(stroke
			(width 0)
			(type solid)
		)
		(fill yes)
		(layer "F.Cu")
		(net "M_A_DQ<34>")
	)
	(gr_poly
		(pts
			(xy 275.559774 -45.344588) (xy 275.508974 -45.344588) (xy 275.318474 -45.357288) (xy 275.318474 -45.458888)
			(xy 275.508974 -45.471588) (xy 275.559774 -45.471588)
		)
		(stroke
			(width 0)
			(type solid)
		)
		(fill yes)
		(layer "F.Cu")
		(net "M_A_DQ<34>")
	)
	(gr_poly
		(pts
			(xy 275.559774 -44.684188) (xy 275.508974 -44.684188) (xy 275.318474 -44.696888) (xy 275.318474 -44.798488)
			(xy 275.508974 -44.811188) (xy 275.559774 -44.811188)
		)
		(stroke
			(width 0)
			(type solid)
		)
		(fill yes)
		(layer "F.Cu")
		(net "M_A_DQ<34>")
	)
	(gr_poly
		(pts
			(xy 275.559774 -44.023788) (xy 275.508974 -44.023788) (xy 275.318474 -44.036488) (xy 275.318474 -44.138088)
			(xy 275.508974 -44.150788) (xy 275.559774 -44.150788)
		)
		(stroke
			(width 0)
			(type solid)
		)
		(fill yes)
		(layer "F.Cu")
		(net "M_A_DQ<34>")
	)
	(gr_poly
		(pts
			(xy 275.559774 -43.363388) (xy 275.508974 -43.363388) (xy 275.318474 -43.376088) (xy 275.318474 -43.477688)
			(xy 275.508974 -43.490388) (xy 275.559774 -43.490388)
		)
		(stroke
			(width 0)
			(type solid)
		)
		(fill yes)
		(layer "F.Cu")
		(net "M_A_DQ<34>")
	)
	(gr_poly
		(pts
			(xy 275.559774 -42.702988) (xy 275.508974 -42.702988) (xy 275.318474 -42.715688) (xy 275.318474 -42.817288)
			(xy 275.508974 -42.829988) (xy 275.559774 -42.829988)
		)
		(stroke
			(width 0)
			(type solid)
		)
		(fill yes)
		(layer "F.Cu")
		(net "M_A_DQ<34>")
	)
	(gr_poly
		(pts
			(xy 275.559774 -42.042588) (xy 275.508974 -42.042588) (xy 275.318474 -42.055288) (xy 275.318474 -42.156888)
			(xy 275.508974 -42.169588) (xy 275.559774 -42.169588)
		)
		(stroke
			(width 0)
			(type solid)
		)
		(fill yes)
		(layer "F.Cu")
		(net "M_A_DQ<34>")
	)
	(gr_poly
		(pts
			(xy 275.633942 -105.28554) (xy 275.560282 -105.086404) (xy 275.528786 -105.054908) (xy 275.241512 -105.342182)
			(xy 275.273008 -105.373678) (xy 275.472144 -105.447338)
		)
		(stroke
			(width 0)
			(type solid)
		)
		(fill yes)
		(layer "F.Cu")
		(net "M_D_DQS_DP<4>")
	)
	(gr_poly
		(pts
			(xy 275.788374 -111.349536) (xy 275.788374 -111.247936) (xy 275.597874 -111.235236) (xy 275.547074 -111.235236)
			(xy 275.547074 -111.362236) (xy 275.597874 -111.362236)
		)
		(stroke
			(width 0)
			(type solid)
		)
		(fill yes)
		(layer "F.Cu")
		(net "M_D_DQ<38>")
	)
	(gr_poly
		(pts
			(xy 275.788374 -110.689136) (xy 275.788374 -110.587536) (xy 275.597874 -110.574836) (xy 275.547074 -110.574836)
			(xy 275.547074 -110.701836) (xy 275.597874 -110.701836)
		)
		(stroke
			(width 0)
			(type solid)
		)
		(fill yes)
		(layer "F.Cu")
		(net "M_D_DQ<38>")
	)
	(gr_poly
		(pts
			(xy 275.788374 -110.028736) (xy 275.788374 -109.927136) (xy 275.597874 -109.914436) (xy 275.547074 -109.914436)
			(xy 275.547074 -110.041436) (xy 275.597874 -110.041436)
		)
		(stroke
			(width 0)
			(type solid)
		)
		(fill yes)
		(layer "F.Cu")
		(net "M_D_DQ<38>")
	)
	(gr_poly
		(pts
			(xy 275.788374 -109.368336) (xy 275.788374 -109.266736) (xy 275.597874 -109.254036) (xy 275.547074 -109.254036)
			(xy 275.547074 -109.381036) (xy 275.597874 -109.381036)
		)
		(stroke
			(width 0)
			(type solid)
		)
		(fill yes)
		(layer "F.Cu")
		(net "M_D_DQ<38>")
	)
	(gr_poly
		(pts
			(xy 275.788374 -108.707936) (xy 275.788374 -108.606336) (xy 275.597874 -108.593636) (xy 275.547074 -108.593636)
			(xy 275.547074 -108.720636) (xy 275.597874 -108.720636)
		)
		(stroke
			(width 0)
			(type solid)
		)
		(fill yes)
		(layer "F.Cu")
		(net "M_D_DQ<38>")
	)
	(gr_poly
		(pts
			(xy 275.788374 -108.047536) (xy 275.788374 -107.945936) (xy 275.597874 -107.933236) (xy 275.547074 -107.933236)
			(xy 275.547074 -108.060236) (xy 275.597874 -108.060236)
		)
		(stroke
			(width 0)
			(type solid)
		)
		(fill yes)
		(layer "F.Cu")
		(net "M_D_DQ<38>")
	)
	(gr_poly
		(pts
			(xy 275.788374 -107.387136) (xy 275.788374 -107.285536) (xy 275.597874 -107.272836) (xy 275.547074 -107.272836)
			(xy 275.547074 -107.399836) (xy 275.597874 -107.399836)
		)
		(stroke
			(width 0)
			(type solid)
		)
		(fill yes)
		(layer "F.Cu")
		(net "M_D_DQ<38>")
	)
	(gr_poly
		(pts
			(xy 275.801074 -49.091088) (xy 275.801074 -48.989488) (xy 275.610574 -48.976788) (xy 275.559774 -48.976788)
			(xy 275.559774 -49.103788) (xy 275.610574 -49.103788)
		)
		(stroke
			(width 0)
			(type solid)
		)
		(fill yes)
		(layer "F.Cu")
		(net "M_A_DQ<34>")
	)
	(gr_poly
		(pts
			(xy 275.801074 -48.430688) (xy 275.801074 -48.329088) (xy 275.610574 -48.316388) (xy 275.559774 -48.316388)
			(xy 275.559774 -48.443388) (xy 275.610574 -48.443388)
		)
		(stroke
			(width 0)
			(type solid)
		)
		(fill yes)
		(layer "F.Cu")
		(net "M_A_DQ<34>")
	)
	(gr_poly
		(pts
			(xy 275.801074 -47.770288) (xy 275.801074 -47.668688) (xy 275.610574 -47.655988) (xy 275.559774 -47.655988)
			(xy 275.559774 -47.782988) (xy 275.610574 -47.782988)
		)
		(stroke
			(width 0)
			(type solid)
		)
		(fill yes)
		(layer "F.Cu")
		(net "M_A_DQ<34>")
	)
	(gr_poly
		(pts
			(xy 275.801074 -47.109888) (xy 275.801074 -47.008288) (xy 275.610574 -46.995588) (xy 275.559774 -46.995588)
			(xy 275.559774 -47.122588) (xy 275.610574 -47.122588)
		)
		(stroke
			(width 0)
			(type solid)
		)
		(fill yes)
		(layer "F.Cu")
		(net "M_A_DQ<34>")
	)
	(gr_poly
		(pts
			(xy 275.801074 -46.449488) (xy 275.801074 -46.347888) (xy 275.610574 -46.335188) (xy 275.559774 -46.335188)
			(xy 275.559774 -46.462188) (xy 275.610574 -46.462188)
		)
		(stroke
			(width 0)
			(type solid)
		)
		(fill yes)
		(layer "F.Cu")
		(net "M_A_DQ<34>")
	)
	(gr_poly
		(pts
			(xy 275.801074 -45.789088) (xy 275.801074 -45.687488) (xy 275.610574 -45.674788) (xy 275.559774 -45.674788)
			(xy 275.559774 -45.801788) (xy 275.610574 -45.801788)
		)
		(stroke
			(width 0)
			(type solid)
		)
		(fill yes)
		(layer "F.Cu")
		(net "M_A_DQ<34>")
	)
	(gr_poly
		(pts
			(xy 275.801074 -45.128688) (xy 275.801074 -45.027088) (xy 275.610574 -45.014388) (xy 275.559774 -45.014388)
			(xy 275.559774 -45.141388) (xy 275.610574 -45.141388)
		)
		(stroke
			(width 0)
			(type solid)
		)
		(fill yes)
		(layer "F.Cu")
		(net "M_A_DQ<34>")
	)
	(gr_poly
		(pts
			(xy 275.801074 -44.468288) (xy 275.801074 -44.366688) (xy 275.610574 -44.353988) (xy 275.559774 -44.353988)
			(xy 275.559774 -44.480988) (xy 275.610574 -44.480988)
		)
		(stroke
			(width 0)
			(type solid)
		)
		(fill yes)
		(layer "F.Cu")
		(net "M_A_DQ<34>")
	)
	(gr_poly
		(pts
			(xy 275.801074 -43.807888) (xy 275.801074 -43.706288) (xy 275.610574 -43.693588) (xy 275.559774 -43.693588)
			(xy 275.559774 -43.820588) (xy 275.610574 -43.820588)
		)
		(stroke
			(width 0)
			(type solid)
		)
		(fill yes)
		(layer "F.Cu")
		(net "M_A_DQ<34>")
	)
	(gr_poly
		(pts
			(xy 275.801074 -43.147488) (xy 275.801074 -43.045888) (xy 275.610574 -43.033188) (xy 275.559774 -43.033188)
			(xy 275.559774 -43.160188) (xy 275.610574 -43.160188)
		)
		(stroke
			(width 0)
			(type solid)
		)
		(fill yes)
		(layer "F.Cu")
		(net "M_A_DQ<34>")
	)
	(gr_poly
		(pts
			(xy 275.801074 -42.487088) (xy 275.801074 -42.385488) (xy 275.610574 -42.372788) (xy 275.559774 -42.372788)
			(xy 275.559774 -42.499788) (xy 275.610574 -42.499788)
		)
		(stroke
			(width 0)
			(type solid)
		)
		(fill yes)
		(layer "F.Cu")
		(net "M_A_DQ<34>")
	)
	(gr_poly
		(pts
			(xy 275.940774 -111.565436) (xy 275.889974 -111.565436) (xy 275.699474 -111.578136) (xy 275.699474 -111.679736)
			(xy 275.889974 -111.692436) (xy 275.940774 -111.692436)
		)
		(stroke
			(width 0)
			(type solid)
		)
		(fill yes)
		(layer "F.Cu")
		(net "M_D_DQ<39>")
	)
	(gr_poly
		(pts
			(xy 275.940774 -110.905036) (xy 275.889974 -110.905036) (xy 275.699474 -110.917736) (xy 275.699474 -111.019336)
			(xy 275.889974 -111.032036) (xy 275.940774 -111.032036)
		)
		(stroke
			(width 0)
			(type solid)
		)
		(fill yes)
		(layer "F.Cu")
		(net "M_D_DQ<39>")
	)
	(gr_poly
		(pts
			(xy 275.940774 -110.244636) (xy 275.889974 -110.244636) (xy 275.699474 -110.257336) (xy 275.699474 -110.358936)
			(xy 275.889974 -110.371636) (xy 275.940774 -110.371636)
		)
		(stroke
			(width 0)
			(type solid)
		)
		(fill yes)
		(layer "F.Cu")
		(net "M_D_DQ<39>")
	)
	(gr_poly
		(pts
			(xy 275.940774 -109.584236) (xy 275.889974 -109.584236) (xy 275.699474 -109.596936) (xy 275.699474 -109.698536)
			(xy 275.889974 -109.711236) (xy 275.940774 -109.711236)
		)
		(stroke
			(width 0)
			(type solid)
		)
		(fill yes)
		(layer "F.Cu")
		(net "M_D_DQ<39>")
	)
	(gr_poly
		(pts
			(xy 275.940774 -108.923836) (xy 275.889974 -108.923836) (xy 275.699474 -108.936536) (xy 275.699474 -109.038136)
			(xy 275.889974 -109.050836) (xy 275.940774 -109.050836)
		)
		(stroke
			(width 0)
			(type solid)
		)
		(fill yes)
		(layer "F.Cu")
		(net "M_D_DQ<39>")
	)
	(gr_poly
		(pts
			(xy 275.940774 -108.263436) (xy 275.889974 -108.263436) (xy 275.699474 -108.276136) (xy 275.699474 -108.377736)
			(xy 275.889974 -108.390436) (xy 275.940774 -108.390436)
		)
		(stroke
			(width 0)
			(type solid)
		)
		(fill yes)
		(layer "F.Cu")
		(net "M_D_DQ<39>")
	)
	(gr_poly
		(pts
			(xy 275.940774 -107.603036) (xy 275.889974 -107.603036) (xy 275.699474 -107.615736) (xy 275.699474 -107.717336)
			(xy 275.889974 -107.730036) (xy 275.940774 -107.730036)
		)
		(stroke
			(width 0)
			(type solid)
		)
		(fill yes)
		(layer "F.Cu")
		(net "M_D_DQ<39>")
	)
	(gr_poly
		(pts
			(xy 275.940774 -106.942636) (xy 275.889974 -106.942636) (xy 275.699474 -106.955336) (xy 275.699474 -107.056936)
			(xy 275.889974 -107.069636) (xy 275.940774 -107.069636)
		)
		(stroke
			(width 0)
			(type solid)
		)
		(fill yes)
		(layer "F.Cu")
		(net "M_D_DQ<39>")
	)
	(gr_poly
		(pts
			(xy 275.94433 -101.273102) (xy 275.89988 -101.273102) (xy 275.7297 -101.362002) (xy 275.7297 -101.582982)
			(xy 275.89988 -101.671882) (xy 275.94433 -101.671882)
		)
		(stroke
			(width 0)
			(type solid)
		)
		(fill yes)
		(layer "F.Cu")
		(net "M_D_DQ<38>")
	)
	(gr_poly
		(pts
			(xy 275.953474 -49.306988) (xy 275.902674 -49.306988) (xy 275.712174 -49.319688) (xy 275.712174 -49.421288)
			(xy 275.902674 -49.433988) (xy 275.953474 -49.433988)
		)
		(stroke
			(width 0)
			(type solid)
		)
		(fill yes)
		(layer "F.Cu")
		(net "M_A_DQ<35>")
	)
	(gr_poly
		(pts
			(xy 275.953474 -48.646588) (xy 275.902674 -48.646588) (xy 275.712174 -48.659288) (xy 275.712174 -48.760888)
			(xy 275.902674 -48.773588) (xy 275.953474 -48.773588)
		)
		(stroke
			(width 0)
			(type solid)
		)
		(fill yes)
		(layer "F.Cu")
		(net "M_A_DQ<35>")
	)
	(gr_poly
		(pts
			(xy 275.953474 -47.986188) (xy 275.902674 -47.986188) (xy 275.712174 -47.998888) (xy 275.712174 -48.100488)
			(xy 275.902674 -48.113188) (xy 275.953474 -48.113188)
		)
		(stroke
			(width 0)
			(type solid)
		)
		(fill yes)
		(layer "F.Cu")
		(net "M_A_DQ<35>")
	)
	(gr_poly
		(pts
			(xy 275.953474 -47.325788) (xy 275.902674 -47.325788) (xy 275.712174 -47.338488) (xy 275.712174 -47.440088)
			(xy 275.902674 -47.452788) (xy 275.953474 -47.452788)
		)
		(stroke
			(width 0)
			(type solid)
		)
		(fill yes)
		(layer "F.Cu")
		(net "M_A_DQ<35>")
	)
	(gr_poly
		(pts
			(xy 275.953474 -46.665388) (xy 275.902674 -46.665388) (xy 275.712174 -46.678088) (xy 275.712174 -46.779688)
			(xy 275.902674 -46.792388) (xy 275.953474 -46.792388)
		)
		(stroke
			(width 0)
			(type solid)
		)
		(fill yes)
		(layer "F.Cu")
		(net "M_A_DQ<35>")
	)
	(gr_poly
		(pts
			(xy 275.953474 -46.004988) (xy 275.902674 -46.004988) (xy 275.712174 -46.017688) (xy 275.712174 -46.119288)
			(xy 275.902674 -46.131988) (xy 275.953474 -46.131988)
		)
		(stroke
			(width 0)
			(type solid)
		)
		(fill yes)
		(layer "F.Cu")
		(net "M_A_DQ<35>")
	)
	(gr_poly
		(pts
			(xy 275.953474 -45.344588) (xy 275.902674 -45.344588) (xy 275.712174 -45.357288) (xy 275.712174 -45.458888)
			(xy 275.902674 -45.471588) (xy 275.953474 -45.471588)
		)
		(stroke
			(width 0)
			(type solid)
		)
		(fill yes)
		(layer "F.Cu")
		(net "M_A_DQ<35>")
	)
	(gr_poly
		(pts
			(xy 275.953474 -44.684188) (xy 275.902674 -44.684188) (xy 275.712174 -44.696888) (xy 275.712174 -44.798488)
			(xy 275.902674 -44.811188) (xy 275.953474 -44.811188)
		)
		(stroke
			(width 0)
			(type solid)
		)
		(fill yes)
		(layer "F.Cu")
		(net "M_A_DQ<35>")
	)
	(gr_poly
		(pts
			(xy 275.953474 -44.023788) (xy 275.902674 -44.023788) (xy 275.712174 -44.036488) (xy 275.712174 -44.138088)
			(xy 275.902674 -44.150788) (xy 275.953474 -44.150788)
		)
		(stroke
			(width 0)
			(type solid)
		)
		(fill yes)
		(layer "F.Cu")
		(net "M_A_DQ<35>")
	)
	(gr_poly
		(pts
			(xy 275.953474 -43.363388) (xy 275.902674 -43.363388) (xy 275.712174 -43.376088) (xy 275.712174 -43.477688)
			(xy 275.902674 -43.490388) (xy 275.953474 -43.490388)
		)
		(stroke
			(width 0)
			(type solid)
		)
		(fill yes)
		(layer "F.Cu")
		(net "M_A_DQ<35>")
	)
	(gr_poly
		(pts
			(xy 275.953474 -42.702988) (xy 275.902674 -42.702988) (xy 275.712174 -42.715688) (xy 275.712174 -42.817288)
			(xy 275.902674 -42.829988) (xy 275.953474 -42.829988)
		)
		(stroke
			(width 0)
			(type solid)
		)
		(fill yes)
		(layer "F.Cu")
		(net "M_A_DQ<35>")
	)
	(gr_poly
		(pts
			(xy 275.953474 -42.042588) (xy 275.902674 -42.042588) (xy 275.712174 -42.055288) (xy 275.712174 -42.156888)
			(xy 275.902674 -42.169588) (xy 275.953474 -42.169588)
		)
		(stroke
			(width 0)
			(type solid)
		)
		(fill yes)
		(layer "F.Cu")
		(net "M_A_DQ<35>")
	)
	(gr_poly
		(pts
			(xy 275.956014 -103.766874) (xy 275.956014 -103.538274) (xy 275.762974 -103.449374) (xy 275.718524 -103.449374)
			(xy 275.718524 -103.855774) (xy 275.762974 -103.855774)
		)
		(stroke
			(width 0)
			(type solid)
		)
		(fill yes)
		(layer "F.Cu")
		(net "M_D_DQS_DP<4>")
	)
	(gr_poly
		(pts
			(xy 276.182074 -111.349536) (xy 276.182074 -111.247936) (xy 275.991574 -111.235236) (xy 275.940774 -111.235236)
			(xy 275.940774 -111.362236) (xy 275.991574 -111.362236)
		)
		(stroke
			(width 0)
			(type solid)
		)
		(fill yes)
		(layer "F.Cu")
		(net "M_D_DQ<39>")
	)
	(gr_poly
		(pts
			(xy 276.182074 -110.689136) (xy 276.182074 -110.587536) (xy 275.991574 -110.574836) (xy 275.940774 -110.574836)
			(xy 275.940774 -110.701836) (xy 275.991574 -110.701836)
		)
		(stroke
			(width 0)
			(type solid)
		)
		(fill yes)
		(layer "F.Cu")
		(net "M_D_DQ<39>")
	)
	(gr_poly
		(pts
			(xy 276.182074 -110.028736) (xy 276.182074 -109.927136) (xy 275.991574 -109.914436) (xy 275.940774 -109.914436)
			(xy 275.940774 -110.041436) (xy 275.991574 -110.041436)
		)
		(stroke
			(width 0)
			(type solid)
		)
		(fill yes)
		(layer "F.Cu")
		(net "M_D_DQ<39>")
	)
	(gr_poly
		(pts
			(xy 276.182074 -109.368336) (xy 276.182074 -109.266736) (xy 275.991574 -109.254036) (xy 275.940774 -109.254036)
			(xy 275.940774 -109.381036) (xy 275.991574 -109.381036)
		)
		(stroke
			(width 0)
			(type solid)
		)
		(fill yes)
		(layer "F.Cu")
		(net "M_D_DQ<39>")
	)
	(gr_poly
		(pts
			(xy 276.182074 -108.707936) (xy 276.182074 -108.606336) (xy 275.991574 -108.593636) (xy 275.940774 -108.593636)
			(xy 275.940774 -108.720636) (xy 275.991574 -108.720636)
		)
		(stroke
			(width 0)
			(type solid)
		)
		(fill yes)
		(layer "F.Cu")
		(net "M_D_DQ<39>")
	)
	(gr_poly
		(pts
			(xy 276.182074 -108.047536) (xy 276.182074 -107.945936) (xy 275.991574 -107.933236) (xy 275.940774 -107.933236)
			(xy 275.940774 -108.060236) (xy 275.991574 -108.060236)
		)
		(stroke
			(width 0)
			(type solid)
		)
		(fill yes)
		(layer "F.Cu")
		(net "M_D_DQ<39>")
	)
	(gr_poly
		(pts
			(xy 276.182074 -107.387136) (xy 276.182074 -107.285536) (xy 275.991574 -107.272836) (xy 275.940774 -107.272836)
			(xy 275.940774 -107.399836) (xy 275.991574 -107.399836)
		)
		(stroke
			(width 0)
			(type solid)
		)
		(fill yes)
		(layer "F.Cu")
		(net "M_D_DQ<39>")
	)
	(gr_poly
		(pts
			(xy 276.194774 -49.091088) (xy 276.194774 -48.989488) (xy 276.004274 -48.976788) (xy 275.953474 -48.976788)
			(xy 275.953474 -49.103788) (xy 276.004274 -49.103788)
		)
		(stroke
			(width 0)
			(type solid)
		)
		(fill yes)
		(layer "F.Cu")
		(net "M_A_DQ<35>")
	)
	(gr_poly
		(pts
			(xy 276.194774 -48.430688) (xy 276.194774 -48.329088) (xy 276.004274 -48.316388) (xy 275.953474 -48.316388)
			(xy 275.953474 -48.443388) (xy 276.004274 -48.443388)
		)
		(stroke
			(width 0)
			(type solid)
		)
		(fill yes)
		(layer "F.Cu")
		(net "M_A_DQ<35>")
	)
	(gr_poly
		(pts
			(xy 276.194774 -47.770288) (xy 276.194774 -47.668688) (xy 276.004274 -47.655988) (xy 275.953474 -47.655988)
			(xy 275.953474 -47.782988) (xy 276.004274 -47.782988)
		)
		(stroke
			(width 0)
			(type solid)
		)
		(fill yes)
		(layer "F.Cu")
		(net "M_A_DQ<35>")
	)
	(gr_poly
		(pts
			(xy 276.194774 -47.109888) (xy 276.194774 -47.008288) (xy 276.004274 -46.995588) (xy 275.953474 -46.995588)
			(xy 275.953474 -47.122588) (xy 276.004274 -47.122588)
		)
		(stroke
			(width 0)
			(type solid)
		)
		(fill yes)
		(layer "F.Cu")
		(net "M_A_DQ<35>")
	)
	(gr_poly
		(pts
			(xy 276.194774 -46.449488) (xy 276.194774 -46.347888) (xy 276.004274 -46.335188) (xy 275.953474 -46.335188)
			(xy 275.953474 -46.462188) (xy 276.004274 -46.462188)
		)
		(stroke
			(width 0)
			(type solid)
		)
		(fill yes)
		(layer "F.Cu")
		(net "M_A_DQ<35>")
	)
	(gr_poly
		(pts
			(xy 276.194774 -45.789088) (xy 276.194774 -45.687488) (xy 276.004274 -45.674788) (xy 275.953474 -45.674788)
			(xy 275.953474 -45.801788) (xy 276.004274 -45.801788)
		)
		(stroke
			(width 0)
			(type solid)
		)
		(fill yes)
		(layer "F.Cu")
		(net "M_A_DQ<35>")
	)
	(gr_poly
		(pts
			(xy 276.194774 -45.128688) (xy 276.194774 -45.027088) (xy 276.004274 -45.014388) (xy 275.953474 -45.014388)
			(xy 275.953474 -45.141388) (xy 276.004274 -45.141388)
		)
		(stroke
			(width 0)
			(type solid)
		)
		(fill yes)
		(layer "F.Cu")
		(net "M_A_DQ<35>")
	)
	(gr_poly
		(pts
			(xy 276.194774 -44.468288) (xy 276.194774 -44.366688) (xy 276.004274 -44.353988) (xy 275.953474 -44.353988)
			(xy 275.953474 -44.480988) (xy 276.004274 -44.480988)
		)
		(stroke
			(width 0)
			(type solid)
		)
		(fill yes)
		(layer "F.Cu")
		(net "M_A_DQ<35>")
	)
	(gr_poly
		(pts
			(xy 276.194774 -43.807888) (xy 276.194774 -43.706288) (xy 276.004274 -43.693588) (xy 275.953474 -43.693588)
			(xy 275.953474 -43.820588) (xy 276.004274 -43.820588)
		)
		(stroke
			(width 0)
			(type solid)
		)
		(fill yes)
		(layer "F.Cu")
		(net "M_A_DQ<35>")
	)
	(gr_poly
		(pts
			(xy 276.194774 -43.147488) (xy 276.194774 -43.045888) (xy 276.004274 -43.033188) (xy 275.953474 -43.033188)
			(xy 275.953474 -43.160188) (xy 276.004274 -43.160188)
		)
		(stroke
			(width 0)
			(type solid)
		)
		(fill yes)
		(layer "F.Cu")
		(net "M_A_DQ<35>")
	)
	(gr_poly
		(pts
			(xy 276.194774 -42.487088) (xy 276.194774 -42.385488) (xy 276.004274 -42.372788) (xy 275.953474 -42.372788)
			(xy 275.953474 -42.499788) (xy 276.004274 -42.499788)
		)
		(stroke
			(width 0)
			(type solid)
		)
		(fill yes)
		(layer "F.Cu")
		(net "M_A_DQ<35>")
	)
	(gr_poly
		(pts
			(xy 276.291802 -102.084378) (xy 276.291802 -101.863398) (xy 276.121622 -101.774498) (xy 276.077172 -101.774498)
			(xy 276.077172 -102.173278) (xy 276.121622 -102.173278)
		)
		(stroke
			(width 0)
			(type solid)
		)
		(fill yes)
		(layer "F.Cu")
		(net "M_D_DQ<38>")
	)
	(gr_poly
		(pts
			(xy 276.303994 -104.202484) (xy 276.259544 -104.202484) (xy 276.066504 -104.291384) (xy 276.066504 -104.519984)
			(xy 276.259544 -104.608884) (xy 276.303994 -104.608884)
		)
		(stroke
			(width 0)
			(type solid)
		)
		(fill yes)
		(layer "F.Cu")
		(net "M_D_DQ<38>")
	)
	(gr_poly
		(pts
			(xy 276.334474 -111.565436) (xy 276.283674 -111.565436) (xy 276.093174 -111.578136) (xy 276.093174 -111.679736)
			(xy 276.283674 -111.692436) (xy 276.334474 -111.692436)
		)
		(stroke
			(width 0)
			(type solid)
		)
		(fill yes)
		(layer "F.Cu")
		(net "M_D_DQ<34>")
	)
	(gr_poly
		(pts
			(xy 276.334474 -110.905036) (xy 276.283674 -110.905036) (xy 276.093174 -110.917736) (xy 276.093174 -111.019336)
			(xy 276.283674 -111.032036) (xy 276.334474 -111.032036)
		)
		(stroke
			(width 0)
			(type solid)
		)
		(fill yes)
		(layer "F.Cu")
		(net "M_D_DQ<34>")
	)
	(gr_poly
		(pts
			(xy 276.334474 -110.244636) (xy 276.283674 -110.244636) (xy 276.093174 -110.257336) (xy 276.093174 -110.358936)
			(xy 276.283674 -110.371636) (xy 276.334474 -110.371636)
		)
		(stroke
			(width 0)
			(type solid)
		)
		(fill yes)
		(layer "F.Cu")
		(net "M_D_DQ<34>")
	)
	(gr_poly
		(pts
			(xy 276.334474 -109.584236) (xy 276.283674 -109.584236) (xy 276.093174 -109.596936) (xy 276.093174 -109.698536)
			(xy 276.283674 -109.711236) (xy 276.334474 -109.711236)
		)
		(stroke
			(width 0)
			(type solid)
		)
		(fill yes)
		(layer "F.Cu")
		(net "M_D_DQ<34>")
	)
	(gr_poly
		(pts
			(xy 276.334474 -108.923836) (xy 276.283674 -108.923836) (xy 276.093174 -108.936536) (xy 276.093174 -109.038136)
			(xy 276.283674 -109.050836) (xy 276.334474 -109.050836)
		)
		(stroke
			(width 0)
			(type solid)
		)
		(fill yes)
		(layer "F.Cu")
		(net "M_D_DQ<34>")
	)
	(gr_poly
		(pts
			(xy 276.334474 -108.263436) (xy 276.283674 -108.263436) (xy 276.093174 -108.276136) (xy 276.093174 -108.377736)
			(xy 276.283674 -108.390436) (xy 276.334474 -108.390436)
		)
		(stroke
			(width 0)
			(type solid)
		)
		(fill yes)
		(layer "F.Cu")
		(net "M_D_DQ<34>")
	)
	(gr_poly
		(pts
			(xy 276.334474 -107.603036) (xy 276.283674 -107.603036) (xy 276.093174 -107.615736) (xy 276.093174 -107.717336)
			(xy 276.283674 -107.730036) (xy 276.334474 -107.730036)
		)
		(stroke
			(width 0)
			(type solid)
		)
		(fill yes)
		(layer "F.Cu")
		(net "M_D_DQ<34>")
	)
	(gr_poly
		(pts
			(xy 276.334474 -106.942636) (xy 276.283674 -106.942636) (xy 276.093174 -106.955336) (xy 276.093174 -107.056936)
			(xy 276.283674 -107.069636) (xy 276.334474 -107.069636)
		)
		(stroke
			(width 0)
			(type solid)
		)
		(fill yes)
		(layer "F.Cu")
		(net "M_D_DQ<34>")
	)
	(gr_poly
		(pts
			(xy 276.4155 -105.733088) (xy 276.34184 -105.533698) (xy 276.310598 -105.502202) (xy 276.02307 -105.78973)
			(xy 276.054566 -105.820972) (xy 276.253956 -105.894632)
		)
		(stroke
			(width 0)
			(type solid)
		)
		(fill yes)
		(layer "F.Cu")
		(net "M_D_DQ<39>")
	)
	(gr_poly
		(pts
			(xy 276.575774 -111.349536) (xy 276.575774 -111.247936) (xy 276.385274 -111.235236) (xy 276.334474 -111.235236)
			(xy 276.334474 -111.362236) (xy 276.385274 -111.362236)
		)
		(stroke
			(width 0)
			(type solid)
		)
		(fill yes)
		(layer "F.Cu")
		(net "M_D_DQ<34>")
	)
	(gr_poly
		(pts
			(xy 276.575774 -110.689136) (xy 276.575774 -110.587536) (xy 276.385274 -110.574836) (xy 276.334474 -110.574836)
			(xy 276.334474 -110.701836) (xy 276.385274 -110.701836)
		)
		(stroke
			(width 0)
			(type solid)
		)
		(fill yes)
		(layer "F.Cu")
		(net "M_D_DQ<34>")
	)
	(gr_poly
		(pts
			(xy 276.575774 -110.028736) (xy 276.575774 -109.927136) (xy 276.385274 -109.914436) (xy 276.334474 -109.914436)
			(xy 276.334474 -110.041436) (xy 276.385274 -110.041436)
		)
		(stroke
			(width 0)
			(type solid)
		)
		(fill yes)
		(layer "F.Cu")
		(net "M_D_DQ<34>")
	)
	(gr_poly
		(pts
			(xy 276.575774 -109.368336) (xy 276.575774 -109.266736) (xy 276.385274 -109.254036) (xy 276.334474 -109.254036)
			(xy 276.334474 -109.381036) (xy 276.385274 -109.381036)
		)
		(stroke
			(width 0)
			(type solid)
		)
		(fill yes)
		(layer "F.Cu")
		(net "M_D_DQ<34>")
	)
	(gr_poly
		(pts
			(xy 276.575774 -108.707936) (xy 276.575774 -108.606336) (xy 276.385274 -108.593636) (xy 276.334474 -108.593636)
			(xy 276.334474 -108.720636) (xy 276.385274 -108.720636)
		)
		(stroke
			(width 0)
			(type solid)
		)
		(fill yes)
		(layer "F.Cu")
		(net "M_D_DQ<34>")
	)
	(gr_poly
		(pts
			(xy 276.575774 -108.047536) (xy 276.575774 -107.945936) (xy 276.385274 -107.933236) (xy 276.334474 -107.933236)
			(xy 276.334474 -108.060236) (xy 276.385274 -108.060236)
		)
		(stroke
			(width 0)
			(type solid)
		)
		(fill yes)
		(layer "F.Cu")
		(net "M_D_DQ<34>")
	)
	(gr_poly
		(pts
			(xy 276.575774 -107.387136) (xy 276.575774 -107.285536) (xy 276.385274 -107.272836) (xy 276.334474 -107.272836)
			(xy 276.334474 -107.399836) (xy 276.385274 -107.399836)
		)
		(stroke
			(width 0)
			(type solid)
		)
		(fill yes)
		(layer "F.Cu")
		(net "M_D_DQ<34>")
	)
	(gr_poly
		(pts
			(xy 276.579584 -103.630984) (xy 276.579584 -103.402384) (xy 276.386544 -103.313484) (xy 276.342094 -103.313484)
			(xy 276.342094 -103.719884) (xy 276.386544 -103.719884)
		)
		(stroke
			(width 0)
			(type solid)
		)
		(fill yes)
		(layer "F.Cu")
		(net "M_D_DQ<39>")
	)
	(gr_poly
		(pts
			(xy 276.607524 -50.776124) (xy 276.563074 -50.776124) (xy 276.392894 -50.865024) (xy 276.392894 -51.086004)
			(xy 276.563074 -51.174904) (xy 276.607524 -51.174904)
		)
		(stroke
			(width 0)
			(type solid)
		)
		(fill yes)
		(layer "F.Cu")
		(net "M_B_DQ<44>")
	)
	(gr_poly
		(pts
			(xy 276.618954 -101.774244) (xy 276.57425 -101.774498) (xy 276.404578 -101.863652) (xy 276.405086 -102.084632)
			(xy 276.57552 -102.173024) (xy 276.61997 -102.173024)
		)
		(stroke
			(width 0)
			(type solid)
		)
		(fill yes)
		(layer "F.Cu")
		(net "M_D_DQ<34>")
	)
	(gr_poly
		(pts
			(xy 276.728174 -111.565436) (xy 276.677374 -111.565436) (xy 276.486874 -111.578136) (xy 276.486874 -111.679736)
			(xy 276.677374 -111.692436) (xy 276.728174 -111.692436)
		)
		(stroke
			(width 0)
			(type solid)
		)
		(fill yes)
		(layer "F.Cu")
		(net "M_D_DQ<35>")
	)
	(gr_poly
		(pts
			(xy 276.728174 -110.905036) (xy 276.677374 -110.905036) (xy 276.486874 -110.917736) (xy 276.486874 -111.019336)
			(xy 276.677374 -111.032036) (xy 276.728174 -111.032036)
		)
		(stroke
			(width 0)
			(type solid)
		)
		(fill yes)
		(layer "F.Cu")
		(net "M_D_DQ<35>")
	)
	(gr_poly
		(pts
			(xy 276.728174 -110.244636) (xy 276.677374 -110.244636) (xy 276.486874 -110.257336) (xy 276.486874 -110.358936)
			(xy 276.677374 -110.371636) (xy 276.728174 -110.371636)
		)
		(stroke
			(width 0)
			(type solid)
		)
		(fill yes)
		(layer "F.Cu")
		(net "M_D_DQ<35>")
	)
	(gr_poly
		(pts
			(xy 276.728174 -109.584236) (xy 276.677374 -109.584236) (xy 276.486874 -109.596936) (xy 276.486874 -109.698536)
			(xy 276.677374 -109.711236) (xy 276.728174 -109.711236)
		)
		(stroke
			(width 0)
			(type solid)
		)
		(fill yes)
		(layer "F.Cu")
		(net "M_D_DQ<35>")
	)
	(gr_poly
		(pts
			(xy 276.728174 -108.923836) (xy 276.677374 -108.923836) (xy 276.486874 -108.936536) (xy 276.486874 -109.038136)
			(xy 276.677374 -109.050836) (xy 276.728174 -109.050836)
		)
		(stroke
			(width 0)
			(type solid)
		)
		(fill yes)
		(layer "F.Cu")
		(net "M_D_DQ<35>")
	)
	(gr_poly
		(pts
			(xy 276.728174 -108.263436) (xy 276.677374 -108.263436) (xy 276.486874 -108.276136) (xy 276.486874 -108.377736)
			(xy 276.677374 -108.390436) (xy 276.728174 -108.390436)
		)
		(stroke
			(width 0)
			(type solid)
		)
		(fill yes)
		(layer "F.Cu")
		(net "M_D_DQ<35>")
	)
	(gr_poly
		(pts
			(xy 276.728174 -107.603036) (xy 276.677374 -107.603036) (xy 276.486874 -107.615736) (xy 276.486874 -107.717336)
			(xy 276.677374 -107.730036) (xy 276.728174 -107.730036)
		)
		(stroke
			(width 0)
			(type solid)
		)
		(fill yes)
		(layer "F.Cu")
		(net "M_D_DQ<35>")
	)
	(gr_poly
		(pts
			(xy 276.728174 -106.942636) (xy 276.677374 -106.942636) (xy 276.486874 -106.955336) (xy 276.486874 -107.056936)
			(xy 276.677374 -107.069636) (xy 276.728174 -107.069636)
		)
		(stroke
			(width 0)
			(type solid)
		)
		(fill yes)
		(layer "F.Cu")
		(net "M_D_DQ<35>")
	)
	(gr_poly
		(pts
			(xy 276.731984 -104.519984) (xy 276.731984 -104.291384) (xy 276.538944 -104.202484) (xy 276.494494 -104.202484)
			(xy 276.494494 -104.608884) (xy 276.538944 -104.608884)
		)
		(stroke
			(width 0)
			(type solid)
		)
		(fill yes)
		(layer "F.Cu")
		(net "M_D_DQ<39>")
	)
	(gr_poly
		(pts
			(xy 276.836124 -49.543208) (xy 276.785324 -49.543208) (xy 276.594824 -49.555908) (xy 276.594824 -49.657508)
			(xy 276.785324 -49.670208) (xy 276.836124 -49.670208)
		)
		(stroke
			(width 0)
			(type solid)
		)
		(fill yes)
		(layer "F.Cu")
		(net "M_B_DQ<44>")
	)
	(gr_poly
		(pts
			(xy 276.836124 -48.882808) (xy 276.785324 -48.882808) (xy 276.594824 -48.895508) (xy 276.594824 -48.997108)
			(xy 276.785324 -49.009808) (xy 276.836124 -49.009808)
		)
		(stroke
			(width 0)
			(type solid)
		)
		(fill yes)
		(layer "F.Cu")
		(net "M_B_DQ<44>")
	)
	(gr_poly
		(pts
			(xy 276.836124 -48.222408) (xy 276.785324 -48.222408) (xy 276.594824 -48.235108) (xy 276.594824 -48.336708)
			(xy 276.785324 -48.349408) (xy 276.836124 -48.349408)
		)
		(stroke
			(width 0)
			(type solid)
		)
		(fill yes)
		(layer "F.Cu")
		(net "M_B_DQ<44>")
	)
	(gr_poly
		(pts
			(xy 276.836124 -47.562008) (xy 276.785324 -47.562008) (xy 276.594824 -47.574708) (xy 276.594824 -47.676308)
			(xy 276.785324 -47.689008) (xy 276.836124 -47.689008)
		)
		(stroke
			(width 0)
			(type solid)
		)
		(fill yes)
		(layer "F.Cu")
		(net "M_B_DQ<44>")
	)
	(gr_poly
		(pts
			(xy 276.836124 -46.901608) (xy 276.785324 -46.901608) (xy 276.594824 -46.914308) (xy 276.594824 -47.015908)
			(xy 276.785324 -47.028608) (xy 276.836124 -47.028608)
		)
		(stroke
			(width 0)
			(type solid)
		)
		(fill yes)
		(layer "F.Cu")
		(net "M_B_DQ<44>")
	)
	(gr_poly
		(pts
			(xy 276.910038 -105.69829) (xy 276.878542 -105.666794) (xy 276.679406 -105.593134) (xy 276.517608 -105.754932)
			(xy 276.591268 -105.954068) (xy 276.622764 -105.985564)
		)
		(stroke
			(width 0)
			(type solid)
		)
		(fill yes)
		(layer "F.Cu")
		(net "M_D_DQ<34>")
	)
	(gr_poly
		(pts
			(xy 276.969474 -111.349536) (xy 276.969474 -111.247936) (xy 276.778974 -111.235236) (xy 276.728174 -111.235236)
			(xy 276.728174 -111.362236) (xy 276.778974 -111.362236)
		)
		(stroke
			(width 0)
			(type solid)
		)
		(fill yes)
		(layer "F.Cu")
		(net "M_D_DQ<35>")
	)
	(gr_poly
		(pts
			(xy 276.969474 -110.689136) (xy 276.969474 -110.587536) (xy 276.778974 -110.574836) (xy 276.728174 -110.574836)
			(xy 276.728174 -110.701836) (xy 276.778974 -110.701836)
		)
		(stroke
			(width 0)
			(type solid)
		)
		(fill yes)
		(layer "F.Cu")
		(net "M_D_DQ<35>")
	)
	(gr_poly
		(pts
			(xy 276.969474 -110.028736) (xy 276.969474 -109.927136) (xy 276.778974 -109.914436) (xy 276.728174 -109.914436)
			(xy 276.728174 -110.041436) (xy 276.778974 -110.041436)
		)
		(stroke
			(width 0)
			(type solid)
		)
		(fill yes)
		(layer "F.Cu")
		(net "M_D_DQ<35>")
	)
	(gr_poly
		(pts
			(xy 276.969474 -109.368336) (xy 276.969474 -109.266736) (xy 276.778974 -109.254036) (xy 276.728174 -109.254036)
			(xy 276.728174 -109.381036) (xy 276.778974 -109.381036)
		)
		(stroke
			(width 0)
			(type solid)
		)
		(fill yes)
		(layer "F.Cu")
		(net "M_D_DQ<35>")
	)
	(gr_poly
		(pts
			(xy 276.969474 -108.707936) (xy 276.969474 -108.606336) (xy 276.778974 -108.593636) (xy 276.728174 -108.593636)
			(xy 276.728174 -108.720636) (xy 276.778974 -108.720636)
		)
		(stroke
			(width 0)
			(type solid)
		)
		(fill yes)
		(layer "F.Cu")
		(net "M_D_DQ<35>")
	)
	(gr_poly
		(pts
			(xy 276.969474 -108.047536) (xy 276.969474 -107.945936) (xy 276.778974 -107.933236) (xy 276.728174 -107.933236)
			(xy 276.728174 -108.060236) (xy 276.778974 -108.060236)
		)
		(stroke
			(width 0)
			(type solid)
		)
		(fill yes)
		(layer "F.Cu")
		(net "M_D_DQ<35>")
	)
	(gr_poly
		(pts
			(xy 276.969474 -107.387136) (xy 276.969474 -107.285536) (xy 276.778974 -107.272836) (xy 276.728174 -107.272836)
			(xy 276.728174 -107.399836) (xy 276.778974 -107.399836)
		)
		(stroke
			(width 0)
			(type solid)
		)
		(fill yes)
		(layer "F.Cu")
		(net "M_D_DQ<35>")
	)
	(gr_poly
		(pts
			(xy 277.033228 -103.953818) (xy 277.071836 -103.931466) (xy 276.868382 -103.579676) (xy 276.830028 -103.601774)
			(xy 276.707346 -103.77551) (xy 276.821646 -103.973376)
		)
		(stroke
			(width 0)
			(type solid)
		)
		(fill yes)
		(layer "F.Cu")
		(net "M_D_DQ<34>")
	)
	(gr_poly
		(pts
			(xy 277.077424 -49.327308) (xy 277.077424 -49.225708) (xy 276.886924 -49.213008) (xy 276.836124 -49.213008)
			(xy 276.836124 -49.340008) (xy 276.886924 -49.340008)
		)
		(stroke
			(width 0)
			(type solid)
		)
		(fill yes)
		(layer "F.Cu")
		(net "M_B_DQ<44>")
	)
	(gr_poly
		(pts
			(xy 277.077424 -48.666908) (xy 277.077424 -48.565308) (xy 276.886924 -48.552608) (xy 276.836124 -48.552608)
			(xy 276.836124 -48.679608) (xy 276.886924 -48.679608)
		)
		(stroke
			(width 0)
			(type solid)
		)
		(fill yes)
		(layer "F.Cu")
		(net "M_B_DQ<44>")
	)
	(gr_poly
		(pts
			(xy 277.077424 -48.006508) (xy 277.077424 -47.904908) (xy 276.886924 -47.892208) (xy 276.836124 -47.892208)
			(xy 276.836124 -48.019208) (xy 276.886924 -48.019208)
		)
		(stroke
			(width 0)
			(type solid)
		)
		(fill yes)
		(layer "F.Cu")
		(net "M_B_DQ<44>")
	)
	(gr_poly
		(pts
			(xy 277.077424 -47.346108) (xy 277.077424 -47.244508) (xy 276.886924 -47.231808) (xy 276.836124 -47.231808)
			(xy 276.836124 -47.358808) (xy 276.886924 -47.358808)
		)
		(stroke
			(width 0)
			(type solid)
		)
		(fill yes)
		(layer "F.Cu")
		(net "M_B_DQ<44>")
	)
	(gr_poly
		(pts
			(xy 277.096728 -104.542336) (xy 277.052278 -104.542336) (xy 276.859238 -104.631236) (xy 276.859238 -104.859836)
			(xy 277.052278 -104.948736) (xy 277.096728 -104.948736)
		)
		(stroke
			(width 0)
			(type solid)
		)
		(fill yes)
		(layer "F.Cu")
		(net "M_D_DQ<34>")
	)
	(gr_poly
		(pts
			(xy 277.150322 -102.579424) (xy 277.150322 -102.358444) (xy 276.980142 -102.269544) (xy 276.935692 -102.269544)
			(xy 276.935692 -102.668324) (xy 276.980142 -102.668324)
		)
		(stroke
			(width 0)
			(type solid)
		)
		(fill yes)
		(layer "F.Cu")
		(net "M_D_DQ<35>")
	)
	(gr_poly
		(pts
			(xy 277.150322 -52.052474) (xy 277.150322 -51.831494) (xy 276.980142 -51.742594) (xy 276.935692 -51.742594)
			(xy 276.935692 -52.141374) (xy 276.980142 -52.141374)
		)
		(stroke
			(width 0)
			(type solid)
		)
		(fill yes)
		(layer "F.Cu")
		(net "M_B_DQ<45>")
	)
	(gr_poly
		(pts
			(xy 277.16353 -106.077258) (xy 277.08987 -105.878122) (xy 277.058374 -105.846626) (xy 276.7711 -106.1339)
			(xy 276.802596 -106.165396) (xy 277.001732 -106.239056)
		)
		(stroke
			(width 0)
			(type solid)
		)
		(fill yes)
		(layer "F.Cu")
		(net "M_D_DQ<35>")
	)
	(gr_poly
		(pts
			(xy 277.186136 -46.694598) (xy 277.060406 -46.550834) (xy 277.024338 -46.51502) (xy 276.934676 -46.604682)
			(xy 276.97049 -46.64075) (xy 277.114254 -46.76648)
		)
		(stroke
			(width 0)
			(type solid)
		)
		(fill yes)
		(layer "F.Cu")
		(net "M_B_DQ<44>")
	)
	(gr_poly
		(pts
			(xy 277.229824 -49.543208) (xy 277.179024 -49.543208) (xy 276.988524 -49.555908) (xy 276.988524 -49.657508)
			(xy 277.179024 -49.670208) (xy 277.229824 -49.670208)
		)
		(stroke
			(width 0)
			(type solid)
		)
		(fill yes)
		(layer "F.Cu")
		(net "M_B_DQ<45>")
	)
	(gr_poly
		(pts
			(xy 277.229824 -48.882808) (xy 277.179024 -48.882808) (xy 276.988524 -48.895508) (xy 276.988524 -48.997108)
			(xy 277.179024 -49.009808) (xy 277.229824 -49.009808)
		)
		(stroke
			(width 0)
			(type solid)
		)
		(fill yes)
		(layer "F.Cu")
		(net "M_B_DQ<45>")
	)
	(gr_poly
		(pts
			(xy 277.229824 -48.222408) (xy 277.179024 -48.222408) (xy 276.988524 -48.235108) (xy 276.988524 -48.336708)
			(xy 277.179024 -48.349408) (xy 277.229824 -48.349408)
		)
		(stroke
			(width 0)
			(type solid)
		)
		(fill yes)
		(layer "F.Cu")
		(net "M_B_DQ<45>")
	)
	(gr_poly
		(pts
			(xy 277.229824 -47.562008) (xy 277.179024 -47.562008) (xy 276.988524 -47.574708) (xy 276.988524 -47.676308)
			(xy 277.179024 -47.689008) (xy 277.229824 -47.689008)
		)
		(stroke
			(width 0)
			(type solid)
		)
		(fill yes)
		(layer "F.Cu")
		(net "M_B_DQ<45>")
	)
	(gr_poly
		(pts
			(xy 277.257764 -46.281594) (xy 277.22195 -46.245526) (xy 277.078186 -46.119796) (xy 277.006558 -46.191678)
			(xy 277.132034 -46.335442) (xy 277.168102 -46.371256)
		)
		(stroke
			(width 0)
			(type solid)
		)
		(fill yes)
		(layer "F.Cu")
		(net "M_B_DQ<44>")
	)
	(gr_poly
		(pts
			(xy 277.275036 -103.814118) (xy 277.397464 -103.640636) (xy 277.283164 -103.442516) (xy 277.071582 -103.462328)
			(xy 277.032974 -103.484426) (xy 277.236428 -103.83647)
		)
		(stroke
			(width 0)
			(type solid)
		)
		(fill yes)
		(layer "F.Cu")
		(net "M_D_DQ<35>")
	)
	(gr_poly
		(pts
			(xy 277.471124 -49.327308) (xy 277.471124 -49.225708) (xy 277.280624 -49.213008) (xy 277.229824 -49.213008)
			(xy 277.229824 -49.340008) (xy 277.280624 -49.340008)
		)
		(stroke
			(width 0)
			(type solid)
		)
		(fill yes)
		(layer "F.Cu")
		(net "M_B_DQ<45>")
	)
	(gr_poly
		(pts
			(xy 277.471124 -48.666908) (xy 277.471124 -48.565308) (xy 277.280624 -48.552608) (xy 277.229824 -48.552608)
			(xy 277.229824 -48.679608) (xy 277.280624 -48.679608)
		)
		(stroke
			(width 0)
			(type solid)
		)
		(fill yes)
		(layer "F.Cu")
		(net "M_B_DQ<45>")
	)
	(gr_poly
		(pts
			(xy 277.471124 -48.006508) (xy 277.471124 -47.904908) (xy 277.280624 -47.892208) (xy 277.229824 -47.892208)
			(xy 277.229824 -48.019208) (xy 277.280624 -48.019208)
		)
		(stroke
			(width 0)
			(type solid)
		)
		(fill yes)
		(layer "F.Cu")
		(net "M_B_DQ<45>")
	)
	(gr_poly
		(pts
			(xy 277.471124 -47.346108) (xy 277.471124 -47.244508) (xy 277.280624 -47.231808) (xy 277.229824 -47.231808)
			(xy 277.229824 -47.358808) (xy 277.280624 -47.358808)
		)
		(stroke
			(width 0)
			(type solid)
		)
		(fill yes)
		(layer "F.Cu")
		(net "M_B_DQ<45>")
	)
	(gr_poly
		(pts
			(xy 277.524718 -104.859836) (xy 277.524718 -104.631236) (xy 277.331678 -104.542336) (xy 277.287228 -104.542336)
			(xy 277.287228 -104.948736) (xy 277.331678 -104.948736)
		)
		(stroke
			(width 0)
			(type solid)
		)
		(fill yes)
		(layer "F.Cu")
		(net "M_D_DQ<35>")
	)
	(gr_poly
		(pts
			(xy 277.536402 -46.559978) (xy 277.500588 -46.524164) (xy 277.356824 -46.398434) (xy 277.284942 -46.470062)
			(xy 277.410672 -46.613826) (xy 277.446486 -46.649894)
		)
		(stroke
			(width 0)
			(type solid)
		)
		(fill yes)
		(layer "F.Cu")
		(net "M_B_DQ<45>")
	)
	(gr_poly
		(pts
			(xy 277.623524 -48.882808) (xy 277.572724 -48.882808) (xy 277.382224 -48.895508) (xy 277.382224 -48.997108)
			(xy 277.572724 -49.009808) (xy 277.623524 -49.009808)
		)
		(stroke
			(width 0)
			(type solid)
		)
		(fill yes)
		(layer "F.Cu")
		(net "M_B_DQ<40>")
	)
	(gr_poly
		(pts
			(xy 277.623524 -48.222408) (xy 277.572724 -48.222408) (xy 277.382224 -48.235108) (xy 277.382224 -48.336708)
			(xy 277.572724 -48.349408) (xy 277.623524 -48.349408)
		)
		(stroke
			(width 0)
			(type solid)
		)
		(fill yes)
		(layer "F.Cu")
		(net "M_B_DQ<40>")
	)
	(gr_poly
		(pts
			(xy 277.623524 -47.562008) (xy 277.572724 -47.562008) (xy 277.382224 -47.574708) (xy 277.382224 -47.676308)
			(xy 277.572724 -47.689008) (xy 277.623524 -47.689008)
		)
		(stroke
			(width 0)
			(type solid)
		)
		(fill yes)
		(layer "F.Cu")
		(net "M_B_DQ<40>")
	)
	(gr_poly
		(pts
			(xy 277.652988 -46.227492) (xy 277.527258 -46.083982) (xy 277.491444 -46.047914) (xy 277.401528 -46.13783)
			(xy 277.437596 -46.173644) (xy 277.581106 -46.299374)
		)
		(stroke
			(width 0)
			(type solid)
		)
		(fill yes)
		(layer "F.Cu")
		(net "M_B_DQ<44>")
	)
	(gr_poly
		(pts
			(xy 277.72487 -45.814488) (xy 277.689056 -45.778674) (xy 277.545292 -45.652944) (xy 277.47341 -45.724826)
			(xy 277.59914 -45.868336) (xy 277.634954 -45.904404)
		)
		(stroke
			(width 0)
			(type solid)
		)
		(fill yes)
		(layer "F.Cu")
		(net "M_B_DQ<44>")
	)
	(gr_poly
		(pts
			(xy 277.785322 -50.946558) (xy 277.740872 -50.946558) (xy 277.570692 -51.035458) (xy 277.570692 -51.256438)
			(xy 277.740872 -51.345338) (xy 277.785322 -51.345338)
		)
		(stroke
			(width 0)
			(type solid)
		)
		(fill yes)
		(layer "F.Cu")
		(net "M_B_DQ<40>")
	)
	(gr_poly
		(pts
			(xy 277.814786 -46.838616) (xy 277.778972 -46.802548) (xy 277.635208 -46.676818) (xy 277.56358 -46.7487)
			(xy 277.689056 -46.892464) (xy 277.725124 -46.928278)
		)
		(stroke
			(width 0)
			(type solid)
		)
		(fill yes)
		(layer "F.Cu")
		(net "M_B_DQ<40>")
	)
	(gr_poly
		(pts
			(xy 277.864824 -49.327308) (xy 277.864824 -49.225708) (xy 277.674324 -49.213008) (xy 277.623524 -49.213008)
			(xy 277.623524 -49.340008) (xy 277.674324 -49.340008)
		)
		(stroke
			(width 0)
			(type solid)
		)
		(fill yes)
		(layer "F.Cu")
		(net "M_B_DQ<40>")
	)
	(gr_poly
		(pts
			(xy 277.864824 -48.666908) (xy 277.864824 -48.565308) (xy 277.674324 -48.552608) (xy 277.623524 -48.552608)
			(xy 277.623524 -48.679608) (xy 277.674324 -48.679608)
		)
		(stroke
			(width 0)
			(type solid)
		)
		(fill yes)
		(layer "F.Cu")
		(net "M_B_DQ<40>")
	)
	(gr_poly
		(pts
			(xy 277.864824 -48.006508) (xy 277.864824 -47.904908) (xy 277.674324 -47.892208) (xy 277.623524 -47.892208)
			(xy 277.623524 -48.019208) (xy 277.674324 -48.019208)
		)
		(stroke
			(width 0)
			(type solid)
		)
		(fill yes)
		(layer "F.Cu")
		(net "M_B_DQ<40>")
	)
	(gr_poly
		(pts
			(xy 277.864824 -47.346108) (xy 277.864824 -47.244508) (xy 277.674324 -47.231808) (xy 277.623524 -47.231808)
			(xy 277.623524 -47.358808) (xy 277.674324 -47.358808)
		)
		(stroke
			(width 0)
			(type solid)
		)
		(fill yes)
		(layer "F.Cu")
		(net "M_B_DQ<40>")
	)
	(gr_poly
		(pts
			(xy 277.931626 -46.50613) (xy 277.805896 -46.362366) (xy 277.769828 -46.326552) (xy 277.680166 -46.416214)
			(xy 277.71598 -46.452282) (xy 277.859744 -46.578012)
		)
		(stroke
			(width 0)
			(type solid)
		)
		(fill yes)
		(layer "F.Cu")
		(net "M_B_DQ<45>")
	)
	(gr_poly
		(pts
			(xy 278.003254 -46.093126) (xy 277.96744 -46.057058) (xy 277.823676 -45.931328) (xy 277.751794 -46.00321)
			(xy 277.877524 -46.146974) (xy 277.913592 -46.182788)
		)
		(stroke
			(width 0)
			(type solid)
		)
		(fill yes)
		(layer "F.Cu")
		(net "M_B_DQ<45>")
	)
	(gr_poly
		(pts
			(xy 278.017224 -49.543208) (xy 277.966424 -49.543208) (xy 277.775924 -49.555908) (xy 277.775924 -49.657508)
			(xy 277.966424 -49.670208) (xy 278.017224 -49.670208)
		)
		(stroke
			(width 0)
			(type solid)
		)
		(fill yes)
		(layer "F.Cu")
		(net "M_B_DQ<41>")
	)
	(gr_poly
		(pts
			(xy 278.017224 -48.882808) (xy 277.966424 -48.882808) (xy 277.775924 -48.895508) (xy 277.775924 -48.997108)
			(xy 277.966424 -49.009808) (xy 278.017224 -49.009808)
		)
		(stroke
			(width 0)
			(type solid)
		)
		(fill yes)
		(layer "F.Cu")
		(net "M_B_DQ<41>")
	)
	(gr_poly
		(pts
			(xy 278.017224 -48.222408) (xy 277.966424 -48.222408) (xy 277.775924 -48.235108) (xy 277.775924 -48.336708)
			(xy 277.966424 -48.349408) (xy 278.017224 -48.349408)
		)
		(stroke
			(width 0)
			(type solid)
		)
		(fill yes)
		(layer "F.Cu")
		(net "M_B_DQ<41>")
	)
	(gr_poly
		(pts
			(xy 278.017224 -47.562008) (xy 277.966424 -47.562008) (xy 277.775924 -47.574708) (xy 277.775924 -47.676308)
			(xy 277.966424 -47.689008) (xy 278.017224 -47.689008)
		)
		(stroke
			(width 0)
			(type solid)
		)
		(fill yes)
		(layer "F.Cu")
		(net "M_B_DQ<41>")
	)
	(gr_poly
		(pts
			(xy 278.120094 -45.76064) (xy 277.994364 -45.616876) (xy 277.958296 -45.581062) (xy 277.868634 -45.670724)
			(xy 277.904448 -45.706792) (xy 278.048212 -45.832522)
		)
		(stroke
			(width 0)
			(type solid)
		)
		(fill yes)
		(layer "F.Cu")
		(net "M_B_DQ<44>")
	)
	(gr_poly
		(pts
			(xy 278.190452 -51.3842) (xy 278.190452 -51.16322) (xy 278.020272 -51.07432) (xy 277.975822 -51.07432)
			(xy 277.975822 -51.4731) (xy 278.020272 -51.4731)
		)
		(stroke
			(width 0)
			(type solid)
		)
		(fill yes)
		(layer "F.Cu")
		(net "M_B_DQ<41>")
	)
	(gr_poly
		(pts
			(xy 278.191722 -45.347636) (xy 278.155908 -45.311568) (xy 278.012144 -45.185838) (xy 277.940262 -45.25772)
			(xy 278.065992 -45.401484) (xy 278.10206 -45.437298)
		)
		(stroke
			(width 0)
			(type solid)
		)
		(fill yes)
		(layer "F.Cu")
		(net "M_B_DQ<44>")
	)
	(gr_poly
		(pts
			(xy 278.21001 -46.784514) (xy 278.08428 -46.641004) (xy 278.048466 -46.604936) (xy 277.95855 -46.694852)
			(xy 277.994618 -46.730666) (xy 278.138128 -46.856396)
		)
		(stroke
			(width 0)
			(type solid)
		)
		(fill yes)
		(layer "F.Cu")
		(net "M_B_DQ<40>")
	)
	(gr_poly
		(pts
			(xy 278.258524 -49.327308) (xy 278.258524 -49.225708) (xy 278.068024 -49.213008) (xy 278.017224 -49.213008)
			(xy 278.017224 -49.340008) (xy 278.068024 -49.340008)
		)
		(stroke
			(width 0)
			(type solid)
		)
		(fill yes)
		(layer "F.Cu")
		(net "M_B_DQ<41>")
	)
	(gr_poly
		(pts
			(xy 278.258524 -48.666908) (xy 278.258524 -48.565308) (xy 278.068024 -48.552608) (xy 278.017224 -48.552608)
			(xy 278.017224 -48.679608) (xy 278.068024 -48.679608)
		)
		(stroke
			(width 0)
			(type solid)
		)
		(fill yes)
		(layer "F.Cu")
		(net "M_B_DQ<41>")
	)
	(gr_poly
		(pts
			(xy 278.258524 -48.006508) (xy 278.258524 -47.904908) (xy 278.068024 -47.892208) (xy 278.017224 -47.892208)
			(xy 278.017224 -48.019208) (xy 278.068024 -48.019208)
		)
		(stroke
			(width 0)
			(type solid)
		)
		(fill yes)
		(layer "F.Cu")
		(net "M_B_DQ<41>")
	)
	(gr_poly
		(pts
			(xy 278.281892 -46.37151) (xy 278.246078 -46.335696) (xy 278.102314 -46.209966) (xy 278.030432 -46.281848)
			(xy 278.156162 -46.425358) (xy 278.191976 -46.461426)
		)
		(stroke
			(width 0)
			(type solid)
		)
		(fill yes)
		(layer "F.Cu")
		(net "M_B_DQ<40>")
	)
	(gr_poly
		(pts
			(xy 278.30272 -109.417104) (xy 278.25192 -109.417104) (xy 278.06142 -109.429804) (xy 278.06142 -109.531404)
			(xy 278.25192 -109.544104) (xy 278.30272 -109.544104)
		)
		(stroke
			(width 0)
			(type solid)
		)
		(fill yes)
		(layer "F.Cu")
		(net "M_E_DQ<44>")
	)
	(gr_poly
		(pts
			(xy 278.30272 -108.756704) (xy 278.25192 -108.756704) (xy 278.06142 -108.769404) (xy 278.06142 -108.871004)
			(xy 278.25192 -108.883704) (xy 278.30272 -108.883704)
		)
		(stroke
			(width 0)
			(type solid)
		)
		(fill yes)
		(layer "F.Cu")
		(net "M_E_DQ<44>")
	)
	(gr_poly
		(pts
			(xy 278.30272 -108.096304) (xy 278.25192 -108.096304) (xy 278.06142 -108.109004) (xy 278.06142 -108.210604)
			(xy 278.25192 -108.223304) (xy 278.30272 -108.223304)
		)
		(stroke
			(width 0)
			(type solid)
		)
		(fill yes)
		(layer "F.Cu")
		(net "M_E_DQ<44>")
	)
	(gr_poly
		(pts
			(xy 278.30272 -107.435904) (xy 278.25192 -107.435904) (xy 278.06142 -107.448604) (xy 278.06142 -107.550204)
			(xy 278.25192 -107.562904) (xy 278.30272 -107.562904)
		)
		(stroke
			(width 0)
			(type solid)
		)
		(fill yes)
		(layer "F.Cu")
		(net "M_E_DQ<44>")
	)
	(gr_poly
		(pts
			(xy 278.30272 -106.775504) (xy 278.25192 -106.775504) (xy 278.06142 -106.788204) (xy 278.06142 -106.889804)
			(xy 278.25192 -106.902504) (xy 278.30272 -106.902504)
		)
		(stroke
			(width 0)
			(type solid)
		)
		(fill yes)
		(layer "F.Cu")
		(net "M_E_DQ<44>")
	)
	(gr_poly
		(pts
			(xy 278.30272 -106.115104) (xy 278.25192 -106.115104) (xy 278.06142 -106.127804) (xy 278.06142 -106.229404)
			(xy 278.25192 -106.242104) (xy 278.30272 -106.242104)
		)
		(stroke
			(width 0)
			(type solid)
		)
		(fill yes)
		(layer "F.Cu")
		(net "M_E_DQ<44>")
	)
	(gr_poly
		(pts
			(xy 278.398478 -46.039024) (xy 278.272748 -45.895514) (xy 278.236934 -45.859446) (xy 278.147018 -45.949362)
			(xy 278.183086 -45.985176) (xy 278.326596 -46.110906)
		)
		(stroke
			(width 0)
			(type solid)
		)
		(fill yes)
		(layer "F.Cu")
		(net "M_B_DQ<45>")
	)
	(gr_poly
		(pts
			(xy 278.40432 -105.233216) (xy 278.35987 -105.233216) (xy 278.16683 -105.322116) (xy 278.16683 -105.550716)
			(xy 278.35987 -105.639616) (xy 278.40432 -105.639616)
		)
		(stroke
			(width 0)
			(type solid)
		)
		(fill yes)
		(layer "F.Cu")
		(net "M_E_DQ<44>")
	)
	(gr_poly
		(pts
			(xy 278.40432 -104.344216) (xy 278.35987 -104.344216) (xy 278.16683 -104.433116) (xy 278.16683 -104.661716)
			(xy 278.35987 -104.750616) (xy 278.40432 -104.750616)
		)
		(stroke
			(width 0)
			(type solid)
		)
		(fill yes)
		(layer "F.Cu")
		(net "M_E_DQ<44>")
	)
	(gr_poly
		(pts
			(xy 278.410924 -48.882808) (xy 278.360124 -48.882808) (xy 278.169624 -48.895508) (xy 278.169624 -48.997108)
			(xy 278.360124 -49.009808) (xy 278.410924 -49.009808)
		)
		(stroke
			(width 0)
			(type solid)
		)
		(fill yes)
		(layer "F.Cu")
		(net "M_B_DQS_DP<14>")
	)
	(gr_poly
		(pts
			(xy 278.410924 -48.222408) (xy 278.360124 -48.222408) (xy 278.169624 -48.235108) (xy 278.169624 -48.336708)
			(xy 278.360124 -48.349408) (xy 278.410924 -48.349408)
		)
		(stroke
			(width 0)
			(type solid)
		)
		(fill yes)
		(layer "F.Cu")
		(net "M_B_DQS_DP<14>")
	)
	(gr_poly
		(pts
			(xy 278.410924 -47.562008) (xy 278.360124 -47.562008) (xy 278.169624 -47.574708) (xy 278.169624 -47.676308)
			(xy 278.360124 -47.689008) (xy 278.410924 -47.689008)
		)
		(stroke
			(width 0)
			(type solid)
		)
		(fill yes)
		(layer "F.Cu")
		(net "M_B_DQS_DP<14>")
	)
	(gr_poly
		(pts
			(xy 278.47036 -45.62602) (xy 278.434292 -45.590206) (xy 278.290782 -45.464476) (xy 278.2189 -45.536358)
			(xy 278.34463 -45.679868) (xy 278.380444 -45.715936)
		)
		(stroke
			(width 0)
			(type solid)
		)
		(fill yes)
		(layer "F.Cu")
		(net "M_B_DQ<45>")
	)
	(gr_poly
		(pts
			(xy 278.488648 -47.063152) (xy 278.362918 -46.919388) (xy 278.32685 -46.883574) (xy 278.237188 -46.973236)
			(xy 278.273002 -47.009304) (xy 278.416766 -47.135034)
		)
		(stroke
			(width 0)
			(type solid)
		)
		(fill yes)
		(layer "F.Cu")
		(net "M_B_DQ<41>")
	)
	(gr_poly
		(pts
			(xy 278.511 -50.359056) (xy 278.46655 -50.359056) (xy 278.29637 -50.447956) (xy 278.29637 -50.668936)
			(xy 278.46655 -50.757836) (xy 278.511 -50.757836)
		)
		(stroke
			(width 0)
			(type solid)
		)
		(fill yes)
		(layer "F.Cu")
		(net "M_B_DQS_DP<14>")
	)
	(gr_poly
		(pts
			(xy 278.520398 -100.782374) (xy 278.475948 -100.782374) (xy 278.305514 -100.871274) (xy 278.305514 -101.092)
			(xy 278.47544 -101.181154) (xy 278.519636 -101.181154)
		)
		(stroke
			(width 0)
			(type solid)
		)
		(fill yes)
		(layer "F.Cu")
		(net "M_E_DQ<44>")
	)
	(gr_poly
		(pts
			(xy 278.54402 -109.201204) (xy 278.54402 -109.099604) (xy 278.35352 -109.086904) (xy 278.30272 -109.086904)
			(xy 278.30272 -109.213904) (xy 278.35352 -109.213904)
		)
		(stroke
			(width 0)
			(type solid)
		)
		(fill yes)
		(layer "F.Cu")
		(net "M_E_DQ<44>")
	)
	(gr_poly
		(pts
			(xy 278.54402 -108.540804) (xy 278.54402 -108.439204) (xy 278.35352 -108.426504) (xy 278.30272 -108.426504)
			(xy 278.30272 -108.553504) (xy 278.35352 -108.553504)
		)
		(stroke
			(width 0)
			(type solid)
		)
		(fill yes)
		(layer "F.Cu")
		(net "M_E_DQ<44>")
	)
	(gr_poly
		(pts
			(xy 278.54402 -107.880404) (xy 278.54402 -107.778804) (xy 278.35352 -107.766104) (xy 278.30272 -107.766104)
			(xy 278.30272 -107.893104) (xy 278.35352 -107.893104)
		)
		(stroke
			(width 0)
			(type solid)
		)
		(fill yes)
		(layer "F.Cu")
		(net "M_E_DQ<44>")
	)
	(gr_poly
		(pts
			(xy 278.54402 -107.220004) (xy 278.54402 -107.118404) (xy 278.35352 -107.105704) (xy 278.30272 -107.105704)
			(xy 278.30272 -107.232704) (xy 278.35352 -107.232704)
		)
		(stroke
			(width 0)
			(type solid)
		)
		(fill yes)
		(layer "F.Cu")
		(net "M_E_DQ<44>")
	)
	(gr_poly
		(pts
			(xy 278.54402 -106.559604) (xy 278.54402 -106.458004) (xy 278.35352 -106.445304) (xy 278.30272 -106.445304)
			(xy 278.30272 -106.572304) (xy 278.35352 -106.572304)
		)
		(stroke
			(width 0)
			(type solid)
		)
		(fill yes)
		(layer "F.Cu")
		(net "M_E_DQ<44>")
	)
	(gr_poly
		(pts
			(xy 278.560276 -46.650148) (xy 278.524462 -46.61408) (xy 278.380698 -46.48835) (xy 278.308816 -46.560232)
			(xy 278.434546 -46.703996) (xy 278.470614 -46.73981)
		)
		(stroke
			(width 0)
			(type solid)
		)
		(fill yes)
		(layer "F.Cu")
		(net "M_B_DQ<41>")
	)
	(gr_poly
		(pts
			(xy 278.586946 -45.293534) (xy 278.461216 -45.150024) (xy 278.425402 -45.113956) (xy 278.335486 -45.203872)
			(xy 278.371554 -45.239686) (xy 278.515064 -45.365416)
		)
		(stroke
			(width 0)
			(type solid)
		)
		(fill yes)
		(layer "F.Cu")
		(net "M_B_DQ<44>")
	)
	(gr_poly
		(pts
			(xy 278.652224 -49.327308) (xy 278.652224 -49.225708) (xy 278.461724 -49.213008) (xy 278.410924 -49.213008)
			(xy 278.410924 -49.340008) (xy 278.461724 -49.340008)
		)
		(stroke
			(width 0)
			(type solid)
		)
		(fill yes)
		(layer "F.Cu")
		(net "M_B_DQS_DP<14>")
	)
	(gr_poly
		(pts
			(xy 278.652224 -48.666908) (xy 278.652224 -48.565308) (xy 278.461724 -48.552608) (xy 278.410924 -48.552608)
			(xy 278.410924 -48.679608) (xy 278.461724 -48.679608)
		)
		(stroke
			(width 0)
			(type solid)
		)
		(fill yes)
		(layer "F.Cu")
		(net "M_B_DQS_DP<14>")
	)
	(gr_poly
		(pts
			(xy 278.652224 -48.006508) (xy 278.652224 -47.904908) (xy 278.461724 -47.892208) (xy 278.410924 -47.892208)
			(xy 278.410924 -48.019208) (xy 278.461724 -48.019208)
		)
		(stroke
			(width 0)
			(type solid)
		)
		(fill yes)
		(layer "F.Cu")
		(net "M_B_DQS_DP<14>")
	)
	(gr_poly
		(pts
			(xy 278.658828 -44.88053) (xy 278.62276 -44.844716) (xy 278.47925 -44.718986) (xy 278.407368 -44.790868)
			(xy 278.533098 -44.934378) (xy 278.568912 -44.970446)
		)
		(stroke
			(width 0)
			(type solid)
		)
		(fill yes)
		(layer "F.Cu")
		(net "M_B_DQ<44>")
	)
	(gr_poly
		(pts
			(xy 278.66213 -110.07471) (xy 278.78786 -109.9312) (xy 278.715978 -109.859318) (xy 278.572468 -109.985048)
			(xy 278.5364 -110.020862) (xy 278.626316 -110.110778)
		)
		(stroke
			(width 0)
			(type solid)
		)
		(fill yes)
		(layer "F.Cu")
		(net "M_E_DQ<44>")
	)
	(gr_poly
		(pts
			(xy 278.677116 -46.317662) (xy 278.551386 -46.173898) (xy 278.515318 -46.138084) (xy 278.425656 -46.227746)
			(xy 278.46147 -46.263814) (xy 278.605234 -46.389544)
		)
		(stroke
			(width 0)
			(type solid)
		)
		(fill yes)
		(layer "F.Cu")
		(net "M_B_DQ<40>")
	)
	(gr_poly
		(pts
			(xy 278.69642 -109.417104) (xy 278.64562 -109.417104) (xy 278.45512 -109.429804) (xy 278.45512 -109.531404)
			(xy 278.64562 -109.544104) (xy 278.69642 -109.544104)
		)
		(stroke
			(width 0)
			(type solid)
		)
		(fill yes)
		(layer "F.Cu")
		(net "M_E_DQ<45>")
	)
	(gr_poly
		(pts
			(xy 278.69642 -108.756704) (xy 278.64562 -108.756704) (xy 278.45512 -108.769404) (xy 278.45512 -108.871004)
			(xy 278.64562 -108.883704) (xy 278.69642 -108.883704)
		)
		(stroke
			(width 0)
			(type solid)
		)
		(fill yes)
		(layer "F.Cu")
		(net "M_E_DQ<45>")
	)
	(gr_poly
		(pts
			(xy 278.69642 -108.096304) (xy 278.64562 -108.096304) (xy 278.45512 -108.109004) (xy 278.45512 -108.210604)
			(xy 278.64562 -108.223304) (xy 278.69642 -108.223304)
		)
		(stroke
			(width 0)
			(type solid)
		)
		(fill yes)
		(layer "F.Cu")
		(net "M_E_DQ<45>")
	)
	(gr_poly
		(pts
			(xy 278.69642 -107.435904) (xy 278.64562 -107.435904) (xy 278.45512 -107.448604) (xy 278.45512 -107.550204)
			(xy 278.64562 -107.562904) (xy 278.69642 -107.562904)
		)
		(stroke
			(width 0)
			(type solid)
		)
		(fill yes)
		(layer "F.Cu")
		(net "M_E_DQ<45>")
	)
	(gr_poly
		(pts
			(xy 278.69642 -106.775504) (xy 278.64562 -106.775504) (xy 278.45512 -106.788204) (xy 278.45512 -106.889804)
			(xy 278.64562 -106.902504) (xy 278.69642 -106.902504)
		)
		(stroke
			(width 0)
			(type solid)
		)
		(fill yes)
		(layer "F.Cu")
		(net "M_E_DQ<45>")
	)
	(gr_poly
		(pts
			(xy 278.69642 -106.115104) (xy 278.64562 -106.115104) (xy 278.45512 -106.127804) (xy 278.45512 -106.229404)
			(xy 278.64562 -106.242104) (xy 278.69642 -106.242104)
		)
		(stroke
			(width 0)
			(type solid)
		)
		(fill yes)
		(layer "F.Cu")
		(net "M_E_DQ<45>")
	)
	(gr_poly
		(pts
			(xy 278.748744 -45.904658) (xy 278.71293 -45.86859) (xy 278.569166 -45.74286) (xy 278.497284 -45.814742)
			(xy 278.623014 -45.958506) (xy 278.659082 -45.99432)
		)
		(stroke
			(width 0)
			(type solid)
		)
		(fill yes)
		(layer "F.Cu")
		(net "M_B_DQ<40>")
	)
	(gr_poly
		(pts
			(xy 278.767032 -47.341536) (xy 278.641302 -47.198026) (xy 278.605488 -47.161958) (xy 278.515572 -47.251874)
			(xy 278.55164 -47.287688) (xy 278.69515 -47.413418)
		)
		(stroke
			(width 0)
			(type solid)
		)
		(fill yes)
		(layer "F.Cu")
		(net "M_B_DQS_DP<14>")
	)
	(gr_poly
		(pts
			(xy 278.804624 -48.882808) (xy 278.753824 -48.882808) (xy 278.563324 -48.895508) (xy 278.563324 -48.997108)
			(xy 278.753824 -49.009808) (xy 278.804624 -49.009808)
		)
		(stroke
			(width 0)
			(type solid)
		)
		(fill yes)
		(layer "F.Cu")
		(net "M_B_DQS_DN<14>")
	)
	(gr_poly
		(pts
			(xy 278.804624 -48.222408) (xy 278.753824 -48.222408) (xy 278.563324 -48.235108) (xy 278.563324 -48.336708)
			(xy 278.753824 -48.349408) (xy 278.804624 -48.349408)
		)
		(stroke
			(width 0)
			(type solid)
		)
		(fill yes)
		(layer "F.Cu")
		(net "M_B_DQS_DN<14>")
	)
	(gr_poly
		(pts
			(xy 278.823674 -110.380018) (xy 278.859742 -110.344204) (xy 278.769826 -110.254288) (xy 278.734012 -110.290356)
			(xy 278.608282 -110.433866) (xy 278.680164 -110.505748)
		)
		(stroke
			(width 0)
			(type solid)
		)
		(fill yes)
		(layer "F.Cu")
		(net "M_E_DQ<44>")
	)
	(gr_poly
		(pts
			(xy 278.83231 -105.550716) (xy 278.83231 -105.322116) (xy 278.63927 -105.233216) (xy 278.59482 -105.233216)
			(xy 278.59482 -105.639616) (xy 278.63927 -105.639616)
		)
		(stroke
			(width 0)
			(type solid)
		)
		(fill yes)
		(layer "F.Cu")
		(net "M_E_DQ<45>")
	)
	(gr_poly
		(pts
			(xy 278.83231 -104.661716) (xy 278.83231 -104.433116) (xy 278.63927 -104.344216) (xy 278.59482 -104.344216)
			(xy 278.59482 -104.750616) (xy 278.63927 -104.750616)
		)
		(stroke
			(width 0)
			(type solid)
		)
		(fill yes)
		(layer "F.Cu")
		(net "M_E_DQ<45>")
	)
	(gr_poly
		(pts
			(xy 278.838914 -46.928532) (xy 278.8031 -46.892718) (xy 278.659336 -46.766988) (xy 278.587454 -46.83887)
			(xy 278.713184 -46.98238) (xy 278.748998 -47.018448)
		)
		(stroke
			(width 0)
			(type solid)
		)
		(fill yes)
		(layer "F.Cu")
		(net "M_B_DQS_DP<14>")
	)
	(gr_poly
		(pts
			(xy 278.865584 -45.572172) (xy 278.739854 -45.428408) (xy 278.703786 -45.392594) (xy 278.614124 -45.482256)
			(xy 278.649938 -45.518324) (xy 278.793702 -45.644054)
		)
		(stroke
			(width 0)
			(type solid)
		)
		(fill yes)
		(layer "F.Cu")
		(net "M_B_DQ<45>")
	)
	(gr_poly
		(pts
			(xy 278.86787 -102.577138) (xy 278.86787 -102.356158) (xy 278.69769 -102.267258) (xy 278.65324 -102.267258)
			(xy 278.65324 -102.666038) (xy 278.69769 -102.666038)
		)
		(stroke
			(width 0)
			(type solid)
		)
		(fill yes)
		(layer "F.Cu")
		(net "M_E_DQ<45>")
	)
	(gr_poly
		(pts
			(xy 278.913844 -101.571298) (xy 279.007316 -101.371146) (xy 278.890476 -101.218746) (xy 278.850344 -101.19995)
			(xy 278.681688 -101.561138) (xy 278.722074 -101.579934)
		)
		(stroke
			(width 0)
			(type solid)
		)
		(fill yes)
		(layer "F.Cu")
		(net "M_E_DQ<45>")
	)
	(gr_poly
		(pts
			(xy 278.91613 -50.682652) (xy 278.91613 -50.461672) (xy 278.74595 -50.372772) (xy 278.7015 -50.372772)
			(xy 278.7015 -50.771552) (xy 278.74595 -50.771552)
		)
		(stroke
			(width 0)
			(type solid)
		)
		(fill yes)
		(layer "F.Cu")
		(net "M_B_DQS_DN<14>")
	)
	(gr_poly
		(pts
			(xy 278.937212 -45.159168) (xy 278.901398 -45.1231) (xy 278.757634 -44.99737) (xy 278.685752 -45.069252)
			(xy 278.811482 -45.213016) (xy 278.84755 -45.24883)
		)
		(stroke
			(width 0)
			(type solid)
		)
		(fill yes)
		(layer "F.Cu")
		(net "M_B_DQ<45>")
	)
	(gr_poly
		(pts
			(xy 278.93772 -109.201204) (xy 278.93772 -109.099604) (xy 278.74722 -109.086904) (xy 278.69642 -109.086904)
			(xy 278.69642 -109.213904) (xy 278.74722 -109.213904)
		)
		(stroke
			(width 0)
			(type solid)
		)
		(fill yes)
		(layer "F.Cu")
		(net "M_E_DQ<45>")
	)
	(gr_poly
		(pts
			(xy 278.93772 -108.540804) (xy 278.93772 -108.439204) (xy 278.74722 -108.426504) (xy 278.69642 -108.426504)
			(xy 278.69642 -108.553504) (xy 278.74722 -108.553504)
		)
		(stroke
			(width 0)
			(type solid)
		)
		(fill yes)
		(layer "F.Cu")
		(net "M_E_DQ<45>")
	)
	(gr_poly
		(pts
			(xy 278.93772 -107.880404) (xy 278.93772 -107.778804) (xy 278.74722 -107.766104) (xy 278.69642 -107.766104)
			(xy 278.69642 -107.893104) (xy 278.74722 -107.893104)
		)
		(stroke
			(width 0)
			(type solid)
		)
		(fill yes)
		(layer "F.Cu")
		(net "M_E_DQ<45>")
	)
	(gr_poly
		(pts
			(xy 278.93772 -107.220004) (xy 278.93772 -107.118404) (xy 278.74722 -107.105704) (xy 278.69642 -107.105704)
			(xy 278.69642 -107.232704) (xy 278.74722 -107.232704)
		)
		(stroke
			(width 0)
			(type solid)
		)
		(fill yes)
		(layer "F.Cu")
		(net "M_E_DQ<45>")
	)
	(gr_poly
		(pts
			(xy 278.93772 -106.559604) (xy 278.93772 -106.458004) (xy 278.74722 -106.445304) (xy 278.69642 -106.445304)
			(xy 278.69642 -106.572304) (xy 278.74722 -106.572304)
		)
		(stroke
			(width 0)
			(type solid)
		)
		(fill yes)
		(layer "F.Cu")
		(net "M_E_DQ<45>")
	)
	(gr_poly
		(pts
			(xy 278.940768 -109.796326) (xy 279.066498 -109.652562) (xy 278.994616 -109.58068) (xy 278.850852 -109.70641)
			(xy 278.815038 -109.742478) (xy 278.9047 -109.83214)
		)
		(stroke
			(width 0)
			(type solid)
		)
		(fill yes)
		(layer "F.Cu")
		(net "M_E_DQ<45>")
	)
	(gr_poly
		(pts
			(xy 278.9555 -46.596046) (xy 278.82977 -46.452536) (xy 278.793956 -46.416468) (xy 278.70404 -46.506384)
			(xy 278.740108 -46.542198) (xy 278.883618 -46.667928)
		)
		(stroke
			(width 0)
			(type solid)
		)
		(fill yes)
		(layer "F.Cu")
		(net "M_B_DQ<41>")
	)
	(gr_poly
		(pts
			(xy 279.027382 -46.183042) (xy 278.991314 -46.147228) (xy 278.847804 -46.021498) (xy 278.775922 -46.09338)
			(xy 278.901652 -46.23689) (xy 278.937466 -46.272958)
		)
		(stroke
			(width 0)
			(type solid)
		)
		(fill yes)
		(layer "F.Cu")
		(net "M_B_DQ<41>")
	)
	(gr_poly
		(pts
			(xy 279.045924 -49.327308) (xy 279.045924 -49.225708) (xy 278.855424 -49.213008) (xy 278.804624 -49.213008)
			(xy 278.804624 -49.340008) (xy 278.855424 -49.340008)
		)
		(stroke
			(width 0)
			(type solid)
		)
		(fill yes)
		(layer "F.Cu")
		(net "M_B_DQS_DN<14>")
	)
	(gr_poly
		(pts
			(xy 279.045924 -48.666908) (xy 279.045924 -48.565308) (xy 278.855424 -48.552608) (xy 278.804624 -48.552608)
			(xy 278.804624 -48.679608) (xy 278.855424 -48.679608)
		)
		(stroke
			(width 0)
			(type solid)
		)
		(fill yes)
		(layer "F.Cu")
		(net "M_B_DQS_DN<14>")
	)
	(gr_poly
		(pts
			(xy 279.045924 -48.006508) (xy 279.045924 -47.904908) (xy 278.855424 -47.892208) (xy 278.804624 -47.892208)
			(xy 278.804624 -48.019208) (xy 278.855424 -48.019208)
		)
		(stroke
			(width 0)
			(type solid)
		)
		(fill yes)
		(layer "F.Cu")
		(net "M_B_DQS_DN<14>")
	)
	(gr_poly
		(pts
			(xy 279.054052 -44.826682) (xy 278.928322 -44.682918) (xy 278.892254 -44.647104) (xy 278.802592 -44.736766)
			(xy 278.838406 -44.772834) (xy 278.98217 -44.898564)
		)
		(stroke
			(width 0)
			(type solid)
		)
		(fill yes)
		(layer "F.Cu")
		(net "M_B_DQ<44>")
	)
	(gr_poly
		(pts
			(xy 279.09012 -108.756704) (xy 279.03932 -108.756704) (xy 278.84882 -108.769404) (xy 278.84882 -108.871004)
			(xy 279.03932 -108.883704) (xy 279.09012 -108.883704)
		)
		(stroke
			(width 0)
			(type solid)
		)
		(fill yes)
		(layer "F.Cu")
		(net "M_E_DQ<40>")
	)
	(gr_poly
		(pts
			(xy 279.09012 -108.096304) (xy 279.03932 -108.096304) (xy 278.84882 -108.109004) (xy 278.84882 -108.210604)
			(xy 279.03932 -108.223304) (xy 279.09012 -108.223304)
		)
		(stroke
			(width 0)
			(type solid)
		)
		(fill yes)
		(layer "F.Cu")
		(net "M_E_DQ<40>")
	)
	(gr_poly
		(pts
			(xy 279.09012 -107.435904) (xy 279.03932 -107.435904) (xy 278.84882 -107.448604) (xy 278.84882 -107.550204)
			(xy 279.03932 -107.562904) (xy 279.09012 -107.562904)
		)
		(stroke
			(width 0)
			(type solid)
		)
		(fill yes)
		(layer "F.Cu")
		(net "M_E_DQ<40>")
	)
	(gr_poly
		(pts
			(xy 279.09012 -106.775504) (xy 279.03932 -106.775504) (xy 278.84882 -106.788204) (xy 278.84882 -106.889804)
			(xy 279.03932 -106.902504) (xy 279.09012 -106.902504)
		)
		(stroke
			(width 0)
			(type solid)
		)
		(fill yes)
		(layer "F.Cu")
		(net "M_E_DQ<40>")
	)
	(gr_poly
		(pts
			(xy 279.09012 -106.115104) (xy 279.03932 -106.115104) (xy 278.84882 -106.127804) (xy 278.84882 -106.229404)
			(xy 279.03932 -106.242104) (xy 279.09012 -106.242104)
		)
		(stroke
			(width 0)
			(type solid)
		)
		(fill yes)
		(layer "F.Cu")
		(net "M_E_DQ<40>")
	)
	(gr_poly
		(pts
			(xy 279.102312 -110.101634) (xy 279.138126 -110.065566) (xy 279.048464 -109.975904) (xy 279.012396 -110.011718)
			(xy 278.886666 -110.155482) (xy 278.958548 -110.227364)
		)
		(stroke
			(width 0)
			(type solid)
		)
		(fill yes)
		(layer "F.Cu")
		(net "M_E_DQ<45>")
	)
	(gr_poly
		(pts
			(xy 279.117298 -47.20717) (xy 279.081484 -47.171102) (xy 278.93772 -47.045372) (xy 278.865838 -47.117254)
			(xy 278.991568 -47.261018) (xy 279.027636 -47.296832)
		)
		(stroke
			(width 0)
			(type solid)
		)
		(fill yes)
		(layer "F.Cu")
		(net "M_B_DQS_DN<14>")
	)
	(gr_poly
		(pts
			(xy 279.12568 -44.413678) (xy 279.089866 -44.37761) (xy 278.946102 -44.25188) (xy 278.87422 -44.323762)
			(xy 278.99995 -44.467526) (xy 279.036018 -44.50334)
		)
		(stroke
			(width 0)
			(type solid)
		)
		(fill yes)
		(layer "F.Cu")
		(net "M_B_DQ<44>")
	)
	(gr_poly
		(pts
			(xy 279.129236 -110.541816) (xy 279.254966 -110.398052) (xy 279.183084 -110.32617) (xy 279.03932 -110.4519)
			(xy 279.003506 -110.487968) (xy 279.093168 -110.57763)
		)
		(stroke
			(width 0)
			(type solid)
		)
		(fill yes)
		(layer "F.Cu")
		(net "M_E_DQ<44>")
	)
	(gr_poly
		(pts
			(xy 279.143968 -45.850556) (xy 279.018238 -45.707046) (xy 278.982424 -45.670978) (xy 278.892508 -45.760894)
			(xy 278.928576 -45.796708) (xy 279.072086 -45.922438)
		)
		(stroke
			(width 0)
			(type solid)
		)
		(fill yes)
		(layer "F.Cu")
		(net "M_B_DQ<40>")
	)
	(gr_poly
		(pts
			(xy 279.19172 -105.108248) (xy 279.14727 -105.108248) (xy 278.95423 -105.197148) (xy 278.95423 -105.425748)
			(xy 279.14727 -105.514648) (xy 279.19172 -105.514648)
		)
		(stroke
			(width 0)
			(type solid)
		)
		(fill yes)
		(layer "F.Cu")
		(net "M_E_DQ<40>")
	)
	(gr_poly
		(pts
			(xy 279.19172 -104.117648) (xy 279.14727 -104.117648) (xy 278.95423 -104.206548) (xy 278.95423 -104.435148)
			(xy 279.14727 -104.524048) (xy 279.19172 -104.524048)
		)
		(stroke
			(width 0)
			(type solid)
		)
		(fill yes)
		(layer "F.Cu")
		(net "M_E_DQ<40>")
	)
	(gr_poly
		(pts
			(xy 279.198324 -48.882808) (xy 279.147524 -48.882808) (xy 278.957024 -48.895508) (xy 278.957024 -48.997108)
			(xy 279.147524 -49.009808) (xy 279.198324 -49.009808)
		)
		(stroke
			(width 0)
			(type solid)
		)
		(fill yes)
		(layer "F.Cu")
		(net "M_B_DQS_DN<5>")
	)
	(gr_poly
		(pts
			(xy 279.198324 -48.222408) (xy 279.147524 -48.222408) (xy 278.957024 -48.235108) (xy 278.957024 -48.336708)
			(xy 279.147524 -48.349408) (xy 279.198324 -48.349408)
		)
		(stroke
			(width 0)
			(type solid)
		)
		(fill yes)
		(layer "F.Cu")
		(net "M_B_DQS_DN<5>")
	)
	(gr_poly
		(pts
			(xy 279.21585 -45.437552) (xy 279.179782 -45.401738) (xy 279.036272 -45.276008) (xy 278.96439 -45.34789)
			(xy 279.09012 -45.4914) (xy 279.125934 -45.527468)
		)
		(stroke
			(width 0)
			(type solid)
		)
		(fill yes)
		(layer "F.Cu")
		(net "M_B_DQ<40>")
	)
	(gr_poly
		(pts
			(xy 279.234138 -46.874684) (xy 279.108408 -46.73092) (xy 279.07234 -46.695106) (xy 278.982678 -46.784768)
			(xy 279.018492 -46.820836) (xy 279.162256 -46.946566)
		)
		(stroke
			(width 0)
			(type solid)
		)
		(fill yes)
		(layer "F.Cu")
		(net "M_B_DQS_DP<14>")
	)
	(gr_poly
		(pts
			(xy 279.29078 -110.847124) (xy 279.326594 -110.811056) (xy 279.236932 -110.721394) (xy 279.200864 -110.757208)
			(xy 279.075134 -110.900972) (xy 279.147016 -110.972854)
		)
		(stroke
			(width 0)
			(type solid)
		)
		(fill yes)
		(layer "F.Cu")
		(net "M_E_DQ<44>")
	)
	(gr_poly
		(pts
			(xy 279.297384 -50.623724) (xy 279.252934 -50.623724) (xy 279.082754 -50.712624) (xy 279.082754 -50.933604)
			(xy 279.252934 -51.022504) (xy 279.297384 -51.022504)
		)
		(stroke
			(width 0)
			(type solid)
		)
		(fill yes)
		(layer "F.Cu")
		(net "M_B_DQS_DN<5>")
	)
	(gr_poly
		(pts
			(xy 279.305766 -46.46168) (xy 279.269952 -46.425612) (xy 279.126188 -46.299882) (xy 279.054306 -46.371764)
			(xy 279.180036 -46.515528) (xy 279.216104 -46.551342)
		)
		(stroke
			(width 0)
			(type solid)
		)
		(fill yes)
		(layer "F.Cu")
		(net "M_B_DQS_DP<14>")
	)
	(gr_poly
		(pts
			(xy 279.33142 -109.201204) (xy 279.33142 -109.099604) (xy 279.14092 -109.086904) (xy 279.09012 -109.086904)
			(xy 279.09012 -109.213904) (xy 279.14092 -109.213904)
		)
		(stroke
			(width 0)
			(type solid)
		)
		(fill yes)
		(layer "F.Cu")
		(net "M_E_DQ<40>")
	)
	(gr_poly
		(pts
			(xy 279.33142 -108.540804) (xy 279.33142 -108.439204) (xy 279.14092 -108.426504) (xy 279.09012 -108.426504)
			(xy 279.09012 -108.553504) (xy 279.14092 -108.553504)
		)
		(stroke
			(width 0)
			(type solid)
		)
		(fill yes)
		(layer "F.Cu")
		(net "M_E_DQ<40>")
	)
	(gr_poly
		(pts
			(xy 279.33142 -107.880404) (xy 279.33142 -107.778804) (xy 279.14092 -107.766104) (xy 279.09012 -107.766104)
			(xy 279.09012 -107.893104) (xy 279.14092 -107.893104)
		)
		(stroke
			(width 0)
			(type solid)
		)
		(fill yes)
		(layer "F.Cu")
		(net "M_E_DQ<40>")
	)
	(gr_poly
		(pts
			(xy 279.33142 -107.220004) (xy 279.33142 -107.118404) (xy 279.14092 -107.105704) (xy 279.09012 -107.105704)
			(xy 279.09012 -107.232704) (xy 279.14092 -107.232704)
		)
		(stroke
			(width 0)
			(type solid)
		)
		(fill yes)
		(layer "F.Cu")
		(net "M_E_DQ<40>")
	)
	(gr_poly
		(pts
			(xy 279.33142 -106.559604) (xy 279.33142 -106.458004) (xy 279.14092 -106.445304) (xy 279.09012 -106.445304)
			(xy 279.09012 -106.572304) (xy 279.14092 -106.572304)
		)
		(stroke
			(width 0)
			(type solid)
		)
		(fill yes)
		(layer "F.Cu")
		(net "M_E_DQ<40>")
	)
	(gr_poly
		(pts
			(xy 279.332436 -45.105066) (xy 279.206706 -44.961556) (xy 279.170892 -44.925488) (xy 279.080976 -45.015404)
			(xy 279.11679 -45.051218) (xy 279.260554 -45.176948)
		)
		(stroke
			(width 0)
			(type solid)
		)
		(fill yes)
		(layer "F.Cu")
		(net "M_B_DQ<45>")
	)
	(gr_poly
		(pts
			(xy 279.380696 -109.822996) (xy 279.416764 -109.787182) (xy 279.326848 -109.697266) (xy 279.291034 -109.733334)
			(xy 279.165304 -109.876844) (xy 279.237186 -109.948726)
		)
		(stroke
			(width 0)
			(type solid)
		)
		(fill yes)
		(layer "F.Cu")
		(net "M_E_DQ<40>")
	)
	(gr_poly
		(pts
			(xy 279.395936 -47.485554) (xy 279.360122 -47.44974) (xy 279.216358 -47.32401) (xy 279.144476 -47.395892)
			(xy 279.270206 -47.539402) (xy 279.30602 -47.57547)
		)
		(stroke
			(width 0)
			(type solid)
		)
		(fill yes)
		(layer "F.Cu")
		(net "M_B_DQS_DN<5>")
	)
	(gr_poly
		(pts
			(xy 279.404318 -44.692062) (xy 279.36825 -44.656248) (xy 279.22474 -44.530518) (xy 279.152858 -44.6024)
			(xy 279.278588 -44.74591) (xy 279.314402 -44.781978)
		)
		(stroke
			(width 0)
			(type solid)
		)
		(fill yes)
		(layer "F.Cu")
		(net "M_B_DQ<45>")
	)
	(gr_poly
		(pts
			(xy 279.40762 -110.263178) (xy 279.53335 -110.119668) (xy 279.461468 -110.047786) (xy 279.317704 -110.173516)
			(xy 279.28189 -110.20933) (xy 279.371806 -110.299246)
		)
		(stroke
			(width 0)
			(type solid)
		)
		(fill yes)
		(layer "F.Cu")
		(net "M_E_DQ<45>")
	)
	(gr_poly
		(pts
			(xy 279.422606 -46.129194) (xy 279.296876 -45.98543) (xy 279.260808 -45.949616) (xy 279.171146 -46.039278)
			(xy 279.20696 -46.075346) (xy 279.350724 -46.201076)
		)
		(stroke
			(width 0)
			(type solid)
		)
		(fill yes)
		(layer "F.Cu")
		(net "M_B_DQ<41>")
	)
	(gr_poly
		(pts
			(xy 279.429972 -100.531168) (xy 279.4254 -100.486718) (xy 279.31999 -100.326444) (xy 279.10028 -100.348542)
			(xy 279.028906 -100.526596) (xy 279.033224 -100.570792)
		)
		(stroke
			(width 0)
			(type solid)
		)
		(fill yes)
		(layer "F.Cu")
		(net "M_E_DQ<44>")
	)
	(gr_poly
		(pts
			(xy 279.439624 -49.327308) (xy 279.439624 -49.225708) (xy 279.249124 -49.213008) (xy 279.198324 -49.213008)
			(xy 279.198324 -49.340008) (xy 279.249124 -49.340008)
		)
		(stroke
			(width 0)
			(type solid)
		)
		(fill yes)
		(layer "F.Cu")
		(net "M_B_DQS_DN<5>")
	)
	(gr_poly
		(pts
			(xy 279.439624 -48.666908) (xy 279.439624 -48.565308) (xy 279.249124 -48.552608) (xy 279.198324 -48.552608)
			(xy 279.198324 -48.679608) (xy 279.249124 -48.679608)
		)
		(stroke
			(width 0)
			(type solid)
		)
		(fill yes)
		(layer "F.Cu")
		(net "M_B_DQS_DN<5>")
	)
	(gr_poly
		(pts
			(xy 279.439624 -48.006508) (xy 279.439624 -47.904908) (xy 279.249124 -47.892208) (xy 279.198324 -47.892208)
			(xy 279.198324 -48.019208) (xy 279.249124 -48.019208)
		)
		(stroke
			(width 0)
			(type solid)
		)
		(fill yes)
		(layer "F.Cu")
		(net "M_B_DQS_DN<5>")
	)
	(gr_poly
		(pts
			(xy 279.48382 -108.756704) (xy 279.43302 -108.756704) (xy 279.24252 -108.769404) (xy 279.24252 -108.871004)
			(xy 279.43302 -108.883704) (xy 279.48382 -108.883704)
		)
		(stroke
			(width 0)
			(type solid)
		)
		(fill yes)
		(layer "F.Cu")
		(net "M_E_DQ<41>")
	)
	(gr_poly
		(pts
			(xy 279.48382 -108.096304) (xy 279.43302 -108.096304) (xy 279.24252 -108.109004) (xy 279.24252 -108.210604)
			(xy 279.43302 -108.223304) (xy 279.48382 -108.223304)
		)
		(stroke
			(width 0)
			(type solid)
		)
		(fill yes)
		(layer "F.Cu")
		(net "M_E_DQ<41>")
	)
	(gr_poly
		(pts
			(xy 279.48382 -107.435904) (xy 279.43302 -107.435904) (xy 279.24252 -107.448604) (xy 279.24252 -107.550204)
			(xy 279.43302 -107.562904) (xy 279.48382 -107.562904)
		)
		(stroke
			(width 0)
			(type solid)
		)
		(fill yes)
		(layer "F.Cu")
		(net "M_E_DQ<41>")
	)
	(gr_poly
		(pts
			(xy 279.48382 -106.775504) (xy 279.43302 -106.775504) (xy 279.24252 -106.788204) (xy 279.24252 -106.889804)
			(xy 279.43302 -106.902504) (xy 279.48382 -106.902504)
		)
		(stroke
			(width 0)
			(type solid)
		)
		(fill yes)
		(layer "F.Cu")
		(net "M_E_DQ<41>")
	)
	(gr_poly
		(pts
			(xy 279.48382 -106.115104) (xy 279.43302 -106.115104) (xy 279.24252 -106.127804) (xy 279.24252 -106.229404)
			(xy 279.43302 -106.242104) (xy 279.48382 -106.242104)
		)
		(stroke
			(width 0)
			(type solid)
		)
		(fill yes)
		(layer "F.Cu")
		(net "M_E_DQ<41>")
	)
	(gr_poly
		(pts
			(xy 279.494234 -45.71619) (xy 279.45842 -45.680122) (xy 279.314656 -45.554392) (xy 279.242774 -45.626274)
			(xy 279.368504 -45.770038) (xy 279.404572 -45.805852)
		)
		(stroke
			(width 0)
			(type solid)
		)
		(fill yes)
		(layer "F.Cu")
		(net "M_B_DQ<41>")
	)
	(gr_poly
		(pts
			(xy 279.512522 -47.153068) (xy 279.386792 -47.009558) (xy 279.350978 -46.97349) (xy 279.261062 -47.063406)
			(xy 279.29713 -47.09922) (xy 279.44064 -47.22495)
		)
		(stroke
			(width 0)
			(type solid)
		)
		(fill yes)
		(layer "F.Cu")
		(net "M_B_DQS_DN<14>")
	)
	(gr_poly
		(pts
			(xy 279.520904 -44.35983) (xy 279.395174 -44.216066) (xy 279.35936 -44.179998) (xy 279.269444 -44.269914)
			(xy 279.305258 -44.305728) (xy 279.449022 -44.431458)
		)
		(stroke
			(width 0)
			(type solid)
		)
		(fill yes)
		(layer "F.Cu")
		(net "M_B_DQ<44>")
	)
	(gr_poly
		(pts
			(xy 279.569164 -110.568486) (xy 279.605232 -110.532672) (xy 279.515316 -110.442756) (xy 279.479502 -110.478824)
			(xy 279.353772 -110.622334) (xy 279.425654 -110.694216)
		)
		(stroke
			(width 0)
			(type solid)
		)
		(fill yes)
		(layer "F.Cu")
		(net "M_E_DQ<45>")
	)
	(gr_poly
		(pts
			(xy 279.584404 -46.740064) (xy 279.548336 -46.70425) (xy 279.404826 -46.57852) (xy 279.332944 -46.650402)
			(xy 279.458674 -46.793912) (xy 279.494488 -46.82998)
		)
		(stroke
			(width 0)
			(type solid)
		)
		(fill yes)
		(layer "F.Cu")
		(net "M_B_DQS_DN<14>")
	)
	(gr_poly
		(pts
			(xy 279.592024 -48.882808) (xy 279.541224 -48.882808) (xy 279.350724 -48.895508) (xy 279.350724 -48.997108)
			(xy 279.541224 -49.009808) (xy 279.592024 -49.009808)
		)
		(stroke
			(width 0)
			(type solid)
		)
		(fill yes)
		(layer "F.Cu")
		(net "M_B_DQS_DP<5>")
	)
	(gr_poly
		(pts
			(xy 279.592024 -48.222408) (xy 279.541224 -48.222408) (xy 279.350724 -48.235108) (xy 279.350724 -48.336708)
			(xy 279.541224 -48.349408) (xy 279.592024 -48.349408)
		)
		(stroke
			(width 0)
			(type solid)
		)
		(fill yes)
		(layer "F.Cu")
		(net "M_B_DQS_DP<5>")
	)
	(gr_poly
		(pts
			(xy 279.592786 -43.946572) (xy 279.556718 -43.910758) (xy 279.413208 -43.785028) (xy 279.341326 -43.85691)
			(xy 279.467056 -44.00042) (xy 279.50287 -44.036488)
		)
		(stroke
			(width 0)
			(type solid)
		)
		(fill yes)
		(layer "F.Cu")
		(net "M_B_DQ<44>")
	)
	(gr_poly
		(pts
			(xy 279.596088 -111.008668) (xy 279.721818 -110.864904) (xy 279.649936 -110.793276) (xy 279.506172 -110.919006)
			(xy 279.470358 -110.95482) (xy 279.560274 -111.044736)
		)
		(stroke
			(width 0)
			(type solid)
		)
		(fill yes)
		(layer "F.Cu")
		(net "M_E_DQ<44>")
	)
	(gr_poly
		(pts
			(xy 279.611074 -45.383704) (xy 279.485344 -45.23994) (xy 279.449276 -45.204126) (xy 279.359614 -45.293788)
			(xy 279.395428 -45.329856) (xy 279.539192 -45.455586)
		)
		(stroke
			(width 0)
			(type solid)
		)
		(fill yes)
		(layer "F.Cu")
		(net "M_B_DQ<40>")
	)
	(gr_poly
		(pts
			(xy 279.61971 -105.425748) (xy 279.61971 -105.197148) (xy 279.42667 -105.108248) (xy 279.38222 -105.108248)
			(xy 279.38222 -105.514648) (xy 279.42667 -105.514648)
		)
		(stroke
			(width 0)
			(type solid)
		)
		(fill yes)
		(layer "F.Cu")
		(net "M_E_DQ<41>")
	)
	(gr_poly
		(pts
			(xy 279.61971 -104.435148) (xy 279.61971 -104.206548) (xy 279.42667 -104.117648) (xy 279.38222 -104.117648)
			(xy 279.38222 -104.524048) (xy 279.42667 -104.524048)
		)
		(stroke
			(width 0)
			(type solid)
		)
		(fill yes)
		(layer "F.Cu")
		(net "M_E_DQ<41>")
	)
	(gr_poly
		(pts
			(xy 279.659334 -109.544612) (xy 279.695148 -109.508544) (xy 279.605486 -109.418882) (xy 279.569418 -109.454696)
			(xy 279.443688 -109.59846) (xy 279.51557 -109.670342)
		)
		(stroke
			(width 0)
			(type solid)
		)
		(fill yes)
		(layer "F.Cu")
		(net "M_E_DQ<41>")
	)
	(gr_poly
		(pts
			(xy 279.682702 -44.9707) (xy 279.646888 -44.934632) (xy 279.503124 -44.808902) (xy 279.431242 -44.880784)
			(xy 279.556972 -45.024548) (xy 279.59304 -45.060362)
		)
		(stroke
			(width 0)
			(type solid)
		)
		(fill yes)
		(layer "F.Cu")
		(net "M_B_DQ<40>")
	)
	(gr_poly
		(pts
			(xy 279.686258 -109.984794) (xy 279.811988 -109.84103) (xy 279.740106 -109.769148) (xy 279.596342 -109.894878)
			(xy 279.560528 -109.930946) (xy 279.65019 -110.020608)
		)
		(stroke
			(width 0)
			(type solid)
		)
		(fill yes)
		(layer "F.Cu")
		(net "M_E_DQ<40>")
	)
	(gr_poly
		(pts
			(xy 279.70099 -46.407578) (xy 279.57526 -46.264068) (xy 279.539446 -46.228) (xy 279.44953 -46.317916)
			(xy 279.485598 -46.35373) (xy 279.629108 -46.47946)
		)
		(stroke
			(width 0)
			(type solid)
		)
		(fill yes)
		(layer "F.Cu")
		(net "M_B_DQS_DP<14>")
	)
	(gr_poly
		(pts
			(xy 279.702514 -50.94732) (xy 279.702514 -50.72634) (xy 279.532334 -50.63744) (xy 279.487884 -50.63744)
			(xy 279.487884 -51.03622) (xy 279.532334 -51.03622)
		)
		(stroke
			(width 0)
			(type solid)
		)
		(fill yes)
		(layer "F.Cu")
		(net "M_B_DQS_DP<5>")
	)
	(gr_poly
		(pts
			(xy 279.72512 -108.540804) (xy 279.72512 -108.439204) (xy 279.53462 -108.426504) (xy 279.48382 -108.426504)
			(xy 279.48382 -108.553504) (xy 279.53462 -108.553504)
		)
		(stroke
			(width 0)
			(type solid)
		)
		(fill yes)
		(layer "F.Cu")
		(net "M_E_DQ<41>")
	)
	(gr_poly
		(pts
			(xy 279.72512 -107.880404) (xy 279.72512 -107.778804) (xy 279.53462 -107.766104) (xy 279.48382 -107.766104)
			(xy 279.48382 -107.893104) (xy 279.53462 -107.893104)
		)
		(stroke
			(width 0)
			(type solid)
		)
		(fill yes)
		(layer "F.Cu")
		(net "M_E_DQ<41>")
	)
	(gr_poly
		(pts
			(xy 279.72512 -107.220004) (xy 279.72512 -107.118404) (xy 279.53462 -107.105704) (xy 279.48382 -107.105704)
			(xy 279.48382 -107.232704) (xy 279.53462 -107.232704)
		)
		(stroke
			(width 0)
			(type solid)
		)
		(fill yes)
		(layer "F.Cu")
		(net "M_E_DQ<41>")
	)
	(gr_poly
		(pts
			(xy 279.72512 -106.559604) (xy 279.72512 -106.458004) (xy 279.53462 -106.445304) (xy 279.48382 -106.445304)
			(xy 279.48382 -106.572304) (xy 279.53462 -106.572304)
		)
		(stroke
			(width 0)
			(type solid)
		)
		(fill yes)
		(layer "F.Cu")
		(net "M_E_DQ<41>")
	)
	(gr_poly
		(pts
			(xy 279.757632 -111.313976) (xy 279.7937 -111.278162) (xy 279.703784 -111.188246) (xy 279.66797 -111.224314)
			(xy 279.54224 -111.367824) (xy 279.614122 -111.439706)
		)
		(stroke
			(width 0)
			(type solid)
		)
		(fill yes)
		(layer "F.Cu")
		(net "M_E_DQ<44>")
	)
	(gr_poly
		(pts
			(xy 279.772872 -45.994574) (xy 279.736804 -45.95876) (xy 279.593294 -45.83303) (xy 279.521412 -45.904912)
			(xy 279.647142 -46.048422) (xy 279.682956 -46.08449)
		)
		(stroke
			(width 0)
			(type solid)
		)
		(fill yes)
		(layer "F.Cu")
		(net "M_B_DQS_DP<14>")
	)
	(gr_poly
		(pts
			(xy 279.79116 -47.431706) (xy 279.66543 -47.287942) (xy 279.629362 -47.252128) (xy 279.5397 -47.34179)
			(xy 279.575514 -47.377858) (xy 279.719278 -47.503588)
		)
		(stroke
			(width 0)
			(type solid)
		)
		(fill yes)
		(layer "F.Cu")
		(net "M_B_DQS_DN<5>")
	)
	(gr_poly
		(pts
			(xy 279.799542 -44.638214) (xy 279.673812 -44.49445) (xy 279.637744 -44.458636) (xy 279.548082 -44.548298)
			(xy 279.583896 -44.584366) (xy 279.72766 -44.710096)
		)
		(stroke
			(width 0)
			(type solid)
		)
		(fill yes)
		(layer "F.Cu")
		(net "M_B_DQ<45>")
	)
	(gr_poly
		(pts
			(xy 279.833324 -49.327308) (xy 279.833324 -49.225708) (xy 279.642824 -49.213008) (xy 279.592024 -49.213008)
			(xy 279.592024 -49.340008) (xy 279.642824 -49.340008)
		)
		(stroke
			(width 0)
			(type solid)
		)
		(fill yes)
		(layer "F.Cu")
		(net "M_B_DQS_DP<5>")
	)
	(gr_poly
		(pts
			(xy 279.833324 -48.666908) (xy 279.833324 -48.565308) (xy 279.642824 -48.552608) (xy 279.592024 -48.552608)
			(xy 279.592024 -48.679608) (xy 279.642824 -48.679608)
		)
		(stroke
			(width 0)
			(type solid)
		)
		(fill yes)
		(layer "F.Cu")
		(net "M_B_DQS_DP<5>")
	)
	(gr_poly
		(pts
			(xy 279.847802 -110.290102) (xy 279.883616 -110.254034) (xy 279.793954 -110.164372) (xy 279.757886 -110.200186)
			(xy 279.632156 -110.34395) (xy 279.704038 -110.415832)
		)
		(stroke
			(width 0)
			(type solid)
		)
		(fill yes)
		(layer "F.Cu")
		(net "M_E_DQ<40>")
	)
	(gr_poly
		(pts
			(xy 279.862788 -47.018702) (xy 279.826974 -46.982634) (xy 279.68321 -46.856904) (xy 279.611328 -46.928786)
			(xy 279.737058 -47.07255) (xy 279.773126 -47.108364)
		)
		(stroke
			(width 0)
			(type solid)
		)
		(fill yes)
		(layer "F.Cu")
		(net "M_B_DQS_DN<5>")
	)
	(gr_poly
		(pts
			(xy 279.87117 -44.22521) (xy 279.835356 -44.189142) (xy 279.691592 -44.063412) (xy 279.61971 -44.135294)
			(xy 279.74544 -44.279058) (xy 279.781508 -44.314872)
		)
		(stroke
			(width 0)
			(type solid)
		)
		(fill yes)
		(layer "F.Cu")
		(net "M_B_DQ<45>")
	)
	(gr_poly
		(pts
			(xy 279.874726 -110.730284) (xy 280.000456 -110.58652) (xy 279.928574 -110.514638) (xy 279.78481 -110.640368)
			(xy 279.748996 -110.676436) (xy 279.838658 -110.766098)
		)
		(stroke
			(width 0)
			(type solid)
		)
		(fill yes)
		(layer "F.Cu")
		(net "M_E_DQ<45>")
	)
	(gr_poly
		(pts
			(xy 279.87752 -108.756704) (xy 279.82672 -108.756704) (xy 279.63622 -108.769404) (xy 279.63622 -108.871004)
			(xy 279.82672 -108.883704) (xy 279.87752 -108.883704)
		)
		(stroke
			(width 0)
			(type solid)
		)
		(fill yes)
		(layer "F.Cu")
		(net "M_E_DQS_DP<14>")
	)
	(gr_poly
		(pts
			(xy 279.87752 -108.096304) (xy 279.82672 -108.096304) (xy 279.63622 -108.109004) (xy 279.63622 -108.210604)
			(xy 279.82672 -108.223304) (xy 279.87752 -108.223304)
		)
		(stroke
			(width 0)
			(type solid)
		)
		(fill yes)
		(layer "F.Cu")
		(net "M_E_DQS_DP<14>")
	)
	(gr_poly
		(pts
			(xy 279.87752 -107.435904) (xy 279.82672 -107.435904) (xy 279.63622 -107.448604) (xy 279.63622 -107.550204)
			(xy 279.82672 -107.562904) (xy 279.87752 -107.562904)
		)
		(stroke
			(width 0)
			(type solid)
		)
		(fill yes)
		(layer "F.Cu")
		(net "M_E_DQS_DP<14>")
	)
	(gr_poly
		(pts
			(xy 279.87752 -106.775504) (xy 279.82672 -106.775504) (xy 279.63622 -106.788204) (xy 279.63622 -106.889804)
			(xy 279.82672 -106.902504) (xy 279.87752 -106.902504)
		)
		(stroke
			(width 0)
			(type solid)
		)
		(fill yes)
		(layer "F.Cu")
		(net "M_E_DQS_DP<14>")
	)
	(gr_poly
		(pts
			(xy 279.87752 -106.115104) (xy 279.82672 -106.115104) (xy 279.63622 -106.127804) (xy 279.63622 -106.229404)
			(xy 279.82672 -106.242104) (xy 279.87752 -106.242104)
		)
		(stroke
			(width 0)
			(type solid)
		)
		(fill yes)
		(layer "F.Cu")
		(net "M_E_DQS_DP<14>")
	)
	(gr_poly
		(pts
			(xy 279.889458 -45.662088) (xy 279.763728 -45.518578) (xy 279.727914 -45.48251) (xy 279.637998 -45.572426)
			(xy 279.673812 -45.60824) (xy 279.817576 -45.73397)
		)
		(stroke
			(width 0)
			(type solid)
		)
		(fill yes)
		(layer "F.Cu")
		(net "M_B_DQ<41>")
	)
	(gr_poly
		(pts
			(xy 279.909524 -51.119786) (xy 279.865074 -51.119786) (xy 279.694894 -51.208686) (xy 279.694894 -51.429666)
			(xy 279.865074 -51.518566) (xy 279.909524 -51.518566)
		)
		(stroke
			(width 0)
			(type solid)
		)
		(fill yes)
		(layer "F.Cu")
		(net "M_B_DQ<46>")
	)
	(gr_poly
		(pts
			(xy 279.909524 -50.129186) (xy 279.865074 -50.129186) (xy 279.694894 -50.218086) (xy 279.694894 -50.439066)
			(xy 279.865074 -50.527966) (xy 279.909524 -50.527966)
		)
		(stroke
			(width 0)
			(type solid)
		)
		(fill yes)
		(layer "F.Cu")
		(net "M_B_DQ<46>")
	)
	(gr_poly
		(pts
			(xy 279.96134 -45.249084) (xy 279.925272 -45.21327) (xy 279.781762 -45.08754) (xy 279.70988 -45.159422)
			(xy 279.83561 -45.302932) (xy 279.871424 -45.339)
		)
		(stroke
			(width 0)
			(type solid)
		)
		(fill yes)
		(layer "F.Cu")
		(net "M_B_DQ<41>")
	)
	(gr_poly
		(pts
			(xy 279.964642 -109.706156) (xy 280.090372 -109.562646) (xy 280.01849 -109.490764) (xy 279.874726 -109.616494)
			(xy 279.838912 -109.652308) (xy 279.928828 -109.742224)
		)
		(stroke
			(width 0)
			(type solid)
		)
		(fill yes)
		(layer "F.Cu")
		(net "M_E_DQ<41>")
	)
	(gr_poly
		(pts
			(xy 279.97912 -105.235248) (xy 279.93467 -105.235248) (xy 279.74163 -105.324148) (xy 279.74163 -105.552748)
			(xy 279.93467 -105.641648) (xy 279.97912 -105.641648)
		)
		(stroke
			(width 0)
			(type solid)
		)
		(fill yes)
		(layer "F.Cu")
		(net "M_E_DQS_DP<14>")
	)
	(gr_poly
		(pts
			(xy 279.97912 -104.244648) (xy 279.93467 -104.244648) (xy 279.74163 -104.333548) (xy 279.74163 -104.562148)
			(xy 279.93467 -104.651048) (xy 279.97912 -104.651048)
		)
		(stroke
			(width 0)
			(type solid)
		)
		(fill yes)
		(layer "F.Cu")
		(net "M_E_DQS_DP<14>")
	)
	(gr_poly
		(pts
			(xy 279.979628 -46.686216) (xy 279.853898 -46.542452) (xy 279.81783 -46.506638) (xy 279.728168 -46.5963)
			(xy 279.763982 -46.632368) (xy 279.907746 -46.758098)
		)
		(stroke
			(width 0)
			(type solid)
		)
		(fill yes)
		(layer "F.Cu")
		(net "M_B_DQS_DN<14>")
	)
	(gr_poly
		(pts
			(xy 279.985724 -48.882808) (xy 279.934924 -48.882808) (xy 279.744424 -48.895508) (xy 279.744424 -48.997108)
			(xy 279.934924 -49.009808) (xy 279.985724 -49.009808)
		)
		(stroke
			(width 0)
			(type solid)
		)
		(fill yes)
		(layer "F.Cu")
		(net "M_B_DQ<46>")
	)
	(gr_poly
		(pts
			(xy 279.985724 -48.222408) (xy 279.934924 -48.222408) (xy 279.744424 -48.235108) (xy 279.744424 -48.336708)
			(xy 279.934924 -48.349408) (xy 279.985724 -48.349408)
		)
		(stroke
			(width 0)
			(type solid)
		)
		(fill yes)
		(layer "F.Cu")
		(net "M_B_DQ<46>")
	)
	(gr_poly
		(pts
			(xy 279.987756 -43.892724) (xy 279.86228 -43.74896) (xy 279.826212 -43.713146) (xy 279.73655 -43.802808)
			(xy 279.772364 -43.838876) (xy 279.916128 -43.964606)
		)
		(stroke
			(width 0)
			(type solid)
		)
		(fill yes)
		(layer "F.Cu")
		(net "M_B_DQ<44>")
	)
	(gr_poly
		(pts
			(xy 280.03627 -111.035592) (xy 280.072084 -110.999524) (xy 279.982422 -110.909862) (xy 279.946354 -110.945676)
			(xy 279.820624 -111.08944) (xy 279.892506 -111.161322)
		)
		(stroke
			(width 0)
			(type solid)
		)
		(fill yes)
		(layer "F.Cu")
		(net "M_E_DQ<45>")
	)
	(gr_poly
		(pts
			(xy 280.046176 -101.761798) (xy 280.001726 -101.761798) (xy 279.831546 -101.850698) (xy 279.831546 -102.071678)
			(xy 280.001726 -102.160578) (xy 280.046176 -102.160578)
		)
		(stroke
			(width 0)
			(type solid)
		)
		(fill yes)
		(layer "F.Cu")
		(net "M_E_DQS_DP<14>")
	)
	(gr_poly
		(pts
			(xy 280.051256 -46.273212) (xy 280.015442 -46.237144) (xy 279.871678 -46.111414) (xy 279.799796 -46.183296)
			(xy 279.925526 -46.32706) (xy 279.961594 -46.362874)
		)
		(stroke
			(width 0)
			(type solid)
		)
		(fill yes)
		(layer "F.Cu")
		(net "M_B_DQS_DN<14>")
	)
	(gr_poly
		(pts
			(xy 280.059638 -43.47972) (xy 280.023824 -43.443652) (xy 279.88006 -43.317922) (xy 279.808178 -43.389804)
			(xy 279.933908 -43.533568) (xy 279.969976 -43.569382)
		)
		(stroke
			(width 0)
			(type solid)
		)
		(fill yes)
		(layer "F.Cu")
		(net "M_B_DQ<44>")
	)
	(gr_poly
		(pts
			(xy 280.063194 -111.475774) (xy 280.18867 -111.33201) (xy 280.117042 -111.260128) (xy 279.973278 -111.385858)
			(xy 279.937464 -111.421926) (xy 280.027126 -111.511588)
		)
		(stroke
			(width 0)
			(type solid)
		)
		(fill yes)
		(layer "F.Cu")
		(net "M_E_DQ<44>")
	)
	(gr_poly
		(pts
			(xy 280.069544 -47.71009) (xy 279.943814 -47.56658) (xy 279.908 -47.530512) (xy 279.818084 -47.620428)
			(xy 279.854152 -47.656242) (xy 279.997662 -47.781972)
		)
		(stroke
			(width 0)
			(type solid)
		)
		(fill yes)
		(layer "F.Cu")
		(net "M_B_DQS_DP<5>")
	)
	(gr_poly
		(pts
			(xy 280.077926 -44.916852) (xy 279.952196 -44.773088) (xy 279.916382 -44.73702) (xy 279.826466 -44.826936)
			(xy 279.86228 -44.86275) (xy 280.006044 -44.98848)
		)
		(stroke
			(width 0)
			(type solid)
		)
		(fill yes)
		(layer "F.Cu")
		(net "M_B_DQ<40>")
	)
	(gr_poly
		(pts
			(xy 280.11882 -108.540804) (xy 280.11882 -108.439204) (xy 279.92832 -108.426504) (xy 279.87752 -108.426504)
			(xy 279.87752 -108.553504) (xy 279.92832 -108.553504)
		)
		(stroke
			(width 0)
			(type solid)
		)
		(fill yes)
		(layer "F.Cu")
		(net "M_E_DQS_DP<14>")
	)
	(gr_poly
		(pts
			(xy 280.11882 -107.880404) (xy 280.11882 -107.778804) (xy 279.92832 -107.766104) (xy 279.87752 -107.766104)
			(xy 279.87752 -107.893104) (xy 279.92832 -107.893104)
		)
		(stroke
			(width 0)
			(type solid)
		)
		(fill yes)
		(layer "F.Cu")
		(net "M_E_DQS_DP<14>")
	)
	(gr_poly
		(pts
			(xy 280.11882 -107.220004) (xy 280.11882 -107.118404) (xy 279.92832 -107.105704) (xy 279.87752 -107.105704)
			(xy 279.87752 -107.232704) (xy 279.92832 -107.232704)
		)
		(stroke
			(width 0)
			(type solid)
		)
		(fill yes)
		(layer "F.Cu")
		(net "M_E_DQS_DP<14>")
	)
	(gr_poly
		(pts
			(xy 280.11882 -106.559604) (xy 280.11882 -106.458004) (xy 279.92832 -106.445304) (xy 279.87752 -106.445304)
			(xy 279.87752 -106.572304) (xy 279.92832 -106.572304)
		)
		(stroke
			(width 0)
			(type solid)
		)
		(fill yes)
		(layer "F.Cu")
		(net "M_E_DQS_DP<14>")
	)
	(gr_poly
		(pts
			(xy 280.126186 -110.011464) (xy 280.162254 -109.97565) (xy 280.072338 -109.885734) (xy 280.036524 -109.921802)
			(xy 279.910794 -110.065312) (xy 279.982676 -110.137194)
		)
		(stroke
			(width 0)
			(type solid)
		)
		(fill yes)
		(layer "F.Cu")
		(net "M_E_DQ<41>")
	)
	(gr_poly
		(pts
			(xy 280.141426 -47.297086) (xy 280.105358 -47.261272) (xy 279.961848 -47.135542) (xy 279.889966 -47.207424)
			(xy 280.015696 -47.350934) (xy 280.05151 -47.387002)
		)
		(stroke
			(width 0)
			(type solid)
		)
		(fill yes)
		(layer "F.Cu")
		(net "M_B_DQS_DP<5>")
	)
	(gr_poly
		(pts
			(xy 280.149808 -44.503594) (xy 280.11374 -44.46778) (xy 279.97023 -44.34205) (xy 279.898348 -44.413932)
			(xy 280.024078 -44.557442) (xy 280.059892 -44.59351)
		)
		(stroke
			(width 0)
			(type solid)
		)
		(fill yes)
		(layer "F.Cu")
		(net "M_B_DQ<40>")
	)
	(gr_poly
		(pts
			(xy 280.15311 -110.451646) (xy 280.27884 -110.307882) (xy 280.206958 -110.236254) (xy 280.063194 -110.361984)
			(xy 280.02738 -110.397798) (xy 280.117296 -110.487714)
		)
		(stroke
			(width 0)
			(type solid)
		)
		(fill yes)
		(layer "F.Cu")
		(net "M_E_DQ<40>")
	)
	(gr_poly
		(pts
			(xy 280.168096 -45.940726) (xy 280.042366 -45.796962) (xy 280.006298 -45.761148) (xy 279.916636 -45.85081)
			(xy 279.95245 -45.886878) (xy 280.096214 -46.012608)
		)
		(stroke
			(width 0)
			(type solid)
		)
		(fill yes)
		(layer "F.Cu")
		(net "M_B_DQS_DP<14>")
	)
	(gr_poly
		(pts
			(xy 280.224738 -111.781082) (xy 280.260552 -111.745014) (xy 280.17089 -111.655352) (xy 280.134822 -111.691166)
			(xy 280.009092 -111.83493) (xy 280.080974 -111.906812)
		)
		(stroke
			(width 0)
			(type solid)
		)
		(fill yes)
		(layer "F.Cu")
		(net "M_E_DQ<44>")
	)
	(gr_poly
		(pts
			(xy 280.227024 -49.327308) (xy 280.227024 -49.225708) (xy 280.036524 -49.213008) (xy 279.985724 -49.213008)
			(xy 279.985724 -49.340008) (xy 280.036524 -49.340008)
		)
		(stroke
			(width 0)
			(type solid)
		)
		(fill yes)
		(layer "F.Cu")
		(net "M_B_DQ<46>")
	)
	(gr_poly
		(pts
			(xy 280.227024 -48.666908) (xy 280.227024 -48.565308) (xy 280.036524 -48.552608) (xy 279.985724 -48.552608)
			(xy 279.985724 -48.679608) (xy 280.036524 -48.679608)
		)
		(stroke
			(width 0)
			(type solid)
		)
		(fill yes)
		(layer "F.Cu")
		(net "M_B_DQ<46>")
	)
	(gr_poly
		(pts
			(xy 280.239724 -45.527722) (xy 280.20391 -45.491654) (xy 280.060146 -45.365924) (xy 279.988264 -45.437806)
			(xy 280.113994 -45.58157) (xy 280.150062 -45.617384)
		)
		(stroke
			(width 0)
			(type solid)
		)
		(fill yes)
		(layer "F.Cu")
		(net "M_B_DQS_DP<14>")
	)
	(gr_poly
		(pts
			(xy 280.24328 -109.427772) (xy 280.36901 -109.284008) (xy 280.297128 -109.212126) (xy 280.153364 -109.337856)
			(xy 280.11755 -109.373924) (xy 280.207212 -109.463586)
		)
		(stroke
			(width 0)
			(type solid)
		)
		(fill yes)
		(layer "F.Cu")
		(net "M_E_DQS_DP<14>")
	)
	(gr_poly
		(pts
			(xy 280.258012 -46.9646) (xy 280.132282 -46.82109) (xy 280.096468 -46.785022) (xy 280.006552 -46.874938)
			(xy 280.04262 -46.910752) (xy 280.18613 -47.036482)
		)
		(stroke
			(width 0)
			(type solid)
		)
		(fill yes)
		(layer "F.Cu")
		(net "M_B_DQS_DN<5>")
	)
	(gr_poly
		(pts
			(xy 280.266394 -44.171362) (xy 280.140664 -44.027598) (xy 280.10485 -43.99153) (xy 280.014934 -44.081446)
			(xy 280.050748 -44.11726) (xy 280.194512 -44.24299)
		)
		(stroke
			(width 0)
			(type solid)
		)
		(fill yes)
		(layer "F.Cu")
		(net "M_B_DQ<45>")
	)
	(gr_poly
		(pts
			(xy 280.27122 -108.756704) (xy 280.22042 -108.756704) (xy 280.02992 -108.769404) (xy 280.02992 -108.871004)
			(xy 280.22042 -108.883704) (xy 280.27122 -108.883704)
		)
		(stroke
			(width 0)
			(type solid)
		)
		(fill yes)
		(layer "F.Cu")
		(net "M_E_DQS_DN<14>")
	)
	(gr_poly
		(pts
			(xy 280.27122 -108.096304) (xy 280.22042 -108.096304) (xy 280.02992 -108.109004) (xy 280.02992 -108.210604)
			(xy 280.22042 -108.223304) (xy 280.27122 -108.223304)
		)
		(stroke
			(width 0)
			(type solid)
		)
		(fill yes)
		(layer "F.Cu")
		(net "M_E_DQS_DN<14>")
	)
	(gr_poly
		(pts
			(xy 280.27122 -107.435904) (xy 280.22042 -107.435904) (xy 280.02992 -107.448604) (xy 280.02992 -107.550204)
			(xy 280.22042 -107.562904) (xy 280.27122 -107.562904)
		)
		(stroke
			(width 0)
			(type solid)
		)
		(fill yes)
		(layer "F.Cu")
		(net "M_E_DQS_DN<14>")
	)
	(gr_poly
		(pts
			(xy 280.27122 -106.775504) (xy 280.22042 -106.775504) (xy 280.02992 -106.788204) (xy 280.02992 -106.889804)
			(xy 280.22042 -106.902504) (xy 280.27122 -106.902504)
		)
		(stroke
			(width 0)
			(type solid)
		)
		(fill yes)
		(layer "F.Cu")
		(net "M_E_DQS_DN<14>")
	)
	(gr_poly
		(pts
			(xy 280.27122 -106.115104) (xy 280.22042 -106.115104) (xy 280.02992 -106.127804) (xy 280.02992 -106.229404)
			(xy 280.22042 -106.242104) (xy 280.27122 -106.242104)
		)
		(stroke
			(width 0)
			(type solid)
		)
		(fill yes)
		(layer "F.Cu")
		(net "M_E_DQS_DN<14>")
	)
	(gr_poly
		(pts
			(xy 280.314654 -110.756954) (xy 280.350722 -110.72114) (xy 280.260806 -110.631224) (xy 280.224992 -110.667292)
			(xy 280.099262 -110.810802) (xy 280.171144 -110.882684)
		)
		(stroke
			(width 0)
			(type solid)
		)
		(fill yes)
		(layer "F.Cu")
		(net "M_E_DQ<40>")
	)
	(gr_poly
		(pts
			(xy 280.314654 -51.00066) (xy 280.314654 -50.77968) (xy 280.144474 -50.69078) (xy 280.100024 -50.69078)
			(xy 280.100024 -51.08956) (xy 280.144474 -51.08956)
		)
		(stroke
			(width 0)
			(type solid)
		)
		(fill yes)
		(layer "F.Cu")
		(net "M_B_DQ<47>")
	)
	(gr_poly
		(pts
			(xy 280.329894 -46.551596) (xy 280.293826 -46.515782) (xy 280.150316 -46.390052) (xy 280.078434 -46.461934)
			(xy 280.204164 -46.605444) (xy 280.239978 -46.641512)
		)
		(stroke
			(width 0)
			(type solid)
		)
		(fill yes)
		(layer "F.Cu")
		(net "M_B_DQS_DN<5>")
	)
	(gr_poly
		(pts
			(xy 280.338276 -43.758104) (xy 280.302208 -43.72229) (xy 280.158698 -43.59656) (xy 280.086816 -43.668442)
			(xy 280.212546 -43.811952) (xy 280.24836 -43.84802)
		)
		(stroke
			(width 0)
			(type solid)
		)
		(fill yes)
		(layer "F.Cu")
		(net "M_B_DQ<45>")
	)
	(gr_poly
		(pts
			(xy 280.341578 -111.197136) (xy 280.467308 -111.053372) (xy 280.395426 -110.981744) (xy 280.251662 -111.107474)
			(xy 280.215848 -111.143288) (xy 280.305764 -111.233204)
		)
		(stroke
			(width 0)
			(type solid)
		)
		(fill yes)
		(layer "F.Cu")
		(net "M_E_DQ<45>")
	)
	(gr_poly
		(pts
			(xy 280.348182 -47.988728) (xy 280.222452 -47.844964) (xy 280.186384 -47.80915) (xy 280.096722 -47.898812)
			(xy 280.132536 -47.93488) (xy 280.2763 -48.06061)
		)
		(stroke
			(width 0)
			(type solid)
		)
		(fill yes)
		(layer "F.Cu")
		(net "M_B_DQ<46>")
	)
	(gr_poly
		(pts
			(xy 280.356564 -45.195236) (xy 280.230834 -45.051472) (xy 280.194766 -45.015658) (xy 280.105104 -45.10532)
			(xy 280.140918 -45.141388) (xy 280.284682 -45.267118)
		)
		(stroke
			(width 0)
			(type solid)
		)
		(fill yes)
		(layer "F.Cu")
		(net "M_B_DQ<41>")
	)
	(gr_poly
		(pts
			(xy 280.379424 -48.882808) (xy 280.328624 -48.882808) (xy 280.138124 -48.895508) (xy 280.138124 -48.997108)
			(xy 280.328624 -49.009808) (xy 280.379424 -49.009808)
		)
		(stroke
			(width 0)
			(type solid)
		)
		(fill yes)
		(layer "F.Cu")
		(net "M_B_DQ<47>")
	)
	(gr_poly
		(pts
			(xy 280.393648 -53.043328) (xy 280.393648 -52.822348) (xy 280.223468 -52.733448) (xy 280.179018 -52.733448)
			(xy 280.179018 -53.132228) (xy 280.223468 -53.132228)
		)
		(stroke
			(width 0)
			(type solid)
		)
		(fill yes)
		(layer "F.Cu")
		(net "M_B_DQ<47>")
	)
	(gr_poly
		(pts
			(xy 280.393648 -52.057554) (xy 280.393648 -51.836574) (xy 280.223468 -51.747674) (xy 280.179018 -51.747674)
			(xy 280.179018 -52.146454) (xy 280.223468 -52.146454)
		)
		(stroke
			(width 0)
			(type solid)
		)
		(fill yes)
		(layer "F.Cu")
		(net "M_B_DQ<47>")
	)
	(gr_poly
		(pts
			(xy 280.404824 -109.73308) (xy 280.440638 -109.697012) (xy 280.350976 -109.60735) (xy 280.314908 -109.643164)
			(xy 280.189178 -109.786928) (xy 280.26106 -109.85881)
		)
		(stroke
			(width 0)
			(type solid)
		)
		(fill yes)
		(layer "F.Cu")
		(net "M_E_DQS_DP<14>")
	)
	(gr_poly
		(pts
			(xy 280.40711 -105.552748) (xy 280.40711 -105.324148) (xy 280.21407 -105.235248) (xy 280.16962 -105.235248)
			(xy 280.16962 -105.641648) (xy 280.21407 -105.641648)
		)
		(stroke
			(width 0)
			(type solid)
		)
		(fill yes)
		(layer "F.Cu")
		(net "M_E_DQS_DN<14>")
	)
	(gr_poly
		(pts
			(xy 280.40711 -104.562148) (xy 280.40711 -104.333548) (xy 280.21407 -104.244648) (xy 280.16962 -104.244648)
			(xy 280.16962 -104.651048) (xy 280.21407 -104.651048)
		)
		(stroke
			(width 0)
			(type solid)
		)
		(fill yes)
		(layer "F.Cu")
		(net "M_E_DQS_DN<14>")
	)
	(gr_poly
		(pts
			(xy 280.41981 -47.575724) (xy 280.383996 -47.539656) (xy 280.240232 -47.413926) (xy 280.16835 -47.485808)
			(xy 280.29408 -47.629572) (xy 280.330148 -47.665386)
		)
		(stroke
			(width 0)
			(type solid)
		)
		(fill yes)
		(layer "F.Cu")
		(net "M_B_DQ<46>")
	)
	(gr_poly
		(pts
			(xy 280.428192 -44.782232) (xy 280.392378 -44.746164) (xy 280.248614 -44.620434) (xy 280.176732 -44.692316)
			(xy 280.302462 -44.83608) (xy 280.33853 -44.871894)
		)
		(stroke
			(width 0)
			(type solid)
		)
		(fill yes)
		(layer "F.Cu")
		(net "M_B_DQ<41>")
	)
	(gr_poly
		(pts
			(xy 280.431748 -110.173262) (xy 280.557478 -110.029498) (xy 280.485596 -109.957616) (xy 280.341832 -110.083346)
			(xy 280.306018 -110.119414) (xy 280.39568 -110.209076)
		)
		(stroke
			(width 0)
			(type solid)
		)
		(fill yes)
		(layer "F.Cu")
		(net "M_E_DQ<41>")
	)
	(gr_poly
		(pts
			(xy 280.44648 -46.21911) (xy 280.32075 -46.0756) (xy 280.284936 -46.039532) (xy 280.19502 -46.129448)
			(xy 280.230834 -46.165262) (xy 280.374598 -46.290992)
		)
		(stroke
			(width 0)
			(type solid)
		)
		(fill yes)
		(layer "F.Cu")
		(net "M_B_DQS_DN<14>")
	)
	(gr_poly
		(pts
			(xy 280.454862 -43.425872) (xy 280.329132 -43.282108) (xy 280.293318 -43.24604) (xy 280.203402 -43.335956)
			(xy 280.239216 -43.37177) (xy 280.38298 -43.4975)
		)
		(stroke
			(width 0)
			(type solid)
		)
		(fill yes)
		(layer "F.Cu")
		(net "M_B_DQ<44>")
	)
	(gr_poly
		(pts
			(xy 280.503122 -111.502444) (xy 280.53919 -111.46663) (xy 280.449274 -111.376714) (xy 280.41346 -111.412782)
			(xy 280.28773 -111.556292) (xy 280.359612 -111.628174)
		)
		(stroke
			(width 0)
			(type solid)
		)
		(fill yes)
		(layer "F.Cu")
		(net "M_E_DQ<45>")
	)
	(gr_poly
		(pts
			(xy 280.51252 -108.540804) (xy 280.51252 -108.439204) (xy 280.32202 -108.426504) (xy 280.27122 -108.426504)
			(xy 280.27122 -108.553504) (xy 280.32202 -108.553504)
		)
		(stroke
			(width 0)
			(type solid)
		)
		(fill yes)
		(layer "F.Cu")
		(net "M_E_DQS_DN<14>")
	)
	(gr_poly
		(pts
			(xy 280.51252 -107.880404) (xy 280.51252 -107.778804) (xy 280.32202 -107.766104) (xy 280.27122 -107.766104)
			(xy 280.27122 -107.893104) (xy 280.32202 -107.893104)
		)
		(stroke
			(width 0)
			(type solid)
		)
		(fill yes)
		(layer "F.Cu")
		(net "M_E_DQS_DN<14>")
	)
	(gr_poly
		(pts
			(xy 280.51252 -107.220004) (xy 280.51252 -107.118404) (xy 280.32202 -107.105704) (xy 280.27122 -107.105704)
			(xy 280.27122 -107.232704) (xy 280.32202 -107.232704)
		)
		(stroke
			(width 0)
			(type solid)
		)
		(fill yes)
		(layer "F.Cu")
		(net "M_E_DQS_DN<14>")
	)
	(gr_poly
		(pts
			(xy 280.51252 -106.559604) (xy 280.51252 -106.458004) (xy 280.32202 -106.445304) (xy 280.27122 -106.445304)
			(xy 280.27122 -106.572304) (xy 280.32202 -106.572304)
		)
		(stroke
			(width 0)
			(type solid)
		)
		(fill yes)
		(layer "F.Cu")
		(net "M_E_DQS_DN<14>")
	)
	(gr_poly
		(pts
			(xy 280.518362 -45.806106) (xy 280.482294 -45.770292) (xy 280.338784 -45.644562) (xy 280.266902 -45.716444)
			(xy 280.392632 -45.859954) (xy 280.428446 -45.896022)
		)
		(stroke
			(width 0)
			(type solid)
		)
		(fill yes)
		(layer "F.Cu")
		(net "M_B_DQS_DN<14>")
	)
	(gr_poly
		(pts
			(xy 280.521664 -109.149134) (xy 280.647394 -109.005624) (xy 280.575512 -108.933742) (xy 280.431748 -109.059472)
			(xy 280.395934 -109.095286) (xy 280.48585 -109.185202)
		)
		(stroke
			(width 0)
			(type solid)
		)
		(fill yes)
		(layer "F.Cu")
		(net "M_E_DQS_DN<14>")
	)
	(gr_poly
		(pts
			(xy 280.530046 -111.942626) (xy 280.655776 -111.798862) (xy 280.583894 -111.727234) (xy 280.44013 -111.852964)
			(xy 280.404316 -111.888778) (xy 280.494232 -111.978694)
		)
		(stroke
			(width 0)
			(type solid)
		)
		(fill yes)
		(layer "F.Cu")
		(net "M_E_DQ<44>")
	)
	(gr_poly
		(pts
			(xy 280.53665 -47.243238) (xy 280.41092 -47.099474) (xy 280.374852 -47.06366) (xy 280.28519 -47.153322)
			(xy 280.321004 -47.18939) (xy 280.464768 -47.31512)
		)
		(stroke
			(width 0)
			(type solid)
		)
		(fill yes)
		(layer "F.Cu")
		(net "M_B_DQS_DP<5>")
	)
	(gr_poly
		(pts
			(xy 280.544778 -44.449746) (xy 280.419302 -44.305982) (xy 280.383234 -44.270168) (xy 280.293572 -44.35983)
			(xy 280.329386 -44.395898) (xy 280.47315 -44.521628)
		)
		(stroke
			(width 0)
			(type solid)
		)
		(fill yes)
		(layer "F.Cu")
		(net "M_B_DQ<40>")
	)
	(gr_poly
		(pts
			(xy 280.5557 -42.437812) (xy 280.5049 -42.437812) (xy 280.3144 -42.450512) (xy 280.3144 -42.552112)
			(xy 280.5049 -42.564812) (xy 280.5557 -42.564812)
		)
		(stroke
			(width 0)
			(type solid)
		)
		(fill yes)
		(layer "F.Cu")
		(net "M_B_DQ<44>")
	)
	(gr_poly
		(pts
			(xy 280.5557 -41.777412) (xy 280.5049 -41.777412) (xy 280.3144 -41.790112) (xy 280.3144 -41.891712)
			(xy 280.5049 -41.904412) (xy 280.5557 -41.904412)
		)
		(stroke
			(width 0)
			(type solid)
		)
		(fill yes)
		(layer "F.Cu")
		(net "M_B_DQ<44>")
	)
	(gr_poly
		(pts
			(xy 280.584402 -102.579424) (xy 280.584402 -102.358444) (xy 280.414222 -102.269544) (xy 280.369772 -102.269544)
			(xy 280.369772 -102.668324) (xy 280.414222 -102.668324)
		)
		(stroke
			(width 0)
			(type solid)
		)
		(fill yes)
		(layer "F.Cu")
		(net "M_E_DQS_DN<14>")
	)
	(gr_poly
		(pts
			(xy 280.584402 -101.582474) (xy 280.584402 -101.361494) (xy 280.414222 -101.272594) (xy 280.369772 -101.272594)
			(xy 280.369772 -101.671374) (xy 280.414222 -101.671374)
		)
		(stroke
			(width 0)
			(type solid)
		)
		(fill yes)
		(layer "F.Cu")
		(net "M_E_DQS_DN<14>")
	)
	(gr_poly
		(pts
			(xy 280.593292 -110.47857) (xy 280.629106 -110.442502) (xy 280.539444 -110.35284) (xy 280.503376 -110.388654)
			(xy 280.377646 -110.532418) (xy 280.449528 -110.6043)
		)
		(stroke
			(width 0)
			(type solid)
		)
		(fill yes)
		(layer "F.Cu")
		(net "M_E_DQ<41>")
	)
	(gr_poly
		(pts
			(xy 280.608278 -46.830234) (xy 280.572464 -46.794166) (xy 280.4287 -46.668436) (xy 280.356818 -46.740318)
			(xy 280.482548 -46.884082) (xy 280.518616 -46.919896)
		)
		(stroke
			(width 0)
			(type solid)
		)
		(fill yes)
		(layer "F.Cu")
		(net "M_B_DQS_DP<5>")
	)
	(gr_poly
		(pts
			(xy 280.61666 -44.036742) (xy 280.580846 -44.000674) (xy 280.437082 -43.874944) (xy 280.3652 -43.946826)
			(xy 280.49093 -44.09059) (xy 280.526998 -44.126404)
		)
		(stroke
			(width 0)
			(type solid)
		)
		(fill yes)
		(layer "F.Cu")
		(net "M_B_DQ<40>")
	)
	(gr_poly
		(pts
			(xy 280.620216 -110.918752) (xy 280.745692 -110.774988) (xy 280.674064 -110.703106) (xy 280.5303 -110.828836)
			(xy 280.494486 -110.864904) (xy 280.584148 -110.954566)
		)
		(stroke
			(width 0)
			(type solid)
		)
		(fill yes)
		(layer "F.Cu")
		(net "M_E_DQ<40>")
	)
	(gr_poly
		(pts
			(xy 280.620724 -49.327308) (xy 280.620724 -49.225708) (xy 280.430224 -49.213008) (xy 280.379424 -49.213008)
			(xy 280.379424 -49.340008) (xy 280.430224 -49.340008)
		)
		(stroke
			(width 0)
			(type solid)
		)
		(fill yes)
		(layer "F.Cu")
		(net "M_B_DQ<47>")
	)
	(gr_poly
		(pts
			(xy 280.620724 -48.666908) (xy 280.620724 -48.565308) (xy 280.430224 -48.552608) (xy 280.379424 -48.552608)
			(xy 280.379424 -48.679608) (xy 280.430224 -48.679608)
		)
		(stroke
			(width 0)
			(type solid)
		)
		(fill yes)
		(layer "F.Cu")
		(net "M_B_DQ<47>")
	)
	(gr_poly
		(pts
			(xy 280.634948 -45.473874) (xy 280.509218 -45.33011) (xy 280.473404 -45.294042) (xy 280.383488 -45.383958)
			(xy 280.419302 -45.419772) (xy 280.563066 -45.545502)
		)
		(stroke
			(width 0)
			(type solid)
		)
		(fill yes)
		(layer "F.Cu")
		(net "M_B_DQS_DP<14>")
	)
	(gr_poly
		(pts
			(xy 280.66492 -108.096304) (xy 280.61412 -108.096304) (xy 280.42362 -108.109004) (xy 280.42362 -108.210604)
			(xy 280.61412 -108.223304) (xy 280.66492 -108.223304)
		)
		(stroke
			(width 0)
			(type solid)
		)
		(fill yes)
		(layer "F.Cu")
		(net "M_E_DQS_DN<5>")
	)
	(gr_poly
		(pts
			(xy 280.66492 -107.435904) (xy 280.61412 -107.435904) (xy 280.42362 -107.448604) (xy 280.42362 -107.550204)
			(xy 280.61412 -107.562904) (xy 280.66492 -107.562904)
		)
		(stroke
			(width 0)
			(type solid)
		)
		(fill yes)
		(layer "F.Cu")
		(net "M_E_DQS_DN<5>")
	)
	(gr_poly
		(pts
			(xy 280.66492 -106.775504) (xy 280.61412 -106.775504) (xy 280.42362 -106.788204) (xy 280.42362 -106.889804)
			(xy 280.61412 -106.902504) (xy 280.66492 -106.902504)
		)
		(stroke
			(width 0)
			(type solid)
		)
		(fill yes)
		(layer "F.Cu")
		(net "M_E_DQS_DN<5>")
	)
	(gr_poly
		(pts
			(xy 280.66492 -106.115104) (xy 280.61412 -106.115104) (xy 280.42362 -106.127804) (xy 280.42362 -106.229404)
			(xy 280.61412 -106.242104) (xy 280.66492 -106.242104)
		)
		(stroke
			(width 0)
			(type solid)
		)
		(fill yes)
		(layer "F.Cu")
		(net "M_E_DQS_DN<5>")
	)
	(gr_poly
		(pts
			(xy 280.683208 -109.454442) (xy 280.719276 -109.418628) (xy 280.62936 -109.328712) (xy 280.593546 -109.36478)
			(xy 280.467816 -109.50829) (xy 280.539698 -109.580172)
		)
		(stroke
			(width 0)
			(type solid)
		)
		(fill yes)
		(layer "F.Cu")
		(net "M_E_DQS_DN<14>")
	)
	(gr_poly
		(pts
			(xy 280.69159 -112.247934) (xy 280.727658 -112.21212) (xy 280.637742 -112.122204) (xy 280.601928 -112.158272)
			(xy 280.476198 -112.301782) (xy 280.54808 -112.373664)
		)
		(stroke
			(width 0)
			(type solid)
		)
		(fill yes)
		(layer "F.Cu")
		(net "M_E_DQ<44>")
	)
	(gr_poly
		(pts
			(xy 280.698448 -47.854108) (xy 280.66238 -47.818294) (xy 280.51887 -47.692564) (xy 280.446988 -47.764446)
			(xy 280.572718 -47.907956) (xy 280.608532 -47.944024)
		)
		(stroke
			(width 0)
			(type solid)
		)
		(fill yes)
		(layer "F.Cu")
		(net "M_B_DQ<47>")
	)
	(gr_poly
		(pts
			(xy 280.70683 -45.060616) (xy 280.670762 -45.024802) (xy 280.527252 -44.899072) (xy 280.45537 -44.970954)
			(xy 280.5811 -45.114464) (xy 280.616914 -45.150532)
		)
		(stroke
			(width 0)
			(type solid)
		)
		(fill yes)
		(layer "F.Cu")
		(net "M_B_DQS_DP<14>")
	)
	(gr_poly
		(pts
			(xy 280.710132 -109.894624) (xy 280.835862 -109.75086) (xy 280.76398 -109.679232) (xy 280.620216 -109.804962)
			(xy 280.584402 -109.840776) (xy 280.674318 -109.930692)
		)
		(stroke
			(width 0)
			(type solid)
		)
		(fill yes)
		(layer "F.Cu")
		(net "M_E_DQS_DP<14>")
	)
	(gr_poly
		(pts
			(xy 280.725118 -46.497748) (xy 280.599388 -46.353984) (xy 280.56332 -46.31817) (xy 280.473658 -46.407832)
			(xy 280.509472 -46.4439) (xy 280.653236 -46.56963)
		)
		(stroke
			(width 0)
			(type solid)
		)
		(fill yes)
		(layer "F.Cu")
		(net "M_B_DQS_DN<5>")
	)
	(gr_poly
		(pts
			(xy 280.733246 -43.704256) (xy 280.607516 -43.560492) (xy 280.571702 -43.524678) (xy 280.48204 -43.61434)
			(xy 280.517854 -43.650408) (xy 280.661618 -43.776138)
		)
		(stroke
			(width 0)
			(type solid)
		)
		(fill yes)
		(layer "F.Cu")
		(net "M_B_DQ<45>")
	)
	(gr_poly
		(pts
			(xy 280.76652 -105.234232) (xy 280.72207 -105.234232) (xy 280.52903 -105.323132) (xy 280.52903 -105.551732)
			(xy 280.72207 -105.640632) (xy 280.76652 -105.640632)
		)
		(stroke
			(width 0)
			(type solid)
		)
		(fill yes)
		(layer "F.Cu")
		(net "M_E_DQS_DN<5>")
	)
	(gr_poly
		(pts
			(xy 280.76652 -104.243632) (xy 280.72207 -104.243632) (xy 280.52903 -104.332532) (xy 280.52903 -104.561132)
			(xy 280.72207 -104.650032) (xy 280.76652 -104.650032)
		)
		(stroke
			(width 0)
			(type solid)
		)
		(fill yes)
		(layer "F.Cu")
		(net "M_E_DQS_DN<5>")
	)
	(gr_poly
		(pts
			(xy 280.773124 -48.882808) (xy 280.722324 -48.882808) (xy 280.531824 -48.895508) (xy 280.531824 -48.997108)
			(xy 280.722324 -49.009808) (xy 280.773124 -49.009808)
		)
		(stroke
			(width 0)
			(type solid)
		)
		(fill yes)
		(layer "F.Cu")
		(net "M_B_DQ<42>")
	)
	(gr_poly
		(pts
			(xy 280.78176 -111.22406) (xy 280.817574 -111.187992) (xy 280.727912 -111.09833) (xy 280.691844 -111.134144)
			(xy 280.566114 -111.277908) (xy 280.637996 -111.34979)
		)
		(stroke
			(width 0)
			(type solid)
		)
		(fill yes)
		(layer "F.Cu")
		(net "M_E_DQ<40>")
	)
	(gr_poly
		(pts
			(xy 280.796746 -46.084744) (xy 280.760932 -46.048676) (xy 280.617168 -45.922946) (xy 280.545286 -45.994828)
			(xy 280.671016 -46.138592) (xy 280.707084 -46.174406)
		)
		(stroke
			(width 0)
			(type solid)
		)
		(fill yes)
		(layer "F.Cu")
		(net "M_B_DQS_DN<5>")
	)
	(gr_poly
		(pts
			(xy 280.797 -42.882312) (xy 280.797 -42.780712) (xy 280.6065 -42.768012) (xy 280.5557 -42.768012)
			(xy 280.5557 -42.895012) (xy 280.6065 -42.895012)
		)
		(stroke
			(width 0)
			(type solid)
		)
		(fill yes)
		(layer "F.Cu")
		(net "M_B_DQ<44>")
	)
	(gr_poly
		(pts
			(xy 280.797 -42.221912) (xy 280.797 -42.120312) (xy 280.6065 -42.107612) (xy 280.5557 -42.107612)
			(xy 280.5557 -42.234612) (xy 280.6065 -42.234612)
		)
		(stroke
			(width 0)
			(type solid)
		)
		(fill yes)
		(layer "F.Cu")
		(net "M_B_DQ<44>")
	)
	(gr_poly
		(pts
			(xy 280.805128 -43.291252) (xy 280.769314 -43.255184) (xy 280.62555 -43.129454) (xy 280.553668 -43.201336)
			(xy 280.679398 -43.3451) (xy 280.715466 -43.380914)
		)
		(stroke
			(width 0)
			(type solid)
		)
		(fill yes)
		(layer "F.Cu")
		(net "M_B_DQ<45>")
	)
	(gr_poly
		(pts
			(xy 280.80843 -111.664242) (xy 280.93416 -111.520478) (xy 280.862532 -111.448596) (xy 280.718768 -111.574326)
			(xy 280.682954 -111.610394) (xy 280.772616 -111.700056)
		)
		(stroke
			(width 0)
			(type solid)
		)
		(fill yes)
		(layer "F.Cu")
		(net "M_E_DQ<45>")
	)
	(gr_poly
		(pts
			(xy 280.815034 -47.521622) (xy 280.689304 -47.378112) (xy 280.65349 -47.342044) (xy 280.563574 -47.43196)
			(xy 280.599642 -47.467774) (xy 280.743152 -47.593504)
		)
		(stroke
			(width 0)
			(type solid)
		)
		(fill yes)
		(layer "F.Cu")
		(net "M_B_DQ<46>")
	)
	(gr_poly
		(pts
			(xy 280.823416 -44.728384) (xy 280.697686 -44.58462) (xy 280.661872 -44.548552) (xy 280.571956 -44.638468)
			(xy 280.60777 -44.674282) (xy 280.751534 -44.800012)
		)
		(stroke
			(width 0)
			(type solid)
		)
		(fill yes)
		(layer "F.Cu")
		(net "M_B_DQ<41>")
	)
	(gr_poly
		(pts
			(xy 280.871676 -110.199932) (xy 280.907744 -110.164118) (xy 280.817828 -110.074202) (xy 280.782014 -110.11027)
			(xy 280.656284 -110.25378) (xy 280.728166 -110.325662)
		)
		(stroke
			(width 0)
			(type solid)
		)
		(fill yes)
		(layer "F.Cu")
		(net "M_E_DQS_DP<14>")
	)
	(gr_poly
		(pts
			(xy 280.886916 -47.108618) (xy 280.850848 -47.072804) (xy 280.707338 -46.947074) (xy 280.635456 -47.018956)
			(xy 280.761186 -47.162466) (xy 280.797 -47.198534)
		)
		(stroke
			(width 0)
			(type solid)
		)
		(fill yes)
		(layer "F.Cu")
		(net "M_B_DQ<46>")
	)
	(gr_poly
		(pts
			(xy 280.895298 -44.315126) (xy 280.85923 -44.279312) (xy 280.71572 -44.153582) (xy 280.643838 -44.225464)
			(xy 280.769568 -44.368974) (xy 280.805382 -44.405042)
		)
		(stroke
			(width 0)
			(type solid)
		)
		(fill yes)
		(layer "F.Cu")
		(net "M_B_DQ<41>")
	)
	(gr_poly
		(pts
			(xy 280.8986 -110.640114) (xy 281.02433 -110.49635) (xy 280.952448 -110.424722) (xy 280.808684 -110.550452)
			(xy 280.77287 -110.586266) (xy 280.862786 -110.676182)
		)
		(stroke
			(width 0)
			(type solid)
		)
		(fill yes)
		(layer "F.Cu")
		(net "M_E_DQ<41>")
	)
	(gr_poly
		(pts
			(xy 280.903426 -51.822858) (xy 280.862532 -51.805078) (xy 280.671016 -51.819048) (xy 280.583386 -52.02174)
			(xy 280.70429 -52.171092) (xy 280.74493 -52.188618)
		)
		(stroke
			(width 0)
			(type solid)
		)
		(fill yes)
		(layer "F.Cu")
		(net "M_B_DQ<42>")
	)
	(gr_poly
		(pts
			(xy 280.90622 -108.540804) (xy 280.90622 -108.439204) (xy 280.71572 -108.426504) (xy 280.66492 -108.426504)
			(xy 280.66492 -108.553504) (xy 280.71572 -108.553504)
		)
		(stroke
			(width 0)
			(type solid)
		)
		(fill yes)
		(layer "F.Cu")
		(net "M_E_DQS_DN<5>")
	)
	(gr_poly
		(pts
			(xy 280.90622 -107.880404) (xy 280.90622 -107.778804) (xy 280.71572 -107.766104) (xy 280.66492 -107.766104)
			(xy 280.66492 -107.893104) (xy 280.71572 -107.893104)
		)
		(stroke
			(width 0)
			(type solid)
		)
		(fill yes)
		(layer "F.Cu")
		(net "M_E_DQS_DN<5>")
	)
	(gr_poly
		(pts
			(xy 280.90622 -107.220004) (xy 280.90622 -107.118404) (xy 280.71572 -107.105704) (xy 280.66492 -107.105704)
			(xy 280.66492 -107.232704) (xy 280.71572 -107.232704)
		)
		(stroke
			(width 0)
			(type solid)
		)
		(fill yes)
		(layer "F.Cu")
		(net "M_E_DQS_DN<5>")
	)
	(gr_poly
		(pts
			(xy 280.90622 -106.559604) (xy 280.90622 -106.458004) (xy 280.71572 -106.445304) (xy 280.66492 -106.445304)
			(xy 280.66492 -106.572304) (xy 280.71572 -106.572304)
		)
		(stroke
			(width 0)
			(type solid)
		)
		(fill yes)
		(layer "F.Cu")
		(net "M_E_DQS_DN<5>")
	)
	(gr_poly
		(pts
			(xy 280.913586 -45.752258) (xy 280.787856 -45.608494) (xy 280.751788 -45.57268) (xy 280.662126 -45.662342)
			(xy 280.69794 -45.69841) (xy 280.841704 -45.82414)
		)
		(stroke
			(width 0)
			(type solid)
		)
		(fill yes)
		(layer "F.Cu")
		(net "M_B_DQS_DN<14>")
	)
	(gr_poly
		(pts
			(xy 280.9494 -42.437812) (xy 280.8986 -42.437812) (xy 280.7081 -42.450512) (xy 280.7081 -42.552112)
			(xy 280.8986 -42.564812) (xy 280.9494 -42.564812)
		)
		(stroke
			(width 0)
			(type solid)
		)
		(fill yes)
		(layer "F.Cu")
		(net "M_B_DQ<45>")
	)
	(gr_poly
		(pts
			(xy 280.9494 -41.777412) (xy 280.8986 -41.777412) (xy 280.7081 -41.790112) (xy 280.7081 -41.891712)
			(xy 280.8986 -41.904412) (xy 280.9494 -41.904412)
		)
		(stroke
			(width 0)
			(type solid)
		)
		(fill yes)
		(layer "F.Cu")
		(net "M_B_DQ<45>")
	)
	(gr_poly
		(pts
			(xy 280.961846 -109.175804) (xy 280.997914 -109.13999) (xy 280.907998 -109.050074) (xy 280.872184 -109.086142)
			(xy 280.746454 -109.229652) (xy 280.818336 -109.301534)
		)
		(stroke
			(width 0)
			(type solid)
		)
		(fill yes)
		(layer "F.Cu")
		(net "M_E_DQS_DN<5>")
	)
	(gr_poly
		(pts
			(xy 280.970228 -111.96955) (xy 281.006042 -111.933482) (xy 280.91638 -111.84382) (xy 280.880312 -111.879634)
			(xy 280.754582 -112.023398) (xy 280.826464 -112.09528)
		)
		(stroke
			(width 0)
			(type solid)
		)
		(fill yes)
		(layer "F.Cu")
		(net "M_E_DQ<45>")
	)
	(gr_poly
		(pts
			(xy 280.976832 -48.132746) (xy 280.941018 -48.096678) (xy 280.797254 -47.970948) (xy 280.725372 -48.04283)
			(xy 280.851102 -48.186594) (xy 280.88717 -48.222408)
		)
		(stroke
			(width 0)
			(type solid)
		)
		(fill yes)
		(layer "F.Cu")
		(net "M_B_DQ<42>")
	)
	(gr_poly
		(pts
			(xy 280.985214 -45.339254) (xy 280.9494 -45.303186) (xy 280.805636 -45.177456) (xy 280.733754 -45.249338)
			(xy 280.859484 -45.393102) (xy 280.895552 -45.428916)
		)
		(stroke
			(width 0)
			(type solid)
		)
		(fill yes)
		(layer "F.Cu")
		(net "M_B_DQS_DN<14>")
	)
	(gr_poly
		(pts
			(xy 280.98877 -109.61624) (xy 281.1145 -109.472476) (xy 281.042618 -109.400594) (xy 280.898854 -109.526324)
			(xy 280.86304 -109.562392) (xy 280.952702 -109.652054)
		)
		(stroke
			(width 0)
			(type solid)
		)
		(fill yes)
		(layer "F.Cu")
		(net "M_E_DQS_DN<14>")
	)
	(gr_poly
		(pts
			(xy 280.993342 -53.145944) (xy 281.081226 -52.943252) (xy 280.960576 -52.7939) (xy 280.919682 -52.776374)
			(xy 280.761186 -53.142134) (xy 280.801826 -53.159914)
		)
		(stroke
			(width 0)
			(type solid)
		)
		(fill yes)
		(layer "F.Cu")
		(net "M_B_DQ<43>")
	)
	(gr_poly
		(pts
			(xy 280.996898 -112.409732) (xy 281.122628 -112.265968) (xy 281.051 -112.194086) (xy 280.907236 -112.319816)
			(xy 280.871168 -112.35563) (xy 280.961084 -112.445546)
		)
		(stroke
			(width 0)
			(type solid)
		)
		(fill yes)
		(layer "F.Cu")
		(net "M_E_DQ<44>")
	)
	(gr_poly
		(pts
			(xy 281.003502 -46.776132) (xy 280.877772 -46.632622) (xy 280.841958 -46.596554) (xy 280.752042 -46.68647)
			(xy 280.787856 -46.722284) (xy 280.93162 -46.848014)
		)
		(stroke
			(width 0)
			(type solid)
		)
		(fill yes)
		(layer "F.Cu")
		(net "M_B_DQS_DP<5>")
	)
	(gr_poly
		(pts
			(xy 281.011884 -43.982894) (xy 280.886154 -43.83913) (xy 280.85034 -43.803062) (xy 280.760424 -43.892978)
			(xy 280.796238 -43.928792) (xy 280.940002 -44.054522)
		)
		(stroke
			(width 0)
			(type solid)
		)
		(fill yes)
		(layer "F.Cu")
		(net "M_B_DQ<40>")
	)
	(gr_poly
		(pts
			(xy 281.014424 -48.666908) (xy 281.014424 -48.565308) (xy 280.823924 -48.552608) (xy 280.773124 -48.552608)
			(xy 280.773124 -48.679608) (xy 280.823924 -48.679608)
		)
		(stroke
			(width 0)
			(type solid)
		)
		(fill yes)
		(layer "F.Cu")
		(net "M_B_DQ<42>")
	)
	(gr_poly
		(pts
			(xy 281.05862 -108.096304) (xy 281.00782 -108.096304) (xy 280.81732 -108.109004) (xy 280.81732 -108.210604)
			(xy 281.00782 -108.223304) (xy 281.05862 -108.223304)
		)
		(stroke
			(width 0)
			(type solid)
		)
		(fill yes)
		(layer "F.Cu")
		(net "M_E_DQS_DP<5>")
	)
	(gr_poly
		(pts
			(xy 281.05862 -107.435904) (xy 281.00782 -107.435904) (xy 280.81732 -107.448604) (xy 280.81732 -107.550204)
			(xy 281.00782 -107.562904) (xy 281.05862 -107.562904)
		)
		(stroke
			(width 0)
			(type solid)
		)
		(fill yes)
		(layer "F.Cu")
		(net "M_E_DQS_DP<5>")
	)
	(gr_poly
		(pts
			(xy 281.05862 -106.775504) (xy 281.00782 -106.775504) (xy 280.81732 -106.788204) (xy 280.81732 -106.889804)
			(xy 281.00782 -106.902504) (xy 281.05862 -106.902504)
		)
		(stroke
			(width 0)
			(type solid)
		)
		(fill yes)
		(layer "F.Cu")
		(net "M_E_DQS_DP<5>")
	)
	(gr_poly
		(pts
			(xy 281.05862 -106.115104) (xy 281.00782 -106.115104) (xy 280.81732 -106.127804) (xy 280.81732 -106.229404)
			(xy 281.00782 -106.242104) (xy 281.05862 -106.242104)
		)
		(stroke
			(width 0)
			(type solid)
		)
		(fill yes)
		(layer "F.Cu")
		(net "M_E_DQS_DP<5>")
	)
	(gr_poly
		(pts
			(xy 281.060144 -110.945422) (xy 281.096212 -110.909608) (xy 281.006296 -110.819692) (xy 280.970482 -110.85576)
			(xy 280.844752 -110.99927) (xy 280.916634 -111.071152)
		)
		(stroke
			(width 0)
			(type solid)
		)
		(fill yes)
		(layer "F.Cu")
		(net "M_E_DQ<41>")
	)
	(gr_poly
		(pts
			(xy 281.075384 -46.363128) (xy 281.039316 -46.327314) (xy 280.895806 -46.201584) (xy 280.823924 -46.273466)
			(xy 280.949654 -46.416976) (xy 280.985468 -46.453044)
		)
		(stroke
			(width 0)
			(type solid)
		)
		(fill yes)
		(layer "F.Cu")
		(net "M_B_DQS_DP<5>")
	)
	(gr_poly
		(pts
			(xy 281.083766 -43.569636) (xy 281.047698 -43.533822) (xy 280.904188 -43.408092) (xy 280.832306 -43.479974)
			(xy 280.958036 -43.623484) (xy 280.99385 -43.659552)
		)
		(stroke
			(width 0)
			(type solid)
		)
		(fill yes)
		(layer "F.Cu")
		(net "M_B_DQ<40>")
	)
	(gr_poly
		(pts
			(xy 281.087068 -111.385604) (xy 281.212798 -111.24184) (xy 281.140916 -111.170212) (xy 280.997152 -111.295942)
			(xy 280.961338 -111.331756) (xy 281.051254 -111.421672)
		)
		(stroke
			(width 0)
			(type solid)
		)
		(fill yes)
		(layer "F.Cu")
		(net "M_E_DQ<40>")
	)
	(gr_poly
		(pts
			(xy 281.093672 -47.80026) (xy 280.967942 -47.656496) (xy 280.931874 -47.620682) (xy 280.842212 -47.710344)
			(xy 280.878026 -47.746412) (xy 281.02179 -47.872142)
		)
		(stroke
			(width 0)
			(type solid)
		)
		(fill yes)
		(layer "F.Cu")
		(net "M_B_DQ<47>")
	)
	(gr_poly
		(pts
			(xy 281.09545 -101.273102) (xy 281.051 -101.273102) (xy 280.88082 -101.362002) (xy 280.88082 -101.582982)
			(xy 281.051 -101.671882) (xy 281.09545 -101.671882)
		)
		(stroke
			(width 0)
			(type solid)
		)
		(fill yes)
		(layer "F.Cu")
		(net "M_E_DQ<46>")
	)
	(gr_poly
		(pts
			(xy 281.1018 -45.006768) (xy 280.976324 -44.863004) (xy 280.940256 -44.82719) (xy 280.850594 -44.916852)
			(xy 280.886408 -44.95292) (xy 281.030172 -45.07865)
		)
		(stroke
			(width 0)
			(type solid)
		)
		(fill yes)
		(layer "F.Cu")
		(net "M_B_DQS_DP<14>")
	)
	(gr_poly
		(pts
			(xy 281.150314 -109.921548) (xy 281.186128 -109.88548) (xy 281.096466 -109.795818) (xy 281.060398 -109.831632)
			(xy 280.934668 -109.975396) (xy 281.00655 -110.047278)
		)
		(stroke
			(width 0)
			(type solid)
		)
		(fill yes)
		(layer "F.Cu")
		(net "M_E_DQS_DN<14>")
	)
	(gr_poly
		(pts
			(xy 281.158696 -112.71504) (xy 281.19451 -112.678972) (xy 281.104848 -112.58931) (xy 281.06878 -112.625124)
			(xy 280.94305 -112.768888) (xy 281.014932 -112.84077)
		)
		(stroke
			(width 0)
			(type solid)
		)
		(fill yes)
		(layer "F.Cu")
		(net "M_E_DQ<44>")
	)
	(gr_poly
		(pts
			(xy 281.1653 -47.387256) (xy 281.129486 -47.351188) (xy 280.985722 -47.225458) (xy 280.91384 -47.29734)
			(xy 281.03957 -47.441104) (xy 281.075638 -47.476918)
		)
		(stroke
			(width 0)
			(type solid)
		)
		(fill yes)
		(layer "F.Cu")
		(net "M_B_DQ<47>")
	)
	(gr_poly
		(pts
			(xy 281.166824 -48.882808) (xy 281.116024 -48.882808) (xy 280.925524 -48.895508) (xy 280.925524 -48.997108)
			(xy 281.116024 -49.009808) (xy 281.166824 -49.009808)
		)
		(stroke
			(width 0)
			(type solid)
		)
		(fill yes)
		(layer "F.Cu")
		(net "M_B_DQ<43>")
	)
	(gr_poly
		(pts
			(xy 281.173682 -44.593764) (xy 281.137868 -44.557696) (xy 280.994104 -44.431966) (xy 280.922222 -44.503848)
			(xy 281.047952 -44.647612) (xy 281.08402 -44.683426)
		)
		(stroke
			(width 0)
			(type solid)
		)
		(fill yes)
		(layer "F.Cu")
		(net "M_B_DQS_DP<14>")
	)
	(gr_poly
		(pts
			(xy 281.177238 -110.36173) (xy 281.302714 -110.217966) (xy 281.231086 -110.146084) (xy 281.087322 -110.271814)
			(xy 281.051508 -110.307882) (xy 281.14117 -110.397544)
		)
		(stroke
			(width 0)
			(type solid)
		)
		(fill yes)
		(layer "F.Cu")
		(net "M_E_DQS_DP<14>")
	)
	(gr_poly
		(pts
			(xy 281.1907 -42.882312) (xy 281.1907 -42.780712) (xy 281.0002 -42.768012) (xy 280.9494 -42.768012)
			(xy 280.9494 -42.895012) (xy 281.0002 -42.895012)
		)
		(stroke
			(width 0)
			(type solid)
		)
		(fill yes)
		(layer "F.Cu")
		(net "M_B_DQ<45>")
	)
	(gr_poly
		(pts
			(xy 281.1907 -42.221912) (xy 281.1907 -42.120312) (xy 281.0002 -42.107612) (xy 280.9494 -42.107612)
			(xy 280.9494 -42.234612) (xy 281.0002 -42.234612)
		)
		(stroke
			(width 0)
			(type solid)
		)
		(fill yes)
		(layer "F.Cu")
		(net "M_B_DQ<45>")
	)
	(gr_poly
		(pts
			(xy 281.1907 -41.561512) (xy 281.1907 -41.459912) (xy 281.0002 -41.447212) (xy 280.9494 -41.447212)
			(xy 280.9494 -41.574212) (xy 281.0002 -41.574212)
		)
		(stroke
			(width 0)
			(type solid)
		)
		(fill yes)
		(layer "F.Cu")
		(net "M_B_DQ<45>")
	)
	(gr_poly
		(pts
			(xy 281.19197 -46.030896) (xy 281.06624 -45.887132) (xy 281.030426 -45.851064) (xy 280.94051 -45.94098)
			(xy 280.976324 -45.976794) (xy 281.120088 -46.102524)
		)
		(stroke
			(width 0)
			(type solid)
		)
		(fill yes)
		(layer "F.Cu")
		(net "M_B_DQS_DN<5>")
	)
	(gr_poly
		(pts
			(xy 281.19451 -105.551732) (xy 281.19451 -105.323132) (xy 281.00147 -105.234232) (xy 280.95702 -105.234232)
			(xy 280.95702 -105.640632) (xy 281.00147 -105.640632)
		)
		(stroke
			(width 0)
			(type solid)
		)
		(fill yes)
		(layer "F.Cu")
		(net "M_E_DQS_DP<5>")
	)
	(gr_poly
		(pts
			(xy 281.19451 -104.561132) (xy 281.19451 -104.332532) (xy 281.00147 -104.243632) (xy 280.95702 -104.243632)
			(xy 280.95702 -104.650032) (xy 281.00147 -104.650032)
		)
		(stroke
			(width 0)
			(type solid)
		)
		(fill yes)
		(layer "F.Cu")
		(net "M_E_DQS_DP<5>")
	)
	(gr_poly
		(pts
			(xy 281.240484 -108.89742) (xy 281.276298 -108.861352) (xy 281.186636 -108.77169) (xy 281.150568 -108.807504)
			(xy 281.024838 -108.951268) (xy 281.09672 -109.02315)
		)
		(stroke
			(width 0)
			(type solid)
		)
		(fill yes)
		(layer "F.Cu")
		(net "M_E_DQS_DP<5>")
	)
	(gr_poly
		(pts
			(xy 281.248612 -111.690912) (xy 281.28468 -111.655098) (xy 281.194764 -111.565182) (xy 281.15895 -111.60125)
			(xy 281.03322 -111.74476) (xy 281.105102 -111.816642)
		)
		(stroke
			(width 0)
			(type solid)
		)
		(fill yes)
		(layer "F.Cu")
		(net "M_E_DQ<40>")
	)
	(gr_poly
		(pts
			(xy 281.263852 -45.617638) (xy 281.227784 -45.581824) (xy 281.084274 -45.456094) (xy 281.012392 -45.527976)
			(xy 281.138122 -45.671486) (xy 281.173936 -45.707554)
		)
		(stroke
			(width 0)
			(type solid)
		)
		(fill yes)
		(layer "F.Cu")
		(net "M_B_DQS_DN<5>")
	)
	(gr_poly
		(pts
			(xy 281.267408 -109.337602) (xy 281.393138 -109.193838) (xy 281.321256 -109.121956) (xy 281.177492 -109.247686)
			(xy 281.141678 -109.283754) (xy 281.23134 -109.373416)
		)
		(stroke
			(width 0)
			(type solid)
		)
		(fill yes)
		(layer "F.Cu")
		(net "M_E_DQS_DN<5>")
	)
	(gr_poly
		(pts
			(xy 281.275536 -112.131094) (xy 281.401266 -111.98733) (xy 281.329384 -111.915702) (xy 281.18562 -112.041432)
			(xy 281.149806 -112.077246) (xy 281.239722 -112.167162)
		)
		(stroke
			(width 0)
			(type solid)
		)
		(fill yes)
		(layer "F.Cu")
		(net "M_E_DQ<45>")
	)
	(gr_poly
		(pts
			(xy 281.28214 -47.05477) (xy 281.15641 -46.911006) (xy 281.120342 -46.875192) (xy 281.03068 -46.964854)
			(xy 281.066494 -47.000922) (xy 281.210258 -47.126652)
		)
		(stroke
			(width 0)
			(type solid)
		)
		(fill yes)
		(layer "F.Cu")
		(net "M_B_DQ<46>")
	)
	(gr_poly
		(pts
			(xy 281.290268 -44.261278) (xy 281.164538 -44.117514) (xy 281.128724 -44.0817) (xy 281.039062 -44.171362)
			(xy 281.074876 -44.20743) (xy 281.21864 -44.33316)
		)
		(stroke
			(width 0)
			(type solid)
		)
		(fill yes)
		(layer "F.Cu")
		(net "M_B_DQ<41>")
	)
	(gr_poly
		(pts
			(xy 281.29992 -107.880404) (xy 281.29992 -107.778804) (xy 281.10942 -107.766104) (xy 281.05862 -107.766104)
			(xy 281.05862 -107.893104) (xy 281.10942 -107.893104)
		)
		(stroke
			(width 0)
			(type solid)
		)
		(fill yes)
		(layer "F.Cu")
		(net "M_E_DQS_DP<5>")
	)
	(gr_poly
		(pts
			(xy 281.29992 -107.220004) (xy 281.29992 -107.118404) (xy 281.10942 -107.105704) (xy 281.05862 -107.105704)
			(xy 281.05862 -107.232704) (xy 281.10942 -107.232704)
		)
		(stroke
			(width 0)
			(type solid)
		)
		(fill yes)
		(layer "F.Cu")
		(net "M_E_DQS_DP<5>")
	)
	(gr_poly
		(pts
			(xy 281.29992 -106.559604) (xy 281.29992 -106.458004) (xy 281.10942 -106.445304) (xy 281.05862 -106.445304)
			(xy 281.05862 -106.572304) (xy 281.10942 -106.572304)
		)
		(stroke
			(width 0)
			(type solid)
		)
		(fill yes)
		(layer "F.Cu")
		(net "M_E_DQS_DP<5>")
	)
	(gr_poly
		(pts
			(xy 281.338782 -110.667038) (xy 281.374596 -110.63097) (xy 281.284934 -110.541308) (xy 281.248866 -110.577122)
			(xy 281.123136 -110.720886) (xy 281.195018 -110.792768)
		)
		(stroke
			(width 0)
			(type solid)
		)
		(fill yes)
		(layer "F.Cu")
		(net "M_E_DQS_DP<14>")
	)
	(gr_poly
		(pts
			(xy 281.3431 -42.437812) (xy 281.2923 -42.437812) (xy 281.1018 -42.450512) (xy 281.1018 -42.552112)
			(xy 281.2923 -42.564812) (xy 281.3431 -42.564812)
		)
		(stroke
			(width 0)
			(type solid)
		)
		(fill yes)
		(layer "F.Cu")
		(net "M_B_DQ<40>")
	)
	(gr_poly
		(pts
			(xy 281.3431 -41.777412) (xy 281.2923 -41.777412) (xy 281.1018 -41.790112) (xy 281.1018 -41.891712)
			(xy 281.2923 -41.904412) (xy 281.3431 -41.904412)
		)
		(stroke
			(width 0)
			(type solid)
		)
		(fill yes)
		(layer "F.Cu")
		(net "M_B_DQ<40>")
	)
	(gr_poly
		(pts
			(xy 281.353768 -46.641766) (xy 281.317954 -46.605698) (xy 281.17419 -46.479968) (xy 281.102308 -46.55185)
			(xy 281.228038 -46.695614) (xy 281.264106 -46.731428)
		)
		(stroke
			(width 0)
			(type solid)
		)
		(fill yes)
		(layer "F.Cu")
		(net "M_B_DQ<46>")
	)
	(gr_poly
		(pts
			(xy 281.36215 -43.848274) (xy 281.326336 -43.812206) (xy 281.182572 -43.686476) (xy 281.11069 -43.758358)
			(xy 281.23642 -43.902122) (xy 281.272488 -43.937936)
		)
		(stroke
			(width 0)
			(type solid)
		)
		(fill yes)
		(layer "F.Cu")
		(net "M_B_DQ<41>")
	)
	(gr_poly
		(pts
			(xy 281.365452 -111.10722) (xy 281.491182 -110.963456) (xy 281.419554 -110.891574) (xy 281.27579 -111.017304)
			(xy 281.239976 -111.053372) (xy 281.329638 -111.143034)
		)
		(stroke
			(width 0)
			(type solid)
		)
		(fill yes)
		(layer "F.Cu")
		(net "M_E_DQ<41>")
	)
	(gr_poly
		(pts
			(xy 281.372056 -48.078644) (xy 281.246326 -47.935134) (xy 281.210512 -47.899066) (xy 281.120596 -47.988982)
			(xy 281.156664 -48.024796) (xy 281.300174 -48.150526)
		)
		(stroke
			(width 0)
			(type solid)
		)
		(fill yes)
		(layer "F.Cu")
		(net "M_B_DQ<42>")
	)
	(gr_poly
		(pts
			(xy 281.380438 -45.285406) (xy 281.254708 -45.141642) (xy 281.218894 -45.105574) (xy 281.128978 -45.19549)
			(xy 281.164792 -45.231304) (xy 281.308556 -45.357034)
		)
		(stroke
			(width 0)
			(type solid)
		)
		(fill yes)
		(layer "F.Cu")
		(net "M_B_DQS_DN<14>")
	)
	(gr_poly
		(pts
			(xy 281.428952 -109.64291) (xy 281.464766 -109.606842) (xy 281.375104 -109.51718) (xy 281.339036 -109.552994)
			(xy 281.213306 -109.696758) (xy 281.285188 -109.76864)
		)
		(stroke
			(width 0)
			(type solid)
		)
		(fill yes)
		(layer "F.Cu")
		(net "M_E_DQS_DN<5>")
	)
	(gr_poly
		(pts
			(xy 281.43708 -112.436402) (xy 281.473148 -112.400588) (xy 281.383232 -112.310672) (xy 281.347418 -112.34674)
			(xy 281.221688 -112.49025) (xy 281.29357 -112.562132)
		)
		(stroke
			(width 0)
			(type solid)
		)
		(fill yes)
		(layer "F.Cu")
		(net "M_E_DQ<45>")
	)
	(gr_poly
		(pts
			(xy 281.442922 -102.084378) (xy 281.442922 -101.863398) (xy 281.272742 -101.774498) (xy 281.228292 -101.774498)
			(xy 281.228292 -102.173278) (xy 281.272742 -102.173278)
		)
		(stroke
			(width 0)
			(type solid)
		)
		(fill yes)
		(layer "F.Cu")
		(net "M_E_DQ<46>")
	)
	(gr_poly
		(pts
			(xy 281.443938 -47.66564) (xy 281.40787 -47.629826) (xy 281.26436 -47.504096) (xy 281.192478 -47.575978)
			(xy 281.318208 -47.719488) (xy 281.354022 -47.755556)
		)
		(stroke
			(width 0)
			(type solid)
		)
		(fill yes)
		(layer "F.Cu")
		(net "M_B_DQ<42>")
	)
	(gr_poly
		(pts
			(xy 281.45232 -108.096304) (xy 281.40152 -108.096304) (xy 281.21102 -108.109004) (xy 281.21102 -108.210604)
			(xy 281.40152 -108.223304) (xy 281.45232 -108.223304)
		)
		(stroke
			(width 0)
			(type solid)
		)
		(fill yes)
		(layer "F.Cu")
		(net "M_E_DQ<46>")
	)
	(gr_poly
		(pts
			(xy 281.45232 -107.435904) (xy 281.40152 -107.435904) (xy 281.21102 -107.448604) (xy 281.21102 -107.550204)
			(xy 281.40152 -107.562904) (xy 281.45232 -107.562904)
		)
		(stroke
			(width 0)
			(type solid)
		)
		(fill yes)
		(layer "F.Cu")
		(net "M_E_DQ<46>")
	)
	(gr_poly
		(pts
			(xy 281.45232 -106.775504) (xy 281.40152 -106.775504) (xy 281.21102 -106.788204) (xy 281.21102 -106.889804)
			(xy 281.40152 -106.902504) (xy 281.45232 -106.902504)
		)
		(stroke
			(width 0)
			(type solid)
		)
		(fill yes)
		(layer "F.Cu")
		(net "M_E_DQ<46>")
	)
	(gr_poly
		(pts
			(xy 281.45232 -106.115104) (xy 281.40152 -106.115104) (xy 281.21102 -106.127804) (xy 281.21102 -106.229404)
			(xy 281.40152 -106.242104) (xy 281.45232 -106.242104)
		)
		(stroke
			(width 0)
			(type solid)
		)
		(fill yes)
		(layer "F.Cu")
		(net "M_E_DQ<46>")
	)
	(gr_poly
		(pts
			(xy 281.45232 -44.872148) (xy 281.416252 -44.836334) (xy 281.272742 -44.710604) (xy 281.20086 -44.782486)
			(xy 281.32659 -44.925996) (xy 281.362404 -44.962064)
		)
		(stroke
			(width 0)
			(type solid)
		)
		(fill yes)
		(layer "F.Cu")
		(net "M_B_DQS_DN<14>")
	)
	(gr_poly
		(pts
			(xy 281.455622 -110.083092) (xy 281.581352 -109.939328) (xy 281.50947 -109.8677) (xy 281.365706 -109.99343)
			(xy 281.329892 -110.029244) (xy 281.419808 -110.11916)
		)
		(stroke
			(width 0)
			(type solid)
		)
		(fill yes)
		(layer "F.Cu")
		(net "M_E_DQS_DN<14>")
	)
	(gr_poly
		(pts
			(xy 281.464004 -112.876584) (xy 281.589734 -112.73282) (xy 281.518106 -112.660938) (xy 281.374342 -112.786668)
			(xy 281.338274 -112.822482) (xy 281.42819 -112.912398)
		)
		(stroke
			(width 0)
			(type solid)
		)
		(fill yes)
		(layer "F.Cu")
		(net "M_E_DQ<44>")
	)
	(gr_poly
		(pts
			(xy 281.470608 -46.30928) (xy 281.344878 -46.165516) (xy 281.30881 -46.129702) (xy 281.219148 -46.219364)
			(xy 281.254962 -46.255432) (xy 281.398726 -46.381162)
		)
		(stroke
			(width 0)
			(type solid)
		)
		(fill yes)
		(layer "F.Cu")
		(net "M_B_DQS_DP<5>")
	)
	(gr_poly
		(pts
			(xy 281.52725 -111.412528) (xy 281.563064 -111.37646) (xy 281.473402 -111.286798) (xy 281.437334 -111.322612)
			(xy 281.311604 -111.466376) (xy 281.383486 -111.538258)
		)
		(stroke
			(width 0)
			(type solid)
		)
		(fill yes)
		(layer "F.Cu")
		(net "M_E_DQ<41>")
	)
	(gr_poly
		(pts
			(xy 281.542236 -45.896276) (xy 281.506422 -45.860208) (xy 281.362658 -45.734478) (xy 281.290776 -45.80636)
			(xy 281.416506 -45.950124) (xy 281.452574 -45.985938)
		)
		(stroke
			(width 0)
			(type solid)
		)
		(fill yes)
		(layer "F.Cu")
		(net "M_B_DQS_DP<5>")
	)
	(gr_poly
		(pts
			(xy 281.545792 -109.058964) (xy 281.671522 -108.9152) (xy 281.59964 -108.843572) (xy 281.455876 -108.969302)
			(xy 281.420062 -109.005116) (xy 281.509978 -109.095032)
		)
		(stroke
			(width 0)
			(type solid)
		)
		(fill yes)
		(layer "F.Cu")
		(net "M_E_DQS_DP<5>")
	)
	(gr_poly
		(pts
			(xy 281.547062 -105.235248) (xy 281.502612 -105.235248) (xy 281.309572 -105.324148) (xy 281.309572 -105.552748)
			(xy 281.502612 -105.641648) (xy 281.547062 -105.641648)
		)
		(stroke
			(width 0)
			(type solid)
		)
		(fill yes)
		(layer "F.Cu")
		(net "M_E_DQ<46>")
	)
	(gr_poly
		(pts
			(xy 281.547062 -104.244648) (xy 281.502612 -104.244648) (xy 281.309572 -104.333548) (xy 281.309572 -104.562148)
			(xy 281.502612 -104.651048) (xy 281.547062 -104.651048)
		)
		(stroke
			(width 0)
			(type solid)
		)
		(fill yes)
		(layer "F.Cu")
		(net "M_E_DQ<46>")
	)
	(gr_poly
		(pts
			(xy 281.55392 -111.85271) (xy 281.67965 -111.708946) (xy 281.608022 -111.637064) (xy 281.464258 -111.762794)
			(xy 281.42819 -111.798608) (xy 281.518106 -111.888524)
		)
		(stroke
			(width 0)
			(type solid)
		)
		(fill yes)
		(layer "F.Cu")
		(net "M_E_DQ<40>")
	)
	(gr_poly
		(pts
			(xy 281.560524 -47.333154) (xy 281.434794 -47.189644) (xy 281.39898 -47.153576) (xy 281.309064 -47.243492)
			(xy 281.344878 -47.279306) (xy 281.488642 -47.405036)
		)
		(stroke
			(width 0)
			(type solid)
		)
		(fill yes)
		(layer "F.Cu")
		(net "M_B_DQ<47>")
	)
	(gr_poly
		(pts
			(xy 281.568906 -44.539916) (xy 281.443176 -44.396152) (xy 281.407362 -44.360084) (xy 281.317446 -44.45)
			(xy 281.35326 -44.485814) (xy 281.497024 -44.611544)
		)
		(stroke
			(width 0)
			(type solid)
		)
		(fill yes)
		(layer "F.Cu")
		(net "M_B_DQS_DP<14>")
	)
	(gr_poly
		(pts
			(xy 281.5844 -42.882312) (xy 281.5844 -42.780712) (xy 281.3939 -42.768012) (xy 281.3431 -42.768012)
			(xy 281.3431 -42.895012) (xy 281.3939 -42.895012)
		)
		(stroke
			(width 0)
			(type solid)
		)
		(fill yes)
		(layer "F.Cu")
		(net "M_B_DQ<40>")
	)
	(gr_poly
		(pts
			(xy 281.5844 -42.221912) (xy 281.5844 -42.120312) (xy 281.3939 -42.107612) (xy 281.3431 -42.107612)
			(xy 281.3431 -42.234612) (xy 281.3939 -42.234612)
		)
		(stroke
			(width 0)
			(type solid)
		)
		(fill yes)
		(layer "F.Cu")
		(net "M_B_DQ<40>")
	)
	(gr_poly
		(pts
			(xy 281.617166 -110.3884) (xy 281.653234 -110.352586) (xy 281.563318 -110.26267) (xy 281.527504 -110.298738)
			(xy 281.401774 -110.442248) (xy 281.473656 -110.51413)
		)
		(stroke
			(width 0)
			(type solid)
		)
		(fill yes)
		(layer "F.Cu")
		(net "M_E_DQS_DN<14>")
	)
	(gr_poly
		(pts
			(xy 281.632406 -46.92015) (xy 281.596338 -46.884336) (xy 281.452828 -46.758606) (xy 281.380946 -46.830488)
			(xy 281.506676 -46.973998) (xy 281.54249 -47.010066)
		)
		(stroke
			(width 0)
			(type solid)
		)
		(fill yes)
		(layer "F.Cu")
		(net "M_B_DQ<47>")
	)
	(gr_poly
		(pts
			(xy 281.640788 -44.126658) (xy 281.60472 -44.090844) (xy 281.46121 -43.965114) (xy 281.389328 -44.036996)
			(xy 281.515058 -44.180506) (xy 281.550872 -44.216574)
		)
		(stroke
			(width 0)
			(type solid)
		)
		(fill yes)
		(layer "F.Cu")
		(net "M_B_DQS_DP<14>")
	)
	(gr_poly
		(pts
			(xy 281.64409 -110.828582) (xy 281.76982 -110.684818) (xy 281.697938 -110.61319) (xy 281.554174 -110.73892)
			(xy 281.51836 -110.774734) (xy 281.608276 -110.86465)
		)
		(stroke
			(width 0)
			(type solid)
		)
		(fill yes)
		(layer "F.Cu")
		(net "M_E_DQS_DP<14>")
	)
	(gr_poly
		(pts
			(xy 281.650694 -48.357282) (xy 281.524964 -48.213518) (xy 281.488896 -48.177704) (xy 281.399234 -48.267366)
			(xy 281.435048 -48.303434) (xy 281.578812 -48.429164)
		)
		(stroke
			(width 0)
			(type solid)
		)
		(fill yes)
		(layer "F.Cu")
		(net "M_B_DQ<43>")
	)
	(gr_poly
		(pts
			(xy 281.658822 -45.56379) (xy 281.533346 -45.420026) (xy 281.497278 -45.384212) (xy 281.407616 -45.473874)
			(xy 281.44343 -45.509942) (xy 281.587194 -45.635672)
		)
		(stroke
			(width 0)
			(type solid)
		)
		(fill yes)
		(layer "F.Cu")
		(net "M_B_DQS_DN<5>")
	)
	(gr_poly
		(pts
			(xy 281.69362 -107.880404) (xy 281.69362 -107.778804) (xy 281.50312 -107.766104) (xy 281.45232 -107.766104)
			(xy 281.45232 -107.893104) (xy 281.50312 -107.893104)
		)
		(stroke
			(width 0)
			(type solid)
		)
		(fill yes)
		(layer "F.Cu")
		(net "M_E_DQ<46>")
	)
	(gr_poly
		(pts
			(xy 281.69362 -107.220004) (xy 281.69362 -107.118404) (xy 281.50312 -107.105704) (xy 281.45232 -107.105704)
			(xy 281.45232 -107.232704) (xy 281.50312 -107.232704)
		)
		(stroke
			(width 0)
			(type solid)
		)
		(fill yes)
		(layer "F.Cu")
		(net "M_E_DQ<46>")
	)
	(gr_poly
		(pts
			(xy 281.69362 -106.559604) (xy 281.69362 -106.458004) (xy 281.50312 -106.445304) (xy 281.45232 -106.445304)
			(xy 281.45232 -106.572304) (xy 281.50312 -106.572304)
		)
		(stroke
			(width 0)
			(type solid)
		)
		(fill yes)
		(layer "F.Cu")
		(net "M_E_DQ<46>")
	)
	(gr_poly
		(pts
			(xy 281.707336 -109.364272) (xy 281.743404 -109.328458) (xy 281.653488 -109.238542) (xy 281.617674 -109.27461)
			(xy 281.491944 -109.41812) (xy 281.563826 -109.490002)
		)
		(stroke
			(width 0)
			(type solid)
		)
		(fill yes)
		(layer "F.Cu")
		(net "M_E_DQS_DP<5>")
	)
	(gr_poly
		(pts
			(xy 281.715718 -112.158018) (xy 281.751532 -112.12195) (xy 281.66187 -112.032288) (xy 281.625802 -112.068102)
			(xy 281.500072 -112.211866) (xy 281.571954 -112.283748)
		)
		(stroke
			(width 0)
			(type solid)
		)
		(fill yes)
		(layer "F.Cu")
		(net "M_E_DQ<40>")
	)
	(gr_poly
		(pts
			(xy 281.722322 -47.944278) (xy 281.686508 -47.90821) (xy 281.542744 -47.78248) (xy 281.470862 -47.854362)
			(xy 281.596592 -47.998126) (xy 281.63266 -48.03394)
		)
		(stroke
			(width 0)
			(type solid)
		)
		(fill yes)
		(layer "F.Cu")
		(net "M_B_DQ<43>")
	)
	(gr_poly
		(pts
			(xy 281.730704 -45.150786) (xy 281.69489 -45.114718) (xy 281.551126 -44.988988) (xy 281.479244 -45.06087)
			(xy 281.604974 -45.204634) (xy 281.641042 -45.240448)
		)
		(stroke
			(width 0)
			(type solid)
		)
		(fill yes)
		(layer "F.Cu")
		(net "M_B_DQS_DN<5>")
	)
	(gr_poly
		(pts
			(xy 281.73426 -109.804454) (xy 281.85999 -109.66069) (xy 281.788108 -109.589062) (xy 281.644344 -109.714792)
			(xy 281.60853 -109.750606) (xy 281.698446 -109.840522)
		)
		(stroke
			(width 0)
			(type solid)
		)
		(fill yes)
		(layer "F.Cu")
		(net "M_E_DQS_DN<5>")
	)
	(gr_poly
		(pts
			(xy 281.7368 -43.098212) (xy 281.686 -43.098212) (xy 281.4955 -43.110912) (xy 281.4955 -43.212512)
			(xy 281.686 -43.225212) (xy 281.7368 -43.225212)
		)
		(stroke
			(width 0)
			(type solid)
		)
		(fill yes)
		(layer "F.Cu")
		(net "M_B_DQ<41>")
	)
	(gr_poly
		(pts
			(xy 281.7368 -42.437812) (xy 281.686 -42.437812) (xy 281.4955 -42.450512) (xy 281.4955 -42.552112)
			(xy 281.686 -42.564812) (xy 281.7368 -42.564812)
		)
		(stroke
			(width 0)
			(type solid)
		)
		(fill yes)
		(layer "F.Cu")
		(net "M_B_DQ<41>")
	)
	(gr_poly
		(pts
			(xy 281.7368 -41.777412) (xy 281.686 -41.777412) (xy 281.4955 -41.790112) (xy 281.4955 -41.891712)
			(xy 281.686 -41.904412) (xy 281.7368 -41.904412)
		)
		(stroke
			(width 0)
			(type solid)
		)
		(fill yes)
		(layer "F.Cu")
		(net "M_B_DQ<41>")
	)
	(gr_poly
		(pts
			(xy 281.742388 -112.5982) (xy 281.868118 -112.454436) (xy 281.79649 -112.382554) (xy 281.652726 -112.508284)
			(xy 281.616658 -112.544098) (xy 281.706574 -112.634014)
		)
		(stroke
			(width 0)
			(type solid)
		)
		(fill yes)
		(layer "F.Cu")
		(net "M_E_DQ<45>")
	)
	(gr_poly
		(pts
			(xy 281.748992 -46.587918) (xy 281.623262 -46.444154) (xy 281.587448 -46.408086) (xy 281.497532 -46.498002)
			(xy 281.533346 -46.533816) (xy 281.67711 -46.659546)
		)
		(stroke
			(width 0)
			(type solid)
		)
		(fill yes)
		(layer "F.Cu")
		(net "M_B_DQ<46>")
	)
	(gr_poly
		(pts
			(xy 281.757374 -43.794426) (xy 281.631644 -43.650662) (xy 281.59583 -43.614594) (xy 281.505914 -43.70451)
			(xy 281.541728 -43.740324) (xy 281.685492 -43.866054)
		)
		(stroke
			(width 0)
			(type solid)
		)
		(fill yes)
		(layer "F.Cu")
		(net "M_B_DQ<41>")
	)
	(gr_poly
		(pts
			(xy 281.763216 -101.780086) (xy 281.718766 -101.780086) (xy 281.548586 -101.868986) (xy 281.548586 -102.089966)
			(xy 281.718766 -102.178866) (xy 281.763216 -102.178866)
		)
		(stroke
			(width 0)
			(type solid)
		)
		(fill yes)
		(layer "F.Cu")
		(net "M_E_DQ<42>")
	)
	(gr_poly
		(pts
			(xy 281.805634 -111.13389) (xy 281.841702 -111.098076) (xy 281.751786 -111.00816) (xy 281.715972 -111.044228)
			(xy 281.590242 -111.187738) (xy 281.662124 -111.25962)
		)
		(stroke
			(width 0)
			(type solid)
		)
		(fill yes)
		(layer "F.Cu")
		(net "M_E_DQS_DP<14>")
	)
	(gr_poly
		(pts
			(xy 281.820874 -46.17466) (xy 281.784806 -46.138846) (xy 281.641296 -46.013116) (xy 281.569414 -46.084998)
			(xy 281.695144 -46.228508) (xy 281.730958 -46.264576)
		)
		(stroke
			(width 0)
			(type solid)
		)
		(fill yes)
		(layer "F.Cu")
		(net "M_B_DQ<46>")
	)
	(gr_poly
		(pts
			(xy 281.82443 -108.780326) (xy 281.95016 -108.636562) (xy 281.878278 -108.564934) (xy 281.734514 -108.690664)
			(xy 281.6987 -108.726478) (xy 281.788616 -108.816394)
		)
		(stroke
			(width 0)
			(type solid)
		)
		(fill yes)
		(layer "F.Cu")
		(net "M_E_DQ<46>")
	)
	(gr_poly
		(pts
			(xy 281.832558 -111.574072) (xy 281.958288 -111.430308) (xy 281.886406 -111.35868) (xy 281.742642 -111.48441)
			(xy 281.706828 -111.520224) (xy 281.796744 -111.61014)
		)
		(stroke
			(width 0)
			(type solid)
		)
		(fill yes)
		(layer "F.Cu")
		(net "M_E_DQ<41>")
	)
	(gr_poly
		(pts
			(xy 281.839162 -47.611792) (xy 281.713432 -47.468028) (xy 281.677364 -47.432214) (xy 281.587702 -47.521876)
			(xy 281.623516 -47.557944) (xy 281.76728 -47.683674)
		)
		(stroke
			(width 0)
			(type solid)
		)
		(fill yes)
		(layer "F.Cu")
		(net "M_B_DQ<42>")
	)
	(gr_poly
		(pts
			(xy 281.84602 -108.096304) (xy 281.79522 -108.096304) (xy 281.60472 -108.109004) (xy 281.60472 -108.210604)
			(xy 281.79522 -108.223304) (xy 281.84602 -108.223304)
		)
		(stroke
			(width 0)
			(type solid)
		)
		(fill yes)
		(layer "F.Cu")
		(net "M_E_DQ<47>")
	)
	(gr_poly
		(pts
			(xy 281.84602 -107.435904) (xy 281.79522 -107.435904) (xy 281.60472 -107.448604) (xy 281.60472 -107.550204)
			(xy 281.79522 -107.562904) (xy 281.84602 -107.562904)
		)
		(stroke
			(width 0)
			(type solid)
		)
		(fill yes)
		(layer "F.Cu")
		(net "M_E_DQ<47>")
	)
	(gr_poly
		(pts
			(xy 281.84602 -106.775504) (xy 281.79522 -106.775504) (xy 281.60472 -106.788204) (xy 281.60472 -106.889804)
			(xy 281.79522 -106.902504) (xy 281.84602 -106.902504)
		)
		(stroke
			(width 0)
			(type solid)
		)
		(fill yes)
		(layer "F.Cu")
		(net "M_E_DQ<47>")
	)
	(gr_poly
		(pts
			(xy 281.84602 -106.115104) (xy 281.79522 -106.115104) (xy 281.60472 -106.127804) (xy 281.60472 -106.229404)
			(xy 281.79522 -106.242104) (xy 281.84602 -106.242104)
		)
		(stroke
			(width 0)
			(type solid)
		)
		(fill yes)
		(layer "F.Cu")
		(net "M_E_DQ<47>")
	)
	(gr_poly
		(pts
			(xy 281.84729 -44.8183) (xy 281.72156 -44.674536) (xy 281.685746 -44.638722) (xy 281.596084 -44.728384)
			(xy 281.631898 -44.764452) (xy 281.775662 -44.890182)
		)
		(stroke
			(width 0)
			(type solid)
		)
		(fill yes)
		(layer "F.Cu")
		(net "M_B_DQS_DN<14>")
	)
	(gr_poly
		(pts
			(xy 281.895804 -110.109762) (xy 281.931872 -110.073948) (xy 281.841956 -109.984032) (xy 281.806142 -110.0201)
			(xy 281.680412 -110.16361) (xy 281.752294 -110.235492)
		)
		(stroke
			(width 0)
			(type solid)
		)
		(fill yes)
		(layer "F.Cu")
		(net "M_E_DQS_DN<5>")
	)
	(gr_poly
		(pts
			(xy 281.904186 -112.903254) (xy 281.940254 -112.86744) (xy 281.850338 -112.777524) (xy 281.814524 -112.813592)
			(xy 281.688794 -112.957102) (xy 281.760676 -113.028984)
		)
		(stroke
			(width 0)
			(type solid)
		)
		(fill yes)
		(layer "F.Cu")
		(net "M_E_DQ<45>")
	)
	(gr_poly
		(pts
			(xy 281.91079 -47.198788) (xy 281.874976 -47.16272) (xy 281.731212 -47.03699) (xy 281.65933 -47.108872)
			(xy 281.78506 -47.252636) (xy 281.821128 -47.28845)
		)
		(stroke
			(width 0)
			(type solid)
		)
		(fill yes)
		(layer "F.Cu")
		(net "M_B_DQ<42>")
	)
	(gr_poly
		(pts
			(xy 281.919172 -44.405296) (xy 281.883358 -44.369228) (xy 281.739594 -44.243498) (xy 281.667712 -44.31538)
			(xy 281.793442 -44.459144) (xy 281.82951 -44.494958)
		)
		(stroke
			(width 0)
			(type solid)
		)
		(fill yes)
		(layer "F.Cu")
		(net "M_B_DQS_DN<14>")
	)
	(gr_poly
		(pts
			(xy 281.922474 -110.550198) (xy 282.048204 -110.406434) (xy 281.976576 -110.334552) (xy 281.832812 -110.460282)
			(xy 281.796998 -110.49635) (xy 281.88666 -110.586012)
		)
		(stroke
			(width 0)
			(type solid)
		)
		(fill yes)
		(layer "F.Cu")
		(net "M_E_DQS_DN<14>")
	)
	(gr_poly
		(pts
			(xy 281.93746 -45.842428) (xy 281.81173 -45.698664) (xy 281.775916 -45.662596) (xy 281.686 -45.752512)
			(xy 281.721814 -45.788326) (xy 281.865578 -45.914056)
		)
		(stroke
			(width 0)
			(type solid)
		)
		(fill yes)
		(layer "F.Cu")
		(net "M_B_DQS_DP<5>")
	)
	(gr_poly
		(pts
			(xy 281.975052 -105.552748) (xy 281.975052 -105.324148) (xy 281.782012 -105.235248) (xy 281.737562 -105.235248)
			(xy 281.737562 -105.641648) (xy 281.782012 -105.641648)
		)
		(stroke
			(width 0)
			(type solid)
		)
		(fill yes)
		(layer "F.Cu")
		(net "M_E_DQ<47>")
	)
	(gr_poly
		(pts
			(xy 281.975052 -104.562148) (xy 281.975052 -104.333548) (xy 281.782012 -104.244648) (xy 281.737562 -104.244648)
			(xy 281.737562 -104.651048) (xy 281.782012 -104.651048)
		)
		(stroke
			(width 0)
			(type solid)
		)
		(fill yes)
		(layer "F.Cu")
		(net "M_E_DQ<47>")
	)
	(gr_poly
		(pts
			(xy 281.9781 -42.882312) (xy 281.9781 -42.780712) (xy 281.7876 -42.768012) (xy 281.7368 -42.768012)
			(xy 281.7368 -42.895012) (xy 281.7876 -42.895012)
		)
		(stroke
			(width 0)
			(type solid)
		)
		(fill yes)
		(layer "F.Cu")
		(net "M_B_DQ<41>")
	)
	(gr_poly
		(pts
			(xy 281.9781 -42.221912) (xy 281.9781 -42.120312) (xy 281.7876 -42.107612) (xy 281.7368 -42.107612)
			(xy 281.7368 -42.234612) (xy 281.7876 -42.234612)
		)
		(stroke
			(width 0)
			(type solid)
		)
		(fill yes)
		(layer "F.Cu")
		(net "M_B_DQ<41>")
	)
	(gr_poly
		(pts
			(xy 281.985974 -109.085634) (xy 282.022042 -109.04982) (xy 281.932126 -108.959904) (xy 281.896312 -108.995972)
			(xy 281.770582 -109.139482) (xy 281.842464 -109.211364)
		)
		(stroke
			(width 0)
			(type solid)
		)
		(fill yes)
		(layer "F.Cu")
		(net "M_E_DQ<46>")
	)
	(gr_poly
		(pts
			(xy 281.994102 -111.87938) (xy 282.03017 -111.843566) (xy 281.940254 -111.75365) (xy 281.90444 -111.789718)
			(xy 281.77871 -111.933228) (xy 281.850592 -112.00511)
		)
		(stroke
			(width 0)
			(type solid)
		)
		(fill yes)
		(layer "F.Cu")
		(net "M_E_DQ<41>")
	)
	(gr_poly
		(pts
			(xy 282.009342 -45.42917) (xy 281.973274 -45.393356) (xy 281.829764 -45.267626) (xy 281.757882 -45.339508)
			(xy 281.883612 -45.483018) (xy 281.919426 -45.519086)
		)
		(stroke
			(width 0)
			(type solid)
		)
		(fill yes)
		(layer "F.Cu")
		(net "M_B_DQS_DP<5>")
	)
	(gr_poly
		(pts
			(xy 282.012898 -109.52607) (xy 282.138374 -109.382306) (xy 282.066746 -109.310424) (xy 281.922982 -109.436154)
			(xy 281.887168 -109.472222) (xy 281.97683 -109.561884)
		)
		(stroke
			(width 0)
			(type solid)
		)
		(fill yes)
		(layer "F.Cu")
		(net "M_E_DQS_DP<5>")
	)
	(gr_poly
		(pts
			(xy 282.021026 -112.319562) (xy 282.146756 -112.175798) (xy 282.074874 -112.10417) (xy 281.93111 -112.2299)
			(xy 281.895296 -112.265714) (xy 281.985212 -112.35563)
		)
		(stroke
			(width 0)
			(type solid)
		)
		(fill yes)
		(layer "F.Cu")
		(net "M_E_DQ<40>")
	)
	(gr_poly
		(pts
			(xy 282.02763 -46.866302) (xy 281.9019 -46.722538) (xy 281.865832 -46.686724) (xy 281.77617 -46.776386)
			(xy 281.811984 -46.812454) (xy 281.955748 -46.938184)
		)
		(stroke
			(width 0)
			(type solid)
		)
		(fill yes)
		(layer "F.Cu")
		(net "M_B_DQ<47>")
	)
	(gr_poly
		(pts
			(xy 282.035758 -44.07281) (xy 281.910028 -43.929046) (xy 281.874214 -43.893232) (xy 281.784298 -43.983148)
			(xy 281.820366 -44.018962) (xy 281.96413 -44.144692)
		)
		(stroke
			(width 0)
			(type solid)
		)
		(fill yes)
		(layer "F.Cu")
		(net "M_B_DQS_DP<14>")
	)
	(gr_poly
		(pts
			(xy 282.084272 -110.855506) (xy 282.120086 -110.819438) (xy 282.030424 -110.729776) (xy 281.994356 -110.76559)
			(xy 281.868626 -110.909354) (xy 281.940508 -110.981236)
		)
		(stroke
			(width 0)
			(type solid)
		)
		(fill yes)
		(layer "F.Cu")
		(net "M_E_DQS_DN<14>")
	)
	(gr_poly
		(pts
			(xy 282.08732 -107.880404) (xy 282.08732 -107.778804) (xy 281.89682 -107.766104) (xy 281.84602 -107.766104)
			(xy 281.84602 -107.893104) (xy 281.89682 -107.893104)
		)
		(stroke
			(width 0)
			(type solid)
		)
		(fill yes)
		(layer "F.Cu")
		(net "M_E_DQ<47>")
	)
	(gr_poly
		(pts
			(xy 282.08732 -107.220004) (xy 282.08732 -107.118404) (xy 281.89682 -107.105704) (xy 281.84602 -107.105704)
			(xy 281.84602 -107.232704) (xy 281.89682 -107.232704)
		)
		(stroke
			(width 0)
			(type solid)
		)
		(fill yes)
		(layer "F.Cu")
		(net "M_E_DQ<47>")
	)
	(gr_poly
		(pts
			(xy 282.08732 -106.559604) (xy 282.08732 -106.458004) (xy 281.89682 -106.445304) (xy 281.84602 -106.445304)
			(xy 281.84602 -106.572304) (xy 281.89682 -106.572304)
		)
		(stroke
			(width 0)
			(type solid)
		)
		(fill yes)
		(layer "F.Cu")
		(net "M_E_DQ<47>")
	)
	(gr_poly
		(pts
			(xy 282.099258 -46.453298) (xy 282.063444 -46.41723) (xy 281.91968 -46.2915) (xy 281.847798 -46.363382)
			(xy 281.973528 -46.507146) (xy 282.009596 -46.54296)
		)
		(stroke
			(width 0)
			(type solid)
		)
		(fill yes)
		(layer "F.Cu")
		(net "M_B_DQ<47>")
	)
	(gr_poly
		(pts
			(xy 282.103068 -108.501942) (xy 282.228798 -108.358178) (xy 282.156916 -108.286296) (xy 282.013152 -108.412026)
			(xy 281.977338 -108.448094) (xy 282.067 -108.537756)
		)
		(stroke
			(width 0)
			(type solid)
		)
		(fill yes)
		(layer "F.Cu")
		(net "M_E_DQ<47>")
	)
	(gr_poly
		(pts
			(xy 282.110942 -111.295688) (xy 282.236672 -111.151924) (xy 282.165044 -111.080042) (xy 282.02128 -111.205772)
			(xy 281.985212 -111.241586) (xy 282.075128 -111.331502)
		)
		(stroke
			(width 0)
			(type solid)
		)
		(fill yes)
		(layer "F.Cu")
		(net "M_E_DQS_DP<14>")
	)
	(gr_poly
		(pts
			(xy 282.117546 -47.890176) (xy 281.991816 -47.746666) (xy 281.956002 -47.710598) (xy 281.866086 -47.800514)
			(xy 281.9019 -47.836328) (xy 282.045664 -47.962058)
		)
		(stroke
			(width 0)
			(type solid)
		)
		(fill yes)
		(layer "F.Cu")
		(net "M_B_DQ<43>")
	)
	(gr_poly
		(pts
			(xy 282.125928 -45.096938) (xy 282.000198 -44.953174) (xy 281.964384 -44.917106) (xy 281.874468 -45.007022)
			(xy 281.910282 -45.042836) (xy 282.054046 -45.168566)
		)
		(stroke
			(width 0)
			(type solid)
		)
		(fill yes)
		(layer "F.Cu")
		(net "M_B_DQS_DN<5>")
	)
	(gr_poly
		(pts
			(xy 282.131262 -49.591976) (xy 282.099766 -49.56048) (xy 281.916632 -49.503076) (xy 281.760422 -49.659286)
			(xy 281.817826 -49.84242) (xy 281.849322 -49.873916)
		)
		(stroke
			(width 0)
			(type solid)
		)
		(fill yes)
		(layer "F.Cu")
		(net "M_B_DQ<52>")
	)
	(gr_poly
		(pts
			(xy 282.174442 -109.831378) (xy 282.210256 -109.79531) (xy 282.120594 -109.705648) (xy 282.084526 -109.741462)
			(xy 281.958796 -109.885226) (xy 282.030678 -109.957108)
		)
		(stroke
			(width 0)
			(type solid)
		)
		(fill yes)
		(layer "F.Cu")
		(net "M_E_DQS_DP<5>")
	)
	(gr_poly
		(pts
			(xy 282.18257 -112.62487) (xy 282.218638 -112.589056) (xy 282.128722 -112.49914) (xy 282.092908 -112.535208)
			(xy 281.967178 -112.678718) (xy 282.03906 -112.7506)
		)
		(stroke
			(width 0)
			(type solid)
		)
		(fill yes)
		(layer "F.Cu")
		(net "M_E_DQ<40>")
	)
	(gr_poly
		(pts
			(xy 282.189428 -47.477172) (xy 282.15336 -47.441358) (xy 282.00985 -47.315628) (xy 281.937968 -47.38751)
			(xy 282.063698 -47.53102) (xy 282.099512 -47.567088)
		)
		(stroke
			(width 0)
			(type solid)
		)
		(fill yes)
		(layer "F.Cu")
		(net "M_B_DQ<43>")
	)
	(gr_poly
		(pts
			(xy 282.19781 -44.68368) (xy 282.161742 -44.647866) (xy 282.018232 -44.522136) (xy 281.94635 -44.594018)
			(xy 282.07208 -44.737528) (xy 282.107894 -44.773596)
		)
		(stroke
			(width 0)
			(type solid)
		)
		(fill yes)
		(layer "F.Cu")
		(net "M_B_DQS_DN<5>")
	)
	(gr_poly
		(pts
			(xy 282.201112 -110.27156) (xy 282.326842 -110.127796) (xy 282.255214 -110.055914) (xy 282.11145 -110.181644)
			(xy 282.075636 -110.217712) (xy 282.165298 -110.307374)
		)
		(stroke
			(width 0)
			(type solid)
		)
		(fill yes)
		(layer "F.Cu")
		(net "M_E_DQS_DN<5>")
	)
	(gr_poly
		(pts
			(xy 282.215844 -46.120812) (xy 282.090368 -45.977048) (xy 282.0543 -45.941234) (xy 281.964638 -46.030896)
			(xy 282.000452 -46.066964) (xy 282.144216 -46.192694)
		)
		(stroke
			(width 0)
			(type solid)
		)
		(fill yes)
		(layer "F.Cu")
		(net "M_B_DQ<46>")
	)
	(gr_poly
		(pts
			(xy 282.23972 -107.435904) (xy 282.18892 -107.435904) (xy 281.99842 -107.448604) (xy 281.99842 -107.550204)
			(xy 282.18892 -107.562904) (xy 282.23972 -107.562904)
		)
		(stroke
			(width 0)
			(type solid)
		)
		(fill yes)
		(layer "F.Cu")
		(net "M_E_DQ<42>")
	)
	(gr_poly
		(pts
			(xy 282.23972 -106.775504) (xy 282.18892 -106.775504) (xy 281.99842 -106.788204) (xy 281.99842 -106.889804)
			(xy 282.18892 -106.902504) (xy 282.23972 -106.902504)
		)
		(stroke
			(width 0)
			(type solid)
		)
		(fill yes)
		(layer "F.Cu")
		(net "M_E_DQ<42>")
	)
	(gr_poly
		(pts
			(xy 282.23972 -106.115104) (xy 282.18892 -106.115104) (xy 281.99842 -106.127804) (xy 281.99842 -106.229404)
			(xy 282.18892 -106.242104) (xy 282.23972 -106.242104)
		)
		(stroke
			(width 0)
			(type solid)
		)
		(fill yes)
		(layer "F.Cu")
		(net "M_E_DQ<42>")
	)
	(gr_poly
		(pts
			(xy 282.264612 -108.80725) (xy 282.300426 -108.771182) (xy 282.210764 -108.68152) (xy 282.174696 -108.717334)
			(xy 282.048966 -108.861098) (xy 282.120848 -108.93298)
		)
		(stroke
			(width 0)
			(type solid)
		)
		(fill yes)
		(layer "F.Cu")
		(net "M_E_DQ<47>")
	)
	(gr_poly
		(pts
			(xy 282.27274 -111.600996) (xy 282.308554 -111.564928) (xy 282.218892 -111.475266) (xy 282.182824 -111.51108)
			(xy 282.057094 -111.654844) (xy 282.128976 -111.726726)
		)
		(stroke
			(width 0)
			(type solid)
		)
		(fill yes)
		(layer "F.Cu")
		(net "M_E_DQS_DP<14>")
	)
	(gr_poly
		(pts
			(xy 282.287726 -45.707808) (xy 282.251912 -45.67174) (xy 282.108148 -45.54601) (xy 282.036266 -45.617892)
			(xy 282.161996 -45.761656) (xy 282.198064 -45.79747)
		)
		(stroke
			(width 0)
			(type solid)
		)
		(fill yes)
		(layer "F.Cu")
		(net "M_B_DQ<46>")
	)
	(gr_poly
		(pts
			(xy 282.291536 -109.247432) (xy 282.417012 -109.103668) (xy 282.345384 -109.031786) (xy 282.20162 -109.157516)
			(xy 282.165806 -109.193584) (xy 282.255468 -109.283246)
		)
		(stroke
			(width 0)
			(type solid)
		)
		(fill yes)
		(layer "F.Cu")
		(net "M_E_DQ<46>")
	)
	(gr_poly
		(pts
			(xy 282.29941 -112.041178) (xy 282.42514 -111.897414) (xy 282.353512 -111.825532) (xy 282.209748 -111.951262)
			(xy 282.17368 -111.987076) (xy 282.263596 -112.076992)
		)
		(stroke
			(width 0)
			(type solid)
		)
		(fill yes)
		(layer "F.Cu")
		(net "M_E_DQ<41>")
	)
	(gr_poly
		(pts
			(xy 282.301442 -52.051712) (xy 282.301442 -51.830732) (xy 282.131262 -51.741832) (xy 282.086812 -51.741832)
			(xy 282.086812 -52.140612) (xy 282.131262 -52.140612)
		)
		(stroke
			(width 0)
			(type solid)
		)
		(fill yes)
		(layer "F.Cu")
		(net "M_B_DQ<53>")
	)
	(gr_poly
		(pts
			(xy 282.306014 -47.14494) (xy 282.180284 -47.001176) (xy 282.14447 -46.965108) (xy 282.054554 -47.055024)
			(xy 282.090368 -47.090838) (xy 282.234132 -47.216568)
		)
		(stroke
			(width 0)
			(type solid)
		)
		(fill yes)
		(layer "F.Cu")
		(net "M_B_DQ<42>")
	)
	(gr_poly
		(pts
			(xy 282.314396 -44.351448) (xy 282.188666 -44.207684) (xy 282.152852 -44.171616) (xy 282.062936 -44.261532)
			(xy 282.09875 -44.297346) (xy 282.242514 -44.423076)
		)
		(stroke
			(width 0)
			(type solid)
		)
		(fill yes)
		(layer "F.Cu")
		(net "M_B_DQS_DN<14>")
	)
	(gr_poly
		(pts
			(xy 282.34132 -105.235248) (xy 282.29687 -105.235248) (xy 282.10383 -105.324148) (xy 282.10383 -105.552748)
			(xy 282.29687 -105.641648) (xy 282.34132 -105.641648)
		)
		(stroke
			(width 0)
			(type solid)
		)
		(fill yes)
		(layer "F.Cu")
		(net "M_E_DQ<42>")
	)
	(gr_poly
		(pts
			(xy 282.34132 -104.244648) (xy 282.29687 -104.244648) (xy 282.10383 -104.333548) (xy 282.10383 -104.562148)
			(xy 282.29687 -104.651048) (xy 282.34132 -104.651048)
		)
		(stroke
			(width 0)
			(type solid)
		)
		(fill yes)
		(layer "F.Cu")
		(net "M_E_DQ<42>")
	)
	(gr_poly
		(pts
			(xy 282.36291 -110.576868) (xy 282.398724 -110.5408) (xy 282.309062 -110.451138) (xy 282.272994 -110.486952)
			(xy 282.147264 -110.630716) (xy 282.219146 -110.702598)
		)
		(stroke
			(width 0)
			(type solid)
		)
		(fill yes)
		(layer "F.Cu")
		(net "M_E_DQS_DN<5>")
	)
	(gr_poly
		(pts
			(xy 282.377896 -46.731682) (xy 282.341828 -46.695868) (xy 282.198318 -46.570138) (xy 282.126436 -46.64202)
			(xy 282.252166 -46.78553) (xy 282.28798 -46.821598)
		)
		(stroke
			(width 0)
			(type solid)
		)
		(fill yes)
		(layer "F.Cu")
		(net "M_B_DQ<42>")
	)
	(gr_poly
		(pts
			(xy 282.386278 -43.93819) (xy 282.35021 -43.902376) (xy 282.2067 -43.776646) (xy 282.134818 -43.848528)
			(xy 282.260548 -43.992038) (xy 282.296362 -44.028106)
		)
		(stroke
			(width 0)
			(type solid)
		)
		(fill yes)
		(layer "F.Cu")
		(net "M_B_DQS_DN<14>")
	)
	(gr_poly
		(pts
			(xy 282.38958 -111.01705) (xy 282.51531 -110.873286) (xy 282.443428 -110.801658) (xy 282.299664 -110.927388)
			(xy 282.26385 -110.963202) (xy 282.353766 -111.053118)
		)
		(stroke
			(width 0)
			(type solid)
		)
		(fill yes)
		(layer "F.Cu")
		(net "M_E_DQS_DN<14>")
	)
	(gr_poly
		(pts
			(xy 282.404312 -45.375322) (xy 282.278582 -45.231558) (xy 282.242768 -45.195744) (xy 282.153106 -45.285406)
			(xy 282.18892 -45.321474) (xy 282.332684 -45.447204)
		)
		(stroke
			(width 0)
			(type solid)
		)
		(fill yes)
		(layer "F.Cu")
		(net "M_B_DQS_DP<5>")
	)
	(gr_poly
		(pts
			(xy 282.45308 -109.55274) (xy 282.488894 -109.516672) (xy 282.399232 -109.42701) (xy 282.363164 -109.462824)
			(xy 282.237434 -109.606588) (xy 282.309316 -109.67847)
		)
		(stroke
			(width 0)
			(type solid)
		)
		(fill yes)
		(layer "F.Cu")
		(net "M_E_DQ<46>")
	)
	(gr_poly
		(pts
			(xy 282.461208 -112.346486) (xy 282.497022 -112.310418) (xy 282.40736 -112.220756) (xy 282.371292 -112.25657)
			(xy 282.245562 -112.400334) (xy 282.317444 -112.472216)
		)
		(stroke
			(width 0)
			(type solid)
		)
		(fill yes)
		(layer "F.Cu")
		(net "M_E_DQ<41>")
	)
	(gr_poly
		(pts
			(xy 282.47467 -49.821846) (xy 282.417266 -49.638712) (xy 282.38577 -49.607216) (xy 282.10383 -49.889156)
			(xy 282.135072 -49.920652) (xy 282.31846 -49.978056)
		)
		(stroke
			(width 0)
			(type solid)
		)
		(fill yes)
		(layer "F.Cu")
		(net "M_B_DQ<53>")
	)
	(gr_poly
		(pts
			(xy 282.476194 -44.962318) (xy 282.44038 -44.92625) (xy 282.296616 -44.80052) (xy 282.224734 -44.872402)
			(xy 282.350464 -45.016166) (xy 282.386532 -45.05198)
		)
		(stroke
			(width 0)
			(type solid)
		)
		(fill yes)
		(layer "F.Cu")
		(net "M_B_DQS_DP<5>")
	)
	(gr_poly
		(pts
			(xy 282.47975 -109.992922) (xy 282.60548 -109.849158) (xy 282.533598 -109.77753) (xy 282.389834 -109.90326)
			(xy 282.35402 -109.939074) (xy 282.443936 -110.02899)
		)
		(stroke
			(width 0)
			(type solid)
		)
		(fill yes)
		(layer "F.Cu")
		(net "M_E_DQS_DP<5>")
	)
	(gr_poly
		(pts
			(xy 282.48102 -107.880404) (xy 282.48102 -107.778804) (xy 282.29052 -107.766104) (xy 282.23972 -107.766104)
			(xy 282.23972 -107.893104) (xy 282.29052 -107.893104)
		)
		(stroke
			(width 0)
			(type solid)
		)
		(fill yes)
		(layer "F.Cu")
		(net "M_E_DQ<42>")
	)
	(gr_poly
		(pts
			(xy 282.48102 -107.220004) (xy 282.48102 -107.118404) (xy 282.29052 -107.105704) (xy 282.23972 -107.105704)
			(xy 282.23972 -107.232704) (xy 282.29052 -107.232704)
		)
		(stroke
			(width 0)
			(type solid)
		)
		(fill yes)
		(layer "F.Cu")
		(net "M_E_DQ<42>")
	)
	(gr_poly
		(pts
			(xy 282.48102 -106.559604) (xy 282.48102 -106.458004) (xy 282.29052 -106.445304) (xy 282.23972 -106.445304)
			(xy 282.23972 -106.572304) (xy 282.29052 -106.572304)
		)
		(stroke
			(width 0)
			(type solid)
		)
		(fill yes)
		(layer "F.Cu")
		(net "M_E_DQ<42>")
	)
	(gr_poly
		(pts
			(xy 282.487878 -112.786668) (xy 282.613608 -112.642904) (xy 282.541726 -112.571276) (xy 282.397962 -112.697006)
			(xy 282.362148 -112.73282) (xy 282.452064 -112.822736)
		)
		(stroke
			(width 0)
			(type solid)
		)
		(fill yes)
		(layer "F.Cu")
		(net "M_E_DQ<40>")
	)
	(gr_poly
		(pts
			(xy 282.494482 -46.39945) (xy 282.368752 -46.255686) (xy 282.332938 -46.219618) (xy 282.243022 -46.309534)
			(xy 282.278836 -46.345348) (xy 282.4226 -46.471078)
		)
		(stroke
			(width 0)
			(type solid)
		)
		(fill yes)
		(layer "F.Cu")
		(net "M_B_DQ<47>")
	)
	(gr_poly
		(pts
			(xy 282.502864 -43.605958) (xy 282.377134 -43.462194) (xy 282.34132 -43.426126) (xy 282.251404 -43.516042)
			(xy 282.287218 -43.551856) (xy 282.430982 -43.677586)
		)
		(stroke
			(width 0)
			(type solid)
		)
		(fill yes)
		(layer "F.Cu")
		(net "M_B_DQS_DP<14>")
	)
	(gr_poly
		(pts
			(xy 282.542996 -108.528612) (xy 282.579064 -108.492798) (xy 282.489148 -108.402882) (xy 282.453334 -108.43895)
			(xy 282.327604 -108.58246) (xy 282.399486 -108.654342)
		)
		(stroke
			(width 0)
			(type solid)
		)
		(fill yes)
		(layer "F.Cu")
		(net "M_E_DQ<42>")
	)
	(gr_poly
		(pts
			(xy 282.551124 -111.322358) (xy 282.587192 -111.286544) (xy 282.497276 -111.196628) (xy 282.461462 -111.232696)
			(xy 282.335732 -111.376206) (xy 282.407614 -111.448088)
		)
		(stroke
			(width 0)
			(type solid)
		)
		(fill yes)
		(layer "F.Cu")
		(net "M_E_DQS_DN<14>")
	)
	(gr_poly
		(pts
			(xy 282.566364 -45.986192) (xy 282.530296 -45.950378) (xy 282.386786 -45.824648) (xy 282.314904 -45.89653)
			(xy 282.440634 -46.04004) (xy 282.476448 -46.076108)
		)
		(stroke
			(width 0)
			(type solid)
		)
		(fill yes)
		(layer "F.Cu")
		(net "M_B_DQ<47>")
	)
	(gr_poly
		(pts
			(xy 282.56992 -108.968794) (xy 282.69565 -108.82503) (xy 282.623768 -108.753402) (xy 282.480004 -108.879132)
			(xy 282.44419 -108.914946) (xy 282.534106 -109.004862)
		)
		(stroke
			(width 0)
			(type solid)
		)
		(fill yes)
		(layer "F.Cu")
		(net "M_E_DQ<47>")
	)
	(gr_poly
		(pts
			(xy 282.578048 -111.76254) (xy 282.703778 -111.618776) (xy 282.631896 -111.547148) (xy 282.488132 -111.672878)
			(xy 282.452318 -111.708692) (xy 282.542234 -111.798608)
		)
		(stroke
			(width 0)
			(type solid)
		)
		(fill yes)
		(layer "F.Cu")
		(net "M_E_DQS_DP<14>")
	)
	(gr_poly
		(pts
			(xy 282.584652 -47.423324) (xy 282.458922 -47.27956) (xy 282.422854 -47.243746) (xy 282.333192 -47.333408)
			(xy 282.369006 -47.369476) (xy 282.51277 -47.495206)
		)
		(stroke
			(width 0)
			(type solid)
		)
		(fill yes)
		(layer "F.Cu")
		(net "M_B_DQ<43>")
	)
	(gr_poly
		(pts
			(xy 282.59278 -44.629832) (xy 282.46705 -44.486068) (xy 282.431236 -44.450254) (xy 282.34132 -44.54017)
			(xy 282.377388 -44.575984) (xy 282.521152 -44.701714)
		)
		(stroke
			(width 0)
			(type solid)
		)
		(fill yes)
		(layer "F.Cu")
		(net "M_B_DQS_DN<5>")
	)
	(gr_poly
		(pts
			(xy 282.63342 -107.435904) (xy 282.58262 -107.435904) (xy 282.39212 -107.448604) (xy 282.39212 -107.550204)
			(xy 282.58262 -107.562904) (xy 282.63342 -107.562904)
		)
		(stroke
			(width 0)
			(type solid)
		)
		(fill yes)
		(layer "F.Cu")
		(net "M_E_DQ<43>")
	)
	(gr_poly
		(pts
			(xy 282.63342 -106.775504) (xy 282.58262 -106.775504) (xy 282.39212 -106.788204) (xy 282.39212 -106.889804)
			(xy 282.58262 -106.902504) (xy 282.63342 -106.902504)
		)
		(stroke
			(width 0)
			(type solid)
		)
		(fill yes)
		(layer "F.Cu")
		(net "M_E_DQ<43>")
	)
	(gr_poly
		(pts
			(xy 282.63342 -106.115104) (xy 282.58262 -106.115104) (xy 282.39212 -106.127804) (xy 282.39212 -106.229404)
			(xy 282.58262 -106.242104) (xy 282.63342 -106.242104)
		)
		(stroke
			(width 0)
			(type solid)
		)
		(fill yes)
		(layer "F.Cu")
		(net "M_E_DQ<43>")
	)
	(gr_poly
		(pts
			(xy 282.641294 -110.29823) (xy 282.677362 -110.262416) (xy 282.587446 -110.1725) (xy 282.551632 -110.208568)
			(xy 282.425902 -110.352078) (xy 282.497784 -110.42396)
		)
		(stroke
			(width 0)
			(type solid)
		)
		(fill yes)
		(layer "F.Cu")
		(net "M_E_DQS_DP<5>")
	)
	(gr_poly
		(pts
			(xy 282.65628 -47.01032) (xy 282.620466 -46.974252) (xy 282.476702 -46.848522) (xy 282.40482 -46.920404)
			(xy 282.53055 -47.064168) (xy 282.566618 -47.099982)
		)
		(stroke
			(width 0)
			(type solid)
		)
		(fill yes)
		(layer "F.Cu")
		(net "M_B_DQ<43>")
	)
	(gr_poly
		(pts
			(xy 282.664662 -44.216828) (xy 282.628848 -44.18076) (xy 282.485084 -44.05503) (xy 282.413202 -44.126912)
			(xy 282.538932 -44.270676) (xy 282.575 -44.30649)
		)
		(stroke
			(width 0)
			(type solid)
		)
		(fill yes)
		(layer "F.Cu")
		(net "M_B_DQS_DN<5>")
	)
	(gr_poly
		(pts
			(xy 282.668218 -110.738412) (xy 282.793948 -110.594648) (xy 282.722066 -110.52302) (xy 282.578302 -110.64875)
			(xy 282.542488 -110.684564) (xy 282.632404 -110.77448)
		)
		(stroke
			(width 0)
			(type solid)
		)
		(fill yes)
		(layer "F.Cu")
		(net "M_E_DQS_DN<5>")
	)
	(gr_poly
		(pts
			(xy 282.68295 -45.65396) (xy 282.55722 -45.510196) (xy 282.521406 -45.474128) (xy 282.43149 -45.564044)
			(xy 282.467304 -45.599858) (xy 282.611068 -45.725588)
		)
		(stroke
			(width 0)
			(type solid)
		)
		(fill yes)
		(layer "F.Cu")
		(net "M_B_DQ<46>")
	)
	(gr_poly
		(pts
			(xy 282.731464 -109.274102) (xy 282.767532 -109.238288) (xy 282.677616 -109.148372) (xy 282.641802 -109.18444)
			(xy 282.516072 -109.32795) (xy 282.587954 -109.399832)
		)
		(stroke
			(width 0)
			(type solid)
		)
		(fill yes)
		(layer "F.Cu")
		(net "M_E_DQ<47>")
	)
	(gr_poly
		(pts
			(xy 282.739592 -112.067848) (xy 282.77566 -112.032034) (xy 282.685744 -111.942118) (xy 282.64993 -111.978186)
			(xy 282.5242 -112.121696) (xy 282.596082 -112.193578)
		)
		(stroke
			(width 0)
			(type solid)
		)
		(fill yes)
		(layer "F.Cu")
		(net "M_E_DQS_DP<14>")
	)
	(gr_poly
		(pts
			(xy 282.754832 -45.240702) (xy 282.718764 -45.204888) (xy 282.575254 -45.079158) (xy 282.503372 -45.15104)
			(xy 282.629102 -45.29455) (xy 282.664916 -45.330618)
		)
		(stroke
			(width 0)
			(type solid)
		)
		(fill yes)
		(layer "F.Cu")
		(net "M_B_DQ<46>")
	)
	(gr_poly
		(pts
			(xy 282.758388 -109.714284) (xy 282.884118 -109.57052) (xy 282.812236 -109.498892) (xy 282.668472 -109.624622)
			(xy 282.632658 -109.660436) (xy 282.722574 -109.750352)
		)
		(stroke
			(width 0)
			(type solid)
		)
		(fill yes)
		(layer "F.Cu")
		(net "M_E_DQ<46>")
	)
	(gr_poly
		(pts
			(xy 282.766516 -112.50803) (xy 282.892246 -112.364266) (xy 282.820364 -112.292638) (xy 282.6766 -112.418368)
			(xy 282.640786 -112.454182) (xy 282.730448 -112.543844)
		)
		(stroke
			(width 0)
			(type solid)
		)
		(fill yes)
		(layer "F.Cu")
		(net "M_E_DQ<41>")
	)
	(gr_poly
		(pts
			(xy 282.76931 -105.552748) (xy 282.76931 -105.324148) (xy 282.57627 -105.235248) (xy 282.53182 -105.235248)
			(xy 282.53182 -105.641648) (xy 282.57627 -105.641648)
		)
		(stroke
			(width 0)
			(type solid)
		)
		(fill yes)
		(layer "F.Cu")
		(net "M_E_DQ<43>")
	)
	(gr_poly
		(pts
			(xy 282.76931 -104.562148) (xy 282.76931 -104.333548) (xy 282.57627 -104.244648) (xy 282.53182 -104.244648)
			(xy 282.53182 -104.651048) (xy 282.57627 -104.651048)
		)
		(stroke
			(width 0)
			(type solid)
		)
		(fill yes)
		(layer "F.Cu")
		(net "M_E_DQ<43>")
	)
	(gr_poly
		(pts
			(xy 282.772866 -46.677834) (xy 282.64739 -46.53407) (xy 282.611322 -46.498256) (xy 282.52166 -46.587918)
			(xy 282.557474 -46.623986) (xy 282.701238 -46.749716)
		)
		(stroke
			(width 0)
			(type solid)
		)
		(fill yes)
		(layer "F.Cu")
		(net "M_B_DQ<42>")
	)
	(gr_poly
		(pts
			(xy 282.781248 -43.884342) (xy 282.655518 -43.740578) (xy 282.619704 -43.704764) (xy 282.529788 -43.79468)
			(xy 282.565856 -43.830494) (xy 282.70962 -43.956224)
		)
		(stroke
			(width 0)
			(type solid)
		)
		(fill yes)
		(layer "F.Cu")
		(net "M_B_DQS_DN<14>")
	)
	(gr_poly
		(pts
			(xy 282.821634 -108.250228) (xy 282.857448 -108.21416) (xy 282.767786 -108.124498) (xy 282.731718 -108.160312)
			(xy 282.605988 -108.304076) (xy 282.67787 -108.375958)
		)
		(stroke
			(width 0)
			(type solid)
		)
		(fill yes)
		(layer "F.Cu")
		(net "M_E_DQ<43>")
	)
	(gr_poly
		(pts
			(xy 282.824428 -48.74387) (xy 282.698698 -48.60036) (xy 282.662884 -48.564292) (xy 282.572968 -48.654208)
			(xy 282.608782 -48.690022) (xy 282.752546 -48.815752)
		)
		(stroke
			(width 0)
			(type solid)
		)
		(fill yes)
		(layer "F.Cu")
		(net "M_B_DQ<52>")
	)
	(gr_poly
		(pts
			(xy 282.829762 -111.04372) (xy 282.86583 -111.007906) (xy 282.775914 -110.91799) (xy 282.7401 -110.954058)
			(xy 282.61437 -111.097568) (xy 282.686252 -111.16945)
		)
		(stroke
			(width 0)
			(type solid)
		)
		(fill yes)
		(layer "F.Cu")
		(net "M_E_DQS_DN<5>")
	)
	(gr_poly
		(pts
			(xy 282.844748 -46.26483) (xy 282.808934 -46.228762) (xy 282.66517 -46.103032) (xy 282.593288 -46.174914)
			(xy 282.719018 -46.318678) (xy 282.755086 -46.354492)
		)
		(stroke
			(width 0)
			(type solid)
		)
		(fill yes)
		(layer "F.Cu")
		(net "M_B_DQ<42>")
	)
	(gr_poly
		(pts
			(xy 282.848558 -108.69041) (xy 282.974034 -108.546646) (xy 282.902406 -108.474764) (xy 282.758642 -108.600494)
			(xy 282.722828 -108.636562) (xy 282.81249 -108.726224)
		)
		(stroke
			(width 0)
			(type solid)
		)
		(fill yes)
		(layer "F.Cu")
		(net "M_E_DQ<42>")
	)
	(gr_poly
		(pts
			(xy 282.852368 -52.982114) (xy 282.860496 -52.790344) (xy 282.669234 -52.679854) (xy 282.507182 -52.782724)
			(xy 282.48483 -52.821078) (xy 282.83027 -53.020722)
		)
		(stroke
			(width 0)
			(type solid)
		)
		(fill yes)
		(layer "F.Cu")
		(net "M_B_DQ<53>")
	)
	(gr_poly
		(pts
			(xy 282.85313 -43.471338) (xy 282.817316 -43.43527) (xy 282.673552 -43.30954) (xy 282.60167 -43.381422)
			(xy 282.7274 -43.525186) (xy 282.763468 -43.561)
		)
		(stroke
			(width 0)
			(type solid)
		)
		(fill yes)
		(layer "F.Cu")
		(net "M_B_DQS_DN<14>")
	)
	(gr_poly
		(pts
			(xy 282.856432 -111.484156) (xy 282.982162 -111.340392) (xy 282.910534 -111.26851) (xy 282.76677 -111.39424)
			(xy 282.730702 -111.430054) (xy 282.820618 -111.51997)
		)
		(stroke
			(width 0)
			(type solid)
		)
		(fill yes)
		(layer "F.Cu")
		(net "M_E_DQS_DN<14>")
	)
	(gr_poly
		(pts
			(xy 282.871418 -44.90847) (xy 282.745688 -44.764706) (xy 282.709874 -44.728638) (xy 282.619958 -44.818554)
			(xy 282.655772 -44.854368) (xy 282.799536 -44.980098)
		)
		(stroke
			(width 0)
			(type solid)
		)
		(fill yes)
		(layer "F.Cu")
		(net "M_B_DQS_DP<5>")
	)
	(gr_poly
		(pts
			(xy 282.87472 -107.880404) (xy 282.87472 -107.778804) (xy 282.68422 -107.766104) (xy 282.63342 -107.766104)
			(xy 282.63342 -107.893104) (xy 282.68422 -107.893104)
		)
		(stroke
			(width 0)
			(type solid)
		)
		(fill yes)
		(layer "F.Cu")
		(net "M_E_DQ<43>")
	)
	(gr_poly
		(pts
			(xy 282.87472 -107.220004) (xy 282.87472 -107.118404) (xy 282.68422 -107.105704) (xy 282.63342 -107.105704)
			(xy 282.63342 -107.232704) (xy 282.68422 -107.232704)
		)
		(stroke
			(width 0)
			(type solid)
		)
		(fill yes)
		(layer "F.Cu")
		(net "M_E_DQ<43>")
	)
	(gr_poly
		(pts
			(xy 282.87472 -106.559604) (xy 282.87472 -106.458004) (xy 282.68422 -106.445304) (xy 282.63342 -106.445304)
			(xy 282.63342 -106.572304) (xy 282.68422 -106.572304)
		)
		(stroke
			(width 0)
			(type solid)
		)
		(fill yes)
		(layer "F.Cu")
		(net "M_E_DQ<43>")
	)
	(gr_poly
		(pts
			(xy 282.89631 -48.330866) (xy 282.860242 -48.295052) (xy 282.716732 -48.169322) (xy 282.64485 -48.241204)
			(xy 282.77058 -48.384714) (xy 282.806394 -48.420782)
		)
		(stroke
			(width 0)
			(type solid)
		)
		(fill yes)
		(layer "F.Cu")
		(net "M_B_DQ<52>")
	)
	(gr_poly
		(pts
			(xy 282.908248 -42.104056) (xy 282.857448 -42.104056) (xy 282.666948 -42.116756) (xy 282.666948 -42.218356)
			(xy 282.857448 -42.231056) (xy 282.908248 -42.231056)
		)
		(stroke
			(width 0)
			(type solid)
		)
		(fill yes)
		(layer "F.Cu")
		(net "M_B_DQS_DP<14>")
	)
	(gr_poly
		(pts
			(xy 282.908248 -41.443656) (xy 282.857448 -41.443656) (xy 282.666948 -41.456356) (xy 282.666948 -41.557956)
			(xy 282.857448 -41.570656) (xy 282.908248 -41.570656)
		)
		(stroke
			(width 0)
			(type solid)
		)
		(fill yes)
		(layer "F.Cu")
		(net "M_B_DQS_DP<14>")
	)
	(gr_poly
		(pts
			(xy 282.919424 -50.802032) (xy 282.874974 -50.802032) (xy 282.704794 -50.890932) (xy 282.704794 -51.111912)
			(xy 282.874974 -51.200812) (xy 282.919424 -51.200812)
		)
		(stroke
			(width 0)
			(type solid)
		)
		(fill yes)
		(layer "F.Cu")
		(net "M_B_DQ<48>")
	)
	(gr_poly
		(pts
			(xy 282.919424 -49.811432) (xy 282.874974 -49.811432) (xy 282.704794 -49.900332) (xy 282.704794 -50.121312)
			(xy 282.874974 -50.210212) (xy 282.919424 -50.210212)
		)
		(stroke
			(width 0)
			(type solid)
		)
		(fill yes)
		(layer "F.Cu")
		(net "M_B_DQ<48>")
	)
	(gr_poly
		(pts
			(xy 282.919932 -110.019592) (xy 282.956 -109.983778) (xy 282.866084 -109.893862) (xy 282.83027 -109.92993)
			(xy 282.70454 -110.07344) (xy 282.776422 -110.145322)
		)
		(stroke
			(width 0)
			(type solid)
		)
		(fill yes)
		(layer "F.Cu")
		(net "M_E_DQ<46>")
	)
	(gr_poly
		(pts
			(xy 282.92806 -112.813592) (xy 282.963874 -112.777524) (xy 282.874212 -112.687862) (xy 282.838144 -112.723676)
			(xy 282.712414 -112.86744) (xy 282.784296 -112.939322)
		)
		(stroke
			(width 0)
			(type solid)
		)
		(fill yes)
		(layer "F.Cu")
		(net "M_E_DQ<41>")
	)
	(gr_poly
		(pts
			(xy 282.9433 -44.495212) (xy 282.907232 -44.459398) (xy 282.763722 -44.333668) (xy 282.69184 -44.40555)
			(xy 282.81757 -44.54906) (xy 282.853384 -44.585128)
		)
		(stroke
			(width 0)
			(type solid)
		)
		(fill yes)
		(layer "F.Cu")
		(net "M_B_DQS_DP<5>")
	)
	(gr_poly
		(pts
			(xy 282.946602 -110.460028) (xy 283.072332 -110.316264) (xy 283.000704 -110.244382) (xy 282.85694 -110.370112)
			(xy 282.820872 -110.405926) (xy 282.910788 -110.495842)
		)
		(stroke
			(width 0)
			(type solid)
		)
		(fill yes)
		(layer "F.Cu")
		(net "M_E_DQS_DP<5>")
	)
	(gr_poly
		(pts
			(xy 282.961334 -45.932344) (xy 282.835604 -45.78858) (xy 282.79979 -45.752766) (xy 282.710128 -45.842428)
			(xy 282.745942 -45.878496) (xy 282.889706 -46.004226)
		)
		(stroke
			(width 0)
			(type solid)
		)
		(fill yes)
		(layer "F.Cu")
		(net "M_B_DQ<47>")
	)
	(gr_poly
		(pts
			(xy 282.969716 -43.138852) (xy 282.843986 -42.995088) (xy 282.808172 -42.959274) (xy 282.718256 -43.04919)
			(xy 282.754324 -43.085004) (xy 282.898088 -43.210734)
		)
		(stroke
			(width 0)
			(type solid)
		)
		(fill yes)
		(layer "F.Cu")
		(net "M_B_DQS_DP<14>")
	)
	(gr_poly
		(pts
			(xy 283.010102 -108.995718) (xy 283.045916 -108.95965) (xy 282.956254 -108.869988) (xy 282.920186 -108.905802)
			(xy 282.794456 -109.049566) (xy 282.866338 -109.121448)
		)
		(stroke
			(width 0)
			(type solid)
		)
		(fill yes)
		(layer "F.Cu")
		(net "M_E_DQ<42>")
	)
	(gr_poly
		(pts
			(xy 283.01823 -111.789464) (xy 283.054044 -111.753396) (xy 282.964382 -111.663734) (xy 282.928314 -111.699548)
			(xy 282.802584 -111.843312) (xy 282.874466 -111.915194)
		)
		(stroke
			(width 0)
			(type solid)
		)
		(fill yes)
		(layer "F.Cu")
		(net "M_E_DQS_DN<14>")
	)
	(gr_poly
		(pts
			(xy 283.033216 -45.51934) (xy 282.997402 -45.483272) (xy 282.853638 -45.357542) (xy 282.781756 -45.429424)
			(xy 282.907486 -45.573188) (xy 282.943554 -45.609002)
		)
		(stroke
			(width 0)
			(type solid)
		)
		(fill yes)
		(layer "F.Cu")
		(net "M_B_DQ<47>")
	)
	(gr_poly
		(pts
			(xy 283.036772 -109.4359) (xy 283.162502 -109.292136) (xy 283.090874 -109.220254) (xy 282.94711 -109.345984)
			(xy 282.911296 -109.382052) (xy 283.000958 -109.471714)
		)
		(stroke
			(width 0)
			(type solid)
		)
		(fill yes)
		(layer "F.Cu")
		(net "M_E_DQ<47>")
	)
	(gr_poly
		(pts
			(xy 283.0449 -112.229646) (xy 283.17063 -112.085882) (xy 283.099002 -112.014) (xy 282.955238 -112.13973)
			(xy 282.91917 -112.175544) (xy 283.009086 -112.26546)
		)
		(stroke
			(width 0)
			(type solid)
		)
		(fill yes)
		(layer "F.Cu")
		(net "M_E_DQS_DP<14>")
	)
	(gr_poly
		(pts
			(xy 283.051504 -46.956472) (xy 282.925774 -46.812708) (xy 282.88996 -46.77664) (xy 282.800044 -46.866556)
			(xy 282.835858 -46.90237) (xy 282.979622 -47.0281)
		)
		(stroke
			(width 0)
			(type solid)
		)
		(fill yes)
		(layer "F.Cu")
		(net "M_B_DQ<43>")
	)
	(gr_poly
		(pts
			(xy 283.059886 -44.16298) (xy 282.934156 -44.019216) (xy 282.898342 -43.983148) (xy 282.808426 -44.073064)
			(xy 282.84424 -44.108878) (xy 282.988004 -44.234608)
		)
		(stroke
			(width 0)
			(type solid)
		)
		(fill yes)
		(layer "F.Cu")
		(net "M_B_DQS_DN<5>")
	)
	(gr_poly
		(pts
			(xy 283.103066 -49.022508) (xy 282.977336 -48.878744) (xy 282.941268 -48.84293) (xy 282.851606 -48.932592)
			(xy 282.88742 -48.96866) (xy 283.031184 -49.09439)
		)
		(stroke
			(width 0)
			(type solid)
		)
		(fill yes)
		(layer "F.Cu")
		(net "M_B_DQ<53>")
	)
	(gr_poly
		(pts
			(xy 283.1084 -110.765336) (xy 283.144214 -110.729268) (xy 283.054552 -110.639606) (xy 283.018484 -110.67542)
			(xy 282.892754 -110.819184) (xy 282.964636 -110.891066)
		)
		(stroke
			(width 0)
			(type solid)
		)
		(fill yes)
		(layer "F.Cu")
		(net "M_E_DQS_DP<5>")
	)
	(gr_poly
		(pts
			(xy 283.123386 -46.543214) (xy 283.087318 -46.5074) (xy 282.943808 -46.38167) (xy 282.871926 -46.453552)
			(xy 282.997656 -46.597062) (xy 283.03347 -46.63313)
		)
		(stroke
			(width 0)
			(type solid)
		)
		(fill yes)
		(layer "F.Cu")
		(net "M_B_DQ<43>")
	)
	(gr_poly
		(pts
			(xy 283.126942 -108.411772) (xy 283.252672 -108.268008) (xy 283.18079 -108.19638) (xy 283.037026 -108.32211)
			(xy 283.001212 -108.357924) (xy 283.091128 -108.44784)
		)
		(stroke
			(width 0)
			(type solid)
		)
		(fill yes)
		(layer "F.Cu")
		(net "M_E_DQ<43>")
	)
	(gr_poly
		(pts
			(xy 283.131768 -43.749722) (xy 283.0957 -43.713908) (xy 282.95219 -43.588178) (xy 282.880308 -43.66006)
			(xy 283.006038 -43.80357) (xy 283.041852 -43.839638)
		)
		(stroke
			(width 0)
			(type solid)
		)
		(fill yes)
		(layer "F.Cu")
		(net "M_B_DQS_DN<5>")
	)
	(gr_poly
		(pts
			(xy 283.13507 -111.205518) (xy 283.2608 -111.061754) (xy 283.189172 -110.989872) (xy 283.045408 -111.115602)
			(xy 283.00934 -111.151416) (xy 283.099256 -111.241332)
		)
		(stroke
			(width 0)
			(type solid)
		)
		(fill yes)
		(layer "F.Cu")
		(net "M_E_DQS_DN<5>")
	)
	(gr_poly
		(pts
			(xy 283.149548 -42.548556) (xy 283.149548 -42.446956) (xy 282.959048 -42.434256) (xy 282.908248 -42.434256)
			(xy 282.908248 -42.561256) (xy 282.959048 -42.561256)
		)
		(stroke
			(width 0)
			(type solid)
		)
		(fill yes)
		(layer "F.Cu")
		(net "M_B_DQS_DP<14>")
	)
	(gr_poly
		(pts
			(xy 283.149548 -41.888156) (xy 283.149548 -41.786556) (xy 282.959048 -41.773856) (xy 282.908248 -41.773856)
			(xy 282.908248 -41.900856) (xy 282.959048 -41.900856)
		)
		(stroke
			(width 0)
			(type solid)
		)
		(fill yes)
		(layer "F.Cu")
		(net "M_B_DQS_DP<14>")
	)
	(gr_poly
		(pts
			(xy 283.149802 -45.186854) (xy 283.024072 -45.04309) (xy 282.988258 -45.007276) (xy 282.898342 -45.097192)
			(xy 282.93441 -45.133006) (xy 283.078174 -45.258736)
		)
		(stroke
			(width 0)
			(type solid)
		)
		(fill yes)
		(layer "F.Cu")
		(net "M_B_DQ<46>")
	)
	(gr_poly
		(pts
			(xy 283.174694 -48.609504) (xy 283.13888 -48.573436) (xy 282.995116 -48.447706) (xy 282.923234 -48.519588)
			(xy 283.048964 -48.663352) (xy 283.085032 -48.699166)
		)
		(stroke
			(width 0)
			(type solid)
		)
		(fill yes)
		(layer "F.Cu")
		(net "M_B_DQ<53>")
	)
	(gr_poly
		(pts
			(xy 283.19857 -109.741208) (xy 283.234384 -109.70514) (xy 283.144722 -109.615478) (xy 283.108654 -109.651292)
			(xy 282.982924 -109.795056) (xy 283.054806 -109.866938)
		)
		(stroke
			(width 0)
			(type solid)
		)
		(fill yes)
		(layer "F.Cu")
		(net "M_E_DQ<47>")
	)
	(gr_poly
		(pts
			(xy 283.206698 -112.534954) (xy 283.242512 -112.498886) (xy 283.15285 -112.409224) (xy 283.116782 -112.445038)
			(xy 282.991052 -112.588802) (xy 283.062934 -112.660684)
		)
		(stroke
			(width 0)
			(type solid)
		)
		(fill yes)
		(layer "F.Cu")
		(net "M_E_DQS_DP<14>")
	)
	(gr_poly
		(pts
			(xy 283.221684 -44.77385) (xy 283.18587 -44.737782) (xy 283.042106 -44.612052) (xy 282.970224 -44.683934)
			(xy 283.095954 -44.827698) (xy 283.132022 -44.863512)
		)
		(stroke
			(width 0)
			(type solid)
		)
		(fill yes)
		(layer "F.Cu")
		(net "M_B_DQ<46>")
	)
	(gr_poly
		(pts
			(xy 283.22524 -110.18139) (xy 283.35097 -110.037626) (xy 283.279342 -109.965744) (xy 283.135578 -110.091474)
			(xy 283.09951 -110.127288) (xy 283.189426 -110.217204)
		)
		(stroke
			(width 0)
			(type solid)
		)
		(fill yes)
		(layer "F.Cu")
		(net "M_E_DQ<46>")
	)
	(gr_poly
		(pts
			(xy 283.239972 -46.210982) (xy 283.114242 -46.067218) (xy 283.078428 -46.03115) (xy 282.988512 -46.121066)
			(xy 283.024326 -46.15688) (xy 283.16809 -46.28261)
		)
		(stroke
			(width 0)
			(type solid)
		)
		(fill yes)
		(layer "F.Cu")
		(net "M_B_DQ<42>")
	)
	(gr_poly
		(pts
			(xy 283.248354 -43.41749) (xy 283.122624 -43.273726) (xy 283.086556 -43.237912) (xy 282.996894 -43.327574)
			(xy 283.032708 -43.363388) (xy 283.176472 -43.489118)
		)
		(stroke
			(width 0)
			(type solid)
		)
		(fill yes)
		(layer "F.Cu")
		(net "M_B_DQS_DN<14>")
	)
	(gr_poly
		(pts
			(xy 283.288486 -108.71708) (xy 283.324554 -108.681266) (xy 283.234638 -108.59135) (xy 283.198824 -108.627418)
			(xy 283.073094 -108.770928) (xy 283.144976 -108.84281)
		)
		(stroke
			(width 0)
			(type solid)
		)
		(fill yes)
		(layer "F.Cu")
		(net "M_E_DQ<43>")
	)
	(gr_poly
		(pts
			(xy 283.291534 -48.277018) (xy 283.165804 -48.133254) (xy 283.129736 -48.09744) (xy 283.040074 -48.187102)
			(xy 283.075888 -48.22317) (xy 283.219652 -48.3489)
		)
		(stroke
			(width 0)
			(type solid)
		)
		(fill yes)
		(layer "F.Cu")
		(net "M_B_DQ<52>")
	)
	(gr_poly
		(pts
			(xy 283.296868 -111.510826) (xy 283.332682 -111.474758) (xy 283.24302 -111.385096) (xy 283.206952 -111.42091)
			(xy 283.081222 -111.564674) (xy 283.153104 -111.636556)
		)
		(stroke
			(width 0)
			(type solid)
		)
		(fill yes)
		(layer "F.Cu")
		(net "M_E_DQS_DN<5>")
	)
	(gr_poly
		(pts
			(xy 283.301948 -42.764456) (xy 283.251148 -42.764456) (xy 283.060648 -42.777156) (xy 283.060648 -42.878756)
			(xy 283.251148 -42.891456) (xy 283.301948 -42.891456)
		)
		(stroke
			(width 0)
			(type solid)
		)
		(fill yes)
		(layer "F.Cu")
		(net "M_B_DQS_DN<14>")
	)
	(gr_poly
		(pts
			(xy 283.301948 -42.104056) (xy 283.251148 -42.104056) (xy 283.060648 -42.116756) (xy 283.060648 -42.218356)
			(xy 283.251148 -42.231056) (xy 283.301948 -42.231056)
		)
		(stroke
			(width 0)
			(type solid)
		)
		(fill yes)
		(layer "F.Cu")
		(net "M_B_DQS_DN<14>")
	)
	(gr_poly
		(pts
			(xy 283.301948 -41.443656) (xy 283.251148 -41.443656) (xy 283.060648 -41.456356) (xy 283.060648 -41.557956)
			(xy 283.251148 -41.570656) (xy 283.301948 -41.570656)
		)
		(stroke
			(width 0)
			(type solid)
		)
		(fill yes)
		(layer "F.Cu")
		(net "M_B_DQS_DN<14>")
	)
	(gr_poly
		(pts
			(xy 283.311854 -45.797724) (xy 283.275786 -45.76191) (xy 283.132276 -45.63618) (xy 283.060394 -45.708062)
			(xy 283.186124 -45.851572) (xy 283.221938 -45.88764)
		)
		(stroke
			(width 0)
			(type solid)
		)
		(fill yes)
		(layer "F.Cu")
		(net "M_B_DQ<42>")
	)
	(gr_poly
		(pts
			(xy 283.31541 -109.157262) (xy 283.44114 -109.013498) (xy 283.369258 -108.94187) (xy 283.225494 -109.0676)
			(xy 283.18968 -109.103414) (xy 283.279596 -109.19333)
		)
		(stroke
			(width 0)
			(type solid)
		)
		(fill yes)
		(layer "F.Cu")
		(net "M_E_DQ<42>")
	)
	(gr_poly
		(pts
			(xy 283.323538 -111.951008) (xy 283.449268 -111.807244) (xy 283.377386 -111.735616) (xy 283.233622 -111.861346)
			(xy 283.197808 -111.89716) (xy 283.28747 -111.986822)
		)
		(stroke
			(width 0)
			(type solid)
		)
		(fill yes)
		(layer "F.Cu")
		(net "M_E_DQS_DN<14>")
	)
	(gr_poly
		(pts
			(xy 283.324554 -51.111912) (xy 283.324554 -50.890932) (xy 283.154374 -50.802032) (xy 283.109924 -50.802032)
			(xy 283.109924 -51.200812) (xy 283.154374 -51.200812)
		)
		(stroke
			(width 0)
			(type solid)
		)
		(fill yes)
		(layer "F.Cu")
		(net "M_B_DQ<49>")
	)
	(gr_poly
		(pts
			(xy 283.324554 -50.121312) (xy 283.324554 -49.900332) (xy 283.154374 -49.811432) (xy 283.109924 -49.811432)
			(xy 283.109924 -50.210212) (xy 283.154374 -50.210212)
		)
		(stroke
			(width 0)
			(type solid)
		)
		(fill yes)
		(layer "F.Cu")
		(net "M_B_DQ<49>")
	)
	(gr_poly
		(pts
			(xy 283.33827 -44.441364) (xy 283.21254 -44.2976) (xy 283.176726 -44.261786) (xy 283.08681 -44.351702)
			(xy 283.122878 -44.387516) (xy 283.266642 -44.513246)
		)
		(stroke
			(width 0)
			(type solid)
		)
		(fill yes)
		(layer "F.Cu")
		(net "M_B_DQS_DP<5>")
	)
	(gr_poly
		(pts
			(xy 283.363162 -47.864014) (xy 283.327348 -47.827946) (xy 283.183584 -47.702216) (xy 283.111702 -47.774098)
			(xy 283.237432 -47.917862) (xy 283.2735 -47.953676)
		)
		(stroke
			(width 0)
			(type solid)
		)
		(fill yes)
		(layer "F.Cu")
		(net "M_B_DQ<52>")
	)
	(gr_poly
		(pts
			(xy 283.38145 -49.300892) (xy 283.25572 -49.157382) (xy 283.219906 -49.121314) (xy 283.12999 -49.21123)
			(xy 283.165804 -49.247044) (xy 283.309568 -49.372774)
		)
		(stroke
			(width 0)
			(type solid)
		)
		(fill yes)
		(layer "F.Cu")
		(net "M_B_DQ<48>")
	)
	(gr_poly
		(pts
			(xy 283.387038 -110.486698) (xy 283.422852 -110.45063) (xy 283.33319 -110.360968) (xy 283.297122 -110.396782)
			(xy 283.171392 -110.540546) (xy 283.243274 -110.612428)
		)
		(stroke
			(width 0)
			(type solid)
		)
		(fill yes)
		(layer "F.Cu")
		(net "M_E_DQ<46>")
	)
	(gr_poly
		(pts
			(xy 283.410152 -44.02836) (xy 283.374338 -43.992292) (xy 283.230574 -43.866562) (xy 283.158692 -43.938444)
			(xy 283.284422 -44.082208) (xy 283.32049 -44.118022)
		)
		(stroke
			(width 0)
			(type solid)
		)
		(fill yes)
		(layer "F.Cu")
		(net "M_B_DQS_DP<5>")
	)
	(gr_poly
		(pts
			(xy 283.413708 -110.92688) (xy 283.539438 -110.783116) (xy 283.467556 -110.711488) (xy 283.323792 -110.837218)
			(xy 283.287978 -110.873032) (xy 283.377894 -110.962948)
		)
		(stroke
			(width 0)
			(type solid)
		)
		(fill yes)
		(layer "F.Cu")
		(net "M_E_DQS_DP<5>")
	)
	(gr_poly
		(pts
			(xy 283.42844 -45.465492) (xy 283.30271 -45.321728) (xy 283.266896 -45.28566) (xy 283.17698 -45.375576)
			(xy 283.212794 -45.41139) (xy 283.356558 -45.53712)
		)
		(stroke
			(width 0)
			(type solid)
		)
		(fill yes)
		(layer "F.Cu")
		(net "M_B_DQ<47>")
	)
	(gr_poly
		(pts
			(xy 283.453332 -48.887888) (xy 283.417264 -48.852074) (xy 283.273754 -48.726344) (xy 283.201872 -48.798226)
			(xy 283.327602 -48.941736) (xy 283.363416 -48.977804)
		)
		(stroke
			(width 0)
			(type solid)
		)
		(fill yes)
		(layer "F.Cu")
		(net "M_B_DQ<48>")
	)
	(gr_poly
		(pts
			(xy 283.464 -104.639872) (xy 283.4132 -104.639872) (xy 283.22016 -104.728772) (xy 283.22016 -104.957372)
			(xy 283.4132 -105.046272) (xy 283.464 -105.046272)
		)
		(stroke
			(width 0)
			(type solid)
		)
		(fill yes)
		(layer "F.Cu")
		(net "M_E_DQ<52>")
	)
	(gr_poly
		(pts
			(xy 283.476954 -109.46257) (xy 283.513022 -109.426756) (xy 283.423106 -109.33684) (xy 283.387292 -109.372908)
			(xy 283.261562 -109.516418) (xy 283.333444 -109.5883)
		)
		(stroke
			(width 0)
			(type solid)
		)
		(fill yes)
		(layer "F.Cu")
		(net "M_E_DQ<42>")
	)
	(gr_poly
		(pts
			(xy 283.485082 -112.256316) (xy 283.52115 -112.220502) (xy 283.431234 -112.130586) (xy 283.39542 -112.166654)
			(xy 283.26969 -112.310164) (xy 283.341572 -112.382046)
		)
		(stroke
			(width 0)
			(type solid)
		)
		(fill yes)
		(layer "F.Cu")
		(net "M_E_DQS_DN<14>")
	)
	(gr_poly
		(pts
			(xy 283.500322 -45.052234) (xy 283.464254 -45.01642) (xy 283.320744 -44.89069) (xy 283.248862 -44.962572)
			(xy 283.374592 -45.106082) (xy 283.410406 -45.14215)
		)
		(stroke
			(width 0)
			(type solid)
		)
		(fill yes)
		(layer "F.Cu")
		(net "M_B_DQ<47>")
	)
	(gr_poly
		(pts
			(xy 283.503878 -109.902752) (xy 283.629608 -109.758988) (xy 283.557726 -109.68736) (xy 283.413962 -109.81309)
			(xy 283.378148 -109.848904) (xy 283.468064 -109.93882)
		)
		(stroke
			(width 0)
			(type solid)
		)
		(fill yes)
		(layer "F.Cu")
		(net "M_E_DQ<47>")
	)
	(gr_poly
		(pts
			(xy 283.512006 -112.696498) (xy 283.637736 -112.552734) (xy 283.565854 -112.481106) (xy 283.42209 -112.606582)
			(xy 283.386276 -112.64265) (xy 283.475938 -112.732312)
		)
		(stroke
			(width 0)
			(type solid)
		)
		(fill yes)
		(layer "F.Cu")
		(net "M_E_DQS_DP<14>")
	)
	(gr_poly
		(pts
			(xy 283.518356 -46.489366) (xy 283.392626 -46.345602) (xy 283.356812 -46.309788) (xy 283.26715 -46.39945)
			(xy 283.302964 -46.435518) (xy 283.446728 -46.561248)
		)
		(stroke
			(width 0)
			(type solid)
		)
		(fill yes)
		(layer "F.Cu")
		(net "M_B_DQ<43>")
	)
	(gr_poly
		(pts
			(xy 283.526738 -43.695874) (xy 283.401008 -43.55211) (xy 283.365194 -43.516296) (xy 283.275278 -43.606212)
			(xy 283.311346 -43.642026) (xy 283.45511 -43.767756)
		)
		(stroke
			(width 0)
			(type solid)
		)
		(fill yes)
		(layer "F.Cu")
		(net "M_B_DQS_DN<5>")
	)
	(gr_poly
		(pts
			(xy 283.543248 -42.548556) (xy 283.543248 -42.446956) (xy 283.352748 -42.434256) (xy 283.301948 -42.434256)
			(xy 283.301948 -42.561256) (xy 283.352748 -42.561256)
		)
		(stroke
			(width 0)
			(type solid)
		)
		(fill yes)
		(layer "F.Cu")
		(net "M_B_DQS_DN<14>")
	)
	(gr_poly
		(pts
			(xy 283.543248 -41.888156) (xy 283.543248 -41.786556) (xy 283.352748 -41.773856) (xy 283.301948 -41.773856)
			(xy 283.301948 -41.900856) (xy 283.352748 -41.900856)
		)
		(stroke
			(width 0)
			(type solid)
		)
		(fill yes)
		(layer "F.Cu")
		(net "M_B_DQS_DN<14>")
	)
	(gr_poly
		(pts
			(xy 283.569918 -48.555656) (xy 283.444188 -48.411892) (xy 283.408374 -48.375824) (xy 283.318458 -48.46574)
			(xy 283.354272 -48.501554) (xy 283.498036 -48.627284)
		)
		(stroke
			(width 0)
			(type solid)
		)
		(fill yes)
		(layer "F.Cu")
		(net "M_B_DQ<53>")
	)
	(gr_poly
		(pts
			(xy 283.575252 -111.232188) (xy 283.61132 -111.196374) (xy 283.521404 -111.106458) (xy 283.48559 -111.142526)
			(xy 283.35986 -111.286036) (xy 283.431742 -111.357918)
		)
		(stroke
			(width 0)
			(type solid)
		)
		(fill yes)
		(layer "F.Cu")
		(net "M_E_DQS_DP<5>")
	)
	(gr_poly
		(pts
			(xy 283.590238 -46.076362) (xy 283.554424 -46.040294) (xy 283.41066 -45.914564) (xy 283.338778 -45.986446)
			(xy 283.464508 -46.13021) (xy 283.500576 -46.166024)
		)
		(stroke
			(width 0)
			(type solid)
		)
		(fill yes)
		(layer "F.Cu")
		(net "M_B_DQ<43>")
	)
	(gr_poly
		(pts
			(xy 283.593794 -108.878878) (xy 283.719524 -108.735114) (xy 283.647896 -108.663232) (xy 283.504132 -108.788962)
			(xy 283.468318 -108.82503) (xy 283.55798 -108.914692)
		)
		(stroke
			(width 0)
			(type solid)
		)
		(fill yes)
		(layer "F.Cu")
		(net "M_E_DQ<43>")
	)
	(gr_poly
		(pts
			(xy 283.59862 -43.28287) (xy 283.562806 -43.246802) (xy 283.419042 -43.121072) (xy 283.34716 -43.192954)
			(xy 283.47289 -43.336718) (xy 283.508958 -43.372532)
		)
		(stroke
			(width 0)
			(type solid)
		)
		(fill yes)
		(layer "F.Cu")
		(net "M_B_DQS_DN<5>")
	)
	(gr_poly
		(pts
			(xy 283.602176 -111.67237) (xy 283.727906 -111.528606) (xy 283.656024 -111.456978) (xy 283.51226 -111.582708)
			(xy 283.476446 -111.618522) (xy 283.566108 -111.708184)
		)
		(stroke
			(width 0)
			(type solid)
		)
		(fill yes)
		(layer "F.Cu")
		(net "M_E_DQS_DN<5>")
	)
	(gr_poly
		(pts
			(xy 283.616908 -44.720002) (xy 283.491178 -44.576238) (xy 283.455364 -44.54017) (xy 283.365448 -44.630086)
			(xy 283.401262 -44.6659) (xy 283.545026 -44.79163)
		)
		(stroke
			(width 0)
			(type solid)
		)
		(fill yes)
		(layer "F.Cu")
		(net "M_B_DQ<46>")
	)
	(gr_poly
		(pts
			(xy 283.6418 -48.142398) (xy 283.605732 -48.106584) (xy 283.462222 -47.980854) (xy 283.39034 -48.052736)
			(xy 283.51607 -48.196246) (xy 283.551884 -48.232314)
		)
		(stroke
			(width 0)
			(type solid)
		)
		(fill yes)
		(layer "F.Cu")
		(net "M_B_DQ<53>")
	)
	(gr_poly
		(pts
			(xy 283.665422 -110.20806) (xy 283.70149 -110.172246) (xy 283.611574 -110.08233) (xy 283.57576 -110.118398)
			(xy 283.45003 -110.261908) (xy 283.521912 -110.33379)
		)
		(stroke
			(width 0)
			(type solid)
		)
		(fill yes)
		(layer "F.Cu")
		(net "M_E_DQ<47>")
	)
	(gr_poly
		(pts
			(xy 283.68879 -44.306744) (xy 283.652722 -44.27093) (xy 283.509212 -44.1452) (xy 283.43733 -44.217082)
			(xy 283.56306 -44.360592) (xy 283.598874 -44.39666)
		)
		(stroke
			(width 0)
			(type solid)
		)
		(fill yes)
		(layer "F.Cu")
		(net "M_B_DQ<46>")
	)
	(gr_poly
		(pts
			(xy 283.692346 -110.648242) (xy 283.818076 -110.504478) (xy 283.746194 -110.43285) (xy 283.60243 -110.55858)
			(xy 283.566616 -110.594394) (xy 283.656532 -110.68431)
		)
		(stroke
			(width 0)
			(type solid)
		)
		(fill yes)
		(layer "F.Cu")
		(net "M_E_DQ<46>")
	)
	(gr_poly
		(pts
			(xy 283.706824 -45.743876) (xy 283.581094 -45.600112) (xy 283.54528 -45.564298) (xy 283.455364 -45.654214)
			(xy 283.491432 -45.690028) (xy 283.635196 -45.815758)
		)
		(stroke
			(width 0)
			(type solid)
		)
		(fill yes)
		(layer "F.Cu")
		(net "M_B_DQ<42>")
	)
	(gr_poly
		(pts
			(xy 283.731716 -49.166526) (xy 283.695902 -49.130458) (xy 283.552138 -49.004728) (xy 283.480256 -49.07661)
			(xy 283.605986 -49.220374) (xy 283.642054 -49.256188)
		)
		(stroke
			(width 0)
			(type solid)
		)
		(fill yes)
		(layer "F.Cu")
		(net "M_B_DQ<49>")
	)
	(gr_poly
		(pts
			(xy 283.755592 -109.184186) (xy 283.791406 -109.148118) (xy 283.701744 -109.058456) (xy 283.665676 -109.09427)
			(xy 283.539946 -109.238034) (xy 283.611828 -109.309916)
		)
		(stroke
			(width 0)
			(type solid)
		)
		(fill yes)
		(layer "F.Cu")
		(net "M_E_DQ<43>")
	)
	(gr_poly
		(pts
			(xy 283.758386 -47.810166) (xy 283.632656 -47.666402) (xy 283.596842 -47.630334) (xy 283.506926 -47.72025)
			(xy 283.54274 -47.756064) (xy 283.686504 -47.881794)
		)
		(stroke
			(width 0)
			(type solid)
		)
		(fill yes)
		(layer "F.Cu")
		(net "M_B_DQ<52>")
	)
	(gr_poly
		(pts
			(xy 283.76372 -111.977678) (xy 283.799788 -111.941864) (xy 283.709872 -111.851948) (xy 283.674058 -111.888016)
			(xy 283.548328 -112.031526) (xy 283.62021 -112.103408)
		)
		(stroke
			(width 0)
			(type solid)
		)
		(fill yes)
		(layer "F.Cu")
		(net "M_E_DQS_DN<5>")
	)
	(gr_poly
		(pts
			(xy 283.778706 -45.330872) (xy 283.742892 -45.294804) (xy 283.599128 -45.169074) (xy 283.527246 -45.240956)
			(xy 283.652976 -45.38472) (xy 283.689044 -45.420534)
		)
		(stroke
			(width 0)
			(type solid)
		)
		(fill yes)
		(layer "F.Cu")
		(net "M_B_DQ<42>")
	)
	(gr_poly
		(pts
			(xy 283.782262 -109.624368) (xy 283.907992 -109.480604) (xy 283.836364 -109.408722) (xy 283.6926 -109.534452)
			(xy 283.656532 -109.570266) (xy 283.746448 -109.660182)
		)
		(stroke
			(width 0)
			(type solid)
		)
		(fill yes)
		(layer "F.Cu")
		(net "M_E_DQ<42>")
	)
	(gr_poly
		(pts
			(xy 283.79039 -112.418114) (xy 283.91612 -112.27435) (xy 283.844492 -112.202468) (xy 283.700728 -112.328198)
			(xy 283.66466 -112.364012) (xy 283.754576 -112.453928)
		)
		(stroke
			(width 0)
			(type solid)
		)
		(fill yes)
		(layer "F.Cu")
		(net "M_E_DQS_DN<14>")
	)
	(gr_poly
		(pts
			(xy 283.805376 -43.974512) (xy 283.679646 -43.830748) (xy 283.643578 -43.794934) (xy 283.553916 -43.884596)
			(xy 283.58973 -43.92041) (xy 283.733494 -44.04614)
		)
		(stroke
			(width 0)
			(type solid)
		)
		(fill yes)
		(layer "F.Cu")
		(net "M_B_DQS_DP<5>")
	)
	(gr_poly
		(pts
			(xy 283.830268 -47.396908) (xy 283.7942 -47.361094) (xy 283.65069 -47.235364) (xy 283.578808 -47.307246)
			(xy 283.704538 -47.450756) (xy 283.740352 -47.486824)
		)
		(stroke
			(width 0)
			(type solid)
		)
		(fill yes)
		(layer "F.Cu")
		(net "M_B_DQ<52>")
	)
	(gr_poly
		(pts
			(xy 283.848556 -48.83404) (xy 283.722826 -48.690276) (xy 283.686758 -48.654462) (xy 283.597096 -48.744124)
			(xy 283.63291 -48.780192) (xy 283.776674 -48.905922)
		)
		(stroke
			(width 0)
			(type solid)
		)
		(fill yes)
		(layer "F.Cu")
		(net "M_B_DQ<48>")
	)
	(gr_poly
		(pts
			(xy 283.85389 -110.95355) (xy 283.889958 -110.917736) (xy 283.800042 -110.82782) (xy 283.764228 -110.863888)
			(xy 283.638498 -111.007398) (xy 283.71038 -111.07928)
		)
		(stroke
			(width 0)
			(type solid)
		)
		(fill yes)
		(layer "F.Cu")
		(net "M_E_DQ<46>")
	)
	(gr_poly
		(pts
			(xy 283.877258 -43.561254) (xy 283.84119 -43.52544) (xy 283.69768 -43.39971) (xy 283.625798 -43.471592)
			(xy 283.751528 -43.615102) (xy 283.787342 -43.65117)
		)
		(stroke
			(width 0)
			(type solid)
		)
		(fill yes)
		(layer "F.Cu")
		(net "M_B_DQS_DP<5>")
	)
	(gr_poly
		(pts
			(xy 283.88056 -111.393986) (xy 284.00629 -111.250222) (xy 283.934662 -111.17834) (xy 283.790898 -111.30407)
			(xy 283.75483 -111.339884) (xy 283.844746 -111.4298)
		)
		(stroke
			(width 0)
			(type solid)
		)
		(fill yes)
		(layer "F.Cu")
		(net "M_E_DQS_DP<5>")
	)
	(gr_poly
		(pts
			(xy 283.895292 -44.998386) (xy 283.769562 -44.854622) (xy 283.733748 -44.818808) (xy 283.643832 -44.908724)
			(xy 283.6799 -44.944538) (xy 283.823664 -45.070268)
		)
		(stroke
			(width 0)
			(type solid)
		)
		(fill yes)
		(layer "F.Cu")
		(net "M_B_DQ<47>")
	)
	(gr_poly
		(pts
			(xy 283.895546 -106.196384) (xy 284.021276 -106.05262) (xy 283.949394 -105.980992) (xy 283.80563 -106.106722)
			(xy 283.769816 -106.142536) (xy 283.859732 -106.232452)
		)
		(stroke
			(width 0)
			(type solid)
		)
		(fill yes)
		(layer "F.Cu")
		(net "M_E_DQ<52>")
	)
	(gr_poly
		(pts
			(xy 283.89834 -104.957372) (xy 283.89834 -104.728772) (xy 283.7053 -104.639872) (xy 283.6545 -104.639872)
			(xy 283.6545 -105.046272) (xy 283.7053 -105.046272)
		)
		(stroke
			(width 0)
			(type solid)
		)
		(fill yes)
		(layer "F.Cu")
		(net "M_E_DQ<53>")
	)
	(gr_poly
		(pts
			(xy 283.920184 -48.421036) (xy 283.88437 -48.384968) (xy 283.740606 -48.259238) (xy 283.668724 -48.33112)
			(xy 283.794454 -48.474884) (xy 283.830522 -48.510698)
		)
		(stroke
			(width 0)
			(type solid)
		)
		(fill yes)
		(layer "F.Cu")
		(net "M_B_DQ<48>")
	)
	(gr_poly
		(pts
			(xy 283.94406 -109.929676) (xy 283.979874 -109.893608) (xy 283.890212 -109.803946) (xy 283.854144 -109.83976)
			(xy 283.728414 -109.983524) (xy 283.800296 -110.055406)
		)
		(stroke
			(width 0)
			(type solid)
		)
		(fill yes)
		(layer "F.Cu")
		(net "M_E_DQ<42>")
	)
	(gr_poly
		(pts
			(xy 283.952188 -112.723422) (xy 283.988002 -112.687354) (xy 283.89834 -112.597692) (xy 283.862272 -112.633506)
			(xy 283.736542 -112.77727) (xy 283.808424 -112.849152)
		)
		(stroke
			(width 0)
			(type solid)
		)
		(fill yes)
		(layer "F.Cu")
		(net "M_E_DQS_DN<14>")
	)
	(gr_poly
		(pts
			(xy 283.967174 -44.585382) (xy 283.93136 -44.549314) (xy 283.787596 -44.423584) (xy 283.715714 -44.495466)
			(xy 283.841444 -44.63923) (xy 283.877512 -44.675044)
		)
		(stroke
			(width 0)
			(type solid)
		)
		(fill yes)
		(layer "F.Cu")
		(net "M_B_DQ<47>")
	)
	(gr_poly
		(pts
			(xy 283.97073 -110.369858) (xy 284.09646 -110.226094) (xy 284.024832 -110.154212) (xy 283.881068 -110.279942)
			(xy 283.845 -110.315756) (xy 283.934916 -110.405672)
		)
		(stroke
			(width 0)
			(type solid)
		)
		(fill yes)
		(layer "F.Cu")
		(net "M_E_DQ<47>")
	)
	(gr_poly
		(pts
			(xy 283.978858 -113.163604) (xy 284.104588 -113.01984) (xy 284.03296 -112.947958) (xy 283.889196 -113.073688)
			(xy 283.853128 -113.109502) (xy 283.943044 -113.199418)
		)
		(stroke
			(width 0)
			(type solid)
		)
		(fill yes)
		(layer "F.Cu")
		(net "M_E_DQS_DP<14>")
	)
	(gr_poly
		(pts
			(xy 283.985462 -46.022514) (xy 283.859732 -45.87875) (xy 283.823918 -45.842682) (xy 283.734002 -45.932598)
			(xy 283.769816 -45.968412) (xy 283.91358 -46.094142)
		)
		(stroke
			(width 0)
			(type solid)
		)
		(fill yes)
		(layer "F.Cu")
		(net "M_B_DQ<43>")
	)
	(gr_poly
		(pts
			(xy 283.993844 -43.229022) (xy 283.868114 -43.085258) (xy 283.832046 -43.049444) (xy 283.742384 -43.139106)
			(xy 283.778198 -43.175174) (xy 283.921962 -43.30065)
		)
		(stroke
			(width 0)
			(type solid)
		)
		(fill yes)
		(layer "F.Cu")
		(net "M_B_DQS_DN<5>")
	)
	(gr_poly
		(pts
			(xy 284.000448 -42.104056) (xy 283.949648 -42.104056) (xy 283.759148 -42.116756) (xy 283.759148 -42.218356)
			(xy 283.949648 -42.231056) (xy 284.000448 -42.231056)
		)
		(stroke
			(width 0)
			(type solid)
		)
		(fill yes)
		(layer "F.Cu")
		(net "M_B_DQS_DN<5>")
	)
	(gr_poly
		(pts
			(xy 284.03677 -48.08855) (xy 283.911294 -47.944786) (xy 283.875226 -47.908972) (xy 283.785564 -47.998634)
			(xy 283.821378 -48.034702) (xy 283.965142 -48.160432)
		)
		(stroke
			(width 0)
			(type solid)
		)
		(fill yes)
		(layer "F.Cu")
		(net "M_B_DQ<53>")
	)
	(gr_poly
		(pts
			(xy 284.039056 -100.533454) (xy 284.016704 -100.494846) (xy 283.854652 -100.391976) (xy 283.66339 -100.502466)
			(xy 283.671518 -100.694236) (xy 283.693616 -100.73259)
		)
		(stroke
			(width 0)
			(type solid)
		)
		(fill yes)
		(layer "F.Cu")
		(net "M_E_DQ<52>")
	)
	(gr_poly
		(pts
			(xy 284.042358 -111.699294) (xy 284.078172 -111.663226) (xy 283.98851 -111.573564) (xy 283.952442 -111.609378)
			(xy 283.826712 -111.753142) (xy 283.898594 -111.825024)
		)
		(stroke
			(width 0)
			(type solid)
		)
		(fill yes)
		(layer "F.Cu")
		(net "M_E_DQS_DP<5>")
	)
	(gr_poly
		(pts
			(xy 284.05709 -106.501692) (xy 284.093158 -106.465878) (xy 284.003242 -106.375962) (xy 283.967428 -106.41203)
			(xy 283.841698 -106.55554) (xy 283.91358 -106.627422)
		)
		(stroke
			(width 0)
			(type solid)
		)
		(fill yes)
		(layer "F.Cu")
		(net "M_E_DQ<52>")
	)
	(gr_poly
		(pts
			(xy 284.057344 -45.609256) (xy 284.021276 -45.573442) (xy 283.877766 -45.447712) (xy 283.805884 -45.519594)
			(xy 283.931614 -45.663104) (xy 283.967428 -45.699172)
		)
		(stroke
			(width 0)
			(type solid)
		)
		(fill yes)
		(layer "F.Cu")
		(net "M_B_DQ<43>")
	)
	(gr_poly
		(pts
			(xy 284.0609 -109.34573) (xy 284.18663 -109.201966) (xy 284.114748 -109.130338) (xy 283.970984 -109.256068)
			(xy 283.93517 -109.291882) (xy 284.025086 -109.381798)
		)
		(stroke
			(width 0)
			(type solid)
		)
		(fill yes)
		(layer "F.Cu")
		(net "M_E_DQ<43>")
	)
	(gr_poly
		(pts
			(xy 284.069028 -112.139476) (xy 284.194758 -111.995712) (xy 284.12313 -111.92383) (xy 283.979366 -112.04956)
			(xy 283.943298 -112.085374) (xy 284.033214 -112.17529)
		)
		(stroke
			(width 0)
			(type solid)
		)
		(fill yes)
		(layer "F.Cu")
		(net "M_E_DQS_DN<5>")
	)
	(gr_poly
		(pts
			(xy 284.08376 -44.252896) (xy 283.95803 -44.109132) (xy 283.922216 -44.073318) (xy 283.8323 -44.163234)
			(xy 283.868368 -44.199048) (xy 284.012132 -44.324778)
		)
		(stroke
			(width 0)
			(type solid)
		)
		(fill yes)
		(layer "F.Cu")
		(net "M_B_DQ<46>")
	)
	(gr_poly
		(pts
			(xy 284.108652 -47.675546) (xy 284.072838 -47.639478) (xy 283.929074 -47.513748) (xy 283.857192 -47.58563)
			(xy 283.982922 -47.729394) (xy 284.01899 -47.765208)
		)
		(stroke
			(width 0)
			(type solid)
		)
		(fill yes)
		(layer "F.Cu")
		(net "M_B_DQ<53>")
	)
	(gr_poly
		(pts
			(xy 284.132528 -110.675166) (xy 284.168342 -110.639098) (xy 284.07868 -110.549436) (xy 284.042612 -110.58525)
			(xy 283.916882 -110.729014) (xy 283.988764 -110.800896)
		)
		(stroke
			(width 0)
			(type solid)
		)
		(fill yes)
		(layer "F.Cu")
		(net "M_E_DQ<47>")
	)
	(gr_poly
		(pts
			(xy 284.155642 -43.839892) (xy 284.119828 -43.803824) (xy 283.976064 -43.678094) (xy 283.904182 -43.749976)
			(xy 284.029912 -43.89374) (xy 284.06598 -43.929554)
		)
		(stroke
			(width 0)
			(type solid)
		)
		(fill yes)
		(layer "F.Cu")
		(net "M_B_DQ<46>")
	)
	(gr_poly
		(pts
			(xy 284.159198 -111.115348) (xy 284.284928 -110.971584) (xy 284.2133 -110.899702) (xy 284.069536 -111.025432)
			(xy 284.033468 -111.061246) (xy 284.123384 -111.151162)
		)
		(stroke
			(width 0)
			(type solid)
		)
		(fill yes)
		(layer "F.Cu")
		(net "M_E_DQ<46>")
	)
	(gr_poly
		(pts
			(xy 284.17393 -45.277024) (xy 284.0482 -45.13326) (xy 284.012386 -45.097192) (xy 283.92247 -45.187108)
			(xy 283.958284 -45.222922) (xy 284.102048 -45.348652)
		)
		(stroke
			(width 0)
			(type solid)
		)
		(fill yes)
		(layer "F.Cu")
		(net "M_B_DQ<42>")
	)
	(gr_poly
		(pts
			(xy 284.198822 -48.69942) (xy 284.162754 -48.663606) (xy 284.019244 -48.537876) (xy 283.947362 -48.609758)
			(xy 284.073092 -48.753268) (xy 284.108906 -48.789336)
		)
		(stroke
			(width 0)
			(type solid)
		)
		(fill yes)
		(layer "F.Cu")
		(net "M_B_DQ<49>")
	)
	(gr_poly
		(pts
			(xy 284.222444 -109.651038) (xy 284.258512 -109.615224) (xy 284.168596 -109.525308) (xy 284.132782 -109.561376)
			(xy 284.007052 -109.704886) (xy 284.078934 -109.776768)
		)
		(stroke
			(width 0)
			(type solid)
		)
		(fill yes)
		(layer "F.Cu")
		(net "M_E_DQ<43>")
	)
	(gr_poly
		(pts
			(xy 284.225238 -47.34306) (xy 284.099508 -47.199296) (xy 284.063694 -47.163482) (xy 283.974032 -47.253144)
			(xy 284.009846 -47.289212) (xy 284.15361 -47.414942)
		)
		(stroke
			(width 0)
			(type solid)
		)
		(fill yes)
		(layer "F.Cu")
		(net "M_B_DQ<52>")
	)
	(gr_poly
		(pts
			(xy 284.230826 -112.444784) (xy 284.26664 -112.408716) (xy 284.176978 -112.319054) (xy 284.14091 -112.354868)
			(xy 284.01518 -112.498632) (xy 284.087062 -112.570514)
		)
		(stroke
			(width 0)
			(type solid)
		)
		(fill yes)
		(layer "F.Cu")
		(net "M_E_DQS_DN<5>")
	)
	(gr_poly
		(pts
			(xy 284.241748 -42.548556) (xy 284.241748 -42.446956) (xy 284.051248 -42.434256) (xy 284.000448 -42.434256)
			(xy 284.000448 -42.561256) (xy 284.051248 -42.561256)
		)
		(stroke
			(width 0)
			(type solid)
		)
		(fill yes)
		(layer "F.Cu")
		(net "M_B_DQS_DN<5>")
	)
	(gr_poly
		(pts
			(xy 284.241748 -41.888156) (xy 284.241748 -41.786556) (xy 284.051248 -41.773856) (xy 284.000448 -41.773856)
			(xy 284.000448 -41.900856) (xy 284.051248 -41.900856)
		)
		(stroke
			(width 0)
			(type solid)
		)
		(fill yes)
		(layer "F.Cu")
		(net "M_B_DQS_DN<5>")
	)
	(gr_poly
		(pts
			(xy 284.245812 -44.863766) (xy 284.209744 -44.827952) (xy 284.066234 -44.702222) (xy 283.994352 -44.774104)
			(xy 284.120082 -44.917614) (xy 284.155896 -44.953682)
		)
		(stroke
			(width 0)
			(type solid)
		)
		(fill yes)
		(layer "F.Cu")
		(net "M_B_DQ<42>")
	)
	(gr_poly
		(pts
			(xy 284.246066 -49.343056) (xy 284.21457 -49.31156) (xy 284.031436 -49.254156) (xy 283.875226 -49.410366)
			(xy 283.93263 -49.5935) (xy 283.964126 -49.624996)
		)
		(stroke
			(width 0)
			(type solid)
		)
		(fill yes)
		(layer "F.Cu")
		(net "M_B_DQS_DP<15>")
	)
	(gr_poly
		(pts
			(xy 284.249368 -110.09122) (xy 284.375098 -109.947456) (xy 284.303216 -109.875828) (xy 284.159452 -110.001558)
			(xy 284.123638 -110.037372) (xy 284.213554 -110.127288)
		)
		(stroke
			(width 0)
			(type solid)
		)
		(fill yes)
		(layer "F.Cu")
		(net "M_E_DQ<42>")
	)
	(gr_poly
		(pts
			(xy 284.257496 -112.884966) (xy 284.383226 -112.741202) (xy 284.311344 -112.66932) (xy 284.16758 -112.79505)
			(xy 284.131766 -112.831118) (xy 284.221428 -112.92078)
		)
		(stroke
			(width 0)
			(type solid)
		)
		(fill yes)
		(layer "F.Cu")
		(net "M_E_DQS_DN<14>")
	)
	(gr_poly
		(pts
			(xy 284.272228 -43.507406) (xy 284.146498 -43.363642) (xy 284.110684 -43.327828) (xy 284.020768 -43.417744)
			(xy 284.056836 -43.453558) (xy 284.2006 -43.579288)
		)
		(stroke
			(width 0)
			(type solid)
		)
		(fill yes)
		(layer "F.Cu")
		(net "M_B_DQS_DP<5>")
	)
	(gr_poly
		(pts
			(xy 284.2768 -104.400096) (xy 284.226 -104.400096) (xy 284.03296 -104.488996) (xy 284.03296 -104.717596)
			(xy 284.226 -104.806496) (xy 284.2768 -104.806496)
		)
		(stroke
			(width 0)
			(type solid)
		)
		(fill yes)
		(layer "F.Cu")
		(net "M_E_DQ<48>")
	)
	(gr_poly
		(pts
			(xy 284.29712 -46.930056) (xy 284.261306 -46.893988) (xy 284.117542 -46.768258) (xy 284.04566 -46.84014)
			(xy 284.17139 -46.983904) (xy 284.207458 -47.019718)
		)
		(stroke
			(width 0)
			(type solid)
		)
		(fill yes)
		(layer "F.Cu")
		(net "M_B_DQ<52>")
	)
	(gr_poly
		(pts
			(xy 284.315408 -48.367188) (xy 284.189678 -48.223424) (xy 284.153864 -48.187356) (xy 284.063948 -48.277272)
			(xy 284.099762 -48.313086) (xy 284.243526 -48.438816)
		)
		(stroke
			(width 0)
			(type solid)
		)
		(fill yes)
		(layer "F.Cu")
		(net "M_B_DQ<48>")
	)
	(gr_poly
		(pts
			(xy 284.320996 -111.420656) (xy 284.35681 -111.384588) (xy 284.267148 -111.294926) (xy 284.23108 -111.33074)
			(xy 284.10535 -111.474504) (xy 284.177232 -111.546386)
		)
		(stroke
			(width 0)
			(type solid)
		)
		(fill yes)
		(layer "F.Cu")
		(net "M_E_DQ<46>")
	)
	(gr_poly
		(pts
			(xy 284.330902 -50.41392) (xy 284.286452 -50.41392) (xy 284.116272 -50.50282) (xy 284.116272 -50.7238)
			(xy 284.286452 -50.8127) (xy 284.330902 -50.8127)
		)
		(stroke
			(width 0)
			(type solid)
		)
		(fill yes)
		(layer "F.Cu")
		(net "M_B_DQS_DN<6>")
	)
	(gr_poly
		(pts
			(xy 284.335728 -106.223308) (xy 284.371542 -106.18724) (xy 284.28188 -106.097578) (xy 284.245812 -106.133392)
			(xy 284.120082 -106.277156) (xy 284.191964 -106.349038)
		)
		(stroke
			(width 0)
			(type solid)
		)
		(fill yes)
		(layer "F.Cu")
		(net "M_E_DQ<53>")
	)
	(gr_poly
		(pts
			(xy 284.347666 -111.860838) (xy 284.473396 -111.717074) (xy 284.401514 -111.645446) (xy 284.25775 -111.770922)
			(xy 284.221936 -111.80699) (xy 284.311598 -111.896652)
		)
		(stroke
			(width 0)
			(type solid)
		)
		(fill yes)
		(layer "F.Cu")
		(net "M_E_DQS_DP<5>")
	)
	(gr_poly
		(pts
			(xy 284.362398 -106.66349) (xy 284.488128 -106.519726) (xy 284.4165 -106.447844) (xy 284.272736 -106.573574)
			(xy 284.236668 -106.609388) (xy 284.326584 -106.699304)
		)
		(stroke
			(width 0)
			(type solid)
		)
		(fill yes)
		(layer "F.Cu")
		(net "M_E_DQ<52>")
	)
	(gr_poly
		(pts
			(xy 284.362398 -44.531534) (xy 284.236668 -44.38777) (xy 284.2006 -44.351956) (xy 284.110938 -44.441618)
			(xy 284.146752 -44.477432) (xy 284.290516 -44.603162)
		)
		(stroke
			(width 0)
			(type solid)
		)
		(fill yes)
		(layer "F.Cu")
		(net "M_B_DQ<47>")
	)
	(gr_poly
		(pts
			(xy 284.38729 -47.95393) (xy 284.351222 -47.918116) (xy 284.207712 -47.792386) (xy 284.13583 -47.864268)
			(xy 284.26156 -48.007778) (xy 284.297374 -48.043846)
		)
		(stroke
			(width 0)
			(type solid)
		)
		(fill yes)
		(layer "F.Cu")
		(net "M_B_DQ<48>")
	)
	(gr_poly
		(pts
			(xy 284.394148 -42.764456) (xy 284.343348 -42.764456) (xy 284.152848 -42.777156) (xy 284.152848 -42.878756)
			(xy 284.343348 -42.891456) (xy 284.394148 -42.891456)
		)
		(stroke
			(width 0)
			(type solid)
		)
		(fill yes)
		(layer "F.Cu")
		(net "M_B_DQS_DP<5>")
	)
	(gr_poly
		(pts
			(xy 284.394148 -42.104056) (xy 284.343348 -42.104056) (xy 284.152848 -42.116756) (xy 284.152848 -42.218356)
			(xy 284.343348 -42.231056) (xy 284.394148 -42.231056)
		)
		(stroke
			(width 0)
			(type solid)
		)
		(fill yes)
		(layer "F.Cu")
		(net "M_B_DQS_DP<5>")
	)
	(gr_poly
		(pts
			(xy 284.410912 -110.396528) (xy 284.44698 -110.360714) (xy 284.357064 -110.270798) (xy 284.32125 -110.306866)
			(xy 284.19552 -110.450376) (xy 284.267402 -110.522258)
		)
		(stroke
			(width 0)
			(type solid)
		)
		(fill yes)
		(layer "F.Cu")
		(net "M_E_DQ<42>")
	)
	(gr_poly
		(pts
			(xy 284.43428 -44.118276) (xy 284.398212 -44.082462) (xy 284.254702 -43.956732) (xy 284.18282 -44.028614)
			(xy 284.30855 -44.172124) (xy 284.344364 -44.208192)
		)
		(stroke
			(width 0)
			(type solid)
		)
		(fill yes)
		(layer "F.Cu")
		(net "M_B_DQ<47>")
	)
	(gr_poly
		(pts
			(xy 284.437836 -110.83671) (xy 284.563566 -110.692946) (xy 284.491684 -110.621318) (xy 284.34792 -110.747048)
			(xy 284.312106 -110.782862) (xy 284.401768 -110.872524)
		)
		(stroke
			(width 0)
			(type solid)
		)
		(fill yes)
		(layer "F.Cu")
		(net "M_E_DQ<47>")
	)
	(gr_poly
		(pts
			(xy 284.452314 -45.555408) (xy 284.326584 -45.411644) (xy 284.29077 -45.37583) (xy 284.200854 -45.465746)
			(xy 284.236922 -45.50156) (xy 284.380686 -45.62729)
		)
		(stroke
			(width 0)
			(type solid)
		)
		(fill yes)
		(layer "F.Cu")
		(net "M_B_DQ<43>")
	)
	(gr_poly
		(pts
			(xy 284.46984 -49.692306) (xy 284.412182 -49.509172) (xy 284.38094 -49.477676) (xy 284.098746 -49.75987)
			(xy 284.130242 -49.791112) (xy 284.313376 -49.84877)
		)
		(stroke
			(width 0)
			(type solid)
		)
		(fill yes)
		(layer "F.Cu")
		(net "M_B_DQS_DN<15>")
	)
	(gr_poly
		(pts
			(xy 284.503876 -47.621698) (xy 284.378146 -47.477934) (xy 284.342332 -47.441866) (xy 284.252416 -47.531782)
			(xy 284.28823 -47.567596) (xy 284.431994 -47.693326)
		)
		(stroke
			(width 0)
			(type solid)
		)
		(fill yes)
		(layer "F.Cu")
		(net "M_B_DQ<53>")
	)
	(gr_poly
		(pts
			(xy 284.50921 -112.166146) (xy 284.545278 -112.130332) (xy 284.455362 -112.040416) (xy 284.419548 -112.076484)
			(xy 284.293818 -112.219994) (xy 284.3657 -112.291876)
		)
		(stroke
			(width 0)
			(type solid)
		)
		(fill yes)
		(layer "F.Cu")
		(net "M_E_DQS_DP<5>")
	)
	(gr_poly
		(pts
			(xy 284.524196 -106.968798) (xy 284.56001 -106.93273) (xy 284.470348 -106.843068) (xy 284.43428 -106.878882)
			(xy 284.30855 -107.022646) (xy 284.380432 -107.094528)
		)
		(stroke
			(width 0)
			(type solid)
		)
		(fill yes)
		(layer "F.Cu")
		(net "M_E_DQ<52>")
	)
	(gr_poly
		(pts
			(xy 284.524196 -45.142404) (xy 284.488382 -45.106336) (xy 284.344618 -44.980606) (xy 284.272736 -45.052488)
			(xy 284.398466 -45.196252) (xy 284.434534 -45.232066)
		)
		(stroke
			(width 0)
			(type solid)
		)
		(fill yes)
		(layer "F.Cu")
		(net "M_B_DQ<43>")
	)
	(gr_poly
		(pts
			(xy 284.527752 -109.812836) (xy 284.653482 -109.669072) (xy 284.581854 -109.59719) (xy 284.43809 -109.72292)
			(xy 284.402022 -109.758734) (xy 284.491938 -109.84865)
		)
		(stroke
			(width 0)
			(type solid)
		)
		(fill yes)
		(layer "F.Cu")
		(net "M_E_DQ<43>")
	)
	(gr_poly
		(pts
			(xy 284.536134 -112.606328) (xy 284.661864 -112.462564) (xy 284.589982 -112.390682) (xy 284.446218 -112.516412)
			(xy 284.410404 -112.55248) (xy 284.500066 -112.642142)
		)
		(stroke
			(width 0)
			(type solid)
		)
		(fill yes)
		(layer "F.Cu")
		(net "M_E_DQS_DN<5>")
	)
	(gr_poly
		(pts
			(xy 284.550866 -43.786044) (xy 284.425136 -43.64228) (xy 284.389068 -43.606466) (xy 284.299406 -43.696128)
			(xy 284.33522 -43.732196) (xy 284.478984 -43.857672)
		)
		(stroke
			(width 0)
			(type solid)
		)
		(fill yes)
		(layer "F.Cu")
		(net "M_B_DQ<46>")
	)
	(gr_poly
		(pts
			(xy 284.575758 -47.20844) (xy 284.53969 -47.172626) (xy 284.39618 -47.046896) (xy 284.324298 -47.118778)
			(xy 284.450028 -47.262288) (xy 284.485842 -47.298356)
		)
		(stroke
			(width 0)
			(type solid)
		)
		(fill yes)
		(layer "F.Cu")
		(net "M_B_DQ<53>")
	)
	(gr_poly
		(pts
			(xy 284.593792 -48.645572) (xy 284.468316 -48.501808) (xy 284.432248 -48.465994) (xy 284.342586 -48.555656)
			(xy 284.3784 -48.591724) (xy 284.522164 -48.717454)
		)
		(stroke
			(width 0)
			(type solid)
		)
		(fill yes)
		(layer "F.Cu")
		(net "M_B_DQ<49>")
	)
	(gr_poly
		(pts
			(xy 284.59938 -111.142018) (xy 284.635448 -111.106204) (xy 284.545532 -111.016288) (xy 284.509718 -111.052356)
			(xy 284.383988 -111.195866) (xy 284.45587 -111.267748)
		)
		(stroke
			(width 0)
			(type solid)
		)
		(fill yes)
		(layer "F.Cu")
		(net "M_E_DQ<47>")
	)
	(gr_poly
		(pts
			(xy 284.614366 -105.944416) (xy 284.650434 -105.908602) (xy 284.560518 -105.818686) (xy 284.524704 -105.854754)
			(xy 284.398974 -105.998264) (xy 284.470856 -106.070146)
		)
		(stroke
			(width 0)
			(type solid)
		)
		(fill yes)
		(layer "F.Cu")
		(net "M_E_DQ<48>")
	)
	(gr_poly
		(pts
			(xy 284.622748 -43.372786) (xy 284.58668 -43.336972) (xy 284.44317 -43.211242) (xy 284.371288 -43.283124)
			(xy 284.497018 -43.426634) (xy 284.532832 -43.462702)
		)
		(stroke
			(width 0)
			(type solid)
		)
		(fill yes)
		(layer "F.Cu")
		(net "M_B_DQ<46>")
	)
	(gr_poly
		(pts
			(xy 284.626304 -111.5822) (xy 284.752034 -111.438436) (xy 284.680152 -111.366808) (xy 284.536388 -111.492284)
			(xy 284.500574 -111.528352) (xy 284.590236 -111.618014)
		)
		(stroke
			(width 0)
			(type solid)
		)
		(fill yes)
		(layer "F.Cu")
		(net "M_E_DQ<46>")
	)
	(gr_poly
		(pts
			(xy 284.635448 -42.548556) (xy 284.635448 -42.446956) (xy 284.444948 -42.434256) (xy 284.394148 -42.434256)
			(xy 284.394148 -42.561256) (xy 284.444948 -42.561256)
		)
		(stroke
			(width 0)
			(type solid)
		)
		(fill yes)
		(layer "F.Cu")
		(net "M_B_DQS_DP<5>")
	)
	(gr_poly
		(pts
			(xy 284.635448 -41.888156) (xy 284.635448 -41.786556) (xy 284.444948 -41.773856) (xy 284.394148 -41.773856)
			(xy 284.394148 -41.900856) (xy 284.444948 -41.900856)
		)
		(stroke
			(width 0)
			(type solid)
		)
		(fill yes)
		(layer "F.Cu")
		(net "M_B_DQS_DP<5>")
	)
	(gr_poly
		(pts
			(xy 284.640782 -44.809918) (xy 284.515052 -44.666154) (xy 284.479238 -44.63034) (xy 284.389322 -44.720256)
			(xy 284.42539 -44.75607) (xy 284.569154 -44.8818)
		)
		(stroke
			(width 0)
			(type solid)
		)
		(fill yes)
		(layer "F.Cu")
		(net "M_B_DQ<42>")
	)
	(gr_poly
		(pts
			(xy 284.641036 -106.384852) (xy 284.766766 -106.241088) (xy 284.694884 -106.16946) (xy 284.55112 -106.29519)
			(xy 284.515306 -106.331004) (xy 284.605222 -106.42092)
		)
		(stroke
			(width 0)
			(type solid)
		)
		(fill yes)
		(layer "F.Cu")
		(net "M_E_DQ<53>")
	)
	(gr_poly
		(pts
			(xy 284.665674 -48.232568) (xy 284.62986 -48.1965) (xy 284.486096 -48.07077) (xy 284.414214 -48.142652)
			(xy 284.539944 -48.286416) (xy 284.576012 -48.32223)
		)
		(stroke
			(width 0)
			(type solid)
		)
		(fill yes)
		(layer "F.Cu")
		(net "M_B_DQ<49>")
	)
	(gr_poly
		(pts
			(xy 284.68955 -110.118144) (xy 284.725364 -110.082076) (xy 284.635702 -109.992414) (xy 284.599634 -110.028228)
			(xy 284.473904 -110.171992) (xy 284.545786 -110.243874)
		)
		(stroke
			(width 0)
			(type solid)
		)
		(fill yes)
		(layer "F.Cu")
		(net "M_E_DQ<43>")
	)
	(gr_poly
		(pts
			(xy 284.692344 -46.876208) (xy 284.566614 -46.732444) (xy 284.5308 -46.696376) (xy 284.440884 -46.786292)
			(xy 284.476698 -46.822106) (xy 284.620462 -46.947836)
		)
		(stroke
			(width 0)
			(type solid)
		)
		(fill yes)
		(layer "F.Cu")
		(net "M_B_DQ<52>")
	)
	(gr_poly
		(pts
			(xy 284.697678 -112.911636) (xy 284.733746 -112.875822) (xy 284.64383 -112.785906) (xy 284.608016 -112.821974)
			(xy 284.482286 -112.965484) (xy 284.554168 -113.037366)
		)
		(stroke
			(width 0)
			(type solid)
		)
		(fill yes)
		(layer "F.Cu")
		(net "M_E_DQS_DN<5>")
	)
	(gr_poly
		(pts
			(xy 284.706568 -52.625752) (xy 284.876748 -52.536852) (xy 284.876748 -52.315872) (xy 284.706568 -52.226972)
			(xy 284.662372 -52.226972) (xy 284.662118 -52.626006)
		)
		(stroke
			(width 0)
			(type solid)
		)
		(fill yes)
		(layer "F.Cu")
		(net "M_B_DQS_DP<6>")
	)
	(gr_poly
		(pts
			(xy 284.71114 -104.717596) (xy 284.71114 -104.488996) (xy 284.5181 -104.400096) (xy 284.4673 -104.400096)
			(xy 284.4673 -104.806496) (xy 284.5181 -104.806496)
		)
		(stroke
			(width 0)
			(type solid)
		)
		(fill yes)
		(layer "F.Cu")
		(net "M_E_DQ<49>")
	)
	(gr_poly
		(pts
			(xy 284.712664 -44.396914) (xy 284.67685 -44.360846) (xy 284.533086 -44.235116) (xy 284.461204 -44.306998)
			(xy 284.586934 -44.450762) (xy 284.623002 -44.486576)
		)
		(stroke
			(width 0)
			(type solid)
		)
		(fill yes)
		(layer "F.Cu")
		(net "M_B_DQ<42>")
	)
	(gr_poly
		(pts
			(xy 284.71622 -110.558326) (xy 284.84195 -110.414562) (xy 284.770322 -110.34268) (xy 284.626558 -110.46841)
			(xy 284.59049 -110.504224) (xy 284.680406 -110.59414)
		)
		(stroke
			(width 0)
			(type solid)
		)
		(fill yes)
		(layer "F.Cu")
		(net "M_E_DQ<42>")
	)
	(gr_poly
		(pts
			(xy 284.736032 -50.737516) (xy 284.736032 -50.516536) (xy 284.565852 -50.427636) (xy 284.521402 -50.427636)
			(xy 284.521402 -50.826416) (xy 284.565852 -50.826416)
		)
		(stroke
			(width 0)
			(type solid)
		)
		(fill yes)
		(layer "F.Cu")
		(net "M_B_DQS_DP<6>")
	)
	(gr_poly
		(pts
			(xy 284.764226 -46.46295) (xy 284.728158 -46.427136) (xy 284.584648 -46.301406) (xy 284.512766 -46.373288)
			(xy 284.638496 -46.516798) (xy 284.67431 -46.552866)
		)
		(stroke
			(width 0)
			(type solid)
		)
		(fill yes)
		(layer "F.Cu")
		(net "M_B_DQ<52>")
	)
	(gr_poly
		(pts
			(xy 284.78226 -47.900082) (xy 284.65653 -47.756318) (xy 284.620716 -47.720504) (xy 284.531054 -47.810166)
			(xy 284.566868 -47.846234) (xy 284.710632 -47.971964)
		)
		(stroke
			(width 0)
			(type solid)
		)
		(fill yes)
		(layer "F.Cu")
		(net "M_B_DQ<48>")
	)
	(gr_poly
		(pts
			(xy 284.787848 -111.887508) (xy 284.823916 -111.851694) (xy 284.734 -111.761778) (xy 284.698186 -111.797846)
			(xy 284.572456 -111.941356) (xy 284.644338 -112.013238)
		)
		(stroke
			(width 0)
			(type solid)
		)
		(fill yes)
		(layer "F.Cu")
		(net "M_E_DQ<46>")
	)
	(gr_poly
		(pts
			(xy 284.80258 -106.69016) (xy 284.838648 -106.654346) (xy 284.748732 -106.56443) (xy 284.712918 -106.600498)
			(xy 284.587188 -106.744008) (xy 284.65907 -106.81589)
		)
		(stroke
			(width 0)
			(type solid)
		)
		(fill yes)
		(layer "F.Cu")
		(net "M_E_DQ<53>")
	)
	(gr_poly
		(pts
			(xy 284.814518 -112.327944) (xy 284.940248 -112.18418) (xy 284.86862 -112.112298) (xy 284.724856 -112.238028)
			(xy 284.688788 -112.273842) (xy 284.778704 -112.363758)
		)
		(stroke
			(width 0)
			(type solid)
		)
		(fill yes)
		(layer "F.Cu")
		(net "M_E_DQS_DP<5>")
	)
	(gr_poly
		(pts
			(xy 284.82925 -44.064428) (xy 284.70352 -43.920664) (xy 284.667706 -43.88485) (xy 284.57779 -43.974766)
			(xy 284.613858 -44.01058) (xy 284.757622 -44.13631)
		)
		(stroke
			(width 0)
			(type solid)
		)
		(fill yes)
		(layer "F.Cu")
		(net "M_B_DQ<47>")
	)
	(gr_poly
		(pts
			(xy 284.829504 -107.130342) (xy 284.955234 -106.986578) (xy 284.883352 -106.91495) (xy 284.739588 -107.04068)
			(xy 284.703774 -107.076494) (xy 284.79369 -107.16641)
		)
		(stroke
			(width 0)
			(type solid)
		)
		(fill yes)
		(layer "F.Cu")
		(net "M_E_DQ<52>")
	)
	(gr_poly
		(pts
			(xy 284.854142 -47.487078) (xy 284.818328 -47.45101) (xy 284.674564 -47.32528) (xy 284.602682 -47.397162)
			(xy 284.728412 -47.540926) (xy 284.76448 -47.57674)
		)
		(stroke
			(width 0)
			(type solid)
		)
		(fill yes)
		(layer "F.Cu")
		(net "M_B_DQ<48>")
	)
	(gr_poly
		(pts
			(xy 284.872176 -48.92421) (xy 284.7467 -48.780446) (xy 284.710632 -48.744632) (xy 284.62097 -48.834294)
			(xy 284.656784 -48.870362) (xy 284.800548 -48.996092)
		)
		(stroke
			(width 0)
			(type solid)
		)
		(fill yes)
		(layer "F.Cu")
		(net "M_B_DQS_DP<15>")
	)
	(gr_poly
		(pts
			(xy 284.878018 -110.863634) (xy 284.913832 -110.827566) (xy 284.82417 -110.737904) (xy 284.788102 -110.773718)
			(xy 284.662372 -110.917482) (xy 284.734254 -110.989364)
		)
		(stroke
			(width 0)
			(type solid)
		)
		(fill yes)
		(layer "F.Cu")
		(net "M_E_DQ<42>")
	)
	(gr_poly
		(pts
			(xy 284.88386 -51.542442) (xy 284.88386 -51.321462) (xy 284.71368 -51.232562) (xy 284.66923 -51.232562)
			(xy 284.66923 -51.631342) (xy 284.71368 -51.631342)
		)
		(stroke
			(width 0)
			(type solid)
		)
		(fill yes)
		(layer "F.Cu")
		(net "M_B_DQS_DP<6>")
	)
	(gr_poly
		(pts
			(xy 284.893004 -105.666032) (xy 284.928818 -105.629964) (xy 284.839156 -105.540302) (xy 284.803088 -105.576116)
			(xy 284.677358 -105.71988) (xy 284.74924 -105.791762)
		)
		(stroke
			(width 0)
			(type solid)
		)
		(fill yes)
		(layer "F.Cu")
		(net "M_E_DQ<49>")
	)
	(gr_poly
		(pts
			(xy 284.901132 -43.651424) (xy 284.865318 -43.615356) (xy 284.721554 -43.489626) (xy 284.649672 -43.561508)
			(xy 284.775402 -43.705272) (xy 284.81147 -43.741086)
		)
		(stroke
			(width 0)
			(type solid)
		)
		(fill yes)
		(layer "F.Cu")
		(net "M_B_DQ<47>")
	)
	(gr_poly
		(pts
			(xy 284.904688 -111.303816) (xy 285.030418 -111.160052) (xy 284.95879 -111.08817) (xy 284.815026 -111.2139)
			(xy 284.778958 -111.249714) (xy 284.868874 -111.33963)
		)
		(stroke
			(width 0)
			(type solid)
		)
		(fill yes)
		(layer "F.Cu")
		(net "M_E_DQ<47>")
	)
	(gr_poly
		(pts
			(xy 284.91942 -45.088556) (xy 284.79369 -44.944792) (xy 284.757622 -44.908978) (xy 284.66796 -44.99864)
			(xy 284.703774 -45.034454) (xy 284.847538 -45.160184)
		)
		(stroke
			(width 0)
			(type solid)
		)
		(fill yes)
		(layer "F.Cu")
		(net "M_B_DQ<43>")
	)
	(gr_poly
		(pts
			(xy 284.919674 -106.106214) (xy 285.045404 -105.96245) (xy 284.973776 -105.890568) (xy 284.830012 -106.016298)
			(xy 284.793944 -106.052112) (xy 284.88386 -106.142028)
		)
		(stroke
			(width 0)
			(type solid)
		)
		(fill yes)
		(layer "F.Cu")
		(net "M_E_DQ<48>")
	)
	(gr_poly
		(pts
			(xy 284.944312 -48.511206) (xy 284.908498 -48.475138) (xy 284.764734 -48.349408) (xy 284.692852 -48.42129)
			(xy 284.818582 -48.565054) (xy 284.85465 -48.600868)
		)
		(stroke
			(width 0)
			(type solid)
		)
		(fill yes)
		(layer "F.Cu")
		(net "M_B_DQS_DP<15>")
	)
	(gr_poly
		(pts
			(xy 284.970728 -47.154592) (xy 284.844998 -47.010828) (xy 284.809184 -46.975014) (xy 284.719268 -47.06493)
			(xy 284.755336 -47.100744) (xy 284.8991 -47.226474)
		)
		(stroke
			(width 0)
			(type solid)
		)
		(fill yes)
		(layer "F.Cu")
		(net "M_B_DQ<53>")
	)
	(gr_poly
		(pts
			(xy 284.974792 -49.516538) (xy 284.943296 -49.485042) (xy 284.760162 -49.427638) (xy 284.603952 -49.583848)
			(xy 284.661356 -49.766982) (xy 284.692852 -49.798478)
		)
		(stroke
			(width 0)
			(type solid)
		)
		(fill yes)
		(layer "F.Cu")
		(net "M_B_DQS_DN<6>")
	)
	(gr_poly
		(pts
			(xy 284.976316 -112.633252) (xy 285.01213 -112.597184) (xy 284.922468 -112.507522) (xy 284.8864 -112.543336)
			(xy 284.76067 -112.6871) (xy 284.832552 -112.758982)
		)
		(stroke
			(width 0)
			(type solid)
		)
		(fill yes)
		(layer "F.Cu")
		(net "M_E_DQS_DP<5>")
	)
	(gr_poly
		(pts
			(xy 284.991048 -107.43565) (xy 285.027116 -107.399836) (xy 284.9372 -107.30992) (xy 284.901386 -107.345988)
			(xy 284.775656 -107.489498) (xy 284.847538 -107.56138)
		)
		(stroke
			(width 0)
			(type solid)
		)
		(fill yes)
		(layer "F.Cu")
		(net "M_E_DQ<52>")
	)
	(gr_poly
		(pts
			(xy 284.991302 -44.675298) (xy 284.955234 -44.639484) (xy 284.811724 -44.513754) (xy 284.739842 -44.585636)
			(xy 284.865572 -44.729146) (xy 284.901386 -44.765214)
		)
		(stroke
			(width 0)
			(type solid)
		)
		(fill yes)
		(layer "F.Cu")
		(net "M_B_DQ<43>")
	)
	(gr_poly
		(pts
			(xy 284.994858 -110.279688) (xy 285.120588 -110.135924) (xy 285.048706 -110.064296) (xy 284.904942 -110.190026)
			(xy 284.869128 -110.22584) (xy 284.95879 -110.315502)
		)
		(stroke
			(width 0)
			(type solid)
		)
		(fill yes)
		(layer "F.Cu")
		(net "M_E_DQ<43>")
	)
	(gr_poly
		(pts
			(xy 285.017718 -43.318938) (xy 284.891988 -43.175174) (xy 284.856174 -43.13936) (xy 284.766258 -43.229276)
			(xy 284.802326 -43.26509) (xy 284.94609 -43.39082)
		)
		(stroke
			(width 0)
			(type solid)
		)
		(fill yes)
		(layer "F.Cu")
		(net "M_B_DQ<46>")
	)
	(gr_poly
		(pts
			(xy 285.04261 -46.741588) (xy 285.006796 -46.70552) (xy 284.863032 -46.57979) (xy 284.79115 -46.651672)
			(xy 284.91688 -46.795436) (xy 284.952948 -46.83125)
		)
		(stroke
			(width 0)
			(type solid)
		)
		(fill yes)
		(layer "F.Cu")
		(net "M_B_DQ<53>")
	)
	(gr_poly
		(pts
			(xy 285.060898 -48.17872) (xy 284.935168 -48.034956) (xy 284.899354 -47.998888) (xy 284.809438 -48.088804)
			(xy 284.845252 -48.124618) (xy 284.989016 -48.250348)
		)
		(stroke
			(width 0)
			(type solid)
		)
		(fill yes)
		(layer "F.Cu")
		(net "M_B_DQ<49>")
	)
	(gr_poly
		(pts
			(xy 285.066486 -111.609124) (xy 285.1023 -111.573056) (xy 285.012638 -111.483394) (xy 284.97657 -111.519208)
			(xy 284.85084 -111.662972) (xy 284.922722 -111.734854)
		)
		(stroke
			(width 0)
			(type solid)
		)
		(fill yes)
		(layer "F.Cu")
		(net "M_E_DQ<47>")
	)
	(gr_poly
		(pts
			(xy 285.081472 -106.411522) (xy 285.117286 -106.375454) (xy 285.027624 -106.285792) (xy 284.991556 -106.321606)
			(xy 284.865826 -106.46537) (xy 284.937708 -106.537252)
		)
		(stroke
			(width 0)
			(type solid)
		)
		(fill yes)
		(layer "F.Cu")
		(net "M_E_DQ<48>")
	)
	(gr_poly
		(pts
			(xy 285.0896 -104.30256) (xy 285.0388 -104.30256) (xy 284.84576 -104.39146) (xy 284.84576 -104.62006)
			(xy 285.0388 -104.70896) (xy 285.0896 -104.70896)
		)
		(stroke
			(width 0)
			(type solid)
		)
		(fill yes)
		(layer "F.Cu")
		(net "M_E_DQS_DP<15>")
	)
	(gr_poly
		(pts
			(xy 285.093156 -112.049306) (xy 285.218886 -111.905542) (xy 285.147258 -111.83366) (xy 285.003494 -111.95939)
			(xy 284.967426 -111.995204) (xy 285.057342 -112.08512)
		)
		(stroke
			(width 0)
			(type solid)
		)
		(fill yes)
		(layer "F.Cu")
		(net "M_E_DQ<46>")
	)
	(gr_poly
		(pts
			(xy 285.107888 -106.851958) (xy 285.233618 -106.708194) (xy 285.16199 -106.636312) (xy 285.018226 -106.762042)
			(xy 284.982158 -106.797856) (xy 285.072074 -106.887772)
		)
		(stroke
			(width 0)
			(type solid)
		)
		(fill yes)
		(layer "F.Cu")
		(net "M_E_DQ<53>")
	)
	(gr_poly
		(pts
			(xy 285.107888 -44.343066) (xy 284.982158 -44.199302) (xy 284.94609 -44.163488) (xy 284.856428 -44.25315)
			(xy 284.892242 -44.289218) (xy 285.036006 -44.414694)
		)
		(stroke
			(width 0)
			(type solid)
		)
		(fill yes)
		(layer "F.Cu")
		(net "M_B_DQ<42>")
	)
	(gr_poly
		(pts
			(xy 285.113984 -50.761138) (xy 285.069534 -50.761138) (xy 284.899354 -50.850038) (xy 284.899354 -51.071018)
			(xy 285.069534 -51.159918) (xy 285.113984 -51.159918)
		)
		(stroke
			(width 0)
			(type solid)
		)
		(fill yes)
		(layer "F.Cu")
		(net "M_B_DQ<54>")
	)
	(gr_poly
		(pts
			(xy 285.13278 -47.765462) (xy 285.096712 -47.729648) (xy 284.953202 -47.603918) (xy 284.88132 -47.6758)
			(xy 285.00705 -47.81931) (xy 285.042864 -47.855378)
		)
		(stroke
			(width 0)
			(type solid)
		)
		(fill yes)
		(layer "F.Cu")
		(net "M_B_DQ<49>")
	)
	(gr_poly
		(pts
			(xy 285.150814 -49.202594) (xy 285.025338 -49.05883) (xy 284.98927 -49.023016) (xy 284.899608 -49.112678)
			(xy 284.935422 -49.148746) (xy 285.079186 -49.274476)
		)
		(stroke
			(width 0)
			(type solid)
		)
		(fill yes)
		(layer "F.Cu")
		(net "M_B_DQS_DN<15>")
	)
	(gr_poly
		(pts
			(xy 285.156402 -110.584996) (xy 285.19247 -110.549182) (xy 285.102554 -110.459266) (xy 285.06674 -110.495334)
			(xy 284.94101 -110.638844) (xy 285.012892 -110.710726)
		)
		(stroke
			(width 0)
			(type solid)
		)
		(fill yes)
		(layer "F.Cu")
		(net "M_E_DQ<43>")
	)
	(gr_poly
		(pts
			(xy 285.159196 -46.409102) (xy 285.033466 -46.265338) (xy 284.997652 -46.229524) (xy 284.907736 -46.31944)
			(xy 284.943804 -46.355254) (xy 285.087568 -46.480984)
		)
		(stroke
			(width 0)
			(type solid)
		)
		(fill yes)
		(layer "F.Cu")
		(net "M_B_DQ<52>")
	)
	(gr_poly
		(pts
			(xy 285.17977 -43.929808) (xy 285.143702 -43.893994) (xy 285.000192 -43.768264) (xy 284.92831 -43.840146)
			(xy 285.05404 -43.983656) (xy 285.089854 -44.019724)
		)
		(stroke
			(width 0)
			(type solid)
		)
		(fill yes)
		(layer "F.Cu")
		(net "M_B_DQ<42>")
	)
	(gr_poly
		(pts
			(xy 285.183326 -111.025178) (xy 285.309056 -110.881414) (xy 285.237174 -110.809786) (xy 285.09341 -110.935262)
			(xy 285.057596 -110.97133) (xy 285.147258 -111.060992)
		)
		(stroke
			(width 0)
			(type solid)
		)
		(fill yes)
		(layer "F.Cu")
		(net "M_E_DQ<42>")
	)
	(gr_poly
		(pts
			(xy 285.197296 -100.76688) (xy 285.152846 -100.76688) (xy 284.982666 -100.85578) (xy 284.982666 -101.07676)
			(xy 285.152846 -101.165406) (xy 285.197042 -101.16566)
		)
		(stroke
			(width 0)
			(type solid)
		)
		(fill yes)
		(layer "F.Cu")
		(net "M_E_DQS_DP<15>")
	)
	(gr_poly
		(pts
			(xy 285.22295 -48.78959) (xy 285.187136 -48.753522) (xy 285.043372 -48.627792) (xy 284.97149 -48.699674)
			(xy 285.09722 -48.843438) (xy 285.133288 -48.879252)
		)
		(stroke
			(width 0)
			(type solid)
		)
		(fill yes)
		(layer "F.Cu")
		(net "M_B_DQS_DN<15>")
	)
	(gr_poly
		(pts
			(xy 285.231078 -45.996098) (xy 285.195264 -45.96003) (xy 285.0515 -45.8343) (xy 284.979618 -45.906182)
			(xy 285.105348 -46.049946) (xy 285.141416 -46.08576)
		)
		(stroke
			(width 0)
			(type solid)
		)
		(fill yes)
		(layer "F.Cu")
		(net "M_B_DQ<52>")
	)
	(gr_poly
		(pts
			(xy 285.249366 -47.43323) (xy 285.123636 -47.289466) (xy 285.087822 -47.253398) (xy 284.997906 -47.343314)
			(xy 285.03372 -47.379128) (xy 285.177484 -47.504858)
		)
		(stroke
			(width 0)
			(type solid)
		)
		(fill yes)
		(layer "F.Cu")
		(net "M_B_DQ<48>")
	)
	(gr_poly
		(pts
			(xy 285.269686 -107.157266) (xy 285.3055 -107.121198) (xy 285.215838 -107.031536) (xy 285.17977 -107.06735)
			(xy 285.05404 -107.211114) (xy 285.125922 -107.282996)
		)
		(stroke
			(width 0)
			(type solid)
		)
		(fill yes)
		(layer "F.Cu")
		(net "M_E_DQ<53>")
	)
	(gr_poly
		(pts
			(xy 285.296356 -107.597448) (xy 285.422086 -107.453684) (xy 285.350458 -107.381802) (xy 285.206694 -107.507532)
			(xy 285.170626 -107.543346) (xy 285.260542 -107.633262)
		)
		(stroke
			(width 0)
			(type solid)
		)
		(fill yes)
		(layer "F.Cu")
		(net "M_E_DQ<52>")
	)
	(gr_poly
		(pts
			(xy 285.296356 -43.597576) (xy 285.170626 -43.453812) (xy 285.134558 -43.417998) (xy 285.044896 -43.50766)
			(xy 285.08071 -43.543728) (xy 285.224474 -43.669458)
		)
		(stroke
			(width 0)
			(type solid)
		)
		(fill yes)
		(layer "F.Cu")
		(net "M_B_DQ<47>")
	)
	(gr_poly
		(pts
			(xy 285.321248 -47.019972) (xy 285.28518 -46.984158) (xy 285.14167 -46.858428) (xy 285.069788 -46.93031)
			(xy 285.195518 -47.07382) (xy 285.231332 -47.109888)
		)
		(stroke
			(width 0)
			(type solid)
		)
		(fill yes)
		(layer "F.Cu")
		(net "M_B_DQ<48>")
	)
	(gr_poly
		(pts
			(xy 285.339282 -48.457358) (xy 285.213552 -48.313594) (xy 285.177738 -48.277526) (xy 285.087822 -48.367442)
			(xy 285.123636 -48.403256) (xy 285.2674 -48.528986)
		)
		(stroke
			(width 0)
			(type solid)
		)
		(fill yes)
		(layer "F.Cu")
		(net "M_B_DQS_DP<15>")
	)
	(gr_poly
		(pts
			(xy 285.34487 -111.330486) (xy 285.380938 -111.294672) (xy 285.291022 -111.204756) (xy 285.255208 -111.240824)
			(xy 285.129478 -111.384334) (xy 285.20136 -111.456216)
		)
		(stroke
			(width 0)
			(type solid)
		)
		(fill yes)
		(layer "F.Cu")
		(net "M_E_DQ<42>")
	)
	(gr_poly
		(pts
			(xy 285.359856 -106.132884) (xy 285.395924 -106.09707) (xy 285.306008 -106.007154) (xy 285.270194 -106.043222)
			(xy 285.144464 -106.186732) (xy 285.216346 -106.258614)
		)
		(stroke
			(width 0)
			(type solid)
		)
		(fill yes)
		(layer "F.Cu")
		(net "M_E_DQ<49>")
	)
	(gr_poly
		(pts
			(xy 285.368238 -43.184318) (xy 285.33217 -43.148504) (xy 285.18866 -43.022774) (xy 285.116778 -43.094656)
			(xy 285.242508 -43.238166) (xy 285.278322 -43.274234)
		)
		(stroke
			(width 0)
			(type solid)
		)
		(fill yes)
		(layer "F.Cu")
		(net "M_B_DQ<47>")
	)
	(gr_poly
		(pts
			(xy 285.371794 -111.770668) (xy 285.497524 -111.626904) (xy 285.425642 -111.555022) (xy 285.281878 -111.680752)
			(xy 285.246064 -111.71682) (xy 285.335726 -111.806482)
		)
		(stroke
			(width 0)
			(type solid)
		)
		(fill yes)
		(layer "F.Cu")
		(net "M_E_DQ<47>")
	)
	(gr_poly
		(pts
			(xy 285.386272 -44.62145) (xy 285.260542 -44.477686) (xy 285.224728 -44.441872) (xy 285.134812 -44.531788)
			(xy 285.17088 -44.567602) (xy 285.314644 -44.693332)
		)
		(stroke
			(width 0)
			(type solid)
		)
		(fill yes)
		(layer "F.Cu")
		(net "M_B_DQ<43>")
	)
	(gr_poly
		(pts
			(xy 285.38678 -106.573066) (xy 285.51251 -106.429302) (xy 285.440628 -106.357674) (xy 285.296864 -106.483404)
			(xy 285.26105 -106.519218) (xy 285.350966 -106.609134)
		)
		(stroke
			(width 0)
			(type solid)
		)
		(fill yes)
		(layer "F.Cu")
		(net "M_E_DQ<48>")
	)
	(gr_poly
		(pts
			(xy 285.411418 -48.0441) (xy 285.37535 -48.008286) (xy 285.23184 -47.882556) (xy 285.159958 -47.954438)
			(xy 285.285688 -48.097948) (xy 285.321502 -48.134016)
		)
		(stroke
			(width 0)
			(type solid)
		)
		(fill yes)
		(layer "F.Cu")
		(net "M_B_DQS_DP<15>")
	)
	(gr_poly
		(pts
			(xy 285.437834 -46.68774) (xy 285.312104 -46.543976) (xy 285.27629 -46.507908) (xy 285.186374 -46.597824)
			(xy 285.222188 -46.633638) (xy 285.365952 -46.759368)
		)
		(stroke
			(width 0)
			(type solid)
		)
		(fill yes)
		(layer "F.Cu")
		(net "M_B_DQ<53>")
	)
	(gr_poly
		(pts
			(xy 285.458154 -107.902756) (xy 285.493968 -107.866688) (xy 285.404306 -107.777026) (xy 285.368238 -107.81284)
			(xy 285.242508 -107.956604) (xy 285.31439 -108.028486)
		)
		(stroke
			(width 0)
			(type solid)
		)
		(fill yes)
		(layer "F.Cu")
		(net "M_E_DQ<52>")
	)
	(gr_poly
		(pts
			(xy 285.458154 -44.208446) (xy 285.42234 -44.172378) (xy 285.278576 -44.046648) (xy 285.206694 -44.11853)
			(xy 285.332424 -44.262294) (xy 285.368492 -44.298108)
		)
		(stroke
			(width 0)
			(type solid)
		)
		(fill yes)
		(layer "F.Cu")
		(net "M_B_DQ<43>")
	)
	(gr_poly
		(pts
			(xy 285.461456 -50.079402) (xy 285.42996 -50.047906) (xy 285.246826 -49.990502) (xy 285.090616 -50.146712)
			(xy 285.14802 -50.329846) (xy 285.179516 -50.361342)
		)
		(stroke
			(width 0)
			(type solid)
		)
		(fill yes)
		(layer "F.Cu")
		(net "M_B_DQ<54>")
	)
	(gr_poly
		(pts
			(xy 285.46171 -110.746794) (xy 285.58744 -110.60303) (xy 285.515812 -110.531148) (xy 285.372048 -110.656878)
			(xy 285.33598 -110.692692) (xy 285.425896 -110.782608)
		)
		(stroke
			(width 0)
			(type solid)
		)
		(fill yes)
		(layer "F.Cu")
		(net "M_E_DQ<43>")
	)
	(gr_poly
		(pts
			(xy 285.484824 -42.852086) (xy 285.359094 -42.708322) (xy 285.323026 -42.672508) (xy 285.233364 -42.76217)
			(xy 285.269178 -42.798238) (xy 285.412942 -42.923968)
		)
		(stroke
			(width 0)
			(type solid)
		)
		(fill yes)
		(layer "F.Cu")
		(net "M_B_DQ<46>")
	)
	(gr_poly
		(pts
			(xy 285.501334 -49.067974) (xy 285.465266 -49.03216) (xy 285.321756 -48.90643) (xy 285.249874 -48.978312)
			(xy 285.375604 -49.121822) (xy 285.411418 -49.15789)
		)
		(stroke
			(width 0)
			(type solid)
		)
		(fill yes)
		(layer "F.Cu")
		(net "M_B_DQS_DN<6>")
	)
	(gr_poly
		(pts
			(xy 285.509716 -46.274482) (xy 285.473648 -46.238668) (xy 285.330138 -46.112938) (xy 285.258256 -46.18482)
			(xy 285.383986 -46.32833) (xy 285.4198 -46.364398)
		)
		(stroke
			(width 0)
			(type solid)
		)
		(fill yes)
		(layer "F.Cu")
		(net "M_B_DQ<53>")
	)
	(gr_poly
		(pts
			(xy 285.519114 -53.026818) (xy 285.519114 -52.805838) (xy 285.348934 -52.716938) (xy 285.304484 -52.716938)
			(xy 285.304484 -53.115718) (xy 285.348934 -53.115718)
		)
		(stroke
			(width 0)
			(type solid)
		)
		(fill yes)
		(layer "F.Cu")
		(net "M_B_DQ<55>")
	)
	(gr_poly
		(pts
			(xy 285.519114 -52.036218) (xy 285.519114 -51.815238) (xy 285.348934 -51.726338) (xy 285.304484 -51.726338)
			(xy 285.304484 -52.125118) (xy 285.348934 -52.125118)
		)
		(stroke
			(width 0)
			(type solid)
		)
		(fill yes)
		(layer "F.Cu")
		(net "M_B_DQ<55>")
	)
	(gr_poly
		(pts
			(xy 285.52394 -104.62006) (xy 285.52394 -104.39146) (xy 285.3309 -104.30256) (xy 285.2801 -104.30256)
			(xy 285.2801 -104.70896) (xy 285.3309 -104.70896)
		)
		(stroke
			(width 0)
			(type solid)
		)
		(fill yes)
		(layer "F.Cu")
		(net "M_E_DQS_DN<15>")
	)
	(gr_poly
		(pts
			(xy 285.52775 -47.711614) (xy 285.40202 -47.56785) (xy 285.366206 -47.532036) (xy 285.27629 -47.621952)
			(xy 285.312358 -47.657766) (xy 285.456122 -47.783496)
		)
		(stroke
			(width 0)
			(type solid)
		)
		(fill yes)
		(layer "F.Cu")
		(net "M_B_DQ<49>")
	)
	(gr_poly
		(pts
			(xy 285.548324 -106.878374) (xy 285.584392 -106.84256) (xy 285.494476 -106.752644) (xy 285.458662 -106.788712)
			(xy 285.332932 -106.932222) (xy 285.404814 -107.004104)
		)
		(stroke
			(width 0)
			(type solid)
		)
		(fill yes)
		(layer "F.Cu")
		(net "M_E_DQ<48>")
	)
	(gr_poly
		(pts
			(xy 285.57474 -43.87596) (xy 285.44901 -43.732196) (xy 285.413196 -43.696382) (xy 285.32328 -43.786298)
			(xy 285.359348 -43.822112) (xy 285.503112 -43.947842)
		)
		(stroke
			(width 0)
			(type solid)
		)
		(fill yes)
		(layer "F.Cu")
		(net "M_B_DQ<42>")
	)
	(gr_poly
		(pts
			(xy 285.574994 -107.31881) (xy 285.700724 -107.175046) (xy 285.628842 -107.103418) (xy 285.485078 -107.229148)
			(xy 285.449264 -107.264962) (xy 285.538926 -107.354624)
		)
		(stroke
			(width 0)
			(type solid)
		)
		(fill yes)
		(layer "F.Cu")
		(net "M_E_DQ<53>")
	)
	(gr_poly
		(pts
			(xy 285.599632 -47.29861) (xy 285.563818 -47.262542) (xy 285.420054 -47.136812) (xy 285.348172 -47.208694)
			(xy 285.473902 -47.352458) (xy 285.50997 -47.388272)
		)
		(stroke
			(width 0)
			(type solid)
		)
		(fill yes)
		(layer "F.Cu")
		(net "M_B_DQ<49>")
	)
	(gr_poly
		(pts
			(xy 285.61792 -48.735742) (xy 285.49219 -48.591978) (xy 285.456376 -48.55591) (xy 285.36646 -48.645826)
			(xy 285.402274 -48.68164) (xy 285.546038 -48.80737)
		)
		(stroke
			(width 0)
			(type solid)
		)
		(fill yes)
		(layer "F.Cu")
		(net "M_B_DQS_DN<15>")
	)
	(gr_poly
		(pts
			(xy 285.623508 -111.052102) (xy 285.659322 -111.016034) (xy 285.56966 -110.926372) (xy 285.533592 -110.962186)
			(xy 285.407862 -111.10595) (xy 285.479744 -111.177832)
		)
		(stroke
			(width 0)
			(type solid)
		)
		(fill yes)
		(layer "F.Cu")
		(net "M_E_DQ<43>")
	)
	(gr_poly
		(pts
			(xy 285.626302 -45.94225) (xy 285.500572 -45.798486) (xy 285.464504 -45.762672) (xy 285.374842 -45.852334)
			(xy 285.410656 -45.888148) (xy 285.55442 -46.013878)
		)
		(stroke
			(width 0)
			(type solid)
		)
		(fill yes)
		(layer "F.Cu")
		(net "M_B_DQ<52>")
	)
	(gr_poly
		(pts
			(xy 285.638494 -105.854246) (xy 285.674562 -105.818432) (xy 285.584646 -105.728516) (xy 285.548832 -105.764584)
			(xy 285.423102 -105.908094) (xy 285.494984 -105.979976)
		)
		(stroke
			(width 0)
			(type solid)
		)
		(fill yes)
		(layer "F.Cu")
		(net "M_E_DQS_DP<15>")
	)
	(gr_poly
		(pts
			(xy 285.646622 -43.462956) (xy 285.610808 -43.426888) (xy 285.467044 -43.301158) (xy 285.395162 -43.37304)
			(xy 285.520892 -43.516804) (xy 285.55696 -43.552618)
		)
		(stroke
			(width 0)
			(type solid)
		)
		(fill yes)
		(layer "F.Cu")
		(net "M_B_DQ<42>")
	)
	(gr_poly
		(pts
			(xy 285.665164 -106.294682) (xy 285.790894 -106.150918) (xy 285.719266 -106.079036) (xy 285.575502 -106.204766)
			(xy 285.539434 -106.24058) (xy 285.62935 -106.330496)
		)
		(stroke
			(width 0)
			(type solid)
		)
		(fill yes)
		(layer "F.Cu")
		(net "M_E_DQ<49>")
	)
	(gr_poly
		(pts
			(xy 285.688278 -112.3823) (xy 285.688278 -112.3315) (xy 285.561278 -112.3315) (xy 285.561278 -112.3823)
			(xy 285.573978 -112.5728) (xy 285.675578 -112.5728)
		)
		(stroke
			(width 0)
			(type solid)
		)
		(fill yes)
		(layer "F.Cu")
		(net "M_E_DQ<46>")
	)
	(gr_poly
		(pts
			(xy 285.688278 -111.9886) (xy 285.688278 -111.9378) (xy 285.561278 -111.9378) (xy 285.561278 -111.9886)
			(xy 285.573978 -112.1791) (xy 285.675578 -112.1791)
		)
		(stroke
			(width 0)
			(type solid)
		)
		(fill yes)
		(layer "F.Cu")
		(net "M_E_DQ<47>")
	)
	(gr_poly
		(pts
			(xy 285.689802 -48.322484) (xy 285.653734 -48.28667) (xy 285.510224 -48.16094) (xy 285.438342 -48.232822)
			(xy 285.564072 -48.376332) (xy 285.599886 -48.4124)
		)
		(stroke
			(width 0)
			(type solid)
		)
		(fill yes)
		(layer "F.Cu")
		(net "M_B_DQS_DN<15>")
	)
	(gr_poly
		(pts
			(xy 285.698184 -45.528992) (xy 285.662116 -45.493178) (xy 285.518606 -45.367448) (xy 285.446724 -45.43933)
			(xy 285.572454 -45.58284) (xy 285.608268 -45.618908)
		)
		(stroke
			(width 0)
			(type solid)
		)
		(fill yes)
		(layer "F.Cu")
		(net "M_B_DQ<52>")
	)
	(gr_poly
		(pts
			(xy 285.716218 -46.966124) (xy 285.590488 -46.82236) (xy 285.554674 -46.786546) (xy 285.464758 -46.876462)
			(xy 285.500826 -46.912276) (xy 285.64459 -47.038006)
		)
		(stroke
			(width 0)
			(type solid)
		)
		(fill yes)
		(layer "F.Cu")
		(net "M_B_DQ<48>")
	)
	(gr_poly
		(pts
			(xy 285.735014 -102.582218) (xy 285.735014 -102.361238) (xy 285.564834 -102.272338) (xy 285.520384 -102.272338)
			(xy 285.520384 -102.671118) (xy 285.564834 -102.671118)
		)
		(stroke
			(width 0)
			(type solid)
		)
		(fill yes)
		(layer "F.Cu")
		(net "M_E_DQS_DN<15>")
	)
	(gr_poly
		(pts
			(xy 285.736538 -107.624118) (xy 285.772606 -107.588304) (xy 285.68269 -107.498388) (xy 285.646876 -107.534456)
			(xy 285.521146 -107.677966) (xy 285.593028 -107.749848)
		)
		(stroke
			(width 0)
			(type solid)
		)
		(fill yes)
		(layer "F.Cu")
		(net "M_E_DQ<53>")
	)
	(gr_poly
		(pts
			(xy 285.763208 -43.13047) (xy 285.637478 -42.986706) (xy 285.601664 -42.950892) (xy 285.511748 -43.040808)
			(xy 285.547816 -43.076622) (xy 285.691326 -43.202352)
		)
		(stroke
			(width 0)
			(type solid)
		)
		(fill yes)
		(layer "F.Cu")
		(net "M_B_DQ<47>")
	)
	(gr_poly
		(pts
			(xy 285.763462 -108.0643) (xy 285.889192 -107.920536) (xy 285.81731 -107.848908) (xy 285.673546 -107.974384)
			(xy 285.637732 -108.010452) (xy 285.727394 -108.100114)
		)
		(stroke
			(width 0)
			(type solid)
		)
		(fill yes)
		(layer "F.Cu")
		(net "M_E_DQ<52>")
	)
	(gr_poly
		(pts
			(xy 285.779718 -49.346612) (xy 285.743904 -49.310544) (xy 285.60014 -49.184814) (xy 285.528258 -49.256696)
			(xy 285.653988 -49.40046) (xy 285.690056 -49.436274)
		)
		(stroke
			(width 0)
			(type solid)
		)
		(fill yes)
		(layer "F.Cu")
		(net "M_B_DQS_DP<6>")
	)
	(gr_poly
		(pts
			(xy 285.7881 -46.55312) (xy 285.752286 -46.517052) (xy 285.608522 -46.391322) (xy 285.53664 -46.463204)
			(xy 285.66237 -46.606968) (xy 285.698438 -46.642782)
		)
		(stroke
			(width 0)
			(type solid)
		)
		(fill yes)
		(layer "F.Cu")
		(net "M_B_DQ<48>")
	)
	(gr_poly
		(pts
			(xy 285.806134 -47.990252) (xy 285.680404 -47.846488) (xy 285.64459 -47.810674) (xy 285.554674 -47.90059)
			(xy 285.590742 -47.936404) (xy 285.734506 -48.062134)
		)
		(stroke
			(width 0)
			(type solid)
		)
		(fill yes)
		(layer "F.Cu")
		(net "M_B_DQS_DP<15>")
	)
	(gr_poly
		(pts
			(xy 285.826962 -106.59999) (xy 285.862776 -106.563922) (xy 285.773114 -106.47426) (xy 285.737046 -106.510074)
			(xy 285.611316 -106.653838) (xy 285.683198 -106.72572)
		)
		(stroke
			(width 0)
			(type solid)
		)
		(fill yes)
		(layer "F.Cu")
		(net "M_E_DQ<49>")
	)
	(gr_poly
		(pts
			(xy 285.83509 -42.717466) (xy 285.799276 -42.681398) (xy 285.655512 -42.555668) (xy 285.58363 -42.62755)
			(xy 285.70936 -42.771314) (xy 285.745428 -42.807128)
		)
		(stroke
			(width 0)
			(type solid)
		)
		(fill yes)
		(layer "F.Cu")
		(net "M_B_DQ<47>")
	)
	(gr_poly
		(pts
			(xy 285.853378 -44.154598) (xy 285.727648 -44.010834) (xy 285.69158 -43.97502) (xy 285.601918 -44.064682)
			(xy 285.637732 -44.10075) (xy 285.781496 -44.22648)
		)
		(stroke
			(width 0)
			(type solid)
		)
		(fill yes)
		(layer "F.Cu")
		(net "M_B_DQ<43>")
	)
	(gr_poly
		(pts
			(xy 285.853632 -107.040172) (xy 285.979362 -106.896408) (xy 285.907734 -106.824526) (xy 285.76397 -106.950256)
			(xy 285.727902 -106.98607) (xy 285.817818 -107.075986)
		)
		(stroke
			(width 0)
			(type solid)
		)
		(fill yes)
		(layer "F.Cu")
		(net "M_E_DQ<48>")
	)
	(gr_poly
		(pts
			(xy 285.87827 -47.577248) (xy 285.842456 -47.54118) (xy 285.698692 -47.41545) (xy 285.62681 -47.487332)
			(xy 285.75254 -47.631096) (xy 285.788608 -47.66691)
		)
		(stroke
			(width 0)
			(type solid)
		)
		(fill yes)
		(layer "F.Cu")
		(net "M_B_DQS_DP<15>")
	)
	(gr_poly
		(pts
			(xy 285.896304 -49.014126) (xy 285.770574 -48.870362) (xy 285.73476 -48.834548) (xy 285.645098 -48.92421)
			(xy 285.680912 -48.960278) (xy 285.824676 -49.086008)
		)
		(stroke
			(width 0)
			(type solid)
		)
		(fill yes)
		(layer "F.Cu")
		(net "M_B_DQS_DN<6>")
	)
	(gr_poly
		(pts
			(xy 285.904686 -46.220634) (xy 285.778956 -46.07687) (xy 285.743142 -46.041056) (xy 285.653226 -46.130972)
			(xy 285.689294 -46.166786) (xy 285.833058 -46.292516)
		)
		(stroke
			(width 0)
			(type solid)
		)
		(fill yes)
		(layer "F.Cu")
		(net "M_B_DQ<53>")
	)
	(gr_poly
		(pts
			(xy 285.917132 -105.575608) (xy 285.9532 -105.539794) (xy 285.863284 -105.449878) (xy 285.82747 -105.485946)
			(xy 285.70174 -105.629456) (xy 285.773622 -105.701338)
		)
		(stroke
			(width 0)
			(type solid)
		)
		(fill yes)
		(layer "F.Cu")
		(net "M_E_DQS_DN<15>")
	)
	(gr_poly
		(pts
			(xy 285.925006 -108.369608) (xy 285.961074 -108.333794) (xy 285.871158 -108.243878) (xy 285.835344 -108.279946)
			(xy 285.709614 -108.423456) (xy 285.781496 -108.495338)
		)
		(stroke
			(width 0)
			(type solid)
		)
		(fill yes)
		(layer "F.Cu")
		(net "M_E_DQ<52>")
	)
	(gr_poly
		(pts
			(xy 285.92526 -43.74134) (xy 285.889192 -43.705526) (xy 285.745682 -43.579796) (xy 285.6738 -43.651678)
			(xy 285.79953 -43.795188) (xy 285.835344 -43.831256)
		)
		(stroke
			(width 0)
			(type solid)
		)
		(fill yes)
		(layer "F.Cu")
		(net "M_B_DQ<43>")
	)
	(gr_poly
		(pts
			(xy 285.943802 -106.016044) (xy 286.069532 -105.87228) (xy 285.997904 -105.800398) (xy 285.85414 -105.926128)
			(xy 285.818072 -105.961942) (xy 285.907988 -106.051858)
		)
		(stroke
			(width 0)
			(type solid)
		)
		(fill yes)
		(layer "F.Cu")
		(net "M_E_DQS_DP<15>")
	)
	(gr_poly
		(pts
			(xy 285.951676 -42.38498) (xy 285.825946 -42.241216) (xy 285.789878 -42.205402) (xy 285.700216 -42.295064)
			(xy 285.73603 -42.331132) (xy 285.879794 -42.456862)
		)
		(stroke
			(width 0)
			(type solid)
		)
		(fill yes)
		(layer "F.Cu")
		(net "M_B_DQ<46>")
	)
	(gr_poly
		(pts
			(xy 285.968186 -48.601122) (xy 285.932372 -48.565054) (xy 285.788608 -48.439324) (xy 285.716726 -48.511206)
			(xy 285.842456 -48.65497) (xy 285.878524 -48.690784)
		)
		(stroke
			(width 0)
			(type solid)
		)
		(fill yes)
		(layer "F.Cu")
		(net "M_B_DQS_DN<6>")
	)
	(gr_poly
		(pts
			(xy 285.976568 -45.80763) (xy 285.940754 -45.771562) (xy 285.79699 -45.645832) (xy 285.725108 -45.717714)
			(xy 285.850838 -45.861478) (xy 285.886906 -45.897292)
		)
		(stroke
			(width 0)
			(type solid)
		)
		(fill yes)
		(layer "F.Cu")
		(net "M_B_DQ<53>")
	)
	(gr_poly
		(pts
			(xy 285.994856 -47.244762) (xy 285.869126 -47.100998) (xy 285.833312 -47.06493) (xy 285.743396 -47.154846)
			(xy 285.77921 -47.19066) (xy 285.922974 -47.31639)
		)
		(stroke
			(width 0)
			(type solid)
		)
		(fill yes)
		(layer "F.Cu")
		(net "M_B_DQ<49>")
	)
	(gr_poly
		(pts
			(xy 286.01543 -107.34548) (xy 286.051244 -107.309412) (xy 285.961582 -107.21975) (xy 285.925514 -107.255564)
			(xy 285.799784 -107.399328) (xy 285.871666 -107.47121)
		)
		(stroke
			(width 0)
			(type solid)
		)
		(fill yes)
		(layer "F.Cu")
		(net "M_E_DQ<48>")
	)
	(gr_poly
		(pts
			(xy 286.018478 -112.2807) (xy 286.005778 -112.0902) (xy 285.904178 -112.0902) (xy 285.891478 -112.2807)
			(xy 285.891478 -112.3315) (xy 286.018478 -112.3315)
		)
		(stroke
			(width 0)
			(type solid)
		)
		(fill yes)
		(layer "F.Cu")
		(net "M_E_DQ<46>")
	)
	(gr_poly
		(pts
			(xy 286.018478 -111.887) (xy 286.005778 -111.6965) (xy 285.904178 -111.6965) (xy 285.891478 -111.887)
			(xy 285.891478 -111.9378) (xy 286.018478 -111.9378)
		)
		(stroke
			(width 0)
			(type solid)
		)
		(fill yes)
		(layer "F.Cu")
		(net "M_E_DQ<47>")
	)
	(gr_poly
		(pts
			(xy 286.018478 -111.4933) (xy 286.005778 -111.3028) (xy 285.904178 -111.3028) (xy 285.891478 -111.4933)
			(xy 285.891478 -111.5441) (xy 286.018478 -111.5441)
		)
		(stroke
			(width 0)
			(type solid)
		)
		(fill yes)
		(layer "F.Cu")
		(net "M_E_DQ<42>")
	)
	(gr_poly
		(pts
			(xy 286.018478 -111.0996) (xy 286.005778 -110.9091) (xy 285.904178 -110.9091) (xy 285.891478 -111.0996)
			(xy 285.891478 -111.1504) (xy 286.018478 -111.1504)
		)
		(stroke
			(width 0)
			(type solid)
		)
		(fill yes)
		(layer "F.Cu")
		(net "M_E_DQ<43>")
	)
	(gr_poly
		(pts
			(xy 286.041846 -107.785916) (xy 286.167576 -107.642152) (xy 286.095948 -107.57027) (xy 285.952184 -107.696)
			(xy 285.916116 -107.731814) (xy 286.006032 -107.82173)
		)
		(stroke
			(width 0)
			(type solid)
		)
		(fill yes)
		(layer "F.Cu")
		(net "M_E_DQ<53>")
	)
	(gr_poly
		(pts
			(xy 286.041846 -43.409108) (xy 285.916116 -43.265344) (xy 285.880048 -43.22953) (xy 285.790386 -43.319192)
			(xy 285.8262 -43.35526) (xy 285.969964 -43.48099)
		)
		(stroke
			(width 0)
			(type solid)
		)
		(fill yes)
		(layer "F.Cu")
		(net "M_B_DQ<42>")
	)
	(gr_poly
		(pts
			(xy 286.058356 -49.624996) (xy 286.022288 -49.589182) (xy 285.878778 -49.463452) (xy 285.806896 -49.535334)
			(xy 285.932626 -49.678844) (xy 285.96844 -49.714912)
		)
		(stroke
			(width 0)
			(type solid)
		)
		(fill yes)
		(layer "F.Cu")
		(net "M_B_DQ<54>")
	)
	(gr_poly
		(pts
			(xy 286.066738 -46.831504) (xy 286.03067 -46.79569) (xy 285.88716 -46.66996) (xy 285.815278 -46.741842)
			(xy 285.941008 -46.885352) (xy 285.976822 -46.92142)
		)
		(stroke
			(width 0)
			(type solid)
		)
		(fill yes)
		(layer "F.Cu")
		(net "M_B_DQ<49>")
	)
	(gr_poly
		(pts
			(xy 286.084772 -48.268636) (xy 285.959042 -48.124872) (xy 285.923228 -48.089058) (xy 285.833312 -48.178974)
			(xy 285.86938 -48.214788) (xy 286.013144 -48.340518)
		)
		(stroke
			(width 0)
			(type solid)
		)
		(fill yes)
		(layer "F.Cu")
		(net "M_B_DQS_DN<15>")
	)
	(gr_poly
		(pts
			(xy 286.093154 -45.475144) (xy 285.967424 -45.33138) (xy 285.93161 -45.295566) (xy 285.841694 -45.385482)
			(xy 285.877762 -45.421296) (xy 286.021526 -45.547026)
		)
		(stroke
			(width 0)
			(type solid)
		)
		(fill yes)
		(layer "F.Cu")
		(net "M_B_DQ<52>")
	)
	(gr_poly
		(pts
			(xy 286.1056 -106.321352) (xy 286.141414 -106.285284) (xy 286.051752 -106.195622) (xy 286.015684 -106.231436)
			(xy 285.889954 -106.3752) (xy 285.961836 -106.447082)
		)
		(stroke
			(width 0)
			(type solid)
		)
		(fill yes)
		(layer "F.Cu")
		(net "M_E_DQS_DP<15>")
	)
	(gr_poly
		(pts
			(xy 286.113728 -42.99585) (xy 286.07766 -42.960036) (xy 285.93415 -42.834306) (xy 285.862268 -42.906188)
			(xy 285.987998 -43.049698) (xy 286.023812 -43.085766)
		)
		(stroke
			(width 0)
			(type solid)
		)
		(fill yes)
		(layer "F.Cu")
		(net "M_B_DQ<42>")
	)
	(gr_poly
		(pts
			(xy 286.13227 -106.761534) (xy 286.258 -106.61777) (xy 286.186118 -106.546142) (xy 286.042354 -106.671872)
			(xy 286.00654 -106.707686) (xy 286.096202 -106.797348)
		)
		(stroke
			(width 0)
			(type solid)
		)
		(fill yes)
		(layer "F.Cu")
		(net "M_E_DQ<49>")
	)
	(gr_poly
		(pts
			(xy 286.156908 -47.855632) (xy 286.121094 -47.819564) (xy 285.97733 -47.693834) (xy 285.905448 -47.765716)
			(xy 286.031178 -47.90948) (xy 286.067246 -47.945294)
		)
		(stroke
			(width 0)
			(type solid)
		)
		(fill yes)
		(layer "F.Cu")
		(net "M_B_DQS_DN<15>")
	)
	(gr_poly
		(pts
			(xy 286.165036 -45.06214) (xy 286.129222 -45.026072) (xy 285.985458 -44.900342) (xy 285.913576 -44.972224)
			(xy 286.039306 -45.115988) (xy 286.075374 -45.151802)
		)
		(stroke
			(width 0)
			(type solid)
		)
		(fill yes)
		(layer "F.Cu")
		(net "M_B_DQ<52>")
	)
	(gr_poly
		(pts
			(xy 286.174942 -49.292764) (xy 286.049212 -49.149) (xy 286.013398 -49.112932) (xy 285.923482 -49.202848)
			(xy 285.959296 -49.238662) (xy 286.10306 -49.364392)
		)
		(stroke
			(width 0)
			(type solid)
		)
		(fill yes)
		(layer "F.Cu")
		(net "M_B_DQS_DP<6>")
	)
	(gr_poly
		(pts
			(xy 286.183324 -46.499272) (xy 286.057594 -46.355508) (xy 286.021526 -46.319694) (xy 285.931864 -46.409356)
			(xy 285.967678 -46.44517) (xy 286.111442 -46.5709)
		)
		(stroke
			(width 0)
			(type solid)
		)
		(fill yes)
		(layer "F.Cu")
		(net "M_B_DQ<48>")
	)
	(gr_poly
		(pts
			(xy 286.203644 -108.091224) (xy 286.239458 -108.055156) (xy 286.149796 -107.965494) (xy 286.113728 -108.001308)
			(xy 285.987998 -108.145072) (xy 286.05988 -108.216954)
		)
		(stroke
			(width 0)
			(type solid)
		)
		(fill yes)
		(layer "F.Cu")
		(net "M_E_DQ<53>")
	)
	(gr_poly
		(pts
			(xy 286.22244 -105.737406) (xy 286.34817 -105.593642) (xy 286.276542 -105.52176) (xy 286.132778 -105.64749)
			(xy 286.09671 -105.683304) (xy 286.186626 -105.77322)
		)
		(stroke
			(width 0)
			(type solid)
		)
		(fill yes)
		(layer "F.Cu")
		(net "M_E_DQS_DN<15>")
	)
	(gr_poly
		(pts
			(xy 286.23006 -42.663364) (xy 286.10433 -42.5196) (xy 286.068516 -42.483786) (xy 285.9786 -42.573702)
			(xy 286.014668 -42.609516) (xy 286.158178 -42.735246)
		)
		(stroke
			(width 0)
			(type solid)
		)
		(fill yes)
		(layer "F.Cu")
		(net "M_B_DQ<47>")
	)
	(gr_poly
		(pts
			(xy 286.2326 -52.631594) (xy 286.40278 -52.542694) (xy 286.40278 -52.321714) (xy 286.2326 -52.232814)
			(xy 286.188404 -52.232814) (xy 286.18815 -52.631848)
		)
		(stroke
			(width 0)
			(type solid)
		)
		(fill yes)
		(layer "F.Cu")
		(net "M_B_DQ<51>")
	)
	(gr_poly
		(pts
			(xy 286.246316 -101.277674) (xy 286.201866 -101.277674) (xy 286.031686 -101.366574) (xy 286.031686 -101.587554)
			(xy 286.201866 -101.676454) (xy 286.246316 -101.676454)
		)
		(stroke
			(width 0)
			(type solid)
		)
		(fill yes)
		(layer "F.Cu")
		(net "M_E_DQ<54>")
	)
	(gr_poly
		(pts
			(xy 286.246824 -48.879506) (xy 286.210756 -48.843692) (xy 286.067246 -48.717962) (xy 285.995364 -48.789844)
			(xy 286.121094 -48.933354) (xy 286.156908 -48.969422)
		)
		(stroke
			(width 0)
			(type solid)
		)
		(fill yes)
		(layer "F.Cu")
		(net "M_B_DQS_DP<6>")
	)
	(gr_poly
		(pts
			(xy 286.255206 -46.086014) (xy 286.219138 -46.0502) (xy 286.075628 -45.92447) (xy 286.003746 -45.996352)
			(xy 286.129476 -46.139862) (xy 286.16529 -46.17593)
		)
		(stroke
			(width 0)
			(type solid)
		)
		(fill yes)
		(layer "F.Cu")
		(net "M_B_DQ<48>")
	)
	(gr_poly
		(pts
			(xy 286.27324 -47.5234) (xy 286.14751 -47.379636) (xy 286.111696 -47.343568) (xy 286.02178 -47.433484)
			(xy 286.057594 -47.469298) (xy 286.201358 -47.595028)
		)
		(stroke
			(width 0)
			(type solid)
		)
		(fill yes)
		(layer "F.Cu")
		(net "M_B_DQS_DP<15>")
	)
	(gr_poly
		(pts
			(xy 286.293814 -107.066842) (xy 286.329882 -107.031028) (xy 286.239966 -106.941112) (xy 286.204152 -106.97718)
			(xy 286.078422 -107.12069) (xy 286.150304 -107.192572)
		)
		(stroke
			(width 0)
			(type solid)
		)
		(fill yes)
		(layer "F.Cu")
		(net "M_E_DQ<49>")
	)
	(gr_poly
		(pts
			(xy 286.32023 -43.687492) (xy 286.1945 -43.543728) (xy 286.158686 -43.507914) (xy 286.06877 -43.59783)
			(xy 286.104838 -43.633644) (xy 286.248348 -43.759374)
		)
		(stroke
			(width 0)
			(type solid)
		)
		(fill yes)
		(layer "F.Cu")
		(net "M_B_DQ<43>")
	)
	(gr_poly
		(pts
			(xy 286.320738 -107.507024) (xy 286.446468 -107.36326) (xy 286.374586 -107.291632) (xy 286.230822 -107.417108)
			(xy 286.195008 -107.453176) (xy 286.28467 -107.542838)
		)
		(stroke
			(width 0)
			(type solid)
		)
		(fill yes)
		(layer "F.Cu")
		(net "M_E_DQ<48>")
	)
	(gr_poly
		(pts
			(xy 286.345376 -47.110142) (xy 286.309308 -47.074328) (xy 286.165798 -46.948598) (xy 286.093916 -47.02048)
			(xy 286.219646 -47.16399) (xy 286.25546 -47.200058)
		)
		(stroke
			(width 0)
			(type solid)
		)
		(fill yes)
		(layer "F.Cu")
		(net "M_B_DQS_DP<15>")
	)
	(gr_poly
		(pts
			(xy 286.348678 -112.3823) (xy 286.348678 -112.3315) (xy 286.221678 -112.3315) (xy 286.221678 -112.3823)
			(xy 286.234378 -112.5728) (xy 286.335978 -112.5728)
		)
		(stroke
			(width 0)
			(type solid)
		)
		(fill yes)
		(layer "F.Cu")
		(net "M_E_DQ<46>")
	)
	(gr_poly
		(pts
			(xy 286.348678 -111.9886) (xy 286.348678 -111.9378) (xy 286.221678 -111.9378) (xy 286.221678 -111.9886)
			(xy 286.234378 -112.1791) (xy 286.335978 -112.1791)
		)
		(stroke
			(width 0)
			(type solid)
		)
		(fill yes)
		(layer "F.Cu")
		(net "M_E_DQ<47>")
	)
	(gr_poly
		(pts
			(xy 286.348678 -111.5949) (xy 286.348678 -111.5441) (xy 286.221678 -111.5441) (xy 286.221678 -111.5949)
			(xy 286.234378 -111.7854) (xy 286.335978 -111.7854)
		)
		(stroke
			(width 0)
			(type solid)
		)
		(fill yes)
		(layer "F.Cu")
		(net "M_E_DQ<42>")
	)
	(gr_poly
		(pts
			(xy 286.348678 -111.2012) (xy 286.348678 -111.1504) (xy 286.221678 -111.1504) (xy 286.221678 -111.2012)
			(xy 286.234378 -111.3917) (xy 286.335978 -111.3917)
		)
		(stroke
			(width 0)
			(type solid)
		)
		(fill yes)
		(layer "F.Cu")
		(net "M_E_DQ<43>")
	)
	(gr_poly
		(pts
			(xy 286.36341 -48.547274) (xy 286.23768 -48.40351) (xy 286.201866 -48.367442) (xy 286.11195 -48.457358)
			(xy 286.147764 -48.493172) (xy 286.291528 -48.618902)
		)
		(stroke
			(width 0)
			(type solid)
		)
		(fill yes)
		(layer "F.Cu")
		(net "M_B_DQS_DN<6>")
	)
	(gr_poly
		(pts
			(xy 286.371792 -45.753782) (xy 286.246062 -45.610018) (xy 286.209994 -45.574204) (xy 286.120332 -45.663866)
			(xy 286.156146 -45.699934) (xy 286.29991 -45.82541)
		)
		(stroke
			(width 0)
			(type solid)
		)
		(fill yes)
		(layer "F.Cu")
		(net "M_B_DQ<53>")
	)
	(gr_poly
		(pts
			(xy 286.384238 -106.042714) (xy 286.420052 -106.006646) (xy 286.33039 -105.916984) (xy 286.294322 -105.952798)
			(xy 286.168592 -106.096562) (xy 286.240474 -106.168444)
		)
		(stroke
			(width 0)
			(type solid)
		)
		(fill yes)
		(layer "F.Cu")
		(net "M_E_DQS_DN<15>")
	)
	(gr_poly
		(pts
			(xy 286.392112 -43.274488) (xy 286.356298 -43.23842) (xy 286.212534 -43.11269) (xy 286.140652 -43.184572)
			(xy 286.266382 -43.328336) (xy 286.30245 -43.36415)
		)
		(stroke
			(width 0)
			(type solid)
		)
		(fill yes)
		(layer "F.Cu")
		(net "M_B_DQ<43>")
	)
	(gr_poly
		(pts
			(xy 286.410908 -106.482896) (xy 286.536638 -106.339132) (xy 286.464756 -106.267504) (xy 286.320992 -106.393234)
			(xy 286.285178 -106.429048) (xy 286.37484 -106.51871)
		)
		(stroke
			(width 0)
			(type solid)
		)
		(fill yes)
		(layer "F.Cu")
		(net "M_E_DQS_DP<15>")
	)
	(gr_poly
		(pts
			(xy 286.435292 -48.134016) (xy 286.399224 -48.098202) (xy 286.255714 -47.972472) (xy 286.183832 -48.044354)
			(xy 286.309562 -48.187864) (xy 286.345376 -48.223932)
		)
		(stroke
			(width 0)
			(type solid)
		)
		(fill yes)
		(layer "F.Cu")
		(net "M_B_DQS_DN<6>")
	)
	(gr_poly
		(pts
			(xy 286.443674 -45.340524) (xy 286.407606 -45.30471) (xy 286.264096 -45.17898) (xy 286.192214 -45.250862)
			(xy 286.317944 -45.394372) (xy 286.353758 -45.43044)
		)
		(stroke
			(width 0)
			(type solid)
		)
		(fill yes)
		(layer "F.Cu")
		(net "M_B_DQ<53>")
	)
	(gr_poly
		(pts
			(xy 286.453326 -49.571148) (xy 286.327596 -49.427384) (xy 286.291782 -49.39157) (xy 286.20212 -49.481232)
			(xy 286.237934 -49.5173) (xy 286.381698 -49.64303)
		)
		(stroke
			(width 0)
			(type solid)
		)
		(fill yes)
		(layer "F.Cu")
		(net "M_B_DQ<54>")
	)
	(gr_poly
		(pts
			(xy 286.461708 -46.777656) (xy 286.335978 -46.633892) (xy 286.300164 -46.598078) (xy 286.210248 -46.687994)
			(xy 286.246316 -46.723808) (xy 286.39008 -46.849538)
		)
		(stroke
			(width 0)
			(type solid)
		)
		(fill yes)
		(layer "F.Cu")
		(net "M_B_DQ<49>")
	)
	(gr_poly
		(pts
			(xy 286.474408 -50.477166) (xy 286.429958 -50.477166) (xy 286.259778 -50.566066) (xy 286.259778 -50.787046)
			(xy 286.429958 -50.875946) (xy 286.474408 -50.875946)
		)
		(stroke
			(width 0)
			(type solid)
		)
		(fill yes)
		(layer "F.Cu")
		(net "M_B_DQ<50>")
	)
	(gr_poly
		(pts
			(xy 286.482282 -107.812332) (xy 286.51835 -107.776518) (xy 286.428434 -107.686602) (xy 286.39262 -107.72267)
			(xy 286.26689 -107.86618) (xy 286.338772 -107.938062)
		)
		(stroke
			(width 0)
			(type solid)
		)
		(fill yes)
		(layer "F.Cu")
		(net "M_E_DQ<48>")
	)
	(gr_poly
		(pts
			(xy 286.501078 -105.458768) (xy 286.626808 -105.315004) (xy 286.55518 -105.243122) (xy 286.411416 -105.368852)
			(xy 286.375348 -105.404666) (xy 286.465264 -105.494582)
		)
		(stroke
			(width 0)
			(type solid)
		)
		(fill yes)
		(layer "F.Cu")
		(net "M_E_DQS_DN<6>")
	)
	(gr_poly
		(pts
			(xy 286.508698 -42.942002) (xy 286.382968 -42.798492) (xy 286.347154 -42.762424) (xy 286.257238 -42.85234)
			(xy 286.293306 -42.888154) (xy 286.436816 -43.013884)
		)
		(stroke
			(width 0)
			(type solid)
		)
		(fill yes)
		(layer "F.Cu")
		(net "M_B_DQ<42>")
	)
	(gr_poly
		(pts
			(xy 286.50946 -108.572554) (xy 286.49676 -108.382054) (xy 286.39516 -108.382054) (xy 286.38246 -108.572554)
			(xy 286.38246 -108.623354) (xy 286.50946 -108.623354)
		)
		(stroke
			(width 0)
			(type solid)
		)
		(fill yes)
		(layer "F.Cu")
		(net "M_E_DQ<52>")
	)
	(gr_poly
		(pts
			(xy 286.525208 -49.158144) (xy 286.489394 -49.122076) (xy 286.34563 -48.996346) (xy 286.273748 -49.068228)
			(xy 286.399478 -49.211992) (xy 286.435546 -49.247806)
		)
		(stroke
			(width 0)
			(type solid)
		)
		(fill yes)
		(layer "F.Cu")
		(net "M_B_DQ<54>")
	)
	(gr_poly
		(pts
			(xy 286.53359 -46.364652) (xy 286.497776 -46.328584) (xy 286.354012 -46.202854) (xy 286.28213 -46.274736)
			(xy 286.40786 -46.4185) (xy 286.443928 -46.454314)
		)
		(stroke
			(width 0)
			(type solid)
		)
		(fill yes)
		(layer "F.Cu")
		(net "M_B_DQ<49>")
	)
	(gr_poly
		(pts
			(xy 286.551878 -47.801784) (xy 286.426148 -47.65802) (xy 286.390334 -47.621952) (xy 286.300418 -47.711868)
			(xy 286.336232 -47.747682) (xy 286.479996 -47.873412)
		)
		(stroke
			(width 0)
			(type solid)
		)
		(fill yes)
		(layer "F.Cu")
		(net "M_B_DQS_DN<15>")
	)
	(gr_poly
		(pts
			(xy 286.56026 -45.008292) (xy 286.43453 -44.864528) (xy 286.398462 -44.828714) (xy 286.3088 -44.918376)
			(xy 286.344614 -44.954444) (xy 286.488378 -45.080174)
		)
		(stroke
			(width 0)
			(type solid)
		)
		(fill yes)
		(layer "F.Cu")
		(net "M_B_DQ<52>")
	)
	(gr_poly
		(pts
			(xy 286.572452 -106.788204) (xy 286.60852 -106.75239) (xy 286.518604 -106.662474) (xy 286.48279 -106.698542)
			(xy 286.35706 -106.842052) (xy 286.428942 -106.913934)
		)
		(stroke
			(width 0)
			(type solid)
		)
		(fill yes)
		(layer "F.Cu")
		(net "M_E_DQS_DP<15>")
	)
	(gr_poly
		(pts
			(xy 286.580834 -42.528998) (xy 286.544766 -42.493184) (xy 286.401256 -42.367454) (xy 286.329374 -42.439336)
			(xy 286.455104 -42.582846) (xy 286.490918 -42.618914)
		)
		(stroke
			(width 0)
			(type solid)
		)
		(fill yes)
		(layer "F.Cu")
		(net "M_B_DQ<42>")
	)
	(gr_poly
		(pts
			(xy 286.593788 -102.071678) (xy 286.593788 -101.850698) (xy 286.423608 -101.761798) (xy 286.379158 -101.761798)
			(xy 286.379158 -102.160578) (xy 286.423608 -102.160578)
		)
		(stroke
			(width 0)
			(type solid)
		)
		(fill yes)
		(layer "F.Cu")
		(net "M_E_DQ<54>")
	)
	(gr_poly
		(pts
			(xy 286.599122 -107.22864) (xy 286.724852 -107.084876) (xy 286.653224 -107.012994) (xy 286.50946 -107.138724)
			(xy 286.473392 -107.174538) (xy 286.563308 -107.264454)
		)
		(stroke
			(width 0)
			(type solid)
		)
		(fill yes)
		(layer "F.Cu")
		(net "M_E_DQ<49>")
	)
	(gr_poly
		(pts
			(xy 286.62376 -47.388526) (xy 286.587692 -47.352712) (xy 286.444182 -47.226982) (xy 286.3723 -47.298864)
			(xy 286.49803 -47.442374) (xy 286.533844 -47.478442)
		)
		(stroke
			(width 0)
			(type solid)
		)
		(fill yes)
		(layer "F.Cu")
		(net "M_B_DQS_DN<15>")
	)
	(gr_poly
		(pts
			(xy 286.632142 -44.595034) (xy 286.596074 -44.55922) (xy 286.452564 -44.43349) (xy 286.380682 -44.505372)
			(xy 286.506412 -44.648882) (xy 286.542226 -44.68495)
		)
		(stroke
			(width 0)
			(type solid)
		)
		(fill yes)
		(layer "F.Cu")
		(net "M_B_DQ<52>")
	)
	(gr_poly
		(pts
			(xy 286.641794 -48.825658) (xy 286.516064 -48.681894) (xy 286.48025 -48.64608) (xy 286.390334 -48.735996)
			(xy 286.426402 -48.77181) (xy 286.570166 -48.89754)
		)
		(stroke
			(width 0)
			(type solid)
		)
		(fill yes)
		(layer "F.Cu")
		(net "M_B_DQS_DP<6>")
	)
	(gr_poly
		(pts
			(xy 286.650176 -46.032166) (xy 286.524446 -45.888402) (xy 286.488632 -45.852588) (xy 286.398716 -45.942504)
			(xy 286.434784 -45.978318) (xy 286.578548 -46.104048)
		)
		(stroke
			(width 0)
			(type solid)
		)
		(fill yes)
		(layer "F.Cu")
		(net "M_B_DQ<48>")
	)
	(gr_poly
		(pts
			(xy 286.662876 -105.764076) (xy 286.69869 -105.728008) (xy 286.609028 -105.638346) (xy 286.57296 -105.67416)
			(xy 286.44723 -105.817924) (xy 286.519112 -105.889806)
		)
		(stroke
			(width 0)
			(type solid)
		)
		(fill yes)
		(layer "F.Cu")
		(net "M_E_DQS_DN<6>")
	)
	(gr_poly
		(pts
			(xy 286.678878 -111.887) (xy 286.666178 -111.6965) (xy 286.564578 -111.6965) (xy 286.551878 -111.887)
			(xy 286.551878 -111.9378) (xy 286.678878 -111.9378)
		)
		(stroke
			(width 0)
			(type solid)
		)
		(fill yes)
		(layer "F.Cu")
		(net "M_E_DQ<47>")
	)
	(gr_poly
		(pts
			(xy 286.678878 -111.4933) (xy 286.666178 -111.3028) (xy 286.564578 -111.3028) (xy 286.551878 -111.4933)
			(xy 286.551878 -111.5441) (xy 286.678878 -111.5441)
		)
		(stroke
			(width 0)
			(type solid)
		)
		(fill yes)
		(layer "F.Cu")
		(net "M_E_DQ<42>")
	)
	(gr_poly
		(pts
			(xy 286.678878 -111.0996) (xy 286.666178 -110.9091) (xy 286.564578 -110.9091) (xy 286.551878 -111.0996)
			(xy 286.551878 -111.1504) (xy 286.678878 -111.1504)
		)
		(stroke
			(width 0)
			(type solid)
		)
		(fill yes)
		(layer "F.Cu")
		(net "M_E_DQ<43>")
	)
	(gr_poly
		(pts
			(xy 286.68853 -104.337358) (xy 286.81426 -104.193594) (xy 286.742378 -104.121966) (xy 286.598614 -104.247696)
			(xy 286.5628 -104.28351) (xy 286.652716 -104.373426)
		)
		(stroke
			(width 0)
			(type solid)
		)
		(fill yes)
		(layer "F.Cu")
		(net "M_E_DQ<54>")
	)
	(gr_poly
		(pts
			(xy 286.689546 -106.204258) (xy 286.815276 -106.060494) (xy 286.743394 -105.988866) (xy 286.59963 -106.114596)
			(xy 286.563816 -106.15041) (xy 286.653478 -106.240072)
		)
		(stroke
			(width 0)
			(type solid)
		)
		(fill yes)
		(layer "F.Cu")
		(net "M_E_DQS_DN<15>")
	)
	(gr_poly
		(pts
			(xy 286.713676 -48.412654) (xy 286.677862 -48.376586) (xy 286.534098 -48.250856) (xy 286.462216 -48.322738)
			(xy 286.587946 -48.466502) (xy 286.624014 -48.502316)
		)
		(stroke
			(width 0)
			(type solid)
		)
		(fill yes)
		(layer "F.Cu")
		(net "M_B_DQS_DP<6>")
	)
	(gr_poly
		(pts
			(xy 286.722058 -45.619162) (xy 286.686244 -45.583094) (xy 286.54248 -45.457364) (xy 286.470598 -45.529246)
			(xy 286.596328 -45.67301) (xy 286.632396 -45.708824)
		)
		(stroke
			(width 0)
			(type solid)
		)
		(fill yes)
		(layer "F.Cu")
		(net "M_B_DQ<48>")
	)
	(gr_poly
		(pts
			(xy 286.731964 -49.849786) (xy 286.606234 -49.706022) (xy 286.57042 -49.669954) (xy 286.480504 -49.75987)
			(xy 286.516318 -49.795684) (xy 286.660082 -49.921414)
		)
		(stroke
			(width 0)
			(type solid)
		)
		(fill yes)
		(layer "F.Cu")
		(net "M_B_DQ<55>")
	)
	(gr_poly
		(pts
			(xy 286.740092 -47.056294) (xy 286.614362 -46.91253) (xy 286.578548 -46.876716) (xy 286.488632 -46.966632)
			(xy 286.5247 -47.002446) (xy 286.668464 -47.128176)
		)
		(stroke
			(width 0)
			(type solid)
		)
		(fill yes)
		(layer "F.Cu")
		(net "M_B_DQS_DP<15>")
	)
	(gr_poly
		(pts
			(xy 286.779716 -105.18013) (xy 286.905446 -105.036366) (xy 286.833818 -104.964484) (xy 286.690054 -105.090214)
			(xy 286.653986 -105.126028) (xy 286.743902 -105.215944)
		)
		(stroke
			(width 0)
			(type solid)
		)
		(fill yes)
		(layer "F.Cu")
		(net "M_E_DQS_DP<6>")
	)
	(gr_poly
		(pts
			(xy 286.787336 -43.22064) (xy 286.661606 -43.076876) (xy 286.625538 -43.041062) (xy 286.535876 -43.130724)
			(xy 286.57169 -43.166792) (xy 286.715454 -43.292522)
		)
		(stroke
			(width 0)
			(type solid)
		)
		(fill yes)
		(layer "F.Cu")
		(net "M_B_DQ<43>")
	)
	(gr_poly
		(pts
			(xy 286.803846 -49.436528) (xy 286.767778 -49.400714) (xy 286.624268 -49.274984) (xy 286.552386 -49.346866)
			(xy 286.678116 -49.490376) (xy 286.71393 -49.526444)
		)
		(stroke
			(width 0)
			(type solid)
		)
		(fill yes)
		(layer "F.Cu")
		(net "M_B_DQ<55>")
	)
	(gr_poly
		(pts
			(xy 286.812228 -46.64329) (xy 286.776414 -46.607222) (xy 286.63265 -46.481492) (xy 286.560768 -46.553374)
			(xy 286.686498 -46.697138) (xy 286.722566 -46.732952)
		)
		(stroke
			(width 0)
			(type solid)
		)
		(fill yes)
		(layer "F.Cu")
		(net "M_B_DQS_DP<15>")
	)
	(gr_poly
		(pts
			(xy 286.830262 -48.080168) (xy 286.704532 -47.936404) (xy 286.668718 -47.90059) (xy 286.578802 -47.990506)
			(xy 286.61487 -48.02632) (xy 286.758634 -48.15205)
		)
		(stroke
			(width 0)
			(type solid)
		)
		(fill yes)
		(layer "F.Cu")
		(net "M_B_DQS_DN<6>")
	)
	(gr_poly
		(pts
			(xy 286.838644 -45.286676) (xy 286.712914 -45.142912) (xy 286.6771 -45.107098) (xy 286.587184 -45.197014)
			(xy 286.623252 -45.232828) (xy 286.767016 -45.358558)
		)
		(stroke
			(width 0)
			(type solid)
		)
		(fill yes)
		(layer "F.Cu")
		(net "M_B_DQ<53>")
	)
	(gr_poly
		(pts
			(xy 286.83966 -108.674154) (xy 286.83966 -108.623354) (xy 286.71266 -108.623354) (xy 286.71266 -108.674154)
			(xy 286.72536 -108.864654) (xy 286.82696 -108.864654)
		)
		(stroke
			(width 0)
			(type solid)
		)
		(fill yes)
		(layer "F.Cu")
		(net "M_E_DQ<52>")
	)
	(gr_poly
		(pts
			(xy 286.83966 -108.280454) (xy 286.83966 -108.229654) (xy 286.71266 -108.229654) (xy 286.71266 -108.280454)
			(xy 286.72536 -108.470954) (xy 286.82696 -108.470954)
		)
		(stroke
			(width 0)
			(type solid)
		)
		(fill yes)
		(layer "F.Cu")
		(net "M_E_DQ<53>")
	)
	(gr_poly
		(pts
			(xy 286.83966 -107.886754) (xy 286.83966 -107.835954) (xy 286.71266 -107.835954) (xy 286.71266 -107.886754)
			(xy 286.72536 -108.077254) (xy 286.82696 -108.077254)
		)
		(stroke
			(width 0)
			(type solid)
		)
		(fill yes)
		(layer "F.Cu")
		(net "M_E_DQ<48>")
	)
	(gr_poly
		(pts
			(xy 286.850074 -104.642666) (xy 286.886142 -104.606852) (xy 286.796226 -104.516936) (xy 286.760412 -104.553004)
			(xy 286.634682 -104.696514) (xy 286.706564 -104.768396)
		)
		(stroke
			(width 0)
			(type solid)
		)
		(fill yes)
		(layer "F.Cu")
		(net "M_E_DQ<54>")
	)
	(gr_poly
		(pts
			(xy 286.85109 -106.509566) (xy 286.887158 -106.473752) (xy 286.797242 -106.383836) (xy 286.761428 -106.419904)
			(xy 286.635698 -106.563414) (xy 286.70758 -106.635296)
		)
		(stroke
			(width 0)
			(type solid)
		)
		(fill yes)
		(layer "F.Cu")
		(net "M_E_DQS_DN<15>")
	)
	(gr_poly
		(pts
			(xy 286.859218 -42.807636) (xy 286.823404 -42.771568) (xy 286.67964 -42.645838) (xy 286.607758 -42.71772)
			(xy 286.733488 -42.861484) (xy 286.769556 -42.897298)
		)
		(stroke
			(width 0)
			(type solid)
		)
		(fill yes)
		(layer "F.Cu")
		(net "M_B_DQ<43>")
	)
	(gr_poly
		(pts
			(xy 286.879538 -51.009042) (xy 286.879538 -50.788062) (xy 286.709358 -50.699162) (xy 286.664908 -50.699162)
			(xy 286.664908 -51.097942) (xy 286.709358 -51.097942)
		)
		(stroke
			(width 0)
			(type solid)
		)
		(fill yes)
		(layer "F.Cu")
		(net "M_B_DQ<51>")
	)
	(gr_poly
		(pts
			(xy 286.902144 -47.667164) (xy 286.86633 -47.631096) (xy 286.722566 -47.505366) (xy 286.650684 -47.577248)
			(xy 286.776414 -47.721012) (xy 286.812482 -47.756826)
		)
		(stroke
			(width 0)
			(type solid)
		)
		(fill yes)
		(layer "F.Cu")
		(net "M_B_DQS_DN<6>")
	)
	(gr_poly
		(pts
			(xy 286.910526 -44.873672) (xy 286.874712 -44.837604) (xy 286.730948 -44.711874) (xy 286.659066 -44.783756)
			(xy 286.784796 -44.92752) (xy 286.820864 -44.963334)
		)
		(stroke
			(width 0)
			(type solid)
		)
		(fill yes)
		(layer "F.Cu")
		(net "M_B_DQ<53>")
	)
	(gr_poly
		(pts
			(xy 286.91459 -101.746812) (xy 286.87014 -101.746812) (xy 286.69996 -101.835712) (xy 286.699706 -102.056692)
			(xy 286.87014 -102.145338) (xy 286.914336 -102.145592)
		)
		(stroke
			(width 0)
			(type solid)
		)
		(fill yes)
		(layer "F.Cu")
		(net "M_E_DQ<50>")
	)
	(gr_poly
		(pts
			(xy 286.920432 -49.104296) (xy 286.794702 -48.960532) (xy 286.758888 -48.924464) (xy 286.668972 -49.01438)
			(xy 286.704786 -49.050194) (xy 286.84855 -49.175924)
		)
		(stroke
			(width 0)
			(type solid)
		)
		(fill yes)
		(layer "F.Cu")
		(net "M_B_DQ<54>")
	)
	(gr_poly
		(pts
			(xy 286.928814 -46.310804) (xy 286.803084 -46.16704) (xy 286.767016 -46.131226) (xy 286.677354 -46.220888)
			(xy 286.713168 -46.256956) (xy 286.856932 -46.382432)
		)
		(stroke
			(width 0)
			(type solid)
		)
		(fill yes)
		(layer "F.Cu")
		(net "M_B_DQ<49>")
	)
	(gr_poly
		(pts
			(xy 286.941514 -105.485438) (xy 286.977328 -105.44937) (xy 286.887666 -105.359708) (xy 286.851598 -105.395522)
			(xy 286.725868 -105.539286) (xy 286.79775 -105.611168)
		)
		(stroke
			(width 0)
			(type solid)
		)
		(fill yes)
		(layer "F.Cu")
		(net "M_E_DQS_DP<6>")
	)
	(gr_poly
		(pts
			(xy 286.966914 -104.058974) (xy 287.092644 -103.91521) (xy 287.021016 -103.843328) (xy 286.877252 -103.969058)
			(xy 286.841184 -104.004872) (xy 286.9311 -104.094788)
		)
		(stroke
			(width 0)
			(type solid)
		)
		(fill yes)
		(layer "F.Cu")
		(net "M_E_DQ<55>")
	)
	(gr_poly
		(pts
			(xy 286.968184 -105.92562) (xy 287.093914 -105.781856) (xy 287.022032 -105.710228) (xy 286.878268 -105.835958)
			(xy 286.842454 -105.871772) (xy 286.932116 -105.961434)
		)
		(stroke
			(width 0)
			(type solid)
		)
		(fill yes)
		(layer "F.Cu")
		(net "M_E_DQS_DN<6>")
	)
	(gr_poly
		(pts
			(xy 286.975804 -42.47515) (xy 286.850074 -42.33164) (xy 286.81426 -42.295572) (xy 286.724344 -42.385488)
			(xy 286.760412 -42.421302) (xy 286.903922 -42.547032)
		)
		(stroke
			(width 0)
			(type solid)
		)
		(fill yes)
		(layer "F.Cu")
		(net "M_B_DQ<42>")
	)
	(gr_poly
		(pts
			(xy 286.992314 -48.691038) (xy 286.956246 -48.655224) (xy 286.812736 -48.529494) (xy 286.740854 -48.601376)
			(xy 286.866584 -48.744886) (xy 286.902398 -48.780954)
		)
		(stroke
			(width 0)
			(type solid)
		)
		(fill yes)
		(layer "F.Cu")
		(net "M_B_DQ<54>")
	)
	(gr_poly
		(pts
			(xy 287.000696 -45.897546) (xy 286.964628 -45.861732) (xy 286.821118 -45.736002) (xy 286.749236 -45.807884)
			(xy 286.874966 -45.951394) (xy 286.91078 -45.987462)
		)
		(stroke
			(width 0)
			(type solid)
		)
		(fill yes)
		(layer "F.Cu")
		(net "M_B_DQ<49>")
	)
	(gr_poly
		(pts
			(xy 287.005522 -44.451524) (xy 287.005522 -44.400724) (xy 286.878522 -44.400724) (xy 286.878522 -44.451524)
			(xy 286.891222 -44.642024) (xy 286.992822 -44.642024)
		)
		(stroke
			(width 0)
			(type solid)
		)
		(fill yes)
		(layer "F.Cu")
		(net "M_B_DQ<52>")
	)
	(gr_poly
		(pts
			(xy 287.010348 -50.12817) (xy 286.884618 -49.984406) (xy 286.848804 -49.948592) (xy 286.759142 -50.038254)
			(xy 286.794956 -50.074322) (xy 286.93872 -50.200052)
		)
		(stroke
			(width 0)
			(type solid)
		)
		(fill yes)
		(layer "F.Cu")
		(net "M_B_DQ<50>")
	)
	(gr_poly
		(pts
			(xy 287.01873 -47.334678) (xy 286.893 -47.190914) (xy 286.857186 -47.1551) (xy 286.76727 -47.245016)
			(xy 286.803338 -47.28083) (xy 286.947102 -47.40656)
		)
		(stroke
			(width 0)
			(type solid)
		)
		(fill yes)
		(layer "F.Cu")
		(net "M_B_DQS_DN<15>")
	)
	(gr_poly
		(pts
			(xy 287.08223 -49.715166) (xy 287.046416 -49.679098) (xy 286.902652 -49.553368) (xy 286.83077 -49.62525)
			(xy 286.9565 -49.769014) (xy 286.992568 -49.804828)
		)
		(stroke
			(width 0)
			(type solid)
		)
		(fill yes)
		(layer "F.Cu")
		(net "M_B_DQ<50>")
	)
	(gr_poly
		(pts
			(xy 287.090866 -46.921674) (xy 287.055052 -46.885606) (xy 286.911288 -46.759876) (xy 286.839406 -46.831758)
			(xy 286.965136 -46.975522) (xy 287.001204 -47.011336)
		)
		(stroke
			(width 0)
			(type solid)
		)
		(fill yes)
		(layer "F.Cu")
		(net "M_B_DQS_DN<15>")
	)
	(gr_poly
		(pts
			(xy 287.1089 -48.358806) (xy 286.98317 -48.215042) (xy 286.947356 -48.178974) (xy 286.85744 -48.26889)
			(xy 286.893254 -48.304704) (xy 287.037018 -48.430434)
		)
		(stroke
			(width 0)
			(type solid)
		)
		(fill yes)
		(layer "F.Cu")
		(net "M_B_DQS_DP<6>")
	)
	(gr_poly
		(pts
			(xy 287.117282 -45.565314) (xy 286.991552 -45.42155) (xy 286.955484 -45.385736) (xy 286.865822 -45.475398)
			(xy 286.901636 -45.511466) (xy 287.0454 -45.637196)
		)
		(stroke
			(width 0)
			(type solid)
		)
		(fill yes)
		(layer "F.Cu")
		(net "M_B_DQ<48>")
	)
	(gr_poly
		(pts
			(xy 287.128712 -104.364282) (xy 287.164526 -104.328214) (xy 287.074864 -104.238552) (xy 287.038796 -104.274366)
			(xy 286.913066 -104.41813) (xy 286.984948 -104.490012)
		)
		(stroke
			(width 0)
			(type solid)
		)
		(fill yes)
		(layer "F.Cu")
		(net "M_E_DQ<55>")
	)
	(gr_poly
		(pts
			(xy 287.129728 -106.230928) (xy 287.165796 -106.195114) (xy 287.07588 -106.105198) (xy 287.040066 -106.141266)
			(xy 286.914336 -106.284776) (xy 286.986218 -106.356658)
		)
		(stroke
			(width 0)
			(type solid)
		)
		(fill yes)
		(layer "F.Cu")
		(net "M_E_DQS_DN<6>")
	)
	(gr_poly
		(pts
			(xy 287.155382 -104.804464) (xy 287.281112 -104.6607) (xy 287.209484 -104.588818) (xy 287.06572 -104.714548)
			(xy 287.029652 -104.750362) (xy 287.119568 -104.840278)
		)
		(stroke
			(width 0)
			(type solid)
		)
		(fill yes)
		(layer "F.Cu")
		(net "M_E_DQ<54>")
	)
	(gr_poly
		(pts
			(xy 287.16986 -108.572554) (xy 287.15716 -108.382054) (xy 287.05556 -108.382054) (xy 287.04286 -108.572554)
			(xy 287.04286 -108.623354) (xy 287.16986 -108.623354)
		)
		(stroke
			(width 0)
			(type solid)
		)
		(fill yes)
		(layer "F.Cu")
		(net "M_E_DQ<52>")
	)
	(gr_poly
		(pts
			(xy 287.16986 -108.178854) (xy 287.15716 -107.988354) (xy 287.05556 -107.988354) (xy 287.04286 -108.178854)
			(xy 287.04286 -108.229654) (xy 287.16986 -108.229654)
		)
		(stroke
			(width 0)
			(type solid)
		)
		(fill yes)
		(layer "F.Cu")
		(net "M_E_DQ<53>")
	)
	(gr_poly
		(pts
			(xy 287.16986 -107.785154) (xy 287.15716 -107.594654) (xy 287.05556 -107.594654) (xy 287.04286 -107.785154)
			(xy 287.04286 -107.835954) (xy 287.16986 -107.835954)
		)
		(stroke
			(width 0)
			(type solid)
		)
		(fill yes)
		(layer "F.Cu")
		(net "M_E_DQ<48>")
	)
	(gr_poly
		(pts
			(xy 287.16986 -107.391454) (xy 287.15716 -107.200954) (xy 287.05556 -107.200954) (xy 287.04286 -107.391454)
			(xy 287.04286 -107.442254) (xy 287.16986 -107.442254)
		)
		(stroke
			(width 0)
			(type solid)
		)
		(fill yes)
		(layer "F.Cu")
		(net "M_E_DQ<49>")
	)
	(gr_poly
		(pts
			(xy 287.16986 -106.997754) (xy 287.15716 -106.807254) (xy 287.05556 -106.807254) (xy 287.04286 -106.997754)
			(xy 287.04286 -107.048554) (xy 287.16986 -107.048554)
		)
		(stroke
			(width 0)
			(type solid)
		)
		(fill yes)
		(layer "F.Cu")
		(net "M_E_DQS_DP<15>")
	)
	(gr_poly
		(pts
			(xy 287.180782 -47.945548) (xy 287.144714 -47.909734) (xy 287.001204 -47.784004) (xy 286.929322 -47.855886)
			(xy 287.055052 -47.999396) (xy 287.090866 -48.035464)
		)
		(stroke
			(width 0)
			(type solid)
		)
		(fill yes)
		(layer "F.Cu")
		(net "M_B_DQS_DP<6>")
	)
	(gr_poly
		(pts
			(xy 287.198816 -49.38268) (xy 287.073086 -49.238916) (xy 287.037272 -49.203102) (xy 286.947356 -49.293018)
			(xy 286.983424 -49.328832) (xy 287.127188 -49.454562)
		)
		(stroke
			(width 0)
			(type solid)
		)
		(fill yes)
		(layer "F.Cu")
		(net "M_B_DQ<55>")
	)
	(gr_poly
		(pts
			(xy 287.207198 -46.589442) (xy 287.081468 -46.445678) (xy 287.0454 -46.409864) (xy 286.955738 -46.499526)
			(xy 286.991552 -46.535594) (xy 287.135316 -46.66107)
		)
		(stroke
			(width 0)
			(type solid)
		)
		(fill yes)
		(layer "F.Cu")
		(net "M_B_DQS_DP<15>")
	)
	(gr_poly
		(pts
			(xy 287.245552 -103.780336) (xy 287.371282 -103.636572) (xy 287.2994 -103.564944) (xy 287.155636 -103.690674)
			(xy 287.119822 -103.726488) (xy 287.209738 -103.816404)
		)
		(stroke
			(width 0)
			(type solid)
		)
		(fill yes)
		(layer "F.Cu")
		(net "M_E_DQ<50>")
	)
	(gr_poly
		(pts
			(xy 287.246822 -105.646982) (xy 287.372552 -105.503218) (xy 287.30067 -105.43159) (xy 287.156906 -105.55732)
			(xy 287.121092 -105.593134) (xy 287.210754 -105.682796)
		)
		(stroke
			(width 0)
			(type solid)
		)
		(fill yes)
		(layer "F.Cu")
		(net "M_E_DQS_DP<6>")
	)
	(gr_poly
		(pts
			(xy 287.254442 -42.753788) (xy 287.128712 -42.610024) (xy 287.092644 -42.57421) (xy 287.002982 -42.663872)
			(xy 287.038796 -42.69994) (xy 287.18256 -42.82567)
		)
		(stroke
			(width 0)
			(type solid)
		)
		(fill yes)
		(layer "F.Cu")
		(net "M_B_DQ<43>")
	)
	(gr_poly
		(pts
			(xy 287.270698 -48.969676) (xy 287.234884 -48.933608) (xy 287.09112 -48.807878) (xy 287.019238 -48.87976)
			(xy 287.144968 -49.023524) (xy 287.181036 -49.059338)
		)
		(stroke
			(width 0)
			(type solid)
		)
		(fill yes)
		(layer "F.Cu")
		(net "M_B_DQ<55>")
	)
	(gr_poly
		(pts
			(xy 287.279334 -46.176184) (xy 287.243266 -46.14037) (xy 287.099756 -46.01464) (xy 287.027874 -46.086522)
			(xy 287.153604 -46.230032) (xy 287.189418 -46.2661)
		)
		(stroke
			(width 0)
			(type solid)
		)
		(fill yes)
		(layer "F.Cu")
		(net "M_B_DQS_DP<15>")
	)
	(gr_poly
		(pts
			(xy 287.288986 -50.406808) (xy 287.163256 -50.263044) (xy 287.127442 -50.226976) (xy 287.037526 -50.316892)
			(xy 287.07334 -50.352706) (xy 287.217104 -50.478436)
		)
		(stroke
			(width 0)
			(type solid)
		)
		(fill yes)
		(layer "F.Cu")
		(net "M_B_DQ<51>")
	)
	(gr_poly
		(pts
			(xy 287.297368 -47.613316) (xy 287.171638 -47.469552) (xy 287.13557 -47.433738) (xy 287.045908 -47.5234)
			(xy 287.081722 -47.559214) (xy 287.225486 -47.684944)
		)
		(stroke
			(width 0)
			(type solid)
		)
		(fill yes)
		(layer "F.Cu")
		(net "M_B_DQS_DN<6>")
	)
	(gr_poly
		(pts
			(xy 287.31718 -105.109772) (xy 287.352994 -105.073704) (xy 287.263332 -104.984042) (xy 287.227264 -105.019856)
			(xy 287.101534 -105.16362) (xy 287.173416 -105.235502)
		)
		(stroke
			(width 0)
			(type solid)
		)
		(fill yes)
		(layer "F.Cu")
		(net "M_E_DQ<54>")
	)
	(gr_poly
		(pts
			(xy 287.324038 -111.45012) (xy 287.359852 -111.414052) (xy 287.27019 -111.32439) (xy 287.234122 -111.360204)
			(xy 287.108392 -111.503968) (xy 287.180274 -111.57585)
		)
		(stroke
			(width 0)
			(type solid)
		)
		(fill yes)
		(layer "F.Cu")
		(net "M_E_DQ<43>")
	)
	(gr_poly
		(pts
			(xy 287.335722 -44.743624) (xy 287.323022 -44.553124) (xy 287.221422 -44.553124) (xy 287.208722 -44.743624)
			(xy 287.208722 -44.794424) (xy 287.335722 -44.794424)
		)
		(stroke
			(width 0)
			(type solid)
		)
		(fill yes)
		(layer "F.Cu")
		(net "M_B_DQ<53>")
	)
	(gr_poly
		(pts
			(xy 287.335722 -44.349924) (xy 287.323022 -44.159424) (xy 287.221422 -44.159424) (xy 287.208722 -44.349924)
			(xy 287.208722 -44.400724) (xy 287.335722 -44.400724)
		)
		(stroke
			(width 0)
			(type solid)
		)
		(fill yes)
		(layer "F.Cu")
		(net "M_B_DQ<52>")
	)
	(gr_poly
		(pts
			(xy 287.350708 -111.890302) (xy 287.476438 -111.746538) (xy 287.40481 -111.674656) (xy 287.261046 -111.800386)
			(xy 287.224978 -111.8362) (xy 287.314894 -111.926116)
		)
		(stroke
			(width 0)
			(type solid)
		)
		(fill yes)
		(layer "F.Cu")
		(net "M_E_DQ<42>")
	)
	(gr_poly
		(pts
			(xy 287.360868 -49.99355) (xy 287.3248 -49.957736) (xy 287.18129 -49.832006) (xy 287.109408 -49.903888)
			(xy 287.235138 -50.047398) (xy 287.270952 -50.083466)
		)
		(stroke
			(width 0)
			(type solid)
		)
		(fill yes)
		(layer "F.Cu")
		(net "M_B_DQ<51>")
	)
	(gr_poly
		(pts
			(xy 287.36925 -47.200058) (xy 287.333182 -47.164244) (xy 287.189672 -47.038514) (xy 287.11779 -47.110396)
			(xy 287.24352 -47.253906) (xy 287.279334 -47.289974)
		)
		(stroke
			(width 0)
			(type solid)
		)
		(fill yes)
		(layer "F.Cu")
		(net "M_B_DQS_DN<6>")
	)
	(gr_poly
		(pts
			(xy 287.387284 -48.63719) (xy 287.261554 -48.493426) (xy 287.22574 -48.457612) (xy 287.135824 -48.547528)
			(xy 287.171892 -48.583342) (xy 287.315656 -48.709072)
		)
		(stroke
			(width 0)
			(type solid)
		)
		(fill yes)
		(layer "F.Cu")
		(net "M_B_DQ<54>")
	)
	(gr_poly
		(pts
			(xy 287.395666 -45.843698) (xy 287.269936 -45.699934) (xy 287.234122 -45.66412) (xy 287.144206 -45.754036)
			(xy 287.180274 -45.78985) (xy 287.324038 -45.91558)
		)
		(stroke
			(width 0)
			(type solid)
		)
		(fill yes)
		(layer "F.Cu")
		(net "M_B_DQ<49>")
	)
	(gr_poly
		(pts
			(xy 287.407096 -104.085644) (xy 287.443164 -104.04983) (xy 287.353248 -103.959914) (xy 287.317434 -103.995982)
			(xy 287.191704 -104.139492) (xy 287.263586 -104.211374)
		)
		(stroke
			(width 0)
			(type solid)
		)
		(fill yes)
		(layer "F.Cu")
		(net "M_E_DQ<50>")
	)
	(gr_poly
		(pts
			(xy 287.43402 -104.525826) (xy 287.55975 -104.382062) (xy 287.487868 -104.310434) (xy 287.344104 -104.436164)
			(xy 287.30829 -104.471978) (xy 287.398206 -104.561894)
		)
		(stroke
			(width 0)
			(type solid)
		)
		(fill yes)
		(layer "F.Cu")
		(net "M_E_DQ<55>")
	)
	(gr_poly
		(pts
			(xy 287.452308 -102.579424) (xy 287.452308 -102.358444) (xy 287.282128 -102.269544) (xy 287.237678 -102.269544)
			(xy 287.237678 -102.668324) (xy 287.282128 -102.668324)
		)
		(stroke
			(width 0)
			(type solid)
		)
		(fill yes)
		(layer "F.Cu")
		(net "M_E_DQ<51>")
	)
	(gr_poly
		(pts
			(xy 287.459166 -48.224186) (xy 287.423352 -48.188118) (xy 287.279588 -48.062388) (xy 287.207706 -48.13427)
			(xy 287.333436 -48.278034) (xy 287.369504 -48.313848)
		)
		(stroke
			(width 0)
			(type solid)
		)
		(fill yes)
		(layer "F.Cu")
		(net "M_B_DQ<54>")
	)
	(gr_poly
		(pts
			(xy 287.477454 -49.661318) (xy 287.351724 -49.517554) (xy 287.31591 -49.481486) (xy 287.225994 -49.571402)
			(xy 287.261808 -49.607216) (xy 287.405572 -49.732946)
		)
		(stroke
			(width 0)
			(type solid)
		)
		(fill yes)
		(layer "F.Cu")
		(net "M_B_DQ<50>")
	)
	(gr_poly
		(pts
			(xy 287.485836 -46.867826) (xy 287.360106 -46.724062) (xy 287.324038 -46.688248) (xy 287.234376 -46.77791)
			(xy 287.27019 -46.813978) (xy 287.413954 -46.939454)
		)
		(stroke
			(width 0)
			(type solid)
		)
		(fill yes)
		(layer "F.Cu")
		(net "M_B_DQS_DN<15>")
	)
	(gr_poly
		(pts
			(xy 287.50006 -108.674154) (xy 287.50006 -108.623354) (xy 287.37306 -108.623354) (xy 287.37306 -108.674154)
			(xy 287.38576 -108.864654) (xy 287.48736 -108.864654)
		)
		(stroke
			(width 0)
			(type solid)
		)
		(fill yes)
		(layer "F.Cu")
		(net "M_E_DQ<52>")
	)
	(gr_poly
		(pts
			(xy 287.50006 -108.280454) (xy 287.50006 -108.229654) (xy 287.37306 -108.229654) (xy 287.37306 -108.280454)
			(xy 287.38576 -108.470954) (xy 287.48736 -108.470954)
		)
		(stroke
			(width 0)
			(type solid)
		)
		(fill yes)
		(layer "F.Cu")
		(net "M_E_DQ<53>")
	)
	(gr_poly
		(pts
			(xy 287.50006 -107.886754) (xy 287.50006 -107.835954) (xy 287.37306 -107.835954) (xy 287.37306 -107.886754)
			(xy 287.38576 -108.077254) (xy 287.48736 -108.077254)
		)
		(stroke
			(width 0)
			(type solid)
		)
		(fill yes)
		(layer "F.Cu")
		(net "M_E_DQ<48>")
	)
	(gr_poly
		(pts
			(xy 287.50006 -107.493054) (xy 287.50006 -107.442254) (xy 287.37306 -107.442254) (xy 287.37306 -107.493054)
			(xy 287.38576 -107.683554) (xy 287.48736 -107.683554)
		)
		(stroke
			(width 0)
			(type solid)
		)
		(fill yes)
		(layer "F.Cu")
		(net "M_E_DQ<49>")
	)
	(gr_poly
		(pts
			(xy 287.50006 -107.099354) (xy 287.50006 -107.048554) (xy 287.37306 -107.048554) (xy 287.37306 -107.099354)
			(xy 287.38576 -107.289854) (xy 287.48736 -107.289854)
		)
		(stroke
			(width 0)
			(type solid)
		)
		(fill yes)
		(layer "F.Cu")
		(net "M_E_DQS_DP<15>")
	)
	(gr_poly
		(pts
			(xy 287.50006 -106.705654) (xy 287.50006 -106.654854) (xy 287.37306 -106.654854) (xy 287.37306 -106.705654)
			(xy 287.38576 -106.896154) (xy 287.48736 -106.896154)
		)
		(stroke
			(width 0)
			(type solid)
		)
		(fill yes)
		(layer "F.Cu")
		(net "M_E_DQS_DN<15>")
	)
	(gr_poly
		(pts
			(xy 287.50006 -106.311954) (xy 287.50006 -106.261154) (xy 287.37306 -106.261154) (xy 287.37306 -106.311954)
			(xy 287.38576 -106.502454) (xy 287.48736 -106.502454)
		)
		(stroke
			(width 0)
			(type solid)
		)
		(fill yes)
		(layer "F.Cu")
		(net "M_E_DQS_DN<6>")
	)
	(gr_poly
		(pts
			(xy 287.512506 -112.19561) (xy 287.54832 -112.159542) (xy 287.458658 -112.06988) (xy 287.42259 -112.105694)
			(xy 287.29686 -112.249458) (xy 287.368742 -112.32134)
		)
		(stroke
			(width 0)
			(type solid)
		)
		(fill yes)
		(layer "F.Cu")
		(net "M_E_DQ<42>")
	)
	(gr_poly
		(pts
			(xy 287.549336 -49.24806) (xy 287.513268 -49.212246) (xy 287.369758 -49.086516) (xy 287.297876 -49.158398)
			(xy 287.423606 -49.301908) (xy 287.45942 -49.337976)
		)
		(stroke
			(width 0)
			(type solid)
		)
		(fill yes)
		(layer "F.Cu")
		(net "M_B_DQ<50>")
	)
	(gr_poly
		(pts
			(xy 287.557718 -46.454568) (xy 287.52165 -46.418754) (xy 287.37814 -46.293024) (xy 287.306258 -46.364906)
			(xy 287.431988 -46.508416) (xy 287.467802 -46.544484)
		)
		(stroke
			(width 0)
			(type solid)
		)
		(fill yes)
		(layer "F.Cu")
		(net "M_B_DQS_DN<15>")
	)
	(gr_poly
		(pts
			(xy 287.575752 -47.8917) (xy 287.450022 -47.747936) (xy 287.414208 -47.712122) (xy 287.324292 -47.802038)
			(xy 287.36036 -47.837852) (xy 287.504124 -47.963582)
		)
		(stroke
			(width 0)
			(type solid)
		)
		(fill yes)
		(layer "F.Cu")
		(net "M_B_DQS_DP<6>")
	)
	(gr_poly
		(pts
			(xy 287.595564 -104.831134) (xy 287.631632 -104.79532) (xy 287.541716 -104.705404) (xy 287.505902 -104.741472)
			(xy 287.380172 -104.884982) (xy 287.452054 -104.956864)
		)
		(stroke
			(width 0)
			(type solid)
		)
		(fill yes)
		(layer "F.Cu")
		(net "M_E_DQ<55>")
	)
	(gr_poly
		(pts
			(xy 287.622488 -105.271316) (xy 287.748218 -105.127552) (xy 287.676336 -105.055924) (xy 287.532572 -105.181654)
			(xy 287.496758 -105.217468) (xy 287.58642 -105.30713)
		)
		(stroke
			(width 0)
			(type solid)
		)
		(fill yes)
		(layer "F.Cu")
		(net "M_E_DQ<54>")
	)
	(gr_poly
		(pts
			(xy 287.629346 -111.611664) (xy 287.755076 -111.4679) (xy 287.683194 -111.396272) (xy 287.53943 -111.522002)
			(xy 287.503616 -111.557816) (xy 287.593532 -111.647732)
		)
		(stroke
			(width 0)
			(type solid)
		)
		(fill yes)
		(layer "F.Cu")
		(net "M_E_DQ<43>")
	)
	(gr_poly
		(pts
			(xy 287.647634 -47.478696) (xy 287.61182 -47.442628) (xy 287.468056 -47.316898) (xy 287.396174 -47.38878)
			(xy 287.521904 -47.532544) (xy 287.557972 -47.568358)
		)
		(stroke
			(width 0)
			(type solid)
		)
		(fill yes)
		(layer "F.Cu")
		(net "M_B_DQS_DP<6>")
	)
	(gr_poly
		(pts
			(xy 287.665922 -48.915828) (xy 287.540192 -48.772064) (xy 287.504378 -48.735996) (xy 287.414462 -48.825912)
			(xy 287.450276 -48.861726) (xy 287.59404 -48.987456)
		)
		(stroke
			(width 0)
			(type solid)
		)
		(fill yes)
		(layer "F.Cu")
		(net "M_B_DQ<55>")
	)
	(gr_poly
		(pts
			(xy 287.665922 -45.632624) (xy 287.665922 -45.581824) (xy 287.538922 -45.581824) (xy 287.538922 -45.632624)
			(xy 287.551622 -45.823124) (xy 287.653222 -45.823124)
		)
		(stroke
			(width 0)
			(type solid)
		)
		(fill yes)
		(layer "F.Cu")
		(net "M_B_DQ<49>")
	)
	(gr_poly
		(pts
			(xy 287.665922 -45.238924) (xy 287.665922 -45.188124) (xy 287.538922 -45.188124) (xy 287.538922 -45.238924)
			(xy 287.551622 -45.429424) (xy 287.653222 -45.429424)
		)
		(stroke
			(width 0)
			(type solid)
		)
		(fill yes)
		(layer "F.Cu")
		(net "M_B_DQ<48>")
	)
	(gr_poly
		(pts
			(xy 287.665922 -44.845224) (xy 287.665922 -44.794424) (xy 287.538922 -44.794424) (xy 287.538922 -44.845224)
			(xy 287.551622 -45.035724) (xy 287.653222 -45.035724)
		)
		(stroke
			(width 0)
			(type solid)
		)
		(fill yes)
		(layer "F.Cu")
		(net "M_B_DQ<53>")
	)
	(gr_poly
		(pts
			(xy 287.665922 -44.451524) (xy 287.665922 -44.400724) (xy 287.538922 -44.400724) (xy 287.538922 -44.451524)
			(xy 287.551622 -44.642024) (xy 287.653222 -44.642024)
		)
		(stroke
			(width 0)
			(type solid)
		)
		(fill yes)
		(layer "F.Cu")
		(net "M_B_DQ<52>")
	)
	(gr_poly
		(pts
			(xy 287.685734 -103.807006) (xy 287.721802 -103.771192) (xy 287.631886 -103.681276) (xy 287.596072 -103.717344)
			(xy 287.470342 -103.860854) (xy 287.542224 -103.932736)
		)
		(stroke
			(width 0)
			(type solid)
		)
		(fill yes)
		(layer "F.Cu")
		(net "M_E_DQ<51>")
	)
	(gr_poly
		(pts
			(xy 287.712404 -104.247442) (xy 287.838134 -104.103678) (xy 287.766506 -104.031796) (xy 287.622742 -104.157526)
			(xy 287.586674 -104.19334) (xy 287.67659 -104.283256)
		)
		(stroke
			(width 0)
			(type solid)
		)
		(fill yes)
		(layer "F.Cu")
		(net "M_E_DQ<50>")
	)
	(gr_poly
		(pts
			(xy 287.737804 -48.50257) (xy 287.701736 -48.466756) (xy 287.558226 -48.341026) (xy 287.486344 -48.412908)
			(xy 287.612074 -48.556418) (xy 287.647888 -48.592486)
		)
		(stroke
			(width 0)
			(type solid)
		)
		(fill yes)
		(layer "F.Cu")
		(net "M_B_DQ<55>")
	)
	(gr_poly
		(pts
			(xy 287.755838 -49.939702) (xy 287.630108 -49.795938) (xy 287.594294 -49.760124) (xy 287.504378 -49.85004)
			(xy 287.540446 -49.885854) (xy 287.68421 -50.011584)
		)
		(stroke
			(width 0)
			(type solid)
		)
		(fill yes)
		(layer "F.Cu")
		(net "M_B_DQ<51>")
	)
	(gr_poly
		(pts
			(xy 287.76422 -47.14621) (xy 287.63849 -47.002446) (xy 287.602676 -46.966632) (xy 287.51276 -47.056548)
			(xy 287.548828 -47.092362) (xy 287.692592 -47.218092)
		)
		(stroke
			(width 0)
			(type solid)
		)
		(fill yes)
		(layer "F.Cu")
		(net "M_B_DQS_DN<6>")
	)
	(gr_poly
		(pts
			(xy 287.79089 -111.916972) (xy 287.826958 -111.881158) (xy 287.737042 -111.791242) (xy 287.701228 -111.82731)
			(xy 287.575498 -111.97082) (xy 287.64738 -112.042702)
		)
		(stroke
			(width 0)
			(type solid)
		)
		(fill yes)
		(layer "F.Cu")
		(net "M_E_DQ<43>")
	)
	(gr_poly
		(pts
			(xy 287.817814 -112.357154) (xy 287.943544 -112.21339) (xy 287.871662 -112.141762) (xy 287.727898 -112.267492)
			(xy 287.692084 -112.303306) (xy 287.782 -112.393222)
		)
		(stroke
			(width 0)
			(type solid)
		)
		(fill yes)
		(layer "F.Cu")
		(net "M_E_DQ<42>")
	)
	(gr_poly
		(pts
			(xy 287.82772 -49.526698) (xy 287.791906 -49.49063) (xy 287.648142 -49.3649) (xy 287.57626 -49.436782)
			(xy 287.70199 -49.580546) (xy 287.738058 -49.61636)
		)
		(stroke
			(width 0)
			(type solid)
		)
		(fill yes)
		(layer "F.Cu")
		(net "M_B_DQ<51>")
	)
	(gr_poly
		(pts
			(xy 287.83026 -108.572554) (xy 287.81756 -108.382054) (xy 287.71596 -108.382054) (xy 287.70326 -108.572554)
			(xy 287.70326 -108.623354) (xy 287.83026 -108.623354)
		)
		(stroke
			(width 0)
			(type solid)
		)
		(fill yes)
		(layer "F.Cu")
		(net "M_E_DQ<52>")
	)
	(gr_poly
		(pts
			(xy 287.83026 -108.178854) (xy 287.81756 -107.988354) (xy 287.71596 -107.988354) (xy 287.70326 -108.178854)
			(xy 287.70326 -108.229654) (xy 287.83026 -108.229654)
		)
		(stroke
			(width 0)
			(type solid)
		)
		(fill yes)
		(layer "F.Cu")
		(net "M_E_DQ<53>")
	)
	(gr_poly
		(pts
			(xy 287.83026 -107.785154) (xy 287.81756 -107.594654) (xy 287.71596 -107.594654) (xy 287.70326 -107.785154)
			(xy 287.70326 -107.835954) (xy 287.83026 -107.835954)
		)
		(stroke
			(width 0)
			(type solid)
		)
		(fill yes)
		(layer "F.Cu")
		(net "M_E_DQ<48>")
	)
	(gr_poly
		(pts
			(xy 287.83026 -107.391454) (xy 287.81756 -107.200954) (xy 287.71596 -107.200954) (xy 287.70326 -107.391454)
			(xy 287.70326 -107.442254) (xy 287.83026 -107.442254)
		)
		(stroke
			(width 0)
			(type solid)
		)
		(fill yes)
		(layer "F.Cu")
		(net "M_E_DQ<49>")
	)
	(gr_poly
		(pts
			(xy 287.83026 -106.997754) (xy 287.81756 -106.807254) (xy 287.71596 -106.807254) (xy 287.70326 -106.997754)
			(xy 287.70326 -107.048554) (xy 287.83026 -107.048554)
		)
		(stroke
			(width 0)
			(type solid)
		)
		(fill yes)
		(layer "F.Cu")
		(net "M_E_DQS_DP<15>")
	)
	(gr_poly
		(pts
			(xy 287.83026 -106.604054) (xy 287.81756 -106.413554) (xy 287.71596 -106.413554) (xy 287.70326 -106.604054)
			(xy 287.70326 -106.654854) (xy 287.83026 -106.654854)
		)
		(stroke
			(width 0)
			(type solid)
		)
		(fill yes)
		(layer "F.Cu")
		(net "M_E_DQS_DN<15>")
	)
	(gr_poly
		(pts
			(xy 287.83026 -106.210354) (xy 287.81756 -106.019854) (xy 287.71596 -106.019854) (xy 287.70326 -106.210354)
			(xy 287.70326 -106.261154) (xy 287.83026 -106.261154)
		)
		(stroke
			(width 0)
			(type solid)
		)
		(fill yes)
		(layer "F.Cu")
		(net "M_E_DQS_DN<6>")
	)
	(gr_poly
		(pts
			(xy 287.83026 -105.816654) (xy 287.81756 -105.626154) (xy 287.71596 -105.626154) (xy 287.70326 -105.816654)
			(xy 287.70326 -105.867454) (xy 287.83026 -105.867454)
		)
		(stroke
			(width 0)
			(type solid)
		)
		(fill yes)
		(layer "F.Cu")
		(net "M_E_DQS_DP<6>")
	)
	(gr_poly
		(pts
			(xy 287.85439 -48.170338) (xy 287.72866 -48.026574) (xy 287.692592 -47.99076) (xy 287.60293 -48.080422)
			(xy 287.638744 -48.116236) (xy 287.782508 -48.241966)
		)
		(stroke
			(width 0)
			(type solid)
		)
		(fill yes)
		(layer "F.Cu")
		(net "M_B_DQ<54>")
	)
	(gr_poly
		(pts
			(xy 287.874202 -104.55275) (xy 287.910016 -104.516682) (xy 287.820354 -104.42702) (xy 287.784286 -104.462834)
			(xy 287.658556 -104.606598) (xy 287.730438 -104.67848)
		)
		(stroke
			(width 0)
			(type solid)
		)
		(fill yes)
		(layer "F.Cu")
		(net "M_E_DQ<50>")
	)
	(gr_poly
		(pts
			(xy 287.926272 -47.75708) (xy 287.890204 -47.721266) (xy 287.746694 -47.595536) (xy 287.674812 -47.667418)
			(xy 287.800542 -47.810928) (xy 287.836356 -47.846996)
		)
		(stroke
			(width 0)
			(type solid)
		)
		(fill yes)
		(layer "F.Cu")
		(net "M_B_DQ<54>")
	)
	(gr_poly
		(pts
			(xy 287.944306 -49.194212) (xy 287.818576 -49.050448) (xy 287.782762 -49.014634) (xy 287.692846 -49.10455)
			(xy 287.728914 -49.140364) (xy 287.872678 -49.266094)
		)
		(stroke
			(width 0)
			(type solid)
		)
		(fill yes)
		(layer "F.Cu")
		(net "M_B_DQ<50>")
	)
	(gr_poly
		(pts
			(xy 287.991042 -103.968804) (xy 288.116772 -103.82504) (xy 288.045144 -103.753158) (xy 287.90138 -103.878888)
			(xy 287.865312 -103.914702) (xy 287.955228 -104.004618)
		)
		(stroke
			(width 0)
			(type solid)
		)
		(fill yes)
		(layer "F.Cu")
		(net "M_E_DQ<51>")
	)
	(gr_poly
		(pts
			(xy 287.996122 -46.318424) (xy 287.983422 -46.127924) (xy 287.881822 -46.127924) (xy 287.869122 -46.318424)
			(xy 287.869122 -46.369224) (xy 287.996122 -46.369224)
		)
		(stroke
			(width 0)
			(type solid)
		)
		(fill yes)
		(layer "F.Cu")
		(net "M_B_DQS_DN<15>")
	)
	(gr_poly
		(pts
			(xy 287.996122 -45.924724) (xy 287.983422 -45.734224) (xy 287.881822 -45.734224) (xy 287.869122 -45.924724)
			(xy 287.869122 -45.975524) (xy 287.996122 -45.975524)
		)
		(stroke
			(width 0)
			(type solid)
		)
		(fill yes)
		(layer "F.Cu")
		(net "M_B_DQS_DP<15>")
	)
	(gr_poly
		(pts
			(xy 287.996122 -45.531024) (xy 287.983422 -45.340524) (xy 287.881822 -45.340524) (xy 287.869122 -45.531024)
			(xy 287.869122 -45.581824) (xy 287.996122 -45.581824)
		)
		(stroke
			(width 0)
			(type solid)
		)
		(fill yes)
		(layer "F.Cu")
		(net "M_B_DQ<49>")
	)
	(gr_poly
		(pts
			(xy 287.996122 -45.137324) (xy 287.983422 -44.946824) (xy 287.881822 -44.946824) (xy 287.869122 -45.137324)
			(xy 287.869122 -45.188124) (xy 287.996122 -45.188124)
		)
		(stroke
			(width 0)
			(type solid)
		)
		(fill yes)
		(layer "F.Cu")
		(net "M_B_DQ<48>")
	)
	(gr_poly
		(pts
			(xy 287.996122 -44.743624) (xy 287.983422 -44.553124) (xy 287.881822 -44.553124) (xy 287.869122 -44.743624)
			(xy 287.869122 -44.794424) (xy 287.996122 -44.794424)
		)
		(stroke
			(width 0)
			(type solid)
		)
		(fill yes)
		(layer "F.Cu")
		(net "M_B_DQ<53>")
	)
	(gr_poly
		(pts
			(xy 287.996122 -44.349924) (xy 287.983422 -44.159424) (xy 287.881822 -44.159424) (xy 287.869122 -44.349924)
			(xy 287.869122 -44.400724) (xy 287.996122 -44.400724)
		)
		(stroke
			(width 0)
			(type solid)
		)
		(fill yes)
		(layer "F.Cu")
		(net "M_B_DQ<52>")
	)
	(gr_poly
		(pts
			(xy 288.016188 -48.781208) (xy 287.980374 -48.74514) (xy 287.83661 -48.61941) (xy 287.764728 -48.691292)
			(xy 287.890458 -48.835056) (xy 287.926526 -48.87087)
		)
		(stroke
			(width 0)
			(type solid)
		)
		(fill yes)
		(layer "F.Cu")
		(net "M_B_DQ<50>")
	)
	(gr_poly
		(pts
			(xy 288.096198 -112.07877) (xy 288.221928 -111.935006) (xy 288.1503 -111.863124) (xy 288.006536 -111.988854)
			(xy 287.970468 -112.024668) (xy 288.060384 -112.114584)
		)
		(stroke
			(width 0)
			(type solid)
		)
		(fill yes)
		(layer "F.Cu")
		(net "M_E_DQ<43>")
	)
	(gr_poly
		(pts
			(xy 288.132774 -48.448722) (xy 288.007044 -48.304958) (xy 287.97123 -48.269144) (xy 287.881314 -48.35906)
			(xy 287.917382 -48.394874) (xy 288.061146 -48.520604)
		)
		(stroke
			(width 0)
			(type solid)
		)
		(fill yes)
		(layer "F.Cu")
		(net "M_B_DQ<55>")
	)
	(gr_poly
		(pts
			(xy 288.15284 -104.274112) (xy 288.188654 -104.238044) (xy 288.098992 -104.148382) (xy 288.062924 -104.184196)
			(xy 287.937194 -104.32796) (xy 288.009076 -104.399842)
		)
		(stroke
			(width 0)
			(type solid)
		)
		(fill yes)
		(layer "F.Cu")
		(net "M_E_DQ<51>")
	)
	(gr_poly
		(pts
			(xy 288.16046 -108.674154) (xy 288.16046 -108.623354) (xy 288.03346 -108.623354) (xy 288.03346 -108.674154)
			(xy 288.04616 -108.864654) (xy 288.14776 -108.864654)
		)
		(stroke
			(width 0)
			(type solid)
		)
		(fill yes)
		(layer "F.Cu")
		(net "M_E_DQ<52>")
	)
	(gr_poly
		(pts
			(xy 288.16046 -108.280454) (xy 288.16046 -108.229654) (xy 288.03346 -108.229654) (xy 288.03346 -108.280454)
			(xy 288.04616 -108.470954) (xy 288.14776 -108.470954)
		)
		(stroke
			(width 0)
			(type solid)
		)
		(fill yes)
		(layer "F.Cu")
		(net "M_E_DQ<53>")
	)
	(gr_poly
		(pts
			(xy 288.16046 -107.886754) (xy 288.16046 -107.835954) (xy 288.03346 -107.835954) (xy 288.03346 -107.886754)
			(xy 288.04616 -108.077254) (xy 288.14776 -108.077254)
		)
		(stroke
			(width 0)
			(type solid)
		)
		(fill yes)
		(layer "F.Cu")
		(net "M_E_DQ<48>")
	)
	(gr_poly
		(pts
			(xy 288.16046 -107.493054) (xy 288.16046 -107.442254) (xy 288.03346 -107.442254) (xy 288.03346 -107.493054)
			(xy 288.04616 -107.683554) (xy 288.14776 -107.683554)
		)
		(stroke
			(width 0)
			(type solid)
		)
		(fill yes)
		(layer "F.Cu")
		(net "M_E_DQ<49>")
	)
	(gr_poly
		(pts
			(xy 288.16046 -107.099354) (xy 288.16046 -107.048554) (xy 288.03346 -107.048554) (xy 288.03346 -107.099354)
			(xy 288.04616 -107.289854) (xy 288.14776 -107.289854)
		)
		(stroke
			(width 0)
			(type solid)
		)
		(fill yes)
		(layer "F.Cu")
		(net "M_E_DQS_DP<15>")
	)
	(gr_poly
		(pts
			(xy 288.16046 -106.705654) (xy 288.16046 -106.654854) (xy 288.03346 -106.654854) (xy 288.03346 -106.705654)
			(xy 288.04616 -106.896154) (xy 288.14776 -106.896154)
		)
		(stroke
			(width 0)
			(type solid)
		)
		(fill yes)
		(layer "F.Cu")
		(net "M_E_DQS_DN<15>")
	)
	(gr_poly
		(pts
			(xy 288.16046 -106.311954) (xy 288.16046 -106.261154) (xy 288.03346 -106.261154) (xy 288.03346 -106.311954)
			(xy 288.04616 -106.502454) (xy 288.14776 -106.502454)
		)
		(stroke
			(width 0)
			(type solid)
		)
		(fill yes)
		(layer "F.Cu")
		(net "M_E_DQS_DN<6>")
	)
	(gr_poly
		(pts
			(xy 288.16046 -105.918254) (xy 288.16046 -105.867454) (xy 288.03346 -105.867454) (xy 288.03346 -105.918254)
			(xy 288.04616 -106.108754) (xy 288.14776 -106.108754)
		)
		(stroke
			(width 0)
			(type solid)
		)
		(fill yes)
		(layer "F.Cu")
		(net "M_E_DQS_DP<6>")
	)
	(gr_poly
		(pts
			(xy 288.16046 -105.524554) (xy 288.16046 -105.473754) (xy 288.03346 -105.473754) (xy 288.03346 -105.524554)
			(xy 288.04616 -105.715054) (xy 288.14776 -105.715054)
		)
		(stroke
			(width 0)
			(type solid)
		)
		(fill yes)
		(layer "F.Cu")
		(net "M_E_DQ<54>")
	)
	(gr_poly
		(pts
			(xy 288.16046 -105.130854) (xy 288.16046 -105.080054) (xy 288.03346 -105.080054) (xy 288.03346 -105.130854)
			(xy 288.04616 -105.321354) (xy 288.14776 -105.321354)
		)
		(stroke
			(width 0)
			(type solid)
		)
		(fill yes)
		(layer "F.Cu")
		(net "M_E_DQ<55>")
	)
	(gr_poly
		(pts
			(xy 288.204656 -48.035718) (xy 288.168842 -47.99965) (xy 288.025078 -47.87392) (xy 287.953196 -47.945802)
			(xy 288.078926 -48.089566) (xy 288.114994 -48.12538)
		)
		(stroke
			(width 0)
			(type solid)
		)
		(fill yes)
		(layer "F.Cu")
		(net "M_B_DQ<55>")
	)
	(gr_poly
		(pts
			(xy 288.222944 -49.47285) (xy 288.097214 -49.329086) (xy 288.0614 -49.293018) (xy 287.971484 -49.382934)
			(xy 288.007298 -49.418748) (xy 288.151062 -49.544478)
		)
		(stroke
			(width 0)
			(type solid)
		)
		(fill yes)
		(layer "F.Cu")
		(net "M_B_DQ<51>")
	)
	(gr_poly
		(pts
			(xy 288.294826 -49.059592) (xy 288.258758 -49.023778) (xy 288.115248 -48.898048) (xy 288.043366 -48.96993)
			(xy 288.169096 -49.11344) (xy 288.20491 -49.149508)
		)
		(stroke
			(width 0)
			(type solid)
		)
		(fill yes)
		(layer "F.Cu")
		(net "M_B_DQ<51>")
	)
	(gr_poly
		(pts
			(xy 288.326322 -47.207424) (xy 288.326322 -47.156624) (xy 288.199322 -47.156624) (xy 288.199322 -47.207424)
			(xy 288.212022 -47.397924) (xy 288.313622 -47.397924)
		)
		(stroke
			(width 0)
			(type solid)
		)
		(fill yes)
		(layer "F.Cu")
		(net "M_B_DQS_DP<6>")
	)
	(gr_poly
		(pts
			(xy 288.326322 -46.813724) (xy 288.326322 -46.762924) (xy 288.199322 -46.762924) (xy 288.199322 -46.813724)
			(xy 288.212022 -47.004224) (xy 288.313622 -47.004224)
		)
		(stroke
			(width 0)
			(type solid)
		)
		(fill yes)
		(layer "F.Cu")
		(net "M_B_DQS_DN<6>")
	)
	(gr_poly
		(pts
			(xy 288.326322 -46.420024) (xy 288.326322 -46.369224) (xy 288.199322 -46.369224) (xy 288.199322 -46.420024)
			(xy 288.212022 -46.610524) (xy 288.313622 -46.610524)
		)
		(stroke
			(width 0)
			(type solid)
		)
		(fill yes)
		(layer "F.Cu")
		(net "M_B_DQS_DN<15>")
	)
	(gr_poly
		(pts
			(xy 288.326322 -46.026324) (xy 288.326322 -45.975524) (xy 288.199322 -45.975524) (xy 288.199322 -46.026324)
			(xy 288.212022 -46.216824) (xy 288.313622 -46.216824)
		)
		(stroke
			(width 0)
			(type solid)
		)
		(fill yes)
		(layer "F.Cu")
		(net "M_B_DQS_DP<15>")
	)
	(gr_poly
		(pts
			(xy 288.326322 -45.632624) (xy 288.326322 -45.581824) (xy 288.199322 -45.581824) (xy 288.199322 -45.632624)
			(xy 288.212022 -45.823124) (xy 288.313622 -45.823124)
		)
		(stroke
			(width 0)
			(type solid)
		)
		(fill yes)
		(layer "F.Cu")
		(net "M_B_DQ<49>")
	)
	(gr_poly
		(pts
			(xy 288.326322 -45.238924) (xy 288.326322 -45.188124) (xy 288.199322 -45.188124) (xy 288.199322 -45.238924)
			(xy 288.212022 -45.429424) (xy 288.313622 -45.429424)
		)
		(stroke
			(width 0)
			(type solid)
		)
		(fill yes)
		(layer "F.Cu")
		(net "M_B_DQ<48>")
	)
	(gr_poly
		(pts
			(xy 288.326322 -44.845224) (xy 288.326322 -44.794424) (xy 288.199322 -44.794424) (xy 288.199322 -44.845224)
			(xy 288.212022 -45.035724) (xy 288.313622 -45.035724)
		)
		(stroke
			(width 0)
			(type solid)
		)
		(fill yes)
		(layer "F.Cu")
		(net "M_B_DQ<53>")
	)
	(gr_poly
		(pts
			(xy 288.326322 -44.451524) (xy 288.326322 -44.400724) (xy 288.199322 -44.400724) (xy 288.199322 -44.451524)
			(xy 288.212022 -44.642024) (xy 288.313622 -44.642024)
		)
		(stroke
			(width 0)
			(type solid)
		)
		(fill yes)
		(layer "F.Cu")
		(net "M_B_DQ<52>")
	)
	(gr_poly
		(pts
			(xy 288.411412 -48.72736) (xy 288.285682 -48.583596) (xy 288.249614 -48.547782) (xy 288.159952 -48.637444)
			(xy 288.195766 -48.673258) (xy 288.33953 -48.798988)
		)
		(stroke
			(width 0)
			(type solid)
		)
		(fill yes)
		(layer "F.Cu")
		(net "M_B_DQ<50>")
	)
	(gr_poly
		(pts
			(xy 288.49066 -108.572554) (xy 288.47796 -108.382054) (xy 288.37636 -108.382054) (xy 288.36366 -108.572554)
			(xy 288.36366 -108.623354) (xy 288.49066 -108.623354)
		)
		(stroke
			(width 0)
			(type solid)
		)
		(fill yes)
		(layer "F.Cu")
		(net "M_E_DQ<52>")
	)
	(gr_poly
		(pts
			(xy 288.49066 -108.178854) (xy 288.47796 -107.988354) (xy 288.37636 -107.988354) (xy 288.36366 -108.178854)
			(xy 288.36366 -108.229654) (xy 288.49066 -108.229654)
		)
		(stroke
			(width 0)
			(type solid)
		)
		(fill yes)
		(layer "F.Cu")
		(net "M_E_DQ<53>")
	)
	(gr_poly
		(pts
			(xy 288.49066 -107.785154) (xy 288.47796 -107.594654) (xy 288.37636 -107.594654) (xy 288.36366 -107.785154)
			(xy 288.36366 -107.835954) (xy 288.49066 -107.835954)
		)
		(stroke
			(width 0)
			(type solid)
		)
		(fill yes)
		(layer "F.Cu")
		(net "M_E_DQ<48>")
	)
	(gr_poly
		(pts
			(xy 288.49066 -107.391454) (xy 288.47796 -107.200954) (xy 288.37636 -107.200954) (xy 288.36366 -107.391454)
			(xy 288.36366 -107.442254) (xy 288.49066 -107.442254)
		)
		(stroke
			(width 0)
			(type solid)
		)
		(fill yes)
		(layer "F.Cu")
		(net "M_E_DQ<49>")
	)
	(gr_poly
		(pts
			(xy 288.49066 -106.997754) (xy 288.47796 -106.807254) (xy 288.37636 -106.807254) (xy 288.36366 -106.997754)
			(xy 288.36366 -107.048554) (xy 288.49066 -107.048554)
		)
		(stroke
			(width 0)
			(type solid)
		)
		(fill yes)
		(layer "F.Cu")
		(net "M_E_DQS_DP<15>")
	)
	(gr_poly
		(pts
			(xy 288.49066 -106.604054) (xy 288.47796 -106.413554) (xy 288.37636 -106.413554) (xy 288.36366 -106.604054)
			(xy 288.36366 -106.654854) (xy 288.49066 -106.654854)
		)
		(stroke
			(width 0)
			(type solid)
		)
		(fill yes)
		(layer "F.Cu")
		(net "M_E_DQS_DN<15>")
	)
	(gr_poly
		(pts
			(xy 288.49066 -106.210354) (xy 288.47796 -106.019854) (xy 288.37636 -106.019854) (xy 288.36366 -106.210354)
			(xy 288.36366 -106.261154) (xy 288.49066 -106.261154)
		)
		(stroke
			(width 0)
			(type solid)
		)
		(fill yes)
		(layer "F.Cu")
		(net "M_E_DQS_DN<6>")
	)
	(gr_poly
		(pts
			(xy 288.49066 -105.816654) (xy 288.47796 -105.626154) (xy 288.37636 -105.626154) (xy 288.36366 -105.816654)
			(xy 288.36366 -105.867454) (xy 288.49066 -105.867454)
		)
		(stroke
			(width 0)
			(type solid)
		)
		(fill yes)
		(layer "F.Cu")
		(net "M_E_DQS_DP<6>")
	)
	(gr_poly
		(pts
			(xy 288.49066 -105.422954) (xy 288.47796 -105.232454) (xy 288.37636 -105.232454) (xy 288.36366 -105.422954)
			(xy 288.36366 -105.473754) (xy 288.49066 -105.473754)
		)
		(stroke
			(width 0)
			(type solid)
		)
		(fill yes)
		(layer "F.Cu")
		(net "M_E_DQ<54>")
	)
	(gr_poly
		(pts
			(xy 288.49066 -105.029254) (xy 288.47796 -104.838754) (xy 288.37636 -104.838754) (xy 288.36366 -105.029254)
			(xy 288.36366 -105.080054) (xy 288.49066 -105.080054)
		)
		(stroke
			(width 0)
			(type solid)
		)
		(fill yes)
		(layer "F.Cu")
		(net "M_E_DQ<55>")
	)
	(gr_poly
		(pts
			(xy 288.49066 -104.635554) (xy 288.47796 -104.445054) (xy 288.37636 -104.445054) (xy 288.36366 -104.635554)
			(xy 288.36366 -104.686354) (xy 288.49066 -104.686354)
		)
		(stroke
			(width 0)
			(type solid)
		)
		(fill yes)
		(layer "F.Cu")
		(net "M_E_DQ<50>")
	)
	(gr_poly
		(pts
			(xy 288.49066 -104.241854) (xy 288.47796 -104.051354) (xy 288.37636 -104.051354) (xy 288.36366 -104.241854)
			(xy 288.36366 -104.292654) (xy 288.49066 -104.292654)
		)
		(stroke
			(width 0)
			(type solid)
		)
		(fill yes)
		(layer "F.Cu")
		(net "M_E_DQ<51>")
	)
	(gr_poly
		(pts
			(xy 288.656522 -48.286924) (xy 288.643822 -48.096424) (xy 288.542222 -48.096424) (xy 288.529522 -48.286924)
			(xy 288.529522 -48.337724) (xy 288.656522 -48.337724)
		)
		(stroke
			(width 0)
			(type solid)
		)
		(fill yes)
		(layer "F.Cu")
		(net "M_B_DQ<50>")
	)
	(gr_poly
		(pts
			(xy 288.656522 -47.893224) (xy 288.643822 -47.702724) (xy 288.542222 -47.702724) (xy 288.529522 -47.893224)
			(xy 288.529522 -47.944024) (xy 288.656522 -47.944024)
		)
		(stroke
			(width 0)
			(type solid)
		)
		(fill yes)
		(layer "F.Cu")
		(net "M_B_DQ<55>")
	)
	(gr_poly
		(pts
			(xy 288.656522 -47.499524) (xy 288.643822 -47.309024) (xy 288.542222 -47.309024) (xy 288.529522 -47.499524)
			(xy 288.529522 -47.550324) (xy 288.656522 -47.550324)
		)
		(stroke
			(width 0)
			(type solid)
		)
		(fill yes)
		(layer "F.Cu")
		(net "M_B_DQ<54>")
	)
	(gr_poly
		(pts
			(xy 288.656522 -47.105824) (xy 288.643822 -46.915324) (xy 288.542222 -46.915324) (xy 288.529522 -47.105824)
			(xy 288.529522 -47.156624) (xy 288.656522 -47.156624)
		)
		(stroke
			(width 0)
			(type solid)
		)
		(fill yes)
		(layer "F.Cu")
		(net "M_B_DQS_DP<6>")
	)
	(gr_poly
		(pts
			(xy 288.656522 -46.712124) (xy 288.643822 -46.521624) (xy 288.542222 -46.521624) (xy 288.529522 -46.712124)
			(xy 288.529522 -46.762924) (xy 288.656522 -46.762924)
		)
		(stroke
			(width 0)
			(type solid)
		)
		(fill yes)
		(layer "F.Cu")
		(net "M_B_DQS_DN<6>")
	)
	(gr_poly
		(pts
			(xy 288.656522 -46.318424) (xy 288.643822 -46.127924) (xy 288.542222 -46.127924) (xy 288.529522 -46.318424)
			(xy 288.529522 -46.369224) (xy 288.656522 -46.369224)
		)
		(stroke
			(width 0)
			(type solid)
		)
		(fill yes)
		(layer "F.Cu")
		(net "M_B_DQS_DN<15>")
	)
	(gr_poly
		(pts
			(xy 288.656522 -45.924724) (xy 288.643822 -45.734224) (xy 288.542222 -45.734224) (xy 288.529522 -45.924724)
			(xy 288.529522 -45.975524) (xy 288.656522 -45.975524)
		)
		(stroke
			(width 0)
			(type solid)
		)
		(fill yes)
		(layer "F.Cu")
		(net "M_B_DQS_DP<15>")
	)
	(gr_poly
		(pts
			(xy 288.656522 -45.531024) (xy 288.643822 -45.340524) (xy 288.542222 -45.340524) (xy 288.529522 -45.531024)
			(xy 288.529522 -45.581824) (xy 288.656522 -45.581824)
		)
		(stroke
			(width 0)
			(type solid)
		)
		(fill yes)
		(layer "F.Cu")
		(net "M_B_DQ<49>")
	)
	(gr_poly
		(pts
			(xy 288.656522 -45.137324) (xy 288.643822 -44.946824) (xy 288.542222 -44.946824) (xy 288.529522 -45.137324)
			(xy 288.529522 -45.188124) (xy 288.656522 -45.188124)
		)
		(stroke
			(width 0)
			(type solid)
		)
		(fill yes)
		(layer "F.Cu")
		(net "M_B_DQ<48>")
	)
	(gr_poly
		(pts
			(xy 288.656522 -44.743624) (xy 288.643822 -44.553124) (xy 288.542222 -44.553124) (xy 288.529522 -44.743624)
			(xy 288.529522 -44.794424) (xy 288.656522 -44.794424)
		)
		(stroke
			(width 0)
			(type solid)
		)
		(fill yes)
		(layer "F.Cu")
		(net "M_B_DQ<53>")
	)
	(gr_poly
		(pts
			(xy 288.656522 -44.349924) (xy 288.643822 -44.159424) (xy 288.542222 -44.159424) (xy 288.529522 -44.349924)
			(xy 288.529522 -44.400724) (xy 288.656522 -44.400724)
		)
		(stroke
			(width 0)
			(type solid)
		)
		(fill yes)
		(layer "F.Cu")
		(net "M_B_DQ<52>")
	)
	(gr_poly
		(pts
			(xy 288.689796 -49.005744) (xy 288.564066 -48.86198) (xy 288.528252 -48.826166) (xy 288.438336 -48.916082)
			(xy 288.474404 -48.951896) (xy 288.618168 -49.077626)
		)
		(stroke
			(width 0)
			(type solid)
		)
		(fill yes)
		(layer "F.Cu")
		(net "M_B_DQ<51>")
	)
	(gr_poly
		(pts
			(xy 288.82086 -108.674154) (xy 288.82086 -108.623354) (xy 288.69386 -108.623354) (xy 288.69386 -108.674154)
			(xy 288.70656 -108.864654) (xy 288.80816 -108.864654)
		)
		(stroke
			(width 0)
			(type solid)
		)
		(fill yes)
		(layer "F.Cu")
		(net "M_E_DQ<52>")
	)
	(gr_poly
		(pts
			(xy 288.82086 -108.280454) (xy 288.82086 -108.229654) (xy 288.69386 -108.229654) (xy 288.69386 -108.280454)
			(xy 288.70656 -108.470954) (xy 288.80816 -108.470954)
		)
		(stroke
			(width 0)
			(type solid)
		)
		(fill yes)
		(layer "F.Cu")
		(net "M_E_DQ<53>")
	)
	(gr_poly
		(pts
			(xy 288.82086 -107.886754) (xy 288.82086 -107.835954) (xy 288.69386 -107.835954) (xy 288.69386 -107.886754)
			(xy 288.70656 -108.077254) (xy 288.80816 -108.077254)
		)
		(stroke
			(width 0)
			(type solid)
		)
		(fill yes)
		(layer "F.Cu")
		(net "M_E_DQ<48>")
	)
	(gr_poly
		(pts
			(xy 288.82086 -107.493054) (xy 288.82086 -107.442254) (xy 288.69386 -107.442254) (xy 288.69386 -107.493054)
			(xy 288.70656 -107.683554) (xy 288.80816 -107.683554)
		)
		(stroke
			(width 0)
			(type solid)
		)
		(fill yes)
		(layer "F.Cu")
		(net "M_E_DQ<49>")
	)
	(gr_poly
		(pts
			(xy 288.82086 -107.099354) (xy 288.82086 -107.048554) (xy 288.69386 -107.048554) (xy 288.69386 -107.099354)
			(xy 288.70656 -107.289854) (xy 288.80816 -107.289854)
		)
		(stroke
			(width 0)
			(type solid)
		)
		(fill yes)
		(layer "F.Cu")
		(net "M_E_DQS_DP<15>")
	)
	(gr_poly
		(pts
			(xy 288.82086 -106.705654) (xy 288.82086 -106.654854) (xy 288.69386 -106.654854) (xy 288.69386 -106.705654)
			(xy 288.70656 -106.896154) (xy 288.80816 -106.896154)
		)
		(stroke
			(width 0)
			(type solid)
		)
		(fill yes)
		(layer "F.Cu")
		(net "M_E_DQS_DN<15>")
	)
	(gr_poly
		(pts
			(xy 288.82086 -106.311954) (xy 288.82086 -106.261154) (xy 288.69386 -106.261154) (xy 288.69386 -106.311954)
			(xy 288.70656 -106.502454) (xy 288.80816 -106.502454)
		)
		(stroke
			(width 0)
			(type solid)
		)
		(fill yes)
		(layer "F.Cu")
		(net "M_E_DQS_DN<6>")
	)
	(gr_poly
		(pts
			(xy 288.82086 -105.918254) (xy 288.82086 -105.867454) (xy 288.69386 -105.867454) (xy 288.69386 -105.918254)
			(xy 288.70656 -106.108754) (xy 288.80816 -106.108754)
		)
		(stroke
			(width 0)
			(type solid)
		)
		(fill yes)
		(layer "F.Cu")
		(net "M_E_DQS_DP<6>")
	)
	(gr_poly
		(pts
			(xy 288.82086 -105.524554) (xy 288.82086 -105.473754) (xy 288.69386 -105.473754) (xy 288.69386 -105.524554)
			(xy 288.70656 -105.715054) (xy 288.80816 -105.715054)
		)
		(stroke
			(width 0)
			(type solid)
		)
		(fill yes)
		(layer "F.Cu")
		(net "M_E_DQ<54>")
	)
	(gr_poly
		(pts
			(xy 288.82086 -105.130854) (xy 288.82086 -105.080054) (xy 288.69386 -105.080054) (xy 288.69386 -105.130854)
			(xy 288.70656 -105.321354) (xy 288.80816 -105.321354)
		)
		(stroke
			(width 0)
			(type solid)
		)
		(fill yes)
		(layer "F.Cu")
		(net "M_E_DQ<55>")
	)
	(gr_poly
		(pts
			(xy 288.82086 -104.737154) (xy 288.82086 -104.686354) (xy 288.69386 -104.686354) (xy 288.69386 -104.737154)
			(xy 288.70656 -104.927654) (xy 288.80816 -104.927654)
		)
		(stroke
			(width 0)
			(type solid)
		)
		(fill yes)
		(layer "F.Cu")
		(net "M_E_DQ<50>")
	)
	(gr_poly
		(pts
			(xy 288.82086 -104.343454) (xy 288.82086 -104.292654) (xy 288.69386 -104.292654) (xy 288.69386 -104.343454)
			(xy 288.70656 -104.533954) (xy 288.80816 -104.533954)
		)
		(stroke
			(width 0)
			(type solid)
		)
		(fill yes)
		(layer "F.Cu")
		(net "M_E_DQ<51>")
	)
	(gr_poly
		(pts
			(xy 288.986722 -48.782224) (xy 288.986722 -48.731424) (xy 288.859722 -48.731424) (xy 288.859722 -48.782224)
			(xy 288.872422 -48.972724) (xy 288.974022 -48.972724)
		)
		(stroke
			(width 0)
			(type solid)
		)
		(fill yes)
		(layer "F.Cu")
		(net "M_B_DQ<51>")
	)
	(gr_poly
		(pts
			(xy 288.986722 -48.388524) (xy 288.986722 -48.337724) (xy 288.859722 -48.337724) (xy 288.859722 -48.388524)
			(xy 288.872422 -48.579024) (xy 288.974022 -48.579024)
		)
		(stroke
			(width 0)
			(type solid)
		)
		(fill yes)
		(layer "F.Cu")
		(net "M_B_DQ<50>")
	)
	(gr_poly
		(pts
			(xy 288.986722 -47.994824) (xy 288.986722 -47.944024) (xy 288.859722 -47.944024) (xy 288.859722 -47.994824)
			(xy 288.872422 -48.185324) (xy 288.974022 -48.185324)
		)
		(stroke
			(width 0)
			(type solid)
		)
		(fill yes)
		(layer "F.Cu")
		(net "M_B_DQ<55>")
	)
	(gr_poly
		(pts
			(xy 288.986722 -47.601124) (xy 288.986722 -47.550324) (xy 288.859722 -47.550324) (xy 288.859722 -47.601124)
			(xy 288.872422 -47.791624) (xy 288.974022 -47.791624)
		)
		(stroke
			(width 0)
			(type solid)
		)
		(fill yes)
		(layer "F.Cu")
		(net "M_B_DQ<54>")
	)
	(gr_poly
		(pts
			(xy 288.986722 -47.207424) (xy 288.986722 -47.156624) (xy 288.859722 -47.156624) (xy 288.859722 -47.207424)
			(xy 288.872422 -47.397924) (xy 288.974022 -47.397924)
		)
		(stroke
			(width 0)
			(type solid)
		)
		(fill yes)
		(layer "F.Cu")
		(net "M_B_DQS_DP<6>")
	)
	(gr_poly
		(pts
			(xy 288.986722 -46.813724) (xy 288.986722 -46.762924) (xy 288.859722 -46.762924) (xy 288.859722 -46.813724)
			(xy 288.872422 -47.004224) (xy 288.974022 -47.004224)
		)
		(stroke
			(width 0)
			(type solid)
		)
		(fill yes)
		(layer "F.Cu")
		(net "M_B_DQS_DN<6>")
	)
	(gr_poly
		(pts
			(xy 288.986722 -46.420024) (xy 288.986722 -46.369224) (xy 288.859722 -46.369224) (xy 288.859722 -46.420024)
			(xy 288.872422 -46.610524) (xy 288.974022 -46.610524)
		)
		(stroke
			(width 0)
			(type solid)
		)
		(fill yes)
		(layer "F.Cu")
		(net "M_B_DQS_DN<15>")
	)
	(gr_poly
		(pts
			(xy 288.986722 -46.026324) (xy 288.986722 -45.975524) (xy 288.859722 -45.975524) (xy 288.859722 -46.026324)
			(xy 288.872422 -46.216824) (xy 288.974022 -46.216824)
		)
		(stroke
			(width 0)
			(type solid)
		)
		(fill yes)
		(layer "F.Cu")
		(net "M_B_DQS_DP<15>")
	)
	(gr_poly
		(pts
			(xy 288.986722 -45.632624) (xy 288.986722 -45.581824) (xy 288.859722 -45.581824) (xy 288.859722 -45.632624)
			(xy 288.872422 -45.823124) (xy 288.974022 -45.823124)
		)
		(stroke
			(width 0)
			(type solid)
		)
		(fill yes)
		(layer "F.Cu")
		(net "M_B_DQ<49>")
	)
	(gr_poly
		(pts
			(xy 288.986722 -45.238924) (xy 288.986722 -45.188124) (xy 288.859722 -45.188124) (xy 288.859722 -45.238924)
			(xy 288.872422 -45.429424) (xy 288.974022 -45.429424)
		)
		(stroke
			(width 0)
			(type solid)
		)
		(fill yes)
		(layer "F.Cu")
		(net "M_B_DQ<48>")
	)
	(gr_poly
		(pts
			(xy 288.986722 -44.845224) (xy 288.986722 -44.794424) (xy 288.859722 -44.794424) (xy 288.859722 -44.845224)
			(xy 288.872422 -45.035724) (xy 288.974022 -45.035724)
		)
		(stroke
			(width 0)
			(type solid)
		)
		(fill yes)
		(layer "F.Cu")
		(net "M_B_DQ<53>")
	)
	(gr_poly
		(pts
			(xy 288.986722 -44.451524) (xy 288.986722 -44.400724) (xy 288.859722 -44.400724) (xy 288.859722 -44.451524)
			(xy 288.872422 -44.642024) (xy 288.974022 -44.642024)
		)
		(stroke
			(width 0)
			(type solid)
		)
		(fill yes)
		(layer "F.Cu")
		(net "M_B_DQ<52>")
	)
	(gr_poly
		(pts
			(xy 289.15106 -108.572554) (xy 289.13836 -108.382054) (xy 289.03676 -108.382054) (xy 289.02406 -108.572554)
			(xy 289.02406 -108.623354) (xy 289.15106 -108.623354)
		)
		(stroke
			(width 0)
			(type solid)
		)
		(fill yes)
		(layer "F.Cu")
		(net "M_E_DQ<52>")
	)
	(gr_poly
		(pts
			(xy 289.15106 -108.178854) (xy 289.13836 -107.988354) (xy 289.03676 -107.988354) (xy 289.02406 -108.178854)
			(xy 289.02406 -108.229654) (xy 289.15106 -108.229654)
		)
		(stroke
			(width 0)
			(type solid)
		)
		(fill yes)
		(layer "F.Cu")
		(net "M_E_DQ<53>")
	)
	(gr_poly
		(pts
			(xy 289.15106 -107.785154) (xy 289.13836 -107.594654) (xy 289.03676 -107.594654) (xy 289.02406 -107.785154)
			(xy 289.02406 -107.835954) (xy 289.15106 -107.835954)
		)
		(stroke
			(width 0)
			(type solid)
		)
		(fill yes)
		(layer "F.Cu")
		(net "M_E_DQ<48>")
	)
	(gr_poly
		(pts
			(xy 289.15106 -107.391454) (xy 289.13836 -107.200954) (xy 289.03676 -107.200954) (xy 289.02406 -107.391454)
			(xy 289.02406 -107.442254) (xy 289.15106 -107.442254)
		)
		(stroke
			(width 0)
			(type solid)
		)
		(fill yes)
		(layer "F.Cu")
		(net "M_E_DQ<49>")
	)
	(gr_poly
		(pts
			(xy 289.15106 -106.997754) (xy 289.13836 -106.807254) (xy 289.03676 -106.807254) (xy 289.02406 -106.997754)
			(xy 289.02406 -107.048554) (xy 289.15106 -107.048554)
		)
		(stroke
			(width 0)
			(type solid)
		)
		(fill yes)
		(layer "F.Cu")
		(net "M_E_DQS_DP<15>")
	)
	(gr_poly
		(pts
			(xy 289.15106 -106.604054) (xy 289.13836 -106.413554) (xy 289.03676 -106.413554) (xy 289.02406 -106.604054)
			(xy 289.02406 -106.654854) (xy 289.15106 -106.654854)
		)
		(stroke
			(width 0)
			(type solid)
		)
		(fill yes)
		(layer "F.Cu")
		(net "M_E_DQS_DN<15>")
	)
	(gr_poly
		(pts
			(xy 289.15106 -106.210354) (xy 289.13836 -106.019854) (xy 289.03676 -106.019854) (xy 289.02406 -106.210354)
			(xy 289.02406 -106.261154) (xy 289.15106 -106.261154)
		)
		(stroke
			(width 0)
			(type solid)
		)
		(fill yes)
		(layer "F.Cu")
		(net "M_E_DQS_DN<6>")
	)
	(gr_poly
		(pts
			(xy 289.15106 -105.816654) (xy 289.13836 -105.626154) (xy 289.03676 -105.626154) (xy 289.02406 -105.816654)
			(xy 289.02406 -105.867454) (xy 289.15106 -105.867454)
		)
		(stroke
			(width 0)
			(type solid)
		)
		(fill yes)
		(layer "F.Cu")
		(net "M_E_DQS_DP<6>")
	)
	(gr_poly
		(pts
			(xy 289.15106 -105.422954) (xy 289.13836 -105.232454) (xy 289.03676 -105.232454) (xy 289.02406 -105.422954)
			(xy 289.02406 -105.473754) (xy 289.15106 -105.473754)
		)
		(stroke
			(width 0)
			(type solid)
		)
		(fill yes)
		(layer "F.Cu")
		(net "M_E_DQ<54>")
	)
	(gr_poly
		(pts
			(xy 289.15106 -105.029254) (xy 289.13836 -104.838754) (xy 289.03676 -104.838754) (xy 289.02406 -105.029254)
			(xy 289.02406 -105.080054) (xy 289.15106 -105.080054)
		)
		(stroke
			(width 0)
			(type solid)
		)
		(fill yes)
		(layer "F.Cu")
		(net "M_E_DQ<55>")
	)
	(gr_poly
		(pts
			(xy 289.15106 -104.635554) (xy 289.13836 -104.445054) (xy 289.03676 -104.445054) (xy 289.02406 -104.635554)
			(xy 289.02406 -104.686354) (xy 289.15106 -104.686354)
		)
		(stroke
			(width 0)
			(type solid)
		)
		(fill yes)
		(layer "F.Cu")
		(net "M_E_DQ<50>")
	)
	(gr_poly
		(pts
			(xy 289.15106 -104.241854) (xy 289.13836 -104.051354) (xy 289.03676 -104.051354) (xy 289.02406 -104.241854)
			(xy 289.02406 -104.292654) (xy 289.15106 -104.292654)
		)
		(stroke
			(width 0)
			(type solid)
		)
		(fill yes)
		(layer "F.Cu")
		(net "M_E_DQ<51>")
	)
	(gr_poly
		(pts
			(xy 289.316922 -48.680624) (xy 289.304222 -48.490124) (xy 289.202622 -48.490124) (xy 289.189922 -48.680624)
			(xy 289.189922 -48.731424) (xy 289.316922 -48.731424)
		)
		(stroke
			(width 0)
			(type solid)
		)
		(fill yes)
		(layer "F.Cu")
		(net "M_B_DQ<51>")
	)
	(gr_poly
		(pts
			(xy 289.316922 -48.286924) (xy 289.304222 -48.096424) (xy 289.202622 -48.096424) (xy 289.189922 -48.286924)
			(xy 289.189922 -48.337724) (xy 289.316922 -48.337724)
		)
		(stroke
			(width 0)
			(type solid)
		)
		(fill yes)
		(layer "F.Cu")
		(net "M_B_DQ<50>")
	)
	(gr_poly
		(pts
			(xy 289.316922 -47.893224) (xy 289.304222 -47.702724) (xy 289.202622 -47.702724) (xy 289.189922 -47.893224)
			(xy 289.189922 -47.944024) (xy 289.316922 -47.944024)
		)
		(stroke
			(width 0)
			(type solid)
		)
		(fill yes)
		(layer "F.Cu")
		(net "M_B_DQ<55>")
	)
	(gr_poly
		(pts
			(xy 289.316922 -47.499524) (xy 289.304222 -47.309024) (xy 289.202622 -47.309024) (xy 289.189922 -47.499524)
			(xy 289.189922 -47.550324) (xy 289.316922 -47.550324)
		)
		(stroke
			(width 0)
			(type solid)
		)
		(fill yes)
		(layer "F.Cu")
		(net "M_B_DQ<54>")
	)
	(gr_poly
		(pts
			(xy 289.316922 -47.105824) (xy 289.304222 -46.915324) (xy 289.202622 -46.915324) (xy 289.189922 -47.105824)
			(xy 289.189922 -47.156624) (xy 289.316922 -47.156624)
		)
		(stroke
			(width 0)
			(type solid)
		)
		(fill yes)
		(layer "F.Cu")
		(net "M_B_DQS_DP<6>")
	)
	(gr_poly
		(pts
			(xy 289.316922 -46.712124) (xy 289.304222 -46.521624) (xy 289.202622 -46.521624) (xy 289.189922 -46.712124)
			(xy 289.189922 -46.762924) (xy 289.316922 -46.762924)
		)
		(stroke
			(width 0)
			(type solid)
		)
		(fill yes)
		(layer "F.Cu")
		(net "M_B_DQS_DN<6>")
	)
	(gr_poly
		(pts
			(xy 289.316922 -46.318424) (xy 289.304222 -46.127924) (xy 289.202622 -46.127924) (xy 289.189922 -46.318424)
			(xy 289.189922 -46.369224) (xy 289.316922 -46.369224)
		)
		(stroke
			(width 0)
			(type solid)
		)
		(fill yes)
		(layer "F.Cu")
		(net "M_B_DQS_DN<15>")
	)
	(gr_poly
		(pts
			(xy 289.316922 -45.924724) (xy 289.304222 -45.734224) (xy 289.202622 -45.734224) (xy 289.189922 -45.924724)
			(xy 289.189922 -45.975524) (xy 289.316922 -45.975524)
		)
		(stroke
			(width 0)
			(type solid)
		)
		(fill yes)
		(layer "F.Cu")
		(net "M_B_DQS_DP<15>")
	)
	(gr_poly
		(pts
			(xy 289.316922 -45.531024) (xy 289.304222 -45.340524) (xy 289.202622 -45.340524) (xy 289.189922 -45.531024)
			(xy 289.189922 -45.581824) (xy 289.316922 -45.581824)
		)
		(stroke
			(width 0)
			(type solid)
		)
		(fill yes)
		(layer "F.Cu")
		(net "M_B_DQ<49>")
	)
	(gr_poly
		(pts
			(xy 289.316922 -45.137324) (xy 289.304222 -44.946824) (xy 289.202622 -44.946824) (xy 289.189922 -45.137324)
			(xy 289.189922 -45.188124) (xy 289.316922 -45.188124)
		)
		(stroke
			(width 0)
			(type solid)
		)
		(fill yes)
		(layer "F.Cu")
		(net "M_B_DQ<48>")
	)
	(gr_poly
		(pts
			(xy 289.316922 -44.743624) (xy 289.304222 -44.553124) (xy 289.202622 -44.553124) (xy 289.189922 -44.743624)
			(xy 289.189922 -44.794424) (xy 289.316922 -44.794424)
		)
		(stroke
			(width 0)
			(type solid)
		)
		(fill yes)
		(layer "F.Cu")
		(net "M_B_DQ<53>")
	)
	(gr_poly
		(pts
			(xy 289.316922 -44.349924) (xy 289.304222 -44.159424) (xy 289.202622 -44.159424) (xy 289.189922 -44.349924)
			(xy 289.189922 -44.400724) (xy 289.316922 -44.400724)
		)
		(stroke
			(width 0)
			(type solid)
		)
		(fill yes)
		(layer "F.Cu")
		(net "M_B_DQ<52>")
	)
	(gr_poly
		(pts
			(xy 289.48126 -108.674154) (xy 289.48126 -108.623354) (xy 289.35426 -108.623354) (xy 289.35426 -108.674154)
			(xy 289.36696 -108.864654) (xy 289.46856 -108.864654)
		)
		(stroke
			(width 0)
			(type solid)
		)
		(fill yes)
		(layer "F.Cu")
		(net "M_E_DQ<52>")
	)
	(gr_poly
		(pts
			(xy 289.48126 -108.280454) (xy 289.48126 -108.229654) (xy 289.35426 -108.229654) (xy 289.35426 -108.280454)
			(xy 289.36696 -108.470954) (xy 289.46856 -108.470954)
		)
		(stroke
			(width 0)
			(type solid)
		)
		(fill yes)
		(layer "F.Cu")
		(net "M_E_DQ<53>")
	)
	(gr_poly
		(pts
			(xy 289.48126 -107.886754) (xy 289.48126 -107.835954) (xy 289.35426 -107.835954) (xy 289.35426 -107.886754)
			(xy 289.36696 -108.077254) (xy 289.46856 -108.077254)
		)
		(stroke
			(width 0)
			(type solid)
		)
		(fill yes)
		(layer "F.Cu")
		(net "M_E_DQ<48>")
	)
	(gr_poly
		(pts
			(xy 289.48126 -107.493054) (xy 289.48126 -107.442254) (xy 289.35426 -107.442254) (xy 289.35426 -107.493054)
			(xy 289.36696 -107.683554) (xy 289.46856 -107.683554)
		)
		(stroke
			(width 0)
			(type solid)
		)
		(fill yes)
		(layer "F.Cu")
		(net "M_E_DQ<49>")
	)
	(gr_poly
		(pts
			(xy 289.48126 -107.099354) (xy 289.48126 -107.048554) (xy 289.35426 -107.048554) (xy 289.35426 -107.099354)
			(xy 289.36696 -107.289854) (xy 289.46856 -107.289854)
		)
		(stroke
			(width 0)
			(type solid)
		)
		(fill yes)
		(layer "F.Cu")
		(net "M_E_DQS_DP<15>")
	)
	(gr_poly
		(pts
			(xy 289.48126 -106.705654) (xy 289.48126 -106.654854) (xy 289.35426 -106.654854) (xy 289.35426 -106.705654)
			(xy 289.36696 -106.896154) (xy 289.46856 -106.896154)
		)
		(stroke
			(width 0)
			(type solid)
		)
		(fill yes)
		(layer "F.Cu")
		(net "M_E_DQS_DN<15>")
	)
	(gr_poly
		(pts
			(xy 289.48126 -106.311954) (xy 289.48126 -106.261154) (xy 289.35426 -106.261154) (xy 289.35426 -106.311954)
			(xy 289.36696 -106.502454) (xy 289.46856 -106.502454)
		)
		(stroke
			(width 0)
			(type solid)
		)
		(fill yes)
		(layer "F.Cu")
		(net "M_E_DQS_DN<6>")
	)
	(gr_poly
		(pts
			(xy 289.48126 -105.918254) (xy 289.48126 -105.867454) (xy 289.35426 -105.867454) (xy 289.35426 -105.918254)
			(xy 289.36696 -106.108754) (xy 289.46856 -106.108754)
		)
		(stroke
			(width 0)
			(type solid)
		)
		(fill yes)
		(layer "F.Cu")
		(net "M_E_DQS_DP<6>")
	)
	(gr_poly
		(pts
			(xy 289.48126 -105.524554) (xy 289.48126 -105.473754) (xy 289.35426 -105.473754) (xy 289.35426 -105.524554)
			(xy 289.36696 -105.715054) (xy 289.46856 -105.715054)
		)
		(stroke
			(width 0)
			(type solid)
		)
		(fill yes)
		(layer "F.Cu")
		(net "M_E_DQ<54>")
	)
	(gr_poly
		(pts
			(xy 289.48126 -105.130854) (xy 289.48126 -105.080054) (xy 289.35426 -105.080054) (xy 289.35426 -105.130854)
			(xy 289.36696 -105.321354) (xy 289.46856 -105.321354)
		)
		(stroke
			(width 0)
			(type solid)
		)
		(fill yes)
		(layer "F.Cu")
		(net "M_E_DQ<55>")
	)
	(gr_poly
		(pts
			(xy 289.48126 -104.737154) (xy 289.48126 -104.686354) (xy 289.35426 -104.686354) (xy 289.35426 -104.737154)
			(xy 289.36696 -104.927654) (xy 289.46856 -104.927654)
		)
		(stroke
			(width 0)
			(type solid)
		)
		(fill yes)
		(layer "F.Cu")
		(net "M_E_DQ<50>")
	)
	(gr_poly
		(pts
			(xy 289.48126 -104.343454) (xy 289.48126 -104.292654) (xy 289.35426 -104.292654) (xy 289.35426 -104.343454)
			(xy 289.36696 -104.533954) (xy 289.46856 -104.533954)
		)
		(stroke
			(width 0)
			(type solid)
		)
		(fill yes)
		(layer "F.Cu")
		(net "M_E_DQ<51>")
	)
	(gr_poly
		(pts
			(xy 289.647122 -48.782224) (xy 289.647122 -48.731424) (xy 289.520122 -48.731424) (xy 289.520122 -48.782224)
			(xy 289.532822 -48.972724) (xy 289.634422 -48.972724)
		)
		(stroke
			(width 0)
			(type solid)
		)
		(fill yes)
		(layer "F.Cu")
		(net "M_B_DQ<51>")
	)
	(gr_poly
		(pts
			(xy 289.647122 -48.388524) (xy 289.647122 -48.337724) (xy 289.520122 -48.337724) (xy 289.520122 -48.388524)
			(xy 289.532822 -48.579024) (xy 289.634422 -48.579024)
		)
		(stroke
			(width 0)
			(type solid)
		)
		(fill yes)
		(layer "F.Cu")
		(net "M_B_DQ<50>")
	)
	(gr_poly
		(pts
			(xy 289.647122 -47.994824) (xy 289.647122 -47.944024) (xy 289.520122 -47.944024) (xy 289.520122 -47.994824)
			(xy 289.532822 -48.185324) (xy 289.634422 -48.185324)
		)
		(stroke
			(width 0)
			(type solid)
		)
		(fill yes)
		(layer "F.Cu")
		(net "M_B_DQ<55>")
	)
	(gr_poly
		(pts
			(xy 289.647122 -47.601124) (xy 289.647122 -47.550324) (xy 289.520122 -47.550324) (xy 289.520122 -47.601124)
			(xy 289.532822 -47.791624) (xy 289.634422 -47.791624)
		)
		(stroke
			(width 0)
			(type solid)
		)
		(fill yes)
		(layer "F.Cu")
		(net "M_B_DQ<54>")
	)
	(gr_poly
		(pts
			(xy 289.647122 -47.207424) (xy 289.647122 -47.156624) (xy 289.520122 -47.156624) (xy 289.520122 -47.207424)
			(xy 289.532822 -47.397924) (xy 289.634422 -47.397924)
		)
		(stroke
			(width 0)
			(type solid)
		)
		(fill yes)
		(layer "F.Cu")
		(net "M_B_DQS_DP<6>")
	)
	(gr_poly
		(pts
			(xy 289.647122 -46.813724) (xy 289.647122 -46.762924) (xy 289.520122 -46.762924) (xy 289.520122 -46.813724)
			(xy 289.532822 -47.004224) (xy 289.634422 -47.004224)
		)
		(stroke
			(width 0)
			(type solid)
		)
		(fill yes)
		(layer "F.Cu")
		(net "M_B_DQS_DN<6>")
	)
	(gr_poly
		(pts
			(xy 289.647122 -46.420024) (xy 289.647122 -46.369224) (xy 289.520122 -46.369224) (xy 289.520122 -46.420024)
			(xy 289.532822 -46.610524) (xy 289.634422 -46.610524)
		)
		(stroke
			(width 0)
			(type solid)
		)
		(fill yes)
		(layer "F.Cu")
		(net "M_B_DQS_DN<15>")
	)
	(gr_poly
		(pts
			(xy 289.647122 -46.026324) (xy 289.647122 -45.975524) (xy 289.520122 -45.975524) (xy 289.520122 -46.026324)
			(xy 289.532822 -46.216824) (xy 289.634422 -46.216824)
		)
		(stroke
			(width 0)
			(type solid)
		)
		(fill yes)
		(layer "F.Cu")
		(net "M_B_DQS_DP<15>")
	)
	(gr_poly
		(pts
			(xy 289.647122 -45.632624) (xy 289.647122 -45.581824) (xy 289.520122 -45.581824) (xy 289.520122 -45.632624)
			(xy 289.532822 -45.823124) (xy 289.634422 -45.823124)
		)
		(stroke
			(width 0)
			(type solid)
		)
		(fill yes)
		(layer "F.Cu")
		(net "M_B_DQ<49>")
	)
	(gr_poly
		(pts
			(xy 289.647122 -45.238924) (xy 289.647122 -45.188124) (xy 289.520122 -45.188124) (xy 289.520122 -45.238924)
			(xy 289.532822 -45.429424) (xy 289.634422 -45.429424)
		)
		(stroke
			(width 0)
			(type solid)
		)
		(fill yes)
		(layer "F.Cu")
		(net "M_B_DQ<48>")
	)
	(gr_poly
		(pts
			(xy 289.647122 -44.845224) (xy 289.647122 -44.794424) (xy 289.520122 -44.794424) (xy 289.520122 -44.845224)
			(xy 289.532822 -45.035724) (xy 289.634422 -45.035724)
		)
		(stroke
			(width 0)
			(type solid)
		)
		(fill yes)
		(layer "F.Cu")
		(net "M_B_DQ<53>")
	)
	(gr_poly
		(pts
			(xy 289.647122 -44.451524) (xy 289.647122 -44.400724) (xy 289.520122 -44.400724) (xy 289.520122 -44.451524)
			(xy 289.532822 -44.642024) (xy 289.634422 -44.642024)
		)
		(stroke
			(width 0)
			(type solid)
		)
		(fill yes)
		(layer "F.Cu")
		(net "M_B_DQ<52>")
	)
	(gr_poly
		(pts
			(xy 289.81146 -108.572554) (xy 289.79876 -108.382054) (xy 289.69716 -108.382054) (xy 289.68446 -108.572554)
			(xy 289.68446 -108.623354) (xy 289.81146 -108.623354)
		)
		(stroke
			(width 0)
			(type solid)
		)
		(fill yes)
		(layer "F.Cu")
		(net "M_E_DQ<52>")
	)
	(gr_poly
		(pts
			(xy 289.81146 -108.178854) (xy 289.79876 -107.988354) (xy 289.69716 -107.988354) (xy 289.68446 -108.178854)
			(xy 289.68446 -108.229654) (xy 289.81146 -108.229654)
		)
		(stroke
			(width 0)
			(type solid)
		)
		(fill yes)
		(layer "F.Cu")
		(net "M_E_DQ<53>")
	)
	(gr_poly
		(pts
			(xy 289.81146 -107.785154) (xy 289.79876 -107.594654) (xy 289.69716 -107.594654) (xy 289.68446 -107.785154)
			(xy 289.68446 -107.835954) (xy 289.81146 -107.835954)
		)
		(stroke
			(width 0)
			(type solid)
		)
		(fill yes)
		(layer "F.Cu")
		(net "M_E_DQ<48>")
	)
	(gr_poly
		(pts
			(xy 289.81146 -107.391454) (xy 289.79876 -107.200954) (xy 289.69716 -107.200954) (xy 289.68446 -107.391454)
			(xy 289.68446 -107.442254) (xy 289.81146 -107.442254)
		)
		(stroke
			(width 0)
			(type solid)
		)
		(fill yes)
		(layer "F.Cu")
		(net "M_E_DQ<49>")
	)
	(gr_poly
		(pts
			(xy 289.81146 -106.997754) (xy 289.79876 -106.807254) (xy 289.69716 -106.807254) (xy 289.68446 -106.997754)
			(xy 289.68446 -107.048554) (xy 289.81146 -107.048554)
		)
		(stroke
			(width 0)
			(type solid)
		)
		(fill yes)
		(layer "F.Cu")
		(net "M_E_DQS_DP<15>")
	)
	(gr_poly
		(pts
			(xy 289.81146 -106.604054) (xy 289.79876 -106.413554) (xy 289.69716 -106.413554) (xy 289.68446 -106.604054)
			(xy 289.68446 -106.654854) (xy 289.81146 -106.654854)
		)
		(stroke
			(width 0)
			(type solid)
		)
		(fill yes)
		(layer "F.Cu")
		(net "M_E_DQS_DN<15>")
	)
	(gr_poly
		(pts
			(xy 289.81146 -106.210354) (xy 289.79876 -106.019854) (xy 289.69716 -106.019854) (xy 289.68446 -106.210354)
			(xy 289.68446 -106.261154) (xy 289.81146 -106.261154)
		)
		(stroke
			(width 0)
			(type solid)
		)
		(fill yes)
		(layer "F.Cu")
		(net "M_E_DQS_DN<6>")
	)
	(gr_poly
		(pts
			(xy 289.81146 -105.816654) (xy 289.79876 -105.626154) (xy 289.69716 -105.626154) (xy 289.68446 -105.816654)
			(xy 289.68446 -105.867454) (xy 289.81146 -105.867454)
		)
		(stroke
			(width 0)
			(type solid)
		)
		(fill yes)
		(layer "F.Cu")
		(net "M_E_DQS_DP<6>")
	)
	(gr_poly
		(pts
			(xy 289.81146 -105.422954) (xy 289.79876 -105.232454) (xy 289.69716 -105.232454) (xy 289.68446 -105.422954)
			(xy 289.68446 -105.473754) (xy 289.81146 -105.473754)
		)
		(stroke
			(width 0)
			(type solid)
		)
		(fill yes)
		(layer "F.Cu")
		(net "M_E_DQ<54>")
	)
	(gr_poly
		(pts
			(xy 289.81146 -105.029254) (xy 289.79876 -104.838754) (xy 289.69716 -104.838754) (xy 289.68446 -105.029254)
			(xy 289.68446 -105.080054) (xy 289.81146 -105.080054)
		)
		(stroke
			(width 0)
			(type solid)
		)
		(fill yes)
		(layer "F.Cu")
		(net "M_E_DQ<55>")
	)
	(gr_poly
		(pts
			(xy 289.81146 -104.635554) (xy 289.79876 -104.445054) (xy 289.69716 -104.445054) (xy 289.68446 -104.635554)
			(xy 289.68446 -104.686354) (xy 289.81146 -104.686354)
		)
		(stroke
			(width 0)
			(type solid)
		)
		(fill yes)
		(layer "F.Cu")
		(net "M_E_DQ<50>")
	)
	(gr_poly
		(pts
			(xy 289.81146 -104.241854) (xy 289.79876 -104.051354) (xy 289.69716 -104.051354) (xy 289.68446 -104.241854)
			(xy 289.68446 -104.292654) (xy 289.81146 -104.292654)
		)
		(stroke
			(width 0)
			(type solid)
		)
		(fill yes)
		(layer "F.Cu")
		(net "M_E_DQ<51>")
	)
	(gr_poly
		(pts
			(xy 289.977322 -48.680624) (xy 289.964622 -48.490124) (xy 289.863022 -48.490124) (xy 289.850322 -48.680624)
			(xy 289.850322 -48.731424) (xy 289.977322 -48.731424)
		)
		(stroke
			(width 0)
			(type solid)
		)
		(fill yes)
		(layer "F.Cu")
		(net "M_B_DQ<51>")
	)
	(gr_poly
		(pts
			(xy 289.977322 -48.286924) (xy 289.964622 -48.096424) (xy 289.863022 -48.096424) (xy 289.850322 -48.286924)
			(xy 289.850322 -48.337724) (xy 289.977322 -48.337724)
		)
		(stroke
			(width 0)
			(type solid)
		)
		(fill yes)
		(layer "F.Cu")
		(net "M_B_DQ<50>")
	)
	(gr_poly
		(pts
			(xy 289.977322 -47.893224) (xy 289.964622 -47.702724) (xy 289.863022 -47.702724) (xy 289.850322 -47.893224)
			(xy 289.850322 -47.944024) (xy 289.977322 -47.944024)
		)
		(stroke
			(width 0)
			(type solid)
		)
		(fill yes)
		(layer "F.Cu")
		(net "M_B_DQ<55>")
	)
	(gr_poly
		(pts
			(xy 289.977322 -47.499524) (xy 289.964622 -47.309024) (xy 289.863022 -47.309024) (xy 289.850322 -47.499524)
			(xy 289.850322 -47.550324) (xy 289.977322 -47.550324)
		)
		(stroke
			(width 0)
			(type solid)
		)
		(fill yes)
		(layer "F.Cu")
		(net "M_B_DQ<54>")
	)
	(gr_poly
		(pts
			(xy 289.977322 -47.105824) (xy 289.964622 -46.915324) (xy 289.863022 -46.915324) (xy 289.850322 -47.105824)
			(xy 289.850322 -47.156624) (xy 289.977322 -47.156624)
		)
		(stroke
			(width 0)
			(type solid)
		)
		(fill yes)
		(layer "F.Cu")
		(net "M_B_DQS_DP<6>")
	)
	(gr_poly
		(pts
			(xy 289.977322 -46.712124) (xy 289.964622 -46.521624) (xy 289.863022 -46.521624) (xy 289.850322 -46.712124)
			(xy 289.850322 -46.762924) (xy 289.977322 -46.762924)
		)
		(stroke
			(width 0)
			(type solid)
		)
		(fill yes)
		(layer "F.Cu")
		(net "M_B_DQS_DN<6>")
	)
	(gr_poly
		(pts
			(xy 289.977322 -46.318424) (xy 289.964622 -46.127924) (xy 289.863022 -46.127924) (xy 289.850322 -46.318424)
			(xy 289.850322 -46.369224) (xy 289.977322 -46.369224)
		)
		(stroke
			(width 0)
			(type solid)
		)
		(fill yes)
		(layer "F.Cu")
		(net "M_B_DQS_DN<15>")
	)
	(gr_poly
		(pts
			(xy 289.977322 -45.924724) (xy 289.964622 -45.734224) (xy 289.863022 -45.734224) (xy 289.850322 -45.924724)
			(xy 289.850322 -45.975524) (xy 289.977322 -45.975524)
		)
		(stroke
			(width 0)
			(type solid)
		)
		(fill yes)
		(layer "F.Cu")
		(net "M_B_DQS_DP<15>")
	)
	(gr_poly
		(pts
			(xy 289.977322 -45.531024) (xy 289.964622 -45.340524) (xy 289.863022 -45.340524) (xy 289.850322 -45.531024)
			(xy 289.850322 -45.581824) (xy 289.977322 -45.581824)
		)
		(stroke
			(width 0)
			(type solid)
		)
		(fill yes)
		(layer "F.Cu")
		(net "M_B_DQ<49>")
	)
	(gr_poly
		(pts
			(xy 289.977322 -45.137324) (xy 289.964622 -44.946824) (xy 289.863022 -44.946824) (xy 289.850322 -45.137324)
			(xy 289.850322 -45.188124) (xy 289.977322 -45.188124)
		)
		(stroke
			(width 0)
			(type solid)
		)
		(fill yes)
		(layer "F.Cu")
		(net "M_B_DQ<48>")
	)
	(gr_poly
		(pts
			(xy 289.977322 -44.743624) (xy 289.964622 -44.553124) (xy 289.863022 -44.553124) (xy 289.850322 -44.743624)
			(xy 289.850322 -44.794424) (xy 289.977322 -44.794424)
		)
		(stroke
			(width 0)
			(type solid)
		)
		(fill yes)
		(layer "F.Cu")
		(net "M_B_DQ<53>")
	)
	(gr_poly
		(pts
			(xy 289.977322 -44.349924) (xy 289.964622 -44.159424) (xy 289.863022 -44.159424) (xy 289.850322 -44.349924)
			(xy 289.850322 -44.400724) (xy 289.977322 -44.400724)
		)
		(stroke
			(width 0)
			(type solid)
		)
		(fill yes)
		(layer "F.Cu")
		(net "M_B_DQ<52>")
	)
	(gr_poly
		(pts
			(xy 290.14166 -108.674154) (xy 290.14166 -108.623354) (xy 290.01466 -108.623354) (xy 290.01466 -108.674154)
			(xy 290.02736 -108.864654) (xy 290.12896 -108.864654)
		)
		(stroke
			(width 0)
			(type solid)
		)
		(fill yes)
		(layer "F.Cu")
		(net "M_E_DQ<52>")
	)
	(gr_poly
		(pts
			(xy 290.14166 -108.280454) (xy 290.14166 -108.229654) (xy 290.01466 -108.229654) (xy 290.01466 -108.280454)
			(xy 290.02736 -108.470954) (xy 290.12896 -108.470954)
		)
		(stroke
			(width 0)
			(type solid)
		)
		(fill yes)
		(layer "F.Cu")
		(net "M_E_DQ<53>")
	)
	(gr_poly
		(pts
			(xy 290.14166 -107.886754) (xy 290.14166 -107.835954) (xy 290.01466 -107.835954) (xy 290.01466 -107.886754)
			(xy 290.02736 -108.077254) (xy 290.12896 -108.077254)
		)
		(stroke
			(width 0)
			(type solid)
		)
		(fill yes)
		(layer "F.Cu")
		(net "M_E_DQ<48>")
	)
	(gr_poly
		(pts
			(xy 290.14166 -107.493054) (xy 290.14166 -107.442254) (xy 290.01466 -107.442254) (xy 290.01466 -107.493054)
			(xy 290.02736 -107.683554) (xy 290.12896 -107.683554)
		)
		(stroke
			(width 0)
			(type solid)
		)
		(fill yes)
		(layer "F.Cu")
		(net "M_E_DQ<49>")
	)
	(gr_poly
		(pts
			(xy 290.14166 -107.099354) (xy 290.14166 -107.048554) (xy 290.01466 -107.048554) (xy 290.01466 -107.099354)
			(xy 290.02736 -107.289854) (xy 290.12896 -107.289854)
		)
		(stroke
			(width 0)
			(type solid)
		)
		(fill yes)
		(layer "F.Cu")
		(net "M_E_DQS_DP<15>")
	)
	(gr_poly
		(pts
			(xy 290.14166 -106.705654) (xy 290.14166 -106.654854) (xy 290.01466 -106.654854) (xy 290.01466 -106.705654)
			(xy 290.02736 -106.896154) (xy 290.12896 -106.896154)
		)
		(stroke
			(width 0)
			(type solid)
		)
		(fill yes)
		(layer "F.Cu")
		(net "M_E_DQS_DN<15>")
	)
	(gr_poly
		(pts
			(xy 290.14166 -106.311954) (xy 290.14166 -106.261154) (xy 290.01466 -106.261154) (xy 290.01466 -106.311954)
			(xy 290.02736 -106.502454) (xy 290.12896 -106.502454)
		)
		(stroke
			(width 0)
			(type solid)
		)
		(fill yes)
		(layer "F.Cu")
		(net "M_E_DQS_DN<6>")
	)
	(gr_poly
		(pts
			(xy 290.14166 -105.918254) (xy 290.14166 -105.867454) (xy 290.01466 -105.867454) (xy 290.01466 -105.918254)
			(xy 290.02736 -106.108754) (xy 290.12896 -106.108754)
		)
		(stroke
			(width 0)
			(type solid)
		)
		(fill yes)
		(layer "F.Cu")
		(net "M_E_DQS_DP<6>")
	)
	(gr_poly
		(pts
			(xy 290.14166 -105.524554) (xy 290.14166 -105.473754) (xy 290.01466 -105.473754) (xy 290.01466 -105.524554)
			(xy 290.02736 -105.715054) (xy 290.12896 -105.715054)
		)
		(stroke
			(width 0)
			(type solid)
		)
		(fill yes)
		(layer "F.Cu")
		(net "M_E_DQ<54>")
	)
	(gr_poly
		(pts
			(xy 290.14166 -105.130854) (xy 290.14166 -105.080054) (xy 290.01466 -105.080054) (xy 290.01466 -105.130854)
			(xy 290.02736 -105.321354) (xy 290.12896 -105.321354)
		)
		(stroke
			(width 0)
			(type solid)
		)
		(fill yes)
		(layer "F.Cu")
		(net "M_E_DQ<55>")
	)
	(gr_poly
		(pts
			(xy 290.14166 -104.737154) (xy 290.14166 -104.686354) (xy 290.01466 -104.686354) (xy 290.01466 -104.737154)
			(xy 290.02736 -104.927654) (xy 290.12896 -104.927654)
		)
		(stroke
			(width 0)
			(type solid)
		)
		(fill yes)
		(layer "F.Cu")
		(net "M_E_DQ<50>")
	)
	(gr_poly
		(pts
			(xy 290.14166 -104.343454) (xy 290.14166 -104.292654) (xy 290.01466 -104.292654) (xy 290.01466 -104.343454)
			(xy 290.02736 -104.533954) (xy 290.12896 -104.533954)
		)
		(stroke
			(width 0)
			(type solid)
		)
		(fill yes)
		(layer "F.Cu")
		(net "M_E_DQ<51>")
	)
	(gr_poly
		(pts
			(xy 290.307522 -48.782224) (xy 290.307522 -48.731424) (xy 290.180522 -48.731424) (xy 290.180522 -48.782224)
			(xy 290.193222 -48.972724) (xy 290.294822 -48.972724)
		)
		(stroke
			(width 0)
			(type solid)
		)
		(fill yes)
		(layer "F.Cu")
		(net "M_B_DQ<51>")
	)
	(gr_poly
		(pts
			(xy 290.307522 -48.388524) (xy 290.307522 -48.337724) (xy 290.180522 -48.337724) (xy 290.180522 -48.388524)
			(xy 290.193222 -48.579024) (xy 290.294822 -48.579024)
		)
		(stroke
			(width 0)
			(type solid)
		)
		(fill yes)
		(layer "F.Cu")
		(net "M_B_DQ<50>")
	)
	(gr_poly
		(pts
			(xy 290.307522 -47.994824) (xy 290.307522 -47.944024) (xy 290.180522 -47.944024) (xy 290.180522 -47.994824)
			(xy 290.193222 -48.185324) (xy 290.294822 -48.185324)
		)
		(stroke
			(width 0)
			(type solid)
		)
		(fill yes)
		(layer "F.Cu")
		(net "M_B_DQ<55>")
	)
	(gr_poly
		(pts
			(xy 290.307522 -47.601124) (xy 290.307522 -47.550324) (xy 290.180522 -47.550324) (xy 290.180522 -47.601124)
			(xy 290.193222 -47.791624) (xy 290.294822 -47.791624)
		)
		(stroke
			(width 0)
			(type solid)
		)
		(fill yes)
		(layer "F.Cu")
		(net "M_B_DQ<54>")
	)
	(gr_poly
		(pts
			(xy 290.307522 -47.207424) (xy 290.307522 -47.156624) (xy 290.180522 -47.156624) (xy 290.180522 -47.207424)
			(xy 290.193222 -47.397924) (xy 290.294822 -47.397924)
		)
		(stroke
			(width 0)
			(type solid)
		)
		(fill yes)
		(layer "F.Cu")
		(net "M_B_DQS_DP<6>")
	)
	(gr_poly
		(pts
			(xy 290.307522 -46.813724) (xy 290.307522 -46.762924) (xy 290.180522 -46.762924) (xy 290.180522 -46.813724)
			(xy 290.193222 -47.004224) (xy 290.294822 -47.004224)
		)
		(stroke
			(width 0)
			(type solid)
		)
		(fill yes)
		(layer "F.Cu")
		(net "M_B_DQS_DN<6>")
	)
	(gr_poly
		(pts
			(xy 290.307522 -46.420024) (xy 290.307522 -46.369224) (xy 290.180522 -46.369224) (xy 290.180522 -46.420024)
			(xy 290.193222 -46.610524) (xy 290.294822 -46.610524)
		)
		(stroke
			(width 0)
			(type solid)
		)
		(fill yes)
		(layer "F.Cu")
		(net "M_B_DQS_DN<15>")
	)
	(gr_poly
		(pts
			(xy 290.307522 -46.026324) (xy 290.307522 -45.975524) (xy 290.180522 -45.975524) (xy 290.180522 -46.026324)
			(xy 290.193222 -46.216824) (xy 290.294822 -46.216824)
		)
		(stroke
			(width 0)
			(type solid)
		)
		(fill yes)
		(layer "F.Cu")
		(net "M_B_DQS_DP<15>")
	)
	(gr_poly
		(pts
			(xy 290.307522 -45.632624) (xy 290.307522 -45.581824) (xy 290.180522 -45.581824) (xy 290.180522 -45.632624)
			(xy 290.193222 -45.823124) (xy 290.294822 -45.823124)
		)
		(stroke
			(width 0)
			(type solid)
		)
		(fill yes)
		(layer "F.Cu")
		(net "M_B_DQ<49>")
	)
	(gr_poly
		(pts
			(xy 290.307522 -45.238924) (xy 290.307522 -45.188124) (xy 290.180522 -45.188124) (xy 290.180522 -45.238924)
			(xy 290.193222 -45.429424) (xy 290.294822 -45.429424)
		)
		(stroke
			(width 0)
			(type solid)
		)
		(fill yes)
		(layer "F.Cu")
		(net "M_B_DQ<48>")
	)
	(gr_poly
		(pts
			(xy 290.307522 -44.845224) (xy 290.307522 -44.794424) (xy 290.180522 -44.794424) (xy 290.180522 -44.845224)
			(xy 290.193222 -45.035724) (xy 290.294822 -45.035724)
		)
		(stroke
			(width 0)
			(type solid)
		)
		(fill yes)
		(layer "F.Cu")
		(net "M_B_DQ<53>")
	)
	(gr_poly
		(pts
			(xy 290.307522 -44.451524) (xy 290.307522 -44.400724) (xy 290.180522 -44.400724) (xy 290.180522 -44.451524)
			(xy 290.193222 -44.642024) (xy 290.294822 -44.642024)
		)
		(stroke
			(width 0)
			(type solid)
		)
		(fill yes)
		(layer "F.Cu")
		(net "M_B_DQ<52>")
	)
	(gr_poly
		(pts
			(xy 290.47186 -108.572554) (xy 290.45916 -108.382054) (xy 290.35756 -108.382054) (xy 290.34486 -108.572554)
			(xy 290.34486 -108.623354) (xy 290.47186 -108.623354)
		)
		(stroke
			(width 0)
			(type solid)
		)
		(fill yes)
		(layer "F.Cu")
		(net "M_E_DQ<52>")
	)
	(gr_poly
		(pts
			(xy 290.47186 -108.178854) (xy 290.45916 -107.988354) (xy 290.35756 -107.988354) (xy 290.34486 -108.178854)
			(xy 290.34486 -108.229654) (xy 290.47186 -108.229654)
		)
		(stroke
			(width 0)
			(type solid)
		)
		(fill yes)
		(layer "F.Cu")
		(net "M_E_DQ<53>")
	)
	(gr_poly
		(pts
			(xy 290.47186 -107.785154) (xy 290.45916 -107.594654) (xy 290.35756 -107.594654) (xy 290.34486 -107.785154)
			(xy 290.34486 -107.835954) (xy 290.47186 -107.835954)
		)
		(stroke
			(width 0)
			(type solid)
		)
		(fill yes)
		(layer "F.Cu")
		(net "M_E_DQ<48>")
	)
	(gr_poly
		(pts
			(xy 290.47186 -107.391454) (xy 290.45916 -107.200954) (xy 290.35756 -107.200954) (xy 290.34486 -107.391454)
			(xy 290.34486 -107.442254) (xy 290.47186 -107.442254)
		)
		(stroke
			(width 0)
			(type solid)
		)
		(fill yes)
		(layer "F.Cu")
		(net "M_E_DQ<49>")
	)
	(gr_poly
		(pts
			(xy 290.47186 -106.997754) (xy 290.45916 -106.807254) (xy 290.35756 -106.807254) (xy 290.34486 -106.997754)
			(xy 290.34486 -107.048554) (xy 290.47186 -107.048554)
		)
		(stroke
			(width 0)
			(type solid)
		)
		(fill yes)
		(layer "F.Cu")
		(net "M_E_DQS_DP<15>")
	)
	(gr_poly
		(pts
			(xy 290.47186 -106.604054) (xy 290.45916 -106.413554) (xy 290.35756 -106.413554) (xy 290.34486 -106.604054)
			(xy 290.34486 -106.654854) (xy 290.47186 -106.654854)
		)
		(stroke
			(width 0)
			(type solid)
		)
		(fill yes)
		(layer "F.Cu")
		(net "M_E_DQS_DN<15>")
	)
	(gr_poly
		(pts
			(xy 290.47186 -106.210354) (xy 290.45916 -106.019854) (xy 290.35756 -106.019854) (xy 290.34486 -106.210354)
			(xy 290.34486 -106.261154) (xy 290.47186 -106.261154)
		)
		(stroke
			(width 0)
			(type solid)
		)
		(fill yes)
		(layer "F.Cu")
		(net "M_E_DQS_DN<6>")
	)
	(gr_poly
		(pts
			(xy 290.47186 -105.816654) (xy 290.45916 -105.626154) (xy 290.35756 -105.626154) (xy 290.34486 -105.816654)
			(xy 290.34486 -105.867454) (xy 290.47186 -105.867454)
		)
		(stroke
			(width 0)
			(type solid)
		)
		(fill yes)
		(layer "F.Cu")
		(net "M_E_DQS_DP<6>")
	)
	(gr_poly
		(pts
			(xy 290.47186 -105.422954) (xy 290.45916 -105.232454) (xy 290.35756 -105.232454) (xy 290.34486 -105.422954)
			(xy 290.34486 -105.473754) (xy 290.47186 -105.473754)
		)
		(stroke
			(width 0)
			(type solid)
		)
		(fill yes)
		(layer "F.Cu")
		(net "M_E_DQ<54>")
	)
	(gr_poly
		(pts
			(xy 290.47186 -105.029254) (xy 290.45916 -104.838754) (xy 290.35756 -104.838754) (xy 290.34486 -105.029254)
			(xy 290.34486 -105.080054) (xy 290.47186 -105.080054)
		)
		(stroke
			(width 0)
			(type solid)
		)
		(fill yes)
		(layer "F.Cu")
		(net "M_E_DQ<55>")
	)
	(gr_poly
		(pts
			(xy 290.47186 -104.635554) (xy 290.45916 -104.445054) (xy 290.35756 -104.445054) (xy 290.34486 -104.635554)
			(xy 290.34486 -104.686354) (xy 290.47186 -104.686354)
		)
		(stroke
			(width 0)
			(type solid)
		)
		(fill yes)
		(layer "F.Cu")
		(net "M_E_DQ<50>")
	)
	(gr_poly
		(pts
			(xy 290.47186 -104.241854) (xy 290.45916 -104.051354) (xy 290.35756 -104.051354) (xy 290.34486 -104.241854)
			(xy 290.34486 -104.292654) (xy 290.47186 -104.292654)
		)
		(stroke
			(width 0)
			(type solid)
		)
		(fill yes)
		(layer "F.Cu")
		(net "M_E_DQ<51>")
	)
	(gr_poly
		(pts
			(xy 290.637722 -48.680624) (xy 290.625022 -48.490124) (xy 290.523422 -48.490124) (xy 290.510722 -48.680624)
			(xy 290.510722 -48.731424) (xy 290.637722 -48.731424)
		)
		(stroke
			(width 0)
			(type solid)
		)
		(fill yes)
		(layer "F.Cu")
		(net "M_B_DQ<51>")
	)
	(gr_poly
		(pts
			(xy 290.637722 -48.286924) (xy 290.625022 -48.096424) (xy 290.523422 -48.096424) (xy 290.510722 -48.286924)
			(xy 290.510722 -48.337724) (xy 290.637722 -48.337724)
		)
		(stroke
			(width 0)
			(type solid)
		)
		(fill yes)
		(layer "F.Cu")
		(net "M_B_DQ<50>")
	)
	(gr_poly
		(pts
			(xy 290.637722 -47.893224) (xy 290.625022 -47.702724) (xy 290.523422 -47.702724) (xy 290.510722 -47.893224)
			(xy 290.510722 -47.944024) (xy 290.637722 -47.944024)
		)
		(stroke
			(width 0)
			(type solid)
		)
		(fill yes)
		(layer "F.Cu")
		(net "M_B_DQ<55>")
	)
	(gr_poly
		(pts
			(xy 290.637722 -47.499524) (xy 290.625022 -47.309024) (xy 290.523422 -47.309024) (xy 290.510722 -47.499524)
			(xy 290.510722 -47.550324) (xy 290.637722 -47.550324)
		)
		(stroke
			(width 0)
			(type solid)
		)
		(fill yes)
		(layer "F.Cu")
		(net "M_B_DQ<54>")
	)
	(gr_poly
		(pts
			(xy 290.637722 -47.105824) (xy 290.625022 -46.915324) (xy 290.523422 -46.915324) (xy 290.510722 -47.105824)
			(xy 290.510722 -47.156624) (xy 290.637722 -47.156624)
		)
		(stroke
			(width 0)
			(type solid)
		)
		(fill yes)
		(layer "F.Cu")
		(net "M_B_DQS_DP<6>")
	)
	(gr_poly
		(pts
			(xy 290.637722 -46.712124) (xy 290.625022 -46.521624) (xy 290.523422 -46.521624) (xy 290.510722 -46.712124)
			(xy 290.510722 -46.762924) (xy 290.637722 -46.762924)
		)
		(stroke
			(width 0)
			(type solid)
		)
		(fill yes)
		(layer "F.Cu")
		(net "M_B_DQS_DN<6>")
	)
	(gr_poly
		(pts
			(xy 290.637722 -46.318424) (xy 290.625022 -46.127924) (xy 290.523422 -46.127924) (xy 290.510722 -46.318424)
			(xy 290.510722 -46.369224) (xy 290.637722 -46.369224)
		)
		(stroke
			(width 0)
			(type solid)
		)
		(fill yes)
		(layer "F.Cu")
		(net "M_B_DQS_DN<15>")
	)
	(gr_poly
		(pts
			(xy 290.637722 -45.924724) (xy 290.625022 -45.734224) (xy 290.523422 -45.734224) (xy 290.510722 -45.924724)
			(xy 290.510722 -45.975524) (xy 290.637722 -45.975524)
		)
		(stroke
			(width 0)
			(type solid)
		)
		(fill yes)
		(layer "F.Cu")
		(net "M_B_DQS_DP<15>")
	)
	(gr_poly
		(pts
			(xy 290.637722 -45.531024) (xy 290.625022 -45.340524) (xy 290.523422 -45.340524) (xy 290.510722 -45.531024)
			(xy 290.510722 -45.581824) (xy 290.637722 -45.581824)
		)
		(stroke
			(width 0)
			(type solid)
		)
		(fill yes)
		(layer "F.Cu")
		(net "M_B_DQ<49>")
	)
	(gr_poly
		(pts
			(xy 290.637722 -45.137324) (xy 290.625022 -44.946824) (xy 290.523422 -44.946824) (xy 290.510722 -45.137324)
			(xy 290.510722 -45.188124) (xy 290.637722 -45.188124)
		)
		(stroke
			(width 0)
			(type solid)
		)
		(fill yes)
		(layer "F.Cu")
		(net "M_B_DQ<48>")
	)
	(gr_poly
		(pts
			(xy 290.637722 -44.743624) (xy 290.625022 -44.553124) (xy 290.523422 -44.553124) (xy 290.510722 -44.743624)
			(xy 290.510722 -44.794424) (xy 290.637722 -44.794424)
		)
		(stroke
			(width 0)
			(type solid)
		)
		(fill yes)
		(layer "F.Cu")
		(net "M_B_DQ<53>")
	)
	(gr_poly
		(pts
			(xy 290.637722 -44.349924) (xy 290.625022 -44.159424) (xy 290.523422 -44.159424) (xy 290.510722 -44.349924)
			(xy 290.510722 -44.400724) (xy 290.637722 -44.400724)
		)
		(stroke
			(width 0)
			(type solid)
		)
		(fill yes)
		(layer "F.Cu")
		(net "M_B_DQ<52>")
	)
	(gr_poly
		(pts
			(xy 290.80206 -108.674154) (xy 290.80206 -108.623354) (xy 290.67506 -108.623354) (xy 290.67506 -108.674154)
			(xy 290.68776 -108.864654) (xy 290.78936 -108.864654)
		)
		(stroke
			(width 0)
			(type solid)
		)
		(fill yes)
		(layer "F.Cu")
		(net "M_E_DQ<52>")
	)
	(gr_poly
		(pts
			(xy 290.80206 -108.280454) (xy 290.80206 -108.229654) (xy 290.67506 -108.229654) (xy 290.67506 -108.280454)
			(xy 290.68776 -108.470954) (xy 290.78936 -108.470954)
		)
		(stroke
			(width 0)
			(type solid)
		)
		(fill yes)
		(layer "F.Cu")
		(net "M_E_DQ<53>")
	)
	(gr_poly
		(pts
			(xy 290.80206 -107.886754) (xy 290.80206 -107.835954) (xy 290.67506 -107.835954) (xy 290.67506 -107.886754)
			(xy 290.68776 -108.077254) (xy 290.78936 -108.077254)
		)
		(stroke
			(width 0)
			(type solid)
		)
		(fill yes)
		(layer "F.Cu")
		(net "M_E_DQ<48>")
	)
	(gr_poly
		(pts
			(xy 290.80206 -107.493054) (xy 290.80206 -107.442254) (xy 290.67506 -107.442254) (xy 290.67506 -107.493054)
			(xy 290.68776 -107.683554) (xy 290.78936 -107.683554)
		)
		(stroke
			(width 0)
			(type solid)
		)
		(fill yes)
		(layer "F.Cu")
		(net "M_E_DQ<49>")
	)
	(gr_poly
		(pts
			(xy 290.80206 -107.099354) (xy 290.80206 -107.048554) (xy 290.67506 -107.048554) (xy 290.67506 -107.099354)
			(xy 290.68776 -107.289854) (xy 290.78936 -107.289854)
		)
		(stroke
			(width 0)
			(type solid)
		)
		(fill yes)
		(layer "F.Cu")
		(net "M_E_DQS_DP<15>")
	)
	(gr_poly
		(pts
			(xy 290.80206 -106.705654) (xy 290.80206 -106.654854) (xy 290.67506 -106.654854) (xy 290.67506 -106.705654)
			(xy 290.68776 -106.896154) (xy 290.78936 -106.896154)
		)
		(stroke
			(width 0)
			(type solid)
		)
		(fill yes)
		(layer "F.Cu")
		(net "M_E_DQS_DN<15>")
	)
	(gr_poly
		(pts
			(xy 290.80206 -106.311954) (xy 290.80206 -106.261154) (xy 290.67506 -106.261154) (xy 290.67506 -106.311954)
			(xy 290.68776 -106.502454) (xy 290.78936 -106.502454)
		)
		(stroke
			(width 0)
			(type solid)
		)
		(fill yes)
		(layer "F.Cu")
		(net "M_E_DQS_DN<6>")
	)
	(gr_poly
		(pts
			(xy 290.80206 -105.918254) (xy 290.80206 -105.867454) (xy 290.67506 -105.867454) (xy 290.67506 -105.918254)
			(xy 290.68776 -106.108754) (xy 290.78936 -106.108754)
		)
		(stroke
			(width 0)
			(type solid)
		)
		(fill yes)
		(layer "F.Cu")
		(net "M_E_DQS_DP<6>")
	)
	(gr_poly
		(pts
			(xy 290.80206 -105.524554) (xy 290.80206 -105.473754) (xy 290.67506 -105.473754) (xy 290.67506 -105.524554)
			(xy 290.68776 -105.715054) (xy 290.78936 -105.715054)
		)
		(stroke
			(width 0)
			(type solid)
		)
		(fill yes)
		(layer "F.Cu")
		(net "M_E_DQ<54>")
	)
	(gr_poly
		(pts
			(xy 290.80206 -105.130854) (xy 290.80206 -105.080054) (xy 290.67506 -105.080054) (xy 290.67506 -105.130854)
			(xy 290.68776 -105.321354) (xy 290.78936 -105.321354)
		)
		(stroke
			(width 0)
			(type solid)
		)
		(fill yes)
		(layer "F.Cu")
		(net "M_E_DQ<55>")
	)
	(gr_poly
		(pts
			(xy 290.80206 -104.737154) (xy 290.80206 -104.686354) (xy 290.67506 -104.686354) (xy 290.67506 -104.737154)
			(xy 290.68776 -104.927654) (xy 290.78936 -104.927654)
		)
		(stroke
			(width 0)
			(type solid)
		)
		(fill yes)
		(layer "F.Cu")
		(net "M_E_DQ<50>")
	)
	(gr_poly
		(pts
			(xy 290.80206 -104.343454) (xy 290.80206 -104.292654) (xy 290.67506 -104.292654) (xy 290.67506 -104.343454)
			(xy 290.68776 -104.533954) (xy 290.78936 -104.533954)
		)
		(stroke
			(width 0)
			(type solid)
		)
		(fill yes)
		(layer "F.Cu")
		(net "M_E_DQ<51>")
	)
	(gr_poly
		(pts
			(xy 290.967922 -48.782224) (xy 290.967922 -48.731424) (xy 290.840922 -48.731424) (xy 290.840922 -48.782224)
			(xy 290.853622 -48.972724) (xy 290.955222 -48.972724)
		)
		(stroke
			(width 0)
			(type solid)
		)
		(fill yes)
		(layer "F.Cu")
		(net "M_B_DQ<51>")
	)
	(gr_poly
		(pts
			(xy 290.967922 -48.388524) (xy 290.967922 -48.337724) (xy 290.840922 -48.337724) (xy 290.840922 -48.388524)
			(xy 290.853622 -48.579024) (xy 290.955222 -48.579024)
		)
		(stroke
			(width 0)
			(type solid)
		)
		(fill yes)
		(layer "F.Cu")
		(net "M_B_DQ<50>")
	)
	(gr_poly
		(pts
			(xy 290.967922 -47.994824) (xy 290.967922 -47.944024) (xy 290.840922 -47.944024) (xy 290.840922 -47.994824)
			(xy 290.853622 -48.185324) (xy 290.955222 -48.185324)
		)
		(stroke
			(width 0)
			(type solid)
		)
		(fill yes)
		(layer "F.Cu")
		(net "M_B_DQ<55>")
	)
	(gr_poly
		(pts
			(xy 290.967922 -47.601124) (xy 290.967922 -47.550324) (xy 290.840922 -47.550324) (xy 290.840922 -47.601124)
			(xy 290.853622 -47.791624) (xy 290.955222 -47.791624)
		)
		(stroke
			(width 0)
			(type solid)
		)
		(fill yes)
		(layer "F.Cu")
		(net "M_B_DQ<54>")
	)
	(gr_poly
		(pts
			(xy 290.967922 -47.207424) (xy 290.967922 -47.156624) (xy 290.840922 -47.156624) (xy 290.840922 -47.207424)
			(xy 290.853622 -47.397924) (xy 290.955222 -47.397924)
		)
		(stroke
			(width 0)
			(type solid)
		)
		(fill yes)
		(layer "F.Cu")
		(net "M_B_DQS_DP<6>")
	)
	(gr_poly
		(pts
			(xy 290.967922 -46.813724) (xy 290.967922 -46.762924) (xy 290.840922 -46.762924) (xy 290.840922 -46.813724)
			(xy 290.853622 -47.004224) (xy 290.955222 -47.004224)
		)
		(stroke
			(width 0)
			(type solid)
		)
		(fill yes)
		(layer "F.Cu")
		(net "M_B_DQS_DN<6>")
	)
	(gr_poly
		(pts
			(xy 290.967922 -46.420024) (xy 290.967922 -46.369224) (xy 290.840922 -46.369224) (xy 290.840922 -46.420024)
			(xy 290.853622 -46.610524) (xy 290.955222 -46.610524)
		)
		(stroke
			(width 0)
			(type solid)
		)
		(fill yes)
		(layer "F.Cu")
		(net "M_B_DQS_DN<15>")
	)
	(gr_poly
		(pts
			(xy 290.967922 -46.026324) (xy 290.967922 -45.975524) (xy 290.840922 -45.975524) (xy 290.840922 -46.026324)
			(xy 290.853622 -46.216824) (xy 290.955222 -46.216824)
		)
		(stroke
			(width 0)
			(type solid)
		)
		(fill yes)
		(layer "F.Cu")
		(net "M_B_DQS_DP<15>")
	)
	(gr_poly
		(pts
			(xy 290.967922 -45.632624) (xy 290.967922 -45.581824) (xy 290.840922 -45.581824) (xy 290.840922 -45.632624)
			(xy 290.853622 -45.823124) (xy 290.955222 -45.823124)
		)
		(stroke
			(width 0)
			(type solid)
		)
		(fill yes)
		(layer "F.Cu")
		(net "M_B_DQ<49>")
	)
	(gr_poly
		(pts
			(xy 290.967922 -45.238924) (xy 290.967922 -45.188124) (xy 290.840922 -45.188124) (xy 290.840922 -45.238924)
			(xy 290.853622 -45.429424) (xy 290.955222 -45.429424)
		)
		(stroke
			(width 0)
			(type solid)
		)
		(fill yes)
		(layer "F.Cu")
		(net "M_B_DQ<48>")
	)
	(gr_poly
		(pts
			(xy 290.967922 -44.845224) (xy 290.967922 -44.794424) (xy 290.840922 -44.794424) (xy 290.840922 -44.845224)
			(xy 290.853622 -45.035724) (xy 290.955222 -45.035724)
		)
		(stroke
			(width 0)
			(type solid)
		)
		(fill yes)
		(layer "F.Cu")
		(net "M_B_DQ<53>")
	)
	(gr_poly
		(pts
			(xy 290.967922 -44.451524) (xy 290.967922 -44.400724) (xy 290.840922 -44.400724) (xy 290.840922 -44.451524)
			(xy 290.853622 -44.642024) (xy 290.955222 -44.642024)
		)
		(stroke
			(width 0)
			(type solid)
		)
		(fill yes)
		(layer "F.Cu")
		(net "M_B_DQ<52>")
	)
	(gr_poly
		(pts
			(xy 291.13226 -108.572554) (xy 291.11956 -108.382054) (xy 291.01796 -108.382054) (xy 291.00526 -108.572554)
			(xy 291.00526 -108.623354) (xy 291.13226 -108.623354)
		)
		(stroke
			(width 0)
			(type solid)
		)
		(fill yes)
		(layer "F.Cu")
		(net "M_E_DQ<52>")
	)
	(gr_poly
		(pts
			(xy 291.13226 -108.178854) (xy 291.11956 -107.988354) (xy 291.01796 -107.988354) (xy 291.00526 -108.178854)
			(xy 291.00526 -108.229654) (xy 291.13226 -108.229654)
		)
		(stroke
			(width 0)
			(type solid)
		)
		(fill yes)
		(layer "F.Cu")
		(net "M_E_DQ<53>")
	)
	(gr_poly
		(pts
			(xy 291.13226 -107.785154) (xy 291.11956 -107.594654) (xy 291.01796 -107.594654) (xy 291.00526 -107.785154)
			(xy 291.00526 -107.835954) (xy 291.13226 -107.835954)
		)
		(stroke
			(width 0)
			(type solid)
		)
		(fill yes)
		(layer "F.Cu")
		(net "M_E_DQ<48>")
	)
	(gr_poly
		(pts
			(xy 291.13226 -107.391454) (xy 291.11956 -107.200954) (xy 291.01796 -107.200954) (xy 291.00526 -107.391454)
			(xy 291.00526 -107.442254) (xy 291.13226 -107.442254)
		)
		(stroke
			(width 0)
			(type solid)
		)
		(fill yes)
		(layer "F.Cu")
		(net "M_E_DQ<49>")
	)
	(gr_poly
		(pts
			(xy 291.13226 -106.997754) (xy 291.11956 -106.807254) (xy 291.01796 -106.807254) (xy 291.00526 -106.997754)
			(xy 291.00526 -107.048554) (xy 291.13226 -107.048554)
		)
		(stroke
			(width 0)
			(type solid)
		)
		(fill yes)
		(layer "F.Cu")
		(net "M_E_DQS_DP<15>")
	)
	(gr_poly
		(pts
			(xy 291.13226 -106.604054) (xy 291.11956 -106.413554) (xy 291.01796 -106.413554) (xy 291.00526 -106.604054)
			(xy 291.00526 -106.654854) (xy 291.13226 -106.654854)
		)
		(stroke
			(width 0)
			(type solid)
		)
		(fill yes)
		(layer "F.Cu")
		(net "M_E_DQS_DN<15>")
	)
	(gr_poly
		(pts
			(xy 291.13226 -106.210354) (xy 291.11956 -106.019854) (xy 291.01796 -106.019854) (xy 291.00526 -106.210354)
			(xy 291.00526 -106.261154) (xy 291.13226 -106.261154)
		)
		(stroke
			(width 0)
			(type solid)
		)
		(fill yes)
		(layer "F.Cu")
		(net "M_E_DQS_DN<6>")
	)
	(gr_poly
		(pts
			(xy 291.13226 -105.816654) (xy 291.11956 -105.626154) (xy 291.01796 -105.626154) (xy 291.00526 -105.816654)
			(xy 291.00526 -105.867454) (xy 291.13226 -105.867454)
		)
		(stroke
			(width 0)
			(type solid)
		)
		(fill yes)
		(layer "F.Cu")
		(net "M_E_DQS_DP<6>")
	)
	(gr_poly
		(pts
			(xy 291.13226 -105.422954) (xy 291.11956 -105.232454) (xy 291.01796 -105.232454) (xy 291.00526 -105.422954)
			(xy 291.00526 -105.473754) (xy 291.13226 -105.473754)
		)
		(stroke
			(width 0)
			(type solid)
		)
		(fill yes)
		(layer "F.Cu")
		(net "M_E_DQ<54>")
	)
	(gr_poly
		(pts
			(xy 291.13226 -105.029254) (xy 291.11956 -104.838754) (xy 291.01796 -104.838754) (xy 291.00526 -105.029254)
			(xy 291.00526 -105.080054) (xy 291.13226 -105.080054)
		)
		(stroke
			(width 0)
			(type solid)
		)
		(fill yes)
		(layer "F.Cu")
		(net "M_E_DQ<55>")
	)
	(gr_poly
		(pts
			(xy 291.13226 -104.635554) (xy 291.11956 -104.445054) (xy 291.01796 -104.445054) (xy 291.00526 -104.635554)
			(xy 291.00526 -104.686354) (xy 291.13226 -104.686354)
		)
		(stroke
			(width 0)
			(type solid)
		)
		(fill yes)
		(layer "F.Cu")
		(net "M_E_DQ<50>")
	)
	(gr_poly
		(pts
			(xy 291.13226 -104.241854) (xy 291.11956 -104.051354) (xy 291.01796 -104.051354) (xy 291.00526 -104.241854)
			(xy 291.00526 -104.292654) (xy 291.13226 -104.292654)
		)
		(stroke
			(width 0)
			(type solid)
		)
		(fill yes)
		(layer "F.Cu")
		(net "M_E_DQ<51>")
	)
	(gr_poly
		(pts
			(xy 291.298122 -48.680624) (xy 291.285422 -48.490124) (xy 291.183822 -48.490124) (xy 291.171122 -48.680624)
			(xy 291.171122 -48.731424) (xy 291.298122 -48.731424)
		)
		(stroke
			(width 0)
			(type solid)
		)
		(fill yes)
		(layer "F.Cu")
		(net "M_B_DQ<51>")
	)
	(gr_poly
		(pts
			(xy 291.298122 -48.286924) (xy 291.285422 -48.096424) (xy 291.183822 -48.096424) (xy 291.171122 -48.286924)
			(xy 291.171122 -48.337724) (xy 291.298122 -48.337724)
		)
		(stroke
			(width 0)
			(type solid)
		)
		(fill yes)
		(layer "F.Cu")
		(net "M_B_DQ<50>")
	)
	(gr_poly
		(pts
			(xy 291.298122 -47.893224) (xy 291.285422 -47.702724) (xy 291.183822 -47.702724) (xy 291.171122 -47.893224)
			(xy 291.171122 -47.944024) (xy 291.298122 -47.944024)
		)
		(stroke
			(width 0)
			(type solid)
		)
		(fill yes)
		(layer "F.Cu")
		(net "M_B_DQ<55>")
	)
	(gr_poly
		(pts
			(xy 291.298122 -47.499524) (xy 291.285422 -47.309024) (xy 291.183822 -47.309024) (xy 291.171122 -47.499524)
			(xy 291.171122 -47.550324) (xy 291.298122 -47.550324)
		)
		(stroke
			(width 0)
			(type solid)
		)
		(fill yes)
		(layer "F.Cu")
		(net "M_B_DQ<54>")
	)
	(gr_poly
		(pts
			(xy 291.298122 -47.105824) (xy 291.285422 -46.915324) (xy 291.183822 -46.915324) (xy 291.171122 -47.105824)
			(xy 291.171122 -47.156624) (xy 291.298122 -47.156624)
		)
		(stroke
			(width 0)
			(type solid)
		)
		(fill yes)
		(layer "F.Cu")
		(net "M_B_DQS_DP<6>")
	)
	(gr_poly
		(pts
			(xy 291.298122 -46.712124) (xy 291.285422 -46.521624) (xy 291.183822 -46.521624) (xy 291.171122 -46.712124)
			(xy 291.171122 -46.762924) (xy 291.298122 -46.762924)
		)
		(stroke
			(width 0)
			(type solid)
		)
		(fill yes)
		(layer "F.Cu")
		(net "M_B_DQS_DN<6>")
	)
	(gr_poly
		(pts
			(xy 291.298122 -46.318424) (xy 291.285422 -46.127924) (xy 291.183822 -46.127924) (xy 291.171122 -46.318424)
			(xy 291.171122 -46.369224) (xy 291.298122 -46.369224)
		)
		(stroke
			(width 0)
			(type solid)
		)
		(fill yes)
		(layer "F.Cu")
		(net "M_B_DQS_DN<15>")
	)
	(gr_poly
		(pts
			(xy 291.298122 -45.924724) (xy 291.285422 -45.734224) (xy 291.183822 -45.734224) (xy 291.171122 -45.924724)
			(xy 291.171122 -45.975524) (xy 291.298122 -45.975524)
		)
		(stroke
			(width 0)
			(type solid)
		)
		(fill yes)
		(layer "F.Cu")
		(net "M_B_DQS_DP<15>")
	)
	(gr_poly
		(pts
			(xy 291.298122 -45.531024) (xy 291.285422 -45.340524) (xy 291.183822 -45.340524) (xy 291.171122 -45.531024)
			(xy 291.171122 -45.581824) (xy 291.298122 -45.581824)
		)
		(stroke
			(width 0)
			(type solid)
		)
		(fill yes)
		(layer "F.Cu")
		(net "M_B_DQ<49>")
	)
	(gr_poly
		(pts
			(xy 291.298122 -45.137324) (xy 291.285422 -44.946824) (xy 291.183822 -44.946824) (xy 291.171122 -45.137324)
			(xy 291.171122 -45.188124) (xy 291.298122 -45.188124)
		)
		(stroke
			(width 0)
			(type solid)
		)
		(fill yes)
		(layer "F.Cu")
		(net "M_B_DQ<48>")
	)
	(gr_poly
		(pts
			(xy 291.298122 -44.743624) (xy 291.285422 -44.553124) (xy 291.183822 -44.553124) (xy 291.171122 -44.743624)
			(xy 291.171122 -44.794424) (xy 291.298122 -44.794424)
		)
		(stroke
			(width 0)
			(type solid)
		)
		(fill yes)
		(layer "F.Cu")
		(net "M_B_DQ<53>")
	)
	(gr_poly
		(pts
			(xy 291.298122 -44.349924) (xy 291.285422 -44.159424) (xy 291.183822 -44.159424) (xy 291.171122 -44.349924)
			(xy 291.171122 -44.400724) (xy 291.298122 -44.400724)
		)
		(stroke
			(width 0)
			(type solid)
		)
		(fill yes)
		(layer "F.Cu")
		(net "M_B_DQ<52>")
	)
	(gr_poly
		(pts
			(xy 291.46246 -108.674154) (xy 291.46246 -108.623354) (xy 291.33546 -108.623354) (xy 291.33546 -108.674154)
			(xy 291.34816 -108.864654) (xy 291.44976 -108.864654)
		)
		(stroke
			(width 0)
			(type solid)
		)
		(fill yes)
		(layer "F.Cu")
		(net "M_E_DQ<52>")
	)
	(gr_poly
		(pts
			(xy 291.46246 -108.280454) (xy 291.46246 -108.229654) (xy 291.33546 -108.229654) (xy 291.33546 -108.280454)
			(xy 291.34816 -108.470954) (xy 291.44976 -108.470954)
		)
		(stroke
			(width 0)
			(type solid)
		)
		(fill yes)
		(layer "F.Cu")
		(net "M_E_DQ<53>")
	)
	(gr_poly
		(pts
			(xy 291.46246 -107.886754) (xy 291.46246 -107.835954) (xy 291.33546 -107.835954) (xy 291.33546 -107.886754)
			(xy 291.34816 -108.077254) (xy 291.44976 -108.077254)
		)
		(stroke
			(width 0)
			(type solid)
		)
		(fill yes)
		(layer "F.Cu")
		(net "M_E_DQ<48>")
	)
	(gr_poly
		(pts
			(xy 291.46246 -107.493054) (xy 291.46246 -107.442254) (xy 291.33546 -107.442254) (xy 291.33546 -107.493054)
			(xy 291.34816 -107.683554) (xy 291.44976 -107.683554)
		)
		(stroke
			(width 0)
			(type solid)
		)
		(fill yes)
		(layer "F.Cu")
		(net "M_E_DQ<49>")
	)
	(gr_poly
		(pts
			(xy 291.46246 -107.099354) (xy 291.46246 -107.048554) (xy 291.33546 -107.048554) (xy 291.33546 -107.099354)
			(xy 291.34816 -107.289854) (xy 291.44976 -107.289854)
		)
		(stroke
			(width 0)
			(type solid)
		)
		(fill yes)
		(layer "F.Cu")
		(net "M_E_DQS_DP<15>")
	)
	(gr_poly
		(pts
			(xy 291.46246 -106.705654) (xy 291.46246 -106.654854) (xy 291.33546 -106.654854) (xy 291.33546 -106.705654)
			(xy 291.34816 -106.896154) (xy 291.44976 -106.896154)
		)
		(stroke
			(width 0)
			(type solid)
		)
		(fill yes)
		(layer "F.Cu")
		(net "M_E_DQS_DN<15>")
	)
	(gr_poly
		(pts
			(xy 291.46246 -106.311954) (xy 291.46246 -106.261154) (xy 291.33546 -106.261154) (xy 291.33546 -106.311954)
			(xy 291.34816 -106.502454) (xy 291.44976 -106.502454)
		)
		(stroke
			(width 0)
			(type solid)
		)
		(fill yes)
		(layer "F.Cu")
		(net "M_E_DQS_DN<6>")
	)
	(gr_poly
		(pts
			(xy 291.46246 -105.918254) (xy 291.46246 -105.867454) (xy 291.33546 -105.867454) (xy 291.33546 -105.918254)
			(xy 291.34816 -106.108754) (xy 291.44976 -106.108754)
		)
		(stroke
			(width 0)
			(type solid)
		)
		(fill yes)
		(layer "F.Cu")
		(net "M_E_DQS_DP<6>")
	)
	(gr_poly
		(pts
			(xy 291.46246 -105.524554) (xy 291.46246 -105.473754) (xy 291.33546 -105.473754) (xy 291.33546 -105.524554)
			(xy 291.34816 -105.715054) (xy 291.44976 -105.715054)
		)
		(stroke
			(width 0)
			(type solid)
		)
		(fill yes)
		(layer "F.Cu")
		(net "M_E_DQ<54>")
	)
	(gr_poly
		(pts
			(xy 291.46246 -105.130854) (xy 291.46246 -105.080054) (xy 291.33546 -105.080054) (xy 291.33546 -105.130854)
			(xy 291.34816 -105.321354) (xy 291.44976 -105.321354)
		)
		(stroke
			(width 0)
			(type solid)
		)
		(fill yes)
		(layer "F.Cu")
		(net "M_E_DQ<55>")
	)
	(gr_poly
		(pts
			(xy 291.46246 -104.737154) (xy 291.46246 -104.686354) (xy 291.33546 -104.686354) (xy 291.33546 -104.737154)
			(xy 291.34816 -104.927654) (xy 291.44976 -104.927654)
		)
		(stroke
			(width 0)
			(type solid)
		)
		(fill yes)
		(layer "F.Cu")
		(net "M_E_DQ<50>")
	)
	(gr_poly
		(pts
			(xy 291.46246 -104.343454) (xy 291.46246 -104.292654) (xy 291.33546 -104.292654) (xy 291.33546 -104.343454)
			(xy 291.34816 -104.533954) (xy 291.44976 -104.533954)
		)
		(stroke
			(width 0)
			(type solid)
		)
		(fill yes)
		(layer "F.Cu")
		(net "M_E_DQ<51>")
	)
	(gr_poly
		(pts
			(xy 291.628322 -48.782224) (xy 291.628322 -48.731424) (xy 291.501322 -48.731424) (xy 291.501322 -48.782224)
			(xy 291.514022 -48.972724) (xy 291.615622 -48.972724)
		)
		(stroke
			(width 0)
			(type solid)
		)
		(fill yes)
		(layer "F.Cu")
		(net "M_B_DQ<51>")
	)
	(gr_poly
		(pts
			(xy 291.628322 -48.388524) (xy 291.628322 -48.337724) (xy 291.501322 -48.337724) (xy 291.501322 -48.388524)
			(xy 291.514022 -48.579024) (xy 291.615622 -48.579024)
		)
		(stroke
			(width 0)
			(type solid)
		)
		(fill yes)
		(layer "F.Cu")
		(net "M_B_DQ<50>")
	)
	(gr_poly
		(pts
			(xy 291.628322 -47.994824) (xy 291.628322 -47.944024) (xy 291.501322 -47.944024) (xy 291.501322 -47.994824)
			(xy 291.514022 -48.185324) (xy 291.615622 -48.185324)
		)
		(stroke
			(width 0)
			(type solid)
		)
		(fill yes)
		(layer "F.Cu")
		(net "M_B_DQ<55>")
	)
	(gr_poly
		(pts
			(xy 291.628322 -47.601124) (xy 291.628322 -47.550324) (xy 291.501322 -47.550324) (xy 291.501322 -47.601124)
			(xy 291.514022 -47.791624) (xy 291.615622 -47.791624)
		)
		(stroke
			(width 0)
			(type solid)
		)
		(fill yes)
		(layer "F.Cu")
		(net "M_B_DQ<54>")
	)
	(gr_poly
		(pts
			(xy 291.628322 -47.207424) (xy 291.628322 -47.156624) (xy 291.501322 -47.156624) (xy 291.501322 -47.207424)
			(xy 291.514022 -47.397924) (xy 291.615622 -47.397924)
		)
		(stroke
			(width 0)
			(type solid)
		)
		(fill yes)
		(layer "F.Cu")
		(net "M_B_DQS_DP<6>")
	)
	(gr_poly
		(pts
			(xy 291.628322 -46.813724) (xy 291.628322 -46.762924) (xy 291.501322 -46.762924) (xy 291.501322 -46.813724)
			(xy 291.514022 -47.004224) (xy 291.615622 -47.004224)
		)
		(stroke
			(width 0)
			(type solid)
		)
		(fill yes)
		(layer "F.Cu")
		(net "M_B_DQS_DN<6>")
	)
	(gr_poly
		(pts
			(xy 291.628322 -46.420024) (xy 291.628322 -46.369224) (xy 291.501322 -46.369224) (xy 291.501322 -46.420024)
			(xy 291.514022 -46.610524) (xy 291.615622 -46.610524)
		)
		(stroke
			(width 0)
			(type solid)
		)
		(fill yes)
		(layer "F.Cu")
		(net "M_B_DQS_DN<15>")
	)
	(gr_poly
		(pts
			(xy 291.628322 -46.026324) (xy 291.628322 -45.975524) (xy 291.501322 -45.975524) (xy 291.501322 -46.026324)
			(xy 291.514022 -46.216824) (xy 291.615622 -46.216824)
		)
		(stroke
			(width 0)
			(type solid)
		)
		(fill yes)
		(layer "F.Cu")
		(net "M_B_DQS_DP<15>")
	)
	(gr_poly
		(pts
			(xy 291.628322 -45.632624) (xy 291.628322 -45.581824) (xy 291.501322 -45.581824) (xy 291.501322 -45.632624)
			(xy 291.514022 -45.823124) (xy 291.615622 -45.823124)
		)
		(stroke
			(width 0)
			(type solid)
		)
		(fill yes)
		(layer "F.Cu")
		(net "M_B_DQ<49>")
	)
	(gr_poly
		(pts
			(xy 291.628322 -45.238924) (xy 291.628322 -45.188124) (xy 291.501322 -45.188124) (xy 291.501322 -45.238924)
			(xy 291.514022 -45.429424) (xy 291.615622 -45.429424)
		)
		(stroke
			(width 0)
			(type solid)
		)
		(fill yes)
		(layer "F.Cu")
		(net "M_B_DQ<48>")
	)
	(gr_poly
		(pts
			(xy 291.628322 -44.845224) (xy 291.628322 -44.794424) (xy 291.501322 -44.794424) (xy 291.501322 -44.845224)
			(xy 291.514022 -45.035724) (xy 291.615622 -45.035724)
		)
		(stroke
			(width 0)
			(type solid)
		)
		(fill yes)
		(layer "F.Cu")
		(net "M_B_DQ<53>")
	)
	(gr_poly
		(pts
			(xy 291.628322 -44.451524) (xy 291.628322 -44.400724) (xy 291.501322 -44.400724) (xy 291.501322 -44.451524)
			(xy 291.514022 -44.642024) (xy 291.615622 -44.642024)
		)
		(stroke
			(width 0)
			(type solid)
		)
		(fill yes)
		(layer "F.Cu")
		(net "M_B_DQ<52>")
	)
	(gr_poly
		(pts
			(xy 291.79266 -108.572554) (xy 291.77996 -108.382054) (xy 291.67836 -108.382054) (xy 291.66566 -108.572554)
			(xy 291.66566 -108.623354) (xy 291.79266 -108.623354)
		)
		(stroke
			(width 0)
			(type solid)
		)
		(fill yes)
		(layer "F.Cu")
		(net "M_E_DQ<52>")
	)
	(gr_poly
		(pts
			(xy 291.79266 -108.178854) (xy 291.77996 -107.988354) (xy 291.67836 -107.988354) (xy 291.66566 -108.178854)
			(xy 291.66566 -108.229654) (xy 291.79266 -108.229654)
		)
		(stroke
			(width 0)
			(type solid)
		)
		(fill yes)
		(layer "F.Cu")
		(net "M_E_DQ<53>")
	)
	(gr_poly
		(pts
			(xy 291.79266 -107.785154) (xy 291.77996 -107.594654) (xy 291.67836 -107.594654) (xy 291.66566 -107.785154)
			(xy 291.66566 -107.835954) (xy 291.79266 -107.835954)
		)
		(stroke
			(width 0)
			(type solid)
		)
		(fill yes)
		(layer "F.Cu")
		(net "M_E_DQ<48>")
	)
	(gr_poly
		(pts
			(xy 291.79266 -107.391454) (xy 291.77996 -107.200954) (xy 291.67836 -107.200954) (xy 291.66566 -107.391454)
			(xy 291.66566 -107.442254) (xy 291.79266 -107.442254)
		)
		(stroke
			(width 0)
			(type solid)
		)
		(fill yes)
		(layer "F.Cu")
		(net "M_E_DQ<49>")
	)
	(gr_poly
		(pts
			(xy 291.79266 -106.997754) (xy 291.77996 -106.807254) (xy 291.67836 -106.807254) (xy 291.66566 -106.997754)
			(xy 291.66566 -107.048554) (xy 291.79266 -107.048554)
		)
		(stroke
			(width 0)
			(type solid)
		)
		(fill yes)
		(layer "F.Cu")
		(net "M_E_DQS_DP<15>")
	)
	(gr_poly
		(pts
			(xy 291.79266 -106.604054) (xy 291.77996 -106.413554) (xy 291.67836 -106.413554) (xy 291.66566 -106.604054)
			(xy 291.66566 -106.654854) (xy 291.79266 -106.654854)
		)
		(stroke
			(width 0)
			(type solid)
		)
		(fill yes)
		(layer "F.Cu")
		(net "M_E_DQS_DN<15>")
	)
	(gr_poly
		(pts
			(xy 291.79266 -106.210354) (xy 291.77996 -106.019854) (xy 291.67836 -106.019854) (xy 291.66566 -106.210354)
			(xy 291.66566 -106.261154) (xy 291.79266 -106.261154)
		)
		(stroke
			(width 0)
			(type solid)
		)
		(fill yes)
		(layer "F.Cu")
		(net "M_E_DQS_DN<6>")
	)
	(gr_poly
		(pts
			(xy 291.79266 -105.816654) (xy 291.77996 -105.626154) (xy 291.67836 -105.626154) (xy 291.66566 -105.816654)
			(xy 291.66566 -105.867454) (xy 291.79266 -105.867454)
		)
		(stroke
			(width 0)
			(type solid)
		)
		(fill yes)
		(layer "F.Cu")
		(net "M_E_DQS_DP<6>")
	)
	(gr_poly
		(pts
			(xy 291.79266 -105.422954) (xy 291.77996 -105.232454) (xy 291.67836 -105.232454) (xy 291.66566 -105.422954)
			(xy 291.66566 -105.473754) (xy 291.79266 -105.473754)
		)
		(stroke
			(width 0)
			(type solid)
		)
		(fill yes)
		(layer "F.Cu")
		(net "M_E_DQ<54>")
	)
	(gr_poly
		(pts
			(xy 291.79266 -105.029254) (xy 291.77996 -104.838754) (xy 291.67836 -104.838754) (xy 291.66566 -105.029254)
			(xy 291.66566 -105.080054) (xy 291.79266 -105.080054)
		)
		(stroke
			(width 0)
			(type solid)
		)
		(fill yes)
		(layer "F.Cu")
		(net "M_E_DQ<55>")
	)
	(gr_poly
		(pts
			(xy 291.79266 -104.635554) (xy 291.77996 -104.445054) (xy 291.67836 -104.445054) (xy 291.66566 -104.635554)
			(xy 291.66566 -104.686354) (xy 291.79266 -104.686354)
		)
		(stroke
			(width 0)
			(type solid)
		)
		(fill yes)
		(layer "F.Cu")
		(net "M_E_DQ<50>")
	)
	(gr_poly
		(pts
			(xy 291.79266 -104.241854) (xy 291.77996 -104.051354) (xy 291.67836 -104.051354) (xy 291.66566 -104.241854)
			(xy 291.66566 -104.292654) (xy 291.79266 -104.292654)
		)
		(stroke
			(width 0)
			(type solid)
		)
		(fill yes)
		(layer "F.Cu")
		(net "M_E_DQ<51>")
	)
	(gr_poly
		(pts
			(xy 291.958522 -48.680624) (xy 291.945822 -48.490124) (xy 291.844222 -48.490124) (xy 291.831522 -48.680624)
			(xy 291.831522 -48.731424) (xy 291.958522 -48.731424)
		)
		(stroke
			(width 0)
			(type solid)
		)
		(fill yes)
		(layer "F.Cu")
		(net "M_B_DQ<51>")
	)
	(gr_poly
		(pts
			(xy 291.958522 -48.286924) (xy 291.945822 -48.096424) (xy 291.844222 -48.096424) (xy 291.831522 -48.286924)
			(xy 291.831522 -48.337724) (xy 291.958522 -48.337724)
		)
		(stroke
			(width 0)
			(type solid)
		)
		(fill yes)
		(layer "F.Cu")
		(net "M_B_DQ<50>")
	)
	(gr_poly
		(pts
			(xy 291.958522 -47.893224) (xy 291.945822 -47.702724) (xy 291.844222 -47.702724) (xy 291.831522 -47.893224)
			(xy 291.831522 -47.944024) (xy 291.958522 -47.944024)
		)
		(stroke
			(width 0)
			(type solid)
		)
		(fill yes)
		(layer "F.Cu")
		(net "M_B_DQ<55>")
	)
	(gr_poly
		(pts
			(xy 291.958522 -47.499524) (xy 291.945822 -47.309024) (xy 291.844222 -47.309024) (xy 291.831522 -47.499524)
			(xy 291.831522 -47.550324) (xy 291.958522 -47.550324)
		)
		(stroke
			(width 0)
			(type solid)
		)
		(fill yes)
		(layer "F.Cu")
		(net "M_B_DQ<54>")
	)
	(gr_poly
		(pts
			(xy 291.958522 -47.105824) (xy 291.945822 -46.915324) (xy 291.844222 -46.915324) (xy 291.831522 -47.105824)
			(xy 291.831522 -47.156624) (xy 291.958522 -47.156624)
		)
		(stroke
			(width 0)
			(type solid)
		)
		(fill yes)
		(layer "F.Cu")
		(net "M_B_DQS_DP<6>")
	)
	(gr_poly
		(pts
			(xy 291.958522 -46.712124) (xy 291.945822 -46.521624) (xy 291.844222 -46.521624) (xy 291.831522 -46.712124)
			(xy 291.831522 -46.762924) (xy 291.958522 -46.762924)
		)
		(stroke
			(width 0)
			(type solid)
		)
		(fill yes)
		(layer "F.Cu")
		(net "M_B_DQS_DN<6>")
	)
	(gr_poly
		(pts
			(xy 291.958522 -46.318424) (xy 291.945822 -46.127924) (xy 291.844222 -46.127924) (xy 291.831522 -46.318424)
			(xy 291.831522 -46.369224) (xy 291.958522 -46.369224)
		)
		(stroke
			(width 0)
			(type solid)
		)
		(fill yes)
		(layer "F.Cu")
		(net "M_B_DQS_DN<15>")
	)
	(gr_poly
		(pts
			(xy 291.958522 -45.924724) (xy 291.945822 -45.734224) (xy 291.844222 -45.734224) (xy 291.831522 -45.924724)
			(xy 291.831522 -45.975524) (xy 291.958522 -45.975524)
		)
		(stroke
			(width 0)
			(type solid)
		)
		(fill yes)
		(layer "F.Cu")
		(net "M_B_DQS_DP<15>")
	)
	(gr_poly
		(pts
			(xy 291.958522 -45.531024) (xy 291.945822 -45.340524) (xy 291.844222 -45.340524) (xy 291.831522 -45.531024)
			(xy 291.831522 -45.581824) (xy 291.958522 -45.581824)
		)
		(stroke
			(width 0)
			(type solid)
		)
		(fill yes)
		(layer "F.Cu")
		(net "M_B_DQ<49>")
	)
	(gr_poly
		(pts
			(xy 291.958522 -45.137324) (xy 291.945822 -44.946824) (xy 291.844222 -44.946824) (xy 291.831522 -45.137324)
			(xy 291.831522 -45.188124) (xy 291.958522 -45.188124)
		)
		(stroke
			(width 0)
			(type solid)
		)
		(fill yes)
		(layer "F.Cu")
		(net "M_B_DQ<48>")
	)
	(gr_poly
		(pts
			(xy 291.958522 -44.743624) (xy 291.945822 -44.553124) (xy 291.844222 -44.553124) (xy 291.831522 -44.743624)
			(xy 291.831522 -44.794424) (xy 291.958522 -44.794424)
		)
		(stroke
			(width 0)
			(type solid)
		)
		(fill yes)
		(layer "F.Cu")
		(net "M_B_DQ<53>")
	)
	(gr_poly
		(pts
			(xy 291.958522 -44.349924) (xy 291.945822 -44.159424) (xy 291.844222 -44.159424) (xy 291.831522 -44.349924)
			(xy 291.831522 -44.400724) (xy 291.958522 -44.400724)
		)
		(stroke
			(width 0)
			(type solid)
		)
		(fill yes)
		(layer "F.Cu")
		(net "M_B_DQ<52>")
	)
	(gr_poly
		(pts
			(xy 292.12286 -108.674154) (xy 292.12286 -108.623354) (xy 291.99586 -108.623354) (xy 291.99586 -108.674154)
			(xy 292.00856 -108.864654) (xy 292.11016 -108.864654)
		)
		(stroke
			(width 0)
			(type solid)
		)
		(fill yes)
		(layer "F.Cu")
		(net "M_E_DQ<52>")
	)
	(gr_poly
		(pts
			(xy 292.12286 -108.280454) (xy 292.12286 -108.229654) (xy 291.99586 -108.229654) (xy 291.99586 -108.280454)
			(xy 292.00856 -108.470954) (xy 292.11016 -108.470954)
		)
		(stroke
			(width 0)
			(type solid)
		)
		(fill yes)
		(layer "F.Cu")
		(net "M_E_DQ<53>")
	)
	(gr_poly
		(pts
			(xy 292.12286 -107.886754) (xy 292.12286 -107.835954) (xy 291.99586 -107.835954) (xy 291.99586 -107.886754)
			(xy 292.00856 -108.077254) (xy 292.11016 -108.077254)
		)
		(stroke
			(width 0)
			(type solid)
		)
		(fill yes)
		(layer "F.Cu")
		(net "M_E_DQ<48>")
	)
	(gr_poly
		(pts
			(xy 292.12286 -107.493054) (xy 292.12286 -107.442254) (xy 291.99586 -107.442254) (xy 291.99586 -107.493054)
			(xy 292.00856 -107.683554) (xy 292.11016 -107.683554)
		)
		(stroke
			(width 0)
			(type solid)
		)
		(fill yes)
		(layer "F.Cu")
		(net "M_E_DQ<49>")
	)
	(gr_poly
		(pts
			(xy 292.12286 -107.099354) (xy 292.12286 -107.048554) (xy 291.99586 -107.048554) (xy 291.99586 -107.099354)
			(xy 292.00856 -107.289854) (xy 292.11016 -107.289854)
		)
		(stroke
			(width 0)
			(type solid)
		)
		(fill yes)
		(layer "F.Cu")
		(net "M_E_DQS_DP<15>")
	)
	(gr_poly
		(pts
			(xy 292.12286 -106.705654) (xy 292.12286 -106.654854) (xy 291.99586 -106.654854) (xy 291.99586 -106.705654)
			(xy 292.00856 -106.896154) (xy 292.11016 -106.896154)
		)
		(stroke
			(width 0)
			(type solid)
		)
		(fill yes)
		(layer "F.Cu")
		(net "M_E_DQS_DN<15>")
	)
	(gr_poly
		(pts
			(xy 292.12286 -106.311954) (xy 292.12286 -106.261154) (xy 291.99586 -106.261154) (xy 291.99586 -106.311954)
			(xy 292.00856 -106.502454) (xy 292.11016 -106.502454)
		)
		(stroke
			(width 0)
			(type solid)
		)
		(fill yes)
		(layer "F.Cu")
		(net "M_E_DQS_DN<6>")
	)
	(gr_poly
		(pts
			(xy 292.12286 -105.918254) (xy 292.12286 -105.867454) (xy 291.99586 -105.867454) (xy 291.99586 -105.918254)
			(xy 292.00856 -106.108754) (xy 292.11016 -106.108754)
		)
		(stroke
			(width 0)
			(type solid)
		)
		(fill yes)
		(layer "F.Cu")
		(net "M_E_DQS_DP<6>")
	)
	(gr_poly
		(pts
			(xy 292.12286 -105.524554) (xy 292.12286 -105.473754) (xy 291.99586 -105.473754) (xy 291.99586 -105.524554)
			(xy 292.00856 -105.715054) (xy 292.11016 -105.715054)
		)
		(stroke
			(width 0)
			(type solid)
		)
		(fill yes)
		(layer "F.Cu")
		(net "M_E_DQ<54>")
	)
	(gr_poly
		(pts
			(xy 292.12286 -105.130854) (xy 292.12286 -105.080054) (xy 291.99586 -105.080054) (xy 291.99586 -105.130854)
			(xy 292.00856 -105.321354) (xy 292.11016 -105.321354)
		)
		(stroke
			(width 0)
			(type solid)
		)
		(fill yes)
		(layer "F.Cu")
		(net "M_E_DQ<55>")
	)
	(gr_poly
		(pts
			(xy 292.12286 -104.737154) (xy 292.12286 -104.686354) (xy 291.99586 -104.686354) (xy 291.99586 -104.737154)
			(xy 292.00856 -104.927654) (xy 292.11016 -104.927654)
		)
		(stroke
			(width 0)
			(type solid)
		)
		(fill yes)
		(layer "F.Cu")
		(net "M_E_DQ<50>")
	)
	(gr_poly
		(pts
			(xy 292.12286 -104.343454) (xy 292.12286 -104.292654) (xy 291.99586 -104.292654) (xy 291.99586 -104.343454)
			(xy 292.00856 -104.533954) (xy 292.11016 -104.533954)
		)
		(stroke
			(width 0)
			(type solid)
		)
		(fill yes)
		(layer "F.Cu")
		(net "M_E_DQ<51>")
	)
	(gr_poly
		(pts
			(xy 292.288722 -48.782224) (xy 292.288722 -48.731424) (xy 292.161722 -48.731424) (xy 292.161722 -48.782224)
			(xy 292.174422 -48.972724) (xy 292.276022 -48.972724)
		)
		(stroke
			(width 0)
			(type solid)
		)
		(fill yes)
		(layer "F.Cu")
		(net "M_B_DQ<51>")
	)
	(gr_poly
		(pts
			(xy 292.288722 -48.388524) (xy 292.288722 -48.337724) (xy 292.161722 -48.337724) (xy 292.161722 -48.388524)
			(xy 292.174422 -48.579024) (xy 292.276022 -48.579024)
		)
		(stroke
			(width 0)
			(type solid)
		)
		(fill yes)
		(layer "F.Cu")
		(net "M_B_DQ<50>")
	)
	(gr_poly
		(pts
			(xy 292.288722 -47.994824) (xy 292.288722 -47.944024) (xy 292.161722 -47.944024) (xy 292.161722 -47.994824)
			(xy 292.174422 -48.185324) (xy 292.276022 -48.185324)
		)
		(stroke
			(width 0)
			(type solid)
		)
		(fill yes)
		(layer "F.Cu")
		(net "M_B_DQ<55>")
	)
	(gr_poly
		(pts
			(xy 292.288722 -47.601124) (xy 292.288722 -47.550324) (xy 292.161722 -47.550324) (xy 292.161722 -47.601124)
			(xy 292.174422 -47.791624) (xy 292.276022 -47.791624)
		)
		(stroke
			(width 0)
			(type solid)
		)
		(fill yes)
		(layer "F.Cu")
		(net "M_B_DQ<54>")
	)
	(gr_poly
		(pts
			(xy 292.288722 -47.207424) (xy 292.288722 -47.156624) (xy 292.161722 -47.156624) (xy 292.161722 -47.207424)
			(xy 292.174422 -47.397924) (xy 292.276022 -47.397924)
		)
		(stroke
			(width 0)
			(type solid)
		)
		(fill yes)
		(layer "F.Cu")
		(net "M_B_DQS_DP<6>")
	)
	(gr_poly
		(pts
			(xy 292.288722 -46.813724) (xy 292.288722 -46.762924) (xy 292.161722 -46.762924) (xy 292.161722 -46.813724)
			(xy 292.174422 -47.004224) (xy 292.276022 -47.004224)
		)
		(stroke
			(width 0)
			(type solid)
		)
		(fill yes)
		(layer "F.Cu")
		(net "M_B_DQS_DN<6>")
	)
	(gr_poly
		(pts
			(xy 292.288722 -46.420024) (xy 292.288722 -46.369224) (xy 292.161722 -46.369224) (xy 292.161722 -46.420024)
			(xy 292.174422 -46.610524) (xy 292.276022 -46.610524)
		)
		(stroke
			(width 0)
			(type solid)
		)
		(fill yes)
		(layer "F.Cu")
		(net "M_B_DQS_DN<15>")
	)
	(gr_poly
		(pts
			(xy 292.288722 -46.026324) (xy 292.288722 -45.975524) (xy 292.161722 -45.975524) (xy 292.161722 -46.026324)
			(xy 292.174422 -46.216824) (xy 292.276022 -46.216824)
		)
		(stroke
			(width 0)
			(type solid)
		)
		(fill yes)
		(layer "F.Cu")
		(net "M_B_DQS_DP<15>")
	)
	(gr_poly
		(pts
			(xy 292.288722 -45.632624) (xy 292.288722 -45.581824) (xy 292.161722 -45.581824) (xy 292.161722 -45.632624)
			(xy 292.174422 -45.823124) (xy 292.276022 -45.823124)
		)
		(stroke
			(width 0)
			(type solid)
		)
		(fill yes)
		(layer "F.Cu")
		(net "M_B_DQ<49>")
	)
	(gr_poly
		(pts
			(xy 292.288722 -45.238924) (xy 292.288722 -45.188124) (xy 292.161722 -45.188124) (xy 292.161722 -45.238924)
			(xy 292.174422 -45.429424) (xy 292.276022 -45.429424)
		)
		(stroke
			(width 0)
			(type solid)
		)
		(fill yes)
		(layer "F.Cu")
		(net "M_B_DQ<48>")
	)
	(gr_poly
		(pts
			(xy 292.288722 -44.845224) (xy 292.288722 -44.794424) (xy 292.161722 -44.794424) (xy 292.161722 -44.845224)
			(xy 292.174422 -45.035724) (xy 292.276022 -45.035724)
		)
		(stroke
			(width 0)
			(type solid)
		)
		(fill yes)
		(layer "F.Cu")
		(net "M_B_DQ<53>")
	)
	(gr_poly
		(pts
			(xy 292.288722 -44.451524) (xy 292.288722 -44.400724) (xy 292.161722 -44.400724) (xy 292.161722 -44.451524)
			(xy 292.174422 -44.642024) (xy 292.276022 -44.642024)
		)
		(stroke
			(width 0)
			(type solid)
		)
		(fill yes)
		(layer "F.Cu")
		(net "M_B_DQ<52>")
	)
	(gr_poly
		(pts
			(xy 292.45306 -108.572554) (xy 292.44036 -108.382054) (xy 292.33876 -108.382054) (xy 292.32606 -108.572554)
			(xy 292.32606 -108.623354) (xy 292.45306 -108.623354)
		)
		(stroke
			(width 0)
			(type solid)
		)
		(fill yes)
		(layer "F.Cu")
		(net "M_E_DQ<52>")
	)
	(gr_poly
		(pts
			(xy 292.45306 -108.178854) (xy 292.44036 -107.988354) (xy 292.33876 -107.988354) (xy 292.32606 -108.178854)
			(xy 292.32606 -108.229654) (xy 292.45306 -108.229654)
		)
		(stroke
			(width 0)
			(type solid)
		)
		(fill yes)
		(layer "F.Cu")
		(net "M_E_DQ<53>")
	)
	(gr_poly
		(pts
			(xy 292.45306 -107.785154) (xy 292.44036 -107.594654) (xy 292.33876 -107.594654) (xy 292.32606 -107.785154)
			(xy 292.32606 -107.835954) (xy 292.45306 -107.835954)
		)
		(stroke
			(width 0)
			(type solid)
		)
		(fill yes)
		(layer "F.Cu")
		(net "M_E_DQ<48>")
	)
	(gr_poly
		(pts
			(xy 292.45306 -107.391454) (xy 292.44036 -107.200954) (xy 292.33876 -107.200954) (xy 292.32606 -107.391454)
			(xy 292.32606 -107.442254) (xy 292.45306 -107.442254)
		)
		(stroke
			(width 0)
			(type solid)
		)
		(fill yes)
		(layer "F.Cu")
		(net "M_E_DQ<49>")
	)
	(gr_poly
		(pts
			(xy 292.45306 -106.997754) (xy 292.44036 -106.807254) (xy 292.33876 -106.807254) (xy 292.32606 -106.997754)
			(xy 292.32606 -107.048554) (xy 292.45306 -107.048554)
		)
		(stroke
			(width 0)
			(type solid)
		)
		(fill yes)
		(layer "F.Cu")
		(net "M_E_DQS_DP<15>")
	)
	(gr_poly
		(pts
			(xy 292.45306 -106.604054) (xy 292.44036 -106.413554) (xy 292.33876 -106.413554) (xy 292.32606 -106.604054)
			(xy 292.32606 -106.654854) (xy 292.45306 -106.654854)
		)
		(stroke
			(width 0)
			(type solid)
		)
		(fill yes)
		(layer "F.Cu")
		(net "M_E_DQS_DN<15>")
	)
	(gr_poly
		(pts
			(xy 292.45306 -106.210354) (xy 292.44036 -106.019854) (xy 292.33876 -106.019854) (xy 292.32606 -106.210354)
			(xy 292.32606 -106.261154) (xy 292.45306 -106.261154)
		)
		(stroke
			(width 0)
			(type solid)
		)
		(fill yes)
		(layer "F.Cu")
		(net "M_E_DQS_DN<6>")
	)
	(gr_poly
		(pts
			(xy 292.45306 -105.816654) (xy 292.44036 -105.626154) (xy 292.33876 -105.626154) (xy 292.32606 -105.816654)
			(xy 292.32606 -105.867454) (xy 292.45306 -105.867454)
		)
		(stroke
			(width 0)
			(type solid)
		)
		(fill yes)
		(layer "F.Cu")
		(net "M_E_DQS_DP<6>")
	)
	(gr_poly
		(pts
			(xy 292.45306 -105.422954) (xy 292.44036 -105.232454) (xy 292.33876 -105.232454) (xy 292.32606 -105.422954)
			(xy 292.32606 -105.473754) (xy 292.45306 -105.473754)
		)
		(stroke
			(width 0)
			(type solid)
		)
		(fill yes)
		(layer "F.Cu")
		(net "M_E_DQ<54>")
	)
	(gr_poly
		(pts
			(xy 292.45306 -105.029254) (xy 292.44036 -104.838754) (xy 292.33876 -104.838754) (xy 292.32606 -105.029254)
			(xy 292.32606 -105.080054) (xy 292.45306 -105.080054)
		)
		(stroke
			(width 0)
			(type solid)
		)
		(fill yes)
		(layer "F.Cu")
		(net "M_E_DQ<55>")
	)
	(gr_poly
		(pts
			(xy 292.45306 -104.635554) (xy 292.44036 -104.445054) (xy 292.33876 -104.445054) (xy 292.32606 -104.635554)
			(xy 292.32606 -104.686354) (xy 292.45306 -104.686354)
		)
		(stroke
			(width 0)
			(type solid)
		)
		(fill yes)
		(layer "F.Cu")
		(net "M_E_DQ<50>")
	)
	(gr_poly
		(pts
			(xy 292.45306 -104.241854) (xy 292.44036 -104.051354) (xy 292.33876 -104.051354) (xy 292.32606 -104.241854)
			(xy 292.32606 -104.292654) (xy 292.45306 -104.292654)
		)
		(stroke
			(width 0)
			(type solid)
		)
		(fill yes)
		(layer "F.Cu")
		(net "M_E_DQ<51>")
	)
	(gr_poly
		(pts
			(xy 292.618922 -48.680624) (xy 292.606222 -48.490124) (xy 292.504622 -48.490124) (xy 292.491922 -48.680624)
			(xy 292.491922 -48.731424) (xy 292.618922 -48.731424)
		)
		(stroke
			(width 0)
			(type solid)
		)
		(fill yes)
		(layer "F.Cu")
		(net "M_B_DQ<51>")
	)
	(gr_poly
		(pts
			(xy 292.618922 -48.286924) (xy 292.606222 -48.096424) (xy 292.504622 -48.096424) (xy 292.491922 -48.286924)
			(xy 292.491922 -48.337724) (xy 292.618922 -48.337724)
		)
		(stroke
			(width 0)
			(type solid)
		)
		(fill yes)
		(layer "F.Cu")
		(net "M_B_DQ<50>")
	)
	(gr_poly
		(pts
			(xy 292.618922 -47.893224) (xy 292.606222 -47.702724) (xy 292.504622 -47.702724) (xy 292.491922 -47.893224)
			(xy 292.491922 -47.944024) (xy 292.618922 -47.944024)
		)
		(stroke
			(width 0)
			(type solid)
		)
		(fill yes)
		(layer "F.Cu")
		(net "M_B_DQ<55>")
	)
	(gr_poly
		(pts
			(xy 292.618922 -47.499524) (xy 292.606222 -47.309024) (xy 292.504622 -47.309024) (xy 292.491922 -47.499524)
			(xy 292.491922 -47.550324) (xy 292.618922 -47.550324)
		)
		(stroke
			(width 0)
			(type solid)
		)
		(fill yes)
		(layer "F.Cu")
		(net "M_B_DQ<54>")
	)
	(gr_poly
		(pts
			(xy 292.618922 -47.105824) (xy 292.606222 -46.915324) (xy 292.504622 -46.915324) (xy 292.491922 -47.105824)
			(xy 292.491922 -47.156624) (xy 292.618922 -47.156624)
		)
		(stroke
			(width 0)
			(type solid)
		)
		(fill yes)
		(layer "F.Cu")
		(net "M_B_DQS_DP<6>")
	)
	(gr_poly
		(pts
			(xy 292.618922 -46.712124) (xy 292.606222 -46.521624) (xy 292.504622 -46.521624) (xy 292.491922 -46.712124)
			(xy 292.491922 -46.762924) (xy 292.618922 -46.762924)
		)
		(stroke
			(width 0)
			(type solid)
		)
		(fill yes)
		(layer "F.Cu")
		(net "M_B_DQS_DN<6>")
	)
	(gr_poly
		(pts
			(xy 292.618922 -46.318424) (xy 292.606222 -46.127924) (xy 292.504622 -46.127924) (xy 292.491922 -46.318424)
			(xy 292.491922 -46.369224) (xy 292.618922 -46.369224)
		)
		(stroke
			(width 0)
			(type solid)
		)
		(fill yes)
		(layer "F.Cu")
		(net "M_B_DQS_DN<15>")
	)
	(gr_poly
		(pts
			(xy 292.618922 -45.924724) (xy 292.606222 -45.734224) (xy 292.504622 -45.734224) (xy 292.491922 -45.924724)
			(xy 292.491922 -45.975524) (xy 292.618922 -45.975524)
		)
		(stroke
			(width 0)
			(type solid)
		)
		(fill yes)
		(layer "F.Cu")
		(net "M_B_DQS_DP<15>")
	)
	(gr_poly
		(pts
			(xy 292.618922 -45.531024) (xy 292.606222 -45.340524) (xy 292.504622 -45.340524) (xy 292.491922 -45.531024)
			(xy 292.491922 -45.581824) (xy 292.618922 -45.581824)
		)
		(stroke
			(width 0)
			(type solid)
		)
		(fill yes)
		(layer "F.Cu")
		(net "M_B_DQ<49>")
	)
	(gr_poly
		(pts
			(xy 292.618922 -45.137324) (xy 292.606222 -44.946824) (xy 292.504622 -44.946824) (xy 292.491922 -45.137324)
			(xy 292.491922 -45.188124) (xy 292.618922 -45.188124)
		)
		(stroke
			(width 0)
			(type solid)
		)
		(fill yes)
		(layer "F.Cu")
		(net "M_B_DQ<48>")
	)
	(gr_poly
		(pts
			(xy 292.618922 -44.743624) (xy 292.606222 -44.553124) (xy 292.504622 -44.553124) (xy 292.491922 -44.743624)
			(xy 292.491922 -44.794424) (xy 292.618922 -44.794424)
		)
		(stroke
			(width 0)
			(type solid)
		)
		(fill yes)
		(layer "F.Cu")
		(net "M_B_DQ<53>")
	)
	(gr_poly
		(pts
			(xy 292.618922 -44.349924) (xy 292.606222 -44.159424) (xy 292.504622 -44.159424) (xy 292.491922 -44.349924)
			(xy 292.491922 -44.400724) (xy 292.618922 -44.400724)
		)
		(stroke
			(width 0)
			(type solid)
		)
		(fill yes)
		(layer "F.Cu")
		(net "M_B_DQ<52>")
	)
	(gr_poly
		(pts
			(xy 292.78326 -108.674154) (xy 292.78326 -108.623354) (xy 292.65626 -108.623354) (xy 292.65626 -108.674154)
			(xy 292.66896 -108.864654) (xy 292.77056 -108.864654)
		)
		(stroke
			(width 0)
			(type solid)
		)
		(fill yes)
		(layer "F.Cu")
		(net "M_E_DQ<52>")
	)
	(gr_poly
		(pts
			(xy 292.78326 -108.280454) (xy 292.78326 -108.229654) (xy 292.65626 -108.229654) (xy 292.65626 -108.280454)
			(xy 292.66896 -108.470954) (xy 292.77056 -108.470954)
		)
		(stroke
			(width 0)
			(type solid)
		)
		(fill yes)
		(layer "F.Cu")
		(net "M_E_DQ<53>")
	)
	(gr_poly
		(pts
			(xy 292.78326 -107.886754) (xy 292.78326 -107.835954) (xy 292.65626 -107.835954) (xy 292.65626 -107.886754)
			(xy 292.66896 -108.077254) (xy 292.77056 -108.077254)
		)
		(stroke
			(width 0)
			(type solid)
		)
		(fill yes)
		(layer "F.Cu")
		(net "M_E_DQ<48>")
	)
	(gr_poly
		(pts
			(xy 292.78326 -107.493054) (xy 292.78326 -107.442254) (xy 292.65626 -107.442254) (xy 292.65626 -107.493054)
			(xy 292.66896 -107.683554) (xy 292.77056 -107.683554)
		)
		(stroke
			(width 0)
			(type solid)
		)
		(fill yes)
		(layer "F.Cu")
		(net "M_E_DQ<49>")
	)
	(gr_poly
		(pts
			(xy 292.78326 -107.099354) (xy 292.78326 -107.048554) (xy 292.65626 -107.048554) (xy 292.65626 -107.099354)
			(xy 292.66896 -107.289854) (xy 292.77056 -107.289854)
		)
		(stroke
			(width 0)
			(type solid)
		)
		(fill yes)
		(layer "F.Cu")
		(net "M_E_DQS_DP<15>")
	)
	(gr_poly
		(pts
			(xy 292.78326 -106.705654) (xy 292.78326 -106.654854) (xy 292.65626 -106.654854) (xy 292.65626 -106.705654)
			(xy 292.66896 -106.896154) (xy 292.77056 -106.896154)
		)
		(stroke
			(width 0)
			(type solid)
		)
		(fill yes)
		(layer "F.Cu")
		(net "M_E_DQS_DN<15>")
	)
	(gr_poly
		(pts
			(xy 292.78326 -106.311954) (xy 292.78326 -106.261154) (xy 292.65626 -106.261154) (xy 292.65626 -106.311954)
			(xy 292.66896 -106.502454) (xy 292.77056 -106.502454)
		)
		(stroke
			(width 0)
			(type solid)
		)
		(fill yes)
		(layer "F.Cu")
		(net "M_E_DQS_DN<6>")
	)
	(gr_poly
		(pts
			(xy 292.78326 -105.918254) (xy 292.78326 -105.867454) (xy 292.65626 -105.867454) (xy 292.65626 -105.918254)
			(xy 292.66896 -106.108754) (xy 292.77056 -106.108754)
		)
		(stroke
			(width 0)
			(type solid)
		)
		(fill yes)
		(layer "F.Cu")
		(net "M_E_DQS_DP<6>")
	)
	(gr_poly
		(pts
			(xy 292.78326 -105.524554) (xy 292.78326 -105.473754) (xy 292.65626 -105.473754) (xy 292.65626 -105.524554)
			(xy 292.66896 -105.715054) (xy 292.77056 -105.715054)
		)
		(stroke
			(width 0)
			(type solid)
		)
		(fill yes)
		(layer "F.Cu")
		(net "M_E_DQ<54>")
	)
	(gr_poly
		(pts
			(xy 292.78326 -105.130854) (xy 292.78326 -105.080054) (xy 292.65626 -105.080054) (xy 292.65626 -105.130854)
			(xy 292.66896 -105.321354) (xy 292.77056 -105.321354)
		)
		(stroke
			(width 0)
			(type solid)
		)
		(fill yes)
		(layer "F.Cu")
		(net "M_E_DQ<55>")
	)
	(gr_poly
		(pts
			(xy 292.78326 -104.737154) (xy 292.78326 -104.686354) (xy 292.65626 -104.686354) (xy 292.65626 -104.737154)
			(xy 292.66896 -104.927654) (xy 292.77056 -104.927654)
		)
		(stroke
			(width 0)
			(type solid)
		)
		(fill yes)
		(layer "F.Cu")
		(net "M_E_DQ<50>")
	)
	(gr_poly
		(pts
			(xy 292.78326 -104.343454) (xy 292.78326 -104.292654) (xy 292.65626 -104.292654) (xy 292.65626 -104.343454)
			(xy 292.66896 -104.533954) (xy 292.77056 -104.533954)
		)
		(stroke
			(width 0)
			(type solid)
		)
		(fill yes)
		(layer "F.Cu")
		(net "M_E_DQ<51>")
	)
	(gr_poly
		(pts
			(xy 292.949122 -48.782224) (xy 292.949122 -48.731424) (xy 292.822122 -48.731424) (xy 292.822122 -48.782224)
			(xy 292.834822 -48.972724) (xy 292.936422 -48.972724)
		)
		(stroke
			(width 0)
			(type solid)
		)
		(fill yes)
		(layer "F.Cu")
		(net "M_B_DQ<51>")
	)
	(gr_poly
		(pts
			(xy 292.949122 -48.388524) (xy 292.949122 -48.337724) (xy 292.822122 -48.337724) (xy 292.822122 -48.388524)
			(xy 292.834822 -48.579024) (xy 292.936422 -48.579024)
		)
		(stroke
			(width 0)
			(type solid)
		)
		(fill yes)
		(layer "F.Cu")
		(net "M_B_DQ<50>")
	)
	(gr_poly
		(pts
			(xy 292.949122 -47.994824) (xy 292.949122 -47.944024) (xy 292.822122 -47.944024) (xy 292.822122 -47.994824)
			(xy 292.834822 -48.185324) (xy 292.936422 -48.185324)
		)
		(stroke
			(width 0)
			(type solid)
		)
		(fill yes)
		(layer "F.Cu")
		(net "M_B_DQ<55>")
	)
	(gr_poly
		(pts
			(xy 292.949122 -47.601124) (xy 292.949122 -47.550324) (xy 292.822122 -47.550324) (xy 292.822122 -47.601124)
			(xy 292.834822 -47.791624) (xy 292.936422 -47.791624)
		)
		(stroke
			(width 0)
			(type solid)
		)
		(fill yes)
		(layer "F.Cu")
		(net "M_B_DQ<54>")
	)
	(gr_poly
		(pts
			(xy 292.949122 -47.207424) (xy 292.949122 -47.156624) (xy 292.822122 -47.156624) (xy 292.822122 -47.207424)
			(xy 292.834822 -47.397924) (xy 292.936422 -47.397924)
		)
		(stroke
			(width 0)
			(type solid)
		)
		(fill yes)
		(layer "F.Cu")
		(net "M_B_DQS_DP<6>")
	)
	(gr_poly
		(pts
			(xy 292.949122 -46.813724) (xy 292.949122 -46.762924) (xy 292.822122 -46.762924) (xy 292.822122 -46.813724)
			(xy 292.834822 -47.004224) (xy 292.936422 -47.004224)
		)
		(stroke
			(width 0)
			(type solid)
		)
		(fill yes)
		(layer "F.Cu")
		(net "M_B_DQS_DN<6>")
	)
	(gr_poly
		(pts
			(xy 292.949122 -46.420024) (xy 292.949122 -46.369224) (xy 292.822122 -46.369224) (xy 292.822122 -46.420024)
			(xy 292.834822 -46.610524) (xy 292.936422 -46.610524)
		)
		(stroke
			(width 0)
			(type solid)
		)
		(fill yes)
		(layer "F.Cu")
		(net "M_B_DQS_DN<15>")
	)
	(gr_poly
		(pts
			(xy 292.949122 -46.026324) (xy 292.949122 -45.975524) (xy 292.822122 -45.975524) (xy 292.822122 -46.026324)
			(xy 292.834822 -46.216824) (xy 292.936422 -46.216824)
		)
		(stroke
			(width 0)
			(type solid)
		)
		(fill yes)
		(layer "F.Cu")
		(net "M_B_DQS_DP<15>")
	)
	(gr_poly
		(pts
			(xy 292.949122 -45.632624) (xy 292.949122 -45.581824) (xy 292.822122 -45.581824) (xy 292.822122 -45.632624)
			(xy 292.834822 -45.823124) (xy 292.936422 -45.823124)
		)
		(stroke
			(width 0)
			(type solid)
		)
		(fill yes)
		(layer "F.Cu")
		(net "M_B_DQ<49>")
	)
	(gr_poly
		(pts
			(xy 292.949122 -45.238924) (xy 292.949122 -45.188124) (xy 292.822122 -45.188124) (xy 292.822122 -45.238924)
			(xy 292.834822 -45.429424) (xy 292.936422 -45.429424)
		)
		(stroke
			(width 0)
			(type solid)
		)
		(fill yes)
		(layer "F.Cu")
		(net "M_B_DQ<48>")
	)
	(gr_poly
		(pts
			(xy 292.949122 -44.845224) (xy 292.949122 -44.794424) (xy 292.822122 -44.794424) (xy 292.822122 -44.845224)
			(xy 292.834822 -45.035724) (xy 292.936422 -45.035724)
		)
		(stroke
			(width 0)
			(type solid)
		)
		(fill yes)
		(layer "F.Cu")
		(net "M_B_DQ<53>")
	)
	(gr_poly
		(pts
			(xy 292.949122 -44.451524) (xy 292.949122 -44.400724) (xy 292.822122 -44.400724) (xy 292.822122 -44.451524)
			(xy 292.834822 -44.642024) (xy 292.936422 -44.642024)
		)
		(stroke
			(width 0)
			(type solid)
		)
		(fill yes)
		(layer "F.Cu")
		(net "M_B_DQ<52>")
	)
	(gr_poly
		(pts
			(xy 293.11346 -108.572554) (xy 293.10076 -108.382054) (xy 292.99916 -108.382054) (xy 292.98646 -108.572554)
			(xy 292.98646 -108.623354) (xy 293.11346 -108.623354)
		)
		(stroke
			(width 0)
			(type solid)
		)
		(fill yes)
		(layer "F.Cu")
		(net "M_E_DQ<52>")
	)
	(gr_poly
		(pts
			(xy 293.11346 -108.178854) (xy 293.10076 -107.988354) (xy 292.99916 -107.988354) (xy 292.98646 -108.178854)
			(xy 292.98646 -108.229654) (xy 293.11346 -108.229654)
		)
		(stroke
			(width 0)
			(type solid)
		)
		(fill yes)
		(layer "F.Cu")
		(net "M_E_DQ<53>")
	)
	(gr_poly
		(pts
			(xy 293.11346 -107.785154) (xy 293.10076 -107.594654) (xy 292.99916 -107.594654) (xy 292.98646 -107.785154)
			(xy 292.98646 -107.835954) (xy 293.11346 -107.835954)
		)
		(stroke
			(width 0)
			(type solid)
		)
		(fill yes)
		(layer "F.Cu")
		(net "M_E_DQ<48>")
	)
	(gr_poly
		(pts
			(xy 293.11346 -107.391454) (xy 293.10076 -107.200954) (xy 292.99916 -107.200954) (xy 292.98646 -107.391454)
			(xy 292.98646 -107.442254) (xy 293.11346 -107.442254)
		)
		(stroke
			(width 0)
			(type solid)
		)
		(fill yes)
		(layer "F.Cu")
		(net "M_E_DQ<49>")
	)
	(gr_poly
		(pts
			(xy 293.11346 -106.997754) (xy 293.10076 -106.807254) (xy 292.99916 -106.807254) (xy 292.98646 -106.997754)
			(xy 292.98646 -107.048554) (xy 293.11346 -107.048554)
		)
		(stroke
			(width 0)
			(type solid)
		)
		(fill yes)
		(layer "F.Cu")
		(net "M_E_DQS_DP<15>")
	)
	(gr_poly
		(pts
			(xy 293.11346 -106.604054) (xy 293.10076 -106.413554) (xy 292.99916 -106.413554) (xy 292.98646 -106.604054)
			(xy 292.98646 -106.654854) (xy 293.11346 -106.654854)
		)
		(stroke
			(width 0)
			(type solid)
		)
		(fill yes)
		(layer "F.Cu")
		(net "M_E_DQS_DN<15>")
	)
	(gr_poly
		(pts
			(xy 293.11346 -106.210354) (xy 293.10076 -106.019854) (xy 292.99916 -106.019854) (xy 292.98646 -106.210354)
			(xy 292.98646 -106.261154) (xy 293.11346 -106.261154)
		)
		(stroke
			(width 0)
			(type solid)
		)
		(fill yes)
		(layer "F.Cu")
		(net "M_E_DQS_DN<6>")
	)
	(gr_poly
		(pts
			(xy 293.11346 -105.816654) (xy 293.10076 -105.626154) (xy 292.99916 -105.626154) (xy 292.98646 -105.816654)
			(xy 292.98646 -105.867454) (xy 293.11346 -105.867454)
		)
		(stroke
			(width 0)
			(type solid)
		)
		(fill yes)
		(layer "F.Cu")
		(net "M_E_DQS_DP<6>")
	)
	(gr_poly
		(pts
			(xy 293.11346 -105.422954) (xy 293.10076 -105.232454) (xy 292.99916 -105.232454) (xy 292.98646 -105.422954)
			(xy 292.98646 -105.473754) (xy 293.11346 -105.473754)
		)
		(stroke
			(width 0)
			(type solid)
		)
		(fill yes)
		(layer "F.Cu")
		(net "M_E_DQ<54>")
	)
	(gr_poly
		(pts
			(xy 293.11346 -105.029254) (xy 293.10076 -104.838754) (xy 292.99916 -104.838754) (xy 292.98646 -105.029254)
			(xy 292.98646 -105.080054) (xy 293.11346 -105.080054)
		)
		(stroke
			(width 0)
			(type solid)
		)
		(fill yes)
		(layer "F.Cu")
		(net "M_E_DQ<55>")
	)
	(gr_poly
		(pts
			(xy 293.11346 -104.635554) (xy 293.10076 -104.445054) (xy 292.99916 -104.445054) (xy 292.98646 -104.635554)
			(xy 292.98646 -104.686354) (xy 293.11346 -104.686354)
		)
		(stroke
			(width 0)
			(type solid)
		)
		(fill yes)
		(layer "F.Cu")
		(net "M_E_DQ<50>")
	)
	(gr_poly
		(pts
			(xy 293.11346 -104.241854) (xy 293.10076 -104.051354) (xy 292.99916 -104.051354) (xy 292.98646 -104.241854)
			(xy 292.98646 -104.292654) (xy 293.11346 -104.292654)
		)
		(stroke
			(width 0)
			(type solid)
		)
		(fill yes)
		(layer "F.Cu")
		(net "M_E_DQ<51>")
	)
	(gr_poly
		(pts
			(xy 293.279322 -48.680624) (xy 293.266622 -48.490124) (xy 293.165022 -48.490124) (xy 293.152322 -48.680624)
			(xy 293.152322 -48.731424) (xy 293.279322 -48.731424)
		)
		(stroke
			(width 0)
			(type solid)
		)
		(fill yes)
		(layer "F.Cu")
		(net "M_B_DQ<51>")
	)
	(gr_poly
		(pts
			(xy 293.279322 -48.286924) (xy 293.266622 -48.096424) (xy 293.165022 -48.096424) (xy 293.152322 -48.286924)
			(xy 293.152322 -48.337724) (xy 293.279322 -48.337724)
		)
		(stroke
			(width 0)
			(type solid)
		)
		(fill yes)
		(layer "F.Cu")
		(net "M_B_DQ<50>")
	)
	(gr_poly
		(pts
			(xy 293.279322 -47.893224) (xy 293.266622 -47.702724) (xy 293.165022 -47.702724) (xy 293.152322 -47.893224)
			(xy 293.152322 -47.944024) (xy 293.279322 -47.944024)
		)
		(stroke
			(width 0)
			(type solid)
		)
		(fill yes)
		(layer "F.Cu")
		(net "M_B_DQ<55>")
	)
	(gr_poly
		(pts
			(xy 293.279322 -47.499524) (xy 293.266622 -47.309024) (xy 293.165022 -47.309024) (xy 293.152322 -47.499524)
			(xy 293.152322 -47.550324) (xy 293.279322 -47.550324)
		)
		(stroke
			(width 0)
			(type solid)
		)
		(fill yes)
		(layer "F.Cu")
		(net "M_B_DQ<54>")
	)
	(gr_poly
		(pts
			(xy 293.279322 -47.105824) (xy 293.266622 -46.915324) (xy 293.165022 -46.915324) (xy 293.152322 -47.105824)
			(xy 293.152322 -47.156624) (xy 293.279322 -47.156624)
		)
		(stroke
			(width 0)
			(type solid)
		)
		(fill yes)
		(layer "F.Cu")
		(net "M_B_DQS_DP<6>")
	)
	(gr_poly
		(pts
			(xy 293.279322 -46.712124) (xy 293.266622 -46.521624) (xy 293.165022 -46.521624) (xy 293.152322 -46.712124)
			(xy 293.152322 -46.762924) (xy 293.279322 -46.762924)
		)
		(stroke
			(width 0)
			(type solid)
		)
		(fill yes)
		(layer "F.Cu")
		(net "M_B_DQS_DN<6>")
	)
	(gr_poly
		(pts
			(xy 293.279322 -46.318424) (xy 293.266622 -46.127924) (xy 293.165022 -46.127924) (xy 293.152322 -46.318424)
			(xy 293.152322 -46.369224) (xy 293.279322 -46.369224)
		)
		(stroke
			(width 0)
			(type solid)
		)
		(fill yes)
		(layer "F.Cu")
		(net "M_B_DQS_DN<15>")
	)
	(gr_poly
		(pts
			(xy 293.279322 -45.924724) (xy 293.266622 -45.734224) (xy 293.165022 -45.734224) (xy 293.152322 -45.924724)
			(xy 293.152322 -45.975524) (xy 293.279322 -45.975524)
		)
		(stroke
			(width 0)
			(type solid)
		)
		(fill yes)
		(layer "F.Cu")
		(net "M_B_DQS_DP<15>")
	)
	(gr_poly
		(pts
			(xy 293.279322 -45.531024) (xy 293.266622 -45.340524) (xy 293.165022 -45.340524) (xy 293.152322 -45.531024)
			(xy 293.152322 -45.581824) (xy 293.279322 -45.581824)
		)
		(stroke
			(width 0)
			(type solid)
		)
		(fill yes)
		(layer "F.Cu")
		(net "M_B_DQ<49>")
	)
	(gr_poly
		(pts
			(xy 293.279322 -45.137324) (xy 293.266622 -44.946824) (xy 293.165022 -44.946824) (xy 293.152322 -45.137324)
			(xy 293.152322 -45.188124) (xy 293.279322 -45.188124)
		)
		(stroke
			(width 0)
			(type solid)
		)
		(fill yes)
		(layer "F.Cu")
		(net "M_B_DQ<48>")
	)
	(gr_poly
		(pts
			(xy 293.279322 -44.743624) (xy 293.266622 -44.553124) (xy 293.165022 -44.553124) (xy 293.152322 -44.743624)
			(xy 293.152322 -44.794424) (xy 293.279322 -44.794424)
		)
		(stroke
			(width 0)
			(type solid)
		)
		(fill yes)
		(layer "F.Cu")
		(net "M_B_DQ<53>")
	)
	(gr_poly
		(pts
			(xy 293.279322 -44.349924) (xy 293.266622 -44.159424) (xy 293.165022 -44.159424) (xy 293.152322 -44.349924)
			(xy 293.152322 -44.400724) (xy 293.279322 -44.400724)
		)
		(stroke
			(width 0)
			(type solid)
		)
		(fill yes)
		(layer "F.Cu")
		(net "M_B_DQ<52>")
	)
	(gr_poly
		(pts
			(xy 293.44366 -108.674154) (xy 293.44366 -108.623354) (xy 293.31666 -108.623354) (xy 293.31666 -108.674154)
			(xy 293.32936 -108.864654) (xy 293.43096 -108.864654)
		)
		(stroke
			(width 0)
			(type solid)
		)
		(fill yes)
		(layer "F.Cu")
		(net "M_E_DQ<52>")
	)
	(gr_poly
		(pts
			(xy 293.44366 -108.280454) (xy 293.44366 -108.229654) (xy 293.31666 -108.229654) (xy 293.31666 -108.280454)
			(xy 293.32936 -108.470954) (xy 293.43096 -108.470954)
		)
		(stroke
			(width 0)
			(type solid)
		)
		(fill yes)
		(layer "F.Cu")
		(net "M_E_DQ<53>")
	)
	(gr_poly
		(pts
			(xy 293.44366 -107.886754) (xy 293.44366 -107.835954) (xy 293.31666 -107.835954) (xy 293.31666 -107.886754)
			(xy 293.32936 -108.077254) (xy 293.43096 -108.077254)
		)
		(stroke
			(width 0)
			(type solid)
		)
		(fill yes)
		(layer "F.Cu")
		(net "M_E_DQ<48>")
	)
	(gr_poly
		(pts
			(xy 293.44366 -107.493054) (xy 293.44366 -107.442254) (xy 293.31666 -107.442254) (xy 293.31666 -107.493054)
			(xy 293.32936 -107.683554) (xy 293.43096 -107.683554)
		)
		(stroke
			(width 0)
			(type solid)
		)
		(fill yes)
		(layer "F.Cu")
		(net "M_E_DQ<49>")
	)
	(gr_poly
		(pts
			(xy 293.44366 -107.099354) (xy 293.44366 -107.048554) (xy 293.31666 -107.048554) (xy 293.31666 -107.099354)
			(xy 293.32936 -107.289854) (xy 293.43096 -107.289854)
		)
		(stroke
			(width 0)
			(type solid)
		)
		(fill yes)
		(layer "F.Cu")
		(net "M_E_DQS_DP<15>")
	)
	(gr_poly
		(pts
			(xy 293.44366 -106.705654) (xy 293.44366 -106.654854) (xy 293.31666 -106.654854) (xy 293.31666 -106.705654)
			(xy 293.32936 -106.896154) (xy 293.43096 -106.896154)
		)
		(stroke
			(width 0)
			(type solid)
		)
		(fill yes)
		(layer "F.Cu")
		(net "M_E_DQS_DN<15>")
	)
	(gr_poly
		(pts
			(xy 293.44366 -106.311954) (xy 293.44366 -106.261154) (xy 293.31666 -106.261154) (xy 293.31666 -106.311954)
			(xy 293.32936 -106.502454) (xy 293.43096 -106.502454)
		)
		(stroke
			(width 0)
			(type solid)
		)
		(fill yes)
		(layer "F.Cu")
		(net "M_E_DQS_DN<6>")
	)
	(gr_poly
		(pts
			(xy 293.44366 -105.918254) (xy 293.44366 -105.867454) (xy 293.31666 -105.867454) (xy 293.31666 -105.918254)
			(xy 293.32936 -106.108754) (xy 293.43096 -106.108754)
		)
		(stroke
			(width 0)
			(type solid)
		)
		(fill yes)
		(layer "F.Cu")
		(net "M_E_DQS_DP<6>")
	)
	(gr_poly
		(pts
			(xy 293.44366 -105.524554) (xy 293.44366 -105.473754) (xy 293.31666 -105.473754) (xy 293.31666 -105.524554)
			(xy 293.32936 -105.715054) (xy 293.43096 -105.715054)
		)
		(stroke
			(width 0)
			(type solid)
		)
		(fill yes)
		(layer "F.Cu")
		(net "M_E_DQ<54>")
	)
	(gr_poly
		(pts
			(xy 293.44366 -105.130854) (xy 293.44366 -105.080054) (xy 293.31666 -105.080054) (xy 293.31666 -105.130854)
			(xy 293.32936 -105.321354) (xy 293.43096 -105.321354)
		)
		(stroke
			(width 0)
			(type solid)
		)
		(fill yes)
		(layer "F.Cu")
		(net "M_E_DQ<55>")
	)
	(gr_poly
		(pts
			(xy 293.44366 -104.737154) (xy 293.44366 -104.686354) (xy 293.31666 -104.686354) (xy 293.31666 -104.737154)
			(xy 293.32936 -104.927654) (xy 293.43096 -104.927654)
		)
		(stroke
			(width 0)
			(type solid)
		)
		(fill yes)
		(layer "F.Cu")
		(net "M_E_DQ<50>")
	)
	(gr_poly
		(pts
			(xy 293.44366 -104.343454) (xy 293.44366 -104.292654) (xy 293.31666 -104.292654) (xy 293.31666 -104.343454)
			(xy 293.32936 -104.533954) (xy 293.43096 -104.533954)
		)
		(stroke
			(width 0)
			(type solid)
		)
		(fill yes)
		(layer "F.Cu")
		(net "M_E_DQ<51>")
	)
	(gr_poly
		(pts
			(xy 293.609522 -48.782224) (xy 293.609522 -48.731424) (xy 293.482522 -48.731424) (xy 293.482522 -48.782224)
			(xy 293.495222 -48.972724) (xy 293.596822 -48.972724)
		)
		(stroke
			(width 0)
			(type solid)
		)
		(fill yes)
		(layer "F.Cu")
		(net "M_B_DQ<51>")
	)
	(gr_poly
		(pts
			(xy 293.609522 -48.388524) (xy 293.609522 -48.337724) (xy 293.482522 -48.337724) (xy 293.482522 -48.388524)
			(xy 293.495222 -48.579024) (xy 293.596822 -48.579024)
		)
		(stroke
			(width 0)
			(type solid)
		)
		(fill yes)
		(layer "F.Cu")
		(net "M_B_DQ<50>")
	)
	(gr_poly
		(pts
			(xy 293.609522 -47.994824) (xy 293.609522 -47.944024) (xy 293.482522 -47.944024) (xy 293.482522 -47.994824)
			(xy 293.495222 -48.185324) (xy 293.596822 -48.185324)
		)
		(stroke
			(width 0)
			(type solid)
		)
		(fill yes)
		(layer "F.Cu")
		(net "M_B_DQ<55>")
	)
	(gr_poly
		(pts
			(xy 293.609522 -47.601124) (xy 293.609522 -47.550324) (xy 293.482522 -47.550324) (xy 293.482522 -47.601124)
			(xy 293.495222 -47.791624) (xy 293.596822 -47.791624)
		)
		(stroke
			(width 0)
			(type solid)
		)
		(fill yes)
		(layer "F.Cu")
		(net "M_B_DQ<54>")
	)
	(gr_poly
		(pts
			(xy 293.609522 -47.207424) (xy 293.609522 -47.156624) (xy 293.482522 -47.156624) (xy 293.482522 -47.207424)
			(xy 293.495222 -47.397924) (xy 293.596822 -47.397924)
		)
		(stroke
			(width 0)
			(type solid)
		)
		(fill yes)
		(layer "F.Cu")
		(net "M_B_DQS_DP<6>")
	)
	(gr_poly
		(pts
			(xy 293.609522 -46.813724) (xy 293.609522 -46.762924) (xy 293.482522 -46.762924) (xy 293.482522 -46.813724)
			(xy 293.495222 -47.004224) (xy 293.596822 -47.004224)
		)
		(stroke
			(width 0)
			(type solid)
		)
		(fill yes)
		(layer "F.Cu")
		(net "M_B_DQS_DN<6>")
	)
	(gr_poly
		(pts
			(xy 293.609522 -46.420024) (xy 293.609522 -46.369224) (xy 293.482522 -46.369224) (xy 293.482522 -46.420024)
			(xy 293.495222 -46.610524) (xy 293.596822 -46.610524)
		)
		(stroke
			(width 0)
			(type solid)
		)
		(fill yes)
		(layer "F.Cu")
		(net "M_B_DQS_DN<15>")
	)
	(gr_poly
		(pts
			(xy 293.609522 -46.026324) (xy 293.609522 -45.975524) (xy 293.482522 -45.975524) (xy 293.482522 -46.026324)
			(xy 293.495222 -46.216824) (xy 293.596822 -46.216824)
		)
		(stroke
			(width 0)
			(type solid)
		)
		(fill yes)
		(layer "F.Cu")
		(net "M_B_DQS_DP<15>")
	)
	(gr_poly
		(pts
			(xy 293.609522 -45.632624) (xy 293.609522 -45.581824) (xy 293.482522 -45.581824) (xy 293.482522 -45.632624)
			(xy 293.495222 -45.823124) (xy 293.596822 -45.823124)
		)
		(stroke
			(width 0)
			(type solid)
		)
		(fill yes)
		(layer "F.Cu")
		(net "M_B_DQ<49>")
	)
	(gr_poly
		(pts
			(xy 293.609522 -45.238924) (xy 293.609522 -45.188124) (xy 293.482522 -45.188124) (xy 293.482522 -45.238924)
			(xy 293.495222 -45.429424) (xy 293.596822 -45.429424)
		)
		(stroke
			(width 0)
			(type solid)
		)
		(fill yes)
		(layer "F.Cu")
		(net "M_B_DQ<48>")
	)
	(gr_poly
		(pts
			(xy 293.609522 -44.845224) (xy 293.609522 -44.794424) (xy 293.482522 -44.794424) (xy 293.482522 -44.845224)
			(xy 293.495222 -45.035724) (xy 293.596822 -45.035724)
		)
		(stroke
			(width 0)
			(type solid)
		)
		(fill yes)
		(layer "F.Cu")
		(net "M_B_DQ<53>")
	)
	(gr_poly
		(pts
			(xy 293.609522 -44.451524) (xy 293.609522 -44.400724) (xy 293.482522 -44.400724) (xy 293.482522 -44.451524)
			(xy 293.495222 -44.642024) (xy 293.596822 -44.642024)
		)
		(stroke
			(width 0)
			(type solid)
		)
		(fill yes)
		(layer "F.Cu")
		(net "M_B_DQ<52>")
	)
	(gr_poly
		(pts
			(xy 293.77386 -108.572554) (xy 293.76116 -108.382054) (xy 293.65956 -108.382054) (xy 293.64686 -108.572554)
			(xy 293.64686 -108.623354) (xy 293.77386 -108.623354)
		)
		(stroke
			(width 0)
			(type solid)
		)
		(fill yes)
		(layer "F.Cu")
		(net "M_E_DQ<52>")
	)
	(gr_poly
		(pts
			(xy 293.77386 -108.178854) (xy 293.76116 -107.988354) (xy 293.65956 -107.988354) (xy 293.64686 -108.178854)
			(xy 293.64686 -108.229654) (xy 293.77386 -108.229654)
		)
		(stroke
			(width 0)
			(type solid)
		)
		(fill yes)
		(layer "F.Cu")
		(net "M_E_DQ<53>")
	)
	(gr_poly
		(pts
			(xy 293.77386 -107.785154) (xy 293.76116 -107.594654) (xy 293.65956 -107.594654) (xy 293.64686 -107.785154)
			(xy 293.64686 -107.835954) (xy 293.77386 -107.835954)
		)
		(stroke
			(width 0)
			(type solid)
		)
		(fill yes)
		(layer "F.Cu")
		(net "M_E_DQ<48>")
	)
	(gr_poly
		(pts
			(xy 293.77386 -107.391454) (xy 293.76116 -107.200954) (xy 293.65956 -107.200954) (xy 293.64686 -107.391454)
			(xy 293.64686 -107.442254) (xy 293.77386 -107.442254)
		)
		(stroke
			(width 0)
			(type solid)
		)
		(fill yes)
		(layer "F.Cu")
		(net "M_E_DQ<49>")
	)
	(gr_poly
		(pts
			(xy 293.77386 -106.997754) (xy 293.76116 -106.807254) (xy 293.65956 -106.807254) (xy 293.64686 -106.997754)
			(xy 293.64686 -107.048554) (xy 293.77386 -107.048554)
		)
		(stroke
			(width 0)
			(type solid)
		)
		(fill yes)
		(layer "F.Cu")
		(net "M_E_DQS_DP<15>")
	)
	(gr_poly
		(pts
			(xy 293.77386 -106.604054) (xy 293.76116 -106.413554) (xy 293.65956 -106.413554) (xy 293.64686 -106.604054)
			(xy 293.64686 -106.654854) (xy 293.77386 -106.654854)
		)
		(stroke
			(width 0)
			(type solid)
		)
		(fill yes)
		(layer "F.Cu")
		(net "M_E_DQS_DN<15>")
	)
	(gr_poly
		(pts
			(xy 293.77386 -106.210354) (xy 293.76116 -106.019854) (xy 293.65956 -106.019854) (xy 293.64686 -106.210354)
			(xy 293.64686 -106.261154) (xy 293.77386 -106.261154)
		)
		(stroke
			(width 0)
			(type solid)
		)
		(fill yes)
		(layer "F.Cu")
		(net "M_E_DQS_DN<6>")
	)
	(gr_poly
		(pts
			(xy 293.77386 -105.816654) (xy 293.76116 -105.626154) (xy 293.65956 -105.626154) (xy 293.64686 -105.816654)
			(xy 293.64686 -105.867454) (xy 293.77386 -105.867454)
		)
		(stroke
			(width 0)
			(type solid)
		)
		(fill yes)
		(layer "F.Cu")
		(net "M_E_DQS_DP<6>")
	)
	(gr_poly
		(pts
			(xy 293.77386 -105.422954) (xy 293.76116 -105.232454) (xy 293.65956 -105.232454) (xy 293.64686 -105.422954)
			(xy 293.64686 -105.473754) (xy 293.77386 -105.473754)
		)
		(stroke
			(width 0)
			(type solid)
		)
		(fill yes)
		(layer "F.Cu")
		(net "M_E_DQ<54>")
	)
	(gr_poly
		(pts
			(xy 293.77386 -105.029254) (xy 293.76116 -104.838754) (xy 293.65956 -104.838754) (xy 293.64686 -105.029254)
			(xy 293.64686 -105.080054) (xy 293.77386 -105.080054)
		)
		(stroke
			(width 0)
			(type solid)
		)
		(fill yes)
		(layer "F.Cu")
		(net "M_E_DQ<55>")
	)
	(gr_poly
		(pts
			(xy 293.77386 -104.635554) (xy 293.76116 -104.445054) (xy 293.65956 -104.445054) (xy 293.64686 -104.635554)
			(xy 293.64686 -104.686354) (xy 293.77386 -104.686354)
		)
		(stroke
			(width 0)
			(type solid)
		)
		(fill yes)
		(layer "F.Cu")
		(net "M_E_DQ<50>")
	)
	(gr_poly
		(pts
			(xy 293.77386 -104.241854) (xy 293.76116 -104.051354) (xy 293.65956 -104.051354) (xy 293.64686 -104.241854)
			(xy 293.64686 -104.292654) (xy 293.77386 -104.292654)
		)
		(stroke
			(width 0)
			(type solid)
		)
		(fill yes)
		(layer "F.Cu")
		(net "M_E_DQ<51>")
	)
	(gr_poly
		(pts
			(xy 293.939722 -48.680624) (xy 293.927022 -48.490124) (xy 293.825422 -48.490124) (xy 293.812722 -48.680624)
			(xy 293.812722 -48.731424) (xy 293.939722 -48.731424)
		)
		(stroke
			(width 0)
			(type solid)
		)
		(fill yes)
		(layer "F.Cu")
		(net "M_B_DQ<51>")
	)
	(gr_poly
		(pts
			(xy 293.939722 -48.286924) (xy 293.927022 -48.096424) (xy 293.825422 -48.096424) (xy 293.812722 -48.286924)
			(xy 293.812722 -48.337724) (xy 293.939722 -48.337724)
		)
		(stroke
			(width 0)
			(type solid)
		)
		(fill yes)
		(layer "F.Cu")
		(net "M_B_DQ<50>")
	)
	(gr_poly
		(pts
			(xy 293.939722 -47.893224) (xy 293.927022 -47.702724) (xy 293.825422 -47.702724) (xy 293.812722 -47.893224)
			(xy 293.812722 -47.944024) (xy 293.939722 -47.944024)
		)
		(stroke
			(width 0)
			(type solid)
		)
		(fill yes)
		(layer "F.Cu")
		(net "M_B_DQ<55>")
	)
	(gr_poly
		(pts
			(xy 293.939722 -47.499524) (xy 293.927022 -47.309024) (xy 293.825422 -47.309024) (xy 293.812722 -47.499524)
			(xy 293.812722 -47.550324) (xy 293.939722 -47.550324)
		)
		(stroke
			(width 0)
			(type solid)
		)
		(fill yes)
		(layer "F.Cu")
		(net "M_B_DQ<54>")
	)
	(gr_poly
		(pts
			(xy 293.939722 -47.105824) (xy 293.927022 -46.915324) (xy 293.825422 -46.915324) (xy 293.812722 -47.105824)
			(xy 293.812722 -47.156624) (xy 293.939722 -47.156624)
		)
		(stroke
			(width 0)
			(type solid)
		)
		(fill yes)
		(layer "F.Cu")
		(net "M_B_DQS_DP<6>")
	)
	(gr_poly
		(pts
			(xy 293.939722 -46.712124) (xy 293.927022 -46.521624) (xy 293.825422 -46.521624) (xy 293.812722 -46.712124)
			(xy 293.812722 -46.762924) (xy 293.939722 -46.762924)
		)
		(stroke
			(width 0)
			(type solid)
		)
		(fill yes)
		(layer "F.Cu")
		(net "M_B_DQS_DN<6>")
	)
	(gr_poly
		(pts
			(xy 293.939722 -46.318424) (xy 293.927022 -46.127924) (xy 293.825422 -46.127924) (xy 293.812722 -46.318424)
			(xy 293.812722 -46.369224) (xy 293.939722 -46.369224)
		)
		(stroke
			(width 0)
			(type solid)
		)
		(fill yes)
		(layer "F.Cu")
		(net "M_B_DQS_DN<15>")
	)
	(gr_poly
		(pts
			(xy 293.939722 -45.924724) (xy 293.927022 -45.734224) (xy 293.825422 -45.734224) (xy 293.812722 -45.924724)
			(xy 293.812722 -45.975524) (xy 293.939722 -45.975524)
		)
		(stroke
			(width 0)
			(type solid)
		)
		(fill yes)
		(layer "F.Cu")
		(net "M_B_DQS_DP<15>")
	)
	(gr_poly
		(pts
			(xy 293.939722 -45.531024) (xy 293.927022 -45.340524) (xy 293.825422 -45.340524) (xy 293.812722 -45.531024)
			(xy 293.812722 -45.581824) (xy 293.939722 -45.581824)
		)
		(stroke
			(width 0)
			(type solid)
		)
		(fill yes)
		(layer "F.Cu")
		(net "M_B_DQ<49>")
	)
	(gr_poly
		(pts
			(xy 294.00373 -44.615608) (xy 293.967916 -44.57954) (xy 293.824152 -44.45381) (xy 293.75227 -44.525692)
			(xy 293.878 -44.669456) (xy 293.914068 -44.70527)
		)
		(stroke
			(width 0)
			(type solid)
		)
		(fill yes)
		(layer "F.Cu")
		(net "M_B_DQ<53>")
	)
	(gr_poly
		(pts
			(xy 294.10406 -108.674154) (xy 294.10406 -108.623354) (xy 293.97706 -108.623354) (xy 293.97706 -108.674154)
			(xy 293.98976 -108.864654) (xy 294.09136 -108.864654)
		)
		(stroke
			(width 0)
			(type solid)
		)
		(fill yes)
		(layer "F.Cu")
		(net "M_E_DQ<52>")
	)
	(gr_poly
		(pts
			(xy 294.10406 -108.280454) (xy 294.10406 -108.229654) (xy 293.97706 -108.229654) (xy 293.97706 -108.280454)
			(xy 293.98976 -108.470954) (xy 294.09136 -108.470954)
		)
		(stroke
			(width 0)
			(type solid)
		)
		(fill yes)
		(layer "F.Cu")
		(net "M_E_DQ<53>")
	)
	(gr_poly
		(pts
			(xy 294.10406 -107.886754) (xy 294.10406 -107.835954) (xy 293.97706 -107.835954) (xy 293.97706 -107.886754)
			(xy 293.98976 -108.077254) (xy 294.09136 -108.077254)
		)
		(stroke
			(width 0)
			(type solid)
		)
		(fill yes)
		(layer "F.Cu")
		(net "M_E_DQ<48>")
	)
	(gr_poly
		(pts
			(xy 294.10406 -107.493054) (xy 294.10406 -107.442254) (xy 293.97706 -107.442254) (xy 293.97706 -107.493054)
			(xy 293.98976 -107.683554) (xy 294.09136 -107.683554)
		)
		(stroke
			(width 0)
			(type solid)
		)
		(fill yes)
		(layer "F.Cu")
		(net "M_E_DQ<49>")
	)
	(gr_poly
		(pts
			(xy 294.10406 -107.099354) (xy 294.10406 -107.048554) (xy 293.97706 -107.048554) (xy 293.97706 -107.099354)
			(xy 293.98976 -107.289854) (xy 294.09136 -107.289854)
		)
		(stroke
			(width 0)
			(type solid)
		)
		(fill yes)
		(layer "F.Cu")
		(net "M_E_DQS_DP<15>")
	)
	(gr_poly
		(pts
			(xy 294.10406 -106.705654) (xy 294.10406 -106.654854) (xy 293.97706 -106.654854) (xy 293.97706 -106.705654)
			(xy 293.98976 -106.896154) (xy 294.09136 -106.896154)
		)
		(stroke
			(width 0)
			(type solid)
		)
		(fill yes)
		(layer "F.Cu")
		(net "M_E_DQS_DN<15>")
	)
	(gr_poly
		(pts
			(xy 294.10406 -106.311954) (xy 294.10406 -106.261154) (xy 293.97706 -106.261154) (xy 293.97706 -106.311954)
			(xy 293.98976 -106.502454) (xy 294.09136 -106.502454)
		)
		(stroke
			(width 0)
			(type solid)
		)
		(fill yes)
		(layer "F.Cu")
		(net "M_E_DQS_DN<6>")
	)
	(gr_poly
		(pts
			(xy 294.10406 -105.918254) (xy 294.10406 -105.867454) (xy 293.97706 -105.867454) (xy 293.97706 -105.918254)
			(xy 293.98976 -106.108754) (xy 294.09136 -106.108754)
		)
		(stroke
			(width 0)
			(type solid)
		)
		(fill yes)
		(layer "F.Cu")
		(net "M_E_DQS_DP<6>")
	)
	(gr_poly
		(pts
			(xy 294.10406 -105.524554) (xy 294.10406 -105.473754) (xy 293.97706 -105.473754) (xy 293.97706 -105.524554)
			(xy 293.98976 -105.715054) (xy 294.09136 -105.715054)
		)
		(stroke
			(width 0)
			(type solid)
		)
		(fill yes)
		(layer "F.Cu")
		(net "M_E_DQ<54>")
	)
	(gr_poly
		(pts
			(xy 294.10406 -105.130854) (xy 294.10406 -105.080054) (xy 293.97706 -105.080054) (xy 293.97706 -105.130854)
			(xy 293.98976 -105.321354) (xy 294.09136 -105.321354)
		)
		(stroke
			(width 0)
			(type solid)
		)
		(fill yes)
		(layer "F.Cu")
		(net "M_E_DQ<55>")
	)
	(gr_poly
		(pts
			(xy 294.10406 -104.737154) (xy 294.10406 -104.686354) (xy 293.97706 -104.686354) (xy 293.97706 -104.737154)
			(xy 293.98976 -104.927654) (xy 294.09136 -104.927654)
		)
		(stroke
			(width 0)
			(type solid)
		)
		(fill yes)
		(layer "F.Cu")
		(net "M_E_DQ<50>")
	)
	(gr_poly
		(pts
			(xy 294.10406 -104.343454) (xy 294.10406 -104.292654) (xy 293.97706 -104.292654) (xy 293.97706 -104.343454)
			(xy 293.98976 -104.533954) (xy 294.09136 -104.533954)
		)
		(stroke
			(width 0)
			(type solid)
		)
		(fill yes)
		(layer "F.Cu")
		(net "M_E_DQ<51>")
	)
	(gr_poly
		(pts
			(xy 294.120316 -44.283122) (xy 293.99484 -44.139358) (xy 293.958772 -44.103544) (xy 293.86911 -44.193206)
			(xy 293.904924 -44.229274) (xy 294.048688 -44.355004)
		)
		(stroke
			(width 0)
			(type solid)
		)
		(fill yes)
		(layer "F.Cu")
		(net "M_B_DQ<52>")
	)
	(gr_poly
		(pts
			(xy 294.192198 -43.870118) (xy 294.156384 -43.83405) (xy 294.01262 -43.70832) (xy 293.940738 -43.780202)
			(xy 294.066468 -43.923966) (xy 294.102536 -43.95978)
		)
		(stroke
			(width 0)
			(type solid)
		)
		(fill yes)
		(layer "F.Cu")
		(net "M_B_DQ<52>")
	)
	(gr_poly
		(pts
			(xy 294.269922 -48.782224) (xy 294.269922 -48.731424) (xy 294.142922 -48.731424) (xy 294.142922 -48.782224)
			(xy 294.155622 -48.972724) (xy 294.257222 -48.972724)
		)
		(stroke
			(width 0)
			(type solid)
		)
		(fill yes)
		(layer "F.Cu")
		(net "M_B_DQ<51>")
	)
	(gr_poly
		(pts
			(xy 294.269922 -48.388524) (xy 294.269922 -48.337724) (xy 294.142922 -48.337724) (xy 294.142922 -48.388524)
			(xy 294.155622 -48.579024) (xy 294.257222 -48.579024)
		)
		(stroke
			(width 0)
			(type solid)
		)
		(fill yes)
		(layer "F.Cu")
		(net "M_B_DQ<50>")
	)
	(gr_poly
		(pts
			(xy 294.269922 -47.994824) (xy 294.269922 -47.944024) (xy 294.142922 -47.944024) (xy 294.142922 -47.994824)
			(xy 294.155622 -48.185324) (xy 294.257222 -48.185324)
		)
		(stroke
			(width 0)
			(type solid)
		)
		(fill yes)
		(layer "F.Cu")
		(net "M_B_DQ<55>")
	)
	(gr_poly
		(pts
			(xy 294.269922 -47.601124) (xy 294.269922 -47.550324) (xy 294.142922 -47.550324) (xy 294.142922 -47.601124)
			(xy 294.155622 -47.791624) (xy 294.257222 -47.791624)
		)
		(stroke
			(width 0)
			(type solid)
		)
		(fill yes)
		(layer "F.Cu")
		(net "M_B_DQ<54>")
	)
	(gr_poly
		(pts
			(xy 294.269922 -47.207424) (xy 294.269922 -47.156624) (xy 294.142922 -47.156624) (xy 294.142922 -47.207424)
			(xy 294.155622 -47.397924) (xy 294.257222 -47.397924)
		)
		(stroke
			(width 0)
			(type solid)
		)
		(fill yes)
		(layer "F.Cu")
		(net "M_B_DQS_DP<6>")
	)
	(gr_poly
		(pts
			(xy 294.269922 -46.813724) (xy 294.269922 -46.762924) (xy 294.142922 -46.762924) (xy 294.142922 -46.813724)
			(xy 294.155622 -47.004224) (xy 294.257222 -47.004224)
		)
		(stroke
			(width 0)
			(type solid)
		)
		(fill yes)
		(layer "F.Cu")
		(net "M_B_DQS_DN<6>")
	)
	(gr_poly
		(pts
			(xy 294.269922 -46.420024) (xy 294.269922 -46.369224) (xy 294.142922 -46.369224) (xy 294.142922 -46.420024)
			(xy 294.155622 -46.610524) (xy 294.257222 -46.610524)
		)
		(stroke
			(width 0)
			(type solid)
		)
		(fill yes)
		(layer "F.Cu")
		(net "M_B_DQS_DN<15>")
	)
	(gr_poly
		(pts
			(xy 294.269922 -46.026324) (xy 294.269922 -45.975524) (xy 294.142922 -45.975524) (xy 294.142922 -46.026324)
			(xy 294.155622 -46.216824) (xy 294.257222 -46.216824)
		)
		(stroke
			(width 0)
			(type solid)
		)
		(fill yes)
		(layer "F.Cu")
		(net "M_B_DQS_DP<15>")
	)
	(gr_poly
		(pts
			(xy 294.282368 -44.893992) (xy 294.2463 -44.858178) (xy 294.10279 -44.732448) (xy 294.030908 -44.80433)
			(xy 294.156638 -44.94784) (xy 294.192452 -44.983908)
		)
		(stroke
			(width 0)
			(type solid)
		)
		(fill yes)
		(layer "F.Cu")
		(net "M_B_DQ<48>")
	)
	(gr_poly
		(pts
			(xy 294.398954 -44.56176) (xy 294.273224 -44.417996) (xy 294.23741 -44.381928) (xy 294.147494 -44.471844)
			(xy 294.183308 -44.507658) (xy 294.327072 -44.633388)
		)
		(stroke
			(width 0)
			(type solid)
		)
		(fill yes)
		(layer "F.Cu")
		(net "M_B_DQ<53>")
	)
	(gr_poly
		(pts
			(xy 294.43426 -108.572554) (xy 294.42156 -108.382054) (xy 294.31996 -108.382054) (xy 294.30726 -108.572554)
			(xy 294.30726 -108.623354) (xy 294.43426 -108.623354)
		)
		(stroke
			(width 0)
			(type solid)
		)
		(fill yes)
		(layer "F.Cu")
		(net "M_E_DQ<52>")
	)
	(gr_poly
		(pts
			(xy 294.43426 -108.178854) (xy 294.42156 -107.988354) (xy 294.31996 -107.988354) (xy 294.30726 -108.178854)
			(xy 294.30726 -108.229654) (xy 294.43426 -108.229654)
		)
		(stroke
			(width 0)
			(type solid)
		)
		(fill yes)
		(layer "F.Cu")
		(net "M_E_DQ<53>")
	)
	(gr_poly
		(pts
			(xy 294.43426 -107.785154) (xy 294.42156 -107.594654) (xy 294.31996 -107.594654) (xy 294.30726 -107.785154)
			(xy 294.30726 -107.835954) (xy 294.43426 -107.835954)
		)
		(stroke
			(width 0)
			(type solid)
		)
		(fill yes)
		(layer "F.Cu")
		(net "M_E_DQ<48>")
	)
	(gr_poly
		(pts
			(xy 294.43426 -107.391454) (xy 294.42156 -107.200954) (xy 294.31996 -107.200954) (xy 294.30726 -107.391454)
			(xy 294.30726 -107.442254) (xy 294.43426 -107.442254)
		)
		(stroke
			(width 0)
			(type solid)
		)
		(fill yes)
		(layer "F.Cu")
		(net "M_E_DQ<49>")
	)
	(gr_poly
		(pts
			(xy 294.43426 -106.997754) (xy 294.42156 -106.807254) (xy 294.31996 -106.807254) (xy 294.30726 -106.997754)
			(xy 294.30726 -107.048554) (xy 294.43426 -107.048554)
		)
		(stroke
			(width 0)
			(type solid)
		)
		(fill yes)
		(layer "F.Cu")
		(net "M_E_DQS_DP<15>")
	)
	(gr_poly
		(pts
			(xy 294.43426 -106.604054) (xy 294.42156 -106.413554) (xy 294.31996 -106.413554) (xy 294.30726 -106.604054)
			(xy 294.30726 -106.654854) (xy 294.43426 -106.654854)
		)
		(stroke
			(width 0)
			(type solid)
		)
		(fill yes)
		(layer "F.Cu")
		(net "M_E_DQS_DN<15>")
	)
	(gr_poly
		(pts
			(xy 294.43426 -106.210354) (xy 294.42156 -106.019854) (xy 294.31996 -106.019854) (xy 294.30726 -106.210354)
			(xy 294.30726 -106.261154) (xy 294.43426 -106.261154)
		)
		(stroke
			(width 0)
			(type solid)
		)
		(fill yes)
		(layer "F.Cu")
		(net "M_E_DQS_DN<6>")
	)
	(gr_poly
		(pts
			(xy 294.43426 -105.816654) (xy 294.42156 -105.626154) (xy 294.31996 -105.626154) (xy 294.30726 -105.816654)
			(xy 294.30726 -105.867454) (xy 294.43426 -105.867454)
		)
		(stroke
			(width 0)
			(type solid)
		)
		(fill yes)
		(layer "F.Cu")
		(net "M_E_DQS_DP<6>")
	)
	(gr_poly
		(pts
			(xy 294.43426 -105.422954) (xy 294.42156 -105.232454) (xy 294.31996 -105.232454) (xy 294.30726 -105.422954)
			(xy 294.30726 -105.473754) (xy 294.43426 -105.473754)
		)
		(stroke
			(width 0)
			(type solid)
		)
		(fill yes)
		(layer "F.Cu")
		(net "M_E_DQ<54>")
	)
	(gr_poly
		(pts
			(xy 294.43426 -105.029254) (xy 294.42156 -104.838754) (xy 294.31996 -104.838754) (xy 294.30726 -105.029254)
			(xy 294.30726 -105.080054) (xy 294.43426 -105.080054)
		)
		(stroke
			(width 0)
			(type solid)
		)
		(fill yes)
		(layer "F.Cu")
		(net "M_E_DQ<55>")
	)
	(gr_poly
		(pts
			(xy 294.43426 -104.635554) (xy 294.42156 -104.445054) (xy 294.31996 -104.445054) (xy 294.30726 -104.635554)
			(xy 294.30726 -104.686354) (xy 294.43426 -104.686354)
		)
		(stroke
			(width 0)
			(type solid)
		)
		(fill yes)
		(layer "F.Cu")
		(net "M_E_DQ<50>")
	)
	(gr_poly
		(pts
			(xy 294.43426 -104.241854) (xy 294.42156 -104.051354) (xy 294.31996 -104.051354) (xy 294.30726 -104.241854)
			(xy 294.30726 -104.292654) (xy 294.43426 -104.292654)
		)
		(stroke
			(width 0)
			(type solid)
		)
		(fill yes)
		(layer "F.Cu")
		(net "M_E_DQ<51>")
	)
	(gr_poly
		(pts
			(xy 294.470836 -44.148502) (xy 294.434768 -44.112688) (xy 294.291258 -43.986958) (xy 294.219376 -44.05884)
			(xy 294.345106 -44.20235) (xy 294.38092 -44.238418)
		)
		(stroke
			(width 0)
			(type solid)
		)
		(fill yes)
		(layer "F.Cu")
		(net "M_B_DQ<53>")
	)
	(gr_poly
		(pts
			(xy 294.489124 -45.585634) (xy 294.363394 -45.44187) (xy 294.327326 -45.406056) (xy 294.237664 -45.495718)
			(xy 294.273478 -45.531786) (xy 294.417242 -45.657516)
		)
		(stroke
			(width 0)
			(type solid)
		)
		(fill yes)
		(layer "F.Cu")
		(net "M_B_DQ<49>")
	)
	(gr_poly
		(pts
			(xy 294.560752 -45.17263) (xy 294.524938 -45.136562) (xy 294.381174 -45.010832) (xy 294.309292 -45.082714)
			(xy 294.435022 -45.226478) (xy 294.47109 -45.262292)
		)
		(stroke
			(width 0)
			(type solid)
		)
		(fill yes)
		(layer "F.Cu")
		(net "M_B_DQ<49>")
	)
	(gr_poly
		(pts
			(xy 294.587422 -43.81627) (xy 294.461692 -43.672506) (xy 294.425878 -43.636438) (xy 294.335962 -43.726354)
			(xy 294.371776 -43.762168) (xy 294.51554 -43.887898)
		)
		(stroke
			(width 0)
			(type solid)
		)
		(fill yes)
		(layer "F.Cu")
		(net "M_B_DQ<52>")
	)
	(gr_poly
		(pts
			(xy 294.600122 -48.680624) (xy 294.587422 -48.490124) (xy 294.485822 -48.490124) (xy 294.473122 -48.680624)
			(xy 294.473122 -48.731424) (xy 294.600122 -48.731424)
		)
		(stroke
			(width 0)
			(type solid)
		)
		(fill yes)
		(layer "F.Cu")
		(net "M_B_DQ<51>")
	)
	(gr_poly
		(pts
			(xy 294.600122 -48.286924) (xy 294.587422 -48.096424) (xy 294.485822 -48.096424) (xy 294.473122 -48.286924)
			(xy 294.473122 -48.337724) (xy 294.600122 -48.337724)
		)
		(stroke
			(width 0)
			(type solid)
		)
		(fill yes)
		(layer "F.Cu")
		(net "M_B_DQ<50>")
	)
	(gr_poly
		(pts
			(xy 294.600122 -47.893224) (xy 294.587422 -47.702724) (xy 294.485822 -47.702724) (xy 294.473122 -47.893224)
			(xy 294.473122 -47.944024) (xy 294.600122 -47.944024)
		)
		(stroke
			(width 0)
			(type solid)
		)
		(fill yes)
		(layer "F.Cu")
		(net "M_B_DQ<55>")
	)
	(gr_poly
		(pts
			(xy 294.600122 -47.499524) (xy 294.587422 -47.309024) (xy 294.485822 -47.309024) (xy 294.473122 -47.499524)
			(xy 294.473122 -47.550324) (xy 294.600122 -47.550324)
		)
		(stroke
			(width 0)
			(type solid)
		)
		(fill yes)
		(layer "F.Cu")
		(net "M_B_DQ<54>")
	)
	(gr_poly
		(pts
			(xy 294.600122 -47.105824) (xy 294.587422 -46.915324) (xy 294.485822 -46.915324) (xy 294.473122 -47.105824)
			(xy 294.473122 -47.156624) (xy 294.600122 -47.156624)
		)
		(stroke
			(width 0)
			(type solid)
		)
		(fill yes)
		(layer "F.Cu")
		(net "M_B_DQS_DP<6>")
	)
	(gr_poly
		(pts
			(xy 294.650922 -46.196504) (xy 294.614854 -46.16069) (xy 294.471344 -46.03496) (xy 294.399462 -46.106842)
			(xy 294.525192 -46.250352) (xy 294.561006 -46.28642)
		)
		(stroke
			(width 0)
			(type solid)
		)
		(fill yes)
		(layer "F.Cu")
		(net "M_B_DQS_DN<15>")
	)
	(gr_poly
		(pts
			(xy 294.659304 -43.403012) (xy 294.623236 -43.367198) (xy 294.479726 -43.241468) (xy 294.407844 -43.31335)
			(xy 294.533574 -43.45686) (xy 294.569388 -43.492928)
		)
		(stroke
			(width 0)
			(type solid)
		)
		(fill yes)
		(layer "F.Cu")
		(net "M_B_DQ<52>")
	)
	(gr_poly
		(pts
			(xy 294.677338 -44.840144) (xy 294.551862 -44.69638) (xy 294.515794 -44.660566) (xy 294.426132 -44.750228)
			(xy 294.461946 -44.786296) (xy 294.60571 -44.912026)
		)
		(stroke
			(width 0)
			(type solid)
		)
		(fill yes)
		(layer "F.Cu")
		(net "M_B_DQ<48>")
	)
	(gr_poly
		(pts
			(xy 294.74922 -44.42714) (xy 294.713406 -44.391072) (xy 294.569642 -44.265342) (xy 294.49776 -44.337224)
			(xy 294.62349 -44.480988) (xy 294.659558 -44.516802)
		)
		(stroke
			(width 0)
			(type solid)
		)
		(fill yes)
		(layer "F.Cu")
		(net "M_B_DQ<48>")
	)
	(gr_poly
		(pts
			(xy 294.75938 -108.744766) (xy 294.88511 -108.601002) (xy 294.813228 -108.529374) (xy 294.669464 -108.655104)
			(xy 294.63365 -108.690918) (xy 294.723566 -108.780834)
		)
		(stroke
			(width 0)
			(type solid)
		)
		(fill yes)
		(layer "F.Cu")
		(net "M_E_DQ<52>")
	)
	(gr_poly
		(pts
			(xy 294.76446 -107.886754) (xy 294.76446 -107.835954) (xy 294.63746 -107.835954) (xy 294.63746 -107.886754)
			(xy 294.65016 -108.077254) (xy 294.75176 -108.077254)
		)
		(stroke
			(width 0)
			(type solid)
		)
		(fill yes)
		(layer "F.Cu")
		(net "M_E_DQ<48>")
	)
	(gr_poly
		(pts
			(xy 294.76446 -107.493054) (xy 294.76446 -107.442254) (xy 294.63746 -107.442254) (xy 294.63746 -107.493054)
			(xy 294.65016 -107.683554) (xy 294.75176 -107.683554)
		)
		(stroke
			(width 0)
			(type solid)
		)
		(fill yes)
		(layer "F.Cu")
		(net "M_E_DQ<49>")
	)
	(gr_poly
		(pts
			(xy 294.76446 -107.099354) (xy 294.76446 -107.048554) (xy 294.63746 -107.048554) (xy 294.63746 -107.099354)
			(xy 294.65016 -107.289854) (xy 294.75176 -107.289854)
		)
		(stroke
			(width 0)
			(type solid)
		)
		(fill yes)
		(layer "F.Cu")
		(net "M_E_DQS_DP<15>")
	)
	(gr_poly
		(pts
			(xy 294.76446 -106.705654) (xy 294.76446 -106.654854) (xy 294.63746 -106.654854) (xy 294.63746 -106.705654)
			(xy 294.65016 -106.896154) (xy 294.75176 -106.896154)
		)
		(stroke
			(width 0)
			(type solid)
		)
		(fill yes)
		(layer "F.Cu")
		(net "M_E_DQS_DN<15>")
	)
	(gr_poly
		(pts
			(xy 294.76446 -106.311954) (xy 294.76446 -106.261154) (xy 294.63746 -106.261154) (xy 294.63746 -106.311954)
			(xy 294.65016 -106.502454) (xy 294.75176 -106.502454)
		)
		(stroke
			(width 0)
			(type solid)
		)
		(fill yes)
		(layer "F.Cu")
		(net "M_E_DQS_DN<6>")
	)
	(gr_poly
		(pts
			(xy 294.76446 -105.918254) (xy 294.76446 -105.867454) (xy 294.63746 -105.867454) (xy 294.63746 -105.918254)
			(xy 294.65016 -106.108754) (xy 294.75176 -106.108754)
		)
		(stroke
			(width 0)
			(type solid)
		)
		(fill yes)
		(layer "F.Cu")
		(net "M_E_DQS_DP<6>")
	)
	(gr_poly
		(pts
			(xy 294.76446 -105.524554) (xy 294.76446 -105.473754) (xy 294.63746 -105.473754) (xy 294.63746 -105.524554)
			(xy 294.65016 -105.715054) (xy 294.75176 -105.715054)
		)
		(stroke
			(width 0)
			(type solid)
		)
		(fill yes)
		(layer "F.Cu")
		(net "M_E_DQ<54>")
	)
	(gr_poly
		(pts
			(xy 294.76446 -105.130854) (xy 294.76446 -105.080054) (xy 294.63746 -105.080054) (xy 294.63746 -105.130854)
			(xy 294.65016 -105.321354) (xy 294.75176 -105.321354)
		)
		(stroke
			(width 0)
			(type solid)
		)
		(fill yes)
		(layer "F.Cu")
		(net "M_E_DQ<55>")
	)
	(gr_poly
		(pts
			(xy 294.76446 -104.737154) (xy 294.76446 -104.686354) (xy 294.63746 -104.686354) (xy 294.63746 -104.737154)
			(xy 294.65016 -104.927654) (xy 294.75176 -104.927654)
		)
		(stroke
			(width 0)
			(type solid)
		)
		(fill yes)
		(layer "F.Cu")
		(net "M_E_DQ<50>")
	)
	(gr_poly
		(pts
			(xy 294.76446 -104.343454) (xy 294.76446 -104.292654) (xy 294.63746 -104.292654) (xy 294.63746 -104.343454)
			(xy 294.65016 -104.533954) (xy 294.75176 -104.533954)
		)
		(stroke
			(width 0)
			(type solid)
		)
		(fill yes)
		(layer "F.Cu")
		(net "M_E_DQ<51>")
	)
	(gr_poly
		(pts
			(xy 294.767508 -45.864272) (xy 294.641778 -45.720508) (xy 294.605964 -45.68444) (xy 294.516048 -45.774356)
			(xy 294.551862 -45.81017) (xy 294.695626 -45.9359)
		)
		(stroke
			(width 0)
			(type solid)
		)
		(fill yes)
		(layer "F.Cu")
		(net "M_B_DQS_DP<15>")
	)
	(gr_poly
		(pts
			(xy 294.83939 -45.451014) (xy 294.803322 -45.4152) (xy 294.659812 -45.28947) (xy 294.58793 -45.361352)
			(xy 294.71366 -45.504862) (xy 294.749474 -45.54093)
		)
		(stroke
			(width 0)
			(type solid)
		)
		(fill yes)
		(layer "F.Cu")
		(net "M_B_DQS_DP<15>")
	)
	(gr_poly
		(pts
			(xy 294.865806 -44.094654) (xy 294.740076 -43.95089) (xy 294.704262 -43.915076) (xy 294.6146 -44.004738)
			(xy 294.650414 -44.040806) (xy 294.794178 -44.166536)
		)
		(stroke
			(width 0)
			(type solid)
		)
		(fill yes)
		(layer "F.Cu")
		(net "M_B_DQ<53>")
	)
	(gr_poly
		(pts
			(xy 294.920924 -109.050074) (xy 294.956992 -109.01426) (xy 294.867076 -108.924344) (xy 294.831262 -108.960412)
			(xy 294.705532 -109.103922) (xy 294.777414 -109.175804)
		)
		(stroke
			(width 0)
			(type solid)
		)
		(fill yes)
		(layer "F.Cu")
		(net "M_E_DQ<52>")
	)
	(gr_poly
		(pts
			(xy 294.929306 -46.475142) (xy 294.893492 -46.439074) (xy 294.749728 -46.313344) (xy 294.677846 -46.385226)
			(xy 294.803576 -46.52899) (xy 294.839644 -46.564804)
		)
		(stroke
			(width 0)
			(type solid)
		)
		(fill yes)
		(layer "F.Cu")
		(net "M_B_DQS_DN<6>")
	)
	(gr_poly
		(pts
			(xy 294.930322 -48.782224) (xy 294.930322 -48.731424) (xy 294.803322 -48.731424) (xy 294.803322 -48.782224)
			(xy 294.816022 -48.972724) (xy 294.917622 -48.972724)
		)
		(stroke
			(width 0)
			(type solid)
		)
		(fill yes)
		(layer "F.Cu")
		(net "M_B_DQ<51>")
	)
	(gr_poly
		(pts
			(xy 294.930322 -48.388524) (xy 294.930322 -48.337724) (xy 294.803322 -48.337724) (xy 294.803322 -48.388524)
			(xy 294.816022 -48.579024) (xy 294.917622 -48.579024)
		)
		(stroke
			(width 0)
			(type solid)
		)
		(fill yes)
		(layer "F.Cu")
		(net "M_B_DQ<50>")
	)
	(gr_poly
		(pts
			(xy 294.937688 -43.68165) (xy 294.901874 -43.645582) (xy 294.75811 -43.519852) (xy 294.686228 -43.591734)
			(xy 294.811958 -43.735498) (xy 294.848026 -43.771312)
		)
		(stroke
			(width 0)
			(type solid)
		)
		(fill yes)
		(layer "F.Cu")
		(net "M_B_DQ<53>")
	)
	(gr_poly
		(pts
			(xy 294.955976 -45.118782) (xy 294.830246 -44.975018) (xy 294.794432 -44.93895) (xy 294.704516 -45.028866)
			(xy 294.74033 -45.06468) (xy 294.884094 -45.19041)
		)
		(stroke
			(width 0)
			(type solid)
		)
		(fill yes)
		(layer "F.Cu")
		(net "M_B_DQ<49>")
	)
	(gr_poly
		(pts
			(xy 295.027858 -44.705524) (xy 294.99179 -44.66971) (xy 294.84828 -44.54398) (xy 294.776398 -44.615862)
			(xy 294.902128 -44.759372) (xy 294.937942 -44.79544)
		)
		(stroke
			(width 0)
			(type solid)
		)
		(fill yes)
		(layer "F.Cu")
		(net "M_B_DQ<49>")
	)
	(gr_poly
		(pts
			(xy 295.037764 -108.466382) (xy 295.163494 -108.322618) (xy 295.091866 -108.250736) (xy 294.948102 -108.376466)
			(xy 294.912034 -108.41228) (xy 295.00195 -108.502196)
		)
		(stroke
			(width 0)
			(type solid)
		)
		(fill yes)
		(layer "F.Cu")
		(net "M_E_DQ<53>")
	)
	(gr_poly
		(pts
			(xy 295.046146 -46.142656) (xy 294.920416 -45.998892) (xy 294.884348 -45.963078) (xy 294.794686 -46.05274)
			(xy 294.8305 -46.088808) (xy 294.974264 -46.214538)
		)
		(stroke
			(width 0)
			(type solid)
		)
		(fill yes)
		(layer "F.Cu")
		(net "M_B_DQS_DN<15>")
	)
	(gr_poly
		(pts
			(xy 295.09466 -106.997754) (xy 295.08196 -106.807254) (xy 294.98036 -106.807254) (xy 294.96766 -106.997754)
			(xy 294.96766 -107.048554) (xy 295.09466 -107.048554)
		)
		(stroke
			(width 0)
			(type solid)
		)
		(fill yes)
		(layer "F.Cu")
		(net "M_E_DQS_DP<15>")
	)
	(gr_poly
		(pts
			(xy 295.09466 -106.604054) (xy 295.08196 -106.413554) (xy 294.98036 -106.413554) (xy 294.96766 -106.604054)
			(xy 294.96766 -106.654854) (xy 295.09466 -106.654854)
		)
		(stroke
			(width 0)
			(type solid)
		)
		(fill yes)
		(layer "F.Cu")
		(net "M_E_DQS_DN<15>")
	)
	(gr_poly
		(pts
			(xy 295.09466 -106.210354) (xy 295.08196 -106.019854) (xy 294.98036 -106.019854) (xy 294.96766 -106.210354)
			(xy 294.96766 -106.261154) (xy 295.09466 -106.261154)
		)
		(stroke
			(width 0)
			(type solid)
		)
		(fill yes)
		(layer "F.Cu")
		(net "M_E_DQS_DN<6>")
	)
	(gr_poly
		(pts
			(xy 295.09466 -105.816654) (xy 295.08196 -105.626154) (xy 294.98036 -105.626154) (xy 294.96766 -105.816654)
			(xy 294.96766 -105.867454) (xy 295.09466 -105.867454)
		)
		(stroke
			(width 0)
			(type solid)
		)
		(fill yes)
		(layer "F.Cu")
		(net "M_E_DQS_DP<6>")
	)
	(gr_poly
		(pts
			(xy 295.09466 -105.422954) (xy 295.08196 -105.232454) (xy 294.98036 -105.232454) (xy 294.96766 -105.422954)
			(xy 294.96766 -105.473754) (xy 295.09466 -105.473754)
		)
		(stroke
			(width 0)
			(type solid)
		)
		(fill yes)
		(layer "F.Cu")
		(net "M_E_DQ<54>")
	)
	(gr_poly
		(pts
			(xy 295.09466 -105.029254) (xy 295.08196 -104.838754) (xy 294.98036 -104.838754) (xy 294.96766 -105.029254)
			(xy 294.96766 -105.080054) (xy 295.09466 -105.080054)
		)
		(stroke
			(width 0)
			(type solid)
		)
		(fill yes)
		(layer "F.Cu")
		(net "M_E_DQ<55>")
	)
	(gr_poly
		(pts
			(xy 295.09466 -104.635554) (xy 295.08196 -104.445054) (xy 294.98036 -104.445054) (xy 294.96766 -104.635554)
			(xy 294.96766 -104.686354) (xy 295.09466 -104.686354)
		)
		(stroke
			(width 0)
			(type solid)
		)
		(fill yes)
		(layer "F.Cu")
		(net "M_E_DQ<50>")
	)
	(gr_poly
		(pts
			(xy 295.09466 -104.241854) (xy 295.08196 -104.051354) (xy 294.98036 -104.051354) (xy 294.96766 -104.241854)
			(xy 294.96766 -104.292654) (xy 295.09466 -104.292654)
		)
		(stroke
			(width 0)
			(type solid)
		)
		(fill yes)
		(layer "F.Cu")
		(net "M_E_DQ<51>")
	)
	(gr_poly
		(pts
			(xy 295.117774 -45.729652) (xy 295.08196 -45.693584) (xy 294.938196 -45.567854) (xy 294.866314 -45.639736)
			(xy 294.992044 -45.7835) (xy 295.028112 -45.819314)
		)
		(stroke
			(width 0)
			(type solid)
		)
		(fill yes)
		(layer "F.Cu")
		(net "M_B_DQS_DN<15>")
	)
	(gr_poly
		(pts
			(xy 295.136062 -47.16653) (xy 295.010332 -47.02302) (xy 294.974518 -46.986952) (xy 294.884602 -47.076868)
			(xy 294.920416 -47.112682) (xy 295.06418 -47.238412)
		)
		(stroke
			(width 0)
			(type solid)
		)
		(fill yes)
		(layer "F.Cu")
		(net "M_B_DQS_DP<6>")
	)
	(gr_poly
		(pts
			(xy 295.144444 -44.373292) (xy 295.018714 -44.229528) (xy 294.9829 -44.19346) (xy 294.892984 -44.283376)
			(xy 294.928798 -44.31919) (xy 295.072562 -44.44492)
		)
		(stroke
			(width 0)
			(type solid)
		)
		(fill yes)
		(layer "F.Cu")
		(net "M_B_DQ<48>")
	)
	(gr_poly
		(pts
			(xy 295.199562 -108.77169) (xy 295.235376 -108.735622) (xy 295.145714 -108.64596) (xy 295.109646 -108.681774)
			(xy 294.983916 -108.825538) (xy 295.055798 -108.89742)
		)
		(stroke
			(width 0)
			(type solid)
		)
		(fill yes)
		(layer "F.Cu")
		(net "M_E_DQ<53>")
	)
	(gr_poly
		(pts
			(xy 295.207944 -46.753526) (xy 295.171876 -46.717712) (xy 295.028366 -46.591982) (xy 294.956484 -46.663864)
			(xy 295.082214 -46.807374) (xy 295.118028 -46.843442)
		)
		(stroke
			(width 0)
			(type solid)
		)
		(fill yes)
		(layer "F.Cu")
		(net "M_B_DQS_DP<6>")
	)
	(gr_poly
		(pts
			(xy 295.216326 -43.960034) (xy 295.180258 -43.92422) (xy 295.036748 -43.79849) (xy 294.964866 -43.870372)
			(xy 295.090596 -44.013882) (xy 295.12641 -44.04995)
		)
		(stroke
			(width 0)
			(type solid)
		)
		(fill yes)
		(layer "F.Cu")
		(net "M_B_DQ<48>")
	)
	(gr_poly
		(pts
			(xy 295.226232 -109.211872) (xy 295.351962 -109.068108) (xy 295.280334 -108.996226) (xy 295.13657 -109.121956)
			(xy 295.100502 -109.15777) (xy 295.190418 -109.247686)
		)
		(stroke
			(width 0)
			(type solid)
		)
		(fill yes)
		(layer "F.Cu")
		(net "M_E_DQ<52>")
	)
	(gr_poly
		(pts
			(xy 295.23436 -45.397166) (xy 295.108884 -45.253402) (xy 295.072816 -45.217588) (xy 294.983154 -45.30725)
			(xy 295.018968 -45.343318) (xy 295.162732 -45.469048)
		)
		(stroke
			(width 0)
			(type solid)
		)
		(fill yes)
		(layer "F.Cu")
		(net "M_B_DQS_DP<15>")
	)
	(gr_poly
		(pts
			(xy 295.289478 -107.747562) (xy 295.325546 -107.711748) (xy 295.23563 -107.621832) (xy 295.199816 -107.6579)
			(xy 295.074086 -107.80141) (xy 295.145968 -107.873292)
		)
		(stroke
			(width 0)
			(type solid)
		)
		(fill yes)
		(layer "F.Cu")
		(net "M_E_DQ<49>")
	)
	(gr_poly
		(pts
			(xy 295.29786 -47.777654) (xy 295.262046 -47.741586) (xy 295.118282 -47.615856) (xy 295.0464 -47.687738)
			(xy 295.17213 -47.831502) (xy 295.208198 -47.867316)
		)
		(stroke
			(width 0)
			(type solid)
		)
		(fill yes)
		(layer "F.Cu")
		(net "M_B_DQ<55>")
	)
	(gr_poly
		(pts
			(xy 295.306242 -44.984162) (xy 295.270428 -44.948094) (xy 295.126664 -44.822364) (xy 295.054782 -44.894246)
			(xy 295.180512 -45.03801) (xy 295.21658 -45.073824)
		)
		(stroke
			(width 0)
			(type solid)
		)
		(fill yes)
		(layer "F.Cu")
		(net "M_B_DQS_DP<15>")
	)
	(gr_poly
		(pts
			(xy 295.316402 -108.187744) (xy 295.442132 -108.04398) (xy 295.37025 -107.972352) (xy 295.226486 -108.098082)
			(xy 295.190672 -108.133896) (xy 295.280588 -108.223812)
		)
		(stroke
			(width 0)
			(type solid)
		)
		(fill yes)
		(layer "F.Cu")
		(net "M_E_DQ<48>")
	)
	(gr_poly
		(pts
			(xy 295.32453 -46.421294) (xy 295.1988 -46.27753) (xy 295.162986 -46.241462) (xy 295.07307 -46.331378)
			(xy 295.108884 -46.367192) (xy 295.252648 -46.492922)
		)
		(stroke
			(width 0)
			(type solid)
		)
		(fill yes)
		(layer "F.Cu")
		(net "M_B_DQS_DN<6>")
	)
	(gr_poly
		(pts
			(xy 295.332912 -43.627802) (xy 295.207182 -43.484038) (xy 295.171368 -43.44797) (xy 295.081452 -43.537886)
			(xy 295.117266 -43.5737) (xy 295.26103 -43.69943)
		)
		(stroke
			(width 0)
			(type solid)
		)
		(fill yes)
		(layer "F.Cu")
		(net "M_B_DQ<53>")
	)
	(gr_poly
		(pts
			(xy 295.38803 -109.51718) (xy 295.423844 -109.481112) (xy 295.334182 -109.39145) (xy 295.298114 -109.427264)
			(xy 295.172384 -109.571028) (xy 295.244266 -109.64291)
		)
		(stroke
			(width 0)
			(type solid)
		)
		(fill yes)
		(layer "F.Cu")
		(net "M_E_DQ<52>")
	)
	(gr_poly
		(pts
			(xy 295.396412 -46.008036) (xy 295.360344 -45.972222) (xy 295.216834 -45.846492) (xy 295.144952 -45.918374)
			(xy 295.270682 -46.061884) (xy 295.306496 -46.097952)
		)
		(stroke
			(width 0)
			(type solid)
		)
		(fill yes)
		(layer "F.Cu")
		(net "M_B_DQS_DN<6>")
	)
	(gr_poly
		(pts
			(xy 295.406318 -107.16387) (xy 295.532048 -107.020106) (xy 295.46042 -106.948224) (xy 295.316656 -107.073954)
			(xy 295.280842 -107.110022) (xy 295.370504 -107.199684)
		)
		(stroke
			(width 0)
			(type solid)
		)
		(fill yes)
		(layer "F.Cu")
		(net "M_E_DQS_DP<15>")
	)
	(gr_poly
		(pts
			(xy 295.4147 -47.445168) (xy 295.28897 -47.301404) (xy 295.252902 -47.26559) (xy 295.16324 -47.355252)
			(xy 295.199054 -47.39132) (xy 295.342818 -47.51705)
		)
		(stroke
			(width 0)
			(type solid)
		)
		(fill yes)
		(layer "F.Cu")
		(net "M_B_DQ<54>")
	)
	(gr_poly
		(pts
			(xy 295.422828 -44.651676) (xy 295.297098 -44.507912) (xy 295.261284 -44.472098) (xy 295.171622 -44.56176)
			(xy 295.207436 -44.597828) (xy 295.3512 -44.723558)
		)
		(stroke
			(width 0)
			(type solid)
		)
		(fill yes)
		(layer "F.Cu")
		(net "M_B_DQ<49>")
	)
	(gr_poly
		(pts
			(xy 295.42486 -106.311954) (xy 295.42486 -106.261154) (xy 295.29786 -106.261154) (xy 295.29786 -106.311954)
			(xy 295.31056 -106.502454) (xy 295.41216 -106.502454)
		)
		(stroke
			(width 0)
			(type solid)
		)
		(fill yes)
		(layer "F.Cu")
		(net "M_E_DQS_DN<6>")
	)
	(gr_poly
		(pts
			(xy 295.42486 -105.918254) (xy 295.42486 -105.867454) (xy 295.29786 -105.867454) (xy 295.29786 -105.918254)
			(xy 295.31056 -106.108754) (xy 295.41216 -106.108754)
		)
		(stroke
			(width 0)
			(type solid)
		)
		(fill yes)
		(layer "F.Cu")
		(net "M_E_DQS_DP<6>")
	)
	(gr_poly
		(pts
			(xy 295.42486 -105.524554) (xy 295.42486 -105.473754) (xy 295.29786 -105.473754) (xy 295.29786 -105.524554)
			(xy 295.31056 -105.715054) (xy 295.41216 -105.715054)
		)
		(stroke
			(width 0)
			(type solid)
		)
		(fill yes)
		(layer "F.Cu")
		(net "M_E_DQ<54>")
	)
	(gr_poly
		(pts
			(xy 295.42486 -105.130854) (xy 295.42486 -105.080054) (xy 295.29786 -105.080054) (xy 295.29786 -105.130854)
			(xy 295.31056 -105.321354) (xy 295.41216 -105.321354)
		)
		(stroke
			(width 0)
			(type solid)
		)
		(fill yes)
		(layer "F.Cu")
		(net "M_E_DQ<55>")
	)
	(gr_poly
		(pts
			(xy 295.42486 -104.737154) (xy 295.42486 -104.686354) (xy 295.29786 -104.686354) (xy 295.29786 -104.737154)
			(xy 295.31056 -104.927654) (xy 295.41216 -104.927654)
		)
		(stroke
			(width 0)
			(type solid)
		)
		(fill yes)
		(layer "F.Cu")
		(net "M_E_DQ<50>")
	)
	(gr_poly
		(pts
			(xy 295.42486 -104.343454) (xy 295.42486 -104.292654) (xy 295.29786 -104.292654) (xy 295.29786 -104.343454)
			(xy 295.31056 -104.533954) (xy 295.41216 -104.533954)
		)
		(stroke
			(width 0)
			(type solid)
		)
		(fill yes)
		(layer "F.Cu")
		(net "M_E_DQ<51>")
	)
	(gr_poly
		(pts
			(xy 295.477946 -108.493052) (xy 295.514014 -108.457238) (xy 295.424098 -108.367322) (xy 295.388284 -108.40339)
			(xy 295.262554 -108.5469) (xy 295.334436 -108.618782)
		)
		(stroke
			(width 0)
			(type solid)
		)
		(fill yes)
		(layer "F.Cu")
		(net "M_E_DQ<48>")
	)
	(gr_poly
		(pts
			(xy 295.486328 -47.032164) (xy 295.450514 -46.996096) (xy 295.30675 -46.870366) (xy 295.234868 -46.942248)
			(xy 295.360598 -47.086012) (xy 295.396666 -47.121826)
		)
		(stroke
			(width 0)
			(type solid)
		)
		(fill yes)
		(layer "F.Cu")
		(net "M_B_DQ<54>")
	)
	(gr_poly
		(pts
			(xy 295.49471 -44.238672) (xy 295.458896 -44.202604) (xy 295.315132 -44.076874) (xy 295.24325 -44.148756)
			(xy 295.36898 -44.29252) (xy 295.405048 -44.328334)
		)
		(stroke
			(width 0)
			(type solid)
		)
		(fill yes)
		(layer "F.Cu")
		(net "M_B_DQ<49>")
	)
	(gr_poly
		(pts
			(xy 295.50487 -108.933234) (xy 295.6306 -108.78947) (xy 295.558718 -108.717842) (xy 295.414954 -108.843572)
			(xy 295.37914 -108.879386) (xy 295.469056 -108.969302)
		)
		(stroke
			(width 0)
			(type solid)
		)
		(fill yes)
		(layer "F.Cu")
		(net "M_E_DQ<53>")
	)
	(gr_poly
		(pts
			(xy 295.512998 -45.675804) (xy 295.387268 -45.53204) (xy 295.351454 -45.495972) (xy 295.261538 -45.585888)
			(xy 295.297352 -45.621702) (xy 295.441116 -45.747432)
		)
		(stroke
			(width 0)
			(type solid)
		)
		(fill yes)
		(layer "F.Cu")
		(net "M_B_DQS_DN<15>")
	)
	(gr_poly
		(pts
			(xy 295.568116 -107.469178) (xy 295.60393 -107.43311) (xy 295.514268 -107.343448) (xy 295.4782 -107.379262)
			(xy 295.35247 -107.523026) (xy 295.424352 -107.594908)
		)
		(stroke
			(width 0)
			(type solid)
		)
		(fill yes)
		(layer "F.Cu")
		(net "M_E_DQS_DP<15>")
	)
	(gr_poly
		(pts
			(xy 295.576498 -48.056038) (xy 295.54043 -48.020224) (xy 295.39692 -47.894494) (xy 295.325038 -47.966376)
			(xy 295.450768 -48.109886) (xy 295.486582 -48.145954)
		)
		(stroke
			(width 0)
			(type solid)
		)
		(fill yes)
		(layer "F.Cu")
		(net "M_B_DQ<50>")
	)
	(gr_poly
		(pts
			(xy 295.58488 -45.262546) (xy 295.548812 -45.226732) (xy 295.405302 -45.101002) (xy 295.33342 -45.172884)
			(xy 295.45915 -45.316394) (xy 295.494964 -45.352462)
		)
		(stroke
			(width 0)
			(type solid)
		)
		(fill yes)
		(layer "F.Cu")
		(net "M_B_DQS_DN<15>")
	)
	(gr_poly
		(pts
			(xy 295.594786 -107.90936) (xy 295.720516 -107.765596) (xy 295.648888 -107.693714) (xy 295.505124 -107.819444)
			(xy 295.469056 -107.855258) (xy 295.558972 -107.945174)
		)
		(stroke
			(width 0)
			(type solid)
		)
		(fill yes)
		(layer "F.Cu")
		(net "M_E_DQ<49>")
	)
	(gr_poly
		(pts
			(xy 295.603168 -46.699678) (xy 295.477438 -46.555914) (xy 295.44137 -46.5201) (xy 295.351708 -46.609762)
			(xy 295.387522 -46.64583) (xy 295.531286 -46.77156)
		)
		(stroke
			(width 0)
			(type solid)
		)
		(fill yes)
		(layer "F.Cu")
		(net "M_B_DQS_DP<6>")
	)
	(gr_poly
		(pts
			(xy 295.611296 -43.906186) (xy 295.485566 -43.762422) (xy 295.449752 -43.726608) (xy 295.359836 -43.816524)
			(xy 295.395904 -43.852338) (xy 295.539668 -43.978068)
		)
		(stroke
			(width 0)
			(type solid)
		)
		(fill yes)
		(layer "F.Cu")
		(net "M_B_DQ<48>")
	)
	(gr_poly
		(pts
			(xy 295.666414 -109.238542) (xy 295.702482 -109.202728) (xy 295.612566 -109.112812) (xy 295.576752 -109.14888)
			(xy 295.451022 -109.29239) (xy 295.522904 -109.364272)
		)
		(stroke
			(width 0)
			(type solid)
		)
		(fill yes)
		(layer "F.Cu")
		(net "M_E_DQ<53>")
	)
	(gr_poly
		(pts
			(xy 295.674796 -46.286674) (xy 295.638982 -46.250606) (xy 295.495218 -46.124876) (xy 295.423336 -46.196758)
			(xy 295.549066 -46.340522) (xy 295.585134 -46.376336)
		)
		(stroke
			(width 0)
			(type solid)
		)
		(fill yes)
		(layer "F.Cu")
		(net "M_B_DQS_DP<6>")
	)
	(gr_poly
		(pts
			(xy 295.683178 -43.493182) (xy 295.647364 -43.457114) (xy 295.5036 -43.331384) (xy 295.431718 -43.403266)
			(xy 295.557448 -43.54703) (xy 295.593516 -43.582844)
		)
		(stroke
			(width 0)
			(type solid)
		)
		(fill yes)
		(layer "F.Cu")
		(net "M_B_DQ<48>")
	)
	(gr_poly
		(pts
			(xy 295.684956 -106.885232) (xy 295.810686 -106.741468) (xy 295.738804 -106.66984) (xy 295.59504 -106.79557)
			(xy 295.559226 -106.831384) (xy 295.649142 -106.9213)
		)
		(stroke
			(width 0)
			(type solid)
		)
		(fill yes)
		(layer "F.Cu")
		(net "M_E_DQS_DN<15>")
	)
	(gr_poly
		(pts
			(xy 295.693084 -47.723552) (xy 295.567354 -47.580042) (xy 295.53154 -47.543974) (xy 295.441624 -47.63389)
			(xy 295.477438 -47.669704) (xy 295.621202 -47.795434)
		)
		(stroke
			(width 0)
			(type solid)
		)
		(fill yes)
		(layer "F.Cu")
		(net "M_B_DQ<55>")
	)
	(gr_poly
		(pts
			(xy 295.693338 -109.678724) (xy 295.819068 -109.53496) (xy 295.747186 -109.463332) (xy 295.603422 -109.589062)
			(xy 295.567608 -109.624876) (xy 295.65727 -109.714538)
		)
		(stroke
			(width 0)
			(type solid)
		)
		(fill yes)
		(layer "F.Cu")
		(net "M_E_DQ<52>")
	)
	(gr_poly
		(pts
			(xy 295.701466 -44.930314) (xy 295.575736 -44.78655) (xy 295.539922 -44.750482) (xy 295.450006 -44.840398)
			(xy 295.48582 -44.876212) (xy 295.629584 -45.001942)
		)
		(stroke
			(width 0)
			(type solid)
		)
		(fill yes)
		(layer "F.Cu")
		(net "M_B_DQS_DP<15>")
	)
	(gr_poly
		(pts
			(xy 295.75506 -105.422954) (xy 295.74236 -105.232454) (xy 295.64076 -105.232454) (xy 295.62806 -105.422954)
			(xy 295.62806 -105.473754) (xy 295.75506 -105.473754)
		)
		(stroke
			(width 0)
			(type solid)
		)
		(fill yes)
		(layer "F.Cu")
		(net "M_E_DQ<54>")
	)
	(gr_poly
		(pts
			(xy 295.75506 -105.029254) (xy 295.74236 -104.838754) (xy 295.64076 -104.838754) (xy 295.62806 -105.029254)
			(xy 295.62806 -105.080054) (xy 295.75506 -105.080054)
		)
		(stroke
			(width 0)
			(type solid)
		)
		(fill yes)
		(layer "F.Cu")
		(net "M_E_DQ<55>")
	)
	(gr_poly
		(pts
			(xy 295.75506 -104.635554) (xy 295.74236 -104.445054) (xy 295.64076 -104.445054) (xy 295.62806 -104.635554)
			(xy 295.62806 -104.686354) (xy 295.75506 -104.686354)
		)
		(stroke
			(width 0)
			(type solid)
		)
		(fill yes)
		(layer "F.Cu")
		(net "M_E_DQ<50>")
	)
	(gr_poly
		(pts
			(xy 295.75506 -104.241854) (xy 295.74236 -104.051354) (xy 295.64076 -104.051354) (xy 295.62806 -104.241854)
			(xy 295.62806 -104.292654) (xy 295.75506 -104.292654)
		)
		(stroke
			(width 0)
			(type solid)
		)
		(fill yes)
		(layer "F.Cu")
		(net "M_E_DQ<51>")
	)
	(gr_poly
		(pts
			(xy 295.756584 -108.214668) (xy 295.792398 -108.1786) (xy 295.702736 -108.088938) (xy 295.666668 -108.124752)
			(xy 295.540938 -108.268516) (xy 295.61282 -108.340398)
		)
		(stroke
			(width 0)
			(type solid)
		)
		(fill yes)
		(layer "F.Cu")
		(net "M_E_DQ<49>")
	)
	(gr_poly
		(pts
			(xy 295.764966 -47.310548) (xy 295.728898 -47.274734) (xy 295.585388 -47.149004) (xy 295.513506 -47.220886)
			(xy 295.639236 -47.364396) (xy 295.67505 -47.400464)
		)
		(stroke
			(width 0)
			(type solid)
		)
		(fill yes)
		(layer "F.Cu")
		(net "M_B_DQ<55>")
	)
	(gr_poly
		(pts
			(xy 295.773348 -44.517056) (xy 295.73728 -44.481242) (xy 295.59377 -44.355512) (xy 295.521888 -44.427394)
			(xy 295.647618 -44.570904) (xy 295.683432 -44.606972)
		)
		(stroke
			(width 0)
			(type solid)
		)
		(fill yes)
		(layer "F.Cu")
		(net "M_B_DQS_DP<15>")
	)
	(gr_poly
		(pts
			(xy 295.783254 -108.65485) (xy 295.908984 -108.511086) (xy 295.837356 -108.439204) (xy 295.693592 -108.564934)
			(xy 295.657524 -108.600748) (xy 295.74744 -108.690664)
		)
		(stroke
			(width 0)
			(type solid)
		)
		(fill yes)
		(layer "F.Cu")
		(net "M_E_DQ<48>")
	)
	(gr_poly
		(pts
			(xy 295.783254 -48.74768) (xy 295.657524 -48.603916) (xy 295.621456 -48.568102) (xy 295.531794 -48.657764)
			(xy 295.567608 -48.693832) (xy 295.711372 -48.819562)
		)
		(stroke
			(width 0)
			(type solid)
		)
		(fill yes)
		(layer "F.Cu")
		(net "M_B_DQ<51>")
	)
	(gr_poly
		(pts
			(xy 295.791382 -45.954188) (xy 295.665906 -45.810424) (xy 295.629838 -45.77461) (xy 295.540176 -45.864272)
			(xy 295.57599 -45.90034) (xy 295.719754 -46.02607)
		)
		(stroke
			(width 0)
			(type solid)
		)
		(fill yes)
		(layer "F.Cu")
		(net "M_B_DQS_DN<6>")
	)
	(gr_poly
		(pts
			(xy 295.8465 -107.19054) (xy 295.882568 -107.154726) (xy 295.792652 -107.06481) (xy 295.756838 -107.100878)
			(xy 295.631108 -107.244388) (xy 295.70299 -107.31627)
		)
		(stroke
			(width 0)
			(type solid)
		)
		(fill yes)
		(layer "F.Cu")
		(net "M_E_DQS_DN<15>")
	)
	(gr_poly
		(pts
			(xy 295.854882 -109.984032) (xy 295.89095 -109.948218) (xy 295.801034 -109.858302) (xy 295.76522 -109.89437)
			(xy 295.63949 -110.03788) (xy 295.711372 -110.109762)
		)
		(stroke
			(width 0)
			(type solid)
		)
		(fill yes)
		(layer "F.Cu")
		(net "M_E_DQ<52>")
	)
	(gr_poly
		(pts
			(xy 295.854882 -48.334676) (xy 295.819068 -48.298608) (xy 295.675304 -48.172878) (xy 295.603422 -48.24476)
			(xy 295.729152 -48.388524) (xy 295.76522 -48.424338)
		)
		(stroke
			(width 0)
			(type solid)
		)
		(fill yes)
		(layer "F.Cu")
		(net "M_B_DQ<51>")
	)
	(gr_poly
		(pts
			(xy 295.863264 -45.541184) (xy 295.82745 -45.505116) (xy 295.683686 -45.379386) (xy 295.611804 -45.451268)
			(xy 295.737534 -45.595032) (xy 295.773602 -45.630846)
		)
		(stroke
			(width 0)
			(type solid)
		)
		(fill yes)
		(layer "F.Cu")
		(net "M_B_DQS_DN<6>")
	)
	(gr_poly
		(pts
			(xy 295.873424 -107.630722) (xy 295.999154 -107.486958) (xy 295.927272 -107.41533) (xy 295.783508 -107.54106)
			(xy 295.747694 -107.576874) (xy 295.83761 -107.66679)
		)
		(stroke
			(width 0)
			(type solid)
		)
		(fill yes)
		(layer "F.Cu")
		(net "M_E_DQS_DP<15>")
	)
	(gr_poly
		(pts
			(xy 295.881552 -46.978316) (xy 295.755822 -46.834552) (xy 295.720008 -46.798484) (xy 295.630092 -46.8884)
			(xy 295.665906 -46.924214) (xy 295.80967 -47.049944)
		)
		(stroke
			(width 0)
			(type solid)
		)
		(fill yes)
		(layer "F.Cu")
		(net "M_B_DQ<54>")
	)
	(gr_poly
		(pts
			(xy 295.889934 -44.184824) (xy 295.764204 -44.04106) (xy 295.72839 -44.004992) (xy 295.638474 -44.094908)
			(xy 295.674288 -44.130722) (xy 295.818052 -44.256452)
		)
		(stroke
			(width 0)
			(type solid)
		)
		(fill yes)
		(layer "F.Cu")
		(net "M_B_DQ<49>")
	)
	(gr_poly
		(pts
			(xy 295.93667 -106.166412) (xy 295.972738 -106.130598) (xy 295.882822 -106.040682) (xy 295.847008 -106.07675)
			(xy 295.721278 -106.22026) (xy 295.79316 -106.292142)
		)
		(stroke
			(width 0)
			(type solid)
		)
		(fill yes)
		(layer "F.Cu")
		(net "M_E_DQS_DP<6>")
	)
	(gr_poly
		(pts
			(xy 295.945052 -108.960158) (xy 295.980866 -108.92409) (xy 295.891204 -108.834428) (xy 295.855136 -108.870242)
			(xy 295.729406 -109.014006) (xy 295.801288 -109.085888)
		)
		(stroke
			(width 0)
			(type solid)
		)
		(fill yes)
		(layer "F.Cu")
		(net "M_E_DQ<48>")
	)
	(gr_poly
		(pts
			(xy 295.953434 -46.565058) (xy 295.917366 -46.529244) (xy 295.773856 -46.403514) (xy 295.701974 -46.475396)
			(xy 295.827704 -46.618906) (xy 295.863518 -46.654974)
		)
		(stroke
			(width 0)
			(type solid)
		)
		(fill yes)
		(layer "F.Cu")
		(net "M_B_DQ<54>")
	)
	(gr_poly
		(pts
			(xy 295.961816 -43.771566) (xy 295.925748 -43.735752) (xy 295.782238 -43.610022) (xy 295.710356 -43.681904)
			(xy 295.836086 -43.825414) (xy 295.8719 -43.861482)
		)
		(stroke
			(width 0)
			(type solid)
		)
		(fill yes)
		(layer "F.Cu")
		(net "M_B_DQ<49>")
	)
	(gr_poly
		(pts
			(xy 295.963594 -106.606594) (xy 296.089324 -106.46283) (xy 296.017442 -106.391202) (xy 295.873678 -106.516932)
			(xy 295.837864 -106.552746) (xy 295.92778 -106.642662)
		)
		(stroke
			(width 0)
			(type solid)
		)
		(fill yes)
		(layer "F.Cu")
		(net "M_E_DQS_DN<6>")
	)
	(gr_poly
		(pts
			(xy 295.971722 -109.40034) (xy 296.097452 -109.256576) (xy 296.025824 -109.184694) (xy 295.88206 -109.310424)
			(xy 295.845992 -109.346238) (xy 295.935908 -109.436154)
		)
		(stroke
			(width 0)
			(type solid)
		)
		(fill yes)
		(layer "F.Cu")
		(net "M_E_DQ<53>")
	)
	(gr_poly
		(pts
			(xy 295.971722 -48.00219) (xy 295.845992 -47.858426) (xy 295.809924 -47.822612) (xy 295.720262 -47.912274)
			(xy 295.756076 -47.948342) (xy 295.89984 -48.074072)
		)
		(stroke
			(width 0)
			(type solid)
		)
		(fill yes)
		(layer "F.Cu")
		(net "M_B_DQ<50>")
	)
	(gr_poly
		(pts
			(xy 295.97985 -45.208698) (xy 295.85412 -45.064934) (xy 295.818306 -45.02912) (xy 295.728644 -45.118782)
			(xy 295.764458 -45.15485) (xy 295.908222 -45.28058)
		)
		(stroke
			(width 0)
			(type solid)
		)
		(fill yes)
		(layer "F.Cu")
		(net "M_B_DQS_DN<15>")
	)
	(gr_poly
		(pts
			(xy 296.034968 -107.93603) (xy 296.071036 -107.900216) (xy 295.98112 -107.8103) (xy 295.945306 -107.846368)
			(xy 295.819576 -107.989878) (xy 295.891458 -108.06176)
		)
		(stroke
			(width 0)
			(type solid)
		)
		(fill yes)
		(layer "F.Cu")
		(net "M_E_DQS_DP<15>")
	)
	(gr_poly
		(pts
			(xy 296.04335 -47.589186) (xy 296.007536 -47.553118) (xy 295.863772 -47.427388) (xy 295.79189 -47.49927)
			(xy 295.91762 -47.643034) (xy 295.953688 -47.678848)
		)
		(stroke
			(width 0)
			(type solid)
		)
		(fill yes)
		(layer "F.Cu")
		(net "M_B_DQ<50>")
	)
	(gr_poly
		(pts
			(xy 296.051732 -44.795694) (xy 296.015918 -44.759626) (xy 295.872154 -44.633896) (xy 295.800272 -44.705778)
			(xy 295.926002 -44.849542) (xy 295.96207 -44.885356)
		)
		(stroke
			(width 0)
			(type solid)
		)
		(fill yes)
		(layer "F.Cu")
		(net "M_B_DQS_DN<15>")
	)
	(gr_poly
		(pts
			(xy 296.053764 -105.582466) (xy 296.179494 -105.438702) (xy 296.107612 -105.367074) (xy 295.963848 -105.492804)
			(xy 295.928034 -105.528618) (xy 296.01795 -105.618534)
		)
		(stroke
			(width 0)
			(type solid)
		)
		(fill yes)
		(layer "F.Cu")
		(net "M_E_DQ<54>")
	)
	(gr_poly
		(pts
			(xy 296.061892 -108.376212) (xy 296.187622 -108.232448) (xy 296.11574 -108.16082) (xy 295.971976 -108.28655)
			(xy 295.936162 -108.322364) (xy 296.026078 -108.41228)
		)
		(stroke
			(width 0)
			(type solid)
		)
		(fill yes)
		(layer "F.Cu")
		(net "M_E_DQ<49>")
	)
	(gr_poly
		(pts
			(xy 296.07002 -46.232826) (xy 295.94429 -46.089062) (xy 295.908476 -46.052994) (xy 295.81856 -46.14291)
			(xy 295.854374 -46.178724) (xy 295.998138 -46.304454)
		)
		(stroke
			(width 0)
			(type solid)
		)
		(fill yes)
		(layer "F.Cu")
		(net "M_B_DQS_DP<6>")
	)
	(gr_poly
		(pts
			(xy 296.078402 -43.439334) (xy 295.952672 -43.29557) (xy 295.916858 -43.259502) (xy 295.826942 -43.349418)
			(xy 295.862756 -43.385232) (xy 296.00652 -43.510962)
		)
		(stroke
			(width 0)
			(type solid)
		)
		(fill yes)
		(layer "F.Cu")
		(net "M_B_DQ<48>")
	)
	(gr_poly
		(pts
			(xy 296.08526 -104.737154) (xy 296.08526 -104.686354) (xy 295.95826 -104.686354) (xy 295.95826 -104.737154)
			(xy 295.97096 -104.927654) (xy 296.07256 -104.927654)
		)
		(stroke
			(width 0)
			(type solid)
		)
		(fill yes)
		(layer "F.Cu")
		(net "M_E_DQ<50>")
	)
	(gr_poly
		(pts
			(xy 296.08526 -104.343454) (xy 296.08526 -104.292654) (xy 295.95826 -104.292654) (xy 295.95826 -104.343454)
			(xy 295.97096 -104.533954) (xy 296.07256 -104.533954)
		)
		(stroke
			(width 0)
			(type solid)
		)
		(fill yes)
		(layer "F.Cu")
		(net "M_E_DQ<51>")
	)
	(gr_poly
		(pts
			(xy 296.125138 -106.911902) (xy 296.161206 -106.876088) (xy 296.07129 -106.786172) (xy 296.035476 -106.82224)
			(xy 295.909746 -106.96575) (xy 295.981628 -107.037632)
		)
		(stroke
			(width 0)
			(type solid)
		)
		(fill yes)
		(layer "F.Cu")
		(net "M_E_DQS_DN<6>")
	)
	(gr_poly
		(pts
			(xy 296.13352 -109.705648) (xy 296.169334 -109.66958) (xy 296.079672 -109.579918) (xy 296.043604 -109.615732)
			(xy 295.917874 -109.759496) (xy 295.989756 -109.831378)
		)
		(stroke
			(width 0)
			(type solid)
		)
		(fill yes)
		(layer "F.Cu")
		(net "M_E_DQ<53>")
	)
	(gr_poly
		(pts
			(xy 296.141902 -45.819568) (xy 296.105834 -45.783754) (xy 295.962324 -45.658024) (xy 295.890442 -45.729906)
			(xy 296.016172 -45.873416) (xy 296.051986 -45.909484)
		)
		(stroke
			(width 0)
			(type solid)
		)
		(fill yes)
		(layer "F.Cu")
		(net "M_B_DQS_DP<6>")
	)
	(gr_poly
		(pts
			(xy 296.151808 -107.352338) (xy 296.277538 -107.208574) (xy 296.20591 -107.136692) (xy 296.062146 -107.262422)
			(xy 296.026078 -107.298236) (xy 296.115994 -107.388152)
		)
		(stroke
			(width 0)
			(type solid)
		)
		(fill yes)
		(layer "F.Cu")
		(net "M_E_DQS_DN<15>")
	)
	(gr_poly
		(pts
			(xy 296.16019 -47.2567) (xy 296.03446 -47.112936) (xy 295.998392 -47.077122) (xy 295.90873 -47.166784)
			(xy 295.944544 -47.202852) (xy 296.088308 -47.328582)
		)
		(stroke
			(width 0)
			(type solid)
		)
		(fill yes)
		(layer "F.Cu")
		(net "M_B_DQ<55>")
	)
	(gr_poly
		(pts
			(xy 296.168318 -44.463208) (xy 296.042588 -44.319444) (xy 296.006774 -44.28363) (xy 295.916858 -44.373546)
			(xy 295.952926 -44.40936) (xy 296.09669 -44.53509)
		)
		(stroke
			(width 0)
			(type solid)
		)
		(fill yes)
		(layer "F.Cu")
		(net "M_B_DQS_DP<15>")
	)
	(gr_poly
		(pts
			(xy 296.215308 -105.887774) (xy 296.251376 -105.85196) (xy 296.16146 -105.762044) (xy 296.125646 -105.798112)
			(xy 295.999916 -105.941622) (xy 296.071798 -106.013504)
		)
		(stroke
			(width 0)
			(type solid)
		)
		(fill yes)
		(layer "F.Cu")
		(net "M_E_DQ<54>")
	)
	(gr_poly
		(pts
			(xy 296.223436 -108.68152) (xy 296.259504 -108.645706) (xy 296.169588 -108.55579) (xy 296.133774 -108.591858)
			(xy 296.008044 -108.735368) (xy 296.079926 -108.80725)
		)
		(stroke
			(width 0)
			(type solid)
		)
		(fill yes)
		(layer "F.Cu")
		(net "M_E_DQ<49>")
	)
	(gr_poly
		(pts
			(xy 296.231818 -46.843696) (xy 296.196004 -46.807628) (xy 296.05224 -46.681898) (xy 295.980358 -46.75378)
			(xy 296.106088 -46.897544) (xy 296.142156 -46.933358)
		)
		(stroke
			(width 0)
			(type solid)
		)
		(fill yes)
		(layer "F.Cu")
		(net "M_B_DQ<55>")
	)
	(gr_poly
		(pts
			(xy 296.2402 -44.050204) (xy 296.204386 -44.014136) (xy 296.060622 -43.888406) (xy 295.98874 -43.960288)
			(xy 296.11447 -44.104052) (xy 296.150538 -44.139866)
		)
		(stroke
			(width 0)
			(type solid)
		)
		(fill yes)
		(layer "F.Cu")
		(net "M_B_DQS_DP<15>")
	)
	(gr_poly
		(pts
			(xy 296.241978 -106.32821) (xy 296.367708 -106.184446) (xy 296.29608 -106.112564) (xy 296.152316 -106.238294)
			(xy 296.116502 -106.274362) (xy 296.206164 -106.364024)
		)
		(stroke
			(width 0)
			(type solid)
		)
		(fill yes)
		(layer "F.Cu")
		(net "M_E_DQS_DP<6>")
	)
	(gr_poly
		(pts
			(xy 296.250106 -48.280574) (xy 296.124376 -48.137064) (xy 296.088562 -48.100996) (xy 295.998646 -48.190912)
			(xy 296.03446 -48.226726) (xy 296.178224 -48.352456)
		)
		(stroke
			(width 0)
			(type solid)
		)
		(fill yes)
		(layer "F.Cu")
		(net "M_B_DQ<51>")
	)
	(gr_poly
		(pts
			(xy 296.25036 -109.121702) (xy 296.37609 -108.977938) (xy 296.304208 -108.90631) (xy 296.160444 -109.03204)
			(xy 296.12463 -109.067854) (xy 296.214292 -109.157516)
		)
		(stroke
			(width 0)
			(type solid)
		)
		(fill yes)
		(layer "F.Cu")
		(net "M_E_DQ<48>")
	)
	(gr_poly
		(pts
			(xy 296.258488 -45.487336) (xy 296.132758 -45.343572) (xy 296.096944 -45.307504) (xy 296.007028 -45.39742)
			(xy 296.042842 -45.433234) (xy 296.186606 -45.558964)
		)
		(stroke
			(width 0)
			(type solid)
		)
		(fill yes)
		(layer "F.Cu")
		(net "M_B_DQS_DN<6>")
	)
	(gr_poly
		(pts
			(xy 296.313606 -107.657646) (xy 296.34942 -107.621578) (xy 296.259758 -107.531916) (xy 296.22369 -107.56773)
			(xy 296.09796 -107.711494) (xy 296.169842 -107.783376)
		)
		(stroke
			(width 0)
			(type solid)
		)
		(fill yes)
		(layer "F.Cu")
		(net "M_E_DQS_DN<15>")
	)
	(gr_poly
		(pts
			(xy 296.321988 -47.86757) (xy 296.28592 -47.831756) (xy 296.14241 -47.706026) (xy 296.070528 -47.777908)
			(xy 296.196258 -47.921418) (xy 296.232072 -47.957486)
		)
		(stroke
			(width 0)
			(type solid)
		)
		(fill yes)
		(layer "F.Cu")
		(net "M_B_DQ<51>")
	)
	(gr_poly
		(pts
			(xy 296.33037 -45.074078) (xy 296.294302 -45.038264) (xy 296.150792 -44.912534) (xy 296.07891 -44.984416)
			(xy 296.20464 -45.127926) (xy 296.240454 -45.163994)
		)
		(stroke
			(width 0)
			(type solid)
		)
		(fill yes)
		(layer "F.Cu")
		(net "M_B_DQS_DN<6>")
	)
	(gr_poly
		(pts
			(xy 296.332402 -105.304082) (xy 296.457878 -105.160318) (xy 296.38625 -105.088436) (xy 296.242486 -105.214166)
			(xy 296.206672 -105.250234) (xy 296.296334 -105.339896)
		)
		(stroke
			(width 0)
			(type solid)
		)
		(fill yes)
		(layer "F.Cu")
		(net "M_E_DQ<55>")
	)
	(gr_poly
		(pts
			(xy 296.340276 -108.097828) (xy 296.466006 -107.954064) (xy 296.394378 -107.882182) (xy 296.250614 -108.007912)
			(xy 296.214546 -108.043726) (xy 296.304462 -108.133642)
		)
		(stroke
			(width 0)
			(type solid)
		)
		(fill yes)
		(layer "F.Cu")
		(net "M_E_DQS_DP<15>")
	)
	(gr_poly
		(pts
			(xy 296.348404 -46.51121) (xy 296.222928 -46.367446) (xy 296.18686 -46.331632) (xy 296.097198 -46.421294)
			(xy 296.133012 -46.457362) (xy 296.276776 -46.583092)
		)
		(stroke
			(width 0)
			(type solid)
		)
		(fill yes)
		(layer "F.Cu")
		(net "M_B_DQ<54>")
	)
	(gr_poly
		(pts
			(xy 296.356786 -43.717718) (xy 296.231056 -43.573954) (xy 296.195242 -43.53814) (xy 296.105326 -43.628056)
			(xy 296.141394 -43.66387) (xy 296.285158 -43.7896)
		)
		(stroke
			(width 0)
			(type solid)
		)
		(fill yes)
		(layer "F.Cu")
		(net "M_B_DQ<49>")
	)
	(gr_poly
		(pts
			(xy 296.403776 -106.633518) (xy 296.43959 -106.59745) (xy 296.349928 -106.507788) (xy 296.31386 -106.543602)
			(xy 296.18813 -106.687366) (xy 296.260012 -106.759248)
		)
		(stroke
			(width 0)
			(type solid)
		)
		(fill yes)
		(layer "F.Cu")
		(net "M_E_DQS_DP<6>")
	)
	(gr_poly
		(pts
			(xy 296.411904 -109.42701) (xy 296.447972 -109.391196) (xy 296.358056 -109.30128) (xy 296.322242 -109.337348)
			(xy 296.196512 -109.480858) (xy 296.268394 -109.55274)
		)
		(stroke
			(width 0)
			(type solid)
		)
		(fill yes)
		(layer "F.Cu")
		(net "M_E_DQ<48>")
	)
	(gr_poly
		(pts
			(xy 296.420286 -46.098206) (xy 296.384472 -46.062138) (xy 296.240708 -45.936408) (xy 296.168826 -46.00829)
			(xy 296.294556 -46.152054) (xy 296.330624 -46.187868)
		)
		(stroke
			(width 0)
			(type solid)
		)
		(fill yes)
		(layer "F.Cu")
		(net "M_B_DQ<54>")
	)
	(gr_poly
		(pts
			(xy 296.430446 -107.0737) (xy 296.556176 -106.929936) (xy 296.484548 -106.858054) (xy 296.340784 -106.983784)
			(xy 296.304716 -107.019598) (xy 296.394632 -107.109514)
		)
		(stroke
			(width 0)
			(type solid)
		)
		(fill yes)
		(layer "F.Cu")
		(net "M_E_DQS_DN<6>")
	)
	(gr_poly
		(pts
			(xy 296.438574 -47.535338) (xy 296.312844 -47.391574) (xy 296.27703 -47.355506) (xy 296.187114 -47.445422)
			(xy 296.222928 -47.481236) (xy 296.366692 -47.606966)
		)
		(stroke
			(width 0)
			(type solid)
		)
		(fill yes)
		(layer "F.Cu")
		(net "M_B_DQ<50>")
	)
	(gr_poly
		(pts
			(xy 296.438828 -109.867192) (xy 296.564558 -109.723428) (xy 296.492676 -109.6518) (xy 296.348912 -109.777276)
			(xy 296.313098 -109.813344) (xy 296.40276 -109.903006)
		)
		(stroke
			(width 0)
			(type solid)
		)
		(fill yes)
		(layer "F.Cu")
		(net "M_E_DQ<53>")
	)
	(gr_poly
		(pts
			(xy 296.446956 -44.741846) (xy 296.321226 -44.598082) (xy 296.285412 -44.562014) (xy 296.195496 -44.65193)
			(xy 296.23131 -44.687744) (xy 296.375074 -44.813474)
		)
		(stroke
			(width 0)
			(type solid)
		)
		(fill yes)
		(layer "F.Cu")
		(net "M_B_DQS_DN<15>")
	)
	(gr_poly
		(pts
			(xy 296.493946 -105.60939) (xy 296.52976 -105.573322) (xy 296.440098 -105.48366) (xy 296.40403 -105.519474)
			(xy 296.2783 -105.663238) (xy 296.350182 -105.73512)
		)
		(stroke
			(width 0)
			(type solid)
		)
		(fill yes)
		(layer "F.Cu")
		(net "M_E_DQ<55>")
	)
	(gr_poly
		(pts
			(xy 296.502074 -108.403136) (xy 296.537888 -108.367068) (xy 296.448226 -108.277406) (xy 296.412158 -108.31322)
			(xy 296.286428 -108.456984) (xy 296.35831 -108.528866)
		)
		(stroke
			(width 0)
			(type solid)
		)
		(fill yes)
		(layer "F.Cu")
		(net "M_E_DQS_DP<15>")
	)
	(gr_poly
		(pts
			(xy 296.510456 -47.12208) (xy 296.474388 -47.086266) (xy 296.330878 -46.960536) (xy 296.258996 -47.032418)
			(xy 296.384726 -47.175928) (xy 296.42054 -47.211996)
		)
		(stroke
			(width 0)
			(type solid)
		)
		(fill yes)
		(layer "F.Cu")
		(net "M_B_DQ<50>")
	)
	(gr_poly
		(pts
			(xy 296.518838 -44.328588) (xy 296.48277 -44.292774) (xy 296.33926 -44.167044) (xy 296.267378 -44.238926)
			(xy 296.393108 -44.382436) (xy 296.428922 -44.418504)
		)
		(stroke
			(width 0)
			(type solid)
		)
		(fill yes)
		(layer "F.Cu")
		(net "M_B_DQS_DN<15>")
	)
	(gr_poly
		(pts
			(xy 296.520616 -106.049572) (xy 296.646346 -105.905808) (xy 296.574718 -105.833926) (xy 296.430954 -105.959656)
			(xy 296.39514 -105.995724) (xy 296.484802 -106.085386)
		)
		(stroke
			(width 0)
			(type solid)
		)
		(fill yes)
		(layer "F.Cu")
		(net "M_E_DQ<54>")
	)
	(gr_poly
		(pts
			(xy 296.528744 -108.843318) (xy 296.654474 -108.699554) (xy 296.582846 -108.627672) (xy 296.439082 -108.753402)
			(xy 296.403014 -108.789216) (xy 296.49293 -108.879132)
		)
		(stroke
			(width 0)
			(type solid)
		)
		(fill yes)
		(layer "F.Cu")
		(net "M_E_DQ<49>")
	)
	(gr_poly
		(pts
			(xy 296.536872 -45.76572) (xy 296.411142 -45.621956) (xy 296.375328 -45.586142) (xy 296.285666 -45.675804)
			(xy 296.32148 -45.711872) (xy 296.465244 -45.837602)
		)
		(stroke
			(width 0)
			(type solid)
		)
		(fill yes)
		(layer "F.Cu")
		(net "M_B_DQS_DP<6>")
	)
	(gr_poly
		(pts
			(xy 296.583862 -104.585262) (xy 296.61993 -104.549448) (xy 296.530014 -104.459532) (xy 296.4942 -104.4956)
			(xy 296.36847 -104.63911) (xy 296.440352 -104.710992)
		)
		(stroke
			(width 0)
			(type solid)
		)
		(fill yes)
		(layer "F.Cu")
		(net "M_E_DQ<51>")
	)
	(gr_poly
		(pts
			(xy 296.592244 -107.379008) (xy 296.628058 -107.34294) (xy 296.538396 -107.253278) (xy 296.502328 -107.289092)
			(xy 296.376598 -107.432856) (xy 296.44848 -107.504738)
		)
		(stroke
			(width 0)
			(type solid)
		)
		(fill yes)
		(layer "F.Cu")
		(net "M_E_DQS_DN<6>")
	)
	(gr_poly
		(pts
			(xy 296.608754 -45.352716) (xy 296.57294 -45.316648) (xy 296.429176 -45.190918) (xy 296.357294 -45.2628)
			(xy 296.483024 -45.406564) (xy 296.519092 -45.442378)
		)
		(stroke
			(width 0)
			(type solid)
		)
		(fill yes)
		(layer "F.Cu")
		(net "M_B_DQS_DP<6>")
	)
	(gr_poly
		(pts
			(xy 296.610786 -105.025444) (xy 296.736516 -104.88168) (xy 296.664634 -104.810052) (xy 296.52087 -104.935782)
			(xy 296.485056 -104.971596) (xy 296.574972 -105.061512)
		)
		(stroke
			(width 0)
			(type solid)
		)
		(fill yes)
		(layer "F.Cu")
		(net "M_E_DQ<50>")
	)
	(gr_poly
		(pts
			(xy 296.618914 -107.81919) (xy 296.744644 -107.675426) (xy 296.672762 -107.603798) (xy 296.528998 -107.729528)
			(xy 296.493184 -107.765342) (xy 296.5831 -107.855258)
		)
		(stroke
			(width 0)
			(type solid)
		)
		(fill yes)
		(layer "F.Cu")
		(net "M_E_DQS_DN<15>")
	)
	(gr_poly
		(pts
			(xy 296.627042 -46.789848) (xy 296.501312 -46.646084) (xy 296.465498 -46.610016) (xy 296.375582 -46.699932)
			(xy 296.411396 -46.735746) (xy 296.55516 -46.861476)
		)
		(stroke
			(width 0)
			(type solid)
		)
		(fill yes)
		(layer "F.Cu")
		(net "M_B_DQ<55>")
	)
	(gr_poly
		(pts
			(xy 296.635424 -43.996356) (xy 296.509694 -43.852592) (xy 296.47388 -43.816524) (xy 296.383964 -43.90644)
			(xy 296.419778 -43.942254) (xy 296.563542 -44.067984)
		)
		(stroke
			(width 0)
			(type solid)
		)
		(fill yes)
		(layer "F.Cu")
		(net "M_B_DQS_DP<15>")
	)
	(gr_poly
		(pts
			(xy 296.682414 -106.35488) (xy 296.718228 -106.318812) (xy 296.628566 -106.22915) (xy 296.592498 -106.264964)
			(xy 296.466768 -106.408728) (xy 296.53865 -106.48061)
		)
		(stroke
			(width 0)
			(type solid)
		)
		(fill yes)
		(layer "F.Cu")
		(net "M_E_DQ<54>")
	)
	(gr_poly
		(pts
			(xy 296.690542 -109.148626) (xy 296.726356 -109.112558) (xy 296.636694 -109.022896) (xy 296.600626 -109.05871)
			(xy 296.474896 -109.202474) (xy 296.546778 -109.274356)
		)
		(stroke
			(width 0)
			(type solid)
		)
		(fill yes)
		(layer "F.Cu")
		(net "M_E_DQ<49>")
	)
	(gr_poly
		(pts
			(xy 296.698924 -46.37659) (xy 296.662856 -46.340776) (xy 296.519346 -46.215046) (xy 296.447464 -46.286928)
			(xy 296.573194 -46.430438) (xy 296.609008 -46.466506)
		)
		(stroke
			(width 0)
			(type solid)
		)
		(fill yes)
		(layer "F.Cu")
		(net "M_B_DQ<55>")
	)
	(gr_poly
		(pts
			(xy 296.707306 -43.583098) (xy 296.671238 -43.547284) (xy 296.527728 -43.421554) (xy 296.455846 -43.493436)
			(xy 296.581576 -43.636946) (xy 296.61739 -43.673014)
		)
		(stroke
			(width 0)
			(type solid)
		)
		(fill yes)
		(layer "F.Cu")
		(net "M_B_DQS_DP<15>")
	)
	(gr_poly
		(pts
			(xy 296.709084 -106.795062) (xy 296.834814 -106.651298) (xy 296.762932 -106.57967) (xy 296.619168 -106.7054)
			(xy 296.583354 -106.741214) (xy 296.67327 -106.83113)
		)
		(stroke
			(width 0)
			(type solid)
		)
		(fill yes)
		(layer "F.Cu")
		(net "M_E_DQS_DP<6>")
	)
	(gr_poly
		(pts
			(xy 296.717212 -109.588808) (xy 296.842942 -109.445044) (xy 296.771314 -109.373162) (xy 296.62755 -109.498892)
			(xy 296.591482 -109.534706) (xy 296.681398 -109.624622)
		)
		(stroke
			(width 0)
			(type solid)
		)
		(fill yes)
		(layer "F.Cu")
		(net "M_E_DQ<48>")
	)
	(gr_poly
		(pts
			(xy 296.717212 -47.813722) (xy 296.591482 -47.669958) (xy 296.555414 -47.634144) (xy 296.465752 -47.723806)
			(xy 296.501566 -47.759874) (xy 296.64533 -47.885604)
		)
		(stroke
			(width 0)
			(type solid)
		)
		(fill yes)
		(layer "F.Cu")
		(net "M_B_DQ<51>")
	)
	(gr_poly
		(pts
			(xy 296.72534 -45.02023) (xy 296.59961 -44.876466) (xy 296.563796 -44.840652) (xy 296.47388 -44.930568)
			(xy 296.509948 -44.966382) (xy 296.653712 -45.092112)
		)
		(stroke
			(width 0)
			(type solid)
		)
		(fill yes)
		(layer "F.Cu")
		(net "M_B_DQS_DN<6>")
	)
	(gr_poly
		(pts
			(xy 296.77233 -105.330752) (xy 296.808398 -105.294938) (xy 296.718482 -105.205022) (xy 296.682668 -105.24109)
			(xy 296.556938 -105.3846) (xy 296.62882 -105.456482)
		)
		(stroke
			(width 0)
			(type solid)
		)
		(fill yes)
		(layer "F.Cu")
		(net "M_E_DQ<50>")
	)
	(gr_poly
		(pts
			(xy 296.780458 -108.124498) (xy 296.816526 -108.088684) (xy 296.72661 -107.998768) (xy 296.690796 -108.034836)
			(xy 296.565066 -108.178346) (xy 296.636948 -108.250228)
		)
		(stroke
			(width 0)
			(type solid)
		)
		(fill yes)
		(layer "F.Cu")
		(net "M_E_DQS_DN<15>")
	)
	(gr_poly
		(pts
			(xy 296.78884 -47.400718) (xy 296.753026 -47.36465) (xy 296.609262 -47.23892) (xy 296.53738 -47.310802)
			(xy 296.66311 -47.454566) (xy 296.699178 -47.49038)
		)
		(stroke
			(width 0)
			(type solid)
		)
		(fill yes)
		(layer "F.Cu")
		(net "M_B_DQ<51>")
	)
	(gr_poly
		(pts
			(xy 296.797222 -44.607226) (xy 296.761408 -44.571158) (xy 296.617644 -44.445428) (xy 296.545762 -44.51731)
			(xy 296.671492 -44.661074) (xy 296.70756 -44.696888)
		)
		(stroke
			(width 0)
			(type solid)
		)
		(fill yes)
		(layer "F.Cu")
		(net "M_B_DQS_DN<6>")
	)
	(gr_poly
		(pts
			(xy 296.799254 -105.770934) (xy 296.924984 -105.62717) (xy 296.853102 -105.555542) (xy 296.709338 -105.681272)
			(xy 296.673524 -105.717086) (xy 296.76344 -105.807002)
		)
		(stroke
			(width 0)
			(type solid)
		)
		(fill yes)
		(layer "F.Cu")
		(net "M_E_DQ<55>")
	)
	(gr_poly
		(pts
			(xy 296.807382 -108.56468) (xy 296.933112 -108.420916) (xy 296.86123 -108.349288) (xy 296.717466 -108.475018)
			(xy 296.681652 -108.510832) (xy 296.771314 -108.600494)
		)
		(stroke
			(width 0)
			(type solid)
		)
		(fill yes)
		(layer "F.Cu")
		(net "M_E_DQS_DP<15>")
	)
	(gr_poly
		(pts
			(xy 296.81551 -46.044358) (xy 296.68978 -45.900594) (xy 296.653966 -45.864526) (xy 296.56405 -45.954442)
			(xy 296.599864 -45.990256) (xy 296.743628 -46.115986)
		)
		(stroke
			(width 0)
			(type solid)
		)
		(fill yes)
		(layer "F.Cu")
		(net "M_B_DQ<54>")
	)
	(gr_poly
		(pts
			(xy 296.823892 -43.250866) (xy 296.698162 -43.107102) (xy 296.662094 -43.071288) (xy 296.572432 -43.16095)
			(xy 296.608246 -43.196764) (xy 296.75201 -43.322494)
		)
		(stroke
			(width 0)
			(type solid)
		)
		(fill yes)
		(layer "F.Cu")
		(net "M_B_DQ<49>")
	)
	(gr_poly
		(pts
			(xy 296.870628 -107.10037) (xy 296.906696 -107.064556) (xy 296.81678 -106.97464) (xy 296.780966 -107.010708)
			(xy 296.655236 -107.154218) (xy 296.727118 -107.2261)
		)
		(stroke
			(width 0)
			(type solid)
		)
		(fill yes)
		(layer "F.Cu")
		(net "M_E_DQS_DP<6>")
	)
	(gr_poly
		(pts
			(xy 296.87901 -109.894116) (xy 296.914824 -109.858048) (xy 296.825162 -109.768386) (xy 296.789094 -109.8042)
			(xy 296.663364 -109.947964) (xy 296.735246 -110.019846)
		)
		(stroke
			(width 0)
			(type solid)
		)
		(fill yes)
		(layer "F.Cu")
		(net "M_E_DQ<48>")
	)
	(gr_poly
		(pts
			(xy 296.887392 -45.6311) (xy 296.851324 -45.595286) (xy 296.707814 -45.469556) (xy 296.635932 -45.541438)
			(xy 296.761662 -45.684948) (xy 296.797476 -45.721016)
		)
		(stroke
			(width 0)
			(type solid)
		)
		(fill yes)
		(layer "F.Cu")
		(net "M_B_DQ<54>")
	)
	(gr_poly
		(pts
			(xy 296.889424 -104.74706) (xy 297.0149 -104.603296) (xy 296.943272 -104.531414) (xy 296.799508 -104.657144)
			(xy 296.763694 -104.693212) (xy 296.853356 -104.782874)
		)
		(stroke
			(width 0)
			(type solid)
		)
		(fill yes)
		(layer "F.Cu")
		(net "M_E_DQ<51>")
	)
	(gr_poly
		(pts
			(xy 296.897552 -107.540552) (xy 297.023282 -107.396788) (xy 296.9514 -107.32516) (xy 296.807636 -107.45089)
			(xy 296.771822 -107.486704) (xy 296.861738 -107.57662)
		)
		(stroke
			(width 0)
			(type solid)
		)
		(fill yes)
		(layer "F.Cu")
		(net "M_E_DQS_DN<6>")
	)
	(gr_poly
		(pts
			(xy 296.905426 -47.068232) (xy 296.77995 -46.924468) (xy 296.743882 -46.888654) (xy 296.65422 -46.978316)
			(xy 296.690034 -47.014384) (xy 296.833798 -47.140114)
		)
		(stroke
			(width 0)
			(type solid)
		)
		(fill yes)
		(layer "F.Cu")
		(net "M_B_DQ<50>")
	)
	(gr_poly
		(pts
			(xy 296.913808 -44.27474) (xy 296.788078 -44.130976) (xy 296.752264 -44.095162) (xy 296.662348 -44.185078)
			(xy 296.698416 -44.220892) (xy 296.84218 -44.346622)
		)
		(stroke
			(width 0)
			(type solid)
		)
		(fill yes)
		(layer "F.Cu")
		(net "M_B_DQS_DN<15>")
	)
	(gr_poly
		(pts
			(xy 296.960798 -106.076242) (xy 296.996866 -106.040428) (xy 296.90695 -105.950512) (xy 296.871136 -105.98658)
			(xy 296.745406 -106.13009) (xy 296.817288 -106.201972)
		)
		(stroke
			(width 0)
			(type solid)
		)
		(fill yes)
		(layer "F.Cu")
		(net "M_E_DQ<55>")
	)
	(gr_poly
		(pts
			(xy 296.968926 -108.869988) (xy 297.004994 -108.834174) (xy 296.915078 -108.744258) (xy 296.879264 -108.780326)
			(xy 296.753534 -108.923836) (xy 296.825416 -108.995718)
		)
		(stroke
			(width 0)
			(type solid)
		)
		(fill yes)
		(layer "F.Cu")
		(net "M_E_DQS_DP<15>")
	)
	(gr_poly
		(pts
			(xy 296.977308 -46.655228) (xy 296.941494 -46.61916) (xy 296.79773 -46.49343) (xy 296.725848 -46.565312)
			(xy 296.851578 -46.709076) (xy 296.887646 -46.74489)
		)
		(stroke
			(width 0)
			(type solid)
		)
		(fill yes)
		(layer "F.Cu")
		(net "M_B_DQ<50>")
	)
	(gr_poly
		(pts
			(xy 296.98569 -43.861736) (xy 296.949876 -43.825668) (xy 296.806112 -43.699938) (xy 296.73423 -43.77182)
			(xy 296.85996 -43.915584) (xy 296.896028 -43.951398)
		)
		(stroke
			(width 0)
			(type solid)
		)
		(fill yes)
		(layer "F.Cu")
		(net "M_B_DQS_DN<15>")
	)
	(gr_poly
		(pts
			(xy 296.987722 -106.516424) (xy 297.113452 -106.37266) (xy 297.04157 -106.301032) (xy 296.897806 -106.426762)
			(xy 296.861992 -106.462576) (xy 296.951908 -106.552492)
		)
		(stroke
			(width 0)
			(type solid)
		)
		(fill yes)
		(layer "F.Cu")
		(net "M_E_DQ<54>")
	)
	(gr_poly
		(pts
			(xy 296.99585 -109.31017) (xy 297.12158 -109.166406) (xy 297.049698 -109.094778) (xy 296.905934 -109.220254)
			(xy 296.87012 -109.256322) (xy 296.959782 -109.345984)
		)
		(stroke
			(width 0)
			(type solid)
		)
		(fill yes)
		(layer "F.Cu")
		(net "M_E_DQ<49>")
	)
	(gr_poly
		(pts
			(xy 297.003978 -45.298868) (xy 296.878248 -45.155104) (xy 296.842434 -45.119036) (xy 296.752518 -45.208952)
			(xy 296.788332 -45.244766) (xy 296.932096 -45.370496)
		)
		(stroke
			(width 0)
			(type solid)
		)
		(fill yes)
		(layer "F.Cu")
		(net "M_B_DQS_DP<6>")
	)
	(gr_poly
		(pts
			(xy 297.050968 -105.052368) (xy 297.086782 -105.0163) (xy 296.99712 -104.926638) (xy 296.961052 -104.962452)
			(xy 296.835322 -105.106216) (xy 296.907204 -105.178098)
		)
		(stroke
			(width 0)
			(type solid)
		)
		(fill yes)
		(layer "F.Cu")
		(net "M_E_DQ<51>")
	)
	(gr_poly
		(pts
			(xy 297.059096 -107.84586) (xy 297.095164 -107.810046) (xy 297.005248 -107.72013) (xy 296.969434 -107.756198)
			(xy 296.843704 -107.899708) (xy 296.915586 -107.97159)
		)
		(stroke
			(width 0)
			(type solid)
		)
		(fill yes)
		(layer "F.Cu")
		(net "M_E_DQS_DN<6>")
	)
	(gr_poly
		(pts
			(xy 297.07586 -44.88561) (xy 297.039792 -44.849796) (xy 296.896282 -44.724066) (xy 296.8244 -44.795948)
			(xy 296.95013 -44.939458) (xy 296.985944 -44.975526)
		)
		(stroke
			(width 0)
			(type solid)
		)
		(fill yes)
		(layer "F.Cu")
		(net "M_B_DQS_DP<6>")
	)
	(gr_poly
		(pts
			(xy 297.077638 -105.49255) (xy 297.203368 -105.348786) (xy 297.13174 -105.276904) (xy 296.987976 -105.402634)
			(xy 296.952162 -105.438702) (xy 297.041824 -105.528364)
		)
		(stroke
			(width 0)
			(type solid)
		)
		(fill yes)
		(layer "F.Cu")
		(net "M_E_DQ<50>")
	)
	(gr_poly
		(pts
			(xy 297.085766 -108.286296) (xy 297.211496 -108.142532) (xy 297.139868 -108.07065) (xy 296.996104 -108.19638)
			(xy 296.960036 -108.232194) (xy 297.049952 -108.32211)
		)
		(stroke
			(width 0)
			(type solid)
		)
		(fill yes)
		(layer "F.Cu")
		(net "M_E_DQS_DN<15>")
	)
	(gr_poly
		(pts
			(xy 297.093894 -46.322742) (xy 296.968164 -46.178978) (xy 296.93235 -46.143164) (xy 296.842688 -46.232826)
			(xy 296.878502 -46.268894) (xy 297.022266 -46.394624)
		)
		(stroke
			(width 0)
			(type solid)
		)
		(fill yes)
		(layer "F.Cu")
		(net "M_B_DQ<55>")
	)
	(gr_poly
		(pts
			(xy 297.102276 -43.52925) (xy 296.976546 -43.385486) (xy 296.940732 -43.349672) (xy 296.850816 -43.439588)
			(xy 296.886884 -43.475402) (xy 297.030648 -43.601132)
		)
		(stroke
			(width 0)
			(type solid)
		)
		(fill yes)
		(layer "F.Cu")
		(net "M_B_DQS_DP<15>")
	)
	(gr_poly
		(pts
			(xy 297.149266 -106.821732) (xy 297.185334 -106.785918) (xy 297.095418 -106.696002) (xy 297.059604 -106.73207)
			(xy 296.933874 -106.87558) (xy 297.005756 -106.947462)
		)
		(stroke
			(width 0)
			(type solid)
		)
		(fill yes)
		(layer "F.Cu")
		(net "M_E_DQ<54>")
	)
	(gr_poly
		(pts
			(xy 297.157394 -109.615478) (xy 297.193462 -109.579664) (xy 297.103546 -109.489748) (xy 297.067732 -109.525816)
			(xy 296.942002 -109.669326) (xy 297.013884 -109.741208)
		)
		(stroke
			(width 0)
			(type solid)
		)
		(fill yes)
		(layer "F.Cu")
		(net "M_E_DQ<49>")
	)
	(gr_poly
		(pts
			(xy 297.165776 -45.909738) (xy 297.129962 -45.87367) (xy 296.986198 -45.74794) (xy 296.914316 -45.819822)
			(xy 297.040046 -45.963586) (xy 297.076114 -45.9994)
		)
		(stroke
			(width 0)
			(type solid)
		)
		(fill yes)
		(layer "F.Cu")
		(net "M_B_DQ<55>")
	)
	(gr_poly
		(pts
			(xy 297.174412 -43.116246) (xy 297.138344 -43.080432) (xy 296.994834 -42.954702) (xy 296.922952 -43.026584)
			(xy 297.048682 -43.170094) (xy 297.084496 -43.206162)
		)
		(stroke
			(width 0)
			(type solid)
		)
		(fill yes)
		(layer "F.Cu")
		(net "M_B_DQS_DP<15>")
	)
	(gr_poly
		(pts
			(xy 297.175936 -107.262168) (xy 297.301666 -107.118404) (xy 297.230038 -107.046522) (xy 297.086274 -107.172252)
			(xy 297.050206 -107.208066) (xy 297.140122 -107.297982)
		)
		(stroke
			(width 0)
			(type solid)
		)
		(fill yes)
		(layer "F.Cu")
		(net "M_E_DQS_DP<6>")
	)
	(gr_poly
		(pts
			(xy 297.184064 -47.34687) (xy 297.058334 -47.203106) (xy 297.02252 -47.167038) (xy 296.932604 -47.256954)
			(xy 296.968418 -47.292768) (xy 297.112182 -47.418498)
		)
		(stroke
			(width 0)
			(type solid)
		)
		(fill yes)
		(layer "F.Cu")
		(net "M_B_DQ<51>")
	)
	(gr_poly
		(pts
			(xy 297.192446 -44.553378) (xy 297.066716 -44.409614) (xy 297.030902 -44.373546) (xy 296.940986 -44.463462)
			(xy 296.9768 -44.499276) (xy 297.120564 -44.625006)
		)
		(stroke
			(width 0)
			(type solid)
		)
		(fill yes)
		(layer "F.Cu")
		(net "M_B_DQS_DN<6>")
	)
	(gr_poly
		(pts
			(xy 297.239436 -105.797858) (xy 297.27525 -105.76179) (xy 297.185588 -105.672128) (xy 297.14952 -105.707942)
			(xy 297.02379 -105.851706) (xy 297.095672 -105.923588)
		)
		(stroke
			(width 0)
			(type solid)
		)
		(fill yes)
		(layer "F.Cu")
		(net "M_E_DQ<50>")
	)
	(gr_poly
		(pts
			(xy 297.247564 -108.591604) (xy 297.283378 -108.555536) (xy 297.193716 -108.465874) (xy 297.157648 -108.501688)
			(xy 297.031918 -108.645452) (xy 297.1038 -108.717334)
		)
		(stroke
			(width 0)
			(type solid)
		)
		(fill yes)
		(layer "F.Cu")
		(net "M_E_DQS_DN<15>")
	)
	(gr_poly
		(pts
			(xy 297.255946 -46.933612) (xy 297.219878 -46.897798) (xy 297.076368 -46.772068) (xy 297.004486 -46.84395)
			(xy 297.130216 -46.98746) (xy 297.16603 -47.023528)
		)
		(stroke
			(width 0)
			(type solid)
		)
		(fill yes)
		(layer "F.Cu")
		(net "M_B_DQ<51>")
	)
	(gr_poly
		(pts
			(xy 297.264328 -44.14012) (xy 297.22826 -44.104306) (xy 297.08475 -43.978576) (xy 297.012868 -44.050458)
			(xy 297.138598 -44.193968) (xy 297.174412 -44.230036)
		)
		(stroke
			(width 0)
			(type solid)
		)
		(fill yes)
		(layer "F.Cu")
		(net "M_B_DQS_DN<6>")
	)
	(gr_poly
		(pts
			(xy 297.266106 -106.23804) (xy 297.391836 -106.094276) (xy 297.320208 -106.022394) (xy 297.176444 -106.148124)
			(xy 297.140376 -106.183938) (xy 297.230292 -106.273854)
		)
		(stroke
			(width 0)
			(type solid)
		)
		(fill yes)
		(layer "F.Cu")
		(net "M_E_DQ<55>")
	)
	(gr_poly
		(pts
			(xy 297.274234 -109.031786) (xy 297.399964 -108.888022) (xy 297.328336 -108.81614) (xy 297.184572 -108.94187)
			(xy 297.148504 -108.977684) (xy 297.23842 -109.0676)
		)
		(stroke
			(width 0)
			(type solid)
		)
		(fill yes)
		(layer "F.Cu")
		(net "M_E_DQS_DP<15>")
	)
	(gr_poly
		(pts
			(xy 297.282362 -45.577252) (xy 297.156632 -45.433488) (xy 297.120818 -45.397674) (xy 297.030902 -45.48759)
			(xy 297.06697 -45.523404) (xy 297.210734 -45.649134)
		)
		(stroke
			(width 0)
			(type solid)
		)
		(fill yes)
		(layer "F.Cu")
		(net "M_B_DQ<54>")
	)
	(gr_poly
		(pts
			(xy 297.337734 -107.567476) (xy 297.373548 -107.531408) (xy 297.283886 -107.441746) (xy 297.247818 -107.47756)
			(xy 297.122088 -107.621324) (xy 297.19397 -107.693206)
		)
		(stroke
			(width 0)
			(type solid)
		)
		(fill yes)
		(layer "F.Cu")
		(net "M_E_DQS_DP<6>")
	)
	(gr_poly
		(pts
			(xy 297.354244 -45.164248) (xy 297.31843 -45.12818) (xy 297.174666 -45.00245) (xy 297.102784 -45.074332)
			(xy 297.228514 -45.218096) (xy 297.264582 -45.25391)
		)
		(stroke
			(width 0)
			(type solid)
		)
		(fill yes)
		(layer "F.Cu")
		(net "M_B_DQ<54>")
	)
	(gr_poly
		(pts
			(xy 297.356276 -105.213912) (xy 297.482006 -105.070148) (xy 297.410124 -104.99852) (xy 297.26636 -105.12425)
			(xy 297.230546 -105.160064) (xy 297.320462 -105.24998)
		)
		(stroke
			(width 0)
			(type solid)
		)
		(fill yes)
		(layer "F.Cu")
		(net "M_E_DQ<51>")
	)
	(gr_poly
		(pts
			(xy 297.364404 -108.007658) (xy 297.490134 -107.863894) (xy 297.418506 -107.792012) (xy 297.274742 -107.917742)
			(xy 297.238674 -107.953556) (xy 297.32859 -108.043472)
		)
		(stroke
			(width 0)
			(type solid)
		)
		(fill yes)
		(layer "F.Cu")
		(net "M_E_DQS_DN<6>")
	)
	(gr_poly
		(pts
			(xy 297.372532 -46.60138) (xy 297.246802 -46.457616) (xy 297.210988 -46.421548) (xy 297.121072 -46.511464)
			(xy 297.156886 -46.547278) (xy 297.30065 -46.673008)
		)
		(stroke
			(width 0)
			(type solid)
		)
		(fill yes)
		(layer "F.Cu")
		(net "M_B_DQ<50>")
	)
	(gr_poly
		(pts
			(xy 297.380914 -43.807888) (xy 297.255184 -43.664124) (xy 297.219116 -43.62831) (xy 297.129454 -43.717972)
			(xy 297.165268 -43.753786) (xy 297.309032 -43.879516)
		)
		(stroke
			(width 0)
			(type solid)
		)
		(fill yes)
		(layer "F.Cu")
		(net "M_B_DQS_DN<15>")
	)
	(gr_poly
		(pts
			(xy 297.427904 -106.543348) (xy 297.463718 -106.50728) (xy 297.374056 -106.417618) (xy 297.337988 -106.453432)
			(xy 297.212258 -106.597196) (xy 297.28414 -106.669078)
		)
		(stroke
			(width 0)
			(type solid)
		)
		(fill yes)
		(layer "F.Cu")
		(net "M_E_DQ<55>")
	)
	(gr_poly
		(pts
			(xy 297.436032 -109.337094) (xy 297.471846 -109.301026) (xy 297.382184 -109.211364) (xy 297.346116 -109.247178)
			(xy 297.220386 -109.390942) (xy 297.292268 -109.462824)
		)
		(stroke
			(width 0)
			(type solid)
		)
		(fill yes)
		(layer "F.Cu")
		(net "M_E_DQS_DP<15>")
	)
	(gr_poly
		(pts
			(xy 297.444414 -46.188122) (xy 297.408346 -46.152308) (xy 297.264836 -46.026578) (xy 297.192954 -46.09846)
			(xy 297.318684 -46.24197) (xy 297.354498 -46.278038)
		)
		(stroke
			(width 0)
			(type solid)
		)
		(fill yes)
		(layer "F.Cu")
		(net "M_B_DQ<50>")
	)
	(gr_poly
		(pts
			(xy 297.452796 -43.39463) (xy 297.416728 -43.358816) (xy 297.273218 -43.233086) (xy 297.201336 -43.304968)
			(xy 297.327066 -43.448478) (xy 297.36288 -43.484546)
		)
		(stroke
			(width 0)
			(type solid)
		)
		(fill yes)
		(layer "F.Cu")
		(net "M_B_DQS_DN<15>")
	)
	(gr_poly
		(pts
			(xy 297.454574 -106.98353) (xy 297.580304 -106.839766) (xy 297.508676 -106.767884) (xy 297.364912 -106.893614)
			(xy 297.328844 -106.929428) (xy 297.41876 -107.019344)
		)
		(stroke
			(width 0)
			(type solid)
		)
		(fill yes)
		(layer "F.Cu")
		(net "M_E_DQ<54>")
	)
	(gr_poly
		(pts
			(xy 297.462702 -109.777276) (xy 297.588432 -109.633512) (xy 297.516804 -109.56163) (xy 297.37304 -109.68736)
			(xy 297.336972 -109.723174) (xy 297.426888 -109.81309)
		)
		(stroke
			(width 0)
			(type solid)
		)
		(fill yes)
		(layer "F.Cu")
		(net "M_E_DQ<49>")
	)
	(gr_poly
		(pts
			(xy 297.47083 -44.831762) (xy 297.3451 -44.687998) (xy 297.309286 -44.652184) (xy 297.21937 -44.7421)
			(xy 297.255438 -44.777914) (xy 297.399202 -44.903644)
		)
		(stroke
			(width 0)
			(type solid)
		)
		(fill yes)
		(layer "F.Cu")
		(net "M_B_DQS_DP<6>")
	)
	(gr_poly
		(pts
			(xy 297.51782 -105.51922) (xy 297.553888 -105.483406) (xy 297.463972 -105.39349) (xy 297.428158 -105.429558)
			(xy 297.302428 -105.573068) (xy 297.37431 -105.64495)
		)
		(stroke
			(width 0)
			(type solid)
		)
		(fill yes)
		(layer "F.Cu")
		(net "M_E_DQ<51>")
	)
	(gr_poly
		(pts
			(xy 297.526202 -108.312966) (xy 297.562016 -108.276898) (xy 297.472354 -108.187236) (xy 297.436286 -108.22305)
			(xy 297.310556 -108.366814) (xy 297.382438 -108.438696)
		)
		(stroke
			(width 0)
			(type solid)
		)
		(fill yes)
		(layer "F.Cu")
		(net "M_E_DQS_DN<6>")
	)
	(gr_poly
		(pts
			(xy 297.542712 -44.418758) (xy 297.506898 -44.38269) (xy 297.363134 -44.25696) (xy 297.291252 -44.328842)
			(xy 297.416982 -44.472606) (xy 297.45305 -44.50842)
		)
		(stroke
			(width 0)
			(type solid)
		)
		(fill yes)
		(layer "F.Cu")
		(net "M_B_DQS_DP<6>")
	)
	(gr_poly
		(pts
			(xy 297.544744 -105.959402) (xy 297.670474 -105.815638) (xy 297.598592 -105.74401) (xy 297.454828 -105.86974)
			(xy 297.419014 -105.905554) (xy 297.50893 -105.99547)
		)
		(stroke
			(width 0)
			(type solid)
		)
		(fill yes)
		(layer "F.Cu")
		(net "M_E_DQ<50>")
	)
	(gr_poly
		(pts
			(xy 297.552872 -108.753148) (xy 297.678602 -108.609384) (xy 297.60672 -108.537756) (xy 297.462956 -108.663232)
			(xy 297.427142 -108.6993) (xy 297.516804 -108.788962)
		)
		(stroke
			(width 0)
			(type solid)
		)
		(fill yes)
		(layer "F.Cu")
		(net "M_E_DQS_DN<15>")
	)
	(gr_poly
		(pts
			(xy 297.561 -45.85589) (xy 297.43527 -45.712126) (xy 297.399456 -45.676058) (xy 297.30954 -45.765974)
			(xy 297.345354 -45.801788) (xy 297.489118 -45.927518)
		)
		(stroke
			(width 0)
			(type solid)
		)
		(fill yes)
		(layer "F.Cu")
		(net "M_B_DQ<55>")
	)
	(gr_poly
		(pts
			(xy 297.616372 -107.288838) (xy 297.652186 -107.25277) (xy 297.562524 -107.163108) (xy 297.526456 -107.198922)
			(xy 297.400726 -107.342686) (xy 297.472608 -107.414568)
		)
		(stroke
			(width 0)
			(type solid)
		)
		(fill yes)
		(layer "F.Cu")
		(net "M_E_DQ<54>")
	)
	(gr_poly
		(pts
			(xy 297.632882 -45.442632) (xy 297.596814 -45.406818) (xy 297.453304 -45.281088) (xy 297.381422 -45.35297)
			(xy 297.507152 -45.49648) (xy 297.542966 -45.532548)
		)
		(stroke
			(width 0)
			(type solid)
		)
		(fill yes)
		(layer "F.Cu")
		(net "M_B_DQ<55>")
	)
	(gr_poly
		(pts
			(xy 297.643042 -107.72902) (xy 297.768772 -107.585256) (xy 297.69689 -107.513628) (xy 297.553126 -107.639358)
			(xy 297.517312 -107.675172) (xy 297.606974 -107.764834)
		)
		(stroke
			(width 0)
			(type solid)
		)
		(fill yes)
		(layer "F.Cu")
		(net "M_E_DQS_DP<6>")
	)
	(gr_poly
		(pts
			(xy 297.650916 -46.879764) (xy 297.525186 -46.736) (xy 297.489372 -46.700186) (xy 297.39971 -46.789848)
			(xy 297.435524 -46.825916) (xy 297.579288 -46.951646)
		)
		(stroke
			(width 0)
			(type solid)
		)
		(fill yes)
		(layer "F.Cu")
		(net "M_B_DQ<51>")
	)
	(gr_poly
		(pts
			(xy 297.659298 -44.086272) (xy 297.533568 -43.942508) (xy 297.497754 -43.906694) (xy 297.407838 -43.99661)
			(xy 297.443906 -44.032424) (xy 297.58767 -44.158154)
		)
		(stroke
			(width 0)
			(type solid)
		)
		(fill yes)
		(layer "F.Cu")
		(net "M_B_DQS_DN<6>")
	)
	(gr_poly
		(pts
			(xy 297.706288 -106.26471) (xy 297.742356 -106.228896) (xy 297.65244 -106.13898) (xy 297.616626 -106.175048)
			(xy 297.490896 -106.318558) (xy 297.562778 -106.39044)
		)
		(stroke
			(width 0)
			(type solid)
		)
		(fill yes)
		(layer "F.Cu")
		(net "M_E_DQ<50>")
	)
	(gr_poly
		(pts
			(xy 297.714416 -109.058456) (xy 297.750484 -109.022642) (xy 297.660568 -108.932726) (xy 297.624754 -108.968794)
			(xy 297.499024 -109.112304) (xy 297.570906 -109.184186)
		)
		(stroke
			(width 0)
			(type solid)
		)
		(fill yes)
		(layer "F.Cu")
		(net "M_E_DQS_DN<15>")
	)
	(gr_poly
		(pts
			(xy 297.722798 -46.46676) (xy 297.686984 -46.430692) (xy 297.54322 -46.304962) (xy 297.471338 -46.376844)
			(xy 297.597068 -46.520608) (xy 297.633136 -46.556422)
		)
		(stroke
			(width 0)
			(type solid)
		)
		(fill yes)
		(layer "F.Cu")
		(net "M_B_DQ<51>")
	)
	(gr_poly
		(pts
			(xy 297.73118 -43.673268) (xy 297.695366 -43.6372) (xy 297.551602 -43.51147) (xy 297.47972 -43.583352)
			(xy 297.60545 -43.727116) (xy 297.641518 -43.76293)
		)
		(stroke
			(width 0)
			(type solid)
		)
		(fill yes)
		(layer "F.Cu")
		(net "M_B_DQS_DN<6>")
	)
	(gr_poly
		(pts
			(xy 297.733212 -106.704892) (xy 297.858942 -106.561128) (xy 297.78706 -106.4895) (xy 297.643296 -106.61523)
			(xy 297.607482 -106.651044) (xy 297.697398 -106.74096)
		)
		(stroke
			(width 0)
			(type solid)
		)
		(fill yes)
		(layer "F.Cu")
		(net "M_E_DQ<55>")
	)
	(gr_poly
		(pts
			(xy 297.74134 -109.498638) (xy 297.86707 -109.354874) (xy 297.795188 -109.282992) (xy 297.651424 -109.408722)
			(xy 297.61561 -109.44479) (xy 297.705272 -109.534452)
		)
		(stroke
			(width 0)
			(type solid)
		)
		(fill yes)
		(layer "F.Cu")
		(net "M_E_DQS_DP<15>")
	)
	(gr_poly
		(pts
			(xy 297.749468 -45.1104) (xy 297.623738 -44.966636) (xy 297.587924 -44.930568) (xy 297.498008 -45.020484)
			(xy 297.533822 -45.056298) (xy 297.677586 -45.182028)
		)
		(stroke
			(width 0)
			(type solid)
		)
		(fill yes)
		(layer "F.Cu")
		(net "M_B_DQ<54>")
	)
	(gr_poly
		(pts
			(xy 297.804586 -108.034328) (xy 297.840654 -107.998514) (xy 297.750738 -107.908598) (xy 297.714924 -107.944666)
			(xy 297.589194 -108.088176) (xy 297.661076 -108.160058)
		)
		(stroke
			(width 0)
			(type solid)
		)
		(fill yes)
		(layer "F.Cu")
		(net "M_E_DQS_DP<6>")
	)
	(gr_poly
		(pts
			(xy 297.82135 -44.697142) (xy 297.785282 -44.661328) (xy 297.641772 -44.535598) (xy 297.56989 -44.60748)
			(xy 297.69562 -44.75099) (xy 297.731434 -44.787058)
		)
		(stroke
			(width 0)
			(type solid)
		)
		(fill yes)
		(layer "F.Cu")
		(net "M_B_DQ<54>")
	)
	(gr_poly
		(pts
			(xy 297.823128 -105.681018) (xy 297.948858 -105.537254) (xy 297.87723 -105.465372) (xy 297.733466 -105.591102)
			(xy 297.697398 -105.626916) (xy 297.787314 -105.716832)
		)
		(stroke
			(width 0)
			(type solid)
		)
		(fill yes)
		(layer "F.Cu")
		(net "M_E_DQ<51>")
	)
	(gr_poly
		(pts
			(xy 297.83151 -108.47451) (xy 297.95724 -108.330746) (xy 297.885358 -108.259118) (xy 297.741594 -108.384594)
			(xy 297.70578 -108.420662) (xy 297.795442 -108.510324)
		)
		(stroke
			(width 0)
			(type solid)
		)
		(fill yes)
		(layer "F.Cu")
		(net "M_E_DQS_DN<6>")
	)
	(gr_poly
		(pts
			(xy 297.839384 -46.134274) (xy 297.713654 -45.99051) (xy 297.67784 -45.954696) (xy 297.587924 -46.044612)
			(xy 297.623992 -46.080426) (xy 297.767756 -46.206156)
		)
		(stroke
			(width 0)
			(type solid)
		)
		(fill yes)
		(layer "F.Cu")
		(net "M_B_DQ<50>")
	)
	(gr_poly
		(pts
			(xy 297.894756 -107.0102) (xy 297.930824 -106.974386) (xy 297.840908 -106.88447) (xy 297.805094 -106.920538)
			(xy 297.679364 -107.064048) (xy 297.751246 -107.13593)
		)
		(stroke
			(width 0)
			(type solid)
		)
		(fill yes)
		(layer "F.Cu")
		(net "M_E_DQ<55>")
	)
	(gr_poly
		(pts
			(xy 297.902884 -109.803946) (xy 297.938952 -109.768132) (xy 297.849036 -109.678216) (xy 297.813222 -109.714284)
			(xy 297.687492 -109.857794) (xy 297.759374 -109.929676)
		)
		(stroke
			(width 0)
			(type solid)
		)
		(fill yes)
		(layer "F.Cu")
		(net "M_E_DQS_DP<15>")
	)
	(gr_poly
		(pts
			(xy 297.911266 -45.72127) (xy 297.875452 -45.685202) (xy 297.731688 -45.559472) (xy 297.659806 -45.631354)
			(xy 297.785536 -45.775118) (xy 297.821604 -45.810932)
		)
		(stroke
			(width 0)
			(type solid)
		)
		(fill yes)
		(layer "F.Cu")
		(net "M_B_DQ<50>")
	)
	(gr_poly
		(pts
			(xy 297.92168 -107.450382) (xy 298.04741 -107.306618) (xy 297.975528 -107.23499) (xy 297.831764 -107.36072)
			(xy 297.79595 -107.396534) (xy 297.885612 -107.486196)
		)
		(stroke
			(width 0)
			(type solid)
		)
		(fill yes)
		(layer "F.Cu")
		(net "M_E_DQ<54>")
	)
	(gr_poly
		(pts
			(xy 297.937936 -44.36491) (xy 297.812206 -44.221146) (xy 297.776138 -44.185332) (xy 297.686476 -44.274994)
			(xy 297.72229 -44.310808) (xy 297.866054 -44.436538)
		)
		(stroke
			(width 0)
			(type solid)
		)
		(fill yes)
		(layer "F.Cu")
		(net "M_B_DQS_DP<6>")
	)
	(gr_poly
		(pts
			(xy 297.984926 -105.986326) (xy 298.02074 -105.950258) (xy 297.931078 -105.860596) (xy 297.89501 -105.89641)
			(xy 297.76928 -106.040174) (xy 297.841162 -106.112056)
		)
		(stroke
			(width 0)
			(type solid)
		)
		(fill yes)
		(layer "F.Cu")
		(net "M_E_DQ<51>")
	)
	(gr_poly
		(pts
			(xy 297.993054 -108.779818) (xy 298.029122 -108.744004) (xy 297.939206 -108.654088) (xy 297.903392 -108.690156)
			(xy 297.777662 -108.833666) (xy 297.849544 -108.905548)
		)
		(stroke
			(width 0)
			(type solid)
		)
		(fill yes)
		(layer "F.Cu")
		(net "M_E_DQS_DN<6>")
	)
	(gr_poly
		(pts
			(xy 298.009818 -43.951652) (xy 297.97375 -43.915838) (xy 297.83024 -43.790108) (xy 297.758358 -43.86199)
			(xy 297.884088 -44.0055) (xy 297.919902 -44.041568)
		)
		(stroke
			(width 0)
			(type solid)
		)
		(fill yes)
		(layer "F.Cu")
		(net "M_B_DQS_DP<6>")
	)
	(gr_poly
		(pts
			(xy 298.011596 -106.426508) (xy 298.137326 -106.282744) (xy 298.065698 -106.210862) (xy 297.921934 -106.336592)
			(xy 297.885866 -106.372406) (xy 297.975782 -106.462322)
		)
		(stroke
			(width 0)
			(type solid)
		)
		(fill yes)
		(layer "F.Cu")
		(net "M_E_DQ<50>")
	)
	(gr_poly
		(pts
			(xy 298.019724 -109.220254) (xy 298.145454 -109.07649) (xy 298.073826 -109.004608) (xy 297.930062 -109.130338)
			(xy 297.893994 -109.166152) (xy 297.98391 -109.256068)
		)
		(stroke
			(width 0)
			(type solid)
		)
		(fill yes)
		(layer "F.Cu")
		(net "M_E_DQS_DN<15>")
	)
	(gr_poly
		(pts
			(xy 298.027852 -45.388784) (xy 297.902122 -45.24502) (xy 297.866308 -45.209206) (xy 297.776392 -45.299122)
			(xy 297.81246 -45.334936) (xy 297.956224 -45.460666)
		)
		(stroke
			(width 0)
			(type solid)
		)
		(fill yes)
		(layer "F.Cu")
		(net "M_B_DQ<55>")
	)
	(gr_poly
		(pts
			(xy 298.083224 -107.75569) (xy 298.119292 -107.719876) (xy 298.029376 -107.62996) (xy 297.993562 -107.666028)
			(xy 297.867832 -107.809538) (xy 297.939714 -107.88142)
		)
		(stroke
			(width 0)
			(type solid)
		)
		(fill yes)
		(layer "F.Cu")
		(net "M_E_DQ<54>")
	)
	(gr_poly
		(pts
			(xy 298.099734 -44.97578) (xy 298.06392 -44.939712) (xy 297.920156 -44.813982) (xy 297.848274 -44.885864)
			(xy 297.974004 -45.029628) (xy 298.010072 -45.065442)
		)
		(stroke
			(width 0)
			(type solid)
		)
		(fill yes)
		(layer "F.Cu")
		(net "M_B_DQ<55>")
	)
	(gr_poly
		(pts
			(xy 298.109894 -108.196126) (xy 298.235624 -108.052362) (xy 298.163996 -107.98048) (xy 298.020232 -108.10621)
			(xy 297.984164 -108.142024) (xy 298.07408 -108.23194)
		)
		(stroke
			(width 0)
			(type solid)
		)
		(fill yes)
		(layer "F.Cu")
		(net "M_E_DQS_DP<6>")
	)
	(gr_poly
		(pts
			(xy 298.118022 -46.412912) (xy 297.992292 -46.269148) (xy 297.956478 -46.23308) (xy 297.866562 -46.322996)
			(xy 297.902376 -46.35881) (xy 298.04614 -46.48454)
		)
		(stroke
			(width 0)
			(type solid)
		)
		(fill yes)
		(layer "F.Cu")
		(net "M_B_DQ<51>")
	)
	(gr_poly
		(pts
			(xy 298.126404 -43.61942) (xy 298.000674 -43.475656) (xy 297.964606 -43.439842) (xy 297.874944 -43.529504)
			(xy 297.910758 -43.565572) (xy 298.054522 -43.691048)
		)
		(stroke
			(width 0)
			(type solid)
		)
		(fill yes)
		(layer "F.Cu")
		(net "M_B_DQS_DN<6>")
	)
	(gr_poly
		(pts
			(xy 298.173394 -106.731816) (xy 298.209208 -106.695748) (xy 298.119546 -106.606086) (xy 298.083478 -106.6419)
			(xy 297.957748 -106.785664) (xy 298.02963 -106.857546)
		)
		(stroke
			(width 0)
			(type solid)
		)
		(fill yes)
		(layer "F.Cu")
		(net "M_E_DQ<50>")
	)
	(gr_poly
		(pts
			(xy 298.181522 -109.525562) (xy 298.217336 -109.489494) (xy 298.127674 -109.399832) (xy 298.091606 -109.435646)
			(xy 297.965876 -109.57941) (xy 298.037758 -109.651292)
		)
		(stroke
			(width 0)
			(type solid)
		)
		(fill yes)
		(layer "F.Cu")
		(net "M_E_DQS_DN<15>")
	)
	(gr_poly
		(pts
			(xy 298.189904 -45.999654) (xy 298.153836 -45.96384) (xy 298.010326 -45.83811) (xy 297.938444 -45.909992)
			(xy 298.064174 -46.053502) (xy 298.099988 -46.08957)
		)
		(stroke
			(width 0)
			(type solid)
		)
		(fill yes)
		(layer "F.Cu")
		(net "M_B_DQ<51>")
	)
	(gr_poly
		(pts
			(xy 298.198286 -43.206416) (xy 298.162472 -43.170348) (xy 298.018708 -43.044618) (xy 297.946826 -43.1165)
			(xy 298.072556 -43.260264) (xy 298.108624 -43.296078)
		)
		(stroke
			(width 0)
			(type solid)
		)
		(fill yes)
		(layer "F.Cu")
		(net "M_B_DQS_DN<6>")
	)
	(gr_poly
		(pts
			(xy 298.200064 -107.171998) (xy 298.325794 -107.028234) (xy 298.254166 -106.956352) (xy 298.110402 -107.082082)
			(xy 298.074334 -107.117896) (xy 298.16425 -107.207812)
		)
		(stroke
			(width 0)
			(type solid)
		)
		(fill yes)
		(layer "F.Cu")
		(net "M_E_DQ<55>")
	)
	(gr_poly
		(pts
			(xy 298.21632 -44.643294) (xy 298.09059 -44.49953) (xy 298.054776 -44.463716) (xy 297.96486 -44.553632)
			(xy 298.000928 -44.589446) (xy 298.144692 -44.715176)
		)
		(stroke
			(width 0)
			(type solid)
		)
		(fill yes)
		(layer "F.Cu")
		(net "M_B_DQ<54>")
	)
	(gr_poly
		(pts
			(xy 298.271692 -108.501434) (xy 298.307506 -108.465366) (xy 298.217844 -108.375704) (xy 298.181776 -108.411518)
			(xy 298.056046 -108.555282) (xy 298.127928 -108.627164)
		)
		(stroke
			(width 0)
			(type solid)
		)
		(fill yes)
		(layer "F.Cu")
		(net "M_E_DQS_DP<6>")
	)
	(gr_poly
		(pts
			(xy 298.288202 -44.23029) (xy 298.252388 -44.194222) (xy 298.108624 -44.068492) (xy 298.036742 -44.140374)
			(xy 298.162472 -44.284138) (xy 298.19854 -44.319952)
		)
		(stroke
			(width 0)
			(type solid)
		)
		(fill yes)
		(layer "F.Cu")
		(net "M_B_DQ<54>")
	)
	(gr_poly
		(pts
			(xy 298.290234 -106.14787) (xy 298.415964 -106.004106) (xy 298.344082 -105.932478) (xy 298.200318 -106.058208)
			(xy 298.164504 -106.094022) (xy 298.25442 -106.183938)
		)
		(stroke
			(width 0)
			(type solid)
		)
		(fill yes)
		(layer "F.Cu")
		(net "M_E_DQ<51>")
	)
	(gr_poly
		(pts
			(xy 298.298362 -108.941616) (xy 298.424092 -108.797852) (xy 298.352464 -108.72597) (xy 298.2087 -108.8517)
			(xy 298.172632 -108.887514) (xy 298.262548 -108.97743)
		)
		(stroke
			(width 0)
			(type solid)
		)
		(fill yes)
		(layer "F.Cu")
		(net "M_E_DQS_DN<6>")
	)
	(gr_poly
		(pts
			(xy 298.30649 -45.667422) (xy 298.18076 -45.523658) (xy 298.144946 -45.48759) (xy 298.05503 -45.577506)
			(xy 298.090844 -45.61332) (xy 298.234608 -45.73905)
		)
		(stroke
			(width 0)
			(type solid)
		)
		(fill yes)
		(layer "F.Cu")
		(net "M_B_DQ<50>")
	)
	(gr_poly
		(pts
			(xy 298.361862 -107.477306) (xy 298.397676 -107.441238) (xy 298.308014 -107.351576) (xy 298.271946 -107.38739)
			(xy 298.146216 -107.531154) (xy 298.218098 -107.603036)
		)
		(stroke
			(width 0)
			(type solid)
		)
		(fill yes)
		(layer "F.Cu")
		(net "M_E_DQ<55>")
	)
	(gr_poly
		(pts
			(xy 298.378372 -45.254164) (xy 298.342304 -45.21835) (xy 298.198794 -45.09262) (xy 298.126912 -45.164502)
			(xy 298.252642 -45.308012) (xy 298.288456 -45.34408)
		)
		(stroke
			(width 0)
			(type solid)
		)
		(fill yes)
		(layer "F.Cu")
		(net "M_B_DQ<50>")
	)
	(gr_poly
		(pts
			(xy 298.388532 -107.917488) (xy 298.514262 -107.773724) (xy 298.442634 -107.701842) (xy 298.29887 -107.827572)
			(xy 298.262802 -107.863386) (xy 298.352718 -107.953302)
		)
		(stroke
			(width 0)
			(type solid)
		)
		(fill yes)
		(layer "F.Cu")
		(net "M_E_DQ<54>")
	)
	(gr_poly
		(pts
			(xy 298.404788 -43.897804) (xy 298.279058 -43.75404) (xy 298.243244 -43.718226) (xy 298.153328 -43.808142)
			(xy 298.189396 -43.843956) (xy 298.33316 -43.969686)
		)
		(stroke
			(width 0)
			(type solid)
		)
		(fill yes)
		(layer "F.Cu")
		(net "M_B_DQS_DP<6>")
	)
	(gr_poly
		(pts
			(xy 298.451778 -106.453178) (xy 298.487846 -106.417364) (xy 298.39793 -106.327448) (xy 298.362116 -106.363516)
			(xy 298.236386 -106.507026) (xy 298.308268 -106.578908)
		)
		(stroke
			(width 0)
			(type solid)
		)
		(fill yes)
		(layer "F.Cu")
		(net "M_E_DQ<51>")
	)
	(gr_poly
		(pts
			(xy 298.46016 -109.246924) (xy 298.495974 -109.210856) (xy 298.406312 -109.121194) (xy 298.370244 -109.157008)
			(xy 298.244514 -109.300772) (xy 298.316396 -109.372654)
		)
		(stroke
			(width 0)
			(type solid)
		)
		(fill yes)
		(layer "F.Cu")
		(net "M_E_DQS_DN<6>")
	)
	(gr_poly
		(pts
			(xy 298.47667 -43.4848) (xy 298.440856 -43.448732) (xy 298.297092 -43.323002) (xy 298.22521 -43.394884)
			(xy 298.35094 -43.538648) (xy 298.387008 -43.574462)
		)
		(stroke
			(width 0)
			(type solid)
		)
		(fill yes)
		(layer "F.Cu")
		(net "M_B_DQS_DP<6>")
	)
	(gr_poly
		(pts
			(xy 298.478702 -106.89336) (xy 298.604432 -106.749596) (xy 298.53255 -106.677968) (xy 298.388786 -106.803698)
			(xy 298.352972 -106.839512) (xy 298.442634 -106.929174)
		)
		(stroke
			(width 0)
			(type solid)
		)
		(fill yes)
		(layer "F.Cu")
		(net "M_E_DQ<50>")
	)
	(gr_poly
		(pts
			(xy 298.494958 -44.921932) (xy 298.369228 -44.778168) (xy 298.33316 -44.742354) (xy 298.243498 -44.832016)
			(xy 298.279312 -44.86783) (xy 298.423076 -44.99356)
		)
		(stroke
			(width 0)
			(type solid)
		)
		(fill yes)
		(layer "F.Cu")
		(net "M_B_DQ<55>")
	)
	(gr_poly
		(pts
			(xy 298.55033 -108.222796) (xy 298.586144 -108.186728) (xy 298.496482 -108.097066) (xy 298.460414 -108.13288)
			(xy 298.334684 -108.276644) (xy 298.406566 -108.348526)
		)
		(stroke
			(width 0)
			(type solid)
		)
		(fill yes)
		(layer "F.Cu")
		(net "M_E_DQ<54>")
	)
	(gr_poly
		(pts
			(xy 298.56684 -44.508674) (xy 298.530772 -44.47286) (xy 298.387262 -44.34713) (xy 298.31538 -44.419012)
			(xy 298.44111 -44.562522) (xy 298.476924 -44.59859)
		)
		(stroke
			(width 0)
			(type solid)
		)
		(fill yes)
		(layer "F.Cu")
		(net "M_B_DQ<55>")
	)
	(gr_poly
		(pts
			(xy 298.577 -108.662978) (xy 298.70273 -108.519214) (xy 298.630848 -108.447332) (xy 298.487084 -108.573062)
			(xy 298.45127 -108.60913) (xy 298.540932 -108.698792)
		)
		(stroke
			(width 0)
			(type solid)
		)
		(fill yes)
		(layer "F.Cu")
		(net "M_E_DQS_DP<6>")
	)
	(gr_poly
		(pts
			(xy 298.584874 -45.945806) (xy 298.459144 -45.802042) (xy 298.42333 -45.766228) (xy 298.333414 -45.856144)
			(xy 298.369482 -45.891958) (xy 298.513246 -46.017688)
		)
		(stroke
			(width 0)
			(type solid)
		)
		(fill yes)
		(layer "F.Cu")
		(net "M_B_DQ<51>")
	)
	(gr_poly
		(pts
			(xy 298.593256 -43.152568) (xy 298.467526 -43.008804) (xy 298.431458 -42.97299) (xy 298.341796 -43.062652)
			(xy 298.37761 -43.09872) (xy 298.521374 -43.224196)
		)
		(stroke
			(width 0)
			(type solid)
		)
		(fill yes)
		(layer "F.Cu")
		(net "M_B_DQS_DN<6>")
	)
	(gr_poly
		(pts
			(xy 298.640246 -107.198668) (xy 298.676314 -107.162854) (xy 298.586398 -107.072938) (xy 298.550584 -107.109006)
			(xy 298.424854 -107.252516) (xy 298.496736 -107.324398)
		)
		(stroke
			(width 0)
			(type solid)
		)
		(fill yes)
		(layer "F.Cu")
		(net "M_E_DQ<50>")
	)
	(gr_poly
		(pts
			(xy 298.656756 -45.532802) (xy 298.620942 -45.496734) (xy 298.477178 -45.371004) (xy 298.405296 -45.442886)
			(xy 298.531026 -45.58665) (xy 298.567094 -45.622464)
		)
		(stroke
			(width 0)
			(type solid)
		)
		(fill yes)
		(layer "F.Cu")
		(net "M_B_DQ<51>")
	)
	(gr_poly
		(pts
			(xy 298.66717 -107.63885) (xy 298.7929 -107.495086) (xy 298.721018 -107.423458) (xy 298.577254 -107.548934)
			(xy 298.54144 -107.585002) (xy 298.631102 -107.674664)
		)
		(stroke
			(width 0)
			(type solid)
		)
		(fill yes)
		(layer "F.Cu")
		(net "M_E_DQ<55>")
	)
	(gr_poly
		(pts
			(xy 298.683426 -44.176442) (xy 298.557696 -44.032678) (xy 298.521628 -43.996864) (xy 298.431966 -44.086526)
			(xy 298.46778 -44.122594) (xy 298.611544 -44.24807)
		)
		(stroke
			(width 0)
			(type solid)
		)
		(fill yes)
		(layer "F.Cu")
		(net "M_B_DQ<54>")
	)
	(gr_poly
		(pts
			(xy 298.738544 -108.968286) (xy 298.774612 -108.932472) (xy 298.684696 -108.842556) (xy 298.648882 -108.878624)
			(xy 298.523152 -109.022134) (xy 298.595034 -109.094016)
		)
		(stroke
			(width 0)
			(type solid)
		)
		(fill yes)
		(layer "F.Cu")
		(net "M_E_DQS_DP<6>")
	)
	(gr_poly
		(pts
			(xy 298.755308 -43.763184) (xy 298.71924 -43.72737) (xy 298.57573 -43.60164) (xy 298.503848 -43.673522)
			(xy 298.629578 -43.817032) (xy 298.665392 -43.8531)
		)
		(stroke
			(width 0)
			(type solid)
		)
		(fill yes)
		(layer "F.Cu")
		(net "M_B_DQ<54>")
	)
	(gr_poly
		(pts
			(xy 298.757086 -106.614976) (xy 298.882816 -106.471212) (xy 298.811188 -106.39933) (xy 298.667424 -106.52506)
			(xy 298.631356 -106.560874) (xy 298.721272 -106.65079)
		)
		(stroke
			(width 0)
			(type solid)
		)
		(fill yes)
		(layer "F.Cu")
		(net "M_E_DQ<51>")
	)
	(gr_poly
		(pts
			(xy 298.773342 -45.200316) (xy 298.647612 -45.056552) (xy 298.611798 -45.020738) (xy 298.521882 -45.110654)
			(xy 298.55795 -45.146468) (xy 298.701714 -45.272198)
		)
		(stroke
			(width 0)
			(type solid)
		)
		(fill yes)
		(layer "F.Cu")
		(net "M_B_DQ<50>")
	)
	(gr_poly
		(pts
			(xy 298.828714 -107.944158) (xy 298.864782 -107.908344) (xy 298.774866 -107.818428) (xy 298.739052 -107.854496)
			(xy 298.613322 -107.998006) (xy 298.685204 -108.069888)
		)
		(stroke
			(width 0)
			(type solid)
		)
		(fill yes)
		(layer "F.Cu")
		(net "M_E_DQ<55>")
	)
	(gr_poly
		(pts
			(xy 298.845224 -44.787312) (xy 298.80941 -44.751244) (xy 298.665646 -44.625514) (xy 298.593764 -44.697396)
			(xy 298.719494 -44.84116) (xy 298.755562 -44.876974)
		)
		(stroke
			(width 0)
			(type solid)
		)
		(fill yes)
		(layer "F.Cu")
		(net "M_B_DQ<50>")
	)
	(gr_poly
		(pts
			(xy 298.855638 -108.38434) (xy 298.981368 -108.240576) (xy 298.909486 -108.168694) (xy 298.765722 -108.294424)
			(xy 298.729908 -108.330492) (xy 298.81957 -108.420154)
		)
		(stroke
			(width 0)
			(type solid)
		)
		(fill yes)
		(layer "F.Cu")
		(net "M_E_DQ<54>")
	)
	(gr_poly
		(pts
			(xy 298.918884 -106.920284) (xy 298.954698 -106.884216) (xy 298.865036 -106.794554) (xy 298.828968 -106.830368)
			(xy 298.703238 -106.974132) (xy 298.77512 -107.046014)
		)
		(stroke
			(width 0)
			(type solid)
		)
		(fill yes)
		(layer "F.Cu")
		(net "M_E_DQ<51>")
	)
	(gr_poly
		(pts
			(xy 298.945554 -107.360466) (xy 299.071284 -107.216702) (xy 298.999656 -107.14482) (xy 298.855892 -107.27055)
			(xy 298.819824 -107.306364) (xy 298.90974 -107.39628)
		)
		(stroke
			(width 0)
			(type solid)
		)
		(fill yes)
		(layer "F.Cu")
		(net "M_E_DQ<50>")
	)
	(gr_poly
		(pts
			(xy 298.96181 -44.454826) (xy 298.83608 -44.311062) (xy 298.800266 -44.275248) (xy 298.71035 -44.365164)
			(xy 298.746418 -44.400978) (xy 298.890182 -44.526708)
		)
		(stroke
			(width 0)
			(type solid)
		)
		(fill yes)
		(layer "F.Cu")
		(net "M_B_DQ<55>")
	)
	(gr_poly
		(pts
			(xy 299.033692 -44.041822) (xy 298.997878 -44.005754) (xy 298.854114 -43.880024) (xy 298.782232 -43.951906)
			(xy 298.907962 -44.09567) (xy 298.94403 -44.131484)
		)
		(stroke
			(width 0)
			(type solid)
		)
		(fill yes)
		(layer "F.Cu")
		(net "M_B_DQ<55>")
	)
	(gr_poly
		(pts
			(xy 299.05198 -45.478954) (xy 298.92625 -45.33519) (xy 298.890182 -45.299376) (xy 298.80052 -45.389038)
			(xy 298.836334 -45.424852) (xy 298.980098 -45.550582)
		)
		(stroke
			(width 0)
			(type solid)
		)
		(fill yes)
		(layer "F.Cu")
		(net "M_B_DQ<51>")
	)
	(gr_poly
		(pts
			(xy 299.107352 -107.665774) (xy 299.143166 -107.629706) (xy 299.053504 -107.540044) (xy 299.017436 -107.575858)
			(xy 298.891706 -107.719622) (xy 298.963588 -107.791504)
		)
		(stroke
			(width 0)
			(type solid)
		)
		(fill yes)
		(layer "F.Cu")
		(net "M_E_DQ<50>")
	)
	(gr_poly
		(pts
			(xy 299.123862 -45.065696) (xy 299.087794 -45.029882) (xy 298.944284 -44.904152) (xy 298.872402 -44.976034)
			(xy 298.998132 -45.119544) (xy 299.033946 -45.155612)
		)
		(stroke
			(width 0)
			(type solid)
		)
		(fill yes)
		(layer "F.Cu")
		(net "M_B_DQ<51>")
	)
	(gr_poly
		(pts
			(xy 299.134022 -108.105956) (xy 299.259752 -107.962192) (xy 299.188124 -107.89031) (xy 299.04436 -108.01604)
			(xy 299.008292 -108.051854) (xy 299.098208 -108.14177)
		)
		(stroke
			(width 0)
			(type solid)
		)
		(fill yes)
		(layer "F.Cu")
		(net "M_E_DQ<55>")
	)
	(gr_poly
		(pts
			(xy 299.150278 -43.709336) (xy 299.024548 -43.565572) (xy 298.988734 -43.529758) (xy 298.898818 -43.619674)
			(xy 298.934886 -43.655488) (xy 299.07865 -43.781218)
		)
		(stroke
			(width 0)
			(type solid)
		)
		(fill yes)
		(layer "F.Cu")
		(net "M_B_DQ<54>")
	)
	(gr_poly
		(pts
			(xy 299.224192 -107.081828) (xy 299.349922 -106.938064) (xy 299.27804 -106.866436) (xy 299.134276 -106.991912)
			(xy 299.098462 -107.02798) (xy 299.188124 -107.117642)
		)
		(stroke
			(width 0)
			(type solid)
		)
		(fill yes)
		(layer "F.Cu")
		(net "M_E_DQ<51>")
	)
	(gr_poly
		(pts
			(xy 299.240448 -44.733464) (xy 299.114718 -44.5897) (xy 299.07865 -44.553886) (xy 298.988988 -44.643548)
			(xy 299.024802 -44.679616) (xy 299.168566 -44.805092)
		)
		(stroke
			(width 0)
			(type solid)
		)
		(fill yes)
		(layer "F.Cu")
		(net "M_B_DQ<50>")
	)
	(gr_poly
		(pts
			(xy 299.31233 -44.320206) (xy 299.276262 -44.284392) (xy 299.132752 -44.158662) (xy 299.06087 -44.230544)
			(xy 299.1866 -44.374054) (xy 299.222414 -44.410122)
		)
		(stroke
			(width 0)
			(type solid)
		)
		(fill yes)
		(layer "F.Cu")
		(net "M_B_DQ<50>")
	)
	(gr_poly
		(pts
			(xy 299.385736 -107.387136) (xy 299.421804 -107.351322) (xy 299.331888 -107.261406) (xy 299.296074 -107.297474)
			(xy 299.170344 -107.440984) (xy 299.242226 -107.512866)
		)
		(stroke
			(width 0)
			(type solid)
		)
		(fill yes)
		(layer "F.Cu")
		(net "M_E_DQ<51>")
	)
	(gr_poly
		(pts
			(xy 299.428916 -43.987974) (xy 299.303186 -43.84421) (xy 299.267118 -43.808396) (xy 299.177456 -43.898058)
			(xy 299.21327 -43.934126) (xy 299.357034 -44.059856)
		)
		(stroke
			(width 0)
			(type solid)
		)
		(fill yes)
		(layer "F.Cu")
		(net "M_B_DQ<55>")
	)
	(gr_poly
		(pts
			(xy 299.518832 -45.011848) (xy 299.393102 -44.868084) (xy 299.357288 -44.83227) (xy 299.267372 -44.922186)
			(xy 299.30344 -44.958) (xy 299.447204 -45.08373)
		)
		(stroke
			(width 0)
			(type solid)
		)
		(fill yes)
		(layer "F.Cu")
		(net "M_B_DQ<51>")
	)
	(gr_poly
		(pts
			(xy 299.590714 -44.598844) (xy 299.5549 -44.562776) (xy 299.411136 -44.437046) (xy 299.339254 -44.508928)
			(xy 299.464984 -44.652692) (xy 299.501052 -44.688506)
		)
		(stroke
			(width 0)
			(type solid)
		)
		(fill yes)
		(layer "F.Cu")
		(net "M_B_DQ<51>")
	)
	(gr_poly
		(pts
			(xy 299.7073 -44.266358) (xy 299.58157 -44.122594) (xy 299.545756 -44.08678) (xy 299.45584 -44.176696)
			(xy 299.491908 -44.21251) (xy 299.635672 -44.33824)
		)
		(stroke
			(width 0)
			(type solid)
		)
		(fill yes)
		(layer "F.Cu")
		(net "M_B_DQ<50>")
	)
	(gr_poly
		(pts
			(xy 299.985938 -44.544996) (xy 299.860208 -44.401232) (xy 299.82414 -44.365418) (xy 299.734478 -44.45508)
			(xy 299.770292 -44.491148) (xy 299.914056 -44.616878)
		)
		(stroke
			(width 0)
			(type solid)
		)
		(fill yes)
		(layer "F.Cu")
		(net "M_B_DQ<51>")
	)
	(gr_poly
		(pts
			(xy 33.434782 -93.18879) (xy 33.434782 -92.491814) (xy 33.630616 -92.29598) (xy 33.630616 -89.93378)
			(xy 31.6484 -89.93378) (xy 31.6484 -91.270582) (xy 31.613602 -91.30538) (xy 31.613602 -91.317064)
			(xy 31.486602 -91.444064) (xy 30.734 -91.444064) (xy 30.189424 -91.98864) (xy 28.8798 -91.98864)
			(xy 28.829 -92.03944) (xy 28.829 -92.125292) (xy 28.829508 -92.125292) (xy 28.829508 -92.583254)
			(xy 29.452316 -93.206316) (xy 31.636716 -93.206316) (xy 31.987998 -92.855034) (xy 32.71012 -92.855034)
			(xy 33.127188 -93.272102) (xy 33.35147 -93.272102)
		)
		(stroke
			(width 0)
			(type solid)
		)
		(fill yes)
		(layer "F.Cu")
		(net "VR_FET_SW_P12V_STBY_PVCCIN_CPU1")
	)
	(gr_poly
		(pts
			(arc
				(start 30.1752 -75.8698)
				(mid 30.229082 -75.847482)
				(end 30.2514 -75.7936)
			)
			(arc
				(start 30.2514 -75.7936)
				(mid 30.229082 -75.739718)
				(end 30.1752 -75.7174)
			)
			(arc
				(start 30.1752 -75.7174)
				(mid 30.121318 -75.739718)
				(end 30.099 -75.7936)
			)
			(arc
				(start 30.099 -75.7936)
				(mid 30.121318 -75.847482)
				(end 30.1752 -75.8698)
			)
		)
		(stroke
			(width 0)
			(type solid)
		)
		(fill yes)
		(layer "F.Cu")
		(net "GND")
	)
	(gr_poly
		(pts
			(arc
				(start 187.0202 -137.6172)
				(mid 187.074082 -137.594882)
				(end 187.0964 -137.541)
			)
			(arc
				(start 187.0964 -137.541)
				(mid 187.074082 -137.487118)
				(end 187.0202 -137.4648)
			)
			(arc
				(start 187.0202 -137.4648)
				(mid 186.966318 -137.487118)
				(end 186.944 -137.541)
			)
			(arc
				(start 186.944 -137.541)
				(mid 186.966318 -137.594882)
				(end 187.0202 -137.6172)
			)
		)
		(stroke
			(width 0)
			(type solid)
		)
		(fill yes)
		(layer "F.Cu")
		(net "GND")
	)
	(gr_poly
		(pts
			(arc
				(start 316.820804 -31.267908)
				(mid 316.874686 -31.24559)
				(end 316.897004 -31.191708)
			)
			(arc
				(start 316.897004 -31.191708)
				(mid 316.874686 -31.137826)
				(end 316.820804 -31.115508)
			)
			(arc
				(start 316.820804 -31.115508)
				(mid 316.766922 -31.137826)
				(end 316.744604 -31.191708)
			)
			(arc
				(start 316.744604 -31.191708)
				(mid 316.766922 -31.24559)
				(end 316.820804 -31.267908)
			)
		)
		(stroke
			(width 0)
			(type solid)
		)
		(fill yes)
		(layer "F.Cu")
		(net "GND")
	)
	(gr_poly
		(pts
			(arc
				(start 319.4812 -28.2448)
				(mid 319.535082 -28.222482)
				(end 319.5574 -28.1686)
			)
			(arc
				(start 319.5574 -28.1686)
				(mid 319.535082 -28.114718)
				(end 319.4812 -28.0924)
			)
			(arc
				(start 319.4812 -28.0924)
				(mid 319.427318 -28.114718)
				(end 319.405 -28.1686)
			)
			(arc
				(start 319.405 -28.1686)
				(mid 319.427318 -28.222482)
				(end 319.4812 -28.2448)
			)
		)
		(stroke
			(width 0)
			(type solid)
		)
		(fill yes)
		(layer "F.Cu")
		(net "GND")
	)
	(gr_poly
		(pts
			(arc
				(start 320.167 -29.919422)
				(mid 320.220882 -29.897104)
				(end 320.2432 -29.843222)
			)
			(arc
				(start 320.2432 -29.843222)
				(mid 320.220882 -29.78934)
				(end 320.167 -29.767022)
			)
			(arc
				(start 320.167 -29.767022)
				(mid 320.113118 -29.78934)
				(end 320.0908 -29.843222)
			)
			(arc
				(start 320.0908 -29.843222)
				(mid 320.113118 -29.897104)
				(end 320.167 -29.919422)
			)
		)
		(stroke
			(width 0)
			(type solid)
		)
		(fill yes)
		(layer "F.Cu")
		(net "GND")
	)
	(gr_poly
		(pts
			(arc
				(start 333.9846 -59.755786)
				(mid 334.038482 -59.733468)
				(end 334.0608 -59.679586)
			)
			(arc
				(start 334.0608 -59.679586)
				(mid 334.038482 -59.625704)
				(end 333.9846 -59.603386)
			)
			(arc
				(start 333.9846 -59.603386)
				(mid 333.930718 -59.625704)
				(end 333.9084 -59.679586)
			)
			(arc
				(start 333.9084 -59.679586)
				(mid 333.930718 -59.733468)
				(end 333.9846 -59.755786)
			)
		)
		(stroke
			(width 0)
			(type solid)
		)
		(fill yes)
		(layer "F.Cu")
		(net "GND")
	)
	(gr_poly
		(pts
			(arc
				(start 334.3402 -71.7042)
				(mid 334.394082 -71.681882)
				(end 334.4164 -71.628)
			)
			(arc
				(start 334.4164 -71.628)
				(mid 334.394082 -71.574118)
				(end 334.3402 -71.5518)
			)
			(arc
				(start 334.3402 -71.5518)
				(mid 334.286318 -71.574118)
				(end 334.264 -71.628)
			)
			(arc
				(start 334.264 -71.628)
				(mid 334.286318 -71.681882)
				(end 334.3402 -71.7042)
			)
		)
		(stroke
			(width 0)
			(type solid)
		)
		(fill yes)
		(layer "F.Cu")
		(net "GND")
	)
	(gr_poly
		(pts
			(arc
				(start 335.3816 -59.755786)
				(mid 335.435482 -59.733468)
				(end 335.4578 -59.679586)
			)
			(arc
				(start 335.4578 -59.679586)
				(mid 335.435482 -59.625704)
				(end 335.3816 -59.603386)
			)
			(arc
				(start 335.3816 -59.603386)
				(mid 335.327718 -59.625704)
				(end 335.3054 -59.679586)
			)
			(arc
				(start 335.3054 -59.679586)
				(mid 335.327718 -59.733468)
				(end 335.3816 -59.755786)
			)
		)
		(stroke
			(width 0)
			(type solid)
		)
		(fill yes)
		(layer "F.Cu")
		(net "GND")
	)
	(gr_poly
		(pts
			(arc
				(start 336.6262 -71.8566)
				(mid 336.680082 -71.834282)
				(end 336.7024 -71.7804)
			)
			(arc
				(start 336.7024 -71.7804)
				(mid 336.680082 -71.726518)
				(end 336.6262 -71.7042)
			)
			(arc
				(start 336.6262 -71.7042)
				(mid 336.572318 -71.726518)
				(end 336.55 -71.7804)
			)
			(arc
				(start 336.55 -71.7804)
				(mid 336.572318 -71.834282)
				(end 336.6262 -71.8566)
			)
		)
		(stroke
			(width 0)
			(type solid)
		)
		(fill yes)
		(layer "F.Cu")
		(net "GND")
	)
	(gr_poly
		(pts
			(arc
				(start 336.7786 -59.755786)
				(mid 336.832482 -59.733468)
				(end 336.8548 -59.679586)
			)
			(arc
				(start 336.8548 -59.679586)
				(mid 336.832482 -59.625704)
				(end 336.7786 -59.603386)
			)
			(arc
				(start 336.7786 -59.603386)
				(mid 336.724718 -59.625704)
				(end 336.7024 -59.679586)
			)
			(arc
				(start 336.7024 -59.679586)
				(mid 336.724718 -59.733468)
				(end 336.7786 -59.755786)
			)
		)
		(stroke
			(width 0)
			(type solid)
		)
		(fill yes)
		(layer "F.Cu")
		(net "GND")
	)
	(gr_poly
		(pts
			(arc
				(start 338.1756 -59.755786)
				(mid 338.229482 -59.733468)
				(end 338.2518 -59.679586)
			)
			(arc
				(start 338.2518 -59.679586)
				(mid 338.229482 -59.625704)
				(end 338.1756 -59.603386)
			)
			(arc
				(start 338.1756 -59.603386)
				(mid 338.121718 -59.625704)
				(end 338.0994 -59.679586)
			)
			(arc
				(start 338.0994 -59.679586)
				(mid 338.121718 -59.733468)
				(end 338.1756 -59.755786)
			)
		)
		(stroke
			(width 0)
			(type solid)
		)
		(fill yes)
		(layer "F.Cu")
		(net "GND")
	)
	(gr_poly
		(pts
			(arc
				(start 338.864702 -69.44741)
				(mid 338.918584 -69.425092)
				(end 338.940902 -69.37121)
			)
			(arc
				(start 338.940902 -69.37121)
				(mid 338.918584 -69.317328)
				(end 338.864702 -69.29501)
			)
			(arc
				(start 338.864702 -69.29501)
				(mid 338.81082 -69.317328)
				(end 338.788502 -69.37121)
			)
			(arc
				(start 338.788502 -69.37121)
				(mid 338.81082 -69.425092)
				(end 338.864702 -69.44741)
			)
		)
		(stroke
			(width 0)
			(type solid)
		)
		(fill yes)
		(layer "F.Cu")
		(net "GND")
	)
	(gr_poly
		(pts
			(arc
				(start 339.46592 -78.75397)
				(mid 339.519802 -78.731652)
				(end 339.54212 -78.67777)
			)
			(arc
				(start 339.54212 -78.67777)
				(mid 339.519802 -78.623888)
				(end 339.46592 -78.60157)
			)
			(arc
				(start 339.46592 -78.60157)
				(mid 339.412038 -78.623888)
				(end 339.38972 -78.67777)
			)
			(arc
				(start 339.38972 -78.67777)
				(mid 339.412038 -78.731652)
				(end 339.46592 -78.75397)
			)
		)
		(stroke
			(width 0)
			(type solid)
		)
		(fill yes)
		(layer "F.Cu")
		(net "GND")
	)
	(gr_poly
		(pts
			(arc
				(start 339.545422 -77.237336)
				(mid 339.599304 -77.215018)
				(end 339.621622 -77.161136)
			)
			(arc
				(start 339.621622 -77.161136)
				(mid 339.599304 -77.107254)
				(end 339.545422 -77.084936)
			)
			(arc
				(start 339.545422 -77.084936)
				(mid 339.49154 -77.107254)
				(end 339.469222 -77.161136)
			)
			(arc
				(start 339.469222 -77.161136)
				(mid 339.49154 -77.215018)
				(end 339.545422 -77.237336)
			)
		)
		(stroke
			(width 0)
			(type solid)
		)
		(fill yes)
		(layer "F.Cu")
		(net "GND")
	)
	(gr_poly
		(pts
			(arc
				(start 339.5726 -59.755786)
				(mid 339.626482 -59.733468)
				(end 339.6488 -59.679586)
			)
			(arc
				(start 339.6488 -59.679586)
				(mid 339.626482 -59.625704)
				(end 339.5726 -59.603386)
			)
			(arc
				(start 339.5726 -59.603386)
				(mid 339.518718 -59.625704)
				(end 339.4964 -59.679586)
			)
			(arc
				(start 339.4964 -59.679586)
				(mid 339.518718 -59.733468)
				(end 339.5726 -59.755786)
			)
		)
		(stroke
			(width 0)
			(type solid)
		)
		(fill yes)
		(layer "F.Cu")
		(net "GND")
	)
	(gr_poly
		(pts
			(arc
				(start 339.979 -81.2546)
				(mid 340.032882 -81.232282)
				(end 340.0552 -81.1784)
			)
			(arc
				(start 340.0552 -81.1784)
				(mid 340.032882 -81.124518)
				(end 339.979 -81.1022)
			)
			(arc
				(start 339.979 -81.1022)
				(mid 339.925118 -81.124518)
				(end 339.9028 -81.1784)
			)
			(arc
				(start 339.9028 -81.1784)
				(mid 339.925118 -81.232282)
				(end 339.979 -81.2546)
			)
		)
		(stroke
			(width 0)
			(type solid)
		)
		(fill yes)
		(layer "F.Cu")
		(net "GND")
	)
	(gr_poly
		(pts
			(arc
				(start 340.579964 -68.35013)
				(mid 340.633846 -68.327812)
				(end 340.656164 -68.27393)
			)
			(arc
				(start 340.656164 -68.27393)
				(mid 340.633846 -68.220048)
				(end 340.579964 -68.19773)
			)
			(arc
				(start 340.579964 -68.19773)
				(mid 340.526082 -68.220048)
				(end 340.503764 -68.27393)
			)
			(arc
				(start 340.503764 -68.27393)
				(mid 340.526082 -68.327812)
				(end 340.579964 -68.35013)
			)
		)
		(stroke
			(width 0)
			(type solid)
		)
		(fill yes)
		(layer "F.Cu")
		(net "GND")
	)
	(gr_poly
		(pts
			(arc
				(start 340.84768 -78.75397)
				(mid 340.901562 -78.731652)
				(end 340.92388 -78.67777)
			)
			(arc
				(start 340.92388 -78.67777)
				(mid 340.901562 -78.623888)
				(end 340.84768 -78.60157)
			)
			(arc
				(start 340.84768 -78.60157)
				(mid 340.793798 -78.623888)
				(end 340.77148 -78.67777)
			)
			(arc
				(start 340.77148 -78.67777)
				(mid 340.793798 -78.731652)
				(end 340.84768 -78.75397)
			)
		)
		(stroke
			(width 0)
			(type solid)
		)
		(fill yes)
		(layer "F.Cu")
		(net "GND")
	)
	(gr_poly
		(pts
			(arc
				(start 340.9696 -59.755786)
				(mid 341.023482 -59.733468)
				(end 341.0458 -59.679586)
			)
			(arc
				(start 341.0458 -59.679586)
				(mid 341.023482 -59.625704)
				(end 340.9696 -59.603386)
			)
			(arc
				(start 340.9696 -59.603386)
				(mid 340.915718 -59.625704)
				(end 340.8934 -59.679586)
			)
			(arc
				(start 340.8934 -59.679586)
				(mid 340.915718 -59.733468)
				(end 340.9696 -59.755786)
			)
		)
		(stroke
			(width 0)
			(type solid)
		)
		(fill yes)
		(layer "F.Cu")
		(net "GND")
	)
	(gr_poly
		(pts
			(arc
				(start 340.98992 -77.254608)
				(mid 341.043802 -77.23229)
				(end 341.06612 -77.178408)
			)
			(arc
				(start 341.06612 -77.178408)
				(mid 341.043802 -77.124526)
				(end 340.98992 -77.102208)
			)
			(arc
				(start 340.98992 -77.102208)
				(mid 340.936038 -77.124526)
				(end 340.91372 -77.178408)
			)
			(arc
				(start 340.91372 -77.178408)
				(mid 340.936038 -77.23229)
				(end 340.98992 -77.254608)
			)
		)
		(stroke
			(width 0)
			(type solid)
		)
		(fill yes)
		(layer "F.Cu")
		(net "GND")
	)
	(gr_poly
		(pts
			(arc
				(start 340.995 -79.3496)
				(mid 341.048882 -79.327282)
				(end 341.0712 -79.2734)
			)
			(arc
				(start 341.0712 -79.2734)
				(mid 341.048882 -79.219518)
				(end 340.995 -79.1972)
			)
			(arc
				(start 340.995 -79.1972)
				(mid 340.941118 -79.219518)
				(end 340.9188 -79.2734)
			)
			(arc
				(start 340.9188 -79.2734)
				(mid 340.941118 -79.327282)
				(end 340.995 -79.3496)
			)
		)
		(stroke
			(width 0)
			(type solid)
		)
		(fill yes)
		(layer "F.Cu")
		(net "GND")
	)
	(gr_poly
		(pts
			(arc
				(start 342.0237 -81.9531)
				(mid 342.077582 -81.930782)
				(end 342.0999 -81.8769)
			)
			(arc
				(start 342.0999 -81.8769)
				(mid 342.077582 -81.823018)
				(end 342.0237 -81.8007)
			)
			(arc
				(start 342.0237 -81.8007)
				(mid 341.969818 -81.823018)
				(end 341.9475 -81.8769)
			)
			(arc
				(start 341.9475 -81.8769)
				(mid 341.969818 -81.930782)
				(end 342.0237 -81.9531)
			)
		)
		(stroke
			(width 0)
			(type solid)
		)
		(fill yes)
		(layer "F.Cu")
		(net "GND")
	)
	(gr_poly
		(pts
			(arc
				(start 342.3666 -59.755786)
				(mid 342.420482 -59.733468)
				(end 342.4428 -59.679586)
			)
			(arc
				(start 342.4428 -59.679586)
				(mid 342.420482 -59.625704)
				(end 342.3666 -59.603386)
			)
			(arc
				(start 342.3666 -59.603386)
				(mid 342.312718 -59.625704)
				(end 342.2904 -59.679586)
			)
			(arc
				(start 342.2904 -59.679586)
				(mid 342.312718 -59.733468)
				(end 342.3666 -59.755786)
			)
		)
		(stroke
			(width 0)
			(type solid)
		)
		(fill yes)
		(layer "F.Cu")
		(net "GND")
	)
	(gr_poly
		(pts
			(arc
				(start 342.41232 -78.77175)
				(mid 342.466202 -78.749432)
				(end 342.48852 -78.69555)
			)
			(arc
				(start 342.48852 -78.69555)
				(mid 342.466202 -78.641668)
				(end 342.41232 -78.61935)
			)
			(arc
				(start 342.41232 -78.61935)
				(mid 342.358438 -78.641668)
				(end 342.33612 -78.69555)
			)
			(arc
				(start 342.33612 -78.69555)
				(mid 342.358438 -78.749432)
				(end 342.41232 -78.77175)
			)
		)
		(stroke
			(width 0)
			(type solid)
		)
		(fill yes)
		(layer "F.Cu")
		(net "GND")
	)
	(gr_poly
		(pts
			(arc
				(start 342.44026 -77.24394)
				(mid 342.494142 -77.221622)
				(end 342.51646 -77.16774)
			)
			(arc
				(start 342.51646 -77.16774)
				(mid 342.494142 -77.113858)
				(end 342.44026 -77.09154)
			)
			(arc
				(start 342.44026 -77.09154)
				(mid 342.386378 -77.113858)
				(end 342.36406 -77.16774)
			)
			(arc
				(start 342.36406 -77.16774)
				(mid 342.386378 -77.221622)
				(end 342.44026 -77.24394)
			)
		)
		(stroke
			(width 0)
			(type solid)
		)
		(fill yes)
		(layer "F.Cu")
		(net "GND")
	)
	(gr_poly
		(pts
			(arc
				(start 342.773 -67.5132)
				(mid 342.826882 -67.490882)
				(end 342.8492 -67.437)
			)
			(arc
				(start 342.8492 -67.437)
				(mid 342.826882 -67.383118)
				(end 342.773 -67.3608)
			)
			(arc
				(start 342.773 -67.3608)
				(mid 342.719118 -67.383118)
				(end 342.6968 -67.437)
			)
			(arc
				(start 342.6968 -67.437)
				(mid 342.719118 -67.490882)
				(end 342.773 -67.5132)
			)
		)
		(stroke
			(width 0)
			(type solid)
		)
		(fill yes)
		(layer "F.Cu")
		(net "GND")
	)
	(gr_poly
		(pts
			(arc
				(start 343.0651 -80.0989)
				(mid 343.118982 -80.076582)
				(end 343.1413 -80.0227)
			)
			(arc
				(start 343.1413 -80.0227)
				(mid 343.118982 -79.968818)
				(end 343.0651 -79.9465)
			)
			(arc
				(start 343.0651 -79.9465)
				(mid 343.011218 -79.968818)
				(end 342.9889 -80.0227)
			)
			(arc
				(start 342.9889 -80.0227)
				(mid 343.011218 -80.076582)
				(end 343.0651 -80.0989)
			)
		)
		(stroke
			(width 0)
			(type solid)
		)
		(fill yes)
		(layer "F.Cu")
		(net "GND")
	)
	(gr_poly
		(pts
			(arc
				(start 343.698068 -78.755494)
				(mid 343.75195 -78.733176)
				(end 343.774268 -78.679294)
			)
			(arc
				(start 343.774268 -78.679294)
				(mid 343.75195 -78.625412)
				(end 343.698068 -78.603094)
			)
			(arc
				(start 343.698068 -78.603094)
				(mid 343.644186 -78.625412)
				(end 343.621868 -78.679294)
			)
			(arc
				(start 343.621868 -78.679294)
				(mid 343.644186 -78.733176)
				(end 343.698068 -78.755494)
			)
		)
		(stroke
			(width 0)
			(type solid)
		)
		(fill yes)
		(layer "F.Cu")
		(net "GND")
	)
	(gr_poly
		(pts
			(arc
				(start 343.753186 -77.233018)
				(mid 343.807068 -77.2107)
				(end 343.829386 -77.156818)
			)
			(arc
				(start 343.829386 -77.156818)
				(mid 343.807068 -77.102936)
				(end 343.753186 -77.080618)
			)
			(arc
				(start 343.753186 -77.080618)
				(mid 343.699304 -77.102936)
				(end 343.676986 -77.156818)
			)
			(arc
				(start 343.676986 -77.156818)
				(mid 343.699304 -77.2107)
				(end 343.753186 -77.233018)
			)
		)
		(stroke
			(width 0)
			(type solid)
		)
		(fill yes)
		(layer "F.Cu")
		(net "GND")
	)
	(gr_poly
		(pts
			(arc
				(start 343.7636 -59.755786)
				(mid 343.817482 -59.733468)
				(end 343.8398 -59.679586)
			)
			(arc
				(start 343.8398 -59.679586)
				(mid 343.817482 -59.625704)
				(end 343.7636 -59.603386)
			)
			(arc
				(start 343.7636 -59.603386)
				(mid 343.709718 -59.625704)
				(end 343.6874 -59.679586)
			)
			(arc
				(start 343.6874 -59.679586)
				(mid 343.709718 -59.733468)
				(end 343.7636 -59.755786)
			)
		)
		(stroke
			(width 0)
			(type solid)
		)
		(fill yes)
		(layer "F.Cu")
		(net "GND")
	)
	(gr_poly
		(pts
			(arc
				(start 344.792808 -81.20253)
				(mid 344.84669 -81.180212)
				(end 344.869008 -81.12633)
			)
			(arc
				(start 344.869008 -81.12633)
				(mid 344.84669 -81.072448)
				(end 344.792808 -81.05013)
			)
			(arc
				(start 344.792808 -81.05013)
				(mid 344.738926 -81.072448)
				(end 344.716608 -81.12633)
			)
			(arc
				(start 344.716608 -81.12633)
				(mid 344.738926 -81.180212)
				(end 344.792808 -81.20253)
			)
		)
		(stroke
			(width 0)
			(type solid)
		)
		(fill yes)
		(layer "F.Cu")
		(net "GND")
	)
	(gr_poly
		(pts
			(arc
				(start 345.133168 -78.75524)
				(mid 345.18705 -78.732922)
				(end 345.209368 -78.67904)
			)
			(arc
				(start 345.209368 -78.67904)
				(mid 345.18705 -78.625158)
				(end 345.133168 -78.60284)
			)
			(arc
				(start 345.133168 -78.60284)
				(mid 345.079286 -78.625158)
				(end 345.056968 -78.67904)
			)
			(arc
				(start 345.056968 -78.67904)
				(mid 345.079286 -78.732922)
				(end 345.133168 -78.75524)
			)
		)
		(stroke
			(width 0)
			(type solid)
		)
		(fill yes)
		(layer "F.Cu")
		(net "GND")
	)
	(gr_poly
		(pts
			(arc
				(start 345.1352 -77.216)
				(mid 345.189082 -77.193682)
				(end 345.2114 -77.1398)
			)
			(arc
				(start 345.2114 -77.1398)
				(mid 345.189082 -77.085918)
				(end 345.1352 -77.0636)
			)
			(arc
				(start 345.1352 -77.0636)
				(mid 345.081318 -77.085918)
				(end 345.059 -77.1398)
			)
			(arc
				(start 345.059 -77.1398)
				(mid 345.081318 -77.193682)
				(end 345.1352 -77.216)
			)
		)
		(stroke
			(width 0)
			(type solid)
		)
		(fill yes)
		(layer "F.Cu")
		(net "GND")
	)
	(gr_poly
		(pts
			(arc
				(start 345.1606 -59.755786)
				(mid 345.214482 -59.733468)
				(end 345.2368 -59.679586)
			)
			(arc
				(start 345.2368 -59.679586)
				(mid 345.214482 -59.625704)
				(end 345.1606 -59.603386)
			)
			(arc
				(start 345.1606 -59.603386)
				(mid 345.106718 -59.625704)
				(end 345.0844 -59.679586)
			)
			(arc
				(start 345.0844 -59.679586)
				(mid 345.106718 -59.733468)
				(end 345.1606 -59.755786)
			)
		)
		(stroke
			(width 0)
			(type solid)
		)
		(fill yes)
		(layer "F.Cu")
		(net "GND")
	)
	(gr_poly
		(pts
			(arc
				(start 345.2114 -67.5386)
				(mid 345.265282 -67.516282)
				(end 345.2876 -67.4624)
			)
			(arc
				(start 345.2876 -67.4624)
				(mid 345.265282 -67.408518)
				(end 345.2114 -67.3862)
			)
			(arc
				(start 345.2114 -67.3862)
				(mid 345.157518 -67.408518)
				(end 345.1352 -67.4624)
			)
			(arc
				(start 345.1352 -67.4624)
				(mid 345.157518 -67.516282)
				(end 345.2114 -67.5386)
			)
		)
		(stroke
			(width 0)
			(type solid)
		)
		(fill yes)
		(layer "F.Cu")
		(net "GND")
	)
	(gr_poly
		(pts
			(arc
				(start 346.216986 -79.962756)
				(mid 346.270868 -79.940438)
				(end 346.293186 -79.886556)
			)
			(arc
				(start 346.293186 -79.886556)
				(mid 346.270868 -79.832674)
				(end 346.216986 -79.810356)
			)
			(arc
				(start 346.216986 -79.810356)
				(mid 346.163104 -79.832674)
				(end 346.140786 -79.886556)
			)
			(arc
				(start 346.140786 -79.886556)
				(mid 346.163104 -79.940438)
				(end 346.216986 -79.962756)
			)
		)
		(stroke
			(width 0)
			(type solid)
		)
		(fill yes)
		(layer "F.Cu")
		(net "GND")
	)
	(gr_poly
		(pts
			(arc
				(start 346.346272 -139.925806)
				(mid 346.400154 -139.903488)
				(end 346.422472 -139.849606)
			)
			(arc
				(start 346.422472 -139.849606)
				(mid 346.400154 -139.795724)
				(end 346.346272 -139.773406)
			)
			(arc
				(start 346.346272 -139.773406)
				(mid 346.29239 -139.795724)
				(end 346.270072 -139.849606)
			)
			(arc
				(start 346.270072 -139.849606)
				(mid 346.29239 -139.903488)
				(end 346.346272 -139.925806)
			)
		)
		(stroke
			(width 0)
			(type solid)
		)
		(fill yes)
		(layer "F.Cu")
		(net "GND")
	)
	(gr_poly
		(pts
			(arc
				(start 346.370148 -123.681744)
				(mid 346.42403 -123.659426)
				(end 346.446348 -123.605544)
			)
			(arc
				(start 346.446348 -123.605544)
				(mid 346.42403 -123.551662)
				(end 346.370148 -123.529344)
			)
			(arc
				(start 346.370148 -123.529344)
				(mid 346.316266 -123.551662)
				(end 346.293948 -123.605544)
			)
			(arc
				(start 346.293948 -123.605544)
				(mid 346.316266 -123.659426)
				(end 346.370148 -123.681744)
			)
		)
		(stroke
			(width 0)
			(type solid)
		)
		(fill yes)
		(layer "F.Cu")
		(net "GND")
	)
	(gr_poly
		(pts
			(arc
				(start 346.4052 -122.4026)
				(mid 346.459082 -122.380282)
				(end 346.4814 -122.3264)
			)
			(arc
				(start 346.4814 -122.3264)
				(mid 346.459082 -122.272518)
				(end 346.4052 -122.2502)
			)
			(arc
				(start 346.4052 -122.2502)
				(mid 346.351318 -122.272518)
				(end 346.329 -122.3264)
			)
			(arc
				(start 346.329 -122.3264)
				(mid 346.351318 -122.380282)
				(end 346.4052 -122.4026)
			)
		)
		(stroke
			(width 0)
			(type solid)
		)
		(fill yes)
		(layer "F.Cu")
		(net "GND")
	)
	(gr_poly
		(pts
			(arc
				(start 346.467176 -78.737714)
				(mid 346.521058 -78.715396)
				(end 346.543376 -78.661514)
			)
			(arc
				(start 346.543376 -78.661514)
				(mid 346.521058 -78.607632)
				(end 346.467176 -78.585314)
			)
			(arc
				(start 346.467176 -78.585314)
				(mid 346.413294 -78.607632)
				(end 346.390976 -78.661514)
			)
			(arc
				(start 346.390976 -78.661514)
				(mid 346.413294 -78.715396)
				(end 346.467176 -78.737714)
			)
		)
		(stroke
			(width 0)
			(type solid)
		)
		(fill yes)
		(layer "F.Cu")
		(net "GND")
	)
	(gr_poly
		(pts
			(arc
				(start 346.510102 -77.214476)
				(mid 346.563984 -77.192158)
				(end 346.586302 -77.138276)
			)
			(arc
				(start 346.586302 -77.138276)
				(mid 346.563984 -77.084394)
				(end 346.510102 -77.062076)
			)
			(arc
				(start 346.510102 -77.062076)
				(mid 346.45622 -77.084394)
				(end 346.433902 -77.138276)
			)
			(arc
				(start 346.433902 -77.138276)
				(mid 346.45622 -77.192158)
				(end 346.510102 -77.214476)
			)
		)
		(stroke
			(width 0)
			(type solid)
		)
		(fill yes)
		(layer "F.Cu")
		(net "GND")
	)
	(gr_poly
		(pts
			(arc
				(start 346.5576 -59.755786)
				(mid 346.611482 -59.733468)
				(end 346.6338 -59.679586)
			)
			(arc
				(start 346.6338 -59.679586)
				(mid 346.611482 -59.625704)
				(end 346.5576 -59.603386)
			)
			(arc
				(start 346.5576 -59.603386)
				(mid 346.503718 -59.625704)
				(end 346.4814 -59.679586)
			)
			(arc
				(start 346.4814 -59.679586)
				(mid 346.503718 -59.733468)
				(end 346.5576 -59.755786)
			)
		)
		(stroke
			(width 0)
			(type solid)
		)
		(fill yes)
		(layer "F.Cu")
		(net "GND")
	)
	(gr_poly
		(pts
			(arc
				(start 346.892626 -126.45263)
				(mid 346.946508 -126.430312)
				(end 346.968826 -126.37643)
			)
			(arc
				(start 346.968826 -126.37643)
				(mid 346.946508 -126.322548)
				(end 346.892626 -126.30023)
			)
			(arc
				(start 346.892626 -126.30023)
				(mid 346.838744 -126.322548)
				(end 346.816426 -126.37643)
			)
			(arc
				(start 346.816426 -126.37643)
				(mid 346.838744 -126.430312)
				(end 346.892626 -126.45263)
			)
		)
		(stroke
			(width 0)
			(type solid)
		)
		(fill yes)
		(layer "F.Cu")
		(net "GND")
	)
	(gr_poly
		(pts
			(arc
				(start 346.898214 -125.227842)
				(mid 346.952096 -125.205524)
				(end 346.974414 -125.151642)
			)
			(arc
				(start 346.974414 -125.151642)
				(mid 346.952096 -125.09776)
				(end 346.898214 -125.075442)
			)
			(arc
				(start 346.898214 -125.075442)
				(mid 346.844332 -125.09776)
				(end 346.822014 -125.151642)
			)
			(arc
				(start 346.822014 -125.151642)
				(mid 346.844332 -125.205524)
				(end 346.898214 -125.227842)
			)
		)
		(stroke
			(width 0)
			(type solid)
		)
		(fill yes)
		(layer "F.Cu")
		(net "GND")
	)
	(gr_poly
		(pts
			(arc
				(start 347.080586 -139.925806)
				(mid 347.134468 -139.903488)
				(end 347.156786 -139.849606)
			)
			(arc
				(start 347.156786 -139.849606)
				(mid 347.134468 -139.795724)
				(end 347.080586 -139.773406)
			)
			(arc
				(start 347.080586 -139.773406)
				(mid 347.026704 -139.795724)
				(end 347.004386 -139.849606)
			)
			(arc
				(start 347.004386 -139.849606)
				(mid 347.026704 -139.903488)
				(end 347.080586 -139.925806)
			)
		)
		(stroke
			(width 0)
			(type solid)
		)
		(fill yes)
		(layer "F.Cu")
		(net "GND")
	)
	(gr_poly
		(pts
			(arc
				(start 347.712538 -79.830422)
				(mid 347.76642 -79.808104)
				(end 347.788738 -79.754222)
			)
			(arc
				(start 347.788738 -79.754222)
				(mid 347.76642 -79.70034)
				(end 347.712538 -79.678022)
			)
			(arc
				(start 347.712538 -79.678022)
				(mid 347.658656 -79.70034)
				(end 347.636338 -79.754222)
			)
			(arc
				(start 347.636338 -79.754222)
				(mid 347.658656 -79.808104)
				(end 347.712538 -79.830422)
			)
		)
		(stroke
			(width 0)
			(type solid)
		)
		(fill yes)
		(layer "F.Cu")
		(net "GND")
	)
	(gr_poly
		(pts
			(arc
				(start 347.734636 -116.42725)
				(mid 347.788518 -116.404932)
				(end 347.810836 -116.35105)
			)
			(arc
				(start 347.810836 -116.35105)
				(mid 347.788518 -116.297168)
				(end 347.734636 -116.27485)
			)
			(arc
				(start 347.734636 -116.27485)
				(mid 347.680754 -116.297168)
				(end 347.658436 -116.35105)
			)
			(arc
				(start 347.658436 -116.35105)
				(mid 347.680754 -116.404932)
				(end 347.734636 -116.42725)
			)
		)
		(stroke
			(width 0)
			(type solid)
		)
		(fill yes)
		(layer "F.Cu")
		(net "GND")
	)
	(gr_poly
		(pts
			(arc
				(start 347.7514 -67.5132)
				(mid 347.805282 -67.490882)
				(end 347.8276 -67.437)
			)
			(arc
				(start 347.8276 -67.437)
				(mid 347.805282 -67.383118)
				(end 347.7514 -67.3608)
			)
			(arc
				(start 347.7514 -67.3608)
				(mid 347.697518 -67.383118)
				(end 347.6752 -67.437)
			)
			(arc
				(start 347.6752 -67.437)
				(mid 347.697518 -67.490882)
				(end 347.7514 -67.5132)
			)
		)
		(stroke
			(width 0)
			(type solid)
		)
		(fill yes)
		(layer "F.Cu")
		(net "GND")
	)
	(gr_poly
		(pts
			(arc
				(start 347.86316 -78.84795)
				(mid 347.917042 -78.825632)
				(end 347.93936 -78.77175)
			)
			(arc
				(start 347.93936 -78.77175)
				(mid 347.917042 -78.717868)
				(end 347.86316 -78.69555)
			)
			(arc
				(start 347.86316 -78.69555)
				(mid 347.809278 -78.717868)
				(end 347.78696 -78.77175)
			)
			(arc
				(start 347.78696 -78.77175)
				(mid 347.809278 -78.825632)
				(end 347.86316 -78.84795)
			)
		)
		(stroke
			(width 0)
			(type solid)
		)
		(fill yes)
		(layer "F.Cu")
		(net "GND")
	)
	(gr_poly
		(pts
			(arc
				(start 347.86316 -77.32649)
				(mid 347.917042 -77.304172)
				(end 347.93936 -77.25029)
			)
			(arc
				(start 347.93936 -77.25029)
				(mid 347.917042 -77.196408)
				(end 347.86316 -77.17409)
			)
			(arc
				(start 347.86316 -77.17409)
				(mid 347.809278 -77.196408)
				(end 347.78696 -77.25029)
			)
			(arc
				(start 347.78696 -77.25029)
				(mid 347.809278 -77.304172)
				(end 347.86316 -77.32649)
			)
		)
		(stroke
			(width 0)
			(type solid)
		)
		(fill yes)
		(layer "F.Cu")
		(net "GND")
	)
	(gr_poly
		(pts
			(arc
				(start 347.9546 -59.755786)
				(mid 348.008482 -59.733468)
				(end 348.0308 -59.679586)
			)
			(arc
				(start 348.0308 -59.679586)
				(mid 348.008482 -59.625704)
				(end 347.9546 -59.603386)
			)
			(arc
				(start 347.9546 -59.603386)
				(mid 347.900718 -59.625704)
				(end 347.8784 -59.679586)
			)
			(arc
				(start 347.8784 -59.679586)
				(mid 347.900718 -59.733468)
				(end 347.9546 -59.755786)
			)
		)
		(stroke
			(width 0)
			(type solid)
		)
		(fill yes)
		(layer "F.Cu")
		(net "GND")
	)
	(gr_poly
		(pts
			(arc
				(start 348.234 -81.9658)
				(mid 348.287882 -81.943482)
				(end 348.3102 -81.8896)
			)
			(arc
				(start 348.3102 -81.8896)
				(mid 348.287882 -81.835718)
				(end 348.234 -81.8134)
			)
			(arc
				(start 348.234 -81.8134)
				(mid 348.180118 -81.835718)
				(end 348.1578 -81.8896)
			)
			(arc
				(start 348.1578 -81.8896)
				(mid 348.180118 -81.943482)
				(end 348.234 -81.9658)
			)
		)
		(stroke
			(width 0)
			(type solid)
		)
		(fill yes)
		(layer "F.Cu")
		(net "GND")
	)
	(gr_poly
		(pts
			(arc
				(start 349.215456 -67.545966)
				(mid 349.269338 -67.523648)
				(end 349.291656 -67.469766)
			)
			(arc
				(start 349.291656 -67.469766)
				(mid 349.269338 -67.415884)
				(end 349.215456 -67.393566)
			)
			(arc
				(start 349.215456 -67.393566)
				(mid 349.161574 -67.415884)
				(end 349.139256 -67.469766)
			)
			(arc
				(start 349.139256 -67.469766)
				(mid 349.161574 -67.523648)
				(end 349.215456 -67.545966)
			)
		)
		(stroke
			(width 0)
			(type solid)
		)
		(fill yes)
		(layer "F.Cu")
		(net "GND")
	)
	(gr_poly
		(pts
			(arc
				(start 349.2246 -78.84922)
				(mid 349.278482 -78.826902)
				(end 349.3008 -78.77302)
			)
			(arc
				(start 349.3008 -78.77302)
				(mid 349.278482 -78.719138)
				(end 349.2246 -78.69682)
			)
			(arc
				(start 349.2246 -78.69682)
				(mid 349.170718 -78.719138)
				(end 349.1484 -78.77302)
			)
			(arc
				(start 349.1484 -78.77302)
				(mid 349.170718 -78.826902)
				(end 349.2246 -78.84922)
			)
		)
		(stroke
			(width 0)
			(type solid)
		)
		(fill yes)
		(layer "F.Cu")
		(net "GND")
	)
	(gr_poly
		(pts
			(arc
				(start 349.26016 -77.32649)
				(mid 349.314042 -77.304172)
				(end 349.33636 -77.25029)
			)
			(arc
				(start 349.33636 -77.25029)
				(mid 349.314042 -77.196408)
				(end 349.26016 -77.17409)
			)
			(arc
				(start 349.26016 -77.17409)
				(mid 349.206278 -77.196408)
				(end 349.18396 -77.25029)
			)
			(arc
				(start 349.18396 -77.25029)
				(mid 349.206278 -77.304172)
				(end 349.26016 -77.32649)
			)
		)
		(stroke
			(width 0)
			(type solid)
		)
		(fill yes)
		(layer "F.Cu")
		(net "GND")
	)
	(gr_poly
		(pts
			(arc
				(start 349.3516 -59.7916)
				(mid 349.405482 -59.769282)
				(end 349.4278 -59.7154)
			)
			(arc
				(start 349.4278 -59.7154)
				(mid 349.405482 -59.661518)
				(end 349.3516 -59.6392)
			)
			(arc
				(start 349.3516 -59.6392)
				(mid 349.297718 -59.661518)
				(end 349.2754 -59.7154)
			)
			(arc
				(start 349.2754 -59.7154)
				(mid 349.297718 -59.769282)
				(end 349.3516 -59.7916)
			)
		)
		(stroke
			(width 0)
			(type solid)
		)
		(fill yes)
		(layer "F.Cu")
		(net "GND")
	)
	(gr_poly
		(pts
			(arc
				(start 350.483678 -116.435632)
				(mid 350.53756 -116.413314)
				(end 350.559878 -116.359432)
			)
			(arc
				(start 350.559878 -116.359432)
				(mid 350.53756 -116.30555)
				(end 350.483678 -116.283232)
			)
			(arc
				(start 350.483678 -116.283232)
				(mid 350.429796 -116.30555)
				(end 350.407478 -116.359432)
			)
			(arc
				(start 350.407478 -116.359432)
				(mid 350.429796 -116.413314)
				(end 350.483678 -116.435632)
			)
		)
		(stroke
			(width 0)
			(type solid)
		)
		(fill yes)
		(layer "F.Cu")
		(net "GND")
	)
	(gr_poly
		(pts
			(arc
				(start 350.7486 -59.755786)
				(mid 350.802482 -59.733468)
				(end 350.8248 -59.679586)
			)
			(arc
				(start 350.8248 -59.679586)
				(mid 350.802482 -59.625704)
				(end 350.7486 -59.603386)
			)
			(arc
				(start 350.7486 -59.603386)
				(mid 350.694718 -59.625704)
				(end 350.6724 -59.679586)
			)
			(arc
				(start 350.6724 -59.679586)
				(mid 350.694718 -59.733468)
				(end 350.7486 -59.755786)
			)
		)
		(stroke
			(width 0)
			(type solid)
		)
		(fill yes)
		(layer "F.Cu")
		(net "GND")
	)
	(gr_poly
		(pts
			(arc
				(start 350.75114 -78.8924)
				(mid 350.805022 -78.870082)
				(end 350.82734 -78.8162)
			)
			(arc
				(start 350.82734 -78.8162)
				(mid 350.805022 -78.762318)
				(end 350.75114 -78.74)
			)
			(arc
				(start 350.75114 -78.74)
				(mid 350.697258 -78.762318)
				(end 350.67494 -78.8162)
			)
			(arc
				(start 350.67494 -78.8162)
				(mid 350.697258 -78.870082)
				(end 350.75114 -78.8924)
			)
		)
		(stroke
			(width 0)
			(type solid)
		)
		(fill yes)
		(layer "F.Cu")
		(net "GND")
	)
	(gr_poly
		(pts
			(arc
				(start 350.7994 -77.38364)
				(mid 350.853282 -77.361322)
				(end 350.8756 -77.30744)
			)
			(arc
				(start 350.8756 -77.30744)
				(mid 350.853282 -77.253558)
				(end 350.7994 -77.23124)
			)
			(arc
				(start 350.7994 -77.23124)
				(mid 350.745518 -77.253558)
				(end 350.7232 -77.30744)
			)
			(arc
				(start 350.7232 -77.30744)
				(mid 350.745518 -77.361322)
				(end 350.7994 -77.38364)
			)
		)
		(stroke
			(width 0)
			(type solid)
		)
		(fill yes)
		(layer "F.Cu")
		(net "GND")
	)
	(gr_poly
		(pts
			(arc
				(start 351.413826 -123.88723)
				(mid 351.467708 -123.864912)
				(end 351.490026 -123.81103)
			)
			(arc
				(start 351.490026 -123.81103)
				(mid 351.467708 -123.757148)
				(end 351.413826 -123.73483)
			)
			(arc
				(start 351.413826 -123.73483)
				(mid 351.359944 -123.757148)
				(end 351.337626 -123.81103)
			)
			(arc
				(start 351.337626 -123.81103)
				(mid 351.359944 -123.864912)
				(end 351.413826 -123.88723)
			)
		)
		(stroke
			(width 0)
			(type solid)
		)
		(fill yes)
		(layer "F.Cu")
		(net "GND")
	)
	(gr_poly
		(pts
			(arc
				(start 351.4344 -122.632216)
				(mid 351.488282 -122.609898)
				(end 351.5106 -122.556016)
			)
			(arc
				(start 351.5106 -122.556016)
				(mid 351.488282 -122.502134)
				(end 351.4344 -122.479816)
			)
			(arc
				(start 351.4344 -122.479816)
				(mid 351.380518 -122.502134)
				(end 351.3582 -122.556016)
			)
			(arc
				(start 351.3582 -122.556016)
				(mid 351.380518 -122.609898)
				(end 351.4344 -122.632216)
			)
		)
		(stroke
			(width 0)
			(type solid)
		)
		(fill yes)
		(layer "F.Cu")
		(net "GND")
	)
	(gr_poly
		(pts
			(arc
				(start 351.444306 -80.155796)
				(mid 351.498188 -80.133478)
				(end 351.520506 -80.079596)
			)
			(arc
				(start 351.520506 -80.079596)
				(mid 351.498188 -80.025714)
				(end 351.444306 -80.003396)
			)
			(arc
				(start 351.444306 -80.003396)
				(mid 351.390424 -80.025714)
				(end 351.368106 -80.079596)
			)
			(arc
				(start 351.368106 -80.079596)
				(mid 351.390424 -80.133478)
				(end 351.444306 -80.155796)
			)
		)
		(stroke
			(width 0)
			(type solid)
		)
		(fill yes)
		(layer "F.Cu")
		(net "GND")
	)
	(gr_poly
		(pts
			(arc
				(start 351.473262 -67.525392)
				(mid 351.527144 -67.503074)
				(end 351.549462 -67.449192)
			)
			(arc
				(start 351.549462 -67.449192)
				(mid 351.527144 -67.39531)
				(end 351.473262 -67.372992)
			)
			(arc
				(start 351.473262 -67.372992)
				(mid 351.41938 -67.39531)
				(end 351.397062 -67.449192)
			)
			(arc
				(start 351.397062 -67.449192)
				(mid 351.41938 -67.503074)
				(end 351.473262 -67.525392)
			)
		)
		(stroke
			(width 0)
			(type solid)
		)
		(fill yes)
		(layer "F.Cu")
		(net "GND")
	)
	(gr_poly
		(pts
			(arc
				(start 351.542096 -81.41335)
				(mid 351.595978 -81.391032)
				(end 351.618296 -81.33715)
			)
			(arc
				(start 351.618296 -81.33715)
				(mid 351.595978 -81.283268)
				(end 351.542096 -81.26095)
			)
			(arc
				(start 351.542096 -81.26095)
				(mid 351.488214 -81.283268)
				(end 351.465896 -81.33715)
			)
			(arc
				(start 351.465896 -81.33715)
				(mid 351.488214 -81.391032)
				(end 351.542096 -81.41335)
			)
		)
		(stroke
			(width 0)
			(type solid)
		)
		(fill yes)
		(layer "F.Cu")
		(net "GND")
	)
	(gr_poly
		(pts
			(arc
				(start 352.052382 -126.774194)
				(mid 352.106264 -126.751876)
				(end 352.128582 -126.697994)
			)
			(arc
				(start 352.128582 -126.697994)
				(mid 352.106264 -126.644112)
				(end 352.052382 -126.621794)
			)
			(arc
				(start 352.052382 -126.621794)
				(mid 351.9985 -126.644112)
				(end 351.976182 -126.697994)
			)
			(arc
				(start 351.976182 -126.697994)
				(mid 351.9985 -126.751876)
				(end 352.052382 -126.774194)
			)
		)
		(stroke
			(width 0)
			(type solid)
		)
		(fill yes)
		(layer "F.Cu")
		(net "GND")
	)
	(gr_poly
		(pts
			(arc
				(start 352.054414 -125.481842)
				(mid 352.108296 -125.459524)
				(end 352.130614 -125.405642)
			)
			(arc
				(start 352.130614 -125.405642)
				(mid 352.108296 -125.35176)
				(end 352.054414 -125.329442)
			)
			(arc
				(start 352.054414 -125.329442)
				(mid 352.000532 -125.35176)
				(end 351.978214 -125.405642)
			)
			(arc
				(start 351.978214 -125.405642)
				(mid 352.000532 -125.459524)
				(end 352.054414 -125.481842)
			)
		)
		(stroke
			(width 0)
			(type solid)
		)
		(fill yes)
		(layer "F.Cu")
		(net "GND")
	)
	(gr_poly
		(pts
			(arc
				(start 352.056192 -78.89494)
				(mid 352.110074 -78.872622)
				(end 352.132392 -78.81874)
			)
			(arc
				(start 352.132392 -78.81874)
				(mid 352.110074 -78.764858)
				(end 352.056192 -78.74254)
			)
			(arc
				(start 352.056192 -78.74254)
				(mid 352.00231 -78.764858)
				(end 351.979992 -78.81874)
			)
			(arc
				(start 351.979992 -78.81874)
				(mid 352.00231 -78.872622)
				(end 352.056192 -78.89494)
			)
		)
		(stroke
			(width 0)
			(type solid)
		)
		(fill yes)
		(layer "F.Cu")
		(net "GND")
	)
	(gr_poly
		(pts
			(arc
				(start 352.11131 -77.37094)
				(mid 352.165192 -77.348622)
				(end 352.18751 -77.29474)
			)
			(arc
				(start 352.18751 -77.29474)
				(mid 352.165192 -77.240858)
				(end 352.11131 -77.21854)
			)
			(arc
				(start 352.11131 -77.21854)
				(mid 352.057428 -77.240858)
				(end 352.03511 -77.29474)
			)
			(arc
				(start 352.03511 -77.29474)
				(mid 352.057428 -77.348622)
				(end 352.11131 -77.37094)
			)
		)
		(stroke
			(width 0)
			(type solid)
		)
		(fill yes)
		(layer "F.Cu")
		(net "GND")
	)
	(gr_poly
		(pts
			(arc
				(start 352.1456 -59.755786)
				(mid 352.199482 -59.733468)
				(end 352.2218 -59.679586)
			)
			(arc
				(start 352.2218 -59.679586)
				(mid 352.199482 -59.625704)
				(end 352.1456 -59.603386)
			)
			(arc
				(start 352.1456 -59.603386)
				(mid 352.091718 -59.625704)
				(end 352.0694 -59.679586)
			)
			(arc
				(start 352.0694 -59.679586)
				(mid 352.091718 -59.733468)
				(end 352.1456 -59.755786)
			)
		)
		(stroke
			(width 0)
			(type solid)
		)
		(fill yes)
		(layer "F.Cu")
		(net "GND")
	)
	(gr_poly
		(pts
			(arc
				(start 352.841052 -14.934946)
				(mid 352.894934 -14.912628)
				(end 352.917252 -14.858746)
			)
			(arc
				(start 352.917252 -14.858746)
				(mid 352.894934 -14.804864)
				(end 352.841052 -14.782546)
			)
			(arc
				(start 352.841052 -14.782546)
				(mid 352.78717 -14.804864)
				(end 352.764852 -14.858746)
			)
			(arc
				(start 352.764852 -14.858746)
				(mid 352.78717 -14.912628)
				(end 352.841052 -14.934946)
			)
		)
		(stroke
			(width 0)
			(type solid)
		)
		(fill yes)
		(layer "F.Cu")
		(net "GND")
	)
	(gr_poly
		(pts
			(arc
				(start 352.9584 -81.3816)
				(mid 353.012282 -81.359282)
				(end 353.0346 -81.3054)
			)
			(arc
				(start 353.0346 -81.3054)
				(mid 353.012282 -81.251518)
				(end 352.9584 -81.2292)
			)
			(arc
				(start 352.9584 -81.2292)
				(mid 352.904518 -81.251518)
				(end 352.8822 -81.3054)
			)
			(arc
				(start 352.8822 -81.3054)
				(mid 352.904518 -81.359282)
				(end 352.9584 -81.3816)
			)
		)
		(stroke
			(width 0)
			(type solid)
		)
		(fill yes)
		(layer "F.Cu")
		(net "GND")
	)
	(gr_poly
		(pts
			(arc
				(start 352.9584 -80.137)
				(mid 353.012282 -80.114682)
				(end 353.0346 -80.0608)
			)
			(arc
				(start 353.0346 -80.0608)
				(mid 353.012282 -80.006918)
				(end 352.9584 -79.9846)
			)
			(arc
				(start 352.9584 -79.9846)
				(mid 352.904518 -80.006918)
				(end 352.8822 -80.0608)
			)
			(arc
				(start 352.8822 -80.0608)
				(mid 352.904518 -80.114682)
				(end 352.9584 -80.137)
			)
		)
		(stroke
			(width 0)
			(type solid)
		)
		(fill yes)
		(layer "F.Cu")
		(net "GND")
	)
	(gr_poly
		(pts
			(arc
				(start 353.5426 -59.755786)
				(mid 353.596482 -59.733468)
				(end 353.6188 -59.679586)
			)
			(arc
				(start 353.6188 -59.679586)
				(mid 353.596482 -59.625704)
				(end 353.5426 -59.603386)
			)
			(arc
				(start 353.5426 -59.603386)
				(mid 353.488718 -59.625704)
				(end 353.4664 -59.679586)
			)
			(arc
				(start 353.4664 -59.679586)
				(mid 353.488718 -59.733468)
				(end 353.5426 -59.755786)
			)
		)
		(stroke
			(width 0)
			(type solid)
		)
		(fill yes)
		(layer "F.Cu")
		(net "GND")
	)
	(gr_poly
		(pts
			(arc
				(start 353.65436 -78.97495)
				(mid 353.708242 -78.952632)
				(end 353.73056 -78.89875)
			)
			(arc
				(start 353.73056 -78.89875)
				(mid 353.708242 -78.844868)
				(end 353.65436 -78.82255)
			)
			(arc
				(start 353.65436 -78.82255)
				(mid 353.600478 -78.844868)
				(end 353.57816 -78.89875)
			)
			(arc
				(start 353.57816 -78.89875)
				(mid 353.600478 -78.952632)
				(end 353.65436 -78.97495)
			)
		)
		(stroke
			(width 0)
			(type solid)
		)
		(fill yes)
		(layer "F.Cu")
		(net "GND")
	)
	(gr_poly
		(pts
			(arc
				(start 353.66452 -77.45476)
				(mid 353.718402 -77.432442)
				(end 353.74072 -77.37856)
			)
			(arc
				(start 353.74072 -77.37856)
				(mid 353.718402 -77.324678)
				(end 353.66452 -77.30236)
			)
			(arc
				(start 353.66452 -77.30236)
				(mid 353.610638 -77.324678)
				(end 353.58832 -77.37856)
			)
			(arc
				(start 353.58832 -77.37856)
				(mid 353.610638 -77.432442)
				(end 353.66452 -77.45476)
			)
		)
		(stroke
			(width 0)
			(type solid)
		)
		(fill yes)
		(layer "F.Cu")
		(net "GND")
	)
	(gr_poly
		(pts
			(arc
				(start 353.695 -87.6046)
				(mid 353.748882 -87.582282)
				(end 353.7712 -87.5284)
			)
			(arc
				(start 353.7712 -87.5284)
				(mid 353.748882 -87.474518)
				(end 353.695 -87.4522)
			)
			(arc
				(start 353.695 -87.4522)
				(mid 353.641118 -87.474518)
				(end 353.6188 -87.5284)
			)
			(arc
				(start 353.6188 -87.5284)
				(mid 353.641118 -87.582282)
				(end 353.695 -87.6046)
			)
		)
		(stroke
			(width 0)
			(type solid)
		)
		(fill yes)
		(layer "F.Cu")
		(net "GND")
	)
	(gr_poly
		(pts
			(arc
				(start 354.887022 -28.677108)
				(mid 354.940904 -28.65479)
				(end 354.963222 -28.600908)
			)
			(arc
				(start 354.963222 -28.600908)
				(mid 354.940904 -28.547026)
				(end 354.887022 -28.524708)
			)
			(arc
				(start 354.887022 -28.524708)
				(mid 354.83314 -28.547026)
				(end 354.810822 -28.600908)
			)
			(arc
				(start 354.810822 -28.600908)
				(mid 354.83314 -28.65479)
				(end 354.887022 -28.677108)
			)
		)
		(stroke
			(width 0)
			(type solid)
		)
		(fill yes)
		(layer "F.Cu")
		(net "GND")
	)
	(gr_poly
		(pts
			(arc
				(start 354.9396 -59.755786)
				(mid 354.993482 -59.733468)
				(end 355.0158 -59.679586)
			)
			(arc
				(start 355.0158 -59.679586)
				(mid 354.993482 -59.625704)
				(end 354.9396 -59.603386)
			)
			(arc
				(start 354.9396 -59.603386)
				(mid 354.885718 -59.625704)
				(end 354.8634 -59.679586)
			)
			(arc
				(start 354.8634 -59.679586)
				(mid 354.885718 -59.733468)
				(end 354.9396 -59.755786)
			)
		)
		(stroke
			(width 0)
			(type solid)
		)
		(fill yes)
		(layer "F.Cu")
		(net "GND")
	)
	(gr_poly
		(pts
			(arc
				(start 354.965 -13.0302)
				(mid 355.018882 -13.007882)
				(end 355.0412 -12.954)
			)
			(arc
				(start 355.0412 -12.954)
				(mid 355.018882 -12.900118)
				(end 354.965 -12.8778)
			)
			(arc
				(start 354.965 -12.8778)
				(mid 354.911118 -12.900118)
				(end 354.8888 -12.954)
			)
			(arc
				(start 354.8888 -12.954)
				(mid 354.911118 -13.007882)
				(end 354.965 -13.0302)
			)
		)
		(stroke
			(width 0)
			(type solid)
		)
		(fill yes)
		(layer "F.Cu")
		(net "GND")
	)
	(gr_poly
		(pts
			(arc
				(start 355.00056 -78.976474)
				(mid 355.054442 -78.954156)
				(end 355.07676 -78.900274)
			)
			(arc
				(start 355.07676 -78.900274)
				(mid 355.054442 -78.846392)
				(end 355.00056 -78.824074)
			)
			(arc
				(start 355.00056 -78.824074)
				(mid 354.946678 -78.846392)
				(end 354.92436 -78.900274)
			)
			(arc
				(start 354.92436 -78.900274)
				(mid 354.946678 -78.954156)
				(end 355.00056 -78.976474)
			)
		)
		(stroke
			(width 0)
			(type solid)
		)
		(fill yes)
		(layer "F.Cu")
		(net "GND")
	)
	(gr_poly
		(pts
			(arc
				(start 355.06152 -77.45476)
				(mid 355.115402 -77.432442)
				(end 355.13772 -77.37856)
			)
			(arc
				(start 355.13772 -77.37856)
				(mid 355.115402 -77.324678)
				(end 355.06152 -77.30236)
			)
			(arc
				(start 355.06152 -77.30236)
				(mid 355.007638 -77.324678)
				(end 354.98532 -77.37856)
			)
			(arc
				(start 354.98532 -77.37856)
				(mid 355.007638 -77.432442)
				(end 355.06152 -77.45476)
			)
		)
		(stroke
			(width 0)
			(type solid)
		)
		(fill yes)
		(layer "F.Cu")
		(net "GND")
	)
	(gr_poly
		(pts
			(arc
				(start 355.08565 -116.296694)
				(mid 355.139532 -116.274376)
				(end 355.16185 -116.220494)
			)
			(arc
				(start 355.16185 -116.220494)
				(mid 355.139532 -116.166612)
				(end 355.08565 -116.144294)
			)
			(arc
				(start 355.08565 -116.144294)
				(mid 355.031768 -116.166612)
				(end 355.00945 -116.220494)
			)
			(arc
				(start 355.00945 -116.220494)
				(mid 355.031768 -116.274376)
				(end 355.08565 -116.296694)
			)
		)
		(stroke
			(width 0)
			(type solid)
		)
		(fill yes)
		(layer "F.Cu")
		(net "GND")
	)
	(gr_poly
		(pts
			(arc
				(start 355.107748 -80.274922)
				(mid 355.16163 -80.252604)
				(end 355.183948 -80.198722)
			)
			(arc
				(start 355.183948 -80.198722)
				(mid 355.16163 -80.14484)
				(end 355.107748 -80.122522)
			)
			(arc
				(start 355.107748 -80.122522)
				(mid 355.053866 -80.14484)
				(end 355.031548 -80.198722)
			)
			(arc
				(start 355.031548 -80.198722)
				(mid 355.053866 -80.252604)
				(end 355.107748 -80.274922)
			)
		)
		(stroke
			(width 0)
			(type solid)
		)
		(fill yes)
		(layer "F.Cu")
		(net "GND")
	)
	(gr_poly
		(pts
			(arc
				(start 355.16185 -115.280694)
				(mid 355.215732 -115.258376)
				(end 355.23805 -115.204494)
			)
			(arc
				(start 355.23805 -115.204494)
				(mid 355.215732 -115.150612)
				(end 355.16185 -115.128294)
			)
			(arc
				(start 355.16185 -115.128294)
				(mid 355.107968 -115.150612)
				(end 355.08565 -115.204494)
			)
			(arc
				(start 355.08565 -115.204494)
				(mid 355.107968 -115.258376)
				(end 355.16185 -115.280694)
			)
		)
		(stroke
			(width 0)
			(type solid)
		)
		(fill yes)
		(layer "F.Cu")
		(net "GND")
	)
	(gr_poly
		(pts
			(arc
				(start 356.2858 -13.0556)
				(mid 356.339682 -13.033282)
				(end 356.362 -12.9794)
			)
			(arc
				(start 356.362 -12.9794)
				(mid 356.339682 -12.925518)
				(end 356.2858 -12.9032)
			)
			(arc
				(start 356.2858 -12.9032)
				(mid 356.231918 -12.925518)
				(end 356.2096 -12.9794)
			)
			(arc
				(start 356.2096 -12.9794)
				(mid 356.231918 -13.033282)
				(end 356.2858 -13.0556)
			)
		)
		(stroke
			(width 0)
			(type solid)
		)
		(fill yes)
		(layer "F.Cu")
		(net "GND")
	)
	(gr_poly
		(pts
			(arc
				(start 356.3874 -81.6991)
				(mid 356.441282 -81.676782)
				(end 356.4636 -81.6229)
			)
			(arc
				(start 356.4636 -81.6229)
				(mid 356.441282 -81.569018)
				(end 356.3874 -81.5467)
			)
			(arc
				(start 356.3874 -81.5467)
				(mid 356.333518 -81.569018)
				(end 356.3112 -81.6229)
			)
			(arc
				(start 356.3112 -81.6229)
				(mid 356.333518 -81.676782)
				(end 356.3874 -81.6991)
			)
		)
		(stroke
			(width 0)
			(type solid)
		)
		(fill yes)
		(layer "F.Cu")
		(net "GND")
	)
	(gr_poly
		(pts
			(arc
				(start 356.42804 -78.974442)
				(mid 356.481922 -78.952124)
				(end 356.50424 -78.898242)
			)
			(arc
				(start 356.50424 -78.898242)
				(mid 356.481922 -78.84436)
				(end 356.42804 -78.822042)
			)
			(arc
				(start 356.42804 -78.822042)
				(mid 356.374158 -78.84436)
				(end 356.35184 -78.898242)
			)
			(arc
				(start 356.35184 -78.898242)
				(mid 356.374158 -78.952124)
				(end 356.42804 -78.974442)
			)
		)
		(stroke
			(width 0)
			(type solid)
		)
		(fill yes)
		(layer "F.Cu")
		(net "GND")
	)
	(gr_poly
		(pts
			(arc
				(start 356.4382 -77.45476)
				(mid 356.492082 -77.432442)
				(end 356.5144 -77.37856)
			)
			(arc
				(start 356.5144 -77.37856)
				(mid 356.492082 -77.324678)
				(end 356.4382 -77.30236)
			)
			(arc
				(start 356.4382 -77.30236)
				(mid 356.384318 -77.324678)
				(end 356.362 -77.37856)
			)
			(arc
				(start 356.362 -77.37856)
				(mid 356.384318 -77.432442)
				(end 356.4382 -77.45476)
			)
		)
		(stroke
			(width 0)
			(type solid)
		)
		(fill yes)
		(layer "F.Cu")
		(net "GND")
	)
	(gr_poly
		(pts
			(arc
				(start 356.615492 -110.50905)
				(mid 356.669374 -110.486732)
				(end 356.691692 -110.43285)
			)
			(arc
				(start 356.691692 -110.43285)
				(mid 356.669374 -110.378968)
				(end 356.615492 -110.35665)
			)
			(arc
				(start 356.615492 -110.35665)
				(mid 356.56161 -110.378968)
				(end 356.539292 -110.43285)
			)
			(arc
				(start 356.539292 -110.43285)
				(mid 356.56161 -110.486732)
				(end 356.615492 -110.50905)
			)
		)
		(stroke
			(width 0)
			(type solid)
		)
		(fill yes)
		(layer "F.Cu")
		(net "GND")
	)
	(gr_poly
		(pts
			(arc
				(start 356.615492 -109.23905)
				(mid 356.669374 -109.216732)
				(end 356.691692 -109.16285)
			)
			(arc
				(start 356.691692 -109.16285)
				(mid 356.669374 -109.108968)
				(end 356.615492 -109.08665)
			)
			(arc
				(start 356.615492 -109.08665)
				(mid 356.56161 -109.108968)
				(end 356.539292 -109.16285)
			)
			(arc
				(start 356.539292 -109.16285)
				(mid 356.56161 -109.216732)
				(end 356.615492 -109.23905)
			)
		)
		(stroke
			(width 0)
			(type solid)
		)
		(fill yes)
		(layer "F.Cu")
		(net "GND")
	)
	(gr_poly
		(pts
			(arc
				(start 356.96525 -115.280694)
				(mid 357.019132 -115.258376)
				(end 357.04145 -115.204494)
			)
			(arc
				(start 357.04145 -115.204494)
				(mid 357.019132 -115.150612)
				(end 356.96525 -115.128294)
			)
			(arc
				(start 356.96525 -115.128294)
				(mid 356.911368 -115.150612)
				(end 356.88905 -115.204494)
			)
			(arc
				(start 356.88905 -115.204494)
				(mid 356.911368 -115.258376)
				(end 356.96525 -115.280694)
			)
		)
		(stroke
			(width 0)
			(type solid)
		)
		(fill yes)
		(layer "F.Cu")
		(net "GND")
	)
	(gr_poly
		(pts
			(arc
				(start 357.024432 -116.093494)
				(mid 357.078314 -116.071176)
				(end 357.100632 -116.017294)
			)
			(arc
				(start 357.100632 -116.017294)
				(mid 357.078314 -115.963412)
				(end 357.024432 -115.941094)
			)
			(arc
				(start 357.024432 -115.941094)
				(mid 356.97055 -115.963412)
				(end 356.948232 -116.017294)
			)
			(arc
				(start 356.948232 -116.017294)
				(mid 356.97055 -116.071176)
				(end 357.024432 -116.093494)
			)
		)
		(stroke
			(width 0)
			(type solid)
		)
		(fill yes)
		(layer "F.Cu")
		(net "GND")
	)
	(gr_poly
		(pts
			(arc
				(start 357.77932 -78.976728)
				(mid 357.833202 -78.95441)
				(end 357.85552 -78.900528)
			)
			(arc
				(start 357.85552 -78.900528)
				(mid 357.833202 -78.846646)
				(end 357.77932 -78.824328)
			)
			(arc
				(start 357.77932 -78.824328)
				(mid 357.725438 -78.846646)
				(end 357.70312 -78.900528)
			)
			(arc
				(start 357.70312 -78.900528)
				(mid 357.725438 -78.95441)
				(end 357.77932 -78.976728)
			)
		)
		(stroke
			(width 0)
			(type solid)
		)
		(fill yes)
		(layer "F.Cu")
		(net "GND")
	)
	(gr_poly
		(pts
			(arc
				(start 357.82504 -77.453998)
				(mid 357.878922 -77.43168)
				(end 357.90124 -77.377798)
			)
			(arc
				(start 357.90124 -77.377798)
				(mid 357.878922 -77.323916)
				(end 357.82504 -77.301598)
			)
			(arc
				(start 357.82504 -77.301598)
				(mid 357.771158 -77.323916)
				(end 357.74884 -77.377798)
			)
			(arc
				(start 357.74884 -77.377798)
				(mid 357.771158 -77.43168)
				(end 357.82504 -77.453998)
			)
		)
		(stroke
			(width 0)
			(type solid)
		)
		(fill yes)
		(layer "F.Cu")
		(net "GND")
	)
	(gr_poly
		(pts
			(arc
				(start 358.2797 -81.5594)
				(mid 358.333582 -81.537082)
				(end 358.3559 -81.4832)
			)
			(arc
				(start 358.3559 -81.4832)
				(mid 358.333582 -81.429318)
				(end 358.2797 -81.407)
			)
			(arc
				(start 358.2797 -81.407)
				(mid 358.225818 -81.429318)
				(end 358.2035 -81.4832)
			)
			(arc
				(start 358.2035 -81.4832)
				(mid 358.225818 -81.537082)
				(end 358.2797 -81.5594)
			)
		)
		(stroke
			(width 0)
			(type solid)
		)
		(fill yes)
		(layer "F.Cu")
		(net "GND")
	)
	(gr_poly
		(pts
			(arc
				(start 358.3432 -80.3656)
				(mid 358.397082 -80.343282)
				(end 358.4194 -80.2894)
			)
			(arc
				(start 358.4194 -80.2894)
				(mid 358.397082 -80.235518)
				(end 358.3432 -80.2132)
			)
			(arc
				(start 358.3432 -80.2132)
				(mid 358.289318 -80.235518)
				(end 358.267 -80.2894)
			)
			(arc
				(start 358.267 -80.2894)
				(mid 358.289318 -80.343282)
				(end 358.3432 -80.3656)
			)
		)
		(stroke
			(width 0)
			(type solid)
		)
		(fill yes)
		(layer "F.Cu")
		(net "GND")
	)
	(gr_poly
		(pts
			(arc
				(start 358.6226 -110.50905)
				(mid 358.676482 -110.486732)
				(end 358.6988 -110.43285)
			)
			(arc
				(start 358.6988 -110.43285)
				(mid 358.676482 -110.378968)
				(end 358.6226 -110.35665)
			)
			(arc
				(start 358.6226 -110.35665)
				(mid 358.568718 -110.378968)
				(end 358.5464 -110.43285)
			)
			(arc
				(start 358.5464 -110.43285)
				(mid 358.568718 -110.486732)
				(end 358.6226 -110.50905)
			)
		)
		(stroke
			(width 0)
			(type solid)
		)
		(fill yes)
		(layer "F.Cu")
		(net "GND")
	)
	(gr_poly
		(pts
			(arc
				(start 358.6226 -109.23905)
				(mid 358.676482 -109.216732)
				(end 358.6988 -109.16285)
			)
			(arc
				(start 358.6988 -109.16285)
				(mid 358.676482 -109.108968)
				(end 358.6226 -109.08665)
			)
			(arc
				(start 358.6226 -109.08665)
				(mid 358.568718 -109.108968)
				(end 358.5464 -109.16285)
			)
			(arc
				(start 358.5464 -109.16285)
				(mid 358.568718 -109.216732)
				(end 358.6226 -109.23905)
			)
		)
		(stroke
			(width 0)
			(type solid)
		)
		(fill yes)
		(layer "F.Cu")
		(net "GND")
	)
	(gr_poly
		(pts
			(arc
				(start 358.92105 -116.296694)
				(mid 358.974932 -116.274376)
				(end 358.99725 -116.220494)
			)
			(arc
				(start 358.99725 -116.220494)
				(mid 358.974932 -116.166612)
				(end 358.92105 -116.144294)
			)
			(arc
				(start 358.92105 -116.144294)
				(mid 358.867168 -116.166612)
				(end 358.84485 -116.220494)
			)
			(arc
				(start 358.84485 -116.220494)
				(mid 358.867168 -116.274376)
				(end 358.92105 -116.296694)
			)
		)
		(stroke
			(width 0)
			(type solid)
		)
		(fill yes)
		(layer "F.Cu")
		(net "GND")
	)
	(gr_poly
		(pts
			(arc
				(start 358.9782 -115.4938)
				(mid 359.032082 -115.471482)
				(end 359.0544 -115.4176)
			)
			(arc
				(start 359.0544 -115.4176)
				(mid 359.032082 -115.363718)
				(end 358.9782 -115.3414)
			)
			(arc
				(start 358.9782 -115.3414)
				(mid 358.924318 -115.363718)
				(end 358.902 -115.4176)
			)
			(arc
				(start 358.902 -115.4176)
				(mid 358.924318 -115.471482)
				(end 358.9782 -115.4938)
			)
		)
		(stroke
			(width 0)
			(type solid)
		)
		(fill yes)
		(layer "F.Cu")
		(net "GND")
	)
	(gr_poly
		(pts
			(arc
				(start 359.141522 -78.975712)
				(mid 359.195404 -78.953394)
				(end 359.217722 -78.899512)
			)
			(arc
				(start 359.217722 -78.899512)
				(mid 359.195404 -78.84563)
				(end 359.141522 -78.823312)
			)
			(arc
				(start 359.141522 -78.823312)
				(mid 359.08764 -78.84563)
				(end 359.065322 -78.899512)
			)
			(arc
				(start 359.065322 -78.899512)
				(mid 359.08764 -78.953394)
				(end 359.141522 -78.975712)
			)
		)
		(stroke
			(width 0)
			(type solid)
		)
		(fill yes)
		(layer "F.Cu")
		(net "GND")
	)
	(gr_poly
		(pts
			(arc
				(start 359.151682 -77.45603)
				(mid 359.205564 -77.433712)
				(end 359.227882 -77.37983)
			)
			(arc
				(start 359.227882 -77.37983)
				(mid 359.205564 -77.325948)
				(end 359.151682 -77.30363)
			)
			(arc
				(start 359.151682 -77.30363)
				(mid 359.0978 -77.325948)
				(end 359.075482 -77.37983)
			)
			(arc
				(start 359.075482 -77.37983)
				(mid 359.0978 -77.433712)
				(end 359.151682 -77.45603)
			)
		)
		(stroke
			(width 0)
			(type solid)
		)
		(fill yes)
		(layer "F.Cu")
		(net "GND")
	)
	(gr_poly
		(pts
			(arc
				(start 359.3592 -147.3454)
				(mid 359.413082 -147.323082)
				(end 359.4354 -147.2692)
			)
			(arc
				(start 359.4354 -147.2692)
				(mid 359.413082 -147.215318)
				(end 359.3592 -147.193)
			)
			(arc
				(start 359.3592 -147.193)
				(mid 359.305318 -147.215318)
				(end 359.283 -147.2692)
			)
			(arc
				(start 359.283 -147.2692)
				(mid 359.305318 -147.323082)
				(end 359.3592 -147.3454)
			)
		)
		(stroke
			(width 0)
			(type solid)
		)
		(fill yes)
		(layer "F.Cu")
		(net "GND")
	)
	(gr_poly
		(pts
			(arc
				(start 359.547414 -124.415042)
				(mid 359.601296 -124.392724)
				(end 359.623614 -124.338842)
			)
			(arc
				(start 359.623614 -124.338842)
				(mid 359.601296 -124.28496)
				(end 359.547414 -124.262642)
			)
			(arc
				(start 359.547414 -124.262642)
				(mid 359.493532 -124.28496)
				(end 359.471214 -124.338842)
			)
			(arc
				(start 359.471214 -124.338842)
				(mid 359.493532 -124.392724)
				(end 359.547414 -124.415042)
			)
		)
		(stroke
			(width 0)
			(type solid)
		)
		(fill yes)
		(layer "F.Cu")
		(net "GND")
	)
	(gr_poly
		(pts
			(arc
				(start 359.6132 -125.857)
				(mid 359.667082 -125.834682)
				(end 359.6894 -125.7808)
			)
			(arc
				(start 359.6894 -125.7808)
				(mid 359.667082 -125.726918)
				(end 359.6132 -125.7046)
			)
			(arc
				(start 359.6132 -125.7046)
				(mid 359.559318 -125.726918)
				(end 359.537 -125.7808)
			)
			(arc
				(start 359.537 -125.7808)
				(mid 359.559318 -125.834682)
				(end 359.6132 -125.857)
			)
		)
		(stroke
			(width 0)
			(type solid)
		)
		(fill yes)
		(layer "F.Cu")
		(net "GND")
	)
	(gr_poly
		(pts
			(arc
				(start 359.6132 -121.3612)
				(mid 359.667082 -121.338882)
				(end 359.6894 -121.285)
			)
			(arc
				(start 359.6894 -121.285)
				(mid 359.667082 -121.231118)
				(end 359.6132 -121.2088)
			)
			(arc
				(start 359.6132 -121.2088)
				(mid 359.559318 -121.231118)
				(end 359.537 -121.285)
			)
			(arc
				(start 359.537 -121.285)
				(mid 359.559318 -121.338882)
				(end 359.6132 -121.3612)
			)
		)
		(stroke
			(width 0)
			(type solid)
		)
		(fill yes)
		(layer "F.Cu")
		(net "GND")
	)
	(gr_poly
		(pts
			(arc
				(start 359.6894 -122.8852)
				(mid 359.743282 -122.862882)
				(end 359.7656 -122.809)
			)
			(arc
				(start 359.7656 -122.809)
				(mid 359.743282 -122.755118)
				(end 359.6894 -122.7328)
			)
			(arc
				(start 359.6894 -122.7328)
				(mid 359.635518 -122.755118)
				(end 359.6132 -122.809)
			)
			(arc
				(start 359.6132 -122.809)
				(mid 359.635518 -122.862882)
				(end 359.6894 -122.8852)
			)
		)
		(stroke
			(width 0)
			(type solid)
		)
		(fill yes)
		(layer "F.Cu")
		(net "GND")
	)
	(gr_poly
		(pts
			(arc
				(start 360.497882 -77.43698)
				(mid 360.551764 -77.414662)
				(end 360.574082 -77.36078)
			)
			(arc
				(start 360.574082 -77.36078)
				(mid 360.551764 -77.306898)
				(end 360.497882 -77.28458)
			)
			(arc
				(start 360.497882 -77.28458)
				(mid 360.444 -77.306898)
				(end 360.421682 -77.36078)
			)
			(arc
				(start 360.421682 -77.36078)
				(mid 360.444 -77.414662)
				(end 360.497882 -77.43698)
			)
		)
		(stroke
			(width 0)
			(type solid)
		)
		(fill yes)
		(layer "F.Cu")
		(net "GND")
	)
	(gr_poly
		(pts
			(arc
				(start 360.513122 -78.981808)
				(mid 360.567004 -78.95949)
				(end 360.589322 -78.905608)
			)
			(arc
				(start 360.589322 -78.905608)
				(mid 360.567004 -78.851726)
				(end 360.513122 -78.829408)
			)
			(arc
				(start 360.513122 -78.829408)
				(mid 360.45924 -78.851726)
				(end 360.436922 -78.905608)
			)
			(arc
				(start 360.436922 -78.905608)
				(mid 360.45924 -78.95949)
				(end 360.513122 -78.981808)
			)
		)
		(stroke
			(width 0)
			(type solid)
		)
		(fill yes)
		(layer "F.Cu")
		(net "GND")
	)
	(gr_poly
		(pts
			(arc
				(start 361.315 -147.3454)
				(mid 361.368882 -147.323082)
				(end 361.3912 -147.2692)
			)
			(arc
				(start 361.3912 -147.2692)
				(mid 361.368882 -147.215318)
				(end 361.315 -147.193)
			)
			(arc
				(start 361.315 -147.193)
				(mid 361.261118 -147.215318)
				(end 361.2388 -147.2692)
			)
			(arc
				(start 361.2388 -147.2692)
				(mid 361.261118 -147.323082)
				(end 361.315 -147.3454)
			)
		)
		(stroke
			(width 0)
			(type solid)
		)
		(fill yes)
		(layer "F.Cu")
		(net "GND")
	)
	(gr_poly
		(pts
			(arc
				(start 362.966 -113.8682)
				(mid 363.019882 -113.845882)
				(end 363.0422 -113.792)
			)
			(arc
				(start 363.0422 -113.792)
				(mid 363.019882 -113.738118)
				(end 362.966 -113.7158)
			)
			(arc
				(start 362.966 -113.7158)
				(mid 362.912118 -113.738118)
				(end 362.8898 -113.792)
			)
			(arc
				(start 362.8898 -113.792)
				(mid 362.912118 -113.845882)
				(end 362.966 -113.8682)
			)
		)
		(stroke
			(width 0)
			(type solid)
		)
		(fill yes)
		(layer "F.Cu")
		(net "GND")
	)
	(gr_poly
		(pts
			(arc
				(start 362.966 -112.4966)
				(mid 363.019882 -112.474282)
				(end 363.0422 -112.4204)
			)
			(arc
				(start 363.0422 -112.4204)
				(mid 363.019882 -112.366518)
				(end 362.966 -112.3442)
			)
			(arc
				(start 362.966 -112.3442)
				(mid 362.912118 -112.366518)
				(end 362.8898 -112.4204)
			)
			(arc
				(start 362.8898 -112.4204)
				(mid 362.912118 -112.474282)
				(end 362.966 -112.4966)
			)
		)
		(stroke
			(width 0)
			(type solid)
		)
		(fill yes)
		(layer "F.Cu")
		(net "GND")
	)
	(gr_poly
		(pts
			(arc
				(start 362.966 -111.089186)
				(mid 363.019882 -111.066868)
				(end 363.0422 -111.012986)
			)
			(arc
				(start 363.0422 -111.012986)
				(mid 363.019882 -110.959104)
				(end 362.966 -110.936786)
			)
			(arc
				(start 362.966 -110.936786)
				(mid 362.912118 -110.959104)
				(end 362.8898 -111.012986)
			)
			(arc
				(start 362.8898 -111.012986)
				(mid 362.912118 -111.066868)
				(end 362.966 -111.089186)
			)
		)
		(stroke
			(width 0)
			(type solid)
		)
		(fill yes)
		(layer "F.Cu")
		(net "GND")
	)
	(gr_poly
		(pts
			(arc
				(start 362.9914 -115.2398)
				(mid 363.045282 -115.217482)
				(end 363.0676 -115.1636)
			)
			(arc
				(start 363.0676 -115.1636)
				(mid 363.045282 -115.109718)
				(end 362.9914 -115.0874)
			)
			(arc
				(start 362.9914 -115.0874)
				(mid 362.937518 -115.109718)
				(end 362.9152 -115.1636)
			)
			(arc
				(start 362.9152 -115.1636)
				(mid 362.937518 -115.217482)
				(end 362.9914 -115.2398)
			)
		)
		(stroke
			(width 0)
			(type solid)
		)
		(fill yes)
		(layer "F.Cu")
		(net "GND")
	)
	(gr_poly
		(pts
			(arc
				(start 365.585756 -121.417842)
				(mid 365.639638 -121.395524)
				(end 365.661956 -121.341642)
			)
			(arc
				(start 365.661956 -121.341642)
				(mid 365.639638 -121.28776)
				(end 365.585756 -121.265442)
			)
			(arc
				(start 365.585756 -121.265442)
				(mid 365.531874 -121.28776)
				(end 365.509556 -121.341642)
			)
			(arc
				(start 365.509556 -121.341642)
				(mid 365.531874 -121.395524)
				(end 365.585756 -121.417842)
			)
		)
		(stroke
			(width 0)
			(type solid)
		)
		(fill yes)
		(layer "F.Cu")
		(net "GND")
	)
	(gr_poly
		(pts
			(arc
				(start 365.592614 -124.364242)
				(mid 365.646496 -124.341924)
				(end 365.668814 -124.288042)
			)
			(arc
				(start 365.668814 -124.288042)
				(mid 365.646496 -124.23416)
				(end 365.592614 -124.211842)
			)
			(arc
				(start 365.592614 -124.211842)
				(mid 365.538732 -124.23416)
				(end 365.516414 -124.288042)
			)
			(arc
				(start 365.516414 -124.288042)
				(mid 365.538732 -124.341924)
				(end 365.592614 -124.364242)
			)
		)
		(stroke
			(width 0)
			(type solid)
		)
		(fill yes)
		(layer "F.Cu")
		(net "GND")
	)
	(gr_poly
		(pts
			(arc
				(start 365.6076 -125.73)
				(mid 365.661482 -125.707682)
				(end 365.6838 -125.6538)
			)
			(arc
				(start 365.6838 -125.6538)
				(mid 365.661482 -125.599918)
				(end 365.6076 -125.5776)
			)
			(arc
				(start 365.6076 -125.5776)
				(mid 365.553718 -125.599918)
				(end 365.5314 -125.6538)
			)
			(arc
				(start 365.5314 -125.6538)
				(mid 365.553718 -125.707682)
				(end 365.6076 -125.73)
			)
		)
		(stroke
			(width 0)
			(type solid)
		)
		(fill yes)
		(layer "F.Cu")
		(net "GND")
	)
	(gr_poly
		(pts
			(arc
				(start 366.903 -113.8682)
				(mid 366.956882 -113.845882)
				(end 366.9792 -113.792)
			)
			(arc
				(start 366.9792 -113.792)
				(mid 366.956882 -113.738118)
				(end 366.903 -113.7158)
			)
			(arc
				(start 366.903 -113.7158)
				(mid 366.849118 -113.738118)
				(end 366.8268 -113.792)
			)
			(arc
				(start 366.8268 -113.792)
				(mid 366.849118 -113.845882)
				(end 366.903 -113.8682)
			)
		)
		(stroke
			(width 0)
			(type solid)
		)
		(fill yes)
		(layer "F.Cu")
		(net "GND")
	)
	(gr_poly
		(pts
			(arc
				(start 366.9792 -112.4712)
				(mid 367.033082 -112.448882)
				(end 367.0554 -112.395)
			)
			(arc
				(start 367.0554 -112.395)
				(mid 367.033082 -112.341118)
				(end 366.9792 -112.3188)
			)
			(arc
				(start 366.9792 -112.3188)
				(mid 366.925318 -112.341118)
				(end 366.903 -112.395)
			)
			(arc
				(start 366.903 -112.395)
				(mid 366.925318 -112.448882)
				(end 366.9792 -112.4712)
			)
		)
		(stroke
			(width 0)
			(type solid)
		)
		(fill yes)
		(layer "F.Cu")
		(net "GND")
	)
	(gr_poly
		(pts
			(arc
				(start 367.03 -111.0742)
				(mid 367.083882 -111.051882)
				(end 367.1062 -110.998)
			)
			(arc
				(start 367.1062 -110.998)
				(mid 367.083882 -110.944118)
				(end 367.03 -110.9218)
			)
			(arc
				(start 367.03 -110.9218)
				(mid 366.976118 -110.944118)
				(end 366.9538 -110.998)
			)
			(arc
				(start 366.9538 -110.998)
				(mid 366.976118 -111.051882)
				(end 367.03 -111.0742)
			)
		)
		(stroke
			(width 0)
			(type solid)
		)
		(fill yes)
		(layer "F.Cu")
		(net "GND")
	)
	(gr_poly
		(pts
			(arc
				(start 367.2332 -145.9484)
				(mid 367.287082 -145.926082)
				(end 367.3094 -145.8722)
			)
			(arc
				(start 367.3094 -145.8722)
				(mid 367.287082 -145.818318)
				(end 367.2332 -145.796)
			)
			(arc
				(start 367.2332 -145.796)
				(mid 367.179318 -145.818318)
				(end 367.157 -145.8722)
			)
			(arc
				(start 367.157 -145.8722)
				(mid 367.179318 -145.926082)
				(end 367.2332 -145.9484)
			)
		)
		(stroke
			(width 0)
			(type solid)
		)
		(fill yes)
		(layer "F.Cu")
		(net "GND")
	)
	(gr_poly
		(pts
			(arc
				(start 368.6556 -118.3132)
				(mid 368.709482 -118.290882)
				(end 368.7318 -118.237)
			)
			(arc
				(start 368.7318 -118.237)
				(mid 368.709482 -118.183118)
				(end 368.6556 -118.1608)
			)
			(arc
				(start 368.6556 -118.1608)
				(mid 368.601718 -118.183118)
				(end 368.5794 -118.237)
			)
			(arc
				(start 368.5794 -118.237)
				(mid 368.601718 -118.290882)
				(end 368.6556 -118.3132)
			)
		)
		(stroke
			(width 0)
			(type solid)
		)
		(fill yes)
		(layer "F.Cu")
		(net "GND")
	)
	(gr_poly
		(pts
			(arc
				(start 368.6556 -116.8654)
				(mid 368.709482 -116.843082)
				(end 368.7318 -116.7892)
			)
			(arc
				(start 368.7318 -116.7892)
				(mid 368.709482 -116.735318)
				(end 368.6556 -116.713)
			)
			(arc
				(start 368.6556 -116.713)
				(mid 368.601718 -116.735318)
				(end 368.5794 -116.7892)
			)
			(arc
				(start 368.5794 -116.7892)
				(mid 368.601718 -116.843082)
				(end 368.6556 -116.8654)
			)
		)
		(stroke
			(width 0)
			(type solid)
		)
		(fill yes)
		(layer "F.Cu")
		(net "GND")
	)
	(gr_poly
		(pts
			(arc
				(start 368.6556 -115.4176)
				(mid 368.709482 -115.395282)
				(end 368.7318 -115.3414)
			)
			(arc
				(start 368.7318 -115.3414)
				(mid 368.709482 -115.287518)
				(end 368.6556 -115.2652)
			)
			(arc
				(start 368.6556 -115.2652)
				(mid 368.601718 -115.287518)
				(end 368.5794 -115.3414)
			)
			(arc
				(start 368.5794 -115.3414)
				(mid 368.601718 -115.395282)
				(end 368.6556 -115.4176)
			)
		)
		(stroke
			(width 0)
			(type solid)
		)
		(fill yes)
		(layer "F.Cu")
		(net "GND")
	)
	(gr_poly
		(pts
			(arc
				(start 370.586 -114.375438)
				(mid 370.639882 -114.35312)
				(end 370.6622 -114.299238)
			)
			(arc
				(start 370.6622 -114.299238)
				(mid 370.639882 -114.245356)
				(end 370.586 -114.223038)
			)
			(arc
				(start 370.586 -114.223038)
				(mid 370.532118 -114.245356)
				(end 370.5098 -114.299238)
			)
			(arc
				(start 370.5098 -114.299238)
				(mid 370.532118 -114.35312)
				(end 370.586 -114.375438)
			)
		)
		(stroke
			(width 0)
			(type solid)
		)
		(fill yes)
		(layer "F.Cu")
		(net "GND")
	)
	(gr_poly
		(pts
			(arc
				(start 370.6368 -118.3132)
				(mid 370.690682 -118.290882)
				(end 370.713 -118.237)
			)
			(arc
				(start 370.713 -118.237)
				(mid 370.690682 -118.183118)
				(end 370.6368 -118.1608)
			)
			(arc
				(start 370.6368 -118.1608)
				(mid 370.582918 -118.183118)
				(end 370.5606 -118.237)
			)
			(arc
				(start 370.5606 -118.237)
				(mid 370.582918 -118.290882)
				(end 370.6368 -118.3132)
			)
		)
		(stroke
			(width 0)
			(type solid)
		)
		(fill yes)
		(layer "F.Cu")
		(net "GND")
	)
	(gr_poly
		(pts
			(arc
				(start 370.6368 -116.8654)
				(mid 370.690682 -116.843082)
				(end 370.713 -116.7892)
			)
			(arc
				(start 370.713 -116.7892)
				(mid 370.690682 -116.735318)
				(end 370.6368 -116.713)
			)
			(arc
				(start 370.6368 -116.713)
				(mid 370.582918 -116.735318)
				(end 370.5606 -116.7892)
			)
			(arc
				(start 370.5606 -116.7892)
				(mid 370.582918 -116.843082)
				(end 370.6368 -116.8654)
			)
		)
		(stroke
			(width 0)
			(type solid)
		)
		(fill yes)
		(layer "F.Cu")
		(net "GND")
	)
	(gr_poly
		(pts
			(arc
				(start 370.6368 -115.4176)
				(mid 370.690682 -115.395282)
				(end 370.713 -115.3414)
			)
			(arc
				(start 370.713 -115.3414)
				(mid 370.690682 -115.287518)
				(end 370.6368 -115.2652)
			)
			(arc
				(start 370.6368 -115.2652)
				(mid 370.582918 -115.287518)
				(end 370.5606 -115.3414)
			)
			(arc
				(start 370.5606 -115.3414)
				(mid 370.582918 -115.395282)
				(end 370.6368 -115.4176)
			)
		)
		(stroke
			(width 0)
			(type solid)
		)
		(fill yes)
		(layer "F.Cu")
		(net "GND")
	)
	(gr_poly
		(pts
			(arc
				(start 372.5672 -114.375438)
				(mid 372.621082 -114.35312)
				(end 372.6434 -114.299238)
			)
			(arc
				(start 372.6434 -114.299238)
				(mid 372.621082 -114.245356)
				(end 372.5672 -114.223038)
			)
			(arc
				(start 372.5672 -114.223038)
				(mid 372.513318 -114.245356)
				(end 372.491 -114.299238)
			)
			(arc
				(start 372.491 -114.299238)
				(mid 372.513318 -114.35312)
				(end 372.5672 -114.375438)
			)
		)
		(stroke
			(width 0)
			(type solid)
		)
		(fill yes)
		(layer "F.Cu")
		(net "GND")
	)
	(gr_poly
		(pts
			(arc
				(start 372.618 -118.3132)
				(mid 372.671882 -118.290882)
				(end 372.6942 -118.237)
			)
			(arc
				(start 372.6942 -118.237)
				(mid 372.671882 -118.183118)
				(end 372.618 -118.1608)
			)
			(arc
				(start 372.618 -118.1608)
				(mid 372.564118 -118.183118)
				(end 372.5418 -118.237)
			)
			(arc
				(start 372.5418 -118.237)
				(mid 372.564118 -118.290882)
				(end 372.618 -118.3132)
			)
		)
		(stroke
			(width 0)
			(type solid)
		)
		(fill yes)
		(layer "F.Cu")
		(net "GND")
	)
	(gr_poly
		(pts
			(arc
				(start 372.618 -116.8654)
				(mid 372.671882 -116.843082)
				(end 372.6942 -116.7892)
			)
			(arc
				(start 372.6942 -116.7892)
				(mid 372.671882 -116.735318)
				(end 372.618 -116.713)
			)
			(arc
				(start 372.618 -116.713)
				(mid 372.564118 -116.735318)
				(end 372.5418 -116.7892)
			)
			(arc
				(start 372.5418 -116.7892)
				(mid 372.564118 -116.843082)
				(end 372.618 -116.8654)
			)
		)
		(stroke
			(width 0)
			(type solid)
		)
		(fill yes)
		(layer "F.Cu")
		(net "GND")
	)
	(gr_poly
		(pts
			(arc
				(start 372.618 -115.4176)
				(mid 372.671882 -115.395282)
				(end 372.6942 -115.3414)
			)
			(arc
				(start 372.6942 -115.3414)
				(mid 372.671882 -115.287518)
				(end 372.618 -115.2652)
			)
			(arc
				(start 372.618 -115.2652)
				(mid 372.564118 -115.287518)
				(end 372.5418 -115.3414)
			)
			(arc
				(start 372.5418 -115.3414)
				(mid 372.564118 -115.395282)
				(end 372.618 -115.4176)
			)
		)
		(stroke
			(width 0)
			(type solid)
		)
		(fill yes)
		(layer "F.Cu")
		(net "GND")
	)
	(gr_poly
		(pts
			(arc
				(start 376.5042 -30.1498)
				(mid 376.558082 -30.127482)
				(end 376.5804 -30.0736)
			)
			(arc
				(start 376.5804 -30.0736)
				(mid 376.558082 -30.019718)
				(end 376.5042 -29.9974)
			)
			(arc
				(start 376.5042 -29.9974)
				(mid 376.450318 -30.019718)
				(end 376.428 -30.0736)
			)
			(arc
				(start 376.428 -30.0736)
				(mid 376.450318 -30.127482)
				(end 376.5042 -30.1498)
			)
		)
		(stroke
			(width 0)
			(type solid)
		)
		(fill yes)
		(layer "F.Cu")
		(net "GND")
	)
	(gr_poly
		(pts
			(arc
				(start 376.705622 -33.298384)
				(mid 376.759504 -33.276066)
				(end 376.781822 -33.222184)
			)
			(arc
				(start 376.781822 -33.222184)
				(mid 376.759504 -33.168302)
				(end 376.705622 -33.145984)
			)
			(arc
				(start 376.705622 -33.145984)
				(mid 376.65174 -33.168302)
				(end 376.629422 -33.222184)
			)
			(arc
				(start 376.629422 -33.222184)
				(mid 376.65174 -33.276066)
				(end 376.705622 -33.298384)
			)
		)
		(stroke
			(width 0)
			(type solid)
		)
		(fill yes)
		(layer "F.Cu")
		(net "GND")
	)
	(gr_poly
		(pts
			(arc
				(start 380.415546 -28.55976)
				(mid 380.469428 -28.537442)
				(end 380.491746 -28.48356)
			)
			(arc
				(start 380.491746 -28.48356)
				(mid 380.469428 -28.429678)
				(end 380.415546 -28.40736)
			)
			(arc
				(start 380.415546 -28.40736)
				(mid 380.361664 -28.429678)
				(end 380.339346 -28.48356)
			)
			(arc
				(start 380.339346 -28.48356)
				(mid 380.361664 -28.537442)
				(end 380.415546 -28.55976)
			)
		)
		(stroke
			(width 0)
			(type solid)
		)
		(fill yes)
		(layer "F.Cu")
		(net "GND")
	)
	(gr_poly
		(pts
			(arc
				(start 380.902972 -31.70428)
				(mid 380.956854 -31.681962)
				(end 380.979172 -31.62808)
			)
			(arc
				(start 380.979172 -31.62808)
				(mid 380.956854 -31.574198)
				(end 380.902972 -31.55188)
			)
			(arc
				(start 380.902972 -31.55188)
				(mid 380.84909 -31.574198)
				(end 380.826772 -31.62808)
			)
			(arc
				(start 380.826772 -31.62808)
				(mid 380.84909 -31.681962)
				(end 380.902972 -31.70428)
			)
		)
		(stroke
			(width 0)
			(type solid)
		)
		(fill yes)
		(layer "F.Cu")
		(net "GND")
	)
	(gr_poly
		(pts
			(arc
				(start 381.19685 -24.993854)
				(mid 381.250732 -24.971536)
				(end 381.27305 -24.917654)
			)
			(arc
				(start 381.27305 -24.917654)
				(mid 381.250732 -24.863772)
				(end 381.19685 -24.841454)
			)
			(arc
				(start 381.19685 -24.841454)
				(mid 381.142968 -24.863772)
				(end 381.12065 -24.917654)
			)
			(arc
				(start 381.12065 -24.917654)
				(mid 381.142968 -24.971536)
				(end 381.19685 -24.993854)
			)
		)
		(stroke
			(width 0)
			(type solid)
		)
		(fill yes)
		(layer "F.Cu")
		(net "GND")
	)
	(gr_poly
		(pts
			(arc
				(start 381.407162 -27.6352)
				(mid 381.461044 -27.612882)
				(end 381.483362 -27.559)
			)
			(arc
				(start 381.483362 -27.559)
				(mid 381.461044 -27.505118)
				(end 381.407162 -27.4828)
			)
			(arc
				(start 381.407162 -27.4828)
				(mid 381.35328 -27.505118)
				(end 381.330962 -27.559)
			)
			(arc
				(start 381.330962 -27.559)
				(mid 381.35328 -27.612882)
				(end 381.407162 -27.6352)
			)
		)
		(stroke
			(width 0)
			(type solid)
		)
		(fill yes)
		(layer "F.Cu")
		(net "GND")
	)
	(gr_poly
		(pts
			(arc
				(start 381.4318 -26.3144)
				(mid 381.485682 -26.292082)
				(end 381.508 -26.2382)
			)
			(arc
				(start 381.508 -26.2382)
				(mid 381.485682 -26.184318)
				(end 381.4318 -26.162)
			)
			(arc
				(start 381.4318 -26.162)
				(mid 381.377918 -26.184318)
				(end 381.3556 -26.2382)
			)
			(arc
				(start 381.3556 -26.2382)
				(mid 381.377918 -26.292082)
				(end 381.4318 -26.3144)
			)
		)
		(stroke
			(width 0)
			(type solid)
		)
		(fill yes)
		(layer "F.Cu")
		(net "GND")
	)
	(gr_poly
		(pts
			(arc
				(start 384.0226 -73.1012)
				(mid 384.076482 -73.078882)
				(end 384.0988 -73.025)
			)
			(arc
				(start 384.0988 -73.025)
				(mid 384.076482 -72.971118)
				(end 384.0226 -72.9488)
			)
			(arc
				(start 384.0226 -72.9488)
				(mid 383.968718 -72.971118)
				(end 383.9464 -73.025)
			)
			(arc
				(start 383.9464 -73.025)
				(mid 383.968718 -73.078882)
				(end 384.0226 -73.1012)
			)
		)
		(stroke
			(width 0)
			(type solid)
		)
		(fill yes)
		(layer "F.Cu")
		(net "GND")
	)
	(gr_poly
		(pts
			(arc
				(start 384.932428 -71.3994)
				(mid 384.98631 -71.377082)
				(end 385.008628 -71.3232)
			)
			(arc
				(start 385.008628 -71.3232)
				(mid 384.98631 -71.269318)
				(end 384.932428 -71.247)
			)
			(arc
				(start 384.932428 -71.247)
				(mid 384.878546 -71.269318)
				(end 384.856228 -71.3232)
			)
			(arc
				(start 384.856228 -71.3232)
				(mid 384.878546 -71.377082)
				(end 384.932428 -71.3994)
			)
		)
		(stroke
			(width 0)
			(type solid)
		)
		(fill yes)
		(layer "F.Cu")
		(net "GND")
	)
	(gr_poly
		(pts
			(arc
				(start 387.024626 -38.046152)
				(mid 387.078508 -38.023834)
				(end 387.100826 -37.969952)
			)
			(arc
				(start 387.100826 -37.969952)
				(mid 387.078508 -37.91607)
				(end 387.024626 -37.893752)
			)
			(arc
				(start 387.024626 -37.893752)
				(mid 386.970744 -37.91607)
				(end 386.948426 -37.969952)
			)
			(arc
				(start 386.948426 -37.969952)
				(mid 386.970744 -38.023834)
				(end 387.024626 -38.046152)
			)
		)
		(stroke
			(width 0)
			(type solid)
		)
		(fill yes)
		(layer "F.Cu")
		(net "GND")
	)
	(gr_poly
		(pts
			(arc
				(start 387.787388 -75.1078)
				(mid 387.84127 -75.085482)
				(end 387.863588 -75.0316)
			)
			(arc
				(start 387.863588 -75.0316)
				(mid 387.84127 -74.977718)
				(end 387.787388 -74.9554)
			)
			(arc
				(start 387.787388 -74.9554)
				(mid 387.733506 -74.977718)
				(end 387.711188 -75.0316)
			)
			(arc
				(start 387.711188 -75.0316)
				(mid 387.733506 -75.085482)
				(end 387.787388 -75.1078)
			)
		)
		(stroke
			(width 0)
			(type solid)
		)
		(fill yes)
		(layer "F.Cu")
		(net "GND")
	)
	(gr_poly
		(pts
			(arc
				(start 394.9192 -32.8676)
				(mid 394.973082 -32.845282)
				(end 394.9954 -32.7914)
			)
			(arc
				(start 394.9954 -32.7914)
				(mid 394.973082 -32.737518)
				(end 394.9192 -32.7152)
			)
			(arc
				(start 394.9192 -32.7152)
				(mid 394.865318 -32.737518)
				(end 394.843 -32.7914)
			)
			(arc
				(start 394.843 -32.7914)
				(mid 394.865318 -32.845282)
				(end 394.9192 -32.8676)
			)
		)
		(stroke
			(width 0)
			(type solid)
		)
		(fill yes)
		(layer "F.Cu")
		(net "GND")
	)
	(gr_poly
		(pts
			(arc
				(start 394.9192 -25.019)
				(mid 394.973082 -24.996682)
				(end 394.9954 -24.9428)
			)
			(arc
				(start 394.9954 -24.9428)
				(mid 394.973082 -24.888918)
				(end 394.9192 -24.8666)
			)
			(arc
				(start 394.9192 -24.8666)
				(mid 394.865318 -24.888918)
				(end 394.843 -24.9428)
			)
			(arc
				(start 394.843 -24.9428)
				(mid 394.865318 -24.996682)
				(end 394.9192 -25.019)
			)
		)
		(stroke
			(width 0)
			(type solid)
		)
		(fill yes)
		(layer "F.Cu")
		(net "GND")
	)
	(gr_poly
		(pts
			(arc
				(start 394.95603 -33.9598)
				(mid 395.009912 -33.937482)
				(end 395.03223 -33.8836)
			)
			(arc
				(start 395.03223 -33.8836)
				(mid 395.009912 -33.829718)
				(end 394.95603 -33.8074)
			)
			(arc
				(start 394.95603 -33.8074)
				(mid 394.902148 -33.829718)
				(end 394.87983 -33.8836)
			)
			(arc
				(start 394.87983 -33.8836)
				(mid 394.902148 -33.937482)
				(end 394.95603 -33.9598)
			)
		)
		(stroke
			(width 0)
			(type solid)
		)
		(fill yes)
		(layer "F.Cu")
		(net "GND")
	)
	(gr_poly
		(pts
			(arc
				(start 394.97 -35.3822)
				(mid 395.023882 -35.359882)
				(end 395.0462 -35.306)
			)
			(arc
				(start 395.0462 -35.306)
				(mid 395.023882 -35.252118)
				(end 394.97 -35.2298)
			)
			(arc
				(start 394.97 -35.2298)
				(mid 394.916118 -35.252118)
				(end 394.8938 -35.306)
			)
			(arc
				(start 394.8938 -35.306)
				(mid 394.916118 -35.359882)
				(end 394.97 -35.3822)
			)
		)
		(stroke
			(width 0)
			(type solid)
		)
		(fill yes)
		(layer "F.Cu")
		(net "GND")
	)
	(gr_poly
		(pts
			(arc
				(start 395.7574 -25.019)
				(mid 395.811282 -24.996682)
				(end 395.8336 -24.9428)
			)
			(arc
				(start 395.8336 -24.9428)
				(mid 395.811282 -24.888918)
				(end 395.7574 -24.8666)
			)
			(arc
				(start 395.7574 -24.8666)
				(mid 395.703518 -24.888918)
				(end 395.6812 -24.9428)
			)
			(arc
				(start 395.6812 -24.9428)
				(mid 395.703518 -24.996682)
				(end 395.7574 -25.019)
			)
		)
		(stroke
			(width 0)
			(type solid)
		)
		(fill yes)
		(layer "F.Cu")
		(net "GND")
	)
	(gr_poly
		(pts
			(arc
				(start 408.1018 -1.2446)
				(mid 408.155682 -1.222282)
				(end 408.178 -1.1684)
			)
			(arc
				(start 408.178 -1.1684)
				(mid 408.155682 -1.114518)
				(end 408.1018 -1.0922)
			)
			(arc
				(start 408.1018 -1.0922)
				(mid 408.047918 -1.114518)
				(end 408.0256 -1.1684)
			)
			(arc
				(start 408.0256 -1.1684)
				(mid 408.047918 -1.222282)
				(end 408.1018 -1.2446)
			)
		)
		(stroke
			(width 0)
			(type solid)
		)
		(fill yes)
		(layer "F.Cu")
		(net "GND")
	)
	(gr_poly
		(pts
			(arc
				(start 411.2514 -1.7272)
				(mid 411.305282 -1.704882)
				(end 411.3276 -1.651)
			)
			(arc
				(start 411.3276 -1.651)
				(mid 411.305282 -1.597118)
				(end 411.2514 -1.5748)
			)
			(arc
				(start 411.2514 -1.5748)
				(mid 411.197518 -1.597118)
				(end 411.1752 -1.651)
			)
			(arc
				(start 411.1752 -1.651)
				(mid 411.197518 -1.704882)
				(end 411.2514 -1.7272)
			)
		)
		(stroke
			(width 0)
			(type solid)
		)
		(fill yes)
		(layer "F.Cu")
		(net "GND")
	)
	(gr_poly
		(pts
			(arc
				(start 413.1056 -1.2446)
				(mid 413.159482 -1.222282)
				(end 413.1818 -1.1684)
			)
			(arc
				(start 413.1818 -1.1684)
				(mid 413.159482 -1.114518)
				(end 413.1056 -1.0922)
			)
			(arc
				(start 413.1056 -1.0922)
				(mid 413.051718 -1.114518)
				(end 413.0294 -1.1684)
			)
			(arc
				(start 413.0294 -1.1684)
				(mid 413.051718 -1.222282)
				(end 413.1056 -1.2446)
			)
		)
		(stroke
			(width 0)
			(type solid)
		)
		(fill yes)
		(layer "F.Cu")
		(net "GND")
	)
	(gr_poly
		(pts
			(arc
				(start 415.671 -1.2446)
				(mid 415.724882 -1.222282)
				(end 415.7472 -1.1684)
			)
			(arc
				(start 415.7472 -1.1684)
				(mid 415.724882 -1.114518)
				(end 415.671 -1.0922)
			)
			(arc
				(start 415.671 -1.0922)
				(mid 415.617118 -1.114518)
				(end 415.5948 -1.1684)
			)
			(arc
				(start 415.5948 -1.1684)
				(mid 415.617118 -1.222282)
				(end 415.671 -1.2446)
			)
		)
		(stroke
			(width 0)
			(type solid)
		)
		(fill yes)
		(layer "F.Cu")
		(net "GND")
	)
	(gr_poly
		(pts
			(arc
				(start 417.096956 -93.584268)
				(mid 417.150838 -93.56195)
				(end 417.173156 -93.508068)
			)
			(arc
				(start 417.173156 -93.508068)
				(mid 417.150838 -93.454186)
				(end 417.096956 -93.431868)
			)
			(arc
				(start 417.096956 -93.431868)
				(mid 417.043074 -93.454186)
				(end 417.020756 -93.508068)
			)
			(arc
				(start 417.020756 -93.508068)
				(mid 417.043074 -93.56195)
				(end 417.096956 -93.584268)
			)
		)
		(stroke
			(width 0)
			(type solid)
		)
		(fill yes)
		(layer "F.Cu")
		(net "GND")
	)
	(gr_poly
		(pts
			(arc
				(start 417.100004 -90.981276)
				(mid 417.153886 -90.958958)
				(end 417.176204 -90.905076)
			)
			(arc
				(start 417.176204 -90.905076)
				(mid 417.153886 -90.851194)
				(end 417.100004 -90.828876)
			)
			(arc
				(start 417.100004 -90.828876)
				(mid 417.046122 -90.851194)
				(end 417.023804 -90.905076)
			)
			(arc
				(start 417.023804 -90.905076)
				(mid 417.046122 -90.958958)
				(end 417.100004 -90.981276)
			)
		)
		(stroke
			(width 0)
			(type solid)
		)
		(fill yes)
		(layer "F.Cu")
		(net "GND")
	)
	(gr_poly
		(pts
			(arc
				(start 418.1348 -1.4224)
				(mid 418.188682 -1.400082)
				(end 418.211 -1.3462)
			)
			(arc
				(start 418.211 -1.3462)
				(mid 418.188682 -1.292318)
				(end 418.1348 -1.27)
			)
			(arc
				(start 418.1348 -1.27)
				(mid 418.080918 -1.292318)
				(end 418.0586 -1.3462)
			)
			(arc
				(start 418.0586 -1.3462)
				(mid 418.080918 -1.400082)
				(end 418.1348 -1.4224)
			)
		)
		(stroke
			(width 0)
			(type solid)
		)
		(fill yes)
		(layer "F.Cu")
		(net "GND")
	)
	(gr_poly
		(pts
			(arc
				(start 419.22192 -93.60281)
				(mid 419.275802 -93.580492)
				(end 419.29812 -93.52661)
			)
			(arc
				(start 419.29812 -93.52661)
				(mid 419.275802 -93.472728)
				(end 419.22192 -93.45041)
			)
			(arc
				(start 419.22192 -93.45041)
				(mid 419.168038 -93.472728)
				(end 419.14572 -93.52661)
			)
			(arc
				(start 419.14572 -93.52661)
				(mid 419.168038 -93.580492)
				(end 419.22192 -93.60281)
			)
		)
		(stroke
			(width 0)
			(type solid)
		)
		(fill yes)
		(layer "F.Cu")
		(net "GND")
	)
	(gr_poly
		(pts
			(arc
				(start 419.258496 -90.978736)
				(mid 419.312378 -90.956418)
				(end 419.334696 -90.902536)
			)
			(arc
				(start 419.334696 -90.902536)
				(mid 419.312378 -90.848654)
				(end 419.258496 -90.826336)
			)
			(arc
				(start 419.258496 -90.826336)
				(mid 419.204614 -90.848654)
				(end 419.182296 -90.902536)
			)
			(arc
				(start 419.182296 -90.902536)
				(mid 419.204614 -90.956418)
				(end 419.258496 -90.978736)
			)
		)
		(stroke
			(width 0)
			(type solid)
		)
		(fill yes)
		(layer "F.Cu")
		(net "GND")
	)
	(gr_poly
		(pts
			(arc
				(start 420.7764 -1.6764)
				(mid 420.830282 -1.654082)
				(end 420.8526 -1.6002)
			)
			(arc
				(start 420.8526 -1.6002)
				(mid 420.830282 -1.546318)
				(end 420.7764 -1.524)
			)
			(arc
				(start 420.7764 -1.524)
				(mid 420.722518 -1.546318)
				(end 420.7002 -1.6002)
			)
			(arc
				(start 420.7002 -1.6002)
				(mid 420.722518 -1.654082)
				(end 420.7764 -1.6764)
			)
		)
		(stroke
			(width 0)
			(type solid)
		)
		(fill yes)
		(layer "F.Cu")
		(net "GND")
	)
	(gr_poly
		(pts
			(arc
				(start 421.119046 -65.41516)
				(mid 421.172928 -65.392842)
				(end 421.195246 -65.33896)
			)
			(arc
				(start 421.195246 -65.33896)
				(mid 421.172928 -65.285078)
				(end 421.119046 -65.26276)
			)
			(arc
				(start 421.119046 -65.26276)
				(mid 421.065164 -65.285078)
				(end 421.042846 -65.33896)
			)
			(arc
				(start 421.042846 -65.33896)
				(mid 421.065164 -65.392842)
				(end 421.119046 -65.41516)
			)
		)
		(stroke
			(width 0)
			(type solid)
		)
		(fill yes)
		(layer "F.Cu")
		(net "GND")
	)
	(gr_poly
		(pts
			(arc
				(start 422.7068 -1.4478)
				(mid 422.760682 -1.425482)
				(end 422.783 -1.3716)
			)
			(arc
				(start 422.783 -1.3716)
				(mid 422.760682 -1.317718)
				(end 422.7068 -1.2954)
			)
			(arc
				(start 422.7068 -1.2954)
				(mid 422.652918 -1.317718)
				(end 422.6306 -1.3716)
			)
			(arc
				(start 422.6306 -1.3716)
				(mid 422.652918 -1.425482)
				(end 422.7068 -1.4478)
			)
		)
		(stroke
			(width 0)
			(type solid)
		)
		(fill yes)
		(layer "F.Cu")
		(net "GND")
	)
	(gr_poly
		(pts
			(arc
				(start 425.6532 -1.1176)
				(mid 425.707082 -1.095282)
				(end 425.7294 -1.0414)
			)
			(arc
				(start 425.7294 -1.0414)
				(mid 425.707082 -0.987518)
				(end 425.6532 -0.9652)
			)
			(arc
				(start 425.6532 -0.9652)
				(mid 425.599318 -0.987518)
				(end 425.577 -1.0414)
			)
			(arc
				(start 425.577 -1.0414)
				(mid 425.599318 -1.095282)
				(end 425.6532 -1.1176)
			)
		)
		(stroke
			(width 0)
			(type solid)
		)
		(fill yes)
		(layer "F.Cu")
		(net "GND")
	)
	(gr_poly
		(pts
			(arc
				(start 444.338456 -9.974834)
				(mid 444.392338 -9.952516)
				(end 444.414656 -9.898634)
			)
			(arc
				(start 444.414656 -9.898634)
				(mid 444.392338 -9.844752)
				(end 444.338456 -9.822434)
			)
			(arc
				(start 444.338456 -9.822434)
				(mid 444.284574 -9.844752)
				(end 444.262256 -9.898634)
			)
			(arc
				(start 444.262256 -9.898634)
				(mid 444.284574 -9.952516)
				(end 444.338456 -9.974834)
			)
		)
		(stroke
			(width 0)
			(type solid)
		)
		(fill yes)
		(layer "F.Cu")
		(net "GND")
	)
	(gr_poly
		(pts
			(arc
				(start 445.491362 -5.693664)
				(mid 445.545244 -5.671346)
				(end 445.567562 -5.617464)
			)
			(arc
				(start 445.567562 -5.617464)
				(mid 445.545244 -5.563582)
				(end 445.491362 -5.541264)
			)
			(arc
				(start 445.491362 -5.541264)
				(mid 445.43748 -5.563582)
				(end 445.415162 -5.617464)
			)
			(arc
				(start 445.415162 -5.617464)
				(mid 445.43748 -5.671346)
				(end 445.491362 -5.693664)
			)
		)
		(stroke
			(width 0)
			(type solid)
		)
		(fill yes)
		(layer "F.Cu")
		(net "GND")
	)
	(gr_poly
		(pts
			(arc
				(start 446.5574 -9.4742)
				(mid 446.611282 -9.451882)
				(end 446.6336 -9.398)
			)
			(arc
				(start 446.6336 -9.398)
				(mid 446.611282 -9.344118)
				(end 446.5574 -9.3218)
			)
			(arc
				(start 446.5574 -9.3218)
				(mid 446.503518 -9.344118)
				(end 446.4812 -9.398)
			)
			(arc
				(start 446.4812 -9.398)
				(mid 446.503518 -9.451882)
				(end 446.5574 -9.4742)
			)
		)
		(stroke
			(width 0)
			(type solid)
		)
		(fill yes)
		(layer "F.Cu")
		(net "GND")
	)
	(gr_poly
		(pts
			(arc
				(start 447.8274 -5.5372)
				(mid 447.881282 -5.514882)
				(end 447.9036 -5.461)
			)
			(arc
				(start 447.9036 -5.461)
				(mid 447.881282 -5.407118)
				(end 447.8274 -5.3848)
			)
			(arc
				(start 447.8274 -5.3848)
				(mid 447.773518 -5.407118)
				(end 447.7512 -5.461)
			)
			(arc
				(start 447.7512 -5.461)
				(mid 447.773518 -5.514882)
				(end 447.8274 -5.5372)
			)
		)
		(stroke
			(width 0)
			(type solid)
		)
		(fill yes)
		(layer "F.Cu")
		(net "GND")
	)
	(gr_poly
		(pts
			(arc
				(start 452.50354 -138.852148)
				(mid 452.557422 -138.82983)
				(end 452.57974 -138.775948)
			)
			(arc
				(start 452.57974 -138.775948)
				(mid 452.557422 -138.722066)
				(end 452.50354 -138.699748)
			)
			(arc
				(start 452.50354 -138.699748)
				(mid 452.449658 -138.722066)
				(end 452.42734 -138.775948)
			)
			(arc
				(start 452.42734 -138.775948)
				(mid 452.449658 -138.82983)
				(end 452.50354 -138.852148)
			)
		)
		(stroke
			(width 0)
			(type solid)
		)
		(fill yes)
		(layer "F.Cu")
		(net "GND")
	)
	(gr_poly
		(pts
			(arc
				(start 468.2998 -64.4398)
				(mid 468.353682 -64.417482)
				(end 468.376 -64.3636)
			)
			(arc
				(start 468.376 -64.3636)
				(mid 468.353682 -64.309718)
				(end 468.2998 -64.2874)
			)
			(arc
				(start 468.2998 -64.2874)
				(mid 468.245918 -64.309718)
				(end 468.2236 -64.3636)
			)
			(arc
				(start 468.2236 -64.3636)
				(mid 468.245918 -64.417482)
				(end 468.2998 -64.4398)
			)
		)
		(stroke
			(width 0)
			(type solid)
		)
		(fill yes)
		(layer "F.Cu")
		(net "GND")
	)
	(gr_poly
		(pts
			(arc
				(start 469.0872 -24.3078)
				(mid 469.141082 -24.285482)
				(end 469.1634 -24.2316)
			)
			(arc
				(start 469.1634 -24.2316)
				(mid 469.141082 -24.177718)
				(end 469.0872 -24.1554)
			)
			(arc
				(start 469.0872 -24.1554)
				(mid 469.033318 -24.177718)
				(end 469.011 -24.2316)
			)
			(arc
				(start 469.011 -24.2316)
				(mid 469.033318 -24.285482)
				(end 469.0872 -24.3078)
			)
		)
		(stroke
			(width 0)
			(type solid)
		)
		(fill yes)
		(layer "F.Cu")
		(net "GND")
	)
	(gr_poly
		(pts
			(arc
				(start 470.4842 -64.0842)
				(mid 470.538082 -64.061882)
				(end 470.5604 -64.008)
			)
			(arc
				(start 470.5604 -64.008)
				(mid 470.538082 -63.954118)
				(end 470.4842 -63.9318)
			)
			(arc
				(start 470.4842 -63.9318)
				(mid 470.430318 -63.954118)
				(end 470.408 -64.008)
			)
			(arc
				(start 470.408 -64.008)
				(mid 470.430318 -64.061882)
				(end 470.4842 -64.0842)
			)
		)
		(stroke
			(width 0)
			(type solid)
		)
		(fill yes)
		(layer "F.Cu")
		(net "GND")
	)
	(gr_poly
		(pts
			(arc
				(start 470.5604 -24.8412)
				(mid 470.614282 -24.818882)
				(end 470.6366 -24.765)
			)
			(arc
				(start 470.6366 -24.765)
				(mid 470.614282 -24.711118)
				(end 470.5604 -24.6888)
			)
			(arc
				(start 470.5604 -24.6888)
				(mid 470.506518 -24.711118)
				(end 470.4842 -24.765)
			)
			(arc
				(start 470.4842 -24.765)
				(mid 470.506518 -24.818882)
				(end 470.5604 -24.8412)
			)
		)
		(stroke
			(width 0)
			(type solid)
		)
		(fill yes)
		(layer "F.Cu")
		(net "GND")
	)
	(gr_poly
		(pts
			(arc
				(start 472.0336 -63.881)
				(mid 472.087482 -63.858682)
				(end 472.1098 -63.8048)
			)
			(arc
				(start 472.1098 -63.8048)
				(mid 472.087482 -63.750918)
				(end 472.0336 -63.7286)
			)
			(arc
				(start 472.0336 -63.7286)
				(mid 471.979718 -63.750918)
				(end 471.9574 -63.8048)
			)
			(arc
				(start 471.9574 -63.8048)
				(mid 471.979718 -63.858682)
				(end 472.0336 -63.881)
			)
		)
		(stroke
			(width 0)
			(type solid)
		)
		(fill yes)
		(layer "F.Cu")
		(net "GND")
	)
	(gr_poly
		(pts
			(arc
				(start 477.1517 -25.34158)
				(mid 477.205582 -25.319262)
				(end 477.2279 -25.26538)
			)
			(arc
				(start 477.2279 -25.26538)
				(mid 477.205582 -25.211498)
				(end 477.1517 -25.18918)
			)
			(arc
				(start 477.1517 -25.18918)
				(mid 477.097818 -25.211498)
				(end 477.0755 -25.26538)
			)
			(arc
				(start 477.0755 -25.26538)
				(mid 477.097818 -25.319262)
				(end 477.1517 -25.34158)
			)
		)
		(stroke
			(width 0)
			(type solid)
		)
		(fill yes)
		(layer "F.Cu")
		(net "GND")
	)
	(gr_poly
		(pts
			(arc
				(start 478.1677 -25.34158)
				(mid 478.221582 -25.319262)
				(end 478.2439 -25.26538)
			)
			(arc
				(start 478.2439 -25.26538)
				(mid 478.221582 -25.211498)
				(end 478.1677 -25.18918)
			)
			(arc
				(start 478.1677 -25.18918)
				(mid 478.113818 -25.211498)
				(end 478.0915 -25.26538)
			)
			(arc
				(start 478.0915 -25.26538)
				(mid 478.113818 -25.319262)
				(end 478.1677 -25.34158)
			)
		)
		(stroke
			(width 0)
			(type solid)
		)
		(fill yes)
		(layer "F.Cu")
		(net "GND")
	)
	(gr_poly
		(pts
			(arc
				(start 478.8916 -37.4142)
				(mid 478.945482 -37.391882)
				(end 478.9678 -37.338)
			)
			(arc
				(start 478.9678 -37.338)
				(mid 478.945482 -37.284118)
				(end 478.8916 -37.2618)
			)
			(arc
				(start 478.8916 -37.2618)
				(mid 478.837718 -37.284118)
				(end 478.8154 -37.338)
			)
			(arc
				(start 478.8154 -37.338)
				(mid 478.837718 -37.391882)
				(end 478.8916 -37.4142)
			)
		)
		(stroke
			(width 0)
			(type solid)
		)
		(fill yes)
		(layer "F.Cu")
		(net "GND")
	)
	(gr_poly
		(pts
			(arc
				(start 479.50882 -26.041858)
				(mid 479.562702 -26.01954)
				(end 479.58502 -25.965658)
			)
			(arc
				(start 479.58502 -25.965658)
				(mid 479.562702 -25.911776)
				(end 479.50882 -25.889458)
			)
			(arc
				(start 479.50882 -25.889458)
				(mid 479.454938 -25.911776)
				(end 479.43262 -25.965658)
			)
			(arc
				(start 479.43262 -25.965658)
				(mid 479.454938 -26.01954)
				(end 479.50882 -26.041858)
			)
		)
		(stroke
			(width 0)
			(type solid)
		)
		(fill yes)
		(layer "F.Cu")
		(net "GND")
	)
	(gr_poly
		(pts
			(arc
				(start 479.861372 -13.67282)
				(mid 479.915254 -13.650502)
				(end 479.937572 -13.59662)
			)
			(arc
				(start 479.937572 -13.59662)
				(mid 479.915254 -13.542738)
				(end 479.861372 -13.52042)
			)
			(arc
				(start 479.861372 -13.52042)
				(mid 479.80749 -13.542738)
				(end 479.785172 -13.59662)
			)
			(arc
				(start 479.785172 -13.59662)
				(mid 479.80749 -13.650502)
				(end 479.861372 -13.67282)
			)
		)
		(stroke
			(width 0)
			(type solid)
		)
		(fill yes)
		(layer "F.Cu")
		(net "GND")
	)
	(gr_poly
		(pts
			(arc
				(start 479.861372 -11.13282)
				(mid 479.915254 -11.110502)
				(end 479.937572 -11.05662)
			)
			(arc
				(start 479.937572 -11.05662)
				(mid 479.915254 -11.002738)
				(end 479.861372 -10.98042)
			)
			(arc
				(start 479.861372 -10.98042)
				(mid 479.80749 -11.002738)
				(end 479.785172 -11.05662)
			)
			(arc
				(start 479.785172 -11.05662)
				(mid 479.80749 -11.110502)
				(end 479.861372 -11.13282)
			)
		)
		(stroke
			(width 0)
			(type solid)
		)
		(fill yes)
		(layer "F.Cu")
		(net "GND")
	)
	(gr_poly
		(pts
			(arc
				(start 480.263962 -16.126206)
				(mid 480.317844 -16.103888)
				(end 480.340162 -16.050006)
			)
			(arc
				(start 480.340162 -16.050006)
				(mid 480.317844 -15.996124)
				(end 480.263962 -15.973806)
			)
			(arc
				(start 480.263962 -15.973806)
				(mid 480.21008 -15.996124)
				(end 480.187762 -16.050006)
			)
			(arc
				(start 480.187762 -16.050006)
				(mid 480.21008 -16.103888)
				(end 480.263962 -16.126206)
			)
		)
		(stroke
			(width 0)
			(type solid)
		)
		(fill yes)
		(layer "F.Cu")
		(net "GND")
	)
	(gr_poly
		(pts
			(arc
				(start 481.5332 -37.973)
				(mid 481.587082 -37.950682)
				(end 481.6094 -37.8968)
			)
			(arc
				(start 481.6094 -37.8968)
				(mid 481.587082 -37.842918)
				(end 481.5332 -37.8206)
			)
			(arc
				(start 481.5332 -37.8206)
				(mid 481.479318 -37.842918)
				(end 481.457 -37.8968)
			)
			(arc
				(start 481.457 -37.8968)
				(mid 481.479318 -37.950682)
				(end 481.5332 -37.973)
			)
		)
		(stroke
			(width 0)
			(type solid)
		)
		(fill yes)
		(layer "F.Cu")
		(net "GND")
	)
	(gr_poly
		(pts
			(arc
				(start 482.6254 -36.9316)
				(mid 482.679282 -36.909282)
				(end 482.7016 -36.8554)
			)
			(arc
				(start 482.7016 -36.8554)
				(mid 482.679282 -36.801518)
				(end 482.6254 -36.7792)
			)
			(arc
				(start 482.6254 -36.7792)
				(mid 482.571518 -36.801518)
				(end 482.5492 -36.8554)
			)
			(arc
				(start 482.5492 -36.8554)
				(mid 482.571518 -36.909282)
				(end 482.6254 -36.9316)
			)
		)
		(stroke
			(width 0)
			(type solid)
		)
		(fill yes)
		(layer "F.Cu")
		(net "GND")
	)
	(gr_poly
		(pts
			(arc
				(start 485.6734 -36.2966)
				(mid 485.727282 -36.274282)
				(end 485.7496 -36.2204)
			)
			(arc
				(start 485.7496 -36.2204)
				(mid 485.727282 -36.166518)
				(end 485.6734 -36.1442)
			)
			(arc
				(start 485.6734 -36.1442)
				(mid 485.619518 -36.166518)
				(end 485.5972 -36.2204)
			)
			(arc
				(start 485.5972 -36.2204)
				(mid 485.619518 -36.274282)
				(end 485.6734 -36.2966)
			)
		)
		(stroke
			(width 0)
			(type solid)
		)
		(fill yes)
		(layer "F.Cu")
		(net "GND")
	)
	(gr_poly
		(pts
			(arc
				(start 486.41762 -37.4777)
				(mid 486.471502 -37.455382)
				(end 486.49382 -37.4015)
			)
			(arc
				(start 486.49382 -37.4015)
				(mid 486.471502 -37.347618)
				(end 486.41762 -37.3253)
			)
			(arc
				(start 486.41762 -37.3253)
				(mid 486.363738 -37.347618)
				(end 486.34142 -37.4015)
			)
			(arc
				(start 486.34142 -37.4015)
				(mid 486.363738 -37.455382)
				(end 486.41762 -37.4777)
			)
		)
		(stroke
			(width 0)
			(type solid)
		)
		(fill yes)
		(layer "F.Cu")
		(net "GND")
	)
	(gr_poly
		(pts
			(xy 30.04439 -85.101176) (xy 31.004256 -85.101176) (xy 31.38551 -84.719922) (xy 32.09544 -84.719922)
			(xy 32.117792 -84.723732) (xy 32.53232 -85.13826) (xy 33.4137 -85.13826) (xy 33.44672 -85.105494)
			(xy 33.44672 -84.351876) (xy 33.630616 -84.16798) (xy 33.630616 -81.80578) (xy 31.6484 -81.80578)
			(xy 31.6484 -83.142582) (xy 31.613602 -83.17738) (xy 31.613602 -83.189064) (xy 31.486602 -83.316064)
			(xy 30.496002 -83.316064) (xy 30.355286 -83.45678) (xy 30.353 -83.45678) (xy 30.2768 -83.53298) (xy 29.5402 -83.53298)
			(xy 29.3878 -83.68538) (xy 29.3878 -84.90839) (xy 29.61767 -85.13826) (xy 30.007306 -85.13826)
		)
		(stroke
			(width 0)
			(type solid)
		)
		(fill yes)
		(layer "F.Cu")
		(net "VR_FET_SW_P12V_STBY_PVCCIN_CPU1")
	)
	(gr_poly
		(pts
			(xy 31.907988 -76.970128) (xy 32.671004 -76.970128) (xy 32.671004 -76.980542) (xy 33.428686 -76.980542)
			(xy 33.458658 -76.95057) (xy 33.458658 -76.211938) (xy 33.630616 -76.03998) (xy 33.630616 -73.67778)
			(xy 31.6484 -73.67778) (xy 31.6484 -75.014582) (xy 31.613602 -75.04938) (xy 31.613602 -75.061064)
			(xy 31.486602 -75.188064) (xy 30.619954 -75.188064) (xy 30.548326 -75.259692) (xy 30.548326 -75.94981)
			(xy 30.334204 -76.163932) (xy 28.871926 -76.163932) (xy 28.829508 -76.206604) (xy 28.829508 -76.708254)
			(xy 28.92425 -76.80325) (xy 30.907736 -76.80325) (xy 31.07436 -76.970128) (xy 31.782004 -76.970128)
			(xy 31.782004 -76.980542) (xy 31.907988 -76.980542)
		)
		(stroke
			(width 0)
			(type solid)
		)
		(fill yes)
		(layer "F.Cu")
		(net "VR_FET_SW_P12V_STBY_PVCCIN_CPU1")
	)
	(gr_poly
		(pts
			(arc
				(start 83.158838 -126.927356)
				(mid 82.854038 -126.927356)
				(end 83.158838 -126.927356)
			)
		)
		(stroke
			(width 0)
			(type solid)
		)
		(fill yes)
		(layer "F.Cu")
		(net "PVDDQ_KLM")
	)
	(gr_poly
		(pts
			(arc
				(start 142.883636 -82.677508)
				(mid 142.595092 -82.677508)
				(end 142.883636 -82.677508)
			)
		)
		(stroke
			(width 0)
			(type solid)
		)
		(fill yes)
		(layer "F.Cu")
		(net "GND")
	)
	(gr_poly
		(pts
			(arc
				(start 142.884906 -80.59928)
				(mid 142.596362 -80.59928)
				(end 142.884906 -80.59928)
			)
		)
		(stroke
			(width 0)
			(type solid)
		)
		(fill yes)
		(layer "F.Cu")
		(net "GND")
	)
	(gr_poly
		(pts
			(arc
				(start 21.122894 -157.208728)
				(mid 20.766278 -157.208728)
				(end 21.122894 -157.208728)
			)
		)
		(stroke
			(width 0)
			(type solid)
		)
		(fill yes)
		(layer "F.Cu")
		(net "GND")
	)
	(gr_poly
		(pts
			(arc
				(start 26.0604 -155.316682)
				(mid 25.703784 -155.316682)
				(end 26.0604 -155.316682)
			)
		)
		(stroke
			(width 0)
			(type solid)
		)
		(fill yes)
		(layer "F.Cu")
		(net "GND")
	)
	(gr_poly
		(pts
			(xy 372.74119 -85.900006) (xy 372.740693 -85.819577) (xy 372.732738 -85.658916) (xy 372.716847 -85.498845)
			(xy 372.69306 -85.339756) (xy 372.661434 -85.182038) (xy 372.622047 -85.026077) (xy 372.574996 -84.872254)
			(xy 372.520395 -84.720947) (xy 372.458378 -84.572524) (xy 372.389097 -84.427351) (xy 372.312722 -84.285781)
			(xy 372.229439 -84.148162) (xy 372.139451 -84.014829) (xy 372.042981 -83.88611) (xy 371.940262 -83.76232)
			(xy 371.831547 -83.64376) (xy 371.717103 -83.530722) (xy 371.597208 -83.423482) (xy 371.472156 -83.322303)
			(xy 371.342254 -83.227431) (xy 371.207818 -83.1391) (xy 371.069179 -83.057525) (xy 370.926676 -82.982906)
			(xy 370.780657 -82.915426) (xy 370.631479 -82.85525) (xy 370.479508 -82.802524) (xy 370.325115 -82.757379)
			(xy 370.168678 -82.719924) (xy 370.010581 -82.690252) (xy 369.85121 -82.668434) (xy 369.690955 -82.654525)
			(xy 369.530208 -82.648557) (xy 369.369362 -82.650547) (xy 369.208812 -82.660488) (xy 369.04895 -82.678357)
			(xy 368.890167 -82.70411) (xy 368.732852 -82.737684) (xy 368.57739 -82.778997) (xy 368.424161 -82.827947)
			(xy 368.27354 -82.884415) (xy 368.125896 -82.948263) (xy 367.981591 -83.019334) (xy 367.840977 -83.097455)
			(xy 367.704398 -83.182434) (xy 367.572189 -83.274063) (xy 367.444672 -83.372119) (xy 367.322162 -83.476361)
			(xy 367.204956 -83.586533) (xy 367.093342 -83.702367) (xy 366.987593 -83.82358) (xy 366.887968 -83.949873)
			(xy 366.79471 -84.080939) (xy 366.708049 -84.216456) (xy 366.628195 -84.356094) (xy 366.555344 -84.499509)
			(xy 366.489675 -84.646352) (xy 366.431349 -84.796263) (xy 366.380507 -84.948874) (xy 366.337275 -85.103814)
			(xy 366.301758 -85.260701) (xy 366.274043 -85.419154) (xy 366.254198 -85.578782) (xy 366.242271 -85.739197)
			(xy 366.238293 -85.900006) (xy 367.52074 -85.900006) (xy 367.524705 -85.775108) (xy 367.536583 -85.650714)
			(xy 367.556327 -85.527323) (xy 367.583857 -85.405433) (xy 367.619062 -85.285534) (xy 367.661801 -85.16811)
			(xy 367.711902 -85.053632) (xy 367.769162 -84.942563) (xy 367.833351 -84.835349) (xy 367.904212 -84.732422)
			(xy 367.981457 -84.634196) (xy 368.064777 -84.541068) (xy 368.153835 -84.453411) (xy 368.248274 -84.37158)
			(xy 368.347713 -84.295902) (xy 368.451751 -84.226684) (xy 368.55997 -84.164204) (xy 368.671934 -84.108713)
			(xy 368.787192 -84.060435) (xy 368.90528 -84.019565) (xy 369.025722 -83.986266) (xy 369.148033 -83.960673)
			(xy 369.271722 -83.94289) (xy 369.396289 -83.932986) (xy 369.521234 -83.931004) (xy 369.646053 -83.93695)
			(xy 369.770243 -83.9508) (xy 369.893306 -83.972499) (xy 370.014744 -84.00196) (xy 370.134069 -84.039063)
			(xy 370.2508 -84.08366) (xy 370.364468 -84.13557) (xy 370.474615 -84.194585) (xy 370.580797 -84.260468)
			(xy 370.682587 -84.332952) (xy 370.779575 -84.411746) (xy 370.871369 -84.496533) (xy 370.957602 -84.586971)
			(xy 371.037925 -84.682696) (xy 371.112015 -84.783323) (xy 371.179574 -84.888447) (xy 371.240329 -84.997643)
			(xy 371.294037 -85.110474) (xy 371.34048 -85.226483) (xy 371.379472 -85.345204) (xy 371.410855 -85.466159)
			(xy 371.434504 -85.588862) (xy 371.450323 -85.712817) (xy 371.458249 -85.837526) (xy 371.458744 -85.900006)
			(xy 371.458249 -85.962486) (xy 371.450323 -86.087195) (xy 371.434504 -86.21115) (xy 371.410855 -86.333853)
			(xy 371.379472 -86.454808) (xy 371.34048 -86.573529) (xy 371.294037 -86.689538) (xy 371.240329 -86.802369)
			(xy 371.179574 -86.911565) (xy 371.112015 -87.016689) (xy 371.037925 -87.117316) (xy 370.957602 -87.213041)
			(xy 370.871369 -87.303479) (xy 370.779575 -87.388266) (xy 370.682587 -87.46706) (xy 370.580797 -87.539544)
			(xy 370.474615 -87.605427) (xy 370.364468 -87.664442) (xy 370.2508 -87.716352) (xy 370.134069 -87.760949)
			(xy 370.014744 -87.798052) (xy 369.893306 -87.827513) (xy 369.770243 -87.849212) (xy 369.646053 -87.863062)
			(xy 369.521234 -87.869008) (xy 369.396289 -87.867026) (xy 369.271722 -87.857122) (xy 369.148033 -87.839339)
			(xy 369.025722 -87.813746) (xy 368.90528 -87.780447) (xy 368.787192 -87.739577) (xy 368.671934 -87.691299)
			(xy 368.55997 -87.635808) (xy 368.451751 -87.573328) (xy 368.347713 -87.50411) (xy 368.248274 -87.428432)
			(xy 368.153835 -87.346601) (xy 368.064777 -87.258944) (xy 367.981457 -87.165816) (xy 367.904212 -87.06759)
			(xy 367.833351 -86.964663) (xy 367.769162 -86.857449) (xy 367.711902 -86.74638) (xy 367.661801 -86.631902)
			(xy 367.619062 -86.514478) (xy 367.583857 -86.394579) (xy 367.556327 -86.272689) (xy 367.536583 -86.149298)
			(xy 367.524705 -86.024904) (xy 367.52074 -85.900006) (xy 366.238293 -85.900006) (xy 366.242271 -86.060815)
			(xy 366.254198 -86.22123) (xy 366.274043 -86.380858) (xy 366.301758 -86.539311) (xy 366.337275 -86.696198)
			(xy 366.380507 -86.851138) (xy 366.431349 -87.003749) (xy 366.489675 -87.15366) (xy 366.555344 -87.300503)
			(xy 366.628195 -87.443918) (xy 366.708049 -87.583556) (xy 366.79471 -87.719073) (xy 366.887968 -87.850139)
			(xy 366.987593 -87.976432) (xy 367.093342 -88.097645) (xy 367.204956 -88.213479) (xy 367.322162 -88.323651)
			(xy 367.444672 -88.427893) (xy 367.572189 -88.525949) (xy 367.704398 -88.617578) (xy 367.840977 -88.702557)
			(xy 367.981591 -88.780678) (xy 368.125896 -88.851749) (xy 368.27354 -88.915597) (xy 368.424161 -88.972065)
			(xy 368.57739 -89.021015) (xy 368.732852 -89.062328) (xy 368.890167 -89.095902) (xy 369.04895 -89.121655)
			(xy 369.208812 -89.139524) (xy 369.369362 -89.149465) (xy 369.530208 -89.151455) (xy 369.690955 -89.145487)
			(xy 369.85121 -89.131578) (xy 370.010581 -89.10976) (xy 370.168678 -89.080088) (xy 370.325115 -89.042633)
			(xy 370.479508 -88.997488) (xy 370.631479 -88.944762) (xy 370.780657 -88.884586) (xy 370.926676 -88.817106)
			(xy 371.069179 -88.742487) (xy 371.207818 -88.660912) (xy 371.342254 -88.572581) (xy 371.472156 -88.477709)
			(xy 371.597208 -88.37653) (xy 371.717103 -88.26929) (xy 371.831547 -88.156252) (xy 371.940262 -88.037692)
			(xy 372.042981 -87.913902) (xy 372.139451 -87.785183) (xy 372.229439 -87.65185) (xy 372.312722 -87.514231)
			(xy 372.389097 -87.372661) (xy 372.458378 -87.227488) (xy 372.520395 -87.079065) (xy 372.574996 -86.927758)
			(xy 372.622047 -86.773935) (xy 372.661434 -86.617974) (xy 372.69306 -86.460256) (xy 372.716847 -86.301167)
			(xy 372.732738 -86.141096) (xy 372.740693 -85.980435)
		)
		(stroke
			(width 0)
			(type solid)
		)
		(fill yes)
		(layer "F.Cu")
		(net "Net_130")
	)
	(gr_poly
		(pts
			(xy 409.74137 -133.89991) (xy 409.740873 -133.819481) (xy 409.732918 -133.65882) (xy 409.717027 -133.498749)
			(xy 409.69324 -133.33966) (xy 409.661614 -133.181942) (xy 409.622227 -133.025981) (xy 409.575176 -132.872158)
			(xy 409.520575 -132.720851) (xy 409.458558 -132.572428) (xy 409.389277 -132.427255) (xy 409.312902 -132.285685)
			(xy 409.229619 -132.148066) (xy 409.139631 -132.014733) (xy 409.043161 -131.886014) (xy 408.940442 -131.762224)
			(xy 408.831727 -131.643664) (xy 408.717283 -131.530626) (xy 408.597388 -131.423386) (xy 408.472336 -131.322207)
			(xy 408.342434 -131.227335) (xy 408.207998 -131.139004) (xy 408.069359 -131.057429) (xy 407.926856 -130.98281)
			(xy 407.780837 -130.91533) (xy 407.631659 -130.855154) (xy 407.479688 -130.802428) (xy 407.325295 -130.757283)
			(xy 407.168858 -130.719828) (xy 407.010761 -130.690156) (xy 406.85139 -130.668338) (xy 406.691135 -130.654429)
			(xy 406.530388 -130.648461) (xy 406.369542 -130.650451) (xy 406.208992 -130.660392) (xy 406.04913 -130.678261)
			(xy 405.890347 -130.704014) (xy 405.733032 -130.737588) (xy 405.57757 -130.778901) (xy 405.424341 -130.827851)
			(xy 405.27372 -130.884319) (xy 405.126076 -130.948167) (xy 404.981771 -131.019238) (xy 404.841157 -131.097359)
			(xy 404.704578 -131.182338) (xy 404.572369 -131.273967) (xy 404.444852 -131.372023) (xy 404.322342 -131.476265)
			(xy 404.205136 -131.586437) (xy 404.093522 -131.702271) (xy 403.987773 -131.823484) (xy 403.888148 -131.949777)
			(xy 403.79489 -132.080843) (xy 403.708229 -132.21636) (xy 403.628375 -132.355998) (xy 403.555524 -132.499413)
			(xy 403.489855 -132.646256) (xy 403.431529 -132.796167) (xy 403.380687 -132.948778) (xy 403.337455 -133.103718)
			(xy 403.301938 -133.260605) (xy 403.274223 -133.419058) (xy 403.254378 -133.578686) (xy 403.242451 -133.739101)
			(xy 403.238473 -133.89991) (xy 404.52092 -133.89991) (xy 404.524885 -133.775012) (xy 404.536763 -133.650618)
			(xy 404.556507 -133.527227) (xy 404.584037 -133.405337) (xy 404.619242 -133.285438) (xy 404.661981 -133.168014)
			(xy 404.712082 -133.053536) (xy 404.769342 -132.942467) (xy 404.833531 -132.835253) (xy 404.904392 -132.732326)
			(xy 404.981637 -132.6341) (xy 405.064957 -132.540972) (xy 405.154015 -132.453315) (xy 405.248454 -132.371484)
			(xy 405.347893 -132.295806) (xy 405.451931 -132.226588) (xy 405.56015 -132.164108) (xy 405.672114 -132.108617)
			(xy 405.787372 -132.060339) (xy 405.90546 -132.019469) (xy 406.025902 -131.98617) (xy 406.148213 -131.960577)
			(xy 406.271902 -131.942794) (xy 406.396469 -131.93289) (xy 406.521414 -131.930908) (xy 406.646233 -131.936854)
			(xy 406.770423 -131.950704) (xy 406.893486 -131.972403) (xy 407.014924 -132.001864) (xy 407.134249 -132.038967)
			(xy 407.25098 -132.083564) (xy 407.364648 -132.135474) (xy 407.474795 -132.194489) (xy 407.580977 -132.260372)
			(xy 407.682767 -132.332856) (xy 407.779755 -132.41165) (xy 407.871549 -132.496437) (xy 407.957782 -132.586875)
			(xy 408.038105 -132.6826) (xy 408.112195 -132.783227) (xy 408.179754 -132.888351) (xy 408.240509 -132.997547)
			(xy 408.294217 -133.110378) (xy 408.34066 -133.226387) (xy 408.379652 -133.345108) (xy 408.411035 -133.466063)
			(xy 408.434684 -133.588766) (xy 408.450503 -133.712721) (xy 408.458429 -133.83743) (xy 408.458924 -133.89991)
			(xy 408.458429 -133.96239) (xy 408.450503 -134.087099) (xy 408.434684 -134.211054) (xy 408.411035 -134.333757)
			(xy 408.379652 -134.454712) (xy 408.34066 -134.573433) (xy 408.294217 -134.689442) (xy 408.240509 -134.802273)
			(xy 408.179754 -134.911469) (xy 408.112195 -135.016593) (xy 408.038105 -135.11722) (xy 407.957782 -135.212945)
			(xy 407.871549 -135.303383) (xy 407.779755 -135.38817) (xy 407.682767 -135.466964) (xy 407.580977 -135.539448)
			(xy 407.474795 -135.605331) (xy 407.364648 -135.664346) (xy 407.25098 -135.716256) (xy 407.134249 -135.760853)
			(xy 407.014924 -135.797956) (xy 406.893486 -135.827417) (xy 406.770423 -135.849116) (xy 406.646233 -135.862966)
			(xy 406.521414 -135.868912) (xy 406.396469 -135.86693) (xy 406.271902 -135.857026) (xy 406.148213 -135.839243)
			(xy 406.025902 -135.81365) (xy 405.90546 -135.780351) (xy 405.787372 -135.739481) (xy 405.672114 -135.691203)
			(xy 405.56015 -135.635712) (xy 405.451931 -135.573232) (xy 405.347893 -135.504014) (xy 405.248454 -135.428336)
			(xy 405.154015 -135.346505) (xy 405.064957 -135.258848) (xy 404.981637 -135.16572) (xy 404.904392 -135.067494)
			(xy 404.833531 -134.964567) (xy 404.769342 -134.857353) (xy 404.712082 -134.746284) (xy 404.661981 -134.631806)
			(xy 404.619242 -134.514382) (xy 404.584037 -134.394483) (xy 404.556507 -134.272593) (xy 404.536763 -134.149202)
			(xy 404.524885 -134.024808) (xy 404.52092 -133.89991) (xy 403.238473 -133.89991) (xy 403.242451 -134.060719)
			(xy 403.254378 -134.221134) (xy 403.274223 -134.380762) (xy 403.301938 -134.539215) (xy 403.337455 -134.696102)
			(xy 403.380687 -134.851042) (xy 403.431529 -135.003653) (xy 403.489855 -135.153564) (xy 403.555524 -135.300407)
			(xy 403.628375 -135.443822) (xy 403.708229 -135.58346) (xy 403.79489 -135.718977) (xy 403.888148 -135.850043)
			(xy 403.987773 -135.976336) (xy 404.093522 -136.097549) (xy 404.205136 -136.213383) (xy 404.322342 -136.323555)
			(xy 404.444852 -136.427797) (xy 404.572369 -136.525853) (xy 404.704578 -136.617482) (xy 404.841157 -136.702461)
			(xy 404.981771 -136.780582) (xy 405.126076 -136.851653) (xy 405.27372 -136.915501) (xy 405.424341 -136.971969)
			(xy 405.57757 -137.020919) (xy 405.733032 -137.062232) (xy 405.890347 -137.095806) (xy 406.04913 -137.121559)
			(xy 406.208992 -137.139428) (xy 406.369542 -137.149369) (xy 406.530388 -137.151359) (xy 406.691135 -137.145391)
			(xy 406.85139 -137.131482) (xy 407.010761 -137.109664) (xy 407.168858 -137.079992) (xy 407.325295 -137.042537)
			(xy 407.479688 -136.997392) (xy 407.631659 -136.944666) (xy 407.780837 -136.88449) (xy 407.926856 -136.81701)
			(xy 408.069359 -136.742391) (xy 408.207998 -136.660816) (xy 408.342434 -136.572485) (xy 408.472336 -136.477613)
			(xy 408.597388 -136.376434) (xy 408.717283 -136.269194) (xy 408.831727 -136.156156) (xy 408.940442 -136.037596)
			(xy 409.043161 -135.913806) (xy 409.139631 -135.785087) (xy 409.229619 -135.651754) (xy 409.312902 -135.514135)
			(xy 409.389277 -135.372565) (xy 409.458558 -135.227392) (xy 409.520575 -135.078969) (xy 409.575176 -134.927662)
			(xy 409.622227 -134.773839) (xy 409.661614 -134.617878) (xy 409.69324 -134.46016) (xy 409.717027 -134.301071)
			(xy 409.732918 -134.141) (xy 409.740873 -133.980339)
		)
		(stroke
			(width 0)
			(type solid)
		)
		(fill yes)
		(layer "F.Cu")
		(net "Net_131")
	)
	(gr_line
		(start 5.055616 -64.557148)
		(end 5.466588 -64.96812)
		(stroke
			(width 0.1905)
			(type default)
		)
		(layer "F.Cu")
	)
	(gr_line
		(start 5.466588 -64.96812)
		(end 7.366 -64.96812)
		(stroke
			(width 0.1905)
			(type default)
		)
		(layer "F.Cu")
	)
	(gr_line
		(start 6.026912 -4.757674)
		(end 6.5913 -4.757674)
		(stroke
			(width 0.0635)
			(type default)
		)
		(layer "F.Cu")
	)
	(gr_line
		(start 6.36524 -4.118356)
		(end 6.82371 -3.659886)
		(stroke
			(width 0.053848)
			(type default)
		)
		(layer "F.Cu")
	)
	(gr_line
		(start 6.5913 -4.757674)
		(end 6.800088 -4.548886)
		(stroke
			(width 0.0635)
			(type default)
		)
		(layer "F.Cu")
	)
	(gr_line
		(start 6.800088 -4.548886)
		(end 7.137146 -4.548886)
		(stroke
			(width 0.0635)
			(type default)
		)
		(layer "F.Cu")
	)
	(gr_line
		(start 6.82371 -3.659886)
		(end 7.137146 -3.659886)
		(stroke
			(width 0.053848)
			(type default)
		)
		(layer "F.Cu")
	)
	(gr_line
		(start 7.137146 -3.198622)
		(end 7.137146 -3.659886)
		(stroke
			(width 0.053848)
			(type default)
		)
		(layer "F.Cu")
	)
	(gr_line
		(start 7.137146 -3.198622)
		(end 8.132318 -2.20345)
		(stroke
			(width 0.053848)
			(type default)
		)
		(layer "F.Cu")
	)
	(gr_line
		(start 8.132318 -2.20345)
		(end 8.232902 -2.20345)
		(stroke
			(width 0.053848)
			(type default)
		)
		(layer "F.Cu")
	)
	(gr_line
		(start 9.398 -69.85)
		(end 10.3632 -70.8152)
		(stroke
			(width 0.2032)
			(type default)
		)
		(layer "F.Cu")
	)
	(gr_line
		(start 9.398 -69.760338)
		(end 9.398 -69.85)
		(stroke
			(width 0.2032)
			(type default)
		)
		(layer "F.Cu")
	)
	(gr_line
		(start 9.398 -68.9483)
		(end 9.398 -69.760338)
		(stroke
			(width 0.1905)
			(type default)
		)
		(layer "F.Cu")
	)
	(gr_line
		(start 9.398 -67.3989)
		(end 9.398 -68.0593)
		(stroke
			(width 0.1905)
			(type default)
		)
		(layer "F.Cu")
	)
	(gr_line
		(start 10.3632 -70.8152)
		(end 11.6332 -70.8152)
		(stroke
			(width 0.2032)
			(type default)
		)
		(layer "F.Cu")
	)
	(gr_line
		(start 10.414 -69.760338)
		(end 10.859262 -70.2056)
		(stroke
			(width 0.2032)
			(type default)
		)
		(layer "F.Cu")
	)
	(gr_line
		(start 10.414 -68.9483)
		(end 10.414 -69.760338)
		(stroke
			(width 0.1905)
			(type default)
		)
		(layer "F.Cu")
	)
	(gr_line
		(start 10.414 -67.3989)
		(end 10.414 -68.0593)
		(stroke
			(width 0.1905)
			(type default)
		)
		(layer "F.Cu")
	)
	(gr_line
		(start 10.859262 -70.2056)
		(end 11.4046 -70.2056)
		(stroke
			(width 0.2032)
			(type default)
		)
		(layer "F.Cu")
	)
	(gr_line
		(start 11.4046 -70.2056)
		(end 13.0302 -68.58)
		(stroke
			(width 0.2032)
			(type default)
		)
		(layer "F.Cu")
	)
	(gr_line
		(start 11.6332 -70.8152)
		(end 11.6586 -70.7898)
		(stroke
			(width 0.1905)
			(type default)
		)
		(layer "F.Cu")
	)
	(gr_line
		(start 11.6586 -70.7898)
		(end 13.3096 -69.1388)
		(stroke
			(width 0.2032)
			(type default)
		)
		(layer "F.Cu")
	)
	(gr_line
		(start 11.9126 -36.36645)
		(end 11.9126 -36.7665)
		(stroke
			(width 0.05715)
			(type default)
		)
		(layer "F.Cu")
	)
	(gr_line
		(start 11.9126 -36.36645)
		(end 11.975084 -36.303966)
		(stroke
			(width 0.05715)
			(type default)
		)
		(layer "F.Cu")
	)
	(gr_line
		(start 11.9126 -35.89655)
		(end 11.975084 -35.959034)
		(stroke
			(width 0.05715)
			(type default)
		)
		(layer "F.Cu")
	)
	(gr_line
		(start 11.9126 -35.4965)
		(end 11.9126 -35.89655)
		(stroke
			(width 0.05715)
			(type default)
		)
		(layer "F.Cu")
	)
	(gr_line
		(start 11.9126 -32.81045)
		(end 11.9126 -33.2105)
		(stroke
			(width 0.05715)
			(type default)
		)
		(layer "F.Cu")
	)
	(gr_line
		(start 11.9126 -32.81045)
		(end 11.975084 -32.747966)
		(stroke
			(width 0.05715)
			(type default)
		)
		(layer "F.Cu")
	)
	(gr_line
		(start 11.9126 -32.34055)
		(end 11.975084 -32.403034)
		(stroke
			(width 0.05715)
			(type default)
		)
		(layer "F.Cu")
	)
	(gr_line
		(start 11.9126 -31.9405)
		(end 11.9126 -32.34055)
		(stroke
			(width 0.05715)
			(type default)
		)
		(layer "F.Cu")
	)
	(gr_line
		(start 11.9126 -29.25445)
		(end 11.9126 -29.6545)
		(stroke
			(width 0.05715)
			(type default)
		)
		(layer "F.Cu")
	)
	(gr_line
		(start 11.9126 -29.25445)
		(end 11.975084 -29.191966)
		(stroke
			(width 0.05715)
			(type default)
		)
		(layer "F.Cu")
	)
	(gr_line
		(start 11.9126 -28.78455)
		(end 11.975084 -28.847034)
		(stroke
			(width 0.05715)
			(type default)
		)
		(layer "F.Cu")
	)
	(gr_line
		(start 11.9126 -28.3845)
		(end 11.9126 -28.78455)
		(stroke
			(width 0.05715)
			(type default)
		)
		(layer "F.Cu")
	)
	(gr_line
		(start 11.9126 -25.69845)
		(end 11.9126 -26.0985)
		(stroke
			(width 0.05715)
			(type default)
		)
		(layer "F.Cu")
	)
	(gr_line
		(start 11.9126 -25.69845)
		(end 11.975084 -25.635966)
		(stroke
			(width 0.05715)
			(type default)
		)
		(layer "F.Cu")
	)
	(gr_line
		(start 11.9126 -25.22855)
		(end 11.975084 -25.291034)
		(stroke
			(width 0.05715)
			(type default)
		)
		(layer "F.Cu")
	)
	(gr_line
		(start 11.9126 -24.8285)
		(end 11.9126 -25.22855)
		(stroke
			(width 0.05715)
			(type default)
		)
		(layer "F.Cu")
	)
	(gr_line
		(start 12.3698 -64.96812)
		(end 14.17828 -64.96812)
		(stroke
			(width 0.1905)
			(type default)
		)
		(layer "F.Cu")
	)
	(gr_line
		(start 13.0302 -68.58)
		(end 15.0622 -68.58)
		(stroke
			(width 0.2032)
			(type default)
		)
		(layer "F.Cu")
	)
	(gr_line
		(start 13.050774 -27.47645)
		(end 13.050774 -27.8765)
		(stroke
			(width 0.05715)
			(type default)
		)
		(layer "F.Cu")
	)
	(gr_line
		(start 13.050774 -27.47645)
		(end 13.14704 -27.380184)
		(stroke
			(width 0.05715)
			(type default)
		)
		(layer "F.Cu")
	)
	(gr_line
		(start 13.050774 -27.00655)
		(end 13.14704 -27.102816)
		(stroke
			(width 0.05715)
			(type default)
		)
		(layer "F.Cu")
	)
	(gr_line
		(start 13.050774 -26.6065)
		(end 13.050774 -27.00655)
		(stroke
			(width 0.05715)
			(type default)
		)
		(layer "F.Cu")
	)
	(gr_line
		(start 13.050774 -23.92045)
		(end 13.050774 -24.3205)
		(stroke
			(width 0.05715)
			(type default)
		)
		(layer "F.Cu")
	)
	(gr_line
		(start 13.050774 -23.92045)
		(end 13.14704 -23.824184)
		(stroke
			(width 0.05715)
			(type default)
		)
		(layer "F.Cu")
	)
	(gr_line
		(start 13.050774 -23.45055)
		(end 13.14704 -23.546816)
		(stroke
			(width 0.05715)
			(type default)
		)
		(layer "F.Cu")
	)
	(gr_line
		(start 13.050774 -23.0505)
		(end 13.050774 -23.45055)
		(stroke
			(width 0.05715)
			(type default)
		)
		(layer "F.Cu")
	)
	(gr_line
		(start 13.098526 -34.58845)
		(end 13.098526 -34.9885)
		(stroke
			(width 0.05715)
			(type default)
		)
		(layer "F.Cu")
	)
	(gr_line
		(start 13.098526 -34.58845)
		(end 13.16101 -34.525966)
		(stroke
			(width 0.05715)
			(type default)
		)
		(layer "F.Cu")
	)
	(gr_line
		(start 13.098526 -34.11855)
		(end 13.16101 -34.181034)
		(stroke
			(width 0.05715)
			(type default)
		)
		(layer "F.Cu")
	)
	(gr_line
		(start 13.098526 -33.7185)
		(end 13.098526 -34.11855)
		(stroke
			(width 0.05715)
			(type default)
		)
		(layer "F.Cu")
	)
	(gr_line
		(start 13.098526 -31.03245)
		(end 13.098526 -31.4325)
		(stroke
			(width 0.05715)
			(type default)
		)
		(layer "F.Cu")
	)
	(gr_line
		(start 13.098526 -31.03245)
		(end 13.16101 -30.969966)
		(stroke
			(width 0.05715)
			(type default)
		)
		(layer "F.Cu")
	)
	(gr_line
		(start 13.098526 -30.56255)
		(end 13.16101 -30.625034)
		(stroke
			(width 0.05715)
			(type default)
		)
		(layer "F.Cu")
	)
	(gr_line
		(start 13.098526 -30.1625)
		(end 13.098526 -30.56255)
		(stroke
			(width 0.05715)
			(type default)
		)
		(layer "F.Cu")
	)
	(gr_line
		(start 13.14704 -27.380184)
		(end 13.587984 -27.380184)
		(stroke
			(width 0.05715)
			(type default)
		)
		(layer "F.Cu")
	)
	(gr_line
		(start 13.14704 -27.102816)
		(end 13.587984 -27.102816)
		(stroke
			(width 0.05715)
			(type default)
		)
		(layer "F.Cu")
	)
	(gr_line
		(start 13.14704 -23.824184)
		(end 13.587984 -23.824184)
		(stroke
			(width 0.05715)
			(type default)
		)
		(layer "F.Cu")
	)
	(gr_line
		(start 13.14704 -23.546816)
		(end 13.587984 -23.546816)
		(stroke
			(width 0.05715)
			(type default)
		)
		(layer "F.Cu")
	)
	(gr_line
		(start 13.3096 -69.1388)
		(end 14.732 -69.1388)
		(stroke
			(width 0.2032)
			(type default)
		)
		(layer "F.Cu")
	)
	(gr_line
		(start 13.587984 -27.380184)
		(end 13.8938 -27.686)
		(stroke
			(width 0.05715)
			(type default)
		)
		(layer "F.Cu")
	)
	(gr_line
		(start 13.587984 -27.102816)
		(end 13.8938 -26.797)
		(stroke
			(width 0.05715)
			(type default)
		)
		(layer "F.Cu")
	)
	(gr_line
		(start 13.587984 -23.824184)
		(end 13.8938 -24.13)
		(stroke
			(width 0.05715)
			(type default)
		)
		(layer "F.Cu")
	)
	(gr_line
		(start 13.587984 -23.546816)
		(end 13.8938 -23.241)
		(stroke
			(width 0.05715)
			(type default)
		)
		(layer "F.Cu")
	)
	(gr_line
		(start 13.621766 -36.303966)
		(end 13.8938 -36.576)
		(stroke
			(width 0.05715)
			(type default)
		)
		(layer "F.Cu")
	)
	(gr_line
		(start 13.621766 -35.959034)
		(end 13.8938 -35.687)
		(stroke
			(width 0.05715)
			(type default)
		)
		(layer "F.Cu")
	)
	(gr_line
		(start 13.621766 -34.525966)
		(end 13.8938 -34.798)
		(stroke
			(width 0.05715)
			(type default)
		)
		(layer "F.Cu")
	)
	(gr_line
		(start 13.621766 -34.181034)
		(end 13.8938 -33.909)
		(stroke
			(width 0.05715)
			(type default)
		)
		(layer "F.Cu")
	)
	(gr_line
		(start 13.621766 -32.747966)
		(end 13.8938 -33.02)
		(stroke
			(width 0.05715)
			(type default)
		)
		(layer "F.Cu")
	)
	(gr_line
		(start 13.621766 -32.403034)
		(end 13.8938 -32.131)
		(stroke
			(width 0.05715)
			(type default)
		)
		(layer "F.Cu")
	)
	(gr_line
		(start 13.621766 -30.969966)
		(end 13.8938 -31.242)
		(stroke
			(width 0.05715)
			(type default)
		)
		(layer "F.Cu")
	)
	(gr_line
		(start 13.621766 -30.625034)
		(end 13.8938 -30.353)
		(stroke
			(width 0.05715)
			(type default)
		)
		(layer "F.Cu")
	)
	(gr_line
		(start 13.621766 -29.191966)
		(end 13.8938 -29.464)
		(stroke
			(width 0.05715)
			(type default)
		)
		(layer "F.Cu")
	)
	(gr_line
		(start 13.621766 -28.847034)
		(end 13.8938 -28.575)
		(stroke
			(width 0.05715)
			(type default)
		)
		(layer "F.Cu")
	)
	(gr_line
		(start 13.621766 -25.635966)
		(end 13.8938 -25.908)
		(stroke
			(width 0.05715)
			(type default)
		)
		(layer "F.Cu")
	)
	(gr_line
		(start 13.621766 -25.291034)
		(end 13.8938 -25.019)
		(stroke
			(width 0.05715)
			(type default)
		)
		(layer "F.Cu")
	)
	(gr_line
		(start 14.17828 -64.96812)
		(end 14.605 -64.5414)
		(stroke
			(width 0.1905)
			(type default)
		)
		(layer "F.Cu")
	)
	(gr_line
		(start 14.224 -70.612)
		(end 14.859 -71.247)
		(stroke
			(width 0.1905)
			(type default)
		)
		(layer "F.Cu")
	)
	(gr_line
		(start 14.224 -69.977)
		(end 14.224 -70.612)
		(stroke
			(width 0.1905)
			(type default)
		)
		(layer "F.Cu")
	)
	(gr_line
		(start 14.732 -69.1388)
		(end 15.113 -69.5198)
		(stroke
			(width 0.2032)
			(type default)
		)
		(layer "F.Cu")
	)
	(gr_line
		(start 14.7828 -36.576)
		(end 15.054834 -36.303966)
		(stroke
			(width 0.05715)
			(type default)
		)
		(layer "F.Cu")
	)
	(gr_line
		(start 14.7828 -35.687)
		(end 15.054834 -35.959034)
		(stroke
			(width 0.05715)
			(type default)
		)
		(layer "F.Cu")
	)
	(gr_line
		(start 14.7828 -34.798)
		(end 15.054834 -34.525966)
		(stroke
			(width 0.05715)
			(type default)
		)
		(layer "F.Cu")
	)
	(gr_line
		(start 14.7828 -33.909)
		(end 15.054834 -34.181034)
		(stroke
			(width 0.05715)
			(type default)
		)
		(layer "F.Cu")
	)
	(gr_line
		(start 14.7828 -33.02)
		(end 15.088616 -32.714184)
		(stroke
			(width 0.05715)
			(type default)
		)
		(layer "F.Cu")
	)
	(gr_line
		(start 14.7828 -32.131)
		(end 15.088616 -32.436816)
		(stroke
			(width 0.05715)
			(type default)
		)
		(layer "F.Cu")
	)
	(gr_line
		(start 14.7828 -31.242)
		(end 15.054834 -30.969966)
		(stroke
			(width 0.05715)
			(type default)
		)
		(layer "F.Cu")
	)
	(gr_line
		(start 14.7828 -30.353)
		(end 15.054834 -30.625034)
		(stroke
			(width 0.05715)
			(type default)
		)
		(layer "F.Cu")
	)
	(gr_line
		(start 14.7828 -29.464)
		(end 15.054834 -29.191966)
		(stroke
			(width 0.05715)
			(type default)
		)
		(layer "F.Cu")
	)
	(gr_line
		(start 14.7828 -28.575)
		(end 15.054834 -28.847034)
		(stroke
			(width 0.05715)
			(type default)
		)
		(layer "F.Cu")
	)
	(gr_line
		(start 14.7828 -27.686)
		(end 15.054834 -27.413966)
		(stroke
			(width 0.05715)
			(type default)
		)
		(layer "F.Cu")
	)
	(gr_line
		(start 14.7828 -26.797)
		(end 15.054834 -27.069034)
		(stroke
			(width 0.05715)
			(type default)
		)
		(layer "F.Cu")
	)
	(gr_line
		(start 14.7828 -25.908)
		(end 15.088616 -25.602184)
		(stroke
			(width 0.05715)
			(type default)
		)
		(layer "F.Cu")
	)
	(gr_line
		(start 14.7828 -25.019)
		(end 15.088616 -25.324816)
		(stroke
			(width 0.05715)
			(type default)
		)
		(layer "F.Cu")
	)
	(gr_line
		(start 14.7828 -24.13)
		(end 14.910054 -24.002746)
		(stroke
			(width 0.05715)
			(type default)
		)
		(layer "F.Cu")
	)
	(gr_line
		(start 14.7828 -23.53056)
		(end 14.910054 -23.657814)
		(stroke
			(width 0.05715)
			(type default)
		)
		(layer "F.Cu")
	)
	(gr_line
		(start 14.7828 -23.241)
		(end 14.7828 -23.53056)
		(stroke
			(width 0.05715)
			(type default)
		)
		(layer "F.Cu")
	)
	(gr_line
		(start 14.859 -71.247)
		(end 14.986 -71.247)
		(stroke
			(width 0.1905)
			(type default)
		)
		(layer "F.Cu")
	)
	(gr_line
		(start 14.9098 -71.8693)
		(end 14.9098 -71.882)
		(stroke
			(width 0.1905)
			(type default)
		)
		(layer "F.Cu")
	)
	(gr_line
		(start 14.9098 -71.8693)
		(end 14.986 -71.7931)
		(stroke
			(width 0.1905)
			(type default)
		)
		(layer "F.Cu")
	)
	(gr_line
		(start 14.986 -71.247)
		(end 14.986 -71.7931)
		(stroke
			(width 0.1905)
			(type default)
		)
		(layer "F.Cu")
	)
	(gr_line
		(start 15.0622 -68.58)
		(end 15.875 -69.3928)
		(stroke
			(width 0.2032)
			(type default)
		)
		(layer "F.Cu")
	)
	(gr_line
		(start 15.088616 -32.714184)
		(end 15.354808 -32.714184)
		(stroke
			(width 0.05715)
			(type default)
		)
		(layer "F.Cu")
	)
	(gr_line
		(start 15.088616 -32.436816)
		(end 15.354808 -32.436816)
		(stroke
			(width 0.05715)
			(type default)
		)
		(layer "F.Cu")
	)
	(gr_line
		(start 15.088616 -25.602184)
		(end 15.354808 -25.602184)
		(stroke
			(width 0.05715)
			(type default)
		)
		(layer "F.Cu")
	)
	(gr_line
		(start 15.088616 -25.324816)
		(end 15.354808 -25.324816)
		(stroke
			(width 0.05715)
			(type default)
		)
		(layer "F.Cu")
	)
	(gr_line
		(start 15.113 -69.5198)
		(end 15.113 -69.977)
		(stroke
			(width 0.2032)
			(type default)
		)
		(layer "F.Cu")
	)
	(gr_line
		(start 15.354808 -32.714184)
		(end 15.451074 -32.81045)
		(stroke
			(width 0.05715)
			(type default)
		)
		(layer "F.Cu")
	)
	(gr_line
		(start 15.354808 -32.436816)
		(end 15.451074 -32.34055)
		(stroke
			(width 0.05715)
			(type default)
		)
		(layer "F.Cu")
	)
	(gr_line
		(start 15.354808 -25.602184)
		(end 15.451074 -25.69845)
		(stroke
			(width 0.05715)
			(type default)
		)
		(layer "F.Cu")
	)
	(gr_line
		(start 15.354808 -25.324816)
		(end 15.451074 -25.22855)
		(stroke
			(width 0.05715)
			(type default)
		)
		(layer "F.Cu")
	)
	(gr_line
		(start 15.355316 -29.191966)
		(end 15.4178 -29.25445)
		(stroke
			(width 0.05715)
			(type default)
		)
		(layer "F.Cu")
	)
	(gr_line
		(start 15.355316 -28.847034)
		(end 15.4178 -28.78455)
		(stroke
			(width 0.05715)
			(type default)
		)
		(layer "F.Cu")
	)
	(gr_line
		(start 15.38859 -36.303966)
		(end 15.451074 -36.36645)
		(stroke
			(width 0.05715)
			(type default)
		)
		(layer "F.Cu")
	)
	(gr_line
		(start 15.38859 -35.959034)
		(end 15.451074 -35.89655)
		(stroke
			(width 0.05715)
			(type default)
		)
		(layer "F.Cu")
	)
	(gr_line
		(start 15.4178 -29.25445)
		(end 15.4178 -29.6545)
		(stroke
			(width 0.05715)
			(type default)
		)
		(layer "F.Cu")
	)
	(gr_line
		(start 15.4178 -28.3845)
		(end 15.4178 -28.78455)
		(stroke
			(width 0.05715)
			(type default)
		)
		(layer "F.Cu")
	)
	(gr_line
		(start 15.443454 -26.0985)
		(end 15.451074 -25.69845)
		(stroke
			(width 0.05715)
			(type default)
		)
		(layer "F.Cu")
	)
	(gr_line
		(start 15.443454 -24.8285)
		(end 15.451074 -25.22855)
		(stroke
			(width 0.05715)
			(type default)
		)
		(layer "F.Cu")
	)
	(gr_line
		(start 15.451074 -36.36645)
		(end 15.451074 -36.7665)
		(stroke
			(width 0.05715)
			(type default)
		)
		(layer "F.Cu")
	)
	(gr_line
		(start 15.451074 -35.4965)
		(end 15.451074 -35.89655)
		(stroke
			(width 0.05715)
			(type default)
		)
		(layer "F.Cu")
	)
	(gr_line
		(start 15.451074 -32.81045)
		(end 15.451074 -33.2105)
		(stroke
			(width 0.05715)
			(type default)
		)
		(layer "F.Cu")
	)
	(gr_line
		(start 15.451074 -31.9405)
		(end 15.451074 -32.34055)
		(stroke
			(width 0.05715)
			(type default)
		)
		(layer "F.Cu")
	)
	(gr_line
		(start 15.748 -70.612)
		(end 15.875 -70.485)
		(stroke
			(width 0.1905)
			(type default)
		)
		(layer "F.Cu")
	)
	(gr_line
		(start 15.875 -69.977)
		(end 15.875 -70.485)
		(stroke
			(width 0.1905)
			(type default)
		)
		(layer "F.Cu")
	)
	(gr_line
		(start 15.875 -69.3928)
		(end 15.875 -69.977)
		(stroke
			(width 0.2032)
			(type default)
		)
		(layer "F.Cu")
	)
	(gr_line
		(start 16.18615 -23.0886)
		(end 16.6497 -23.0886)
		(stroke
			(width 0.05715)
			(type default)
		)
		(layer "F.Cu")
	)
	(gr_line
		(start 16.341344 -27.36469)
		(end 16.607536 -27.630882)
		(stroke
			(width 0.05715)
			(type default)
		)
		(layer "F.Cu")
	)
	(gr_line
		(start 16.493236 -27.12085)
		(end 16.607536 -27.00655)
		(stroke
			(width 0.05715)
			(type default)
		)
		(layer "F.Cu")
	)
	(gr_line
		(start 16.550386 -30.964886)
		(end 16.61287 -31.02737)
		(stroke
			(width 0.05715)
			(type default)
		)
		(layer "F.Cu")
	)
	(gr_line
		(start 16.550386 -30.619954)
		(end 16.61287 -30.55747)
		(stroke
			(width 0.05715)
			(type default)
		)
		(layer "F.Cu")
	)
	(gr_line
		(start 16.607536 -27.630882)
		(end 16.607536 -27.8765)
		(stroke
			(width 0.05715)
			(type default)
		)
		(layer "F.Cu")
	)
	(gr_line
		(start 16.607536 -26.6065)
		(end 16.607536 -27.00655)
		(stroke
			(width 0.05715)
			(type default)
		)
		(layer "F.Cu")
	)
	(gr_line
		(start 16.61287 -31.02737)
		(end 16.61287 -31.42742)
		(stroke
			(width 0.05715)
			(type default)
		)
		(layer "F.Cu")
	)
	(gr_line
		(start 16.61287 -30.15742)
		(end 16.61287 -30.55747)
		(stroke
			(width 0.05715)
			(type default)
		)
		(layer "F.Cu")
	)
	(gr_line
		(start 16.622014 -34.525966)
		(end 16.684498 -34.58845)
		(stroke
			(width 0.05715)
			(type default)
		)
		(layer "F.Cu")
	)
	(gr_line
		(start 16.622014 -34.181034)
		(end 16.684498 -34.11855)
		(stroke
			(width 0.05715)
			(type default)
		)
		(layer "F.Cu")
	)
	(gr_line
		(start 16.6497 -23.0886)
		(end 16.712184 -23.151084)
		(stroke
			(width 0.05715)
			(type default)
		)
		(layer "F.Cu")
	)
	(gr_line
		(start 16.684498 -34.58845)
		(end 16.684498 -34.9885)
		(stroke
			(width 0.05715)
			(type default)
		)
		(layer "F.Cu")
	)
	(gr_line
		(start 16.684498 -33.7185)
		(end 16.684498 -34.11855)
		(stroke
			(width 0.05715)
			(type default)
		)
		(layer "F.Cu")
	)
	(gr_line
		(start 17.057116 -23.151084)
		(end 17.1196 -23.0886)
		(stroke
			(width 0.05715)
			(type default)
		)
		(layer "F.Cu")
	)
	(gr_line
		(start 17.1196 -23.0886)
		(end 17.45615 -23.0886)
		(stroke
			(width 0.05715)
			(type default)
		)
		(layer "F.Cu")
	)
	(gr_line
		(start 17.3482 -71.5264)
		(end 17.41043 -71.58863)
		(stroke
			(width 0.127)
			(type default)
		)
		(layer "F.Cu")
	)
	(gr_line
		(start 17.41043 -71.58863)
		(end 17.41043 -73.3425)
		(stroke
			(width 0.127)
			(type default)
		)
		(layer "F.Cu")
	)
	(gr_line
		(start 18.41119 -72.470518)
		(end 18.41119 -73.3425)
		(stroke
			(width 0.127)
			(type default)
		)
		(layer "F.Cu")
	)
	(gr_line
		(start 18.41119 -72.470518)
		(end 18.517616 -72.364092)
		(stroke
			(width 0.127)
			(type default)
		)
		(layer "F.Cu")
	)
	(gr_line
		(start 20.831048 -89.074752)
		(end 20.831048 -89.5604)
		(stroke
			(width 0.0635)
			(type default)
		)
		(layer "F.Cu")
	)
	(gr_line
		(start 20.831048 -89.074752)
		(end 21.6408 -88.265)
		(stroke
			(width 0.0635)
			(type default)
		)
		(layer "F.Cu")
	)
	(gr_line
		(start 21.6408 -88.138)
		(end 21.6408 -88.265)
		(stroke
			(width 0.0635)
			(type default)
		)
		(layer "F.Cu")
	)
	(gr_line
		(start 21.6408 -88.138)
		(end 21.7678 -88.265)
		(stroke
			(width 0.0635)
			(type default)
		)
		(layer "F.Cu")
	)
	(gr_line
		(start 21.6408 -87.3506)
		(end 22.352 -87.3506)
		(stroke
			(width 0.0635)
			(type default)
		)
		(layer "F.Cu")
	)
	(gr_line
		(start 21.7678 -88.265)
		(end 22.3266 -88.265)
		(stroke
			(width 0.0635)
			(type default)
		)
		(layer "F.Cu")
	)
	(gr_line
		(start 22.3266 -94.655894)
		(end 22.593554 -94.655894)
		(stroke
			(width 0.1016)
			(type default)
		)
		(layer "F.Cu")
	)
	(gr_line
		(start 22.593554 -94.655894)
		(end 22.75078 -94.81312)
		(stroke
			(width 0.1016)
			(type default)
		)
		(layer "F.Cu")
	)
	(gr_line
		(start 22.75078 -95.49384)
		(end 23.084536 -95.827596)
		(stroke
			(width 0.127)
			(type default)
		)
		(layer "F.Cu")
	)
	(gr_line
		(start 22.75078 -94.81312)
		(end 22.75078 -95.49384)
		(stroke
			(width 0.127)
			(type default)
		)
		(layer "F.Cu")
	)
	(gr_line
		(start 23.084536 -95.827596)
		(end 23.366984 -95.827596)
		(stroke
			(width 0.127)
			(type default)
		)
		(layer "F.Cu")
	)
	(gr_line
		(start 23.366984 -95.827596)
		(end 23.802848 -96.26346)
		(stroke
			(width 0.127)
			(type default)
		)
		(layer "F.Cu")
	)
	(gr_line
		(start 23.802848 -96.26346)
		(end 23.802848 -96.648778)
		(stroke
			(width 0.127)
			(type default)
		)
		(layer "F.Cu")
	)
	(gr_line
		(start 24.230584 -95.827596)
		(end 24.757888 -96.3549)
		(stroke
			(width 0.127)
			(type default)
		)
		(layer "F.Cu")
	)
	(gr_line
		(start 24.757888 -96.3549)
		(end 24.757888 -96.757236)
		(stroke
			(width 0.127)
			(type default)
		)
		(layer "F.Cu")
	)
	(gr_circle
		(center 25.2984 -61.0362)
		(end 25.5524 -61.0362)
		(stroke
			(width 0.2)
			(type default)
		)
		(fill no)
		(layer "F.Cu")
	)
	(gr_line
		(start 25.459182 -149.778212)
		(end 25.71496 -149.778212)
		(stroke
			(width 0.2)
			(type default)
		)
		(layer "F.Cu")
	)
	(gr_line
		(start 25.459182 -140.177012)
		(end 25.713182 -140.177012)
		(stroke
			(width 0.2)
			(type default)
		)
		(layer "F.Cu")
	)
	(gr_line
		(start 25.459182 -130.575812)
		(end 25.713182 -130.575812)
		(stroke
			(width 0.2)
			(type default)
		)
		(layer "F.Cu")
	)
	(gr_circle
		(center 27.432 -62.7888)
		(end 27.686 -62.7888)
		(stroke
			(width 0.2)
			(type default)
		)
		(fill no)
		(layer "F.Cu")
	)
	(gr_line
		(start 38.1 -50.7619)
		(end 38.2905 -50.5714)
		(stroke
			(width 0.0635)
			(type default)
		)
		(layer "F.Cu")
	)
	(gr_line
		(start 38.1 -49.4919)
		(end 38.2905 -49.6824)
		(stroke
			(width 0.0635)
			(type default)
		)
		(layer "F.Cu")
	)
	(gr_line
		(start 38.2905 -50.5714)
		(end 38.9128 -50.5714)
		(stroke
			(width 0.0635)
			(type default)
		)
		(layer "F.Cu")
	)
	(gr_line
		(start 38.2905 -49.6824)
		(end 38.9128 -49.6824)
		(stroke
			(width 0.0635)
			(type default)
		)
		(layer "F.Cu")
	)
	(gr_line
		(start 38.9128 -50.5714)
		(end 39.6748 -50.5714)
		(stroke
			(width 0.0635)
			(type default)
		)
		(layer "F.Cu")
	)
	(gr_line
		(start 38.9128 -49.6824)
		(end 39.6748 -49.6824)
		(stroke
			(width 0.0635)
			(type default)
		)
		(layer "F.Cu")
	)
	(gr_line
		(start 38.961568 -103.505)
		(end 39.723568 -103.505)
		(stroke
			(width 0.127)
			(type default)
		)
		(layer "F.Cu")
	)
	(gr_line
		(start 38.961568 -102.616)
		(end 39.723568 -102.616)
		(stroke
			(width 0.127)
			(type default)
		)
		(layer "F.Cu")
	)
	(gr_line
		(start 39.723568 -103.505)
		(end 39.737284 -103.491284)
		(stroke
			(width 0.127)
			(type default)
		)
		(layer "F.Cu")
	)
	(gr_line
		(start 39.723568 -102.616)
		(end 40.034972 -102.616)
		(stroke
			(width 0.127)
			(type default)
		)
		(layer "F.Cu")
	)
	(gr_line
		(start 39.737284 -103.491284)
		(end 40.60825 -103.491284)
		(stroke
			(width 0.127)
			(type default)
		)
		(layer "F.Cu")
	)
	(gr_line
		(start 40.034972 -102.616)
		(end 40.148256 -102.729284)
		(stroke
			(width 0.127)
			(type default)
		)
		(layer "F.Cu")
	)
	(gr_line
		(start 40.148256 -102.729284)
		(end 40.60825 -102.729284)
		(stroke
			(width 0.127)
			(type default)
		)
		(layer "F.Cu")
	)
	(gr_line
		(start 40.5638 -50.5714)
		(end 40.954452 -50.5714)
		(stroke
			(width 0.0635)
			(type default)
		)
		(layer "F.Cu")
	)
	(gr_line
		(start 40.5638 -49.6824)
		(end 41.3512 -49.6824)
		(stroke
			(width 0.0635)
			(type default)
		)
		(layer "F.Cu")
	)
	(gr_line
		(start 40.954452 -50.5714)
		(end 41.348152 -50.9651)
		(stroke
			(width 0.0635)
			(type default)
		)
		(layer "F.Cu")
	)
	(gr_line
		(start 41.49725 -103.491284)
		(end 42.338244 -103.491284)
		(stroke
			(width 0.127)
			(type default)
		)
		(layer "F.Cu")
	)
	(gr_line
		(start 41.49725 -102.729284)
		(end 42.479976 -102.729284)
		(stroke
			(width 0.127)
			(type default)
		)
		(layer "F.Cu")
	)
	(gr_line
		(start 42.338244 -103.491284)
		(end 42.59072 -103.74376)
		(stroke
			(width 0.127)
			(type default)
		)
		(layer "F.Cu")
	)
	(gr_line
		(start 42.479976 -102.729284)
		(end 42.58056 -102.829868)
		(stroke
			(width 0.127)
			(type default)
		)
		(layer "F.Cu")
	)
	(gr_line
		(start 49.0474 -63.524892)
		(end 49.0474 -63.825882)
		(stroke
			(width 0.2)
			(type default)
		)
		(layer "F.Cu")
	)
	(gr_line
		(start 49.0474 -58.698892)
		(end 49.0474 -58.364882)
		(stroke
			(width 0.2)
			(type default)
		)
		(layer "F.Cu")
	)
	(gr_line
		(start 67.101466 -69.45884)
		(end 67.749166 -69.45884)
		(stroke
			(width 0.0635)
			(type default)
		)
		(layer "F.Cu")
	)
	(gr_line
		(start 68.036186 -68.963286)
		(end 68.607686 -68.963286)
		(stroke
			(width 0.0635)
			(type default)
		)
		(layer "F.Cu")
	)
	(gr_line
		(start 75.762866 -82.33664)
		(end 76.334366 -82.33664)
		(stroke
			(width 0.0635)
			(type default)
		)
		(layer "F.Cu")
	)
	(gr_line
		(start 75.762866 -81.34604)
		(end 76.334366 -81.34604)
		(stroke
			(width 0.0635)
			(type default)
		)
		(layer "F.Cu")
	)
	(gr_line
		(start 119.929402 -87.603584)
		(end 120.500902 -87.603584)
		(stroke
			(width 0.05715)
			(type default)
		)
		(layer "F.Cu")
	)
	(gr_line
		(start 120.787668 -89.089738)
		(end 121.359168 -89.089738)
		(stroke
			(width 0.05715)
			(type default)
		)
		(layer "F.Cu")
	)
	(gr_line
		(start 120.787668 -88.099138)
		(end 121.359168 -88.099138)
		(stroke
			(width 0.05715)
			(type default)
		)
		(layer "F.Cu")
	)
	(gr_line
		(start 121.646188 -88.594184)
		(end 122.217688 -88.594184)
		(stroke
			(width 0.05715)
			(type default)
		)
		(layer "F.Cu")
	)
	(gr_line
		(start 121.646188 -72.744584)
		(end 122.217688 -72.744584)
		(stroke
			(width 0.05715)
			(type default)
		)
		(layer "F.Cu")
	)
	(gr_line
		(start 121.646188 -71.753984)
		(end 122.217688 -71.753984)
		(stroke
			(width 0.05715)
			(type default)
		)
		(layer "F.Cu")
	)
	(gr_line
		(start 122.504708 -70.268084)
		(end 123.076208 -70.268084)
		(stroke
			(width 0.05715)
			(type default)
		)
		(layer "F.Cu")
	)
	(gr_line
		(start 122.504708 -69.277738)
		(end 123.076208 -69.277738)
		(stroke
			(width 0.05715)
			(type default)
		)
		(layer "F.Cu")
	)
	(gr_line
		(start 125.080268 -65.810384)
		(end 125.651768 -65.810384)
		(stroke
			(width 0.0635)
			(type default)
		)
		(layer "F.Cu")
	)
	(gr_line
		(start 125.938788 -66.305938)
		(end 126.510288 -66.305938)
		(stroke
			(width 0.0635)
			(type default)
		)
		(layer "F.Cu")
	)
	(gr_line
		(start 126.797308 -98.500184)
		(end 127.368808 -98.500184)
		(stroke
			(width 0.05715)
			(type default)
		)
		(layer "F.Cu")
	)
	(gr_line
		(start 127.655828 -100.976684)
		(end 128.227328 -100.976684)
		(stroke
			(width 0.05715)
			(type default)
		)
		(layer "F.Cu")
	)
	(gr_line
		(start 127.655828 -99.986338)
		(end 128.227328 -99.986338)
		(stroke
			(width 0.05715)
			(type default)
		)
		(layer "F.Cu")
	)
	(gr_line
		(start 127.655828 -98.995738)
		(end 128.227328 -98.995738)
		(stroke
			(width 0.05715)
			(type default)
		)
		(layer "F.Cu")
	)
	(gr_line
		(start 127.655828 -98.005138)
		(end 128.227328 -98.005138)
		(stroke
			(width 0.05715)
			(type default)
		)
		(layer "F.Cu")
	)
	(gr_line
		(start 128.514348 -100.481638)
		(end 129.085848 -100.481638)
		(stroke
			(width 0.05715)
			(type default)
		)
		(layer "F.Cu")
	)
	(gr_line
		(start 128.514348 -99.490784)
		(end 129.085848 -99.490784)
		(stroke
			(width 0.05715)
			(type default)
		)
		(layer "F.Cu")
	)
	(gr_line
		(start 128.514348 -78.688438)
		(end 129.085848 -78.688438)
		(stroke
			(width 0.0635)
			(type default)
		)
		(layer "F.Cu")
	)
	(gr_line
		(start 129.372868 -99.986338)
		(end 129.944368 -99.986338)
		(stroke
			(width 0.05715)
			(type default)
		)
		(layer "F.Cu")
	)
	(gr_line
		(start 129.372868 -98.005138)
		(end 129.944368 -98.005138)
		(stroke
			(width 0.05715)
			(type default)
		)
		(layer "F.Cu")
	)
	(gr_line
		(start 129.372868 -97.014538)
		(end 129.944368 -97.014538)
		(stroke
			(width 0.05715)
			(type default)
		)
		(layer "F.Cu")
	)
	(gr_line
		(start 129.372868 -79.183738)
		(end 129.944368 -79.183738)
		(stroke
			(width 0.0635)
			(type default)
		)
		(layer "F.Cu")
	)
	(gr_line
		(start 129.372868 -77.202538)
		(end 129.944368 -77.202538)
		(stroke
			(width 0.0635)
			(type default)
		)
		(layer "F.Cu")
	)
	(gr_line
		(start 129.372868 -76.211938)
		(end 129.944368 -76.211938)
		(stroke
			(width 0.0635)
			(type default)
		)
		(layer "F.Cu")
	)
	(gr_line
		(start 130.231388 -97.509584)
		(end 130.802888 -97.509584)
		(stroke
			(width 0.05715)
			(type default)
		)
		(layer "F.Cu")
	)
	(gr_line
		(start 131.089908 -102.958138)
		(end 131.661408 -102.958138)
		(stroke
			(width 0.05715)
			(type default)
		)
		(layer "F.Cu")
	)
	(gr_line
		(start 131.089908 -101.967538)
		(end 131.661408 -101.967538)
		(stroke
			(width 0.05715)
			(type default)
		)
		(layer "F.Cu")
	)
	(gr_line
		(start 131.089908 -98.005138)
		(end 131.661408 -98.005138)
		(stroke
			(width 0.05715)
			(type default)
		)
		(layer "F.Cu")
	)
	(gr_line
		(start 131.089908 -97.014538)
		(end 131.661408 -97.014538)
		(stroke
			(width 0.05715)
			(type default)
		)
		(layer "F.Cu")
	)
	(gr_line
		(start 131.089908 -96.023938)
		(end 131.661408 -96.023938)
		(stroke
			(width 0.05715)
			(type default)
		)
		(layer "F.Cu")
	)
	(gr_line
		(start 131.089908 -95.033084)
		(end 131.661408 -95.033084)
		(stroke
			(width 0.05715)
			(type default)
		)
		(layer "F.Cu")
	)
	(gr_line
		(start 131.948174 -102.462584)
		(end 132.519674 -102.462584)
		(stroke
			(width 0.05715)
			(type default)
		)
		(layer "F.Cu")
	)
	(gr_line
		(start 131.948174 -96.518984)
		(end 132.519674 -96.518984)
		(stroke
			(width 0.05715)
			(type default)
		)
		(layer "F.Cu")
	)
	(gr_line
		(start 131.948174 -95.528384)
		(end 132.519674 -95.528384)
		(stroke
			(width 0.05715)
			(type default)
		)
		(layer "F.Cu")
	)
	(gr_line
		(start 131.948174 -92.556584)
		(end 132.519674 -92.556584)
		(stroke
			(width 0.05715)
			(type default)
		)
		(layer "F.Cu")
	)
	(gr_line
		(start 132.124704 -96.818196)
		(end 131.518914 -96.766634)
		(stroke
			(width 0.127)
			(type default)
		)
		(layer "F.Cu")
	)
	(gr_line
		(start 132.806694 -102.958138)
		(end 133.378194 -102.958138)
		(stroke
			(width 0.05715)
			(type default)
		)
		(layer "F.Cu")
	)
	(gr_line
		(start 132.806694 -101.967538)
		(end 133.378194 -101.967538)
		(stroke
			(width 0.05715)
			(type default)
		)
		(layer "F.Cu")
	)
	(gr_line
		(start 132.806694 -96.023938)
		(end 133.378194 -96.023938)
		(stroke
			(width 0.05715)
			(type default)
		)
		(layer "F.Cu")
	)
	(gr_line
		(start 132.806694 -95.033084)
		(end 133.378194 -95.033084)
		(stroke
			(width 0.05715)
			(type default)
		)
		(layer "F.Cu")
	)
	(gr_line
		(start 132.806694 -94.042738)
		(end 133.378194 -94.042738)
		(stroke
			(width 0.05715)
			(type default)
		)
		(layer "F.Cu")
	)
	(gr_line
		(start 132.806694 -93.052138)
		(end 133.378194 -93.052138)
		(stroke
			(width 0.05715)
			(type default)
		)
		(layer "F.Cu")
	)
	(gr_line
		(start 132.806694 -92.061538)
		(end 133.378194 -92.061538)
		(stroke
			(width 0.05715)
			(type default)
		)
		(layer "F.Cu")
	)
	(gr_line
		(start 132.806694 -91.070938)
		(end 133.378194 -91.070938)
		(stroke
			(width 0.05715)
			(type default)
		)
		(layer "F.Cu")
	)
	(gr_line
		(start 133.38937 -91.566238)
		(end 133.235954 -91.318334)
		(stroke
			(width 0.127)
			(type default)
		)
		(layer "F.Cu")
	)
	(gr_line
		(start 133.665214 -101.471984)
		(end 134.236714 -101.471984)
		(stroke
			(width 0.05715)
			(type default)
		)
		(layer "F.Cu")
	)
	(gr_line
		(start 133.665214 -100.481638)
		(end 134.236714 -100.481638)
		(stroke
			(width 0.05715)
			(type default)
		)
		(layer "F.Cu")
	)
	(gr_line
		(start 133.665214 -94.538038)
		(end 134.236714 -94.538038)
		(stroke
			(width 0.05715)
			(type default)
		)
		(layer "F.Cu")
	)
	(gr_line
		(start 133.665214 -93.547184)
		(end 134.236714 -93.547184)
		(stroke
			(width 0.05715)
			(type default)
		)
		(layer "F.Cu")
	)
	(gr_line
		(start 133.665214 -91.565984)
		(end 134.236714 -91.565984)
		(stroke
			(width 0.05715)
			(type default)
		)
		(layer "F.Cu")
	)
	(gr_line
		(start 133.665214 -90.575384)
		(end 134.236714 -90.575384)
		(stroke
			(width 0.05715)
			(type default)
		)
		(layer "F.Cu")
	)
	(gr_line
		(start 134.523734 -100.976684)
		(end 135.095234 -100.976684)
		(stroke
			(width 0.05715)
			(type default)
		)
		(layer "F.Cu")
	)
	(gr_line
		(start 134.523734 -99.986338)
		(end 135.095234 -99.986338)
		(stroke
			(width 0.05715)
			(type default)
		)
		(layer "F.Cu")
	)
	(gr_line
		(start 134.523734 -94.042738)
		(end 135.095234 -94.042738)
		(stroke
			(width 0.05715)
			(type default)
		)
		(layer "F.Cu")
	)
	(gr_line
		(start 134.523734 -90.080338)
		(end 135.095234 -90.080338)
		(stroke
			(width 0.05715)
			(type default)
		)
		(layer "F.Cu")
	)
	(gr_line
		(start 134.523734 -89.089738)
		(end 135.095234 -89.089738)
		(stroke
			(width 0.05715)
			(type default)
		)
		(layer "F.Cu")
	)
	(gr_line
		(start 135.382254 -101.471984)
		(end 135.953754 -101.471984)
		(stroke
			(width 0.05715)
			(type default)
		)
		(layer "F.Cu")
	)
	(gr_line
		(start 135.382254 -100.481638)
		(end 135.953754 -100.481638)
		(stroke
			(width 0.05715)
			(type default)
		)
		(layer "F.Cu")
	)
	(gr_line
		(start 135.382254 -99.490784)
		(end 135.953754 -99.490784)
		(stroke
			(width 0.05715)
			(type default)
		)
		(layer "F.Cu")
	)
	(gr_line
		(start 135.382254 -98.500184)
		(end 135.953754 -98.500184)
		(stroke
			(width 0.05715)
			(type default)
		)
		(layer "F.Cu")
	)
	(gr_line
		(start 135.382254 -89.584784)
		(end 135.953754 -89.584784)
		(stroke
			(width 0.05715)
			(type default)
		)
		(layer "F.Cu")
	)
	(gr_line
		(start 136.240774 -98.995738)
		(end 136.812274 -98.995738)
		(stroke
			(width 0.05715)
			(type default)
		)
		(layer "F.Cu")
	)
	(gr_line
		(start 136.240774 -98.005138)
		(end 136.812274 -98.005138)
		(stroke
			(width 0.05715)
			(type default)
		)
		(layer "F.Cu")
	)
	(gr_line
		(start 137.099294 -97.509584)
		(end 137.670794 -97.509584)
		(stroke
			(width 0.05715)
			(type default)
		)
		(layer "F.Cu")
	)
	(gr_line
		(start 137.099294 -96.518984)
		(end 137.670794 -96.518984)
		(stroke
			(width 0.05715)
			(type default)
		)
		(layer "F.Cu")
	)
	(gr_line
		(start 137.957814 -97.014538)
		(end 138.529314 -97.014538)
		(stroke
			(width 0.05715)
			(type default)
		)
		(layer "F.Cu")
	)
	(gr_line
		(start 137.957814 -96.023938)
		(end 138.529314 -96.023938)
		(stroke
			(width 0.05715)
			(type default)
		)
		(layer "F.Cu")
	)
	(gr_line
		(start 137.957814 -95.033084)
		(end 138.529314 -95.033084)
		(stroke
			(width 0.05715)
			(type default)
		)
		(layer "F.Cu")
	)
	(gr_line
		(start 137.957814 -94.042738)
		(end 138.529314 -94.042738)
		(stroke
			(width 0.05715)
			(type default)
		)
		(layer "F.Cu")
	)
	(gr_line
		(start 137.957814 -92.061538)
		(end 138.529314 -92.061538)
		(stroke
			(width 0.05715)
			(type default)
		)
		(layer "F.Cu")
	)
	(gr_line
		(start 138.816334 -97.509584)
		(end 139.387834 -97.509584)
		(stroke
			(width 0.05715)
			(type default)
		)
		(layer "F.Cu")
	)
	(gr_line
		(start 138.816334 -96.518984)
		(end 139.387834 -96.518984)
		(stroke
			(width 0.05715)
			(type default)
		)
		(layer "F.Cu")
	)
	(gr_line
		(start 138.816334 -95.528384)
		(end 139.387834 -95.528384)
		(stroke
			(width 0.05715)
			(type default)
		)
		(layer "F.Cu")
	)
	(gr_line
		(start 138.816334 -94.538038)
		(end 138.816588 -94.537784)
		(stroke
			(width 0.05715)
			(type default)
		)
		(layer "F.Cu")
	)
	(gr_line
		(start 138.816334 -92.556584)
		(end 139.387834 -92.556584)
		(stroke
			(width 0.05715)
			(type default)
		)
		(layer "F.Cu")
	)
	(gr_line
		(start 138.816334 -91.565984)
		(end 139.387834 -91.565984)
		(stroke
			(width 0.05715)
			(type default)
		)
		(layer "F.Cu")
	)
	(gr_line
		(start 138.816334 -90.575384)
		(end 139.387834 -90.575384)
		(stroke
			(width 0.05715)
			(type default)
		)
		(layer "F.Cu")
	)
	(gr_line
		(start 138.816334 -89.584784)
		(end 139.387834 -89.584784)
		(stroke
			(width 0.05715)
			(type default)
		)
		(layer "F.Cu")
	)
	(gr_line
		(start 138.816334 -74.725784)
		(end 139.387834 -74.725784)
		(stroke
			(width 0.0635)
			(type default)
		)
		(layer "F.Cu")
	)
	(gr_line
		(start 138.816334 -73.735184)
		(end 139.387834 -73.735184)
		(stroke
			(width 0.0635)
			(type default)
		)
		(layer "F.Cu")
	)
	(gr_line
		(start 138.816588 -94.537784)
		(end 139.387834 -94.537784)
		(stroke
			(width 0.05715)
			(type default)
		)
		(layer "F.Cu")
	)
	(gr_line
		(start 139.674854 -95.033084)
		(end 140.246354 -95.033084)
		(stroke
			(width 0.05715)
			(type default)
		)
		(layer "F.Cu")
	)
	(gr_line
		(start 139.674854 -91.070938)
		(end 140.246354 -91.070938)
		(stroke
			(width 0.05715)
			(type default)
		)
		(layer "F.Cu")
	)
	(gr_circle
		(center 145.762218 -116.815362)
		(end 146.016218 -116.815362)
		(stroke
			(width 0.2)
			(type default)
		)
		(fill no)
		(layer "F.Cu")
	)
	(gr_circle
		(center 146.205956 -117.270276)
		(end 146.459956 -117.270276)
		(stroke
			(width 0.2)
			(type default)
		)
		(fill no)
		(layer "F.Cu")
	)
	(gr_circle
		(center 147.582128 -118.669308)
		(end 147.836128 -118.669308)
		(stroke
			(width 0.2)
			(type default)
		)
		(fill no)
		(layer "F.Cu")
	)
	(gr_circle
		(center 148.059648 -119.112792)
		(end 148.313648 -119.112792)
		(stroke
			(width 0.2)
			(type default)
		)
		(fill no)
		(layer "F.Cu")
	)
	(gr_line
		(start 156.071824 -62.218824)
		(end 156.43606 -62.218824)
		(stroke
			(width 0.0635)
			(type default)
		)
		(layer "F.Cu")
	)
	(gr_line
		(start 156.44114 -62.218824)
		(end 156.547566 -62.218824)
		(stroke
			(width 0.0635)
			(type default)
		)
		(layer "F.Cu")
	)
	(gr_line
		(start 156.6926 -62.8396)
		(end 156.77769 -62.92469)
		(stroke
			(width 0.0635)
			(type default)
		)
		(layer "F.Cu")
	)
	(gr_line
		(start 156.6926 -62.510162)
		(end 156.6926 -62.8396)
		(stroke
			(width 0.0635)
			(type default)
		)
		(layer "F.Cu")
	)
	(gr_line
		(start 156.6926 -62.4332)
		(end 156.6926 -62.505082)
		(stroke
			(width 0.0635)
			(type default)
		)
		(layer "F.Cu")
	)
	(gr_line
		(start 160.355788 -69.011292)
		(end 160.412684 -68.954396)
		(stroke
			(width 0.0635)
			(type default)
		)
		(layer "F.Cu")
	)
	(gr_line
		(start 160.375092 -69.239892)
		(end 160.412684 -69.277484)
		(stroke
			(width 0.0635)
			(type default)
		)
		(layer "F.Cu")
	)
	(gr_line
		(start 160.414462 -69.279262)
		(end 160.88614 -69.75094)
		(stroke
			(width 0.0635)
			(type default)
		)
		(layer "F.Cu")
	)
	(gr_line
		(start 160.414462 -68.952618)
		(end 160.88614 -68.48094)
		(stroke
			(width 0.0635)
			(type default)
		)
		(layer "F.Cu")
	)
	(gr_line
		(start 160.909 -65.4304)
		(end 160.956244 -65.477644)
		(stroke
			(width 0.0635)
			(type default)
		)
		(layer "F.Cu")
	)
	(gr_line
		(start 160.909 -65.2018)
		(end 160.956244 -65.154556)
		(stroke
			(width 0.0635)
			(type default)
		)
		(layer "F.Cu")
	)
	(gr_line
		(start 160.958022 -65.479422)
		(end 161.2646 -65.786)
		(stroke
			(width 0.0635)
			(type default)
		)
		(layer "F.Cu")
	)
	(gr_line
		(start 160.958022 -65.152778)
		(end 161.2138 -64.897)
		(stroke
			(width 0.0635)
			(type default)
		)
		(layer "F.Cu")
	)
	(gr_line
		(start 161.2138 -64.897)
		(end 161.6456 -64.897)
		(stroke
			(width 0.0635)
			(type default)
		)
		(layer "F.Cu")
	)
	(gr_line
		(start 161.2646 -65.786)
		(end 161.6456 -65.786)
		(stroke
			(width 0.0635)
			(type default)
		)
		(layer "F.Cu")
	)
	(gr_line
		(start 161.6456 -65.786)
		(end 161.671 -65.7606)
		(stroke
			(width 0.0635)
			(type default)
		)
		(layer "F.Cu")
	)
	(gr_line
		(start 161.6456 -64.897)
		(end 161.671 -64.8716)
		(stroke
			(width 0.0635)
			(type default)
		)
		(layer "F.Cu")
	)
	(gr_line
		(start 161.671 -65.7606)
		(end 162.306 -65.7606)
		(stroke
			(width 0.0635)
			(type default)
		)
		(layer "F.Cu")
	)
	(gr_line
		(start 161.671 -64.8716)
		(end 162.306 -64.8716)
		(stroke
			(width 0.0635)
			(type default)
		)
		(layer "F.Cu")
	)
	(gr_line
		(start 161.9504 -77.596746)
		(end 161.9504 -77.978)
		(stroke
			(width 0.05715)
			(type default)
		)
		(layer "F.Cu")
	)
	(gr_line
		(start 161.9504 -77.596746)
		(end 162.070034 -77.477112)
		(stroke
			(width 0.05715)
			(type default)
		)
		(layer "F.Cu")
	)
	(gr_line
		(start 161.9504 -77.120496)
		(end 162.016186 -77.186282)
		(stroke
			(width 0.05715)
			(type default)
		)
		(layer "F.Cu")
	)
	(gr_line
		(start 161.9504 -76.708)
		(end 161.9504 -77.120496)
		(stroke
			(width 0.05715)
			(type default)
		)
		(layer "F.Cu")
	)
	(gr_line
		(start 161.970974 -85.272372)
		(end 161.970974 -85.69706)
		(stroke
			(width 0.05715)
			(type default)
		)
		(layer "F.Cu")
	)
	(gr_line
		(start 161.970974 -85.272372)
		(end 162.102546 -85.1408)
		(stroke
			(width 0.05715)
			(type default)
		)
		(layer "F.Cu")
	)
	(gr_line
		(start 161.970974 -84.74202)
		(end 162.099498 -84.870544)
		(stroke
			(width 0.05715)
			(type default)
		)
		(layer "F.Cu")
	)
	(gr_line
		(start 161.970974 -84.42706)
		(end 161.970974 -84.74202)
		(stroke
			(width 0.05715)
			(type default)
		)
		(layer "F.Cu")
	)
	(gr_line
		(start 162.099498 -84.870544)
		(end 162.5727 -84.870544)
		(stroke
			(width 0.05715)
			(type default)
		)
		(layer "F.Cu")
	)
	(gr_line
		(start 162.102546 -85.1408)
		(end 162.5727 -85.1408)
		(stroke
			(width 0.05715)
			(type default)
		)
		(layer "F.Cu")
	)
	(gr_line
		(start 162.224466 -77.515466)
		(end 162.687 -77.978)
		(stroke
			(width 0.05715)
			(type default)
		)
		(layer "F.Cu")
	)
	(gr_line
		(start 162.224466 -77.170534)
		(end 162.687 -76.708)
		(stroke
			(width 0.05715)
			(type default)
		)
		(layer "F.Cu")
	)
	(gr_line
		(start 162.5727 -85.1408)
		(end 162.687 -85.2551)
		(stroke
			(width 0.05715)
			(type default)
		)
		(layer "F.Cu")
	)
	(gr_line
		(start 162.5727 -84.870544)
		(end 162.687 -84.756244)
		(stroke
			(width 0.05715)
			(type default)
		)
		(layer "F.Cu")
	)
	(gr_line
		(start 162.687 -85.2551)
		(end 162.687 -85.598)
		(stroke
			(width 0.05715)
			(type default)
		)
		(layer "F.Cu")
	)
	(gr_line
		(start 162.687 -84.328)
		(end 162.687 -84.756244)
		(stroke
			(width 0.05715)
			(type default)
		)
		(layer "F.Cu")
	)
	(gr_line
		(start 162.8394 -65.7606)
		(end 163.0426 -65.7606)
		(stroke
			(width 0.0635)
			(type default)
		)
		(layer "F.Cu")
	)
	(gr_line
		(start 162.8394 -63.861696)
		(end 162.8394 -64.8716)
		(stroke
			(width 0.0635)
			(type default)
		)
		(layer "F.Cu")
	)
	(gr_line
		(start 162.8394 -63.861696)
		(end 162.871912 -63.829184)
		(stroke
			(width 0.0635)
			(type default)
		)
		(layer "F.Cu")
	)
	(gr_line
		(start 162.871912 -63.829184)
		(end 163.400232 -63.829184)
		(stroke
			(width 0.0635)
			(type default)
		)
		(layer "F.Cu")
	)
	(gr_line
		(start 163.0426 -65.7606)
		(end 163.3474 -65.4558)
		(stroke
			(width 0.0635)
			(type default)
		)
		(layer "F.Cu")
	)
	(gr_line
		(start 163.3474 -64.4398)
		(end 163.3474 -65.4558)
		(stroke
			(width 0.0635)
			(type default)
		)
		(layer "F.Cu")
	)
	(gr_line
		(start 163.400232 -63.829184)
		(end 164.084 -64.512952)
		(stroke
			(width 0.0635)
			(type default)
		)
		(layer "F.Cu")
	)
	(gr_line
		(start 163.576 -85.24621)
		(end 163.576 -85.598)
		(stroke
			(width 0.05715)
			(type default)
		)
		(layer "F.Cu")
	)
	(gr_line
		(start 163.576 -85.24621)
		(end 163.66109 -85.16112)
		(stroke
			(width 0.05715)
			(type default)
		)
		(layer "F.Cu")
	)
	(gr_line
		(start 163.576 -84.731098)
		(end 163.66109 -84.816188)
		(stroke
			(width 0.05715)
			(type default)
		)
		(layer "F.Cu")
	)
	(gr_line
		(start 163.576 -84.328)
		(end 163.576 -84.731098)
		(stroke
			(width 0.05715)
			(type default)
		)
		(layer "F.Cu")
	)
	(gr_line
		(start 163.576 -77.646276)
		(end 163.576 -77.978)
		(stroke
			(width 0.05715)
			(type default)
		)
		(layer "F.Cu")
	)
	(gr_line
		(start 163.576 -77.646276)
		(end 163.6903 -77.531976)
		(stroke
			(width 0.05715)
			(type default)
		)
		(layer "F.Cu")
	)
	(gr_line
		(start 163.576 -77.054964)
		(end 163.809172 -77.288136)
		(stroke
			(width 0.05715)
			(type default)
		)
		(layer "F.Cu")
	)
	(gr_line
		(start 163.576 -76.708)
		(end 163.576 -77.054964)
		(stroke
			(width 0.05715)
			(type default)
		)
		(layer "F.Cu")
	)
	(gr_line
		(start 164.084 -64.512952)
		(end 164.084 -64.9224)
		(stroke
			(width 0.0635)
			(type default)
		)
		(layer "F.Cu")
	)
	(gr_line
		(start 164.23894 -40.38346)
		(end 164.6174 -40.005)
		(stroke
			(width 0.0635)
			(type default)
		)
		(layer "F.Cu")
	)
	(gr_line
		(start 164.444426 -77.63383)
		(end 164.521896 -77.7113)
		(stroke
			(width 0.05715)
			(type default)
		)
		(layer "F.Cu")
	)
	(gr_line
		(start 164.444426 -77.288898)
		(end 164.52215 -77.211174)
		(stroke
			(width 0.05715)
			(type default)
		)
		(layer "F.Cu")
	)
	(gr_line
		(start 164.49294 -40.64)
		(end 165.2778 -40.64)
		(stroke
			(width 0.0635)
			(type default)
		)
		(layer "F.Cu")
	)
	(gr_line
		(start 164.521896 -77.7113)
		(end 165.054026 -77.7113)
		(stroke
			(width 0.05715)
			(type default)
		)
		(layer "F.Cu")
	)
	(gr_line
		(start 164.52215 -77.211174)
		(end 165.054026 -77.211174)
		(stroke
			(width 0.05715)
			(type default)
		)
		(layer "F.Cu")
	)
	(gr_line
		(start 164.615114 -39.99103)
		(end 164.6174 -40.005)
		(stroke
			(width 0.0635)
			(type default)
		)
		(layer "F.Cu")
	)
	(gr_line
		(start 164.846 -87.757)
		(end 165.192202 -87.757)
		(stroke
			(width 0.05715)
			(type default)
		)
		(layer "F.Cu")
	)
	(gr_line
		(start 164.846 -86.868)
		(end 165.2016 -86.868)
		(stroke
			(width 0.05715)
			(type default)
		)
		(layer "F.Cu")
	)
	(gr_line
		(start 164.895276 -89.206324)
		(end 165.197028 -89.206324)
		(stroke
			(width 0.05715)
			(type default)
		)
		(layer "F.Cu")
	)
	(gr_line
		(start 164.973 -64.9224)
		(end 165.6842 -64.9224)
		(stroke
			(width 0.0635)
			(type default)
		)
		(layer "F.Cu")
	)
	(gr_line
		(start 164.973 -64.3255)
		(end 164.973 -64.9224)
		(stroke
			(width 0.0635)
			(type default)
		)
		(layer "F.Cu")
	)
	(gr_line
		(start 164.973 -64.3255)
		(end 165.0492 -64.2493)
		(stroke
			(width 0.0635)
			(type default)
		)
		(layer "F.Cu")
	)
	(gr_line
		(start 164.976302 -84.135214)
		(end 165.054026 -84.212938)
		(stroke
			(width 0.05715)
			(type default)
		)
		(layer "F.Cu")
	)
	(gr_line
		(start 164.976302 -83.790536)
		(end 165.054026 -83.712812)
		(stroke
			(width 0.05715)
			(type default)
		)
		(layer "F.Cu")
	)
	(gr_line
		(start 165.0492 -64.1604)
		(end 165.0492 -64.2493)
		(stroke
			(width 0.0635)
			(type default)
		)
		(layer "F.Cu")
	)
	(gr_line
		(start 165.192202 -87.757)
		(end 165.320726 -87.885524)
		(stroke
			(width 0.05715)
			(type default)
		)
		(layer "F.Cu")
	)
	(gr_line
		(start 165.197028 -89.206324)
		(end 165.33368 -89.069672)
		(stroke
			(width 0.05715)
			(type default)
		)
		(layer "F.Cu")
	)
	(gr_line
		(start 165.2016 -86.868)
		(end 165.302946 -86.766654)
		(stroke
			(width 0.05715)
			(type default)
		)
		(layer "F.Cu")
	)
	(gr_line
		(start 165.2778 -40.64)
		(end 165.8874 -40.0304)
		(stroke
			(width 0.0635)
			(type default)
		)
		(layer "F.Cu")
	)
	(gr_line
		(start 165.647878 -86.766654)
		(end 165.749224 -86.868)
		(stroke
			(width 0.05715)
			(type default)
		)
		(layer "F.Cu")
	)
	(gr_line
		(start 165.665404 -87.885524)
		(end 165.793928 -87.757)
		(stroke
			(width 0.05715)
			(type default)
		)
		(layer "F.Cu")
	)
	(gr_line
		(start 165.678612 -89.069672)
		(end 165.815264 -89.206324)
		(stroke
			(width 0.05715)
			(type default)
		)
		(layer "F.Cu")
	)
	(gr_line
		(start 165.6842 -64.9224)
		(end 165.763702 -65.001902)
		(stroke
			(width 0.0635)
			(type default)
		)
		(layer "F.Cu")
	)
	(gr_line
		(start 165.749224 -86.868)
		(end 166.116 -86.868)
		(stroke
			(width 0.05715)
			(type default)
		)
		(layer "F.Cu")
	)
	(gr_line
		(start 165.763702 -65.001902)
		(end 166.7383 -65.001902)
		(stroke
			(width 0.0635)
			(type default)
		)
		(layer "F.Cu")
	)
	(gr_line
		(start 165.793928 -87.757)
		(end 166.116 -87.757)
		(stroke
			(width 0.05715)
			(type default)
		)
		(layer "F.Cu")
	)
	(gr_line
		(start 165.815264 -89.206324)
		(end 166.165276 -89.206324)
		(stroke
			(width 0.05715)
			(type default)
		)
		(layer "F.Cu")
	)
	(gr_line
		(start 165.885114 -39.99103)
		(end 165.8874 -40.005)
		(stroke
			(width 0.0635)
			(type default)
		)
		(layer "F.Cu")
	)
	(gr_line
		(start 165.8874 -40.005)
		(end 165.8874 -40.0304)
		(stroke
			(width 0.0635)
			(type default)
		)
		(layer "F.Cu")
	)
	(gr_line
		(start 166.172134 -85.654134)
		(end 166.248334 -85.730334)
		(stroke
			(width 0.05715)
			(type default)
		)
		(layer "F.Cu")
	)
	(gr_line
		(start 166.172134 -85.330792)
		(end 166.172134 -85.654134)
		(stroke
			(width 0.05715)
			(type default)
		)
		(layer "F.Cu")
	)
	(gr_line
		(start 166.593266 -85.730334)
		(end 166.67226 -85.65134)
		(stroke
			(width 0.05715)
			(type default)
		)
		(layer "F.Cu")
	)
	(gr_line
		(start 166.67226 -85.330792)
		(end 166.67226 -85.65134)
		(stroke
			(width 0.05715)
			(type default)
		)
		(layer "F.Cu")
	)
	(gr_line
		(start 167.386 -87.757)
		(end 167.63238 -87.757)
		(stroke
			(width 0.05715)
			(type default)
		)
		(layer "F.Cu")
	)
	(gr_line
		(start 167.386 -86.868)
		(end 167.766746 -86.868)
		(stroke
			(width 0.05715)
			(type default)
		)
		(layer "F.Cu")
	)
	(gr_line
		(start 167.562276 -89.206324)
		(end 167.709596 -89.206324)
		(stroke
			(width 0.05715)
			(type default)
		)
		(layer "F.Cu")
	)
	(gr_line
		(start 167.63238 -87.757)
		(end 167.885364 -88.009984)
		(stroke
			(width 0.05715)
			(type default)
		)
		(layer "F.Cu")
	)
	(gr_line
		(start 167.709596 -89.206324)
		(end 167.905684 -89.010236)
		(stroke
			(width 0.05715)
			(type default)
		)
		(layer "F.Cu")
	)
	(gr_line
		(start 167.766746 -86.868)
		(end 167.85717 -86.777576)
		(stroke
			(width 0.05715)
			(type default)
		)
		(layer "F.Cu")
	)
	(gr_line
		(start 167.7924 -44.45)
		(end 168.425114 -43.817286)
		(stroke
			(width 0.0635)
			(type default)
		)
		(layer "F.Cu")
	)
	(gr_line
		(start 167.7924 -43.18)
		(end 168.4274 -42.545)
		(stroke
			(width 0.0635)
			(type default)
		)
		(layer "F.Cu")
	)
	(gr_line
		(start 168.172638 -85.720682)
		(end 168.254172 -85.802216)
		(stroke
			(width 0.05715)
			(type default)
		)
		(layer "F.Cu")
	)
	(gr_line
		(start 168.172638 -85.330792)
		(end 168.172638 -85.720682)
		(stroke
			(width 0.05715)
			(type default)
		)
		(layer "F.Cu")
	)
	(gr_line
		(start 168.202102 -86.777576)
		(end 168.292526 -86.868)
		(stroke
			(width 0.05715)
			(type default)
		)
		(layer "F.Cu")
	)
	(gr_line
		(start 168.230296 -88.009984)
		(end 168.48328 -87.757)
		(stroke
			(width 0.05715)
			(type default)
		)
		(layer "F.Cu")
	)
	(gr_line
		(start 168.250616 -89.010236)
		(end 168.446704 -89.206324)
		(stroke
			(width 0.05715)
			(type default)
		)
		(layer "F.Cu")
	)
	(gr_line
		(start 168.292526 -86.868)
		(end 168.656 -86.868)
		(stroke
			(width 0.05715)
			(type default)
		)
		(layer "F.Cu")
	)
	(gr_line
		(start 168.425114 -43.80103)
		(end 168.425114 -43.817286)
		(stroke
			(width 0.0635)
			(type default)
		)
		(layer "F.Cu")
	)
	(gr_line
		(start 168.425114 -42.53103)
		(end 168.4274 -42.545)
		(stroke
			(width 0.0635)
			(type default)
		)
		(layer "F.Cu")
	)
	(gr_line
		(start 168.446704 -89.206324)
		(end 168.705276 -89.206324)
		(stroke
			(width 0.05715)
			(type default)
		)
		(layer "F.Cu")
	)
	(gr_line
		(start 168.48328 -87.757)
		(end 168.656 -87.757)
		(stroke
			(width 0.05715)
			(type default)
		)
		(layer "F.Cu")
	)
	(gr_line
		(start 168.599104 -85.802216)
		(end 168.672764 -85.728556)
		(stroke
			(width 0.05715)
			(type default)
		)
		(layer "F.Cu")
	)
	(gr_line
		(start 168.672764 -85.330792)
		(end 168.672764 -85.728556)
		(stroke
			(width 0.05715)
			(type default)
		)
		(layer "F.Cu")
	)
	(gr_line
		(start 169.926 -87.757)
		(end 170.272202 -87.757)
		(stroke
			(width 0.05715)
			(type default)
		)
		(layer "F.Cu")
	)
	(gr_line
		(start 169.926 -86.868)
		(end 170.172634 -86.868)
		(stroke
			(width 0.05715)
			(type default)
		)
		(layer "F.Cu")
	)
	(gr_line
		(start 169.975276 -89.206324)
		(end 170.190668 -89.206324)
		(stroke
			(width 0.05715)
			(type default)
		)
		(layer "F.Cu")
	)
	(gr_line
		(start 170.172634 -86.868)
		(end 170.39082 -86.649814)
		(stroke
			(width 0.05715)
			(type default)
		)
		(layer "F.Cu")
	)
	(gr_line
		(start 170.173142 -85.828632)
		(end 170.25366 -85.90915)
		(stroke
			(width 0.05715)
			(type default)
		)
		(layer "F.Cu")
	)
	(gr_line
		(start 170.173142 -85.330792)
		(end 170.173142 -85.828632)
		(stroke
			(width 0.05715)
			(type default)
		)
		(layer "F.Cu")
	)
	(gr_line
		(start 170.190668 -89.206324)
		(end 170.409616 -88.987376)
		(stroke
			(width 0.05715)
			(type default)
		)
		(layer "F.Cu")
	)
	(gr_line
		(start 170.272202 -87.757)
		(end 170.403012 -87.88781)
		(stroke
			(width 0.05715)
			(type default)
		)
		(layer "F.Cu")
	)
	(gr_line
		(start 170.442636 -86.337902)
		(end 170.442636 -86.344506)
		(stroke
			(width 0.05715)
			(type default)
		)
		(layer "F.Cu")
	)
	(gr_line
		(start 170.551856 -86.099142)
		(end 170.551856 -86.105746)
		(stroke
			(width 0.05715)
			(type default)
		)
		(layer "F.Cu")
	)
	(gr_line
		(start 170.598338 -85.90915)
		(end 170.673268 -85.83422)
		(stroke
			(width 0.05715)
			(type default)
		)
		(layer "F.Cu")
	)
	(gr_line
		(start 170.673268 -85.330792)
		(end 170.673268 -85.83422)
		(stroke
			(width 0.05715)
			(type default)
		)
		(layer "F.Cu")
	)
	(gr_line
		(start 170.735752 -86.649814)
		(end 170.953938 -86.868)
		(stroke
			(width 0.05715)
			(type default)
		)
		(layer "F.Cu")
	)
	(gr_line
		(start 170.74769 -87.88781)
		(end 170.8785 -87.757)
		(stroke
			(width 0.05715)
			(type default)
		)
		(layer "F.Cu")
	)
	(gr_line
		(start 170.754548 -88.987376)
		(end 170.973496 -89.206324)
		(stroke
			(width 0.05715)
			(type default)
		)
		(layer "F.Cu")
	)
	(gr_line
		(start 170.8785 -87.757)
		(end 171.196 -87.757)
		(stroke
			(width 0.05715)
			(type default)
		)
		(layer "F.Cu")
	)
	(gr_line
		(start 170.953938 -86.868)
		(end 171.196 -86.868)
		(stroke
			(width 0.05715)
			(type default)
		)
		(layer "F.Cu")
	)
	(gr_line
		(start 170.973496 -89.206324)
		(end 171.245276 -89.206324)
		(stroke
			(width 0.05715)
			(type default)
		)
		(layer "F.Cu")
	)
	(gr_circle
		(center 172.6946 -32.5628)
		(end 172.9486 -32.5628)
		(stroke
			(width 0.2)
			(type default)
		)
		(fill no)
		(layer "F.Cu")
	)
	(gr_line
		(start 172.7708 -109.7534)
		(end 172.787564 -109.7534)
		(stroke
			(width 0.0635)
			(type default)
		)
		(layer "F.Cu")
	)
	(gr_line
		(start 172.787564 -109.7534)
		(end 173.505114 -110.47095)
		(stroke
			(width 0.0635)
			(type default)
		)
		(layer "F.Cu")
	)
	(gr_line
		(start 172.81398 -108.65358)
		(end 173.36135 -109.20095)
		(stroke
			(width 0.0635)
			(type default)
		)
		(layer "F.Cu")
	)
	(gr_circle
		(center 173.3296 -32.27959)
		(end 173.5836 -32.27959)
		(stroke
			(width 0.2)
			(type default)
		)
		(fill no)
		(layer "F.Cu")
	)
	(gr_line
		(start 173.36135 -109.20095)
		(end 173.505114 -109.20095)
		(stroke
			(width 0.0635)
			(type default)
		)
		(layer "F.Cu")
	)
	(gr_line
		(start 173.791626 -82.212434)
		(end 174.349918 -82.212434)
		(stroke
			(width 0.05715)
			(type default)
		)
		(layer "F.Cu")
	)
	(gr_line
		(start 173.791626 -81.712308)
		(end 174.219616 -81.712308)
		(stroke
			(width 0.05715)
			(type default)
		)
		(layer "F.Cu")
	)
	(gr_line
		(start 173.791626 -79.711804)
		(end 174.323502 -79.711804)
		(stroke
			(width 0.05715)
			(type default)
		)
		(layer "F.Cu")
	)
	(gr_line
		(start 173.791626 -79.211678)
		(end 174.323756 -79.211678)
		(stroke
			(width 0.05715)
			(type default)
		)
		(layer "F.Cu")
	)
	(gr_line
		(start 173.791626 -77.7113)
		(end 174.109126 -77.7113)
		(stroke
			(width 0.05715)
			(type default)
		)
		(layer "F.Cu")
	)
	(gr_line
		(start 173.791626 -77.211174)
		(end 174.118016 -77.211174)
		(stroke
			(width 0.05715)
			(type default)
		)
		(layer "F.Cu")
	)
	(gr_line
		(start 174.109126 -77.7113)
		(end 174.191168 -77.629258)
		(stroke
			(width 0.05715)
			(type default)
		)
		(layer "F.Cu")
	)
	(gr_line
		(start 174.118016 -77.211174)
		(end 174.191168 -77.284326)
		(stroke
			(width 0.05715)
			(type default)
		)
		(layer "F.Cu")
	)
	(gr_line
		(start 174.219616 -81.712308)
		(end 174.362364 -81.855056)
		(stroke
			(width 0.05715)
			(type default)
		)
		(layer "F.Cu")
	)
	(gr_line
		(start 174.323502 -79.711804)
		(end 174.401226 -79.63408)
		(stroke
			(width 0.05715)
			(type default)
		)
		(layer "F.Cu")
	)
	(gr_line
		(start 174.323756 -79.211678)
		(end 174.401226 -79.289148)
		(stroke
			(width 0.05715)
			(type default)
		)
		(layer "F.Cu")
	)
	(gr_line
		(start 174.349918 -82.212434)
		(end 174.362364 -82.199988)
		(stroke
			(width 0.05715)
			(type default)
		)
		(layer "F.Cu")
	)
	(gr_line
		(start 175.103028 -81.904332)
		(end 175.387 -81.62036)
		(stroke
			(width 0.05715)
			(type default)
		)
		(layer "F.Cu")
	)
	(gr_line
		(start 175.20666 -82.148172)
		(end 175.387 -82.328512)
		(stroke
			(width 0.05715)
			(type default)
		)
		(layer "F.Cu")
	)
	(gr_line
		(start 175.305466 -77.132434)
		(end 175.387 -77.213968)
		(stroke
			(width 0.05715)
			(type default)
		)
		(layer "F.Cu")
	)
	(gr_line
		(start 175.305466 -76.787502)
		(end 175.387 -76.705968)
		(stroke
			(width 0.05715)
			(type default)
		)
		(layer "F.Cu")
	)
	(gr_line
		(start 175.387 -82.328512)
		(end 175.387 -82.677)
		(stroke
			(width 0.05715)
			(type default)
		)
		(layer "F.Cu")
	)
	(gr_line
		(start 175.387 -81.407)
		(end 175.387 -81.62036)
		(stroke
			(width 0.05715)
			(type default)
		)
		(layer "F.Cu")
	)
	(gr_line
		(start 175.387 -77.213968)
		(end 175.387 -77.597)
		(stroke
			(width 0.05715)
			(type default)
		)
		(layer "F.Cu")
	)
	(gr_line
		(start 175.387 -76.327)
		(end 175.387 -76.705968)
		(stroke
			(width 0.05715)
			(type default)
		)
		(layer "F.Cu")
	)
	(gr_line
		(start 176.276 -82.267552)
		(end 176.276 -82.677)
		(stroke
			(width 0.05715)
			(type default)
		)
		(layer "F.Cu")
	)
	(gr_line
		(start 176.276 -82.267552)
		(end 176.337976 -82.205576)
		(stroke
			(width 0.05715)
			(type default)
		)
		(layer "F.Cu")
	)
	(gr_line
		(start 176.276 -81.798668)
		(end 176.337976 -81.860644)
		(stroke
			(width 0.05715)
			(type default)
		)
		(layer "F.Cu")
	)
	(gr_line
		(start 176.276 -81.407)
		(end 176.276 -81.798668)
		(stroke
			(width 0.05715)
			(type default)
		)
		(layer "F.Cu")
	)
	(gr_line
		(start 176.276 -77.187552)
		(end 176.276 -77.597)
		(stroke
			(width 0.05715)
			(type default)
		)
		(layer "F.Cu")
	)
	(gr_line
		(start 176.276 -77.187552)
		(end 176.3522 -77.111352)
		(stroke
			(width 0.05715)
			(type default)
		)
		(layer "F.Cu")
	)
	(gr_line
		(start 176.276 -76.690474)
		(end 176.3522 -76.766674)
		(stroke
			(width 0.05715)
			(type default)
		)
		(layer "F.Cu")
	)
	(gr_line
		(start 176.276 -76.327)
		(end 176.276 -76.690474)
		(stroke
			(width 0.05715)
			(type default)
		)
		(layer "F.Cu")
	)
	(gr_line
		(start 176.702466 -79.674466)
		(end 177.165 -80.137)
		(stroke
			(width 0.05715)
			(type default)
		)
		(layer "F.Cu")
	)
	(gr_line
		(start 176.702466 -79.329534)
		(end 177.165 -78.867)
		(stroke
			(width 0.05715)
			(type default)
		)
		(layer "F.Cu")
	)
	(gr_line
		(start 176.797462 -77.128116)
		(end 177.06848 -77.399134)
		(stroke
			(width 0.05715)
			(type default)
		)
		(layer "F.Cu")
	)
	(gr_line
		(start 176.797462 -76.783184)
		(end 177.06848 -76.512166)
		(stroke
			(width 0.05715)
			(type default)
		)
		(layer "F.Cu")
	)
	(gr_line
		(start 177.06848 -77.399134)
		(end 177.06848 -77.558646)
		(stroke
			(width 0.05715)
			(type default)
		)
		(layer "F.Cu")
	)
	(gr_line
		(start 177.06848 -76.288646)
		(end 177.06848 -76.512166)
		(stroke
			(width 0.05715)
			(type default)
		)
		(layer "F.Cu")
	)
	(gr_line
		(start 177.12309 -82.214466)
		(end 177.170334 -82.26171)
		(stroke
			(width 0.05715)
			(type default)
		)
		(layer "F.Cu")
	)
	(gr_line
		(start 177.12309 -81.869534)
		(end 177.170334 -81.82229)
		(stroke
			(width 0.05715)
			(type default)
		)
		(layer "F.Cu")
	)
	(gr_line
		(start 177.170334 -82.26171)
		(end 177.170334 -82.677)
		(stroke
			(width 0.05715)
			(type default)
		)
		(layer "F.Cu")
	)
	(gr_line
		(start 177.170334 -81.407)
		(end 177.170334 -81.82229)
		(stroke
			(width 0.05715)
			(type default)
		)
		(layer "F.Cu")
	)
	(gr_line
		(start 178.054 -80.137)
		(end 178.497484 -79.693516)
		(stroke
			(width 0.05715)
			(type default)
		)
		(layer "F.Cu")
	)
	(gr_line
		(start 178.054 -78.9051)
		(end 178.497484 -79.348584)
		(stroke
			(width 0.05715)
			(type default)
		)
		(layer "F.Cu")
	)
	(gr_line
		(start 178.054 -78.867)
		(end 178.054 -78.9051)
		(stroke
			(width 0.05715)
			(type default)
		)
		(layer "F.Cu")
	)
	(gr_line
		(start 178.839368 -79.731616)
		(end 178.918616 -79.810864)
		(stroke
			(width 0.05715)
			(type default)
		)
		(layer "F.Cu")
	)
	(gr_line
		(start 178.839368 -79.386684)
		(end 178.918616 -79.307436)
		(stroke
			(width 0.05715)
			(type default)
		)
		(layer "F.Cu")
	)
	(gr_line
		(start 178.918616 -79.810864)
		(end 178.918616 -80.23225)
		(stroke
			(width 0.05715)
			(type default)
		)
		(layer "F.Cu")
	)
	(gr_line
		(start 178.918616 -78.96225)
		(end 178.918616 -79.307436)
		(stroke
			(width 0.05715)
			(type default)
		)
		(layer "F.Cu")
	)
	(gr_circle
		(center 184.15 -135.5598)
		(end 184.404 -135.5598)
		(stroke
			(width 0.2)
			(type default)
		)
		(fill no)
		(layer "F.Cu")
	)
	(gr_circle
		(center 184.7342 -135.5598)
		(end 184.9882 -135.5598)
		(stroke
			(width 0.2)
			(type default)
		)
		(fill no)
		(layer "F.Cu")
	)
	(gr_line
		(start 185.677048 -66.240152)
		(end 185.677048 -66.9544)
		(stroke
			(width 0.0635)
			(type default)
		)
		(layer "F.Cu")
	)
	(gr_line
		(start 185.677048 -66.240152)
		(end 186.6265 -65.2907)
		(stroke
			(width 0.0635)
			(type default)
		)
		(layer "F.Cu")
	)
	(gr_line
		(start 186.6265 -65.2907)
		(end 186.8805 -65.2907)
		(stroke
			(width 0.0635)
			(type default)
		)
		(layer "F.Cu")
	)
	(gr_line
		(start 186.8805 -65.2907)
		(end 187.198 -64.9732)
		(stroke
			(width 0.0635)
			(type default)
		)
		(layer "F.Cu")
	)
	(gr_line
		(start 187.1726 -72.049894)
		(end 187.365894 -72.049894)
		(stroke
			(width 0.0635)
			(type default)
		)
		(layer "F.Cu")
	)
	(gr_line
		(start 187.198 -64.77)
		(end 187.198 -64.9732)
		(stroke
			(width 0.0635)
			(type default)
		)
		(layer "F.Cu")
	)
	(gr_line
		(start 187.198 -64.77)
		(end 187.262008 -64.77)
		(stroke
			(width 0.0635)
			(type default)
		)
		(layer "F.Cu")
	)
	(gr_line
		(start 187.262008 -64.77)
		(end 187.668408 -64.3636)
		(stroke
			(width 0.0635)
			(type default)
		)
		(layer "F.Cu")
	)
	(gr_line
		(start 187.365894 -72.049894)
		(end 188.010546 -72.694546)
		(stroke
			(width 0.0635)
			(type default)
		)
		(layer "F.Cu")
	)
	(gr_line
		(start 187.429648 -80.137)
		(end 187.7187 -79.847948)
		(stroke
			(width 0.0635)
			(type default)
		)
		(layer "F.Cu")
	)
	(gr_line
		(start 187.668408 -64.3636)
		(end 187.8076 -64.3636)
		(stroke
			(width 0.0635)
			(type default)
		)
		(layer "F.Cu")
	)
	(gr_line
		(start 187.720478 -79.84617)
		(end 187.7568 -79.809848)
		(stroke
			(width 0.0635)
			(type default)
		)
		(layer "F.Cu")
	)
	(gr_line
		(start 187.833 -62.865)
		(end 187.833 -63.627)
		(stroke
			(width 0.0635)
			(type default)
		)
		(layer "F.Cu")
	)
	(gr_line
		(start 187.9854 -79.788004)
		(end 188.043566 -79.84617)
		(stroke
			(width 0.0635)
			(type default)
		)
		(layer "F.Cu")
	)
	(gr_line
		(start 188.010546 -73.02119)
		(end 188.522356 -73.533)
		(stroke
			(width 0.0635)
			(type default)
		)
		(layer "F.Cu")
	)
	(gr_line
		(start 188.010546 -72.694546)
		(end 188.010546 -73.02119)
		(stroke
			(width 0.0635)
			(type default)
		)
		(layer "F.Cu")
	)
	(gr_line
		(start 188.045344 -79.847948)
		(end 188.344048 -80.146652)
		(stroke
			(width 0.0635)
			(type default)
		)
		(layer "F.Cu")
	)
	(gr_line
		(start 188.522356 -73.533)
		(end 188.73978 -73.533)
		(stroke
			(width 0.0635)
			(type default)
		)
		(layer "F.Cu")
	)
	(gr_line
		(start 188.73978 -73.533)
		(end 189.065408 -73.858628)
		(stroke
			(width 0.0635)
			(type default)
		)
		(layer "F.Cu")
	)
	(gr_line
		(start 189.067186 -73.860406)
		(end 189.128654 -73.921874)
		(stroke
			(width 0.0635)
			(type default)
		)
		(layer "F.Cu")
	)
	(gr_line
		(start 189.357254 -73.893426)
		(end 189.390274 -73.860406)
		(stroke
			(width 0.0635)
			(type default)
		)
		(layer "F.Cu")
	)
	(gr_line
		(start 189.392052 -73.858628)
		(end 189.70498 -73.5457)
		(stroke
			(width 0.0635)
			(type default)
		)
		(layer "F.Cu")
	)
	(gr_line
		(start 190.459614 -149.778212)
		(end 190.713614 -149.778212)
		(stroke
			(width 0.2)
			(type default)
		)
		(layer "F.Cu")
	)
	(gr_line
		(start 190.459614 -140.177012)
		(end 190.713614 -140.177012)
		(stroke
			(width 0.2)
			(type default)
		)
		(layer "F.Cu")
	)
	(gr_line
		(start 190.459614 -130.575812)
		(end 190.754 -130.575812)
		(stroke
			(width 0.2)
			(type default)
		)
		(layer "F.Cu")
	)
	(gr_line
		(start 204.563218 -103.4796)
		(end 204.7621 -103.4796)
		(stroke
			(width 0.0635)
			(type default)
		)
		(layer "F.Cu")
	)
	(gr_line
		(start 204.6224 -102.5906)
		(end 204.8383 -102.5906)
		(stroke
			(width 0.0635)
			(type default)
		)
		(layer "F.Cu")
	)
	(gr_line
		(start 204.7621 -103.4796)
		(end 204.7875 -103.505)
		(stroke
			(width 0.0635)
			(type default)
		)
		(layer "F.Cu")
	)
	(gr_line
		(start 204.7875 -103.505)
		(end 205.486 -103.505)
		(stroke
			(width 0.0635)
			(type default)
		)
		(layer "F.Cu")
	)
	(gr_line
		(start 204.8383 -102.5906)
		(end 204.8637 -102.616)
		(stroke
			(width 0.0635)
			(type default)
		)
		(layer "F.Cu")
	)
	(gr_line
		(start 204.8637 -102.616)
		(end 205.486 -102.616)
		(stroke
			(width 0.0635)
			(type default)
		)
		(layer "F.Cu")
	)
	(gr_line
		(start 205.486 -103.505)
		(end 206.248 -103.505)
		(stroke
			(width 0.0635)
			(type default)
		)
		(layer "F.Cu")
	)
	(gr_line
		(start 205.486 -102.616)
		(end 206.248 -102.616)
		(stroke
			(width 0.0635)
			(type default)
		)
		(layer "F.Cu")
	)
	(gr_line
		(start 205.9178 -50.5714)
		(end 206.629 -50.5714)
		(stroke
			(width 0.0635)
			(type default)
		)
		(layer "F.Cu")
	)
	(gr_line
		(start 205.9178 -49.6824)
		(end 206.6798 -49.6824)
		(stroke
			(width 0.0635)
			(type default)
		)
		(layer "F.Cu")
	)
	(gr_line
		(start 206.629 -50.5714)
		(end 206.6798 -50.5206)
		(stroke
			(width 0.0635)
			(type default)
		)
		(layer "F.Cu")
	)
	(gr_line
		(start 207.137 -103.505)
		(end 207.391 -103.505)
		(stroke
			(width 0.127)
			(type default)
		)
		(layer "F.Cu")
	)
	(gr_line
		(start 207.137 -102.616)
		(end 207.391 -102.616)
		(stroke
			(width 0.127)
			(type default)
		)
		(layer "F.Cu")
	)
	(gr_line
		(start 207.391 -103.505)
		(end 207.564228 -103.331772)
		(stroke
			(width 0.127)
			(type default)
		)
		(layer "F.Cu")
	)
	(gr_line
		(start 207.391 -102.616)
		(end 207.564228 -102.789228)
		(stroke
			(width 0.127)
			(type default)
		)
		(layer "F.Cu")
	)
	(gr_line
		(start 212.667088 -99.42068)
		(end 212.74024 -99.42068)
		(stroke
			(width 0.127)
			(type default)
		)
		(layer "F.Cu")
	)
	(gr_line
		(start 212.74024 -99.42068)
		(end 212.853778 -99.534218)
		(stroke
			(width 0.127)
			(type default)
		)
		(layer "F.Cu")
	)
	(gr_line
		(start 213.396068 -99.534218)
		(end 213.519766 -99.41052)
		(stroke
			(width 0.127)
			(type default)
		)
		(layer "F.Cu")
	)
	(gr_line
		(start 213.519766 -99.41052)
		(end 213.581234 -99.41052)
		(stroke
			(width 0.127)
			(type default)
		)
		(layer "F.Cu")
	)
	(gr_line
		(start 214.122 -63.53302)
		(end 214.117428 -63.825882)
		(stroke
			(width 0.2)
			(type default)
		)
		(layer "F.Cu")
	)
	(gr_line
		(start 232.101898 -69.45884)
		(end 232.749598 -69.45884)
		(stroke
			(width 0.0635)
			(type default)
		)
		(layer "F.Cu")
	)
	(gr_line
		(start 233.036618 -68.963286)
		(end 233.608118 -68.963286)
		(stroke
			(width 0.0635)
			(type default)
		)
		(layer "F.Cu")
	)
	(gr_line
		(start 240.763298 -82.33664)
		(end 241.334798 -82.33664)
		(stroke
			(width 0.0635)
			(type default)
		)
		(layer "F.Cu")
	)
	(gr_line
		(start 240.763298 -81.34604)
		(end 241.334798 -81.34604)
		(stroke
			(width 0.0635)
			(type default)
		)
		(layer "F.Cu")
	)
	(gr_line
		(start 284.929834 -87.603584)
		(end 285.501334 -87.603584)
		(stroke
			(width 0.05715)
			(type default)
		)
		(layer "F.Cu")
	)
	(gr_line
		(start 285.7881 -89.089738)
		(end 286.3596 -89.089738)
		(stroke
			(width 0.05715)
			(type default)
		)
		(layer "F.Cu")
	)
	(gr_line
		(start 285.7881 -88.099138)
		(end 286.3596 -88.099138)
		(stroke
			(width 0.05715)
			(type default)
		)
		(layer "F.Cu")
	)
	(gr_line
		(start 286.64662 -88.594184)
		(end 287.21812 -88.594184)
		(stroke
			(width 0.05715)
			(type default)
		)
		(layer "F.Cu")
	)
	(gr_line
		(start 286.64662 -72.744584)
		(end 287.21812 -72.744584)
		(stroke
			(width 0.05715)
			(type default)
		)
		(layer "F.Cu")
	)
	(gr_line
		(start 286.64662 -71.753984)
		(end 287.21812 -71.753984)
		(stroke
			(width 0.05715)
			(type default)
		)
		(layer "F.Cu")
	)
	(gr_line
		(start 287.50514 -70.268084)
		(end 288.07664 -70.268084)
		(stroke
			(width 0.05715)
			(type default)
		)
		(layer "F.Cu")
	)
	(gr_line
		(start 287.50514 -69.277738)
		(end 288.07664 -69.277738)
		(stroke
			(width 0.05715)
			(type default)
		)
		(layer "F.Cu")
	)
	(gr_line
		(start 290.0807 -65.810384)
		(end 290.6522 -65.810384)
		(stroke
			(width 0.0635)
			(type default)
		)
		(layer "F.Cu")
	)
	(gr_line
		(start 290.93922 -66.305938)
		(end 291.51072 -66.305938)
		(stroke
			(width 0.0635)
			(type default)
		)
		(layer "F.Cu")
	)
	(gr_line
		(start 291.79774 -98.500184)
		(end 292.36924 -98.500184)
		(stroke
			(width 0.05715)
			(type default)
		)
		(layer "F.Cu")
	)
	(gr_line
		(start 292.65626 -100.976684)
		(end 293.22776 -100.976684)
		(stroke
			(width 0.05715)
			(type default)
		)
		(layer "F.Cu")
	)
	(gr_line
		(start 292.65626 -99.986338)
		(end 293.22776 -99.986338)
		(stroke
			(width 0.05715)
			(type default)
		)
		(layer "F.Cu")
	)
	(gr_line
		(start 292.65626 -98.995738)
		(end 293.22776 -98.995738)
		(stroke
			(width 0.05715)
			(type default)
		)
		(layer "F.Cu")
	)
	(gr_line
		(start 292.65626 -98.005138)
		(end 293.22776 -98.005138)
		(stroke
			(width 0.05715)
			(type default)
		)
		(layer "F.Cu")
	)
	(gr_line
		(start 293.51478 -100.481638)
		(end 294.08628 -100.481638)
		(stroke
			(width 0.05715)
			(type default)
		)
		(layer "F.Cu")
	)
	(gr_line
		(start 293.51478 -99.490784)
		(end 294.08628 -99.490784)
		(stroke
			(width 0.05715)
			(type default)
		)
		(layer "F.Cu")
	)
	(gr_line
		(start 293.51478 -78.688438)
		(end 294.08628 -78.688438)
		(stroke
			(width 0.0635)
			(type default)
		)
		(layer "F.Cu")
	)
	(gr_line
		(start 294.3733 -99.986338)
		(end 294.9448 -99.986338)
		(stroke
			(width 0.05715)
			(type default)
		)
		(layer "F.Cu")
	)
	(gr_line
		(start 294.3733 -98.995738)
		(end 294.9448 -98.995738)
		(stroke
			(width 0.05715)
			(type default)
		)
		(layer "F.Cu")
	)
	(gr_line
		(start 294.3733 -98.005138)
		(end 294.9448 -98.005138)
		(stroke
			(width 0.05715)
			(type default)
		)
		(layer "F.Cu")
	)
	(gr_line
		(start 294.3733 -97.014538)
		(end 294.9448 -97.014538)
		(stroke
			(width 0.05715)
			(type default)
		)
		(layer "F.Cu")
	)
	(gr_line
		(start 294.3733 -79.183738)
		(end 294.9448 -79.183738)
		(stroke
			(width 0.0635)
			(type default)
		)
		(layer "F.Cu")
	)
	(gr_line
		(start 294.3733 -77.202538)
		(end 294.9448 -77.202538)
		(stroke
			(width 0.0635)
			(type default)
		)
		(layer "F.Cu")
	)
	(gr_line
		(start 294.3733 -76.211938)
		(end 294.9448 -76.211938)
		(stroke
			(width 0.0635)
			(type default)
		)
		(layer "F.Cu")
	)
	(gr_line
		(start 295.23182 -100.481638)
		(end 295.80332 -100.481638)
		(stroke
			(width 0.05715)
			(type default)
		)
		(layer "F.Cu")
	)
	(gr_line
		(start 295.23182 -99.490784)
		(end 295.80332 -99.490784)
		(stroke
			(width 0.05715)
			(type default)
		)
		(layer "F.Cu")
	)
	(gr_line
		(start 295.23182 -98.500184)
		(end 295.80332 -98.500184)
		(stroke
			(width 0.05715)
			(type default)
		)
		(layer "F.Cu")
	)
	(gr_line
		(start 295.23182 -97.509584)
		(end 295.80332 -97.509584)
		(stroke
			(width 0.05715)
			(type default)
		)
		(layer "F.Cu")
	)
	(gr_line
		(start 296.09034 -102.958138)
		(end 296.66184 -102.958138)
		(stroke
			(width 0.05715)
			(type default)
		)
		(layer "F.Cu")
	)
	(gr_line
		(start 296.09034 -101.967538)
		(end 296.66184 -101.967538)
		(stroke
			(width 0.05715)
			(type default)
		)
		(layer "F.Cu")
	)
	(gr_line
		(start 296.09034 -99.986338)
		(end 296.66184 -99.986338)
		(stroke
			(width 0.05715)
			(type default)
		)
		(layer "F.Cu")
	)
	(gr_line
		(start 296.09034 -98.005138)
		(end 296.66184 -98.005138)
		(stroke
			(width 0.05715)
			(type default)
		)
		(layer "F.Cu")
	)
	(gr_line
		(start 296.09034 -97.014538)
		(end 296.66184 -97.014538)
		(stroke
			(width 0.05715)
			(type default)
		)
		(layer "F.Cu")
	)
	(gr_line
		(start 296.09034 -96.023938)
		(end 296.66184 -96.023938)
		(stroke
			(width 0.05715)
			(type default)
		)
		(layer "F.Cu")
	)
	(gr_line
		(start 296.09034 -95.033084)
		(end 296.66184 -95.033084)
		(stroke
			(width 0.05715)
			(type default)
		)
		(layer "F.Cu")
	)
	(gr_line
		(start 296.948606 -102.462584)
		(end 297.520106 -102.462584)
		(stroke
			(width 0.05715)
			(type default)
		)
		(layer "F.Cu")
	)
	(gr_line
		(start 296.948606 -100.481638)
		(end 297.519852 -100.481638)
		(stroke
			(width 0.05715)
			(type default)
		)
		(layer "F.Cu")
	)
	(gr_line
		(start 296.948606 -99.490784)
		(end 297.520106 -99.490784)
		(stroke
			(width 0.05715)
			(type default)
		)
		(layer "F.Cu")
	)
	(gr_line
		(start 296.948606 -98.500184)
		(end 297.520106 -98.500184)
		(stroke
			(width 0.05715)
			(type default)
		)
		(layer "F.Cu")
	)
	(gr_line
		(start 296.948606 -97.509584)
		(end 297.520106 -97.509584)
		(stroke
			(width 0.05715)
			(type default)
		)
		(layer "F.Cu")
	)
	(gr_line
		(start 296.948606 -96.518984)
		(end 297.520106 -96.518984)
		(stroke
			(width 0.05715)
			(type default)
		)
		(layer "F.Cu")
	)
	(gr_line
		(start 296.948606 -95.528384)
		(end 297.520106 -95.528384)
		(stroke
			(width 0.05715)
			(type default)
		)
		(layer "F.Cu")
	)
	(gr_line
		(start 296.948606 -92.556584)
		(end 297.520106 -92.556584)
		(stroke
			(width 0.05715)
			(type default)
		)
		(layer "F.Cu")
	)
	(gr_line
		(start 297.519852 -100.481638)
		(end 297.520106 -100.481384)
		(stroke
			(width 0.05715)
			(type default)
		)
		(layer "F.Cu")
	)
	(gr_line
		(start 297.807126 -102.958138)
		(end 298.378626 -102.958138)
		(stroke
			(width 0.05715)
			(type default)
		)
		(layer "F.Cu")
	)
	(gr_line
		(start 297.807126 -101.967538)
		(end 298.378626 -101.967538)
		(stroke
			(width 0.05715)
			(type default)
		)
		(layer "F.Cu")
	)
	(gr_line
		(start 297.807126 -98.995738)
		(end 298.378626 -98.995738)
		(stroke
			(width 0.05715)
			(type default)
		)
		(layer "F.Cu")
	)
	(gr_line
		(start 297.807126 -98.005138)
		(end 298.378626 -98.005138)
		(stroke
			(width 0.05715)
			(type default)
		)
		(layer "F.Cu")
	)
	(gr_line
		(start 297.807126 -96.023938)
		(end 298.378626 -96.023938)
		(stroke
			(width 0.05715)
			(type default)
		)
		(layer "F.Cu")
	)
	(gr_line
		(start 297.807126 -95.033084)
		(end 298.378626 -95.033084)
		(stroke
			(width 0.05715)
			(type default)
		)
		(layer "F.Cu")
	)
	(gr_line
		(start 297.807126 -94.042738)
		(end 298.378626 -94.042738)
		(stroke
			(width 0.05715)
			(type default)
		)
		(layer "F.Cu")
	)
	(gr_line
		(start 297.807126 -93.052138)
		(end 298.378626 -93.052138)
		(stroke
			(width 0.05715)
			(type default)
		)
		(layer "F.Cu")
	)
	(gr_line
		(start 297.807126 -92.061538)
		(end 298.378626 -92.061538)
		(stroke
			(width 0.05715)
			(type default)
		)
		(layer "F.Cu")
	)
	(gr_line
		(start 297.807126 -91.070938)
		(end 298.378626 -91.070938)
		(stroke
			(width 0.05715)
			(type default)
		)
		(layer "F.Cu")
	)
	(gr_line
		(start 297.807126 -88.099138)
		(end 298.378626 -88.099138)
		(stroke
			(width 0.05715)
			(type default)
		)
		(layer "F.Cu")
	)
	(gr_line
		(start 298.665646 -101.471984)
		(end 299.237146 -101.471984)
		(stroke
			(width 0.05715)
			(type default)
		)
		(layer "F.Cu")
	)
	(gr_line
		(start 298.665646 -100.481638)
		(end 298.6659 -100.481384)
		(stroke
			(width 0.05715)
			(type default)
		)
		(layer "F.Cu")
	)
	(gr_line
		(start 298.665646 -98.500184)
		(end 299.237146 -98.500184)
		(stroke
			(width 0.05715)
			(type default)
		)
		(layer "F.Cu")
	)
	(gr_line
		(start 298.665646 -97.509584)
		(end 299.237146 -97.509584)
		(stroke
			(width 0.05715)
			(type default)
		)
		(layer "F.Cu")
	)
	(gr_line
		(start 298.665646 -96.518984)
		(end 299.237146 -96.518984)
		(stroke
			(width 0.05715)
			(type default)
		)
		(layer "F.Cu")
	)
	(gr_line
		(start 298.665646 -95.528384)
		(end 299.237146 -95.528384)
		(stroke
			(width 0.05715)
			(type default)
		)
		(layer "F.Cu")
	)
	(gr_line
		(start 298.665646 -94.538038)
		(end 299.237146 -94.538038)
		(stroke
			(width 0.05715)
			(type default)
		)
		(layer "F.Cu")
	)
	(gr_line
		(start 298.665646 -93.547184)
		(end 299.237146 -93.547184)
		(stroke
			(width 0.05715)
			(type default)
		)
		(layer "F.Cu")
	)
	(gr_line
		(start 298.665646 -91.565984)
		(end 299.237146 -91.565984)
		(stroke
			(width 0.05715)
			(type default)
		)
		(layer "F.Cu")
	)
	(gr_line
		(start 298.665646 -90.575384)
		(end 299.237146 -90.575384)
		(stroke
			(width 0.05715)
			(type default)
		)
		(layer "F.Cu")
	)
	(gr_line
		(start 298.665646 -89.584784)
		(end 299.237146 -89.584784)
		(stroke
			(width 0.05715)
			(type default)
		)
		(layer "F.Cu")
	)
	(gr_line
		(start 298.665646 -88.594184)
		(end 299.237146 -88.594184)
		(stroke
			(width 0.05715)
			(type default)
		)
		(layer "F.Cu")
	)
	(gr_line
		(start 298.665646 -87.603584)
		(end 299.237146 -87.603584)
		(stroke
			(width 0.05715)
			(type default)
		)
		(layer "F.Cu")
	)
	(gr_line
		(start 298.665646 -86.612984)
		(end 299.237146 -86.612984)
		(stroke
			(width 0.05715)
			(type default)
		)
		(layer "F.Cu")
	)
	(gr_line
		(start 298.6659 -100.481384)
		(end 299.237146 -100.481384)
		(stroke
			(width 0.05715)
			(type default)
		)
		(layer "F.Cu")
	)
	(gr_line
		(start 299.524166 -100.976684)
		(end 300.095666 -100.976684)
		(stroke
			(width 0.05715)
			(type default)
		)
		(layer "F.Cu")
	)
	(gr_line
		(start 299.524166 -99.986338)
		(end 300.095666 -99.986338)
		(stroke
			(width 0.05715)
			(type default)
		)
		(layer "F.Cu")
	)
	(gr_line
		(start 299.524166 -97.014538)
		(end 300.095666 -97.014538)
		(stroke
			(width 0.05715)
			(type default)
		)
		(layer "F.Cu")
	)
	(gr_line
		(start 299.524166 -96.023938)
		(end 300.095666 -96.023938)
		(stroke
			(width 0.05715)
			(type default)
		)
		(layer "F.Cu")
	)
	(gr_line
		(start 299.524166 -94.042738)
		(end 300.095666 -94.042738)
		(stroke
			(width 0.05715)
			(type default)
		)
		(layer "F.Cu")
	)
	(gr_line
		(start 299.524166 -93.052138)
		(end 300.095666 -93.052138)
		(stroke
			(width 0.05715)
			(type default)
		)
		(layer "F.Cu")
	)
	(gr_line
		(start 299.524166 -92.061538)
		(end 300.095666 -92.061538)
		(stroke
			(width 0.05715)
			(type default)
		)
		(layer "F.Cu")
	)
	(gr_line
		(start 299.524166 -91.070938)
		(end 300.095666 -91.070938)
		(stroke
			(width 0.05715)
			(type default)
		)
		(layer "F.Cu")
	)
	(gr_line
		(start 299.524166 -90.080338)
		(end 300.095666 -90.080338)
		(stroke
			(width 0.05715)
			(type default)
		)
		(layer "F.Cu")
	)
	(gr_line
		(start 299.524166 -89.089738)
		(end 300.095666 -89.089738)
		(stroke
			(width 0.05715)
			(type default)
		)
		(layer "F.Cu")
	)
	(gr_line
		(start 299.524166 -87.108538)
		(end 300.095666 -87.108538)
		(stroke
			(width 0.05715)
			(type default)
		)
		(layer "F.Cu")
	)
	(gr_line
		(start 299.524166 -86.117938)
		(end 300.095666 -86.117938)
		(stroke
			(width 0.05715)
			(type default)
		)
		(layer "F.Cu")
	)
	(gr_line
		(start 299.524166 -75.221338)
		(end 300.095666 -75.221338)
		(stroke
			(width 0.05715)
			(type default)
		)
		(layer "F.Cu")
	)
	(gr_line
		(start 300.382686 -102.462584)
		(end 300.66996 -102.296976)
		(stroke
			(width 0.04445)
			(type default)
		)
		(layer "F.Cu")
	)
	(gr_line
		(start 300.382686 -101.471984)
		(end 300.954186 -101.471984)
		(stroke
			(width 0.05715)
			(type default)
		)
		(layer "F.Cu")
	)
	(gr_line
		(start 300.382686 -100.481638)
		(end 300.38294 -100.481384)
		(stroke
			(width 0.05715)
			(type default)
		)
		(layer "F.Cu")
	)
	(gr_line
		(start 300.382686 -99.490784)
		(end 300.954186 -99.490784)
		(stroke
			(width 0.05715)
			(type default)
		)
		(layer "F.Cu")
	)
	(gr_line
		(start 300.382686 -98.500184)
		(end 300.954186 -98.500184)
		(stroke
			(width 0.05715)
			(type default)
		)
		(layer "F.Cu")
	)
	(gr_line
		(start 300.382686 -96.518984)
		(end 300.954186 -96.518984)
		(stroke
			(width 0.05715)
			(type default)
		)
		(layer "F.Cu")
	)
	(gr_line
		(start 300.382686 -95.528384)
		(end 300.954186 -95.528384)
		(stroke
			(width 0.05715)
			(type default)
		)
		(layer "F.Cu")
	)
	(gr_line
		(start 300.382686 -94.538038)
		(end 300.954186 -94.538038)
		(stroke
			(width 0.05715)
			(type default)
		)
		(layer "F.Cu")
	)
	(gr_line
		(start 300.382686 -93.547184)
		(end 300.954186 -93.547184)
		(stroke
			(width 0.05715)
			(type default)
		)
		(layer "F.Cu")
	)
	(gr_line
		(start 300.382686 -92.556584)
		(end 300.954186 -92.556584)
		(stroke
			(width 0.05715)
			(type default)
		)
		(layer "F.Cu")
	)
	(gr_line
		(start 300.382686 -91.565984)
		(end 300.954186 -91.565984)
		(stroke
			(width 0.05715)
			(type default)
		)
		(layer "F.Cu")
	)
	(gr_line
		(start 300.382686 -89.584784)
		(end 300.954186 -89.584784)
		(stroke
			(width 0.05715)
			(type default)
		)
		(layer "F.Cu")
	)
	(gr_line
		(start 300.382686 -88.594184)
		(end 300.954186 -88.594184)
		(stroke
			(width 0.05715)
			(type default)
		)
		(layer "F.Cu")
	)
	(gr_line
		(start 300.382686 -87.603584)
		(end 300.954186 -87.603584)
		(stroke
			(width 0.05715)
			(type default)
		)
		(layer "F.Cu")
	)
	(gr_line
		(start 300.382686 -86.612984)
		(end 300.954186 -86.612984)
		(stroke
			(width 0.05715)
			(type default)
		)
		(layer "F.Cu")
	)
	(gr_line
		(start 300.382686 -85.622384)
		(end 300.954186 -85.622384)
		(stroke
			(width 0.05715)
			(type default)
		)
		(layer "F.Cu")
	)
	(gr_line
		(start 300.382686 -80.669384)
		(end 300.954186 -80.669384)
		(stroke
			(width 0.05715)
			(type default)
		)
		(layer "F.Cu")
	)
	(gr_line
		(start 300.382686 -79.678784)
		(end 300.954186 -79.678784)
		(stroke
			(width 0.05715)
			(type default)
		)
		(layer "F.Cu")
	)
	(gr_line
		(start 300.382686 -77.697584)
		(end 300.954186 -77.697584)
		(stroke
			(width 0.05715)
			(type default)
		)
		(layer "F.Cu")
	)
	(gr_line
		(start 300.382686 -75.716384)
		(end 300.954186 -75.716384)
		(stroke
			(width 0.05715)
			(type default)
		)
		(layer "F.Cu")
	)
	(gr_line
		(start 300.38294 -100.481384)
		(end 300.954186 -100.481384)
		(stroke
			(width 0.05715)
			(type default)
		)
		(layer "F.Cu")
	)
	(gr_line
		(start 300.650402 -103.70185)
		(end 300.652942 -103.707438)
		(stroke
			(width 0.04445)
			(type default)
		)
		(layer "F.Cu")
	)
	(gr_line
		(start 300.66996 -102.296976)
		(end 300.75505 -102.319836)
		(stroke
			(width 0.04445)
			(type default)
		)
		(layer "F.Cu")
	)
	(gr_line
		(start 300.76394 -103.97617)
		(end 300.766734 -103.982774)
		(stroke
			(width 0.04445)
			(type default)
		)
		(layer "F.Cu")
	)
	(gr_line
		(start 300.92777 -102.230682)
		(end 300.953932 -102.133146)
		(stroke
			(width 0.04445)
			(type default)
		)
		(layer "F.Cu")
	)
	(gr_line
		(start 300.953932 -102.133146)
		(end 301.241206 -101.967538)
		(stroke
			(width 0.04445)
			(type default)
		)
		(layer "F.Cu")
	)
	(gr_line
		(start 301.241206 -100.976684)
		(end 301.52848 -101.142292)
		(stroke
			(width 0.04445)
			(type default)
		)
		(layer "F.Cu")
	)
	(gr_line
		(start 301.241206 -98.995738)
		(end 301.812706 -98.995738)
		(stroke
			(width 0.05715)
			(type default)
		)
		(layer "F.Cu")
	)
	(gr_line
		(start 301.241206 -98.005138)
		(end 301.812706 -98.005138)
		(stroke
			(width 0.05715)
			(type default)
		)
		(layer "F.Cu")
	)
	(gr_line
		(start 301.241206 -95.033084)
		(end 301.812706 -95.033084)
		(stroke
			(width 0.05715)
			(type default)
		)
		(layer "F.Cu")
	)
	(gr_line
		(start 301.241206 -92.061538)
		(end 301.812706 -92.061538)
		(stroke
			(width 0.05715)
			(type default)
		)
		(layer "F.Cu")
	)
	(gr_line
		(start 301.241206 -91.070938)
		(end 301.812706 -91.070938)
		(stroke
			(width 0.05715)
			(type default)
		)
		(layer "F.Cu")
	)
	(gr_line
		(start 301.241206 -90.080338)
		(end 301.812706 -90.080338)
		(stroke
			(width 0.05715)
			(type default)
		)
		(layer "F.Cu")
	)
	(gr_line
		(start 301.241206 -89.089738)
		(end 301.812706 -89.089738)
		(stroke
			(width 0.05715)
			(type default)
		)
		(layer "F.Cu")
	)
	(gr_line
		(start 301.241206 -88.099138)
		(end 301.812706 -88.099138)
		(stroke
			(width 0.05715)
			(type default)
		)
		(layer "F.Cu")
	)
	(gr_line
		(start 301.241206 -87.108538)
		(end 301.812706 -87.108538)
		(stroke
			(width 0.05715)
			(type default)
		)
		(layer "F.Cu")
	)
	(gr_line
		(start 301.241206 -84.136738)
		(end 301.812706 -84.136738)
		(stroke
			(width 0.05715)
			(type default)
		)
		(layer "F.Cu")
	)
	(gr_line
		(start 301.241206 -83.146138)
		(end 301.812706 -83.146138)
		(stroke
			(width 0.05715)
			(type default)
		)
		(layer "F.Cu")
	)
	(gr_line
		(start 301.241206 -82.155284)
		(end 301.812706 -82.155284)
		(stroke
			(width 0.05715)
			(type default)
		)
		(layer "F.Cu")
	)
	(gr_line
		(start 301.241206 -80.174338)
		(end 301.812706 -80.174338)
		(stroke
			(width 0.05715)
			(type default)
		)
		(layer "F.Cu")
	)
	(gr_line
		(start 301.241206 -78.193138)
		(end 301.812706 -78.193138)
		(stroke
			(width 0.05715)
			(type default)
		)
		(layer "F.Cu")
	)
	(gr_line
		(start 301.241206 -77.202538)
		(end 301.812706 -77.202538)
		(stroke
			(width 0.05715)
			(type default)
		)
		(layer "F.Cu")
	)
	(gr_line
		(start 301.241206 -76.211938)
		(end 301.812706 -76.211938)
		(stroke
			(width 0.05715)
			(type default)
		)
		(layer "F.Cu")
	)
	(gr_line
		(start 301.241206 -75.221338)
		(end 301.812706 -75.221338)
		(stroke
			(width 0.05715)
			(type default)
		)
		(layer "F.Cu")
	)
	(gr_line
		(start 301.52848 -101.142292)
		(end 301.554642 -101.240082)
		(stroke
			(width 0.04445)
			(type default)
		)
		(layer "F.Cu")
	)
	(gr_line
		(start 301.669958 -103.535734)
		(end 301.672498 -103.541322)
		(stroke
			(width 0.04445)
			(type default)
		)
		(layer "F.Cu")
	)
	(gr_line
		(start 301.727362 -101.329236)
		(end 301.812452 -101.306376)
		(stroke
			(width 0.04445)
			(type default)
		)
		(layer "F.Cu")
	)
	(gr_line
		(start 301.803816 -103.859076)
		(end 301.80661 -103.86568)
		(stroke
			(width 0.04445)
			(type default)
		)
		(layer "F.Cu")
	)
	(gr_line
		(start 301.812452 -101.306376)
		(end 302.099726 -101.471984)
		(stroke
			(width 0.04445)
			(type default)
		)
		(layer "F.Cu")
	)
	(gr_line
		(start 301.850552 -102.832154)
		(end 301.860458 -102.849426)
		(stroke
			(width 0.04445)
			(type default)
		)
		(layer "F.Cu")
	)
	(gr_line
		(start 302.099726 -100.481638)
		(end 302.387 -100.31603)
		(stroke
			(width 0.04445)
			(type default)
		)
		(layer "F.Cu")
	)
	(gr_line
		(start 302.099726 -99.490784)
		(end 302.184308 -99.19462)
		(stroke
			(width 0.04445)
			(type default)
		)
		(layer "F.Cu")
	)
	(gr_line
		(start 302.099726 -98.500184)
		(end 302.56226 -99.122992)
		(stroke
			(width 0.04445)
			(type default)
		)
		(layer "F.Cu")
	)
	(gr_line
		(start 302.099726 -97.509584)
		(end 302.671226 -97.509584)
		(stroke
			(width 0.05715)
			(type default)
		)
		(layer "F.Cu")
	)
	(gr_line
		(start 302.099726 -96.518984)
		(end 302.671226 -96.518984)
		(stroke
			(width 0.05715)
			(type default)
		)
		(layer "F.Cu")
	)
	(gr_line
		(start 302.099726 -90.575384)
		(end 302.671226 -90.575384)
		(stroke
			(width 0.05715)
			(type default)
		)
		(layer "F.Cu")
	)
	(gr_line
		(start 302.099726 -87.603584)
		(end 302.671226 -87.603584)
		(stroke
			(width 0.05715)
			(type default)
		)
		(layer "F.Cu")
	)
	(gr_line
		(start 302.099726 -86.612984)
		(end 302.671226 -86.612984)
		(stroke
			(width 0.05715)
			(type default)
		)
		(layer "F.Cu")
	)
	(gr_line
		(start 302.099726 -85.622384)
		(end 302.671226 -85.622384)
		(stroke
			(width 0.05715)
			(type default)
		)
		(layer "F.Cu")
	)
	(gr_line
		(start 302.099726 -84.631784)
		(end 302.671226 -84.631784)
		(stroke
			(width 0.05715)
			(type default)
		)
		(layer "F.Cu")
	)
	(gr_line
		(start 302.099726 -83.641184)
		(end 302.671226 -83.641184)
		(stroke
			(width 0.05715)
			(type default)
		)
		(layer "F.Cu")
	)
	(gr_line
		(start 302.099726 -82.650584)
		(end 302.671226 -82.650584)
		(stroke
			(width 0.05715)
			(type default)
		)
		(layer "F.Cu")
	)
	(gr_line
		(start 302.099726 -80.669384)
		(end 302.671226 -80.669384)
		(stroke
			(width 0.05715)
			(type default)
		)
		(layer "F.Cu")
	)
	(gr_line
		(start 302.099726 -79.678784)
		(end 302.671226 -79.678784)
		(stroke
			(width 0.05715)
			(type default)
		)
		(layer "F.Cu")
	)
	(gr_line
		(start 302.099726 -78.688438)
		(end 302.671226 -78.688438)
		(stroke
			(width 0.05715)
			(type default)
		)
		(layer "F.Cu")
	)
	(gr_line
		(start 302.099726 -77.697584)
		(end 302.671226 -77.697584)
		(stroke
			(width 0.05715)
			(type default)
		)
		(layer "F.Cu")
	)
	(gr_line
		(start 302.099726 -76.706984)
		(end 302.671226 -76.706984)
		(stroke
			(width 0.05715)
			(type default)
		)
		(layer "F.Cu")
	)
	(gr_line
		(start 302.184308 -99.19462)
		(end 302.186594 -99.193858)
		(stroke
			(width 0.04445)
			(type default)
		)
		(layer "F.Cu")
	)
	(gr_line
		(start 302.387 -100.31603)
		(end 302.47209 -100.33889)
		(stroke
			(width 0.04445)
			(type default)
		)
		(layer "F.Cu")
	)
	(gr_line
		(start 302.388778 -102.877112)
		(end 302.392588 -102.86873)
		(stroke
			(width 0.04445)
			(type default)
		)
		(layer "F.Cu")
	)
	(gr_arc
		(start 302.446436 -99.290886)
		(mid 302.333948 -99.195668)
		(end 302.186594 -99.193858)
		(stroke
			(width 0.04445)
			(type default)
		)
		(layer "F.Cu")
	)
	(gr_line
		(start 302.51273 -102.345236)
		(end 302.51273 -102.350062)
		(stroke
			(width 0.04445)
			(type default)
		)
		(layer "F.Cu")
	)
	(gr_arc
		(start 302.611536 -99.195636)
		(mid 302.588254 -99.158394)
		(end 302.56226 -99.122992)
		(stroke
			(width 0.04445)
			(type default)
		)
		(layer "F.Cu")
	)
	(gr_line
		(start 302.64481 -100.24999)
		(end 302.670972 -100.151946)
		(stroke
			(width 0.04445)
			(type default)
		)
		(layer "F.Cu")
	)
	(gr_line
		(start 302.670464 -102.238302)
		(end 302.670718 -102.238302)
		(stroke
			(width 0.04445)
			(type default)
		)
		(layer "F.Cu")
	)
	(gr_line
		(start 302.670972 -100.151946)
		(end 302.958246 -99.986338)
		(stroke
			(width 0.04445)
			(type default)
		)
		(layer "F.Cu")
	)
	(gr_line
		(start 302.958246 -98.995738)
		(end 303.24552 -99.161346)
		(stroke
			(width 0.04445)
			(type default)
		)
		(layer "F.Cu")
	)
	(gr_line
		(start 302.958246 -97.014538)
		(end 303.529746 -97.014538)
		(stroke
			(width 0.05715)
			(type default)
		)
		(layer "F.Cu")
	)
	(gr_line
		(start 302.958246 -96.023938)
		(end 303.529746 -96.023938)
		(stroke
			(width 0.05715)
			(type default)
		)
		(layer "F.Cu")
	)
	(gr_line
		(start 302.958246 -95.033084)
		(end 303.529746 -95.033084)
		(stroke
			(width 0.05715)
			(type default)
		)
		(layer "F.Cu")
	)
	(gr_line
		(start 302.958246 -94.042738)
		(end 303.529746 -94.042738)
		(stroke
			(width 0.05715)
			(type default)
		)
		(layer "F.Cu")
	)
	(gr_line
		(start 302.958246 -92.061538)
		(end 303.529746 -92.061538)
		(stroke
			(width 0.05715)
			(type default)
		)
		(layer "F.Cu")
	)
	(gr_line
		(start 302.958246 -86.117938)
		(end 303.529746 -86.117938)
		(stroke
			(width 0.05715)
			(type default)
		)
		(layer "F.Cu")
	)
	(gr_line
		(start 302.958246 -83.146138)
		(end 303.529746 -83.146138)
		(stroke
			(width 0.05715)
			(type default)
		)
		(layer "F.Cu")
	)
	(gr_line
		(start 302.958246 -79.183738)
		(end 303.529746 -79.183738)
		(stroke
			(width 0.05715)
			(type default)
		)
		(layer "F.Cu")
	)
	(gr_line
		(start 303.028604 -104.436418)
		(end 303.06264 -104.470454)
		(stroke
			(width 0.04445)
			(type default)
		)
		(layer "F.Cu")
	)
	(gr_line
		(start 303.104042 -104.78135)
		(end 303.260252 -104.93756)
		(stroke
			(width 0.04445)
			(type default)
		)
		(layer "F.Cu")
	)
	(gr_line
		(start 303.201578 -106.315002)
		(end 303.243234 -106.356658)
		(stroke
			(width 0.04445)
			(type default)
		)
		(layer "F.Cu")
	)
	(gr_line
		(start 303.203356 -106.04373)
		(end 303.325784 -106.04373)
		(stroke
			(width 0.04445)
			(type default)
		)
		(layer "F.Cu")
	)
	(gr_line
		(start 303.220628 -104.624886)
		(end 303.342802 -104.624886)
		(stroke
			(width 0.04445)
			(type default)
		)
		(layer "F.Cu")
	)
	(gr_line
		(start 303.24552 -99.161346)
		(end 303.343564 -99.13493)
		(stroke
			(width 0.04445)
			(type default)
		)
		(layer "F.Cu")
	)
	(gr_line
		(start 303.2506 -101.270308)
		(end 303.261014 -101.252274)
		(stroke
			(width 0.04445)
			(type default)
		)
		(layer "F.Cu")
	)
	(gr_line
		(start 303.304956 -100.186236)
		(end 303.309782 -100.1776)
		(stroke
			(width 0.04445)
			(type default)
		)
		(layer "F.Cu")
	)
	(gr_line
		(start 303.325784 -106.04373)
		(end 303.514506 -106.232452)
		(stroke
			(width 0.04445)
			(type default)
		)
		(layer "F.Cu")
	)
	(gr_line
		(start 303.342802 -104.624886)
		(end 303.531524 -104.813608)
		(stroke
			(width 0.04445)
			(type default)
		)
		(layer "F.Cu")
	)
	(gr_line
		(start 303.506886 -99.240086)
		(end 303.529492 -99.325176)
		(stroke
			(width 0.04445)
			(type default)
		)
		(layer "F.Cu")
	)
	(gr_line
		(start 303.514506 -106.232452)
		(end 303.514506 -106.35488)
		(stroke
			(width 0.04445)
			(type default)
		)
		(layer "F.Cu")
	)
	(gr_line
		(start 303.529492 -99.325176)
		(end 303.816766 -99.490784)
		(stroke
			(width 0.04445)
			(type default)
		)
		(layer "F.Cu")
	)
	(gr_line
		(start 303.531524 -104.813608)
		(end 303.531524 -104.935782)
		(stroke
			(width 0.04445)
			(type default)
		)
		(layer "F.Cu")
	)
	(gr_line
		(start 303.55286 -104.191054)
		(end 303.567338 -104.191054)
		(stroke
			(width 0.04445)
			(type default)
		)
		(layer "F.Cu")
	)
	(gr_line
		(start 303.568862 -106.682286)
		(end 303.568862 -106.717338)
		(stroke
			(width 0.04445)
			(type default)
		)
		(layer "F.Cu")
	)
	(gr_line
		(start 303.606962 -105.28427)
		(end 303.763172 -105.44048)
		(stroke
			(width 0.04445)
			(type default)
		)
		(layer "F.Cu")
	)
	(gr_line
		(start 303.702974 -106.54665)
		(end 303.73955 -106.54665)
		(stroke
			(width 0.04445)
			(type default)
		)
		(layer "F.Cu")
	)
	(gr_line
		(start 303.723548 -105.127806)
		(end 303.845722 -105.127806)
		(stroke
			(width 0.04445)
			(type default)
		)
		(layer "F.Cu")
	)
	(gr_line
		(start 303.798986 -98.900234)
		(end 303.834546 -98.900234)
		(stroke
			(width 0.04445)
			(type default)
		)
		(layer "F.Cu")
	)
	(gr_arc
		(start 303.816766 -98.500184)
		(mid 304.234433 -98.571734)
		(end 304.657506 -98.595688)
		(stroke
			(width 0.04445)
			(type default)
		)
		(layer "F.Cu")
	)
	(gr_line
		(start 303.816766 -97.509584)
		(end 304.388266 -97.509584)
		(stroke
			(width 0.05715)
			(type default)
		)
		(layer "F.Cu")
	)
	(gr_line
		(start 303.816766 -96.518984)
		(end 304.388266 -96.518984)
		(stroke
			(width 0.05715)
			(type default)
		)
		(layer "F.Cu")
	)
	(gr_line
		(start 303.816766 -95.528384)
		(end 304.388266 -95.528384)
		(stroke
			(width 0.05715)
			(type default)
		)
		(layer "F.Cu")
	)
	(gr_line
		(start 303.816766 -94.538038)
		(end 304.388266 -94.538038)
		(stroke
			(width 0.05715)
			(type default)
		)
		(layer "F.Cu")
	)
	(gr_line
		(start 303.816766 -92.556584)
		(end 304.388266 -92.556584)
		(stroke
			(width 0.05715)
			(type default)
		)
		(layer "F.Cu")
	)
	(gr_line
		(start 303.816766 -91.565984)
		(end 304.388266 -91.565984)
		(stroke
			(width 0.05715)
			(type default)
		)
		(layer "F.Cu")
	)
	(gr_line
		(start 303.816766 -90.575384)
		(end 304.388266 -90.575384)
		(stroke
			(width 0.05715)
			(type default)
		)
		(layer "F.Cu")
	)
	(gr_line
		(start 303.816766 -89.584784)
		(end 304.388266 -89.584784)
		(stroke
			(width 0.05715)
			(type default)
		)
		(layer "F.Cu")
	)
	(gr_line
		(start 303.816766 -87.603584)
		(end 304.388266 -87.603584)
		(stroke
			(width 0.05715)
			(type default)
		)
		(layer "F.Cu")
	)
	(gr_line
		(start 303.816766 -84.631784)
		(end 304.388266 -84.631784)
		(stroke
			(width 0.05715)
			(type default)
		)
		(layer "F.Cu")
	)
	(gr_line
		(start 303.816766 -80.669384)
		(end 304.10404 -80.835246)
		(stroke
			(width 0.04445)
			(type default)
		)
		(layer "F.Cu")
	)
	(gr_arc
		(start 303.816766 -77.697584)
		(mid 304.234433 -77.769134)
		(end 304.657506 -77.793088)
		(stroke
			(width 0.04445)
			(type default)
		)
		(layer "F.Cu")
	)
	(gr_line
		(start 303.816766 -76.706984)
		(end 303.988978 -76.282042)
		(stroke
			(width 0.04445)
			(type default)
		)
		(layer "F.Cu")
	)
	(gr_line
		(start 303.816766 -75.716384)
		(end 303.967642 -76.087224)
		(stroke
			(width 0.04445)
			(type default)
		)
		(layer "F.Cu")
	)
	(gr_line
		(start 303.816766 -74.725784)
		(end 304.388266 -74.725784)
		(stroke
			(width 0.0635)
			(type default)
		)
		(layer "F.Cu")
	)
	(gr_line
		(start 303.816766 -73.735184)
		(end 304.388266 -73.735184)
		(stroke
			(width 0.0635)
			(type default)
		)
		(layer "F.Cu")
	)
	(gr_line
		(start 303.845722 -105.127806)
		(end 304.034444 -105.316528)
		(stroke
			(width 0.04445)
			(type default)
		)
		(layer "F.Cu")
	)
	(gr_line
		(start 304.034444 -105.316528)
		(end 304.034444 -105.438956)
		(stroke
			(width 0.04445)
			(type default)
		)
		(layer "F.Cu")
	)
	(gr_line
		(start 304.067464 -101.89718)
		(end 304.1015 -101.931216)
		(stroke
			(width 0.04445)
			(type default)
		)
		(layer "F.Cu")
	)
	(gr_line
		(start 304.10404 -80.835246)
		(end 304.202084 -80.80883)
		(stroke
			(width 0.04445)
			(type default)
		)
		(layer "F.Cu")
	)
	(gr_line
		(start 304.109882 -105.78719)
		(end 304.266092 -105.9434)
		(stroke
			(width 0.04445)
			(type default)
		)
		(layer "F.Cu")
	)
	(gr_line
		(start 304.226214 -105.630726)
		(end 304.348642 -105.630726)
		(stroke
			(width 0.04445)
			(type default)
		)
		(layer "F.Cu")
	)
	(gr_line
		(start 304.267616 -104.478582)
		(end 304.622454 -104.625648)
		(stroke
			(width 0.04445)
			(type default)
		)
		(layer "F.Cu")
	)
	(gr_line
		(start 304.279808 -102.464108)
		(end 304.284634 -102.472744)
		(stroke
			(width 0.04445)
			(type default)
		)
		(layer "F.Cu")
	)
	(gr_line
		(start 304.315876 -104.289606)
		(end 304.428906 -104.24287)
		(stroke
			(width 0.04445)
			(type default)
		)
		(layer "F.Cu")
	)
	(gr_line
		(start 304.348642 -105.630726)
		(end 304.537364 -105.819448)
		(stroke
			(width 0.04445)
			(type default)
		)
		(layer "F.Cu")
	)
	(gr_line
		(start 304.364898 -98.25736)
		(end 304.388012 -98.170746)
		(stroke
			(width 0.04445)
			(type default)
		)
		(layer "F.Cu")
	)
	(gr_line
		(start 304.364898 -77.45476)
		(end 304.388012 -77.368146)
		(stroke
			(width 0.04445)
			(type default)
		)
		(layer "F.Cu")
	)
	(gr_line
		(start 304.365406 -80.913986)
		(end 304.388012 -80.999076)
		(stroke
			(width 0.04445)
			(type default)
		)
		(layer "F.Cu")
	)
	(gr_line
		(start 304.388012 -98.170746)
		(end 304.675286 -98.005138)
		(stroke
			(width 0.04445)
			(type default)
		)
		(layer "F.Cu")
	)
	(gr_line
		(start 304.388012 -80.999076)
		(end 304.675286 -81.164938)
		(stroke
			(width 0.04445)
			(type default)
		)
		(layer "F.Cu")
	)
	(gr_line
		(start 304.388012 -77.368146)
		(end 304.531776 -77.285342)
		(stroke
			(width 0.04445)
			(type default)
		)
		(layer "F.Cu")
	)
	(gr_line
		(start 304.428906 -104.24287)
		(end 304.67554 -104.344978)
		(stroke
			(width 0.04445)
			(type default)
		)
		(layer "F.Cu")
	)
	(gr_line
		(start 304.531776 -77.285342)
		(end 304.675286 -77.202538)
		(stroke
			(width 0.04445)
			(type default)
		)
		(layer "F.Cu")
	)
	(gr_line
		(start 304.537364 -105.819448)
		(end 304.537364 -105.941876)
		(stroke
			(width 0.04445)
			(type default)
		)
		(layer "F.Cu")
	)
	(gr_line
		(start 304.612802 -106.29011)
		(end 304.769012 -106.44632)
		(stroke
			(width 0.04445)
			(type default)
		)
		(layer "F.Cu")
	)
	(gr_line
		(start 304.657506 -98.595688)
		(end 304.693066 -98.595688)
		(stroke
			(width 0.04445)
			(type default)
		)
		(layer "F.Cu")
	)
	(gr_line
		(start 304.657506 -77.793088)
		(end 304.693066 -77.793088)
		(stroke
			(width 0.04445)
			(type default)
		)
		(layer "F.Cu")
	)
	(gr_line
		(start 304.675286 -99.654614)
		(end 304.675286 -99.986338)
		(stroke
			(width 0.04445)
			(type default)
		)
		(layer "F.Cu")
	)
	(gr_line
		(start 304.675286 -99.654614)
		(end 304.702464 -99.627436)
		(stroke
			(width 0.04445)
			(type default)
		)
		(layer "F.Cu")
	)
	(gr_line
		(start 304.675286 -99.327462)
		(end 304.702464 -99.35464)
		(stroke
			(width 0.04445)
			(type default)
		)
		(layer "F.Cu")
	)
	(gr_line
		(start 304.675286 -98.995738)
		(end 304.675286 -99.327462)
		(stroke
			(width 0.04445)
			(type default)
		)
		(layer "F.Cu")
	)
	(gr_line
		(start 304.675286 -95.033084)
		(end 305.246786 -95.033084)
		(stroke
			(width 0.05715)
			(type default)
		)
		(layer "F.Cu")
	)
	(gr_line
		(start 304.675286 -94.042738)
		(end 304.96256 -93.876876)
		(stroke
			(width 0.04445)
			(type default)
		)
		(layer "F.Cu")
	)
	(gr_line
		(start 304.675286 -93.052138)
		(end 304.819812 -92.678758)
		(stroke
			(width 0.04445)
			(type default)
		)
		(layer "F.Cu")
	)
	(gr_line
		(start 304.675286 -92.061538)
		(end 304.82794 -92.481146)
		(stroke
			(width 0.04445)
			(type default)
		)
		(layer "F.Cu")
	)
	(gr_line
		(start 304.675286 -91.070938)
		(end 305.246786 -91.070938)
		(stroke
			(width 0.05715)
			(type default)
		)
		(layer "F.Cu")
	)
	(gr_line
		(start 304.675286 -90.080338)
		(end 304.96256 -90.245946)
		(stroke
			(width 0.04445)
			(type default)
		)
		(layer "F.Cu")
	)
	(gr_line
		(start 304.675286 -88.099138)
		(end 305.246786 -88.099138)
		(stroke
			(width 0.05715)
			(type default)
		)
		(layer "F.Cu")
	)
	(gr_line
		(start 304.675286 -87.108538)
		(end 305.246786 -87.108538)
		(stroke
			(width 0.05715)
			(type default)
		)
		(layer "F.Cu")
	)
	(gr_line
		(start 304.675286 -86.117938)
		(end 305.246786 -86.117938)
		(stroke
			(width 0.05715)
			(type default)
		)
		(layer "F.Cu")
	)
	(gr_line
		(start 304.675286 -85.127338)
		(end 305.246786 -85.127338)
		(stroke
			(width 0.05715)
			(type default)
		)
		(layer "F.Cu")
	)
	(gr_line
		(start 304.675286 -84.136738)
		(end 305.246786 -84.136738)
		(stroke
			(width 0.05715)
			(type default)
		)
		(layer "F.Cu")
	)
	(gr_line
		(start 304.675286 -80.174338)
		(end 304.96256 -80.008476)
		(stroke
			(width 0.04445)
			(type default)
		)
		(layer "F.Cu")
	)
	(gr_line
		(start 304.675286 -79.183738)
		(end 304.845212 -78.759304)
		(stroke
			(width 0.04445)
			(type default)
		)
		(layer "F.Cu")
	)
	(gr_line
		(start 304.675286 -78.193138)
		(end 304.825908 -78.563724)
		(stroke
			(width 0.04445)
			(type default)
		)
		(layer "F.Cu")
	)
	(gr_line
		(start 304.675286 -76.211938)
		(end 304.96256 -76.377546)
		(stroke
			(width 0.04445)
			(type default)
		)
		(layer "F.Cu")
	)
	(gr_line
		(start 304.67554 -104.344978)
		(end 304.722276 -104.458008)
		(stroke
			(width 0.04445)
			(type default)
		)
		(layer "F.Cu")
	)
	(gr_line
		(start 304.6857 -102.423722)
		(end 304.715418 -102.428802)
		(stroke
			(width 0.04445)
			(type default)
		)
		(layer "F.Cu")
	)
	(gr_line
		(start 304.704242 -99.625658)
		(end 304.738786 -99.591114)
		(stroke
			(width 0.04445)
			(type default)
		)
		(layer "F.Cu")
	)
	(gr_line
		(start 304.704242 -99.356418)
		(end 304.747422 -99.399598)
		(stroke
			(width 0.04445)
			(type default)
		)
		(layer "F.Cu")
	)
	(gr_line
		(start 304.729134 -106.133646)
		(end 304.851562 -106.133646)
		(stroke
			(width 0.04445)
			(type default)
		)
		(layer "F.Cu")
	)
	(gr_line
		(start 304.812192 -102.9208)
		(end 305.000914 -103.109522)
		(stroke
			(width 0.04445)
			(type default)
		)
		(layer "F.Cu")
	)
	(gr_line
		(start 304.812192 -102.798626)
		(end 304.812192 -102.9208)
		(stroke
			(width 0.04445)
			(type default)
		)
		(layer "F.Cu")
	)
	(gr_line
		(start 304.851562 -106.133646)
		(end 305.040284 -106.322368)
		(stroke
			(width 0.04445)
			(type default)
		)
		(layer "F.Cu")
	)
	(gr_line
		(start 304.96256 -93.876876)
		(end 305.060604 -93.903292)
		(stroke
			(width 0.04445)
			(type default)
		)
		(layer "F.Cu")
	)
	(gr_line
		(start 304.96256 -90.245946)
		(end 305.060604 -90.21953)
		(stroke
			(width 0.04445)
			(type default)
		)
		(layer "F.Cu")
	)
	(gr_line
		(start 304.96256 -80.008476)
		(end 304.988722 -79.910432)
		(stroke
			(width 0.04445)
			(type default)
		)
		(layer "F.Cu")
	)
	(gr_line
		(start 304.96256 -76.377546)
		(end 305.060604 -76.35113)
		(stroke
			(width 0.04445)
			(type default)
		)
		(layer "F.Cu")
	)
	(gr_line
		(start 304.963322 -104.56037)
		(end 304.969926 -104.563164)
		(stroke
			(width 0.04445)
			(type default)
		)
		(layer "F.Cu")
	)
	(gr_line
		(start 304.968656 -102.68204)
		(end 305.124866 -102.83825)
		(stroke
			(width 0.04445)
			(type default)
		)
		(layer "F.Cu")
	)
	(gr_line
		(start 305.000914 -103.109522)
		(end 305.123342 -103.109522)
		(stroke
			(width 0.04445)
			(type default)
		)
		(layer "F.Cu")
	)
	(gr_line
		(start 305.040284 -106.322368)
		(end 305.040284 -106.444796)
		(stroke
			(width 0.04445)
			(type default)
		)
		(layer "F.Cu")
	)
	(gr_line
		(start 305.161696 -79.821786)
		(end 305.246532 -79.844646)
		(stroke
			(width 0.04445)
			(type default)
		)
		(layer "F.Cu")
	)
	(gr_line
		(start 305.186842 -78.48854)
		(end 305.187096 -78.48854)
		(stroke
			(width 0.04445)
			(type default)
		)
		(layer "F.Cu")
	)
	(gr_line
		(start 305.223418 -83.388962)
		(end 305.246532 -83.475576)
		(stroke
			(width 0.04445)
			(type default)
		)
		(layer "F.Cu")
	)
	(gr_line
		(start 305.223926 -93.798136)
		(end 305.246532 -93.713046)
		(stroke
			(width 0.04445)
			(type default)
		)
		(layer "F.Cu")
	)
	(gr_line
		(start 305.223926 -90.324686)
		(end 305.246532 -90.409776)
		(stroke
			(width 0.04445)
			(type default)
		)
		(layer "F.Cu")
	)
	(gr_line
		(start 305.223926 -76.456286)
		(end 305.246532 -76.541376)
		(stroke
			(width 0.04445)
			(type default)
		)
		(layer "F.Cu")
	)
	(gr_line
		(start 305.246532 -93.713046)
		(end 305.533806 -93.547184)
		(stroke
			(width 0.04445)
			(type default)
		)
		(layer "F.Cu")
	)
	(gr_line
		(start 305.246532 -90.409776)
		(end 305.533806 -90.575384)
		(stroke
			(width 0.04445)
			(type default)
		)
		(layer "F.Cu")
	)
	(gr_line
		(start 305.246532 -83.475576)
		(end 305.533806 -83.641184)
		(stroke
			(width 0.04445)
			(type default)
		)
		(layer "F.Cu")
	)
	(gr_line
		(start 305.246532 -79.844646)
		(end 305.533806 -79.678784)
		(stroke
			(width 0.04445)
			(type default)
		)
		(layer "F.Cu")
	)
	(gr_line
		(start 305.246532 -76.541376)
		(end 305.533806 -76.706984)
		(stroke
			(width 0.04445)
			(type default)
		)
		(layer "F.Cu")
	)
	(gr_line
		(start 305.267106 -105.165906)
		(end 305.2826 -105.1814)
		(stroke
			(width 0.04445)
			(type default)
		)
		(layer "F.Cu")
	)
	(gr_line
		(start 305.267106 -105.129838)
		(end 305.267106 -105.165906)
		(stroke
			(width 0.04445)
			(type default)
		)
		(layer "F.Cu")
	)
	(gr_arc
		(start 305.272948 -97.206562)
		(mid 305.251729 -97.488638)
		(end 305.533806 -97.509584)
		(stroke
			(width 0.04445)
			(type default)
		)
		(layer "F.Cu")
	)
	(gr_line
		(start 305.315112 -103.42372)
		(end 305.503834 -103.612442)
		(stroke
			(width 0.04445)
			(type default)
		)
		(layer "F.Cu")
	)
	(gr_line
		(start 305.315112 -103.301292)
		(end 305.315112 -103.42372)
		(stroke
			(width 0.04445)
			(type default)
		)
		(layer "F.Cu")
	)
	(gr_line
		(start 305.40198 -104.995218)
		(end 305.437794 -104.995218)
		(stroke
			(width 0.04445)
			(type default)
		)
		(layer "F.Cu")
	)
	(gr_line
		(start 305.437794 -104.995218)
		(end 305.453288 -105.010712)
		(stroke
			(width 0.04445)
			(type default)
		)
		(layer "F.Cu")
	)
	(gr_line
		(start 305.471576 -103.18496)
		(end 305.742848 -103.455978)
		(stroke
			(width 0.04445)
			(type default)
		)
		(layer "F.Cu")
	)
	(gr_line
		(start 305.503834 -103.612442)
		(end 305.626262 -103.612442)
		(stroke
			(width 0.04445)
			(type default)
		)
		(layer "F.Cu")
	)
	(gr_arc
		(start 305.516026 -83.050634)
		(mid 305.092952 -83.074585)
		(end 304.675286 -83.146138)
		(stroke
			(width 0.04445)
			(type default)
		)
		(layer "F.Cu")
	)
	(gr_line
		(start 305.521106 -100.081334)
		(end 305.542696 -100.081334)
		(stroke
			(width 0.04445)
			(type default)
		)
		(layer "F.Cu")
	)
	(gr_arc
		(start 305.52263 -83.241134)
		(mid 305.356856 -83.28234)
		(end 305.223418 -83.388962)
		(stroke
			(width 0.04445)
			(type default)
		)
		(layer "F.Cu")
	)
	(gr_line
		(start 305.533806 -99.490784)
		(end 305.82108 -99.325176)
		(stroke
			(width 0.04445)
			(type default)
		)
		(layer "F.Cu")
	)
	(gr_arc
		(start 305.533806 -96.518984)
		(mid 305.951472 -96.590541)
		(end 306.374546 -96.614488)
		(stroke
			(width 0.04445)
			(type default)
		)
		(layer "F.Cu")
	)
	(gr_line
		(start 305.533806 -95.528384)
		(end 305.667156 -95.151194)
		(stroke
			(width 0.04445)
			(type default)
		)
		(layer "F.Cu")
	)
	(gr_line
		(start 305.533806 -94.538038)
		(end 305.689 -94.9579)
		(stroke
			(width 0.04445)
			(type default)
		)
		(layer "F.Cu")
	)
	(gr_line
		(start 305.533806 -92.556584)
		(end 305.82108 -92.722446)
		(stroke
			(width 0.04445)
			(type default)
		)
		(layer "F.Cu")
	)
	(gr_line
		(start 305.533806 -89.584784)
		(end 305.82108 -89.419176)
		(stroke
			(width 0.04445)
			(type default)
		)
		(layer "F.Cu")
	)
	(gr_line
		(start 305.533806 -88.594184)
		(end 305.685444 -88.175084)
		(stroke
			(width 0.04445)
			(type default)
		)
		(layer "F.Cu")
	)
	(gr_line
		(start 305.533806 -87.603584)
		(end 305.666648 -87.981282)
		(stroke
			(width 0.04445)
			(type default)
		)
		(layer "F.Cu")
	)
	(gr_line
		(start 305.533806 -86.612984)
		(end 306.105306 -86.612984)
		(stroke
			(width 0.05715)
			(type default)
		)
		(layer "F.Cu")
	)
	(gr_arc
		(start 305.533806 -82.650584)
		(mid 305.666917 -82.347502)
		(end 305.797966 -82.043524)
		(stroke
			(width 0.04445)
			(type default)
		)
		(layer "F.Cu")
	)
	(gr_line
		(start 305.533806 -81.659984)
		(end 305.821842 -81.202276)
		(stroke
			(width 0.04445)
			(type default)
		)
		(layer "F.Cu")
	)
	(gr_line
		(start 305.533806 -80.669384)
		(end 305.746658 -80.882236)
		(stroke
			(width 0.04445)
			(type default)
		)
		(layer "F.Cu")
	)
	(gr_arc
		(start 305.551586 -96.919034)
		(mid 305.110119 -96.936355)
		(end 304.675286 -97.014538)
		(stroke
			(width 0.04445)
			(type default)
		)
		(layer "F.Cu")
	)
	(gr_line
		(start 305.597306 -99.893882)
		(end 305.597306 -99.894136)
		(stroke
			(width 0.04445)
			(type default)
		)
		(layer "F.Cu")
	)
	(gr_line
		(start 305.715162 -78.095348)
		(end 305.7779 -78.03261)
		(stroke
			(width 0.04445)
			(type default)
		)
		(layer "F.Cu")
	)
	(gr_line
		(start 305.71694 -75.123294)
		(end 305.776376 -75.063858)
		(stroke
			(width 0.04445)
			(type default)
		)
		(layer "F.Cu")
	)
	(gr_line
		(start 305.746658 -80.882236)
		(end 305.868832 -80.882236)
		(stroke
			(width 0.04445)
			(type default)
		)
		(layer "F.Cu")
	)
	(gr_line
		(start 305.776376 -75.063858)
		(end 305.954176 -75.063858)
		(stroke
			(width 0.04445)
			(type default)
		)
		(layer "F.Cu")
	)
	(gr_line
		(start 305.7779 -78.03261)
		(end 305.9557 -78.03261)
		(stroke
			(width 0.04445)
			(type default)
		)
		(layer "F.Cu")
	)
	(gr_line
		(start 305.792124 -77.104494)
		(end 305.863498 -77.03312)
		(stroke
			(width 0.04445)
			(type default)
		)
		(layer "F.Cu")
	)
	(gr_line
		(start 305.818032 -103.92664)
		(end 306.006754 -104.115362)
		(stroke
			(width 0.04445)
			(type default)
		)
		(layer "F.Cu")
	)
	(gr_line
		(start 305.818032 -103.804212)
		(end 305.818032 -103.92664)
		(stroke
			(width 0.04445)
			(type default)
		)
		(layer "F.Cu")
	)
	(gr_line
		(start 305.82108 -99.325176)
		(end 305.919124 -99.351592)
		(stroke
			(width 0.04445)
			(type default)
		)
		(layer "F.Cu")
	)
	(gr_line
		(start 305.82108 -92.722446)
		(end 305.919124 -92.69603)
		(stroke
			(width 0.04445)
			(type default)
		)
		(layer "F.Cu")
	)
	(gr_line
		(start 305.82108 -89.419176)
		(end 305.847242 -89.32164)
		(stroke
			(width 0.04445)
			(type default)
		)
		(layer "F.Cu")
	)
	(gr_line
		(start 305.821842 -81.202276)
		(end 305.87061 -81.153508)
		(stroke
			(width 0.04445)
			(type default)
		)
		(layer "F.Cu")
	)
	(gr_line
		(start 305.847242 -79.281528)
		(end 305.935634 -79.36992)
		(stroke
			(width 0.04445)
			(type default)
		)
		(layer "F.Cu")
	)
	(gr_line
		(start 305.863498 -77.03312)
		(end 306.130198 -77.03312)
		(stroke
			(width 0.04445)
			(type default)
		)
		(layer "F.Cu")
	)
	(gr_line
		(start 305.869594 -107.58297)
		(end 305.885088 -107.598464)
		(stroke
			(width 0.04445)
			(type default)
		)
		(layer "F.Cu")
	)
	(gr_line
		(start 305.869594 -107.547156)
		(end 305.869594 -107.58297)
		(stroke
			(width 0.04445)
			(type default)
		)
		(layer "F.Cu")
	)
	(gr_line
		(start 305.935634 -79.36992)
		(end 306.202334 -79.36992)
		(stroke
			(width 0.04445)
			(type default)
		)
		(layer "F.Cu")
	)
	(gr_line
		(start 305.954176 -75.063858)
		(end 306.013612 -75.123294)
		(stroke
			(width 0.04445)
			(type default)
		)
		(layer "F.Cu")
	)
	(gr_line
		(start 305.9557 -78.03261)
		(end 306.018438 -78.095348)
		(stroke
			(width 0.04445)
			(type default)
		)
		(layer "F.Cu")
	)
	(gr_line
		(start 305.973988 -82.180938)
		(end 306.105052 -82.320892)
		(stroke
			(width 0.04445)
			(type default)
		)
		(layer "F.Cu")
	)
	(gr_line
		(start 305.974496 -103.687626)
		(end 306.13096 -103.84409)
		(stroke
			(width 0.04445)
			(type default)
		)
		(layer "F.Cu")
	)
	(gr_line
		(start 305.982624 -77.297534)
		(end 306.011072 -77.297534)
		(stroke
			(width 0.04445)
			(type default)
		)
		(layer "F.Cu")
	)
	(gr_line
		(start 306.004722 -107.412536)
		(end 306.040536 -107.412536)
		(stroke
			(width 0.04445)
			(type default)
		)
		(layer "F.Cu")
	)
	(gr_line
		(start 306.006754 -104.115362)
		(end 306.129182 -104.115362)
		(stroke
			(width 0.04445)
			(type default)
		)
		(layer "F.Cu")
	)
	(gr_line
		(start 306.019708 -89.231978)
		(end 306.145692 -89.231978)
		(stroke
			(width 0.04445)
			(type default)
		)
		(layer "F.Cu")
	)
	(gr_line
		(start 306.037742 -79.088488)
		(end 306.100226 -79.088488)
		(stroke
			(width 0.04445)
			(type default)
		)
		(layer "F.Cu")
	)
	(gr_line
		(start 306.040536 -107.412536)
		(end 306.05603 -107.42803)
		(stroke
			(width 0.04445)
			(type default)
		)
		(layer "F.Cu")
	)
	(gr_line
		(start 306.081938 -96.27616)
		(end 306.105052 -96.189546)
		(stroke
			(width 0.04445)
			(type default)
		)
		(layer "F.Cu")
	)
	(gr_arc
		(start 306.081938 -96.27616)
		(mid 306.215383 -96.382785)
		(end 306.38115 -96.423988)
		(stroke
			(width 0.04445)
			(type default)
		)
		(layer "F.Cu")
	)
	(gr_line
		(start 306.081938 -85.865462)
		(end 306.105052 -85.952076)
		(stroke
			(width 0.04445)
			(type default)
		)
		(layer "F.Cu")
	)
	(gr_line
		(start 306.082446 -99.246436)
		(end 306.105052 -99.161346)
		(stroke
			(width 0.04445)
			(type default)
		)
		(layer "F.Cu")
	)
	(gr_line
		(start 306.082446 -92.801186)
		(end 306.105052 -92.886276)
		(stroke
			(width 0.04445)
			(type default)
		)
		(layer "F.Cu")
	)
	(gr_line
		(start 306.105052 -99.161346)
		(end 306.392326 -98.995738)
		(stroke
			(width 0.04445)
			(type default)
		)
		(layer "F.Cu")
	)
	(gr_line
		(start 306.105052 -96.189546)
		(end 306.392326 -96.023938)
		(stroke
			(width 0.04445)
			(type default)
		)
		(layer "F.Cu")
	)
	(gr_line
		(start 306.105052 -92.886276)
		(end 306.392326 -93.052138)
		(stroke
			(width 0.04445)
			(type default)
		)
		(layer "F.Cu")
	)
	(gr_line
		(start 306.105052 -85.952076)
		(end 306.392326 -86.117938)
		(stroke
			(width 0.04445)
			(type default)
		)
		(layer "F.Cu")
	)
	(gr_line
		(start 306.105052 -82.320892)
		(end 306.392326 -82.155284)
		(stroke
			(width 0.04445)
			(type default)
		)
		(layer "F.Cu")
	)
	(gr_line
		(start 306.130198 -77.03312)
		(end 306.201572 -77.104494)
		(stroke
			(width 0.04445)
			(type default)
		)
		(layer "F.Cu")
	)
	(gr_line
		(start 306.145692 -89.231978)
		(end 306.392326 -89.089738)
		(stroke
			(width 0.04445)
			(type default)
		)
		(layer "F.Cu")
	)
	(gr_line
		(start 306.152042 -107.865672)
		(end 306.35956 -108.07319)
		(stroke
			(width 0.05715)
			(type default)
		)
		(layer "F.Cu")
	)
	(gr_line
		(start 306.182268 -102.260654)
		(end 306.37099 -102.449376)
		(stroke
			(width 0.04445)
			(type default)
		)
		(layer "F.Cu")
	)
	(gr_line
		(start 306.182268 -102.138226)
		(end 306.182268 -102.260654)
		(stroke
			(width 0.04445)
			(type default)
		)
		(layer "F.Cu")
	)
	(gr_line
		(start 306.202334 -79.36992)
		(end 306.290726 -79.281528)
		(stroke
			(width 0.04445)
			(type default)
		)
		(layer "F.Cu")
	)
	(gr_line
		(start 306.239926 -104.258872)
		(end 306.255674 -104.27462)
		(stroke
			(width 0.04445)
			(type default)
		)
		(layer "F.Cu")
	)
	(gr_line
		(start 306.239926 -104.222804)
		(end 306.239926 -104.258872)
		(stroke
			(width 0.04445)
			(type default)
		)
		(layer "F.Cu")
	)
	(gr_line
		(start 306.279042 -100.80498)
		(end 306.467764 -100.993702)
		(stroke
			(width 0.04445)
			(type default)
		)
		(layer "F.Cu")
	)
	(gr_line
		(start 306.279042 -100.682552)
		(end 306.279042 -100.80498)
		(stroke
			(width 0.04445)
			(type default)
		)
		(layer "F.Cu")
	)
	(gr_line
		(start 306.302156 -107.6706)
		(end 306.460144 -107.6706)
		(stroke
			(width 0.05715)
			(type default)
		)
		(layer "F.Cu")
	)
	(gr_line
		(start 306.343558 -80.068674)
		(end 306.429918 -80.155034)
		(stroke
			(width 0.04445)
			(type default)
		)
		(layer "F.Cu")
	)
	(gr_line
		(start 306.360576 -78.095348)
		(end 306.459128 -77.996796)
		(stroke
			(width 0.04445)
			(type default)
		)
		(layer "F.Cu")
	)
	(gr_arc
		(start 306.370736 -85.527388)
		(mid 305.949585 -85.551219)
		(end 305.533806 -85.622384)
		(stroke
			(width 0.04445)
			(type default)
		)
		(layer "F.Cu")
	)
	(gr_line
		(start 306.37099 -102.449376)
		(end 306.493418 -102.449376)
		(stroke
			(width 0.04445)
			(type default)
		)
		(layer "F.Cu")
	)
	(gr_line
		(start 306.375308 -104.088438)
		(end 306.410868 -104.088438)
		(stroke
			(width 0.04445)
			(type default)
		)
		(layer "F.Cu")
	)
	(gr_arc
		(start 306.37734 -85.717888)
		(mid 306.213702 -85.759783)
		(end 306.081938 -85.865462)
		(stroke
			(width 0.04445)
			(type default)
		)
		(layer "F.Cu")
	)
	(gr_line
		(start 306.392326 -92.061538)
		(end 306.6796 -91.895676)
		(stroke
			(width 0.04445)
			(type default)
		)
		(layer "F.Cu")
	)
	(gr_line
		(start 306.392326 -90.739214)
		(end 306.392326 -91.070938)
		(stroke
			(width 0.04445)
			(type default)
		)
		(layer "F.Cu")
	)
	(gr_line
		(start 306.392326 -90.739214)
		(end 306.419504 -90.712036)
		(stroke
			(width 0.04445)
			(type default)
		)
		(layer "F.Cu")
	)
	(gr_line
		(start 306.392326 -90.412062)
		(end 306.419504 -90.43924)
		(stroke
			(width 0.04445)
			(type default)
		)
		(layer "F.Cu")
	)
	(gr_line
		(start 306.392326 -90.080338)
		(end 306.392326 -90.412062)
		(stroke
			(width 0.04445)
			(type default)
		)
		(layer "F.Cu")
	)
	(gr_line
		(start 306.392326 -88.099138)
		(end 306.6796 -88.264746)
		(stroke
			(width 0.04445)
			(type default)
		)
		(layer "F.Cu")
	)
	(gr_line
		(start 306.392326 -84.136738)
		(end 306.71516 -83.813904)
		(stroke
			(width 0.05715)
			(type default)
		)
		(layer "F.Cu")
	)
	(gr_line
		(start 306.392326 -83.146138)
		(end 306.71516 -83.468972)
		(stroke
			(width 0.05715)
			(type default)
		)
		(layer "F.Cu")
	)
	(gr_line
		(start 306.410868 -104.088438)
		(end 306.426362 -104.103932)
		(stroke
			(width 0.04445)
			(type default)
		)
		(layer "F.Cu")
	)
	(gr_line
		(start 306.421282 -90.710258)
		(end 306.455826 -90.675714)
		(stroke
			(width 0.04445)
			(type default)
		)
		(layer "F.Cu")
	)
	(gr_line
		(start 306.421282 -90.441018)
		(end 306.464462 -90.484198)
		(stroke
			(width 0.04445)
			(type default)
		)
		(layer "F.Cu")
	)
	(gr_line
		(start 306.429918 -80.155034)
		(end 306.696618 -80.155034)
		(stroke
			(width 0.04445)
			(type default)
		)
		(layer "F.Cu")
	)
	(gr_line
		(start 306.45354 -102.136448)
		(end 306.495196 -102.178104)
		(stroke
			(width 0.04445)
			(type default)
		)
		(layer "F.Cu")
	)
	(gr_line
		(start 306.459128 -77.996796)
		(end 306.636928 -77.996796)
		(stroke
			(width 0.04445)
			(type default)
		)
		(layer "F.Cu")
	)
	(gr_line
		(start 306.460144 -107.6706)
		(end 306.702714 -107.912916)
		(stroke
			(width 0.05715)
			(type default)
		)
		(layer "F.Cu")
	)
	(gr_line
		(start 306.467764 -100.993702)
		(end 306.590192 -100.993702)
		(stroke
			(width 0.04445)
			(type default)
		)
		(layer "F.Cu")
	)
	(gr_line
		(start 306.488338 -77.104494)
		(end 306.552854 -77.039978)
		(stroke
			(width 0.04445)
			(type default)
		)
		(layer "F.Cu")
	)
	(gr_line
		(start 306.496466 -75.316334)
		(end 306.530248 -75.283568)
		(stroke
			(width 0.04445)
			(type default)
		)
		(layer "F.Cu")
	)
	(gr_line
		(start 306.520342 -109.833156)
		(end 306.752244 -110.321344)
		(stroke
			(width 0.05715)
			(type default)
		)
		(layer "F.Cu")
	)
	(gr_line
		(start 306.529232 -96.423988)
		(end 306.60975 -96.423988)
		(stroke
			(width 0.04445)
			(type default)
		)
		(layer "F.Cu")
	)
	(gr_line
		(start 306.534058 -79.875634)
		(end 306.592478 -79.875634)
		(stroke
			(width 0.04445)
			(type default)
		)
		(layer "F.Cu")
	)
	(gr_line
		(start 306.550568 -100.681028)
		(end 306.59197 -100.72243)
		(stroke
			(width 0.04445)
			(type default)
		)
		(layer "F.Cu")
	)
	(gr_line
		(start 306.552854 -77.039978)
		(end 306.819554 -77.039978)
		(stroke
			(width 0.04445)
			(type default)
		)
		(layer "F.Cu")
	)
	(gr_line
		(start 306.562506 -79.281528)
		(end 306.650898 -79.36992)
		(stroke
			(width 0.04445)
			(type default)
		)
		(layer "F.Cu")
	)
	(gr_line
		(start 306.572158 -109.379258)
		(end 306.575714 -109.386624)
		(stroke
			(width 0.05715)
			(type default)
		)
		(layer "F.Cu")
	)
	(gr_line
		(start 306.617116 -99.393248)
		(end 306.715668 -99.294696)
		(stroke
			(width 0.04445)
			(type default)
		)
		(layer "F.Cu")
	)
	(gr_line
		(start 306.636928 -77.996796)
		(end 306.73548 -78.095348)
		(stroke
			(width 0.04445)
			(type default)
		)
		(layer "F.Cu")
	)
	(gr_line
		(start 306.650898 -79.36992)
		(end 306.917598 -79.36992)
		(stroke
			(width 0.04445)
			(type default)
		)
		(layer "F.Cu")
	)
	(gr_line
		(start 306.661312 -82.748374)
		(end 306.747672 -82.834734)
		(stroke
			(width 0.04445)
			(type default)
		)
		(layer "F.Cu")
	)
	(gr_line
		(start 306.678838 -77.297534)
		(end 306.69357 -77.297534)
		(stroke
			(width 0.04445)
			(type default)
		)
		(layer "F.Cu")
	)
	(gr_line
		(start 306.6796 -91.895676)
		(end 306.777644 -91.922092)
		(stroke
			(width 0.04445)
			(type default)
		)
		(layer "F.Cu")
	)
	(gr_line
		(start 306.6796 -88.264746)
		(end 306.777644 -88.23833)
		(stroke
			(width 0.04445)
			(type default)
		)
		(layer "F.Cu")
	)
	(gr_line
		(start 306.685188 -102.763574)
		(end 306.87391 -102.952296)
		(stroke
			(width 0.04445)
			(type default)
		)
		(layer "F.Cu")
	)
	(gr_line
		(start 306.685188 -102.641146)
		(end 306.685188 -102.763574)
		(stroke
			(width 0.04445)
			(type default)
		)
		(layer "F.Cu")
	)
	(gr_line
		(start 306.696618 -104.715564)
		(end 307.051964 -105.07091)
		(stroke
			(width 0.05715)
			(type default)
		)
		(layer "F.Cu")
	)
	(gr_line
		(start 306.696618 -80.155034)
		(end 306.782978 -80.068674)
		(stroke
			(width 0.04445)
			(type default)
		)
		(layer "F.Cu")
	)
	(gr_line
		(start 306.702714 -107.912916)
		(end 306.702714 -108.071412)
		(stroke
			(width 0.05715)
			(type default)
		)
		(layer "F.Cu")
	)
	(gr_line
		(start 306.715668 -99.294696)
		(end 306.982368 -99.294696)
		(stroke
			(width 0.04445)
			(type default)
		)
		(layer "F.Cu")
	)
	(gr_line
		(start 306.719732 -96.5835)
		(end 306.80025 -96.5835)
		(stroke
			(width 0.04445)
			(type default)
		)
		(layer "F.Cu")
	)
	(gr_line
		(start 306.727606 -109.70133)
		(end 306.890674 -109.759496)
		(stroke
			(width 0.05715)
			(type default)
		)
		(layer "F.Cu")
	)
	(gr_line
		(start 306.737766 -81.757774)
		(end 306.824126 -81.844134)
		(stroke
			(width 0.04445)
			(type default)
		)
		(layer "F.Cu")
	)
	(gr_line
		(start 306.747672 -82.834734)
		(end 307.014372 -82.834734)
		(stroke
			(width 0.04445)
			(type default)
		)
		(layer "F.Cu")
	)
	(gr_line
		(start 306.753006 -79.088488)
		(end 306.81549 -79.088488)
		(stroke
			(width 0.04445)
			(type default)
		)
		(layer "F.Cu")
	)
	(gr_line
		(start 306.77993 -74.56678)
		(end 306.803044 -74.704702)
		(stroke
			(width 0.04445)
			(type default)
		)
		(layer "F.Cu")
	)
	(gr_line
		(start 306.77993 -74.56678)
		(end 306.883054 -74.421746)
		(stroke
			(width 0.04445)
			(type default)
		)
		(layer "F.Cu")
	)
	(gr_line
		(start 306.781962 -101.3079)
		(end 306.970684 -101.496622)
		(stroke
			(width 0.04445)
			(type default)
		)
		(layer "F.Cu")
	)
	(gr_line
		(start 306.781962 -101.185472)
		(end 306.781962 -101.3079)
		(stroke
			(width 0.04445)
			(type default)
		)
		(layer "F.Cu")
	)
	(gr_line
		(start 306.790344 -92.654628)
		(end 306.886864 -92.751148)
		(stroke
			(width 0.04445)
			(type default)
		)
		(layer "F.Cu")
	)
	(gr_line
		(start 306.807616 -99.586288)
		(end 306.89042 -99.586288)
		(stroke
			(width 0.04445)
			(type default)
		)
		(layer "F.Cu")
	)
	(gr_line
		(start 306.819554 -77.039978)
		(end 306.88407 -77.104494)
		(stroke
			(width 0.04445)
			(type default)
		)
		(layer "F.Cu")
	)
	(gr_line
		(start 306.824126 -81.844134)
		(end 307.090826 -81.844134)
		(stroke
			(width 0.04445)
			(type default)
		)
		(layer "F.Cu")
	)
	(gr_line
		(start 306.83835 -76.306934)
		(end 306.866798 -76.28382)
		(stroke
			(width 0.04445)
			(type default)
		)
		(layer "F.Cu")
	)
	(gr_line
		(start 306.846224 -104.520492)
		(end 307.004466 -104.520492)
		(stroke
			(width 0.05715)
			(type default)
		)
		(layer "F.Cu")
	)
	(gr_line
		(start 306.851812 -82.555334)
		(end 306.910232 -82.555334)
		(stroke
			(width 0.04445)
			(type default)
		)
		(layer "F.Cu")
	)
	(gr_line
		(start 306.87391 -102.952296)
		(end 306.996338 -102.952296)
		(stroke
			(width 0.04445)
			(type default)
		)
		(layer "F.Cu")
	)
	(gr_line
		(start 306.883054 -74.421746)
		(end 307.020976 -74.398378)
		(stroke
			(width 0.04445)
			(type default)
		)
		(layer "F.Cu")
	)
	(gr_line
		(start 306.886864 -92.751148)
		(end 307.166264 -92.751148)
		(stroke
			(width 0.04445)
			(type default)
		)
		(layer "F.Cu")
	)
	(gr_line
		(start 306.890674 -109.759496)
		(end 307.043328 -110.080552)
		(stroke
			(width 0.05715)
			(type default)
		)
		(layer "F.Cu")
	)
	(gr_line
		(start 306.917598 -79.36992)
		(end 307.00599 -79.281528)
		(stroke
			(width 0.04445)
			(type default)
		)
		(layer "F.Cu")
	)
	(gr_line
		(start 306.91836 -78.095348)
		(end 307.016912 -77.996796)
		(stroke
			(width 0.04445)
			(type default)
		)
		(layer "F.Cu")
	)
	(gr_line
		(start 306.928266 -81.564734)
		(end 306.986686 -81.564734)
		(stroke
			(width 0.04445)
			(type default)
		)
		(layer "F.Cu")
	)
	(gr_line
		(start 306.940966 -91.816936)
		(end 306.963572 -91.731846)
		(stroke
			(width 0.04445)
			(type default)
		)
		(layer "F.Cu")
	)
	(gr_line
		(start 306.940966 -88.343486)
		(end 306.963572 -88.428576)
		(stroke
			(width 0.04445)
			(type default)
		)
		(layer "F.Cu")
	)
	(gr_line
		(start 306.946554 -108.660184)
		(end 307.00599 -108.71962)
		(stroke
			(width 0.05715)
			(type default)
		)
		(layer "F.Cu")
	)
	(gr_line
		(start 306.948332 -108.31703)
		(end 307.106828 -108.31703)
		(stroke
			(width 0.05715)
			(type default)
		)
		(layer "F.Cu")
	)
	(gr_line
		(start 306.95646 -102.639368)
		(end 306.998116 -102.681024)
		(stroke
			(width 0.04445)
			(type default)
		)
		(layer "F.Cu")
	)
	(gr_line
		(start 306.963572 -91.731846)
		(end 307.250846 -91.565984)
		(stroke
			(width 0.04445)
			(type default)
		)
		(layer "F.Cu")
	)
	(gr_line
		(start 306.963572 -88.428576)
		(end 307.250846 -88.594184)
		(stroke
			(width 0.04445)
			(type default)
		)
		(layer "F.Cu")
	)
	(gr_line
		(start 306.970684 -101.496622)
		(end 307.093112 -101.496622)
		(stroke
			(width 0.04445)
			(type default)
		)
		(layer "F.Cu")
	)
	(gr_line
		(start 306.976018 -74.794618)
		(end 307.161946 -74.533252)
		(stroke
			(width 0.04445)
			(type default)
		)
		(layer "F.Cu")
	)
	(gr_line
		(start 306.980844 -92.461588)
		(end 307.072284 -92.461588)
		(stroke
			(width 0.04445)
			(type default)
		)
		(layer "F.Cu")
	)
	(gr_line
		(start 306.982368 -99.294696)
		(end 307.08092 -99.393248)
		(stroke
			(width 0.04445)
			(type default)
		)
		(layer "F.Cu")
	)
	(gr_line
		(start 306.985416 -110.24362)
		(end 307.043328 -110.080552)
		(stroke
			(width 0.05715)
			(type default)
		)
		(layer "F.Cu")
	)
	(gr_line
		(start 307.004466 -104.520492)
		(end 307.247036 -104.763062)
		(stroke
			(width 0.05715)
			(type default)
		)
		(layer "F.Cu")
	)
	(gr_line
		(start 307.014372 -82.834734)
		(end 307.100732 -82.748374)
		(stroke
			(width 0.04445)
			(type default)
		)
		(layer "F.Cu")
	)
	(gr_line
		(start 307.016912 -77.996796)
		(end 307.194712 -77.996796)
		(stroke
			(width 0.04445)
			(type default)
		)
		(layer "F.Cu")
	)
	(gr_line
		(start 307.032914 -98.405188)
		(end 307.040534 -98.40849)
		(stroke
			(width 0.04445)
			(type default)
		)
		(layer "F.Cu")
	)
	(gr_line
		(start 307.043836 -96.39046)
		(end 307.140356 -96.29394)
		(stroke
			(width 0.04445)
			(type default)
		)
		(layer "F.Cu")
	)
	(gr_line
		(start 307.053234 -101.183694)
		(end 307.09489 -101.22535)
		(stroke
			(width 0.04445)
			(type default)
		)
		(layer "F.Cu")
	)
	(gr_line
		(start 307.054758 -80.068674)
		(end 307.141118 -80.155034)
		(stroke
			(width 0.04445)
			(type default)
		)
		(layer "F.Cu")
	)
	(gr_line
		(start 307.090826 -81.844134)
		(end 307.177186 -81.757774)
		(stroke
			(width 0.04445)
			(type default)
		)
		(layer "F.Cu")
	)
	(gr_line
		(start 307.103526 -74.11212)
		(end 307.12664 -74.250042)
		(stroke
			(width 0.04445)
			(type default)
		)
		(layer "F.Cu")
	)
	(gr_line
		(start 307.103526 -74.11212)
		(end 307.20665 -73.967086)
		(stroke
			(width 0.04445)
			(type default)
		)
		(layer "F.Cu")
	)
	(gr_line
		(start 307.106828 -108.31703)
		(end 307.349144 -108.5596)
		(stroke
			(width 0.05715)
			(type default)
		)
		(layer "F.Cu")
	)
	(gr_line
		(start 307.138832 -77.297534)
		(end 307.152548 -77.290422)
		(stroke
			(width 0.04445)
			(type default)
		)
		(layer "F.Cu")
	)
	(gr_line
		(start 307.140356 -96.29394)
		(end 307.419756 -96.29394)
		(stroke
			(width 0.04445)
			(type default)
		)
		(layer "F.Cu")
	)
	(gr_line
		(start 307.141118 -80.155034)
		(end 307.407818 -80.155034)
		(stroke
			(width 0.04445)
			(type default)
		)
		(layer "F.Cu")
	)
	(gr_line
		(start 307.166264 -92.751148)
		(end 307.262784 -92.654628)
		(stroke
			(width 0.04445)
			(type default)
		)
		(layer "F.Cu")
	)
	(gr_line
		(start 307.180742 -77.058012)
		(end 307.21808 -76.93914)
		(stroke
			(width 0.04445)
			(type default)
		)
		(layer "F.Cu")
	)
	(gr_line
		(start 307.188108 -103.266494)
		(end 307.37683 -103.455216)
		(stroke
			(width 0.04445)
			(type default)
		)
		(layer "F.Cu")
	)
	(gr_line
		(start 307.188108 -103.144066)
		(end 307.188108 -103.266494)
		(stroke
			(width 0.04445)
			(type default)
		)
		(layer "F.Cu")
	)
	(gr_line
		(start 307.194712 -77.996796)
		(end 307.293264 -78.095348)
		(stroke
			(width 0.04445)
			(type default)
		)
		(layer "F.Cu")
	)
	(gr_line
		(start 307.20665 -73.967086)
		(end 307.344572 -73.943972)
		(stroke
			(width 0.04445)
			(type default)
		)
		(layer "F.Cu")
	)
	(gr_line
		(start 307.21808 -76.93914)
		(end 307.455316 -76.815696)
		(stroke
			(width 0.04445)
			(type default)
		)
		(layer "F.Cu")
	)
	(gr_line
		(start 307.234336 -96.5835)
		(end 307.325776 -96.5835)
		(stroke
			(width 0.04445)
			(type default)
		)
		(layer "F.Cu")
	)
	(gr_line
		(start 307.245258 -79.875634)
		(end 307.303678 -79.875634)
		(stroke
			(width 0.04445)
			(type default)
		)
		(layer "F.Cu")
	)
	(gr_line
		(start 307.247036 -104.763062)
		(end 307.247036 -104.921304)
		(stroke
			(width 0.05715)
			(type default)
		)
		(layer "F.Cu")
	)
	(gr_line
		(start 307.250846 -86.612984)
		(end 307.57368 -86.29015)
		(stroke
			(width 0.05715)
			(type default)
		)
		(layer "F.Cu")
	)
	(gr_line
		(start 307.250846 -85.622384)
		(end 307.57368 -85.945218)
		(stroke
			(width 0.05715)
			(type default)
		)
		(layer "F.Cu")
	)
	(gr_line
		(start 307.252878 -98.702876)
		(end 307.607716 -98.849942)
		(stroke
			(width 0.04445)
			(type default)
		)
		(layer "F.Cu")
	)
	(gr_line
		(start 307.266594 -99.395788)
		(end 307.272182 -99.398328)
		(stroke
			(width 0.04445)
			(type default)
		)
		(layer "F.Cu")
	)
	(gr_line
		(start 307.27777 -79.281528)
		(end 307.366162 -79.36992)
		(stroke
			(width 0.04445)
			(type default)
		)
		(layer "F.Cu")
	)
	(gr_line
		(start 307.295042 -77.216)
		(end 307.638196 -77.037946)
		(stroke
			(width 0.04445)
			(type default)
		)
		(layer "F.Cu")
	)
	(gr_line
		(start 307.29936 -74.340466)
		(end 307.485796 -74.078592)
		(stroke
			(width 0.04445)
			(type default)
		)
		(layer "F.Cu")
	)
	(gr_line
		(start 307.301392 -98.514154)
		(end 307.414676 -98.467164)
		(stroke
			(width 0.04445)
			(type default)
		)
		(layer "F.Cu")
	)
	(gr_line
		(start 307.342794 -105.362248)
		(end 307.550312 -105.569766)
		(stroke
			(width 0.05715)
			(type default)
		)
		(layer "F.Cu")
	)
	(gr_line
		(start 307.343302 -80.50276)
		(end 307.429662 -80.4164)
		(stroke
			(width 0.04445)
			(type default)
		)
		(layer "F.Cu")
	)
	(gr_line
		(start 307.349144 -108.5596)
		(end 307.349144 -108.717842)
		(stroke
			(width 0.05715)
			(type default)
		)
		(layer "F.Cu")
	)
	(gr_line
		(start 307.366162 -79.36992)
		(end 307.632862 -79.36992)
		(stroke
			(width 0.04445)
			(type default)
		)
		(layer "F.Cu")
	)
	(gr_line
		(start 307.372512 -82.748374)
		(end 307.458872 -82.834734)
		(stroke
			(width 0.04445)
			(type default)
		)
		(layer "F.Cu")
	)
	(gr_line
		(start 307.37683 -103.455216)
		(end 307.499258 -103.455216)
		(stroke
			(width 0.04445)
			(type default)
		)
		(layer "F.Cu")
	)
	(gr_line
		(start 307.384704 -99.651058)
		(end 307.76164 -99.807268)
		(stroke
			(width 0.04445)
			(type default)
		)
		(layer "F.Cu")
	)
	(gr_line
		(start 307.407818 -80.155034)
		(end 307.494178 -80.068674)
		(stroke
			(width 0.04445)
			(type default)
		)
		(layer "F.Cu")
	)
	(gr_line
		(start 307.414676 -98.467164)
		(end 307.661056 -98.569272)
		(stroke
			(width 0.04445)
			(type default)
		)
		(layer "F.Cu")
	)
	(gr_line
		(start 307.419756 -96.29394)
		(end 307.516276 -96.39046)
		(stroke
			(width 0.04445)
			(type default)
		)
		(layer "F.Cu")
	)
	(gr_line
		(start 307.429662 -80.4164)
		(end 307.696362 -80.4164)
		(stroke
			(width 0.04445)
			(type default)
		)
		(layer "F.Cu")
	)
	(gr_line
		(start 307.431186 -107.329986)
		(end 307.490368 -107.389168)
		(stroke
			(width 0.05715)
			(type default)
		)
		(layer "F.Cu")
	)
	(gr_line
		(start 307.432964 -106.986832)
		(end 307.590952 -106.986832)
		(stroke
			(width 0.05715)
			(type default)
		)
		(layer "F.Cu")
	)
	(gr_line
		(start 307.432964 -99.462082)
		(end 307.560726 -99.408742)
		(stroke
			(width 0.04445)
			(type default)
		)
		(layer "F.Cu")
	)
	(gr_line
		(start 307.441854 -75.485244)
		(end 307.44795 -75.436984)
		(stroke
			(width 0.04445)
			(type default)
		)
		(layer "F.Cu")
	)
	(gr_line
		(start 307.448966 -81.757774)
		(end 307.535326 -81.844134)
		(stroke
			(width 0.04445)
			(type default)
		)
		(layer "F.Cu")
	)
	(gr_line
		(start 307.455316 -76.815696)
		(end 307.574188 -76.853542)
		(stroke
			(width 0.04445)
			(type default)
		)
		(layer "F.Cu")
	)
	(gr_line
		(start 307.458872 -82.834734)
		(end 307.725572 -82.834734)
		(stroke
			(width 0.04445)
			(type default)
		)
		(layer "F.Cu")
	)
	(gr_line
		(start 307.45938 -103.142288)
		(end 307.501036 -103.183944)
		(stroke
			(width 0.04445)
			(type default)
		)
		(layer "F.Cu")
	)
	(gr_line
		(start 307.46827 -79.088488)
		(end 307.530754 -79.088488)
		(stroke
			(width 0.04445)
			(type default)
		)
		(layer "F.Cu")
	)
	(gr_line
		(start 307.492908 -105.167176)
		(end 307.65115 -105.167176)
		(stroke
			(width 0.05715)
			(type default)
		)
		(layer "F.Cu")
	)
	(gr_line
		(start 307.512212 -91.96324)
		(end 307.608732 -91.86672)
		(stroke
			(width 0.04445)
			(type default)
		)
		(layer "F.Cu")
	)
	(gr_line
		(start 307.519324 -78.288388)
		(end 307.532278 -78.281784)
		(stroke
			(width 0.04445)
			(type default)
		)
		(layer "F.Cu")
	)
	(gr_line
		(start 307.533802 -80.6958)
		(end 307.592222 -80.6958)
		(stroke
			(width 0.04445)
			(type default)
		)
		(layer "F.Cu")
	)
	(gr_line
		(start 307.535326 -81.844134)
		(end 307.802026 -81.844134)
		(stroke
			(width 0.04445)
			(type default)
		)
		(layer "F.Cu")
	)
	(gr_line
		(start 307.560726 -99.408742)
		(end 307.80736 -99.511104)
		(stroke
			(width 0.04445)
			(type default)
		)
		(layer "F.Cu")
	)
	(gr_line
		(start 307.563012 -82.555334)
		(end 307.621432 -82.555334)
		(stroke
			(width 0.04445)
			(type default)
		)
		(layer "F.Cu")
	)
	(gr_line
		(start 307.590952 -106.986832)
		(end 307.833522 -107.229148)
		(stroke
			(width 0.05715)
			(type default)
		)
		(layer "F.Cu")
	)
	(gr_line
		(start 307.601112 -75.598528)
		(end 307.644546 -75.576938)
		(stroke
			(width 0.04445)
			(type default)
		)
		(layer "F.Cu")
	)
	(gr_line
		(start 307.608732 -91.86672)
		(end 307.888132 -91.86672)
		(stroke
			(width 0.04445)
			(type default)
		)
		(layer "F.Cu")
	)
	(gr_line
		(start 307.632862 -79.36992)
		(end 307.721254 -79.281528)
		(stroke
			(width 0.04445)
			(type default)
		)
		(layer "F.Cu")
	)
	(gr_line
		(start 307.639466 -81.564734)
		(end 307.697886 -81.564734)
		(stroke
			(width 0.04445)
			(type default)
		)
		(layer "F.Cu")
	)
	(gr_line
		(start 307.65115 -105.167176)
		(end 307.893466 -105.409492)
		(stroke
			(width 0.05715)
			(type default)
		)
		(layer "F.Cu")
	)
	(gr_line
		(start 307.661056 -98.569272)
		(end 307.707792 -98.682556)
		(stroke
			(width 0.04445)
			(type default)
		)
		(layer "F.Cu")
	)
	(gr_line
		(start 307.67782 -85.224874)
		(end 307.76418 -85.311234)
		(stroke
			(width 0.04445)
			(type default)
		)
		(layer "F.Cu")
	)
	(gr_line
		(start 307.682646 -73.468992)
		(end 307.688742 -73.420732)
		(stroke
			(width 0.04445)
			(type default)
		)
		(layer "F.Cu")
	)
	(gr_line
		(start 307.685948 -92.909644)
		(end 307.88356 -93.107256)
		(stroke
			(width 0.04445)
			(type default)
		)
		(layer "F.Cu")
	)
	(gr_line
		(start 307.685948 -92.773246)
		(end 307.685948 -92.909644)
		(stroke
			(width 0.04445)
			(type default)
		)
		(layer "F.Cu")
	)
	(gr_line
		(start 307.690774 -102.126542)
		(end 307.698902 -102.13467)
		(stroke
			(width 0.04445)
			(type default)
		)
		(layer "F.Cu")
	)
	(gr_line
		(start 307.690774 -102.090728)
		(end 307.690774 -102.126542)
		(stroke
			(width 0.04445)
			(type default)
		)
		(layer "F.Cu")
	)
	(gr_line
		(start 307.691028 -103.769414)
		(end 307.87975 -103.958136)
		(stroke
			(width 0.04445)
			(type default)
		)
		(layer "F.Cu")
	)
	(gr_line
		(start 307.691028 -103.646986)
		(end 307.691028 -103.769414)
		(stroke
			(width 0.04445)
			(type default)
		)
		(layer "F.Cu")
	)
	(gr_line
		(start 307.696362 -80.4164)
		(end 307.782722 -80.50276)
		(stroke
			(width 0.04445)
			(type default)
		)
		(layer "F.Cu")
	)
	(gr_line
		(start 307.702712 -92.15628)
		(end 307.794152 -92.15628)
		(stroke
			(width 0.04445)
			(type default)
		)
		(layer "F.Cu")
	)
	(gr_line
		(start 307.725572 -82.834734)
		(end 307.811932 -82.748374)
		(stroke
			(width 0.04445)
			(type default)
		)
		(layer "F.Cu")
	)
	(gr_line
		(start 307.733192 -88.200992)
		(end 307.819552 -88.287352)
		(stroke
			(width 0.04445)
			(type default)
		)
		(layer "F.Cu")
	)
	(gr_line
		(start 307.76418 -85.311234)
		(end 308.03088 -85.311234)
		(stroke
			(width 0.04445)
			(type default)
		)
		(layer "F.Cu")
	)
	(gr_line
		(start 307.790596 -76.53528)
		(end 307.808376 -76.637896)
		(stroke
			(width 0.04445)
			(type default)
		)
		(layer "F.Cu")
	)
	(gr_line
		(start 307.790596 -76.53528)
		(end 307.945536 -76.317602)
		(stroke
			(width 0.04445)
			(type default)
		)
		(layer "F.Cu")
	)
	(gr_line
		(start 307.802026 -81.844134)
		(end 307.888386 -81.757774)
		(stroke
			(width 0.04445)
			(type default)
		)
		(layer "F.Cu")
	)
	(gr_line
		(start 307.80736 -99.511104)
		(end 307.860192 -99.63912)
		(stroke
			(width 0.04445)
			(type default)
		)
		(layer "F.Cu")
	)
	(gr_line
		(start 307.81752 -76.944728)
		(end 307.832506 -76.936854)
		(stroke
			(width 0.04445)
			(type default)
		)
		(layer "F.Cu")
	)
	(gr_line
		(start 307.818028 -101.948488)
		(end 307.854096 -101.948488)
		(stroke
			(width 0.04445)
			(type default)
		)
		(layer "F.Cu")
	)
	(gr_line
		(start 307.819552 -88.287352)
		(end 308.086252 -88.287352)
		(stroke
			(width 0.04445)
			(type default)
		)
		(layer "F.Cu")
	)
	(gr_line
		(start 307.832506 -76.936854)
		(end 307.842158 -76.923392)
		(stroke
			(width 0.04445)
			(type default)
		)
		(layer "F.Cu")
	)
	(gr_line
		(start 307.833522 -107.229148)
		(end 307.833522 -107.38739)
		(stroke
			(width 0.05715)
			(type default)
		)
		(layer "F.Cu")
	)
	(gr_line
		(start 307.841904 -73.582276)
		(end 307.885338 -73.560686)
		(stroke
			(width 0.04445)
			(type default)
		)
		(layer "F.Cu")
	)
	(gr_line
		(start 307.854096 -101.948488)
		(end 307.86959 -101.963982)
		(stroke
			(width 0.04445)
			(type default)
		)
		(layer "F.Cu")
	)
	(gr_line
		(start 307.86832 -85.031834)
		(end 307.92674 -85.031834)
		(stroke
			(width 0.04445)
			(type default)
		)
		(layer "F.Cu")
	)
	(gr_line
		(start 307.87975 -103.958136)
		(end 308.002178 -103.958136)
		(stroke
			(width 0.04445)
			(type default)
		)
		(layer "F.Cu")
	)
	(gr_line
		(start 307.88356 -93.107256)
		(end 308.019958 -93.107256)
		(stroke
			(width 0.04445)
			(type default)
		)
		(layer "F.Cu")
	)
	(gr_line
		(start 307.888132 -91.86672)
		(end 307.984652 -91.96324)
		(stroke
			(width 0.04445)
			(type default)
		)
		(layer "F.Cu")
	)
	(gr_line
		(start 307.893466 -105.409492)
		(end 307.893466 -105.567988)
		(stroke
			(width 0.05715)
			(type default)
		)
		(layer "F.Cu")
	)
	(gr_line
		(start 307.904134 -79.278988)
		(end 307.91785 -79.271622)
		(stroke
			(width 0.04445)
			(type default)
		)
		(layer "F.Cu")
	)
	(gr_line
		(start 307.911246 -98.975672)
		(end 308.264814 -99.12223)
		(stroke
			(width 0.04445)
			(type default)
		)
		(layer "F.Cu")
	)
	(gr_line
		(start 307.923692 -88.007952)
		(end 307.982112 -88.007952)
		(stroke
			(width 0.04445)
			(type default)
		)
		(layer "F.Cu")
	)
	(gr_line
		(start 307.945536 -76.317602)
		(end 308.048406 -76.300838)
		(stroke
			(width 0.04445)
			(type default)
		)
		(layer "F.Cu")
	)
	(gr_line
		(start 307.95722 -92.771468)
		(end 308.021736 -92.835984)
		(stroke
			(width 0.04445)
			(type default)
		)
		(layer "F.Cu")
	)
	(gr_line
		(start 307.95849 -98.786442)
		(end 308.071774 -98.739452)
		(stroke
			(width 0.04445)
			(type default)
		)
		(layer "F.Cu")
	)
	(gr_line
		(start 307.9623 -103.645208)
		(end 308.003956 -103.686864)
		(stroke
			(width 0.04445)
			(type default)
		)
		(layer "F.Cu")
	)
	(gr_line
		(start 307.981858 -76.72705)
		(end 308.103778 -76.5556)
		(stroke
			(width 0.04445)
			(type default)
		)
		(layer "F.Cu")
	)
	(gr_line
		(start 308.022244 -109.394244)
		(end 308.02707 -109.39907)
		(stroke
			(width 0.05715)
			(type default)
		)
		(layer "F.Cu")
	)
	(gr_line
		(start 308.02707 -109.39907)
		(end 308.029864 -109.404912)
		(stroke
			(width 0.05715)
			(type default)
		)
		(layer "F.Cu")
	)
	(gr_line
		(start 308.03088 -85.311234)
		(end 308.11724 -85.224874)
		(stroke
			(width 0.04445)
			(type default)
		)
		(layer "F.Cu")
	)
	(gr_line
		(start 308.054502 -80.50276)
		(end 308.140862 -80.4164)
		(stroke
			(width 0.04445)
			(type default)
		)
		(layer "F.Cu")
	)
	(gr_line
		(start 308.05882 -99.723956)
		(end 308.065424 -99.72675)
		(stroke
			(width 0.04445)
			(type default)
		)
		(layer "F.Cu")
	)
	(gr_line
		(start 308.061868 -89.187274)
		(end 308.148228 -89.273634)
		(stroke
			(width 0.04445)
			(type default)
		)
		(layer "F.Cu")
	)
	(gr_line
		(start 308.067456 -90.177874)
		(end 308.163976 -90.274394)
		(stroke
			(width 0.04445)
			(type default)
		)
		(layer "F.Cu")
	)
	(gr_line
		(start 308.071774 -98.739452)
		(end 308.318154 -98.841814)
		(stroke
			(width 0.04445)
			(type default)
		)
		(layer "F.Cu")
	)
	(gr_line
		(start 308.086252 -88.287352)
		(end 308.172612 -88.200992)
		(stroke
			(width 0.04445)
			(type default)
		)
		(layer "F.Cu")
	)
	(gr_line
		(start 308.103778 -76.5556)
		(end 308.104032 -76.5556)
		(stroke
			(width 0.04445)
			(type default)
		)
		(layer "F.Cu")
	)
	(gr_line
		(start 308.104032 -76.5556)
		(end 308.189376 -76.435458)
		(stroke
			(width 0.04445)
			(type default)
		)
		(layer "F.Cu")
	)
	(gr_line
		(start 308.118256 -82.745834)
		(end 308.143656 -82.771234)
		(stroke
			(width 0.04445)
			(type default)
		)
		(layer "F.Cu")
	)
	(gr_line
		(start 308.118256 -82.555334)
		(end 308.143656 -82.529934)
		(stroke
			(width 0.04445)
			(type default)
		)
		(layer "F.Cu")
	)
	(gr_line
		(start 308.140862 -80.4164)
		(end 308.407562 -80.4164)
		(stroke
			(width 0.04445)
			(type default)
		)
		(layer "F.Cu")
	)
	(gr_line
		(start 308.143656 -82.529934)
		(end 308.165754 -82.529934)
		(stroke
			(width 0.04445)
			(type default)
		)
		(layer "F.Cu")
	)
	(gr_line
		(start 308.148228 -89.273634)
		(end 308.414928 -89.273634)
		(stroke
			(width 0.04445)
			(type default)
		)
		(layer "F.Cu")
	)
	(gr_line
		(start 308.160166 -81.757774)
		(end 308.246526 -81.844134)
		(stroke
			(width 0.04445)
			(type default)
		)
		(layer "F.Cu")
	)
	(gr_line
		(start 308.163976 -90.274394)
		(end 308.443376 -90.274394)
		(stroke
			(width 0.04445)
			(type default)
		)
		(layer "F.Cu")
	)
	(gr_line
		(start 308.17693 -76.120752)
		(end 308.177438 -76.07935)
		(stroke
			(width 0.04445)
			(type default)
		)
		(layer "F.Cu")
	)
	(gr_line
		(start 308.187598 -100.118418)
		(end 308.194202 -100.121212)
		(stroke
			(width 0.04445)
			(type default)
		)
		(layer "F.Cu")
	)
	(gr_line
		(start 308.245002 -80.6958)
		(end 308.303422 -80.6958)
		(stroke
			(width 0.04445)
			(type default)
		)
		(layer "F.Cu")
	)
	(gr_line
		(start 308.246526 -81.844134)
		(end 308.513226 -81.844134)
		(stroke
			(width 0.04445)
			(type default)
		)
		(layer "F.Cu")
	)
	(gr_line
		(start 308.252368 -88.994234)
		(end 308.310788 -88.994234)
		(stroke
			(width 0.04445)
			(type default)
		)
		(layer "F.Cu")
	)
	(gr_line
		(start 308.257956 -89.984834)
		(end 308.349396 -89.984834)
		(stroke
			(width 0.04445)
			(type default)
		)
		(layer "F.Cu")
	)
	(gr_line
		(start 308.269132 -91.96324)
		(end 308.365652 -91.86672)
		(stroke
			(width 0.04445)
			(type default)
		)
		(layer "F.Cu")
	)
	(gr_line
		(start 308.318154 -98.841814)
		(end 308.36489 -98.954844)
		(stroke
			(width 0.04445)
			(type default)
		)
		(layer "F.Cu")
	)
	(gr_line
		(start 308.3306 -76.241148)
		(end 308.374034 -76.219304)
		(stroke
			(width 0.04445)
			(type default)
		)
		(layer "F.Cu")
	)
	(gr_line
		(start 308.350666 -81.564734)
		(end 308.409086 -81.564734)
		(stroke
			(width 0.04445)
			(type default)
		)
		(layer "F.Cu")
	)
	(gr_line
		(start 308.356 -80.066134)
		(end 308.3814 -80.091534)
		(stroke
			(width 0.04445)
			(type default)
		)
		(layer "F.Cu")
	)
	(gr_line
		(start 308.356 -79.875634)
		(end 308.3814 -79.850234)
		(stroke
			(width 0.04445)
			(type default)
		)
		(layer "F.Cu")
	)
	(gr_line
		(start 308.357016 -104.34574)
		(end 308.37251 -104.361234)
		(stroke
			(width 0.04445)
			(type default)
		)
		(layer "F.Cu")
	)
	(gr_line
		(start 308.357016 -104.309672)
		(end 308.357016 -104.34574)
		(stroke
			(width 0.04445)
			(type default)
		)
		(layer "F.Cu")
	)
	(gr_line
		(start 308.365652 -91.86672)
		(end 308.645052 -91.86672)
		(stroke
			(width 0.04445)
			(type default)
		)
		(layer "F.Cu")
	)
	(gr_line
		(start 308.368954 -77.85735)
		(end 308.383178 -77.850238)
		(stroke
			(width 0.04445)
			(type default)
		)
		(layer "F.Cu")
	)
	(gr_line
		(start 308.375304 -85.031834)
		(end 308.400704 -85.006434)
		(stroke
			(width 0.04445)
			(type default)
		)
		(layer "F.Cu")
	)
	(gr_line
		(start 308.3814 -80.091534)
		(end 308.403498 -80.091534)
		(stroke
			(width 0.04445)
			(type default)
		)
		(layer "F.Cu")
	)
	(gr_line
		(start 308.3814 -79.850234)
		(end 308.403498 -79.850234)
		(stroke
			(width 0.04445)
			(type default)
		)
		(layer "F.Cu")
	)
	(gr_line
		(start 308.383178 -77.850238)
		(end 308.39283 -77.836776)
		(stroke
			(width 0.04445)
			(type default)
		)
		(layer "F.Cu")
	)
	(gr_line
		(start 308.38648 -85.222334)
		(end 308.41188 -85.247734)
		(stroke
			(width 0.04445)
			(type default)
		)
		(layer "F.Cu")
	)
	(gr_line
		(start 308.400704 -85.006434)
		(end 308.41188 -85.006434)
		(stroke
			(width 0.04445)
			(type default)
		)
		(layer "F.Cu")
	)
	(gr_line
		(start 308.407562 -80.4164)
		(end 308.493922 -80.50276)
		(stroke
			(width 0.04445)
			(type default)
		)
		(layer "F.Cu")
	)
	(gr_line
		(start 308.414928 -89.273634)
		(end 308.501288 -89.187274)
		(stroke
			(width 0.04445)
			(type default)
		)
		(layer "F.Cu")
	)
	(gr_line
		(start 308.443376 -90.274394)
		(end 308.539896 -90.177874)
		(stroke
			(width 0.04445)
			(type default)
		)
		(layer "F.Cu")
	)
	(gr_line
		(start 308.444392 -88.200992)
		(end 308.530752 -88.287352)
		(stroke
			(width 0.04445)
			(type default)
		)
		(layer "F.Cu")
	)
	(gr_line
		(start 308.459632 -92.15628)
		(end 308.551072 -92.15628)
		(stroke
			(width 0.04445)
			(type default)
		)
		(layer "F.Cu")
	)
	(gr_line
		(start 308.478174 -100.23856)
		(end 308.483762 -100.2411)
		(stroke
			(width 0.04445)
			(type default)
		)
		(layer "F.Cu")
	)
	(gr_line
		(start 308.492144 -104.175052)
		(end 308.527704 -104.175052)
		(stroke
			(width 0.04445)
			(type default)
		)
		(layer "F.Cu")
	)
	(gr_line
		(start 308.513226 -81.844134)
		(end 308.599586 -81.757774)
		(stroke
			(width 0.04445)
			(type default)
		)
		(layer "F.Cu")
	)
	(gr_line
		(start 308.518052 -77.329284)
		(end 308.51856 -77.287374)
		(stroke
			(width 0.04445)
			(type default)
		)
		(layer "F.Cu")
	)
	(gr_line
		(start 308.527704 -104.175052)
		(end 308.543198 -104.190546)
		(stroke
			(width 0.04445)
			(type default)
		)
		(layer "F.Cu")
	)
	(gr_line
		(start 308.530752 -88.287352)
		(end 308.797452 -88.287352)
		(stroke
			(width 0.04445)
			(type default)
		)
		(layer "F.Cu")
	)
	(gr_line
		(start 308.545484 -108.102908)
		(end 308.548278 -108.109004)
		(stroke
			(width 0.05715)
			(type default)
		)
		(layer "F.Cu")
	)
	(gr_line
		(start 308.56174 -95.034354)
		(end 308.65826 -94.937834)
		(stroke
			(width 0.04445)
			(type default)
		)
		(layer "F.Cu")
	)
	(gr_line
		(start 308.56809 -99.24796)
		(end 308.57444 -99.2505)
		(stroke
			(width 0.04445)
			(type default)
		)
		(layer "F.Cu")
	)
	(gr_line
		(start 308.61 -87.203534)
		(end 308.6354 -87.228934)
		(stroke
			(width 0.04445)
			(type default)
		)
		(layer "F.Cu")
	)
	(gr_line
		(start 308.61 -87.013034)
		(end 308.6354 -86.987634)
		(stroke
			(width 0.04445)
			(type default)
		)
		(layer "F.Cu")
	)
	(gr_line
		(start 308.634892 -88.007952)
		(end 308.693312 -88.007952)
		(stroke
			(width 0.04445)
			(type default)
		)
		(layer "F.Cu")
	)
	(gr_line
		(start 308.6354 -87.228934)
		(end 308.657498 -87.228934)
		(stroke
			(width 0.04445)
			(type default)
		)
		(layer "F.Cu")
	)
	(gr_line
		(start 308.645052 -91.86672)
		(end 308.741572 -91.96324)
		(stroke
			(width 0.04445)
			(type default)
		)
		(layer "F.Cu")
	)
	(gr_line
		(start 308.65826 -94.937834)
		(end 308.93766 -94.937834)
		(stroke
			(width 0.04445)
			(type default)
		)
		(layer "F.Cu")
	)
	(gr_line
		(start 308.67223 -77.448664)
		(end 308.715156 -77.427328)
		(stroke
			(width 0.04445)
			(type default)
		)
		(layer "F.Cu")
	)
	(gr_line
		(start 308.67604 -100.2411)
		(end 308.70144 -100.2665)
		(stroke
			(width 0.04445)
			(type default)
		)
		(layer "F.Cu")
	)
	(gr_line
		(start 308.67604 -100.0506)
		(end 308.70144 -100.0252)
		(stroke
			(width 0.04445)
			(type default)
		)
		(layer "F.Cu")
	)
	(gr_line
		(start 308.70144 -100.2665)
		(end 308.723538 -100.2665)
		(stroke
			(width 0.04445)
			(type default)
		)
		(layer "F.Cu")
	)
	(gr_line
		(start 308.70144 -100.0252)
		(end 308.723538 -100.0252)
		(stroke
			(width 0.04445)
			(type default)
		)
		(layer "F.Cu")
	)
	(gr_line
		(start 308.745636 -94.244668)
		(end 308.771036 -94.270068)
		(stroke
			(width 0.04445)
			(type default)
		)
		(layer "F.Cu")
	)
	(gr_line
		(start 308.745636 -94.054168)
		(end 308.771036 -94.028768)
		(stroke
			(width 0.04445)
			(type default)
		)
		(layer "F.Cu")
	)
	(gr_line
		(start 308.75224 -95.227394)
		(end 308.84368 -95.227394)
		(stroke
			(width 0.04445)
			(type default)
		)
		(layer "F.Cu")
	)
	(gr_line
		(start 308.764432 -97.149666)
		(end 308.789832 -97.175066)
		(stroke
			(width 0.04445)
			(type default)
		)
		(layer "F.Cu")
	)
	(gr_line
		(start 308.764432 -96.959166)
		(end 308.789832 -96.933766)
		(stroke
			(width 0.04445)
			(type default)
		)
		(layer "F.Cu")
	)
	(gr_line
		(start 308.771036 -94.270068)
		(end 308.793134 -94.270068)
		(stroke
			(width 0.04445)
			(type default)
		)
		(layer "F.Cu")
	)
	(gr_line
		(start 308.771036 -94.028768)
		(end 308.793134 -94.028768)
		(stroke
			(width 0.04445)
			(type default)
		)
		(layer "F.Cu")
	)
	(gr_line
		(start 308.773068 -89.187274)
		(end 308.859428 -89.273634)
		(stroke
			(width 0.04445)
			(type default)
		)
		(layer "F.Cu")
	)
	(gr_line
		(start 308.789832 -97.175066)
		(end 308.81193 -97.175066)
		(stroke
			(width 0.04445)
			(type default)
		)
		(layer "F.Cu")
	)
	(gr_line
		(start 308.789832 -96.933766)
		(end 308.81193 -96.933766)
		(stroke
			(width 0.04445)
			(type default)
		)
		(layer "F.Cu")
	)
	(gr_line
		(start 308.797452 -88.287352)
		(end 308.883812 -88.200992)
		(stroke
			(width 0.04445)
			(type default)
		)
		(layer "F.Cu")
	)
	(gr_line
		(start 308.824376 -90.177874)
		(end 308.920896 -90.274394)
		(stroke
			(width 0.04445)
			(type default)
		)
		(layer "F.Cu")
	)
	(gr_line
		(start 308.847998 -98.129598)
		(end 308.873398 -98.154998)
		(stroke
			(width 0.04445)
			(type default)
		)
		(layer "F.Cu")
	)
	(gr_line
		(start 308.847998 -97.939098)
		(end 308.873398 -97.913698)
		(stroke
			(width 0.04445)
			(type default)
		)
		(layer "F.Cu")
	)
	(gr_line
		(start 308.859428 -89.273634)
		(end 309.126128 -89.273634)
		(stroke
			(width 0.04445)
			(type default)
		)
		(layer "F.Cu")
	)
	(gr_line
		(start 308.868826 -81.755234)
		(end 308.894226 -81.780634)
		(stroke
			(width 0.04445)
			(type default)
		)
		(layer "F.Cu")
	)
	(gr_line
		(start 308.868826 -81.564734)
		(end 308.894226 -81.539334)
		(stroke
			(width 0.04445)
			(type default)
		)
		(layer "F.Cu")
	)
	(gr_line
		(start 308.873398 -98.154998)
		(end 308.895496 -98.154998)
		(stroke
			(width 0.04445)
			(type default)
		)
		(layer "F.Cu")
	)
	(gr_line
		(start 308.873398 -97.913698)
		(end 308.895496 -97.913698)
		(stroke
			(width 0.04445)
			(type default)
		)
		(layer "F.Cu")
	)
	(gr_line
		(start 308.894226 -81.780634)
		(end 308.916324 -81.780634)
		(stroke
			(width 0.04445)
			(type default)
		)
		(layer "F.Cu")
	)
	(gr_line
		(start 308.905656 -106.58348)
		(end 308.91099 -106.588814)
		(stroke
			(width 0.05715)
			(type default)
		)
		(layer "F.Cu")
	)
	(gr_line
		(start 308.91099 -106.588814)
		(end 308.914292 -106.595418)
		(stroke
			(width 0.05715)
			(type default)
		)
		(layer "F.Cu")
	)
	(gr_line
		(start 308.920896 -90.274394)
		(end 309.200296 -90.274394)
		(stroke
			(width 0.04445)
			(type default)
		)
		(layer "F.Cu")
	)
	(gr_line
		(start 308.93766 -94.937834)
		(end 309.03418 -95.034354)
		(stroke
			(width 0.04445)
			(type default)
		)
		(layer "F.Cu")
	)
	(gr_line
		(start 308.94147 -78.73238)
		(end 308.954678 -78.725522)
		(stroke
			(width 0.04445)
			(type default)
		)
		(layer "F.Cu")
	)
	(gr_line
		(start 308.954678 -78.725522)
		(end 308.963568 -78.713076)
		(stroke
			(width 0.04445)
			(type default)
		)
		(layer "F.Cu")
	)
	(gr_line
		(start 308.963568 -88.994234)
		(end 309.021988 -88.994234)
		(stroke
			(width 0.04445)
			(type default)
		)
		(layer "F.Cu")
	)
	(gr_line
		(start 308.978046 -105.113582)
		(end 309.20944 -105.56367)
		(stroke
			(width 0.05715)
			(type default)
		)
		(layer "F.Cu")
	)
	(gr_line
		(start 308.99354 -100.0252)
		(end 309.025544 -100.046536)
		(stroke
			(width 0.05715)
			(type default)
		)
		(layer "F.Cu")
	)
	(gr_line
		(start 308.999636 -78.329282)
		(end 309.005732 -78.280768)
		(stroke
			(width 0.04445)
			(type default)
		)
		(layer "F.Cu")
	)
	(gr_line
		(start 309.014876 -89.984834)
		(end 309.106316 -89.984834)
		(stroke
			(width 0.04445)
			(type default)
		)
		(layer "F.Cu")
	)
	(gr_line
		(start 309.020972 -104.66832)
		(end 309.022496 -104.671114)
		(stroke
			(width 0.05715)
			(type default)
		)
		(layer "F.Cu")
	)
	(gr_line
		(start 309.045356 -99.2505)
		(end 309.070756 -99.2759)
		(stroke
			(width 0.04445)
			(type default)
		)
		(layer "F.Cu")
	)
	(gr_line
		(start 309.045356 -99.06)
		(end 309.070756 -99.0346)
		(stroke
			(width 0.04445)
			(type default)
		)
		(layer "F.Cu")
	)
	(gr_line
		(start 309.054246 -85.247734)
		(end 309.075074 -85.237066)
		(stroke
			(width 0.05715)
			(type default)
		)
		(layer "F.Cu")
	)
	(gr_line
		(start 309.070756 -99.2759)
		(end 309.092854 -99.2759)
		(stroke
			(width 0.04445)
			(type default)
		)
		(layer "F.Cu")
	)
	(gr_line
		(start 309.070756 -99.0346)
		(end 309.092854 -99.0346)
		(stroke
			(width 0.04445)
			(type default)
		)
		(layer "F.Cu")
	)
	(gr_line
		(start 309.099204 -93.25864)
		(end 309.124604 -93.28404)
		(stroke
			(width 0.04445)
			(type default)
		)
		(layer "F.Cu")
	)
	(gr_line
		(start 309.099204 -93.06814)
		(end 309.124604 -93.04274)
		(stroke
			(width 0.04445)
			(type default)
		)
		(layer "F.Cu")
	)
	(gr_line
		(start 309.115968 -92.15628)
		(end 309.125112 -92.15628)
		(stroke
			(width 0.04445)
			(type default)
		)
		(layer "F.Cu")
	)
	(gr_line
		(start 309.124604 -93.28404)
		(end 309.146702 -93.28404)
		(stroke
			(width 0.04445)
			(type default)
		)
		(layer "F.Cu")
	)
	(gr_line
		(start 309.124604 -93.04274)
		(end 309.146702 -93.04274)
		(stroke
			(width 0.04445)
			(type default)
		)
		(layer "F.Cu")
	)
	(gr_line
		(start 309.126128 -89.273634)
		(end 309.212488 -89.187274)
		(stroke
			(width 0.04445)
			(type default)
		)
		(layer "F.Cu")
	)
	(gr_line
		(start 309.15229 -80.5053)
		(end 309.17769 -80.4799)
		(stroke
			(width 0.04445)
			(type default)
		)
		(layer "F.Cu")
	)
	(gr_line
		(start 309.153052 -88.198452)
		(end 309.178452 -88.223852)
		(stroke
			(width 0.04445)
			(type default)
		)
		(layer "F.Cu")
	)
	(gr_line
		(start 309.153052 -88.007952)
		(end 309.178452 -87.982552)
		(stroke
			(width 0.04445)
			(type default)
		)
		(layer "F.Cu")
	)
	(gr_line
		(start 309.159148 -78.442312)
		(end 309.202328 -78.420722)
		(stroke
			(width 0.04445)
			(type default)
		)
		(layer "F.Cu")
	)
	(gr_line
		(start 309.162958 -91.285314)
		(end 309.188358 -91.310714)
		(stroke
			(width 0.04445)
			(type default)
		)
		(layer "F.Cu")
	)
	(gr_line
		(start 309.162958 -91.094814)
		(end 309.188358 -91.069414)
		(stroke
			(width 0.04445)
			(type default)
		)
		(layer "F.Cu")
	)
	(gr_line
		(start 309.174388 -80.6958)
		(end 309.199788 -80.7212)
		(stroke
			(width 0.04445)
			(type default)
		)
		(layer "F.Cu")
	)
	(gr_line
		(start 309.17769 -80.4799)
		(end 309.199788 -80.4799)
		(stroke
			(width 0.04445)
			(type default)
		)
		(layer "F.Cu")
	)
	(gr_line
		(start 309.178452 -88.223852)
		(end 309.20055 -88.223852)
		(stroke
			(width 0.04445)
			(type default)
		)
		(layer "F.Cu")
	)
	(gr_line
		(start 309.178452 -87.982552)
		(end 309.20055 -87.982552)
		(stroke
			(width 0.04445)
			(type default)
		)
		(layer "F.Cu")
	)
	(gr_line
		(start 309.180738 -104.97439)
		(end 309.331614 -105.02265)
		(stroke
			(width 0.05715)
			(type default)
		)
		(layer "F.Cu")
	)
	(gr_line
		(start 309.188358 -91.310714)
		(end 309.210456 -91.310714)
		(stroke
			(width 0.04445)
			(type default)
		)
		(layer "F.Cu")
	)
	(gr_line
		(start 309.188358 -91.069414)
		(end 309.210456 -91.069414)
		(stroke
			(width 0.04445)
			(type default)
		)
		(layer "F.Cu")
	)
	(gr_line
		(start 309.192422 -100.158296)
		(end 309.217314 -100.174806)
		(stroke
			(width 0.05715)
			(type default)
		)
		(layer "F.Cu")
	)
	(gr_line
		(start 309.200296 -90.274394)
		(end 309.296816 -90.177874)
		(stroke
			(width 0.04445)
			(type default)
		)
		(layer "F.Cu")
	)
	(gr_line
		(start 309.217314 -100.174806)
		(end 309.230776 -100.202492)
		(stroke
			(width 0.05715)
			(type default)
		)
		(layer "F.Cu")
	)
	(gr_line
		(start 309.251096 -86.238334)
		(end 309.271924 -86.227666)
		(stroke
			(width 0.05715)
			(type default)
		)
		(layer "F.Cu")
	)
	(gr_line
		(start 309.262272 -96.182688)
		(end 309.287672 -96.208088)
		(stroke
			(width 0.04445)
			(type default)
		)
		(layer "F.Cu")
	)
	(gr_line
		(start 309.262272 -95.992188)
		(end 309.287672 -95.966788)
		(stroke
			(width 0.04445)
			(type default)
		)
		(layer "F.Cu")
	)
	(gr_line
		(start 309.287672 -96.208088)
		(end 309.30977 -96.208088)
		(stroke
			(width 0.04445)
			(type default)
		)
		(layer "F.Cu")
	)
	(gr_line
		(start 309.287672 -95.966788)
		(end 309.30977 -95.966788)
		(stroke
			(width 0.04445)
			(type default)
		)
		(layer "F.Cu")
	)
	(gr_line
		(start 309.306468 -92.068142)
		(end 309.315612 -92.068142)
		(stroke
			(width 0.04445)
			(type default)
		)
		(layer "F.Cu")
	)
	(gr_line
		(start 309.31866 -95.034354)
		(end 309.41518 -94.937834)
		(stroke
			(width 0.04445)
			(type default)
		)
		(layer "F.Cu")
	)
	(gr_line
		(start 309.331614 -105.02265)
		(end 309.488332 -105.327704)
		(stroke
			(width 0.05715)
			(type default)
		)
		(layer "F.Cu")
	)
	(gr_line
		(start 309.41518 -94.937834)
		(end 309.69458 -94.937834)
		(stroke
			(width 0.04445)
			(type default)
		)
		(layer "F.Cu")
	)
	(gr_line
		(start 309.422546 -80.7212)
		(end 309.456328 -80.696816)
		(stroke
			(width 0.05715)
			(type default)
		)
		(layer "F.Cu")
	)
	(gr_line
		(start 309.433468 -87.228934)
		(end 309.45328 -87.218774)
		(stroke
			(width 0.05715)
			(type default)
		)
		(layer "F.Cu")
	)
	(gr_line
		(start 309.438802 -81.780634)
		(end 309.45963 -81.769966)
		(stroke
			(width 0.05715)
			(type default)
		)
		(layer "F.Cu")
	)
	(gr_line
		(start 309.440072 -105.47858)
		(end 309.488332 -105.327704)
		(stroke
			(width 0.05715)
			(type default)
		)
		(layer "F.Cu")
	)
	(gr_line
		(start 309.448708 -99.0346)
		(end 309.480712 -99.055936)
		(stroke
			(width 0.05715)
			(type default)
		)
		(layer "F.Cu")
	)
	(gr_line
		(start 309.484268 -89.187274)
		(end 309.570628 -89.273634)
		(stroke
			(width 0.04445)
			(type default)
		)
		(layer "F.Cu")
	)
	(gr_line
		(start 309.50916 -95.227394)
		(end 309.6006 -95.227394)
		(stroke
			(width 0.04445)
			(type default)
		)
		(layer "F.Cu")
	)
	(gr_line
		(start 309.570628 -89.273634)
		(end 309.837328 -89.273634)
		(stroke
			(width 0.04445)
			(type default)
		)
		(layer "F.Cu")
	)
	(gr_line
		(start 309.61711 -97.913698)
		(end 309.631588 -97.920048)
		(stroke
			(width 0.05715)
			(type default)
		)
		(layer "F.Cu")
	)
	(gr_line
		(start 309.63997 -82.771234)
		(end 309.660798 -82.760566)
		(stroke
			(width 0.05715)
			(type default)
		)
		(layer "F.Cu")
	)
	(gr_line
		(start 309.674768 -88.994234)
		(end 309.733188 -88.994234)
		(stroke
			(width 0.04445)
			(type default)
		)
		(layer "F.Cu")
	)
	(gr_line
		(start 309.688738 -88.223852)
		(end 309.709566 -88.213184)
		(stroke
			(width 0.05715)
			(type default)
		)
		(layer "F.Cu")
	)
	(gr_line
		(start 309.69458 -94.937834)
		(end 309.7911 -95.034354)
		(stroke
			(width 0.04445)
			(type default)
		)
		(layer "F.Cu")
	)
	(gr_line
		(start 309.695088 -90.175334)
		(end 309.720488 -90.200734)
		(stroke
			(width 0.04445)
			(type default)
		)
		(layer "F.Cu")
	)
	(gr_line
		(start 309.695088 -89.984834)
		(end 309.720488 -89.959434)
		(stroke
			(width 0.04445)
			(type default)
		)
		(layer "F.Cu")
	)
	(gr_line
		(start 309.720488 -90.200734)
		(end 309.742586 -90.200734)
		(stroke
			(width 0.04445)
			(type default)
		)
		(layer "F.Cu")
	)
	(gr_line
		(start 309.720488 -89.959434)
		(end 309.742586 -89.959434)
		(stroke
			(width 0.04445)
			(type default)
		)
		(layer "F.Cu")
	)
	(gr_line
		(start 309.837328 -89.273634)
		(end 309.923688 -89.187274)
		(stroke
			(width 0.04445)
			(type default)
		)
		(layer "F.Cu")
	)
	(gr_line
		(start 309.83809 -83.7565)
		(end 309.858918 -83.745832)
		(stroke
			(width 0.05715)
			(type default)
		)
		(layer "F.Cu")
	)
	(gr_line
		(start 309.912766 -92.258642)
		(end 309.938166 -92.284042)
		(stroke
			(width 0.04445)
			(type default)
		)
		(layer "F.Cu")
	)
	(gr_line
		(start 309.912766 -92.068142)
		(end 309.938166 -92.042742)
		(stroke
			(width 0.04445)
			(type default)
		)
		(layer "F.Cu")
	)
	(gr_line
		(start 309.932578 -96.933766)
		(end 309.947056 -96.940116)
		(stroke
			(width 0.05715)
			(type default)
		)
		(layer "F.Cu")
	)
	(gr_line
		(start 309.938166 -92.284042)
		(end 309.960264 -92.284042)
		(stroke
			(width 0.04445)
			(type default)
		)
		(layer "F.Cu")
	)
	(gr_line
		(start 309.938166 -92.042742)
		(end 309.960264 -92.042742)
		(stroke
			(width 0.04445)
			(type default)
		)
		(layer "F.Cu")
	)
	(gr_line
		(start 310.030876 -104.125522)
		(end 310.036464 -104.13111)
		(stroke
			(width 0.05715)
			(type default)
		)
		(layer "F.Cu")
	)
	(gr_line
		(start 310.036464 -104.13111)
		(end 310.039766 -104.137968)
		(stroke
			(width 0.05715)
			(type default)
		)
		(layer "F.Cu")
	)
	(gr_line
		(start 310.073548 -89.184734)
		(end 310.085994 -89.178638)
		(stroke
			(width 0.04445)
			(type default)
		)
		(layer "F.Cu")
	)
	(gr_line
		(start 310.104282 -99.473004)
		(end 310.132984 -99.492308)
		(stroke
			(width 0.05715)
			(type default)
		)
		(layer "F.Cu")
	)
	(gr_line
		(start 310.132984 -99.492308)
		(end 310.147462 -99.523804)
		(stroke
			(width 0.05715)
			(type default)
		)
		(layer "F.Cu")
	)
	(gr_line
		(start 310.18988 -95.966788)
		(end 310.204358 -95.973138)
		(stroke
			(width 0.05715)
			(type default)
		)
		(layer "F.Cu")
	)
	(gr_line
		(start 310.196992 -88.907874)
		(end 310.207152 -88.876886)
		(stroke
			(width 0.04445)
			(type default)
		)
		(layer "F.Cu")
	)
	(gr_line
		(start 310.207152 -88.876886)
		(end 310.226964 -88.867234)
		(stroke
			(width 0.04445)
			(type default)
		)
		(layer "F.Cu")
	)
	(gr_line
		(start 310.284114 -89.082626)
		(end 310.314594 -89.09304)
		(stroke
			(width 0.04445)
			(type default)
		)
		(layer "F.Cu")
	)
	(gr_line
		(start 310.286908 -95.227394)
		(end 310.312308 -95.252794)
		(stroke
			(width 0.04445)
			(type default)
		)
		(layer "F.Cu")
	)
	(gr_line
		(start 310.286908 -95.036894)
		(end 310.312308 -95.011494)
		(stroke
			(width 0.04445)
			(type default)
		)
		(layer "F.Cu")
	)
	(gr_line
		(start 310.312308 -95.252794)
		(end 310.334406 -95.252794)
		(stroke
			(width 0.04445)
			(type default)
		)
		(layer "F.Cu")
	)
	(gr_line
		(start 310.312308 -95.011494)
		(end 310.334406 -95.011494)
		(stroke
			(width 0.04445)
			(type default)
		)
		(layer "F.Cu")
	)
	(gr_line
		(start 310.314594 -89.09304)
		(end 310.334406 -89.083388)
		(stroke
			(width 0.04445)
			(type default)
		)
		(layer "F.Cu")
	)
	(gr_line
		(start 310.34101 -90.200734)
		(end 310.360314 -90.191082)
		(stroke
			(width 0.05715)
			(type default)
		)
		(layer "F.Cu")
	)
	(gr_line
		(start 310.698134 -118.621556)
		(end 310.706008 -118.63832)
		(stroke
			(width 0.05715)
			(type default)
		)
		(layer "F.Cu")
	)
	(gr_line
		(start 310.706008 -118.63832)
		(end 310.720486 -118.650766)
		(stroke
			(width 0.05715)
			(type default)
		)
		(layer "F.Cu")
	)
	(gr_line
		(start 310.79948 -98.43262)
		(end 310.849518 -98.454718)
		(stroke
			(width 0.05715)
			(type default)
		)
		(layer "F.Cu")
	)
	(gr_line
		(start 310.849518 -98.454718)
		(end 310.873648 -98.503994)
		(stroke
			(width 0.05715)
			(type default)
		)
		(layer "F.Cu")
	)
	(gr_line
		(start 311.307226 -105.01503)
		(end 311.32018 -105.041446)
		(stroke
			(width 0.05715)
			(type default)
		)
		(layer "F.Cu")
	)
	(gr_line
		(start 311.32018 -105.041446)
		(end 311.34431 -105.05821)
		(stroke
			(width 0.05715)
			(type default)
		)
		(layer "F.Cu")
	)
	(gr_line
		(start 311.538112 -97.638362)
		(end 311.58815 -97.66046)
		(stroke
			(width 0.05715)
			(type default)
		)
		(layer "F.Cu")
	)
	(gr_line
		(start 311.560464 -91.310714)
		(end 311.582308 -91.29903)
		(stroke
			(width 0.05715)
			(type default)
		)
		(layer "F.Cu")
	)
	(gr_line
		(start 311.58815 -97.66046)
		(end 311.61228 -97.709736)
		(stroke
			(width 0.05715)
			(type default)
		)
		(layer "F.Cu")
	)
	(gr_line
		(start 311.602374 -105.240074)
		(end 311.630568 -105.39603)
		(stroke
			(width 0.05715)
			(type default)
		)
		(layer "F.Cu")
	)
	(gr_line
		(start 311.630568 -105.39603)
		(end 311.912254 -105.59161)
		(stroke
			(width 0.05715)
			(type default)
		)
		(layer "F.Cu")
	)
	(gr_line
		(start 311.767728 -105.058464)
		(end 312.179462 -105.344468)
		(stroke
			(width 0.05715)
			(type default)
		)
		(layer "F.Cu")
	)
	(gr_line
		(start 311.912254 -105.59161)
		(end 312.06821 -105.563416)
		(stroke
			(width 0.05715)
			(type default)
		)
		(layer "F.Cu")
	)
	(gr_line
		(start 312.065924 -104.309926)
		(end 312.078878 -104.33812)
		(stroke
			(width 0.05715)
			(type default)
		)
		(layer "F.Cu")
	)
	(gr_line
		(start 312.078878 -104.33812)
		(end 312.104278 -104.3559)
		(stroke
			(width 0.05715)
			(type default)
		)
		(layer "F.Cu")
	)
	(gr_line
		(start 312.08726 -92.284042)
		(end 312.108596 -92.27312)
		(stroke
			(width 0.05715)
			(type default)
		)
		(layer "F.Cu")
	)
	(gr_line
		(start 312.117486 -118.48973)
		(end 312.128154 -118.511828)
		(stroke
			(width 0.05715)
			(type default)
		)
		(layer "F.Cu")
	)
	(gr_line
		(start 312.128154 -118.511828)
		(end 312.147458 -118.526306)
		(stroke
			(width 0.05715)
			(type default)
		)
		(layer "F.Cu")
	)
	(gr_line
		(start 312.2168 -109.278166)
		(end 312.231278 -109.308646)
		(stroke
			(width 0.05715)
			(type default)
		)
		(layer "F.Cu")
	)
	(gr_line
		(start 312.231278 -109.308646)
		(end 312.259472 -109.327442)
		(stroke
			(width 0.05715)
			(type default)
		)
		(layer "F.Cu")
	)
	(gr_line
		(start 312.264806 -96.877632)
		(end 312.314844 -96.89973)
		(stroke
			(width 0.05715)
			(type default)
		)
		(layer "F.Cu")
	)
	(gr_line
		(start 312.314844 -96.89973)
		(end 312.338974 -96.949006)
		(stroke
			(width 0.05715)
			(type default)
		)
		(layer "F.Cu")
	)
	(gr_line
		(start 312.353452 -105.761536)
		(end 312.381646 -105.917492)
		(stroke
			(width 0.05715)
			(type default)
		)
		(layer "F.Cu")
	)
	(gr_line
		(start 312.36031 -78.621636)
		(end 312.365136 -78.618334)
		(stroke
			(width 0.05715)
			(type default)
		)
		(layer "F.Cu")
	)
	(gr_line
		(start 312.365136 -78.618334)
		(end 312.368438 -78.613508)
		(stroke
			(width 0.05715)
			(type default)
		)
		(layer "F.Cu")
	)
	(gr_line
		(start 312.381646 -105.917492)
		(end 312.663332 -106.113072)
		(stroke
			(width 0.05715)
			(type default)
		)
		(layer "F.Cu")
	)
	(gr_line
		(start 312.520076 -105.580942)
		(end 312.930032 -105.865676)
		(stroke
			(width 0.05715)
			(type default)
		)
		(layer "F.Cu")
	)
	(gr_line
		(start 312.561224 -80.173068)
		(end 312.583322 -80.161638)
		(stroke
			(width 0.05715)
			(type default)
		)
		(layer "F.Cu")
	)
	(gr_line
		(start 312.576464 -93.28404)
		(end 312.597038 -93.273626)
		(stroke
			(width 0.05715)
			(type default)
		)
		(layer "F.Cu")
	)
	(gr_line
		(start 312.583322 -80.161384)
		(end 312.583322 -80.161638)
		(stroke
			(width 0.05715)
			(type default)
		)
		(layer "F.Cu")
	)
	(gr_line
		(start 312.583322 -80.161384)
		(end 312.596784 -80.142334)
		(stroke
			(width 0.05715)
			(type default)
		)
		(layer "F.Cu")
	)
	(gr_line
		(start 312.599578 -117.18036)
		(end 312.606182 -117.191282)
		(stroke
			(width 0.05715)
			(type default)
		)
		(layer "F.Cu")
	)
	(gr_line
		(start 312.606182 -117.191282)
		(end 312.617358 -117.199918)
		(stroke
			(width 0.05715)
			(type default)
		)
		(layer "F.Cu")
	)
	(gr_line
		(start 312.663332 -106.113072)
		(end 312.819288 -106.084878)
		(stroke
			(width 0.05715)
			(type default)
		)
		(layer "F.Cu")
	)
	(gr_line
		(start 312.837576 -94.270068)
		(end 312.85815 -94.259654)
		(stroke
			(width 0.05715)
			(type default)
		)
		(layer "F.Cu")
	)
	(gr_line
		(start 312.859166 -66.174112)
		(end 312.864246 -66.167)
		(stroke
			(width 0.05715)
			(type default)
		)
		(layer "F.Cu")
	)
	(gr_line
		(start 312.864246 -66.167)
		(end 312.871104 -66.162174)
		(stroke
			(width 0.05715)
			(type default)
		)
		(layer "F.Cu")
	)
	(gr_line
		(start 313.092338 -95.252794)
		(end 313.113166 -95.242126)
		(stroke
			(width 0.05715)
			(type default)
		)
		(layer "F.Cu")
	)
	(gr_line
		(start 313.10453 -106.282998)
		(end 313.132724 -106.438954)
		(stroke
			(width 0.05715)
			(type default)
		)
		(layer "F.Cu")
	)
	(gr_line
		(start 313.108086 -103.63962)
		(end 313.119262 -103.662734)
		(stroke
			(width 0.05715)
			(type default)
		)
		(layer "F.Cu")
	)
	(gr_line
		(start 313.119262 -103.662734)
		(end 313.140344 -103.67772)
		(stroke
			(width 0.05715)
			(type default)
		)
		(layer "F.Cu")
	)
	(gr_line
		(start 313.132724 -106.438954)
		(end 313.41441 -106.634534)
		(stroke
			(width 0.05715)
			(type default)
		)
		(layer "F.Cu")
	)
	(gr_line
		(start 313.24931 -116.126006)
		(end 313.262518 -116.153438)
		(stroke
			(width 0.05715)
			(type default)
		)
		(layer "F.Cu")
	)
	(gr_line
		(start 313.262518 -116.153438)
		(end 313.28741 -116.169948)
		(stroke
			(width 0.05715)
			(type default)
		)
		(layer "F.Cu")
	)
	(gr_line
		(start 313.270646 -106.101896)
		(end 313.68238 -106.387646)
		(stroke
			(width 0.05715)
			(type default)
		)
		(layer "F.Cu")
	)
	(gr_line
		(start 313.34964 -113.617756)
		(end 313.363356 -113.644426)
		(stroke
			(width 0.05715)
			(type default)
		)
		(layer "F.Cu")
	)
	(gr_line
		(start 313.363356 -113.644426)
		(end 313.390026 -113.662206)
		(stroke
			(width 0.05715)
			(type default)
		)
		(layer "F.Cu")
	)
	(gr_line
		(start 313.41441 -106.634534)
		(end 313.570366 -106.60634)
		(stroke
			(width 0.05715)
			(type default)
		)
		(layer "F.Cu")
	)
	(gr_line
		(start 313.545982 -66.888106)
		(end 313.551824 -66.879978)
		(stroke
			(width 0.05715)
			(type default)
		)
		(layer "F.Cu")
	)
	(gr_line
		(start 313.551824 -66.879978)
		(end 313.552078 -66.879978)
		(stroke
			(width 0.05715)
			(type default)
		)
		(layer "F.Cu")
	)
	(gr_line
		(start 313.552078 -66.879978)
		(end 313.558682 -66.875406)
		(stroke
			(width 0.05715)
			(type default)
		)
		(layer "F.Cu")
	)
	(gr_line
		(start 313.634628 -80.713072)
		(end 313.655202 -80.702404)
		(stroke
			(width 0.05715)
			(type default)
		)
		(layer "F.Cu")
	)
	(gr_line
		(start 313.655202 -80.702404)
		(end 313.668664 -80.683354)
		(stroke
			(width 0.05715)
			(type default)
		)
		(layer "F.Cu")
	)
	(gr_line
		(start 313.94019 -103.036624)
		(end 313.951366 -103.059738)
		(stroke
			(width 0.05715)
			(type default)
		)
		(layer "F.Cu")
	)
	(gr_line
		(start 313.951366 -103.059738)
		(end 313.972448 -103.074724)
		(stroke
			(width 0.05715)
			(type default)
		)
		(layer "F.Cu")
	)
	(gr_line
		(start 314.217812 -67.611498)
		(end 314.222892 -67.604386)
		(stroke
			(width 0.05715)
			(type default)
		)
		(layer "F.Cu")
	)
	(gr_line
		(start 314.222892 -67.604386)
		(end 314.229496 -67.599814)
		(stroke
			(width 0.05715)
			(type default)
		)
		(layer "F.Cu")
	)
	(gr_line
		(start 314.287154 -81.464658)
		(end 314.307728 -81.45399)
		(stroke
			(width 0.05715)
			(type default)
		)
		(layer "F.Cu")
	)
	(gr_line
		(start 314.307728 -81.45399)
		(end 314.32119 -81.43494)
		(stroke
			(width 0.05715)
			(type default)
		)
		(layer "F.Cu")
	)
	(gr_line
		(start 314.722764 -102.392734)
		(end 314.73394 -102.415848)
		(stroke
			(width 0.05715)
			(type default)
		)
		(layer "F.Cu")
	)
	(gr_line
		(start 314.73394 -102.415848)
		(end 314.755022 -102.430834)
		(stroke
			(width 0.05715)
			(type default)
		)
		(layer "F.Cu")
	)
	(gr_line
		(start 314.917074 -68.316856)
		(end 314.922154 -68.309744)
		(stroke
			(width 0.05715)
			(type default)
		)
		(layer "F.Cu")
	)
	(gr_line
		(start 314.922154 -68.309744)
		(end 314.928758 -68.305172)
		(stroke
			(width 0.05715)
			(type default)
		)
		(layer "F.Cu")
	)
	(gr_line
		(start 315.167772 -105.134664)
		(end 315.176408 -105.14076)
		(stroke
			(width 0.05715)
			(type default)
		)
		(layer "F.Cu")
	)
	(gr_line
		(start 315.176408 -105.14076)
		(end 315.186568 -105.143554)
		(stroke
			(width 0.05715)
			(type default)
		)
		(layer "F.Cu")
	)
	(gr_line
		(start 315.198506 -82.08264)
		(end 315.220604 -82.07121)
		(stroke
			(width 0.05715)
			(type default)
		)
		(layer "F.Cu")
	)
	(gr_line
		(start 315.220604 -82.07121)
		(end 315.234828 -82.05089)
		(stroke
			(width 0.05715)
			(type default)
		)
		(layer "F.Cu")
	)
	(gr_line
		(start 315.414152 -111.427006)
		(end 315.835792 -111.707676)
		(stroke
			(width 0.05715)
			(type default)
		)
		(layer "F.Cu")
	)
	(gr_line
		(start 315.518038 -104.185974)
		(end 315.525912 -104.191562)
		(stroke
			(width 0.05715)
			(type default)
		)
		(layer "F.Cu")
	)
	(gr_line
		(start 315.523626 -111.207042)
		(end 315.679074 -111.1758)
		(stroke
			(width 0.05715)
			(type default)
		)
		(layer "F.Cu")
	)
	(gr_line
		(start 315.525912 -104.191562)
		(end 315.53531 -104.194102)
		(stroke
			(width 0.05715)
			(type default)
		)
		(layer "F.Cu")
	)
	(gr_line
		(start 315.602366 -69.031358)
		(end 315.607446 -69.024246)
		(stroke
			(width 0.05715)
			(type default)
		)
		(layer "F.Cu")
	)
	(gr_line
		(start 315.607446 -69.024246)
		(end 315.61405 -69.019674)
		(stroke
			(width 0.05715)
			(type default)
		)
		(layer "F.Cu")
	)
	(gr_line
		(start 315.679074 -111.1758)
		(end 315.96457 -111.365792)
		(stroke
			(width 0.05715)
			(type default)
		)
		(layer "F.Cu")
	)
	(gr_line
		(start 315.914024 -123.079002)
		(end 315.9252 -123.0884)
		(stroke
			(width 0.05715)
			(type default)
		)
		(layer "F.Cu")
	)
	(gr_line
		(start 315.9252 -123.0884)
		(end 315.93917 -123.092972)
		(stroke
			(width 0.05715)
			(type default)
		)
		(layer "F.Cu")
	)
	(gr_line
		(start 315.946028 -103.28656)
		(end 315.953902 -103.292148)
		(stroke
			(width 0.05715)
			(type default)
		)
		(layer "F.Cu")
	)
	(gr_line
		(start 315.953902 -103.292148)
		(end 315.9633 -103.294688)
		(stroke
			(width 0.05715)
			(type default)
		)
		(layer "F.Cu")
	)
	(gr_line
		(start 315.96457 -111.365792)
		(end 315.996066 -111.52124)
		(stroke
			(width 0.05715)
			(type default)
		)
		(layer "F.Cu")
	)
	(gr_line
		(start 315.978794 -82.771742)
		(end 316.002162 -82.759804)
		(stroke
			(width 0.05715)
			(type default)
		)
		(layer "F.Cu")
	)
	(gr_line
		(start 316.002162 -82.759804)
		(end 316.017656 -82.737706)
		(stroke
			(width 0.05715)
			(type default)
		)
		(layer "F.Cu")
	)
	(gr_line
		(start 316.175898 -111.93399)
		(end 316.596776 -112.214152)
		(stroke
			(width 0.05715)
			(type default)
		)
		(layer "F.Cu")
	)
	(gr_line
		(start 316.284864 -111.713772)
		(end 316.440312 -111.68253)
		(stroke
			(width 0.05715)
			(type default)
		)
		(layer "F.Cu")
	)
	(gr_line
		(start 316.440312 -111.68253)
		(end 316.725808 -111.872522)
		(stroke
			(width 0.05715)
			(type default)
		)
		(layer "F.Cu")
	)
	(gr_line
		(start 316.593474 -63.875158)
		(end 316.601094 -63.869824)
		(stroke
			(width 0.05715)
			(type default)
		)
		(layer "F.Cu")
	)
	(gr_line
		(start 316.601094 -63.869824)
		(end 316.606428 -63.862204)
		(stroke
			(width 0.05715)
			(type default)
		)
		(layer "F.Cu")
	)
	(gr_line
		(start 316.617858 -83.559142)
		(end 316.640718 -83.547458)
		(stroke
			(width 0.05715)
			(type default)
		)
		(layer "F.Cu")
	)
	(gr_line
		(start 316.640718 -83.547458)
		(end 316.654688 -83.527138)
		(stroke
			(width 0.05715)
			(type default)
		)
		(layer "F.Cu")
	)
	(gr_line
		(start 316.685422 -69.890386)
		(end 316.709806 -70.04685)
		(stroke
			(width 0.05715)
			(type default)
		)
		(layer "F.Cu")
	)
	(gr_line
		(start 316.685422 -69.890386)
		(end 316.887606 -69.613526)
		(stroke
			(width 0.05715)
			(type default)
		)
		(layer "F.Cu")
	)
	(gr_line
		(start 316.725808 -111.872522)
		(end 316.757304 -112.02797)
		(stroke
			(width 0.05715)
			(type default)
		)
		(layer "F.Cu")
	)
	(gr_line
		(start 316.887606 -69.613526)
		(end 317.04407 -69.589142)
		(stroke
			(width 0.05715)
			(type default)
		)
		(layer "F.Cu")
	)
	(gr_line
		(start 316.925198 -70.165214)
		(end 317.222124 -69.758814)
		(stroke
			(width 0.05715)
			(type default)
		)
		(layer "F.Cu")
	)
	(gr_line
		(start 317.01613 -103.573072)
		(end 317.039752 -103.579422)
		(stroke
			(width 0.05715)
			(type default)
		)
		(layer "F.Cu")
	)
	(gr_line
		(start 317.039752 -103.579422)
		(end 317.063374 -103.574088)
		(stroke
			(width 0.05715)
			(type default)
		)
		(layer "F.Cu")
	)
	(gr_line
		(start 317.195962 -122.332496)
		(end 317.232538 -122.359928)
		(stroke
			(width 0.05715)
			(type default)
		)
		(layer "F.Cu")
	)
	(gr_line
		(start 317.305944 -64.57061)
		(end 317.313564 -64.565276)
		(stroke
			(width 0.05715)
			(type default)
		)
		(layer "F.Cu")
	)
	(gr_line
		(start 317.313564 -64.565276)
		(end 317.318898 -64.557656)
		(stroke
			(width 0.05715)
			(type default)
		)
		(layer "F.Cu")
	)
	(gr_line
		(start 317.33109 -105.704132)
		(end 317.354204 -105.710228)
		(stroke
			(width 0.05715)
			(type default)
		)
		(layer "F.Cu")
	)
	(gr_line
		(start 317.342012 -84.289646)
		(end 317.364364 -84.278216)
		(stroke
			(width 0.05715)
			(type default)
		)
		(layer "F.Cu")
	)
	(gr_line
		(start 317.354204 -105.710228)
		(end 317.378334 -105.704894)
		(stroke
			(width 0.05715)
			(type default)
		)
		(layer "F.Cu")
	)
	(gr_line
		(start 317.363856 -69.15531)
		(end 317.36665 -69.1515)
		(stroke
			(width 0.05715)
			(type default)
		)
		(layer "F.Cu")
	)
	(gr_line
		(start 317.364364 -84.278216)
		(end 317.379096 -84.257134)
		(stroke
			(width 0.05715)
			(type default)
		)
		(layer "F.Cu")
	)
	(gr_line
		(start 317.36665 -69.1515)
		(end 317.370714 -69.148706)
		(stroke
			(width 0.05715)
			(type default)
		)
		(layer "F.Cu")
	)
	(gr_line
		(start 317.377826 -104.681782)
		(end 317.40094 -104.687878)
		(stroke
			(width 0.05715)
			(type default)
		)
		(layer "F.Cu")
	)
	(gr_line
		(start 317.40094 -104.687878)
		(end 317.424562 -104.682544)
		(stroke
			(width 0.05715)
			(type default)
		)
		(layer "F.Cu")
	)
	(gr_line
		(start 317.493396 -123.337828)
		(end 317.500254 -123.340114)
		(stroke
			(width 0.05715)
			(type default)
		)
		(layer "F.Cu")
	)
	(gr_line
		(start 317.500254 -123.340114)
		(end 317.505588 -123.344178)
		(stroke
			(width 0.05715)
			(type default)
		)
		(layer "F.Cu")
	)
	(gr_line
		(start 317.811912 -85.365082)
		(end 317.836042 -85.353144)
		(stroke
			(width 0.05715)
			(type default)
		)
		(layer "F.Cu")
	)
	(gr_line
		(start 317.836042 -85.353144)
		(end 317.851282 -85.331046)
		(stroke
			(width 0.05715)
			(type default)
		)
		(layer "F.Cu")
	)
	(gr_line
		(start 318.106806 -124.099828)
		(end 318.143128 -124.12726)
		(stroke
			(width 0.05715)
			(type default)
		)
		(layer "F.Cu")
	)
	(gr_line
		(start 318.137286 -121.359676)
		(end 318.173862 -121.387108)
		(stroke
			(width 0.05715)
			(type default)
		)
		(layer "F.Cu")
	)
	(gr_line
		(start 318.53251 -69.55155)
		(end 318.53759 -69.544692)
		(stroke
			(width 0.05715)
			(type default)
		)
		(layer "F.Cu")
	)
	(gr_line
		(start 318.53759 -69.544692)
		(end 318.544194 -69.54012)
		(stroke
			(width 0.05715)
			(type default)
		)
		(layer "F.Cu")
	)
	(gr_line
		(start 318.602106 -64.861948)
		(end 318.609726 -64.856614)
		(stroke
			(width 0.05715)
			(type default)
		)
		(layer "F.Cu")
	)
	(gr_line
		(start 318.609726 -64.856614)
		(end 318.61506 -64.848994)
		(stroke
			(width 0.05715)
			(type default)
		)
		(layer "F.Cu")
	)
	(gr_line
		(start 318.645032 -86.071456)
		(end 318.67094 -86.058502)
		(stroke
			(width 0.05715)
			(type default)
		)
		(layer "F.Cu")
	)
	(gr_line
		(start 318.67094 -86.058502)
		(end 318.68745 -86.034626)
		(stroke
			(width 0.05715)
			(type default)
		)
		(layer "F.Cu")
	)
	(gr_line
		(start 319.042542 -120.025668)
		(end 319.074546 -120.047004)
		(stroke
			(width 0.05715)
			(type default)
		)
		(layer "F.Cu")
	)
	(gr_line
		(start 319.10528 -124.62764)
		(end 319.14592 -124.587)
		(stroke
			(width 0.05715)
			(type default)
		)
		(layer "F.Cu")
	)
	(gr_line
		(start 319.1129 -123.46432)
		(end 319.26022 -123.317)
		(stroke
			(width 0.05715)
			(type default)
		)
		(layer "F.Cu")
	)
	(gr_line
		(start 319.14592 -124.587)
		(end 319.7225 -124.587)
		(stroke
			(width 0.05715)
			(type default)
		)
		(layer "F.Cu")
	)
	(gr_line
		(start 319.244472 -70.403466)
		(end 319.249552 -70.396608)
		(stroke
			(width 0.05715)
			(type default)
		)
		(layer "F.Cu")
	)
	(gr_line
		(start 319.249552 -70.396608)
		(end 319.256156 -70.392036)
		(stroke
			(width 0.05715)
			(type default)
		)
		(layer "F.Cu")
	)
	(gr_line
		(start 319.26022 -123.317)
		(end 319.7225 -123.317)
		(stroke
			(width 0.05715)
			(type default)
		)
		(layer "F.Cu")
	)
	(gr_line
		(start 319.280032 -65.58153)
		(end 319.288668 -65.575434)
		(stroke
			(width 0.05715)
			(type default)
		)
		(layer "F.Cu")
	)
	(gr_line
		(start 319.288668 -65.575434)
		(end 319.294764 -65.566798)
		(stroke
			(width 0.05715)
			(type default)
		)
		(layer "F.Cu")
	)
	(gr_line
		(start 319.564004 -119.26316)
		(end 320.27622 -119.26316)
		(stroke
			(width 0.05715)
			(type default)
		)
		(layer "F.Cu")
	)
	(gr_line
		(start 319.56756 -120.53316)
		(end 320.27622 -120.53316)
		(stroke
			(width 0.05715)
			(type default)
		)
		(layer "F.Cu")
	)
	(gr_line
		(start 320.11874 -102.896416)
		(end 320.134742 -102.89286)
		(stroke
			(width 0.05715)
			(type default)
		)
		(layer "F.Cu")
	)
	(gr_line
		(start 320.134742 -102.89286)
		(end 320.14795 -102.883462)
		(stroke
			(width 0.05715)
			(type default)
		)
		(layer "F.Cu")
	)
	(gr_line
		(start 320.199004 -104.067864)
		(end 320.214752 -104.064562)
		(stroke
			(width 0.05715)
			(type default)
		)
		(layer "F.Cu")
	)
	(gr_line
		(start 320.214752 -104.064562)
		(end 320.228468 -104.054656)
		(stroke
			(width 0.05715)
			(type default)
		)
		(layer "F.Cu")
	)
	(gr_line
		(start 320.317622 -70.941946)
		(end 320.322702 -70.935088)
		(stroke
			(width 0.05715)
			(type default)
		)
		(layer "F.Cu")
	)
	(gr_line
		(start 320.322702 -70.935088)
		(end 320.329306 -70.930516)
		(stroke
			(width 0.05715)
			(type default)
		)
		(layer "F.Cu")
	)
	(gr_line
		(start 320.524886 -124.154946)
		(end 320.6115 -124.24156)
		(stroke
			(width 0.05715)
			(type default)
		)
		(layer "F.Cu")
	)
	(gr_line
		(start 320.524886 -123.810014)
		(end 320.6115 -123.7234)
		(stroke
			(width 0.05715)
			(type default)
		)
		(layer "F.Cu")
	)
	(gr_line
		(start 320.6115 -124.24156)
		(end 320.6115 -124.587)
		(stroke
			(width 0.05715)
			(type default)
		)
		(layer "F.Cu")
	)
	(gr_line
		(start 320.6115 -123.317)
		(end 320.6115 -123.7234)
		(stroke
			(width 0.05715)
			(type default)
		)
		(layer "F.Cu")
	)
	(gr_line
		(start 320.68262 -104.97058)
		(end 320.69913 -104.96677)
		(stroke
			(width 0.05715)
			(type default)
		)
		(layer "F.Cu")
	)
	(gr_line
		(start 320.69913 -104.96677)
		(end 320.712846 -104.956864)
		(stroke
			(width 0.05715)
			(type default)
		)
		(layer "F.Cu")
	)
	(gr_line
		(start 320.7258 -117.298216)
		(end 320.802 -117.222016)
		(stroke
			(width 0.05715)
			(type default)
		)
		(layer "F.Cu")
	)
	(gr_line
		(start 320.7766 -118.492016)
		(end 320.8528 -118.415816)
		(stroke
			(width 0.05715)
			(type default)
		)
		(layer "F.Cu")
	)
	(gr_line
		(start 320.802 -117.222016)
		(end 322.1355 -117.222016)
		(stroke
			(width 0.05715)
			(type default)
		)
		(layer "F.Cu")
	)
	(gr_line
		(start 320.8528 -118.415816)
		(end 322.1355 -118.415816)
		(stroke
			(width 0.05715)
			(type default)
		)
		(layer "F.Cu")
	)
	(gr_line
		(start 320.974212 -71.687436)
		(end 320.979292 -71.680578)
		(stroke
			(width 0.05715)
			(type default)
		)
		(layer "F.Cu")
	)
	(gr_line
		(start 320.979292 -71.680578)
		(end 320.985896 -71.676006)
		(stroke
			(width 0.05715)
			(type default)
		)
		(layer "F.Cu")
	)
	(gr_line
		(start 321.05727 -120.104662)
		(end 321.16522 -120.212612)
		(stroke
			(width 0.05715)
			(type default)
		)
		(layer "F.Cu")
	)
	(gr_line
		(start 321.05727 -119.75973)
		(end 321.16522 -119.65178)
		(stroke
			(width 0.05715)
			(type default)
		)
		(layer "F.Cu")
	)
	(gr_line
		(start 321.16522 -120.212612)
		(end 321.16522 -120.53316)
		(stroke
			(width 0.05715)
			(type default)
		)
		(layer "F.Cu")
	)
	(gr_line
		(start 321.16522 -119.26316)
		(end 321.16522 -119.65178)
		(stroke
			(width 0.05715)
			(type default)
		)
		(layer "F.Cu")
	)
	(gr_line
		(start 321.343782 -65.340992)
		(end 321.351402 -65.335658)
		(stroke
			(width 0.05715)
			(type default)
		)
		(layer "F.Cu")
	)
	(gr_line
		(start 321.351402 -65.335658)
		(end 321.356736 -65.328038)
		(stroke
			(width 0.05715)
			(type default)
		)
		(layer "F.Cu")
	)
	(gr_line
		(start 321.5005 -124.1933)
		(end 321.5005 -124.587)
		(stroke
			(width 0.05715)
			(type default)
		)
		(layer "F.Cu")
	)
	(gr_line
		(start 321.5005 -124.1933)
		(end 321.544696 -124.149104)
		(stroke
			(width 0.05715)
			(type default)
		)
		(layer "F.Cu")
	)
	(gr_line
		(start 321.5005 -123.759976)
		(end 321.544696 -123.804172)
		(stroke
			(width 0.05715)
			(type default)
		)
		(layer "F.Cu")
	)
	(gr_line
		(start 321.5005 -123.317)
		(end 321.5005 -123.759976)
		(stroke
			(width 0.05715)
			(type default)
		)
		(layer "F.Cu")
	)
	(gr_line
		(start 321.53733 -115.501928)
		(end 321.568318 -115.522756)
		(stroke
			(width 0.05715)
			(type default)
		)
		(layer "F.Cu")
	)
	(gr_line
		(start 321.742308 -72.33539)
		(end 321.747134 -72.328532)
		(stroke
			(width 0.05715)
			(type default)
		)
		(layer "F.Cu")
	)
	(gr_line
		(start 321.747134 -72.328532)
		(end 321.753992 -72.323706)
		(stroke
			(width 0.05715)
			(type default)
		)
		(layer "F.Cu")
	)
	(gr_line
		(start 321.790822 -123.8377)
		(end 321.814444 -123.850654)
		(stroke
			(width 0.05715)
			(type default)
		)
		(layer "F.Cu")
	)
	(gr_line
		(start 321.957446 -66.157602)
		(end 321.963288 -66.153284)
		(stroke
			(width 0.05715)
			(type default)
		)
		(layer "F.Cu")
	)
	(gr_line
		(start 321.963288 -66.153284)
		(end 321.967098 -66.147696)
		(stroke
			(width 0.05715)
			(type default)
		)
		(layer "F.Cu")
	)
	(gr_line
		(start 322.05422 -120.094756)
		(end 322.05422 -120.53316)
		(stroke
			(width 0.05715)
			(type default)
		)
		(layer "F.Cu")
	)
	(gr_line
		(start 322.05422 -120.094756)
		(end 322.136262 -120.012714)
		(stroke
			(width 0.05715)
			(type default)
		)
		(layer "F.Cu")
	)
	(gr_line
		(start 322.05422 -119.58574)
		(end 322.136262 -119.667782)
		(stroke
			(width 0.05715)
			(type default)
		)
		(layer "F.Cu")
	)
	(gr_line
		(start 322.05422 -119.26316)
		(end 322.05422 -119.58574)
		(stroke
			(width 0.05715)
			(type default)
		)
		(layer "F.Cu")
	)
	(gr_line
		(start 322.455286 -73.06437)
		(end 322.461636 -73.055226)
		(stroke
			(width 0.05715)
			(type default)
		)
		(layer "F.Cu")
	)
	(gr_line
		(start 322.461636 -73.055226)
		(end 322.471288 -73.048622)
		(stroke
			(width 0.05715)
			(type default)
		)
		(layer "F.Cu")
	)
	(gr_line
		(start 322.901818 -124.447808)
		(end 322.922138 -124.458984)
		(stroke
			(width 0.05715)
			(type default)
		)
		(layer "F.Cu")
	)
	(gr_line
		(start 322.922138 -124.458984)
		(end 322.934838 -124.477526)
		(stroke
			(width 0.05715)
			(type default)
		)
		(layer "F.Cu")
	)
	(gr_line
		(start 322.938648 -117.9957)
		(end 323.0245 -118.081552)
		(stroke
			(width 0.05715)
			(type default)
		)
		(layer "F.Cu")
	)
	(gr_line
		(start 322.938648 -117.650768)
		(end 323.0245 -117.564916)
		(stroke
			(width 0.05715)
			(type default)
		)
		(layer "F.Cu")
	)
	(gr_line
		(start 322.979034 -121.666)
		(end 323.6595 -121.666)
		(stroke
			(width 0.05715)
			(type default)
		)
		(layer "F.Cu")
	)
	(gr_line
		(start 322.99656 -120.50268)
		(end 323.10324 -120.396)
		(stroke
			(width 0.05715)
			(type default)
		)
		(layer "F.Cu")
	)
	(gr_line
		(start 322.998338 -122.555)
		(end 323.6595 -122.555)
		(stroke
			(width 0.05715)
			(type default)
		)
		(layer "F.Cu")
	)
	(gr_line
		(start 323.002148 -123.780804)
		(end 323.046344 -123.825)
		(stroke
			(width 0.05715)
			(type default)
		)
		(layer "F.Cu")
	)
	(gr_line
		(start 323.0245 -118.081552)
		(end 323.0245 -118.415816)
		(stroke
			(width 0.05715)
			(type default)
		)
		(layer "F.Cu")
	)
	(gr_line
		(start 323.0245 -117.222016)
		(end 323.0245 -117.564916)
		(stroke
			(width 0.05715)
			(type default)
		)
		(layer "F.Cu")
	)
	(gr_line
		(start 323.043804 -73.918572)
		(end 323.050662 -73.90892)
		(stroke
			(width 0.05715)
			(type default)
		)
		(layer "F.Cu")
	)
	(gr_line
		(start 323.046344 -123.825)
		(end 323.6595 -123.825)
		(stroke
			(width 0.05715)
			(type default)
		)
		(layer "F.Cu")
	)
	(gr_line
		(start 323.050662 -73.90892)
		(end 323.060314 -73.902316)
		(stroke
			(width 0.05715)
			(type default)
		)
		(layer "F.Cu")
	)
	(gr_line
		(start 323.10324 -120.396)
		(end 323.6595 -120.396)
		(stroke
			(width 0.05715)
			(type default)
		)
		(layer "F.Cu")
	)
	(gr_line
		(start 323.199506 -125.292104)
		(end 323.218556 -125.31979)
		(stroke
			(width 0.05715)
			(type default)
		)
		(layer "F.Cu")
	)
	(gr_line
		(start 323.218556 -125.31979)
		(end 323.24929 -125.333506)
		(stroke
			(width 0.05715)
			(type default)
		)
		(layer "F.Cu")
	)
	(gr_line
		(start 323.219826 -53.820314)
		(end 323.221858 -53.81752)
		(stroke
			(width 0.05715)
			(type default)
		)
		(layer "F.Cu")
	)
	(gr_line
		(start 323.221858 -53.81752)
		(end 323.224652 -53.815234)
		(stroke
			(width 0.05715)
			(type default)
		)
		(layer "F.Cu")
	)
	(gr_line
		(start 323.694298 -54.861968)
		(end 323.69633 -54.859174)
		(stroke
			(width 0.05715)
			(type default)
		)
		(layer "F.Cu")
	)
	(gr_line
		(start 323.69633 -54.859174)
		(end 323.696584 -54.859174)
		(stroke
			(width 0.05715)
			(type default)
		)
		(layer "F.Cu")
	)
	(gr_line
		(start 323.696584 -54.859174)
		(end 323.698362 -54.85765)
		(stroke
			(width 0.05715)
			(type default)
		)
		(layer "F.Cu")
	)
	(gr_line
		(start 323.82333 -74.569828)
		(end 323.828664 -74.561954)
		(stroke
			(width 0.05715)
			(type default)
		)
		(layer "F.Cu")
	)
	(gr_line
		(start 323.828664 -74.561954)
		(end 323.8373 -74.556112)
		(stroke
			(width 0.05715)
			(type default)
		)
		(layer "F.Cu")
	)
	(gr_line
		(start 323.9135 -118.0973)
		(end 323.9135 -118.415816)
		(stroke
			(width 0.05715)
			(type default)
		)
		(layer "F.Cu")
	)
	(gr_line
		(start 323.9135 -118.0973)
		(end 324.007734 -118.003066)
		(stroke
			(width 0.05715)
			(type default)
		)
		(layer "F.Cu")
	)
	(gr_line
		(start 323.9135 -117.5639)
		(end 324.007734 -117.658134)
		(stroke
			(width 0.05715)
			(type default)
		)
		(layer "F.Cu")
	)
	(gr_line
		(start 323.9135 -117.222016)
		(end 323.9135 -117.5639)
		(stroke
			(width 0.05715)
			(type default)
		)
		(layer "F.Cu")
	)
	(gr_line
		(start 323.981064 -66.064384)
		(end 323.98462 -66.061844)
		(stroke
			(width 0.05715)
			(type default)
		)
		(layer "F.Cu")
	)
	(gr_line
		(start 323.98462 -66.061844)
		(end 323.98716 -66.058542)
		(stroke
			(width 0.05715)
			(type default)
		)
		(layer "F.Cu")
	)
	(gr_line
		(start 324.305422 -125.802898)
		(end 324.346824 -125.821186)
		(stroke
			(width 0.05715)
			(type default)
		)
		(layer "F.Cu")
	)
	(gr_line
		(start 324.346824 -125.821186)
		(end 324.391274 -125.81128)
		(stroke
			(width 0.05715)
			(type default)
		)
		(layer "F.Cu")
	)
	(gr_line
		(start 324.403974 -67.116706)
		(end 324.40753 -67.114166)
		(stroke
			(width 0.05715)
			(type default)
		)
		(layer "F.Cu")
	)
	(gr_line
		(start 324.40753 -67.114166)
		(end 324.41007 -67.110864)
		(stroke
			(width 0.05715)
			(type default)
		)
		(layer "F.Cu")
	)
	(gr_line
		(start 324.472554 -121.259854)
		(end 324.5485 -121.3358)
		(stroke
			(width 0.05715)
			(type default)
		)
		(layer "F.Cu")
	)
	(gr_line
		(start 324.472554 -120.914922)
		(end 324.5485 -120.838976)
		(stroke
			(width 0.05715)
			(type default)
		)
		(layer "F.Cu")
	)
	(gr_line
		(start 324.504304 -123.387104)
		(end 324.5485 -123.4313)
		(stroke
			(width 0.05715)
			(type default)
		)
		(layer "F.Cu")
	)
	(gr_line
		(start 324.504304 -123.042172)
		(end 324.5485 -122.997976)
		(stroke
			(width 0.05715)
			(type default)
		)
		(layer "F.Cu")
	)
	(gr_line
		(start 324.54342 -75.27671)
		(end 324.548754 -75.268836)
		(stroke
			(width 0.05715)
			(type default)
		)
		(layer "F.Cu")
	)
	(gr_line
		(start 324.5485 -123.4313)
		(end 324.5485 -123.825)
		(stroke
			(width 0.05715)
			(type default)
		)
		(layer "F.Cu")
	)
	(gr_line
		(start 324.5485 -122.555)
		(end 324.5485 -122.997976)
		(stroke
			(width 0.05715)
			(type default)
		)
		(layer "F.Cu")
	)
	(gr_line
		(start 324.5485 -121.3358)
		(end 324.5485 -121.666)
		(stroke
			(width 0.05715)
			(type default)
		)
		(layer "F.Cu")
	)
	(gr_line
		(start 324.5485 -120.396)
		(end 324.5485 -120.838976)
		(stroke
			(width 0.05715)
			(type default)
		)
		(layer "F.Cu")
	)
	(gr_line
		(start 324.548754 -75.268836)
		(end 324.557136 -75.262994)
		(stroke
			(width 0.05715)
			(type default)
		)
		(layer "F.Cu")
	)
	(gr_line
		(start 325.010272 -67.978528)
		(end 325.013828 -67.975988)
		(stroke
			(width 0.05715)
			(type default)
		)
		(layer "F.Cu")
	)
	(gr_line
		(start 325.013828 -67.975988)
		(end 325.016368 -67.972686)
		(stroke
			(width 0.05715)
			(type default)
		)
		(layer "F.Cu")
	)
	(gr_line
		(start 325.035672 -55.08752)
		(end 325.036688 -55.085996)
		(stroke
			(width 0.05715)
			(type default)
		)
		(layer "F.Cu")
	)
	(gr_line
		(start 325.036688 -55.085996)
		(end 325.038466 -55.084472)
		(stroke
			(width 0.05715)
			(type default)
		)
		(layer "F.Cu")
	)
	(gr_line
		(start 325.28383 -75.963272)
		(end 325.289926 -75.954382)
		(stroke
			(width 0.05715)
			(type default)
		)
		(layer "F.Cu")
	)
	(gr_line
		(start 325.289926 -75.954382)
		(end 325.299324 -75.948032)
		(stroke
			(width 0.05715)
			(type default)
		)
		(layer "F.Cu")
	)
	(gr_line
		(start 325.325232 -125.355858)
		(end 325.377556 -125.344174)
		(stroke
			(width 0.05715)
			(type default)
		)
		(layer "F.Cu")
	)
	(gr_line
		(start 325.377556 -125.344174)
		(end 325.425308 -125.369066)
		(stroke
			(width 0.05715)
			(type default)
		)
		(layer "F.Cu")
	)
	(gr_line
		(start 325.389494 -99.103688)
		(end 325.42099 -99.080828)
		(stroke
			(width 0.05715)
			(type default)
		)
		(layer "F.Cu")
	)
	(gr_line
		(start 325.42099 -99.080828)
		(end 325.434706 -99.044506)
		(stroke
			(width 0.05715)
			(type default)
		)
		(layer "F.Cu")
	)
	(gr_line
		(start 325.4375 -123.3805)
		(end 325.4375 -123.825)
		(stroke
			(width 0.05715)
			(type default)
		)
		(layer "F.Cu")
	)
	(gr_line
		(start 325.4375 -123.3805)
		(end 325.477886 -123.340114)
		(stroke
			(width 0.05715)
			(type default)
		)
		(layer "F.Cu")
	)
	(gr_line
		(start 325.4375 -122.954796)
		(end 325.477886 -122.995182)
		(stroke
			(width 0.05715)
			(type default)
		)
		(layer "F.Cu")
	)
	(gr_line
		(start 325.4375 -122.555)
		(end 325.4375 -122.954796)
		(stroke
			(width 0.05715)
			(type default)
		)
		(layer "F.Cu")
	)
	(gr_line
		(start 325.4375 -121.250456)
		(end 325.4375 -121.666)
		(stroke
			(width 0.05715)
			(type default)
		)
		(layer "F.Cu")
	)
	(gr_line
		(start 325.4375 -121.250456)
		(end 325.495412 -121.192544)
		(stroke
			(width 0.05715)
			(type default)
		)
		(layer "F.Cu")
	)
	(gr_line
		(start 325.4375 -120.7897)
		(end 325.495412 -120.847612)
		(stroke
			(width 0.05715)
			(type default)
		)
		(layer "F.Cu")
	)
	(gr_line
		(start 325.4375 -120.396)
		(end 325.4375 -120.7897)
		(stroke
			(width 0.05715)
			(type default)
		)
		(layer "F.Cu")
	)
	(gr_line
		(start 325.68261 -55.854346)
		(end 325.683626 -55.852822)
		(stroke
			(width 0.05715)
			(type default)
		)
		(layer "F.Cu")
	)
	(gr_line
		(start 325.683626 -55.852822)
		(end 325.685404 -55.851298)
		(stroke
			(width 0.05715)
			(type default)
		)
		(layer "F.Cu")
	)
	(gr_line
		(start 325.787004 -123.06935)
		(end 325.825358 -123.09983)
		(stroke
			(width 0.05715)
			(type default)
		)
		(layer "F.Cu")
	)
	(gr_line
		(start 326.192896 -99.743768)
		(end 326.224138 -99.721162)
		(stroke
			(width 0.05715)
			(type default)
		)
		(layer "F.Cu")
	)
	(gr_line
		(start 326.224138 -99.721162)
		(end 326.238108 -99.683824)
		(stroke
			(width 0.05715)
			(type default)
		)
		(layer "F.Cu")
	)
	(gr_line
		(start 326.313038 -68.27647)
		(end 326.321674 -68.270628)
		(stroke
			(width 0.05715)
			(type default)
		)
		(layer "F.Cu")
	)
	(gr_line
		(start 326.321674 -68.270628)
		(end 326.328024 -68.26123)
		(stroke
			(width 0.05715)
			(type default)
		)
		(layer "F.Cu")
	)
	(gr_line
		(start 326.407018 -123.561856)
		(end 326.417432 -123.569984)
		(stroke
			(width 0.05715)
			(type default)
		)
		(layer "F.Cu")
	)
	(gr_line
		(start 326.417432 -123.569984)
		(end 326.42429 -123.581922)
		(stroke
			(width 0.05715)
			(type default)
		)
		(layer "F.Cu")
	)
	(gr_line
		(start 326.783192 -110.755176)
		(end 326.81672 -110.768638)
		(stroke
			(width 0.05715)
			(type default)
		)
		(layer "F.Cu")
	)
	(gr_line
		(start 326.81672 -110.768638)
		(end 326.838056 -110.797594)
		(stroke
			(width 0.05715)
			(type default)
		)
		(layer "F.Cu")
	)
	(gr_line
		(start 326.97674 -100.43287)
		(end 327.010522 -100.408486)
		(stroke
			(width 0.05715)
			(type default)
		)
		(layer "F.Cu")
	)
	(gr_line
		(start 327.010522 -100.408486)
		(end 327.025762 -100.368354)
		(stroke
			(width 0.05715)
			(type default)
		)
		(layer "F.Cu")
	)
	(gr_line
		(start 327.122028 -125.287532)
		(end 327.137522 -125.314456)
		(stroke
			(width 0.05715)
			(type default)
		)
		(layer "F.Cu")
	)
	(gr_line
		(start 327.137522 -125.314456)
		(end 327.1647 -125.330458)
		(stroke
			(width 0.05715)
			(type default)
		)
		(layer "F.Cu")
	)
	(gr_line
		(start 327.241916 -93.58376)
		(end 327.256902 -93.543882)
		(stroke
			(width 0.05715)
			(type default)
		)
		(layer "F.Cu")
	)
	(gr_line
		(start 327.248266 -68.80606)
		(end 327.25995 -68.797932)
		(stroke
			(width 0.05715)
			(type default)
		)
		(layer "F.Cu")
	)
	(gr_line
		(start 327.256902 -93.543882)
		(end 327.29297 -93.520006)
		(stroke
			(width 0.05715)
			(type default)
		)
		(layer "F.Cu")
	)
	(gr_line
		(start 327.25995 -68.797932)
		(end 327.267316 -68.785994)
		(stroke
			(width 0.05715)
			(type default)
		)
		(layer "F.Cu")
	)
	(gr_line
		(start 327.55332 -55.892446)
		(end 327.554336 -55.890922)
		(stroke
			(width 0.05715)
			(type default)
		)
		(layer "F.Cu")
	)
	(gr_line
		(start 327.554336 -55.890922)
		(end 327.556114 -55.889398)
		(stroke
			(width 0.05715)
			(type default)
		)
		(layer "F.Cu")
	)
	(gr_line
		(start 328.014076 -94.309184)
		(end 328.028808 -94.269814)
		(stroke
			(width 0.05715)
			(type default)
		)
		(layer "F.Cu")
	)
	(gr_line
		(start 328.028808 -94.269814)
		(end 328.064114 -94.246192)
		(stroke
			(width 0.05715)
			(type default)
		)
		(layer "F.Cu")
	)
	(gr_line
		(start 328.1045 -56.797956)
		(end 328.106024 -56.795924)
		(stroke
			(width 0.05715)
			(type default)
		)
		(layer "F.Cu")
	)
	(gr_line
		(start 328.106024 -56.795924)
		(end 328.107802 -56.794654)
		(stroke
			(width 0.05715)
			(type default)
		)
		(layer "F.Cu")
	)
	(gr_line
		(start 328.404982 -112.935258)
		(end 328.43089 -112.970564)
		(stroke
			(width 0.05715)
			(type default)
		)
		(layer "F.Cu")
	)
	(gr_line
		(start 328.535792 -69.225668)
		(end 328.548492 -69.217032)
		(stroke
			(width 0.05715)
			(type default)
		)
		(layer "F.Cu")
	)
	(gr_line
		(start 328.548492 -69.217032)
		(end 328.557128 -69.203824)
		(stroke
			(width 0.05715)
			(type default)
		)
		(layer "F.Cu")
	)
	(gr_line
		(start 328.61631 -95.479616)
		(end 328.631296 -95.439738)
		(stroke
			(width 0.05715)
			(type default)
		)
		(layer "F.Cu")
	)
	(gr_line
		(start 328.631296 -95.439738)
		(end 328.667364 -95.415862)
		(stroke
			(width 0.05715)
			(type default)
		)
		(layer "F.Cu")
	)
	(gr_line
		(start 328.669142 -117.805454)
		(end 328.728324 -117.864636)
		(stroke
			(width 0.05715)
			(type default)
		)
		(layer "F.Cu")
	)
	(gr_line
		(start 328.67092 -117.4623)
		(end 328.828908 -117.4623)
		(stroke
			(width 0.05715)
			(type default)
		)
		(layer "F.Cu")
	)
	(gr_line
		(start 328.684128 -127.329946)
		(end 328.728324 -127.352806)
		(stroke
			(width 0.05715)
			(type default)
		)
		(layer "F.Cu")
	)
	(gr_line
		(start 328.687176 -66.073274)
		(end 328.699622 -66.053208)
		(stroke
			(width 0.05715)
			(type default)
		)
		(layer "F.Cu")
	)
	(gr_line
		(start 328.690478 -126.227332)
		(end 328.739246 -126.256288)
		(stroke
			(width 0.05715)
			(type default)
		)
		(layer "F.Cu")
	)
	(gr_line
		(start 328.699622 -66.053208)
		(end 328.720196 -66.041016)
		(stroke
			(width 0.05715)
			(type default)
		)
		(layer "F.Cu")
	)
	(gr_line
		(start 328.728324 -127.352806)
		(end 328.777092 -127.343154)
		(stroke
			(width 0.05715)
			(type default)
		)
		(layer "F.Cu")
	)
	(gr_line
		(start 328.739246 -126.256288)
		(end 328.795888 -126.245366)
		(stroke
			(width 0.05715)
			(type default)
		)
		(layer "F.Cu")
	)
	(gr_line
		(start 328.828908 -117.4623)
		(end 329.071478 -117.704616)
		(stroke
			(width 0.05715)
			(type default)
		)
		(layer "F.Cu")
	)
	(gr_line
		(start 329.057 -40.63238)
		(end 329.594972 -40.094408)
		(stroke
			(width 0.0635)
			(type default)
		)
		(layer "F.Cu")
	)
	(gr_line
		(start 329.071478 -117.704616)
		(end 329.071478 -117.862858)
		(stroke
			(width 0.05715)
			(type default)
		)
		(layer "F.Cu")
	)
	(gr_line
		(start 329.21956 -95.045022)
		(end 329.250548 -94.889828)
		(stroke
			(width 0.05715)
			(type default)
		)
		(layer "F.Cu")
	)
	(gr_line
		(start 329.250548 -94.889828)
		(end 329.53579 -94.699582)
		(stroke
			(width 0.05715)
			(type default)
		)
		(layer "F.Cu")
	)
	(gr_line
		(start 329.38085 -95.230696)
		(end 329.801728 -94.95028)
		(stroke
			(width 0.05715)
			(type default)
		)
		(layer "F.Cu")
	)
	(gr_line
		(start 329.53579 -94.699582)
		(end 329.691238 -94.730824)
		(stroke
			(width 0.05715)
			(type default)
		)
		(layer "F.Cu")
	)
	(gr_line
		(start 329.54976 -67.2338)
		(end 329.576176 -67.19316)
		(stroke
			(width 0.05715)
			(type default)
		)
		(layer "F.Cu")
	)
	(gr_line
		(start 329.576176 -67.19316)
		(end 329.62215 -67.177412)
		(stroke
			(width 0.05715)
			(type default)
		)
		(layer "F.Cu")
	)
	(gr_line
		(start 329.594972 -39.99103)
		(end 329.594972 -40.094408)
		(stroke
			(width 0.0635)
			(type default)
		)
		(layer "F.Cu")
	)
	(gr_line
		(start 329.602592 -126.088648)
		(end 329.602846 -126.088648)
		(stroke
			(width 0.05715)
			(type default)
		)
		(layer "F.Cu")
	)
	(gr_line
		(start 329.98029 -94.538038)
		(end 330.011532 -94.38259)
		(stroke
			(width 0.05715)
			(type default)
		)
		(layer "F.Cu")
	)
	(gr_line
		(start 330.011532 -94.38259)
		(end 330.296774 -94.192598)
		(stroke
			(width 0.05715)
			(type default)
		)
		(layer "F.Cu")
	)
	(gr_line
		(start 330.141072 -94.723966)
		(end 330.562458 -94.443042)
		(stroke
			(width 0.05715)
			(type default)
		)
		(layer "F.Cu")
	)
	(gr_line
		(start 330.145898 -127.070104)
		(end 330.154534 -127.068326)
		(stroke
			(width 0.05715)
			(type default)
		)
		(layer "F.Cu")
	)
	(gr_line
		(start 330.154534 -127.068326)
		(end 330.161646 -127.063754)
		(stroke
			(width 0.05715)
			(type default)
		)
		(layer "F.Cu")
	)
	(gr_line
		(start 330.176378 -40.591232)
		(end 330.77658 -39.99103)
		(stroke
			(width 0.0635)
			(type default)
		)
		(layer "F.Cu")
	)
	(gr_line
		(start 330.296774 -94.192598)
		(end 330.452476 -94.223586)
		(stroke
			(width 0.05715)
			(type default)
		)
		(layer "F.Cu")
	)
	(gr_line
		(start 330.741274 -94.031054)
		(end 330.772262 -93.875606)
		(stroke
			(width 0.05715)
			(type default)
		)
		(layer "F.Cu")
	)
	(gr_line
		(start 330.772262 -93.875606)
		(end 331.057758 -93.68536)
		(stroke
			(width 0.05715)
			(type default)
		)
		(layer "F.Cu")
	)
	(gr_line
		(start 330.77658 -39.99103)
		(end 330.864972 -39.99103)
		(stroke
			(width 0.0635)
			(type default)
		)
		(layer "F.Cu")
	)
	(gr_line
		(start 330.902056 -94.216982)
		(end 331.323696 -93.936058)
		(stroke
			(width 0.05715)
			(type default)
		)
		(layer "F.Cu")
	)
	(gr_line
		(start 331.057758 -93.68536)
		(end 331.213206 -93.716602)
		(stroke
			(width 0.05715)
			(type default)
		)
		(layer "F.Cu")
	)
	(gr_line
		(start 331.07122 -47.689262)
		(end 331.078078 -47.683928)
		(stroke
			(width 0.05715)
			(type default)
		)
		(layer "F.Cu")
	)
	(gr_line
		(start 331.078078 -47.683928)
		(end 331.08646 -47.681134)
		(stroke
			(width 0.05715)
			(type default)
		)
		(layer "F.Cu")
	)
	(gr_line
		(start 331.2668 -118.5164)
		(end 332.01102 -118.5164)
		(stroke
			(width 0.05715)
			(type default)
		)
		(layer "F.Cu")
	)
	(gr_line
		(start 331.2668 -117.35562)
		(end 331.999844 -117.35562)
		(stroke
			(width 0.05715)
			(type default)
		)
		(layer "F.Cu")
	)
	(gr_line
		(start 331.409294 -124.882148)
		(end 331.429868 -124.871226)
		(stroke
			(width 0.05715)
			(type default)
		)
		(layer "F.Cu")
	)
	(gr_line
		(start 331.502004 -93.52407)
		(end 331.533246 -93.368368)
		(stroke
			(width 0.05715)
			(type default)
		)
		(layer "F.Cu")
	)
	(gr_line
		(start 331.533246 -93.368368)
		(end 331.818742 -93.178376)
		(stroke
			(width 0.05715)
			(type default)
		)
		(layer "F.Cu")
	)
	(gr_line
		(start 331.619606 -125.875034)
		(end 331.648816 -125.857)
		(stroke
			(width 0.05715)
			(type default)
		)
		(layer "F.Cu")
	)
	(gr_line
		(start 331.66177 -93.71076)
		(end 332.084172 -93.429328)
		(stroke
			(width 0.05715)
			(type default)
		)
		(layer "F.Cu")
	)
	(gr_line
		(start 331.818742 -93.178376)
		(end 331.97419 -93.209618)
		(stroke
			(width 0.05715)
			(type default)
		)
		(layer "F.Cu")
	)
	(gr_line
		(start 331.902562 -83.471766)
		(end 331.973682 -83.32978)
		(stroke
			(width 0.05715)
			(type default)
		)
		(layer "F.Cu")
	)
	(gr_line
		(start 331.908658 -48.44669)
		(end 331.915516 -48.441356)
		(stroke
			(width 0.05715)
			(type default)
		)
		(layer "F.Cu")
	)
	(gr_line
		(start 331.915516 -48.441356)
		(end 331.923898 -48.438562)
		(stroke
			(width 0.05715)
			(type default)
		)
		(layer "F.Cu")
	)
	(gr_line
		(start 331.973682 -83.32978)
		(end 332.29931 -83.22183)
		(stroke
			(width 0.05715)
			(type default)
		)
		(layer "F.Cu")
	)
	(gr_line
		(start 332.00848 -83.693254)
		(end 332.488032 -83.533996)
		(stroke
			(width 0.05715)
			(type default)
		)
		(layer "F.Cu")
	)
	(gr_line
		(start 332.180946 -93.07449)
		(end 332.188312 -93.069664)
		(stroke
			(width 0.05715)
			(type default)
		)
		(layer "F.Cu")
	)
	(gr_line
		(start 332.188312 -93.069664)
		(end 332.19644 -93.067886)
		(stroke
			(width 0.05715)
			(type default)
		)
		(layer "F.Cu")
	)
	(gr_line
		(start 332.22438 -90.234262)
		(end 332.23327 -90.228166)
		(stroke
			(width 0.05715)
			(type default)
		)
		(layer "F.Cu")
	)
	(gr_line
		(start 332.23327 -90.228166)
		(end 332.243938 -90.226134)
		(stroke
			(width 0.05715)
			(type default)
		)
		(layer "F.Cu")
	)
	(gr_line
		(start 332.29931 -83.22183)
		(end 332.440788 -83.29295)
		(stroke
			(width 0.05715)
			(type default)
		)
		(layer "F.Cu")
	)
	(gr_line
		(start 332.440534 -49.304194)
		(end 332.447392 -49.29886)
		(stroke
			(width 0.05715)
			(type default)
		)
		(layer "F.Cu")
	)
	(gr_line
		(start 332.447392 -49.29886)
		(end 332.447646 -49.298606)
		(stroke
			(width 0.05715)
			(type default)
		)
		(layer "F.Cu")
	)
	(gr_line
		(start 332.447646 -49.298606)
		(end 332.45679 -49.295558)
		(stroke
			(width 0.05715)
			(type default)
		)
		(layer "F.Cu")
	)
	(gr_line
		(start 332.53553 -92.982542)
		(end 332.625192 -92.835222)
		(stroke
			(width 0.05715)
			(type default)
		)
		(layer "F.Cu")
	)
	(gr_line
		(start 332.624176 -93.211904)
		(end 333.143606 -93.085412)
		(stroke
			(width 0.05715)
			(type default)
		)
		(layer "F.Cu")
	)
	(gr_line
		(start 332.625192 -92.835222)
		(end 332.970886 -92.750894)
		(stroke
			(width 0.05715)
			(type default)
		)
		(layer "F.Cu")
	)
	(gr_line
		(start 332.710282 -57.300622)
		(end 332.735682 -57.26684)
		(stroke
			(width 0.05715)
			(type default)
		)
		(layer "F.Cu")
	)
	(gr_line
		(start 332.735682 -57.26684)
		(end 332.77556 -57.253632)
		(stroke
			(width 0.05715)
			(type default)
		)
		(layer "F.Cu")
	)
	(gr_line
		(start 332.744064 -91.124278)
		(end 332.753716 -91.117928)
		(stroke
			(width 0.05715)
			(type default)
		)
		(layer "F.Cu")
	)
	(gr_line
		(start 332.753716 -91.117928)
		(end 332.765146 -91.115388)
		(stroke
			(width 0.05715)
			(type default)
		)
		(layer "F.Cu")
	)
	(gr_line
		(start 332.77048 -83.183222)
		(end 332.8416 -83.04149)
		(stroke
			(width 0.05715)
			(type default)
		)
		(layer "F.Cu")
	)
	(gr_line
		(start 332.823566 -63.599568)
		(end 332.83017 -63.595758)
		(stroke
			(width 0.05715)
			(type default)
		)
		(layer "F.Cu")
	)
	(gr_line
		(start 332.827376 -118.088156)
		(end 332.90002 -118.1608)
		(stroke
			(width 0.05715)
			(type default)
		)
		(layer "F.Cu")
	)
	(gr_line
		(start 332.827376 -117.743224)
		(end 332.888844 -117.681756)
		(stroke
			(width 0.05715)
			(type default)
		)
		(layer "F.Cu")
	)
	(gr_line
		(start 332.83017 -63.595758)
		(end 332.837536 -63.594234)
		(stroke
			(width 0.05715)
			(type default)
		)
		(layer "F.Cu")
	)
	(gr_line
		(start 332.8416 -83.04149)
		(end 333.166974 -82.93354)
		(stroke
			(width 0.05715)
			(type default)
		)
		(layer "F.Cu")
	)
	(gr_line
		(start 332.876652 -83.404964)
		(end 333.356458 -83.245706)
		(stroke
			(width 0.05715)
			(type default)
		)
		(layer "F.Cu")
	)
	(gr_line
		(start 332.888844 -117.35562)
		(end 332.888844 -117.681756)
		(stroke
			(width 0.05715)
			(type default)
		)
		(layer "F.Cu")
	)
	(gr_line
		(start 332.90002 -118.1608)
		(end 332.90002 -118.5164)
		(stroke
			(width 0.05715)
			(type default)
		)
		(layer "F.Cu")
	)
	(gr_line
		(start 332.970886 -92.750894)
		(end 333.118206 -92.84081)
		(stroke
			(width 0.05715)
			(type default)
		)
		(layer "F.Cu")
	)
	(gr_line
		(start 332.972918 -50.161698)
		(end 332.979776 -50.156364)
		(stroke
			(width 0.05715)
			(type default)
		)
		(layer "F.Cu")
	)
	(gr_line
		(start 332.979776 -50.156364)
		(end 332.988158 -50.15357)
		(stroke
			(width 0.05715)
			(type default)
		)
		(layer "F.Cu")
	)
	(gr_line
		(start 333.166974 -82.93354)
		(end 333.308706 -83.00466)
		(stroke
			(width 0.05715)
			(type default)
		)
		(layer "F.Cu")
	)
	(gr_line
		(start 333.4004 -43.815)
		(end 333.404972 -43.80103)
		(stroke
			(width 0.0635)
			(type default)
		)
		(layer "F.Cu")
	)
	(gr_line
		(start 333.4004 -43.815)
		(end 334.0481 -43.1673)
		(stroke
			(width 0.0635)
			(type default)
		)
		(layer "F.Cu")
	)
	(gr_line
		(start 333.4004 -42.545)
		(end 333.404972 -42.53103)
		(stroke
			(width 0.0635)
			(type default)
		)
		(layer "F.Cu")
	)
	(gr_line
		(start 333.4004 -42.545)
		(end 334.04302 -41.90238)
		(stroke
			(width 0.0635)
			(type default)
		)
		(layer "F.Cu")
	)
	(gr_line
		(start 333.420466 -58.096912)
		(end 333.445866 -58.06313)
		(stroke
			(width 0.05715)
			(type default)
		)
		(layer "F.Cu")
	)
	(gr_line
		(start 333.445866 -58.06313)
		(end 333.485744 -58.049922)
		(stroke
			(width 0.05715)
			(type default)
		)
		(layer "F.Cu")
	)
	(gr_line
		(start 333.638144 -82.895186)
		(end 333.709264 -82.7532)
		(stroke
			(width 0.05715)
			(type default)
		)
		(layer "F.Cu")
	)
	(gr_line
		(start 333.709264 -82.7532)
		(end 334.034638 -82.64525)
		(stroke
			(width 0.05715)
			(type default)
		)
		(layer "F.Cu")
	)
	(gr_line
		(start 333.7433 -83.117182)
		(end 334.225138 -82.957162)
		(stroke
			(width 0.05715)
			(type default)
		)
		(layer "F.Cu")
	)
	(gr_line
		(start 333.777844 -117.654324)
		(end 333.838804 -117.715284)
		(stroke
			(width 0.05715)
			(type default)
		)
		(layer "F.Cu")
	)
	(gr_line
		(start 333.777844 -117.35562)
		(end 333.777844 -117.654324)
		(stroke
			(width 0.05715)
			(type default)
		)
		(layer "F.Cu")
	)
	(gr_line
		(start 333.78902 -118.11)
		(end 333.78902 -118.5164)
		(stroke
			(width 0.05715)
			(type default)
		)
		(layer "F.Cu")
	)
	(gr_line
		(start 333.78902 -118.11)
		(end 333.838804 -118.060216)
		(stroke
			(width 0.05715)
			(type default)
		)
		(layer "F.Cu")
	)
	(gr_line
		(start 333.826612 -86.098888)
		(end 333.853536 -86.089998)
		(stroke
			(width 0.05715)
			(type default)
		)
		(layer "F.Cu")
	)
	(gr_line
		(start 333.853536 -86.089998)
		(end 333.880968 -86.095078)
		(stroke
			(width 0.05715)
			(type default)
		)
		(layer "F.Cu")
	)
	(gr_line
		(start 333.978758 -50.871882)
		(end 333.98587 -50.866548)
		(stroke
			(width 0.05715)
			(type default)
		)
		(layer "F.Cu")
	)
	(gr_line
		(start 333.98587 -50.866548)
		(end 333.994252 -50.863754)
		(stroke
			(width 0.05715)
			(type default)
		)
		(layer "F.Cu")
	)
	(gr_line
		(start 334.034638 -82.64525)
		(end 334.17637 -82.71637)
		(stroke
			(width 0.05715)
			(type default)
		)
		(layer "F.Cu")
	)
	(gr_line
		(start 334.04302 -41.87698)
		(end 334.04302 -41.90238)
		(stroke
			(width 0.0635)
			(type default)
		)
		(layer "F.Cu")
	)
	(gr_line
		(start 334.0481 -43.1673)
		(end 334.05572 -43.1673)
		(stroke
			(width 0.0635)
			(type default)
		)
		(layer "F.Cu")
	)
	(gr_line
		(start 334.062578 -90.841576)
		(end 334.077056 -90.838528)
		(stroke
			(width 0.05715)
			(type default)
		)
		(layer "F.Cu")
	)
	(gr_line
		(start 334.077056 -90.838528)
		(end 334.091534 -90.841322)
		(stroke
			(width 0.05715)
			(type default)
		)
		(layer "F.Cu")
	)
	(gr_line
		(start 334.131666 -119.09679)
		(end 334.243426 -118.98503)
		(stroke
			(width 0.05715)
			(type default)
		)
		(layer "F.Cu")
	)
	(gr_line
		(start 334.159098 -89.82202)
		(end 334.173576 -89.818972)
		(stroke
			(width 0.05715)
			(type default)
		)
		(layer "F.Cu")
	)
	(gr_line
		(start 334.173576 -89.818972)
		(end 334.188054 -89.821766)
		(stroke
			(width 0.05715)
			(type default)
		)
		(layer "F.Cu")
	)
	(gr_line
		(start 334.243426 -118.98503)
		(end 334.586326 -118.98503)
		(stroke
			(width 0.05715)
			(type default)
		)
		(layer "F.Cu")
	)
	(gr_line
		(start 334.284574 -80.501744)
		(end 334.345534 -80.355694)
		(stroke
			(width 0.05715)
			(type default)
		)
		(layer "F.Cu")
	)
	(gr_line
		(start 334.345534 -80.355694)
		(end 334.662526 -80.225138)
		(stroke
			(width 0.05715)
			(type default)
		)
		(layer "F.Cu")
	)
	(gr_line
		(start 334.372966 -119.34063)
		(end 334.456786 -119.34063)
		(stroke
			(width 0.05715)
			(type default)
		)
		(layer "F.Cu")
	)
	(gr_line
		(start 334.40624 -80.715358)
		(end 334.873346 -80.523334)
		(stroke
			(width 0.05715)
			(type default)
		)
		(layer "F.Cu")
	)
	(gr_line
		(start 334.505808 -82.606896)
		(end 334.577182 -82.46491)
		(stroke
			(width 0.05715)
			(type default)
		)
		(layer "F.Cu")
	)
	(gr_line
		(start 334.561942 -51.700176)
		(end 334.571594 -51.692556)
		(stroke
			(width 0.05715)
			(type default)
		)
		(layer "F.Cu")
	)
	(gr_line
		(start 334.571594 -51.692556)
		(end 334.583024 -51.689)
		(stroke
			(width 0.05715)
			(type default)
		)
		(layer "F.Cu")
	)
	(gr_line
		(start 334.577182 -82.46491)
		(end 334.902556 -82.35696)
		(stroke
			(width 0.05715)
			(type default)
		)
		(layer "F.Cu")
	)
	(gr_line
		(start 334.586326 -118.98503)
		(end 334.698086 -119.09679)
		(stroke
			(width 0.05715)
			(type default)
		)
		(layer "F.Cu")
	)
	(gr_line
		(start 334.609948 -82.8294)
		(end 335.092802 -82.668872)
		(stroke
			(width 0.05715)
			(type default)
		)
		(layer "F.Cu")
	)
	(gr_line
		(start 334.662526 -80.225138)
		(end 334.809084 -80.286098)
		(stroke
			(width 0.05715)
			(type default)
		)
		(layer "F.Cu")
	)
	(gr_line
		(start 334.66913 -54.2417)
		(end 334.67675 -54.23535)
		(stroke
			(width 0.05715)
			(type default)
		)
		(layer "F.Cu")
	)
	(gr_line
		(start 334.67675 -54.23535)
		(end 334.686656 -54.232048)
		(stroke
			(width 0.05715)
			(type default)
		)
		(layer "F.Cu")
	)
	(gr_line
		(start 334.902556 -82.35696)
		(end 335.044288 -82.42808)
		(stroke
			(width 0.05715)
			(type default)
		)
		(layer "F.Cu")
	)
	(gr_line
		(start 335.05521 -52.577492)
		(end 335.062068 -52.572158)
		(stroke
			(width 0.05715)
			(type default)
		)
		(layer "F.Cu")
	)
	(gr_line
		(start 335.062068 -52.572158)
		(end 335.07045 -52.569364)
		(stroke
			(width 0.05715)
			(type default)
		)
		(layer "F.Cu")
	)
	(gr_line
		(start 335.13014 -80.154018)
		(end 335.1911 -80.007968)
		(stroke
			(width 0.05715)
			(type default)
		)
		(layer "F.Cu")
	)
	(gr_line
		(start 335.1911 -80.007968)
		(end 335.508346 -79.877412)
		(stroke
			(width 0.05715)
			(type default)
		)
		(layer "F.Cu")
	)
	(gr_line
		(start 335.251806 -80.367632)
		(end 335.717134 -80.17637)
		(stroke
			(width 0.05715)
			(type default)
		)
		(layer "F.Cu")
	)
	(gr_line
		(start 335.401412 -86.61654)
		(end 335.423002 -86.620604)
		(stroke
			(width 0.05715)
			(type default)
		)
		(layer "F.Cu")
	)
	(gr_line
		(start 335.423002 -86.620604)
		(end 335.444338 -86.614508)
		(stroke
			(width 0.05715)
			(type default)
		)
		(layer "F.Cu")
	)
	(gr_line
		(start 335.508346 -79.877412)
		(end 335.654396 -79.938626)
		(stroke
			(width 0.05715)
			(type default)
		)
		(layer "F.Cu")
	)
	(gr_line
		(start 335.660746 -91.401392)
		(end 335.675224 -91.398344)
		(stroke
			(width 0.05715)
			(type default)
		)
		(layer "F.Cu")
	)
	(gr_line
		(start 335.728564 -90.37574)
		(end 335.743042 -90.378534)
		(stroke
			(width 0.05715)
			(type default)
		)
		(layer "F.Cu")
	)
	(gr_line
		(start 335.743042 -90.378534)
		(end 335.75752 -90.375486)
		(stroke
			(width 0.05715)
			(type default)
		)
		(layer "F.Cu")
	)
	(gr_line
		(start 335.85404 -121.282968)
		(end 336.515202 -121.282968)
		(stroke
			(width 0.05715)
			(type default)
		)
		(layer "F.Cu")
	)
	(gr_line
		(start 335.87944 -120.038368)
		(end 336.540602 -120.038368)
		(stroke
			(width 0.05715)
			(type default)
		)
		(layer "F.Cu")
	)
	(gr_line
		(start 335.97596 -79.806292)
		(end 336.03692 -79.660242)
		(stroke
			(width 0.05715)
			(type default)
		)
		(layer "F.Cu")
	)
	(gr_line
		(start 336.03692 -79.660242)
		(end 336.354166 -79.52994)
		(stroke
			(width 0.05715)
			(type default)
		)
		(layer "F.Cu")
	)
	(gr_line
		(start 336.098642 -80.019398)
		(end 336.5627 -79.828644)
		(stroke
			(width 0.05715)
			(type default)
		)
		(layer "F.Cu")
	)
	(gr_line
		(start 336.109564 -53.76672)
		(end 336.136742 -53.75783)
		(stroke
			(width 0.05715)
			(type default)
		)
		(layer "F.Cu")
	)
	(gr_line
		(start 336.136742 -53.75783)
		(end 336.164682 -53.763418)
		(stroke
			(width 0.05715)
			(type default)
		)
		(layer "F.Cu")
	)
	(gr_line
		(start 336.354166 -79.52994)
		(end 336.500216 -79.5909)
		(stroke
			(width 0.05715)
			(type default)
		)
		(layer "F.Cu")
	)
	(gr_line
		(start 336.821526 -79.45882)
		(end 336.88274 -79.312516)
		(stroke
			(width 0.05715)
			(type default)
		)
		(layer "F.Cu")
	)
	(gr_line
		(start 336.88274 -79.312516)
		(end 337.199732 -79.182214)
		(stroke
			(width 0.05715)
			(type default)
		)
		(layer "F.Cu")
	)
	(gr_line
		(start 336.925666 -85.935312)
		(end 336.950558 -85.9282)
		(stroke
			(width 0.05715)
			(type default)
		)
		(layer "F.Cu")
	)
	(gr_line
		(start 336.943192 -79.67218)
		(end 337.40852 -79.480918)
		(stroke
			(width 0.05715)
			(type default)
		)
		(layer "F.Cu")
	)
	(gr_line
		(start 336.950558 -85.9282)
		(end 336.975704 -85.933534)
		(stroke
			(width 0.05715)
			(type default)
		)
		(layer "F.Cu")
	)
	(gr_line
		(start 337.095084 -55.840376)
		(end 337.124548 -55.830724)
		(stroke
			(width 0.05715)
			(type default)
		)
		(layer "F.Cu")
	)
	(gr_line
		(start 337.124548 -55.830724)
		(end 337.154774 -55.837074)
		(stroke
			(width 0.05715)
			(type default)
		)
		(layer "F.Cu")
	)
	(gr_line
		(start 337.130644 -56.857392)
		(end 337.160108 -56.84774)
		(stroke
			(width 0.05715)
			(type default)
		)
		(layer "F.Cu")
	)
	(gr_line
		(start 337.147154 -45.698918)
		(end 337.174332 -45.690028)
		(stroke
			(width 0.05715)
			(type default)
		)
		(layer "F.Cu")
	)
	(gr_line
		(start 337.160108 -56.84774)
		(end 337.190334 -56.85409)
		(stroke
			(width 0.05715)
			(type default)
		)
		(layer "F.Cu")
	)
	(gr_line
		(start 337.172808 -14.108176)
		(end 337.310984 -13.97)
		(stroke
			(width 0.0635)
			(type default)
		)
		(layer "F.Cu")
	)
	(gr_line
		(start 337.174332 -45.690028)
		(end 337.202272 -45.695616)
		(stroke
			(width 0.05715)
			(type default)
		)
		(layer "F.Cu")
	)
	(gr_line
		(start 337.185 -13.092938)
		(end 337.274662 -13.1826)
		(stroke
			(width 0.0635)
			(type default)
		)
		(layer "F.Cu")
	)
	(gr_line
		(start 337.196684 -54.2163)
		(end 337.209892 -54.21884)
		(stroke
			(width 0.05715)
			(type default)
		)
		(layer "F.Cu")
	)
	(gr_line
		(start 337.199732 -79.182214)
		(end 337.345782 -79.243174)
		(stroke
			(width 0.05715)
			(type default)
		)
		(layer "F.Cu")
	)
	(gr_line
		(start 337.209892 -54.21884)
		(end 337.2231 -54.2163)
		(stroke
			(width 0.05715)
			(type default)
		)
		(layer "F.Cu")
	)
	(gr_line
		(start 337.222846 -46.704758)
		(end 337.250024 -46.695868)
		(stroke
			(width 0.05715)
			(type default)
		)
		(layer "F.Cu")
	)
	(gr_line
		(start 337.250024 -46.695868)
		(end 337.277964 -46.701456)
		(stroke
			(width 0.05715)
			(type default)
		)
		(layer "F.Cu")
	)
	(gr_line
		(start 337.274662 -13.1826)
		(end 337.947 -13.1826)
		(stroke
			(width 0.0635)
			(type default)
		)
		(layer "F.Cu")
	)
	(gr_line
		(start 337.293712 -120.84685)
		(end 337.404202 -120.95734)
		(stroke
			(width 0.05715)
			(type default)
		)
		(layer "F.Cu")
	)
	(gr_line
		(start 337.293712 -120.501918)
		(end 337.429602 -120.366028)
		(stroke
			(width 0.05715)
			(type default)
		)
		(layer "F.Cu")
	)
	(gr_line
		(start 337.301332 -47.711106)
		(end 337.32851 -47.702216)
		(stroke
			(width 0.05715)
			(type default)
		)
		(layer "F.Cu")
	)
	(gr_line
		(start 337.310984 -13.97)
		(end 337.947 -13.97)
		(stroke
			(width 0.0635)
			(type default)
		)
		(layer "F.Cu")
	)
	(gr_line
		(start 337.32851 -47.702216)
		(end 337.35645 -47.707804)
		(stroke
			(width 0.05715)
			(type default)
		)
		(layer "F.Cu")
	)
	(gr_line
		(start 337.368388 -48.720248)
		(end 337.395566 -48.711358)
		(stroke
			(width 0.05715)
			(type default)
		)
		(layer "F.Cu")
	)
	(gr_line
		(start 337.381088 -91.804998)
		(end 337.399122 -91.80068)
		(stroke
			(width 0.05715)
			(type default)
		)
		(layer "F.Cu")
	)
	(gr_line
		(start 337.393788 -90.789506)
		(end 337.408266 -90.786458)
		(stroke
			(width 0.05715)
			(type default)
		)
		(layer "F.Cu")
	)
	(gr_line
		(start 337.395566 -48.711358)
		(end 337.423506 -48.716946)
		(stroke
			(width 0.05715)
			(type default)
		)
		(layer "F.Cu")
	)
	(gr_line
		(start 337.399122 -91.80068)
		(end 337.41741 -91.804236)
		(stroke
			(width 0.05715)
			(type default)
		)
		(layer "F.Cu")
	)
	(gr_line
		(start 337.404202 -120.95734)
		(end 337.404202 -121.282968)
		(stroke
			(width 0.05715)
			(type default)
		)
		(layer "F.Cu")
	)
	(gr_line
		(start 337.408266 -90.786458)
		(end 337.422744 -90.789252)
		(stroke
			(width 0.05715)
			(type default)
		)
		(layer "F.Cu")
	)
	(gr_line
		(start 337.429602 -120.038368)
		(end 337.429602 -120.366028)
		(stroke
			(width 0.05715)
			(type default)
		)
		(layer "F.Cu")
	)
	(gr_line
		(start 337.450684 -49.732692)
		(end 337.478624 -49.723548)
		(stroke
			(width 0.05715)
			(type default)
		)
		(layer "F.Cu")
	)
	(gr_line
		(start 337.478624 -49.723548)
		(end 337.507326 -49.729136)
		(stroke
			(width 0.05715)
			(type default)
		)
		(layer "F.Cu")
	)
	(gr_line
		(start 337.505548 -89.760298)
		(end 337.520026 -89.75725)
		(stroke
			(width 0.05715)
			(type default)
		)
		(layer "F.Cu")
	)
	(gr_line
		(start 337.520026 -89.75725)
		(end 337.534504 -89.760044)
		(stroke
			(width 0.05715)
			(type default)
		)
		(layer "F.Cu")
	)
	(gr_line
		(start 337.549744 -50.737516)
		(end 337.577684 -50.728626)
		(stroke
			(width 0.05715)
			(type default)
		)
		(layer "F.Cu")
	)
	(gr_line
		(start 337.577684 -50.728626)
		(end 337.606386 -50.734468)
		(stroke
			(width 0.05715)
			(type default)
		)
		(layer "F.Cu")
	)
	(gr_line
		(start 337.614514 -81.576418)
		(end 337.643978 -81.566512)
		(stroke
			(width 0.05715)
			(type default)
		)
		(layer "F.Cu")
	)
	(gr_line
		(start 337.617816 -51.736752)
		(end 337.644994 -51.727862)
		(stroke
			(width 0.05715)
			(type default)
		)
		(layer "F.Cu")
	)
	(gr_line
		(start 337.643978 -81.566512)
		(end 337.673442 -81.572354)
		(stroke
			(width 0.05715)
			(type default)
		)
		(layer "F.Cu")
	)
	(gr_line
		(start 337.644994 -51.727862)
		(end 337.672934 -51.73345)
		(stroke
			(width 0.05715)
			(type default)
		)
		(layer "F.Cu")
	)
	(gr_line
		(start 337.672426 -119.211598)
		(end 338.333588 -119.211598)
		(stroke
			(width 0.05715)
			(type default)
		)
		(layer "F.Cu")
	)
	(gr_line
		(start 337.672426 -117.941598)
		(end 338.333588 -117.941598)
		(stroke
			(width 0.05715)
			(type default)
		)
		(layer "F.Cu")
	)
	(gr_line
		(start 337.858354 -79.034894)
		(end 337.89493 -79.019908)
		(stroke
			(width 0.05715)
			(type default)
		)
		(layer "F.Cu")
	)
	(gr_line
		(start 337.89493 -79.019908)
		(end 337.933792 -79.027782)
		(stroke
			(width 0.05715)
			(type default)
		)
		(layer "F.Cu")
	)
	(gr_line
		(start 337.947 -13.1826)
		(end 338.6201 -12.5095)
		(stroke
			(width 0.0635)
			(type default)
		)
		(layer "F.Cu")
	)
	(gr_line
		(start 337.956398 -82.6389)
		(end 337.984338 -82.629756)
		(stroke
			(width 0.05715)
			(type default)
		)
		(layer "F.Cu")
	)
	(gr_line
		(start 337.967066 -81.8769)
		(end 338.459826 -81.97469)
		(stroke
			(width 0.05715)
			(type default)
		)
		(layer "F.Cu")
	)
	(gr_line
		(start 337.983068 -81.631536)
		(end 338.11464 -81.543652)
		(stroke
			(width 0.05715)
			(type default)
		)
		(layer "F.Cu")
	)
	(gr_line
		(start 337.984338 -82.629756)
		(end 338.012786 -82.635344)
		(stroke
			(width 0.05715)
			(type default)
		)
		(layer "F.Cu")
	)
	(gr_line
		(start 337.999324 -83.658202)
		(end 338.02701 -83.649058)
		(stroke
			(width 0.05715)
			(type default)
		)
		(layer "F.Cu")
	)
	(gr_line
		(start 338.02701 -83.649058)
		(end 338.055712 -83.654646)
		(stroke
			(width 0.05715)
			(type default)
		)
		(layer "F.Cu")
	)
	(gr_line
		(start 338.11464 -81.543652)
		(end 338.450936 -81.610454)
		(stroke
			(width 0.05715)
			(type default)
		)
		(layer "F.Cu")
	)
	(gr_line
		(start 338.244434 -86.450932)
		(end 338.263738 -86.454996)
		(stroke
			(width 0.05715)
			(type default)
		)
		(layer "F.Cu")
	)
	(gr_line
		(start 338.263738 -86.454996)
		(end 338.283042 -86.450424)
		(stroke
			(width 0.05715)
			(type default)
		)
		(layer "F.Cu")
	)
	(gr_line
		(start 338.263738 -53.761894)
		(end 338.276946 -53.759354)
		(stroke
			(width 0.05715)
			(type default)
		)
		(layer "F.Cu")
	)
	(gr_line
		(start 338.276946 -53.759354)
		(end 338.290154 -53.761894)
		(stroke
			(width 0.05715)
			(type default)
		)
		(layer "F.Cu")
	)
	(gr_line
		(start 338.293202 -120.880632)
		(end 338.293202 -121.282968)
		(stroke
			(width 0.05715)
			(type default)
		)
		(layer "F.Cu")
	)
	(gr_line
		(start 338.293202 -120.880632)
		(end 338.39404 -120.779794)
		(stroke
			(width 0.05715)
			(type default)
		)
		(layer "F.Cu")
	)
	(gr_line
		(start 338.293964 -56.325516)
		(end 338.319618 -56.33085)
		(stroke
			(width 0.05715)
			(type default)
		)
		(layer "F.Cu")
	)
	(gr_line
		(start 338.318602 -120.359424)
		(end 338.39404 -120.434862)
		(stroke
			(width 0.05715)
			(type default)
		)
		(layer "F.Cu")
	)
	(gr_line
		(start 338.318602 -120.038368)
		(end 338.318602 -120.359424)
		(stroke
			(width 0.05715)
			(type default)
		)
		(layer "F.Cu")
	)
	(gr_line
		(start 338.319618 -56.33085)
		(end 338.344764 -56.323738)
		(stroke
			(width 0.05715)
			(type default)
		)
		(layer "F.Cu")
	)
	(gr_line
		(start 338.352384 -57.347358)
		(end 338.378038 -57.352692)
		(stroke
			(width 0.05715)
			(type default)
		)
		(layer "F.Cu")
	)
	(gr_line
		(start 338.378038 -57.352692)
		(end 338.403184 -57.34558)
		(stroke
			(width 0.05715)
			(type default)
		)
		(layer "F.Cu")
	)
	(gr_line
		(start 338.450936 -81.610454)
		(end 338.539074 -81.742026)
		(stroke
			(width 0.05715)
			(type default)
		)
		(layer "F.Cu")
	)
	(gr_line
		(start 338.4804 -110.49)
		(end 338.484972 -110.47095)
		(stroke
			(width 0.0635)
			(type default)
		)
		(layer "F.Cu")
	)
	(gr_line
		(start 338.4804 -110.49)
		(end 339.1154 -109.855)
		(stroke
			(width 0.0635)
			(type default)
		)
		(layer "F.Cu")
	)
	(gr_line
		(start 338.4804 -109.22)
		(end 338.484972 -109.20095)
		(stroke
			(width 0.0635)
			(type default)
		)
		(layer "F.Cu")
	)
	(gr_line
		(start 338.4804 -109.22)
		(end 339.1154 -108.585)
		(stroke
			(width 0.0635)
			(type default)
		)
		(layer "F.Cu")
	)
	(gr_line
		(start 338.6201 -12.5095)
		(end 340.614 -12.5095)
		(stroke
			(width 0.0635)
			(type default)
		)
		(layer "F.Cu")
	)
	(gr_line
		(start 338.791804 -91.308936)
		(end 338.805012 -91.311476)
		(stroke
			(width 0.05715)
			(type default)
		)
		(layer "F.Cu")
	)
	(gr_line
		(start 338.805012 -91.311476)
		(end 338.81822 -91.308936)
		(stroke
			(width 0.05715)
			(type default)
		)
		(layer "F.Cu")
	)
	(gr_line
		(start 338.91982 -90.283284)
		(end 338.933028 -90.285824)
		(stroke
			(width 0.05715)
			(type default)
		)
		(layer "F.Cu")
	)
	(gr_line
		(start 338.933028 -90.285824)
		(end 338.946236 -90.283284)
		(stroke
			(width 0.05715)
			(type default)
		)
		(layer "F.Cu")
	)
	(gr_line
		(start 339.077046 -46.3169)
		(end 339.089746 -46.31944)
		(stroke
			(width 0.05715)
			(type default)
		)
		(layer "F.Cu")
	)
	(gr_line
		(start 339.089492 -47.31004)
		(end 339.1027 -47.31258)
		(stroke
			(width 0.05715)
			(type default)
		)
		(layer "F.Cu")
	)
	(gr_line
		(start 339.089746 -46.31944)
		(end 339.102954 -46.3169)
		(stroke
			(width 0.05715)
			(type default)
		)
		(layer "F.Cu")
	)
	(gr_line
		(start 339.1027 -47.31258)
		(end 339.115908 -47.31004)
		(stroke
			(width 0.05715)
			(type default)
		)
		(layer "F.Cu")
	)
	(gr_line
		(start 339.123782 -118.780306)
		(end 339.222588 -118.879112)
		(stroke
			(width 0.05715)
			(type default)
		)
		(layer "F.Cu")
	)
	(gr_line
		(start 339.123782 -118.435374)
		(end 339.222588 -118.336568)
		(stroke
			(width 0.05715)
			(type default)
		)
		(layer "F.Cu")
	)
	(gr_line
		(start 339.141308 -48.3108)
		(end 339.153754 -48.31334)
		(stroke
			(width 0.05715)
			(type default)
		)
		(layer "F.Cu")
	)
	(gr_line
		(start 339.1535 -50.304446)
		(end 339.166708 -50.306986)
		(stroke
			(width 0.05715)
			(type default)
		)
		(layer "F.Cu")
	)
	(gr_line
		(start 339.153754 -48.31334)
		(end 339.166454 -48.3108)
		(stroke
			(width 0.05715)
			(type default)
		)
		(layer "F.Cu")
	)
	(gr_line
		(start 339.166708 -50.306986)
		(end 339.179916 -50.304446)
		(stroke
			(width 0.05715)
			(type default)
		)
		(layer "F.Cu")
	)
	(gr_line
		(start 339.178392 -49.3141)
		(end 339.1916 -49.31664)
		(stroke
			(width 0.05715)
			(type default)
		)
		(layer "F.Cu")
	)
	(gr_line
		(start 339.191346 -51.29784)
		(end 339.204554 -51.30038)
		(stroke
			(width 0.05715)
			(type default)
		)
		(layer "F.Cu")
	)
	(gr_line
		(start 339.1916 -49.31664)
		(end 339.204808 -49.3141)
		(stroke
			(width 0.05715)
			(type default)
		)
		(layer "F.Cu")
	)
	(gr_line
		(start 339.204554 -51.30038)
		(end 339.217762 -51.29784)
		(stroke
			(width 0.05715)
			(type default)
		)
		(layer "F.Cu")
	)
	(gr_line
		(start 339.222588 -118.879112)
		(end 339.222588 -119.211598)
		(stroke
			(width 0.05715)
			(type default)
		)
		(layer "F.Cu")
	)
	(gr_line
		(start 339.222588 -117.941598)
		(end 339.222588 -118.336568)
		(stroke
			(width 0.05715)
			(type default)
		)
		(layer "F.Cu")
	)
	(gr_line
		(start 339.241892 -52.29352)
		(end 339.2551 -52.29606)
		(stroke
			(width 0.05715)
			(type default)
		)
		(layer "F.Cu")
	)
	(gr_line
		(start 339.2551 -52.29606)
		(end 339.268308 -52.29352)
		(stroke
			(width 0.05715)
			(type default)
		)
		(layer "F.Cu")
	)
	(gr_line
		(start 339.306662 -79.54899)
		(end 339.34527 -79.55661)
		(stroke
			(width 0.05715)
			(type default)
		)
		(layer "F.Cu")
	)
	(gr_line
		(start 339.34527 -79.55661)
		(end 339.381592 -79.54137)
		(stroke
			(width 0.05715)
			(type default)
		)
		(layer "F.Cu")
	)
	(gr_line
		(start 339.40496 -77.91704)
		(end 339.86851 -77.91704)
		(stroke
			(width 0.05715)
			(type default)
		)
		(layer "F.Cu")
	)
	(gr_line
		(start 339.720174 -79.399384)
		(end 339.732112 -79.394304)
		(stroke
			(width 0.05715)
			(type default)
		)
		(layer "F.Cu")
	)
	(gr_line
		(start 339.841332 -82.249772)
		(end 339.86343 -82.25409)
		(stroke
			(width 0.05715)
			(type default)
		)
		(layer "F.Cu")
	)
	(gr_line
		(start 339.86343 -82.25409)
		(end 339.88502 -82.247994)
		(stroke
			(width 0.05715)
			(type default)
		)
		(layer "F.Cu")
	)
	(gr_line
		(start 339.86851 -77.91704)
		(end 339.930994 -77.979524)
		(stroke
			(width 0.05715)
			(type default)
		)
		(layer "F.Cu")
	)
	(gr_line
		(start 339.89518 -85.820758)
		(end 339.93709 -85.810852)
		(stroke
			(width 0.05715)
			(type default)
		)
		(layer "F.Cu")
	)
	(gr_line
		(start 339.93709 -85.810852)
		(end 339.977222 -85.827108)
		(stroke
			(width 0.05715)
			(type default)
		)
		(layer "F.Cu")
	)
	(gr_line
		(start 340.027768 -92.572586)
		(end 340.042246 -92.57538)
		(stroke
			(width 0.05715)
			(type default)
		)
		(layer "F.Cu")
	)
	(gr_line
		(start 340.042246 -92.57538)
		(end 340.056724 -92.572332)
		(stroke
			(width 0.05715)
			(type default)
		)
		(layer "F.Cu")
	)
	(gr_line
		(start 340.111588 -118.836694)
		(end 340.111588 -119.211598)
		(stroke
			(width 0.05715)
			(type default)
		)
		(layer "F.Cu")
	)
	(gr_line
		(start 340.111588 -118.836694)
		(end 340.271608 -118.676674)
		(stroke
			(width 0.05715)
			(type default)
		)
		(layer "F.Cu")
	)
	(gr_line
		(start 340.111588 -118.171722)
		(end 340.271608 -118.331742)
		(stroke
			(width 0.05715)
			(type default)
		)
		(layer "F.Cu")
	)
	(gr_line
		(start 340.111588 -117.941598)
		(end 340.111588 -118.171722)
		(stroke
			(width 0.05715)
			(type default)
		)
		(layer "F.Cu")
	)
	(gr_line
		(start 340.127082 -83.302348)
		(end 340.14918 -83.306666)
		(stroke
			(width 0.05715)
			(type default)
		)
		(layer "F.Cu")
	)
	(gr_line
		(start 340.14918 -83.306666)
		(end 340.170262 -83.300824)
		(stroke
			(width 0.05715)
			(type default)
		)
		(layer "F.Cu")
	)
	(gr_line
		(start 340.275926 -77.979524)
		(end 340.33841 -77.91704)
		(stroke
			(width 0.05715)
			(type default)
		)
		(layer "F.Cu")
	)
	(gr_line
		(start 340.308946 -54.41188)
		(end 340.322154 -54.40934)
		(stroke
			(width 0.05715)
			(type default)
		)
		(layer "F.Cu")
	)
	(gr_line
		(start 340.33841 -77.91704)
		(end 340.80196 -77.91704)
		(stroke
			(width 0.05715)
			(type default)
		)
		(layer "F.Cu")
	)
	(gr_line
		(start 340.472268 -82.96402)
		(end 340.549992 -82.826352)
		(stroke
			(width 0.05715)
			(type default)
		)
		(layer "F.Cu")
	)
	(gr_line
		(start 340.549992 -82.826352)
		(end 340.880446 -82.734658)
		(stroke
			(width 0.05715)
			(type default)
		)
		(layer "F.Cu")
	)
	(gr_line
		(start 340.568534 -83.190334)
		(end 341.051388 -83.056476)
		(stroke
			(width 0.05715)
			(type default)
		)
		(layer "F.Cu")
	)
	(gr_line
		(start 340.607396 -84.408264)
		(end 340.620604 -84.410804)
		(stroke
			(width 0.05715)
			(type default)
		)
		(layer "F.Cu")
	)
	(gr_line
		(start 340.614 -12.5095)
		(end 340.84514 -12.74064)
		(stroke
			(width 0.0635)
			(type default)
		)
		(layer "F.Cu")
	)
	(gr_line
		(start 340.620604 -84.410804)
		(end 340.633812 -84.408264)
		(stroke
			(width 0.05715)
			(type default)
		)
		(layer "F.Cu")
	)
	(gr_line
		(start 340.72957 -89.92616)
		(end 340.742016 -89.923874)
		(stroke
			(width 0.05715)
			(type default)
		)
		(layer "F.Cu")
	)
	(gr_line
		(start 340.742016 -89.923874)
		(end 340.753192 -89.916508)
		(stroke
			(width 0.05715)
			(type default)
		)
		(layer "F.Cu")
	)
	(gr_line
		(start 340.84514 -12.74064)
		(end 340.93277 -12.74064)
		(stroke
			(width 0.0635)
			(type default)
		)
		(layer "F.Cu")
	)
	(gr_line
		(start 340.880446 -82.734658)
		(end 341.01786 -82.812636)
		(stroke
			(width 0.05715)
			(type default)
		)
		(layer "F.Cu")
	)
	(gr_line
		(start 340.93277 -12.74064)
		(end 341.400638 -12.74064)
		(stroke
			(width 0.0635)
			(type default)
		)
		(layer "F.Cu")
	)
	(gr_line
		(start 341.211662 -81.880202)
		(end 341.261192 -81.866486)
		(stroke
			(width 0.05715)
			(type default)
		)
		(layer "F.Cu")
	)
	(gr_line
		(start 341.235792 -49.647094)
		(end 341.249 -49.644554)
		(stroke
			(width 0.05715)
			(type default)
		)
		(layer "F.Cu")
	)
	(gr_line
		(start 341.248492 -50.645314)
		(end 341.2617 -50.642774)
		(stroke
			(width 0.05715)
			(type default)
		)
		(layer "F.Cu")
	)
	(gr_line
		(start 341.248492 -48.659034)
		(end 341.2617 -48.656494)
		(stroke
			(width 0.05715)
			(type default)
		)
		(layer "F.Cu")
	)
	(gr_line
		(start 341.249 -49.644554)
		(end 341.262208 -49.647094)
		(stroke
			(width 0.05715)
			(type default)
		)
		(layer "F.Cu")
	)
	(gr_line
		(start 341.261192 -81.866486)
		(end 341.290656 -81.82483)
		(stroke
			(width 0.05715)
			(type default)
		)
		(layer "F.Cu")
	)
	(gr_line
		(start 341.2617 -50.642774)
		(end 341.274908 -50.645314)
		(stroke
			(width 0.05715)
			(type default)
		)
		(layer "F.Cu")
	)
	(gr_line
		(start 341.2617 -48.656494)
		(end 341.274908 -48.659034)
		(stroke
			(width 0.05715)
			(type default)
		)
		(layer "F.Cu")
	)
	(gr_line
		(start 341.273638 -47.643034)
		(end 341.286846 -47.640494)
		(stroke
			(width 0.05715)
			(type default)
		)
		(layer "F.Cu")
	)
	(gr_line
		(start 341.286592 -45.633894)
		(end 341.2998 -45.631354)
		(stroke
			(width 0.05715)
			(type default)
		)
		(layer "F.Cu")
	)
	(gr_line
		(start 341.286846 -47.640494)
		(end 341.300054 -47.643034)
		(stroke
			(width 0.05715)
			(type default)
		)
		(layer "F.Cu")
	)
	(gr_line
		(start 341.2871 -51.643534)
		(end 341.300308 -51.646074)
		(stroke
			(width 0.05715)
			(type default)
		)
		(layer "F.Cu")
	)
	(gr_line
		(start 341.299292 -46.627034)
		(end 341.3125 -46.624494)
		(stroke
			(width 0.05715)
			(type default)
		)
		(layer "F.Cu")
	)
	(gr_line
		(start 341.2998 -45.631354)
		(end 341.313008 -45.633894)
		(stroke
			(width 0.05715)
			(type default)
		)
		(layer "F.Cu")
	)
	(gr_line
		(start 341.3125 -46.624494)
		(end 341.325708 -46.627034)
		(stroke
			(width 0.05715)
			(type default)
		)
		(layer "F.Cu")
	)
	(gr_line
		(start 341.353394 -82.719418)
		(end 341.431118 -82.582004)
		(stroke
			(width 0.05715)
			(type default)
		)
		(layer "F.Cu")
	)
	(gr_line
		(start 341.400638 -12.74064)
		(end 342.2269 -13.566902)
		(stroke
			(width 0.0635)
			(type default)
		)
		(layer "F.Cu")
	)
	(gr_line
		(start 341.431118 -82.582004)
		(end 341.761572 -82.49031)
		(stroke
			(width 0.05715)
			(type default)
		)
		(layer "F.Cu")
	)
	(gr_line
		(start 341.449914 -82.945986)
		(end 341.934292 -82.81162)
		(stroke
			(width 0.05715)
			(type default)
		)
		(layer "F.Cu")
	)
	(gr_line
		(start 341.561674 -90.759788)
		(end 341.57412 -90.757502)
		(stroke
			(width 0.05715)
			(type default)
		)
		(layer "F.Cu")
	)
	(gr_line
		(start 341.57412 -90.757502)
		(end 341.585296 -90.750136)
		(stroke
			(width 0.05715)
			(type default)
		)
		(layer "F.Cu")
	)
	(gr_line
		(start 341.7189 -92.221558)
		(end 341.729568 -92.219526)
		(stroke
			(width 0.05715)
			(type default)
		)
		(layer "F.Cu")
	)
	(gr_line
		(start 341.729568 -92.219526)
		(end 341.738458 -92.21343)
		(stroke
			(width 0.05715)
			(type default)
		)
		(layer "F.Cu")
	)
	(gr_line
		(start 341.761572 -82.49031)
		(end 341.89924 -82.568034)
		(stroke
			(width 0.05715)
			(type default)
		)
		(layer "F.Cu")
	)
	(gr_line
		(start 341.927688 -80.927956)
		(end 341.93607 -80.916018)
		(stroke
			(width 0.05715)
			(type default)
		)
		(layer "F.Cu")
	)
	(gr_line
		(start 341.93607 -80.916018)
		(end 341.939372 -80.901794)
		(stroke
			(width 0.05715)
			(type default)
		)
		(layer "F.Cu")
	)
	(gr_line
		(start 341.99068 -79.58836)
		(end 341.9983 -79.555086)
		(stroke
			(width 0.05715)
			(type default)
		)
		(layer "F.Cu")
	)
	(gr_line
		(start 341.9983 -79.555086)
		(end 342.022684 -79.530448)
		(stroke
			(width 0.05715)
			(type default)
		)
		(layer "F.Cu")
	)
	(gr_line
		(start 342.086692 -53.810154)
		(end 342.0999 -53.807614)
		(stroke
			(width 0.05715)
			(type default)
		)
		(layer "F.Cu")
	)
	(gr_line
		(start 342.0999 -53.807614)
		(end 342.113108 -53.810154)
		(stroke
			(width 0.05715)
			(type default)
		)
		(layer "F.Cu")
	)
	(gr_line
		(start 342.263984 -54.9529)
		(end 342.287098 -54.946296)
		(stroke
			(width 0.05715)
			(type default)
		)
		(layer "F.Cu")
	)
	(gr_line
		(start 342.265 -79.28737)
		(end 342.310974 -79.241142)
		(stroke
			(width 0.05715)
			(type default)
		)
		(layer "F.Cu")
	)
	(gr_line
		(start 342.287098 -54.946296)
		(end 342.310466 -54.950868)
		(stroke
			(width 0.05715)
			(type default)
		)
		(layer "F.Cu")
	)
	(gr_line
		(start 342.301068 -77.91704)
		(end 342.714072 -77.91704)
		(stroke
			(width 0.05715)
			(type default)
		)
		(layer "F.Cu")
	)
	(gr_line
		(start 342.362028 -55.963312)
		(end 342.385142 -55.956708)
		(stroke
			(width 0.05715)
			(type default)
		)
		(layer "F.Cu")
	)
	(gr_line
		(start 342.385142 -55.956708)
		(end 342.40851 -55.96128)
		(stroke
			(width 0.05715)
			(type default)
		)
		(layer "F.Cu")
	)
	(gr_line
		(start 342.651842 -88.360504)
		(end 342.664288 -88.358218)
		(stroke
			(width 0.05715)
			(type default)
		)
		(layer "F.Cu")
	)
	(gr_line
		(start 342.69553 -87.192358)
		(end 342.730836 -87.206582)
		(stroke
			(width 0.05715)
			(type default)
		)
		(layer "F.Cu")
	)
	(gr_line
		(start 342.714072 -77.91704)
		(end 342.834214 -78.037182)
		(stroke
			(width 0.05715)
			(type default)
		)
		(layer "F.Cu")
	)
	(gr_line
		(start 342.730836 -87.206582)
		(end 342.767666 -87.199216)
		(stroke
			(width 0.05715)
			(type default)
		)
		(layer "F.Cu")
	)
	(gr_line
		(start 342.772746 -89.668096)
		(end 342.783922 -89.66073)
		(stroke
			(width 0.05715)
			(type default)
		)
		(layer "F.Cu")
	)
	(gr_line
		(start 342.783922 -89.66073)
		(end 342.796368 -89.658444)
		(stroke
			(width 0.05715)
			(type default)
		)
		(layer "F.Cu")
	)
	(gr_line
		(start 342.998552 -82.516218)
		(end 343.079832 -82.493612)
		(stroke
			(width 0.05715)
			(type default)
		)
		(layer "F.Cu")
	)
	(gr_line
		(start 343.048336 -83.675728)
		(end 343.135966 -83.544156)
		(stroke
			(width 0.05715)
			(type default)
		)
		(layer "F.Cu")
	)
	(gr_line
		(start 343.079832 -82.493612)
		(end 343.111582 -82.415634)
		(stroke
			(width 0.05715)
			(type default)
		)
		(layer "F.Cu")
	)
	(gr_line
		(start 343.092532 -86.885526)
		(end 343.180416 -86.753954)
		(stroke
			(width 0.05715)
			(type default)
		)
		(layer "F.Cu")
	)
	(gr_line
		(start 343.128092 -83.908646)
		(end 343.619836 -83.810094)
		(stroke
			(width 0.05715)
			(type default)
		)
		(layer "F.Cu")
	)
	(gr_line
		(start 343.135966 -83.544156)
		(end 343.472262 -83.476846)
		(stroke
			(width 0.05715)
			(type default)
		)
		(layer "F.Cu")
	)
	(gr_line
		(start 343.170764 -87.118698)
		(end 343.665048 -87.019638)
		(stroke
			(width 0.05715)
			(type default)
		)
		(layer "F.Cu")
	)
	(gr_line
		(start 343.179146 -78.037182)
		(end 343.299288 -77.91704)
		(stroke
			(width 0.05715)
			(type default)
		)
		(layer "F.Cu")
	)
	(gr_line
		(start 343.180416 -86.753954)
		(end 343.516712 -86.686644)
		(stroke
			(width 0.05715)
			(type default)
		)
		(layer "F.Cu")
	)
	(gr_line
		(start 343.231724 -81.1784)
		(end 343.293192 -81.324196)
		(stroke
			(width 0.05715)
			(type default)
		)
		(layer "F.Cu")
	)
	(gr_line
		(start 343.231724 -81.1784)
		(end 343.36101 -80.8609)
		(stroke
			(width 0.05715)
			(type default)
		)
		(layer "F.Cu")
	)
	(gr_line
		(start 343.299288 -77.91704)
		(end 343.698068 -77.91704)
		(stroke
			(width 0.05715)
			(type default)
		)
		(layer "F.Cu")
	)
	(gr_line
		(start 343.36101 -80.8609)
		(end 343.50706 -80.799432)
		(stroke
			(width 0.05715)
			(type default)
		)
		(layer "F.Cu")
	)
	(gr_line
		(start 343.472262 -83.476846)
		(end 343.603834 -83.564476)
		(stroke
			(width 0.05715)
			(type default)
		)
		(layer "F.Cu")
	)
	(gr_line
		(start 343.516712 -86.686644)
		(end 343.648284 -86.774528)
		(stroke
			(width 0.05715)
			(type default)
		)
		(layer "F.Cu")
	)
	(gr_line
		(start 343.5223 -49.35474)
		(end 343.535508 -49.3522)
		(stroke
			(width 0.05715)
			(type default)
		)
		(layer "F.Cu")
	)
	(gr_line
		(start 343.53119 -81.386426)
		(end 343.720674 -80.920844)
		(stroke
			(width 0.05715)
			(type default)
		)
		(layer "F.Cu")
	)
	(gr_line
		(start 343.535 -50.34788)
		(end 343.548208 -50.34534)
		(stroke
			(width 0.05715)
			(type default)
		)
		(layer "F.Cu")
	)
	(gr_line
		(start 343.5731 -51.35118)
		(end 343.586308 -51.34864)
		(stroke
			(width 0.05715)
			(type default)
		)
		(layer "F.Cu")
	)
	(gr_line
		(start 343.585292 -48.34636)
		(end 343.5985 -48.3489)
		(stroke
			(width 0.05715)
			(type default)
		)
		(layer "F.Cu")
	)
	(gr_line
		(start 343.5985 -52.35194)
		(end 343.611708 -52.3494)
		(stroke
			(width 0.05715)
			(type default)
		)
		(layer "F.Cu")
	)
	(gr_line
		(start 343.5985 -48.3489)
		(end 343.611708 -48.34636)
		(stroke
			(width 0.05715)
			(type default)
		)
		(layer "F.Cu")
	)
	(gr_line
		(start 343.6239 -46.3423)
		(end 343.637108 -46.33976)
		(stroke
			(width 0.05715)
			(type default)
		)
		(layer "F.Cu")
	)
	(gr_line
		(start 343.633552 -80.494886)
		(end 343.639394 -80.480662)
		(stroke
			(width 0.05715)
			(type default)
		)
		(layer "F.Cu")
	)
	(gr_line
		(start 343.6874 -47.3456)
		(end 343.700608 -47.34306)
		(stroke
			(width 0.05715)
			(type default)
		)
		(layer "F.Cu")
	)
	(gr_line
		(start 343.708736 -90.61069)
		(end 343.72169 -90.602054)
		(stroke
			(width 0.05715)
			(type default)
		)
		(layer "F.Cu")
	)
	(gr_line
		(start 343.72169 -90.602054)
		(end 343.736676 -90.59926)
		(stroke
			(width 0.05715)
			(type default)
		)
		(layer "F.Cu")
	)
	(gr_line
		(start 343.88806 -66.380106)
		(end 343.903046 -66.377058)
		(stroke
			(width 0.05715)
			(type default)
		)
		(layer "F.Cu")
	)
	(gr_line
		(start 343.902538 -80.05572)
		(end 343.902538 -80.214216)
		(stroke
			(width 0.05715)
			(type default)
		)
		(layer "F.Cu")
	)
	(gr_line
		(start 343.902538 -80.05572)
		(end 344.145108 -79.813404)
		(stroke
			(width 0.05715)
			(type default)
		)
		(layer "F.Cu")
	)
	(gr_line
		(start 343.903046 -66.377058)
		(end 343.918032 -66.379852)
		(stroke
			(width 0.05715)
			(type default)
		)
		(layer "F.Cu")
	)
	(gr_line
		(start 343.944702 -83.49615)
		(end 344.032586 -83.364578)
		(stroke
			(width 0.05715)
			(type default)
		)
		(layer "F.Cu")
	)
	(gr_line
		(start 343.944956 -65.375028)
		(end 343.96045 -65.371726)
		(stroke
			(width 0.05715)
			(type default)
		)
		(layer "F.Cu")
	)
	(gr_line
		(start 343.948766 -62.376812)
		(end 343.96426 -62.37351)
		(stroke
			(width 0.05715)
			(type default)
		)
		(layer "F.Cu")
	)
	(gr_line
		(start 343.95029 -64.3763)
		(end 343.965784 -64.372998)
		(stroke
			(width 0.05715)
			(type default)
		)
		(layer "F.Cu")
	)
	(gr_line
		(start 343.95537 -63.377826)
		(end 343.970864 -63.374524)
		(stroke
			(width 0.05715)
			(type default)
		)
		(layer "F.Cu")
	)
	(gr_line
		(start 343.96045 -65.371726)
		(end 343.976452 -65.375028)
		(stroke
			(width 0.05715)
			(type default)
		)
		(layer "F.Cu")
	)
	(gr_line
		(start 343.960958 -61.353954)
		(end 343.976452 -61.350652)
		(stroke
			(width 0.05715)
			(type default)
		)
		(layer "F.Cu")
	)
	(gr_line
		(start 343.96426 -62.37351)
		(end 343.980262 -62.376812)
		(stroke
			(width 0.05715)
			(type default)
		)
		(layer "F.Cu")
	)
	(gr_line
		(start 343.965784 -64.372998)
		(end 343.981786 -64.3763)
		(stroke
			(width 0.05715)
			(type default)
		)
		(layer "F.Cu")
	)
	(gr_line
		(start 343.970864 -63.374524)
		(end 343.986866 -63.377826)
		(stroke
			(width 0.05715)
			(type default)
		)
		(layer "F.Cu")
	)
	(gr_line
		(start 343.976452 -61.350652)
		(end 343.992454 -61.353954)
		(stroke
			(width 0.05715)
			(type default)
		)
		(layer "F.Cu")
	)
	(gr_line
		(start 343.989152 -86.706202)
		(end 344.077036 -86.57463)
		(stroke
			(width 0.05715)
			(type default)
		)
		(layer "F.Cu")
	)
	(gr_line
		(start 344.022934 -83.729322)
		(end 344.51671 -83.630516)
		(stroke
			(width 0.05715)
			(type default)
		)
		(layer "F.Cu")
	)
	(gr_line
		(start 344.032586 -83.364578)
		(end 344.368882 -83.297268)
		(stroke
			(width 0.05715)
			(type default)
		)
		(layer "F.Cu")
	)
	(gr_line
		(start 344.066622 -86.939628)
		(end 344.56243 -86.840314)
		(stroke
			(width 0.05715)
			(type default)
		)
		(layer "F.Cu")
	)
	(gr_line
		(start 344.077036 -86.57463)
		(end 344.413332 -86.50732)
		(stroke
			(width 0.05715)
			(type default)
		)
		(layer "F.Cu")
	)
	(gr_line
		(start 344.145108 -79.813404)
		(end 344.30335 -79.813404)
		(stroke
			(width 0.05715)
			(type default)
		)
		(layer "F.Cu")
	)
	(gr_line
		(start 344.245692 -80.215994)
		(end 344.305128 -80.156558)
		(stroke
			(width 0.05715)
			(type default)
		)
		(layer "F.Cu")
	)
	(gr_line
		(start 344.368882 -83.297268)
		(end 344.5002 -83.384898)
		(stroke
			(width 0.05715)
			(type default)
		)
		(layer "F.Cu")
	)
	(gr_line
		(start 344.413332 -86.50732)
		(end 344.544904 -86.595204)
		(stroke
			(width 0.05715)
			(type default)
		)
		(layer "F.Cu")
	)
	(gr_line
		(start 344.497914 -89.317576)
		(end 344.511122 -89.315036)
		(stroke
			(width 0.05715)
			(type default)
		)
		(layer "F.Cu")
	)
	(gr_line
		(start 344.511122 -89.315036)
		(end 344.52433 -89.317576)
		(stroke
			(width 0.05715)
			(type default)
		)
		(layer "F.Cu")
	)
	(gr_line
		(start 344.566748 -90.433652)
		(end 344.579956 -90.431112)
		(stroke
			(width 0.05715)
			(type default)
		)
		(layer "F.Cu")
	)
	(gr_line
		(start 344.579956 -90.431112)
		(end 344.593164 -90.433652)
		(stroke
			(width 0.05715)
			(type default)
		)
		(layer "F.Cu")
	)
	(gr_line
		(start 344.69578 -87.951564)
		(end 344.708988 -87.949024)
		(stroke
			(width 0.05715)
			(type default)
		)
		(layer "F.Cu")
	)
	(gr_line
		(start 344.708988 -87.949024)
		(end 344.722196 -87.951564)
		(stroke
			(width 0.05715)
			(type default)
		)
		(layer "F.Cu")
	)
	(gr_line
		(start 344.728546 -54.57952)
		(end 344.742516 -54.582314)
		(stroke
			(width 0.05715)
			(type default)
		)
		(layer "F.Cu")
	)
	(gr_line
		(start 344.742516 -54.582314)
		(end 344.757248 -54.579266)
		(stroke
			(width 0.05715)
			(type default)
		)
		(layer "F.Cu")
	)
	(gr_line
		(start 344.74531 -65.785492)
		(end 344.762582 -65.789048)
		(stroke
			(width 0.05715)
			(type default)
		)
		(layer "F.Cu")
	)
	(gr_line
		(start 344.745818 -64.785748)
		(end 344.76309 -64.789304)
		(stroke
			(width 0.05715)
			(type default)
		)
		(layer "F.Cu")
	)
	(gr_line
		(start 344.745818 -63.786004)
		(end 344.76309 -63.78956)
		(stroke
			(width 0.05715)
			(type default)
		)
		(layer "F.Cu")
	)
	(gr_line
		(start 344.750644 -61.761878)
		(end 344.767916 -61.765434)
		(stroke
			(width 0.05715)
			(type default)
		)
		(layer "F.Cu")
	)
	(gr_line
		(start 344.750898 -66.78549)
		(end 344.76309 -66.787776)
		(stroke
			(width 0.05715)
			(type default)
		)
		(layer "F.Cu")
	)
	(gr_line
		(start 344.750898 -62.78753)
		(end 344.76817 -62.791086)
		(stroke
			(width 0.05715)
			(type default)
		)
		(layer "F.Cu")
	)
	(gr_line
		(start 344.762582 -65.789048)
		(end 344.779854 -65.785492)
		(stroke
			(width 0.05715)
			(type default)
		)
		(layer "F.Cu")
	)
	(gr_line
		(start 344.76309 -66.788792)
		(end 344.780108 -66.785236)
		(stroke
			(width 0.05715)
			(type default)
		)
		(layer "F.Cu")
	)
	(gr_line
		(start 344.76309 -66.787776)
		(end 344.76309 -66.788792)
		(stroke
			(width 0.05715)
			(type default)
		)
		(layer "F.Cu")
	)
	(gr_line
		(start 344.76309 -64.789304)
		(end 344.780362 -64.785748)
		(stroke
			(width 0.05715)
			(type default)
		)
		(layer "F.Cu")
	)
	(gr_line
		(start 344.76309 -63.78956)
		(end 344.780362 -63.786004)
		(stroke
			(width 0.05715)
			(type default)
		)
		(layer "F.Cu")
	)
	(gr_line
		(start 344.767916 -61.765434)
		(end 344.785188 -61.761878)
		(stroke
			(width 0.05715)
			(type default)
		)
		(layer "F.Cu")
	)
	(gr_line
		(start 344.76817 -62.791086)
		(end 344.785442 -62.78753)
		(stroke
			(width 0.05715)
			(type default)
		)
		(layer "F.Cu")
	)
	(gr_line
		(start 344.841576 -83.316572)
		(end 344.929206 -83.185)
		(stroke
			(width 0.05715)
			(type default)
		)
		(layer "F.Cu")
	)
	(gr_line
		(start 344.92184 -83.549236)
		(end 345.413076 -83.450938)
		(stroke
			(width 0.05715)
			(type default)
		)
		(layer "F.Cu")
	)
	(gr_line
		(start 344.929206 -83.185)
		(end 345.265248 -83.11769)
		(stroke
			(width 0.05715)
			(type default)
		)
		(layer "F.Cu")
	)
	(gr_line
		(start 345.070176 -77.89926)
		(end 345.533726 -77.89926)
		(stroke
			(width 0.05715)
			(type default)
		)
		(layer "F.Cu")
	)
	(gr_line
		(start 345.265248 -83.11769)
		(end 345.39682 -83.20532)
		(stroke
			(width 0.05715)
			(type default)
		)
		(layer "F.Cu")
	)
	(gr_line
		(start 345.490292 -86.408514)
		(end 345.5035 -86.405974)
		(stroke
			(width 0.05715)
			(type default)
		)
		(layer "F.Cu")
	)
	(gr_line
		(start 345.492832 -116.958872)
		(end 345.519502 -116.958872)
		(stroke
			(width 0.05715)
			(type default)
		)
		(layer "F.Cu")
	)
	(gr_line
		(start 345.5035 -86.405974)
		(end 345.516708 -86.408514)
		(stroke
			(width 0.05715)
			(type default)
		)
		(layer "F.Cu")
	)
	(gr_line
		(start 345.533726 -77.89926)
		(end 345.59621 -77.961744)
		(stroke
			(width 0.05715)
			(type default)
		)
		(layer "F.Cu")
	)
	(gr_line
		(start 345.731592 -117.088158)
		(end 345.758262 -117.088158)
		(stroke
			(width 0.05715)
			(type default)
		)
		(layer "F.Cu")
	)
	(gr_line
		(start 345.738196 -83.136994)
		(end 345.825572 -83.005422)
		(stroke
			(width 0.05715)
			(type default)
		)
		(layer "F.Cu")
	)
	(gr_line
		(start 345.817698 -83.369912)
		(end 346.309442 -83.27136)
		(stroke
			(width 0.05715)
			(type default)
		)
		(layer "F.Cu")
	)
	(gr_line
		(start 345.825572 -83.005422)
		(end 346.161868 -82.938112)
		(stroke
			(width 0.05715)
			(type default)
		)
		(layer "F.Cu")
	)
	(gr_line
		(start 345.941142 -77.961744)
		(end 346.003626 -77.89926)
		(stroke
			(width 0.05715)
			(type default)
		)
		(layer "F.Cu")
	)
	(gr_line
		(start 345.980258 -61.260736)
		(end 345.99753 -61.25718)
		(stroke
			(width 0.05715)
			(type default)
		)
		(layer "F.Cu")
	)
	(gr_line
		(start 345.987878 -65.28181)
		(end 346.00515 -65.278254)
		(stroke
			(width 0.05715)
			(type default)
		)
		(layer "F.Cu")
	)
	(gr_line
		(start 345.988386 -66.281554)
		(end 346.005658 -66.277998)
		(stroke
			(width 0.05715)
			(type default)
		)
		(layer "F.Cu")
	)
	(gr_line
		(start 345.988386 -64.281812)
		(end 346.005658 -64.278256)
		(stroke
			(width 0.05715)
			(type default)
		)
		(layer "F.Cu")
	)
	(gr_line
		(start 345.988386 -63.282322)
		(end 346.005658 -63.278766)
		(stroke
			(width 0.05715)
			(type default)
		)
		(layer "F.Cu")
	)
	(gr_line
		(start 345.993212 -62.283594)
		(end 346.010484 -62.280038)
		(stroke
			(width 0.05715)
			(type default)
		)
		(layer "F.Cu")
	)
	(gr_line
		(start 345.99753 -61.25718)
		(end 346.014802 -61.260736)
		(stroke
			(width 0.05715)
			(type default)
		)
		(layer "F.Cu")
	)
	(gr_line
		(start 346.003626 -77.89926)
		(end 346.467176 -77.89926)
		(stroke
			(width 0.05715)
			(type default)
		)
		(layer "F.Cu")
	)
	(gr_line
		(start 346.00515 -65.278254)
		(end 346.022422 -65.28181)
		(stroke
			(width 0.05715)
			(type default)
		)
		(layer "F.Cu")
	)
	(gr_line
		(start 346.005658 -66.277998)
		(end 346.02293 -66.281554)
		(stroke
			(width 0.05715)
			(type default)
		)
		(layer "F.Cu")
	)
	(gr_line
		(start 346.005658 -64.278256)
		(end 346.02293 -64.281812)
		(stroke
			(width 0.05715)
			(type default)
		)
		(layer "F.Cu")
	)
	(gr_line
		(start 346.005658 -63.278766)
		(end 346.02293 -63.282322)
		(stroke
			(width 0.05715)
			(type default)
		)
		(layer "F.Cu")
	)
	(gr_line
		(start 346.010484 -62.280038)
		(end 346.027756 -62.283594)
		(stroke
			(width 0.05715)
			(type default)
		)
		(layer "F.Cu")
	)
	(gr_line
		(start 346.138246 -88.4809)
		(end 346.151454 -88.48344)
		(stroke
			(width 0.05715)
			(type default)
		)
		(layer "F.Cu")
	)
	(gr_line
		(start 346.151454 -88.48344)
		(end 346.164662 -88.4809)
		(stroke
			(width 0.05715)
			(type default)
		)
		(layer "F.Cu")
	)
	(gr_line
		(start 346.161868 -82.938112)
		(end 346.29344 -83.025742)
		(stroke
			(width 0.05715)
			(type default)
		)
		(layer "F.Cu")
	)
	(gr_line
		(start 347.156024 -61.750448)
		(end 347.173296 -61.754004)
		(stroke
			(width 0.05715)
			(type default)
		)
		(layer "F.Cu")
	)
	(gr_line
		(start 347.164406 -66.771012)
		(end 347.181678 -66.774568)
		(stroke
			(width 0.05715)
			(type default)
		)
		(layer "F.Cu")
	)
	(gr_line
		(start 347.164406 -65.771268)
		(end 347.181678 -65.774824)
		(stroke
			(width 0.05715)
			(type default)
		)
		(layer "F.Cu")
	)
	(gr_line
		(start 347.164406 -63.77178)
		(end 347.181678 -63.775336)
		(stroke
			(width 0.05715)
			(type default)
		)
		(layer "F.Cu")
	)
	(gr_line
		(start 347.169232 -62.773306)
		(end 347.186504 -62.776862)
		(stroke
			(width 0.05715)
			(type default)
		)
		(layer "F.Cu")
	)
	(gr_line
		(start 347.173296 -61.754004)
		(end 347.190568 -61.750448)
		(stroke
			(width 0.05715)
			(type default)
		)
		(layer "F.Cu")
	)
	(gr_line
		(start 347.181678 -66.774568)
		(end 347.19895 -66.771012)
		(stroke
			(width 0.05715)
			(type default)
		)
		(layer "F.Cu")
	)
	(gr_line
		(start 347.181678 -65.774824)
		(end 347.19895 -65.771268)
		(stroke
			(width 0.05715)
			(type default)
		)
		(layer "F.Cu")
	)
	(gr_line
		(start 347.181678 -63.775336)
		(end 347.19895 -63.77178)
		(stroke
			(width 0.05715)
			(type default)
		)
		(layer "F.Cu")
	)
	(gr_line
		(start 347.184472 -64.775588)
		(end 347.201744 -64.779144)
		(stroke
			(width 0.05715)
			(type default)
		)
		(layer "F.Cu")
	)
	(gr_line
		(start 347.186504 -62.776862)
		(end 347.203776 -62.773306)
		(stroke
			(width 0.05715)
			(type default)
		)
		(layer "F.Cu")
	)
	(gr_line
		(start 347.201744 -64.779144)
		(end 347.219016 -64.775588)
		(stroke
			(width 0.05715)
			(type default)
		)
		(layer "F.Cu")
	)
	(gr_line
		(start 347.277436 -87.006938)
		(end 347.290644 -87.009478)
		(stroke
			(width 0.05715)
			(type default)
		)
		(layer "F.Cu")
	)
	(gr_line
		(start 347.290644 -87.009478)
		(end 347.303852 -87.006938)
		(stroke
			(width 0.05715)
			(type default)
		)
		(layer "F.Cu")
	)
	(gr_line
		(start 347.58249 -51.309016)
		(end 347.595698 -51.311556)
		(stroke
			(width 0.05715)
			(type default)
		)
		(layer "F.Cu")
	)
	(gr_line
		(start 347.5863 -49.291494)
		(end 347.599508 -49.294034)
		(stroke
			(width 0.05715)
			(type default)
		)
		(layer "F.Cu")
	)
	(gr_line
		(start 347.599 -48.293274)
		(end 347.612208 -48.295814)
		(stroke
			(width 0.05715)
			(type default)
		)
		(layer "F.Cu")
	)
	(gr_line
		(start 347.6244 -50.294794)
		(end 347.637608 -50.297334)
		(stroke
			(width 0.05715)
			(type default)
		)
		(layer "F.Cu")
	)
	(gr_line
		(start 347.6244 -47.297594)
		(end 347.637608 -47.300134)
		(stroke
			(width 0.05715)
			(type default)
		)
		(layer "F.Cu")
	)
	(gr_line
		(start 347.694758 -46.29785)
		(end 347.707966 -46.29531)
		(stroke
			(width 0.05715)
			(type default)
		)
		(layer "F.Cu")
	)
	(gr_line
		(start 347.7006 -45.280834)
		(end 347.713808 -45.283374)
		(stroke
			(width 0.05715)
			(type default)
		)
		(layer "F.Cu")
	)
	(gr_line
		(start 347.707966 -46.29531)
		(end 347.721174 -46.29785)
		(stroke
			(width 0.05715)
			(type default)
		)
		(layer "F.Cu")
	)
	(gr_line
		(start 347.81236 -78.01102)
		(end 348.27591 -78.01102)
		(stroke
			(width 0.05715)
			(type default)
		)
		(layer "F.Cu")
	)
	(gr_line
		(start 347.921834 -56.317134)
		(end 347.936312 -56.319928)
		(stroke
			(width 0.05715)
			(type default)
		)
		(layer "F.Cu")
	)
	(gr_line
		(start 347.936312 -56.319928)
		(end 347.951298 -56.31688)
		(stroke
			(width 0.05715)
			(type default)
		)
		(layer "F.Cu")
	)
	(gr_line
		(start 347.942408 -82.943954)
		(end 347.954854 -82.941668)
		(stroke
			(width 0.05715)
			(type default)
		)
		(layer "F.Cu")
	)
	(gr_line
		(start 347.954854 -82.941668)
		(end 347.96603 -82.934302)
		(stroke
			(width 0.05715)
			(type default)
		)
		(layer "F.Cu")
	)
	(gr_line
		(start 347.960442 -86.875366)
		(end 347.972888 -86.87308)
		(stroke
			(width 0.05715)
			(type default)
		)
		(layer "F.Cu")
	)
	(gr_line
		(start 347.972888 -86.87308)
		(end 347.984064 -86.865714)
		(stroke
			(width 0.05715)
			(type default)
		)
		(layer "F.Cu")
	)
	(gr_line
		(start 348.27591 -78.01102)
		(end 348.338394 -78.073504)
		(stroke
			(width 0.05715)
			(type default)
		)
		(layer "F.Cu")
	)
	(gr_line
		(start 348.39021 -78.95209)
		(end 348.40164 -78.97368)
		(stroke
			(width 0.05715)
			(type default)
		)
		(layer "F.Cu")
	)
	(gr_line
		(start 348.406466 -66.26733)
		(end 348.423738 -66.263774)
		(stroke
			(width 0.05715)
			(type default)
		)
		(layer "F.Cu")
	)
	(gr_line
		(start 348.410276 -61.243718)
		(end 348.427548 -61.240162)
		(stroke
			(width 0.05715)
			(type default)
		)
		(layer "F.Cu")
	)
	(gr_line
		(start 348.41053 -62.26937)
		(end 348.427802 -62.265814)
		(stroke
			(width 0.05715)
			(type default)
		)
		(layer "F.Cu")
	)
	(gr_line
		(start 348.415864 -63.266066)
		(end 348.433136 -63.26251)
		(stroke
			(width 0.05715)
			(type default)
		)
		(layer "F.Cu")
	)
	(gr_line
		(start 348.418658 -65.265046)
		(end 348.436184 -65.26149)
		(stroke
			(width 0.05715)
			(type default)
		)
		(layer "F.Cu")
	)
	(gr_line
		(start 348.423738 -66.263774)
		(end 348.44101 -66.26733)
		(stroke
			(width 0.05715)
			(type default)
		)
		(layer "F.Cu")
	)
	(gr_line
		(start 348.426532 -64.271906)
		(end 348.443804 -64.26835)
		(stroke
			(width 0.05715)
			(type default)
		)
		(layer "F.Cu")
	)
	(gr_line
		(start 348.427548 -61.240162)
		(end 348.44482 -61.243718)
		(stroke
			(width 0.05715)
			(type default)
		)
		(layer "F.Cu")
	)
	(gr_line
		(start 348.427802 -62.265814)
		(end 348.445074 -62.26937)
		(stroke
			(width 0.05715)
			(type default)
		)
		(layer "F.Cu")
	)
	(gr_line
		(start 348.433136 -63.26251)
		(end 348.450408 -63.266066)
		(stroke
			(width 0.05715)
			(type default)
		)
		(layer "F.Cu")
	)
	(gr_line
		(start 348.436184 -65.26149)
		(end 348.453456 -65.265046)
		(stroke
			(width 0.05715)
			(type default)
		)
		(layer "F.Cu")
	)
	(gr_line
		(start 348.443804 -64.26835)
		(end 348.461076 -64.271906)
		(stroke
			(width 0.05715)
			(type default)
		)
		(layer "F.Cu")
	)
	(gr_line
		(start 348.44863 -91.451938)
		(end 348.461838 -91.454478)
		(stroke
			(width 0.05715)
			(type default)
		)
		(layer "F.Cu")
	)
	(gr_line
		(start 348.461838 -91.454478)
		(end 348.475046 -91.451938)
		(stroke
			(width 0.05715)
			(type default)
		)
		(layer "F.Cu")
	)
	(gr_line
		(start 348.683326 -78.073504)
		(end 348.74581 -78.01102)
		(stroke
			(width 0.05715)
			(type default)
		)
		(layer "F.Cu")
	)
	(gr_line
		(start 348.714822 -90.402664)
		(end 348.72803 -90.405204)
		(stroke
			(width 0.05715)
			(type default)
		)
		(layer "F.Cu")
	)
	(gr_line
		(start 348.72803 -90.405204)
		(end 348.741238 -90.402664)
		(stroke
			(width 0.05715)
			(type default)
		)
		(layer "F.Cu")
	)
	(gr_line
		(start 348.74581 -78.01102)
		(end 349.20936 -78.01102)
		(stroke
			(width 0.05715)
			(type default)
		)
		(layer "F.Cu")
	)
	(gr_line
		(start 348.755208 -87.962486)
		(end 348.819216 -87.949532)
		(stroke
			(width 0.05715)
			(type default)
		)
		(layer "F.Cu")
	)
	(gr_line
		(start 348.781624 -57.480708)
		(end 348.796102 -57.483502)
		(stroke
			(width 0.05715)
			(type default)
		)
		(layer "F.Cu")
	)
	(gr_line
		(start 348.796102 -57.483502)
		(end 348.81058 -57.480454)
		(stroke
			(width 0.05715)
			(type default)
		)
		(layer "F.Cu")
	)
	(gr_line
		(start 348.819216 -87.949532)
		(end 348.8563 -87.893906)
		(stroke
			(width 0.05715)
			(type default)
		)
		(layer "F.Cu")
	)
	(gr_line
		(start 349.0722 -82.196686)
		(end 349.12173 -82.163666)
		(stroke
			(width 0.05715)
			(type default)
		)
		(layer "F.Cu")
	)
	(gr_line
		(start 349.12173 -82.163666)
		(end 349.135954 -82.105246)
		(stroke
			(width 0.05715)
			(type default)
		)
		(layer "F.Cu")
	)
	(gr_line
		(start 349.183706 -86.967568)
		(end 349.192342 -86.954614)
		(stroke
			(width 0.05715)
			(type default)
		)
		(layer "F.Cu")
	)
	(gr_line
		(start 349.192342 -86.954614)
		(end 349.205296 -86.945978)
		(stroke
			(width 0.05715)
			(type default)
		)
		(layer "F.Cu")
	)
	(gr_line
		(start 349.418148 -85.618828)
		(end 349.429324 -85.611462)
		(stroke
			(width 0.05715)
			(type default)
		)
		(layer "F.Cu")
	)
	(gr_line
		(start 349.429324 -85.611462)
		(end 349.44177 -85.609176)
		(stroke
			(width 0.05715)
			(type default)
		)
		(layer "F.Cu")
	)
	(gr_line
		(start 349.484188 -80.51673)
		(end 349.51035 -80.566768)
		(stroke
			(width 0.05715)
			(type default)
		)
		(layer "F.Cu")
	)
	(gr_line
		(start 349.497142 -80.621378)
		(end 349.51035 -80.566768)
		(stroke
			(width 0.05715)
			(type default)
		)
		(layer "F.Cu")
	)
	(gr_line
		(start 349.505524 -62.74181)
		(end 349.522796 -62.745366)
		(stroke
			(width 0.05715)
			(type default)
		)
		(layer "F.Cu")
	)
	(gr_line
		(start 349.522796 -62.745366)
		(end 349.540068 -62.74181)
		(stroke
			(width 0.05715)
			(type default)
		)
		(layer "F.Cu")
	)
	(gr_line
		(start 349.582994 -61.732668)
		(end 349.600266 -61.736224)
		(stroke
			(width 0.05715)
			(type default)
		)
		(layer "F.Cu")
	)
	(gr_line
		(start 349.600266 -61.736224)
		(end 349.617538 -61.732668)
		(stroke
			(width 0.05715)
			(type default)
		)
		(layer "F.Cu")
	)
	(gr_line
		(start 349.622364 -64.765936)
		(end 349.639636 -64.769492)
		(stroke
			(width 0.05715)
			(type default)
		)
		(layer "F.Cu")
	)
	(gr_line
		(start 349.624904 -66.765932)
		(end 349.642176 -66.769488)
		(stroke
			(width 0.05715)
			(type default)
		)
		(layer "F.Cu")
	)
	(gr_line
		(start 349.632016 -63.76416)
		(end 349.649288 -63.767716)
		(stroke
			(width 0.05715)
			(type default)
		)
		(layer "F.Cu")
	)
	(gr_line
		(start 349.63481 -65.76314)
		(end 349.652082 -65.766696)
		(stroke
			(width 0.05715)
			(type default)
		)
		(layer "F.Cu")
	)
	(gr_line
		(start 349.639636 -64.769492)
		(end 349.656908 -64.765936)
		(stroke
			(width 0.05715)
			(type default)
		)
		(layer "F.Cu")
	)
	(gr_line
		(start 349.642176 -66.769488)
		(end 349.659448 -66.765932)
		(stroke
			(width 0.05715)
			(type default)
		)
		(layer "F.Cu")
	)
	(gr_line
		(start 349.649288 -63.767716)
		(end 349.66656 -63.76416)
		(stroke
			(width 0.05715)
			(type default)
		)
		(layer "F.Cu")
	)
	(gr_line
		(start 349.652082 -65.766696)
		(end 349.669354 -65.76314)
		(stroke
			(width 0.05715)
			(type default)
		)
		(layer "F.Cu")
	)
	(gr_line
		(start 349.712788 -45.92955)
		(end 349.725996 -45.93209)
		(stroke
			(width 0.05715)
			(type default)
		)
		(layer "F.Cu")
	)
	(gr_line
		(start 349.725996 -45.93209)
		(end 349.739204 -45.92955)
		(stroke
			(width 0.05715)
			(type default)
		)
		(layer "F.Cu")
	)
	(gr_line
		(start 349.778066 -86.56447)
		(end 349.789242 -86.557104)
		(stroke
			(width 0.05715)
			(type default)
		)
		(layer "F.Cu")
	)
	(gr_line
		(start 349.789242 -86.557104)
		(end 349.801688 -86.554818)
		(stroke
			(width 0.05715)
			(type default)
		)
		(layer "F.Cu")
	)
	(gr_line
		(start 349.863156 -52.011326)
		(end 349.876364 -52.013866)
		(stroke
			(width 0.05715)
			(type default)
		)
		(layer "F.Cu")
	)
	(gr_line
		(start 349.876364 -52.013866)
		(end 349.889572 -52.011326)
		(stroke
			(width 0.05715)
			(type default)
		)
		(layer "F.Cu")
	)
	(gr_line
		(start 349.890842 -46.978062)
		(end 349.90405 -46.980602)
		(stroke
			(width 0.05715)
			(type default)
		)
		(layer "F.Cu")
	)
	(gr_line
		(start 349.90405 -46.980602)
		(end 349.917258 -46.978062)
		(stroke
			(width 0.05715)
			(type default)
		)
		(layer "F.Cu")
	)
	(gr_line
		(start 349.928434 -51.00193)
		(end 349.941642 -51.00447)
		(stroke
			(width 0.05715)
			(type default)
		)
		(layer "F.Cu")
	)
	(gr_line
		(start 349.941642 -51.00447)
		(end 349.95485 -51.00193)
		(stroke
			(width 0.05715)
			(type default)
		)
		(layer "F.Cu")
	)
	(gr_line
		(start 349.953326 -50.011076)
		(end 349.966534 -50.013616)
		(stroke
			(width 0.05715)
			(type default)
		)
		(layer "F.Cu")
	)
	(gr_line
		(start 349.954088 -48.00981)
		(end 349.967296 -48.01235)
		(stroke
			(width 0.05715)
			(type default)
		)
		(layer "F.Cu")
	)
	(gr_line
		(start 349.960184 -49.01184)
		(end 349.973392 -49.01438)
		(stroke
			(width 0.05715)
			(type default)
		)
		(layer "F.Cu")
	)
	(gr_line
		(start 349.966534 -50.013616)
		(end 349.979742 -50.011076)
		(stroke
			(width 0.05715)
			(type default)
		)
		(layer "F.Cu")
	)
	(gr_line
		(start 349.967296 -48.01235)
		(end 349.980504 -48.00981)
		(stroke
			(width 0.05715)
			(type default)
		)
		(layer "F.Cu")
	)
	(gr_line
		(start 349.973392 -49.01438)
		(end 349.9866 -49.01184)
		(stroke
			(width 0.05715)
			(type default)
		)
		(layer "F.Cu")
	)
	(gr_line
		(start 350.157034 -85.7123)
		(end 350.171766 -85.709252)
		(stroke
			(width 0.05715)
			(type default)
		)
		(layer "F.Cu")
	)
	(gr_line
		(start 350.171766 -85.709252)
		(end 350.184466 -85.70087)
		(stroke
			(width 0.05715)
			(type default)
		)
		(layer "F.Cu")
	)
	(gr_line
		(start 350.659192 -78.05674)
		(end 351.122742 -78.05674)
		(stroke
			(width 0.05715)
			(type default)
		)
		(layer "F.Cu")
	)
	(gr_line
		(start 350.865186 -66.262758)
		(end 350.891856 -66.25717)
		(stroke
			(width 0.05715)
			(type default)
		)
		(layer "F.Cu")
	)
	(gr_line
		(start 350.891856 -66.25717)
		(end 350.915732 -66.263774)
		(stroke
			(width 0.05715)
			(type default)
		)
		(layer "F.Cu")
	)
	(gr_line
		(start 350.948498 -65.244218)
		(end 350.972882 -65.239138)
		(stroke
			(width 0.05715)
			(type default)
		)
		(layer "F.Cu")
	)
	(gr_line
		(start 350.972882 -65.239138)
		(end 350.996758 -65.245742)
		(stroke
			(width 0.05715)
			(type default)
		)
		(layer "F.Cu")
	)
	(gr_line
		(start 351.03181 -64.226694)
		(end 351.056194 -64.221614)
		(stroke
			(width 0.05715)
			(type default)
		)
		(layer "F.Cu")
	)
	(gr_line
		(start 351.040192 -85.13064)
		(end 351.053146 -85.122004)
		(stroke
			(width 0.05715)
			(type default)
		)
		(layer "F.Cu")
	)
	(gr_line
		(start 351.053146 -85.122004)
		(end 351.061782 -85.10905)
		(stroke
			(width 0.05715)
			(type default)
		)
		(layer "F.Cu")
	)
	(gr_line
		(start 351.056194 -64.221614)
		(end 351.08007 -64.228218)
		(stroke
			(width 0.05715)
			(type default)
		)
		(layer "F.Cu")
	)
	(gr_line
		(start 351.081594 -86.295992)
		(end 351.169224 -86.16442)
		(stroke
			(width 0.05715)
			(type default)
		)
		(layer "F.Cu")
	)
	(gr_line
		(start 351.122742 -78.05674)
		(end 351.185226 -78.119224)
		(stroke
			(width 0.05715)
			(type default)
		)
		(layer "F.Cu")
	)
	(gr_line
		(start 351.161604 -86.528656)
		(end 351.65284 -86.430358)
		(stroke
			(width 0.05715)
			(type default)
		)
		(layer "F.Cu")
	)
	(gr_line
		(start 351.169224 -86.16442)
		(end 351.50552 -86.09711)
		(stroke
			(width 0.05715)
			(type default)
		)
		(layer "F.Cu")
	)
	(gr_line
		(start 351.206562 -62.140592)
		(end 351.22993 -62.135766)
		(stroke
			(width 0.05715)
			(type default)
		)
		(layer "F.Cu")
	)
	(gr_line
		(start 351.22993 -62.135766)
		(end 351.253044 -62.141862)
		(stroke
			(width 0.05715)
			(type default)
		)
		(layer "F.Cu")
	)
	(gr_line
		(start 351.234756 -63.184278)
		(end 351.256346 -63.179706)
		(stroke
			(width 0.05715)
			(type default)
		)
		(layer "F.Cu")
	)
	(gr_line
		(start 351.237042 -78.890368)
		(end 351.258124 -78.922118)
		(stroke
			(width 0.05715)
			(type default)
		)
		(layer "F.Cu")
	)
	(gr_line
		(start 351.256346 -63.179706)
		(end 351.277428 -63.185294)
		(stroke
			(width 0.05715)
			(type default)
		)
		(layer "F.Cu")
	)
	(gr_line
		(start 351.299526 -61.128148)
		(end 351.322894 -61.123322)
		(stroke
			(width 0.05715)
			(type default)
		)
		(layer "F.Cu")
	)
	(gr_line
		(start 351.322894 -61.123322)
		(end 351.346008 -61.129418)
		(stroke
			(width 0.05715)
			(type default)
		)
		(layer "F.Cu")
	)
	(gr_line
		(start 351.373694 -83.999324)
		(end 351.404936 -84.154772)
		(stroke
			(width 0.05715)
			(type default)
		)
		(layer "F.Cu")
	)
	(gr_line
		(start 351.373694 -83.999324)
		(end 351.56394 -83.714082)
		(stroke
			(width 0.05715)
			(type default)
		)
		(layer "F.Cu")
	)
	(gr_line
		(start 351.50552 -86.09711)
		(end 351.637092 -86.184994)
		(stroke
			(width 0.05715)
			(type default)
		)
		(layer "F.Cu")
	)
	(gr_line
		(start 351.530158 -78.119224)
		(end 351.592642 -78.05674)
		(stroke
			(width 0.05715)
			(type default)
		)
		(layer "F.Cu")
	)
	(gr_line
		(start 351.56394 -83.714082)
		(end 351.719134 -83.683094)
		(stroke
			(width 0.05715)
			(type default)
		)
		(layer "F.Cu")
	)
	(gr_line
		(start 351.592642 -78.05674)
		(end 352.056192 -78.05674)
		(stroke
			(width 0.05715)
			(type default)
		)
		(layer "F.Cu")
	)
	(gr_line
		(start 351.6249 -84.264246)
		(end 351.905062 -83.843876)
		(stroke
			(width 0.05715)
			(type default)
		)
		(layer "F.Cu")
	)
	(gr_line
		(start 351.823528 -55.512716)
		(end 351.83572 -55.510176)
		(stroke
			(width 0.05715)
			(type default)
		)
		(layer "F.Cu")
	)
	(gr_line
		(start 351.83572 -55.510176)
		(end 351.846134 -55.503318)
		(stroke
			(width 0.05715)
			(type default)
		)
		(layer "F.Cu")
	)
	(gr_line
		(start 351.880932 -83.23834)
		(end 351.912174 -83.393788)
		(stroke
			(width 0.05715)
			(type default)
		)
		(layer "F.Cu")
	)
	(gr_line
		(start 351.880932 -83.23834)
		(end 352.071178 -82.953098)
		(stroke
			(width 0.05715)
			(type default)
		)
		(layer "F.Cu")
	)
	(gr_line
		(start 351.97796 -86.116668)
		(end 352.065844 -85.985096)
		(stroke
			(width 0.05715)
			(type default)
		)
		(layer "F.Cu")
	)
	(gr_line
		(start 352.051366 -90.491818)
		(end 352.064574 -90.489278)
		(stroke
			(width 0.05715)
			(type default)
		)
		(layer "F.Cu")
	)
	(gr_line
		(start 352.056192 -86.34984)
		(end 352.549714 -86.251034)
		(stroke
			(width 0.05715)
			(type default)
		)
		(layer "F.Cu")
	)
	(gr_line
		(start 352.064574 -90.489278)
		(end 352.077782 -90.491818)
		(stroke
			(width 0.05715)
			(type default)
		)
		(layer "F.Cu")
	)
	(gr_line
		(start 352.065844 -85.985096)
		(end 352.40214 -85.917786)
		(stroke
			(width 0.05715)
			(type default)
		)
		(layer "F.Cu")
	)
	(gr_line
		(start 352.071178 -82.953098)
		(end 352.226372 -82.92211)
		(stroke
			(width 0.05715)
			(type default)
		)
		(layer "F.Cu")
	)
	(gr_line
		(start 352.078798 -89.490296)
		(end 352.092006 -89.487756)
		(stroke
			(width 0.05715)
			(type default)
		)
		(layer "F.Cu")
	)
	(gr_line
		(start 352.092006 -89.487756)
		(end 352.105214 -89.490296)
		(stroke
			(width 0.05715)
			(type default)
		)
		(layer "F.Cu")
	)
	(gr_line
		(start 352.131884 -83.50377)
		(end 352.4123 -83.082892)
		(stroke
			(width 0.05715)
			(type default)
		)
		(layer "F.Cu")
	)
	(gr_line
		(start 352.161094 -79.84109)
		(end 352.16846 -79.852266)
		(stroke
			(width 0.05715)
			(type default)
		)
		(layer "F.Cu")
	)
	(gr_line
		(start 352.16846 -79.852266)
		(end 352.170746 -79.864712)
		(stroke
			(width 0.05715)
			(type default)
		)
		(layer "F.Cu")
	)
	(gr_line
		(start 352.40214 -85.917786)
		(end 352.533712 -86.005416)
		(stroke
			(width 0.05715)
			(type default)
		)
		(layer "F.Cu")
	)
	(gr_line
		(start 352.547428 -121.838466)
		(end 352.581972 -121.86285)
		(stroke
			(width 0.05715)
			(type default)
		)
		(layer "F.Cu")
	)
	(gr_line
		(start 352.639376 -82.742278)
		(end 352.64725 -82.73034)
		(stroke
			(width 0.05715)
			(type default)
		)
		(layer "F.Cu")
	)
	(gr_line
		(start 352.64725 -82.73034)
		(end 352.650044 -82.716624)
		(stroke
			(width 0.05715)
			(type default)
		)
		(layer "F.Cu")
	)
	(gr_line
		(start 352.69297 -82.474054)
		(end 352.695764 -82.488024)
		(stroke
			(width 0.05715)
			(type default)
		)
		(layer "F.Cu")
	)
	(gr_line
		(start 352.693224 -82.501232)
		(end 352.695764 -82.488024)
		(stroke
			(width 0.05715)
			(type default)
		)
		(layer "F.Cu")
	)
	(gr_line
		(start 352.887788 -45.29963)
		(end 352.903028 -45.296582)
		(stroke
			(width 0.05715)
			(type default)
		)
		(layer "F.Cu")
	)
	(gr_line
		(start 352.903028 -45.296582)
		(end 352.916236 -45.287692)
		(stroke
			(width 0.05715)
			(type default)
		)
		(layer "F.Cu")
	)
	(gr_line
		(start 352.95459 -86.169754)
		(end 352.967036 -86.167468)
		(stroke
			(width 0.05715)
			(type default)
		)
		(layer "F.Cu")
	)
	(gr_line
		(start 352.967036 -86.167468)
		(end 352.978212 -86.160102)
		(stroke
			(width 0.05715)
			(type default)
		)
		(layer "F.Cu")
	)
	(gr_line
		(start 353.0727 -46.346364)
		(end 353.08794 -46.343316)
		(stroke
			(width 0.05715)
			(type default)
		)
		(layer "F.Cu")
	)
	(gr_line
		(start 353.08794 -46.343316)
		(end 353.101148 -46.334426)
		(stroke
			(width 0.05715)
			(type default)
		)
		(layer "F.Cu")
	)
	(gr_line
		(start 353.167442 -63.92672)
		(end 353.187 -63.9318)
		(stroke
			(width 0.05715)
			(type default)
		)
		(layer "F.Cu")
	)
	(gr_line
		(start 353.187 -63.9318)
		(end 353.206558 -63.92799)
		(stroke
			(width 0.05715)
			(type default)
		)
		(layer "F.Cu")
	)
	(gr_line
		(start 353.212654 -62.90183)
		(end 353.232974 -62.907164)
		(stroke
			(width 0.05715)
			(type default)
		)
		(layer "F.Cu")
	)
	(gr_line
		(start 353.219258 -61.86678)
		(end 353.238816 -61.87186)
		(stroke
			(width 0.05715)
			(type default)
		)
		(layer "F.Cu")
	)
	(gr_line
		(start 353.232974 -62.907164)
		(end 353.253294 -62.9031)
		(stroke
			(width 0.05715)
			(type default)
		)
		(layer "F.Cu")
	)
	(gr_line
		(start 353.238816 -61.87186)
		(end 353.258374 -61.86805)
		(stroke
			(width 0.05715)
			(type default)
		)
		(layer "F.Cu")
	)
	(gr_line
		(start 353.265486 -120.865646)
		(end 353.287076 -120.876822)
		(stroke
			(width 0.05715)
			(type default)
		)
		(layer "F.Cu")
	)
	(gr_line
		(start 353.393502 -47.32655)
		(end 353.405948 -47.324264)
		(stroke
			(width 0.05715)
			(type default)
		)
		(layer "F.Cu")
	)
	(gr_line
		(start 353.405948 -47.324264)
		(end 353.417124 -47.316898)
		(stroke
			(width 0.05715)
			(type default)
		)
		(layer "F.Cu")
	)
	(gr_line
		(start 353.60229 -78.13802)
		(end 354.06584 -78.13802)
		(stroke
			(width 0.05715)
			(type default)
		)
		(layer "F.Cu")
	)
	(gr_line
		(start 353.861624 -48.23714)
		(end 353.87661 -48.234092)
		(stroke
			(width 0.05715)
			(type default)
		)
		(layer "F.Cu")
	)
	(gr_line
		(start 353.87661 -48.234092)
		(end 353.88931 -48.22571)
		(stroke
			(width 0.05715)
			(type default)
		)
		(layer "F.Cu")
	)
	(gr_line
		(start 354.021644 -124.480066)
		(end 354.053394 -124.501148)
		(stroke
			(width 0.05715)
			(type default)
		)
		(layer "F.Cu")
	)
	(gr_line
		(start 354.06584 -78.13802)
		(end 354.128324 -78.200504)
		(stroke
			(width 0.05715)
			(type default)
		)
		(layer "F.Cu")
	)
	(gr_line
		(start 354.12299 -80.708754)
		(end 354.134166 -80.66405)
		(stroke
			(width 0.05715)
			(type default)
		)
		(layer "F.Cu")
	)
	(gr_line
		(start 354.12299 -80.708754)
		(end 354.14077 -80.750918)
		(stroke
			(width 0.05715)
			(type default)
		)
		(layer "F.Cu")
	)
	(gr_line
		(start 354.134166 -80.663796)
		(end 354.134166 -80.66405)
		(stroke
			(width 0.05715)
			(type default)
		)
		(layer "F.Cu")
	)
	(gr_line
		(start 354.156264 -90.146886)
		(end 354.220272 -90.159586)
		(stroke
			(width 0.05715)
			(type default)
		)
		(layer "F.Cu")
	)
	(gr_line
		(start 354.18014 -79.51597)
		(end 354.187252 -79.531718)
		(stroke
			(width 0.05715)
			(type default)
		)
		(layer "F.Cu")
	)
	(gr_line
		(start 354.220272 -90.159586)
		(end 354.273612 -90.123772)
		(stroke
			(width 0.05715)
			(type default)
		)
		(layer "F.Cu")
	)
	(gr_line
		(start 354.23094 -49.160938)
		(end 354.245926 -49.15789)
		(stroke
			(width 0.05715)
			(type default)
		)
		(layer "F.Cu")
	)
	(gr_line
		(start 354.245926 -49.15789)
		(end 354.258372 -49.149508)
		(stroke
			(width 0.05715)
			(type default)
		)
		(layer "F.Cu")
	)
	(gr_line
		(start 354.32492 -81.479644)
		(end 354.384356 -81.332832)
		(stroke
			(width 0.05715)
			(type default)
		)
		(layer "F.Cu")
	)
	(gr_line
		(start 354.32492 -81.479644)
		(end 354.458524 -81.795366)
		(stroke
			(width 0.05715)
			(type default)
		)
		(layer "F.Cu")
	)
	(gr_line
		(start 354.404422 -52.596288)
		(end 354.41763 -52.593494)
		(stroke
			(width 0.05715)
			(type default)
		)
		(layer "F.Cu")
	)
	(gr_line
		(start 354.41763 -52.593494)
		(end 354.428552 -52.586128)
		(stroke
			(width 0.05715)
			(type default)
		)
		(layer "F.Cu")
	)
	(gr_line
		(start 354.458524 -81.795366)
		(end 354.605082 -81.854802)
		(stroke
			(width 0.05715)
			(type default)
		)
		(layer "F.Cu")
	)
	(gr_line
		(start 354.458778 -91.214702)
		(end 354.522786 -91.227402)
		(stroke
			(width 0.05715)
			(type default)
		)
		(layer "F.Cu")
	)
	(gr_line
		(start 354.473256 -78.200504)
		(end 354.53574 -78.13802)
		(stroke
			(width 0.05715)
			(type default)
		)
		(layer "F.Cu")
	)
	(gr_line
		(start 354.522786 -91.227402)
		(end 354.576126 -91.191588)
		(stroke
			(width 0.05715)
			(type default)
		)
		(layer "F.Cu")
	)
	(gr_line
		(start 354.53574 -78.13802)
		(end 354.99929 -78.13802)
		(stroke
			(width 0.05715)
			(type default)
		)
		(layer "F.Cu")
	)
	(gr_line
		(start 354.569776 -79.78775)
		(end 354.590858 -79.833978)
		(stroke
			(width 0.05715)
			(type default)
		)
		(layer "F.Cu")
	)
	(gr_line
		(start 354.578666 -79.883)
		(end 354.590858 -79.833978)
		(stroke
			(width 0.05715)
			(type default)
		)
		(layer "F.Cu")
	)
	(gr_line
		(start 354.61321 -50.06975)
		(end 354.626926 -50.066956)
		(stroke
			(width 0.05715)
			(type default)
		)
		(layer "F.Cu")
	)
	(gr_line
		(start 354.621338 -81.267554)
		(end 354.817172 -81.729834)
		(stroke
			(width 0.05715)
			(type default)
		)
		(layer "F.Cu")
	)
	(gr_line
		(start 354.626926 -50.066956)
		(end 354.63861 -50.059082)
		(stroke
			(width 0.05715)
			(type default)
		)
		(layer "F.Cu")
	)
	(gr_line
		(start 354.681282 -82.321654)
		(end 354.740718 -82.175096)
		(stroke
			(width 0.05715)
			(type default)
		)
		(layer "F.Cu")
	)
	(gr_line
		(start 354.681282 -82.321654)
		(end 354.814886 -82.63763)
		(stroke
			(width 0.05715)
			(type default)
		)
		(layer "F.Cu")
	)
	(gr_line
		(start 354.814886 -82.63763)
		(end 354.961444 -82.697066)
		(stroke
			(width 0.05715)
			(type default)
		)
		(layer "F.Cu")
	)
	(gr_line
		(start 354.835714 -84.921852)
		(end 354.848668 -84.913216)
		(stroke
			(width 0.05715)
			(type default)
		)
		(layer "F.Cu")
	)
	(gr_line
		(start 354.848668 -84.913216)
		(end 354.857304 -84.900262)
		(stroke
			(width 0.05715)
			(type default)
		)
		(layer "F.Cu")
	)
	(gr_line
		(start 354.9777 -82.10931)
		(end 355.173534 -82.572352)
		(stroke
			(width 0.05715)
			(type default)
		)
		(layer "F.Cu")
	)
	(gr_line
		(start 355.03739 -50.982118)
		(end 355.052376 -50.97907)
		(stroke
			(width 0.05715)
			(type default)
		)
		(layer "F.Cu")
	)
	(gr_line
		(start 355.052376 -50.97907)
		(end 355.064568 -50.970688)
		(stroke
			(width 0.05715)
			(type default)
		)
		(layer "F.Cu")
	)
	(gr_line
		(start 355.335586 -84.182458)
		(end 355.338634 -84.17814)
		(stroke
			(width 0.05715)
			(type default)
		)
		(layer "F.Cu")
	)
	(gr_line
		(start 355.338634 -84.17814)
		(end 355.340158 -84.172806)
		(stroke
			(width 0.05715)
			(type default)
		)
		(layer "F.Cu")
	)
	(gr_line
		(start 355.360986 -89.397586)
		(end 355.415596 -89.36101)
		(stroke
			(width 0.05715)
			(type default)
		)
		(layer "F.Cu")
	)
	(gr_line
		(start 355.415596 -89.36101)
		(end 355.42855 -89.296494)
		(stroke
			(width 0.05715)
			(type default)
		)
		(layer "F.Cu")
	)
	(gr_line
		(start 355.417628 -87.539322)
		(end 355.484938 -87.203026)
		(stroke
			(width 0.05715)
			(type default)
		)
		(layer "F.Cu")
	)
	(gr_line
		(start 355.417628 -87.539322)
		(end 355.505512 -87.671148)
		(stroke
			(width 0.05715)
			(type default)
		)
		(layer "F.Cu")
	)
	(gr_line
		(start 355.472746 -120.727216)
		(end 355.548184 -120.866408)
		(stroke
			(width 0.05715)
			(type default)
		)
		(layer "F.Cu")
	)
	(gr_line
		(start 355.484938 -87.203026)
		(end 355.616764 -87.115396)
		(stroke
			(width 0.05715)
			(type default)
		)
		(layer "F.Cu")
	)
	(gr_line
		(start 355.497384 -67.763644)
		(end 355.519228 -67.76974)
		(stroke
			(width 0.05715)
			(type default)
		)
		(layer "F.Cu")
	)
	(gr_line
		(start 355.519228 -67.76974)
		(end 355.541072 -67.765422)
		(stroke
			(width 0.05715)
			(type default)
		)
		(layer "F.Cu")
	)
	(gr_line
		(start 355.522276 -83.396836)
		(end 355.54158 -83.442048)
		(stroke
			(width 0.05715)
			(type default)
		)
		(layer "F.Cu")
	)
	(gr_line
		(start 355.528372 -83.489546)
		(end 355.54158 -83.442048)
		(stroke
			(width 0.05715)
			(type default)
		)
		(layer "F.Cu")
	)
	(gr_line
		(start 355.534468 -66.733928)
		(end 355.556312 -66.740024)
		(stroke
			(width 0.05715)
			(type default)
		)
		(layer "F.Cu")
	)
	(gr_line
		(start 355.548184 -120.866408)
		(end 355.87686 -120.96369)
		(stroke
			(width 0.05715)
			(type default)
		)
		(layer "F.Cu")
	)
	(gr_line
		(start 355.556312 -66.740024)
		(end 355.578156 -66.735706)
		(stroke
			(width 0.05715)
			(type default)
		)
		(layer "F.Cu")
	)
	(gr_line
		(start 355.571552 -65.703958)
		(end 355.593396 -65.710054)
		(stroke
			(width 0.05715)
			(type default)
		)
		(layer "F.Cu")
	)
	(gr_line
		(start 355.573076 -120.50268)
		(end 356.055422 -120.645682)
		(stroke
			(width 0.05715)
			(type default)
		)
		(layer "F.Cu")
	)
	(gr_line
		(start 355.593396 -65.710054)
		(end 355.61524 -65.705736)
		(stroke
			(width 0.05715)
			(type default)
		)
		(layer "F.Cu")
	)
	(gr_line
		(start 355.597206 -86.642702)
		(end 355.664516 -86.30666)
		(stroke
			(width 0.05715)
			(type default)
		)
		(layer "F.Cu")
	)
	(gr_line
		(start 355.597206 -86.642702)
		(end 355.68509 -86.774528)
		(stroke
			(width 0.05715)
			(type default)
		)
		(layer "F.Cu")
	)
	(gr_line
		(start 355.637846 -63.205614)
		(end 355.666802 -63.200026)
		(stroke
			(width 0.05715)
			(type default)
		)
		(layer "F.Cu")
	)
	(gr_line
		(start 355.664516 -86.30666)
		(end 355.796342 -86.218776)
		(stroke
			(width 0.05715)
			(type default)
		)
		(layer "F.Cu")
	)
	(gr_line
		(start 355.666802 -63.200026)
		(end 355.694234 -63.20917)
		(stroke
			(width 0.05715)
			(type default)
		)
		(layer "F.Cu")
	)
	(gr_line
		(start 355.678232 -61.393578)
		(end 355.690932 -61.391038)
		(stroke
			(width 0.05715)
			(type default)
		)
		(layer "F.Cu")
	)
	(gr_line
		(start 355.690932 -61.391038)
		(end 355.701854 -61.383926)
		(stroke
			(width 0.05715)
			(type default)
		)
		(layer "F.Cu")
	)
	(gr_line
		(start 355.730302 -56.008524)
		(end 355.741986 -56.006238)
		(stroke
			(width 0.05715)
			(type default)
		)
		(layer "F.Cu")
	)
	(gr_line
		(start 355.741986 -56.006238)
		(end 355.752146 -55.99938)
		(stroke
			(width 0.05715)
			(type default)
		)
		(layer "F.Cu")
	)
	(gr_line
		(start 355.750876 -87.68715)
		(end 355.849682 -87.194644)
		(stroke
			(width 0.05715)
			(type default)
		)
		(layer "F.Cu")
	)
	(gr_line
		(start 355.858572 -85.919818)
		(end 355.866446 -85.880702)
		(stroke
			(width 0.05715)
			(type default)
		)
		(layer "F.Cu")
	)
	(gr_line
		(start 355.87686 -120.96369)
		(end 356.016306 -120.888252)
		(stroke
			(width 0.05715)
			(type default)
		)
		(layer "F.Cu")
	)
	(gr_line
		(start 355.930454 -86.79053)
		(end 356.02926 -86.29777)
		(stroke
			(width 0.05715)
			(type default)
		)
		(layer "F.Cu")
	)
	(gr_line
		(start 356.297992 -90.041476)
		(end 356.309422 -90.033856)
		(stroke
			(width 0.05715)
			(type default)
		)
		(layer "F.Cu")
	)
	(gr_line
		(start 356.309422 -90.033856)
		(end 356.317042 -90.022172)
		(stroke
			(width 0.05715)
			(type default)
		)
		(layer "F.Cu")
	)
	(gr_line
		(start 356.309676 -117.667024)
		(end 356.342442 -117.676676)
		(stroke
			(width 0.05715)
			(type default)
		)
		(layer "F.Cu")
	)
	(gr_line
		(start 356.310946 -127.254)
		(end 356.341934 -127.274828)
		(stroke
			(width 0.05715)
			(type default)
		)
		(layer "F.Cu")
	)
	(gr_line
		(start 356.31501 -120.974358)
		(end 356.347776 -120.98401)
		(stroke
			(width 0.05715)
			(type default)
		)
		(layer "F.Cu")
	)
	(gr_line
		(start 356.330504 -119.812054)
		(end 356.362762 -119.821706)
		(stroke
			(width 0.05715)
			(type default)
		)
		(layer "F.Cu")
	)
	(gr_line
		(start 356.342442 -117.676676)
		(end 356.375716 -117.667786)
		(stroke
			(width 0.05715)
			(type default)
		)
		(layer "F.Cu")
	)
	(gr_line
		(start 356.347776 -120.98401)
		(end 356.38105 -120.97512)
		(stroke
			(width 0.05715)
			(type default)
		)
		(layer "F.Cu")
	)
	(gr_line
		(start 356.362762 -119.821706)
		(end 356.396036 -119.812816)
		(stroke
			(width 0.05715)
			(type default)
		)
		(layer "F.Cu")
	)
	(gr_line
		(start 356.371398 -78.13802)
		(end 356.834948 -78.13802)
		(stroke
			(width 0.05715)
			(type default)
		)
		(layer "F.Cu")
	)
	(gr_line
		(start 356.408736 -118.77675)
		(end 356.441502 -118.786402)
		(stroke
			(width 0.05715)
			(type default)
		)
		(layer "F.Cu")
	)
	(gr_line
		(start 356.441502 -118.786402)
		(end 356.474776 -118.777512)
		(stroke
			(width 0.05715)
			(type default)
		)
		(layer "F.Cu")
	)
	(gr_line
		(start 356.493318 -62.260988)
		(end 356.50678 -62.258194)
		(stroke
			(width 0.05715)
			(type default)
		)
		(layer "F.Cu")
	)
	(gr_line
		(start 356.50678 -62.258194)
		(end 356.517956 -62.250828)
		(stroke
			(width 0.05715)
			(type default)
		)
		(layer "F.Cu")
	)
	(gr_line
		(start 356.525068 -85.56371)
		(end 356.571296 -85.517482)
		(stroke
			(width 0.05715)
			(type default)
		)
		(layer "F.Cu")
	)
	(gr_line
		(start 356.530656 -37.58565)
		(end 356.537768 -37.61486)
		(stroke
			(width 0.05715)
			(type default)
		)
		(layer "F.Cu")
	)
	(gr_line
		(start 356.530656 -37.58565)
		(end 356.539546 -37.555424)
		(stroke
			(width 0.05715)
			(type default)
		)
		(layer "F.Cu")
	)
	(gr_line
		(start 356.761034 -89.356692)
		(end 356.782116 -89.324942)
		(stroke
			(width 0.05715)
			(type default)
		)
		(layer "F.Cu")
	)
	(gr_line
		(start 356.834948 -80.665574)
		(end 356.946708 -80.777334)
		(stroke
			(width 0.05715)
			(type default)
		)
		(layer "F.Cu")
	)
	(gr_line
		(start 356.834948 -80.322674)
		(end 356.834948 -80.665574)
		(stroke
			(width 0.05715)
			(type default)
		)
		(layer "F.Cu")
	)
	(gr_line
		(start 356.834948 -80.322674)
		(end 356.946708 -80.210914)
		(stroke
			(width 0.05715)
			(type default)
		)
		(layer "F.Cu")
	)
	(gr_line
		(start 356.834948 -79.751174)
		(end 356.946708 -79.862934)
		(stroke
			(width 0.05715)
			(type default)
		)
		(layer "F.Cu")
	)
	(gr_line
		(start 356.834948 -79.408274)
		(end 356.834948 -79.751174)
		(stroke
			(width 0.05715)
			(type default)
		)
		(layer "F.Cu")
	)
	(gr_line
		(start 356.834948 -79.408274)
		(end 356.946708 -79.296514)
		(stroke
			(width 0.05715)
			(type default)
		)
		(layer "F.Cu")
	)
	(gr_line
		(start 356.834948 -78.13802)
		(end 356.897432 -78.200504)
		(stroke
			(width 0.05715)
			(type default)
		)
		(layer "F.Cu")
	)
	(gr_line
		(start 356.902766 -63.866522)
		(end 356.934262 -63.876936)
		(stroke
			(width 0.05715)
			(type default)
		)
		(layer "F.Cu")
	)
	(gr_line
		(start 356.934262 -63.876936)
		(end 356.966774 -63.86957)
		(stroke
			(width 0.05715)
			(type default)
		)
		(layer "F.Cu")
	)
	(gr_line
		(start 356.993698 -42.526458)
		(end 357.04526 -42.491406)
		(stroke
			(width 0.05715)
			(type default)
		)
		(layer "F.Cu")
	)
	(gr_line
		(start 357.04526 -42.491406)
		(end 357.05796 -42.4307)
		(stroke
			(width 0.05715)
			(type default)
		)
		(layer "F.Cu")
	)
	(gr_line
		(start 357.190548 -80.452214)
		(end 357.190548 -80.536034)
		(stroke
			(width 0.05715)
			(type default)
		)
		(layer "F.Cu")
	)
	(gr_line
		(start 357.190548 -79.537814)
		(end 357.190548 -79.621634)
		(stroke
			(width 0.05715)
			(type default)
		)
		(layer "F.Cu")
	)
	(gr_line
		(start 357.227124 -60.373768)
		(end 357.236014 -60.367926)
		(stroke
			(width 0.05715)
			(type default)
		)
		(layer "F.Cu")
	)
	(gr_line
		(start 357.236014 -60.367926)
		(end 357.242364 -60.35929)
		(stroke
			(width 0.05715)
			(type default)
		)
		(layer "F.Cu")
	)
	(gr_line
		(start 357.242364 -78.200504)
		(end 357.304848 -78.13802)
		(stroke
			(width 0.05715)
			(type default)
		)
		(layer "F.Cu")
	)
	(gr_line
		(start 357.304848 -78.13802)
		(end 357.768398 -78.13802)
		(stroke
			(width 0.05715)
			(type default)
		)
		(layer "F.Cu")
	)
	(gr_line
		(start 357.470202 -40.448738)
		(end 357.475282 -40.469312)
		(stroke
			(width 0.05715)
			(type default)
		)
		(layer "F.Cu")
	)
	(gr_line
		(start 357.470964 -40.489378)
		(end 357.475282 -40.469312)
		(stroke
			(width 0.05715)
			(type default)
		)
		(layer "F.Cu")
	)
	(gr_line
		(start 357.565198 -37.627306)
		(end 357.57231 -37.656516)
		(stroke
			(width 0.05715)
			(type default)
		)
		(layer "F.Cu")
	)
	(gr_line
		(start 357.565198 -37.627306)
		(end 357.574088 -37.59708)
		(stroke
			(width 0.05715)
			(type default)
		)
		(layer "F.Cu")
	)
	(gr_line
		(start 357.598726 -128.402588)
		(end 357.610918 -128.410716)
		(stroke
			(width 0.05715)
			(type default)
		)
		(layer "F.Cu")
	)
	(gr_line
		(start 357.610918 -128.410716)
		(end 357.62565 -128.413764)
		(stroke
			(width 0.05715)
			(type default)
		)
		(layer "F.Cu")
	)
	(gr_line
		(start 357.768906 -61.422534)
		(end 357.781606 -61.414152)
		(stroke
			(width 0.05715)
			(type default)
		)
		(layer "F.Cu")
	)
	(gr_line
		(start 357.781606 -61.414152)
		(end 357.789988 -61.401452)
		(stroke
			(width 0.05715)
			(type default)
		)
		(layer "F.Cu")
	)
	(gr_line
		(start 357.891842 -43.090592)
		(end 357.945436 -43.05427)
		(stroke
			(width 0.05715)
			(type default)
		)
		(layer "F.Cu")
	)
	(gr_line
		(start 357.945436 -43.05427)
		(end 357.95839 -42.991024)
		(stroke
			(width 0.05715)
			(type default)
		)
		(layer "F.Cu")
	)
	(gr_line
		(start 357.974392 -123.585224)
		(end 357.995982 -123.5964)
		(stroke
			(width 0.05715)
			(type default)
		)
		(layer "F.Cu")
	)
	(gr_line
		(start 358.023922 -63.626238)
		(end 358.032304 -63.624206)
		(stroke
			(width 0.05715)
			(type default)
		)
		(layer "F.Cu")
	)
	(gr_line
		(start 358.032304 -63.624206)
		(end 358.039416 -63.619634)
		(stroke
			(width 0.05715)
			(type default)
		)
		(layer "F.Cu")
	)
	(gr_line
		(start 358.09936 -58.012584)
		(end 358.17937 -58.148982)
		(stroke
			(width 0.05715)
			(type default)
		)
		(layer "F.Cu")
	)
	(gr_line
		(start 358.09936 -58.012584)
		(end 358.18572 -57.680606)
		(stroke
			(width 0.05715)
			(type default)
		)
		(layer "F.Cu")
	)
	(gr_line
		(start 358.110536 -127.497078)
		(end 358.121712 -127.504444)
		(stroke
			(width 0.05715)
			(type default)
		)
		(layer "F.Cu")
	)
	(gr_line
		(start 358.121712 -127.504444)
		(end 358.134158 -127.50673)
		(stroke
			(width 0.05715)
			(type default)
		)
		(layer "F.Cu")
	)
	(gr_line
		(start 358.18572 -57.680606)
		(end 358.322372 -57.600596)
		(stroke
			(width 0.05715)
			(type default)
		)
		(layer "F.Cu")
	)
	(gr_line
		(start 358.201214 -59.017916)
		(end 358.206802 -59.010042)
		(stroke
			(width 0.05715)
			(type default)
		)
		(layer "F.Cu")
	)
	(gr_line
		(start 358.206802 -59.010042)
		(end 358.209342 -59.000644)
		(stroke
			(width 0.05715)
			(type default)
		)
		(layer "F.Cu")
	)
	(gr_line
		(start 358.329992 -57.127648)
		(end 358.410002 -57.264046)
		(stroke
			(width 0.05715)
			(type default)
		)
		(layer "F.Cu")
	)
	(gr_line
		(start 358.329992 -57.127648)
		(end 358.416606 -56.79567)
		(stroke
			(width 0.05715)
			(type default)
		)
		(layer "F.Cu")
	)
	(gr_line
		(start 358.39019 -65.160144)
		(end 358.412034 -65.155826)
		(stroke
			(width 0.05715)
			(type default)
		)
		(layer "F.Cu")
	)
	(gr_line
		(start 358.412034 -65.155826)
		(end 358.42956 -65.142618)
		(stroke
			(width 0.05715)
			(type default)
		)
		(layer "F.Cu")
	)
	(gr_line
		(start 358.416606 -56.79567)
		(end 358.553004 -56.715406)
		(stroke
			(width 0.05715)
			(type default)
		)
		(layer "F.Cu")
	)
	(gr_line
		(start 358.423464 -58.1787)
		(end 358.55021 -57.692798)
		(stroke
			(width 0.05715)
			(type default)
		)
		(layer "F.Cu")
	)
	(gr_line
		(start 358.480106 -40.392604)
		(end 358.484932 -40.412162)
		(stroke
			(width 0.05715)
			(type default)
		)
		(layer "F.Cu")
	)
	(gr_line
		(start 358.480868 -40.431974)
		(end 358.484932 -40.412162)
		(stroke
			(width 0.05715)
			(type default)
		)
		(layer "F.Cu")
	)
	(gr_line
		(start 358.560624 -56.242712)
		(end 358.640634 -56.379364)
		(stroke
			(width 0.05715)
			(type default)
		)
		(layer "F.Cu")
	)
	(gr_line
		(start 358.560624 -56.242712)
		(end 358.647238 -55.910734)
		(stroke
			(width 0.05715)
			(type default)
		)
		(layer "F.Cu")
	)
	(gr_line
		(start 358.583992 -37.718746)
		(end 358.591104 -37.747956)
		(stroke
			(width 0.05715)
			(type default)
		)
		(layer "F.Cu")
	)
	(gr_line
		(start 358.583992 -37.718746)
		(end 358.592882 -37.68852)
		(stroke
			(width 0.05715)
			(type default)
		)
		(layer "F.Cu")
	)
	(gr_line
		(start 358.647238 -55.910734)
		(end 358.783636 -55.830724)
		(stroke
			(width 0.05715)
			(type default)
		)
		(layer "F.Cu")
	)
	(gr_line
		(start 358.654096 -57.294272)
		(end 358.781096 -56.807354)
		(stroke
			(width 0.05715)
			(type default)
		)
		(layer "F.Cu")
	)
	(gr_line
		(start 358.791256 -55.357776)
		(end 358.87152 -55.494428)
		(stroke
			(width 0.05715)
			(type default)
		)
		(layer "F.Cu")
	)
	(gr_line
		(start 358.791256 -55.357776)
		(end 358.87787 -55.025798)
		(stroke
			(width 0.05715)
			(type default)
		)
		(layer "F.Cu")
	)
	(gr_line
		(start 358.793796 -43.731688)
		(end 358.848152 -43.69562)
		(stroke
			(width 0.05715)
			(type default)
		)
		(layer "F.Cu")
	)
	(gr_line
		(start 358.811576 -66.099944)
		(end 358.831896 -66.09588)
		(stroke
			(width 0.05715)
			(type default)
		)
		(layer "F.Cu")
	)
	(gr_line
		(start 358.831896 -66.09588)
		(end 358.848406 -66.083434)
		(stroke
			(width 0.05715)
			(type default)
		)
		(layer "F.Cu")
	)
	(gr_line
		(start 358.848152 -43.69562)
		(end 358.86136 -43.631358)
		(stroke
			(width 0.05715)
			(type default)
		)
		(layer "F.Cu")
	)
	(gr_line
		(start 358.87787 -55.025798)
		(end 359.014522 -54.945788)
		(stroke
			(width 0.05715)
			(type default)
		)
		(layer "F.Cu")
	)
	(gr_line
		(start 358.884728 -56.40959)
		(end 359.011474 -55.923434)
		(stroke
			(width 0.05715)
			(type default)
		)
		(layer "F.Cu")
	)
	(gr_line
		(start 358.923082 -126.648718)
		(end 358.937814 -126.659132)
		(stroke
			(width 0.05715)
			(type default)
		)
		(layer "F.Cu")
	)
	(gr_line
		(start 358.937814 -126.659132)
		(end 358.955594 -126.662688)
		(stroke
			(width 0.05715)
			(type default)
		)
		(layer "F.Cu")
	)
	(gr_line
		(start 359.08488 -78.139036)
		(end 359.558844 -78.135734)
		(stroke
			(width 0.05715)
			(type default)
		)
		(layer "F.Cu")
	)
	(gr_line
		(start 359.088944 -54.66842)
		(end 359.103676 -54.612286)
		(stroke
			(width 0.05715)
			(type default)
		)
		(layer "F.Cu")
	)
	(gr_line
		(start 359.103676 -54.612286)
		(end 359.150666 -54.580536)
		(stroke
			(width 0.05715)
			(type default)
		)
		(layer "F.Cu")
	)
	(gr_line
		(start 359.11536 -55.524908)
		(end 359.24236 -55.038244)
		(stroke
			(width 0.05715)
			(type default)
		)
		(layer "F.Cu")
	)
	(gr_line
		(start 359.156254 -59.337702)
		(end 359.159048 -59.333384)
		(stroke
			(width 0.05715)
			(type default)
		)
		(layer "F.Cu")
	)
	(gr_line
		(start 359.159048 -59.333384)
		(end 359.160318 -59.328558)
		(stroke
			(width 0.05715)
			(type default)
		)
		(layer "F.Cu")
	)
	(gr_line
		(start 359.231438 -67.039998)
		(end 359.251758 -67.035934)
		(stroke
			(width 0.05715)
			(type default)
		)
		(layer "F.Cu")
	)
	(gr_line
		(start 359.251758 -67.035934)
		(end 359.268268 -67.023488)
		(stroke
			(width 0.05715)
			(type default)
		)
		(layer "F.Cu")
	)
	(gr_line
		(start 359.282492 -62.811152)
		(end 359.332276 -62.77864)
		(stroke
			(width 0.05715)
			(type default)
		)
		(layer "F.Cu")
	)
	(gr_line
		(start 359.332276 -62.77864)
		(end 359.347262 -62.721236)
		(stroke
			(width 0.05715)
			(type default)
		)
		(layer "F.Cu")
	)
	(gr_line
		(start 359.498392 -40.477186)
		(end 359.503218 -40.496744)
		(stroke
			(width 0.05715)
			(type default)
		)
		(layer "F.Cu")
	)
	(gr_line
		(start 359.499154 -40.516556)
		(end 359.503218 -40.496744)
		(stroke
			(width 0.05715)
			(type default)
		)
		(layer "F.Cu")
	)
	(gr_line
		(start 359.558844 -78.135734)
		(end 359.67543 -78.251304)
		(stroke
			(width 0.05715)
			(type default)
		)
		(layer "F.Cu")
	)
	(gr_line
		(start 359.621582 -37.748972)
		(end 359.628694 -37.778182)
		(stroke
			(width 0.05715)
			(type default)
		)
		(layer "F.Cu")
	)
	(gr_line
		(start 359.621582 -37.748972)
		(end 359.630472 -37.718746)
		(stroke
			(width 0.05715)
			(type default)
		)
		(layer "F.Cu")
	)
	(gr_line
		(start 359.691432 -44.303442)
		(end 359.744772 -44.267374)
		(stroke
			(width 0.05715)
			(type default)
		)
		(layer "F.Cu")
	)
	(gr_line
		(start 359.744772 -44.267374)
		(end 359.757726 -44.204128)
		(stroke
			(width 0.05715)
			(type default)
		)
		(layer "F.Cu")
	)
	(gr_line
		(start 359.847642 -59.84367)
		(end 359.850182 -59.834272)
		(stroke
			(width 0.05715)
			(type default)
		)
		(layer "F.Cu")
	)
	(gr_line
		(start 359.850182 -59.834272)
		(end 359.850436 -59.834018)
		(stroke
			(width 0.05715)
			(type default)
		)
		(layer "F.Cu")
	)
	(gr_line
		(start 359.850436 -59.834018)
		(end 359.855516 -59.826652)
		(stroke
			(width 0.05715)
			(type default)
		)
		(layer "F.Cu")
	)
	(gr_line
		(start 359.921556 -78.245462)
		(end 360.032554 -78.133194)
		(stroke
			(width 0.05715)
			(type default)
		)
		(layer "F.Cu")
	)
	(gr_line
		(start 359.97515 -55.247794)
		(end 359.98912 -55.193692)
		(stroke
			(width 0.05715)
			(type default)
		)
		(layer "F.Cu")
	)
	(gr_line
		(start 359.98912 -55.193692)
		(end 360.03611 -55.161942)
		(stroke
			(width 0.05715)
			(type default)
		)
		(layer "F.Cu")
	)
	(gr_line
		(start 359.994454 -63.962788)
		(end 360.03357 -63.933578)
		(stroke
			(width 0.05715)
			(type default)
		)
		(layer "F.Cu")
	)
	(gr_line
		(start 360.032554 -78.133194)
		(end 360.510582 -78.129892)
		(stroke
			(width 0.05715)
			(type default)
		)
		(layer "F.Cu")
	)
	(gr_line
		(start 360.03357 -63.933578)
		(end 360.046016 -63.885826)
		(stroke
			(width 0.05715)
			(type default)
		)
		(layer "F.Cu")
	)
	(gr_line
		(start 360.107738 -126.893066)
		(end 360.120946 -126.895606)
		(stroke
			(width 0.05715)
			(type default)
		)
		(layer "F.Cu")
	)
	(gr_line
		(start 360.120946 -126.895606)
		(end 360.134154 -126.893066)
		(stroke
			(width 0.05715)
			(type default)
		)
		(layer "F.Cu")
	)
	(gr_line
		(start 360.138472 -19.809968)
		(end 360.138726 -19.810222)
		(stroke
			(width 0.05715)
			(type default)
		)
		(layer "F.Cu")
	)
	(gr_line
		(start 360.138472 -19.80946)
		(end 360.138472 -19.809968)
		(stroke
			(width 0.05715)
			(type default)
		)
		(layer "F.Cu")
	)
	(gr_line
		(start 360.138472 -19.80946)
		(end 360.142282 -19.791426)
		(stroke
			(width 0.05715)
			(type default)
		)
		(layer "F.Cu")
	)
	(gr_line
		(start 360.138726 -19.810222)
		(end 360.142028 -19.82597)
		(stroke
			(width 0.05715)
			(type default)
		)
		(layer "F.Cu")
	)
	(gr_line
		(start 360.156506 -22.64283)
		(end 360.160062 -22.660102)
		(stroke
			(width 0.05715)
			(type default)
		)
		(layer "F.Cu")
	)
	(gr_line
		(start 360.156506 -22.64283)
		(end 360.160062 -22.625812)
		(stroke
			(width 0.05715)
			(type default)
		)
		(layer "F.Cu")
	)
	(gr_line
		(start 360.160062 -22.625304)
		(end 360.160062 -22.625812)
		(stroke
			(width 0.05715)
			(type default)
		)
		(layer "F.Cu")
	)
	(gr_line
		(start 360.387392 -127.95758)
		(end 360.4006 -127.96012)
		(stroke
			(width 0.05715)
			(type default)
		)
		(layer "F.Cu")
	)
	(gr_line
		(start 360.400092 -128.968246)
		(end 360.4133 -128.970786)
		(stroke
			(width 0.05715)
			(type default)
		)
		(layer "F.Cu")
	)
	(gr_line
		(start 360.4006 -127.96012)
		(end 360.413808 -127.95758)
		(stroke
			(width 0.05715)
			(type default)
		)
		(layer "F.Cu")
	)
	(gr_line
		(start 360.4133 -128.970786)
		(end 360.426508 -128.968246)
		(stroke
			(width 0.05715)
			(type default)
		)
		(layer "F.Cu")
	)
	(gr_line
		(start 360.518202 -40.437562)
		(end 360.523028 -40.45712)
		(stroke
			(width 0.05715)
			(type default)
		)
		(layer "F.Cu")
	)
	(gr_line
		(start 360.518964 -40.476932)
		(end 360.523028 -40.45712)
		(stroke
			(width 0.05715)
			(type default)
		)
		(layer "F.Cu")
	)
	(gr_line
		(start 360.59364 -44.86656)
		(end 360.647742 -44.829984)
		(stroke
			(width 0.05715)
			(type default)
		)
		(layer "F.Cu")
	)
	(gr_line
		(start 360.647742 -44.829984)
		(end 360.66095 -44.765722)
		(stroke
			(width 0.05715)
			(type default)
		)
		(layer "F.Cu")
	)
	(gr_line
		(start 360.650536 -37.80917)
		(end 360.657648 -37.83838)
		(stroke
			(width 0.05715)
			(type default)
		)
		(layer "F.Cu")
	)
	(gr_line
		(start 360.650536 -37.80917)
		(end 360.659426 -37.778944)
		(stroke
			(width 0.05715)
			(type default)
		)
		(layer "F.Cu")
	)
	(gr_line
		(start 360.691684 -21.284946)
		(end 360.69524 -21.268182)
		(stroke
			(width 0.05715)
			(type default)
		)
		(layer "F.Cu")
	)
	(gr_line
		(start 360.691684 -21.251418)
		(end 360.69524 -21.268182)
		(stroke
			(width 0.05715)
			(type default)
		)
		(layer "F.Cu")
	)
	(gr_line
		(start 360.691684 -21.25091)
		(end 360.691684 -21.251164)
		(stroke
			(width 0.05715)
			(type default)
		)
		(layer "F.Cu")
	)
	(gr_line
		(start 360.731816 -60.298584)
		(end 360.734102 -60.290202)
		(stroke
			(width 0.05715)
			(type default)
		)
		(layer "F.Cu")
	)
	(gr_line
		(start 360.733848 -24.256746)
		(end 360.741468 -24.230838)
		(stroke
			(width 0.05715)
			(type default)
		)
		(layer "F.Cu")
	)
	(gr_line
		(start 360.734102 -60.290202)
		(end 360.738928 -60.283344)
		(stroke
			(width 0.05715)
			(type default)
		)
		(layer "F.Cu")
	)
	(gr_line
		(start 360.735626 -24.20366)
		(end 360.741468 -24.230838)
		(stroke
			(width 0.05715)
			(type default)
		)
		(layer "F.Cu")
	)
	(gr_line
		(start 360.78033 -51.362102)
		(end 360.792014 -51.354482)
		(stroke
			(width 0.05715)
			(type default)
		)
		(layer "F.Cu")
	)
	(gr_line
		(start 360.847132 -64.576452)
		(end 360.886248 -64.547242)
		(stroke
			(width 0.05715)
			(type default)
		)
		(layer "F.Cu")
	)
	(gr_line
		(start 360.886248 -64.547242)
		(end 360.898694 -64.49949)
		(stroke
			(width 0.05715)
			(type default)
		)
		(layer "F.Cu")
	)
	(gr_line
		(start 361.164378 -19.809714)
		(end 361.167934 -19.826986)
		(stroke
			(width 0.05715)
			(type default)
		)
		(layer "F.Cu")
	)
	(gr_line
		(start 361.164378 -19.809714)
		(end 361.168188 -19.79168)
		(stroke
			(width 0.05715)
			(type default)
		)
		(layer "F.Cu")
	)
	(gr_line
		(start 361.182412 -22.642322)
		(end 361.185968 -22.659594)
		(stroke
			(width 0.05715)
			(type default)
		)
		(layer "F.Cu")
	)
	(gr_line
		(start 361.182412 -22.642322)
		(end 361.185968 -22.625304)
		(stroke
			(width 0.05715)
			(type default)
		)
		(layer "F.Cu")
	)
	(gr_line
		(start 361.185968 -22.62505)
		(end 361.186222 -22.624288)
		(stroke
			(width 0.05715)
			(type default)
		)
		(layer "F.Cu")
	)
	(gr_line
		(start 361.300268 -2.937002)
		(end 361.648248 -2.937002)
		(stroke
			(width 0.05715)
			(type default)
		)
		(layer "F.Cu")
	)
	(gr_line
		(start 361.469432 -45.44187)
		(end 361.523534 -45.405294)
		(stroke
			(width 0.05715)
			(type default)
		)
		(layer "F.Cu")
	)
	(gr_line
		(start 361.48518 -3.708146)
		(end 361.48518 -4.389882)
		(stroke
			(width 0.05715)
			(type default)
		)
		(layer "F.Cu")
	)
	(gr_line
		(start 361.48518 -3.708146)
		(end 361.70489 -3.488436)
		(stroke
			(width 0.05715)
			(type default)
		)
		(layer "F.Cu")
	)
	(gr_line
		(start 361.51439 -119.337836)
		(end 361.535726 -119.331994)
		(stroke
			(width 0.05715)
			(type default)
		)
		(layer "F.Cu")
	)
	(gr_line
		(start 361.523534 -45.405294)
		(end 361.536742 -45.341032)
		(stroke
			(width 0.05715)
			(type default)
		)
		(layer "F.Cu")
	)
	(gr_line
		(start 361.535218 -40.447214)
		(end 361.540044 -40.466772)
		(stroke
			(width 0.05715)
			(type default)
		)
		(layer "F.Cu")
	)
	(gr_line
		(start 361.535726 -119.331994)
		(end 361.557316 -119.336312)
		(stroke
			(width 0.05715)
			(type default)
		)
		(layer "F.Cu")
	)
	(gr_line
		(start 361.53598 -40.486584)
		(end 361.540044 -40.466772)
		(stroke
			(width 0.05715)
			(type default)
		)
		(layer "F.Cu")
	)
	(gr_line
		(start 361.562396 -60.997084)
		(end 361.564682 -60.988702)
		(stroke
			(width 0.05715)
			(type default)
		)
		(layer "F.Cu")
	)
	(gr_line
		(start 361.564682 -60.988702)
		(end 361.569508 -60.981844)
		(stroke
			(width 0.05715)
			(type default)
		)
		(layer "F.Cu")
	)
	(gr_line
		(start 361.580684 -118.161562)
		(end 361.602528 -118.15572)
		(stroke
			(width 0.05715)
			(type default)
		)
		(layer "F.Cu")
	)
	(gr_line
		(start 361.602528 -118.15572)
		(end 361.624372 -118.160038)
		(stroke
			(width 0.05715)
			(type default)
		)
		(layer "F.Cu")
	)
	(gr_line
		(start 361.648248 -2.937002)
		(end 361.722924 -3.011678)
		(stroke
			(width 0.05715)
			(type default)
		)
		(layer "F.Cu")
	)
	(gr_line
		(start 361.685078 -37.847778)
		(end 361.69219 -37.876988)
		(stroke
			(width 0.05715)
			(type default)
		)
		(layer "F.Cu")
	)
	(gr_line
		(start 361.685078 -37.847778)
		(end 361.693968 -37.817552)
		(stroke
			(width 0.05715)
			(type default)
		)
		(layer "F.Cu")
	)
	(gr_line
		(start 361.689396 -65.198244)
		(end 361.72902 -65.168272)
		(stroke
			(width 0.05715)
			(type default)
		)
		(layer "F.Cu")
	)
	(gr_line
		(start 361.717336 -21.250148)
		(end 361.71759 -21.25091)
		(stroke
			(width 0.05715)
			(type default)
		)
		(layer "F.Cu")
	)
	(gr_line
		(start 361.71759 -21.285454)
		(end 361.721146 -21.268182)
		(stroke
			(width 0.05715)
			(type default)
		)
		(layer "F.Cu")
	)
	(gr_line
		(start 361.71759 -21.251164)
		(end 361.721146 -21.268182)
		(stroke
			(width 0.05715)
			(type default)
		)
		(layer "F.Cu")
	)
	(gr_line
		(start 361.72648 -115.971574)
		(end 361.749594 -115.965224)
		(stroke
			(width 0.05715)
			(type default)
		)
		(layer "F.Cu")
	)
	(gr_line
		(start 361.72902 -65.168272)
		(end 361.741466 -65.12052)
		(stroke
			(width 0.05715)
			(type default)
		)
		(layer "F.Cu")
	)
	(gr_line
		(start 361.74934 -140.21054)
		(end 363.31017 -141.77137)
		(stroke
			(width 0.0635)
			(type default)
		)
		(layer "F.Cu")
	)
	(gr_line
		(start 361.74934 -139.964668)
		(end 361.74934 -140.21054)
		(stroke
			(width 0.0635)
			(type default)
		)
		(layer "F.Cu")
	)
	(gr_line
		(start 361.749594 -115.965224)
		(end 361.772454 -115.970304)
		(stroke
			(width 0.05715)
			(type default)
		)
		(layer "F.Cu")
	)
	(gr_line
		(start 361.768136 -24.296878)
		(end 361.775756 -24.271224)
		(stroke
			(width 0.05715)
			(type default)
		)
		(layer "F.Cu")
	)
	(gr_line
		(start 361.770168 -24.2443)
		(end 361.775756 -24.271224)
		(stroke
			(width 0.05715)
			(type default)
		)
		(layer "F.Cu")
	)
	(gr_line
		(start 361.796584 -14.130528)
		(end 361.853226 -14.278356)
		(stroke
			(width 0.05715)
			(type default)
		)
		(layer "F.Cu")
	)
	(gr_line
		(start 361.796584 -14.130528)
		(end 361.936538 -13.8176)
		(stroke
			(width 0.05715)
			(type default)
		)
		(layer "F.Cu")
	)
	(gr_line
		(start 361.936538 -13.8176)
		(end 362.084366 -13.760958)
		(stroke
			(width 0.05715)
			(type default)
		)
		(layer "F.Cu")
	)
	(gr_line
		(start 361.98302 -119.667782)
		(end 362.00461 -119.6721)
		(stroke
			(width 0.04445)
			(type default)
		)
		(layer "F.Cu")
	)
	(gr_line
		(start 361.992164 -117.03685)
		(end 362.016294 -117.030246)
		(stroke
			(width 0.05715)
			(type default)
		)
		(layer "F.Cu")
	)
	(gr_line
		(start 362.00461 -119.6721)
		(end 362.032042 -119.653558)
		(stroke
			(width 0.04445)
			(type default)
		)
		(layer "F.Cu")
	)
	(gr_line
		(start 362.016294 -117.030246)
		(end 362.04144 -117.035834)
		(stroke
			(width 0.05715)
			(type default)
		)
		(layer "F.Cu")
	)
	(gr_line
		(start 362.03001 -119.431054)
		(end 362.0516 -119.435372)
		(stroke
			(width 0.04445)
			(type default)
		)
		(layer "F.Cu")
	)
	(gr_line
		(start 362.049822 -3.488436)
		(end 362.285026 -3.72364)
		(stroke
			(width 0.05715)
			(type default)
		)
		(layer "F.Cu")
	)
	(gr_line
		(start 362.0516 -119.435372)
		(end 362.069888 -119.461788)
		(stroke
			(width 0.04445)
			(type default)
		)
		(layer "F.Cu")
	)
	(gr_line
		(start 362.067856 -3.011678)
		(end 362.142532 -2.937002)
		(stroke
			(width 0.05715)
			(type default)
		)
		(layer "F.Cu")
	)
	(gr_line
		(start 362.089192 -14.347952)
		(end 362.293916 -13.889736)
		(stroke
			(width 0.05715)
			(type default)
		)
		(layer "F.Cu")
	)
	(gr_line
		(start 362.142532 -2.937002)
		(end 362.570268 -2.937002)
		(stroke
			(width 0.05715)
			(type default)
		)
		(layer "F.Cu")
	)
	(gr_line
		(start 362.16971 -13.29563)
		(end 362.226098 -13.443458)
		(stroke
			(width 0.05715)
			(type default)
		)
		(layer "F.Cu")
	)
	(gr_line
		(start 362.16971 -13.29563)
		(end 362.309664 -12.982702)
		(stroke
			(width 0.05715)
			(type default)
		)
		(layer "F.Cu")
	)
	(gr_line
		(start 362.189776 -19.80946)
		(end 362.193332 -19.826732)
		(stroke
			(width 0.05715)
			(type default)
		)
		(layer "F.Cu")
	)
	(gr_line
		(start 362.189776 -19.80946)
		(end 362.193586 -19.791426)
		(stroke
			(width 0.05715)
			(type default)
		)
		(layer "F.Cu")
	)
	(gr_line
		(start 362.208064 -22.641814)
		(end 362.21162 -22.658832)
		(stroke
			(width 0.05715)
			(type default)
		)
		(layer "F.Cu")
	)
	(gr_line
		(start 362.208064 -22.641814)
		(end 362.211874 -22.624542)
		(stroke
			(width 0.05715)
			(type default)
		)
		(layer "F.Cu")
	)
	(gr_line
		(start 362.276644 -10.916158)
		(end 362.548678 -11.188192)
		(stroke
			(width 0.05715)
			(type default)
		)
		(layer "F.Cu")
	)
	(gr_line
		(start 362.276644 -10.027158)
		(end 362.548678 -9.755124)
		(stroke
			(width 0.05715)
			(type default)
		)
		(layer "F.Cu")
	)
	(gr_line
		(start 362.285026 -8.5979)
		(end 362.51261 -8.825484)
		(stroke
			(width 0.05715)
			(type default)
		)
		(layer "F.Cu")
	)
	(gr_line
		(start 362.285026 -7.789926)
		(end 362.285026 -8.5979)
		(stroke
			(width 0.05715)
			(type default)
		)
		(layer "F.Cu")
	)
	(gr_line
		(start 362.285026 -3.72364)
		(end 362.285026 -4.389882)
		(stroke
			(width 0.05715)
			(type default)
		)
		(layer "F.Cu")
	)
	(gr_line
		(start 362.309664 -12.982702)
		(end 362.457238 -12.926314)
		(stroke
			(width 0.05715)
			(type default)
		)
		(layer "F.Cu")
	)
	(gr_line
		(start 362.447078 -61.458856)
		(end 362.449364 -61.450474)
		(stroke
			(width 0.05715)
			(type default)
		)
		(layer "F.Cu")
	)
	(gr_line
		(start 362.449364 -61.450474)
		(end 362.45419 -61.443616)
		(stroke
			(width 0.05715)
			(type default)
		)
		(layer "F.Cu")
	)
	(gr_line
		(start 362.46181 -13.513816)
		(end 362.666788 -13.055092)
		(stroke
			(width 0.05715)
			(type default)
		)
		(layer "F.Cu")
	)
	(gr_line
		(start 362.469176 -45.970952)
		(end 362.522262 -45.935138)
		(stroke
			(width 0.05715)
			(type default)
		)
		(layer "F.Cu")
	)
	(gr_line
		(start 362.522262 -45.935138)
		(end 362.534708 -45.872654)
		(stroke
			(width 0.05715)
			(type default)
		)
		(layer "F.Cu")
	)
	(gr_line
		(start 362.543852 -40.375078)
		(end 362.548678 -40.394636)
		(stroke
			(width 0.05715)
			(type default)
		)
		(layer "F.Cu")
	)
	(gr_line
		(start 362.544614 -40.414448)
		(end 362.548678 -40.394636)
		(stroke
			(width 0.05715)
			(type default)
		)
		(layer "F.Cu")
	)
	(gr_line
		(start 362.56087 -119.759222)
		(end 362.628434 -119.860822)
		(stroke
			(width 0.04445)
			(type default)
		)
		(layer "F.Cu")
	)
	(gr_line
		(start 362.627164 -51.049174)
		(end 362.657136 -50.893726)
		(stroke
			(width 0.05715)
			(type default)
		)
		(layer "F.Cu")
	)
	(gr_line
		(start 362.627418 -119.575834)
		(end 363.000544 -119.650256)
		(stroke
			(width 0.04445)
			(type default)
		)
		(layer "F.Cu")
	)
	(gr_line
		(start 362.628434 -119.860822)
		(end 362.890054 -119.913146)
		(stroke
			(width 0.04445)
			(type default)
		)
		(layer "F.Cu")
	)
	(gr_line
		(start 362.657136 -50.893726)
		(end 362.941108 -50.701448)
		(stroke
			(width 0.05715)
			(type default)
		)
		(layer "F.Cu")
	)
	(gr_line
		(start 362.722922 -37.926772)
		(end 362.730034 -37.955982)
		(stroke
			(width 0.05715)
			(type default)
		)
		(layer "F.Cu")
	)
	(gr_line
		(start 362.722922 -37.926772)
		(end 362.731812 -37.897054)
		(stroke
			(width 0.05715)
			(type default)
		)
		(layer "F.Cu")
	)
	(gr_line
		(start 362.742988 -21.250148)
		(end 362.743242 -21.25091)
		(stroke
			(width 0.05715)
			(type default)
		)
		(layer "F.Cu")
	)
	(gr_line
		(start 362.743242 -21.285454)
		(end 362.746798 -21.268182)
		(stroke
			(width 0.05715)
			(type default)
		)
		(layer "F.Cu")
	)
	(gr_line
		(start 362.743242 -21.251164)
		(end 362.746798 -21.268182)
		(stroke
			(width 0.05715)
			(type default)
		)
		(layer "F.Cu")
	)
	(gr_line
		(start 362.789724 -51.233832)
		(end 363.20857 -50.950368)
		(stroke
			(width 0.05715)
			(type default)
		)
		(layer "F.Cu")
	)
	(gr_line
		(start 362.802424 -24.337772)
		(end 362.810044 -24.312372)
		(stroke
			(width 0.05715)
			(type default)
		)
		(layer "F.Cu")
	)
	(gr_line
		(start 362.804456 -24.285448)
		(end 362.810044 -24.312372)
		(stroke
			(width 0.05715)
			(type default)
		)
		(layer "F.Cu")
	)
	(gr_line
		(start 362.804456 -24.285194)
		(end 362.804456 -24.285702)
		(stroke
			(width 0.05715)
			(type default)
		)
		(layer "F.Cu")
	)
	(gr_line
		(start 362.83519 -12.677648)
		(end 362.841794 -12.663424)
		(stroke
			(width 0.05715)
			(type default)
		)
		(layer "F.Cu")
	)
	(gr_line
		(start 362.857542 -8.825484)
		(end 363.085126 -8.5979)
		(stroke
			(width 0.05715)
			(type default)
		)
		(layer "F.Cu")
	)
	(gr_line
		(start 362.875068 -123.5075)
		(end 362.897166 -123.5075)
		(stroke
			(width 0.04445)
			(type default)
		)
		(layer "F.Cu")
	)
	(gr_line
		(start 362.875068 -123.2662)
		(end 362.897166 -123.2662)
		(stroke
			(width 0.04445)
			(type default)
		)
		(layer "F.Cu")
	)
	(gr_line
		(start 362.890054 -119.913146)
		(end 362.991908 -119.845328)
		(stroke
			(width 0.04445)
			(type default)
		)
		(layer "F.Cu")
	)
	(gr_line
		(start 362.89361 -11.188192)
		(end 363.165644 -10.916158)
		(stroke
			(width 0.05715)
			(type default)
		)
		(layer "F.Cu")
	)
	(gr_line
		(start 362.89361 -9.755124)
		(end 363.165644 -10.027158)
		(stroke
			(width 0.05715)
			(type default)
		)
		(layer "F.Cu")
	)
	(gr_line
		(start 362.897166 -123.5075)
		(end 362.922566 -123.4821)
		(stroke
			(width 0.04445)
			(type default)
		)
		(layer "F.Cu")
	)
	(gr_line
		(start 362.897166 -123.2662)
		(end 362.922566 -123.2916)
		(stroke
			(width 0.04445)
			(type default)
		)
		(layer "F.Cu")
	)
	(gr_line
		(start 362.930694 -47.710852)
		(end 362.938822 -47.69866)
		(stroke
			(width 0.05715)
			(type default)
		)
		(layer "F.Cu")
	)
	(gr_line
		(start 362.938822 -47.69866)
		(end 362.950506 -47.69104)
		(stroke
			(width 0.05715)
			(type default)
		)
		(layer "F.Cu")
	)
	(gr_line
		(start 362.941108 -50.701448)
		(end 363.09681 -50.73142)
		(stroke
			(width 0.05715)
			(type default)
		)
		(layer "F.Cu")
	)
	(gr_line
		(start 362.95584 -55.416704)
		(end 362.961936 -55.408068)
		(stroke
			(width 0.05715)
			(type default)
		)
		(layer "F.Cu")
	)
	(gr_line
		(start 362.961936 -55.408068)
		(end 362.970572 -55.402226)
		(stroke
			(width 0.05715)
			(type default)
		)
		(layer "F.Cu")
	)
	(gr_line
		(start 363.085126 -7.789926)
		(end 363.085126 -8.5979)
		(stroke
			(width 0.05715)
			(type default)
		)
		(layer "F.Cu")
	)
	(gr_line
		(start 363.159548 -14.158976)
		(end 363.161072 -14.156182)
		(stroke
			(width 0.05715)
			(type default)
		)
		(layer "F.Cu")
	)
	(gr_line
		(start 363.215428 -19.809206)
		(end 363.218984 -19.826478)
		(stroke
			(width 0.05715)
			(type default)
		)
		(layer "F.Cu")
	)
	(gr_line
		(start 363.215428 -19.809206)
		(end 363.219238 -19.791172)
		(stroke
			(width 0.05715)
			(type default)
		)
		(layer "F.Cu")
	)
	(gr_line
		(start 363.233716 -22.642068)
		(end 363.237272 -22.65934)
		(stroke
			(width 0.05715)
			(type default)
		)
		(layer "F.Cu")
	)
	(gr_line
		(start 363.233716 -22.642068)
		(end 363.237272 -22.62505)
		(stroke
			(width 0.05715)
			(type default)
		)
		(layer "F.Cu")
	)
	(gr_line
		(start 363.237272 -22.624796)
		(end 363.237526 -22.624034)
		(stroke
			(width 0.05715)
			(type default)
		)
		(layer "F.Cu")
	)
	(gr_line
		(start 363.2581 -119.898414)
		(end 363.325918 -120.000268)
		(stroke
			(width 0.04445)
			(type default)
		)
		(layer "F.Cu")
	)
	(gr_line
		(start 363.264196 -56.692038)
		(end 363.27207 -56.680862)
		(stroke
			(width 0.05715)
			(type default)
		)
		(layer "F.Cu")
	)
	(gr_line
		(start 363.27207 -56.680862)
		(end 363.28223 -56.674004)
		(stroke
			(width 0.05715)
			(type default)
		)
		(layer "F.Cu")
	)
	(gr_line
		(start 363.31017 -141.77137)
		(end 363.87024 -141.77137)
		(stroke
			(width 0.0635)
			(type default)
		)
		(layer "F.Cu")
	)
	(gr_line
		(start 363.323378 -119.714772)
		(end 363.540294 -119.758206)
		(stroke
			(width 0.04445)
			(type default)
		)
		(layer "F.Cu")
	)
	(gr_line
		(start 363.325918 -120.000268)
		(end 363.587538 -120.052592)
		(stroke
			(width 0.04445)
			(type default)
		)
		(layer "F.Cu")
	)
	(gr_line
		(start 363.338872 -46.552104)
		(end 363.392466 -46.515782)
		(stroke
			(width 0.05715)
			(type default)
		)
		(layer "F.Cu")
	)
	(gr_line
		(start 363.344206 -123.48464)
		(end 363.430566 -123.571)
		(stroke
			(width 0.04445)
			(type default)
		)
		(layer "F.Cu")
	)
	(gr_line
		(start 363.392466 -46.515782)
		(end 363.40542 -46.45279)
		(stroke
			(width 0.05715)
			(type default)
		)
		(layer "F.Cu")
	)
	(gr_line
		(start 363.430566 -123.571)
		(end 363.697266 -123.571)
		(stroke
			(width 0.04445)
			(type default)
		)
		(layer "F.Cu")
	)
	(gr_line
		(start 363.48035 -1.970024)
		(end 363.746796 -1.970024)
		(stroke
			(width 0.05715)
			(type default)
		)
		(layer "F.Cu")
	)
	(gr_line
		(start 363.534706 -123.2916)
		(end 363.593126 -123.2916)
		(stroke
			(width 0.04445)
			(type default)
		)
		(layer "F.Cu")
	)
	(gr_line
		(start 363.546898 -50.720752)
		(end 363.558582 -50.713132)
		(stroke
			(width 0.05715)
			(type default)
		)
		(layer "F.Cu")
	)
	(gr_line
		(start 363.558582 -50.713132)
		(end 363.56671 -50.70094)
		(stroke
			(width 0.05715)
			(type default)
		)
		(layer "F.Cu")
	)
	(gr_line
		(start 363.587538 -120.052592)
		(end 363.689392 -119.98452)
		(stroke
			(width 0.04445)
			(type default)
		)
		(layer "F.Cu")
	)
	(gr_line
		(start 363.606842 -40.557958)
		(end 363.611668 -40.578024)
		(stroke
			(width 0.05715)
			(type default)
		)
		(layer "F.Cu")
	)
	(gr_line
		(start 363.607604 -40.597582)
		(end 363.611668 -40.578024)
		(stroke
			(width 0.05715)
			(type default)
		)
		(layer "F.Cu")
	)
	(gr_line
		(start 363.634782 -13.520674)
		(end 363.634782 -13.678916)
		(stroke
			(width 0.05715)
			(type default)
		)
		(layer "F.Cu")
	)
	(gr_line
		(start 363.634782 -13.520674)
		(end 363.877352 -13.278358)
		(stroke
			(width 0.05715)
			(type default)
		)
		(layer "F.Cu")
	)
	(gr_line
		(start 363.697266 -123.571)
		(end 363.783626 -123.48464)
		(stroke
			(width 0.04445)
			(type default)
		)
		(layer "F.Cu")
	)
	(gr_line
		(start 363.7026 -115.189)
		(end 364.617 -115.189)
		(stroke
			(width 0.05715)
			(type default)
		)
		(layer "F.Cu")
	)
	(gr_line
		(start 363.7026 -113.792)
		(end 364.617 -113.792)
		(stroke
			(width 0.05715)
			(type default)
		)
		(layer "F.Cu")
	)
	(gr_line
		(start 363.7026 -112.4204)
		(end 363.728 -112.395)
		(stroke
			(width 0.05715)
			(type default)
		)
		(layer "F.Cu")
	)
	(gr_line
		(start 363.7026 -111.0234)
		(end 363.728 -110.998)
		(stroke
			(width 0.05715)
			(type default)
		)
		(layer "F.Cu")
	)
	(gr_line
		(start 363.728 -112.395)
		(end 364.617 -112.395)
		(stroke
			(width 0.05715)
			(type default)
		)
		(layer "F.Cu")
	)
	(gr_line
		(start 363.728 -110.998)
		(end 364.617 -110.998)
		(stroke
			(width 0.05715)
			(type default)
		)
		(layer "F.Cu")
	)
	(gr_line
		(start 363.732064 -49.811432)
		(end 363.763052 -49.96688)
		(stroke
			(width 0.05715)
			(type default)
		)
		(layer "F.Cu")
	)
	(gr_line
		(start 363.732064 -49.811432)
		(end 363.92231 -49.52619)
		(stroke
			(width 0.05715)
			(type default)
		)
		(layer "F.Cu")
	)
	(gr_line
		(start 363.746796 -1.970024)
		(end 363.92612 -2.149348)
		(stroke
			(width 0.05715)
			(type default)
		)
		(layer "F.Cu")
	)
	(gr_line
		(start 363.76864 -21.250148)
		(end 363.768894 -21.25091)
		(stroke
			(width 0.05715)
			(type default)
		)
		(layer "F.Cu")
	)
	(gr_line
		(start 363.768894 -21.285454)
		(end 363.77245 -21.268182)
		(stroke
			(width 0.05715)
			(type default)
		)
		(layer "F.Cu")
	)
	(gr_line
		(start 363.768894 -21.251164)
		(end 363.77245 -21.268182)
		(stroke
			(width 0.05715)
			(type default)
		)
		(layer "F.Cu")
	)
	(gr_line
		(start 363.7788 -37.967666)
		(end 363.785912 -37.996876)
		(stroke
			(width 0.05715)
			(type default)
		)
		(layer "F.Cu")
	)
	(gr_line
		(start 363.7788 -37.967666)
		(end 363.787436 -37.937948)
		(stroke
			(width 0.05715)
			(type default)
		)
		(layer "F.Cu")
	)
	(gr_line
		(start 363.787436 -37.938202)
		(end 363.78769 -37.93744)
		(stroke
			(width 0.05715)
			(type default)
		)
		(layer "F.Cu")
	)
	(gr_line
		(start 363.807756 -118.844314)
		(end 363.829346 -118.848632)
		(stroke
			(width 0.04445)
			(type default)
		)
		(layer "F.Cu")
	)
	(gr_line
		(start 363.829346 -118.848632)
		(end 363.856778 -118.83009)
		(stroke
			(width 0.04445)
			(type default)
		)
		(layer "F.Cu")
	)
	(gr_line
		(start 363.836712 -24.379428)
		(end 363.844332 -24.35352)
		(stroke
			(width 0.05715)
			(type default)
		)
		(layer "F.Cu")
	)
	(gr_line
		(start 363.83849 -24.326342)
		(end 363.844332 -24.35352)
		(stroke
			(width 0.05715)
			(type default)
		)
		(layer "F.Cu")
	)
	(gr_line
		(start 363.855 -118.607586)
		(end 363.87659 -118.61165)
		(stroke
			(width 0.04445)
			(type default)
		)
		(layer "F.Cu")
	)
	(gr_line
		(start 363.87024 -141.77137)
		(end 363.87024 -142.53464)
		(stroke
			(width 0.0635)
			(type default)
		)
		(layer "F.Cu")
	)
	(gr_line
		(start 363.87659 -118.61165)
		(end 363.89437 -118.63832)
		(stroke
			(width 0.04445)
			(type default)
		)
		(layer "F.Cu")
	)
	(gr_line
		(start 363.877352 -13.278358)
		(end 364.035594 -13.278104)
		(stroke
			(width 0.05715)
			(type default)
		)
		(layer "F.Cu")
	)
	(gr_line
		(start 363.885226 -3.70205)
		(end 363.885226 -4.389882)
		(stroke
			(width 0.05715)
			(type default)
		)
		(layer "F.Cu")
	)
	(gr_line
		(start 363.885226 -3.70205)
		(end 364.082584 -3.504692)
		(stroke
			(width 0.05715)
			(type default)
		)
		(layer "F.Cu")
	)
	(gr_line
		(start 363.92231 -49.52619)
		(end 364.077504 -49.495202)
		(stroke
			(width 0.05715)
			(type default)
		)
		(layer "F.Cu")
	)
	(gr_line
		(start 363.934502 -126.4031)
		(end 363.9566 -126.4031)
		(stroke
			(width 0.04445)
			(type default)
		)
		(layer "F.Cu")
	)
	(gr_line
		(start 363.934502 -126.1618)
		(end 363.9566 -126.1618)
		(stroke
			(width 0.04445)
			(type default)
		)
		(layer "F.Cu")
	)
	(gr_line
		(start 363.935518 -117.70487)
		(end 363.957108 -117.709696)
		(stroke
			(width 0.04445)
			(type default)
		)
		(layer "F.Cu")
	)
	(gr_line
		(start 363.955584 -120.03786)
		(end 364.023402 -120.139714)
		(stroke
			(width 0.04445)
			(type default)
		)
		(layer "F.Cu")
	)
	(gr_line
		(start 363.9566 -126.4031)
		(end 363.982 -126.3777)
		(stroke
			(width 0.04445)
			(type default)
		)
		(layer "F.Cu")
	)
	(gr_line
		(start 363.9566 -126.1618)
		(end 363.982 -126.1872)
		(stroke
			(width 0.04445)
			(type default)
		)
		(layer "F.Cu")
	)
	(gr_line
		(start 363.957108 -117.709696)
		(end 363.984286 -117.691916)
		(stroke
			(width 0.04445)
			(type default)
		)
		(layer "F.Cu")
	)
	(gr_line
		(start 363.977936 -13.680694)
		(end 364.037372 -13.621258)
		(stroke
			(width 0.05715)
			(type default)
		)
		(layer "F.Cu")
	)
	(gr_line
		(start 363.982508 -50.077116)
		(end 364.262924 -49.656746)
		(stroke
			(width 0.05715)
			(type default)
		)
		(layer "F.Cu")
	)
	(gr_line
		(start 363.987842 -117.469158)
		(end 364.009432 -117.473984)
		(stroke
			(width 0.04445)
			(type default)
		)
		(layer "F.Cu")
	)
	(gr_line
		(start 364.009432 -117.473984)
		(end 364.02645 -117.501162)
		(stroke
			(width 0.04445)
			(type default)
		)
		(layer "F.Cu")
	)
	(gr_line
		(start 364.020862 -119.853964)
		(end 364.397544 -119.929402)
		(stroke
			(width 0.04445)
			(type default)
		)
		(layer "F.Cu")
	)
	(gr_line
		(start 364.023402 -120.139714)
		(end 364.285022 -120.191784)
		(stroke
			(width 0.04445)
			(type default)
		)
		(layer "F.Cu")
	)
	(gr_line
		(start 364.066328 -14.63167)
		(end 364.079282 -14.606524)
		(stroke
			(width 0.05715)
			(type default)
		)
		(layer "F.Cu")
	)
	(gr_line
		(start 364.079282 -14.606524)
		(end 364.102904 -14.59103)
		(stroke
			(width 0.05715)
			(type default)
		)
		(layer "F.Cu")
	)
	(gr_line
		(start 364.135416 -46.887892)
		(end 364.148624 -46.879002)
		(stroke
			(width 0.05715)
			(type default)
		)
		(layer "F.Cu")
	)
	(gr_line
		(start 364.148624 -46.879002)
		(end 364.163864 -46.875954)
		(stroke
			(width 0.05715)
			(type default)
		)
		(layer "F.Cu")
	)
	(gr_line
		(start 364.183422 -32.982662)
		(end 364.197646 -32.93491)
		(stroke
			(width 0.05715)
			(type default)
		)
		(layer "F.Cu")
	)
	(gr_line
		(start 364.196122 -57.244234)
		(end 364.202218 -57.235598)
		(stroke
			(width 0.05715)
			(type default)
		)
		(layer "F.Cu")
	)
	(gr_line
		(start 364.197646 -32.93491)
		(end 364.238286 -32.905954)
		(stroke
			(width 0.05715)
			(type default)
		)
		(layer "F.Cu")
	)
	(gr_line
		(start 364.202218 -57.235598)
		(end 364.211108 -57.229502)
		(stroke
			(width 0.05715)
			(type default)
		)
		(layer "F.Cu")
	)
	(gr_line
		(start 364.239302 -49.050702)
		(end 364.27029 -49.205896)
		(stroke
			(width 0.05715)
			(type default)
		)
		(layer "F.Cu")
	)
	(gr_line
		(start 364.239302 -49.050702)
		(end 364.429548 -48.765206)
		(stroke
			(width 0.05715)
			(type default)
		)
		(layer "F.Cu")
	)
	(gr_line
		(start 364.24108 -19.809206)
		(end 364.244636 -19.826478)
		(stroke
			(width 0.05715)
			(type default)
		)
		(layer "F.Cu")
	)
	(gr_line
		(start 364.24108 -19.809206)
		(end 364.24489 -19.791172)
		(stroke
			(width 0.05715)
			(type default)
		)
		(layer "F.Cu")
	)
	(gr_line
		(start 364.255558 -51.415188)
		(end 364.267242 -51.407568)
		(stroke
			(width 0.05715)
			(type default)
		)
		(layer "F.Cu")
	)
	(gr_line
		(start 364.26013 -22.645878)
		(end 364.263686 -22.66315)
		(stroke
			(width 0.05715)
			(type default)
		)
		(layer "F.Cu")
	)
	(gr_line
		(start 364.26013 -22.645878)
		(end 364.263686 -22.62886)
		(stroke
			(width 0.05715)
			(type default)
		)
		(layer "F.Cu")
	)
	(gr_line
		(start 364.263686 -22.628606)
		(end 364.26394 -22.627844)
		(stroke
			(width 0.05715)
			(type default)
		)
		(layer "F.Cu")
	)
	(gr_line
		(start 364.267242 -51.407568)
		(end 364.27537 -51.395376)
		(stroke
			(width 0.05715)
			(type default)
		)
		(layer "F.Cu")
	)
	(gr_line
		(start 364.271052 -2.149348)
		(end 364.450376 -1.970024)
		(stroke
			(width 0.05715)
			(type default)
		)
		(layer "F.Cu")
	)
	(gr_line
		(start 364.285022 -120.191784)
		(end 364.38713 -120.123966)
		(stroke
			(width 0.04445)
			(type default)
		)
		(layer "F.Cu")
	)
	(gr_line
		(start 364.40364 -123.48464)
		(end 364.49 -123.571)
		(stroke
			(width 0.04445)
			(type default)
		)
		(layer "F.Cu")
	)
	(gr_line
		(start 364.427516 -3.504692)
		(end 364.685072 -3.762248)
		(stroke
			(width 0.05715)
			(type default)
		)
		(layer "F.Cu")
	)
	(gr_line
		(start 364.429548 -48.765206)
		(end 364.584742 -48.734472)
		(stroke
			(width 0.05715)
			(type default)
		)
		(layer "F.Cu")
	)
	(gr_line
		(start 364.450376 -1.970024)
		(end 364.75035 -1.970024)
		(stroke
			(width 0.05715)
			(type default)
		)
		(layer "F.Cu")
	)
	(gr_line
		(start 364.49 -123.571)
		(end 364.7567 -123.571)
		(stroke
			(width 0.04445)
			(type default)
		)
		(layer "F.Cu")
	)
	(gr_line
		(start 364.49127 -49.3141)
		(end 364.770162 -48.896016)
		(stroke
			(width 0.05715)
			(type default)
		)
		(layer "F.Cu")
	)
	(gr_line
		(start 364.49508 -126.38024)
		(end 364.58144 -126.4666)
		(stroke
			(width 0.04445)
			(type default)
		)
		(layer "F.Cu")
	)
	(gr_line
		(start 364.575344 -127.4445)
		(end 364.597442 -127.4445)
		(stroke
			(width 0.04445)
			(type default)
		)
		(layer "F.Cu")
	)
	(gr_line
		(start 364.575344 -127.2032)
		(end 364.597442 -127.2032)
		(stroke
			(width 0.04445)
			(type default)
		)
		(layer "F.Cu")
	)
	(gr_line
		(start 364.58144 -126.4666)
		(end 364.84814 -126.4666)
		(stroke
			(width 0.04445)
			(type default)
		)
		(layer "F.Cu")
	)
	(gr_line
		(start 364.59414 -123.2916)
		(end 364.65256 -123.2916)
		(stroke
			(width 0.04445)
			(type default)
		)
		(layer "F.Cu")
	)
	(gr_line
		(start 364.597442 -127.4445)
		(end 364.622842 -127.4191)
		(stroke
			(width 0.04445)
			(type default)
		)
		(layer "F.Cu")
	)
	(gr_line
		(start 364.597442 -127.2032)
		(end 364.622842 -127.2286)
		(stroke
			(width 0.04445)
			(type default)
		)
		(layer "F.Cu")
	)
	(gr_line
		(start 364.600744 -10.916158)
		(end 364.872778 -11.188192)
		(stroke
			(width 0.05715)
			(type default)
		)
		(layer "F.Cu")
	)
	(gr_line
		(start 364.600744 -10.027158)
		(end 364.872778 -9.755124)
		(stroke
			(width 0.05715)
			(type default)
		)
		(layer "F.Cu")
	)
	(gr_line
		(start 364.621826 -40.429688)
		(end 364.626652 -40.449754)
		(stroke
			(width 0.05715)
			(type default)
		)
		(layer "F.Cu")
	)
	(gr_line
		(start 364.622588 -40.469312)
		(end 364.626652 -40.449754)
		(stroke
			(width 0.05715)
			(type default)
		)
		(layer "F.Cu")
	)
	(gr_line
		(start 364.655862 -118.00078)
		(end 364.67161 -118.009416)
		(stroke
			(width 0.04445)
			(type default)
		)
		(layer "F.Cu")
	)
	(gr_line
		(start 364.6678 -15.599664)
		(end 364.681516 -15.573248)
		(stroke
			(width 0.05715)
			(type default)
		)
		(layer "F.Cu")
	)
	(gr_line
		(start 364.681516 -15.573248)
		(end 364.706408 -15.556738)
		(stroke
			(width 0.05715)
			(type default)
		)
		(layer "F.Cu")
	)
	(gr_line
		(start 364.685072 -8.5979)
		(end 364.912656 -8.825484)
		(stroke
			(width 0.05715)
			(type default)
		)
		(layer "F.Cu")
	)
	(gr_line
		(start 364.685072 -7.789926)
		(end 364.685072 -8.5979)
		(stroke
			(width 0.05715)
			(type default)
		)
		(layer "F.Cu")
	)
	(gr_line
		(start 364.685072 -3.762248)
		(end 364.685072 -4.389882)
		(stroke
			(width 0.05715)
			(type default)
		)
		(layer "F.Cu")
	)
	(gr_line
		(start 364.68558 -126.1872)
		(end 364.744 -126.1872)
		(stroke
			(width 0.04445)
			(type default)
		)
		(layer "F.Cu")
	)
	(gr_line
		(start 364.744 -58.185558)
		(end 364.750096 -58.176668)
		(stroke
			(width 0.05715)
			(type default)
		)
		(layer "F.Cu")
	)
	(gr_line
		(start 364.750096 -58.176668)
		(end 364.758224 -58.17108)
		(stroke
			(width 0.05715)
			(type default)
		)
		(layer "F.Cu")
	)
	(gr_line
		(start 364.7567 -123.571)
		(end 364.84306 -123.48464)
		(stroke
			(width 0.04445)
			(type default)
		)
		(layer "F.Cu")
	)
	(gr_line
		(start 364.78464 -141.77137)
		(end 364.78464 -142.5448)
		(stroke
			(width 0.0635)
			(type default)
		)
		(layer "F.Cu")
	)
	(gr_line
		(start 364.795054 -21.25472)
		(end 364.795308 -21.255482)
		(stroke
			(width 0.05715)
			(type default)
		)
		(layer "F.Cu")
	)
	(gr_line
		(start 364.795308 -21.290026)
		(end 364.798864 -21.272754)
		(stroke
			(width 0.05715)
			(type default)
		)
		(layer "F.Cu")
	)
	(gr_line
		(start 364.795308 -21.255736)
		(end 364.798864 -21.272754)
		(stroke
			(width 0.05715)
			(type default)
		)
		(layer "F.Cu")
	)
	(gr_line
		(start 364.809024 -48.401986)
		(end 364.81766 -48.389032)
		(stroke
			(width 0.05715)
			(type default)
		)
		(layer "F.Cu")
	)
	(gr_line
		(start 364.81385 -34.47796)
		(end 364.827566 -34.431732)
		(stroke
			(width 0.05715)
			(type default)
		)
		(layer "F.Cu")
	)
	(gr_line
		(start 364.81766 -48.389032)
		(end 364.830614 -48.380396)
		(stroke
			(width 0.05715)
			(type default)
		)
		(layer "F.Cu")
	)
	(gr_line
		(start 364.82528 -120.211596)
		(end 364.893098 -120.313196)
		(stroke
			(width 0.04445)
			(type default)
		)
		(layer "F.Cu")
	)
	(gr_line
		(start 364.827566 -34.431732)
		(end 364.866936 -34.403792)
		(stroke
			(width 0.05715)
			(type default)
		)
		(layer "F.Cu")
	)
	(gr_line
		(start 364.84814 -126.4666)
		(end 364.9345 -126.38024)
		(stroke
			(width 0.04445)
			(type default)
		)
		(layer "F.Cu")
	)
	(gr_line
		(start 364.870746 -24.420068)
		(end 364.878366 -24.394668)
		(stroke
			(width 0.05715)
			(type default)
		)
		(layer "F.Cu")
	)
	(gr_line
		(start 364.872778 -24.36749)
		(end 364.878366 -24.394668)
		(stroke
			(width 0.05715)
			(type default)
		)
		(layer "F.Cu")
	)
	(gr_line
		(start 364.891066 -120.0277)
		(end 365.26597 -120.10263)
		(stroke
			(width 0.04445)
			(type default)
		)
		(layer "F.Cu")
	)
	(gr_line
		(start 364.893098 -120.313196)
		(end 365.154718 -120.36552)
		(stroke
			(width 0.04445)
			(type default)
		)
		(layer "F.Cu")
	)
	(gr_line
		(start 364.981236 -52.112672)
		(end 364.992158 -52.105306)
		(stroke
			(width 0.05715)
			(type default)
		)
		(layer "F.Cu")
	)
	(gr_line
		(start 364.983776 -12.674854)
		(end 364.989364 -12.661392)
		(stroke
			(width 0.05715)
			(type default)
		)
		(layer "F.Cu")
	)
	(gr_line
		(start 364.98784 -127.42164)
		(end 365.0742 -127.508)
		(stroke
			(width 0.04445)
			(type default)
		)
		(layer "F.Cu")
	)
	(gr_line
		(start 364.992158 -52.105306)
		(end 364.99927 -52.094638)
		(stroke
			(width 0.05715)
			(type default)
		)
		(layer "F.Cu")
	)
	(gr_line
		(start 364.999778 -119.058944)
		(end 365.06785 -119.160798)
		(stroke
			(width 0.04445)
			(type default)
		)
		(layer "F.Cu")
	)
	(gr_line
		(start 365.026448 -13.976604)
		(end 365.057944 -13.821918)
		(stroke
			(width 0.05715)
			(type default)
		)
		(layer "F.Cu")
	)
	(gr_line
		(start 365.057944 -13.821918)
		(end 365.343948 -13.632434)
		(stroke
			(width 0.05715)
			(type default)
		)
		(layer "F.Cu")
	)
	(gr_line
		(start 365.064802 -118.875048)
		(end 365.4425 -118.95074)
		(stroke
			(width 0.04445)
			(type default)
		)
		(layer "F.Cu")
	)
	(gr_line
		(start 365.06785 -119.160798)
		(end 365.32947 -119.213122)
		(stroke
			(width 0.04445)
			(type default)
		)
		(layer "F.Cu")
	)
	(gr_line
		(start 365.0742 -127.508)
		(end 365.3409 -127.508)
		(stroke
			(width 0.04445)
			(type default)
		)
		(layer "F.Cu")
	)
	(gr_line
		(start 365.11484 -123.48464)
		(end 365.2012 -123.571)
		(stroke
			(width 0.04445)
			(type default)
		)
		(layer "F.Cu")
	)
	(gr_line
		(start 365.154718 -120.36552)
		(end 365.256318 -120.297702)
		(stroke
			(width 0.04445)
			(type default)
		)
		(layer "F.Cu")
	)
	(gr_line
		(start 365.161068 -12.247118)
		(end 365.165894 -12.23518)
		(stroke
			(width 0.05715)
			(type default)
		)
		(layer "F.Cu")
	)
	(gr_line
		(start 365.17834 -127.2286)
		(end 365.23676 -127.2286)
		(stroke
			(width 0.04445)
			(type default)
		)
		(layer "F.Cu")
	)
	(gr_line
		(start 365.187992 -14.162278)
		(end 365.6076 -13.884656)
		(stroke
			(width 0.05715)
			(type default)
		)
		(layer "F.Cu")
	)
	(gr_line
		(start 365.2012 -123.571)
		(end 365.4679 -123.571)
		(stroke
			(width 0.04445)
			(type default)
		)
		(layer "F.Cu")
	)
	(gr_line
		(start 365.20628 -126.38024)
		(end 365.29264 -126.4666)
		(stroke
			(width 0.04445)
			(type default)
		)
		(layer "F.Cu")
	)
	(gr_line
		(start 365.21771 -11.188192)
		(end 365.489744 -10.916158)
		(stroke
			(width 0.05715)
			(type default)
		)
		(layer "F.Cu")
	)
	(gr_line
		(start 365.21771 -9.755124)
		(end 365.489744 -10.027158)
		(stroke
			(width 0.05715)
			(type default)
		)
		(layer "F.Cu")
	)
	(gr_line
		(start 365.257588 -8.825484)
		(end 365.485172 -8.5979)
		(stroke
			(width 0.05715)
			(type default)
		)
		(layer "F.Cu")
	)
	(gr_line
		(start 365.261906 -128.51384)
		(end 365.373666 -128.6256)
		(stroke
			(width 0.05715)
			(type default)
		)
		(layer "F.Cu")
	)
	(gr_line
		(start 365.266732 -19.808952)
		(end 365.270288 -19.826224)
		(stroke
			(width 0.05715)
			(type default)
		)
		(layer "F.Cu")
	)
	(gr_line
		(start 365.266732 -19.808952)
		(end 365.270542 -19.790918)
		(stroke
			(width 0.05715)
			(type default)
		)
		(layer "F.Cu")
	)
	(gr_line
		(start 365.271812 -16.54556)
		(end 365.285528 -16.519144)
		(stroke
			(width 0.05715)
			(type default)
		)
		(layer "F.Cu")
	)
	(gr_line
		(start 365.28502 -22.642322)
		(end 365.288576 -22.659594)
		(stroke
			(width 0.05715)
			(type default)
		)
		(layer "F.Cu")
	)
	(gr_line
		(start 365.28502 -22.642322)
		(end 365.28883 -22.624288)
		(stroke
			(width 0.05715)
			(type default)
		)
		(layer "F.Cu")
	)
	(gr_line
		(start 365.285528 -16.519144)
		(end 365.31042 -16.502634)
		(stroke
			(width 0.05715)
			(type default)
		)
		(layer "F.Cu")
	)
	(gr_line
		(start 365.29264 -126.4666)
		(end 365.55934 -126.4666)
		(stroke
			(width 0.04445)
			(type default)
		)
		(layer "F.Cu")
	)
	(gr_line
		(start 365.30534 -123.2916)
		(end 365.36376 -123.2916)
		(stroke
			(width 0.04445)
			(type default)
		)
		(layer "F.Cu")
	)
	(gr_line
		(start 365.32947 -119.213122)
		(end 365.431324 -119.145304)
		(stroke
			(width 0.04445)
			(type default)
		)
		(layer "F.Cu")
	)
	(gr_line
		(start 365.3409 -127.508)
		(end 365.42726 -127.42164)
		(stroke
			(width 0.04445)
			(type default)
		)
		(layer "F.Cu")
	)
	(gr_line
		(start 365.343948 -13.632434)
		(end 365.498888 -13.66393)
		(stroke
			(width 0.05715)
			(type default)
		)
		(layer "F.Cu")
	)
	(gr_line
		(start 365.373666 -128.6256)
		(end 365.716566 -128.6256)
		(stroke
			(width 0.05715)
			(type default)
		)
		(layer "F.Cu")
	)
	(gr_line
		(start 365.39678 -126.1872)
		(end 365.4552 -126.1872)
		(stroke
			(width 0.04445)
			(type default)
		)
		(layer "F.Cu")
	)
	(gr_line
		(start 365.4679 -123.571)
		(end 365.55426 -123.48464)
		(stroke
			(width 0.04445)
			(type default)
		)
		(layer "F.Cu")
	)
	(gr_line
		(start 365.485172 -7.789926)
		(end 365.485172 -8.5979)
		(stroke
			(width 0.05715)
			(type default)
		)
		(layer "F.Cu")
	)
	(gr_line
		(start 365.503206 -128.27)
		(end 365.587026 -128.27)
		(stroke
			(width 0.05715)
			(type default)
		)
		(layer "F.Cu")
	)
	(gr_line
		(start 365.506 -115.189)
		(end 366.032034 -114.662966)
		(stroke
			(width 0.05715)
			(type default)
		)
		(layer "F.Cu")
	)
	(gr_line
		(start 365.506 -113.792)
		(end 366.032034 -114.318034)
		(stroke
			(width 0.05715)
			(type default)
		)
		(layer "F.Cu")
	)
	(gr_line
		(start 365.506 -112.395)
		(end 366.032034 -111.868966)
		(stroke
			(width 0.05715)
			(type default)
		)
		(layer "F.Cu")
	)
	(gr_line
		(start 365.506 -110.998)
		(end 366.032034 -111.524034)
		(stroke
			(width 0.05715)
			(type default)
		)
		(layer "F.Cu")
	)
	(gr_line
		(start 365.512858 -49.103788)
		(end 365.521494 -49.090834)
		(stroke
			(width 0.05715)
			(type default)
		)
		(layer "F.Cu")
	)
	(gr_line
		(start 365.521494 -49.090834)
		(end 365.534448 -49.082198)
		(stroke
			(width 0.05715)
			(type default)
		)
		(layer "F.Cu")
	)
	(gr_line
		(start 365.52251 -120.350788)
		(end 365.590582 -120.452642)
		(stroke
			(width 0.04445)
			(type default)
		)
		(layer "F.Cu")
	)
	(gr_line
		(start 365.55934 -126.4666)
		(end 365.6457 -126.38024)
		(stroke
			(width 0.04445)
			(type default)
		)
		(layer "F.Cu")
	)
	(gr_line
		(start 365.587026 -120.166638)
		(end 365.964724 -120.24233)
		(stroke
			(width 0.04445)
			(type default)
		)
		(layer "F.Cu")
	)
	(gr_line
		(start 365.590582 -120.452642)
		(end 365.852202 -120.504966)
		(stroke
			(width 0.04445)
			(type default)
		)
		(layer "F.Cu")
	)
	(gr_line
		(start 365.671354 -104.766364)
		(end 365.90605 -104.531668)
		(stroke
			(width 0.05715)
			(type default)
		)
		(layer "F.Cu")
	)
	(gr_line
		(start 365.697262 -119.19839)
		(end 365.765334 -119.300244)
		(stroke
			(width 0.04445)
			(type default)
		)
		(layer "F.Cu")
	)
	(gr_line
		(start 365.69904 -127.42164)
		(end 365.7854 -127.508)
		(stroke
			(width 0.04445)
			(type default)
		)
		(layer "F.Cu")
	)
	(gr_line
		(start 365.712502 -103.993188)
		(end 365.90605 -104.186736)
		(stroke
			(width 0.05715)
			(type default)
		)
		(layer "F.Cu")
	)
	(gr_line
		(start 365.716566 -128.6256)
		(end 365.828326 -128.51384)
		(stroke
			(width 0.05715)
			(type default)
		)
		(layer "F.Cu")
	)
	(gr_line
		(start 365.747808 -53.819298)
		(end 365.75873 -53.811932)
		(stroke
			(width 0.05715)
			(type default)
		)
		(layer "F.Cu")
	)
	(gr_line
		(start 365.75873 -53.811932)
		(end 365.765842 -53.801264)
		(stroke
			(width 0.05715)
			(type default)
		)
		(layer "F.Cu")
	)
	(gr_line
		(start 365.761778 -119.014494)
		(end 366.138968 -119.090186)
		(stroke
			(width 0.04445)
			(type default)
		)
		(layer "F.Cu")
	)
	(gr_line
		(start 365.765334 -119.300244)
		(end 366.026954 -119.352568)
		(stroke
			(width 0.04445)
			(type default)
		)
		(layer "F.Cu")
	)
	(gr_line
		(start 365.78286 -118.011956)
		(end 365.86922 -118.098316)
		(stroke
			(width 0.04445)
			(type default)
		)
		(layer "F.Cu")
	)
	(gr_line
		(start 365.7854 -127.508)
		(end 366.0521 -127.508)
		(stroke
			(width 0.04445)
			(type default)
		)
		(layer "F.Cu")
	)
	(gr_line
		(start 365.788956 -13.47216)
		(end 365.820452 -13.31722)
		(stroke
			(width 0.05715)
			(type default)
		)
		(layer "F.Cu")
	)
	(gr_line
		(start 365.8108 -116.79047)
		(end 365.833152 -116.79047)
		(stroke
			(width 0.04445)
			(type default)
		)
		(layer "F.Cu")
	)
	(gr_line
		(start 365.8108 -116.54917)
		(end 365.832898 -116.54917)
		(stroke
			(width 0.04445)
			(type default)
		)
		(layer "F.Cu")
	)
	(gr_line
		(start 365.819944 -21.249894)
		(end 365.820198 -21.250656)
		(stroke
			(width 0.05715)
			(type default)
		)
		(layer "F.Cu")
	)
	(gr_line
		(start 365.820198 -21.2852)
		(end 365.823754 -21.267928)
		(stroke
			(width 0.05715)
			(type default)
		)
		(layer "F.Cu")
	)
	(gr_line
		(start 365.820198 -21.25091)
		(end 365.823754 -21.267928)
		(stroke
			(width 0.05715)
			(type default)
		)
		(layer "F.Cu")
	)
	(gr_line
		(start 365.820452 -13.31722)
		(end 366.106456 -13.127736)
		(stroke
			(width 0.05715)
			(type default)
		)
		(layer "F.Cu")
	)
	(gr_line
		(start 365.82604 -123.48464)
		(end 365.9124 -123.571)
		(stroke
			(width 0.04445)
			(type default)
		)
		(layer "F.Cu")
	)
	(gr_line
		(start 365.832898 -116.54917)
		(end 365.858298 -116.57457)
		(stroke
			(width 0.04445)
			(type default)
		)
		(layer "F.Cu")
	)
	(gr_line
		(start 365.833152 -116.79047)
		(end 365.858552 -116.76507)
		(stroke
			(width 0.04445)
			(type default)
		)
		(layer "F.Cu")
	)
	(gr_line
		(start 365.852202 -120.504966)
		(end 365.953802 -120.436894)
		(stroke
			(width 0.04445)
			(type default)
		)
		(layer "F.Cu")
	)
	(gr_line
		(start 365.86922 -118.098316)
		(end 366.13592 -118.098316)
		(stroke
			(width 0.04445)
			(type default)
		)
		(layer "F.Cu")
	)
	(gr_line
		(start 365.88954 -127.2286)
		(end 365.94796 -127.2286)
		(stroke
			(width 0.04445)
			(type default)
		)
		(layer "F.Cu")
	)
	(gr_line
		(start 365.905288 -24.46147)
		(end 365.912908 -24.43607)
		(stroke
			(width 0.05715)
			(type default)
		)
		(layer "F.Cu")
	)
	(gr_line
		(start 365.90732 -24.408892)
		(end 365.912908 -24.43607)
		(stroke
			(width 0.05715)
			(type default)
		)
		(layer "F.Cu")
	)
	(gr_line
		(start 365.9124 -123.571)
		(end 366.1791 -123.571)
		(stroke
			(width 0.04445)
			(type default)
		)
		(layer "F.Cu")
	)
	(gr_line
		(start 365.91748 -126.38024)
		(end 366.00384 -126.4666)
		(stroke
			(width 0.04445)
			(type default)
		)
		(layer "F.Cu")
	)
	(gr_line
		(start 365.949738 -13.658088)
		(end 366.369092 -13.380212)
		(stroke
			(width 0.05715)
			(type default)
		)
		(layer "F.Cu")
	)
	(gr_line
		(start 365.97336 -117.818916)
		(end 366.03178 -117.818916)
		(stroke
			(width 0.04445)
			(type default)
		)
		(layer "F.Cu")
	)
	(gr_line
		(start 365.985552 -17.30883)
		(end 365.99876 -17.28343)
		(stroke
			(width 0.05715)
			(type default)
		)
		(layer "F.Cu")
	)
	(gr_line
		(start 365.99876 -17.28343)
		(end 366.022382 -17.267936)
		(stroke
			(width 0.05715)
			(type default)
		)
		(layer "F.Cu")
	)
	(gr_line
		(start 366.00384 -126.4666)
		(end 366.27054 -126.4666)
		(stroke
			(width 0.04445)
			(type default)
		)
		(layer "F.Cu")
	)
	(gr_line
		(start 366.01654 -123.2916)
		(end 366.07496 -123.2916)
		(stroke
			(width 0.04445)
			(type default)
		)
		(layer "F.Cu")
	)
	(gr_line
		(start 366.026954 -119.352568)
		(end 366.128554 -119.28475)
		(stroke
			(width 0.04445)
			(type default)
		)
		(layer "F.Cu")
	)
	(gr_line
		(start 366.0521 -127.508)
		(end 366.13846 -127.42164)
		(stroke
			(width 0.04445)
			(type default)
		)
		(layer "F.Cu")
	)
	(gr_line
		(start 366.10036 -2.937002)
		(end 366.44834 -2.937002)
		(stroke
			(width 0.05715)
			(type default)
		)
		(layer "F.Cu")
	)
	(gr_line
		(start 366.106456 -13.127736)
		(end 366.261396 -13.159232)
		(stroke
			(width 0.05715)
			(type default)
		)
		(layer "F.Cu")
	)
	(gr_line
		(start 366.10798 -126.1872)
		(end 366.1664 -126.1872)
		(stroke
			(width 0.04445)
			(type default)
		)
		(layer "F.Cu")
	)
	(gr_line
		(start 366.13592 -118.098316)
		(end 366.22228 -118.011956)
		(stroke
			(width 0.04445)
			(type default)
		)
		(layer "F.Cu")
	)
	(gr_line
		(start 366.1791 -123.571)
		(end 366.26546 -123.48464)
		(stroke
			(width 0.04445)
			(type default)
		)
		(layer "F.Cu")
	)
	(gr_line
		(start 366.212628 -47.459138)
		(end 366.223804 -47.451772)
		(stroke
			(width 0.05715)
			(type default)
		)
		(layer "F.Cu")
	)
	(gr_line
		(start 366.223804 -47.451772)
		(end 366.23625 -47.449486)
		(stroke
			(width 0.05715)
			(type default)
		)
		(layer "F.Cu")
	)
	(gr_line
		(start 366.23752 -49.802542)
		(end 366.246156 -49.789588)
		(stroke
			(width 0.05715)
			(type default)
		)
		(layer "F.Cu")
	)
	(gr_line
		(start 366.246156 -49.789588)
		(end 366.25911 -49.780952)
		(stroke
			(width 0.05715)
			(type default)
		)
		(layer "F.Cu")
	)
	(gr_line
		(start 366.27054 -126.4666)
		(end 366.3569 -126.38024)
		(stroke
			(width 0.04445)
			(type default)
		)
		(layer "F.Cu")
	)
	(gr_line
		(start 366.285018 -3.7084)
		(end 366.285018 -4.389882)
		(stroke
			(width 0.05715)
			(type default)
		)
		(layer "F.Cu")
	)
	(gr_line
		(start 366.285018 -3.7084)
		(end 366.504982 -3.488436)
		(stroke
			(width 0.05715)
			(type default)
		)
		(layer "F.Cu")
	)
	(gr_line
		(start 366.369346 -120.323102)
		(end 366.376966 -120.324626)
		(stroke
			(width 0.04445)
			(type default)
		)
		(layer "F.Cu")
	)
	(gr_line
		(start 366.376966 -120.324626)
		(end 366.383062 -120.32869)
		(stroke
			(width 0.04445)
			(type default)
		)
		(layer "F.Cu")
	)
	(gr_line
		(start 366.41024 -127.42164)
		(end 366.4966 -127.508)
		(stroke
			(width 0.04445)
			(type default)
		)
		(layer "F.Cu")
	)
	(gr_line
		(start 366.44834 -2.937002)
		(end 366.523016 -3.011678)
		(stroke
			(width 0.05715)
			(type default)
		)
		(layer "F.Cu")
	)
	(gr_line
		(start 366.45977 -119.154194)
		(end 366.46739 -119.155718)
		(stroke
			(width 0.04445)
			(type default)
		)
		(layer "F.Cu")
	)
	(gr_line
		(start 366.46739 -119.155718)
		(end 366.473486 -119.159782)
		(stroke
			(width 0.04445)
			(type default)
		)
		(layer "F.Cu")
	)
	(gr_line
		(start 366.4966 -127.508)
		(end 366.7633 -127.508)
		(stroke
			(width 0.04445)
			(type default)
		)
		(layer "F.Cu")
	)
	(gr_line
		(start 366.60074 -127.2286)
		(end 366.65916 -127.2286)
		(stroke
			(width 0.04445)
			(type default)
		)
		(layer "F.Cu")
	)
	(gr_line
		(start 366.609884 -48.365156)
		(end 366.62106 -48.35779)
		(stroke
			(width 0.05715)
			(type default)
		)
		(layer "F.Cu")
	)
	(gr_line
		(start 366.62106 -48.35779)
		(end 366.633506 -48.355504)
		(stroke
			(width 0.05715)
			(type default)
		)
		(layer "F.Cu")
	)
	(gr_line
		(start 366.64519 -119.506238)
		(end 366.669066 -119.626126)
		(stroke
			(width 0.04445)
			(type default)
		)
		(layer "F.Cu")
	)
	(gr_line
		(start 366.669066 -119.626126)
		(end 366.891062 -119.774208)
		(stroke
			(width 0.04445)
			(type default)
		)
		(layer "F.Cu")
	)
	(gr_line
		(start 366.680242 -118.323868)
		(end 366.868964 -118.51259)
		(stroke
			(width 0.04445)
			(type default)
		)
		(layer "F.Cu")
	)
	(gr_line
		(start 366.680242 -118.201694)
		(end 366.680242 -118.323868)
		(stroke
			(width 0.04445)
			(type default)
		)
		(layer "F.Cu")
	)
	(gr_line
		(start 366.7633 -127.508)
		(end 366.84966 -127.42164)
		(stroke
			(width 0.04445)
			(type default)
		)
		(layer "F.Cu")
	)
	(gr_line
		(start 366.773206 -117.33403)
		(end 366.961928 -117.522752)
		(stroke
			(width 0.04445)
			(type default)
		)
		(layer "F.Cu")
	)
	(gr_line
		(start 366.773206 -117.211856)
		(end 366.773206 -117.33403)
		(stroke
			(width 0.04445)
			(type default)
		)
		(layer "F.Cu")
	)
	(gr_line
		(start 366.774984 -119.360696)
		(end 367.095532 -119.574564)
		(stroke
			(width 0.04445)
			(type default)
		)
		(layer "F.Cu")
	)
	(gr_line
		(start 366.795558 -122.951748)
		(end 366.83696 -122.910346)
		(stroke
			(width 0.04445)
			(type default)
		)
		(layer "F.Cu")
	)
	(gr_line
		(start 366.797336 -123.22302)
		(end 366.91951 -123.22302)
		(stroke
			(width 0.04445)
			(type default)
		)
		(layer "F.Cu")
	)
	(gr_line
		(start 366.849914 -3.488436)
		(end 367.085118 -3.72364)
		(stroke
			(width 0.05715)
			(type default)
		)
		(layer "F.Cu")
	)
	(gr_line
		(start 366.867948 -3.011678)
		(end 366.942624 -2.937002)
		(stroke
			(width 0.05715)
			(type default)
		)
		(layer "F.Cu")
	)
	(gr_line
		(start 366.868964 -118.51259)
		(end 366.991138 -118.51259)
		(stroke
			(width 0.04445)
			(type default)
		)
		(layer "F.Cu")
	)
	(gr_line
		(start 366.891062 -119.774208)
		(end 367.011204 -119.750078)
		(stroke
			(width 0.04445)
			(type default)
		)
		(layer "F.Cu")
	)
	(gr_line
		(start 366.91951 -123.22302)
		(end 367.108232 -123.034298)
		(stroke
			(width 0.04445)
			(type default)
		)
		(layer "F.Cu")
	)
	(gr_line
		(start 366.942624 -2.937002)
		(end 367.37036 -2.937002)
		(stroke
			(width 0.05715)
			(type default)
		)
		(layer "F.Cu")
	)
	(gr_line
		(start 366.951514 -118.199916)
		(end 366.992916 -118.241318)
		(stroke
			(width 0.04445)
			(type default)
		)
		(layer "F.Cu")
	)
	(gr_line
		(start 366.957864 -120.943878)
		(end 366.98174 -121.063766)
		(stroke
			(width 0.04445)
			(type default)
		)
		(layer "F.Cu")
	)
	(gr_line
		(start 366.959134 -49.3141)
		(end 366.97031 -49.306734)
		(stroke
			(width 0.05715)
			(type default)
		)
		(layer "F.Cu")
	)
	(gr_line
		(start 366.961928 -117.522752)
		(end 367.084102 -117.522752)
		(stroke
			(width 0.04445)
			(type default)
		)
		(layer "F.Cu")
	)
	(gr_line
		(start 366.97031 -49.306734)
		(end 366.982756 -49.304448)
		(stroke
			(width 0.05715)
			(type default)
		)
		(layer "F.Cu")
	)
	(gr_line
		(start 366.98174 -121.063766)
		(end 367.203736 -121.211848)
		(stroke
			(width 0.04445)
			(type default)
		)
		(layer "F.Cu")
	)
	(gr_line
		(start 366.982502 -128.5113)
		(end 367.0046 -128.5113)
		(stroke
			(width 0.04445)
			(type default)
		)
		(layer "F.Cu")
	)
	(gr_line
		(start 366.982502 -128.27)
		(end 367.0046 -128.27)
		(stroke
			(width 0.04445)
			(type default)
		)
		(layer "F.Cu")
	)
	(gr_line
		(start 367.0046 -128.5113)
		(end 367.03 -128.4859)
		(stroke
			(width 0.04445)
			(type default)
		)
		(layer "F.Cu")
	)
	(gr_line
		(start 367.0046 -128.27)
		(end 367.03 -128.2954)
		(stroke
			(width 0.04445)
			(type default)
		)
		(layer "F.Cu")
	)
	(gr_line
		(start 367.044478 -117.210078)
		(end 367.08588 -117.25148)
		(stroke
			(width 0.04445)
			(type default)
		)
		(layer "F.Cu")
	)
	(gr_line
		(start 367.077244 -10.916158)
		(end 367.349278 -11.188192)
		(stroke
			(width 0.05715)
			(type default)
		)
		(layer "F.Cu")
	)
	(gr_line
		(start 367.077244 -10.027158)
		(end 367.349278 -9.755124)
		(stroke
			(width 0.05715)
			(type default)
		)
		(layer "F.Cu")
	)
	(gr_line
		(start 367.085118 -8.5979)
		(end 367.312702 -8.825484)
		(stroke
			(width 0.05715)
			(type default)
		)
		(layer "F.Cu")
	)
	(gr_line
		(start 367.085118 -7.789926)
		(end 367.085118 -8.5979)
		(stroke
			(width 0.05715)
			(type default)
		)
		(layer "F.Cu")
	)
	(gr_line
		(start 367.085118 -3.72364)
		(end 367.085118 -4.389882)
		(stroke
			(width 0.05715)
			(type default)
		)
		(layer "F.Cu")
	)
	(gr_line
		(start 367.087912 -120.79859)
		(end 367.407952 -121.01195)
		(stroke
			(width 0.04445)
			(type default)
		)
		(layer "F.Cu")
	)
	(gr_line
		(start 367.108232 -122.912124)
		(end 367.108232 -123.034298)
		(stroke
			(width 0.04445)
			(type default)
		)
		(layer "F.Cu")
	)
	(gr_line
		(start 367.183162 -118.826788)
		(end 367.371884 -119.01551)
		(stroke
			(width 0.04445)
			(type default)
		)
		(layer "F.Cu")
	)
	(gr_line
		(start 367.183162 -118.704614)
		(end 367.183162 -118.826788)
		(stroke
			(width 0.04445)
			(type default)
		)
		(layer "F.Cu")
	)
	(gr_line
		(start 367.203736 -121.211848)
		(end 367.323624 -121.187972)
		(stroke
			(width 0.04445)
			(type default)
		)
		(layer "F.Cu")
	)
	(gr_line
		(start 367.23701 -119.9007)
		(end 367.260886 -120.020588)
		(stroke
			(width 0.04445)
			(type default)
		)
		(layer "F.Cu")
	)
	(gr_line
		(start 367.260886 -120.020588)
		(end 367.482882 -120.16867)
		(stroke
			(width 0.04445)
			(type default)
		)
		(layer "F.Cu")
	)
	(gr_line
		(start 367.276126 -117.83695)
		(end 367.464848 -118.025672)
		(stroke
			(width 0.04445)
			(type default)
		)
		(layer "F.Cu")
	)
	(gr_line
		(start 367.276126 -117.714776)
		(end 367.276126 -117.83695)
		(stroke
			(width 0.04445)
			(type default)
		)
		(layer "F.Cu")
	)
	(gr_line
		(start 367.278158 -125.034548)
		(end 367.31956 -124.993146)
		(stroke
			(width 0.04445)
			(type default)
		)
		(layer "F.Cu")
	)
	(gr_line
		(start 367.279936 -125.30582)
		(end 367.40211 -125.30582)
		(stroke
			(width 0.04445)
			(type default)
		)
		(layer "F.Cu")
	)
	(gr_line
		(start 367.305844 -12.760706)
		(end 367.337594 -12.739624)
		(stroke
			(width 0.05715)
			(type default)
		)
		(layer "F.Cu")
	)
	(gr_line
		(start 367.337594 -12.739624)
		(end 367.353088 -12.704826)
		(stroke
			(width 0.05715)
			(type default)
		)
		(layer "F.Cu")
	)
	(gr_line
		(start 367.353342 -13.801852)
		(end 367.384838 -13.646912)
		(stroke
			(width 0.05715)
			(type default)
		)
		(layer "F.Cu")
	)
	(gr_line
		(start 367.367312 -119.755666)
		(end 367.687098 -119.968772)
		(stroke
			(width 0.04445)
			(type default)
		)
		(layer "F.Cu")
	)
	(gr_line
		(start 367.371884 -119.01551)
		(end 367.494058 -119.01551)
		(stroke
			(width 0.04445)
			(type default)
		)
		(layer "F.Cu")
	)
	(gr_line
		(start 367.384838 -13.646912)
		(end 367.670842 -13.457428)
		(stroke
			(width 0.05715)
			(type default)
		)
		(layer "F.Cu")
	)
	(gr_line
		(start 367.40211 -125.30582)
		(end 367.590832 -125.117098)
		(stroke
			(width 0.04445)
			(type default)
		)
		(layer "F.Cu")
	)
	(gr_line
		(start 367.406428 -50.904394)
		(end 367.415064 -50.89144)
		(stroke
			(width 0.05715)
			(type default)
		)
		(layer "F.Cu")
	)
	(gr_line
		(start 367.415064 -50.89144)
		(end 367.428018 -50.882804)
		(stroke
			(width 0.05715)
			(type default)
		)
		(layer "F.Cu")
	)
	(gr_line
		(start 367.454434 -118.702836)
		(end 367.495836 -118.744238)
		(stroke
			(width 0.04445)
			(type default)
		)
		(layer "F.Cu")
	)
	(gr_line
		(start 367.464848 -118.025672)
		(end 367.587022 -118.025672)
		(stroke
			(width 0.04445)
			(type default)
		)
		(layer "F.Cu")
	)
	(gr_line
		(start 367.482882 -120.16867)
		(end 367.603024 -120.14454)
		(stroke
			(width 0.04445)
			(type default)
		)
		(layer "F.Cu")
	)
	(gr_line
		(start 367.51387 -13.988034)
		(end 367.934494 -13.70965)
		(stroke
			(width 0.05715)
			(type default)
		)
		(layer "F.Cu")
	)
	(gr_line
		(start 367.547398 -117.712998)
		(end 367.5888 -117.7544)
		(stroke
			(width 0.04445)
			(type default)
		)
		(layer "F.Cu")
	)
	(gr_line
		(start 367.549684 -121.33834)
		(end 367.57356 -121.458228)
		(stroke
			(width 0.04445)
			(type default)
		)
		(layer "F.Cu")
	)
	(gr_line
		(start 367.57356 -121.458228)
		(end 367.795556 -121.60631)
		(stroke
			(width 0.04445)
			(type default)
		)
		(layer "F.Cu")
	)
	(gr_line
		(start 367.590832 -124.994924)
		(end 367.590832 -125.117098)
		(stroke
			(width 0.04445)
			(type default)
		)
		(layer "F.Cu")
	)
	(gr_line
		(start 367.633758 -126.634748)
		(end 367.67516 -126.593346)
		(stroke
			(width 0.04445)
			(type default)
		)
		(layer "F.Cu")
	)
	(gr_line
		(start 367.635536 -126.90602)
		(end 367.75771 -126.90602)
		(stroke
			(width 0.04445)
			(type default)
		)
		(layer "F.Cu")
	)
	(gr_line
		(start 367.636044 -12.062206)
		(end 367.642394 -12.047728)
		(stroke
			(width 0.05715)
			(type default)
		)
		(layer "F.Cu")
	)
	(gr_line
		(start 367.657634 -8.825484)
		(end 367.885218 -8.5979)
		(stroke
			(width 0.05715)
			(type default)
		)
		(layer "F.Cu")
	)
	(gr_line
		(start 367.665 -113.792)
		(end 368.554 -113.792)
		(stroke
			(width 0.05715)
			(type default)
		)
		(layer "F.Cu")
	)
	(gr_line
		(start 367.667032 -122.72264)
		(end 367.753392 -122.809)
		(stroke
			(width 0.04445)
			(type default)
		)
		(layer "F.Cu")
	)
	(gr_line
		(start 367.670842 -13.457428)
		(end 367.825782 -13.488924)
		(stroke
			(width 0.05715)
			(type default)
		)
		(layer "F.Cu")
	)
	(gr_line
		(start 367.679986 -121.193306)
		(end 367.999264 -121.406158)
		(stroke
			(width 0.04445)
			(type default)
		)
		(layer "F.Cu")
	)
	(gr_line
		(start 367.686082 -119.329708)
		(end 367.874804 -119.51843)
		(stroke
			(width 0.04445)
			(type default)
		)
		(layer "F.Cu")
	)
	(gr_line
		(start 367.686082 -119.207534)
		(end 367.686082 -119.329708)
		(stroke
			(width 0.04445)
			(type default)
		)
		(layer "F.Cu")
	)
	(gr_line
		(start 367.69421 -11.188192)
		(end 367.966244 -10.916158)
		(stroke
			(width 0.05715)
			(type default)
		)
		(layer "F.Cu")
	)
	(gr_line
		(start 367.69421 -9.755124)
		(end 367.966244 -10.027158)
		(stroke
			(width 0.05715)
			(type default)
		)
		(layer "F.Cu")
	)
	(gr_line
		(start 367.7158 -112.395)
		(end 368.554 -112.395)
		(stroke
			(width 0.05715)
			(type default)
		)
		(layer "F.Cu")
	)
	(gr_line
		(start 367.753392 -122.809)
		(end 368.020092 -122.809)
		(stroke
			(width 0.04445)
			(type default)
		)
		(layer "F.Cu")
	)
	(gr_line
		(start 367.75771 -126.90602)
		(end 367.946432 -126.717298)
		(stroke
			(width 0.04445)
			(type default)
		)
		(layer "F.Cu")
	)
	(gr_line
		(start 367.779046 -118.33987)
		(end 367.967768 -118.528592)
		(stroke
			(width 0.04445)
			(type default)
		)
		(layer "F.Cu")
	)
	(gr_line
		(start 367.779046 -118.217696)
		(end 367.779046 -118.33987)
		(stroke
			(width 0.04445)
			(type default)
		)
		(layer "F.Cu")
	)
	(gr_line
		(start 367.792 -110.998)
		(end 368.554 -110.998)
		(stroke
			(width 0.05715)
			(type default)
		)
		(layer "F.Cu")
	)
	(gr_line
		(start 367.792 -109.601)
		(end 368.554 -109.601)
		(stroke
			(width 0.05715)
			(type default)
		)
		(layer "F.Cu")
	)
	(gr_line
		(start 367.795556 -121.60631)
		(end 367.915444 -121.582434)
		(stroke
			(width 0.04445)
			(type default)
		)
		(layer "F.Cu")
	)
	(gr_line
		(start 367.82883 -120.295162)
		(end 367.852706 -120.41505)
		(stroke
			(width 0.04445)
			(type default)
		)
		(layer "F.Cu")
	)
	(gr_line
		(start 367.852706 -120.41505)
		(end 368.074702 -120.563132)
		(stroke
			(width 0.04445)
			(type default)
		)
		(layer "F.Cu")
	)
	(gr_line
		(start 367.857532 -122.5296)
		(end 367.915952 -122.5296)
		(stroke
			(width 0.04445)
			(type default)
		)
		(layer "F.Cu")
	)
	(gr_line
		(start 367.866676 -50.591212)
		(end 367.87709 -50.5841)
		(stroke
			(width 0.05715)
			(type default)
		)
		(layer "F.Cu")
	)
	(gr_line
		(start 367.874804 -119.51843)
		(end 367.996978 -119.51843)
		(stroke
			(width 0.04445)
			(type default)
		)
		(layer "F.Cu")
	)
	(gr_line
		(start 367.87709 -50.5841)
		(end 367.889536 -50.58156)
		(stroke
			(width 0.05715)
			(type default)
		)
		(layer "F.Cu")
	)
	(gr_line
		(start 367.885218 -7.789926)
		(end 367.885218 -8.5979)
		(stroke
			(width 0.05715)
			(type default)
		)
		(layer "F.Cu")
	)
	(gr_line
		(start 367.946432 -126.595124)
		(end 367.946432 -126.717298)
		(stroke
			(width 0.04445)
			(type default)
		)
		(layer "F.Cu")
	)
	(gr_line
		(start 367.957354 -119.205756)
		(end 367.998756 -119.247158)
		(stroke
			(width 0.04445)
			(type default)
		)
		(layer "F.Cu")
	)
	(gr_line
		(start 367.959132 -120.150128)
		(end 368.278918 -120.363234)
		(stroke
			(width 0.04445)
			(type default)
		)
		(layer "F.Cu")
	)
	(gr_line
		(start 367.967768 -118.528592)
		(end 368.089942 -118.528592)
		(stroke
			(width 0.04445)
			(type default)
		)
		(layer "F.Cu")
	)
	(gr_line
		(start 367.978944 -49.105058)
		(end 367.999518 -49.100994)
		(stroke
			(width 0.05715)
			(type default)
		)
		(layer "F.Cu")
	)
	(gr_line
		(start 367.98758 -127.779526)
		(end 368.028982 -127.738124)
		(stroke
			(width 0.04445)
			(type default)
		)
		(layer "F.Cu")
	)
	(gr_line
		(start 367.989358 -128.050798)
		(end 368.111532 -128.050798)
		(stroke
			(width 0.04445)
			(type default)
		)
		(layer "F.Cu")
	)
	(gr_line
		(start 367.999518 -49.100994)
		(end 368.020346 -49.106328)
		(stroke
			(width 0.05715)
			(type default)
		)
		(layer "F.Cu")
	)
	(gr_line
		(start 368.020092 -122.809)
		(end 368.106452 -122.72264)
		(stroke
			(width 0.04445)
			(type default)
		)
		(layer "F.Cu")
	)
	(gr_line
		(start 368.050318 -118.215918)
		(end 368.09172 -118.25732)
		(stroke
			(width 0.04445)
			(type default)
		)
		(layer "F.Cu")
	)
	(gr_line
		(start 368.054128 -111.79175)
		(end 368.076226 -111.79175)
		(stroke
			(width 0.04445)
			(type default)
		)
		(layer "F.Cu")
	)
	(gr_line
		(start 368.054128 -111.55045)
		(end 368.076226 -111.55045)
		(stroke
			(width 0.04445)
			(type default)
		)
		(layer "F.Cu")
	)
	(gr_line
		(start 368.074702 -120.563132)
		(end 368.194844 -120.539002)
		(stroke
			(width 0.04445)
			(type default)
		)
		(layer "F.Cu")
	)
	(gr_line
		(start 368.076226 -111.79175)
		(end 368.101626 -111.76635)
		(stroke
			(width 0.04445)
			(type default)
		)
		(layer "F.Cu")
	)
	(gr_line
		(start 368.076226 -111.55045)
		(end 368.101626 -111.57585)
		(stroke
			(width 0.04445)
			(type default)
		)
		(layer "F.Cu")
	)
	(gr_line
		(start 368.111532 -128.050798)
		(end 368.300254 -127.862076)
		(stroke
			(width 0.04445)
			(type default)
		)
		(layer "F.Cu")
	)
	(gr_line
		(start 368.11585 -13.297154)
		(end 368.147346 -13.142214)
		(stroke
			(width 0.05715)
			(type default)
		)
		(layer "F.Cu")
	)
	(gr_line
		(start 368.118644 -121.714768)
		(end 368.140742 -121.7295)
		(stroke
			(width 0.04445)
			(type default)
		)
		(layer "F.Cu")
	)
	(gr_line
		(start 368.127534 -124.80544)
		(end 368.213894 -124.8918)
		(stroke
			(width 0.04445)
			(type default)
		)
		(layer "F.Cu")
	)
	(gr_line
		(start 368.133884 -114.61115)
		(end 368.155982 -114.61115)
		(stroke
			(width 0.04445)
			(type default)
		)
		(layer "F.Cu")
	)
	(gr_line
		(start 368.133884 -114.36985)
		(end 368.155982 -114.36985)
		(stroke
			(width 0.04445)
			(type default)
		)
		(layer "F.Cu")
	)
	(gr_line
		(start 368.147346 -13.142214)
		(end 368.43335 -12.95273)
		(stroke
			(width 0.05715)
			(type default)
		)
		(layer "F.Cu")
	)
	(gr_line
		(start 368.155982 -114.61115)
		(end 368.181382 -114.58575)
		(stroke
			(width 0.04445)
			(type default)
		)
		(layer "F.Cu")
	)
	(gr_line
		(start 368.155982 -114.36985)
		(end 368.181382 -114.39525)
		(stroke
			(width 0.04445)
			(type default)
		)
		(layer "F.Cu")
	)
	(gr_line
		(start 368.189002 -119.832628)
		(end 368.377724 -120.02135)
		(stroke
			(width 0.04445)
			(type default)
		)
		(layer "F.Cu")
	)
	(gr_line
		(start 368.189002 -119.710454)
		(end 368.189002 -119.832628)
		(stroke
			(width 0.04445)
			(type default)
		)
		(layer "F.Cu")
	)
	(gr_line
		(start 368.213894 -124.8918)
		(end 368.480594 -124.8918)
		(stroke
			(width 0.04445)
			(type default)
		)
		(layer "F.Cu")
	)
	(gr_line
		(start 368.276378 -13.483336)
		(end 368.697002 -13.204952)
		(stroke
			(width 0.05715)
			(type default)
		)
		(layer "F.Cu")
	)
	(gr_line
		(start 368.278156 -111.76889)
		(end 368.376708 -111.867442)
		(stroke
			(width 0.04445)
			(type default)
		)
		(layer "F.Cu")
	)
	(gr_line
		(start 368.281966 -118.84279)
		(end 368.470688 -119.031512)
		(stroke
			(width 0.04445)
			(type default)
		)
		(layer "F.Cu")
	)
	(gr_line
		(start 368.281966 -118.720616)
		(end 368.281966 -118.84279)
		(stroke
			(width 0.04445)
			(type default)
		)
		(layer "F.Cu")
	)
	(gr_line
		(start 368.297714 -1.419606)
		(end 368.697764 -1.419606)
		(stroke
			(width 0.05715)
			(type default)
		)
		(layer "F.Cu")
	)
	(gr_line
		(start 368.300254 -127.739902)
		(end 368.300254 -127.862076)
		(stroke
			(width 0.04445)
			(type default)
		)
		(layer "F.Cu")
	)
	(gr_line
		(start 368.318034 -124.6124)
		(end 368.376454 -124.6124)
		(stroke
			(width 0.04445)
			(type default)
		)
		(layer "F.Cu")
	)
	(gr_line
		(start 368.320574 -46.291754)
		(end 368.33556 -46.288706)
		(stroke
			(width 0.05715)
			(type default)
		)
		(layer "F.Cu")
	)
	(gr_line
		(start 368.33556 -46.288706)
		(end 368.348006 -46.280324)
		(stroke
			(width 0.05715)
			(type default)
		)
		(layer "F.Cu")
	)
	(gr_line
		(start 368.376708 -111.867442)
		(end 368.554508 -111.867442)
		(stroke
			(width 0.04445)
			(type default)
		)
		(layer "F.Cu")
	)
	(gr_line
		(start 368.377724 -120.02135)
		(end 368.499898 -120.02135)
		(stroke
			(width 0.04445)
			(type default)
		)
		(layer "F.Cu")
	)
	(gr_line
		(start 368.378232 -122.72264)
		(end 368.464592 -122.809)
		(stroke
			(width 0.04445)
			(type default)
		)
		(layer "F.Cu")
	)
	(gr_line
		(start 368.409982 -121.73204)
		(end 368.496342 -121.8184)
		(stroke
			(width 0.04445)
			(type default)
		)
		(layer "F.Cu")
	)
	(gr_line
		(start 368.43335 -12.95273)
		(end 368.58829 -12.984226)
		(stroke
			(width 0.05715)
			(type default)
		)
		(layer "F.Cu")
	)
	(gr_line
		(start 368.435382 -120.696736)
		(end 368.457988 -120.711722)
		(stroke
			(width 0.04445)
			(type default)
		)
		(layer "F.Cu")
	)
	(gr_line
		(start 368.460274 -119.708676)
		(end 368.501676 -119.750078)
		(stroke
			(width 0.04445)
			(type default)
		)
		(layer "F.Cu")
	)
	(gr_line
		(start 368.464592 -122.809)
		(end 368.731292 -122.809)
		(stroke
			(width 0.04445)
			(type default)
		)
		(layer "F.Cu")
	)
	(gr_line
		(start 368.470688 -119.031512)
		(end 368.592862 -119.031512)
		(stroke
			(width 0.04445)
			(type default)
		)
		(layer "F.Cu")
	)
	(gr_line
		(start 368.480594 -124.8918)
		(end 368.566954 -124.80544)
		(stroke
			(width 0.04445)
			(type default)
		)
		(layer "F.Cu")
	)
	(gr_line
		(start 368.4905 -127.276606)
		(end 368.531648 -127.235458)
		(stroke
			(width 0.04445)
			(type default)
		)
		(layer "F.Cu")
	)
	(gr_line
		(start 368.492278 -127.547878)
		(end 368.614452 -127.547878)
		(stroke
			(width 0.04445)
			(type default)
		)
		(layer "F.Cu")
	)
	(gr_line
		(start 368.496342 -121.8184)
		(end 368.763042 -121.8184)
		(stroke
			(width 0.04445)
			(type default)
		)
		(layer "F.Cu")
	)
	(gr_line
		(start 368.552984 -114.58829)
		(end 368.65179 -114.687096)
		(stroke
			(width 0.04445)
			(type default)
		)
		(layer "F.Cu")
	)
	(gr_line
		(start 368.553238 -118.718838)
		(end 368.59464 -118.76024)
		(stroke
			(width 0.04445)
			(type default)
		)
		(layer "F.Cu")
	)
	(gr_line
		(start 368.554508 -111.867442)
		(end 368.65306 -111.76889)
		(stroke
			(width 0.04445)
			(type default)
		)
		(layer "F.Cu")
	)
	(gr_line
		(start 368.568732 -122.5296)
		(end 368.627152 -122.5296)
		(stroke
			(width 0.04445)
			(type default)
		)
		(layer "F.Cu")
	)
	(gr_line
		(start 368.600482 -121.539)
		(end 368.658902 -121.539)
		(stroke
			(width 0.04445)
			(type default)
		)
		(layer "F.Cu")
	)
	(gr_line
		(start 368.606832 -104.740456)
		(end 368.609626 -104.740456)
		(stroke
			(width 0.05715)
			(type default)
		)
		(layer "F.Cu")
	)
	(gr_line
		(start 368.614452 -127.547878)
		(end 368.80292 -127.359156)
		(stroke
			(width 0.04445)
			(type default)
		)
		(layer "F.Cu")
	)
	(gr_line
		(start 368.62004 -126.35484)
		(end 368.7064 -126.4412)
		(stroke
			(width 0.04445)
			(type default)
		)
		(layer "F.Cu")
	)
	(gr_line
		(start 368.65179 -114.687096)
		(end 368.82959 -114.687096)
		(stroke
			(width 0.04445)
			(type default)
		)
		(layer "F.Cu")
	)
	(gr_line
		(start 368.685064 -3.753612)
		(end 368.685064 -4.389882)
		(stroke
			(width 0.05715)
			(type default)
		)
		(layer "F.Cu")
	)
	(gr_line
		(start 368.685064 -3.753612)
		(end 368.944144 -3.494532)
		(stroke
			(width 0.05715)
			(type default)
		)
		(layer "F.Cu")
	)
	(gr_line
		(start 368.689382 -134.078218)
		(end 368.812572 -134.078218)
		(stroke
			(width 0.0635)
			(type default)
		)
		(layer "F.Cu")
	)
	(gr_line
		(start 368.697764 -47.20336)
		(end 368.71275 -47.200312)
		(stroke
			(width 0.05715)
			(type default)
		)
		(layer "F.Cu")
	)
	(gr_line
		(start 368.697764 -1.419606)
		(end 368.760248 -1.48209)
		(stroke
			(width 0.05715)
			(type default)
		)
		(layer "F.Cu")
	)
	(gr_line
		(start 368.7064 -126.4412)
		(end 368.9731 -126.4412)
		(stroke
			(width 0.04445)
			(type default)
		)
		(layer "F.Cu")
	)
	(gr_line
		(start 368.71275 -47.200312)
		(end 368.725196 -47.19193)
		(stroke
			(width 0.05715)
			(type default)
		)
		(layer "F.Cu")
	)
	(gr_line
		(start 368.729006 -120.714262)
		(end 368.825526 -120.810782)
		(stroke
			(width 0.04445)
			(type default)
		)
		(layer "F.Cu")
	)
	(gr_line
		(start 368.731292 -122.809)
		(end 368.817652 -122.72264)
		(stroke
			(width 0.04445)
			(type default)
		)
		(layer "F.Cu")
	)
	(gr_line
		(start 368.763042 -121.8184)
		(end 368.849402 -121.73204)
		(stroke
			(width 0.04445)
			(type default)
		)
		(layer "F.Cu")
	)
	(gr_line
		(start 368.784886 -119.34571)
		(end 368.973608 -119.534432)
		(stroke
			(width 0.04445)
			(type default)
		)
		(layer "F.Cu")
	)
	(gr_line
		(start 368.784886 -119.223536)
		(end 368.784886 -119.34571)
		(stroke
			(width 0.04445)
			(type default)
		)
		(layer "F.Cu")
	)
	(gr_line
		(start 368.80292 -127.237236)
		(end 368.80292 -127.359156)
		(stroke
			(width 0.04445)
			(type default)
		)
		(layer "F.Cu")
	)
	(gr_line
		(start 368.81054 -126.1618)
		(end 368.86896 -126.1618)
		(stroke
			(width 0.04445)
			(type default)
		)
		(layer "F.Cu")
	)
	(gr_line
		(start 368.812572 -134.078218)
		(end 369.9256 -135.191246)
		(stroke
			(width 0.0635)
			(type default)
		)
		(layer "F.Cu")
	)
	(gr_line
		(start 368.825526 -120.810782)
		(end 369.092226 -120.810782)
		(stroke
			(width 0.04445)
			(type default)
		)
		(layer "F.Cu")
	)
	(gr_line
		(start 368.82959 -114.687096)
		(end 368.928396 -114.58829)
		(stroke
			(width 0.04445)
			(type default)
		)
		(layer "F.Cu")
	)
	(gr_line
		(start 368.838734 -124.80544)
		(end 368.925094 -124.8918)
		(stroke
			(width 0.04445)
			(type default)
		)
		(layer "F.Cu")
	)
	(gr_line
		(start 368.845592 -104.635046)
		(end 368.848386 -104.635046)
		(stroke
			(width 0.05715)
			(type default)
		)
		(layer "F.Cu")
	)
	(gr_line
		(start 368.850672 -50.389028)
		(end 368.86388 -50.386488)
		(stroke
			(width 0.05715)
			(type default)
		)
		(layer "F.Cu")
	)
	(gr_line
		(start 368.86388 -50.386488)
		(end 368.877088 -50.389028)
		(stroke
			(width 0.05715)
			(type default)
		)
		(layer "F.Cu")
	)
	(gr_line
		(start 368.865912 -111.76889)
		(end 368.964464 -111.867442)
		(stroke
			(width 0.04445)
			(type default)
		)
		(layer "F.Cu")
	)
	(gr_line
		(start 368.919506 -120.521222)
		(end 368.998246 -120.521222)
		(stroke
			(width 0.04445)
			(type default)
		)
		(layer "F.Cu")
	)
	(gr_line
		(start 368.925094 -124.8918)
		(end 369.191794 -124.8918)
		(stroke
			(width 0.04445)
			(type default)
		)
		(layer "F.Cu")
	)
	(gr_line
		(start 368.964464 -111.867442)
		(end 369.142264 -111.867442)
		(stroke
			(width 0.04445)
			(type default)
		)
		(layer "F.Cu")
	)
	(gr_line
		(start 368.9731 -126.4412)
		(end 369.05946 -126.35484)
		(stroke
			(width 0.04445)
			(type default)
		)
		(layer "F.Cu")
	)
	(gr_line
		(start 368.973608 -119.534432)
		(end 369.095782 -119.534432)
		(stroke
			(width 0.04445)
			(type default)
		)
		(layer "F.Cu")
	)
	(gr_line
		(start 369.029234 -124.6124)
		(end 369.087654 -124.6124)
		(stroke
			(width 0.04445)
			(type default)
		)
		(layer "F.Cu")
	)
	(gr_line
		(start 369.056158 -119.221758)
		(end 369.09756 -119.26316)
		(stroke
			(width 0.04445)
			(type default)
		)
		(layer "F.Cu")
	)
	(gr_line
		(start 369.061492 -104.92613)
		(end 369.333526 -105.198164)
		(stroke
			(width 0.05715)
			(type default)
		)
		(layer "F.Cu")
	)
	(gr_line
		(start 369.061492 -104.581198)
		(end 369.333526 -104.309164)
		(stroke
			(width 0.05715)
			(type default)
		)
		(layer "F.Cu")
	)
	(gr_line
		(start 369.07851 -48.112934)
		(end 369.09375 -48.109886)
		(stroke
			(width 0.05715)
			(type default)
		)
		(layer "F.Cu")
	)
	(gr_line
		(start 369.089432 -122.72264)
		(end 369.175792 -122.809)
		(stroke
			(width 0.04445)
			(type default)
		)
		(layer "F.Cu")
	)
	(gr_line
		(start 369.092226 -120.810782)
		(end 369.188746 -120.714262)
		(stroke
			(width 0.04445)
			(type default)
		)
		(layer "F.Cu")
	)
	(gr_line
		(start 369.09375 -48.109886)
		(end 369.106958 -48.100996)
		(stroke
			(width 0.05715)
			(type default)
		)
		(layer "F.Cu")
	)
	(gr_line
		(start 369.094512 -120.212358)
		(end 369.180872 -120.298718)
		(stroke
			(width 0.04445)
			(type default)
		)
		(layer "F.Cu")
	)
	(gr_line
		(start 369.10518 -1.48209)
		(end 369.167664 -1.419606)
		(stroke
			(width 0.05715)
			(type default)
		)
		(layer "F.Cu")
	)
	(gr_line
		(start 369.111276 -114.58829)
		(end 369.210082 -114.687096)
		(stroke
			(width 0.04445)
			(type default)
		)
		(layer "F.Cu")
	)
	(gr_line
		(start 369.121182 -121.73204)
		(end 369.207542 -121.8184)
		(stroke
			(width 0.04445)
			(type default)
		)
		(layer "F.Cu")
	)
	(gr_line
		(start 369.142264 -111.867442)
		(end 369.240816 -111.76889)
		(stroke
			(width 0.04445)
			(type default)
		)
		(layer "F.Cu")
	)
	(gr_line
		(start 369.167664 -1.419606)
		(end 369.567714 -1.419606)
		(stroke
			(width 0.05715)
			(type default)
		)
		(layer "F.Cu")
	)
	(gr_line
		(start 369.175792 -122.809)
		(end 369.442492 -122.809)
		(stroke
			(width 0.04445)
			(type default)
		)
		(layer "F.Cu")
	)
	(gr_line
		(start 369.180872 -120.298718)
		(end 369.447572 -120.298718)
		(stroke
			(width 0.04445)
			(type default)
		)
		(layer "F.Cu")
	)
	(gr_line
		(start 369.191794 -124.8918)
		(end 369.278154 -124.80544)
		(stroke
			(width 0.04445)
			(type default)
		)
		(layer "F.Cu")
	)
	(gr_line
		(start 369.197382 -135.297418)
		(end 369.544346 -135.297418)
		(stroke
			(width 0.0635)
			(type default)
		)
		(layer "F.Cu")
	)
	(gr_line
		(start 369.207034 -126.95174)
		(end 369.25885 -127.003556)
		(stroke
			(width 0.04445)
			(type default)
		)
		(layer "F.Cu")
	)
	(gr_line
		(start 369.207542 -121.8184)
		(end 369.474242 -121.8184)
		(stroke
			(width 0.04445)
			(type default)
		)
		(layer "F.Cu")
	)
	(gr_line
		(start 369.210082 -114.687096)
		(end 369.387882 -114.687096)
		(stroke
			(width 0.04445)
			(type default)
		)
		(layer "F.Cu")
	)
	(gr_line
		(start 369.25885 -127.003556)
		(end 369.594638 -127.003556)
		(stroke
			(width 0.04445)
			(type default)
		)
		(layer "F.Cu")
	)
	(gr_line
		(start 369.279932 -122.5296)
		(end 369.338352 -122.5296)
		(stroke
			(width 0.04445)
			(type default)
		)
		(layer "F.Cu")
	)
	(gr_line
		(start 369.285012 -120.019318)
		(end 369.343432 -120.019318)
		(stroke
			(width 0.04445)
			(type default)
		)
		(layer "F.Cu")
	)
	(gr_line
		(start 369.289076 -3.494532)
		(end 369.485164 -3.69062)
		(stroke
			(width 0.05715)
			(type default)
		)
		(layer "F.Cu")
	)
	(gr_line
		(start 369.311682 -121.539)
		(end 369.370102 -121.539)
		(stroke
			(width 0.04445)
			(type default)
		)
		(layer "F.Cu")
	)
	(gr_line
		(start 369.316 -118.237)
		(end 369.406424 -118.237)
		(stroke
			(width 0.04445)
			(type default)
		)
		(layer "F.Cu")
	)
	(gr_line
		(start 369.316 -117.236748)
		(end 369.512342 -117.43309)
		(stroke
			(width 0.04445)
			(type default)
		)
		(layer "F.Cu")
	)
	(gr_line
		(start 369.316 -116.7892)
		(end 369.316 -117.236748)
		(stroke
			(width 0.04445)
			(type default)
		)
		(layer "F.Cu")
	)
	(gr_line
		(start 369.316 -115.3414)
		(end 369.406424 -115.3414)
		(stroke
			(width 0.04445)
			(type default)
		)
		(layer "F.Cu")
	)
	(gr_line
		(start 369.33124 -126.35484)
		(end 369.4176 -126.4412)
		(stroke
			(width 0.04445)
			(type default)
		)
		(layer "F.Cu")
	)
	(gr_line
		(start 369.336066 -45.611288)
		(end 369.375436 -45.584618)
		(stroke
			(width 0.05715)
			(type default)
		)
		(layer "F.Cu")
	)
	(gr_line
		(start 369.375436 -45.584618)
		(end 369.390168 -45.540168)
		(stroke
			(width 0.05715)
			(type default)
		)
		(layer "F.Cu")
	)
	(gr_line
		(start 369.387882 -114.687096)
		(end 369.486688 -114.58829)
		(stroke
			(width 0.04445)
			(type default)
		)
		(layer "F.Cu")
	)
	(gr_line
		(start 369.397534 -126.7587)
		(end 369.455954 -126.7587)
		(stroke
			(width 0.04445)
			(type default)
		)
		(layer "F.Cu")
	)
	(gr_line
		(start 369.406424 -118.237)
		(end 369.698778 -118.529354)
		(stroke
			(width 0.04445)
			(type default)
		)
		(layer "F.Cu")
	)
	(gr_line
		(start 369.406424 -115.3414)
		(end 369.698778 -115.633754)
		(stroke
			(width 0.04445)
			(type default)
		)
		(layer "F.Cu")
	)
	(gr_line
		(start 369.407186 -12.734544)
		(end 369.42776 -12.721082)
		(stroke
			(width 0.05715)
			(type default)
		)
		(layer "F.Cu")
	)
	(gr_line
		(start 369.4176 -126.4412)
		(end 369.6843 -126.4412)
		(stroke
			(width 0.04445)
			(type default)
		)
		(layer "F.Cu")
	)
	(gr_line
		(start 369.42776 -12.721082)
		(end 369.439444 -12.699492)
		(stroke
			(width 0.05715)
			(type default)
		)
		(layer "F.Cu")
	)
	(gr_line
		(start 369.442492 -122.809)
		(end 369.528852 -122.72264)
		(stroke
			(width 0.04445)
			(type default)
		)
		(layer "F.Cu")
	)
	(gr_line
		(start 369.443 -113.252504)
		(end 369.443 -113.792)
		(stroke
			(width 0.04445)
			(type default)
		)
		(layer "F.Cu")
	)
	(gr_line
		(start 369.443 -113.252504)
		(end 369.6081 -113.087404)
		(stroke
			(width 0.04445)
			(type default)
		)
		(layer "F.Cu")
	)
	(gr_line
		(start 369.443 -112.634776)
		(end 369.702588 -112.894364)
		(stroke
			(width 0.04445)
			(type default)
		)
		(layer "F.Cu")
	)
	(gr_line
		(start 369.443 -112.395)
		(end 369.443 -112.634776)
		(stroke
			(width 0.04445)
			(type default)
		)
		(layer "F.Cu")
	)
	(gr_line
		(start 369.443 -110.435898)
		(end 369.443 -110.998)
		(stroke
			(width 0.04445)
			(type default)
		)
		(layer "F.Cu")
	)
	(gr_line
		(start 369.443 -110.435898)
		(end 369.579398 -110.2995)
		(stroke
			(width 0.04445)
			(type default)
		)
		(layer "F.Cu")
	)
	(gr_line
		(start 369.443 -109.883956)
		(end 369.665504 -110.10646)
		(stroke
			(width 0.04445)
			(type default)
		)
		(layer "F.Cu")
	)
	(gr_line
		(start 369.443 -109.601)
		(end 369.443 -109.883956)
		(stroke
			(width 0.04445)
			(type default)
		)
		(layer "F.Cu")
	)
	(gr_line
		(start 369.447572 -120.298718)
		(end 369.533932 -120.212358)
		(stroke
			(width 0.04445)
			(type default)
		)
		(layer "F.Cu")
	)
	(gr_line
		(start 369.460526 -120.714262)
		(end 369.557046 -120.810782)
		(stroke
			(width 0.04445)
			(type default)
		)
		(layer "F.Cu")
	)
	(gr_line
		(start 369.474242 -121.8184)
		(end 369.560602 -121.73204)
		(stroke
			(width 0.04445)
			(type default)
		)
		(layer "F.Cu")
	)
	(gr_line
		(start 369.477544 -10.916158)
		(end 369.749578 -11.188192)
		(stroke
			(width 0.05715)
			(type default)
		)
		(layer "F.Cu")
	)
	(gr_line
		(start 369.477544 -10.027158)
		(end 369.749578 -9.755124)
		(stroke
			(width 0.05715)
			(type default)
		)
		(layer "F.Cu")
	)
	(gr_line
		(start 369.477798 -111.76889)
		(end 369.57635 -111.867442)
		(stroke
			(width 0.04445)
			(type default)
		)
		(layer "F.Cu")
	)
	(gr_line
		(start 369.485164 -8.598154)
		(end 369.712494 -8.825484)
		(stroke
			(width 0.05715)
			(type default)
		)
		(layer "F.Cu")
	)
	(gr_line
		(start 369.485164 -7.789926)
		(end 369.485164 -8.598154)
		(stroke
			(width 0.05715)
			(type default)
		)
		(layer "F.Cu")
	)
	(gr_line
		(start 369.485164 -3.69062)
		(end 369.485164 -4.389882)
		(stroke
			(width 0.05715)
			(type default)
		)
		(layer "F.Cu")
	)
	(gr_line
		(start 369.512342 -117.43309)
		(end 369.795552 -117.43309)
		(stroke
			(width 0.04445)
			(type default)
		)
		(layer "F.Cu")
	)
	(gr_line
		(start 369.52174 -126.1618)
		(end 369.58016 -126.1618)
		(stroke
			(width 0.04445)
			(type default)
		)
		(layer "F.Cu")
	)
	(gr_line
		(start 369.544346 -135.297418)
		(end 369.66906 -135.422132)
		(stroke
			(width 0.0635)
			(type default)
		)
		(layer "F.Cu")
	)
	(gr_line
		(start 369.549934 -124.80544)
		(end 369.636294 -124.8918)
		(stroke
			(width 0.04445)
			(type default)
		)
		(layer "F.Cu")
	)
	(gr_line
		(start 369.557046 -120.810782)
		(end 369.823746 -120.810782)
		(stroke
			(width 0.04445)
			(type default)
		)
		(layer "F.Cu")
	)
	(gr_line
		(start 369.57 -136.4615)
		(end 369.769644 -136.261856)
		(stroke
			(width 0.0635)
			(type default)
		)
		(layer "F.Cu")
	)
	(gr_line
		(start 369.57635 -111.867442)
		(end 369.75415 -111.867442)
		(stroke
			(width 0.04445)
			(type default)
		)
		(layer "F.Cu")
	)
	(gr_line
		(start 369.594638 -127.003556)
		(end 369.646454 -126.95174)
		(stroke
			(width 0.04445)
			(type default)
		)
		(layer "F.Cu")
	)
	(gr_line
		(start 369.62588 -119.72544)
		(end 369.71224 -119.8118)
		(stroke
			(width 0.04445)
			(type default)
		)
		(layer "F.Cu")
	)
	(gr_line
		(start 369.636294 -124.8918)
		(end 369.902994 -124.8918)
		(stroke
			(width 0.04445)
			(type default)
		)
		(layer "F.Cu")
	)
	(gr_line
		(start 369.651026 -120.521222)
		(end 369.729766 -120.521222)
		(stroke
			(width 0.04445)
			(type default)
		)
		(layer "F.Cu")
	)
	(gr_line
		(start 369.666266 -49.779936)
		(end 369.686078 -49.785016)
		(stroke
			(width 0.05715)
			(type default)
		)
		(layer "F.Cu")
	)
	(gr_line
		(start 369.6843 -126.4412)
		(end 369.77066 -126.35484)
		(stroke
			(width 0.04445)
			(type default)
		)
		(layer "F.Cu")
	)
	(gr_line
		(start 369.686078 -49.785016)
		(end 369.706144 -49.780698)
		(stroke
			(width 0.05715)
			(type default)
		)
		(layer "F.Cu")
	)
	(gr_line
		(start 369.700556 -118.531132)
		(end 369.709192 -118.539768)
		(stroke
			(width 0.04445)
			(type default)
		)
		(layer "F.Cu")
	)
	(gr_line
		(start 369.700556 -115.635532)
		(end 369.709192 -115.644168)
		(stroke
			(width 0.04445)
			(type default)
		)
		(layer "F.Cu")
	)
	(gr_line
		(start 369.71224 -119.8118)
		(end 369.97894 -119.8118)
		(stroke
			(width 0.04445)
			(type default)
		)
		(layer "F.Cu")
	)
	(gr_line
		(start 369.740434 -124.6124)
		(end 369.798854 -124.6124)
		(stroke
			(width 0.04445)
			(type default)
		)
		(layer "F.Cu")
	)
	(gr_line
		(start 369.75415 -111.867442)
		(end 369.852702 -111.76889)
		(stroke
			(width 0.04445)
			(type default)
		)
		(layer "F.Cu")
	)
	(gr_line
		(start 369.800632 -122.72264)
		(end 369.886992 -122.809)
		(stroke
			(width 0.04445)
			(type default)
		)
		(layer "F.Cu")
	)
	(gr_line
		(start 369.805712 -120.212358)
		(end 369.892072 -120.298718)
		(stroke
			(width 0.04445)
			(type default)
		)
		(layer "F.Cu")
	)
	(gr_line
		(start 369.80749 -114.448844)
		(end 369.94719 -114.448844)
		(stroke
			(width 0.04445)
			(type default)
		)
		(layer "F.Cu")
	)
	(gr_line
		(start 369.81638 -119.5324)
		(end 369.8748 -119.5324)
		(stroke
			(width 0.04445)
			(type default)
		)
		(layer "F.Cu")
	)
	(gr_line
		(start 369.823746 -120.810782)
		(end 369.920266 -120.714262)
		(stroke
			(width 0.04445)
			(type default)
		)
		(layer "F.Cu")
	)
	(gr_line
		(start 369.832382 -121.73204)
		(end 369.918742 -121.8184)
		(stroke
			(width 0.04445)
			(type default)
		)
		(layer "F.Cu")
	)
	(gr_line
		(start 369.853972 -40.414448)
		(end 369.85575 -40.424354)
		(stroke
			(width 0.05715)
			(type default)
		)
		(layer "F.Cu")
	)
	(gr_line
		(start 369.853972 -40.414448)
		(end 369.856258 -40.403018)
		(stroke
			(width 0.05715)
			(type default)
		)
		(layer "F.Cu")
	)
	(gr_line
		(start 369.886992 -122.809)
		(end 370.153692 -122.809)
		(stroke
			(width 0.04445)
			(type default)
		)
		(layer "F.Cu")
	)
	(gr_line
		(start 369.892072 -120.298718)
		(end 370.158772 -120.298718)
		(stroke
			(width 0.04445)
			(type default)
		)
		(layer "F.Cu")
	)
	(gr_line
		(start 369.899692 -118.60149)
		(end 369.908328 -118.610126)
		(stroke
			(width 0.04445)
			(type default)
		)
		(layer "F.Cu")
	)
	(gr_line
		(start 369.899692 -118.42242)
		(end 369.9764 -118.237)
		(stroke
			(width 0.04445)
			(type default)
		)
		(layer "F.Cu")
	)
	(gr_line
		(start 369.899692 -117.15369)
		(end 369.94592 -117.199918)
		(stroke
			(width 0.04445)
			(type default)
		)
		(layer "F.Cu")
	)
	(gr_line
		(start 369.899692 -116.865908)
		(end 369.899692 -117.15369)
		(stroke
			(width 0.04445)
			(type default)
		)
		(layer "F.Cu")
	)
	(gr_line
		(start 369.899692 -116.865908)
		(end 369.9764 -116.7892)
		(stroke
			(width 0.04445)
			(type default)
		)
		(layer "F.Cu")
	)
	(gr_line
		(start 369.899692 -115.70589)
		(end 369.908328 -115.714526)
		(stroke
			(width 0.04445)
			(type default)
		)
		(layer "F.Cu")
	)
	(gr_line
		(start 369.899692 -115.418108)
		(end 369.899692 -115.451128)
		(stroke
			(width 0.04445)
			(type default)
		)
		(layer "F.Cu")
	)
	(gr_line
		(start 369.899692 -115.418108)
		(end 369.9764 -115.3414)
		(stroke
			(width 0.04445)
			(type default)
		)
		(layer "F.Cu")
	)
	(gr_line
		(start 369.902994 -124.8918)
		(end 369.989354 -124.80544)
		(stroke
			(width 0.04445)
			(type default)
		)
		(layer "F.Cu")
	)
	(gr_line
		(start 369.918234 -126.95174)
		(end 370.004594 -127.0381)
		(stroke
			(width 0.04445)
			(type default)
		)
		(layer "F.Cu")
	)
	(gr_line
		(start 369.918742 -121.8184)
		(end 370.185442 -121.8184)
		(stroke
			(width 0.04445)
			(type default)
		)
		(layer "F.Cu")
	)
	(gr_line
		(start 369.94719 -114.448844)
		(end 370.07292 -114.323114)
		(stroke
			(width 0.04445)
			(type default)
		)
		(layer "F.Cu")
	)
	(gr_line
		(start 369.947698 -118.649496)
		(end 369.988592 -118.69039)
		(stroke
			(width 0.04445)
			(type default)
		)
		(layer "F.Cu")
	)
	(gr_line
		(start 369.947698 -117.201696)
		(end 369.988592 -117.24259)
		(stroke
			(width 0.04445)
			(type default)
		)
		(layer "F.Cu")
	)
	(gr_line
		(start 369.947698 -115.753896)
		(end 369.988592 -115.79479)
		(stroke
			(width 0.04445)
			(type default)
		)
		(layer "F.Cu")
	)
	(gr_line
		(start 369.97894 -119.8118)
		(end 370.0653 -119.72544)
		(stroke
			(width 0.04445)
			(type default)
		)
		(layer "F.Cu")
	)
	(gr_line
		(start 369.985544 -118.88089)
		(end 370.026438 -118.921784)
		(stroke
			(width 0.04445)
			(type default)
		)
		(layer "F.Cu")
	)
	(gr_line
		(start 369.985544 -117.43309)
		(end 370.026438 -117.473984)
		(stroke
			(width 0.04445)
			(type default)
		)
		(layer "F.Cu")
	)
	(gr_line
		(start 369.985544 -115.98529)
		(end 370.026438 -116.026184)
		(stroke
			(width 0.04445)
			(type default)
		)
		(layer "F.Cu")
	)
	(gr_line
		(start 369.991132 -122.5296)
		(end 370.049552 -122.5296)
		(stroke
			(width 0.04445)
			(type default)
		)
		(layer "F.Cu")
	)
	(gr_line
		(start 369.996212 -120.019318)
		(end 370.054632 -120.019318)
		(stroke
			(width 0.04445)
			(type default)
		)
		(layer "F.Cu")
	)
	(gr_line
		(start 370.004594 -127.0381)
		(end 370.271294 -127.0381)
		(stroke
			(width 0.04445)
			(type default)
		)
		(layer "F.Cu")
	)
	(gr_line
		(start 370.01069 -50.86223)
		(end 370.023898 -50.86477)
		(stroke
			(width 0.05715)
			(type default)
		)
		(layer "F.Cu")
	)
	(gr_line
		(start 370.022882 -121.539)
		(end 370.081302 -121.539)
		(stroke
			(width 0.04445)
			(type default)
		)
		(layer "F.Cu")
	)
	(gr_line
		(start 370.023898 -50.86477)
		(end 370.037106 -50.86223)
		(stroke
			(width 0.05715)
			(type default)
		)
		(layer "F.Cu")
	)
	(gr_line
		(start 370.028216 -118.923562)
		(end 370.076476 -118.971822)
		(stroke
			(width 0.04445)
			(type default)
		)
		(layer "F.Cu")
	)
	(gr_line
		(start 370.028216 -117.475762)
		(end 370.076476 -117.524022)
		(stroke
			(width 0.04445)
			(type default)
		)
		(layer "F.Cu")
	)
	(gr_line
		(start 370.028216 -116.027962)
		(end 370.076476 -116.076222)
		(stroke
			(width 0.04445)
			(type default)
		)
		(layer "F.Cu")
	)
	(gr_line
		(start 370.02974 -11.625834)
		(end 370.042694 -11.602212)
		(stroke
			(width 0.05715)
			(type default)
		)
		(layer "F.Cu")
	)
	(gr_line
		(start 370.035582 -111.76889)
		(end 370.134134 -111.867442)
		(stroke
			(width 0.04445)
			(type default)
		)
		(layer "F.Cu")
	)
	(gr_line
		(start 370.04244 -126.35484)
		(end 370.1288 -126.4412)
		(stroke
			(width 0.04445)
			(type default)
		)
		(layer "F.Cu")
	)
	(gr_line
		(start 370.055394 -110.30204)
		(end 370.141754 -110.3884)
		(stroke
			(width 0.04445)
			(type default)
		)
		(layer "F.Cu")
	)
	(gr_line
		(start 370.057426 -8.825484)
		(end 370.28501 -8.5979)
		(stroke
			(width 0.05715)
			(type default)
		)
		(layer "F.Cu")
	)
	(gr_line
		(start 370.06657 -37.189156)
		(end 370.06911 -37.20211)
		(stroke
			(width 0.05715)
			(type default)
		)
		(layer "F.Cu")
	)
	(gr_line
		(start 370.06657 -37.189156)
		(end 370.06911 -37.175948)
		(stroke
			(width 0.05715)
			(type default)
		)
		(layer "F.Cu")
	)
	(gr_line
		(start 370.07292 -114.183414)
		(end 370.07292 -114.323114)
		(stroke
			(width 0.04445)
			(type default)
		)
		(layer "F.Cu")
	)
	(gr_line
		(start 370.076476 -118.971822)
		(end 370.254276 -118.971822)
		(stroke
			(width 0.04445)
			(type default)
		)
		(layer "F.Cu")
	)
	(gr_line
		(start 370.076476 -117.524022)
		(end 370.254276 -117.524022)
		(stroke
			(width 0.04445)
			(type default)
		)
		(layer "F.Cu")
	)
	(gr_line
		(start 370.076476 -116.076222)
		(end 370.254276 -116.076222)
		(stroke
			(width 0.04445)
			(type default)
		)
		(layer "F.Cu")
	)
	(gr_line
		(start 370.091462 -113.089944)
		(end 370.190014 -113.188496)
		(stroke
			(width 0.04445)
			(type default)
		)
		(layer "F.Cu")
	)
	(gr_line
		(start 370.09451 -11.188192)
		(end 370.366544 -10.916158)
		(stroke
			(width 0.05715)
			(type default)
		)
		(layer "F.Cu")
	)
	(gr_line
		(start 370.09451 -9.755124)
		(end 370.366544 -10.027158)
		(stroke
			(width 0.05715)
			(type default)
		)
		(layer "F.Cu")
	)
	(gr_line
		(start 370.108734 -126.7587)
		(end 370.167154 -126.7587)
		(stroke
			(width 0.04445)
			(type default)
		)
		(layer "F.Cu")
	)
	(gr_line
		(start 370.1288 -126.4412)
		(end 370.3955 -126.4412)
		(stroke
			(width 0.04445)
			(type default)
		)
		(layer "F.Cu")
	)
	(gr_line
		(start 370.132356 -136.261856)
		(end 370.332 -136.4615)
		(stroke
			(width 0.0635)
			(type default)
		)
		(layer "F.Cu")
	)
	(gr_line
		(start 370.134134 -111.867442)
		(end 370.311934 -111.867442)
		(stroke
			(width 0.04445)
			(type default)
		)
		(layer "F.Cu")
	)
	(gr_line
		(start 370.141754 -110.485936)
		(end 370.256816 -110.600998)
		(stroke
			(width 0.04445)
			(type default)
		)
		(layer "F.Cu")
	)
	(gr_line
		(start 370.141754 -110.3884)
		(end 370.141754 -110.485936)
		(stroke
			(width 0.04445)
			(type default)
		)
		(layer "F.Cu")
	)
	(gr_line
		(start 370.153692 -122.809)
		(end 370.240052 -122.72264)
		(stroke
			(width 0.04445)
			(type default)
		)
		(layer "F.Cu")
	)
	(gr_line
		(start 370.158772 -120.298718)
		(end 370.245132 -120.212358)
		(stroke
			(width 0.04445)
			(type default)
		)
		(layer "F.Cu")
	)
	(gr_line
		(start 370.17706 -110.109)
		(end 370.397786 -110.329726)
		(stroke
			(width 0.04445)
			(type default)
		)
		(layer "F.Cu")
	)
	(gr_line
		(start 370.185442 -121.8184)
		(end 370.271802 -121.73204)
		(stroke
			(width 0.04445)
			(type default)
		)
		(layer "F.Cu")
	)
	(gr_line
		(start 370.190014 -113.188496)
		(end 370.367814 -113.188496)
		(stroke
			(width 0.04445)
			(type default)
		)
		(layer "F.Cu")
	)
	(gr_line
		(start 370.190522 -46.199806)
		(end 370.229892 -46.173136)
		(stroke
			(width 0.05715)
			(type default)
		)
		(layer "F.Cu")
	)
	(gr_line
		(start 370.192046 -120.714262)
		(end 370.288566 -120.810782)
		(stroke
			(width 0.04445)
			(type default)
		)
		(layer "F.Cu")
	)
	(gr_line
		(start 370.222526 -104.857296)
		(end 370.222526 -105.198164)
		(stroke
			(width 0.04445)
			(type default)
		)
		(layer "F.Cu")
	)
	(gr_line
		(start 370.222526 -104.857296)
		(end 370.330476 -104.749346)
		(stroke
			(width 0.04445)
			(type default)
		)
		(layer "F.Cu")
	)
	(gr_line
		(start 370.222526 -104.309164)
		(end 370.469668 -104.556306)
		(stroke
			(width 0.04445)
			(type default)
		)
		(layer "F.Cu")
	)
	(gr_line
		(start 370.229892 -46.173136)
		(end 370.245132 -46.128178)
		(stroke
			(width 0.05715)
			(type default)
		)
		(layer "F.Cu")
	)
	(gr_line
		(start 370.23294 -126.1618)
		(end 370.29136 -126.1618)
		(stroke
			(width 0.04445)
			(type default)
		)
		(layer "F.Cu")
	)
	(gr_line
		(start 370.254276 -118.971822)
		(end 370.342668 -118.88343)
		(stroke
			(width 0.04445)
			(type default)
		)
		(layer "F.Cu")
	)
	(gr_line
		(start 370.254276 -117.524022)
		(end 370.342668 -117.43563)
		(stroke
			(width 0.04445)
			(type default)
		)
		(layer "F.Cu")
	)
	(gr_line
		(start 370.254276 -116.076222)
		(end 370.342668 -115.98783)
		(stroke
			(width 0.04445)
			(type default)
		)
		(layer "F.Cu")
	)
	(gr_line
		(start 370.256816 -110.600998)
		(end 370.396008 -110.600998)
		(stroke
			(width 0.04445)
			(type default)
		)
		(layer "F.Cu")
	)
	(gr_line
		(start 370.267484 -28.905454)
		(end 370.3193 -28.868624)
		(stroke
			(width 0.05715)
			(type default)
		)
		(layer "F.Cu")
	)
	(gr_line
		(start 370.271294 -127.0381)
		(end 370.357654 -126.95174)
		(stroke
			(width 0.04445)
			(type default)
		)
		(layer "F.Cu")
	)
	(gr_line
		(start 370.28501 -7.789926)
		(end 370.28501 -8.5979)
		(stroke
			(width 0.05715)
			(type default)
		)
		(layer "F.Cu")
	)
	(gr_line
		(start 370.288566 -120.810782)
		(end 370.555266 -120.810782)
		(stroke
			(width 0.04445)
			(type default)
		)
		(layer "F.Cu")
	)
	(gr_line
		(start 370.311934 -111.867442)
		(end 370.410486 -111.76889)
		(stroke
			(width 0.04445)
			(type default)
		)
		(layer "F.Cu")
	)
	(gr_line
		(start 370.3193 -28.868624)
		(end 370.331746 -28.806648)
		(stroke
			(width 0.05715)
			(type default)
		)
		(layer "F.Cu")
	)
	(gr_line
		(start 370.33708 -119.72544)
		(end 370.42344 -119.8118)
		(stroke
			(width 0.04445)
			(type default)
		)
		(layer "F.Cu")
	)
	(gr_line
		(start 370.367814 -113.188496)
		(end 370.466366 -113.089944)
		(stroke
			(width 0.04445)
			(type default)
		)
		(layer "F.Cu")
	)
	(gr_line
		(start 370.382546 -120.521222)
		(end 370.461286 -120.521222)
		(stroke
			(width 0.04445)
			(type default)
		)
		(layer "F.Cu")
	)
	(gr_line
		(start 370.3955 -126.4412)
		(end 370.48186 -126.35484)
		(stroke
			(width 0.04445)
			(type default)
		)
		(layer "F.Cu")
	)
	(gr_line
		(start 370.42344 -119.8118)
		(end 370.69014 -119.8118)
		(stroke
			(width 0.04445)
			(type default)
		)
		(layer "F.Cu")
	)
	(gr_line
		(start 370.441982 -42.403522)
		(end 370.450364 -42.378884)
		(stroke
			(width 0.05715)
			(type default)
		)
		(layer "F.Cu")
	)
	(gr_line
		(start 370.44376 -13.10259)
		(end 370.47551 -12.947142)
		(stroke
			(width 0.05715)
			(type default)
		)
		(layer "F.Cu")
	)
	(gr_line
		(start 370.445538 -42.352468)
		(end 370.450364 -42.378884)
		(stroke
			(width 0.05715)
			(type default)
		)
		(layer "F.Cu")
	)
	(gr_line
		(start 370.453666 -124.338334)
		(end 370.4971 -124.2949)
		(stroke
			(width 0.04445)
			(type default)
		)
		(layer "F.Cu")
	)
	(gr_line
		(start 370.47551 -12.947142)
		(end 370.761514 -12.757912)
		(stroke
			(width 0.05715)
			(type default)
		)
		(layer "F.Cu")
	)
	(gr_line
		(start 370.509292 -122.7201)
		(end 370.515388 -122.71756)
		(stroke
			(width 0.04445)
			(type default)
		)
		(layer "F.Cu")
	)
	(gr_line
		(start 370.514372 -110.858554)
		(end 370.629434 -110.973616)
		(stroke
			(width 0.04445)
			(type default)
		)
		(layer "F.Cu")
	)
	(gr_line
		(start 370.514372 -110.719362)
		(end 370.514372 -110.858554)
		(stroke
			(width 0.04445)
			(type default)
		)
		(layer "F.Cu")
	)
	(gr_line
		(start 370.516912 -120.212358)
		(end 370.603272 -120.298718)
		(stroke
			(width 0.04445)
			(type default)
		)
		(layer "F.Cu")
	)
	(gr_line
		(start 370.525548 -118.88343)
		(end 370.61394 -118.971822)
		(stroke
			(width 0.04445)
			(type default)
		)
		(layer "F.Cu")
	)
	(gr_line
		(start 370.525548 -117.43563)
		(end 370.61394 -117.524022)
		(stroke
			(width 0.04445)
			(type default)
		)
		(layer "F.Cu")
	)
	(gr_line
		(start 370.525548 -115.98783)
		(end 370.61394 -116.076222)
		(stroke
			(width 0.04445)
			(type default)
		)
		(layer "F.Cu")
	)
	(gr_line
		(start 370.52631 -38.256718)
		(end 370.529104 -38.270688)
		(stroke
			(width 0.05715)
			(type default)
		)
		(layer "F.Cu")
	)
	(gr_line
		(start 370.526564 -38.283896)
		(end 370.529104 -38.270688)
		(stroke
			(width 0.05715)
			(type default)
		)
		(layer "F.Cu")
	)
	(gr_line
		(start 370.52758 -119.5324)
		(end 370.586 -119.5324)
		(stroke
			(width 0.04445)
			(type default)
		)
		(layer "F.Cu")
	)
	(gr_line
		(start 370.543582 -121.73204)
		(end 370.629942 -121.8184)
		(stroke
			(width 0.04445)
			(type default)
		)
		(layer "F.Cu")
	)
	(gr_line
		(start 370.555266 -120.810782)
		(end 370.651786 -120.714262)
		(stroke
			(width 0.04445)
			(type default)
		)
		(layer "F.Cu")
	)
	(gr_line
		(start 370.586 -18.151094)
		(end 370.59362 -18.189448)
		(stroke
			(width 0.05715)
			(type default)
		)
		(layer "F.Cu")
	)
	(gr_line
		(start 370.586 -18.151094)
		(end 370.601494 -18.11401)
		(stroke
			(width 0.05715)
			(type default)
		)
		(layer "F.Cu")
	)
	(gr_line
		(start 370.596414 -49.59731)
		(end 370.60251 -49.59604)
		(stroke
			(width 0.05715)
			(type default)
		)
		(layer "F.Cu")
	)
	(gr_line
		(start 370.60251 -49.59604)
		(end 370.608352 -49.592738)
		(stroke
			(width 0.05715)
			(type default)
		)
		(layer "F.Cu")
	)
	(gr_line
		(start 370.603272 -120.298718)
		(end 370.869972 -120.298718)
		(stroke
			(width 0.04445)
			(type default)
		)
		(layer "F.Cu")
	)
	(gr_line
		(start 370.604542 -13.288518)
		(end 371.025674 -13.00988)
		(stroke
			(width 0.05715)
			(type default)
		)
		(layer "F.Cu")
	)
	(gr_line
		(start 370.61394 -118.971822)
		(end 370.79174 -118.971822)
		(stroke
			(width 0.04445)
			(type default)
		)
		(layer "F.Cu")
	)
	(gr_line
		(start 370.61394 -117.524022)
		(end 370.79174 -117.524022)
		(stroke
			(width 0.04445)
			(type default)
		)
		(layer "F.Cu")
	)
	(gr_line
		(start 370.61394 -116.076222)
		(end 370.79174 -116.076222)
		(stroke
			(width 0.04445)
			(type default)
		)
		(layer "F.Cu")
	)
	(gr_line
		(start 370.629434 -126.95174)
		(end 370.715794 -127.0381)
		(stroke
			(width 0.04445)
			(type default)
		)
		(layer "F.Cu")
	)
	(gr_line
		(start 370.629434 -110.973616)
		(end 370.768626 -110.973616)
		(stroke
			(width 0.04445)
			(type default)
		)
		(layer "F.Cu")
	)
	(gr_line
		(start 370.629942 -121.8184)
		(end 370.896642 -121.8184)
		(stroke
			(width 0.04445)
			(type default)
		)
		(layer "F.Cu")
	)
	(gr_line
		(start 370.656866 -17.685258)
		(end 370.717064 -17.831562)
		(stroke
			(width 0.05715)
			(type default)
		)
		(layer "F.Cu")
	)
	(gr_line
		(start 370.656866 -17.685258)
		(end 370.7892 -17.368774)
		(stroke
			(width 0.05715)
			(type default)
		)
		(layer "F.Cu")
	)
	(gr_line
		(start 370.680488 -113.762282)
		(end 370.779294 -113.861088)
		(stroke
			(width 0.04445)
			(type default)
		)
		(layer "F.Cu")
	)
	(gr_line
		(start 370.683028 -113.089944)
		(end 370.78158 -113.188496)
		(stroke
			(width 0.04445)
			(type default)
		)
		(layer "F.Cu")
	)
	(gr_line
		(start 370.6876 -124.302774)
		(end 370.731034 -124.25934)
		(stroke
			(width 0.04445)
			(type default)
		)
		(layer "F.Cu")
	)
	(gr_line
		(start 370.69014 -119.8118)
		(end 370.7765 -119.72544)
		(stroke
			(width 0.04445)
			(type default)
		)
		(layer "F.Cu")
	)
	(gr_line
		(start 370.707412 -120.019318)
		(end 370.765832 -120.019318)
		(stroke
			(width 0.04445)
			(type default)
		)
		(layer "F.Cu")
	)
	(gr_line
		(start 370.707412 -109.960918)
		(end 371.31879 -110.572296)
		(stroke
			(width 0.04445)
			(type default)
		)
		(layer "F.Cu")
	)
	(gr_line
		(start 370.707412 -109.944154)
		(end 370.707412 -109.960918)
		(stroke
			(width 0.04445)
			(type default)
		)
		(layer "F.Cu")
	)
	(gr_line
		(start 370.715794 -127.0381)
		(end 370.982494 -127.0381)
		(stroke
			(width 0.04445)
			(type default)
		)
		(layer "F.Cu")
	)
	(gr_line
		(start 370.720366 -22.173184)
		(end 370.72316 -22.187408)
		(stroke
			(width 0.05715)
			(type default)
		)
		(layer "F.Cu")
	)
	(gr_line
		(start 370.720366 -22.173184)
		(end 370.723414 -22.158198)
		(stroke
			(width 0.05715)
			(type default)
		)
		(layer "F.Cu")
	)
	(gr_line
		(start 370.734082 -121.539)
		(end 370.792502 -121.539)
		(stroke
			(width 0.04445)
			(type default)
		)
		(layer "F.Cu")
	)
	(gr_line
		(start 370.7384 -128.524)
		(end 370.967 -128.2954)
		(stroke
			(width 0.0508)
			(type default)
		)
		(layer "F.Cu")
	)
	(gr_line
		(start 370.7384 -127.762)
		(end 370.967 -127.9906)
		(stroke
			(width 0.0508)
			(type default)
		)
		(layer "F.Cu")
	)
	(gr_line
		(start 370.761514 -12.757912)
		(end 370.916708 -12.789662)
		(stroke
			(width 0.05715)
			(type default)
		)
		(layer "F.Cu")
	)
	(gr_line
		(start 370.779294 -113.861088)
		(end 370.957094 -113.861088)
		(stroke
			(width 0.04445)
			(type default)
		)
		(layer "F.Cu")
	)
	(gr_line
		(start 370.779548 -50.713894)
		(end 370.794534 -50.710846)
		(stroke
			(width 0.05715)
			(type default)
		)
		(layer "F.Cu")
	)
	(gr_line
		(start 370.78158 -113.188496)
		(end 370.95938 -113.188496)
		(stroke
			(width 0.04445)
			(type default)
		)
		(layer "F.Cu")
	)
	(gr_line
		(start 370.7892 -17.368774)
		(end 370.935758 -17.30883)
		(stroke
			(width 0.05715)
			(type default)
		)
		(layer "F.Cu")
	)
	(gr_line
		(start 370.79174 -118.971822)
		(end 370.880132 -118.88343)
		(stroke
			(width 0.04445)
			(type default)
		)
		(layer "F.Cu")
	)
	(gr_line
		(start 370.79174 -117.524022)
		(end 370.880132 -117.43563)
		(stroke
			(width 0.04445)
			(type default)
		)
		(layer "F.Cu")
	)
	(gr_line
		(start 370.79174 -116.076222)
		(end 370.880132 -115.98783)
		(stroke
			(width 0.04445)
			(type default)
		)
		(layer "F.Cu")
	)
	(gr_line
		(start 370.794534 -50.710846)
		(end 370.80698 -50.702464)
		(stroke
			(width 0.05715)
			(type default)
		)
		(layer "F.Cu")
	)
	(gr_line
		(start 370.806726 -112.150144)
		(end 370.932456 -112.275874)
		(stroke
			(width 0.04445)
			(type default)
		)
		(layer "F.Cu")
	)
	(gr_line
		(start 370.806726 -112.010444)
		(end 370.806726 -112.150144)
		(stroke
			(width 0.04445)
			(type default)
		)
		(layer "F.Cu")
	)
	(gr_line
		(start 370.819934 -126.7587)
		(end 370.878354 -126.7587)
		(stroke
			(width 0.04445)
			(type default)
		)
		(layer "F.Cu")
	)
	(gr_line
		(start 370.869972 -120.298718)
		(end 370.956332 -120.212358)
		(stroke
			(width 0.04445)
			(type default)
		)
		(layer "F.Cu")
	)
	(gr_line
		(start 370.88699 -111.231172)
		(end 371.002052 -111.346234)
		(stroke
			(width 0.04445)
			(type default)
		)
		(layer "F.Cu")
	)
	(gr_line
		(start 370.88699 -111.09198)
		(end 370.88699 -111.231172)
		(stroke
			(width 0.04445)
			(type default)
		)
		(layer "F.Cu")
	)
	(gr_line
		(start 370.887752 -128.374648)
		(end 370.967 -128.2954)
		(stroke
			(width 0.0508)
			(type default)
		)
		(layer "F.Cu")
	)
	(gr_line
		(start 370.887752 -127.911352)
		(end 370.967 -127.9906)
		(stroke
			(width 0.0508)
			(type default)
		)
		(layer "F.Cu")
	)
	(gr_line
		(start 370.896642 -121.8184)
		(end 370.983002 -121.73204)
		(stroke
			(width 0.04445)
			(type default)
		)
		(layer "F.Cu")
	)
	(gr_line
		(start 370.900198 -2.937002)
		(end 371.248178 -2.937002)
		(stroke
			(width 0.05715)
			(type default)
		)
		(layer "F.Cu")
	)
	(gr_line
		(start 370.921026 -40.285416)
		(end 370.922804 -40.295322)
		(stroke
			(width 0.05715)
			(type default)
		)
		(layer "F.Cu")
	)
	(gr_line
		(start 370.921026 -40.285416)
		(end 370.923312 -40.273986)
		(stroke
			(width 0.05715)
			(type default)
		)
		(layer "F.Cu")
	)
	(gr_line
		(start 370.923566 -120.714262)
		(end 371.020086 -120.810782)
		(stroke
			(width 0.04445)
			(type default)
		)
		(layer "F.Cu")
	)
	(gr_line
		(start 370.932456 -112.275874)
		(end 371.072156 -112.275874)
		(stroke
			(width 0.04445)
			(type default)
		)
		(layer "F.Cu")
	)
	(gr_line
		(start 370.954554 -17.895824)
		(end 371.14861 -17.43202)
		(stroke
			(width 0.05715)
			(type default)
		)
		(layer "F.Cu")
	)
	(gr_line
		(start 370.957094 -113.861088)
		(end 371.0559 -113.762282)
		(stroke
			(width 0.04445)
			(type default)
		)
		(layer "F.Cu")
	)
	(gr_line
		(start 370.959126 -122.329194)
		(end 371.312694 -122.183906)
		(stroke
			(width 0.04445)
			(type default)
		)
		(layer "F.Cu")
	)
	(gr_line
		(start 370.95938 -113.188496)
		(end 371.057932 -113.089944)
		(stroke
			(width 0.04445)
			(type default)
		)
		(layer "F.Cu")
	)
	(gr_line
		(start 370.967 -128.2954)
		(end 373.55272 -128.2954)
		(stroke
			(width 0.0508)
			(type default)
		)
		(layer "F.Cu")
	)
	(gr_line
		(start 370.967 -127.9906)
		(end 373.426228 -127.9906)
		(stroke
			(width 0.0508)
			(type default)
		)
		(layer "F.Cu")
	)
	(gr_line
		(start 370.982494 -127.0381)
		(end 371.068854 -126.95174)
		(stroke
			(width 0.04445)
			(type default)
		)
		(layer "F.Cu")
	)
	(gr_line
		(start 370.99367 -30.33141)
		(end 371.042692 -30.296612)
		(stroke
			(width 0.05715)
			(type default)
		)
		(layer "F.Cu")
	)
	(gr_line
		(start 371.002052 -111.346234)
		(end 371.141244 -111.346234)
		(stroke
			(width 0.04445)
			(type default)
		)
		(layer "F.Cu")
	)
	(gr_line
		(start 371.005608 -122.518678)
		(end 371.118384 -122.565922)
		(stroke
			(width 0.04445)
			(type default)
		)
		(layer "F.Cu")
	)
	(gr_line
		(start 371.009926 -16.841724)
		(end 371.06987 -16.988028)
		(stroke
			(width 0.05715)
			(type default)
		)
		(layer "F.Cu")
	)
	(gr_line
		(start 371.009926 -16.841724)
		(end 371.14226 -16.52524)
		(stroke
			(width 0.05715)
			(type default)
		)
		(layer "F.Cu")
	)
	(gr_line
		(start 371.020086 -120.810782)
		(end 371.286786 -120.810782)
		(stroke
			(width 0.04445)
			(type default)
		)
		(layer "F.Cu")
	)
	(gr_line
		(start 371.042692 -30.296612)
		(end 371.05463 -30.237176)
		(stroke
			(width 0.05715)
			(type default)
		)
		(layer "F.Cu")
	)
	(gr_line
		(start 371.04828 -119.72544)
		(end 371.13464 -119.8118)
		(stroke
			(width 0.04445)
			(type default)
		)
		(layer "F.Cu")
	)
	(gr_line
		(start 371.08511 -3.708146)
		(end 371.08511 -4.389882)
		(stroke
			(width 0.05715)
			(type default)
		)
		(layer "F.Cu")
	)
	(gr_line
		(start 371.08511 -3.708146)
		(end 371.30482 -3.488436)
		(stroke
			(width 0.05715)
			(type default)
		)
		(layer "F.Cu")
	)
	(gr_line
		(start 371.093492 -37.336222)
		(end 371.096032 -37.34943)
		(stroke
			(width 0.05715)
			(type default)
		)
		(layer "F.Cu")
	)
	(gr_line
		(start 371.093492 -37.336222)
		(end 371.096286 -37.322252)
		(stroke
			(width 0.05715)
			(type default)
		)
		(layer "F.Cu")
	)
	(gr_line
		(start 371.094508 -46.754796)
		(end 371.132608 -46.729142)
		(stroke
			(width 0.05715)
			(type default)
		)
		(layer "F.Cu")
	)
	(gr_line
		(start 371.114066 -120.521222)
		(end 371.192806 -120.521222)
		(stroke
			(width 0.04445)
			(type default)
		)
		(layer "F.Cu")
	)
	(gr_line
		(start 371.118384 -122.565922)
		(end 371.365018 -122.464576)
		(stroke
			(width 0.04445)
			(type default)
		)
		(layer "F.Cu")
	)
	(gr_line
		(start 371.119908 -117.615716)
		(end 371.245638 -117.741446)
		(stroke
			(width 0.04445)
			(type default)
		)
		(layer "F.Cu")
	)
	(gr_line
		(start 371.119908 -117.528086)
		(end 371.119908 -117.615716)
		(stroke
			(width 0.04445)
			(type default)
		)
		(layer "F.Cu")
	)
	(gr_line
		(start 371.119908 -116.167916)
		(end 371.245638 -116.293646)
		(stroke
			(width 0.04445)
			(type default)
		)
		(layer "F.Cu")
	)
	(gr_line
		(start 371.119908 -116.080286)
		(end 371.119908 -116.167916)
		(stroke
			(width 0.04445)
			(type default)
		)
		(layer "F.Cu")
	)
	(gr_line
		(start 371.124734 -119.100854)
		(end 371.250464 -119.226584)
		(stroke
			(width 0.04445)
			(type default)
		)
		(layer "F.Cu")
	)
	(gr_line
		(start 371.124734 -118.980712)
		(end 371.124734 -119.100854)
		(stroke
			(width 0.04445)
			(type default)
		)
		(layer "F.Cu")
	)
	(gr_line
		(start 371.131338 -125.702568)
		(end 371.17274 -125.661166)
		(stroke
			(width 0.04445)
			(type default)
		)
		(layer "F.Cu")
	)
	(gr_line
		(start 371.132608 -46.729142)
		(end 371.132862 -46.729142)
		(stroke
			(width 0.05715)
			(type default)
		)
		(layer "F.Cu")
	)
	(gr_line
		(start 371.132862 -46.729142)
		(end 371.148102 -46.684184)
		(stroke
			(width 0.05715)
			(type default)
		)
		(layer "F.Cu")
	)
	(gr_line
		(start 371.133116 -125.97384)
		(end 371.25529 -125.97384)
		(stroke
			(width 0.04445)
			(type default)
		)
		(layer "F.Cu")
	)
	(gr_line
		(start 371.13464 -119.8118)
		(end 371.40134 -119.8118)
		(stroke
			(width 0.04445)
			(type default)
		)
		(layer "F.Cu")
	)
	(gr_line
		(start 371.14226 -16.52524)
		(end 371.288564 -16.465296)
		(stroke
			(width 0.05715)
			(type default)
		)
		(layer "F.Cu")
	)
	(gr_line
		(start 371.174264 -49.257204)
		(end 371.213634 -49.233836)
		(stroke
			(width 0.05715)
			(type default)
		)
		(layer "F.Cu")
	)
	(gr_line
		(start 371.18544 -105.4735)
		(end 371.29847 -105.58653)
		(stroke
			(width 0.04445)
			(type default)
		)
		(layer "F.Cu")
	)
	(gr_line
		(start 371.18544 -105.3338)
		(end 371.18544 -105.4735)
		(stroke
			(width 0.04445)
			(type default)
		)
		(layer "F.Cu")
	)
	(gr_line
		(start 371.213634 -49.233836)
		(end 371.23116 -49.191672)
		(stroke
			(width 0.05715)
			(type default)
		)
		(layer "F.Cu")
	)
	(gr_line
		(start 371.228112 -120.212358)
		(end 371.314472 -120.298718)
		(stroke
			(width 0.04445)
			(type default)
		)
		(layer "F.Cu")
	)
	(gr_line
		(start 371.23878 -119.5324)
		(end 371.2972 -119.5324)
		(stroke
			(width 0.04445)
			(type default)
		)
		(layer "F.Cu")
	)
	(gr_line
		(start 371.23878 -113.762282)
		(end 371.337586 -113.861088)
		(stroke
			(width 0.04445)
			(type default)
		)
		(layer "F.Cu")
	)
	(gr_line
		(start 371.240812 -113.089944)
		(end 371.339364 -113.188496)
		(stroke
			(width 0.04445)
			(type default)
		)
		(layer "F.Cu")
	)
	(gr_line
		(start 371.245638 -117.741446)
		(end 371.318282 -117.741446)
		(stroke
			(width 0.04445)
			(type default)
		)
		(layer "F.Cu")
	)
	(gr_line
		(start 371.245638 -116.293646)
		(end 371.318282 -116.293646)
		(stroke
			(width 0.04445)
			(type default)
		)
		(layer "F.Cu")
	)
	(gr_line
		(start 371.2464 -114.553492)
		(end 371.608858 -114.91595)
		(stroke
			(width 0.04445)
			(type default)
		)
		(layer "F.Cu")
	)
	(gr_line
		(start 371.2464 -114.299238)
		(end 371.2464 -114.553492)
		(stroke
			(width 0.04445)
			(type default)
		)
		(layer "F.Cu")
	)
	(gr_line
		(start 371.248178 -2.937002)
		(end 371.322854 -3.011678)
		(stroke
			(width 0.05715)
			(type default)
		)
		(layer "F.Cu")
	)
	(gr_line
		(start 371.250464 -119.226584)
		(end 371.362732 -119.226584)
		(stroke
			(width 0.04445)
			(type default)
		)
		(layer "F.Cu")
	)
	(gr_line
		(start 371.25529 -125.97384)
		(end 371.444012 -125.785118)
		(stroke
			(width 0.04445)
			(type default)
		)
		(layer "F.Cu")
	)
	(gr_line
		(start 371.259608 -111.60379)
		(end 371.37467 -111.718852)
		(stroke
			(width 0.04445)
			(type default)
		)
		(layer "F.Cu")
	)
	(gr_line
		(start 371.259608 -111.464598)
		(end 371.259608 -111.60379)
		(stroke
			(width 0.04445)
			(type default)
		)
		(layer "F.Cu")
	)
	(gr_line
		(start 371.286786 -120.810782)
		(end 371.383306 -120.714262)
		(stroke
			(width 0.04445)
			(type default)
		)
		(layer "F.Cu")
	)
	(gr_line
		(start 371.2972 -118.237)
		(end 371.392704 -118.237)
		(stroke
			(width 0.04445)
			(type default)
		)
		(layer "F.Cu")
	)
	(gr_line
		(start 371.2972 -116.7892)
		(end 371.392704 -116.7892)
		(stroke
			(width 0.04445)
			(type default)
		)
		(layer "F.Cu")
	)
	(gr_line
		(start 371.2972 -115.3414)
		(end 371.423184 -115.3414)
		(stroke
			(width 0.04445)
			(type default)
		)
		(layer "F.Cu")
	)
	(gr_line
		(start 371.29847 -105.58653)
		(end 371.43817 -105.58653)
		(stroke
			(width 0.04445)
			(type default)
		)
		(layer "F.Cu")
	)
	(gr_line
		(start 371.300502 -20.533868)
		(end 371.30355 -20.518882)
		(stroke
			(width 0.05715)
			(type default)
		)
		(layer "F.Cu")
	)
	(gr_line
		(start 371.300502 -20.503896)
		(end 371.30355 -20.518882)
		(stroke
			(width 0.05715)
			(type default)
		)
		(layer "F.Cu")
	)
	(gr_line
		(start 371.307106 -17.052798)
		(end 371.501416 -16.588486)
		(stroke
			(width 0.05715)
			(type default)
		)
		(layer "F.Cu")
	)
	(gr_line
		(start 371.3099 -23.888446)
		(end 371.312694 -23.902416)
		(stroke
			(width 0.05715)
			(type default)
		)
		(layer "F.Cu")
	)
	(gr_line
		(start 371.310154 -23.915624)
		(end 371.312694 -23.902416)
		(stroke
			(width 0.05715)
			(type default)
		)
		(layer "F.Cu")
	)
	(gr_line
		(start 371.314472 -120.298718)
		(end 371.581172 -120.298718)
		(stroke
			(width 0.04445)
			(type default)
		)
		(layer "F.Cu")
	)
	(gr_line
		(start 371.31879 -110.572296)
		(end 371.59184 -110.572296)
		(stroke
			(width 0.04445)
			(type default)
		)
		(layer "F.Cu")
	)
	(gr_line
		(start 371.320822 -117.741446)
		(end 371.336824 -117.741446)
		(stroke
			(width 0.04445)
			(type default)
		)
		(layer "F.Cu")
	)
	(gr_line
		(start 371.320822 -116.293646)
		(end 371.336824 -116.293646)
		(stroke
			(width 0.04445)
			(type default)
		)
		(layer "F.Cu")
	)
	(gr_line
		(start 371.337586 -113.861088)
		(end 371.515386 -113.861088)
		(stroke
			(width 0.04445)
			(type default)
		)
		(layer "F.Cu")
	)
	(gr_line
		(start 371.339364 -113.188496)
		(end 371.517164 -113.188496)
		(stroke
			(width 0.04445)
			(type default)
		)
		(layer "F.Cu")
	)
	(gr_line
		(start 371.365018 -122.464576)
		(end 371.412262 -122.3518)
		(stroke
			(width 0.04445)
			(type default)
		)
		(layer "F.Cu")
	)
	(gr_line
		(start 371.365272 -119.226584)
		(end 371.374162 -119.226584)
		(stroke
			(width 0.04445)
			(type default)
		)
		(layer "F.Cu")
	)
	(gr_line
		(start 371.37467 -111.718852)
		(end 371.513862 -111.718852)
		(stroke
			(width 0.04445)
			(type default)
		)
		(layer "F.Cu")
	)
	(gr_line
		(start 371.381274 -109.96803)
		(end 371.78234 -110.369096)
		(stroke
			(width 0.04445)
			(type default)
		)
		(layer "F.Cu")
	)
	(gr_line
		(start 371.381274 -109.944154)
		(end 371.381274 -109.96803)
		(stroke
			(width 0.04445)
			(type default)
		)
		(layer "F.Cu")
	)
	(gr_line
		(start 371.392704 -118.237)
		(end 371.694964 -118.53926)
		(stroke
			(width 0.04445)
			(type default)
		)
		(layer "F.Cu")
	)
	(gr_line
		(start 371.392704 -116.7892)
		(end 371.694964 -117.09146)
		(stroke
			(width 0.04445)
			(type default)
		)
		(layer "F.Cu")
	)
	(gr_line
		(start 371.40134 -119.8118)
		(end 371.4877 -119.72544)
		(stroke
			(width 0.04445)
			(type default)
		)
		(layer "F.Cu")
	)
	(gr_line
		(start 371.418612 -120.019318)
		(end 371.477032 -120.019318)
		(stroke
			(width 0.04445)
			(type default)
		)
		(layer "F.Cu")
	)
	(gr_line
		(start 371.423184 -115.3414)
		(end 371.59946 -115.517676)
		(stroke
			(width 0.04445)
			(type default)
		)
		(layer "F.Cu")
	)
	(gr_line
		(start 371.444012 -125.662944)
		(end 371.444012 -125.785118)
		(stroke
			(width 0.04445)
			(type default)
		)
		(layer "F.Cu")
	)
	(gr_line
		(start 371.461284 -123.442476)
		(end 371.502686 -123.401074)
		(stroke
			(width 0.04445)
			(type default)
		)
		(layer "F.Cu")
	)
	(gr_line
		(start 371.463062 -123.713748)
		(end 371.585236 -123.713748)
		(stroke
			(width 0.04445)
			(type default)
		)
		(layer "F.Cu")
	)
	(gr_line
		(start 371.511322 -117.64645)
		(end 371.527324 -117.64645)
		(stroke
			(width 0.04445)
			(type default)
		)
		(layer "F.Cu")
	)
	(gr_line
		(start 371.511322 -116.19865)
		(end 371.527324 -116.19865)
		(stroke
			(width 0.04445)
			(type default)
		)
		(layer "F.Cu")
	)
	(gr_line
		(start 371.515132 -112.469676)
		(end 371.603524 -112.558068)
		(stroke
			(width 0.04445)
			(type default)
		)
		(layer "F.Cu")
	)
	(gr_line
		(start 371.515386 -113.861088)
		(end 371.614192 -113.762282)
		(stroke
			(width 0.04445)
			(type default)
		)
		(layer "F.Cu")
	)
	(gr_line
		(start 371.517164 -113.188496)
		(end 371.615716 -113.089944)
		(stroke
			(width 0.04445)
			(type default)
		)
		(layer "F.Cu")
	)
	(gr_line
		(start 371.519196 -42.330116)
		(end 371.527578 -42.305478)
		(stroke
			(width 0.05715)
			(type default)
		)
		(layer "F.Cu")
	)
	(gr_line
		(start 371.522498 -126.419102)
		(end 371.5639 -126.3777)
		(stroke
			(width 0.04445)
			(type default)
		)
		(layer "F.Cu")
	)
	(gr_line
		(start 371.522752 -42.279062)
		(end 371.527578 -42.305478)
		(stroke
			(width 0.05715)
			(type default)
		)
		(layer "F.Cu")
	)
	(gr_line
		(start 371.524276 -126.690374)
		(end 371.64645 -126.690374)
		(stroke
			(width 0.04445)
			(type default)
		)
		(layer "F.Cu")
	)
	(gr_line
		(start 371.545612 -38.365684)
		(end 371.548406 -38.379654)
		(stroke
			(width 0.05715)
			(type default)
		)
		(layer "F.Cu")
	)
	(gr_line
		(start 371.545866 -38.392862)
		(end 371.548406 -38.379654)
		(stroke
			(width 0.05715)
			(type default)
		)
		(layer "F.Cu")
	)
	(gr_line
		(start 371.55501 -105.84307)
		(end 371.66804 -105.956354)
		(stroke
			(width 0.04445)
			(type default)
		)
		(layer "F.Cu")
	)
	(gr_line
		(start 371.55501 -105.70337)
		(end 371.55501 -105.84307)
		(stroke
			(width 0.04445)
			(type default)
		)
		(layer "F.Cu")
	)
	(gr_line
		(start 371.555772 -119.1387)
		(end 371.564662 -119.1387)
		(stroke
			(width 0.04445)
			(type default)
		)
		(layer "F.Cu")
	)
	(gr_line
		(start 371.581172 -120.298718)
		(end 371.667532 -120.212358)
		(stroke
			(width 0.04445)
			(type default)
		)
		(layer "F.Cu")
	)
	(gr_line
		(start 371.585236 -123.713748)
		(end 371.773958 -123.525026)
		(stroke
			(width 0.04445)
			(type default)
		)
		(layer "F.Cu")
	)
	(gr_line
		(start 371.59946 -115.589558)
		(end 371.686328 -115.676426)
		(stroke
			(width 0.04445)
			(type default)
		)
		(layer "F.Cu")
	)
	(gr_line
		(start 371.59946 -115.517676)
		(end 371.59946 -115.589558)
		(stroke
			(width 0.04445)
			(type default)
		)
		(layer "F.Cu")
	)
	(gr_line
		(start 371.603524 -112.558068)
		(end 371.781324 -112.558068)
		(stroke
			(width 0.04445)
			(type default)
		)
		(layer "F.Cu")
	)
	(gr_line
		(start 371.608858 -114.91595)
		(end 371.823742 -114.91595)
		(stroke
			(width 0.04445)
			(type default)
		)
		(layer "F.Cu")
	)
	(gr_line
		(start 371.616224 -122.059192)
		(end 371.970808 -121.913396)
		(stroke
			(width 0.04445)
			(type default)
		)
		(layer "F.Cu")
	)
	(gr_line
		(start 371.634258 -125.199648)
		(end 371.67566 -125.158246)
		(stroke
			(width 0.04445)
			(type default)
		)
		(layer "F.Cu")
	)
	(gr_line
		(start 371.636036 -125.47092)
		(end 371.75821 -125.47092)
		(stroke
			(width 0.04445)
			(type default)
		)
		(layer "F.Cu")
	)
	(gr_line
		(start 371.64645 -126.690374)
		(end 371.835172 -126.501652)
		(stroke
			(width 0.04445)
			(type default)
		)
		(layer "F.Cu")
	)
	(gr_line
		(start 371.649752 -3.488436)
		(end 371.88521 -3.723894)
		(stroke
			(width 0.05715)
			(type default)
		)
		(layer "F.Cu")
	)
	(gr_line
		(start 371.655086 -120.714262)
		(end 371.751606 -120.810782)
		(stroke
			(width 0.04445)
			(type default)
		)
		(layer "F.Cu")
	)
	(gr_line
		(start 371.663468 -122.248422)
		(end 371.776244 -122.295666)
		(stroke
			(width 0.04445)
			(type default)
		)
		(layer "F.Cu")
	)
	(gr_line
		(start 371.667786 -3.011678)
		(end 371.742462 -2.937002)
		(stroke
			(width 0.05715)
			(type default)
		)
		(layer "F.Cu")
	)
	(gr_line
		(start 371.66804 -105.956354)
		(end 371.807994 -105.956354)
		(stroke
			(width 0.04445)
			(type default)
		)
		(layer "F.Cu")
	)
	(gr_line
		(start 371.696742 -118.541038)
		(end 371.728746 -118.573042)
		(stroke
			(width 0.04445)
			(type default)
		)
		(layer "F.Cu")
	)
	(gr_line
		(start 371.696742 -117.093238)
		(end 371.728746 -117.125242)
		(stroke
			(width 0.04445)
			(type default)
		)
		(layer "F.Cu")
	)
	(gr_line
		(start 371.705124 -18.634456)
		(end 371.712744 -18.672556)
		(stroke
			(width 0.05715)
			(type default)
		)
		(layer "F.Cu")
	)
	(gr_line
		(start 371.705124 -18.634456)
		(end 371.720618 -18.597372)
		(stroke
			(width 0.05715)
			(type default)
		)
		(layer "F.Cu")
	)
	(gr_line
		(start 371.730016 -22.06498)
		(end 371.73281 -22.079204)
		(stroke
			(width 0.05715)
			(type default)
		)
		(layer "F.Cu")
	)
	(gr_line
		(start 371.730016 -22.06498)
		(end 371.733064 -22.050248)
		(stroke
			(width 0.05715)
			(type default)
		)
		(layer "F.Cu")
	)
	(gr_line
		(start 371.730016 -12.54379)
		(end 371.734588 -12.540742)
		(stroke
			(width 0.05715)
			(type default)
		)
		(layer "F.Cu")
	)
	(gr_line
		(start 371.734588 -12.540742)
		(end 371.738144 -12.536424)
		(stroke
			(width 0.05715)
			(type default)
		)
		(layer "F.Cu")
	)
	(gr_line
		(start 371.742462 -2.937002)
		(end 372.170198 -2.937002)
		(stroke
			(width 0.05715)
			(type default)
		)
		(layer "F.Cu")
	)
	(gr_line
		(start 371.751606 -120.810782)
		(end 372.018306 -120.810782)
		(stroke
			(width 0.04445)
			(type default)
		)
		(layer "F.Cu")
	)
	(gr_line
		(start 371.75821 -125.47092)
		(end 371.946932 -125.282198)
		(stroke
			(width 0.04445)
			(type default)
		)
		(layer "F.Cu")
	)
	(gr_line
		(start 371.75948 -119.72544)
		(end 371.84584 -119.8118)
		(stroke
			(width 0.04445)
			(type default)
		)
		(layer "F.Cu")
	)
	(gr_line
		(start 371.773958 -123.402852)
		(end 371.773958 -123.525026)
		(stroke
			(width 0.04445)
			(type default)
		)
		(layer "F.Cu")
	)
	(gr_line
		(start 371.776244 -122.295666)
		(end 372.022878 -122.19432)
		(stroke
			(width 0.04445)
			(type default)
		)
		(layer "F.Cu")
	)
	(gr_line
		(start 371.781324 -112.558068)
		(end 371.869716 -112.469676)
		(stroke
			(width 0.04445)
			(type default)
		)
		(layer "F.Cu")
	)
	(gr_line
		(start 371.785388 -121.7295)
		(end 371.790976 -121.72696)
		(stroke
			(width 0.04445)
			(type default)
		)
		(layer "F.Cu")
	)
	(gr_line
		(start 371.793516 -18.12671)
		(end 371.853714 -18.273014)
		(stroke
			(width 0.05715)
			(type default)
		)
		(layer "F.Cu")
	)
	(gr_line
		(start 371.793516 -18.12671)
		(end 371.92585 -17.810226)
		(stroke
			(width 0.05715)
			(type default)
		)
		(layer "F.Cu")
	)
	(gr_line
		(start 371.797072 -113.762282)
		(end 371.895878 -113.861088)
		(stroke
			(width 0.04445)
			(type default)
		)
		(layer "F.Cu")
	)
	(gr_line
		(start 371.798596 -113.089944)
		(end 371.897148 -113.188496)
		(stroke
			(width 0.04445)
			(type default)
		)
		(layer "F.Cu")
	)
	(gr_line
		(start 371.823488 -111.8362)
		(end 371.922294 -111.935006)
		(stroke
			(width 0.04445)
			(type default)
		)
		(layer "F.Cu")
	)
	(gr_line
		(start 371.835172 -126.379478)
		(end 371.835172 -126.501652)
		(stroke
			(width 0.04445)
			(type default)
		)
		(layer "F.Cu")
	)
	(gr_line
		(start 371.845586 -120.521222)
		(end 371.924326 -120.521222)
		(stroke
			(width 0.04445)
			(type default)
		)
		(layer "F.Cu")
	)
	(gr_line
		(start 371.84584 -119.8118)
		(end 372.11254 -119.8118)
		(stroke
			(width 0.04445)
			(type default)
		)
		(layer "F.Cu")
	)
	(gr_line
		(start 371.877844 -10.916158)
		(end 372.149878 -11.188192)
		(stroke
			(width 0.05715)
			(type default)
		)
		(layer "F.Cu")
	)
	(gr_line
		(start 371.877844 -10.027158)
		(end 372.149878 -9.755124)
		(stroke
			(width 0.05715)
			(type default)
		)
		(layer "F.Cu")
	)
	(gr_line
		(start 371.88521 -8.598154)
		(end 372.11254 -8.825484)
		(stroke
			(width 0.05715)
			(type default)
		)
		(layer "F.Cu")
	)
	(gr_line
		(start 371.88521 -7.789926)
		(end 371.88521 -8.598154)
		(stroke
			(width 0.05715)
			(type default)
		)
		(layer "F.Cu")
	)
	(gr_line
		(start 371.88521 -3.723894)
		(end 371.88521 -4.389882)
		(stroke
			(width 0.05715)
			(type default)
		)
		(layer "F.Cu")
	)
	(gr_line
		(start 371.895878 -113.861088)
		(end 372.073678 -113.861088)
		(stroke
			(width 0.04445)
			(type default)
		)
		(layer "F.Cu")
	)
	(gr_line
		(start 371.897148 -113.188496)
		(end 372.074948 -113.188496)
		(stroke
			(width 0.04445)
			(type default)
		)
		(layer "F.Cu")
	)
	(gr_line
		(start 371.9068 -114.615468)
		(end 372.014242 -114.72291)
		(stroke
			(width 0.04445)
			(type default)
		)
		(layer "F.Cu")
	)
	(gr_line
		(start 371.9068 -114.299238)
		(end 371.9068 -114.615468)
		(stroke
			(width 0.04445)
			(type default)
		)
		(layer "F.Cu")
	)
	(gr_line
		(start 371.919246 -118.588028)
		(end 371.968268 -118.63705)
		(stroke
			(width 0.04445)
			(type default)
		)
		(layer "F.Cu")
	)
	(gr_line
		(start 371.919246 -118.275354)
		(end 371.919246 -118.380002)
		(stroke
			(width 0.04445)
			(type default)
		)
		(layer "F.Cu")
	)
	(gr_line
		(start 371.919246 -118.275354)
		(end 371.9576 -118.237)
		(stroke
			(width 0.04445)
			(type default)
		)
		(layer "F.Cu")
	)
	(gr_line
		(start 371.919246 -117.140228)
		(end 371.968268 -117.18925)
		(stroke
			(width 0.04445)
			(type default)
		)
		(layer "F.Cu")
	)
	(gr_line
		(start 371.919246 -116.827554)
		(end 371.919246 -116.932202)
		(stroke
			(width 0.04445)
			(type default)
		)
		(layer "F.Cu")
	)
	(gr_line
		(start 371.919246 -116.827554)
		(end 371.9576 -116.7892)
		(stroke
			(width 0.04445)
			(type default)
		)
		(layer "F.Cu")
	)
	(gr_line
		(start 371.922294 -111.935006)
		(end 372.082314 -111.935006)
		(stroke
			(width 0.04445)
			(type default)
		)
		(layer "F.Cu")
	)
	(gr_line
		(start 371.92585 -17.810226)
		(end 372.072408 -17.750282)
		(stroke
			(width 0.05715)
			(type default)
		)
		(layer "F.Cu")
	)
	(gr_line
		(start 371.939312 -120.212358)
		(end 372.025672 -120.298718)
		(stroke
			(width 0.04445)
			(type default)
		)
		(layer "F.Cu")
	)
	(gr_line
		(start 371.9449 -124.360686)
		(end 371.9449 -124.419106)
		(stroke
			(width 0.04445)
			(type default)
		)
		(layer "F.Cu")
	)
	(gr_line
		(start 371.946932 -125.160024)
		(end 371.946932 -125.282198)
		(stroke
			(width 0.04445)
			(type default)
		)
		(layer "F.Cu")
	)
	(gr_line
		(start 371.94998 -119.5324)
		(end 372.0084 -119.5324)
		(stroke
			(width 0.04445)
			(type default)
		)
		(layer "F.Cu")
	)
	(gr_line
		(start 371.9576 -115.3414)
		(end 371.9576 -115.674648)
		(stroke
			(width 0.04445)
			(type default)
		)
		(layer "F.Cu")
	)
	(gr_line
		(start 371.964204 -122.939556)
		(end 372.005606 -122.898154)
		(stroke
			(width 0.04445)
			(type default)
		)
		(layer "F.Cu")
	)
	(gr_line
		(start 371.965982 -123.210828)
		(end 372.088156 -123.210828)
		(stroke
			(width 0.04445)
			(type default)
		)
		(layer "F.Cu")
	)
	(gr_line
		(start 371.97157 -118.82755)
		(end 372.009416 -118.865396)
		(stroke
			(width 0.04445)
			(type default)
		)
		(layer "F.Cu")
	)
	(gr_line
		(start 371.98173 -117.37975)
		(end 372.014496 -117.412516)
		(stroke
			(width 0.04445)
			(type default)
		)
		(layer "F.Cu")
	)
	(gr_line
		(start 371.98427 -40.520874)
		(end 371.986048 -40.53078)
		(stroke
			(width 0.05715)
			(type default)
		)
		(layer "F.Cu")
	)
	(gr_line
		(start 371.98427 -40.520874)
		(end 371.986556 -40.509444)
		(stroke
			(width 0.05715)
			(type default)
		)
		(layer "F.Cu")
	)
	(gr_line
		(start 372.011194 -118.867174)
		(end 372.070884 -118.926864)
		(stroke
			(width 0.04445)
			(type default)
		)
		(layer "F.Cu")
	)
	(gr_line
		(start 372.016274 -117.414294)
		(end 372.05793 -117.45595)
		(stroke
			(width 0.04445)
			(type default)
		)
		(layer "F.Cu")
	)
	(gr_line
		(start 372.018306 -120.810782)
		(end 372.114826 -120.714262)
		(stroke
			(width 0.04445)
			(type default)
		)
		(layer "F.Cu")
	)
	(gr_line
		(start 372.022878 -122.19432)
		(end 372.070122 -122.08129)
		(stroke
			(width 0.04445)
			(type default)
		)
		(layer "F.Cu")
	)
	(gr_line
		(start 372.025418 -125.916182)
		(end 372.06682 -125.87478)
		(stroke
			(width 0.04445)
			(type default)
		)
		(layer "F.Cu")
	)
	(gr_line
		(start 372.025672 -120.298718)
		(end 372.292372 -120.298718)
		(stroke
			(width 0.04445)
			(type default)
		)
		(layer "F.Cu")
	)
	(gr_line
		(start 372.027196 -126.187454)
		(end 372.14937 -126.187454)
		(stroke
			(width 0.04445)
			(type default)
		)
		(layer "F.Cu")
	)
	(gr_line
		(start 372.039134 -14.677136)
		(end 372.053866 -14.642084)
		(stroke
			(width 0.05715)
			(type default)
		)
		(layer "F.Cu")
	)
	(gr_line
		(start 372.045484 -110.584996)
		(end 372.121684 -110.661196)
		(stroke
			(width 0.04445)
			(type default)
		)
		(layer "F.Cu")
	)
	(gr_line
		(start 372.052596 -112.469676)
		(end 372.140988 -112.558068)
		(stroke
			(width 0.04445)
			(type default)
		)
		(layer "F.Cu")
	)
	(gr_line
		(start 372.053866 -14.642084)
		(end 372.085362 -14.621256)
		(stroke
			(width 0.05715)
			(type default)
		)
		(layer "F.Cu")
	)
	(gr_line
		(start 372.05793 -117.45595)
		(end 372.261384 -117.45595)
		(stroke
			(width 0.04445)
			(type default)
		)
		(layer "F.Cu")
	)
	(gr_line
		(start 372.070884 -118.926864)
		(end 372.24843 -118.926864)
		(stroke
			(width 0.04445)
			(type default)
		)
		(layer "F.Cu")
	)
	(gr_line
		(start 372.073678 -113.861088)
		(end 372.172484 -113.762282)
		(stroke
			(width 0.04445)
			(type default)
		)
		(layer "F.Cu")
	)
	(gr_line
		(start 372.074948 -113.188496)
		(end 372.1735 -113.089944)
		(stroke
			(width 0.04445)
			(type default)
		)
		(layer "F.Cu")
	)
	(gr_line
		(start 372.082314 -111.935006)
		(end 372.18112 -111.8362)
		(stroke
			(width 0.04445)
			(type default)
		)
		(layer "F.Cu")
	)
	(gr_line
		(start 372.088156 -123.210828)
		(end 372.276878 -123.022106)
		(stroke
			(width 0.04445)
			(type default)
		)
		(layer "F.Cu")
	)
	(gr_line
		(start 372.091204 -18.337276)
		(end 372.28526 -17.873472)
		(stroke
			(width 0.05715)
			(type default)
		)
		(layer "F.Cu")
	)
	(gr_line
		(start 372.11254 -119.8118)
		(end 372.1989 -119.72544)
		(stroke
			(width 0.04445)
			(type default)
		)
		(layer "F.Cu")
	)
	(gr_line
		(start 372.121684 -110.661196)
		(end 372.388384 -110.661196)
		(stroke
			(width 0.04445)
			(type default)
		)
		(layer "F.Cu")
	)
	(gr_line
		(start 372.129812 -120.019318)
		(end 372.188232 -120.019318)
		(stroke
			(width 0.04445)
			(type default)
		)
		(layer "F.Cu")
	)
	(gr_line
		(start 372.129812 -106.071924)
		(end 372.228618 -106.17073)
		(stroke
			(width 0.04445)
			(type default)
		)
		(layer "F.Cu")
	)
	(gr_line
		(start 372.134638 -116.39169)
		(end 372.206774 -116.463826)
		(stroke
			(width 0.04445)
			(type default)
		)
		(layer "F.Cu")
	)
	(gr_line
		(start 372.13794 -124.609606)
		(end 372.2243 -124.523246)
		(stroke
			(width 0.04445)
			(type default)
		)
		(layer "F.Cu")
	)
	(gr_line
		(start 372.13794 -124.170186)
		(end 372.2243 -124.256546)
		(stroke
			(width 0.04445)
			(type default)
		)
		(layer "F.Cu")
	)
	(gr_line
		(start 372.140988 -112.558068)
		(end 372.318788 -112.558068)
		(stroke
			(width 0.04445)
			(type default)
		)
		(layer "F.Cu")
	)
	(gr_line
		(start 372.146322 -17.283176)
		(end 372.20652 -17.42948)
		(stroke
			(width 0.05715)
			(type default)
		)
		(layer "F.Cu")
	)
	(gr_line
		(start 372.146322 -17.283176)
		(end 372.278656 -16.966692)
		(stroke
			(width 0.05715)
			(type default)
		)
		(layer "F.Cu")
	)
	(gr_line
		(start 372.14937 -126.187454)
		(end 372.338092 -125.998732)
		(stroke
			(width 0.04445)
			(type default)
		)
		(layer "F.Cu")
	)
	(gr_line
		(start 372.151656 -117.83949)
		(end 372.217442 -117.905276)
		(stroke
			(width 0.04445)
			(type default)
		)
		(layer "F.Cu")
	)
	(gr_line
		(start 372.206774 -116.463826)
		(end 372.384574 -116.463826)
		(stroke
			(width 0.04445)
			(type default)
		)
		(layer "F.Cu")
	)
	(gr_line
		(start 372.217442 -117.905276)
		(end 372.395242 -117.905276)
		(stroke
			(width 0.04445)
			(type default)
		)
		(layer "F.Cu")
	)
	(gr_line
		(start 372.21795 -37.24402)
		(end 372.22049 -37.257228)
		(stroke
			(width 0.05715)
			(type default)
		)
		(layer "F.Cu")
	)
	(gr_line
		(start 372.21795 -37.24402)
		(end 372.220744 -37.23005)
		(stroke
			(width 0.05715)
			(type default)
		)
		(layer "F.Cu")
	)
	(gr_line
		(start 372.2243 -124.256546)
		(end 372.2243 -124.523246)
		(stroke
			(width 0.04445)
			(type default)
		)
		(layer "F.Cu")
	)
	(gr_line
		(start 372.228618 -106.17073)
		(end 372.388638 -106.17073)
		(stroke
			(width 0.04445)
			(type default)
		)
		(layer "F.Cu")
	)
	(gr_line
		(start 372.235984 -110.381796)
		(end 372.274084 -110.381796)
		(stroke
			(width 0.04445)
			(type default)
		)
		(layer "F.Cu")
	)
	(gr_line
		(start 372.24843 -118.926864)
		(end 372.345204 -118.83009)
		(stroke
			(width 0.04445)
			(type default)
		)
		(layer "F.Cu")
	)
	(gr_line
		(start 372.261384 -117.45595)
		(end 372.335044 -117.38229)
		(stroke
			(width 0.04445)
			(type default)
		)
		(layer "F.Cu")
	)
	(gr_line
		(start 372.272814 -121.78919)
		(end 372.628668 -121.642886)
		(stroke
			(width 0.04445)
			(type default)
		)
		(layer "F.Cu")
	)
	(gr_line
		(start 372.276878 -122.899932)
		(end 372.276878 -123.022106)
		(stroke
			(width 0.04445)
			(type default)
		)
		(layer "F.Cu")
	)
	(gr_line
		(start 372.278656 -16.966692)
		(end 372.42496 -16.906748)
		(stroke
			(width 0.05715)
			(type default)
		)
		(layer "F.Cu")
	)
	(gr_line
		(start 372.292372 -120.298718)
		(end 372.378732 -120.212358)
		(stroke
			(width 0.04445)
			(type default)
		)
		(layer "F.Cu")
	)
	(gr_line
		(start 372.306088 -20.446238)
		(end 372.309136 -20.431252)
		(stroke
			(width 0.05715)
			(type default)
		)
		(layer "F.Cu")
	)
	(gr_line
		(start 372.306088 -20.416266)
		(end 372.309136 -20.431252)
		(stroke
			(width 0.05715)
			(type default)
		)
		(layer "F.Cu")
	)
	(gr_line
		(start 372.318788 -112.558068)
		(end 372.40718 -112.469676)
		(stroke
			(width 0.04445)
			(type default)
		)
		(layer "F.Cu")
	)
	(gr_line
		(start 372.321074 -121.978166)
		(end 372.434104 -122.025156)
		(stroke
			(width 0.04445)
			(type default)
		)
		(layer "F.Cu")
	)
	(gr_line
		(start 372.330472 -23.835106)
		(end 372.333266 -23.849076)
		(stroke
			(width 0.05715)
			(type default)
		)
		(layer "F.Cu")
	)
	(gr_line
		(start 372.330726 -23.862284)
		(end 372.333266 -23.849076)
		(stroke
			(width 0.05715)
			(type default)
		)
		(layer "F.Cu")
	)
	(gr_line
		(start 372.338092 -125.876558)
		(end 372.338092 -125.998732)
		(stroke
			(width 0.04445)
			(type default)
		)
		(layer "F.Cu")
	)
	(gr_line
		(start 372.340632 -14.449298)
		(end 372.372128 -14.294358)
		(stroke
			(width 0.05715)
			(type default)
		)
		(layer "F.Cu")
	)
	(gr_line
		(start 372.34622 -111.8362)
		(end 372.445026 -111.935006)
		(stroke
			(width 0.04445)
			(type default)
		)
		(layer "F.Cu")
	)
	(gr_line
		(start 372.353332 -123.23572)
		(end 372.394734 -123.194318)
		(stroke
			(width 0.04445)
			(type default)
		)
		(layer "F.Cu")
	)
	(gr_line
		(start 372.35511 -123.506992)
		(end 372.477284 -123.506992)
		(stroke
			(width 0.04445)
			(type default)
		)
		(layer "F.Cu")
	)
	(gr_line
		(start 372.355364 -113.762282)
		(end 372.45417 -113.861088)
		(stroke
			(width 0.04445)
			(type default)
		)
		(layer "F.Cu")
	)
	(gr_line
		(start 372.35638 -113.089944)
		(end 372.454932 -113.188496)
		(stroke
			(width 0.04445)
			(type default)
		)
		(layer "F.Cu")
	)
	(gr_line
		(start 372.372128 -14.294358)
		(end 372.658132 -14.105382)
		(stroke
			(width 0.05715)
			(type default)
		)
		(layer "F.Cu")
	)
	(gr_line
		(start 372.384574 -116.463826)
		(end 372.45671 -116.39169)
		(stroke
			(width 0.04445)
			(type default)
		)
		(layer "F.Cu")
	)
	(gr_line
		(start 372.386606 -120.714262)
		(end 372.483126 -120.810782)
		(stroke
			(width 0.04445)
			(type default)
		)
		(layer "F.Cu")
	)
	(gr_line
		(start 372.388384 -110.661196)
		(end 372.464584 -110.584996)
		(stroke
			(width 0.04445)
			(type default)
		)
		(layer "F.Cu")
	)
	(gr_line
		(start 372.388638 -106.17073)
		(end 372.487444 -106.071924)
		(stroke
			(width 0.04445)
			(type default)
		)
		(layer "F.Cu")
	)
	(gr_line
		(start 372.395242 -117.905276)
		(end 372.461028 -117.83949)
		(stroke
			(width 0.04445)
			(type default)
		)
		(layer "F.Cu")
	)
	(gr_line
		(start 372.412768 -11.68146)
		(end 372.442994 -11.643106)
		(stroke
			(width 0.05715)
			(type default)
		)
		(layer "F.Cu")
	)
	(gr_line
		(start 372.434104 -122.025156)
		(end 372.680738 -121.92381)
		(stroke
			(width 0.04445)
			(type default)
		)
		(layer "F.Cu")
	)
	(gr_line
		(start 372.44401 -17.493488)
		(end 372.637812 -17.030446)
		(stroke
			(width 0.05715)
			(type default)
		)
		(layer "F.Cu")
	)
	(gr_line
		(start 372.445026 -111.935006)
		(end 372.605046 -111.935006)
		(stroke
			(width 0.04445)
			(type default)
		)
		(layer "F.Cu")
	)
	(gr_line
		(start 372.45417 -113.861088)
		(end 372.63197 -113.861088)
		(stroke
			(width 0.04445)
			(type default)
		)
		(layer "F.Cu")
	)
	(gr_line
		(start 372.454932 -113.188496)
		(end 372.632732 -113.188496)
		(stroke
			(width 0.04445)
			(type default)
		)
		(layer "F.Cu")
	)
	(gr_line
		(start 372.457472 -8.825484)
		(end 372.685056 -8.5979)
		(stroke
			(width 0.05715)
			(type default)
		)
		(layer "F.Cu")
	)
	(gr_line
		(start 372.467124 -122.436636)
		(end 372.508526 -122.395234)
		(stroke
			(width 0.04445)
			(type default)
		)
		(layer "F.Cu")
	)
	(gr_line
		(start 372.468902 -122.707908)
		(end 372.591076 -122.707908)
		(stroke
			(width 0.04445)
			(type default)
		)
		(layer "F.Cu")
	)
	(gr_line
		(start 372.47068 -119.72544)
		(end 372.55704 -119.8118)
		(stroke
			(width 0.04445)
			(type default)
		)
		(layer "F.Cu")
	)
	(gr_line
		(start 372.477284 -123.506992)
		(end 372.666006 -123.31827)
		(stroke
			(width 0.04445)
			(type default)
		)
		(layer "F.Cu")
	)
	(gr_line
		(start 372.483126 -120.810782)
		(end 372.749826 -120.810782)
		(stroke
			(width 0.04445)
			(type default)
		)
		(layer "F.Cu")
	)
	(gr_line
		(start 372.49481 -11.188192)
		(end 372.766844 -10.916158)
		(stroke
			(width 0.05715)
			(type default)
		)
		(layer "F.Cu")
	)
	(gr_line
		(start 372.49481 -9.755124)
		(end 372.766844 -10.027158)
		(stroke
			(width 0.05715)
			(type default)
		)
		(layer "F.Cu")
	)
	(gr_line
		(start 372.499128 -16.439642)
		(end 372.559326 -16.585946)
		(stroke
			(width 0.05715)
			(type default)
		)
		(layer "F.Cu")
	)
	(gr_line
		(start 372.499128 -16.439642)
		(end 372.631462 -16.123158)
		(stroke
			(width 0.05715)
			(type default)
		)
		(layer "F.Cu")
	)
	(gr_line
		(start 372.502684 -14.634464)
		(end 372.920006 -14.358366)
		(stroke
			(width 0.05715)
			(type default)
		)
		(layer "F.Cu")
	)
	(gr_line
		(start 372.511574 -118.83009)
		(end 372.608348 -118.926864)
		(stroke
			(width 0.04445)
			(type default)
		)
		(layer "F.Cu")
	)
	(gr_line
		(start 372.511574 -117.38229)
		(end 372.585234 -117.45595)
		(stroke
			(width 0.04445)
			(type default)
		)
		(layer "F.Cu")
	)
	(gr_line
		(start 372.528338 -125.413262)
		(end 372.56974 -125.37186)
		(stroke
			(width 0.04445)
			(type default)
		)
		(layer "F.Cu")
	)
	(gr_line
		(start 372.530116 -125.684534)
		(end 372.65229 -125.684534)
		(stroke
			(width 0.04445)
			(type default)
		)
		(layer "F.Cu")
	)
	(gr_line
		(start 372.55704 -119.8118)
		(end 372.82374 -119.8118)
		(stroke
			(width 0.04445)
			(type default)
		)
		(layer "F.Cu")
	)
	(gr_line
		(start 372.563644 -42.46372)
		(end 372.572026 -42.439082)
		(stroke
			(width 0.05715)
			(type default)
		)
		(layer "F.Cu")
	)
	(gr_line
		(start 372.5672 -42.41292)
		(end 372.572026 -42.439082)
		(stroke
			(width 0.05715)
			(type default)
		)
		(layer "F.Cu")
	)
	(gr_line
		(start 372.577106 -120.521222)
		(end 372.655846 -120.521222)
		(stroke
			(width 0.04445)
			(type default)
		)
		(layer "F.Cu")
	)
	(gr_line
		(start 372.585234 -117.45595)
		(end 372.84025 -117.45595)
		(stroke
			(width 0.04445)
			(type default)
		)
		(layer "F.Cu")
	)
	(gr_line
		(start 372.59006 -112.469676)
		(end 372.678452 -112.558068)
		(stroke
			(width 0.04445)
			(type default)
		)
		(layer "F.Cu")
	)
	(gr_line
		(start 372.591076 -122.707908)
		(end 372.779798 -122.519186)
		(stroke
			(width 0.04445)
			(type default)
		)
		(layer "F.Cu")
	)
	(gr_line
		(start 372.605046 -111.935006)
		(end 372.703852 -111.8362)
		(stroke
			(width 0.04445)
			(type default)
		)
		(layer "F.Cu")
	)
	(gr_line
		(start 372.608348 -118.926864)
		(end 372.806976 -118.926864)
		(stroke
			(width 0.04445)
			(type default)
		)
		(layer "F.Cu")
	)
	(gr_line
		(start 372.631462 -16.123158)
		(end 372.777766 -16.063214)
		(stroke
			(width 0.05715)
			(type default)
		)
		(layer "F.Cu")
	)
	(gr_line
		(start 372.63197 -113.861088)
		(end 372.730776 -113.762282)
		(stroke
			(width 0.04445)
			(type default)
		)
		(layer "F.Cu")
	)
	(gr_line
		(start 372.632732 -113.188496)
		(end 372.731284 -113.089944)
		(stroke
			(width 0.04445)
			(type default)
		)
		(layer "F.Cu")
	)
	(gr_line
		(start 372.650512 -120.212358)
		(end 372.736872 -120.298718)
		(stroke
			(width 0.04445)
			(type default)
		)
		(layer "F.Cu")
	)
	(gr_line
		(start 372.65229 -125.684534)
		(end 372.841012 -125.495812)
		(stroke
			(width 0.04445)
			(type default)
		)
		(layer "F.Cu")
	)
	(gr_line
		(start 372.652544 -106.071924)
		(end 372.75135 -106.17073)
		(stroke
			(width 0.04445)
			(type default)
		)
		(layer "F.Cu")
	)
	(gr_line
		(start 372.658132 -14.105382)
		(end 372.812818 -14.136878)
		(stroke
			(width 0.05715)
			(type default)
		)
		(layer "F.Cu")
	)
	(gr_line
		(start 372.66118 -119.5324)
		(end 372.7196 -119.5324)
		(stroke
			(width 0.04445)
			(type default)
		)
		(layer "F.Cu")
	)
	(gr_line
		(start 372.666006 -123.196096)
		(end 372.666006 -123.31827)
		(stroke
			(width 0.04445)
			(type default)
		)
		(layer "F.Cu")
	)
	(gr_line
		(start 372.672102 -38.283642)
		(end 372.674896 -38.297612)
		(stroke
			(width 0.05715)
			(type default)
		)
		(layer "F.Cu")
	)
	(gr_line
		(start 372.672356 -38.31082)
		(end 372.674896 -38.297612)
		(stroke
			(width 0.05715)
			(type default)
		)
		(layer "F.Cu")
	)
	(gr_line
		(start 372.673626 -34.96564)
		(end 372.676166 -34.953194)
		(stroke
			(width 0.05715)
			(type default)
		)
		(layer "F.Cu")
	)
	(gr_line
		(start 372.676166 -34.953194)
		(end 372.683278 -34.94278)
		(stroke
			(width 0.05715)
			(type default)
		)
		(layer "F.Cu")
	)
	(gr_line
		(start 372.678452 -112.558068)
		(end 372.856252 -112.558068)
		(stroke
			(width 0.04445)
			(type default)
		)
		(layer "F.Cu")
	)
	(gr_line
		(start 372.680738 -121.92381)
		(end 372.727982 -121.811034)
		(stroke
			(width 0.04445)
			(type default)
		)
		(layer "F.Cu")
	)
	(gr_line
		(start 372.685056 -7.789926)
		(end 372.685056 -8.5979)
		(stroke
			(width 0.05715)
			(type default)
		)
		(layer "F.Cu")
	)
	(gr_line
		(start 372.702074 -118.63705)
		(end 372.82374 -118.63705)
		(stroke
			(width 0.04445)
			(type default)
		)
		(layer "F.Cu")
	)
	(gr_line
		(start 372.702074 -117.18925)
		(end 372.8339 -117.18925)
		(stroke
			(width 0.04445)
			(type default)
		)
		(layer "F.Cu")
	)
	(gr_line
		(start 372.736872 -120.298718)
		(end 373.003572 -120.298718)
		(stroke
			(width 0.04445)
			(type default)
		)
		(layer "F.Cu")
	)
	(gr_line
		(start 372.741952 -22.049994)
		(end 372.744746 -22.064218)
		(stroke
			(width 0.05715)
			(type default)
		)
		(layer "F.Cu")
	)
	(gr_line
		(start 372.741952 -22.049994)
		(end 372.745 -22.035262)
		(stroke
			(width 0.05715)
			(type default)
		)
		(layer "F.Cu")
	)
	(gr_line
		(start 372.749064 -18.73885)
		(end 372.756684 -18.777204)
		(stroke
			(width 0.05715)
			(type default)
		)
		(layer "F.Cu")
	)
	(gr_line
		(start 372.749064 -18.73885)
		(end 372.764304 -18.702528)
		(stroke
			(width 0.05715)
			(type default)
		)
		(layer "F.Cu")
	)
	(gr_line
		(start 372.749826 -120.810782)
		(end 372.846346 -120.714262)
		(stroke
			(width 0.04445)
			(type default)
		)
		(layer "F.Cu")
	)
	(gr_line
		(start 372.75135 -106.17073)
		(end 372.91137 -106.17073)
		(stroke
			(width 0.04445)
			(type default)
		)
		(layer "F.Cu")
	)
	(gr_line
		(start 372.764304 -18.702274)
		(end 372.764558 -18.701766)
		(stroke
			(width 0.05715)
			(type default)
		)
		(layer "F.Cu")
	)
	(gr_line
		(start 372.779798 -122.397012)
		(end 372.779798 -122.519186)
		(stroke
			(width 0.04445)
			(type default)
		)
		(layer "F.Cu")
	)
	(gr_line
		(start 372.796562 -16.650716)
		(end 372.990618 -16.186658)
		(stroke
			(width 0.05715)
			(type default)
		)
		(layer "F.Cu")
	)
	(gr_line
		(start 372.806976 -118.926864)
		(end 372.825518 -118.908322)
		(stroke
			(width 0.04445)
			(type default)
		)
		(layer "F.Cu")
	)
	(gr_line
		(start 372.82374 -119.8118)
		(end 372.9101 -119.72544)
		(stroke
			(width 0.04445)
			(type default)
		)
		(layer "F.Cu")
	)
	(gr_line
		(start 372.841012 -125.373638)
		(end 372.841012 -125.495812)
		(stroke
			(width 0.04445)
			(type default)
		)
		(layer "F.Cu")
	)
	(gr_line
		(start 372.841012 -120.019318)
		(end 372.899432 -120.019318)
		(stroke
			(width 0.04445)
			(type default)
		)
		(layer "F.Cu")
	)
	(gr_line
		(start 372.846854 -12.748006)
		(end 372.878604 -12.592558)
		(stroke
			(width 0.05715)
			(type default)
		)
		(layer "F.Cu")
	)
	(gr_line
		(start 372.856252 -122.7328)
		(end 372.897654 -122.691398)
		(stroke
			(width 0.04445)
			(type default)
		)
		(layer "F.Cu")
	)
	(gr_line
		(start 372.856252 -112.558068)
		(end 372.944644 -112.469676)
		(stroke
			(width 0.04445)
			(type default)
		)
		(layer "F.Cu")
	)
	(gr_line
		(start 372.85803 -123.004072)
		(end 372.980204 -123.004072)
		(stroke
			(width 0.04445)
			(type default)
		)
		(layer "F.Cu")
	)
	(gr_line
		(start 372.868952 -111.8362)
		(end 372.967758 -111.935006)
		(stroke
			(width 0.04445)
			(type default)
		)
		(layer "F.Cu")
	)
	(gr_line
		(start 372.878604 -12.592558)
		(end 373.164608 -12.403328)
		(stroke
			(width 0.05715)
			(type default)
		)
		(layer "F.Cu")
	)
	(gr_line
		(start 372.91137 -106.17073)
		(end 373.010176 -106.071924)
		(stroke
			(width 0.04445)
			(type default)
		)
		(layer "F.Cu")
	)
	(gr_line
		(start 372.913656 -113.762282)
		(end 373.012462 -113.861088)
		(stroke
			(width 0.04445)
			(type default)
		)
		(layer "F.Cu")
	)
	(gr_line
		(start 372.967758 -111.935006)
		(end 373.127778 -111.935006)
		(stroke
			(width 0.04445)
			(type default)
		)
		(layer "F.Cu")
	)
	(gr_line
		(start 372.980204 -123.004072)
		(end 373.168926 -122.81535)
		(stroke
			(width 0.04445)
			(type default)
		)
		(layer "F.Cu")
	)
	(gr_line
		(start 372.981728 -121.922032)
		(end 372.988332 -121.919238)
		(stroke
			(width 0.04445)
			(type default)
		)
		(layer "F.Cu")
	)
	(gr_line
		(start 372.993412 -115.146836)
		(end 373.119142 -115.272566)
		(stroke
			(width 0.04445)
			(type default)
		)
		(layer "F.Cu")
	)
	(gr_line
		(start 372.993412 -115.007898)
		(end 372.993412 -115.146836)
		(stroke
			(width 0.04445)
			(type default)
		)
		(layer "F.Cu")
	)
	(gr_line
		(start 373.003572 -120.298718)
		(end 373.089932 -120.212358)
		(stroke
			(width 0.04445)
			(type default)
		)
		(layer "F.Cu")
	)
	(gr_line
		(start 373.007128 -12.934442)
		(end 373.429276 -12.655042)
		(stroke
			(width 0.05715)
			(type default)
		)
		(layer "F.Cu")
	)
	(gr_line
		(start 373.012462 -113.861088)
		(end 373.190262 -113.861088)
		(stroke
			(width 0.04445)
			(type default)
		)
		(layer "F.Cu")
	)
	(gr_line
		(start 373.031258 -124.910342)
		(end 373.07266 -124.86894)
		(stroke
			(width 0.04445)
			(type default)
		)
		(layer "F.Cu")
	)
	(gr_line
		(start 373.033036 -125.181614)
		(end 373.15521 -125.181614)
		(stroke
			(width 0.04445)
			(type default)
		)
		(layer "F.Cu")
	)
	(gr_line
		(start 373.04345 -34.401506)
		(end 373.080788 -34.345372)
		(stroke
			(width 0.05715)
			(type default)
		)
		(layer "F.Cu")
	)
	(gr_line
		(start 373.080788 -34.345372)
		(end 373.147844 -34.332926)
		(stroke
			(width 0.05715)
			(type default)
		)
		(layer "F.Cu")
	)
	(gr_line
		(start 373.101362 -116.19865)
		(end 373.154956 -116.19865)
		(stroke
			(width 0.04445)
			(type default)
		)
		(layer "F.Cu")
	)
	(gr_line
		(start 373.10314 -13.944854)
		(end 373.134636 -13.789914)
		(stroke
			(width 0.05715)
			(type default)
		)
		(layer "F.Cu")
	)
	(gr_line
		(start 373.119142 -115.272566)
		(end 373.206264 -115.272566)
		(stroke
			(width 0.04445)
			(type default)
		)
		(layer "F.Cu")
	)
	(gr_line
		(start 373.127778 -111.935006)
		(end 373.226584 -111.8362)
		(stroke
			(width 0.04445)
			(type default)
		)
		(layer "F.Cu")
	)
	(gr_line
		(start 373.133366 -117.16639)
		(end 373.25554 -117.16639)
		(stroke
			(width 0.04445)
			(type default)
		)
		(layer "F.Cu")
	)
	(gr_line
		(start 373.134636 -13.789914)
		(end 373.42064 -13.600684)
		(stroke
			(width 0.05715)
			(type default)
		)
		(layer "F.Cu")
	)
	(gr_line
		(start 373.151908 -113.058194)
		(end 373.153432 -113.059718)
		(stroke
			(width 0.04445)
			(type default)
		)
		(layer "F.Cu")
	)
	(gr_line
		(start 373.15521 -125.181614)
		(end 373.343932 -124.992892)
		(stroke
			(width 0.04445)
			(type default)
		)
		(layer "F.Cu")
	)
	(gr_line
		(start 373.164608 -12.403328)
		(end 373.319802 -12.435078)
		(stroke
			(width 0.05715)
			(type default)
		)
		(layer "F.Cu")
	)
	(gr_line
		(start 373.168926 -122.693176)
		(end 373.168926 -122.81535)
		(stroke
			(width 0.04445)
			(type default)
		)
		(layer "F.Cu")
	)
	(gr_line
		(start 373.168926 -15.133828)
		(end 373.184674 -15.096236)
		(stroke
			(width 0.05715)
			(type default)
		)
		(layer "F.Cu")
	)
	(gr_line
		(start 373.175276 -106.071924)
		(end 373.274082 -106.17073)
		(stroke
			(width 0.04445)
			(type default)
		)
		(layer "F.Cu")
	)
	(gr_line
		(start 373.184674 -15.096236)
		(end 373.21871 -15.07363)
		(stroke
			(width 0.05715)
			(type default)
		)
		(layer "F.Cu")
	)
	(gr_line
		(start 373.190262 -113.861088)
		(end 373.289068 -113.762282)
		(stroke
			(width 0.04445)
			(type default)
		)
		(layer "F.Cu")
	)
	(gr_line
		(start 373.208804 -115.272566)
		(end 373.261636 -115.272566)
		(stroke
			(width 0.04445)
			(type default)
		)
		(layer "F.Cu")
	)
	(gr_line
		(start 373.224552 -1.419606)
		(end 373.624602 -1.419606)
		(stroke
			(width 0.05715)
			(type default)
		)
		(layer "F.Cu")
	)
	(gr_line
		(start 373.2276 -114.299238)
		(end 373.310912 -114.299238)
		(stroke
			(width 0.04445)
			(type default)
		)
		(layer "F.Cu")
	)
	(gr_line
		(start 373.229378 -113.250218)
		(end 373.230902 -113.251742)
		(stroke
			(width 0.04445)
			(type default)
		)
		(layer "F.Cu")
	)
	(gr_line
		(start 373.23268 -113.25352)
		(end 373.33047 -113.35131)
		(stroke
			(width 0.04445)
			(type default)
		)
		(layer "F.Cu")
	)
	(gr_line
		(start 373.249444 -122.339608)
		(end 373.256048 -122.336814)
		(stroke
			(width 0.04445)
			(type default)
		)
		(layer "F.Cu")
	)
	(gr_line
		(start 373.25554 -117.16639)
		(end 373.38127 -117.04066)
		(stroke
			(width 0.04445)
			(type default)
		)
		(layer "F.Cu")
	)
	(gr_line
		(start 373.26443 -14.130782)
		(end 373.684546 -13.852906)
		(stroke
			(width 0.05715)
			(type default)
		)
		(layer "F.Cu")
	)
	(gr_line
		(start 373.274082 -106.17073)
		(end 373.434102 -106.17073)
		(stroke
			(width 0.04445)
			(type default)
		)
		(layer "F.Cu")
	)
	(gr_line
		(start 373.291862 -116.331238)
		(end 373.345456 -116.331238)
		(stroke
			(width 0.04445)
			(type default)
		)
		(layer "F.Cu")
	)
	(gr_line
		(start 373.310912 -114.299238)
		(end 373.71401 -114.702336)
		(stroke
			(width 0.04445)
			(type default)
		)
		(layer "F.Cu")
	)
	(gr_line
		(start 373.322342 -20.41144)
		(end 373.32539 -20.396962)
		(stroke
			(width 0.05715)
			(type default)
		)
		(layer "F.Cu")
	)
	(gr_line
		(start 373.322342 -20.381976)
		(end 373.32539 -20.396962)
		(stroke
			(width 0.05715)
			(type default)
		)
		(layer "F.Cu")
	)
	(gr_line
		(start 373.33047 -113.35131)
		(end 373.50827 -113.35131)
		(stroke
			(width 0.04445)
			(type default)
		)
		(layer "F.Cu")
	)
	(gr_line
		(start 373.3419 -123.111768)
		(end 373.34444 -123.10618)
		(stroke
			(width 0.04445)
			(type default)
		)
		(layer "F.Cu")
	)
	(gr_line
		(start 373.343932 -124.870718)
		(end 373.343932 -124.992892)
		(stroke
			(width 0.04445)
			(type default)
		)
		(layer "F.Cu")
	)
	(gr_line
		(start 373.361712 -39.62019)
		(end 373.364252 -39.633398)
		(stroke
			(width 0.05715)
			(type default)
		)
		(layer "F.Cu")
	)
	(gr_line
		(start 373.361712 -39.62019)
		(end 373.364506 -39.60622)
		(stroke
			(width 0.05715)
			(type default)
		)
		(layer "F.Cu")
	)
	(gr_line
		(start 373.366538 -115.377468)
		(end 373.565928 -115.377468)
		(stroke
			(width 0.04445)
			(type default)
		)
		(layer "F.Cu")
	)
	(gr_line
		(start 373.369586 -110.931198)
		(end 373.445786 -111.007398)
		(stroke
			(width 0.04445)
			(type default)
		)
		(layer "F.Cu")
	)
	(gr_line
		(start 373.380254 -115.762278)
		(end 373.478806 -115.86083)
		(stroke
			(width 0.04445)
			(type default)
		)
		(layer "F.Cu")
	)
	(gr_line
		(start 373.38127 -116.918486)
		(end 373.38127 -117.04066)
		(stroke
			(width 0.04445)
			(type default)
		)
		(layer "F.Cu")
	)
	(gr_line
		(start 373.386858 -24.04237)
		(end 373.389652 -24.05634)
		(stroke
			(width 0.05715)
			(type default)
		)
		(layer "F.Cu")
	)
	(gr_line
		(start 373.387112 -24.069548)
		(end 373.389652 -24.05634)
		(stroke
			(width 0.05715)
			(type default)
		)
		(layer "F.Cu")
	)
	(gr_line
		(start 373.399304 -115.14074)
		(end 373.452136 -115.14074)
		(stroke
			(width 0.04445)
			(type default)
		)
		(layer "F.Cu")
	)
	(gr_line
		(start 373.42064 -13.600684)
		(end 373.575834 -13.63218)
		(stroke
			(width 0.05715)
			(type default)
		)
		(layer "F.Cu")
	)
	(gr_line
		(start 373.426228 -127.9906)
		(end 373.5451 -127.871728)
		(stroke
			(width 0.0508)
			(type default)
		)
		(layer "F.Cu")
	)
	(gr_line
		(start 373.429276 -122.900948)
		(end 373.432324 -122.893582)
		(stroke
			(width 0.04445)
			(type default)
		)
		(layer "F.Cu")
	)
	(gr_line
		(start 373.432324 -122.893582)
		(end 373.437912 -122.887994)
		(stroke
			(width 0.04445)
			(type default)
		)
		(layer "F.Cu")
	)
	(gr_line
		(start 373.434102 -106.17073)
		(end 373.532908 -106.071924)
		(stroke
			(width 0.04445)
			(type default)
		)
		(layer "F.Cu")
	)
	(gr_line
		(start 373.439182 -112.55883)
		(end 373.443246 -112.562894)
		(stroke
			(width 0.04445)
			(type default)
		)
		(layer "F.Cu")
	)
	(gr_line
		(start 373.445786 -111.007398)
		(end 373.712486 -111.007398)
		(stroke
			(width 0.04445)
			(type default)
		)
		(layer "F.Cu")
	)
	(gr_line
		(start 373.449342 -121.72823)
		(end 373.80418 -121.581164)
		(stroke
			(width 0.04445)
			(type default)
		)
		(layer "F.Cu")
	)
	(gr_line
		(start 373.471948 -113.762282)
		(end 373.570754 -113.861088)
		(stroke
			(width 0.04445)
			(type default)
		)
		(layer "F.Cu")
	)
	(gr_line
		(start 373.478806 -115.86083)
		(end 373.656606 -115.86083)
		(stroke
			(width 0.04445)
			(type default)
		)
		(layer "F.Cu")
	)
	(gr_line
		(start 373.485156 -3.70205)
		(end 373.485156 -4.389882)
		(stroke
			(width 0.05715)
			(type default)
		)
		(layer "F.Cu")
	)
	(gr_line
		(start 373.485156 -3.70205)
		(end 373.682514 -3.504692)
		(stroke
			(width 0.05715)
			(type default)
		)
		(layer "F.Cu")
	)
	(gr_line
		(start 373.497602 -121.917206)
		(end 373.610632 -121.963942)
		(stroke
			(width 0.04445)
			(type default)
		)
		(layer "F.Cu")
	)
	(gr_line
		(start 373.50827 -113.35131)
		(end 373.606822 -113.252758)
		(stroke
			(width 0.04445)
			(type default)
		)
		(layer "F.Cu")
	)
	(gr_line
		(start 373.514112 -112.753394)
		(end 373.518176 -112.757458)
		(stroke
			(width 0.04445)
			(type default)
		)
		(layer "F.Cu")
	)
	(gr_line
		(start 373.51462 -112.101884)
		(end 373.64035 -112.22736)
		(stroke
			(width 0.04445)
			(type default)
		)
		(layer "F.Cu")
	)
	(gr_line
		(start 373.51462 -111.962692)
		(end 373.51462 -112.101884)
		(stroke
			(width 0.04445)
			(type default)
		)
		(layer "F.Cu")
	)
	(gr_line
		(start 373.519954 -112.759236)
		(end 373.60352 -112.842802)
		(stroke
			(width 0.04445)
			(type default)
		)
		(layer "F.Cu")
	)
	(gr_line
		(start 373.53494 -124.377704)
		(end 373.63146 -124.281184)
		(stroke
			(width 0.04445)
			(type default)
		)
		(layer "F.Cu")
	)
	(gr_line
		(start 373.53494 -124.006864)
		(end 373.63146 -124.103384)
		(stroke
			(width 0.04445)
			(type default)
		)
		(layer "F.Cu")
	)
	(gr_line
		(start 373.53494 -123.823984)
		(end 373.63146 -123.727464)
		(stroke
			(width 0.04445)
			(type default)
		)
		(layer "F.Cu")
	)
	(gr_line
		(start 373.53494 -123.453144)
		(end 373.63146 -123.549664)
		(stroke
			(width 0.04445)
			(type default)
		)
		(layer "F.Cu")
	)
	(gr_line
		(start 373.542814 -120.569482)
		(end 373.556276 -120.56491)
		(stroke
			(width 0.04445)
			(type default)
		)
		(layer "F.Cu")
	)
	(gr_line
		(start 373.5451 -127.871728)
		(end 373.903494 -127.513334)
		(stroke
			(width 0.0635)
			(type default)
		)
		(layer "F.Cu")
	)
	(gr_line
		(start 373.55272 -128.2954)
		(end 373.8499 -127.99822)
		(stroke
			(width 0.0508)
			(type default)
		)
		(layer "F.Cu")
	)
	(gr_line
		(start 373.560086 -110.727998)
		(end 373.598186 -110.727998)
		(stroke
			(width 0.04445)
			(type default)
		)
		(layer "F.Cu")
	)
	(gr_line
		(start 373.565928 -115.377468)
		(end 373.609616 -115.33378)
		(stroke
			(width 0.04445)
			(type default)
		)
		(layer "F.Cu")
	)
	(gr_line
		(start 373.570246 -36.360862)
		(end 373.576342 -36.389564)
		(stroke
			(width 0.05715)
			(type default)
		)
		(layer "F.Cu")
	)
	(gr_line
		(start 373.570246 -36.360862)
		(end 373.579644 -36.332414)
		(stroke
			(width 0.05715)
			(type default)
		)
		(layer "F.Cu")
	)
	(gr_line
		(start 373.570754 -113.861088)
		(end 373.748554 -113.861088)
		(stroke
			(width 0.04445)
			(type default)
		)
		(layer "F.Cu")
	)
	(gr_line
		(start 373.60352 -112.842802)
		(end 373.78132 -112.842802)
		(stroke
			(width 0.04445)
			(type default)
		)
		(layer "F.Cu")
	)
	(gr_line
		(start 373.609362 -12.243308)
		(end 373.641112 -12.088114)
		(stroke
			(width 0.05715)
			(type default)
		)
		(layer "F.Cu")
	)
	(gr_line
		(start 373.610632 -121.963942)
		(end 373.857266 -121.861834)
		(stroke
			(width 0.04445)
			(type default)
		)
		(layer "F.Cu")
	)
	(gr_line
		(start 373.623332 -119.009414)
		(end 373.673624 -118.959122)
		(stroke
			(width 0.04445)
			(type default)
		)
		(layer "F.Cu")
	)
	(gr_line
		(start 373.624602 -1.419606)
		(end 373.687086 -1.48209)
		(stroke
			(width 0.05715)
			(type default)
		)
		(layer "F.Cu")
	)
	(gr_line
		(start 373.62511 -119.280686)
		(end 373.747284 -119.280686)
		(stroke
			(width 0.04445)
			(type default)
		)
		(layer "F.Cu")
	)
	(gr_line
		(start 373.63146 -124.103384)
		(end 373.63146 -124.281184)
		(stroke
			(width 0.04445)
			(type default)
		)
		(layer "F.Cu")
	)
	(gr_line
		(start 373.63146 -123.549664)
		(end 373.63146 -123.727464)
		(stroke
			(width 0.04445)
			(type default)
		)
		(layer "F.Cu")
	)
	(gr_line
		(start 373.64035 -112.22736)
		(end 373.779288 -112.22736)
		(stroke
			(width 0.04445)
			(type default)
		)
		(layer "F.Cu")
	)
	(gr_line
		(start 373.641112 -12.088114)
		(end 373.927116 -11.898884)
		(stroke
			(width 0.05715)
			(type default)
		)
		(layer "F.Cu")
	)
	(gr_line
		(start 373.656606 -115.86083)
		(end 373.755158 -115.762278)
		(stroke
			(width 0.04445)
			(type default)
		)
		(layer "F.Cu")
	)
	(gr_line
		(start 373.6721 -122.653806)
		(end 373.67718 -122.648726)
		(stroke
			(width 0.04445)
			(type default)
		)
		(layer "F.Cu")
	)
	(gr_line
		(start 373.67718 -122.648726)
		(end 373.683784 -122.645932)
		(stroke
			(width 0.04445)
			(type default)
		)
		(layer "F.Cu")
	)
	(gr_line
		(start 373.698008 -106.071924)
		(end 373.796814 -106.17073)
		(stroke
			(width 0.04445)
			(type default)
		)
		(layer "F.Cu")
	)
	(gr_line
		(start 373.711978 -48.443642)
		(end 373.718074 -48.439324)
		(stroke
			(width 0.05715)
			(type default)
		)
		(layer "F.Cu")
	)
	(gr_line
		(start 373.712486 -111.007398)
		(end 373.788686 -110.931198)
		(stroke
			(width 0.04445)
			(type default)
		)
		(layer "F.Cu")
	)
	(gr_line
		(start 373.71401 -114.702336)
		(end 373.880634 -114.702336)
		(stroke
			(width 0.04445)
			(type default)
		)
		(layer "F.Cu")
	)
	(gr_line
		(start 373.718074 -48.439324)
		(end 373.72544 -48.437292)
		(stroke
			(width 0.05715)
			(type default)
		)
		(layer "F.Cu")
	)
	(gr_line
		(start 373.747284 -119.280686)
		(end 373.944896 -119.083074)
		(stroke
			(width 0.04445)
			(type default)
		)
		(layer "F.Cu")
	)
	(gr_line
		(start 373.748554 -113.861088)
		(end 373.84736 -113.762282)
		(stroke
			(width 0.04445)
			(type default)
		)
		(layer "F.Cu")
	)
	(gr_line
		(start 373.751094 -115.33378)
		(end 373.795544 -115.37823)
		(stroke
			(width 0.04445)
			(type default)
		)
		(layer "F.Cu")
	)
	(gr_line
		(start 373.769382 -35.759898)
		(end 373.783098 -35.717988)
		(stroke
			(width 0.05715)
			(type default)
		)
		(layer "F.Cu")
	)
	(gr_line
		(start 373.769636 -12.429744)
		(end 374.190006 -12.151614)
		(stroke
			(width 0.05715)
			(type default)
		)
		(layer "F.Cu")
	)
	(gr_line
		(start 373.78132 -112.842802)
		(end 373.868188 -112.755934)
		(stroke
			(width 0.04445)
			(type default)
		)
		(layer "F.Cu")
	)
	(gr_line
		(start 373.783098 -35.717988)
		(end 373.819166 -35.69208)
		(stroke
			(width 0.05715)
			(type default)
		)
		(layer "F.Cu")
	)
	(gr_line
		(start 373.785892 -120.900952)
		(end 373.792496 -120.898158)
		(stroke
			(width 0.04445)
			(type default)
		)
		(layer "F.Cu")
	)
	(gr_line
		(start 373.789702 -113.252758)
		(end 373.888254 -113.35131)
		(stroke
			(width 0.04445)
			(type default)
		)
		(layer "F.Cu")
	)
	(gr_line
		(start 373.793004 -18.843498)
		(end 373.800624 -18.881852)
		(stroke
			(width 0.05715)
			(type default)
		)
		(layer "F.Cu")
	)
	(gr_line
		(start 373.793004 -18.843498)
		(end 373.808244 -18.807176)
		(stroke
			(width 0.05715)
			(type default)
		)
		(layer "F.Cu")
	)
	(gr_line
		(start 373.795544 -115.37823)
		(end 373.973344 -115.37823)
		(stroke
			(width 0.04445)
			(type default)
		)
		(layer "F.Cu")
	)
	(gr_line
		(start 373.796814 -106.17073)
		(end 373.956834 -106.17073)
		(stroke
			(width 0.04445)
			(type default)
		)
		(layer "F.Cu")
	)
	(gr_line
		(start 373.799862 -22.101302)
		(end 373.802402 -22.11451)
		(stroke
			(width 0.05715)
			(type default)
		)
		(layer "F.Cu")
	)
	(gr_line
		(start 373.799862 -22.101302)
		(end 373.802656 -22.087332)
		(stroke
			(width 0.05715)
			(type default)
		)
		(layer "F.Cu")
	)
	(gr_line
		(start 373.808244 -18.806922)
		(end 373.808498 -18.806414)
		(stroke
			(width 0.05715)
			(type default)
		)
		(layer "F.Cu")
	)
	(gr_line
		(start 373.82831 -48.66005)
		(end 373.83593 -48.658018)
		(stroke
			(width 0.05715)
			(type default)
		)
		(layer "F.Cu")
	)
	(gr_line
		(start 373.83593 -48.658018)
		(end 373.842788 -48.653446)
		(stroke
			(width 0.05715)
			(type default)
		)
		(layer "F.Cu")
	)
	(gr_line
		(start 373.8499 -127.99822)
		(end 374.208294 -127.639826)
		(stroke
			(width 0.0635)
			(type default)
		)
		(layer "F.Cu")
	)
	(gr_line
		(start 373.857266 -121.861834)
		(end 373.904002 -121.749058)
		(stroke
			(width 0.04445)
			(type default)
		)
		(layer "F.Cu")
	)
	(gr_line
		(start 373.858536 -48.351186)
		(end 373.866156 -48.346106)
		(stroke
			(width 0.05715)
			(type default)
		)
		(layer "F.Cu")
	)
	(gr_line
		(start 373.865902 -13.44041)
		(end 373.897398 -13.28547)
		(stroke
			(width 0.05715)
			(type default)
		)
		(layer "F.Cu")
	)
	(gr_line
		(start 373.866156 -48.346106)
		(end 373.875046 -48.34382)
		(stroke
			(width 0.05715)
			(type default)
		)
		(layer "F.Cu")
	)
	(gr_line
		(start 373.880634 -114.702336)
		(end 373.97309 -114.794792)
		(stroke
			(width 0.04445)
			(type default)
		)
		(layer "F.Cu")
	)
	(gr_line
		(start 373.888 -114.299238)
		(end 374.100598 -114.511836)
		(stroke
			(width 0.04445)
			(type default)
		)
		(layer "F.Cu")
	)
	(gr_line
		(start 373.888254 -113.35131)
		(end 374.066054 -113.35131)
		(stroke
			(width 0.04445)
			(type default)
		)
		(layer "F.Cu")
	)
	(gr_line
		(start 373.897398 -13.28547)
		(end 374.183148 -13.09624)
		(stroke
			(width 0.05715)
			(type default)
		)
		(layer "F.Cu")
	)
	(gr_line
		(start 373.903494 -127.324612)
		(end 373.903494 -127.513334)
		(stroke
			(width 0.0635)
			(type default)
		)
		(layer "F.Cu")
	)
	(gr_line
		(start 373.903494 -127.324612)
		(end 373.960644 -127.267462)
		(stroke
			(width 0.04445)
			(type default)
		)
		(layer "F.Cu")
	)
	(gr_line
		(start 373.927116 -11.898884)
		(end 374.08231 -11.93038)
		(stroke
			(width 0.05715)
			(type default)
		)
		(layer "F.Cu")
	)
	(gr_line
		(start 373.931434 -121.313702)
		(end 373.938292 -121.310908)
		(stroke
			(width 0.04445)
			(type default)
		)
		(layer "F.Cu")
	)
	(gr_line
		(start 373.933974 -15.90548)
		(end 373.948706 -15.869666)
		(stroke
			(width 0.05715)
			(type default)
		)
		(layer "F.Cu")
	)
	(gr_line
		(start 373.938038 -115.762278)
		(end 374.03659 -115.86083)
		(stroke
			(width 0.04445)
			(type default)
		)
		(layer "F.Cu")
	)
	(gr_line
		(start 373.944896 -118.9609)
		(end 373.944896 -119.083074)
		(stroke
			(width 0.04445)
			(type default)
		)
		(layer "F.Cu")
	)
	(gr_line
		(start 373.94642 -126.195582)
		(end 373.960644 -126.209806)
		(stroke
			(width 0.04445)
			(type default)
		)
		(layer "F.Cu")
	)
	(gr_line
		(start 373.94642 -125.838204)
		(end 373.94642 -126.195582)
		(stroke
			(width 0.04445)
			(type default)
		)
		(layer "F.Cu")
	)
	(gr_line
		(start 373.94642 -125.838204)
		(end 374.217184 -125.184662)
		(stroke
			(width 0.04445)
			(type default)
		)
		(layer "F.Cu")
	)
	(gr_line
		(start 373.948706 -15.869666)
		(end 373.981726 -15.847822)
		(stroke
			(width 0.05715)
			(type default)
		)
		(layer "F.Cu")
	)
	(gr_line
		(start 373.956834 -106.17073)
		(end 374.05564 -106.071924)
		(stroke
			(width 0.04445)
			(type default)
		)
		(layer "F.Cu")
	)
	(gr_line
		(start 373.958866 -41.451784)
		(end 373.968518 -41.422828)
		(stroke
			(width 0.05715)
			(type default)
		)
		(layer "F.Cu")
	)
	(gr_line
		(start 373.960644 -126.417324)
		(end 373.960644 -127.267462)
		(stroke
			(width 0.04445)
			(type default)
		)
		(layer "F.Cu")
	)
	(gr_line
		(start 373.960644 -126.209806)
		(end 373.960644 -127.267462)
		(stroke
			(width 0.04445)
			(type default)
		)
		(layer "F.Cu")
	)
	(gr_line
		(start 373.962422 -41.392856)
		(end 373.968518 -41.422828)
		(stroke
			(width 0.05715)
			(type default)
		)
		(layer "F.Cu")
	)
	(gr_line
		(start 373.97309 -114.794792)
		(end 374.15089 -114.794792)
		(stroke
			(width 0.04445)
			(type default)
		)
		(layer "F.Cu")
	)
	(gr_line
		(start 373.973344 -115.37823)
		(end 374.017794 -115.33378)
		(stroke
			(width 0.04445)
			(type default)
		)
		(layer "F.Cu")
	)
	(gr_line
		(start 373.991378 -116.762276)
		(end 374.08993 -116.860828)
		(stroke
			(width 0.04445)
			(type default)
		)
		(layer "F.Cu")
	)
	(gr_line
		(start 374.026684 -13.626338)
		(end 374.446038 -13.348716)
		(stroke
			(width 0.05715)
			(type default)
		)
		(layer "F.Cu")
	)
	(gr_line
		(start 374.027446 -3.504692)
		(end 374.285002 -3.762248)
		(stroke
			(width 0.05715)
			(type default)
		)
		(layer "F.Cu")
	)
	(gr_line
		(start 374.03024 -113.762282)
		(end 374.129046 -113.861088)
		(stroke
			(width 0.04445)
			(type default)
		)
		(layer "F.Cu")
	)
	(gr_line
		(start 374.032018 -1.48209)
		(end 374.094502 -1.419606)
		(stroke
			(width 0.05715)
			(type default)
		)
		(layer "F.Cu")
	)
	(gr_line
		(start 374.03659 -115.86083)
		(end 374.21439 -115.86083)
		(stroke
			(width 0.04445)
			(type default)
		)
		(layer "F.Cu")
	)
	(gr_line
		(start 374.038622 -37.433504)
		(end 374.04167 -37.447982)
		(stroke
			(width 0.05715)
			(type default)
		)
		(layer "F.Cu")
	)
	(gr_line
		(start 374.038876 -37.461952)
		(end 374.04167 -37.447982)
		(stroke
			(width 0.05715)
			(type default)
		)
		(layer "F.Cu")
	)
	(gr_line
		(start 374.051068 -112.755934)
		(end 374.137936 -112.842802)
		(stroke
			(width 0.04445)
			(type default)
		)
		(layer "F.Cu")
	)
	(gr_line
		(start 374.066054 -113.35131)
		(end 374.164606 -113.252758)
		(stroke
			(width 0.04445)
			(type default)
		)
		(layer "F.Cu")
	)
	(gr_line
		(start 374.08993 -116.860828)
		(end 374.26773 -116.860828)
		(stroke
			(width 0.04445)
			(type default)
		)
		(layer "F.Cu")
	)
	(gr_line
		(start 374.094502 -1.419606)
		(end 374.494552 -1.419606)
		(stroke
			(width 0.05715)
			(type default)
		)
		(layer "F.Cu")
	)
	(gr_line
		(start 374.11025 -117.762274)
		(end 374.189752 -117.841776)
		(stroke
			(width 0.04445)
			(type default)
		)
		(layer "F.Cu")
	)
	(gr_line
		(start 374.116092 -49.33696)
		(end 374.12295 -49.332388)
		(stroke
			(width 0.05715)
			(type default)
		)
		(layer "F.Cu")
	)
	(gr_line
		(start 374.12295 -49.332388)
		(end 374.13057 -49.330356)
		(stroke
			(width 0.05715)
			(type default)
		)
		(layer "F.Cu")
	)
	(gr_line
		(start 374.129046 -113.861088)
		(end 374.306846 -113.861088)
		(stroke
			(width 0.04445)
			(type default)
		)
		(layer "F.Cu")
	)
	(gr_line
		(start 374.137936 -112.842802)
		(end 374.315736 -112.842802)
		(stroke
			(width 0.04445)
			(type default)
		)
		(layer "F.Cu")
	)
	(gr_line
		(start 374.145048 -121.646442)
		(end 374.151652 -121.643648)
		(stroke
			(width 0.04445)
			(type default)
		)
		(layer "F.Cu")
	)
	(gr_line
		(start 374.14708 -117.333776)
		(end 374.192038 -117.378734)
		(stroke
			(width 0.04445)
			(type default)
		)
		(layer "F.Cu")
	)
	(gr_line
		(start 374.14708 -116.333778)
		(end 374.192038 -116.378736)
		(stroke
			(width 0.04445)
			(type default)
		)
		(layer "F.Cu")
	)
	(gr_line
		(start 374.147334 -118.333774)
		(end 374.192038 -118.378478)
		(stroke
			(width 0.04445)
			(type default)
		)
		(layer "F.Cu")
	)
	(gr_line
		(start 374.15089 -114.794792)
		(end 374.240806 -114.704876)
		(stroke
			(width 0.04445)
			(type default)
		)
		(layer "F.Cu")
	)
	(gr_line
		(start 374.151144 -127.267462)
		(end 374.208294 -127.324612)
		(stroke
			(width 0.04445)
			(type default)
		)
		(layer "F.Cu")
	)
	(gr_line
		(start 374.151144 -126.732284)
		(end 374.151144 -127.267462)
		(stroke
			(width 0.04445)
			(type default)
		)
		(layer "F.Cu")
	)
	(gr_line
		(start 374.151144 -126.732284)
		(end 374.275604 -126.607824)
		(stroke
			(width 0.04445)
			(type default)
		)
		(layer "F.Cu")
	)
	(gr_line
		(start 374.151144 -126.732284)
		(end 374.750838 -126.13259)
		(stroke
			(width 0.04445)
			(type default)
		)
		(layer "F.Cu")
	)
	(gr_line
		(start 374.170194 -115.33378)
		(end 374.214644 -115.37823)
		(stroke
			(width 0.04445)
			(type default)
		)
		(layer "F.Cu")
	)
	(gr_line
		(start 374.17121 -122.164094)
		(end 374.177814 -122.1613)
		(stroke
			(width 0.04445)
			(type default)
		)
		(layer "F.Cu")
	)
	(gr_line
		(start 374.183148 -13.09624)
		(end 374.338342 -13.127736)
		(stroke
			(width 0.05715)
			(type default)
		)
		(layer "F.Cu")
	)
	(gr_line
		(start 374.189752 -117.841776)
		(end 374.367552 -117.841776)
		(stroke
			(width 0.04445)
			(type default)
		)
		(layer "F.Cu")
	)
	(gr_line
		(start 374.192038 -118.378478)
		(end 374.369838 -118.378478)
		(stroke
			(width 0.04445)
			(type default)
		)
		(layer "F.Cu")
	)
	(gr_line
		(start 374.192038 -117.378734)
		(end 374.369838 -117.378734)
		(stroke
			(width 0.04445)
			(type default)
		)
		(layer "F.Cu")
	)
	(gr_line
		(start 374.192038 -116.378736)
		(end 374.369838 -116.378736)
		(stroke
			(width 0.04445)
			(type default)
		)
		(layer "F.Cu")
	)
	(gr_line
		(start 374.208294 -127.324612)
		(end 374.208294 -127.639826)
		(stroke
			(width 0.0635)
			(type default)
		)
		(layer "F.Cu")
	)
	(gr_line
		(start 374.21439 -115.86083)
		(end 374.312942 -115.762278)
		(stroke
			(width 0.04445)
			(type default)
		)
		(layer "F.Cu")
	)
	(gr_line
		(start 374.214644 -115.37823)
		(end 374.392444 -115.37823)
		(stroke
			(width 0.04445)
			(type default)
		)
		(layer "F.Cu")
	)
	(gr_line
		(start 374.217184 -125.184662)
		(end 374.456452 -124.945394)
		(stroke
			(width 0.04445)
			(type default)
		)
		(layer "F.Cu")
	)
	(gr_line
		(start 374.26773 -116.860828)
		(end 374.366282 -116.762276)
		(stroke
			(width 0.04445)
			(type default)
		)
		(layer "F.Cu")
	)
	(gr_line
		(start 374.278144 -10.916158)
		(end 374.550178 -11.188192)
		(stroke
			(width 0.05715)
			(type default)
		)
		(layer "F.Cu")
	)
	(gr_line
		(start 374.278144 -10.027158)
		(end 374.550178 -9.755124)
		(stroke
			(width 0.05715)
			(type default)
		)
		(layer "F.Cu")
	)
	(gr_line
		(start 374.285002 -8.5979)
		(end 374.512586 -8.825484)
		(stroke
			(width 0.05715)
			(type default)
		)
		(layer "F.Cu")
	)
	(gr_line
		(start 374.285002 -7.789926)
		(end 374.285002 -8.5979)
		(stroke
			(width 0.05715)
			(type default)
		)
		(layer "F.Cu")
	)
	(gr_line
		(start 374.285002 -3.762248)
		(end 374.285002 -4.389882)
		(stroke
			(width 0.05715)
			(type default)
		)
		(layer "F.Cu")
	)
	(gr_line
		(start 374.302274 -34.365946)
		(end 374.325642 -34.361628)
		(stroke
			(width 0.05715)
			(type default)
		)
		(layer "F.Cu")
	)
	(gr_line
		(start 374.306846 -113.861088)
		(end 374.405652 -113.762282)
		(stroke
			(width 0.04445)
			(type default)
		)
		(layer "F.Cu")
	)
	(gr_line
		(start 374.313958 -110.727998)
		(end 374.359424 -110.727998)
		(stroke
			(width 0.04445)
			(type default)
		)
		(layer "F.Cu")
	)
	(gr_line
		(start 374.315736 -112.842802)
		(end 374.402604 -112.755934)
		(stroke
			(width 0.04445)
			(type default)
		)
		(layer "F.Cu")
	)
	(gr_line
		(start 374.317514 -113.250218)
		(end 374.347994 -113.250218)
		(stroke
			(width 0.04445)
			(type default)
		)
		(layer "F.Cu")
	)
	(gr_line
		(start 374.325642 -34.361628)
		(end 374.344438 -34.346642)
		(stroke
			(width 0.05715)
			(type default)
		)
		(layer "F.Cu")
	)
	(gr_line
		(start 374.364504 -20.479258)
		(end 374.364758 -20.48002)
		(stroke
			(width 0.05715)
			(type default)
		)
		(layer "F.Cu")
	)
	(gr_line
		(start 374.364758 -20.506436)
		(end 374.367298 -20.493228)
		(stroke
			(width 0.05715)
			(type default)
		)
		(layer "F.Cu")
	)
	(gr_line
		(start 374.364758 -20.479766)
		(end 374.367298 -20.493228)
		(stroke
			(width 0.05715)
			(type default)
		)
		(layer "F.Cu")
	)
	(gr_line
		(start 374.367552 -117.841776)
		(end 374.447054 -117.762274)
		(stroke
			(width 0.04445)
			(type default)
		)
		(layer "F.Cu")
	)
	(gr_line
		(start 374.369838 -118.378478)
		(end 374.414542 -118.333774)
		(stroke
			(width 0.04445)
			(type default)
		)
		(layer "F.Cu")
	)
	(gr_line
		(start 374.369838 -117.378734)
		(end 374.414796 -117.333776)
		(stroke
			(width 0.04445)
			(type default)
		)
		(layer "F.Cu")
	)
	(gr_line
		(start 374.369838 -116.378736)
		(end 374.414796 -116.333778)
		(stroke
			(width 0.04445)
			(type default)
		)
		(layer "F.Cu")
	)
	(gr_line
		(start 374.392444 -115.37823)
		(end 374.436894 -115.33378)
		(stroke
			(width 0.04445)
			(type default)
		)
		(layer "F.Cu")
	)
	(gr_line
		(start 374.396 -120.583706)
		(end 374.410478 -120.569228)
		(stroke
			(width 0.04445)
			(type default)
		)
		(layer "F.Cu")
	)
	(gr_line
		(start 374.397778 -120.854978)
		(end 374.674892 -120.854978)
		(stroke
			(width 0.04445)
			(type default)
		)
		(layer "F.Cu")
	)
	(gr_line
		(start 374.405652 -23.90013)
		(end 374.408446 -23.9141)
		(stroke
			(width 0.05715)
			(type default)
		)
		(layer "F.Cu")
	)
	(gr_line
		(start 374.405906 -23.927308)
		(end 374.408446 -23.9141)
		(stroke
			(width 0.05715)
			(type default)
		)
		(layer "F.Cu")
	)
	(gr_line
		(start 374.410478 -120.569228)
		(end 374.83161 -120.569228)
		(stroke
			(width 0.04445)
			(type default)
		)
		(layer "F.Cu")
	)
	(gr_line
		(start 374.456452 -124.945394)
		(end 374.526048 -124.916692)
		(stroke
			(width 0.04445)
			(type default)
		)
		(layer "F.Cu")
	)
	(gr_line
		(start 374.485916 -121.583704)
		(end 374.500648 -121.568972)
		(stroke
			(width 0.04445)
			(type default)
		)
		(layer "F.Cu")
	)
	(gr_line
		(start 374.487694 -121.854976)
		(end 374.674892 -121.854976)
		(stroke
			(width 0.04445)
			(type default)
		)
		(layer "F.Cu")
	)
	(gr_line
		(start 374.500648 -121.568972)
		(end 374.83796 -121.568972)
		(stroke
			(width 0.04445)
			(type default)
		)
		(layer "F.Cu")
	)
	(gr_line
		(start 374.508014 -113.140744)
		(end 374.538494 -113.140744)
		(stroke
			(width 0.04445)
			(type default)
		)
		(layer "F.Cu")
	)
	(gr_line
		(start 374.5103 -31.378144)
		(end 374.514618 -31.357062)
		(stroke
			(width 0.05715)
			(type default)
		)
		(layer "F.Cu")
	)
	(gr_line
		(start 374.5103 -31.378144)
		(end 374.515634 -31.398972)
		(stroke
			(width 0.05715)
			(type default)
		)
		(layer "F.Cu")
	)
	(gr_line
		(start 374.510554 -50.255932)
		(end 374.515888 -50.252376)
		(stroke
			(width 0.05715)
			(type default)
		)
		(layer "F.Cu")
	)
	(gr_line
		(start 374.515888 -50.252376)
		(end 374.522238 -50.250598)
		(stroke
			(width 0.05715)
			(type default)
		)
		(layer "F.Cu")
	)
	(gr_line
		(start 374.524778 -114.704876)
		(end 374.674892 -114.85499)
		(stroke
			(width 0.04445)
			(type default)
		)
		(layer "F.Cu")
	)
	(gr_line
		(start 374.526048 -124.916692)
		(end 374.815608 -124.916692)
		(stroke
			(width 0.04445)
			(type default)
		)
		(layer "F.Cu")
	)
	(gr_line
		(start 374.575832 -112.755934)
		(end 374.674892 -112.854994)
		(stroke
			(width 0.04445)
			(type default)
		)
		(layer "F.Cu")
	)
	(gr_line
		(start 374.581674 -119.761762)
		(end 374.674892 -119.85498)
		(stroke
			(width 0.04445)
			(type default)
		)
		(layer "F.Cu")
	)
	(gr_line
		(start 374.582182 -118.762272)
		(end 374.674892 -118.854982)
		(stroke
			(width 0.04445)
			(type default)
		)
		(layer "F.Cu")
	)
	(gr_line
		(start 374.582182 -115.762278)
		(end 374.674892 -115.854988)
		(stroke
			(width 0.04445)
			(type default)
		)
		(layer "F.Cu")
	)
	(gr_line
		(start 374.588532 -113.762282)
		(end 374.674892 -113.848642)
		(stroke
			(width 0.04445)
			(type default)
		)
		(layer "F.Cu")
	)
	(gr_line
		(start 374.589548 -118.333774)
		(end 374.634506 -118.378732)
		(stroke
			(width 0.04445)
			(type default)
		)
		(layer "F.Cu")
	)
	(gr_line
		(start 374.589548 -116.333778)
		(end 374.634506 -116.378736)
		(stroke
			(width 0.04445)
			(type default)
		)
		(layer "F.Cu")
	)
	(gr_line
		(start 374.604026 -115.33378)
		(end 374.64873 -115.378484)
		(stroke
			(width 0.04445)
			(type default)
		)
		(layer "F.Cu")
	)
	(gr_line
		(start 374.616726 -122.20702)
		(end 374.62333 -122.204226)
		(stroke
			(width 0.04445)
			(type default)
		)
		(layer "F.Cu")
	)
	(gr_line
		(start 374.626378 -116.762276)
		(end 374.674892 -116.81079)
		(stroke
			(width 0.04445)
			(type default)
		)
		(layer "F.Cu")
	)
	(gr_line
		(start 374.626632 -117.762274)
		(end 374.674892 -117.810534)
		(stroke
			(width 0.04445)
			(type default)
		)
		(layer "F.Cu")
	)
	(gr_line
		(start 374.62841 -122.46102)
		(end 374.635014 -122.458226)
		(stroke
			(width 0.04445)
			(type default)
		)
		(layer "F.Cu")
	)
	(gr_line
		(start 374.634506 -118.378732)
		(end 374.812306 -118.378732)
		(stroke
			(width 0.04445)
			(type default)
		)
		(layer "F.Cu")
	)
	(gr_line
		(start 374.634506 -116.378736)
		(end 374.812306 -116.378736)
		(stroke
			(width 0.04445)
			(type default)
		)
		(layer "F.Cu")
	)
	(gr_line
		(start 374.64873 -115.378484)
		(end 374.82653 -115.378484)
		(stroke
			(width 0.04445)
			(type default)
		)
		(layer "F.Cu")
	)
	(gr_line
		(start 374.674892 -117.810534)
		(end 374.674892 -117.854984)
		(stroke
			(width 0.04445)
			(type default)
		)
		(layer "F.Cu")
	)
	(gr_line
		(start 374.674892 -116.81079)
		(end 374.674892 -116.854986)
		(stroke
			(width 0.04445)
			(type default)
		)
		(layer "F.Cu")
	)
	(gr_line
		(start 374.674892 -113.848642)
		(end 374.674892 -113.854992)
		(stroke
			(width 0.04445)
			(type default)
		)
		(layer "F.Cu")
	)
	(gr_line
		(start 374.693434 -116.140738)
		(end 374.781826 -116.140738)
		(stroke
			(width 0.04445)
			(type default)
		)
		(layer "F.Cu")
	)
	(gr_line
		(start 374.696228 -117.140736)
		(end 374.78208 -117.140736)
		(stroke
			(width 0.04445)
			(type default)
		)
		(layer "F.Cu")
	)
	(gr_line
		(start 374.704356 -118.140734)
		(end 374.769888 -118.140734)
		(stroke
			(width 0.04445)
			(type default)
		)
		(layer "F.Cu")
	)
	(gr_line
		(start 374.708674 -106.145076)
		(end 374.762268 -106.145076)
		(stroke
			(width 0.04445)
			(type default)
		)
		(layer "F.Cu")
	)
	(gr_line
		(start 374.715278 -114.511836)
		(end 374.798336 -114.511836)
		(stroke
			(width 0.04445)
			(type default)
		)
		(layer "F.Cu")
	)
	(gr_line
		(start 374.718072 -115.14074)
		(end 374.776746 -115.14074)
		(stroke
			(width 0.04445)
			(type default)
		)
		(layer "F.Cu")
	)
	(gr_line
		(start 374.728486 -16.606774)
		(end 374.743218 -16.57096)
		(stroke
			(width 0.05715)
			(type default)
		)
		(layer "F.Cu")
	)
	(gr_line
		(start 374.736614 -121.140728)
		(end 374.788938 -121.140728)
		(stroke
			(width 0.04445)
			(type default)
		)
		(layer "F.Cu")
	)
	(gr_line
		(start 374.743218 -16.57096)
		(end 374.776238 -16.549116)
		(stroke
			(width 0.05715)
			(type default)
		)
		(layer "F.Cu")
	)
	(gr_line
		(start 374.750838 -125.925834)
		(end 374.750838 -126.13259)
		(stroke
			(width 0.04445)
			(type default)
		)
		(layer "F.Cu")
	)
	(gr_line
		(start 374.750838 -125.925834)
		(end 375.119646 -125.557026)
		(stroke
			(width 0.04445)
			(type default)
		)
		(layer "F.Cu")
	)
	(gr_line
		(start 374.75414 -112.162082)
		(end 374.98401 -112.04067)
		(stroke
			(width 0.04445)
			(type default)
		)
		(layer "F.Cu")
	)
	(gr_line
		(start 374.755664 -26.157936)
		(end 374.758204 -26.171144)
		(stroke
			(width 0.05715)
			(type default)
		)
		(layer "F.Cu")
	)
	(gr_line
		(start 374.755664 -26.157936)
		(end 374.758458 -26.143966)
		(stroke
			(width 0.05715)
			(type default)
		)
		(layer "F.Cu")
	)
	(gr_line
		(start 374.766332 -112.562894)
		(end 374.83796 -112.562894)
		(stroke
			(width 0.04445)
			(type default)
		)
		(layer "F.Cu")
	)
	(gr_line
		(start 374.768364 -106.142536)
		(end 374.800622 -106.129074)
		(stroke
			(width 0.04445)
			(type default)
		)
		(layer "F.Cu")
	)
	(gr_line
		(start 374.769888 -118.140734)
		(end 374.79859 -118.128796)
		(stroke
			(width 0.04445)
			(type default)
		)
		(layer "F.Cu")
	)
	(gr_line
		(start 374.769888 -113.569242)
		(end 375.504964 -113.854992)
		(stroke
			(width 0.04445)
			(type default)
		)
		(layer "F.Cu")
	)
	(gr_line
		(start 374.772174 -119.568722)
		(end 374.833896 -119.568722)
		(stroke
			(width 0.04445)
			(type default)
		)
		(layer "F.Cu")
	)
	(gr_line
		(start 374.772682 -118.569232)
		(end 374.830086 -118.569232)
		(stroke
			(width 0.04445)
			(type default)
		)
		(layer "F.Cu")
	)
	(gr_line
		(start 374.772682 -115.569238)
		(end 374.83288 -115.569238)
		(stroke
			(width 0.04445)
			(type default)
		)
		(layer "F.Cu")
	)
	(gr_line
		(start 374.776746 -115.14074)
		(end 375.01322 -115.04295)
		(stroke
			(width 0.04445)
			(type default)
		)
		(layer "F.Cu")
	)
	(gr_line
		(start 374.781826 -116.140738)
		(end 374.799352 -116.133626)
		(stroke
			(width 0.04445)
			(type default)
		)
		(layer "F.Cu")
	)
	(gr_line
		(start 374.78335 -119.140224)
		(end 375.016776 -119.04345)
		(stroke
			(width 0.04445)
			(type default)
		)
		(layer "F.Cu")
	)
	(gr_line
		(start 374.78462 -120.138444)
		(end 375.020332 -120.040908)
		(stroke
			(width 0.04445)
			(type default)
		)
		(layer "F.Cu")
	)
	(gr_line
		(start 374.788176 -117.138196)
		(end 374.790462 -117.13718)
		(stroke
			(width 0.04445)
			(type default)
		)
		(layer "F.Cu")
	)
	(gr_line
		(start 374.790462 -113.138204)
		(end 375.019316 -113.043462)
		(stroke
			(width 0.04445)
			(type default)
		)
		(layer "F.Cu")
	)
	(gr_line
		(start 374.79097 -11.691366)
		(end 374.843294 -11.643106)
		(stroke
			(width 0.05715)
			(type default)
		)
		(layer "F.Cu")
	)
	(gr_line
		(start 374.798336 -114.511836)
		(end 374.930162 -114.643662)
		(stroke
			(width 0.04445)
			(type default)
		)
		(layer "F.Cu")
	)
	(gr_line
		(start 374.804686 -124.916692)
		(end 374.815608 -124.916692)
		(stroke
			(width 0.04445)
			(type default)
		)
		(layer "F.Cu")
	)
	(gr_line
		(start 374.812306 -118.378732)
		(end 374.891808 -118.29923)
		(stroke
			(width 0.04445)
			(type default)
		)
		(layer "F.Cu")
	)
	(gr_line
		(start 374.812306 -116.378736)
		(end 374.883426 -116.307616)
		(stroke
			(width 0.04445)
			(type default)
		)
		(layer "F.Cu")
	)
	(gr_line
		(start 374.814846 -22.22373)
		(end 374.817894 -22.238208)
		(stroke
			(width 0.05715)
			(type default)
		)
		(layer "F.Cu")
	)
	(gr_line
		(start 374.814846 -22.22373)
		(end 374.817894 -22.208744)
		(stroke
			(width 0.05715)
			(type default)
		)
		(layer "F.Cu")
	)
	(gr_line
		(start 374.815608 -124.916692)
		(end 375.0564 -124.6759)
		(stroke
			(width 0.04445)
			(type default)
		)
		(layer "F.Cu")
	)
	(gr_line
		(start 374.816624 -33.976818)
		(end 374.839484 -33.958784)
		(stroke
			(width 0.05715)
			(type default)
		)
		(layer "F.Cu")
	)
	(gr_line
		(start 374.816878 -116.569236)
		(end 374.833896 -116.569236)
		(stroke
			(width 0.04445)
			(type default)
		)
		(layer "F.Cu")
	)
	(gr_line
		(start 374.817132 -117.569234)
		(end 374.833642 -117.569234)
		(stroke
			(width 0.04445)
			(type default)
		)
		(layer "F.Cu")
	)
	(gr_line
		(start 374.819164 -116.125244)
		(end 375.01703 -116.043202)
		(stroke
			(width 0.04445)
			(type default)
		)
		(layer "F.Cu")
	)
	(gr_line
		(start 374.82653 -115.378484)
		(end 374.908572 -115.296442)
		(stroke
			(width 0.04445)
			(type default)
		)
		(layer "F.Cu")
	)
	(gr_line
		(start 374.827038 -121.331228)
		(end 374.832626 -121.328688)
		(stroke
			(width 0.04445)
			(type default)
		)
		(layer "F.Cu")
	)
	(gr_line
		(start 374.830086 -118.569232)
		(end 374.88114 -118.620286)
		(stroke
			(width 0.04445)
			(type default)
		)
		(layer "F.Cu")
	)
	(gr_line
		(start 374.83161 -120.569228)
		(end 374.891554 -120.629172)
		(stroke
			(width 0.04445)
			(type default)
		)
		(layer "F.Cu")
	)
	(gr_line
		(start 374.83288 -115.569238)
		(end 374.892316 -115.628674)
		(stroke
			(width 0.04445)
			(type default)
		)
		(layer "F.Cu")
	)
	(gr_line
		(start 374.833642 -117.569234)
		(end 374.90019 -117.635782)
		(stroke
			(width 0.04445)
			(type default)
		)
		(layer "F.Cu")
	)
	(gr_line
		(start 374.833896 -119.568722)
		(end 375.06529 -119.699532)
		(stroke
			(width 0.04445)
			(type default)
		)
		(layer "F.Cu")
	)
	(gr_line
		(start 374.833896 -116.569236)
		(end 374.918732 -116.654072)
		(stroke
			(width 0.04445)
			(type default)
		)
		(layer "F.Cu")
	)
	(gr_line
		(start 374.836436 -117.11813)
		(end 375.017538 -117.0432)
		(stroke
			(width 0.04445)
			(type default)
		)
		(layer "F.Cu")
	)
	(gr_line
		(start 374.83669 -18.947892)
		(end 374.84431 -18.986246)
		(stroke
			(width 0.05715)
			(type default)
		)
		(layer "F.Cu")
	)
	(gr_line
		(start 374.83669 -18.947892)
		(end 374.85193 -18.91157)
		(stroke
			(width 0.05715)
			(type default)
		)
		(layer "F.Cu")
	)
	(gr_line
		(start 374.83796 -121.568972)
		(end 374.914668 -121.64568)
		(stroke
			(width 0.04445)
			(type default)
		)
		(layer "F.Cu")
	)
	(gr_line
		(start 374.83796 -112.562894)
		(end 374.91162 -112.636554)
		(stroke
			(width 0.04445)
			(type default)
		)
		(layer "F.Cu")
	)
	(gr_line
		(start 374.839484 -33.958784)
		(end 374.850914 -33.932114)
		(stroke
			(width 0.05715)
			(type default)
		)
		(layer "F.Cu")
	)
	(gr_line
		(start 374.844564 -118.109746)
		(end 375.004076 -118.043706)
		(stroke
			(width 0.04445)
			(type default)
		)
		(layer "F.Cu")
	)
	(gr_line
		(start 374.85193 -106.107992)
		(end 375.016268 -106.03992)
		(stroke
			(width 0.04445)
			(type default)
		)
		(layer "F.Cu")
	)
	(gr_line
		(start 374.85193 -18.911316)
		(end 374.852184 -18.910808)
		(stroke
			(width 0.05715)
			(type default)
		)
		(layer "F.Cu")
	)
	(gr_line
		(start 374.857518 -8.825484)
		(end 375.085102 -8.5979)
		(stroke
			(width 0.05715)
			(type default)
		)
		(layer "F.Cu")
	)
	(gr_line
		(start 374.858788 -106.335576)
		(end 374.895618 -106.298746)
		(stroke
			(width 0.04445)
			(type default)
		)
		(layer "F.Cu")
	)
	(gr_line
		(start 374.860058 -117.331236)
		(end 374.88368 -117.307614)
		(stroke
			(width 0.04445)
			(type default)
		)
		(layer "F.Cu")
	)
	(gr_line
		(start 374.88114 -118.620286)
		(end 375.504964 -118.854982)
		(stroke
			(width 0.04445)
			(type default)
		)
		(layer "F.Cu")
	)
	(gr_line
		(start 374.882918 -121.101866)
		(end 375.033794 -121.039382)
		(stroke
			(width 0.04445)
			(type default)
		)
		(layer "F.Cu")
	)
	(gr_line
		(start 374.883934 -116.307108)
		(end 374.972326 -116.307108)
		(stroke
			(width 0.04445)
			(type default)
		)
		(layer "F.Cu")
	)
	(gr_line
		(start 374.886728 -117.304566)
		(end 374.97258 -117.304566)
		(stroke
			(width 0.04445)
			(type default)
		)
		(layer "F.Cu")
	)
	(gr_line
		(start 374.891554 -120.629172)
		(end 375.504964 -120.854978)
		(stroke
			(width 0.04445)
			(type default)
		)
		(layer "F.Cu")
	)
	(gr_line
		(start 374.892316 -115.628674)
		(end 375.504964 -115.854988)
		(stroke
			(width 0.04445)
			(type default)
		)
		(layer "F.Cu")
	)
	(gr_line
		(start 374.894856 -118.296182)
		(end 374.960388 -118.296182)
		(stroke
			(width 0.04445)
			(type default)
		)
		(layer "F.Cu")
	)
	(gr_line
		(start 374.89511 -11.188192)
		(end 375.167144 -10.916158)
		(stroke
			(width 0.05715)
			(type default)
		)
		(layer "F.Cu")
	)
	(gr_line
		(start 374.89511 -9.755124)
		(end 375.167144 -10.027158)
		(stroke
			(width 0.05715)
			(type default)
		)
		(layer "F.Cu")
	)
	(gr_line
		(start 374.899174 -106.29519)
		(end 374.952768 -106.29519)
		(stroke
			(width 0.04445)
			(type default)
		)
		(layer "F.Cu")
	)
	(gr_line
		(start 374.90019 -117.635782)
		(end 375.504964 -117.854984)
		(stroke
			(width 0.04445)
			(type default)
		)
		(layer "F.Cu")
	)
	(gr_line
		(start 374.908572 -115.296442)
		(end 374.967246 -115.296442)
		(stroke
			(width 0.04445)
			(type default)
		)
		(layer "F.Cu")
	)
	(gr_line
		(start 374.91162 -112.636554)
		(end 375.504964 -112.854994)
		(stroke
			(width 0.04445)
			(type default)
		)
		(layer "F.Cu")
	)
	(gr_line
		(start 374.914668 -121.64568)
		(end 375.504964 -121.854976)
		(stroke
			(width 0.04445)
			(type default)
		)
		(layer "F.Cu")
	)
	(gr_line
		(start 374.918732 -116.654072)
		(end 375.504964 -116.854986)
		(stroke
			(width 0.04445)
			(type default)
		)
		(layer "F.Cu")
	)
	(gr_line
		(start 374.927114 -121.289826)
		(end 374.979438 -121.289826)
		(stroke
			(width 0.04445)
			(type default)
		)
		(layer "F.Cu")
	)
	(gr_line
		(start 374.930162 -114.643662)
		(end 375.013982 -114.659664)
		(stroke
			(width 0.04445)
			(type default)
		)
		(layer "F.Cu")
	)
	(gr_line
		(start 374.942354 -112.355122)
		(end 375.089928 -112.355122)
		(stroke
			(width 0.04445)
			(type default)
		)
		(layer "F.Cu")
	)
	(gr_line
		(start 374.955308 -106.29519)
		(end 375.030238 -106.29519)
		(stroke
			(width 0.04445)
			(type default)
		)
		(layer "F.Cu")
	)
	(gr_line
		(start 374.961404 -122.064018)
		(end 375.034048 -122.034046)
		(stroke
			(width 0.04445)
			(type default)
		)
		(layer "F.Cu")
	)
	(gr_line
		(start 374.962928 -118.296182)
		(end 375.031 -118.296182)
		(stroke
			(width 0.04445)
			(type default)
		)
		(layer "F.Cu")
	)
	(gr_line
		(start 374.969786 -115.296442)
		(end 375.031254 -115.296442)
		(stroke
			(width 0.04445)
			(type default)
		)
		(layer "F.Cu")
	)
	(gr_line
		(start 374.970294 -119.333264)
		(end 375.068084 -119.333264)
		(stroke
			(width 0.04445)
			(type default)
		)
		(layer "F.Cu")
	)
	(gr_line
		(start 374.971564 -120.331484)
		(end 375.066306 -120.331484)
		(stroke
			(width 0.04445)
			(type default)
		)
		(layer "F.Cu")
	)
	(gr_line
		(start 374.974866 -116.307108)
		(end 375.041922 -116.307108)
		(stroke
			(width 0.04445)
			(type default)
		)
		(layer "F.Cu")
	)
	(gr_line
		(start 374.97512 -117.304566)
		(end 375.039382 -117.304566)
		(stroke
			(width 0.04445)
			(type default)
		)
		(layer "F.Cu")
	)
	(gr_line
		(start 374.977406 -113.331244)
		(end 375.066052 -113.331244)
		(stroke
			(width 0.04445)
			(type default)
		)
		(layer "F.Cu")
	)
	(gr_line
		(start 374.981978 -121.289826)
		(end 375.02465 -121.289826)
		(stroke
			(width 0.04445)
			(type default)
		)
		(layer "F.Cu")
	)
	(gr_line
		(start 374.98401 -112.04067)
		(end 375.19229 -112.04067)
		(stroke
			(width 0.04445)
			(type default)
		)
		(layer "F.Cu")
	)
	(gr_line
		(start 374.988836 -51.134772)
		(end 374.997472 -51.128676)
		(stroke
			(width 0.05715)
			(type default)
		)
		(layer "F.Cu")
	)
	(gr_line
		(start 374.997472 -51.128676)
		(end 375.00814 -51.126136)
		(stroke
			(width 0.05715)
			(type default)
		)
		(layer "F.Cu")
	)
	(gr_line
		(start 375.004076 -118.043706)
		(end 375.224548 -118.043706)
		(stroke
			(width 0.04445)
			(type default)
		)
		(layer "F.Cu")
	)
	(gr_line
		(start 375.008648 -122.253502)
		(end 375.089928 -122.334782)
		(stroke
			(width 0.04445)
			(type default)
		)
		(layer "F.Cu")
	)
	(gr_line
		(start 375.01322 -115.04295)
		(end 375.227342 -115.04295)
		(stroke
			(width 0.04445)
			(type default)
		)
		(layer "F.Cu")
	)
	(gr_line
		(start 375.013982 -114.659664)
		(end 375.504964 -114.85499)
		(stroke
			(width 0.04445)
			(type default)
		)
		(layer "F.Cu")
	)
	(gr_line
		(start 375.016268 -106.03992)
		(end 375.119138 -106.03992)
		(stroke
			(width 0.04445)
			(type default)
		)
		(layer "F.Cu")
	)
	(gr_line
		(start 375.016776 -119.04345)
		(end 375.219468 -119.04345)
		(stroke
			(width 0.04445)
			(type default)
		)
		(layer "F.Cu")
	)
	(gr_line
		(start 375.01703 -116.043202)
		(end 375.223532 -116.043202)
		(stroke
			(width 0.04445)
			(type default)
		)
		(layer "F.Cu")
	)
	(gr_line
		(start 375.017538 -117.0432)
		(end 375.217944 -117.0432)
		(stroke
			(width 0.04445)
			(type default)
		)
		(layer "F.Cu")
	)
	(gr_line
		(start 375.019316 -113.043462)
		(end 375.21261 -113.043462)
		(stroke
			(width 0.04445)
			(type default)
		)
		(layer "F.Cu")
	)
	(gr_line
		(start 375.020332 -120.040908)
		(end 375.215912 -120.040908)
		(stroke
			(width 0.04445)
			(type default)
		)
		(layer "F.Cu")
	)
	(gr_line
		(start 375.02465 -121.289826)
		(end 375.089928 -121.355104)
		(stroke
			(width 0.04445)
			(type default)
		)
		(layer "F.Cu")
	)
	(gr_line
		(start 375.030238 -106.29519)
		(end 375.089928 -106.35488)
		(stroke
			(width 0.04445)
			(type default)
		)
		(layer "F.Cu")
	)
	(gr_line
		(start 375.031 -118.296182)
		(end 375.089928 -118.35511)
		(stroke
			(width 0.04445)
			(type default)
		)
		(layer "F.Cu")
	)
	(gr_line
		(start 375.031254 -115.296442)
		(end 375.089928 -115.355116)
		(stroke
			(width 0.04445)
			(type default)
		)
		(layer "F.Cu")
	)
	(gr_line
		(start 375.033794 -121.039382)
		(end 375.207022 -121.039382)
		(stroke
			(width 0.04445)
			(type default)
		)
		(layer "F.Cu")
	)
	(gr_line
		(start 375.034302 -122.0343)
		(end 375.129044 -122.0343)
		(stroke
			(width 0.04445)
			(type default)
		)
		(layer "F.Cu")
	)
	(gr_line
		(start 375.039382 -117.304566)
		(end 375.089928 -117.355112)
		(stroke
			(width 0.04445)
			(type default)
		)
		(layer "F.Cu")
	)
	(gr_line
		(start 375.041922 -116.307108)
		(end 375.089928 -116.355114)
		(stroke
			(width 0.04445)
			(type default)
		)
		(layer "F.Cu")
	)
	(gr_line
		(start 375.0564 -124.66574)
		(end 375.0564 -124.6759)
		(stroke
			(width 0.04445)
			(type default)
		)
		(layer "F.Cu")
	)
	(gr_line
		(start 375.0564 -124.511054)
		(end 375.0564 -124.6759)
		(stroke
			(width 0.04445)
			(type default)
		)
		(layer "F.Cu")
	)
	(gr_line
		(start 375.0564 -124.511054)
		(end 375.233184 -124.33427)
		(stroke
			(width 0.04445)
			(type default)
		)
		(layer "F.Cu")
	)
	(gr_line
		(start 375.06529 -119.699532)
		(end 375.504964 -119.85498)
		(stroke
			(width 0.04445)
			(type default)
		)
		(layer "F.Cu")
	)
	(gr_line
		(start 375.066052 -113.331244)
		(end 375.089928 -113.35512)
		(stroke
			(width 0.04445)
			(type default)
		)
		(layer "F.Cu")
	)
	(gr_line
		(start 375.066306 -120.331484)
		(end 375.089928 -120.355106)
		(stroke
			(width 0.04445)
			(type default)
		)
		(layer "F.Cu")
	)
	(gr_line
		(start 375.068084 -119.333264)
		(end 375.089928 -119.355108)
		(stroke
			(width 0.04445)
			(type default)
		)
		(layer "F.Cu")
	)
	(gr_line
		(start 375.085102 -7.789926)
		(end 375.085102 -8.5979)
		(stroke
			(width 0.05715)
			(type default)
		)
		(layer "F.Cu")
	)
	(gr_line
		(start 375.089928 -122.334782)
		(end 375.089928 -122.355102)
		(stroke
			(width 0.04445)
			(type default)
		)
		(layer "F.Cu")
	)
	(gr_line
		(start 375.119138 -106.03992)
		(end 375.280936 -106.083862)
		(stroke
			(width 0.04445)
			(type default)
		)
		(layer "F.Cu")
	)
	(gr_line
		(start 375.119646 -125.106684)
		(end 375.119646 -125.557026)
		(stroke
			(width 0.04445)
			(type default)
		)
		(layer "F.Cu")
	)
	(gr_line
		(start 375.119646 -125.106684)
		(end 375.119646 -125.231652)
		(stroke
			(width 0.04445)
			(type default)
		)
		(layer "F.Cu")
	)
	(gr_line
		(start 375.119646 -125.106684)
		(end 375.24563 -124.9807)
		(stroke
			(width 0.04445)
			(type default)
		)
		(layer "F.Cu")
	)
	(gr_line
		(start 375.124218 -33.291526)
		(end 375.129806 -33.278572)
		(stroke
			(width 0.05715)
			(type default)
		)
		(layer "F.Cu")
	)
	(gr_line
		(start 375.129044 -122.0343)
		(end 375.308368 -122.108468)
		(stroke
			(width 0.04445)
			(type default)
		)
		(layer "F.Cu")
	)
	(gr_line
		(start 375.19229 -112.04067)
		(end 375.311924 -112.129316)
		(stroke
			(width 0.04445)
			(type default)
		)
		(layer "F.Cu")
	)
	(gr_line
		(start 375.207022 -121.039382)
		(end 375.263918 -121.096278)
		(stroke
			(width 0.04445)
			(type default)
		)
		(layer "F.Cu")
	)
	(gr_line
		(start 375.21261 -113.043462)
		(end 375.266204 -113.097056)
		(stroke
			(width 0.04445)
			(type default)
		)
		(layer "F.Cu")
	)
	(gr_line
		(start 375.215912 -120.040908)
		(end 375.29643 -120.121426)
		(stroke
			(width 0.04445)
			(type default)
		)
		(layer "F.Cu")
	)
	(gr_line
		(start 375.217944 -117.0432)
		(end 375.292366 -117.117622)
		(stroke
			(width 0.04445)
			(type default)
		)
		(layer "F.Cu")
	)
	(gr_line
		(start 375.219468 -119.04345)
		(end 375.288302 -119.112284)
		(stroke
			(width 0.04445)
			(type default)
		)
		(layer "F.Cu")
	)
	(gr_line
		(start 375.223532 -116.043202)
		(end 375.31167 -116.13134)
		(stroke
			(width 0.04445)
			(type default)
		)
		(layer "F.Cu")
	)
	(gr_line
		(start 375.224548 -118.043706)
		(end 375.304812 -118.12397)
		(stroke
			(width 0.04445)
			(type default)
		)
		(layer "F.Cu")
	)
	(gr_line
		(start 375.227342 -115.04295)
		(end 375.309892 -115.1255)
		(stroke
			(width 0.04445)
			(type default)
		)
		(layer "F.Cu")
	)
	(gr_line
		(start 375.233184 -124.33427)
		(end 375.531634 -124.210572)
		(stroke
			(width 0.04445)
			(type default)
		)
		(layer "F.Cu")
	)
	(gr_line
		(start 375.24563 -124.9807)
		(end 375.37136 -124.9807)
		(stroke
			(width 0.04445)
			(type default)
		)
		(layer "F.Cu")
	)
	(gr_line
		(start 375.24563 -124.9807)
		(end 375.6279 -124.9807)
		(stroke
			(width 0.04445)
			(type default)
		)
		(layer "F.Cu")
	)
	(gr_line
		(start 375.263918 -121.096278)
		(end 375.92 -121.355104)
		(stroke
			(width 0.04445)
			(type default)
		)
		(layer "F.Cu")
	)
	(gr_line
		(start 375.266204 -113.097056)
		(end 375.92 -113.35512)
		(stroke
			(width 0.04445)
			(type default)
		)
		(layer "F.Cu")
	)
	(gr_line
		(start 375.280936 -106.083862)
		(end 375.353326 -106.129836)
		(stroke
			(width 0.04445)
			(type default)
		)
		(layer "F.Cu")
	)
	(gr_line
		(start 375.288302 -119.112284)
		(end 375.92 -119.355108)
		(stroke
			(width 0.04445)
			(type default)
		)
		(layer "F.Cu")
	)
	(gr_line
		(start 375.292366 -117.117622)
		(end 375.92 -117.355112)
		(stroke
			(width 0.04445)
			(type default)
		)
		(layer "F.Cu")
	)
	(gr_line
		(start 375.29643 -120.121426)
		(end 375.92 -120.355106)
		(stroke
			(width 0.04445)
			(type default)
		)
		(layer "F.Cu")
	)
	(gr_line
		(start 375.304812 -118.12397)
		(end 375.92 -118.35511)
		(stroke
			(width 0.04445)
			(type default)
		)
		(layer "F.Cu")
	)
	(gr_line
		(start 375.308368 -122.108468)
		(end 375.3358 -122.1359)
		(stroke
			(width 0.04445)
			(type default)
		)
		(layer "F.Cu")
	)
	(gr_line
		(start 375.309892 -115.1255)
		(end 375.92 -115.355116)
		(stroke
			(width 0.04445)
			(type default)
		)
		(layer "F.Cu")
	)
	(gr_line
		(start 375.31167 -116.13134)
		(end 375.92 -116.355114)
		(stroke
			(width 0.04445)
			(type default)
		)
		(layer "F.Cu")
	)
	(gr_line
		(start 375.311924 -112.129316)
		(end 375.92 -112.355122)
		(stroke
			(width 0.04445)
			(type default)
		)
		(layer "F.Cu")
	)
	(gr_line
		(start 375.3358 -122.1359)
		(end 375.92 -122.355102)
		(stroke
			(width 0.04445)
			(type default)
		)
		(layer "F.Cu")
	)
	(gr_line
		(start 375.353326 -106.129836)
		(end 375.92 -106.35488)
		(stroke
			(width 0.04445)
			(type default)
		)
		(layer "F.Cu")
	)
	(gr_line
		(start 375.39803 -20.557998)
		(end 375.40057 -20.545552)
		(stroke
			(width 0.05715)
			(type default)
		)
		(layer "F.Cu")
	)
	(gr_line
		(start 375.39803 -20.531836)
		(end 375.40057 -20.545552)
		(stroke
			(width 0.05715)
			(type default)
		)
		(layer "F.Cu")
	)
	(gr_line
		(start 375.399046 -28.145486)
		(end 375.40184 -28.159456)
		(stroke
			(width 0.05715)
			(type default)
		)
		(layer "F.Cu")
	)
	(gr_line
		(start 375.3993 -28.172664)
		(end 375.40184 -28.159456)
		(stroke
			(width 0.05715)
			(type default)
		)
		(layer "F.Cu")
	)
	(gr_line
		(start 375.421652 -24.027638)
		(end 375.424446 -24.041608)
		(stroke
			(width 0.05715)
			(type default)
		)
		(layer "F.Cu")
	)
	(gr_line
		(start 375.421906 -24.054816)
		(end 375.424446 -24.041608)
		(stroke
			(width 0.05715)
			(type default)
		)
		(layer "F.Cu")
	)
	(gr_line
		(start 375.43994 -124.248418)
		(end 375.531634 -124.210572)
		(stroke
			(width 0.04445)
			(type default)
		)
		(layer "F.Cu")
	)
	(gr_line
		(start 375.441972 -14.880336)
		(end 375.454672 -14.871954)
		(stroke
			(width 0.05715)
			(type default)
		)
		(layer "F.Cu")
	)
	(gr_line
		(start 375.454672 -14.871954)
		(end 375.469404 -14.86916)
		(stroke
			(width 0.05715)
			(type default)
		)
		(layer "F.Cu")
	)
	(gr_line
		(start 375.531634 -124.210572)
		(end 375.7422 -124.000006)
		(stroke
			(width 0.04445)
			(type default)
		)
		(layer "F.Cu")
	)
	(gr_line
		(start 375.545096 -31.144972)
		(end 375.548398 -31.159958)
		(stroke
			(width 0.05715)
			(type default)
		)
		(layer "F.Cu")
	)
	(gr_line
		(start 375.545096 -31.144972)
		(end 375.548398 -31.12897)
		(stroke
			(width 0.05715)
			(type default)
		)
		(layer "F.Cu")
	)
	(gr_line
		(start 375.552462 -17.236694)
		(end 375.567194 -17.20088)
		(stroke
			(width 0.05715)
			(type default)
		)
		(layer "F.Cu")
	)
	(gr_line
		(start 375.567194 -17.20088)
		(end 375.600214 -17.179036)
		(stroke
			(width 0.05715)
			(type default)
		)
		(layer "F.Cu")
	)
	(gr_line
		(start 375.6279 -124.9807)
		(end 375.7549 -124.8537)
		(stroke
			(width 0.04445)
			(type default)
		)
		(layer "F.Cu")
	)
	(gr_line
		(start 375.634758 -34.679636)
		(end 375.661682 -34.660078)
		(stroke
			(width 0.05715)
			(type default)
		)
		(layer "F.Cu")
	)
	(gr_line
		(start 375.661682 -34.660078)
		(end 375.674636 -34.629344)
		(stroke
			(width 0.05715)
			(type default)
		)
		(layer "F.Cu")
	)
	(gr_line
		(start 375.70029 -2.937002)
		(end 376.04827 -2.937002)
		(stroke
			(width 0.05715)
			(type default)
		)
		(layer "F.Cu")
	)
	(gr_line
		(start 375.7422 -123.7488)
		(end 375.7422 -124.000006)
		(stroke
			(width 0.04445)
			(type default)
		)
		(layer "F.Cu")
	)
	(gr_line
		(start 375.7422 -123.7488)
		(end 375.92 -123.571)
		(stroke
			(width 0.04445)
			(type default)
		)
		(layer "F.Cu")
	)
	(gr_line
		(start 375.7549 -124.2568)
		(end 375.7549 -124.8537)
		(stroke
			(width 0.04445)
			(type default)
		)
		(layer "F.Cu")
	)
	(gr_line
		(start 375.7549 -124.2568)
		(end 375.7549 -124.432822)
		(stroke
			(width 0.04445)
			(type default)
		)
		(layer "F.Cu")
	)
	(gr_line
		(start 375.7549 -124.2568)
		(end 375.9327 -124.079)
		(stroke
			(width 0.04445)
			(type default)
		)
		(layer "F.Cu")
	)
	(gr_line
		(start 375.76125 -128.616202)
		(end 375.76125 -129.02565)
		(stroke
			(width 0.04445)
			(type default)
		)
		(layer "F.Cu")
	)
	(gr_line
		(start 375.793508 -14.805914)
		(end 375.882916 -14.675358)
		(stroke
			(width 0.05715)
			(type default)
		)
		(layer "F.Cu")
	)
	(gr_line
		(start 375.868946 -15.040102)
		(end 376.366532 -14.946884)
		(stroke
			(width 0.05715)
			(type default)
		)
		(layer "F.Cu")
	)
	(gr_line
		(start 375.87936 -15.818612)
		(end 375.891044 -15.810992)
		(stroke
			(width 0.05715)
			(type default)
		)
		(layer "F.Cu")
	)
	(gr_line
		(start 375.882916 -14.675358)
		(end 376.219974 -14.612112)
		(stroke
			(width 0.05715)
			(type default)
		)
		(layer "F.Cu")
	)
	(gr_line
		(start 375.885202 -3.708146)
		(end 375.885202 -4.389882)
		(stroke
			(width 0.05715)
			(type default)
		)
		(layer "F.Cu")
	)
	(gr_line
		(start 375.885202 -3.708146)
		(end 376.036586 -3.557016)
		(stroke
			(width 0.05715)
			(type default)
		)
		(layer "F.Cu")
	)
	(gr_line
		(start 375.891044 -15.810992)
		(end 375.904506 -15.808452)
		(stroke
			(width 0.05715)
			(type default)
		)
		(layer "F.Cu")
	)
	(gr_line
		(start 375.92 -123.39574)
		(end 375.92 -123.571)
		(stroke
			(width 0.04445)
			(type default)
		)
		(layer "F.Cu")
	)
	(gr_line
		(start 375.92 -123.3551)
		(end 375.92 -123.571)
		(stroke
			(width 0.04445)
			(type default)
		)
		(layer "F.Cu")
	)
	(gr_line
		(start 375.925334 -29.249878)
		(end 375.929144 -29.229812)
		(stroke
			(width 0.05715)
			(type default)
		)
		(layer "F.Cu")
	)
	(gr_line
		(start 375.929144 -29.229812)
		(end 375.941844 -29.213048)
		(stroke
			(width 0.05715)
			(type default)
		)
		(layer "F.Cu")
	)
	(gr_line
		(start 375.9327 -123.827794)
		(end 375.9327 -124.079)
		(stroke
			(width 0.04445)
			(type default)
		)
		(layer "F.Cu")
	)
	(gr_line
		(start 375.9327 -123.827794)
		(end 376.049794 -123.7107)
		(stroke
			(width 0.04445)
			(type default)
		)
		(layer "F.Cu")
	)
	(gr_arc
		(start 375.95175 -128.423162)
		(mid 375.987088 -128.508474)
		(end 376.0724 -128.543812)
		(stroke
			(width 0.04445)
			(type default)
		)
		(layer "F.Cu")
	)
	(gr_line
		(start 376.036586 -3.557016)
		(end 376.160284 -3.433064)
		(stroke
			(width 0.05715)
			(type default)
		)
		(layer "F.Cu")
	)
	(gr_line
		(start 376.04827 -2.937002)
		(end 376.122946 -3.011678)
		(stroke
			(width 0.05715)
			(type default)
		)
		(layer "F.Cu")
	)
	(gr_line
		(start 376.049794 -123.7107)
		(end 376.1867 -123.7107)
		(stroke
			(width 0.04445)
			(type default)
		)
		(layer "F.Cu")
	)
	(gr_line
		(start 376.0724 -128.543812)
		(end 376.42165 -128.543812)
		(stroke
			(width 0.04445)
			(type default)
		)
		(layer "F.Cu")
	)
	(gr_line
		(start 376.090688 -33.636204)
		(end 376.095768 -33.623758)
		(stroke
			(width 0.05715)
			(type default)
		)
		(layer "F.Cu")
	)
	(gr_line
		(start 376.1867 -123.7107)
		(end 376.206258 -123.730258)
		(stroke
			(width 0.04445)
			(type default)
		)
		(layer "F.Cu")
	)
	(gr_line
		(start 376.1867 -123.7107)
		(end 376.330972 -123.854972)
		(stroke
			(width 0.04445)
			(type default)
		)
		(layer "F.Cu")
	)
	(gr_line
		(start 376.219974 -14.612112)
		(end 376.350784 -14.70152)
		(stroke
			(width 0.05715)
			(type default)
		)
		(layer "F.Cu")
	)
	(gr_line
		(start 376.228102 -16.763238)
		(end 376.240548 -16.75511)
		(stroke
			(width 0.05715)
			(type default)
		)
		(layer "F.Cu")
	)
	(gr_line
		(start 376.240548 -16.75511)
		(end 376.25528 -16.752316)
		(stroke
			(width 0.05715)
			(type default)
		)
		(layer "F.Cu")
	)
	(gr_line
		(start 376.330972 -123.854972)
		(end 376.335036 -123.854972)
		(stroke
			(width 0.04445)
			(type default)
		)
		(layer "F.Cu")
	)
	(gr_line
		(start 376.406156 -3.444748)
		(end 376.685048 -3.72364)
		(stroke
			(width 0.05715)
			(type default)
		)
		(layer "F.Cu")
	)
	(gr_arc
		(start 376.42165 -129.02565)
		(mid 376.543629 -128.975153)
		(end 376.594116 -128.853184)
		(stroke
			(width 0.04445)
			(type default)
		)
		(layer "F.Cu")
	)
	(gr_line
		(start 376.467878 -3.011678)
		(end 376.542554 -2.937002)
		(stroke
			(width 0.05715)
			(type default)
		)
		(layer "F.Cu")
	)
	(gr_arc
		(start 376.469148 -127.46609)
		(mid 376.428792 -127.435669)
		(end 376.380248 -127.42164)
		(stroke
			(width 0.04445)
			(type default)
		)
		(layer "F.Cu")
	)
	(gr_arc
		(start 376.469148 -127.46609)
		(mid 376.509519 -127.496472)
		(end 376.558048 -127.51054)
		(stroke
			(width 0.04445)
			(type default)
		)
		(layer "F.Cu")
	)
	(gr_line
		(start 376.542554 -2.937002)
		(end 376.97029 -2.937002)
		(stroke
			(width 0.05715)
			(type default)
		)
		(layer "F.Cu")
	)
	(gr_line
		(start 376.558048 -127.51054)
		(end 376.824748 -127.51054)
		(stroke
			(width 0.04445)
			(type default)
		)
		(layer "F.Cu")
	)
	(gr_line
		(start 376.573288 -127.23114)
		(end 376.809508 -127.23114)
		(stroke
			(width 0.04445)
			(type default)
		)
		(layer "F.Cu")
	)
	(gr_arc
		(start 376.594116 -128.716278)
		(mid 376.543591 -128.594358)
		(end 376.42165 -128.543812)
		(stroke
			(width 0.04445)
			(type default)
		)
		(layer "F.Cu")
	)
	(gr_line
		(start 376.594116 -128.716278)
		(end 376.594116 -128.853184)
		(stroke
			(width 0.04445)
			(type default)
		)
		(layer "F.Cu")
	)
	(gr_line
		(start 376.678444 -10.916158)
		(end 376.950478 -11.188192)
		(stroke
			(width 0.05715)
			(type default)
		)
		(layer "F.Cu")
	)
	(gr_line
		(start 376.678444 -10.027158)
		(end 376.950478 -9.755124)
		(stroke
			(width 0.05715)
			(type default)
		)
		(layer "F.Cu")
	)
	(gr_line
		(start 376.685048 -8.5979)
		(end 376.912632 -8.825484)
		(stroke
			(width 0.05715)
			(type default)
		)
		(layer "F.Cu")
	)
	(gr_line
		(start 376.685048 -7.789926)
		(end 376.685048 -8.5979)
		(stroke
			(width 0.05715)
			(type default)
		)
		(layer "F.Cu")
	)
	(gr_line
		(start 376.685048 -3.72364)
		(end 376.685048 -4.389882)
		(stroke
			(width 0.05715)
			(type default)
		)
		(layer "F.Cu")
	)
	(gr_line
		(start 376.69216 -14.637512)
		(end 376.781568 -14.506702)
		(stroke
			(width 0.05715)
			(type default)
		)
		(layer "F.Cu")
	)
	(gr_line
		(start 376.766582 -14.8717)
		(end 377.265692 -14.778228)
		(stroke
			(width 0.05715)
			(type default)
		)
		(layer "F.Cu")
	)
	(gr_line
		(start 376.774964 -30.669484)
		(end 376.851164 -30.745684)
		(stroke
			(width 0.05715)
			(type default)
		)
		(layer "F.Cu")
	)
	(gr_line
		(start 376.774964 -29.439108)
		(end 377.313444 -29.439108)
		(stroke
			(width 0.05715)
			(type default)
		)
		(layer "F.Cu")
	)
	(gr_line
		(start 376.781568 -14.506702)
		(end 377.118626 -14.443456)
		(stroke
			(width 0.05715)
			(type default)
		)
		(layer "F.Cu")
	)
	(gr_arc
		(start 376.824748 -127.51054)
		(mid 376.873299 -127.496515)
		(end 376.913648 -127.46609)
		(stroke
			(width 0.04445)
			(type default)
		)
		(layer "F.Cu")
	)
	(gr_line
		(start 376.851164 -30.745684)
		(end 377.403868 -30.745684)
		(stroke
			(width 0.05715)
			(type default)
		)
		(layer "F.Cu")
	)
	(gr_line
		(start 376.964702 -32.642302)
		(end 377.933966 -32.642302)
		(stroke
			(width 0.05715)
			(type default)
		)
		(layer "F.Cu")
	)
	(gr_line
		(start 376.974862 -27.852116)
		(end 377.005596 -27.81173)
		(stroke
			(width 0.05715)
			(type default)
		)
		(layer "F.Cu")
	)
	(gr_arc
		(start 377.002548 -127.42164)
		(mid 376.954022 -127.435705)
		(end 376.913648 -127.46609)
		(stroke
			(width 0.04445)
			(type default)
		)
		(layer "F.Cu")
	)
	(gr_line
		(start 377.005596 -27.81173)
		(end 377.053602 -27.799538)
		(stroke
			(width 0.05715)
			(type default)
		)
		(layer "F.Cu")
	)
	(gr_line
		(start 377.118626 -14.443456)
		(end 377.249436 -14.532864)
		(stroke
			(width 0.05715)
			(type default)
		)
		(layer "F.Cu")
	)
	(gr_line
		(start 377.12396 -11.57732)
		(end 377.169172 -11.547348)
		(stroke
			(width 0.05715)
			(type default)
		)
		(layer "F.Cu")
	)
	(gr_line
		(start 377.127008 -12.488418)
		(end 377.13666 -12.482068)
		(stroke
			(width 0.05715)
			(type default)
		)
		(layer "F.Cu")
	)
	(gr_line
		(start 377.13666 -12.482068)
		(end 377.148344 -12.479528)
		(stroke
			(width 0.05715)
			(type default)
		)
		(layer "F.Cu")
	)
	(gr_line
		(start 377.165362 -48.540416)
		(end 377.193048 -48.533304)
		(stroke
			(width 0.05715)
			(type default)
		)
		(layer "F.Cu")
	)
	(gr_line
		(start 377.169172 -11.547348)
		(end 377.18492 -11.495532)
		(stroke
			(width 0.05715)
			(type default)
		)
		(layer "F.Cu")
	)
	(gr_line
		(start 377.178824 -49.551844)
		(end 377.20651 -49.544478)
		(stroke
			(width 0.05715)
			(type default)
		)
		(layer "F.Cu")
	)
	(gr_line
		(start 377.193048 -48.533304)
		(end 377.220734 -48.540416)
		(stroke
			(width 0.05715)
			(type default)
		)
		(layer "F.Cu")
	)
	(gr_line
		(start 377.19762 -117.77726)
		(end 377.197874 -117.777514)
		(stroke
			(width 0.05715)
			(type default)
		)
		(layer "F.Cu")
	)
	(gr_line
		(start 377.197874 -117.777514)
		(end 377.33605 -118.4402)
		(stroke
			(width 0.05715)
			(type default)
		)
		(layer "F.Cu")
	)
	(gr_line
		(start 377.20651 -49.544478)
		(end 377.233942 -49.55159)
		(stroke
			(width 0.05715)
			(type default)
		)
		(layer "F.Cu")
	)
	(gr_line
		(start 377.24334 -11.302492)
		(end 377.243594 -11.301984)
		(stroke
			(width 0.05715)
			(type default)
		)
		(layer "F.Cu")
	)
	(gr_line
		(start 377.257564 -8.825484)
		(end 377.485148 -8.5979)
		(stroke
			(width 0.05715)
			(type default)
		)
		(layer "F.Cu")
	)
	(gr_line
		(start 377.258326 -50.592736)
		(end 377.286266 -50.586132)
		(stroke
			(width 0.05715)
			(type default)
		)
		(layer "F.Cu")
	)
	(gr_line
		(start 377.286266 -50.586132)
		(end 377.313444 -50.594006)
		(stroke
			(width 0.05715)
			(type default)
		)
		(layer "F.Cu")
	)
	(gr_line
		(start 377.29541 -11.188192)
		(end 377.567444 -10.916158)
		(stroke
			(width 0.05715)
			(type default)
		)
		(layer "F.Cu")
	)
	(gr_line
		(start 377.29541 -9.755124)
		(end 377.567444 -10.027158)
		(stroke
			(width 0.05715)
			(type default)
		)
		(layer "F.Cu")
	)
	(gr_line
		(start 377.29668 -47.508922)
		(end 377.316746 -47.503842)
		(stroke
			(width 0.05715)
			(type default)
		)
		(layer "F.Cu")
	)
	(gr_line
		(start 377.313444 -29.439108)
		(end 377.5202 -29.232352)
		(stroke
			(width 0.05715)
			(type default)
		)
		(layer "F.Cu")
	)
	(gr_line
		(start 377.316746 -47.503842)
		(end 377.33732 -47.50816)
		(stroke
			(width 0.05715)
			(type default)
		)
		(layer "F.Cu")
	)
	(gr_line
		(start 377.33605 -116.72316)
		(end 377.83135 -116.953284)
		(stroke
			(width 0.05715)
			(type default)
		)
		(layer "F.Cu")
	)
	(gr_arc
		(start 377.358148 -127.46609)
		(mid 377.317792 -127.435669)
		(end 377.269248 -127.42164)
		(stroke
			(width 0.04445)
			(type default)
		)
		(layer "F.Cu")
	)
	(gr_arc
		(start 377.358148 -127.46609)
		(mid 377.398519 -127.496472)
		(end 377.447048 -127.51054)
		(stroke
			(width 0.04445)
			(type default)
		)
		(layer "F.Cu")
	)
	(gr_line
		(start 377.366022 -128.681226)
		(end 377.366022 -129.032)
		(stroke
			(width 0.04445)
			(type default)
		)
		(layer "F.Cu")
	)
	(gr_line
		(start 377.38177 -33.444434)
		(end 377.670314 -33.15589)
		(stroke
			(width 0.05715)
			(type default)
		)
		(layer "F.Cu")
	)
	(gr_line
		(start 377.403868 -30.745684)
		(end 377.5202 -30.629352)
		(stroke
			(width 0.05715)
			(type default)
		)
		(layer "F.Cu")
	)
	(gr_line
		(start 377.447048 -127.51054)
		(end 377.713748 -127.51054)
		(stroke
			(width 0.04445)
			(type default)
		)
		(layer "F.Cu")
	)
	(gr_line
		(start 377.462288 -127.23114)
		(end 377.698508 -127.23114)
		(stroke
			(width 0.04445)
			(type default)
		)
		(layer "F.Cu")
	)
	(gr_line
		(start 377.485148 -7.789926)
		(end 377.485148 -8.5979)
		(stroke
			(width 0.05715)
			(type default)
		)
		(layer "F.Cu")
	)
	(gr_arc
		(start 377.556522 -128.488186)
		(mid 377.59 -128.569008)
		(end 377.670822 -128.602486)
		(stroke
			(width 0.04445)
			(type default)
		)
		(layer "F.Cu")
	)
	(gr_line
		(start 377.590812 -14.468856)
		(end 377.68022 -14.338046)
		(stroke
			(width 0.05715)
			(type default)
		)
		(layer "F.Cu")
	)
	(gr_line
		(start 377.664726 -14.703298)
		(end 378.164852 -14.609318)
		(stroke
			(width 0.05715)
			(type default)
		)
		(layer "F.Cu")
	)
	(gr_line
		(start 377.670314 -33.15589)
		(end 378.06249 -33.15589)
		(stroke
			(width 0.05715)
			(type default)
		)
		(layer "F.Cu")
	)
	(gr_line
		(start 377.670822 -128.602486)
		(end 378.20473 -128.602486)
		(stroke
			(width 0.04445)
			(type default)
		)
		(layer "F.Cu")
	)
	(gr_line
		(start 377.68022 -14.338046)
		(end 378.017278 -14.2748)
		(stroke
			(width 0.05715)
			(type default)
		)
		(layer "F.Cu")
	)
	(gr_line
		(start 377.706128 -27.631136)
		(end 377.728988 -27.625294)
		(stroke
			(width 0.05715)
			(type default)
		)
		(layer "F.Cu")
	)
	(gr_arc
		(start 377.713748 -127.51054)
		(mid 377.762299 -127.496515)
		(end 377.802648 -127.46609)
		(stroke
			(width 0.04445)
			(type default)
		)
		(layer "F.Cu")
	)
	(gr_line
		(start 377.728988 -27.625294)
		(end 377.751594 -27.630374)
		(stroke
			(width 0.05715)
			(type default)
		)
		(layer "F.Cu")
	)
	(gr_line
		(start 377.83135 -121.01576)
		(end 378.32665 -121.245884)
		(stroke
			(width 0.05715)
			(type default)
		)
		(layer "F.Cu")
	)
	(gr_line
		(start 377.83135 -117.58168)
		(end 377.90755 -117.790722)
		(stroke
			(width 0.05715)
			(type default)
		)
		(layer "F.Cu")
	)
	(gr_line
		(start 377.83135 -115.86464)
		(end 378.32665 -116.094764)
		(stroke
			(width 0.05715)
			(type default)
		)
		(layer "F.Cu")
	)
	(gr_line
		(start 377.83135 -114.1476)
		(end 378.32665 -114.377724)
		(stroke
			(width 0.05715)
			(type default)
		)
		(layer "F.Cu")
	)
	(gr_arc
		(start 377.891548 -127.42164)
		(mid 377.843022 -127.435705)
		(end 377.802648 -127.46609)
		(stroke
			(width 0.04445)
			(type default)
		)
		(layer "F.Cu")
	)
	(gr_line
		(start 377.90755 -117.790722)
		(end 378.1171 -117.888004)
		(stroke
			(width 0.05715)
			(type default)
		)
		(layer "F.Cu")
	)
	(gr_line
		(start 377.933966 -32.642302)
		(end 378.254768 -32.3215)
		(stroke
			(width 0.05715)
			(type default)
		)
		(layer "F.Cu")
	)
	(gr_line
		(start 378.017278 -14.2748)
		(end 378.148342 -14.364462)
		(stroke
			(width 0.05715)
			(type default)
		)
		(layer "F.Cu")
	)
	(gr_line
		(start 378.026422 -129.032)
		(end 378.20473 -129.032)
		(stroke
			(width 0.04445)
			(type default)
		)
		(layer "F.Cu")
	)
	(gr_line
		(start 378.06249 -33.15589)
		(end 378.254768 -33.348168)
		(stroke
			(width 0.05715)
			(type default)
		)
		(layer "F.Cu")
	)
	(gr_line
		(start 378.1171 -117.888004)
		(end 378.32665 -117.811804)
		(stroke
			(width 0.05715)
			(type default)
		)
		(layer "F.Cu")
	)
	(gr_line
		(start 378.14758 -1.754886)
		(end 378.564902 -1.754886)
		(stroke
			(width 0.05715)
			(type default)
		)
		(layer "F.Cu")
	)
	(gr_arc
		(start 378.20473 -129.032)
		(mid 378.267572 -129.005951)
		(end 378.29363 -128.9431)
		(stroke
			(width 0.04445)
			(type default)
		)
		(layer "F.Cu")
	)
	(gr_line
		(start 378.254768 -33.348168)
		(end 378.254768 -33.7185)
		(stroke
			(width 0.05715)
			(type default)
		)
		(layer "F.Cu")
	)
	(gr_line
		(start 378.284994 -3.642106)
		(end 378.284994 -4.389882)
		(stroke
			(width 0.05715)
			(type default)
		)
		(layer "F.Cu")
	)
	(gr_line
		(start 378.284994 -3.642106)
		(end 378.512578 -3.414522)
		(stroke
			(width 0.05715)
			(type default)
		)
		(layer "F.Cu")
	)
	(gr_arc
		(start 378.29363 -128.691386)
		(mid 378.267589 -128.628523)
		(end 378.20473 -128.602486)
		(stroke
			(width 0.04445)
			(type default)
		)
		(layer "F.Cu")
	)
	(gr_line
		(start 378.29363 -128.691386)
		(end 378.29363 -128.9431)
		(stroke
			(width 0.04445)
			(type default)
		)
		(layer "F.Cu")
	)
	(gr_line
		(start 378.32665 -123.59132)
		(end 378.498608 -123.528582)
		(stroke
			(width 0.05715)
			(type default)
		)
		(layer "F.Cu")
	)
	(gr_line
		(start 378.32665 -121.87428)
		(end 378.753116 -122.0724)
		(stroke
			(width 0.05715)
			(type default)
		)
		(layer "F.Cu")
	)
	(gr_line
		(start 378.32665 -118.4402)
		(end 378.376688 -118.577106)
		(stroke
			(width 0.05715)
			(type default)
		)
		(layer "F.Cu")
	)
	(gr_line
		(start 378.32665 -116.72316)
		(end 378.82195 -116.953284)
		(stroke
			(width 0.05715)
			(type default)
		)
		(layer "F.Cu")
	)
	(gr_line
		(start 378.32665 -115.00612)
		(end 378.82195 -115.236244)
		(stroke
			(width 0.05715)
			(type default)
		)
		(layer "F.Cu")
	)
	(gr_line
		(start 378.376688 -118.577106)
		(end 378.685298 -118.720108)
		(stroke
			(width 0.05715)
			(type default)
		)
		(layer "F.Cu")
	)
	(gr_line
		(start 378.4092 -30.241494)
		(end 378.4092 -30.629352)
		(stroke
			(width 0.05715)
			(type default)
		)
		(layer "F.Cu")
	)
	(gr_line
		(start 378.4092 -30.241494)
		(end 378.505212 -30.145482)
		(stroke
			(width 0.05715)
			(type default)
		)
		(layer "F.Cu")
	)
	(gr_line
		(start 378.4092 -29.704538)
		(end 378.505212 -29.80055)
		(stroke
			(width 0.05715)
			(type default)
		)
		(layer "F.Cu")
	)
	(gr_line
		(start 378.4092 -29.232352)
		(end 378.4092 -29.704538)
		(stroke
			(width 0.05715)
			(type default)
		)
		(layer "F.Cu")
	)
	(gr_line
		(start 378.471684 -12.442698)
		(end 378.49175 -12.43838)
		(stroke
			(width 0.05715)
			(type default)
		)
		(layer "F.Cu")
	)
	(gr_line
		(start 378.4854 -132.08)
		(end 378.530104 -131.642104)
		(stroke
			(width 0.04445)
			(type default)
		)
		(layer "F.Cu")
	)
	(gr_line
		(start 378.48921 -14.300454)
		(end 378.578872 -14.16939)
		(stroke
			(width 0.05715)
			(type default)
		)
		(layer "F.Cu")
	)
	(gr_line
		(start 378.49175 -12.43838)
		(end 378.50826 -12.42568)
		(stroke
			(width 0.05715)
			(type default)
		)
		(layer "F.Cu")
	)
	(gr_line
		(start 378.498608 -123.528582)
		(end 378.759212 -123.649486)
		(stroke
			(width 0.05715)
			(type default)
		)
		(layer "F.Cu")
	)
	(gr_line
		(start 378.508768 -49.119536)
		(end 378.53874 -49.12741)
		(stroke
			(width 0.05715)
			(type default)
		)
		(layer "F.Cu")
	)
	(gr_line
		(start 378.530104 -130.205734)
		(end 378.530104 -130.441954)
		(stroke
			(width 0.04445)
			(type default)
		)
		(layer "F.Cu")
	)
	(gr_line
		(start 378.53874 -49.12741)
		(end 378.568712 -49.118774)
		(stroke
			(width 0.05715)
			(type default)
		)
		(layer "F.Cu")
	)
	(gr_line
		(start 378.562362 -14.534896)
		(end 379.064266 -14.440662)
		(stroke
			(width 0.05715)
			(type default)
		)
		(layer "F.Cu")
	)
	(gr_line
		(start 378.564902 -1.754886)
		(end 378.627386 -1.81737)
		(stroke
			(width 0.05715)
			(type default)
		)
		(layer "F.Cu")
	)
	(gr_line
		(start 378.572522 -48.020478)
		(end 378.612654 -48.029114)
		(stroke
			(width 0.05715)
			(type default)
		)
		(layer "F.Cu")
	)
	(gr_line
		(start 378.573538 -50.139092)
		(end 378.59716 -50.144934)
		(stroke
			(width 0.05715)
			(type default)
		)
		(layer "F.Cu")
	)
	(gr_line
		(start 378.578872 -14.16939)
		(end 378.91593 -14.106144)
		(stroke
			(width 0.05715)
			(type default)
		)
		(layer "F.Cu")
	)
	(gr_line
		(start 378.592588 -127.497332)
		(end 378.75972 -127.3302)
		(stroke
			(width 0.04445)
			(type default)
		)
		(layer "F.Cu")
	)
	(gr_line
		(start 378.59716 -50.144934)
		(end 378.620274 -50.1396)
		(stroke
			(width 0.05715)
			(type default)
		)
		(layer "F.Cu")
	)
	(gr_line
		(start 378.612654 -48.029114)
		(end 378.651516 -48.013112)
		(stroke
			(width 0.05715)
			(type default)
		)
		(layer "F.Cu")
	)
	(gr_line
		(start 378.679202 -2.539746)
		(end 378.679202 -2.589022)
		(stroke
			(width 0.05715)
			(type default)
		)
		(layer "F.Cu")
	)
	(gr_arc
		(start 378.685298 -127.737108)
		(mid 378.635134 -127.744114)
		(end 378.59081 -127.768604)
		(stroke
			(width 0.04445)
			(type default)
		)
		(layer "F.Cu")
	)
	(gr_arc
		(start 378.685298 -127.737108)
		(mid 378.735283 -127.729951)
		(end 378.779532 -127.705612)
		(stroke
			(width 0.04445)
			(type default)
		)
		(layer "F.Cu")
	)
	(gr_line
		(start 378.685298 -118.720108)
		(end 378.82195 -118.670324)
		(stroke
			(width 0.05715)
			(type default)
		)
		(layer "F.Cu")
	)
	(gr_arc
		(start 378.720604 -131.492498)
		(mid 378.758992 -131.585174)
		(end 378.851668 -131.623562)
		(stroke
			(width 0.04445)
			(type default)
		)
		(layer "F.Cu")
	)
	(gr_arc
		(start 378.720604 -130.012694)
		(mid 378.734669 -130.06122)
		(end 378.765054 -130.101594)
		(stroke
			(width 0.04445)
			(type default)
		)
		(layer "F.Cu")
	)
	(gr_line
		(start 378.737368 -125.938026)
		(end 378.86259 -125.730254)
		(stroke
			(width 0.04445)
			(type default)
		)
		(layer "F.Cu")
	)
	(gr_line
		(start 378.753116 -122.0724)
		(end 378.82195 -122.104404)
		(stroke
			(width 0.05715)
			(type default)
		)
		(layer "F.Cu")
	)
	(gr_line
		(start 378.759212 -123.649486)
		(end 378.82195 -123.821444)
		(stroke
			(width 0.05715)
			(type default)
		)
		(layer "F.Cu")
	)
	(gr_arc
		(start 378.765054 -130.546094)
		(mid 378.734633 -130.58645)
		(end 378.720604 -130.634994)
		(stroke
			(width 0.04445)
			(type default)
		)
		(layer "F.Cu")
	)
	(gr_arc
		(start 378.765054 -130.546094)
		(mid 378.795455 -130.505728)
		(end 378.809504 -130.457194)
		(stroke
			(width 0.04445)
			(type default)
		)
		(layer "F.Cu")
	)
	(gr_line
		(start 378.779532 -127.705612)
		(end 378.968 -127.517144)
		(stroke
			(width 0.04445)
			(type default)
		)
		(layer "F.Cu")
	)
	(gr_line
		(start 378.783342 -126.165102)
		(end 378.985018 -126.165102)
		(stroke
			(width 0.04445)
			(type default)
		)
		(layer "F.Cu")
	)
	(gr_arc
		(start 378.809504 -130.190494)
		(mid 378.795468 -130.141951)
		(end 378.765054 -130.101594)
		(stroke
			(width 0.04445)
			(type default)
		)
		(layer "F.Cu")
	)
	(gr_line
		(start 378.809504 -130.190494)
		(end 378.809504 -130.457194)
		(stroke
			(width 0.04445)
			(type default)
		)
		(layer "F.Cu")
	)
	(gr_line
		(start 378.82195 -122.7328)
		(end 379.31725 -122.962924)
		(stroke
			(width 0.05715)
			(type default)
		)
		(layer "F.Cu")
	)
	(gr_line
		(start 378.82195 -121.01576)
		(end 379.31725 -121.245884)
		(stroke
			(width 0.05715)
			(type default)
		)
		(layer "F.Cu")
	)
	(gr_line
		(start 378.82195 -119.29872)
		(end 379.31725 -119.528844)
		(stroke
			(width 0.05715)
			(type default)
		)
		(layer "F.Cu")
	)
	(gr_line
		(start 378.82195 -115.86464)
		(end 379.31725 -116.094764)
		(stroke
			(width 0.05715)
			(type default)
		)
		(layer "F.Cu")
	)
	(gr_line
		(start 378.82195 -114.1476)
		(end 378.822204 -114.1476)
		(stroke
			(width 0.05715)
			(type default)
		)
		(layer "F.Cu")
	)
	(gr_line
		(start 378.822204 -114.1476)
		(end 379.31725 -114.377724)
		(stroke
			(width 0.05715)
			(type default)
		)
		(layer "F.Cu")
	)
	(gr_line
		(start 378.831094 -2.778506)
		(end 378.831094 -2.827782)
		(stroke
			(width 0.05715)
			(type default)
		)
		(layer "F.Cu")
	)
	(gr_line
		(start 378.851668 -131.623562)
		(end 379.224794 -131.623562)
		(stroke
			(width 0.04445)
			(type default)
		)
		(layer "F.Cu")
	)
	(gr_line
		(start 378.85751 -3.414522)
		(end 379.085094 -3.642106)
		(stroke
			(width 0.05715)
			(type default)
		)
		(layer "F.Cu")
	)
	(gr_line
		(start 378.86259 -125.730254)
		(end 378.938282 -125.485652)
		(stroke
			(width 0.04445)
			(type default)
		)
		(layer "F.Cu")
	)
	(gr_line
		(start 378.876306 -28.120848)
		(end 378.930154 -28.132532)
		(stroke
			(width 0.05715)
			(type default)
		)
		(layer "F.Cu")
	)
	(gr_line
		(start 378.91593 -14.106144)
		(end 379.046994 -14.195806)
		(stroke
			(width 0.05715)
			(type default)
		)
		(layer "F.Cu")
	)
	(gr_line
		(start 378.926344 -10.941558)
		(end 379.198378 -11.213592)
		(stroke
			(width 0.05715)
			(type default)
		)
		(layer "F.Cu")
	)
	(gr_line
		(start 378.926344 -10.052558)
		(end 379.198378 -9.780524)
		(stroke
			(width 0.05715)
			(type default)
		)
		(layer "F.Cu")
	)
	(gr_line
		(start 378.930154 -28.132532)
		(end 378.97943 -28.105608)
		(stroke
			(width 0.05715)
			(type default)
		)
		(layer "F.Cu")
	)
	(gr_line
		(start 378.938282 -125.485652)
		(end 378.970794 -125.38075)
		(stroke
			(width 0.04445)
			(type default)
		)
		(layer "F.Cu")
	)
	(gr_arc
		(start 378.968 -127.517144)
		(mid 378.992498 -127.472816)
		(end 378.999496 -127.422656)
		(stroke
			(width 0.04445)
			(type default)
		)
		(layer "F.Cu")
	)
	(gr_line
		(start 378.970794 -125.38075)
		(end 378.985018 -125.33503)
		(stroke
			(width 0.04445)
			(type default)
		)
		(layer "F.Cu")
	)
	(gr_line
		(start 378.972318 -1.81737)
		(end 379.034802 -1.754886)
		(stroke
			(width 0.05715)
			(type default)
		)
		(layer "F.Cu")
	)
	(gr_arc
		(start 379.030992 -127.328422)
		(mid 379.00664 -127.372653)
		(end 378.999496 -127.422656)
		(stroke
			(width 0.04445)
			(type default)
		)
		(layer "F.Cu")
	)
	(gr_line
		(start 379.034802 -1.754886)
		(end 379.41758 -1.754886)
		(stroke
			(width 0.05715)
			(type default)
		)
		(layer "F.Cu")
	)
	(gr_line
		(start 379.085094 -8.5979)
		(end 379.312678 -8.825484)
		(stroke
			(width 0.05715)
			(type default)
		)
		(layer "F.Cu")
	)
	(gr_line
		(start 379.085094 -7.789926)
		(end 379.085094 -8.5979)
		(stroke
			(width 0.05715)
			(type default)
		)
		(layer "F.Cu")
	)
	(gr_line
		(start 379.085094 -3.642106)
		(end 379.085094 -4.389882)
		(stroke
			(width 0.05715)
			(type default)
		)
		(layer "F.Cu")
	)
	(gr_line
		(start 379.104906 -128.380236)
		(end 379.104906 -128.616456)
		(stroke
			(width 0.04445)
			(type default)
		)
		(layer "F.Cu")
	)
	(gr_line
		(start 379.143768 -33.374076)
		(end 379.143768 -33.7185)
		(stroke
			(width 0.05715)
			(type default)
		)
		(layer "F.Cu")
	)
	(gr_line
		(start 379.143768 -33.374076)
		(end 379.324362 -33.193482)
		(stroke
			(width 0.05715)
			(type default)
		)
		(layer "F.Cu")
	)
	(gr_line
		(start 379.143768 -32.667956)
		(end 379.324362 -32.84855)
		(stroke
			(width 0.05715)
			(type default)
		)
		(layer "F.Cu")
	)
	(gr_line
		(start 379.143768 -32.3215)
		(end 379.143768 -32.667956)
		(stroke
			(width 0.05715)
			(type default)
		)
		(layer "F.Cu")
	)
	(gr_line
		(start 379.1458 -132.08)
		(end 379.249686 -132.08)
		(stroke
			(width 0.04445)
			(type default)
		)
		(layer "F.Cu")
	)
	(gr_line
		(start 379.17247 -125.829314)
		(end 379.268736 -126.061978)
		(stroke
			(width 0.04445)
			(type default)
		)
		(layer "F.Cu")
	)
	(gr_line
		(start 379.17247 -125.59792)
		(end 379.17247 -125.829314)
		(stroke
			(width 0.04445)
			(type default)
		)
		(layer "F.Cu")
	)
	(gr_line
		(start 379.17247 -125.59792)
		(end 379.284738 -125.485652)
		(stroke
			(width 0.04445)
			(type default)
		)
		(layer "F.Cu")
	)
	(gr_arc
		(start 379.249686 -132.08)
		(mid 379.362322 -132.033362)
		(end 379.408944 -131.920742)
		(stroke
			(width 0.04445)
			(type default)
		)
		(layer "F.Cu")
	)
	(gr_line
		(start 379.284738 -125.485652)
		(end 379.321822 -125.38075)
		(stroke
			(width 0.04445)
			(type default)
		)
		(layer "F.Cu")
	)
	(gr_arc
		(start 379.295406 -128.187196)
		(mid 379.309471 -128.235722)
		(end 379.339856 -128.276096)
		(stroke
			(width 0.04445)
			(type default)
		)
		(layer "F.Cu")
	)
	(gr_line
		(start 379.2982 -30.629352)
		(end 380.168404 -30.629352)
		(stroke
			(width 0.05715)
			(type default)
		)
		(layer "F.Cu")
	)
	(gr_line
		(start 379.2982 -29.232352)
		(end 380.151132 -29.232352)
		(stroke
			(width 0.05715)
			(type default)
		)
		(layer "F.Cu")
	)
	(gr_line
		(start 379.31725 -123.59132)
		(end 379.81255 -123.821444)
		(stroke
			(width 0.05715)
			(type default)
		)
		(layer "F.Cu")
	)
	(gr_line
		(start 379.31725 -121.87428)
		(end 379.743716 -122.0724)
		(stroke
			(width 0.05715)
			(type default)
		)
		(layer "F.Cu")
	)
	(gr_line
		(start 379.31725 -120.15724)
		(end 379.81255 -120.387364)
		(stroke
			(width 0.05715)
			(type default)
		)
		(layer "F.Cu")
	)
	(gr_line
		(start 379.31725 -118.4402)
		(end 379.81255 -118.670324)
		(stroke
			(width 0.05715)
			(type default)
		)
		(layer "F.Cu")
	)
	(gr_line
		(start 379.31725 -116.72316)
		(end 379.81255 -116.953284)
		(stroke
			(width 0.05715)
			(type default)
		)
		(layer "F.Cu")
	)
	(gr_line
		(start 379.321822 -125.38075)
		(end 379.48489 -124.919994)
		(stroke
			(width 0.04445)
			(type default)
		)
		(layer "F.Cu")
	)
	(gr_arc
		(start 379.339856 -128.720596)
		(mid 379.309435 -128.760952)
		(end 379.295406 -128.809496)
		(stroke
			(width 0.04445)
			(type default)
		)
		(layer "F.Cu")
	)
	(gr_arc
		(start 379.339856 -128.720596)
		(mid 379.370257 -128.68023)
		(end 379.384306 -128.631696)
		(stroke
			(width 0.04445)
			(type default)
		)
		(layer "F.Cu")
	)
	(gr_line
		(start 379.351794 -9.13511)
		(end 379.351794 -9.1694)
		(stroke
			(width 0.05715)
			(type default)
		)
		(layer "F.Cu")
	)
	(gr_line
		(start 379.382274 -47.711106)
		(end 379.410976 -47.699168)
		(stroke
			(width 0.05715)
			(type default)
		)
		(layer "F.Cu")
	)
	(gr_arc
		(start 379.384306 -128.364996)
		(mid 379.37027 -128.316452)
		(end 379.339856 -128.276096)
		(stroke
			(width 0.04445)
			(type default)
		)
		(layer "F.Cu")
	)
	(gr_line
		(start 379.384306 -128.364996)
		(end 379.384306 -128.631696)
		(stroke
			(width 0.04445)
			(type default)
		)
		(layer "F.Cu")
	)
	(gr_arc
		(start 379.408944 -131.807712)
		(mid 379.355012 -131.677493)
		(end 379.224794 -131.623562)
		(stroke
			(width 0.04445)
			(type default)
		)
		(layer "F.Cu")
	)
	(gr_line
		(start 379.408944 -131.807712)
		(end 379.408944 -131.920742)
		(stroke
			(width 0.04445)
			(type default)
		)
		(layer "F.Cu")
	)
	(gr_line
		(start 379.410976 -47.699168)
		(end 379.429772 -47.674276)
		(stroke
			(width 0.05715)
			(type default)
		)
		(layer "F.Cu")
	)
	(gr_line
		(start 379.42266 -11.71702)
		(end 379.4887 -11.665712)
		(stroke
			(width 0.05715)
			(type default)
		)
		(layer "F.Cu")
	)
	(gr_line
		(start 379.461776 -125.77318)
		(end 379.461776 -125.875034)
		(stroke
			(width 0.04445)
			(type default)
		)
		(layer "F.Cu")
	)
	(gr_line
		(start 379.461776 -125.77318)
		(end 379.48489 -125.750066)
		(stroke
			(width 0.04445)
			(type default)
		)
		(layer "F.Cu")
	)
	(gr_line
		(start 379.464824 -25.96642)
		(end 379.47727 -25.925526)
		(stroke
			(width 0.05715)
			(type default)
		)
		(layer "F.Cu")
	)
	(gr_line
		(start 379.464824 -25.96642)
		(end 379.477778 -26.00579)
		(stroke
			(width 0.05715)
			(type default)
		)
		(layer "F.Cu")
	)
	(gr_line
		(start 379.4887 -9.37387)
		(end 379.4887 -9.40816)
		(stroke
			(width 0.05715)
			(type default)
		)
		(layer "F.Cu")
	)
	(gr_line
		(start 379.54331 -11.213592)
		(end 379.815344 -10.941558)
		(stroke
			(width 0.05715)
			(type default)
		)
		(layer "F.Cu")
	)
	(gr_line
		(start 379.54331 -9.780524)
		(end 379.815344 -10.052558)
		(stroke
			(width 0.05715)
			(type default)
		)
		(layer "F.Cu")
	)
	(gr_line
		(start 379.65761 -8.825484)
		(end 379.885194 -8.5979)
		(stroke
			(width 0.05715)
			(type default)
		)
		(layer "F.Cu")
	)
	(gr_line
		(start 379.664976 -21.613114)
		(end 379.673612 -21.580856)
		(stroke
			(width 0.05715)
			(type default)
		)
		(layer "F.Cu")
	)
	(gr_line
		(start 379.664976 -21.613114)
		(end 379.67412 -21.64461)
		(stroke
			(width 0.05715)
			(type default)
		)
		(layer "F.Cu")
	)
	(gr_line
		(start 379.670818 -128.727708)
		(end 379.670818 -128.963928)
		(stroke
			(width 0.04445)
			(type default)
		)
		(layer "F.Cu")
	)
	(gr_line
		(start 379.699266 -126.492254)
		(end 379.699266 -126.507494)
		(stroke
			(width 0.04445)
			(type default)
		)
		(layer "F.Cu")
	)
	(gr_line
		(start 379.699266 -126.006606)
		(end 379.699266 -126.067312)
		(stroke
			(width 0.04445)
			(type default)
		)
		(layer "F.Cu")
	)
	(gr_line
		(start 379.699266 -126.006606)
		(end 379.770894 -125.934978)
		(stroke
			(width 0.04445)
			(type default)
		)
		(layer "F.Cu")
	)
	(gr_line
		(start 379.743716 -122.0724)
		(end 379.81255 -122.104404)
		(stroke
			(width 0.05715)
			(type default)
		)
		(layer "F.Cu")
	)
	(gr_line
		(start 379.770894 -125.934978)
		(end 379.931422 -125.485652)
		(stroke
			(width 0.04445)
			(type default)
		)
		(layer "F.Cu")
	)
	(gr_line
		(start 379.7935 -126.682754)
		(end 379.7935 -126.697994)
		(stroke
			(width 0.04445)
			(type default)
		)
		(layer "F.Cu")
	)
	(gr_line
		(start 379.81255 -122.7328)
		(end 380.30785 -122.962924)
		(stroke
			(width 0.05715)
			(type default)
		)
		(layer "F.Cu")
	)
	(gr_line
		(start 379.81255 -121.01576)
		(end 380.30785 -121.245884)
		(stroke
			(width 0.05715)
			(type default)
		)
		(layer "F.Cu")
	)
	(gr_line
		(start 379.81255 -119.29872)
		(end 379.878082 -119.3292)
		(stroke
			(width 0.05715)
			(type default)
		)
		(layer "F.Cu")
	)
	(gr_line
		(start 379.81255 -117.58168)
		(end 380.30785 -117.811804)
		(stroke
			(width 0.05715)
			(type default)
		)
		(layer "F.Cu")
	)
	(gr_line
		(start 379.83795 -27.639518)
		(end 379.905768 -27.602688)
		(stroke
			(width 0.05715)
			(type default)
		)
		(layer "F.Cu")
	)
	(gr_arc
		(start 379.861318 -128.534668)
		(mid 379.875383 -128.583194)
		(end 379.905768 -128.623568)
		(stroke
			(width 0.04445)
			(type default)
		)
		(layer "F.Cu")
	)
	(gr_line
		(start 379.878082 -119.3292)
		(end 380.30785 -119.528844)
		(stroke
			(width 0.05715)
			(type default)
		)
		(layer "F.Cu")
	)
	(gr_line
		(start 379.885194 -7.789926)
		(end 379.885194 -8.5979)
		(stroke
			(width 0.05715)
			(type default)
		)
		(layer "F.Cu")
	)
	(gr_line
		(start 379.892306 -126.257812)
		(end 379.985016 -126.165102)
		(stroke
			(width 0.04445)
			(type default)
		)
		(layer "F.Cu")
	)
	(gr_arc
		(start 379.905768 -129.068068)
		(mid 379.875347 -129.108424)
		(end 379.861318 -129.156968)
		(stroke
			(width 0.04445)
			(type default)
		)
		(layer "F.Cu")
	)
	(gr_arc
		(start 379.905768 -129.068068)
		(mid 379.936159 -129.027699)
		(end 379.950218 -128.979168)
		(stroke
			(width 0.04445)
			(type default)
		)
		(layer "F.Cu")
	)
	(gr_line
		(start 379.905768 -27.602688)
		(end 379.92177 -27.527504)
		(stroke
			(width 0.05715)
			(type default)
		)
		(layer "F.Cu")
	)
	(gr_line
		(start 379.931422 -125.485652)
		(end 379.96876 -125.38075)
		(stroke
			(width 0.04445)
			(type default)
		)
		(layer "F.Cu")
	)
	(gr_arc
		(start 379.950218 -128.712468)
		(mid 379.936204 -128.663908)
		(end 379.905768 -128.623568)
		(stroke
			(width 0.04445)
			(type default)
		)
		(layer "F.Cu")
	)
	(gr_line
		(start 379.950218 -128.712468)
		(end 379.950218 -128.979168)
		(stroke
			(width 0.04445)
			(type default)
		)
		(layer "F.Cu")
	)
	(gr_line
		(start 379.965712 -51.60137)
		(end 380.00051 -51.611276)
		(stroke
			(width 0.05715)
			(type default)
		)
		(layer "F.Cu")
	)
	(gr_line
		(start 379.96876 -125.38075)
		(end 379.985016 -125.33503)
		(stroke
			(width 0.04445)
			(type default)
		)
		(layer "F.Cu")
	)
	(gr_line
		(start 380.00051 -51.611276)
		(end 380.034546 -51.601116)
		(stroke
			(width 0.05715)
			(type default)
		)
		(layer "F.Cu")
	)
	(gr_line
		(start 380.005082 -129.933192)
		(end 380.286768 -130.214878)
		(stroke
			(width 0.04445)
			(type default)
		)
		(layer "F.Cu")
	)
	(gr_line
		(start 380.032768 -33.7185)
		(end 381.055118 -33.7185)
		(stroke
			(width 0.05715)
			(type default)
		)
		(layer "F.Cu")
	)
	(gr_line
		(start 380.032768 -32.3215)
		(end 380.28245 -32.3215)
		(stroke
			(width 0.05715)
			(type default)
		)
		(layer "F.Cu")
	)
	(gr_line
		(start 380.033784 -26.921206)
		(end 380.043436 -26.950924)
		(stroke
			(width 0.05715)
			(type default)
		)
		(layer "F.Cu")
	)
	(gr_line
		(start 380.037086 -26.981404)
		(end 380.043436 -26.950924)
		(stroke
			(width 0.05715)
			(type default)
		)
		(layer "F.Cu")
	)
	(gr_arc
		(start 380.118112 -129.776728)
		(mid 380.162488 -129.800997)
		(end 380.2126 -129.80797)
		(stroke
			(width 0.04445)
			(type default)
		)
		(layer "F.Cu")
	)
	(gr_line
		(start 380.146306 -19.829526)
		(end 380.1491 -19.819366)
		(stroke
			(width 0.05715)
			(type default)
		)
		(layer "F.Cu")
	)
	(gr_line
		(start 380.1491 -19.819366)
		(end 380.154942 -19.811492)
		(stroke
			(width 0.05715)
			(type default)
		)
		(layer "F.Cu")
	)
	(gr_line
		(start 380.158752 -127.034036)
		(end 380.158752 -127.270256)
		(stroke
			(width 0.04445)
			(type default)
		)
		(layer "F.Cu")
	)
	(gr_line
		(start 380.158752 -126.536196)
		(end 380.161292 -126.530608)
		(stroke
			(width 0.04445)
			(type default)
		)
		(layer "F.Cu")
	)
	(gr_line
		(start 380.171198 -125.822202)
		(end 380.268226 -126.05639)
		(stroke
			(width 0.04445)
			(type default)
		)
		(layer "F.Cu")
	)
	(gr_line
		(start 380.171198 -125.684788)
		(end 380.171198 -125.822202)
		(stroke
			(width 0.04445)
			(type default)
		)
		(layer "F.Cu")
	)
	(gr_line
		(start 380.171198 -125.684788)
		(end 380.217172 -125.57379)
		(stroke
			(width 0.04445)
			(type default)
		)
		(layer "F.Cu")
	)
	(gr_line
		(start 380.217172 -125.57379)
		(end 380.253748 -125.537214)
		(stroke
			(width 0.04445)
			(type default)
		)
		(layer "F.Cu")
	)
	(gr_line
		(start 380.253748 -125.537214)
		(end 380.273052 -125.485652)
		(stroke
			(width 0.04445)
			(type default)
		)
		(layer "F.Cu")
	)
	(gr_line
		(start 380.273052 -125.485652)
		(end 380.312422 -125.38075)
		(stroke
			(width 0.04445)
			(type default)
		)
		(layer "F.Cu")
	)
	(gr_line
		(start 380.28245 -32.3215)
		(end 380.380494 -32.223456)
		(stroke
			(width 0.05715)
			(type default)
		)
		(layer "F.Cu")
	)
	(gr_arc
		(start 380.306834 -129.839466)
		(mid 380.262598 -129.815096)
		(end 380.2126 -129.80797)
		(stroke
			(width 0.04445)
			(type default)
		)
		(layer "F.Cu")
	)
	(gr_line
		(start 380.306834 -129.839466)
		(end 380.495302 -130.028188)
		(stroke
			(width 0.04445)
			(type default)
		)
		(layer "F.Cu")
	)
	(gr_line
		(start 380.30785 -123.59132)
		(end 380.80315 -123.821444)
		(stroke
			(width 0.05715)
			(type default)
		)
		(layer "F.Cu")
	)
	(gr_line
		(start 380.30785 -120.15724)
		(end 380.80315 -120.387364)
		(stroke
			(width 0.05715)
			(type default)
		)
		(layer "F.Cu")
	)
	(gr_line
		(start 380.30785 -118.4402)
		(end 380.799848 -118.6688)
		(stroke
			(width 0.05715)
			(type default)
		)
		(layer "F.Cu")
	)
	(gr_line
		(start 380.30785 -116.72316)
		(end 380.80315 -116.953284)
		(stroke
			(width 0.05715)
			(type default)
		)
		(layer "F.Cu")
	)
	(gr_line
		(start 380.312422 -125.38075)
		(end 380.484888 -124.919994)
		(stroke
			(width 0.04445)
			(type default)
		)
		(layer "F.Cu")
	)
	(gr_arc
		(start 380.349252 -126.840996)
		(mid 380.363317 -126.889522)
		(end 380.393702 -126.929896)
		(stroke
			(width 0.04445)
			(type default)
		)
		(layer "F.Cu")
	)
	(gr_line
		(start 380.380494 -32.223456)
		(end 381.079756 -32.223456)
		(stroke
			(width 0.05715)
			(type default)
		)
		(layer "F.Cu")
	)
	(gr_arc
		(start 380.393702 -127.374396)
		(mid 380.363281 -127.414752)
		(end 380.349252 -127.463296)
		(stroke
			(width 0.04445)
			(type default)
		)
		(layer "F.Cu")
	)
	(gr_arc
		(start 380.393702 -127.374396)
		(mid 380.424094 -127.334027)
		(end 380.438152 -127.285496)
		(stroke
			(width 0.04445)
			(type default)
		)
		(layer "F.Cu")
	)
	(gr_arc
		(start 380.438152 -127.018796)
		(mid 380.424112 -126.970256)
		(end 380.393702 -126.929896)
		(stroke
			(width 0.04445)
			(type default)
		)
		(layer "F.Cu")
	)
	(gr_line
		(start 380.438152 -127.018796)
		(end 380.438152 -127.285496)
		(stroke
			(width 0.04445)
			(type default)
		)
		(layer "F.Cu")
	)
	(gr_line
		(start 380.455932 -23.562818)
		(end 380.467108 -23.526242)
		(stroke
			(width 0.05715)
			(type default)
		)
		(layer "F.Cu")
	)
	(gr_line
		(start 380.45644 -23.489412)
		(end 380.467108 -23.526242)
		(stroke
			(width 0.05715)
			(type default)
		)
		(layer "F.Cu")
	)
	(gr_line
		(start 380.458726 -126.309374)
		(end 380.461266 -126.303786)
		(stroke
			(width 0.04445)
			(type default)
		)
		(layer "F.Cu")
	)
	(gr_line
		(start 380.461266 -125.925834)
		(end 380.498096 -125.889004)
		(stroke
			(width 0.04445)
			(type default)
		)
		(layer "F.Cu")
	)
	(gr_line
		(start 380.484888 -125.750066)
		(end 380.498096 -125.763274)
		(stroke
			(width 0.04445)
			(type default)
		)
		(layer "F.Cu")
	)
	(gr_line
		(start 380.498096 -125.763274)
		(end 380.498096 -125.889004)
		(stroke
			(width 0.04445)
			(type default)
		)
		(layer "F.Cu")
	)
	(gr_line
		(start 380.50597 -130.746754)
		(end 380.50597 -131.094988)
		(stroke
			(width 0.04445)
			(type default)
		)
		(layer "F.Cu")
	)
	(gr_line
		(start 380.510542 -48.555402)
		(end 380.553468 -48.542956)
		(stroke
			(width 0.05715)
			(type default)
		)
		(layer "F.Cu")
	)
	(gr_arc
		(start 380.526798 -130.122422)
		(mid 380.519647 -130.072434)
		(end 380.495302 -130.028188)
		(stroke
			(width 0.04445)
			(type default)
		)
		(layer "F.Cu")
	)
	(gr_arc
		(start 380.526798 -130.122422)
		(mid 380.533748 -130.172416)
		(end 380.55804 -130.216656)
		(stroke
			(width 0.04445)
			(type default)
		)
		(layer "F.Cu")
	)
	(gr_line
		(start 380.553468 -48.542956)
		(end 380.580138 -48.50765)
		(stroke
			(width 0.05715)
			(type default)
		)
		(layer "F.Cu")
	)
	(gr_line
		(start 380.562358 -129.092706)
		(end 380.70917 -128.739138)
		(stroke
			(width 0.04445)
			(type default)
		)
		(layer "F.Cu")
	)
	(gr_line
		(start 380.65964 -26.097484)
		(end 380.723394 -26.097484)
		(stroke
			(width 0.05715)
			(type default)
		)
		(layer "F.Cu")
	)
	(gr_line
		(start 380.67107 -25.278588)
		(end 380.87681 -25.484328)
		(stroke
			(width 0.05715)
			(type default)
		)
		(layer "F.Cu")
	)
	(gr_arc
		(start 380.69647 -130.553714)
		(mid 380.72288 -130.617474)
		(end 380.78664 -130.643884)
		(stroke
			(width 0.04445)
			(type default)
		)
		(layer "F.Cu")
	)
	(gr_line
		(start 380.697232 -126.294642)
		(end 380.70917 -126.30658)
		(stroke
			(width 0.04445)
			(type default)
		)
		(layer "F.Cu")
	)
	(gr_line
		(start 380.697232 -126.010416)
		(end 380.697232 -126.294642)
		(stroke
			(width 0.04445)
			(type default)
		)
		(layer "F.Cu")
	)
	(gr_line
		(start 380.697232 -126.010416)
		(end 380.820422 -125.784864)
		(stroke
			(width 0.04445)
			(type default)
		)
		(layer "F.Cu")
	)
	(gr_line
		(start 380.70917 -128.739138)
		(end 380.713488 -128.65481)
		(stroke
			(width 0.04445)
			(type default)
		)
		(layer "F.Cu")
	)
	(gr_line
		(start 380.70917 -128.65481)
		(end 380.713234 -128.654048)
		(stroke
			(width 0.04445)
			(type default)
		)
		(layer "F.Cu")
	)
	(gr_line
		(start 380.70917 -127.599186)
		(end 380.70917 -127.835406)
		(stroke
			(width 0.04445)
			(type default)
		)
		(layer "F.Cu")
	)
	(gr_line
		(start 380.70917 -126.710186)
		(end 380.70917 -126.946406)
		(stroke
			(width 0.04445)
			(type default)
		)
		(layer "F.Cu")
	)
	(gr_line
		(start 380.723394 -26.097484)
		(end 381.09271 -25.728168)
		(stroke
			(width 0.05715)
			(type default)
		)
		(layer "F.Cu")
	)
	(gr_line
		(start 380.78664 -130.643884)
		(end 381.204724 -130.643884)
		(stroke
			(width 0.04445)
			(type default)
		)
		(layer "F.Cu")
	)
	(gr_line
		(start 380.799848 -118.6688)
		(end 380.80315 -118.670324)
		(stroke
			(width 0.05715)
			(type default)
		)
		(layer "F.Cu")
	)
	(gr_line
		(start 380.80315 -122.7328)
		(end 381.29845 -122.962924)
		(stroke
			(width 0.05715)
			(type default)
		)
		(layer "F.Cu")
	)
	(gr_line
		(start 380.80315 -121.01576)
		(end 380.868174 -121.19356)
		(stroke
			(width 0.05715)
			(type default)
		)
		(layer "F.Cu")
	)
	(gr_line
		(start 380.820422 -125.784864)
		(end 380.985014 -125.33503)
		(stroke
			(width 0.04445)
			(type default)
		)
		(layer "F.Cu")
	)
	(gr_line
		(start 380.868174 -121.19356)
		(end 381.120904 -121.310654)
		(stroke
			(width 0.05715)
			(type default)
		)
		(layer "F.Cu")
	)
	(gr_arc
		(start 380.89967 -128.60401)
		(mid 380.925708 -128.666872)
		(end 380.98857 -128.69291)
		(stroke
			(width 0.04445)
			(type default)
		)
		(layer "F.Cu")
	)
	(gr_arc
		(start 380.89967 -127.406146)
		(mid 380.913735 -127.454672)
		(end 380.94412 -127.495046)
		(stroke
			(width 0.04445)
			(type default)
		)
		(layer "F.Cu")
	)
	(gr_arc
		(start 380.89967 -126.517146)
		(mid 380.913735 -126.565672)
		(end 380.94412 -126.606046)
		(stroke
			(width 0.04445)
			(type default)
		)
		(layer "F.Cu")
	)
	(gr_line
		(start 380.89967 -126.250446)
		(end 380.9111 -126.239016)
		(stroke
			(width 0.04445)
			(type default)
		)
		(layer "F.Cu")
	)
	(gr_line
		(start 380.912878 -126.237238)
		(end 380.985014 -126.165102)
		(stroke
			(width 0.04445)
			(type default)
		)
		(layer "F.Cu")
	)
	(gr_arc
		(start 380.94412 -127.939546)
		(mid 380.913699 -127.979902)
		(end 380.89967 -128.028446)
		(stroke
			(width 0.04445)
			(type default)
		)
		(layer "F.Cu")
	)
	(gr_arc
		(start 380.94412 -127.939546)
		(mid 380.974494 -127.899172)
		(end 380.98857 -127.850646)
		(stroke
			(width 0.04445)
			(type default)
		)
		(layer "F.Cu")
	)
	(gr_arc
		(start 380.94412 -127.050546)
		(mid 380.913699 -127.090902)
		(end 380.89967 -127.139446)
		(stroke
			(width 0.04445)
			(type default)
		)
		(layer "F.Cu")
	)
	(gr_arc
		(start 380.94412 -127.050546)
		(mid 380.974494 -127.010172)
		(end 380.98857 -126.961646)
		(stroke
			(width 0.04445)
			(type default)
		)
		(layer "F.Cu")
	)
	(gr_line
		(start 380.96698 -18.681446)
		(end 380.99365 -18.644108)
		(stroke
			(width 0.05715)
			(type default)
		)
		(layer "F.Cu")
	)
	(gr_line
		(start 380.96825 -22.982174)
		(end 381.278384 -22.67204)
		(stroke
			(width 0.05715)
			(type default)
		)
		(layer "F.Cu")
	)
	(gr_line
		(start 380.96825 -22.016974)
		(end 381.278384 -22.327108)
		(stroke
			(width 0.05715)
			(type default)
		)
		(layer "F.Cu")
	)
	(gr_line
		(start 380.98857 -128.69291)
		(end 381.353822 -128.69291)
		(stroke
			(width 0.04445)
			(type default)
		)
		(layer "F.Cu")
	)
	(gr_arc
		(start 380.98857 -127.583946)
		(mid 380.974546 -127.535394)
		(end 380.94412 -127.495046)
		(stroke
			(width 0.04445)
			(type default)
		)
		(layer "F.Cu")
	)
	(gr_line
		(start 380.98857 -127.583946)
		(end 380.98857 -127.850646)
		(stroke
			(width 0.04445)
			(type default)
		)
		(layer "F.Cu")
	)
	(gr_arc
		(start 380.98857 -126.694946)
		(mid 380.974546 -126.646394)
		(end 380.94412 -126.606046)
		(stroke
			(width 0.04445)
			(type default)
		)
		(layer "F.Cu")
	)
	(gr_line
		(start 380.98857 -126.694946)
		(end 380.98857 -126.961646)
		(stroke
			(width 0.04445)
			(type default)
		)
		(layer "F.Cu")
	)
	(gr_line
		(start 380.99365 -18.644108)
		(end 381.037846 -18.630138)
		(stroke
			(width 0.05715)
			(type default)
		)
		(layer "F.Cu")
	)
	(gr_line
		(start 381.055118 -33.7185)
		(end 381.204724 -33.868106)
		(stroke
			(width 0.05715)
			(type default)
		)
		(layer "F.Cu")
	)
	(gr_line
		(start 381.079756 -32.223456)
		(end 381.1778 -32.3215)
		(stroke
			(width 0.05715)
			(type default)
		)
		(layer "F.Cu")
	)
	(gr_line
		(start 381.11557 -29.054552)
		(end 381.494538 -28.675584)
		(stroke
			(width 0.05715)
			(type default)
		)
		(layer "F.Cu")
	)
	(gr_line
		(start 381.11557 -28.176982)
		(end 381.370332 -28.431744)
		(stroke
			(width 0.05715)
			(type default)
		)
		(layer "F.Cu")
	)
	(gr_line
		(start 381.120904 -121.310654)
		(end 381.29845 -121.245884)
		(stroke
			(width 0.05715)
			(type default)
		)
		(layer "F.Cu")
	)
	(gr_line
		(start 381.16637 -131.094988)
		(end 381.274828 -131.094988)
		(stroke
			(width 0.04445)
			(type default)
		)
		(layer "F.Cu")
	)
	(gr_line
		(start 381.171704 -125.822456)
		(end 381.22352 -125.947932)
		(stroke
			(width 0.04445)
			(type default)
		)
		(layer "F.Cu")
	)
	(gr_line
		(start 381.171704 -125.68682)
		(end 381.171704 -125.822456)
		(stroke
			(width 0.04445)
			(type default)
		)
		(layer "F.Cu")
	)
	(gr_line
		(start 381.171704 -125.68682)
		(end 381.25908 -125.485652)
		(stroke
			(width 0.04445)
			(type default)
		)
		(layer "F.Cu")
	)
	(gr_line
		(start 381.222758 -129.092706)
		(end 381.273558 -129.143506)
		(stroke
			(width 0.04445)
			(type default)
		)
		(layer "F.Cu")
	)
	(gr_arc
		(start 381.233426 -125.971808)
		(mid 381.234057 -125.973207)
		(end 381.234696 -125.974602)
		(stroke
			(width 0.04445)
			(type default)
		)
		(layer "F.Cu")
	)
	(gr_line
		(start 381.25908 -125.485652)
		(end 381.304546 -125.38075)
		(stroke
			(width 0.04445)
			(type default)
		)
		(layer "F.Cu")
	)
	(gr_line
		(start 381.271272 -49.522888)
		(end 381.324612 -49.510442)
		(stroke
			(width 0.05715)
			(type default)
		)
		(layer "F.Cu")
	)
	(gr_line
		(start 381.273558 -129.143506)
		(end 381.404622 -129.143506)
		(stroke
			(width 0.04445)
			(type default)
		)
		(layer "F.Cu")
	)
	(gr_arc
		(start 381.274828 -131.094988)
		(mid 381.337667 -131.068939)
		(end 381.363728 -131.006088)
		(stroke
			(width 0.04445)
			(type default)
		)
		(layer "F.Cu")
	)
	(gr_line
		(start 381.29845 -121.87428)
		(end 381.4064 -121.924318)
		(stroke
			(width 0.05715)
			(type default)
		)
		(layer "F.Cu")
	)
	(gr_line
		(start 381.29845 -120.15724)
		(end 381.4064 -120.207278)
		(stroke
			(width 0.05715)
			(type default)
		)
		(layer "F.Cu")
	)
	(gr_line
		(start 381.304546 -125.38075)
		(end 381.321564 -125.341634)
		(stroke
			(width 0.04445)
			(type default)
		)
		(layer "F.Cu")
	)
	(gr_line
		(start 381.321564 -125.341634)
		(end 381.484886 -124.919994)
		(stroke
			(width 0.04445)
			(type default)
		)
		(layer "F.Cu")
	)
	(gr_line
		(start 381.324612 -49.510442)
		(end 381.35687 -49.466754)
		(stroke
			(width 0.05715)
			(type default)
		)
		(layer "F.Cu")
	)
	(gr_arc
		(start 381.363728 -130.802888)
		(mid 381.317154 -130.690454)
		(end 381.204724 -130.643884)
		(stroke
			(width 0.04445)
			(type default)
		)
		(layer "F.Cu")
	)
	(gr_line
		(start 381.363728 -130.802888)
		(end 381.363728 -131.006088)
		(stroke
			(width 0.04445)
			(type default)
		)
		(layer "F.Cu")
	)
	(gr_arc
		(start 381.404622 -129.143506)
		(mid 381.467472 -129.11746)
		(end 381.493522 -129.054606)
		(stroke
			(width 0.04445)
			(type default)
		)
		(layer "F.Cu")
	)
	(gr_line
		(start 381.4064 -121.924318)
		(end 381.724916 -122.0724)
		(stroke
			(width 0.05715)
			(type default)
		)
		(layer "F.Cu")
	)
	(gr_line
		(start 381.4064 -120.207278)
		(end 381.79375 -120.387364)
		(stroke
			(width 0.05715)
			(type default)
		)
		(layer "F.Cu")
	)
	(gr_line
		(start 381.430276 -125.804676)
		(end 381.484886 -125.750066)
		(stroke
			(width 0.04445)
			(type default)
		)
		(layer "F.Cu")
	)
	(gr_line
		(start 381.46609 -126.035308)
		(end 381.46863 -126.041404)
		(stroke
			(width 0.04445)
			(type default)
		)
		(layer "F.Cu")
	)
	(gr_arc
		(start 381.493522 -128.83261)
		(mid 381.45261 -128.733813)
		(end 381.353822 -128.69291)
		(stroke
			(width 0.04445)
			(type default)
		)
		(layer "F.Cu")
	)
	(gr_line
		(start 381.493522 -128.83261)
		(end 381.493522 -129.054606)
		(stroke
			(width 0.04445)
			(type default)
		)
		(layer "F.Cu")
	)
	(gr_line
		(start 381.5588 -51.15052)
		(end 381.611124 -51.135026)
		(stroke
			(width 0.05715)
			(type default)
		)
		(layer "F.Cu")
	)
	(gr_line
		(start 381.572516 -33.193482)
		(end 381.649986 -33.270952)
		(stroke
			(width 0.05715)
			(type default)
		)
		(layer "F.Cu")
	)
	(gr_line
		(start 381.572516 -32.84855)
		(end 381.65024 -32.770826)
		(stroke
			(width 0.05715)
			(type default)
		)
		(layer "F.Cu")
	)
	(gr_line
		(start 381.611124 -51.135026)
		(end 381.640842 -51.089052)
		(stroke
			(width 0.05715)
			(type default)
		)
		(layer "F.Cu")
	)
	(gr_line
		(start 381.629158 -25.481788)
		(end 381.839978 -25.270968)
		(stroke
			(width 0.05715)
			(type default)
		)
		(layer "F.Cu")
	)
	(gr_line
		(start 381.649986 -33.270952)
		(end 382.797304 -33.270952)
		(stroke
			(width 0.05715)
			(type default)
		)
		(layer "F.Cu")
	)
	(gr_line
		(start 381.65024 -32.770826)
		(end 382.797304 -32.770826)
		(stroke
			(width 0.05715)
			(type default)
		)
		(layer "F.Cu")
	)
	(gr_line
		(start 381.699262 -126.568454)
		(end 381.699262 -126.804674)
		(stroke
			(width 0.04445)
			(type default)
		)
		(layer "F.Cu")
	)
	(gr_line
		(start 381.699262 -126.06528)
		(end 381.699262 -126.067312)
		(stroke
			(width 0.04445)
			(type default)
		)
		(layer "F.Cu")
	)
	(gr_line
		(start 381.699262 -126.06528)
		(end 381.796036 -125.839728)
		(stroke
			(width 0.04445)
			(type default)
		)
		(layer "F.Cu")
	)
	(gr_line
		(start 381.724916 -122.0724)
		(end 381.79375 -122.104404)
		(stroke
			(width 0.05715)
			(type default)
		)
		(layer "F.Cu")
	)
	(gr_line
		(start 381.754888 -22.700996)
		(end 381.824992 -22.7711)
		(stroke
			(width 0.05715)
			(type default)
		)
		(layer "F.Cu")
	)
	(gr_line
		(start 381.754888 -22.356064)
		(end 381.839978 -22.270974)
		(stroke
			(width 0.05715)
			(type default)
		)
		(layer "F.Cu")
	)
	(gr_line
		(start 381.759714 -28.70581)
		(end 381.824992 -28.771088)
		(stroke
			(width 0.05715)
			(type default)
		)
		(layer "F.Cu")
	)
	(gr_line
		(start 381.759714 -28.360878)
		(end 381.84963 -28.270962)
		(stroke
			(width 0.05715)
			(type default)
		)
		(layer "F.Cu")
	)
	(gr_line
		(start 381.774446 -31.61411)
		(end 381.931164 -31.770828)
		(stroke
			(width 0.05715)
			(type default)
		)
		(layer "F.Cu")
	)
	(gr_line
		(start 381.776224 -31.270956)
		(end 382.797304 -31.270956)
		(stroke
			(width 0.05715)
			(type default)
		)
		(layer "F.Cu")
	)
	(gr_line
		(start 381.779526 -25.725628)
		(end 381.824992 -25.771094)
		(stroke
			(width 0.05715)
			(type default)
		)
		(layer "F.Cu")
	)
	(gr_line
		(start 381.79375 -122.7328)
		(end 382.1684 -122.90679)
		(stroke
			(width 0.05715)
			(type default)
		)
		(layer "F.Cu")
	)
	(gr_line
		(start 381.79375 -121.01576)
		(end 381.858266 -121.192036)
		(stroke
			(width 0.05715)
			(type default)
		)
		(layer "F.Cu")
	)
	(gr_line
		(start 381.796036 -125.839728)
		(end 381.928624 -125.485652)
		(stroke
			(width 0.04445)
			(type default)
		)
		(layer "F.Cu")
	)
	(gr_line
		(start 381.824992 -28.771088)
		(end 381.825246 -28.770834)
		(stroke
			(width 0.05715)
			(type default)
		)
		(layer "F.Cu")
	)
	(gr_line
		(start 381.824992 -25.771094)
		(end 381.825246 -25.77084)
		(stroke
			(width 0.05715)
			(type default)
		)
		(layer "F.Cu")
	)
	(gr_line
		(start 381.824992 -22.7711)
		(end 381.825246 -22.770846)
		(stroke
			(width 0.05715)
			(type default)
		)
		(layer "F.Cu")
	)
	(gr_line
		(start 381.825246 -28.770834)
		(end 382.797304 -28.770834)
		(stroke
			(width 0.05715)
			(type default)
		)
		(layer "F.Cu")
	)
	(gr_line
		(start 381.825246 -25.77084)
		(end 382.797304 -25.77084)
		(stroke
			(width 0.05715)
			(type default)
		)
		(layer "F.Cu")
	)
	(gr_line
		(start 381.825246 -22.770846)
		(end 382.797304 -22.770846)
		(stroke
			(width 0.05715)
			(type default)
		)
		(layer "F.Cu")
	)
	(gr_line
		(start 381.839978 -25.270968)
		(end 382.797304 -25.270968)
		(stroke
			(width 0.05715)
			(type default)
		)
		(layer "F.Cu")
	)
	(gr_line
		(start 381.839978 -22.270974)
		(end 382.797304 -22.270974)
		(stroke
			(width 0.05715)
			(type default)
		)
		(layer "F.Cu")
	)
	(gr_line
		(start 381.84963 -28.270962)
		(end 382.797304 -28.270962)
		(stroke
			(width 0.05715)
			(type default)
		)
		(layer "F.Cu")
	)
	(gr_line
		(start 381.858266 -121.192036)
		(end 382.11252 -121.310146)
		(stroke
			(width 0.05715)
			(type default)
		)
		(layer "F.Cu")
	)
	(gr_line
		(start 381.85852 -129.029714)
		(end 381.85852 -129.265934)
		(stroke
			(width 0.04445)
			(type default)
		)
		(layer "F.Cu")
	)
	(gr_arc
		(start 381.889762 -126.375414)
		(mid 381.903827 -126.42394)
		(end 381.934212 -126.464314)
		(stroke
			(width 0.04445)
			(type default)
		)
		(layer "F.Cu")
	)
	(gr_line
		(start 381.892302 -126.257812)
		(end 381.985012 -126.165102)
		(stroke
			(width 0.04445)
			(type default)
		)
		(layer "F.Cu")
	)
	(gr_line
		(start 381.928624 -125.485652)
		(end 381.967994 -125.38075)
		(stroke
			(width 0.04445)
			(type default)
		)
		(layer "F.Cu")
	)
	(gr_line
		(start 381.931164 -31.770828)
		(end 382.797304 -31.770828)
		(stroke
			(width 0.05715)
			(type default)
		)
		(layer "F.Cu")
	)
	(gr_arc
		(start 381.934212 -126.908814)
		(mid 381.903791 -126.94917)
		(end 381.889762 -126.997714)
		(stroke
			(width 0.04445)
			(type default)
		)
		(layer "F.Cu")
	)
	(gr_arc
		(start 381.934212 -126.908814)
		(mid 381.964578 -126.868438)
		(end 381.978662 -126.819914)
		(stroke
			(width 0.04445)
			(type default)
		)
		(layer "F.Cu")
	)
	(gr_line
		(start 381.967994 -125.38075)
		(end 381.985012 -125.33503)
		(stroke
			(width 0.04445)
			(type default)
		)
		(layer "F.Cu")
	)
	(gr_arc
		(start 381.978662 -126.553214)
		(mid 381.964628 -126.50467)
		(end 381.934212 -126.464314)
		(stroke
			(width 0.04445)
			(type default)
		)
		(layer "F.Cu")
	)
	(gr_line
		(start 381.978662 -126.553214)
		(end 381.978662 -126.819914)
		(stroke
			(width 0.04445)
			(type default)
		)
		(layer "F.Cu")
	)
	(gr_arc
		(start 382.04902 -128.836674)
		(mid 382.063085 -128.8852)
		(end 382.09347 -128.925574)
		(stroke
			(width 0.04445)
			(type default)
		)
		(layer "F.Cu")
	)
	(gr_arc
		(start 382.0795 -127.453898)
		(mid 382.123337 -127.477644)
		(end 382.172718 -127.484378)
		(stroke
			(width 0.04445)
			(type default)
		)
		(layer "F.Cu")
	)
	(gr_line
		(start 382.081024 -127.72517)
		(end 382.24714 -127.891286)
		(stroke
			(width 0.04445)
			(type default)
		)
		(layer "F.Cu")
	)
	(gr_arc
		(start 382.09347 -129.370074)
		(mid 382.063049 -129.41043)
		(end 382.04902 -129.458974)
		(stroke
			(width 0.04445)
			(type default)
		)
		(layer "F.Cu")
	)
	(gr_arc
		(start 382.09347 -129.370074)
		(mid 382.123862 -129.329706)
		(end 382.13792 -129.281174)
		(stroke
			(width 0.04445)
			(type default)
		)
		(layer "F.Cu")
	)
	(gr_line
		(start 382.11252 -121.310146)
		(end 382.113028 -121.3104)
		(stroke
			(width 0.05715)
			(type default)
		)
		(layer "F.Cu")
	)
	(gr_line
		(start 382.113028 -121.3104)
		(end 382.28905 -121.245884)
		(stroke
			(width 0.05715)
			(type default)
		)
		(layer "F.Cu")
	)
	(gr_arc
		(start 382.13792 -129.014474)
		(mid 382.123879 -128.965934)
		(end 382.09347 -128.925574)
		(stroke
			(width 0.04445)
			(type default)
		)
		(layer "F.Cu")
	)
	(gr_line
		(start 382.13792 -129.014474)
		(end 382.13792 -129.281174)
		(stroke
			(width 0.04445)
			(type default)
		)
		(layer "F.Cu")
	)
	(gr_line
		(start 382.1684 -122.90679)
		(end 382.28905 -122.962924)
		(stroke
			(width 0.05715)
			(type default)
		)
		(layer "F.Cu")
	)
	(gr_line
		(start 382.17348 -125.833378)
		(end 382.270762 -126.068328)
		(stroke
			(width 0.04445)
			(type default)
		)
		(layer "F.Cu")
	)
	(gr_line
		(start 382.17348 -125.678946)
		(end 382.17348 -125.833378)
		(stroke
			(width 0.04445)
			(type default)
		)
		(layer "F.Cu")
	)
	(gr_line
		(start 382.17348 -125.678946)
		(end 382.259332 -125.485652)
		(stroke
			(width 0.04445)
			(type default)
		)
		(layer "F.Cu")
	)
	(gr_line
		(start 382.259332 -125.485652)
		(end 382.28143 -125.435868)
		(stroke
			(width 0.04445)
			(type default)
		)
		(layer "F.Cu")
	)
	(gr_arc
		(start 382.26365 -129.992882)
		(mid 382.307992 -130.017318)
		(end 382.358138 -130.024378)
		(stroke
			(width 0.04445)
			(type default)
		)
		(layer "F.Cu")
	)
	(gr_line
		(start 382.265428 -130.264154)
		(end 382.43256 -130.431286)
		(stroke
			(width 0.04445)
			(type default)
		)
		(layer "F.Cu")
	)
	(gr_arc
		(start 382.266952 -127.515874)
		(mid 382.222743 -127.491433)
		(end 382.172718 -127.484378)
		(stroke
			(width 0.04445)
			(type default)
		)
		(layer "F.Cu")
	)
	(gr_line
		(start 382.266952 -127.515874)
		(end 382.45542 -127.704342)
		(stroke
			(width 0.04445)
			(type default)
		)
		(layer "F.Cu")
	)
	(gr_line
		(start 382.270762 -126.068328)
		(end 382.328928 -126.26975)
		(stroke
			(width 0.04445)
			(type default)
		)
		(layer "F.Cu")
	)
	(gr_line
		(start 382.28143 -125.435868)
		(end 382.303274 -125.38075)
		(stroke
			(width 0.04445)
			(type default)
		)
		(layer "F.Cu")
	)
	(gr_line
		(start 382.28905 -121.87428)
		(end 382.3462 -121.900696)
		(stroke
			(width 0.05715)
			(type default)
		)
		(layer "F.Cu")
	)
	(gr_line
		(start 382.28905 -120.15724)
		(end 382.3462 -120.183656)
		(stroke
			(width 0.05715)
			(type default)
		)
		(layer "F.Cu")
	)
	(gr_line
		(start 382.28905 -109.855)
		(end 382.387348 -110.39602)
		(stroke
			(width 0.0635)
			(type default)
		)
		(layer "F.Cu")
	)
	(gr_line
		(start 382.303274 -125.38075)
		(end 382.484884 -124.919994)
		(stroke
			(width 0.04445)
			(type default)
		)
		(layer "F.Cu")
	)
	(gr_line
		(start 382.3462 -121.900696)
		(end 382.78435 -122.104404)
		(stroke
			(width 0.05715)
			(type default)
		)
		(layer "F.Cu")
	)
	(gr_line
		(start 382.3462 -120.183656)
		(end 382.78435 -120.387364)
		(stroke
			(width 0.05715)
			(type default)
		)
		(layer "F.Cu")
	)
	(gr_arc
		(start 382.452372 -130.055874)
		(mid 382.408164 -130.031426)
		(end 382.358138 -130.024378)
		(stroke
			(width 0.04445)
			(type default)
		)
		(layer "F.Cu")
	)
	(gr_line
		(start 382.452372 -130.055874)
		(end 382.64084 -130.244342)
		(stroke
			(width 0.04445)
			(type default)
		)
		(layer "F.Cu")
	)
	(gr_line
		(start 382.484884 -125.541024)
		(end 382.484884 -125.750066)
		(stroke
			(width 0.04445)
			(type default)
		)
		(layer "F.Cu")
	)
	(gr_line
		(start 382.484884 -125.541024)
		(end 382.553972 -125.471936)
		(stroke
			(width 0.04445)
			(type default)
		)
		(layer "F.Cu")
	)
	(gr_arc
		(start 382.486916 -127.79883)
		(mid 382.479872 -127.748682)
		(end 382.45542 -127.704342)
		(stroke
			(width 0.04445)
			(type default)
		)
		(layer "F.Cu")
	)
	(gr_arc
		(start 382.486916 -127.79883)
		(mid 382.493962 -127.848866)
		(end 382.518412 -127.893064)
		(stroke
			(width 0.04445)
			(type default)
		)
		(layer "F.Cu")
	)
	(gr_line
		(start 382.521968 -126.125986)
		(end 382.608582 -126.039372)
		(stroke
			(width 0.04445)
			(type default)
		)
		(layer "F.Cu")
	)
	(gr_line
		(start 382.553972 -125.471936)
		(end 382.681734 -125.471936)
		(stroke
			(width 0.04445)
			(type default)
		)
		(layer "F.Cu")
	)
	(gr_line
		(start 382.608582 -126.039372)
		(end 382.668018 -126.039372)
		(stroke
			(width 0.04445)
			(type default)
		)
		(layer "F.Cu")
	)
	(gr_line
		(start 382.668018 -126.039372)
		(end 382.814068 -125.893322)
		(stroke
			(width 0.04445)
			(type default)
		)
		(layer "F.Cu")
	)
	(gr_arc
		(start 382.672336 -130.33883)
		(mid 382.665293 -130.288681)
		(end 382.64084 -130.244342)
		(stroke
			(width 0.04445)
			(type default)
		)
		(layer "F.Cu")
	)
	(gr_arc
		(start 382.672336 -130.33883)
		(mid 382.679382 -130.388866)
		(end 382.703832 -130.433064)
		(stroke
			(width 0.04445)
			(type default)
		)
		(layer "F.Cu")
	)
	(gr_line
		(start 382.681734 -125.471936)
		(end 382.814068 -125.60427)
		(stroke
			(width 0.04445)
			(type default)
		)
		(layer "F.Cu")
	)
	(gr_line
		(start 382.77419 -129.70383)
		(end 382.93929 -129.305304)
		(stroke
			(width 0.04445)
			(type default)
		)
		(layer "F.Cu")
	)
	(gr_line
		(start 382.78435 -122.7328)
		(end 383.096516 -122.7328)
		(stroke
			(width 0.05715)
			(type default)
		)
		(layer "F.Cu")
	)
	(gr_line
		(start 382.797304 -30.270958)
		(end 383.501138 -30.270958)
		(stroke
			(width 0.05715)
			(type default)
		)
		(layer "F.Cu")
	)
	(gr_line
		(start 382.797304 -29.770832)
		(end 383.500884 -29.770832)
		(stroke
			(width 0.05715)
			(type default)
		)
		(layer "F.Cu")
	)
	(gr_line
		(start 382.797304 -27.270964)
		(end 383.501138 -27.270964)
		(stroke
			(width 0.05715)
			(type default)
		)
		(layer "F.Cu")
	)
	(gr_line
		(start 382.797304 -26.770838)
		(end 383.500884 -26.770838)
		(stroke
			(width 0.05715)
			(type default)
		)
		(layer "F.Cu")
	)
	(gr_line
		(start 382.797304 -24.27097)
		(end 383.501138 -24.27097)
		(stroke
			(width 0.05715)
			(type default)
		)
		(layer "F.Cu")
	)
	(gr_line
		(start 382.797304 -23.770844)
		(end 383.500884 -23.770844)
		(stroke
			(width 0.05715)
			(type default)
		)
		(layer "F.Cu")
	)
	(gr_line
		(start 382.814068 -125.60427)
		(end 382.814068 -125.893322)
		(stroke
			(width 0.04445)
			(type default)
		)
		(layer "F.Cu")
	)
	(gr_arc
		(start 382.88087 -131.61137)
		(mid 382.897054 -131.46037)
		(end 382.90246 -131.308602)
		(stroke
			(width 0.04445)
			(type default)
		)
		(layer "F.Cu")
	)
	(gr_line
		(start 382.90246 -131.18084)
		(end 382.90246 -131.308602)
		(stroke
			(width 0.04445)
			(type default)
		)
		(layer "F.Cu")
	)
	(gr_line
		(start 382.93929 -129.288286)
		(end 382.93929 -129.305304)
		(stroke
			(width 0.04445)
			(type default)
		)
		(layer "F.Cu")
	)
	(gr_line
		(start 383.075942 -48.4124)
		(end 383.098802 -48.37684)
		(stroke
			(width 0.05715)
			(type default)
		)
		(layer "F.Cu")
	)
	(gr_arc
		(start 383.09296 -130.9878)
		(mid 383.117109 -131.069752)
		(end 383.18186 -131.125468)
		(stroke
			(width 0.04445)
			(type default)
		)
		(layer "F.Cu")
	)
	(gr_line
		(start 383.096516 -122.7328)
		(end 383.229104 -122.82551)
		(stroke
			(width 0.05715)
			(type default)
		)
		(layer "F.Cu")
	)
	(gr_line
		(start 383.098802 -48.37684)
		(end 383.13868 -48.361346)
		(stroke
			(width 0.05715)
			(type default)
		)
		(layer "F.Cu")
	)
	(gr_arc
		(start 383.12979 -129.095246)
		(mid 383.189752 -129.240008)
		(end 383.334514 -129.29997)
		(stroke
			(width 0.04445)
			(type default)
		)
		(layer "F.Cu")
	)
	(gr_line
		(start 383.18186 -131.125468)
		(end 383.582926 -131.125468)
		(stroke
			(width 0.04445)
			(type default)
		)
		(layer "F.Cu")
	)
	(gr_line
		(start 383.191004 -127.771652)
		(end 383.37617 -127.586486)
		(stroke
			(width 0.04445)
			(type default)
		)
		(layer "F.Cu")
	)
	(gr_line
		(start 383.229104 -122.82551)
		(end 383.27965 -122.962924)
		(stroke
			(width 0.05715)
			(type default)
		)
		(layer "F.Cu")
	)
	(gr_line
		(start 383.27965 -123.59132)
		(end 383.77495 -123.821444)
		(stroke
			(width 0.05715)
			(type default)
		)
		(layer "F.Cu")
	)
	(gr_line
		(start 383.334514 -129.29997)
		(end 383.567432 -129.29997)
		(stroke
			(width 0.04445)
			(type default)
		)
		(layer "F.Cu")
	)
	(gr_arc
		(start 383.37617 -127.586486)
		(mid 383.403642 -127.545344)
		(end 383.413254 -127.496824)
		(stroke
			(width 0.04445)
			(type default)
		)
		(layer "F.Cu")
	)
	(gr_line
		(start 383.38379 -44.431966)
		(end 383.390648 -44.423076)
		(stroke
			(width 0.05715)
			(type default)
		)
		(layer "F.Cu")
	)
	(gr_line
		(start 383.390648 -44.423076)
		(end 383.4003 -44.41698)
		(stroke
			(width 0.05715)
			(type default)
		)
		(layer "F.Cu")
	)
	(gr_line
		(start 383.43459 -129.70383)
		(end 383.64287 -129.70383)
		(stroke
			(width 0.04445)
			(type default)
		)
		(layer "F.Cu")
	)
	(gr_line
		(start 383.500884 -29.770832)
		(end 383.578608 -29.848556)
		(stroke
			(width 0.05715)
			(type default)
		)
		(layer "F.Cu")
	)
	(gr_line
		(start 383.500884 -26.770838)
		(end 383.578608 -26.848562)
		(stroke
			(width 0.05715)
			(type default)
		)
		(layer "F.Cu")
	)
	(gr_line
		(start 383.500884 -23.770844)
		(end 383.578608 -23.848568)
		(stroke
			(width 0.05715)
			(type default)
		)
		(layer "F.Cu")
	)
	(gr_line
		(start 383.501138 -30.270958)
		(end 383.578608 -30.193488)
		(stroke
			(width 0.05715)
			(type default)
		)
		(layer "F.Cu")
	)
	(gr_line
		(start 383.501138 -27.270964)
		(end 383.578608 -27.193494)
		(stroke
			(width 0.05715)
			(type default)
		)
		(layer "F.Cu")
	)
	(gr_line
		(start 383.501138 -24.27097)
		(end 383.578608 -24.1935)
		(stroke
			(width 0.05715)
			(type default)
		)
		(layer "F.Cu")
	)
	(gr_line
		(start 383.54127 -131.61137)
		(end 383.55905 -131.59359)
		(stroke
			(width 0.04445)
			(type default)
		)
		(layer "F.Cu")
	)
	(gr_line
		(start 383.55905 -131.59359)
		(end 383.582926 -131.59359)
		(stroke
			(width 0.04445)
			(type default)
		)
		(layer "F.Cu")
	)
	(gr_arc
		(start 383.582926 -131.59359)
		(mid 383.81719 -131.3595)
		(end 383.582926 -131.125468)
		(stroke
			(width 0.04445)
			(type default)
		)
		(layer "F.Cu")
	)
	(gr_arc
		(start 383.603754 -127.496824)
		(mid 383.613387 -127.545342)
		(end 383.640838 -127.586486)
		(stroke
			(width 0.04445)
			(type default)
		)
		(layer "F.Cu")
	)
	(gr_line
		(start 383.640838 -127.586486)
		(end 383.826004 -127.771652)
		(stroke
			(width 0.04445)
			(type default)
		)
		(layer "F.Cu")
	)
	(gr_arc
		(start 383.64287 -129.70383)
		(mid 383.757113 -129.656525)
		(end 383.804414 -129.542286)
		(stroke
			(width 0.04445)
			(type default)
		)
		(layer "F.Cu")
	)
	(gr_arc
		(start 383.684018 -129.34823)
		(mid 383.630519 -129.312517)
		(end 383.567432 -129.29997)
		(stroke
			(width 0.04445)
			(type default)
		)
		(layer "F.Cu")
	)
	(gr_line
		(start 383.684018 -129.34823)
		(end 383.752344 -129.416556)
		(stroke
			(width 0.04445)
			(type default)
		)
		(layer "F.Cu")
	)
	(gr_line
		(start 383.77495 -122.7328)
		(end 384.27025 -122.962924)
		(stroke
			(width 0.05715)
			(type default)
		)
		(layer "F.Cu")
	)
	(gr_line
		(start 383.77495 -121.01576)
		(end 384.27025 -121.245884)
		(stroke
			(width 0.05715)
			(type default)
		)
		(layer "F.Cu")
	)
	(gr_arc
		(start 383.804414 -129.542286)
		(mid 383.79087 -129.474253)
		(end 383.752344 -129.416556)
		(stroke
			(width 0.04445)
			(type default)
		)
		(layer "F.Cu")
	)
	(gr_line
		(start 384.03911 -48.265842)
		(end 384.06959 -48.253904)
		(stroke
			(width 0.05715)
			(type default)
		)
		(layer "F.Cu")
	)
	(gr_line
		(start 384.05816 -24.275542)
		(end 384.305302 -24.522684)
		(stroke
			(width 0.05715)
			(type default)
		)
		(layer "F.Cu")
	)
	(gr_line
		(start 384.05816 -23.930864)
		(end 384.38709 -23.601934)
		(stroke
			(width 0.05715)
			(type default)
		)
		(layer "F.Cu")
	)
	(gr_line
		(start 384.06959 -48.253904)
		(end 384.089402 -48.227742)
		(stroke
			(width 0.05715)
			(type default)
		)
		(layer "F.Cu")
	)
	(gr_line
		(start 384.229356 -30.206188)
		(end 384.53949 -30.516322)
		(stroke
			(width 0.05715)
			(type default)
		)
		(layer "F.Cu")
	)
	(gr_line
		(start 384.229356 -29.861256)
		(end 384.53949 -29.551122)
		(stroke
			(width 0.05715)
			(type default)
		)
		(layer "F.Cu")
	)
	(gr_line
		(start 384.229356 -27.206194)
		(end 384.53949 -27.516328)
		(stroke
			(width 0.05715)
			(type default)
		)
		(layer "F.Cu")
	)
	(gr_line
		(start 384.229356 -26.861262)
		(end 384.53949 -26.551128)
		(stroke
			(width 0.05715)
			(type default)
		)
		(layer "F.Cu")
	)
	(gr_line
		(start 384.76555 -121.01576)
		(end 385.26085 -121.245884)
		(stroke
			(width 0.05715)
			(type default)
		)
		(layer "F.Cu")
	)
	(gr_line
		(start 384.811524 -33.235392)
		(end 384.824732 -33.170876)
		(stroke
			(width 0.05715)
			(type default)
		)
		(layer "F.Cu")
	)
	(gr_line
		(start 384.811524 -33.235392)
		(end 384.847846 -33.290002)
		(stroke
			(width 0.05715)
			(type default)
		)
		(layer "F.Cu")
	)
	(gr_line
		(start 384.915664 -32.72282)
		(end 384.918458 -32.709358)
		(stroke
			(width 0.05715)
			(type default)
		)
		(layer "F.Cu")
	)
	(gr_line
		(start 384.918458 -32.709358)
		(end 384.925824 -32.698182)
		(stroke
			(width 0.05715)
			(type default)
		)
		(layer "F.Cu")
	)
	(gr_line
		(start 385.084574 -36.952682)
		(end 385.087622 -36.966906)
		(stroke
			(width 0.05715)
			(type default)
		)
		(layer "F.Cu")
	)
	(gr_line
		(start 385.084574 -36.952682)
		(end 385.087622 -36.93795)
		(stroke
			(width 0.05715)
			(type default)
		)
		(layer "F.Cu")
	)
	(gr_line
		(start 385.151884 -39.652448)
		(end 385.156456 -39.672514)
		(stroke
			(width 0.05715)
			(type default)
		)
		(layer "F.Cu")
	)
	(gr_line
		(start 385.151884 -39.652448)
		(end 385.156456 -39.632382)
		(stroke
			(width 0.05715)
			(type default)
		)
		(layer "F.Cu")
	)
	(gr_line
		(start 385.156456 -39.631874)
		(end 385.156456 -39.632382)
		(stroke
			(width 0.05715)
			(type default)
		)
		(layer "F.Cu")
	)
	(gr_line
		(start 385.378452 -46.149768)
		(end 385.383024 -46.143926)
		(stroke
			(width 0.05715)
			(type default)
		)
		(layer "F.Cu")
	)
	(gr_line
		(start 385.383024 -46.143926)
		(end 385.38912 -46.139862)
		(stroke
			(width 0.05715)
			(type default)
		)
		(layer "F.Cu")
	)
	(gr_line
		(start 385.391152 -33.673542)
		(end 385.398518 -33.684718)
		(stroke
			(width 0.05715)
			(type default)
		)
		(layer "F.Cu")
	)
	(gr_line
		(start 385.398518 -33.684718)
		(end 385.401312 -33.69818)
		(stroke
			(width 0.05715)
			(type default)
		)
		(layer "F.Cu")
	)
	(gr_line
		(start 385.46151 -41.737534)
		(end 385.500626 -41.706292)
		(stroke
			(width 0.05715)
			(type default)
		)
		(layer "F.Cu")
	)
	(gr_line
		(start 385.500626 -41.706292)
		(end 385.512056 -41.657524)
		(stroke
			(width 0.05715)
			(type default)
		)
		(layer "F.Cu")
	)
	(gr_line
		(start 385.650486 -38.564312)
		(end 385.654804 -38.546024)
		(stroke
			(width 0.05715)
			(type default)
		)
		(layer "F.Cu")
	)
	(gr_line
		(start 385.650994 -38.527228)
		(end 385.654804 -38.546024)
		(stroke
			(width 0.05715)
			(type default)
		)
		(layer "F.Cu")
	)
	(gr_line
		(start 385.674108 -32.005524)
		(end 385.681474 -31.994348)
		(stroke
			(width 0.05715)
			(type default)
		)
		(layer "F.Cu")
	)
	(gr_line
		(start 385.681474 -31.994348)
		(end 385.684268 -31.980886)
		(stroke
			(width 0.05715)
			(type default)
		)
		(layer "F.Cu")
	)
	(gr_line
		(start 385.68249 -40.922448)
		(end 385.68757 -40.900604)
		(stroke
			(width 0.05715)
			(type default)
		)
		(layer "F.Cu")
	)
	(gr_line
		(start 385.68249 -40.87876)
		(end 385.68757 -40.900604)
		(stroke
			(width 0.05715)
			(type default)
		)
		(layer "F.Cu")
	)
	(gr_line
		(start 385.69392 -35.167316)
		(end 385.696968 -35.153092)
		(stroke
			(width 0.05715)
			(type default)
		)
		(layer "F.Cu")
	)
	(gr_line
		(start 385.69392 -35.13836)
		(end 385.696968 -35.153092)
		(stroke
			(width 0.05715)
			(type default)
		)
		(layer "F.Cu")
	)
	(gr_line
		(start 385.75615 -122.7328)
		(end 386.25145 -122.962924)
		(stroke
			(width 0.05715)
			(type default)
		)
		(layer "F.Cu")
	)
	(gr_line
		(start 385.867402 -24.783542)
		(end 385.8768 -24.737822)
		(stroke
			(width 0.05715)
			(type default)
		)
		(layer "F.Cu")
	)
	(gr_line
		(start 385.867402 -24.783542)
		(end 385.887722 -24.825706)
		(stroke
			(width 0.05715)
			(type default)
		)
		(layer "F.Cu")
	)
	(gr_line
		(start 386.087366 -27.116786)
		(end 386.091684 -27.13863)
		(stroke
			(width 0.05715)
			(type default)
		)
		(layer "F.Cu")
	)
	(gr_line
		(start 386.087366 -27.116786)
		(end 386.093208 -27.095196)
		(stroke
			(width 0.05715)
			(type default)
		)
		(layer "F.Cu")
	)
	(gr_line
		(start 386.093208 -27.094942)
		(end 386.093462 -27.094434)
		(stroke
			(width 0.05715)
			(type default)
		)
		(layer "F.Cu")
	)
	(gr_line
		(start 386.144008 -37.304726)
		(end 386.147056 -37.31895)
		(stroke
			(width 0.05715)
			(type default)
		)
		(layer "F.Cu")
	)
	(gr_line
		(start 386.144008 -37.304726)
		(end 386.147056 -37.289994)
		(stroke
			(width 0.05715)
			(type default)
		)
		(layer "F.Cu")
	)
	(gr_line
		(start 386.249418 -42.921682)
		(end 386.306314 -42.886122)
		(stroke
			(width 0.05715)
			(type default)
		)
		(layer "F.Cu")
	)
	(gr_line
		(start 386.25145 -121.87428)
		(end 386.74675 -122.104404)
		(stroke
			(width 0.05715)
			(type default)
		)
		(layer "F.Cu")
	)
	(gr_line
		(start 386.306314 -42.886122)
		(end 386.321046 -42.821606)
		(stroke
			(width 0.05715)
			(type default)
		)
		(layer "F.Cu")
	)
	(gr_line
		(start 386.457952 -34.118296)
		(end 386.461 -34.13252)
		(stroke
			(width 0.05715)
			(type default)
		)
		(layer "F.Cu")
	)
	(gr_line
		(start 386.457952 -34.118296)
		(end 386.461 -34.103818)
		(stroke
			(width 0.05715)
			(type default)
		)
		(layer "F.Cu")
	)
	(gr_line
		(start 386.484876 -125.750066)
		(end 386.499862 -125.765052)
		(stroke
			(width 0.04445)
			(type default)
		)
		(layer "F.Cu")
	)
	(gr_line
		(start 386.484876 -124.919994)
		(end 386.68198 -125.447806)
		(stroke
			(width 0.04445)
			(type default)
		)
		(layer "F.Cu")
	)
	(gr_line
		(start 386.4991 -27.972258)
		(end 386.502148 -27.95778)
		(stroke
			(width 0.05715)
			(type default)
		)
		(layer "F.Cu")
	)
	(gr_line
		(start 386.4991 -27.943048)
		(end 386.502148 -27.95778)
		(stroke
			(width 0.05715)
			(type default)
		)
		(layer "F.Cu")
	)
	(gr_line
		(start 386.499862 -125.765052)
		(end 386.499862 -125.879098)
		(stroke
			(width 0.04445)
			(type default)
		)
		(layer "F.Cu")
	)
	(gr_line
		(start 386.62991 -33.273492)
		(end 386.632704 -33.260538)
		(stroke
			(width 0.05715)
			(type default)
		)
		(layer "F.Cu")
	)
	(gr_line
		(start 386.632704 -33.260538)
		(end 386.639816 -33.249616)
		(stroke
			(width 0.05715)
			(type default)
		)
		(layer "F.Cu")
	)
	(gr_line
		(start 386.644896 -25.83942)
		(end 386.66928 -25.889966)
		(stroke
			(width 0.05715)
			(type default)
		)
		(layer "F.Cu")
	)
	(gr_line
		(start 386.644896 -25.838912)
		(end 386.64515 -25.839674)
		(stroke
			(width 0.05715)
			(type default)
		)
		(layer "F.Cu")
	)
	(gr_arc
		(start 386.6515 -128.356614)
		(mid 386.688559 -128.543392)
		(end 386.794248 -128.7018)
		(stroke
			(width 0.04445)
			(type default)
		)
		(layer "F.Cu")
	)
	(gr_line
		(start 386.654802 -25.943814)
		(end 386.66928 -25.889966)
		(stroke
			(width 0.05715)
			(type default)
		)
		(layer "F.Cu")
	)
	(gr_line
		(start 386.68198 -125.447806)
		(end 386.799074 -125.641608)
		(stroke
			(width 0.04445)
			(type default)
		)
		(layer "F.Cu")
	)
	(gr_line
		(start 386.692902 -126.066042)
		(end 386.799074 -125.809502)
		(stroke
			(width 0.04445)
			(type default)
		)
		(layer "F.Cu")
	)
	(gr_line
		(start 386.74675 -122.7328)
		(end 387.24205 -122.962924)
		(stroke
			(width 0.05715)
			(type default)
		)
		(layer "F.Cu")
	)
	(gr_line
		(start 386.74675 -121.01576)
		(end 387.24205 -121.245884)
		(stroke
			(width 0.05715)
			(type default)
		)
		(layer "F.Cu")
	)
	(gr_line
		(start 386.783326 -33.032192)
		(end 386.79247 -33.018476)
		(stroke
			(width 0.05715)
			(type default)
		)
		(layer "F.Cu")
	)
	(gr_line
		(start 386.790946 -43.560746)
		(end 386.811266 -43.543982)
		(stroke
			(width 0.05715)
			(type default)
		)
		(layer "F.Cu")
	)
	(gr_line
		(start 386.79247 -33.018476)
		(end 386.806186 -33.009332)
		(stroke
			(width 0.05715)
			(type default)
		)
		(layer "F.Cu")
	)
	(gr_line
		(start 386.799074 -125.641608)
		(end 386.799074 -125.809502)
		(stroke
			(width 0.04445)
			(type default)
		)
		(layer "F.Cu")
	)
	(gr_line
		(start 386.811266 -43.543982)
		(end 386.837174 -43.538648)
		(stroke
			(width 0.05715)
			(type default)
		)
		(layer "F.Cu")
	)
	(gr_arc
		(start 386.842 -128.356614)
		(mid 386.864641 -128.470438)
		(end 386.929122 -128.566926)
		(stroke
			(width 0.04445)
			(type default)
		)
		(layer "F.Cu")
	)
	(gr_line
		(start 386.868416 -34.953956)
		(end 386.871464 -34.939732)
		(stroke
			(width 0.05715)
			(type default)
		)
		(layer "F.Cu")
	)
	(gr_line
		(start 386.868416 -34.925)
		(end 386.871464 -34.939732)
		(stroke
			(width 0.05715)
			(type default)
		)
		(layer "F.Cu")
	)
	(gr_line
		(start 386.93471 -39.980616)
		(end 386.93725 -39.992554)
		(stroke
			(width 0.05715)
			(type default)
		)
		(layer "F.Cu")
	)
	(gr_line
		(start 386.934964 -40.004238)
		(end 386.93725 -39.992554)
		(stroke
			(width 0.05715)
			(type default)
		)
		(layer "F.Cu")
	)
	(gr_line
		(start 386.985002 -126.165102)
		(end 387.1214 -126.3015)
		(stroke
			(width 0.04445)
			(type default)
		)
		(layer "F.Cu")
	)
	(gr_line
		(start 386.985002 -125.370082)
		(end 387.31444 -126.166118)
		(stroke
			(width 0.04445)
			(type default)
		)
		(layer "F.Cu")
	)
	(gr_line
		(start 386.985002 -125.33503)
		(end 386.985002 -125.370082)
		(stroke
			(width 0.04445)
			(type default)
		)
		(layer "F.Cu")
	)
	(gr_arc
		(start 387.014212 -128.984756)
		(mid 387.007107 -128.934752)
		(end 386.982716 -128.890522)
		(stroke
			(width 0.04445)
			(type default)
		)
		(layer "F.Cu")
	)
	(gr_arc
		(start 387.014212 -128.984756)
		(mid 387.021258 -129.034792)
		(end 387.045708 -129.07899)
		(stroke
			(width 0.04445)
			(type default)
		)
		(layer "F.Cu")
	)
	(gr_line
		(start 387.036564 -19.02079)
		(end 387.039358 -19.007328)
		(stroke
			(width 0.05715)
			(type default)
		)
		(layer "F.Cu")
	)
	(gr_line
		(start 387.039358 -19.007328)
		(end 387.046724 -18.996152)
		(stroke
			(width 0.05715)
			(type default)
		)
		(layer "F.Cu")
	)
	(gr_line
		(start 387.045708 -129.07899)
		(end 387.234176 -129.267712)
		(stroke
			(width 0.04445)
			(type default)
		)
		(layer "F.Cu")
	)
	(gr_line
		(start 387.13791 -128.775714)
		(end 387.536436 -129.174494)
		(stroke
			(width 0.04445)
			(type default)
		)
		(layer "F.Cu")
	)
	(gr_arc
		(start 387.234176 -129.267712)
		(mid 387.278432 -129.291941)
		(end 387.32841 -129.298954)
		(stroke
			(width 0.04445)
			(type default)
		)
		(layer "F.Cu")
	)
	(gr_line
		(start 387.24205 -121.87428)
		(end 387.308852 -121.905268)
		(stroke
			(width 0.05715)
			(type default)
		)
		(layer "F.Cu")
	)
	(gr_line
		(start 387.308852 -121.905268)
		(end 387.668516 -122.0724)
		(stroke
			(width 0.05715)
			(type default)
		)
		(layer "F.Cu")
	)
	(gr_line
		(start 387.32206 -127.7366)
		(end 387.55066 -127.9652)
		(stroke
			(width 0.04445)
			(type default)
		)
		(layer "F.Cu")
	)
	(gr_line
		(start 387.32206 -127.19431)
		(end 387.32206 -127.7366)
		(stroke
			(width 0.04445)
			(type default)
		)
		(layer "F.Cu")
	)
	(gr_line
		(start 387.3373 -109.0549)
		(end 387.73735 -109.45495)
		(stroke
			(width 0.0635)
			(type default)
		)
		(layer "F.Cu")
	)
	(gr_arc
		(start 387.422898 -129.33045)
		(mid 387.378543 -129.306037)
		(end 387.32841 -129.298954)
		(stroke
			(width 0.04445)
			(type default)
		)
		(layer "F.Cu")
	)
	(gr_line
		(start 387.55066 -127.9652)
		(end 387.731 -127.9652)
		(stroke
			(width 0.04445)
			(type default)
		)
		(layer "F.Cu")
	)
	(gr_line
		(start 387.593332 -127.192532)
		(end 387.731 -127.3302)
		(stroke
			(width 0.04445)
			(type default)
		)
		(layer "F.Cu")
	)
	(gr_line
		(start 387.597396 -18.16481)
		(end 387.63067 -18.114518)
		(stroke
			(width 0.05715)
			(type default)
		)
		(layer "F.Cu")
	)
	(gr_line
		(start 387.63067 -18.114518)
		(end 387.68909 -18.10004)
		(stroke
			(width 0.05715)
			(type default)
		)
		(layer "F.Cu")
	)
	(gr_arc
		(start 387.642862 -129.613406)
		(mid 387.635775 -129.563392)
		(end 387.611366 -129.519172)
		(stroke
			(width 0.04445)
			(type default)
		)
		(layer "F.Cu")
	)
	(gr_arc
		(start 387.642862 -129.613406)
		(mid 387.649908 -129.663442)
		(end 387.674358 -129.70764)
		(stroke
			(width 0.04445)
			(type default)
		)
		(layer "F.Cu")
	)
	(gr_line
		(start 387.668516 -122.0724)
		(end 387.73735 -122.104404)
		(stroke
			(width 0.05715)
			(type default)
		)
		(layer "F.Cu")
	)
	(gr_line
		(start 387.674358 -129.70764)
		(end 387.862826 -129.896362)
		(stroke
			(width 0.04445)
			(type default)
		)
		(layer "F.Cu")
	)
	(gr_line
		(start 387.73735 -122.7328)
		(end 388.23265 -122.962924)
		(stroke
			(width 0.05715)
			(type default)
		)
		(layer "F.Cu")
	)
	(gr_line
		(start 387.766814 -129.404618)
		(end 388.165086 -129.80289)
		(stroke
			(width 0.04445)
			(type default)
		)
		(layer "F.Cu")
	)
	(gr_arc
		(start 387.862826 -129.896362)
		(mid 387.907082 -129.920591)
		(end 387.95706 -129.927604)
		(stroke
			(width 0.04445)
			(type default)
		)
		(layer "F.Cu")
	)
	(gr_line
		(start 387.920992 -18.04035)
		(end 388.00278 -17.904714)
		(stroke
			(width 0.05715)
			(type default)
		)
		(layer "F.Cu")
	)
	(gr_line
		(start 388.00278 -17.904714)
		(end 388.335774 -17.822672)
		(stroke
			(width 0.05715)
			(type default)
		)
		(layer "F.Cu")
	)
	(gr_line
		(start 388.00913 -18.269966)
		(end 388.49935 -18.148808)
		(stroke
			(width 0.05715)
			(type default)
		)
		(layer "F.Cu")
	)
	(gr_arc
		(start 388.051548 -129.9591)
		(mid 388.007197 -129.934662)
		(end 387.95706 -129.927604)
		(stroke
			(width 0.04445)
			(type default)
		)
		(layer "F.Cu")
	)
	(gr_line
		(start 388.142226 -44.31792)
		(end 388.153402 -44.310554)
		(stroke
			(width 0.05715)
			(type default)
		)
		(layer "F.Cu")
	)
	(gr_line
		(start 388.153402 -44.310554)
		(end 388.166864 -44.30776)
		(stroke
			(width 0.05715)
			(type default)
		)
		(layer "F.Cu")
	)
	(gr_line
		(start 388.164832 -126.454154)
		(end 388.198868 -126.419864)
		(stroke
			(width 0.04445)
			(type default)
		)
		(layer "F.Cu")
	)
	(gr_line
		(start 388.224522 -128.009142)
		(end 388.413244 -128.197864)
		(stroke
			(width 0.04445)
			(type default)
		)
		(layer "F.Cu")
	)
	(gr_line
		(start 388.224522 -127.937514)
		(end 388.224522 -128.009142)
		(stroke
			(width 0.04445)
			(type default)
		)
		(layer "F.Cu")
	)
	(gr_line
		(start 388.224522 -127.883158)
		(end 388.224522 -127.934974)
		(stroke
			(width 0.04445)
			(type default)
		)
		(layer "F.Cu")
	)
	(gr_line
		(start 388.23265 -123.59132)
		(end 388.72795 -123.821444)
		(stroke
			(width 0.05715)
			(type default)
		)
		(layer "F.Cu")
	)
	(gr_line
		(start 388.23265 -121.87428)
		(end 388.659116 -122.0724)
		(stroke
			(width 0.05715)
			(type default)
		)
		(layer "F.Cu")
	)
	(gr_arc
		(start 388.271512 -130.242056)
		(mid 388.264407 -130.192052)
		(end 388.240016 -130.147822)
		(stroke
			(width 0.04445)
			(type default)
		)
		(layer "F.Cu")
	)
	(gr_arc
		(start 388.271512 -130.242056)
		(mid 388.278568 -130.292083)
		(end 388.303008 -130.33629)
		(stroke
			(width 0.04445)
			(type default)
		)
		(layer "F.Cu")
	)
	(gr_line
		(start 388.303008 -130.33629)
		(end 388.491476 -130.525012)
		(stroke
			(width 0.04445)
			(type default)
		)
		(layer "F.Cu")
	)
	(gr_line
		(start 388.335774 -17.822672)
		(end 388.471156 -17.90446)
		(stroke
			(width 0.05715)
			(type default)
		)
		(layer "F.Cu")
	)
	(gr_line
		(start 388.35203 -22.7711)
		(end 388.356602 -22.791166)
		(stroke
			(width 0.05715)
			(type default)
		)
		(layer "F.Cu")
	)
	(gr_line
		(start 388.35203 -22.7711)
		(end 388.356602 -22.75078)
		(stroke
			(width 0.05715)
			(type default)
		)
		(layer "F.Cu")
	)
	(gr_line
		(start 388.355332 -127.692658)
		(end 388.355332 -127.744474)
		(stroke
			(width 0.04445)
			(type default)
		)
		(layer "F.Cu")
	)
	(gr_line
		(start 388.356602 -22.750526)
		(end 388.356602 -22.751034)
		(stroke
			(width 0.05715)
			(type default)
		)
		(layer "F.Cu")
	)
	(gr_line
		(start 388.376668 -25.591516)
		(end 388.381748 -25.613106)
		(stroke
			(width 0.05715)
			(type default)
		)
		(layer "F.Cu")
	)
	(gr_line
		(start 388.376668 -25.591516)
		(end 388.381748 -25.569672)
		(stroke
			(width 0.05715)
			(type default)
		)
		(layer "F.Cu")
	)
	(gr_line
		(start 388.386828 -32.181292)
		(end 388.386828 -32.218376)
		(stroke
			(width 0.05715)
			(type default)
		)
		(layer "F.Cu")
	)
	(gr_line
		(start 388.389622 -28.075382)
		(end 388.394702 -28.096972)
		(stroke
			(width 0.05715)
			(type default)
		)
		(layer "F.Cu")
	)
	(gr_line
		(start 388.389622 -28.075382)
		(end 388.394702 -28.053538)
		(stroke
			(width 0.05715)
			(type default)
		)
		(layer "F.Cu")
	)
	(gr_line
		(start 388.395718 -130.033522)
		(end 388.793736 -130.431794)
		(stroke
			(width 0.04445)
			(type default)
		)
		(layer "F.Cu")
	)
	(gr_line
		(start 388.413244 -128.197864)
		(end 388.535672 -128.197864)
		(stroke
			(width 0.04445)
			(type default)
		)
		(layer "F.Cu")
	)
	(gr_line
		(start 388.485126 -125.750066)
		(end 388.515352 -125.76048)
		(stroke
			(width 0.04445)
			(type default)
		)
		(layer "F.Cu")
	)
	(gr_line
		(start 388.485126 -124.919994)
		(end 388.6708 -125.4125)
		(stroke
			(width 0.04445)
			(type default)
		)
		(layer "F.Cu")
	)
	(gr_arc
		(start 388.491476 -130.525012)
		(mid 388.535723 -130.549284)
		(end 388.58571 -130.556254)
		(stroke
			(width 0.04445)
			(type default)
		)
		(layer "F.Cu")
	)
	(gr_line
		(start 388.495794 -127.884936)
		(end 388.53745 -127.926592)
		(stroke
			(width 0.04445)
			(type default)
		)
		(layer "F.Cu")
	)
	(gr_line
		(start 388.515352 -125.76048)
		(end 388.568946 -125.870716)
		(stroke
			(width 0.04445)
			(type default)
		)
		(layer "F.Cu")
	)
	(gr_line
		(start 388.564882 -21.848826)
		(end 388.566152 -21.843492)
		(stroke
			(width 0.05715)
			(type default)
		)
		(layer "F.Cu")
	)
	(gr_line
		(start 388.566152 -21.843492)
		(end 388.5692 -21.83892)
		(stroke
			(width 0.05715)
			(type default)
		)
		(layer "F.Cu")
	)
	(gr_line
		(start 388.659116 -122.0724)
		(end 388.72795 -122.104404)
		(stroke
			(width 0.05715)
			(type default)
		)
		(layer "F.Cu")
	)
	(gr_line
		(start 388.6708 -125.4125)
		(end 388.7978 -125.674882)
		(stroke
			(width 0.04445)
			(type default)
		)
		(layer "F.Cu")
	)
	(gr_arc
		(start 388.679944 -130.58775)
		(mid 388.635708 -130.563379)
		(end 388.58571 -130.556254)
		(stroke
			(width 0.04445)
			(type default)
		)
		(layer "F.Cu")
	)
	(gr_line
		(start 388.727442 -128.512062)
		(end 388.916164 -128.700784)
		(stroke
			(width 0.04445)
			(type default)
		)
		(layer "F.Cu")
	)
	(gr_line
		(start 388.727442 -128.389634)
		(end 388.727442 -128.512062)
		(stroke
			(width 0.04445)
			(type default)
		)
		(layer "F.Cu")
	)
	(gr_line
		(start 388.72795 -122.7328)
		(end 389.22325 -122.962924)
		(stroke
			(width 0.05715)
			(type default)
		)
		(layer "F.Cu")
	)
	(gr_line
		(start 388.72795 -121.01576)
		(end 389.22325 -121.245884)
		(stroke
			(width 0.053848)
			(type default)
		)
		(layer "F.Cu")
	)
	(gr_arc
		(start 388.74319 -130.650742)
		(mid 388.863572 -130.731179)
		(end 389.005572 -130.759454)
		(stroke
			(width 0.04445)
			(type default)
		)
		(layer "F.Cu")
	)
	(gr_line
		(start 388.75843 -125.91796)
		(end 388.7978 -125.82271)
		(stroke
			(width 0.04445)
			(type default)
		)
		(layer "F.Cu")
	)
	(gr_line
		(start 388.7978 -125.674882)
		(end 388.7978 -125.82271)
		(stroke
			(width 0.04445)
			(type default)
		)
		(layer "F.Cu")
	)
	(gr_line
		(start 388.808722 -17.821148)
		(end 388.89051 -17.685512)
		(stroke
			(width 0.05715)
			(type default)
		)
		(layer "F.Cu")
	)
	(gr_arc
		(start 388.878064 -130.515868)
		(mid 388.936533 -130.555104)
		(end 389.005572 -130.568954)
		(stroke
			(width 0.04445)
			(type default)
		)
		(layer "F.Cu")
	)
	(gr_line
		(start 388.89051 -17.685512)
		(end 389.223504 -17.60347)
		(stroke
			(width 0.05715)
			(type default)
		)
		(layer "F.Cu")
	)
	(gr_line
		(start 388.896098 -18.051018)
		(end 389.387334 -17.929606)
		(stroke
			(width 0.05715)
			(type default)
		)
		(layer "F.Cu")
	)
	(gr_line
		(start 388.912608 -26.882344)
		(end 388.917688 -26.860754)
		(stroke
			(width 0.05715)
			(type default)
		)
		(layer "F.Cu")
	)
	(gr_line
		(start 388.912608 -26.83891)
		(end 388.917688 -26.860754)
		(stroke
			(width 0.05715)
			(type default)
		)
		(layer "F.Cu")
	)
	(gr_line
		(start 388.916164 -128.700784)
		(end 389.030464 -128.700784)
		(stroke
			(width 0.04445)
			(type default)
		)
		(layer "F.Cu")
	)
	(gr_line
		(start 388.93242 -24.258016)
		(end 388.9375 -24.236426)
		(stroke
			(width 0.05715)
			(type default)
		)
		(layer "F.Cu")
	)
	(gr_line
		(start 388.93242 -24.214582)
		(end 388.9375 -24.236426)
		(stroke
			(width 0.05715)
			(type default)
		)
		(layer "F.Cu")
	)
	(gr_line
		(start 388.980426 -29.603446)
		(end 388.985506 -29.581856)
		(stroke
			(width 0.05715)
			(type default)
		)
		(layer "F.Cu")
	)
	(gr_line
		(start 388.980426 -29.560012)
		(end 388.985506 -29.581856)
		(stroke
			(width 0.05715)
			(type default)
		)
		(layer "F.Cu")
	)
	(gr_line
		(start 388.998714 -128.387856)
		(end 389.04037 -128.429512)
		(stroke
			(width 0.04445)
			(type default)
		)
		(layer "F.Cu")
	)
	(gr_line
		(start 389.010906 -21.131022)
		(end 389.030718 -21.099272)
		(stroke
			(width 0.05715)
			(type default)
		)
		(layer "F.Cu")
	)
	(gr_line
		(start 389.030718 -21.099272)
		(end 389.063992 -21.083524)
		(stroke
			(width 0.05715)
			(type default)
		)
		(layer "F.Cu")
	)
	(gr_line
		(start 389.033004 -128.700784)
		(end 389.042148 -128.700784)
		(stroke
			(width 0.04445)
			(type default)
		)
		(layer "F.Cu")
	)
	(gr_line
		(start 389.132064 -43.323764)
		(end 389.145272 -43.32097)
		(stroke
			(width 0.05715)
			(type default)
		)
		(layer "F.Cu")
	)
	(gr_line
		(start 389.145272 -43.32097)
		(end 389.156194 -43.313604)
		(stroke
			(width 0.05715)
			(type default)
		)
		(layer "F.Cu")
	)
	(gr_line
		(start 389.22325 -121.87428)
		(end 389.649716 -122.0724)
		(stroke
			(width 0.05715)
			(type default)
		)
		(layer "F.Cu")
	)
	(gr_line
		(start 389.22325 -120.15724)
		(end 389.71855 -120.387364)
		(stroke
			(width 0.05715)
			(type default)
		)
		(layer "F.Cu")
	)
	(gr_line
		(start 389.223504 -128.612646)
		(end 389.232648 -128.612646)
		(stroke
			(width 0.04445)
			(type default)
		)
		(layer "F.Cu")
	)
	(gr_line
		(start 389.223504 -17.60347)
		(end 389.358632 -17.685258)
		(stroke
			(width 0.05715)
			(type default)
		)
		(layer "F.Cu")
	)
	(gr_line
		(start 389.327644 -128.610106)
		(end 389.53313 -128.40462)
		(stroke
			(width 0.04445)
			(type default)
		)
		(layer "F.Cu")
	)
	(gr_arc
		(start 389.361172 -130.803904)
		(mid 389.320802 -130.773518)
		(end 389.272272 -130.759454)
		(stroke
			(width 0.04445)
			(type default)
		)
		(layer "F.Cu")
	)
	(gr_arc
		(start 389.361172 -130.803904)
		(mid 389.401528 -130.834325)
		(end 389.450072 -130.848354)
		(stroke
			(width 0.04445)
			(type default)
		)
		(layer "F.Cu")
	)
	(gr_line
		(start 389.450072 -130.848354)
		(end 389.716772 -130.848354)
		(stroke
			(width 0.04445)
			(type default)
		)
		(layer "F.Cu")
	)
	(gr_line
		(start 389.462518 -128.803146)
		(end 389.53313 -128.873758)
		(stroke
			(width 0.04445)
			(type default)
		)
		(layer "F.Cu")
	)
	(gr_line
		(start 389.465312 -130.568954)
		(end 389.701532 -130.568954)
		(stroke
			(width 0.04445)
			(type default)
		)
		(layer "F.Cu")
	)
	(gr_line
		(start 389.53313 -128.873758)
		(end 389.53313 -129.29362)
		(stroke
			(width 0.04445)
			(type default)
		)
		(layer "F.Cu")
	)
	(gr_line
		(start 389.588756 -44.265088)
		(end 389.602218 -44.262294)
		(stroke
			(width 0.05715)
			(type default)
		)
		(layer "F.Cu")
	)
	(gr_line
		(start 389.602218 -44.262294)
		(end 389.613394 -44.254928)
		(stroke
			(width 0.05715)
			(type default)
		)
		(layer "F.Cu")
	)
	(gr_line
		(start 389.649716 -122.0724)
		(end 389.71855 -122.104404)
		(stroke
			(width 0.05715)
			(type default)
		)
		(layer "F.Cu")
	)
	(gr_line
		(start 389.696452 -17.601946)
		(end 389.77824 -17.46631)
		(stroke
			(width 0.05715)
			(type default)
		)
		(layer "F.Cu")
	)
	(gr_arc
		(start 389.716772 -130.848354)
		(mid 389.765298 -130.834289)
		(end 389.805672 -130.803904)
		(stroke
			(width 0.04445)
			(type default)
		)
		(layer "F.Cu")
	)
	(gr_line
		(start 389.71855 -121.01576)
		(end 390.21385 -121.245884)
		(stroke
			(width 0.05715)
			(type default)
		)
		(layer "F.Cu")
	)
	(gr_line
		(start 389.77824 -17.46631)
		(end 390.111234 -17.384268)
		(stroke
			(width 0.05715)
			(type default)
		)
		(layer "F.Cu")
	)
	(gr_line
		(start 389.784844 -17.831308)
		(end 390.273794 -17.710404)
		(stroke
			(width 0.05715)
			(type default)
		)
		(layer "F.Cu")
	)
	(gr_arc
		(start 389.894572 -130.759454)
		(mid 389.846038 -130.773501)
		(end 389.805672 -130.803904)
		(stroke
			(width 0.04445)
			(type default)
		)
		(layer "F.Cu")
	)
	(gr_line
		(start 390.111234 -17.384268)
		(end 390.246362 -17.466056)
		(stroke
			(width 0.05715)
			(type default)
		)
		(layer "F.Cu")
	)
	(gr_line
		(start 390.139682 -20.570444)
		(end 390.1821 -20.550378)
		(stroke
			(width 0.05715)
			(type default)
		)
		(layer "F.Cu")
	)
	(gr_line
		(start 390.1821 -20.550378)
		(end 390.227312 -20.559776)
		(stroke
			(width 0.05715)
			(type default)
		)
		(layer "F.Cu")
	)
	(gr_line
		(start 390.21385 -121.87428)
		(end 390.640316 -122.0724)
		(stroke
			(width 0.05715)
			(type default)
		)
		(layer "F.Cu")
	)
	(gr_arc
		(start 390.250172 -130.803904)
		(mid 390.209802 -130.773518)
		(end 390.161272 -130.759454)
		(stroke
			(width 0.04445)
			(type default)
		)
		(layer "F.Cu")
	)
	(gr_arc
		(start 390.250172 -130.803904)
		(mid 390.290528 -130.834325)
		(end 390.339072 -130.848354)
		(stroke
			(width 0.04445)
			(type default)
		)
		(layer "F.Cu")
	)
	(gr_line
		(start 390.339072 -130.848354)
		(end 390.605772 -130.848354)
		(stroke
			(width 0.04445)
			(type default)
		)
		(layer "F.Cu")
	)
	(gr_line
		(start 390.354312 -130.568954)
		(end 390.590532 -130.568954)
		(stroke
			(width 0.04445)
			(type default)
		)
		(layer "F.Cu")
	)
	(gr_line
		(start 390.584182 -17.38249)
		(end 390.66597 -17.247108)
		(stroke
			(width 0.05715)
			(type default)
		)
		(layer "F.Cu")
	)
	(gr_arc
		(start 390.605772 -130.848354)
		(mid 390.654298 -130.834289)
		(end 390.694672 -130.803904)
		(stroke
			(width 0.04445)
			(type default)
		)
		(layer "F.Cu")
	)
	(gr_line
		(start 390.640316 -122.0724)
		(end 390.70915 -122.104404)
		(stroke
			(width 0.05715)
			(type default)
		)
		(layer "F.Cu")
	)
	(gr_line
		(start 390.66597 -17.247108)
		(end 390.998964 -17.165066)
		(stroke
			(width 0.05715)
			(type default)
		)
		(layer "F.Cu")
	)
	(gr_line
		(start 390.673844 -17.611598)
		(end 391.16 -17.491456)
		(stroke
			(width 0.05715)
			(type default)
		)
		(layer "F.Cu")
	)
	(gr_line
		(start 390.7409 -126.398274)
		(end 390.821926 -126.4793)
		(stroke
			(width 0.04445)
			(type default)
		)
		(layer "F.Cu")
	)
	(gr_line
		(start 390.7409 -126.24054)
		(end 390.7409 -126.398274)
		(stroke
			(width 0.04445)
			(type default)
		)
		(layer "F.Cu")
	)
	(gr_line
		(start 390.7409 -126.24054)
		(end 390.816338 -126.165102)
		(stroke
			(width 0.04445)
			(type default)
		)
		(layer "F.Cu")
	)
	(gr_arc
		(start 390.783572 -130.759454)
		(mid 390.735038 -130.773501)
		(end 390.694672 -130.803904)
		(stroke
			(width 0.04445)
			(type default)
		)
		(layer "F.Cu")
	)
	(gr_line
		(start 390.816338 -126.165102)
		(end 390.984994 -126.165102)
		(stroke
			(width 0.04445)
			(type default)
		)
		(layer "F.Cu")
	)
	(gr_line
		(start 390.821926 -126.4793)
		(end 390.881616 -126.4793)
		(stroke
			(width 0.04445)
			(type default)
		)
		(layer "F.Cu")
	)
	(gr_line
		(start 390.881616 -126.4793)
		(end 390.982454 -126.580138)
		(stroke
			(width 0.04445)
			(type default)
		)
		(layer "F.Cu")
	)
	(gr_line
		(start 390.896094 -128.516888)
		(end 390.982454 -128.603248)
		(stroke
			(width 0.04445)
			(type default)
		)
		(layer "F.Cu")
	)
	(gr_line
		(start 390.896094 -128.250188)
		(end 390.896094 -128.516888)
		(stroke
			(width 0.04445)
			(type default)
		)
		(layer "F.Cu")
	)
	(gr_line
		(start 390.896094 -128.250188)
		(end 390.982454 -128.163828)
		(stroke
			(width 0.04445)
			(type default)
		)
		(layer "F.Cu")
	)
	(gr_line
		(start 390.896094 -127.805688)
		(end 390.982454 -127.892048)
		(stroke
			(width 0.04445)
			(type default)
		)
		(layer "F.Cu")
	)
	(gr_line
		(start 390.896094 -127.538988)
		(end 390.896094 -127.805688)
		(stroke
			(width 0.04445)
			(type default)
		)
		(layer "F.Cu")
	)
	(gr_line
		(start 390.896094 -127.538988)
		(end 390.982454 -127.452628)
		(stroke
			(width 0.04445)
			(type default)
		)
		(layer "F.Cu")
	)
	(gr_line
		(start 390.896094 -127.094488)
		(end 390.982454 -127.180848)
		(stroke
			(width 0.04445)
			(type default)
		)
		(layer "F.Cu")
	)
	(gr_line
		(start 390.896094 -126.827788)
		(end 390.896094 -127.094488)
		(stroke
			(width 0.04445)
			(type default)
		)
		(layer "F.Cu")
	)
	(gr_line
		(start 390.896094 -126.827788)
		(end 390.982454 -126.741428)
		(stroke
			(width 0.04445)
			(type default)
		)
		(layer "F.Cu")
	)
	(gr_line
		(start 390.957308 -42.098468)
		(end 390.96823 -42.091102)
		(stroke
			(width 0.05715)
			(type default)
		)
		(layer "F.Cu")
	)
	(gr_line
		(start 390.96823 -42.091102)
		(end 390.975596 -42.08018)
		(stroke
			(width 0.05715)
			(type default)
		)
		(layer "F.Cu")
	)
	(gr_line
		(start 390.984994 -125.707394)
		(end 391.287 -126.0094)
		(stroke
			(width 0.04445)
			(type default)
		)
		(layer "F.Cu")
	)
	(gr_line
		(start 390.984994 -125.33503)
		(end 390.984994 -125.707394)
		(stroke
			(width 0.04445)
			(type default)
		)
		(layer "F.Cu")
	)
	(gr_line
		(start 390.998964 -17.165066)
		(end 391.134092 -17.246854)
		(stroke
			(width 0.05715)
			(type default)
		)
		(layer "F.Cu")
	)
	(gr_line
		(start 391.175494 -128.354328)
		(end 391.175494 -128.412748)
		(stroke
			(width 0.04445)
			(type default)
		)
		(layer "F.Cu")
	)
	(gr_line
		(start 391.175494 -127.643128)
		(end 391.175494 -127.701548)
		(stroke
			(width 0.04445)
			(type default)
		)
		(layer "F.Cu")
	)
	(gr_line
		(start 391.175494 -126.932182)
		(end 391.175494 -126.990348)
		(stroke
			(width 0.04445)
			(type default)
		)
		(layer "F.Cu")
	)
	(gr_line
		(start 391.175494 -126.453138)
		(end 391.287 -126.341632)
		(stroke
			(width 0.04445)
			(type default)
		)
		(layer "F.Cu")
	)
	(gr_arc
		(start 391.200132 -130.818128)
		(mid 391.135347 -130.774776)
		(end 391.058908 -130.759454)
		(stroke
			(width 0.04445)
			(type default)
		)
		(layer "F.Cu")
	)
	(gr_line
		(start 391.287 -126.0094)
		(end 391.287 -126.341632)
		(stroke
			(width 0.04445)
			(type default)
		)
		(layer "F.Cu")
	)
	(gr_arc
		(start 391.335006 -130.683254)
		(mid 391.208317 -130.598666)
		(end 391.058908 -130.568954)
		(stroke
			(width 0.04445)
			(type default)
		)
		(layer "F.Cu")
	)
	(gr_arc
		(start 391.362184 -131.043172)
		(mid 391.35512 -130.993035)
		(end 391.330688 -130.948684)
		(stroke
			(width 0.04445)
			(type default)
		)
		(layer "F.Cu")
	)
	(gr_arc
		(start 391.362184 -131.043172)
		(mid 391.36923 -131.093208)
		(end 391.39368 -131.137406)
		(stroke
			(width 0.04445)
			(type default)
		)
		(layer "F.Cu")
	)
	(gr_line
		(start 391.3886 -127.393446)
		(end 391.477754 -127.4826)
		(stroke
			(width 0.04445)
			(type default)
		)
		(layer "F.Cu")
	)
	(gr_line
		(start 391.3886 -126.669546)
		(end 391.3886 -127.393446)
		(stroke
			(width 0.04445)
			(type default)
		)
		(layer "F.Cu")
	)
	(gr_line
		(start 391.3886 -126.669546)
		(end 391.50036 -126.557786)
		(stroke
			(width 0.04445)
			(type default)
		)
		(layer "F.Cu")
	)
	(gr_line
		(start 391.39368 -131.137406)
		(end 391.582148 -131.325874)
		(stroke
			(width 0.04445)
			(type default)
		)
		(layer "F.Cu")
	)
	(gr_line
		(start 391.466578 -21.058378)
		(end 391.480802 -21.061426)
		(stroke
			(width 0.05715)
			(type default)
		)
		(layer "F.Cu")
	)
	(gr_line
		(start 391.477754 -127.4826)
		(end 391.78865 -127.4826)
		(stroke
			(width 0.04445)
			(type default)
		)
		(layer "F.Cu")
	)
	(gr_line
		(start 391.480802 -21.061426)
		(end 391.495026 -21.058378)
		(stroke
			(width 0.05715)
			(type default)
		)
		(layer "F.Cu")
	)
	(gr_line
		(start 391.48512 -125.953774)
		(end 391.5029 -125.971554)
		(stroke
			(width 0.04445)
			(type default)
		)
		(layer "F.Cu")
	)
	(gr_line
		(start 391.48512 -125.750066)
		(end 391.48512 -125.953774)
		(stroke
			(width 0.04445)
			(type default)
		)
		(layer "F.Cu")
	)
	(gr_line
		(start 391.48512 -124.919994)
		(end 391.622534 -125.38075)
		(stroke
			(width 0.04445)
			(type default)
		)
		(layer "F.Cu")
	)
	(gr_arc
		(start 391.582148 -131.325874)
		(mid 391.62649 -131.35031)
		(end 391.676636 -131.35737)
		(stroke
			(width 0.04445)
			(type default)
		)
		(layer "F.Cu")
	)
	(gr_line
		(start 391.58799 -128.97866)
		(end 391.78865 -128.778)
		(stroke
			(width 0.04445)
			(type default)
		)
		(layer "F.Cu")
	)
	(gr_line
		(start 391.60196 -130.950208)
		(end 391.769346 -131.117594)
		(stroke
			(width 0.04445)
			(type default)
		)
		(layer "F.Cu")
	)
	(gr_line
		(start 391.622534 -125.38075)
		(end 391.64387 -125.45187)
		(stroke
			(width 0.04445)
			(type default)
		)
		(layer "F.Cu")
	)
	(gr_line
		(start 391.64387 -125.45187)
		(end 391.79881 -125.60681)
		(stroke
			(width 0.04445)
			(type default)
		)
		(layer "F.Cu")
	)
	(gr_line
		(start 391.6934 -126.75235)
		(end 391.78865 -126.8476)
		(stroke
			(width 0.04445)
			(type default)
		)
		(layer "F.Cu")
	)
	(gr_line
		(start 391.6934 -126.748286)
		(end 391.6934 -126.75235)
		(stroke
			(width 0.04445)
			(type default)
		)
		(layer "F.Cu")
	)
	(gr_line
		(start 391.69594 -126.06528)
		(end 391.79881 -125.816868)
		(stroke
			(width 0.04445)
			(type default)
		)
		(layer "F.Cu")
	)
	(gr_line
		(start 391.69975 -129.1717)
		(end 391.78865 -129.2606)
		(stroke
			(width 0.04445)
			(type default)
		)
		(layer "F.Cu")
	)
	(gr_arc
		(start 391.77087 -131.388866)
		(mid 391.726661 -131.36442)
		(end 391.676636 -131.35737)
		(stroke
			(width 0.04445)
			(type default)
		)
		(layer "F.Cu")
	)
	(gr_line
		(start 391.78865 -129.2606)
		(end 391.78865 -129.4384)
		(stroke
			(width 0.04445)
			(type default)
		)
		(layer "F.Cu")
	)
	(gr_line
		(start 391.79881 -125.60681)
		(end 391.79881 -125.816868)
		(stroke
			(width 0.04445)
			(type default)
		)
		(layer "F.Cu")
	)
	(gr_line
		(start 391.9093 -126.377954)
		(end 391.99947 -126.468124)
		(stroke
			(width 0.04445)
			(type default)
		)
		(layer "F.Cu")
	)
	(gr_line
		(start 391.9093 -126.240794)
		(end 391.9093 -126.377954)
		(stroke
			(width 0.04445)
			(type default)
		)
		(layer "F.Cu")
	)
	(gr_line
		(start 391.9093 -126.240794)
		(end 391.984992 -126.165102)
		(stroke
			(width 0.04445)
			(type default)
		)
		(layer "F.Cu")
	)
	(gr_line
		(start 391.917428 -36.838382)
		(end 391.920222 -36.851336)
		(stroke
			(width 0.05715)
			(type default)
		)
		(layer "F.Cu")
	)
	(gr_line
		(start 391.917428 -36.838382)
		(end 391.920222 -36.824412)
		(stroke
			(width 0.05715)
			(type default)
		)
		(layer "F.Cu")
	)
	(gr_line
		(start 391.92073 -20.972272)
		(end 391.934192 -20.969478)
		(stroke
			(width 0.05715)
			(type default)
		)
		(layer "F.Cu")
	)
	(gr_line
		(start 391.934192 -20.969478)
		(end 391.945368 -20.962112)
		(stroke
			(width 0.05715)
			(type default)
		)
		(layer "F.Cu")
	)
	(gr_line
		(start 391.984992 -125.33503)
		(end 392.001756 -125.38075)
		(stroke
			(width 0.04445)
			(type default)
		)
		(layer "F.Cu")
	)
	(gr_arc
		(start 391.990834 -131.671822)
		(mid 391.983788 -131.621675)
		(end 391.959338 -131.577334)
		(stroke
			(width 0.04445)
			(type default)
		)
		(layer "F.Cu")
	)
	(gr_arc
		(start 391.990834 -131.671822)
		(mid 391.99788 -131.721858)
		(end 392.02233 -131.766056)
		(stroke
			(width 0.04445)
			(type default)
		)
		(layer "F.Cu")
	)
	(gr_line
		(start 392.001756 -125.38075)
		(end 392.04011 -125.485652)
		(stroke
			(width 0.04445)
			(type default)
		)
		(layer "F.Cu")
	)
	(gr_line
		(start 392.02233 -131.766056)
		(end 392.210798 -131.954524)
		(stroke
			(width 0.04445)
			(type default)
		)
		(layer "F.Cu")
	)
	(gr_line
		(start 392.04011 -125.485652)
		(end 392.202416 -125.928374)
		(stroke
			(width 0.04445)
			(type default)
		)
		(layer "F.Cu")
	)
	(gr_line
		(start 392.119866 -127.25146)
		(end 392.19886 -127.330454)
		(stroke
			(width 0.04445)
			(type default)
		)
		(layer "F.Cu")
	)
	(gr_line
		(start 392.119866 -127.07112)
		(end 392.119866 -127.25146)
		(stroke
			(width 0.04445)
			(type default)
		)
		(layer "F.Cu")
	)
	(gr_line
		(start 392.119866 -127.07112)
		(end 392.19886 -126.992126)
		(stroke
			(width 0.04445)
			(type default)
		)
		(layer "F.Cu")
	)
	(gr_line
		(start 392.174984 -129.189226)
		(end 392.27252 -129.286762)
		(stroke
			(width 0.04445)
			(type default)
		)
		(layer "F.Cu")
	)
	(gr_line
		(start 392.174984 -129.011426)
		(end 392.174984 -129.189226)
		(stroke
			(width 0.04445)
			(type default)
		)
		(layer "F.Cu")
	)
	(gr_line
		(start 392.174984 -129.011426)
		(end 392.27252 -128.91389)
		(stroke
			(width 0.04445)
			(type default)
		)
		(layer "F.Cu")
	)
	(gr_line
		(start 392.176 -128.508252)
		(end 392.27252 -128.604772)
		(stroke
			(width 0.04445)
			(type default)
		)
		(layer "F.Cu")
	)
	(gr_line
		(start 392.176 -128.330452)
		(end 392.176 -128.508252)
		(stroke
			(width 0.04445)
			(type default)
		)
		(layer "F.Cu")
	)
	(gr_line
		(start 392.176 -128.330452)
		(end 392.27252 -128.233932)
		(stroke
			(width 0.04445)
			(type default)
		)
		(layer "F.Cu")
	)
	(gr_line
		(start 392.19505 -120.15724)
		(end 392.69035 -120.387364)
		(stroke
			(width 0.05715)
			(type default)
		)
		(layer "F.Cu")
	)
	(gr_line
		(start 392.202416 -125.928374)
		(end 392.270742 -125.9967)
		(stroke
			(width 0.04445)
			(type default)
		)
		(layer "F.Cu")
	)
	(gr_arc
		(start 392.210798 -131.954524)
		(mid 392.25514 -131.97896)
		(end 392.305286 -131.98602)
		(stroke
			(width 0.04445)
			(type default)
		)
		(layer "F.Cu")
	)
	(gr_line
		(start 392.23061 -131.578858)
		(end 392.513312 -131.86156)
		(stroke
			(width 0.04445)
			(type default)
		)
		(layer "F.Cu")
	)
	(gr_line
		(start 392.23061 -15.710154)
		(end 392.320272 -15.579852)
		(stroke
			(width 0.05715)
			(type default)
		)
		(layer "F.Cu")
	)
	(gr_line
		(start 392.270742 -125.9967)
		(end 392.270742 -126.466346)
		(stroke
			(width 0.04445)
			(type default)
		)
		(layer "F.Cu")
	)
	(gr_line
		(start 392.27506 -128.00584)
		(end 392.27506 -128.043686)
		(stroke
			(width 0.04445)
			(type default)
		)
		(layer "F.Cu")
	)
	(gr_line
		(start 392.296396 -40.084502)
		(end 392.303762 -40.073326)
		(stroke
			(width 0.05715)
			(type default)
		)
		(layer "F.Cu")
	)
	(gr_line
		(start 392.303762 -40.073326)
		(end 392.306556 -40.059864)
		(stroke
			(width 0.05715)
			(type default)
		)
		(layer "F.Cu")
	)
	(gr_line
		(start 392.305794 -15.944342)
		(end 392.802364 -15.853156)
		(stroke
			(width 0.05715)
			(type default)
		)
		(layer "F.Cu")
	)
	(gr_line
		(start 392.320272 -15.579852)
		(end 392.657584 -15.517876)
		(stroke
			(width 0.05715)
			(type default)
		)
		(layer "F.Cu")
	)
	(gr_line
		(start 392.353292 -3.176524)
		(end 392.609324 -3.176524)
		(stroke
			(width 0.05715)
			(type default)
		)
		(layer "F.Cu")
	)
	(gr_line
		(start 392.3919 -127.81534)
		(end 392.3919 -127.853186)
		(stroke
			(width 0.04445)
			(type default)
		)
		(layer "F.Cu")
	)
	(gr_arc
		(start 392.39952 -132.017516)
		(mid 392.355315 -131.993046)
		(end 392.305286 -131.98602)
		(stroke
			(width 0.04445)
			(type default)
		)
		(layer "F.Cu")
	)
	(gr_line
		(start 392.411204 -30.045152)
		(end 392.414252 -30.059376)
		(stroke
			(width 0.05715)
			(type default)
		)
		(layer "F.Cu")
	)
	(gr_line
		(start 392.411204 -30.045152)
		(end 392.414252 -30.03042)
		(stroke
			(width 0.05715)
			(type default)
		)
		(layer "F.Cu")
	)
	(gr_line
		(start 392.470386 -3.758184)
		(end 392.470386 -4.386072)
		(stroke
			(width 0.05715)
			(type default)
		)
		(layer "F.Cu")
	)
	(gr_line
		(start 392.470386 -3.758184)
		(end 392.69797 -3.5306)
		(stroke
			(width 0.05715)
			(type default)
		)
		(layer "F.Cu")
	)
	(gr_line
		(start 392.485118 -125.750066)
		(end 392.503152 -125.7681)
		(stroke
			(width 0.04445)
			(type default)
		)
		(layer "F.Cu")
	)
	(gr_line
		(start 392.485118 -124.919994)
		(end 392.661394 -125.38075)
		(stroke
			(width 0.04445)
			(type default)
		)
		(layer "F.Cu")
	)
	(gr_line
		(start 392.503152 -125.7681)
		(end 392.503152 -125.870462)
		(stroke
			(width 0.04445)
			(type default)
		)
		(layer "F.Cu")
	)
	(gr_line
		(start 392.53541 -129.49555)
		(end 392.55446 -129.5146)
		(stroke
			(width 0.04445)
			(type default)
		)
		(layer "F.Cu")
	)
	(gr_line
		(start 392.535918 -26.401268)
		(end 392.536172 -26.401268)
		(stroke
			(width 0.05715)
			(type default)
		)
		(layer "F.Cu")
	)
	(gr_line
		(start 392.535918 -26.401268)
		(end 392.545062 -26.435304)
		(stroke
			(width 0.05715)
			(type default)
		)
		(layer "F.Cu")
	)
	(gr_line
		(start 392.536172 -26.401268)
		(end 392.546078 -26.368502)
		(stroke
			(width 0.05715)
			(type default)
		)
		(layer "F.Cu")
	)
	(gr_line
		(start 392.546078 -26.367994)
		(end 392.546078 -26.368248)
		(stroke
			(width 0.05715)
			(type default)
		)
		(layer "F.Cu")
	)
	(gr_line
		(start 392.55954 -38.814248)
		(end 392.562588 -38.800024)
		(stroke
			(width 0.05715)
			(type default)
		)
		(layer "F.Cu")
	)
	(gr_line
		(start 392.55954 -38.785292)
		(end 392.562588 -38.800024)
		(stroke
			(width 0.05715)
			(type default)
		)
		(layer "F.Cu")
	)
	(gr_line
		(start 392.5951 -129.7051)
		(end 392.61415 -129.72415)
		(stroke
			(width 0.04445)
			(type default)
		)
		(layer "F.Cu")
	)
	(gr_line
		(start 392.609324 -3.176524)
		(end 392.69797 -3.26517)
		(stroke
			(width 0.05715)
			(type default)
		)
		(layer "F.Cu")
	)
	(gr_line
		(start 392.615928 -129.725928)
		(end 392.68908 -129.79908)
		(stroke
			(width 0.04445)
			(type default)
		)
		(layer "F.Cu")
	)
	(gr_arc
		(start 392.619484 -132.300472)
		(mid 392.612498 -132.250376)
		(end 392.588242 -132.205984)
		(stroke
			(width 0.04445)
			(type default)
		)
		(layer "F.Cu")
	)
	(gr_arc
		(start 392.619484 -132.300472)
		(mid 392.626611 -132.350464)
		(end 392.65098 -132.394706)
		(stroke
			(width 0.04445)
			(type default)
		)
		(layer "F.Cu")
	)
	(gr_line
		(start 392.65098 -132.394706)
		(end 392.839702 -132.583174)
		(stroke
			(width 0.04445)
			(type default)
		)
		(layer "F.Cu")
	)
	(gr_line
		(start 392.655044 -42.241724)
		(end 392.667744 -42.233342)
		(stroke
			(width 0.05715)
			(type default)
		)
		(layer "F.Cu")
	)
	(gr_line
		(start 392.657584 -15.517876)
		(end 392.78814 -15.607792)
		(stroke
			(width 0.05715)
			(type default)
		)
		(layer "F.Cu")
	)
	(gr_line
		(start 392.661394 -125.38075)
		(end 392.694922 -125.468126)
		(stroke
			(width 0.04445)
			(type default)
		)
		(layer "F.Cu")
	)
	(gr_line
		(start 392.667744 -42.233342)
		(end 392.676126 -42.220642)
		(stroke
			(width 0.05715)
			(type default)
		)
		(layer "F.Cu")
	)
	(gr_line
		(start 392.68908 -129.79908)
		(end 392.86434 -129.79908)
		(stroke
			(width 0.04445)
			(type default)
		)
		(layer "F.Cu")
	)
	(gr_line
		(start 392.69035 -121.01576)
		(end 393.18565 -121.245884)
		(stroke
			(width 0.05715)
			(type default)
		)
		(layer "F.Cu")
	)
	(gr_line
		(start 392.694922 -125.468126)
		(end 392.703558 -125.485652)
		(stroke
			(width 0.04445)
			(type default)
		)
		(layer "F.Cu")
	)
	(gr_line
		(start 392.696192 -126.058422)
		(end 392.799062 -125.848872)
		(stroke
			(width 0.04445)
			(type default)
		)
		(layer "F.Cu")
	)
	(gr_line
		(start 392.703558 -125.485652)
		(end 392.799062 -125.681486)
		(stroke
			(width 0.04445)
			(type default)
		)
		(layer "F.Cu")
	)
	(gr_line
		(start 392.744706 -132.092954)
		(end 393.026392 -132.37464)
		(stroke
			(width 0.04445)
			(type default)
		)
		(layer "F.Cu")
	)
	(gr_line
		(start 392.784076 -128.052576)
		(end 392.8872 -128.1557)
		(stroke
			(width 0.04445)
			(type default)
		)
		(layer "F.Cu")
	)
	(gr_line
		(start 392.784076 -127.67818)
		(end 392.784076 -128.052576)
		(stroke
			(width 0.04445)
			(type default)
		)
		(layer "F.Cu")
	)
	(gr_line
		(start 392.784076 -127.58547)
		(end 392.784076 -127.67564)
		(stroke
			(width 0.04445)
			(type default)
		)
		(layer "F.Cu")
	)
	(gr_line
		(start 392.799062 -125.681486)
		(end 392.799062 -125.848872)
		(stroke
			(width 0.04445)
			(type default)
		)
		(layer "F.Cu")
	)
	(gr_arc
		(start 392.839702 -132.583174)
		(mid 392.883933 -132.607526)
		(end 392.933936 -132.61467)
		(stroke
			(width 0.04445)
			(type default)
		)
		(layer "F.Cu")
	)
	(gr_line
		(start 392.86434 -129.79908)
		(end 392.95578 -129.70764)
		(stroke
			(width 0.04445)
			(type default)
		)
		(layer "F.Cu")
	)
	(gr_line
		(start 392.8872 -128.1557)
		(end 393.1285 -128.1557)
		(stroke
			(width 0.04445)
			(type default)
		)
		(layer "F.Cu")
	)
	(gr_line
		(start 392.921998 -36.746942)
		(end 392.925046 -36.761166)
		(stroke
			(width 0.05715)
			(type default)
		)
		(layer "F.Cu")
	)
	(gr_line
		(start 392.921998 -36.746942)
		(end 392.925046 -36.73221)
		(stroke
			(width 0.05715)
			(type default)
		)
		(layer "F.Cu")
	)
	(gr_line
		(start 392.95324 -127.48514)
		(end 392.974576 -127.48514)
		(stroke
			(width 0.04445)
			(type default)
		)
		(layer "F.Cu")
	)
	(gr_line
		(start 392.977116 -127.48514)
		(end 393.16406 -127.48514)
		(stroke
			(width 0.04445)
			(type default)
		)
		(layer "F.Cu")
	)
	(gr_arc
		(start 393.02817 -132.645912)
		(mid 392.983925 -132.621642)
		(end 392.933936 -132.61467)
		(stroke
			(width 0.04445)
			(type default)
		)
		(layer "F.Cu")
	)
	(gr_line
		(start 393.042902 -3.5306)
		(end 393.270486 -3.758184)
		(stroke
			(width 0.05715)
			(type default)
		)
		(layer "F.Cu")
	)
	(gr_line
		(start 393.042902 -3.26517)
		(end 393.131548 -3.176524)
		(stroke
			(width 0.05715)
			(type default)
		)
		(layer "F.Cu")
	)
	(gr_line
		(start 393.0904 -129.5146)
		(end 393.13739 -129.46761)
		(stroke
			(width 0.04445)
			(type default)
		)
		(layer "F.Cu")
	)
	(gr_line
		(start 393.09167 -32.207708)
		(end 393.094718 -32.193484)
		(stroke
			(width 0.05715)
			(type default)
		)
		(layer "F.Cu")
	)
	(gr_line
		(start 393.09167 -32.178752)
		(end 393.094718 -32.193484)
		(stroke
			(width 0.05715)
			(type default)
		)
		(layer "F.Cu")
	)
	(gr_line
		(start 393.10564 -129.7051)
		(end 393.13739 -129.73685)
		(stroke
			(width 0.04445)
			(type default)
		)
		(layer "F.Cu")
	)
	(gr_line
		(start 393.1285 -128.1557)
		(end 393.2682 -128.016)
		(stroke
			(width 0.04445)
			(type default)
		)
		(layer "F.Cu")
	)
	(gr_line
		(start 393.12977 -15.545054)
		(end 393.219686 -15.414752)
		(stroke
			(width 0.05715)
			(type default)
		)
		(layer "F.Cu")
	)
	(gr_line
		(start 393.130278 -27.672792)
		(end 393.13612 -27.694382)
		(stroke
			(width 0.05715)
			(type default)
		)
		(layer "F.Cu")
	)
	(gr_line
		(start 393.131548 -3.176524)
		(end 393.369292 -3.176524)
		(stroke
			(width 0.05715)
			(type default)
		)
		(layer "F.Cu")
	)
	(gr_line
		(start 393.131802 -27.715972)
		(end 393.13612 -27.694382)
		(stroke
			(width 0.05715)
			(type default)
		)
		(layer "F.Cu")
	)
	(gr_line
		(start 393.139168 -129.738628)
		(end 393.2682 -129.86766)
		(stroke
			(width 0.04445)
			(type default)
		)
		(layer "F.Cu")
	)
	(gr_line
		(start 393.139168 -129.465832)
		(end 393.2682 -129.3368)
		(stroke
			(width 0.04445)
			(type default)
		)
		(layer "F.Cu")
	)
	(gr_arc
		(start 393.16025 -132.777992)
		(mid 393.290144 -132.865004)
		(end 393.44346 -132.895594)
		(stroke
			(width 0.04445)
			(type default)
		)
		(layer "F.Cu")
	)
	(gr_line
		(start 393.16406 -127.48514)
		(end 393.2682 -127.381)
		(stroke
			(width 0.04445)
			(type default)
		)
		(layer "F.Cu")
	)
	(gr_line
		(start 393.18565 -121.87428)
		(end 393.612116 -122.0724)
		(stroke
			(width 0.05715)
			(type default)
		)
		(layer "F.Cu")
	)
	(gr_line
		(start 393.202922 -15.77975)
		(end 393.702032 -15.688056)
		(stroke
			(width 0.05715)
			(type default)
		)
		(layer "F.Cu")
	)
	(gr_line
		(start 393.20343 -20.128484)
		(end 393.212828 -20.122388)
		(stroke
			(width 0.05715)
			(type default)
		)
		(layer "F.Cu")
	)
	(gr_line
		(start 393.212828 -20.122388)
		(end 393.219432 -20.11299)
		(stroke
			(width 0.05715)
			(type default)
		)
		(layer "F.Cu")
	)
	(gr_line
		(start 393.219686 -15.414752)
		(end 393.556998 -15.352776)
		(stroke
			(width 0.05715)
			(type default)
		)
		(layer "F.Cu")
	)
	(gr_line
		(start 393.245086 -41.360344)
		(end 393.252452 -41.349168)
		(stroke
			(width 0.05715)
			(type default)
		)
		(layer "F.Cu")
	)
	(gr_line
		(start 393.252452 -41.349168)
		(end 393.255246 -41.335706)
		(stroke
			(width 0.05715)
			(type default)
		)
		(layer "F.Cu")
	)
	(gr_line
		(start 393.254992 -10.917936)
		(end 393.527026 -11.18997)
		(stroke
			(width 0.05715)
			(type default)
		)
		(layer "F.Cu")
	)
	(gr_line
		(start 393.254992 -10.028936)
		(end 393.527026 -9.756902)
		(stroke
			(width 0.05715)
			(type default)
		)
		(layer "F.Cu")
	)
	(gr_line
		(start 393.2682 -129.86766)
		(end 393.2682 -129.9972)
		(stroke
			(width 0.04445)
			(type default)
		)
		(layer "F.Cu")
	)
	(gr_line
		(start 393.270486 -8.597392)
		(end 393.49807 -8.824976)
		(stroke
			(width 0.05715)
			(type default)
		)
		(layer "F.Cu")
	)
	(gr_line
		(start 393.270486 -7.789672)
		(end 393.270486 -8.597392)
		(stroke
			(width 0.05715)
			(type default)
		)
		(layer "F.Cu")
	)
	(gr_line
		(start 393.270486 -3.758184)
		(end 393.270486 -4.386072)
		(stroke
			(width 0.05715)
			(type default)
		)
		(layer "F.Cu")
	)
	(gr_line
		(start 393.2809 -19.4056)
		(end 393.308332 -19.561302)
		(stroke
			(width 0.05715)
			(type default)
		)
		(layer "F.Cu")
	)
	(gr_line
		(start 393.2809 -19.4056)
		(end 393.477496 -19.124676)
		(stroke
			(width 0.05715)
			(type default)
		)
		(layer "F.Cu")
	)
	(gr_arc
		(start 393.295124 -132.643372)
		(mid 393.363258 -132.689072)
		(end 393.443714 -132.705094)
		(stroke
			(width 0.04445)
			(type default)
		)
		(layer "F.Cu")
	)
	(gr_line
		(start 393.477496 -19.124676)
		(end 393.633452 -19.097244)
		(stroke
			(width 0.05715)
			(type default)
		)
		(layer "F.Cu")
	)
	(gr_line
		(start 393.499848 -11.733022)
		(end 393.551156 -11.72337)
		(stroke
			(width 0.05715)
			(type default)
		)
		(layer "F.Cu")
	)
	(gr_line
		(start 393.525756 -19.67611)
		(end 393.815824 -19.262344)
		(stroke
			(width 0.05715)
			(type default)
		)
		(layer "F.Cu")
	)
	(gr_line
		(start 393.551156 -11.72337)
		(end 393.584684 -11.682984)
		(stroke
			(width 0.05715)
			(type default)
		)
		(layer "F.Cu")
	)
	(gr_line
		(start 393.556998 -15.352776)
		(end 393.6873 -15.442692)
		(stroke
			(width 0.05715)
			(type default)
		)
		(layer "F.Cu")
	)
	(gr_line
		(start 393.612116 -122.0724)
		(end 393.68095 -122.104404)
		(stroke
			(width 0.05715)
			(type default)
		)
		(layer "F.Cu")
	)
	(gr_line
		(start 393.67206 -30.942026)
		(end 393.740132 -30.605984)
		(stroke
			(width 0.05715)
			(type default)
		)
		(layer "F.Cu")
	)
	(gr_line
		(start 393.67206 -30.942026)
		(end 393.759436 -31.074106)
		(stroke
			(width 0.05715)
			(type default)
		)
		(layer "F.Cu")
	)
	(gr_line
		(start 393.675362 -39.269162)
		(end 393.67841 -39.254938)
		(stroke
			(width 0.05715)
			(type default)
		)
		(layer "F.Cu")
	)
	(gr_line
		(start 393.675362 -39.240206)
		(end 393.67841 -39.254938)
		(stroke
			(width 0.05715)
			(type default)
		)
		(layer "F.Cu")
	)
	(gr_line
		(start 393.68095 -121.01576)
		(end 394.17625 -121.245884)
		(stroke
			(width 0.05715)
			(type default)
		)
		(layer "F.Cu")
	)
	(gr_line
		(start 393.692888 -31.412942)
		(end 393.69619 -31.429198)
		(stroke
			(width 0.05715)
			(type default)
		)
		(layer "F.Cu")
	)
	(gr_line
		(start 393.692888 -31.412942)
		(end 393.69619 -31.396686)
		(stroke
			(width 0.05715)
			(type default)
		)
		(layer "F.Cu")
	)
	(gr_line
		(start 393.740132 -30.605984)
		(end 393.872212 -30.518608)
		(stroke
			(width 0.05715)
			(type default)
		)
		(layer "F.Cu")
	)
	(gr_line
		(start 393.786868 -11.439398)
		(end 393.820142 -11.399266)
		(stroke
			(width 0.05715)
			(type default)
		)
		(layer "F.Cu")
	)
	(gr_arc
		(start 393.79906 -132.940044)
		(mid 393.758692 -132.909653)
		(end 393.71016 -132.895594)
		(stroke
			(width 0.04445)
			(type default)
		)
		(layer "F.Cu")
	)
	(gr_arc
		(start 393.79906 -132.940044)
		(mid 393.839416 -132.970465)
		(end 393.88796 -132.984494)
		(stroke
			(width 0.04445)
			(type default)
		)
		(layer "F.Cu")
	)
	(gr_line
		(start 393.805664 -18.656808)
		(end 393.833096 -18.812764)
		(stroke
			(width 0.05715)
			(type default)
		)
		(layer "F.Cu")
	)
	(gr_line
		(start 393.805664 -18.656808)
		(end 394.002514 -18.375884)
		(stroke
			(width 0.05715)
			(type default)
		)
		(layer "F.Cu")
	)
	(gr_line
		(start 393.843002 -8.824976)
		(end 394.070586 -8.597392)
		(stroke
			(width 0.05715)
			(type default)
		)
		(layer "F.Cu")
	)
	(gr_line
		(start 393.845542 -25.509728)
		(end 393.855194 -25.545034)
		(stroke
			(width 0.05715)
			(type default)
		)
		(layer "F.Cu")
	)
	(gr_line
		(start 393.845542 -25.509728)
		(end 393.85621 -25.47493)
		(stroke
			(width 0.05715)
			(type default)
		)
		(layer "F.Cu")
	)
	(gr_line
		(start 393.85621 -25.474676)
		(end 393.856464 -25.474168)
		(stroke
			(width 0.05715)
			(type default)
		)
		(layer "F.Cu")
	)
	(gr_line
		(start 393.871958 -11.18997)
		(end 394.143992 -10.917936)
		(stroke
			(width 0.05715)
			(type default)
		)
		(layer "F.Cu")
	)
	(gr_line
		(start 393.871958 -9.756902)
		(end 394.143992 -10.028936)
		(stroke
			(width 0.05715)
			(type default)
		)
		(layer "F.Cu")
	)
	(gr_line
		(start 393.88796 -132.984494)
		(end 394.15466 -132.984494)
		(stroke
			(width 0.04445)
			(type default)
		)
		(layer "F.Cu")
	)
	(gr_line
		(start 393.9032 -132.705094)
		(end 394.13942 -132.705094)
		(stroke
			(width 0.04445)
			(type default)
		)
		(layer "F.Cu")
	)
	(gr_line
		(start 393.949428 -21.712174)
		(end 393.949682 -21.711412)
		(stroke
			(width 0.05715)
			(type default)
		)
		(layer "F.Cu")
	)
	(gr_line
		(start 393.949428 -21.711412)
		(end 393.949682 -21.711412)
		(stroke
			(width 0.05715)
			(type default)
		)
		(layer "F.Cu")
	)
	(gr_line
		(start 393.949428 -21.711412)
		(end 393.950444 -21.709888)
		(stroke
			(width 0.05715)
			(type default)
		)
		(layer "F.Cu")
	)
	(gr_line
		(start 394.002514 -18.375884)
		(end 394.15847 -18.348452)
		(stroke
			(width 0.05715)
			(type default)
		)
		(layer "F.Cu")
	)
	(gr_line
		(start 394.004546 -31.09087)
		(end 394.104622 -30.599126)
		(stroke
			(width 0.05715)
			(type default)
		)
		(layer "F.Cu")
	)
	(gr_line
		(start 394.029184 -15.3797)
		(end 394.1191 -15.249398)
		(stroke
			(width 0.05715)
			(type default)
		)
		(layer "F.Cu")
	)
	(gr_line
		(start 394.05052 -18.927318)
		(end 394.34008 -18.513806)
		(stroke
			(width 0.05715)
			(type default)
		)
		(layer "F.Cu")
	)
	(gr_line
		(start 394.070586 -7.789672)
		(end 394.070586 -8.597392)
		(stroke
			(width 0.05715)
			(type default)
		)
		(layer "F.Cu")
	)
	(gr_line
		(start 394.09116 -28.879546)
		(end 394.159486 -28.543758)
		(stroke
			(width 0.05715)
			(type default)
		)
		(layer "F.Cu")
	)
	(gr_line
		(start 394.09116 -28.879546)
		(end 394.178536 -29.01188)
		(stroke
			(width 0.05715)
			(type default)
		)
		(layer "F.Cu")
	)
	(gr_line
		(start 394.095478 -32.158686)
		(end 394.095732 -32.159194)
		(stroke
			(width 0.05715)
			(type default)
		)
		(layer "F.Cu")
	)
	(gr_line
		(start 394.095732 -32.191198)
		(end 394.099034 -32.17545)
		(stroke
			(width 0.05715)
			(type default)
		)
		(layer "F.Cu")
	)
	(gr_line
		(start 394.095732 -32.159448)
		(end 394.099034 -32.17545)
		(stroke
			(width 0.05715)
			(type default)
		)
		(layer "F.Cu")
	)
	(gr_line
		(start 394.102844 -15.614396)
		(end 394.602208 -15.522702)
		(stroke
			(width 0.05715)
			(type default)
		)
		(layer "F.Cu")
	)
	(gr_line
		(start 394.1191 -15.249398)
		(end 394.456412 -15.187422)
		(stroke
			(width 0.05715)
			(type default)
		)
		(layer "F.Cu")
	)
	(gr_line
		(start 394.124942 -26.963624)
		(end 394.203428 -26.825702)
		(stroke
			(width 0.05715)
			(type default)
		)
		(layer "F.Cu")
	)
	(gr_line
		(start 394.124942 -26.963624)
		(end 394.21562 -27.294332)
		(stroke
			(width 0.05715)
			(type default)
		)
		(layer "F.Cu")
	)
	(gr_arc
		(start 394.15466 -132.984494)
		(mid 394.203186 -132.970429)
		(end 394.24356 -132.940044)
		(stroke
			(width 0.04445)
			(type default)
		)
		(layer "F.Cu")
	)
	(gr_line
		(start 394.159486 -28.543758)
		(end 394.291566 -28.456128)
		(stroke
			(width 0.05715)
			(type default)
		)
		(layer "F.Cu")
	)
	(gr_line
		(start 394.21562 -27.294332)
		(end 394.353034 -27.372564)
		(stroke
			(width 0.05715)
			(type default)
		)
		(layer "F.Cu")
	)
	(gr_arc
		(start 394.33246 -132.895594)
		(mid 394.283903 -132.909612)
		(end 394.24356 -132.940044)
		(stroke
			(width 0.04445)
			(type default)
		)
		(layer "F.Cu")
	)
	(gr_line
		(start 394.423646 -29.02839)
		(end 394.523468 -28.5369)
		(stroke
			(width 0.05715)
			(type default)
		)
		(layer "F.Cu")
	)
	(gr_line
		(start 394.44676 -26.790904)
		(end 394.58011 -27.278076)
		(stroke
			(width 0.05715)
			(type default)
		)
		(layer "F.Cu")
	)
	(gr_line
		(start 394.456412 -15.187422)
		(end 394.586714 -15.277338)
		(stroke
			(width 0.05715)
			(type default)
		)
		(layer "F.Cu")
	)
	(gr_line
		(start 394.518388 -12.289028)
		(end 394.607288 -12.158472)
		(stroke
			(width 0.05715)
			(type default)
		)
		(layer "F.Cu")
	)
	(gr_line
		(start 394.595096 -12.522708)
		(end 395.087856 -12.42949)
		(stroke
			(width 0.05715)
			(type default)
		)
		(layer "F.Cu")
	)
	(gr_line
		(start 394.607288 -12.158472)
		(end 394.944346 -12.094718)
		(stroke
			(width 0.05715)
			(type default)
		)
		(layer "F.Cu")
	)
	(gr_line
		(start 394.67155 -107.27944)
		(end 395.16685 -107.049316)
		(stroke
			(width 0.050038)
			(type default)
		)
		(layer "F.Cu")
	)
	(gr_arc
		(start 394.68806 -132.940044)
		(mid 394.647692 -132.909653)
		(end 394.59916 -132.895594)
		(stroke
			(width 0.04445)
			(type default)
		)
		(layer "F.Cu")
	)
	(gr_arc
		(start 394.68806 -132.940044)
		(mid 394.728416 -132.970465)
		(end 394.77696 -132.984494)
		(stroke
			(width 0.04445)
			(type default)
		)
		(layer "F.Cu")
	)
	(gr_line
		(start 394.688314 -27.673046)
		(end 394.694664 -27.696668)
		(stroke
			(width 0.05715)
			(type default)
		)
		(layer "F.Cu")
	)
	(gr_line
		(start 394.689838 -27.720036)
		(end 394.694664 -27.696668)
		(stroke
			(width 0.05715)
			(type default)
		)
		(layer "F.Cu")
	)
	(gr_line
		(start 394.729208 -17.537938)
		(end 394.765784 -17.485868)
		(stroke
			(width 0.05715)
			(type default)
		)
		(layer "F.Cu")
	)
	(gr_line
		(start 394.753592 -3.125724)
		(end 395.022324 -3.125724)
		(stroke
			(width 0.05715)
			(type default)
		)
		(layer "F.Cu")
	)
	(gr_line
		(start 394.765784 -17.485868)
		(end 394.828268 -17.473168)
		(stroke
			(width 0.05715)
			(type default)
		)
		(layer "F.Cu")
	)
	(gr_line
		(start 394.77696 -132.984494)
		(end 395.04366 -132.984494)
		(stroke
			(width 0.04445)
			(type default)
		)
		(layer "F.Cu")
	)
	(gr_line
		(start 394.7922 -132.705094)
		(end 395.02842 -132.705094)
		(stroke
			(width 0.04445)
			(type default)
		)
		(layer "F.Cu")
	)
	(gr_line
		(start 394.870686 -3.758184)
		(end 394.870686 -4.386072)
		(stroke
			(width 0.05715)
			(type default)
		)
		(layer "F.Cu")
	)
	(gr_line
		(start 394.870686 -3.758184)
		(end 395.09827 -3.5306)
		(stroke
			(width 0.05715)
			(type default)
		)
		(layer "F.Cu")
	)
	(gr_line
		(start 394.875258 -25.622758)
		(end 395.040358 -25.622758)
		(stroke
			(width 0.05715)
			(type default)
		)
		(layer "F.Cu")
	)
	(gr_line
		(start 394.928344 -15.2146)
		(end 395.018514 -15.084298)
		(stroke
			(width 0.05715)
			(type default)
		)
		(layer "F.Cu")
	)
	(gr_line
		(start 394.944346 -12.094718)
		(end 395.074648 -12.183872)
		(stroke
			(width 0.05715)
			(type default)
		)
		(layer "F.Cu")
	)
	(gr_line
		(start 395.001496 -15.449296)
		(end 395.500352 -15.357602)
		(stroke
			(width 0.05715)
			(type default)
		)
		(layer "F.Cu")
	)
	(gr_line
		(start 395.018514 -15.084298)
		(end 395.355572 -15.022322)
		(stroke
			(width 0.05715)
			(type default)
		)
		(layer "F.Cu")
	)
	(gr_line
		(start 395.022324 -3.125724)
		(end 395.102334 -3.205734)
		(stroke
			(width 0.05715)
			(type default)
		)
		(layer "F.Cu")
	)
	(gr_line
		(start 395.040358 -25.622758)
		(end 395.2367 -25.8191)
		(stroke
			(width 0.05715)
			(type default)
		)
		(layer "F.Cu")
	)
	(gr_arc
		(start 395.04366 -132.984494)
		(mid 395.092186 -132.970429)
		(end 395.13256 -132.940044)
		(stroke
			(width 0.04445)
			(type default)
		)
		(layer "F.Cu")
	)
	(gr_line
		(start 395.16685 -123.59132)
		(end 395.224 -123.61799)
		(stroke
			(width 0.05715)
			(type default)
		)
		(layer "F.Cu")
	)
	(gr_arc
		(start 395.22146 -132.895594)
		(mid 395.172903 -132.909612)
		(end 395.13256 -132.940044)
		(stroke
			(width 0.04445)
			(type default)
		)
		(layer "F.Cu")
	)
	(gr_line
		(start 395.224 -123.61799)
		(end 395.66215 -123.821444)
		(stroke
			(width 0.05715)
			(type default)
		)
		(layer "F.Cu")
	)
	(gr_line
		(start 395.2367 -25.8191)
		(end 395.2367 -26.135076)
		(stroke
			(width 0.05715)
			(type default)
		)
		(layer "F.Cu")
	)
	(gr_line
		(start 395.355572 -15.022322)
		(end 395.486128 -15.112238)
		(stroke
			(width 0.05715)
			(type default)
		)
		(layer "F.Cu")
	)
	(gr_line
		(start 395.443202 -3.5306)
		(end 395.670786 -3.758184)
		(stroke
			(width 0.05715)
			(type default)
		)
		(layer "F.Cu")
	)
	(gr_line
		(start 395.447266 -3.205734)
		(end 395.527276 -3.125724)
		(stroke
			(width 0.05715)
			(type default)
		)
		(layer "F.Cu")
	)
	(gr_line
		(start 395.493494 -12.353036)
		(end 395.54531 -12.34313)
		(stroke
			(width 0.05715)
			(type default)
		)
		(layer "F.Cu")
	)
	(gr_line
		(start 395.49705 -25.774396)
		(end 395.49705 -26.050494)
		(stroke
			(width 0.05715)
			(type default)
		)
		(layer "F.Cu")
	)
	(gr_line
		(start 395.49705 -25.774396)
		(end 395.648688 -25.622758)
		(stroke
			(width 0.05715)
			(type default)
		)
		(layer "F.Cu")
	)
	(gr_line
		(start 395.527276 -3.125724)
		(end 395.769592 -3.125724)
		(stroke
			(width 0.05715)
			(type default)
		)
		(layer "F.Cu")
	)
	(gr_line
		(start 395.54531 -12.34313)
		(end 395.579092 -12.30249)
		(stroke
			(width 0.05715)
			(type default)
		)
		(layer "F.Cu")
	)
	(gr_arc
		(start 395.57706 -132.940044)
		(mid 395.536692 -132.909653)
		(end 395.48816 -132.895594)
		(stroke
			(width 0.04445)
			(type default)
		)
		(layer "F.Cu")
	)
	(gr_arc
		(start 395.57706 -132.940044)
		(mid 395.617416 -132.970465)
		(end 395.66596 -132.984494)
		(stroke
			(width 0.04445)
			(type default)
		)
		(layer "F.Cu")
	)
	(gr_line
		(start 395.579092 -10.968736)
		(end 395.851126 -11.24077)
		(stroke
			(width 0.05715)
			(type default)
		)
		(layer "F.Cu")
	)
	(gr_line
		(start 395.579092 -10.079736)
		(end 395.851126 -9.807702)
		(stroke
			(width 0.05715)
			(type default)
		)
		(layer "F.Cu")
	)
	(gr_line
		(start 395.648688 -25.622758)
		(end 395.766544 -25.622758)
		(stroke
			(width 0.05715)
			(type default)
		)
		(layer "F.Cu")
	)
	(gr_line
		(start 395.66215 -122.7328)
		(end 396.15745 -122.962924)
		(stroke
			(width 0.05715)
			(type default)
		)
		(layer "F.Cu")
	)
	(gr_line
		(start 395.66215 -121.01576)
		(end 396.15745 -121.245884)
		(stroke
			(width 0.05715)
			(type default)
		)
		(layer "F.Cu")
	)
	(gr_line
		(start 395.66215 -107.27944)
		(end 396.15745 -107.049316)
		(stroke
			(width 0.050038)
			(type default)
		)
		(layer "F.Cu")
	)
	(gr_line
		(start 395.66596 -132.984494)
		(end 395.93266 -132.984494)
		(stroke
			(width 0.04445)
			(type default)
		)
		(layer "F.Cu")
	)
	(gr_line
		(start 395.670786 -8.597392)
		(end 395.89837 -8.824976)
		(stroke
			(width 0.05715)
			(type default)
		)
		(layer "F.Cu")
	)
	(gr_line
		(start 395.670786 -7.789672)
		(end 395.670786 -8.597392)
		(stroke
			(width 0.05715)
			(type default)
		)
		(layer "F.Cu")
	)
	(gr_line
		(start 395.670786 -3.758184)
		(end 395.670786 -4.386072)
		(stroke
			(width 0.05715)
			(type default)
		)
		(layer "F.Cu")
	)
	(gr_line
		(start 395.6812 -132.705094)
		(end 395.91742 -132.705094)
		(stroke
			(width 0.04445)
			(type default)
		)
		(layer "F.Cu")
	)
	(gr_line
		(start 395.7574 -32.513524)
		(end 395.7574 -32.747204)
		(stroke
			(width 0.05715)
			(type default)
		)
		(layer "F.Cu")
	)
	(gr_line
		(start 395.7574 -32.513524)
		(end 395.947646 -32.323278)
		(stroke
			(width 0.05715)
			(type default)
		)
		(layer "F.Cu")
	)
	(gr_line
		(start 395.7574 -31.7881)
		(end 395.947646 -31.978346)
		(stroke
			(width 0.05715)
			(type default)
		)
		(layer "F.Cu")
	)
	(gr_line
		(start 395.7574 -31.604458)
		(end 395.7574 -31.7881)
		(stroke
			(width 0.05715)
			(type default)
		)
		(layer "F.Cu")
	)
	(gr_line
		(start 395.852396 -16.52143)
		(end 395.865858 -16.518636)
		(stroke
			(width 0.05715)
			(type default)
		)
		(layer "F.Cu")
	)
	(gr_line
		(start 395.865858 -16.518636)
		(end 395.877034 -16.51127)
		(stroke
			(width 0.05715)
			(type default)
		)
		(layer "F.Cu")
	)
	(gr_line
		(start 395.902434 -15.283688)
		(end 395.91742 -15.280894)
		(stroke
			(width 0.05715)
			(type default)
		)
		(layer "F.Cu")
	)
	(gr_line
		(start 395.91742 -15.280894)
		(end 395.929104 -15.27302)
		(stroke
			(width 0.05715)
			(type default)
		)
		(layer "F.Cu")
	)
	(gr_line
		(start 395.921738 -20.493736)
		(end 395.9352 -20.472654)
		(stroke
			(width 0.05715)
			(type default)
		)
		(layer "F.Cu")
	)
	(gr_arc
		(start 395.93266 -132.984494)
		(mid 395.981186 -132.970429)
		(end 396.02156 -132.940044)
		(stroke
			(width 0.04445)
			(type default)
		)
		(layer "F.Cu")
	)
	(gr_line
		(start 395.9352 -20.472654)
		(end 395.95679 -20.460208)
		(stroke
			(width 0.05715)
			(type default)
		)
		(layer "F.Cu")
	)
	(gr_arc
		(start 396.11046 -132.895594)
		(mid 396.061903 -132.909612)
		(end 396.02156 -132.940044)
		(stroke
			(width 0.04445)
			(type default)
		)
		(layer "F.Cu")
	)
	(gr_line
		(start 396.111222 -11.6586)
		(end 396.144242 -11.618468)
		(stroke
			(width 0.05715)
			(type default)
		)
		(layer "F.Cu")
	)
	(gr_line
		(start 396.155672 -18.375376)
		(end 396.164054 -18.362676)
		(stroke
			(width 0.05715)
			(type default)
		)
		(layer "F.Cu")
	)
	(gr_line
		(start 396.15745 -123.59132)
		(end 396.65275 -123.821444)
		(stroke
			(width 0.05715)
			(type default)
		)
		(layer "F.Cu")
	)
	(gr_line
		(start 396.15745 -121.87428)
		(end 396.583916 -122.0724)
		(stroke
			(width 0.05715)
			(type default)
		)
		(layer "F.Cu")
	)
	(gr_line
		(start 396.164054 -18.362676)
		(end 396.176754 -18.354294)
		(stroke
			(width 0.05715)
			(type default)
		)
		(layer "F.Cu")
	)
	(gr_line
		(start 396.196058 -11.24077)
		(end 396.468092 -10.968736)
		(stroke
			(width 0.05715)
			(type default)
		)
		(layer "F.Cu")
	)
	(gr_line
		(start 396.196058 -9.807702)
		(end 396.468092 -10.079736)
		(stroke
			(width 0.05715)
			(type default)
		)
		(layer "F.Cu")
	)
	(gr_line
		(start 396.243302 -8.824976)
		(end 396.470886 -8.597392)
		(stroke
			(width 0.05715)
			(type default)
		)
		(layer "F.Cu")
	)
	(gr_line
		(start 396.244572 -17.432528)
		(end 396.257018 -17.429988)
		(stroke
			(width 0.05715)
			(type default)
		)
		(layer "F.Cu")
	)
	(gr_line
		(start 396.257018 -17.429988)
		(end 396.26794 -17.422876)
		(stroke
			(width 0.05715)
			(type default)
		)
		(layer "F.Cu")
	)
	(gr_line
		(start 396.265908 -127.40259)
		(end 396.352268 -127.48895)
		(stroke
			(width 0.04445)
			(type default)
		)
		(layer "F.Cu")
	)
	(gr_line
		(start 396.265908 -127.13589)
		(end 396.265908 -127.40259)
		(stroke
			(width 0.04445)
			(type default)
		)
		(layer "F.Cu")
	)
	(gr_line
		(start 396.265908 -127.13589)
		(end 396.352268 -127.04953)
		(stroke
			(width 0.04445)
			(type default)
		)
		(layer "F.Cu")
	)
	(gr_line
		(start 396.265908 -126.69139)
		(end 396.352268 -126.77775)
		(stroke
			(width 0.04445)
			(type default)
		)
		(layer "F.Cu")
	)
	(gr_line
		(start 396.265908 -126.42469)
		(end 396.265908 -126.69139)
		(stroke
			(width 0.04445)
			(type default)
		)
		(layer "F.Cu")
	)
	(gr_line
		(start 396.265908 -126.42469)
		(end 396.352268 -126.33833)
		(stroke
			(width 0.04445)
			(type default)
		)
		(layer "F.Cu")
	)
	(gr_arc
		(start 396.46606 -132.940044)
		(mid 396.425692 -132.909653)
		(end 396.37716 -132.895594)
		(stroke
			(width 0.04445)
			(type default)
		)
		(layer "F.Cu")
	)
	(gr_arc
		(start 396.46606 -132.940044)
		(mid 396.506416 -132.970465)
		(end 396.55496 -132.984494)
		(stroke
			(width 0.04445)
			(type default)
		)
		(layer "F.Cu")
	)
	(gr_line
		(start 396.470886 -7.789672)
		(end 396.470886 -8.597392)
		(stroke
			(width 0.05715)
			(type default)
		)
		(layer "F.Cu")
	)
	(gr_line
		(start 396.48511 -125.750066)
		(end 396.535402 -125.800358)
		(stroke
			(width 0.04445)
			(type default)
		)
		(layer "F.Cu")
	)
	(gr_line
		(start 396.48511 -124.919994)
		(end 396.656814 -125.38075)
		(stroke
			(width 0.04445)
			(type default)
		)
		(layer "F.Cu")
	)
	(gr_line
		(start 396.535402 -125.800358)
		(end 396.535402 -125.899164)
		(stroke
			(width 0.04445)
			(type default)
		)
		(layer "F.Cu")
	)
	(gr_line
		(start 396.545308 -127.24003)
		(end 396.545308 -127.29845)
		(stroke
			(width 0.04445)
			(type default)
		)
		(layer "F.Cu")
	)
	(gr_line
		(start 396.545308 -126.52883)
		(end 396.545308 -126.58725)
		(stroke
			(width 0.04445)
			(type default)
		)
		(layer "F.Cu")
	)
	(gr_line
		(start 396.55496 -132.984494)
		(end 396.82166 -132.984494)
		(stroke
			(width 0.04445)
			(type default)
		)
		(layer "F.Cu")
	)
	(gr_line
		(start 396.5702 -132.705094)
		(end 396.80642 -132.705094)
		(stroke
			(width 0.04445)
			(type default)
		)
		(layer "F.Cu")
	)
	(gr_line
		(start 396.583916 -122.0724)
		(end 396.65275 -122.104404)
		(stroke
			(width 0.05715)
			(type default)
		)
		(layer "F.Cu")
	)
	(gr_line
		(start 396.65275 -122.7328)
		(end 397.14805 -122.962924)
		(stroke
			(width 0.05715)
			(type default)
		)
		(layer "F.Cu")
	)
	(gr_line
		(start 396.65275 -121.01576)
		(end 397.14805 -121.245884)
		(stroke
			(width 0.05715)
			(type default)
		)
		(layer "F.Cu")
	)
	(gr_line
		(start 396.65275 -117.58168)
		(end 397.14805 -117.811804)
		(stroke
			(width 0.05715)
			(type default)
		)
		(layer "F.Cu")
	)
	(gr_line
		(start 396.656814 -125.38075)
		(end 396.69593 -125.485652)
		(stroke
			(width 0.04445)
			(type default)
		)
		(layer "F.Cu")
	)
	(gr_line
		(start 396.69593 -125.485652)
		(end 396.713964 -125.533912)
		(stroke
			(width 0.04445)
			(type default)
		)
		(layer "F.Cu")
	)
	(gr_line
		(start 396.713964 -125.533912)
		(end 396.7988 -125.618748)
		(stroke
			(width 0.04445)
			(type default)
		)
		(layer "F.Cu")
	)
	(gr_line
		(start 396.729966 -125.97765)
		(end 396.7988 -125.81128)
		(stroke
			(width 0.04445)
			(type default)
		)
		(layer "F.Cu")
	)
	(gr_line
		(start 396.7988 -125.618748)
		(end 396.7988 -125.81128)
		(stroke
			(width 0.04445)
			(type default)
		)
		(layer "F.Cu")
	)
	(gr_arc
		(start 396.82166 -132.984494)
		(mid 396.870186 -132.970429)
		(end 396.91056 -132.940044)
		(stroke
			(width 0.04445)
			(type default)
		)
		(layer "F.Cu")
	)
	(gr_line
		(start 396.836138 -13.238226)
		(end 396.858236 -13.234162)
		(stroke
			(width 0.05715)
			(type default)
		)
		(layer "F.Cu")
	)
	(gr_line
		(start 396.858236 -13.234162)
		(end 396.875254 -13.221208)
		(stroke
			(width 0.05715)
			(type default)
		)
		(layer "F.Cu")
	)
	(gr_arc
		(start 396.99946 -132.895594)
		(mid 396.950903 -132.909612)
		(end 396.91056 -132.940044)
		(stroke
			(width 0.04445)
			(type default)
		)
		(layer "F.Cu")
	)
	(gr_line
		(start 397.128492 -3.176524)
		(end 397.409924 -3.176524)
		(stroke
			(width 0.05715)
			(type default)
		)
		(layer "F.Cu")
	)
	(gr_line
		(start 397.13916 -128.038606)
		(end 397.337534 -128.23698)
		(stroke
			(width 0.04445)
			(type default)
		)
		(layer "F.Cu")
	)
	(gr_line
		(start 397.14805 -123.59132)
		(end 397.470376 -123.74118)
		(stroke
			(width 0.05715)
			(type default)
		)
		(layer "F.Cu")
	)
	(gr_line
		(start 397.14805 -116.72316)
		(end 397.470376 -116.87302)
		(stroke
			(width 0.05715)
			(type default)
		)
		(layer "F.Cu")
	)
	(gr_line
		(start 397.14805 -105.332276)
		(end 397.558768 -105.52303)
		(stroke
			(width 0.050038)
			(type default)
		)
		(layer "F.Cu")
	)
	(gr_line
		(start 397.270986 -3.758184)
		(end 397.270986 -4.386072)
		(stroke
			(width 0.05715)
			(type default)
		)
		(layer "F.Cu")
	)
	(gr_line
		(start 397.270986 -3.758184)
		(end 397.49857 -3.5306)
		(stroke
			(width 0.05715)
			(type default)
		)
		(layer "F.Cu")
	)
	(gr_line
		(start 397.32966 -127.845566)
		(end 397.51 -127.845566)
		(stroke
			(width 0.04445)
			(type default)
		)
		(layer "F.Cu")
	)
	(gr_line
		(start 397.337534 -128.23698)
		(end 397.3957 -128.23698)
		(stroke
			(width 0.04445)
			(type default)
		)
		(layer "F.Cu")
	)
	(gr_line
		(start 397.3957 -128.23698)
		(end 397.4846 -128.32588)
		(stroke
			(width 0.04445)
			(type default)
		)
		(layer "F.Cu")
	)
	(gr_line
		(start 397.404336 -132.895594)
		(end 397.429736 -132.920994)
		(stroke
			(width 0.04445)
			(type default)
		)
		(layer "F.Cu")
	)
	(gr_line
		(start 397.404336 -132.705094)
		(end 397.429736 -132.679694)
		(stroke
			(width 0.04445)
			(type default)
		)
		(layer "F.Cu")
	)
	(gr_line
		(start 397.409924 -3.176524)
		(end 397.464534 -3.231134)
		(stroke
			(width 0.05715)
			(type default)
		)
		(layer "F.Cu")
	)
	(gr_line
		(start 397.429736 -132.920994)
		(end 397.451834 -132.920994)
		(stroke
			(width 0.04445)
			(type default)
		)
		(layer "F.Cu")
	)
	(gr_line
		(start 397.429736 -132.679694)
		(end 397.451834 -132.679694)
		(stroke
			(width 0.04445)
			(type default)
		)
		(layer "F.Cu")
	)
	(gr_line
		(start 397.470376 -123.74118)
		(end 397.558768 -123.782074)
		(stroke
			(width 0.05715)
			(type default)
		)
		(layer "F.Cu")
	)
	(gr_line
		(start 397.470376 -116.87302)
		(end 397.558768 -116.913914)
		(stroke
			(width 0.05715)
			(type default)
		)
		(layer "F.Cu")
	)
	(gr_line
		(start 397.4846 -128.582166)
		(end 397.51 -128.607566)
		(stroke
			(width 0.04445)
			(type default)
		)
		(layer "F.Cu")
	)
	(gr_line
		(start 397.4846 -128.32588)
		(end 397.4846 -128.582166)
		(stroke
			(width 0.04445)
			(type default)
		)
		(layer "F.Cu")
	)
	(gr_line
		(start 397.543782 -27.689302)
		(end 397.786098 -27.931872)
		(stroke
			(width 0.05715)
			(type default)
		)
		(layer "F.Cu")
	)
	(gr_line
		(start 397.543782 -27.531314)
		(end 397.543782 -27.689302)
		(stroke
			(width 0.05715)
			(type default)
		)
		(layer "F.Cu")
	)
	(gr_line
		(start 397.558768 -123.782074)
		(end 397.64335 -123.821444)
		(stroke
			(width 0.05715)
			(type default)
		)
		(layer "F.Cu")
	)
	(gr_line
		(start 397.558768 -116.913914)
		(end 397.64335 -116.953284)
		(stroke
			(width 0.05715)
			(type default)
		)
		(layer "F.Cu")
	)
	(gr_line
		(start 397.558768 -105.52303)
		(end 397.64335 -105.5624)
		(stroke
			(width 0.050038)
			(type default)
		)
		(layer "F.Cu")
	)
	(gr_line
		(start 397.64335 -122.7328)
		(end 397.7894 -122.800618)
		(stroke
			(width 0.05715)
			(type default)
		)
		(layer "F.Cu")
	)
	(gr_line
		(start 397.786098 -27.931872)
		(end 397.94434 -27.931872)
		(stroke
			(width 0.05715)
			(type default)
		)
		(layer "F.Cu")
	)
	(gr_line
		(start 397.7894 -122.800618)
		(end 398.13865 -122.962924)
		(stroke
			(width 0.05715)
			(type default)
		)
		(layer "F.Cu")
	)
	(gr_line
		(start 397.809466 -3.231134)
		(end 397.864076 -3.176524)
		(stroke
			(width 0.05715)
			(type default)
		)
		(layer "F.Cu")
	)
	(gr_line
		(start 397.843502 -3.5306)
		(end 398.071086 -3.758184)
		(stroke
			(width 0.05715)
			(type default)
		)
		(layer "F.Cu")
	)
	(gr_line
		(start 397.864076 -3.176524)
		(end 398.144492 -3.176524)
		(stroke
			(width 0.05715)
			(type default)
		)
		(layer "F.Cu")
	)
	(gr_line
		(start 397.886936 -27.529536)
		(end 397.946118 -27.588718)
		(stroke
			(width 0.05715)
			(type default)
		)
		(layer "F.Cu")
	)
	(gr_line
		(start 398.030192 -10.917936)
		(end 398.302226 -11.18997)
		(stroke
			(width 0.05715)
			(type default)
		)
		(layer "F.Cu")
	)
	(gr_line
		(start 398.030192 -10.028936)
		(end 398.302226 -9.756902)
		(stroke
			(width 0.05715)
			(type default)
		)
		(layer "F.Cu")
	)
	(gr_line
		(start 398.071086 -8.597392)
		(end 398.29867 -8.824976)
		(stroke
			(width 0.05715)
			(type default)
		)
		(layer "F.Cu")
	)
	(gr_line
		(start 398.071086 -7.789672)
		(end 398.071086 -8.597392)
		(stroke
			(width 0.05715)
			(type default)
		)
		(layer "F.Cu")
	)
	(gr_line
		(start 398.071086 -3.758184)
		(end 398.071086 -4.386072)
		(stroke
			(width 0.05715)
			(type default)
		)
		(layer "F.Cu")
	)
	(gr_line
		(start 398.123664 -19.489166)
		(end 398.180814 -19.4564)
		(stroke
			(width 0.05715)
			(type default)
		)
		(layer "F.Cu")
	)
	(gr_line
		(start 398.13865 -121.87428)
		(end 398.63395 -122.104404)
		(stroke
			(width 0.05715)
			(type default)
		)
		(layer "F.Cu")
	)
	(gr_line
		(start 398.13865 -105.332276)
		(end 398.63395 -105.5624)
		(stroke
			(width 0.050038)
			(type default)
		)
		(layer "F.Cu")
	)
	(gr_line
		(start 398.180814 -19.4564)
		(end 398.198086 -19.392392)
		(stroke
			(width 0.05715)
			(type default)
		)
		(layer "F.Cu")
	)
	(gr_line
		(start 398.264888 -18.213578)
		(end 398.279874 -18.157952)
		(stroke
			(width 0.05715)
			(type default)
		)
		(layer "F.Cu")
	)
	(gr_line
		(start 398.279874 -18.157952)
		(end 398.32788 -18.126202)
		(stroke
			(width 0.05715)
			(type default)
		)
		(layer "F.Cu")
	)
	(gr_line
		(start 398.562322 -11.607292)
		(end 398.595342 -11.567668)
		(stroke
			(width 0.05715)
			(type default)
		)
		(layer "F.Cu")
	)
	(gr_line
		(start 398.63395 -122.7328)
		(end 399.17243 -122.641868)
		(stroke
			(width 0.05715)
			(type default)
		)
		(layer "F.Cu")
	)
	(gr_line
		(start 398.63395 -121.01576)
		(end 399.12925 -121.245884)
		(stroke
			(width 0.05715)
			(type default)
		)
		(layer "F.Cu")
	)
	(gr_line
		(start 398.643602 -8.824976)
		(end 398.871186 -8.597392)
		(stroke
			(width 0.05715)
			(type default)
		)
		(layer "F.Cu")
	)
	(gr_line
		(start 398.647158 -11.18997)
		(end 398.919192 -10.917936)
		(stroke
			(width 0.05715)
			(type default)
		)
		(layer "F.Cu")
	)
	(gr_line
		(start 398.647158 -9.756902)
		(end 398.919192 -10.028936)
		(stroke
			(width 0.05715)
			(type default)
		)
		(layer "F.Cu")
	)
	(gr_line
		(start 398.871186 -7.789672)
		(end 398.871186 -8.597392)
		(stroke
			(width 0.05715)
			(type default)
		)
		(layer "F.Cu")
	)
	(gr_line
		(start 399.554192 -3.176524)
		(end 399.873724 -3.176524)
		(stroke
			(width 0.05715)
			(type default)
		)
		(layer "F.Cu")
	)
	(gr_line
		(start 399.671286 -3.758184)
		(end 399.671286 -4.386072)
		(stroke
			(width 0.05715)
			(type default)
		)
		(layer "F.Cu")
	)
	(gr_line
		(start 399.671286 -3.758184)
		(end 399.89887 -3.5306)
		(stroke
			(width 0.05715)
			(type default)
		)
		(layer "F.Cu")
	)
	(gr_line
		(start 399.873724 -3.176524)
		(end 399.890234 -3.193034)
		(stroke
			(width 0.05715)
			(type default)
		)
		(layer "F.Cu")
	)
	(gr_line
		(start 400.05 -121.355104)
		(end 400.56816 -121.179082)
		(stroke
			(width 0.04445)
			(type default)
		)
		(layer "F.Cu")
	)
	(gr_line
		(start 400.05 -120.355106)
		(end 400.649948 -120.126252)
		(stroke
			(width 0.04445)
			(type default)
		)
		(layer "F.Cu")
	)
	(gr_line
		(start 400.05 -119.355108)
		(end 400.406108 -119.355108)
		(stroke
			(width 0.04445)
			(type default)
		)
		(layer "F.Cu")
	)
	(gr_line
		(start 400.235166 -3.193034)
		(end 400.251676 -3.176524)
		(stroke
			(width 0.05715)
			(type default)
		)
		(layer "F.Cu")
	)
	(gr_line
		(start 400.243802 -3.5306)
		(end 400.471386 -3.758184)
		(stroke
			(width 0.05715)
			(type default)
		)
		(layer "F.Cu")
	)
	(gr_line
		(start 400.251676 -3.176524)
		(end 400.570192 -3.176524)
		(stroke
			(width 0.05715)
			(type default)
		)
		(layer "F.Cu")
	)
	(gr_line
		(start 400.351752 -12.345924)
		(end 400.353784 -12.3444)
		(stroke
			(width 0.05715)
			(type default)
		)
		(layer "F.Cu")
	)
	(gr_line
		(start 400.353784 -12.3444)
		(end 400.355562 -12.342368)
		(stroke
			(width 0.05715)
			(type default)
		)
		(layer "F.Cu")
	)
	(gr_line
		(start 400.406108 -119.355108)
		(end 400.7358 -119.6848)
		(stroke
			(width 0.04445)
			(type default)
		)
		(layer "F.Cu")
	)
	(gr_line
		(start 400.430492 -10.917936)
		(end 400.702526 -11.18997)
		(stroke
			(width 0.05715)
			(type default)
		)
		(layer "F.Cu")
	)
	(gr_line
		(start 400.430492 -10.028936)
		(end 400.702526 -9.756902)
		(stroke
			(width 0.05715)
			(type default)
		)
		(layer "F.Cu")
	)
	(gr_line
		(start 400.465036 -120.854978)
		(end 401.0406 -120.66016)
		(stroke
			(width 0.04445)
			(type default)
		)
		(layer "F.Cu")
	)
	(gr_line
		(start 400.471386 -8.597392)
		(end 400.69897 -8.824976)
		(stroke
			(width 0.05715)
			(type default)
		)
		(layer "F.Cu")
	)
	(gr_line
		(start 400.471386 -7.789672)
		(end 400.471386 -8.597392)
		(stroke
			(width 0.05715)
			(type default)
		)
		(layer "F.Cu")
	)
	(gr_line
		(start 400.471386 -3.758184)
		(end 400.471386 -4.386072)
		(stroke
			(width 0.05715)
			(type default)
		)
		(layer "F.Cu")
	)
	(gr_line
		(start 400.56816 -121.179082)
		(end 400.790156 -121.043954)
		(stroke
			(width 0.04445)
			(type default)
		)
		(layer "F.Cu")
	)
	(gr_line
		(start 400.649948 -120.126252)
		(end 400.732244 -120.043956)
		(stroke
			(width 0.04445)
			(type default)
		)
		(layer "F.Cu")
	)
	(gr_line
		(start 400.732244 -120.043956)
		(end 401.009104 -120.043956)
		(stroke
			(width 0.04445)
			(type default)
		)
		(layer "F.Cu")
	)
	(gr_line
		(start 400.7358 -119.6848)
		(end 401.0152 -119.6848)
		(stroke
			(width 0.04445)
			(type default)
		)
		(layer "F.Cu")
	)
	(gr_line
		(start 400.790156 -121.043954)
		(end 401.002246 -121.043954)
		(stroke
			(width 0.04445)
			(type default)
		)
		(layer "F.Cu")
	)
	(gr_line
		(start 400.880072 -121.355104)
		(end 400.927316 -121.30786)
		(stroke
			(width 0.04445)
			(type default)
		)
		(layer "F.Cu")
	)
	(gr_line
		(start 400.880072 -120.355106)
		(end 400.898868 -120.33631)
		(stroke
			(width 0.04445)
			(type default)
		)
		(layer "F.Cu")
	)
	(gr_line
		(start 400.880072 -119.355108)
		(end 400.961352 -119.355108)
		(stroke
			(width 0.04445)
			(type default)
		)
		(layer "F.Cu")
	)
	(gr_line
		(start 400.898868 -120.33631)
		(end 400.917918 -120.33631)
		(stroke
			(width 0.04445)
			(type default)
		)
		(layer "F.Cu")
	)
	(gr_line
		(start 400.927316 -121.30786)
		(end 400.98853 -121.30786)
		(stroke
			(width 0.04445)
			(type default)
		)
		(layer "F.Cu")
	)
	(gr_line
		(start 400.962622 -11.6078)
		(end 400.995642 -11.567668)
		(stroke
			(width 0.05715)
			(type default)
		)
		(layer "F.Cu")
	)
	(gr_line
		(start 400.99107 -121.30786)
		(end 401.053046 -121.30786)
		(stroke
			(width 0.04445)
			(type default)
		)
		(layer "F.Cu")
	)
	(gr_line
		(start 401.002246 -121.043954)
		(end 401.134072 -121.1326)
		(stroke
			(width 0.04445)
			(type default)
		)
		(layer "F.Cu")
	)
	(gr_line
		(start 401.009104 -120.043956)
		(end 401.108418 -120.14327)
		(stroke
			(width 0.04445)
			(type default)
		)
		(layer "F.Cu")
	)
	(gr_line
		(start 401.0152 -119.6848)
		(end 401.151852 -119.548148)
		(stroke
			(width 0.04445)
			(type default)
		)
		(layer "F.Cu")
	)
	(gr_line
		(start 401.0406 -120.66016)
		(end 401.131532 -120.569228)
		(stroke
			(width 0.04445)
			(type default)
		)
		(layer "F.Cu")
	)
	(gr_line
		(start 401.043902 -8.824976)
		(end 401.271486 -8.597392)
		(stroke
			(width 0.05715)
			(type default)
		)
		(layer "F.Cu")
	)
	(gr_line
		(start 401.047458 -11.18997)
		(end 401.319492 -10.917936)
		(stroke
			(width 0.05715)
			(type default)
		)
		(layer "F.Cu")
	)
	(gr_line
		(start 401.047458 -9.756902)
		(end 401.319492 -10.028936)
		(stroke
			(width 0.05715)
			(type default)
		)
		(layer "F.Cu")
	)
	(gr_line
		(start 401.101052 -121.340118)
		(end 401.123404 -121.355104)
		(stroke
			(width 0.04445)
			(type default)
		)
		(layer "F.Cu")
	)
	(gr_line
		(start 401.131532 -120.569228)
		(end 401.197318 -120.569228)
		(stroke
			(width 0.04445)
			(type default)
		)
		(layer "F.Cu")
	)
	(gr_line
		(start 401.18157 -121.164604)
		(end 401.243546 -121.164604)
		(stroke
			(width 0.04445)
			(type default)
		)
		(layer "F.Cu")
	)
	(gr_line
		(start 401.271486 -7.789672)
		(end 401.271486 -8.597392)
		(stroke
			(width 0.05715)
			(type default)
		)
		(layer "F.Cu")
	)
	(gr_line
		(start 401.295108 -120.854978)
		(end 401.387818 -120.762268)
		(stroke
			(width 0.04445)
			(type default)
		)
		(layer "F.Cu")
	)
	(gr_arc
		(start 401.447254 -132.920994)
		(mid 401.783197 -132.854189)
		(end 402.06803 -132.663946)
		(stroke
			(width 0.05715)
			(type default)
		)
		(layer "F.Cu")
	)
	(gr_arc
		(start 401.447254 -132.679694)
		(mid 401.690834 -132.631228)
		(end 401.897342 -132.493258)
		(stroke
			(width 0.05715)
			(type default)
		)
		(layer "F.Cu")
	)
	(gr_line
		(start 401.827492 -2.88417)
		(end 402.192744 -2.88417)
		(stroke
			(width 0.05715)
			(type default)
		)
		(layer "F.Cu")
	)
	(gr_line
		(start 401.964144 -121.814844)
		(end 402.050504 -121.901204)
		(stroke
			(width 0.04445)
			(type default)
		)
		(layer "F.Cu")
	)
	(gr_line
		(start 402.00834 -12.162536)
		(end 402.023072 -12.152884)
		(stroke
			(width 0.05715)
			(type default)
		)
		(layer "F.Cu")
	)
	(gr_line
		(start 402.023072 -12.152884)
		(end 402.039582 -12.15009)
		(stroke
			(width 0.05715)
			(type default)
		)
		(layer "F.Cu")
	)
	(gr_line
		(start 402.050504 -121.901204)
		(end 402.317204 -121.901204)
		(stroke
			(width 0.04445)
			(type default)
		)
		(layer "F.Cu")
	)
	(gr_line
		(start 402.071586 -3.758184)
		(end 402.071586 -4.386072)
		(stroke
			(width 0.05715)
			(type default)
		)
		(layer "F.Cu")
	)
	(gr_line
		(start 402.071586 -3.758184)
		(end 402.29917 -3.5306)
		(stroke
			(width 0.05715)
			(type default)
		)
		(layer "F.Cu")
	)
	(gr_line
		(start 402.154644 -121.621804)
		(end 402.213064 -121.621804)
		(stroke
			(width 0.04445)
			(type default)
		)
		(layer "F.Cu")
	)
	(gr_line
		(start 402.192744 -2.88417)
		(end 402.310092 -3.001518)
		(stroke
			(width 0.05715)
			(type default)
		)
		(layer "F.Cu")
	)
	(gr_line
		(start 402.298662 -121.26722)
		(end 402.385022 -121.35358)
		(stroke
			(width 0.04445)
			(type default)
		)
		(layer "F.Cu")
	)
	(gr_line
		(start 402.317204 -121.901204)
		(end 402.403564 -121.814844)
		(stroke
			(width 0.04445)
			(type default)
		)
		(layer "F.Cu")
	)
	(gr_line
		(start 402.319236 -13.127736)
		(end 402.330412 -13.12037)
		(stroke
			(width 0.05715)
			(type default)
		)
		(layer "F.Cu")
	)
	(gr_line
		(start 402.330412 -13.12037)
		(end 402.344128 -13.117576)
		(stroke
			(width 0.05715)
			(type default)
		)
		(layer "F.Cu")
	)
	(gr_line
		(start 402.385022 -121.35358)
		(end 402.651722 -121.35358)
		(stroke
			(width 0.04445)
			(type default)
		)
		(layer "F.Cu")
	)
	(gr_line
		(start 402.476208 -30.247844)
		(end 402.587968 -30.359604)
		(stroke
			(width 0.05715)
			(type default)
		)
		(layer "F.Cu")
	)
	(gr_line
		(start 402.489162 -121.07418)
		(end 402.547582 -121.07418)
		(stroke
			(width 0.04445)
			(type default)
		)
		(layer "F.Cu")
	)
	(gr_line
		(start 402.561298 -120.73763)
		(end 402.647658 -120.82399)
		(stroke
			(width 0.04445)
			(type default)
		)
		(layer "F.Cu")
	)
	(gr_line
		(start 402.587968 -30.359604)
		(end 402.930868 -30.359604)
		(stroke
			(width 0.05715)
			(type default)
		)
		(layer "F.Cu")
	)
	(gr_line
		(start 402.606256 -14.099286)
		(end 402.617432 -14.09192)
		(stroke
			(width 0.05715)
			(type default)
		)
		(layer "F.Cu")
	)
	(gr_line
		(start 402.617432 -14.09192)
		(end 402.631148 -14.089126)
		(stroke
			(width 0.05715)
			(type default)
		)
		(layer "F.Cu")
	)
	(gr_line
		(start 402.644102 -3.5306)
		(end 402.871686 -3.758184)
		(stroke
			(width 0.05715)
			(type default)
		)
		(layer "F.Cu")
	)
	(gr_line
		(start 402.647658 -120.82399)
		(end 402.914358 -120.82399)
		(stroke
			(width 0.04445)
			(type default)
		)
		(layer "F.Cu")
	)
	(gr_line
		(start 402.651722 -121.35358)
		(end 402.738082 -121.26722)
		(stroke
			(width 0.04445)
			(type default)
		)
		(layer "F.Cu")
	)
	(gr_line
		(start 402.655024 -3.001518)
		(end 402.772372 -2.88417)
		(stroke
			(width 0.05715)
			(type default)
		)
		(layer "F.Cu")
	)
	(gr_line
		(start 402.675344 -121.814844)
		(end 402.761704 -121.901204)
		(stroke
			(width 0.04445)
			(type default)
		)
		(layer "F.Cu")
	)
	(gr_line
		(start 402.717508 -30.004004)
		(end 402.801328 -30.004004)
		(stroke
			(width 0.05715)
			(type default)
		)
		(layer "F.Cu")
	)
	(gr_line
		(start 402.751798 -120.54459)
		(end 402.810218 -120.54459)
		(stroke
			(width 0.04445)
			(type default)
		)
		(layer "F.Cu")
	)
	(gr_line
		(start 402.761704 -121.901204)
		(end 403.028404 -121.901204)
		(stroke
			(width 0.04445)
			(type default)
		)
		(layer "F.Cu")
	)
	(gr_line
		(start 402.772372 -2.88417)
		(end 403.097492 -2.88417)
		(stroke
			(width 0.05715)
			(type default)
		)
		(layer "F.Cu")
	)
	(gr_line
		(start 402.81606 -12.264136)
		(end 402.877528 -12.253722)
		(stroke
			(width 0.05715)
			(type default)
		)
		(layer "F.Cu")
	)
	(gr_line
		(start 402.830792 -10.917936)
		(end 403.102826 -11.18997)
		(stroke
			(width 0.05715)
			(type default)
		)
		(layer "F.Cu")
	)
	(gr_line
		(start 402.830792 -10.028936)
		(end 403.102826 -9.756902)
		(stroke
			(width 0.05715)
			(type default)
		)
		(layer "F.Cu")
	)
	(gr_line
		(start 402.865844 -121.621804)
		(end 402.924264 -121.621804)
		(stroke
			(width 0.04445)
			(type default)
		)
		(layer "F.Cu")
	)
	(gr_line
		(start 402.871686 -8.597392)
		(end 403.09927 -8.824976)
		(stroke
			(width 0.05715)
			(type default)
		)
		(layer "F.Cu")
	)
	(gr_line
		(start 402.871686 -7.789672)
		(end 402.871686 -8.597392)
		(stroke
			(width 0.05715)
			(type default)
		)
		(layer "F.Cu")
	)
	(gr_line
		(start 402.871686 -3.758184)
		(end 402.871686 -4.386072)
		(stroke
			(width 0.05715)
			(type default)
		)
		(layer "F.Cu")
	)
	(gr_line
		(start 402.877528 -12.253722)
		(end 402.914866 -12.203938)
		(stroke
			(width 0.05715)
			(type default)
		)
		(layer "F.Cu")
	)
	(gr_line
		(start 402.88337 -15.110206)
		(end 402.894546 -15.10284)
		(stroke
			(width 0.05715)
			(type default)
		)
		(layer "F.Cu")
	)
	(gr_line
		(start 402.894546 -15.10284)
		(end 402.908262 -15.100046)
		(stroke
			(width 0.05715)
			(type default)
		)
		(layer "F.Cu")
	)
	(gr_line
		(start 402.914358 -120.82399)
		(end 403.000718 -120.73763)
		(stroke
			(width 0.04445)
			(type default)
		)
		(layer "F.Cu")
	)
	(gr_line
		(start 402.930868 -30.359604)
		(end 403.042628 -30.247844)
		(stroke
			(width 0.05715)
			(type default)
		)
		(layer "F.Cu")
	)
	(gr_line
		(start 402.975064 -119.352568)
		(end 403.061424 -119.266208)
		(stroke
			(width 0.04445)
			(type default)
		)
		(layer "F.Cu")
	)
	(gr_line
		(start 403.009862 -121.26722)
		(end 403.096222 -121.35358)
		(stroke
			(width 0.04445)
			(type default)
		)
		(layer "F.Cu")
	)
	(gr_line
		(start 403.028404 -121.901204)
		(end 403.114764 -121.814844)
		(stroke
			(width 0.04445)
			(type default)
		)
		(layer "F.Cu")
	)
	(gr_line
		(start 403.061424 -119.266208)
		(end 403.328124 -119.266208)
		(stroke
			(width 0.04445)
			(type default)
		)
		(layer "F.Cu")
	)
	(gr_line
		(start 403.096222 -121.35358)
		(end 403.362922 -121.35358)
		(stroke
			(width 0.04445)
			(type default)
		)
		(layer "F.Cu")
	)
	(gr_line
		(start 403.165564 -119.545608)
		(end 403.223984 -119.545608)
		(stroke
			(width 0.04445)
			(type default)
		)
		(layer "F.Cu")
	)
	(gr_line
		(start 403.200362 -121.07418)
		(end 403.258782 -121.07418)
		(stroke
			(width 0.04445)
			(type default)
		)
		(layer "F.Cu")
	)
	(gr_line
		(start 403.272498 -120.73763)
		(end 403.358858 -120.82399)
		(stroke
			(width 0.04445)
			(type default)
		)
		(layer "F.Cu")
	)
	(gr_line
		(start 403.328124 -119.266208)
		(end 403.414484 -119.352568)
		(stroke
			(width 0.04445)
			(type default)
		)
		(layer "F.Cu")
	)
	(gr_line
		(start 403.358858 -120.82399)
		(end 403.625558 -120.82399)
		(stroke
			(width 0.04445)
			(type default)
		)
		(layer "F.Cu")
	)
	(gr_line
		(start 403.362922 -121.35358)
		(end 403.449282 -121.26722)
		(stroke
			(width 0.04445)
			(type default)
		)
		(layer "F.Cu")
	)
	(gr_line
		(start 403.36851 -11.598148)
		(end 403.395942 -11.561318)
		(stroke
			(width 0.05715)
			(type default)
		)
		(layer "F.Cu")
	)
	(gr_line
		(start 403.386544 -121.814844)
		(end 403.472904 -121.901204)
		(stroke
			(width 0.04445)
			(type default)
		)
		(layer "F.Cu")
	)
	(gr_line
		(start 403.390608 -30.247844)
		(end 403.502368 -30.359604)
		(stroke
			(width 0.05715)
			(type default)
		)
		(layer "F.Cu")
	)
	(gr_line
		(start 403.444202 -8.824976)
		(end 403.671786 -8.597392)
		(stroke
			(width 0.05715)
			(type default)
		)
		(layer "F.Cu")
	)
	(gr_line
		(start 403.447758 -11.18997)
		(end 403.719792 -10.917936)
		(stroke
			(width 0.05715)
			(type default)
		)
		(layer "F.Cu")
	)
	(gr_line
		(start 403.447758 -9.756902)
		(end 403.719792 -10.028936)
		(stroke
			(width 0.05715)
			(type default)
		)
		(layer "F.Cu")
	)
	(gr_line
		(start 403.462998 -120.54459)
		(end 403.521418 -120.54459)
		(stroke
			(width 0.04445)
			(type default)
		)
		(layer "F.Cu")
	)
	(gr_line
		(start 403.472904 -121.901204)
		(end 403.739604 -121.901204)
		(stroke
			(width 0.04445)
			(type default)
		)
		(layer "F.Cu")
	)
	(gr_line
		(start 403.502368 -30.359604)
		(end 403.845268 -30.359604)
		(stroke
			(width 0.05715)
			(type default)
		)
		(layer "F.Cu")
	)
	(gr_line
		(start 403.577044 -121.621804)
		(end 403.635464 -121.621804)
		(stroke
			(width 0.04445)
			(type default)
		)
		(layer "F.Cu")
	)
	(gr_line
		(start 403.625558 -120.82399)
		(end 403.711918 -120.73763)
		(stroke
			(width 0.04445)
			(type default)
		)
		(layer "F.Cu")
	)
	(gr_line
		(start 403.631908 -30.004004)
		(end 403.715728 -30.004004)
		(stroke
			(width 0.05715)
			(type default)
		)
		(layer "F.Cu")
	)
	(gr_line
		(start 403.671786 -7.789672)
		(end 403.671786 -8.597392)
		(stroke
			(width 0.05715)
			(type default)
		)
		(layer "F.Cu")
	)
	(gr_line
		(start 403.67458 -12.849098)
		(end 403.76221 -12.717526)
		(stroke
			(width 0.05715)
			(type default)
		)
		(layer "F.Cu")
	)
	(gr_line
		(start 403.686264 -119.352568)
		(end 403.772624 -119.266208)
		(stroke
			(width 0.04445)
			(type default)
		)
		(layer "F.Cu")
	)
	(gr_line
		(start 403.721062 -121.26722)
		(end 403.807422 -121.35358)
		(stroke
			(width 0.04445)
			(type default)
		)
		(layer "F.Cu")
	)
	(gr_line
		(start 403.739604 -121.901204)
		(end 403.825964 -121.814844)
		(stroke
			(width 0.04445)
			(type default)
		)
		(layer "F.Cu")
	)
	(gr_line
		(start 403.754844 -13.081762)
		(end 404.245318 -12.983718)
		(stroke
			(width 0.05715)
			(type default)
		)
		(layer "F.Cu")
	)
	(gr_line
		(start 403.76221 -12.717526)
		(end 404.098506 -12.65047)
		(stroke
			(width 0.05715)
			(type default)
		)
		(layer "F.Cu")
	)
	(gr_line
		(start 403.772624 -119.266208)
		(end 404.039324 -119.266208)
		(stroke
			(width 0.04445)
			(type default)
		)
		(layer "F.Cu")
	)
	(gr_line
		(start 403.807422 -121.35358)
		(end 404.074122 -121.35358)
		(stroke
			(width 0.04445)
			(type default)
		)
		(layer "F.Cu")
	)
	(gr_line
		(start 403.845268 -30.359604)
		(end 403.957028 -30.247844)
		(stroke
			(width 0.05715)
			(type default)
		)
		(layer "F.Cu")
	)
	(gr_line
		(start 403.876764 -119.545608)
		(end 403.935184 -119.545608)
		(stroke
			(width 0.04445)
			(type default)
		)
		(layer "F.Cu")
	)
	(gr_line
		(start 403.911562 -121.07418)
		(end 403.969982 -121.07418)
		(stroke
			(width 0.04445)
			(type default)
		)
		(layer "F.Cu")
	)
	(gr_line
		(start 404.00732 -119.98198)
		(end 404.20036 -120.17502)
		(stroke
			(width 0.04445)
			(type default)
		)
		(layer "F.Cu")
	)
	(gr_line
		(start 404.039324 -119.266208)
		(end 404.125684 -119.352568)
		(stroke
			(width 0.04445)
			(type default)
		)
		(layer "F.Cu")
	)
	(gr_line
		(start 404.074122 -121.35358)
		(end 404.160482 -121.26722)
		(stroke
			(width 0.04445)
			(type default)
		)
		(layer "F.Cu")
	)
	(gr_line
		(start 404.097744 -121.814844)
		(end 404.184104 -121.901204)
		(stroke
			(width 0.04445)
			(type default)
		)
		(layer "F.Cu")
	)
	(gr_line
		(start 404.098506 -12.65047)
		(end 404.229824 -12.7381)
		(stroke
			(width 0.05715)
			(type default)
		)
		(layer "F.Cu")
	)
	(gr_line
		(start 404.184104 -121.901204)
		(end 404.450804 -121.901204)
		(stroke
			(width 0.04445)
			(type default)
		)
		(layer "F.Cu")
	)
	(gr_line
		(start 404.288244 -121.621804)
		(end 404.346664 -121.621804)
		(stroke
			(width 0.04445)
			(type default)
		)
		(layer "F.Cu")
	)
	(gr_line
		(start 404.305008 -30.247844)
		(end 404.416768 -30.359604)
		(stroke
			(width 0.05715)
			(type default)
		)
		(layer "F.Cu")
	)
	(gr_line
		(start 404.329392 -2.897124)
		(end 404.5966 -2.897124)
		(stroke
			(width 0.05715)
			(type default)
		)
		(layer "F.Cu")
	)
	(gr_line
		(start 404.3934 -120.0912)
		(end 404.50262 -119.98198)
		(stroke
			(width 0.04445)
			(type default)
		)
		(layer "F.Cu")
	)
	(gr_line
		(start 404.397464 -119.352568)
		(end 404.483824 -119.266208)
		(stroke
			(width 0.04445)
			(type default)
		)
		(layer "F.Cu")
	)
	(gr_line
		(start 404.416768 -30.359604)
		(end 404.759668 -30.359604)
		(stroke
			(width 0.05715)
			(type default)
		)
		(layer "F.Cu")
	)
	(gr_line
		(start 404.432262 -121.26722)
		(end 404.518622 -121.35358)
		(stroke
			(width 0.04445)
			(type default)
		)
		(layer "F.Cu")
	)
	(gr_line
		(start 404.450804 -121.901204)
		(end 404.537164 -121.814844)
		(stroke
			(width 0.04445)
			(type default)
		)
		(layer "F.Cu")
	)
	(gr_line
		(start 404.471886 -3.758184)
		(end 404.471886 -4.386072)
		(stroke
			(width 0.05715)
			(type default)
		)
		(layer "F.Cu")
	)
	(gr_line
		(start 404.471886 -3.758184)
		(end 404.69947 -3.5306)
		(stroke
			(width 0.05715)
			(type default)
		)
		(layer "F.Cu")
	)
	(gr_line
		(start 404.483824 -119.266208)
		(end 404.750524 -119.266208)
		(stroke
			(width 0.04445)
			(type default)
		)
		(layer "F.Cu")
	)
	(gr_line
		(start 404.50262 -119.98198)
		(end 404.94712 -119.98198)
		(stroke
			(width 0.04445)
			(type default)
		)
		(layer "F.Cu")
	)
	(gr_line
		(start 404.518622 -121.35358)
		(end 404.785322 -121.35358)
		(stroke
			(width 0.04445)
			(type default)
		)
		(layer "F.Cu")
	)
	(gr_line
		(start 404.546308 -30.004004)
		(end 404.630128 -30.004004)
		(stroke
			(width 0.05715)
			(type default)
		)
		(layer "F.Cu")
	)
	(gr_line
		(start 404.587964 -119.545608)
		(end 404.646384 -119.545608)
		(stroke
			(width 0.04445)
			(type default)
		)
		(layer "F.Cu")
	)
	(gr_line
		(start 404.5966 -2.897124)
		(end 404.665434 -2.965958)
		(stroke
			(width 0.05715)
			(type default)
		)
		(layer "F.Cu")
	)
	(gr_line
		(start 404.622762 -121.07418)
		(end 404.681182 -121.07418)
		(stroke
			(width 0.04445)
			(type default)
		)
		(layer "F.Cu")
	)
	(gr_line
		(start 404.700994 -12.892532)
		(end 404.734014 -12.8524)
		(stroke
			(width 0.05715)
			(type default)
		)
		(layer "F.Cu")
	)
	(gr_line
		(start 404.750524 -119.266208)
		(end 404.836884 -119.352568)
		(stroke
			(width 0.04445)
			(type default)
		)
		(layer "F.Cu")
	)
	(gr_line
		(start 404.759668 -30.359604)
		(end 404.871428 -30.247844)
		(stroke
			(width 0.05715)
			(type default)
		)
		(layer "F.Cu")
	)
	(gr_line
		(start 404.785322 -121.35358)
		(end 404.871682 -121.26722)
		(stroke
			(width 0.04445)
			(type default)
		)
		(layer "F.Cu")
	)
	(gr_line
		(start 404.988522 -13.864082)
		(end 405.000968 -13.861796)
		(stroke
			(width 0.05715)
			(type default)
		)
		(layer "F.Cu")
	)
	(gr_line
		(start 405.000968 -13.861796)
		(end 405.012144 -13.85443)
		(stroke
			(width 0.05715)
			(type default)
		)
		(layer "F.Cu")
	)
	(gr_arc
		(start 405.007064 -130.04165)
		(mid 404.71441 -130.099902)
		(end 404.466298 -130.265678)
		(stroke
			(width 0.05715)
			(type default)
		)
		(layer "F.Cu")
	)
	(gr_arc
		(start 405.007064 -129.80035)
		(mid 404.622034 -129.876919)
		(end 404.29561 -130.09499)
		(stroke
			(width 0.05715)
			(type default)
		)
		(layer "F.Cu")
	)
	(gr_line
		(start 405.010366 -2.965958)
		(end 405.0792 -2.897124)
		(stroke
			(width 0.05715)
			(type default)
		)
		(layer "F.Cu")
	)
	(gr_line
		(start 405.023574 -122.055382)
		(end 405.212042 -122.24385)
		(stroke
			(width 0.04445)
			(type default)
		)
		(layer "F.Cu")
	)
	(gr_line
		(start 405.023574 -121.933208)
		(end 405.023574 -122.055382)
		(stroke
			(width 0.04445)
			(type default)
		)
		(layer "F.Cu")
	)
	(gr_line
		(start 405.044402 -3.5306)
		(end 405.271986 -3.758184)
		(stroke
			(width 0.05715)
			(type default)
		)
		(layer "F.Cu")
	)
	(gr_line
		(start 405.0792 -2.897124)
		(end 405.345392 -2.897124)
		(stroke
			(width 0.05715)
			(type default)
		)
		(layer "F.Cu")
	)
	(gr_line
		(start 405.108664 -119.352568)
		(end 405.195024 -119.266208)
		(stroke
			(width 0.04445)
			(type default)
		)
		(layer "F.Cu")
	)
	(gr_line
		(start 405.195024 -119.266208)
		(end 405.461724 -119.266208)
		(stroke
			(width 0.04445)
			(type default)
		)
		(layer "F.Cu")
	)
	(gr_line
		(start 405.212042 -122.24385)
		(end 405.334216 -122.24385)
		(stroke
			(width 0.04445)
			(type default)
		)
		(layer "F.Cu")
	)
	(gr_line
		(start 405.219408 -30.247844)
		(end 405.331168 -30.359604)
		(stroke
			(width 0.05715)
			(type default)
		)
		(layer "F.Cu")
	)
	(gr_line
		(start 405.231092 -10.917936)
		(end 405.503126 -11.18997)
		(stroke
			(width 0.05715)
			(type default)
		)
		(layer "F.Cu")
	)
	(gr_line
		(start 405.231092 -10.028936)
		(end 405.503126 -9.756902)
		(stroke
			(width 0.05715)
			(type default)
		)
		(layer "F.Cu")
	)
	(gr_line
		(start 405.258778 -14.87678)
		(end 405.27351 -14.873732)
		(stroke
			(width 0.05715)
			(type default)
		)
		(layer "F.Cu")
	)
	(gr_line
		(start 405.271986 -8.597392)
		(end 405.49957 -8.824976)
		(stroke
			(width 0.05715)
			(type default)
		)
		(layer "F.Cu")
	)
	(gr_line
		(start 405.271986 -7.789672)
		(end 405.271986 -8.597392)
		(stroke
			(width 0.05715)
			(type default)
		)
		(layer "F.Cu")
	)
	(gr_line
		(start 405.271986 -3.758184)
		(end 405.271986 -4.386072)
		(stroke
			(width 0.05715)
			(type default)
		)
		(layer "F.Cu")
	)
	(gr_line
		(start 405.27351 -14.873732)
		(end 405.28621 -14.86535)
		(stroke
			(width 0.05715)
			(type default)
		)
		(layer "F.Cu")
	)
	(gr_line
		(start 405.294846 -121.93143)
		(end 405.335994 -121.972578)
		(stroke
			(width 0.04445)
			(type default)
		)
		(layer "F.Cu")
	)
	(gr_line
		(start 405.299164 -119.545608)
		(end 405.357584 -119.545608)
		(stroke
			(width 0.04445)
			(type default)
		)
		(layer "F.Cu")
	)
	(gr_line
		(start 405.331168 -30.359604)
		(end 405.674068 -30.359604)
		(stroke
			(width 0.05715)
			(type default)
		)
		(layer "F.Cu")
	)
	(gr_line
		(start 405.342598 -120.80494)
		(end 405.384 -120.763538)
		(stroke
			(width 0.04445)
			(type default)
		)
		(layer "F.Cu")
	)
	(gr_line
		(start 405.344376 -121.076212)
		(end 405.46655 -121.076212)
		(stroke
			(width 0.04445)
			(type default)
		)
		(layer "F.Cu")
	)
	(gr_line
		(start 405.460708 -30.004004)
		(end 405.544528 -30.004004)
		(stroke
			(width 0.05715)
			(type default)
		)
		(layer "F.Cu")
	)
	(gr_line
		(start 405.461724 -119.266208)
		(end 405.548084 -119.352568)
		(stroke
			(width 0.04445)
			(type default)
		)
		(layer "F.Cu")
	)
	(gr_line
		(start 405.46655 -121.076212)
		(end 405.655272 -120.88749)
		(stroke
			(width 0.04445)
			(type default)
		)
		(layer "F.Cu")
	)
	(gr_line
		(start 405.655272 -120.765316)
		(end 405.655272 -120.88749)
		(stroke
			(width 0.04445)
			(type default)
		)
		(layer "F.Cu")
	)
	(gr_line
		(start 405.674068 -30.359604)
		(end 405.785828 -30.247844)
		(stroke
			(width 0.05715)
			(type default)
		)
		(layer "F.Cu")
	)
	(gr_line
		(start 405.73198 -122.3899)
		(end 405.81834 -122.47626)
		(stroke
			(width 0.04445)
			(type default)
		)
		(layer "F.Cu")
	)
	(gr_line
		(start 405.763222 -11.607292)
		(end 405.796242 -11.567668)
		(stroke
			(width 0.05715)
			(type default)
		)
		(layer "F.Cu")
	)
	(gr_line
		(start 405.81834 -122.47626)
		(end 406.08504 -122.47626)
		(stroke
			(width 0.04445)
			(type default)
		)
		(layer "F.Cu")
	)
	(gr_line
		(start 405.819864 -119.352568)
		(end 405.906224 -119.266208)
		(stroke
			(width 0.04445)
			(type default)
		)
		(layer "F.Cu")
	)
	(gr_line
		(start 405.844502 -8.824976)
		(end 406.072086 -8.597392)
		(stroke
			(width 0.05715)
			(type default)
		)
		(layer "F.Cu")
	)
	(gr_line
		(start 405.848058 -11.18997)
		(end 406.120092 -10.917936)
		(stroke
			(width 0.05715)
			(type default)
		)
		(layer "F.Cu")
	)
	(gr_line
		(start 405.848058 -9.756902)
		(end 406.120092 -10.028936)
		(stroke
			(width 0.05715)
			(type default)
		)
		(layer "F.Cu")
	)
	(gr_line
		(start 405.906224 -119.266208)
		(end 406.172924 -119.266208)
		(stroke
			(width 0.04445)
			(type default)
		)
		(layer "F.Cu")
	)
	(gr_line
		(start 405.92248 -122.19686)
		(end 405.9809 -122.19686)
		(stroke
			(width 0.04445)
			(type default)
		)
		(layer "F.Cu")
	)
	(gr_line
		(start 406.004268 -120.54332)
		(end 406.090628 -120.62968)
		(stroke
			(width 0.04445)
			(type default)
		)
		(layer "F.Cu")
	)
	(gr_line
		(start 406.010364 -119.545608)
		(end 406.068784 -119.545608)
		(stroke
			(width 0.04445)
			(type default)
		)
		(layer "F.Cu")
	)
	(gr_line
		(start 406.072086 -7.789672)
		(end 406.072086 -8.597392)
		(stroke
			(width 0.05715)
			(type default)
		)
		(layer "F.Cu")
	)
	(gr_line
		(start 406.08504 -122.47626)
		(end 406.1714 -122.3899)
		(stroke
			(width 0.04445)
			(type default)
		)
		(layer "F.Cu")
	)
	(gr_line
		(start 406.090628 -120.994932)
		(end 406.179528 -121.083832)
		(stroke
			(width 0.04445)
			(type default)
		)
		(layer "F.Cu")
	)
	(gr_line
		(start 406.090628 -120.62968)
		(end 406.090628 -120.994932)
		(stroke
			(width 0.04445)
			(type default)
		)
		(layer "F.Cu")
	)
	(gr_line
		(start 406.131268 -30.245304)
		(end 406.189942 -30.245304)
		(stroke
			(width 0.05715)
			(type default)
		)
		(layer "F.Cu")
	)
	(gr_line
		(start 406.172924 -119.266208)
		(end 406.259284 -119.352568)
		(stroke
			(width 0.04445)
			(type default)
		)
		(layer "F.Cu")
	)
	(gr_line
		(start 406.179528 -121.083832)
		(end 406.516078 -121.083832)
		(stroke
			(width 0.04445)
			(type default)
		)
		(layer "F.Cu")
	)
	(gr_line
		(start 406.194768 -120.35028)
		(end 406.43683 -120.35028)
		(stroke
			(width 0.04445)
			(type default)
		)
		(layer "F.Cu")
	)
	(gr_line
		(start 406.209246 -12.763246)
		(end 406.240488 -12.607798)
		(stroke
			(width 0.05715)
			(type default)
		)
		(layer "F.Cu")
	)
	(gr_line
		(start 406.237186 -31.718504)
		(end 406.242774 -31.718504)
		(stroke
			(width 0.05715)
			(type default)
		)
		(layer "F.Cu")
	)
	(gr_line
		(start 406.240488 -12.607798)
		(end 406.52573 -12.417552)
		(stroke
			(width 0.05715)
			(type default)
		)
		(layer "F.Cu")
	)
	(gr_line
		(start 406.370028 -30.084014)
		(end 406.428702 -30.084014)
		(stroke
			(width 0.05715)
			(type default)
		)
		(layer "F.Cu")
	)
	(gr_line
		(start 406.370536 -12.94892)
		(end 406.425908 -12.911836)
		(stroke
			(width 0.05715)
			(type default)
		)
		(layer "F.Cu")
	)
	(gr_line
		(start 406.425908 -12.911582)
		(end 406.425908 -12.911836)
		(stroke
			(width 0.05715)
			(type default)
		)
		(layer "F.Cu")
	)
	(gr_line
		(start 406.425908 -12.911582)
		(end 406.790652 -12.668504)
		(stroke
			(width 0.05715)
			(type default)
		)
		(layer "F.Cu")
	)
	(gr_line
		(start 406.43683 -120.35028)
		(end 406.516078 -120.271032)
		(stroke
			(width 0.04445)
			(type default)
		)
		(layer "F.Cu")
	)
	(gr_line
		(start 406.44318 -122.3899)
		(end 406.52954 -122.47626)
		(stroke
			(width 0.04445)
			(type default)
		)
		(layer "F.Cu")
	)
	(gr_line
		(start 406.475946 -31.6103)
		(end 406.481534 -31.6103)
		(stroke
			(width 0.05715)
			(type default)
		)
		(layer "F.Cu")
	)
	(gr_line
		(start 406.52573 -12.417552)
		(end 406.681178 -12.44854)
		(stroke
			(width 0.05715)
			(type default)
		)
		(layer "F.Cu")
	)
	(gr_line
		(start 406.52954 -122.47626)
		(end 406.79624 -122.47626)
		(stroke
			(width 0.04445)
			(type default)
		)
		(layer "F.Cu")
	)
	(gr_line
		(start 406.531064 -119.352568)
		(end 406.617424 -119.266208)
		(stroke
			(width 0.04445)
			(type default)
		)
		(layer "F.Cu")
	)
	(gr_line
		(start 406.617424 -119.266208)
		(end 406.884124 -119.266208)
		(stroke
			(width 0.04445)
			(type default)
		)
		(layer "F.Cu")
	)
	(gr_line
		(start 406.628092 -2.88417)
		(end 407.028142 -2.88417)
		(stroke
			(width 0.05715)
			(type default)
		)
		(layer "F.Cu")
	)
	(gr_line
		(start 406.63368 -122.19686)
		(end 406.6921 -122.19686)
		(stroke
			(width 0.04445)
			(type default)
		)
		(layer "F.Cu")
	)
	(gr_line
		(start 406.721564 -119.545608)
		(end 406.779984 -119.545608)
		(stroke
			(width 0.04445)
			(type default)
		)
		(layer "F.Cu")
	)
	(gr_line
		(start 406.79624 -122.47626)
		(end 406.8826 -122.3899)
		(stroke
			(width 0.04445)
			(type default)
		)
		(layer "F.Cu")
	)
	(gr_line
		(start 406.862534 -31.906972)
		(end 407.090118 -32.134556)
		(stroke
			(width 0.05715)
			(type default)
		)
		(layer "F.Cu")
	)
	(gr_line
		(start 406.862534 -31.562294)
		(end 407.090118 -31.33471)
		(stroke
			(width 0.05715)
			(type default)
		)
		(layer "F.Cu")
	)
	(gr_line
		(start 406.872186 -3.758184)
		(end 406.872186 -4.386072)
		(stroke
			(width 0.05715)
			(type default)
		)
		(layer "F.Cu")
	)
	(gr_line
		(start 406.872186 -3.758184)
		(end 407.09977 -3.5306)
		(stroke
			(width 0.05715)
			(type default)
		)
		(layer "F.Cu")
	)
	(gr_line
		(start 406.883362 -30.327854)
		(end 407.090118 -30.53461)
		(stroke
			(width 0.05715)
			(type default)
		)
		(layer "F.Cu")
	)
	(gr_line
		(start 406.884124 -119.266208)
		(end 406.970484 -119.352568)
		(stroke
			(width 0.04445)
			(type default)
		)
		(layer "F.Cu")
	)
	(gr_line
		(start 406.969976 -12.255754)
		(end 407.001218 -12.100306)
		(stroke
			(width 0.05715)
			(type default)
		)
		(layer "F.Cu")
	)
	(gr_line
		(start 407.001218 -12.100306)
		(end 407.28646 -11.91006)
		(stroke
			(width 0.05715)
			(type default)
		)
		(layer "F.Cu")
	)
	(gr_line
		(start 407.028142 -2.88417)
		(end 407.090626 -2.946654)
		(stroke
			(width 0.05715)
			(type default)
		)
		(layer "F.Cu")
	)
	(gr_line
		(start 407.126948 -30.084014)
		(end 407.439622 -30.084014)
		(stroke
			(width 0.05715)
			(type default)
		)
		(layer "F.Cu")
	)
	(gr_line
		(start 407.130758 -12.441682)
		(end 407.551382 -12.161266)
		(stroke
			(width 0.05715)
			(type default)
		)
		(layer "F.Cu")
	)
	(gr_line
		(start 407.24836 -122.38736)
		(end 407.30551 -122.44451)
		(stroke
			(width 0.04445)
			(type default)
		)
		(layer "F.Cu")
	)
	(gr_line
		(start 407.28392 -122.19686)
		(end 407.30551 -122.17527)
		(stroke
			(width 0.04445)
			(type default)
		)
		(layer "F.Cu")
	)
	(gr_line
		(start 407.28646 -11.91006)
		(end 407.441908 -11.941302)
		(stroke
			(width 0.05715)
			(type default)
		)
		(layer "F.Cu")
	)
	(gr_line
		(start 407.307288 -122.446288)
		(end 407.311352 -122.450352)
		(stroke
			(width 0.04445)
			(type default)
		)
		(layer "F.Cu")
	)
	(gr_line
		(start 407.307288 -122.173492)
		(end 407.469594 -122.011186)
		(stroke
			(width 0.04445)
			(type default)
		)
		(layer "F.Cu")
	)
	(gr_line
		(start 407.311352 -122.759978)
		(end 407.37536 -122.823986)
		(stroke
			(width 0.04445)
			(type default)
		)
		(layer "F.Cu")
	)
	(gr_line
		(start 407.311352 -122.450352)
		(end 407.311352 -122.759978)
		(stroke
			(width 0.04445)
			(type default)
		)
		(layer "F.Cu")
	)
	(gr_line
		(start 407.37536 -122.823986)
		(end 407.749502 -122.823986)
		(stroke
			(width 0.04445)
			(type default)
		)
		(layer "F.Cu")
	)
	(gr_line
		(start 407.435558 -2.946654)
		(end 407.498042 -2.88417)
		(stroke
			(width 0.05715)
			(type default)
		)
		(layer "F.Cu")
	)
	(gr_line
		(start 407.439622 -30.084014)
		(end 407.890218 -30.53461)
		(stroke
			(width 0.05715)
			(type default)
		)
		(layer "F.Cu")
	)
	(gr_line
		(start 407.444702 -3.5306)
		(end 407.672286 -3.758184)
		(stroke
			(width 0.05715)
			(type default)
		)
		(layer "F.Cu")
	)
	(gr_line
		(start 407.469594 -122.011186)
		(end 407.749502 -122.011186)
		(stroke
			(width 0.04445)
			(type default)
		)
		(layer "F.Cu")
	)
	(gr_line
		(start 407.498042 -2.88417)
		(end 407.898092 -2.88417)
		(stroke
			(width 0.05715)
			(type default)
		)
		(layer "F.Cu")
	)
	(gr_line
		(start 407.631392 -10.916666)
		(end 407.903426 -11.1887)
		(stroke
			(width 0.05715)
			(type default)
		)
		(layer "F.Cu")
	)
	(gr_line
		(start 407.631392 -10.027666)
		(end 407.903426 -9.755632)
		(stroke
			(width 0.05715)
			(type default)
		)
		(layer "F.Cu")
	)
	(gr_line
		(start 407.672286 -8.597392)
		(end 407.89987 -8.824976)
		(stroke
			(width 0.05715)
			(type default)
		)
		(layer "F.Cu")
	)
	(gr_line
		(start 407.672286 -7.789672)
		(end 407.672286 -8.597392)
		(stroke
			(width 0.05715)
			(type default)
		)
		(layer "F.Cu")
	)
	(gr_line
		(start 407.672286 -3.758184)
		(end 407.672286 -4.386072)
		(stroke
			(width 0.05715)
			(type default)
		)
		(layer "F.Cu")
	)
	(gr_line
		(start 407.71826 -118.861332)
		(end 407.71826 -118.94312)
		(stroke
			(width 0.04445)
			(type default)
		)
		(layer "F.Cu")
	)
	(gr_line
		(start 407.71826 -118.37924)
		(end 407.71826 -118.858792)
		(stroke
			(width 0.04445)
			(type default)
		)
		(layer "F.Cu")
	)
	(gr_line
		(start 407.71826 -118.37924)
		(end 407.858468 -118.239032)
		(stroke
			(width 0.04445)
			(type default)
		)
		(layer "F.Cu")
	)
	(gr_line
		(start 407.725118 -12.045442)
		(end 407.726896 -12.04341)
		(stroke
			(width 0.05715)
			(type default)
		)
		(layer "F.Cu")
	)
	(gr_line
		(start 407.858468 -118.239032)
		(end 408.319478 -118.239032)
		(stroke
			(width 0.04445)
			(type default)
		)
		(layer "F.Cu")
	)
	(gr_line
		(start 407.879042 -119.051832)
		(end 407.90876 -119.051832)
		(stroke
			(width 0.04445)
			(type default)
		)
		(layer "F.Cu")
	)
	(gr_line
		(start 407.9113 -119.051832)
		(end 408.319478 -119.051832)
		(stroke
			(width 0.04445)
			(type default)
		)
		(layer "F.Cu")
	)
	(gr_line
		(start 408.159966 -11.519408)
		(end 408.197812 -11.473688)
		(stroke
			(width 0.05715)
			(type default)
		)
		(layer "F.Cu")
	)
	(gr_arc
		(start 408.182064 -130.16484)
		(mid 408.0456 -130.073653)
		(end 407.88463 -130.04165)
		(stroke
			(width 0.05715)
			(type default)
		)
		(layer "F.Cu")
	)
	(gr_line
		(start 408.18943 -11.247628)
		(end 408.520392 -10.916666)
		(stroke
			(width 0.05715)
			(type default)
		)
		(layer "F.Cu")
	)
	(gr_line
		(start 408.195018 -11.413744)
		(end 408.197812 -11.473688)
		(stroke
			(width 0.05715)
			(type default)
		)
		(layer "F.Cu")
	)
	(gr_line
		(start 408.244802 -8.824976)
		(end 408.472386 -8.597392)
		(stroke
			(width 0.05715)
			(type default)
		)
		(layer "F.Cu")
	)
	(gr_line
		(start 408.248358 -9.755632)
		(end 408.520392 -10.027666)
		(stroke
			(width 0.05715)
			(type default)
		)
		(layer "F.Cu")
	)
	(gr_arc
		(start 408.352752 -129.994152)
		(mid 408.137962 -129.850697)
		(end 407.88463 -129.80035)
		(stroke
			(width 0.05715)
			(type default)
		)
		(layer "F.Cu")
	)
	(gr_line
		(start 408.472386 -7.789672)
		(end 408.472386 -8.597392)
		(stroke
			(width 0.05715)
			(type default)
		)
		(layer "F.Cu")
	)
	(gr_line
		(start 408.638502 -122.823986)
		(end 408.872436 -122.590052)
		(stroke
			(width 0.05715)
			(type default)
		)
		(layer "F.Cu")
	)
	(gr_line
		(start 408.638502 -122.011186)
		(end 408.872436 -122.24512)
		(stroke
			(width 0.05715)
			(type default)
		)
		(layer "F.Cu")
	)
	(gr_line
		(start 408.897582 -1.37795)
		(end 409.297632 -1.37795)
		(stroke
			(width 0.05715)
			(type default)
		)
		(layer "F.Cu")
	)
	(gr_line
		(start 408.947874 -12.140946)
		(end 408.97937 -12.120118)
		(stroke
			(width 0.05715)
			(type default)
		)
		(layer "F.Cu")
	)
	(gr_line
		(start 409.208478 -119.051832)
		(end 409.442412 -118.817898)
		(stroke
			(width 0.05715)
			(type default)
		)
		(layer "F.Cu")
	)
	(gr_line
		(start 409.208478 -118.239032)
		(end 409.442412 -118.472966)
		(stroke
			(width 0.05715)
			(type default)
		)
		(layer "F.Cu")
	)
	(gr_arc
		(start 409.247086 -130.888486)
		(mid 409.3036 -130.920876)
		(end 409.368244 -130.928872)
		(stroke
			(width 0.05715)
			(type default)
		)
		(layer "F.Cu")
	)
	(gr_line
		(start 409.248864 -131.23164)
		(end 409.46959 -131.452366)
		(stroke
			(width 0.05715)
			(type default)
		)
		(layer "F.Cu")
	)
	(gr_line
		(start 409.272486 -3.758184)
		(end 409.272486 -4.386072)
		(stroke
			(width 0.05715)
			(type default)
		)
		(layer "F.Cu")
	)
	(gr_line
		(start 409.272486 -3.758184)
		(end 409.50007 -3.5306)
		(stroke
			(width 0.05715)
			(type default)
		)
		(layer "F.Cu")
	)
	(gr_line
		(start 409.297632 -1.37795)
		(end 409.360116 -1.440434)
		(stroke
			(width 0.05715)
			(type default)
		)
		(layer "F.Cu")
	)
	(gr_line
		(start 409.37307 -121.955814)
		(end 409.37307 -122.114056)
		(stroke
			(width 0.05715)
			(type default)
		)
		(layer "F.Cu")
	)
	(gr_line
		(start 409.37307 -121.955814)
		(end 409.615386 -121.713498)
		(stroke
			(width 0.05715)
			(type default)
		)
		(layer "F.Cu")
	)
	(gr_arc
		(start 409.489656 -130.969258)
		(mid 409.433021 -130.936833)
		(end 409.368244 -130.928872)
		(stroke
			(width 0.05715)
			(type default)
		)
		(layer "F.Cu")
	)
	(gr_line
		(start 409.489656 -130.969258)
		(end 409.731972 -131.211828)
		(stroke
			(width 0.05715)
			(type default)
		)
		(layer "F.Cu")
	)
	(gr_line
		(start 409.615386 -121.713498)
		(end 409.773628 -121.713498)
		(stroke
			(width 0.05715)
			(type default)
		)
		(layer "F.Cu")
	)
	(gr_line
		(start 409.705048 -1.440434)
		(end 409.767532 -1.37795)
		(stroke
			(width 0.05715)
			(type default)
		)
		(layer "F.Cu")
	)
	(gr_line
		(start 409.716224 -122.115834)
		(end 409.775406 -122.056652)
		(stroke
			(width 0.05715)
			(type default)
		)
		(layer "F.Cu")
	)
	(gr_line
		(start 409.767532 -1.37795)
		(end 410.167582 -1.37795)
		(stroke
			(width 0.05715)
			(type default)
		)
		(layer "F.Cu")
	)
	(gr_arc
		(start 409.772358 -131.332986)
		(mid 409.764357 -131.268343)
		(end 409.731972 -131.211828)
		(stroke
			(width 0.05715)
			(type default)
		)
		(layer "F.Cu")
	)
	(gr_arc
		(start 409.772358 -131.332986)
		(mid 409.780368 -131.397625)
		(end 409.812744 -131.454144)
		(stroke
			(width 0.05715)
			(type default)
		)
		(layer "F.Cu")
	)
	(gr_line
		(start 409.845002 -3.5306)
		(end 410.072586 -3.758184)
		(stroke
			(width 0.05715)
			(type default)
		)
		(layer "F.Cu")
	)
	(gr_line
		(start 409.928822 -11.436858)
		(end 410.200856 -11.708892)
		(stroke
			(width 0.05715)
			(type default)
		)
		(layer "F.Cu")
	)
	(gr_line
		(start 409.928822 -10.547858)
		(end 410.200856 -10.275824)
		(stroke
			(width 0.05715)
			(type default)
		)
		(layer "F.Cu")
	)
	(gr_line
		(start 409.956 -120.97131)
		(end 410.064204 -121.09196)
		(stroke
			(width 0.05715)
			(type default)
		)
		(layer "F.Cu")
	)
	(gr_line
		(start 409.956 -120.89638)
		(end 409.956 -120.97131)
		(stroke
			(width 0.05715)
			(type default)
		)
		(layer "F.Cu")
	)
	(gr_line
		(start 410.064204 -121.09196)
		(end 410.456634 -121.133616)
		(stroke
			(width 0.05715)
			(type default)
		)
		(layer "F.Cu")
	)
	(gr_line
		(start 410.072586 -8.597392)
		(end 410.30017 -8.824976)
		(stroke
			(width 0.05715)
			(type default)
		)
		(layer "F.Cu")
	)
	(gr_line
		(start 410.072586 -7.789672)
		(end 410.072586 -8.597392)
		(stroke
			(width 0.05715)
			(type default)
		)
		(layer "F.Cu")
	)
	(gr_line
		(start 410.072586 -3.758184)
		(end 410.072586 -4.386072)
		(stroke
			(width 0.05715)
			(type default)
		)
		(layer "F.Cu")
	)
	(gr_line
		(start 410.1973 -134.43204)
		(end 410.1973 -134.74446)
		(stroke
			(width 0.05715)
			(type default)
		)
		(layer "F.Cu")
	)
	(gr_line
		(start 410.1973 -133.28904)
		(end 410.1973 -133.60146)
		(stroke
			(width 0.05715)
			(type default)
		)
		(layer "F.Cu")
	)
	(gr_arc
		(start 410.1973 -132.62229)
		(mid 410.116062 -132.213736)
		(end 409.884626 -131.867402)
		(stroke
			(width 0.05715)
			(type default)
		)
		(layer "F.Cu")
	)
	(gr_line
		(start 410.351986 -9.56564)
		(end 410.351986 -9.60501)
		(stroke
			(width 0.05715)
			(type default)
		)
		(layer "F.Cu")
	)
	(gr_arc
		(start 410.4386 -134.1882)
		(mid 410.455692 -134.251092)
		(end 410.49575 -134.3025)
		(stroke
			(width 0.05715)
			(type default)
		)
		(layer "F.Cu")
	)
	(gr_arc
		(start 410.4386 -133.0452)
		(mid 410.455692 -133.108092)
		(end 410.49575 -133.1595)
		(stroke
			(width 0.05715)
			(type default)
		)
		(layer "F.Cu")
	)
	(gr_arc
		(start 410.4386 -132.62229)
		(mid 410.338984 -132.121396)
		(end 410.055314 -131.696714)
		(stroke
			(width 0.05715)
			(type default)
		)
		(layer "F.Cu")
	)
	(gr_line
		(start 410.456634 -121.133616)
		(end 410.5275 -121.204482)
		(stroke
			(width 0.05715)
			(type default)
		)
		(layer "F.Cu")
	)
	(gr_line
		(start 410.493972 -9.8044)
		(end 410.493972 -9.84377)
		(stroke
			(width 0.05715)
			(type default)
		)
		(layer "F.Cu")
	)
	(gr_arc
		(start 410.49575 -134.874)
		(mid 410.455676 -134.925396)
		(end 410.4386 -134.9883)
		(stroke
			(width 0.05715)
			(type default)
		)
		(layer "F.Cu")
	)
	(gr_arc
		(start 410.49575 -134.874)
		(mid 410.535804 -134.822595)
		(end 410.5529 -134.7597)
		(stroke
			(width 0.05715)
			(type default)
		)
		(layer "F.Cu")
	)
	(gr_arc
		(start 410.49575 -133.731)
		(mid 410.455676 -133.782396)
		(end 410.4386 -133.8453)
		(stroke
			(width 0.05715)
			(type default)
		)
		(layer "F.Cu")
	)
	(gr_arc
		(start 410.49575 -133.731)
		(mid 410.535804 -133.679595)
		(end 410.5529 -133.6167)
		(stroke
			(width 0.05715)
			(type default)
		)
		(layer "F.Cu")
	)
	(gr_line
		(start 410.5275 -121.204482)
		(end 410.5275 -121.438162)
		(stroke
			(width 0.05715)
			(type default)
		)
		(layer "F.Cu")
	)
	(gr_line
		(start 410.545788 -11.708892)
		(end 410.817822 -11.436858)
		(stroke
			(width 0.05715)
			(type default)
		)
		(layer "F.Cu")
	)
	(gr_line
		(start 410.545788 -10.275824)
		(end 410.817822 -10.547858)
		(stroke
			(width 0.05715)
			(type default)
		)
		(layer "F.Cu")
	)
	(gr_arc
		(start 410.5529 -134.4168)
		(mid 410.535843 -134.353886)
		(end 410.49575 -134.3025)
		(stroke
			(width 0.05715)
			(type default)
		)
		(layer "F.Cu")
	)
	(gr_line
		(start 410.5529 -134.4168)
		(end 410.5529 -134.7597)
		(stroke
			(width 0.05715)
			(type default)
		)
		(layer "F.Cu")
	)
	(gr_arc
		(start 410.5529 -133.2738)
		(mid 410.535843 -133.210886)
		(end 410.49575 -133.1595)
		(stroke
			(width 0.05715)
			(type default)
		)
		(layer "F.Cu")
	)
	(gr_line
		(start 410.5529 -133.2738)
		(end 410.5529 -133.6167)
		(stroke
			(width 0.05715)
			(type default)
		)
		(layer "F.Cu")
	)
	(gr_line
		(start 410.645102 -8.824976)
		(end 410.872686 -8.597392)
		(stroke
			(width 0.05715)
			(type default)
		)
		(layer "F.Cu")
	)
	(gr_line
		(start 410.870654 -121.43994)
		(end 410.8958 -121.414794)
		(stroke
			(width 0.05715)
			(type default)
		)
		(layer "F.Cu")
	)
	(gr_line
		(start 410.872686 -7.789672)
		(end 410.872686 -8.597392)
		(stroke
			(width 0.05715)
			(type default)
		)
		(layer "F.Cu")
	)
	(gr_line
		(start 410.8958 -120.893078)
		(end 410.8958 -121.414794)
		(stroke
			(width 0.05715)
			(type default)
		)
		(layer "F.Cu")
	)
	(gr_line
		(start 411.353 -46.975776)
		(end 411.445202 -46.883574)
		(stroke
			(width 0.05715)
			(type default)
		)
		(layer "F.Cu")
	)
	(gr_line
		(start 411.428692 -2.73177)
		(end 411.686756 -2.73177)
		(stroke
			(width 0.05715)
			(type default)
		)
		(layer "F.Cu")
	)
	(gr_line
		(start 411.672786 -3.69824)
		(end 411.672786 -4.386072)
		(stroke
			(width 0.05715)
			(type default)
		)
		(layer "F.Cu")
	)
	(gr_line
		(start 411.672786 -3.69824)
		(end 411.90037 -3.470656)
		(stroke
			(width 0.05715)
			(type default)
		)
		(layer "F.Cu")
	)
	(gr_line
		(start 411.686756 -2.73177)
		(end 411.90037 -2.945384)
		(stroke
			(width 0.05715)
			(type default)
		)
		(layer "F.Cu")
	)
	(gr_line
		(start 411.790134 -46.883574)
		(end 411.9118 -47.00524)
		(stroke
			(width 0.05715)
			(type default)
		)
		(layer "F.Cu")
	)
	(gr_line
		(start 411.9118 -47.00524)
		(end 412.050992 -47.00524)
		(stroke
			(width 0.05715)
			(type default)
		)
		(layer "F.Cu")
	)
	(gr_line
		(start 411.917134 -46.557438)
		(end 412.0896 -46.557438)
		(stroke
			(width 0.05715)
			(type default)
		)
		(layer "F.Cu")
	)
	(gr_line
		(start 412.0896 -46.557438)
		(end 412.251398 -46.39564)
		(stroke
			(width 0.05715)
			(type default)
		)
		(layer "F.Cu")
	)
	(gr_line
		(start 412.13659 -118.55069)
		(end 412.42107 -118.83517)
		(stroke
			(width 0.05715)
			(type default)
		)
		(layer "F.Cu")
	)
	(gr_line
		(start 412.13659 -118.205758)
		(end 412.432246 -117.910102)
		(stroke
			(width 0.05715)
			(type default)
		)
		(layer "F.Cu")
	)
	(gr_line
		(start 412.14929 -10.1346)
		(end 412.571946 -10.1346)
		(stroke
			(width 0.05715)
			(type default)
		)
		(layer "F.Cu")
	)
	(gr_line
		(start 412.245302 -3.470656)
		(end 412.472886 -3.69824)
		(stroke
			(width 0.05715)
			(type default)
		)
		(layer "F.Cu")
	)
	(gr_line
		(start 412.245302 -2.945384)
		(end 412.458916 -2.73177)
		(stroke
			(width 0.05715)
			(type default)
		)
		(layer "F.Cu")
	)
	(gr_line
		(start 412.251398 -46.223174)
		(end 412.251398 -46.39564)
		(stroke
			(width 0.05715)
			(type default)
		)
		(layer "F.Cu")
	)
	(gr_line
		(start 412.416498 -46.058074)
		(end 412.588964 -46.058074)
		(stroke
			(width 0.05715)
			(type default)
		)
		(layer "F.Cu")
	)
	(gr_line
		(start 412.458916 -2.73177)
		(end 412.698692 -2.73177)
		(stroke
			(width 0.05715)
			(type default)
		)
		(layer "F.Cu")
	)
	(gr_line
		(start 412.472886 -8.511032)
		(end 412.66618 -8.704326)
		(stroke
			(width 0.05715)
			(type default)
		)
		(layer "F.Cu")
	)
	(gr_line
		(start 412.472886 -7.789672)
		(end 412.472886 -8.511032)
		(stroke
			(width 0.05715)
			(type default)
		)
		(layer "F.Cu")
	)
	(gr_line
		(start 412.472886 -3.69824)
		(end 412.472886 -4.386072)
		(stroke
			(width 0.05715)
			(type default)
		)
		(layer "F.Cu")
	)
	(gr_line
		(start 412.571946 -10.1346)
		(end 412.610554 -10.095992)
		(stroke
			(width 0.05715)
			(type default)
		)
		(layer "F.Cu")
	)
	(gr_line
		(start 412.588964 -46.058074)
		(end 412.750762 -45.896276)
		(stroke
			(width 0.05715)
			(type default)
		)
		(layer "F.Cu")
	)
	(gr_line
		(start 412.750762 -45.72381)
		(end 412.750762 -45.896276)
		(stroke
			(width 0.05715)
			(type default)
		)
		(layer "F.Cu")
	)
	(gr_line
		(start 412.91002 -8.882126)
		(end 413.272986 -8.51916)
		(stroke
			(width 0.05715)
			(type default)
		)
		(layer "F.Cu")
	)
	(gr_line
		(start 412.915862 -45.55871)
		(end 413.088328 -45.55871)
		(stroke
			(width 0.05715)
			(type default)
		)
		(layer "F.Cu")
	)
	(gr_line
		(start 412.955486 -10.095992)
		(end 413.00273 -10.143236)
		(stroke
			(width 0.05715)
			(type default)
		)
		(layer "F.Cu")
	)
	(gr_line
		(start 413.00273 -10.143236)
		(end 413.43961 -10.143236)
		(stroke
			(width 0.05715)
			(type default)
		)
		(layer "F.Cu")
	)
	(gr_line
		(start 413.088328 -45.55871)
		(end 413.250126 -45.396912)
		(stroke
			(width 0.05715)
			(type default)
		)
		(layer "F.Cu")
	)
	(gr_line
		(start 413.250126 -45.224446)
		(end 413.250126 -45.396912)
		(stroke
			(width 0.05715)
			(type default)
		)
		(layer "F.Cu")
	)
	(gr_line
		(start 413.272986 -7.789672)
		(end 413.272986 -8.51916)
		(stroke
			(width 0.05715)
			(type default)
		)
		(layer "F.Cu")
	)
	(gr_line
		(start 413.415226 -45.059346)
		(end 413.587692 -45.059346)
		(stroke
			(width 0.05715)
			(type default)
		)
		(layer "F.Cu")
	)
	(gr_line
		(start 413.587692 -45.059346)
		(end 413.74949 -44.897548)
		(stroke
			(width 0.05715)
			(type default)
		)
		(layer "F.Cu")
	)
	(gr_line
		(start 413.74949 -44.725082)
		(end 413.74949 -44.897548)
		(stroke
			(width 0.05715)
			(type default)
		)
		(layer "F.Cu")
	)
	(gr_line
		(start 413.7533 -49.617376)
		(end 414.126172 -49.244504)
		(stroke
			(width 0.05715)
			(type default)
		)
		(layer "F.Cu")
	)
	(gr_line
		(start 413.803592 -1.73355)
		(end 414.203642 -1.73355)
		(stroke
			(width 0.05715)
			(type default)
		)
		(layer "F.Cu")
	)
	(gr_line
		(start 413.898842 -43.316906)
		(end 414.290256 -42.534586)
		(stroke
			(width 0.05715)
			(type default)
		)
		(layer "F.Cu")
	)
	(gr_line
		(start 414.057592 -48.015398)
		(end 414.126172 -48.083978)
		(stroke
			(width 0.04445)
			(type default)
		)
		(layer "F.Cu")
	)
	(gr_line
		(start 414.057592 -47.759874)
		(end 414.057592 -48.015398)
		(stroke
			(width 0.04445)
			(type default)
		)
		(layer "F.Cu")
	)
	(gr_line
		(start 414.057592 -47.759874)
		(end 414.146746 -47.67072)
		(stroke
			(width 0.04445)
			(type default)
		)
		(layer "F.Cu")
	)
	(gr_line
		(start 414.073086 -3.67792)
		(end 414.073086 -4.386072)
		(stroke
			(width 0.05715)
			(type default)
		)
		(layer "F.Cu")
	)
	(gr_line
		(start 414.073086 -3.67792)
		(end 414.280858 -3.470148)
		(stroke
			(width 0.05715)
			(type default)
		)
		(layer "F.Cu")
	)
	(gr_line
		(start 414.126172 -48.972978)
		(end 414.126172 -49.244504)
		(stroke
			(width 0.05715)
			(type default)
		)
		(layer "F.Cu")
	)
	(gr_line
		(start 414.142682 -44.12742)
		(end 414.264602 -44.0055)
		(stroke
			(width 0.05715)
			(type default)
		)
		(layer "F.Cu")
	)
	(gr_line
		(start 414.142682 -43.654726)
		(end 414.264602 -43.776646)
		(stroke
			(width 0.05715)
			(type default)
		)
		(layer "F.Cu")
	)
	(gr_line
		(start 414.142682 -43.401996)
		(end 414.209992 -43.334686)
		(stroke
			(width 0.05715)
			(type default)
		)
		(layer "F.Cu")
	)
	(gr_line
		(start 414.146746 -47.67072)
		(end 414.425892 -47.67072)
		(stroke
			(width 0.04445)
			(type default)
		)
		(layer "F.Cu")
	)
	(gr_line
		(start 414.203642 -1.73355)
		(end 414.304734 -1.834642)
		(stroke
			(width 0.05715)
			(type default)
		)
		(layer "F.Cu")
	)
	(gr_line
		(start 414.209992 -43.334686)
		(end 414.290256 -43.334686)
		(stroke
			(width 0.05715)
			(type default)
		)
		(layer "F.Cu")
	)
	(gr_line
		(start 414.264602 -43.776646)
		(end 414.264602 -44.0055)
		(stroke
			(width 0.05715)
			(type default)
		)
		(layer "F.Cu")
	)
	(gr_line
		(start 414.425892 -47.67072)
		(end 414.512252 -47.58436)
		(stroke
			(width 0.04445)
			(type default)
		)
		(layer "F.Cu")
	)
	(gr_line
		(start 414.425892 -47.15891)
		(end 414.512252 -47.24527)
		(stroke
			(width 0.04445)
			(type default)
		)
		(layer "F.Cu")
	)
	(gr_line
		(start 414.425892 -46.89221)
		(end 414.425892 -47.15891)
		(stroke
			(width 0.04445)
			(type default)
		)
		(layer "F.Cu")
	)
	(gr_line
		(start 414.425892 -46.89221)
		(end 414.512252 -46.80585)
		(stroke
			(width 0.04445)
			(type default)
		)
		(layer "F.Cu")
	)
	(gr_line
		(start 414.425892 -46.44771)
		(end 414.512252 -46.53407)
		(stroke
			(width 0.04445)
			(type default)
		)
		(layer "F.Cu")
	)
	(gr_line
		(start 414.425892 -46.18101)
		(end 414.425892 -46.44771)
		(stroke
			(width 0.04445)
			(type default)
		)
		(layer "F.Cu")
	)
	(gr_line
		(start 414.425892 -46.18101)
		(end 414.512252 -46.09465)
		(stroke
			(width 0.04445)
			(type default)
		)
		(layer "F.Cu")
	)
	(gr_line
		(start 414.514792 -45.891958)
		(end 414.768792 -45.637958)
		(stroke
			(width 0.04445)
			(type default)
		)
		(layer "F.Cu")
	)
	(gr_line
		(start 414.62579 -3.470148)
		(end 414.873186 -3.717544)
		(stroke
			(width 0.05715)
			(type default)
		)
		(layer "F.Cu")
	)
	(gr_line
		(start 414.629092 -10.124948)
		(end 415.029142 -10.124948)
		(stroke
			(width 0.05715)
			(type default)
		)
		(layer "F.Cu")
	)
	(gr_line
		(start 414.649412 -1.834642)
		(end 414.750504 -1.73355)
		(stroke
			(width 0.05715)
			(type default)
		)
		(layer "F.Cu")
	)
	(gr_line
		(start 414.67786 -49.617376)
		(end 414.962594 -49.332642)
		(stroke
			(width 0.05715)
			(type default)
		)
		(layer "F.Cu")
	)
	(gr_line
		(start 414.705292 -47.825914)
		(end 414.962594 -48.083216)
		(stroke
			(width 0.04445)
			(type default)
		)
		(layer "F.Cu")
	)
	(gr_line
		(start 414.705292 -47.77486)
		(end 414.705292 -47.825914)
		(stroke
			(width 0.04445)
			(type default)
		)
		(layer "F.Cu")
	)
	(gr_line
		(start 414.705292 -46.99635)
		(end 414.705292 -47.05477)
		(stroke
			(width 0.04445)
			(type default)
		)
		(layer "F.Cu")
	)
	(gr_line
		(start 414.705292 -46.28515)
		(end 414.705292 -46.34357)
		(stroke
			(width 0.04445)
			(type default)
		)
		(layer "F.Cu")
	)
	(gr_line
		(start 414.707832 -46.00448)
		(end 414.858454 -45.853858)
		(stroke
			(width 0.04445)
			(type default)
		)
		(layer "F.Cu")
	)
	(gr_line
		(start 414.750504 -1.73355)
		(end 415.073592 -1.73355)
		(stroke
			(width 0.05715)
			(type default)
		)
		(layer "F.Cu")
	)
	(gr_line
		(start 414.768792 -45.637958)
		(end 415.257996 -45.637958)
		(stroke
			(width 0.04445)
			(type default)
		)
		(layer "F.Cu")
	)
	(gr_line
		(start 414.858454 -45.853858)
		(end 415.347658 -45.853858)
		(stroke
			(width 0.04445)
			(type default)
		)
		(layer "F.Cu")
	)
	(gr_line
		(start 414.873186 -8.657336)
		(end 415.076386 -8.860536)
		(stroke
			(width 0.05715)
			(type default)
		)
		(layer "F.Cu")
	)
	(gr_line
		(start 414.873186 -7.789672)
		(end 414.873186 -8.657336)
		(stroke
			(width 0.05715)
			(type default)
		)
		(layer "F.Cu")
	)
	(gr_line
		(start 414.873186 -3.717544)
		(end 414.873186 -4.386072)
		(stroke
			(width 0.05715)
			(type default)
		)
		(layer "F.Cu")
	)
	(gr_line
		(start 414.962594 -48.972216)
		(end 414.962594 -49.332642)
		(stroke
			(width 0.05715)
			(type default)
		)
		(layer "F.Cu")
	)
	(gr_line
		(start 415.029142 -10.124948)
		(end 415.091626 -10.062464)
		(stroke
			(width 0.05715)
			(type default)
		)
		(layer "F.Cu")
	)
	(gr_line
		(start 415.090102 -43.334686)
		(end 415.268664 -43.334686)
		(stroke
			(width 0.04445)
			(type default)
		)
		(layer "F.Cu")
	)
	(gr_line
		(start 415.090102 -42.534586)
		(end 415.548064 -43.368976)
		(stroke
			(width 0.04445)
			(type default)
		)
		(layer "F.Cu")
	)
	(gr_line
		(start 415.257996 -45.637958)
		(end 415.332164 -45.56379)
		(stroke
			(width 0.04445)
			(type default)
		)
		(layer "F.Cu")
	)
	(gr_line
		(start 415.268664 -45.381672)
		(end 415.332164 -45.445172)
		(stroke
			(width 0.04445)
			(type default)
		)
		(layer "F.Cu")
	)
	(gr_line
		(start 415.268664 -45.114972)
		(end 415.268664 -45.381672)
		(stroke
			(width 0.04445)
			(type default)
		)
		(layer "F.Cu")
	)
	(gr_line
		(start 415.268664 -45.114972)
		(end 415.355024 -45.028612)
		(stroke
			(width 0.04445)
			(type default)
		)
		(layer "F.Cu")
	)
	(gr_line
		(start 415.268664 -44.670472)
		(end 415.355024 -44.756832)
		(stroke
			(width 0.04445)
			(type default)
		)
		(layer "F.Cu")
	)
	(gr_line
		(start 415.268664 -44.403772)
		(end 415.268664 -44.670472)
		(stroke
			(width 0.04445)
			(type default)
		)
		(layer "F.Cu")
	)
	(gr_line
		(start 415.268664 -44.403772)
		(end 415.355024 -44.317412)
		(stroke
			(width 0.04445)
			(type default)
		)
		(layer "F.Cu")
	)
	(gr_line
		(start 415.268664 -43.959272)
		(end 415.355024 -44.045632)
		(stroke
			(width 0.04445)
			(type default)
		)
		(layer "F.Cu")
	)
	(gr_line
		(start 415.268664 -43.692572)
		(end 415.268664 -43.959272)
		(stroke
			(width 0.04445)
			(type default)
		)
		(layer "F.Cu")
	)
	(gr_line
		(start 415.268664 -43.692572)
		(end 415.355024 -43.606212)
		(stroke
			(width 0.04445)
			(type default)
		)
		(layer "F.Cu")
	)
	(gr_line
		(start 415.268664 -43.334686)
		(end 415.355024 -43.421046)
		(stroke
			(width 0.04445)
			(type default)
		)
		(layer "F.Cu")
	)
	(gr_line
		(start 415.332164 -45.445172)
		(end 415.332164 -45.56379)
		(stroke
			(width 0.04445)
			(type default)
		)
		(layer "F.Cu")
	)
	(gr_line
		(start 415.347658 -45.853858)
		(end 415.548064 -45.653452)
		(stroke
			(width 0.04445)
			(type default)
		)
		(layer "F.Cu")
	)
	(gr_line
		(start 415.379154 -47.102776)
		(end 415.863278 -47.102776)
		(stroke
			(width 0.04445)
			(type default)
		)
		(layer "F.Cu")
	)
	(gr_line
		(start 415.421318 -8.860536)
		(end 415.673286 -8.608568)
		(stroke
			(width 0.05715)
			(type default)
		)
		(layer "F.Cu")
	)
	(gr_line
		(start 415.436558 -10.062464)
		(end 415.499042 -10.124948)
		(stroke
			(width 0.05715)
			(type default)
		)
		(layer "F.Cu")
	)
	(gr_line
		(start 415.499042 -10.124948)
		(end 415.899092 -10.124948)
		(stroke
			(width 0.05715)
			(type default)
		)
		(layer "F.Cu")
	)
	(gr_line
		(start 415.548064 -45.219112)
		(end 415.548064 -45.653452)
		(stroke
			(width 0.04445)
			(type default)
		)
		(layer "F.Cu")
	)
	(gr_line
		(start 415.548064 -44.507912)
		(end 415.548064 -44.566332)
		(stroke
			(width 0.04445)
			(type default)
		)
		(layer "F.Cu")
	)
	(gr_line
		(start 415.548064 -43.796712)
		(end 415.548064 -43.855132)
		(stroke
			(width 0.04445)
			(type default)
		)
		(layer "F.Cu")
	)
	(gr_line
		(start 415.673286 -7.789672)
		(end 415.673286 -8.608568)
		(stroke
			(width 0.05715)
			(type default)
		)
		(layer "F.Cu")
	)
	(gr_line
		(start 415.863278 -47.102776)
		(end 415.958528 -47.007526)
		(stroke
			(width 0.04445)
			(type default)
		)
		(layer "F.Cu")
	)
	(gr_line
		(start 415.890202 -43.334686)
		(end 416.068764 -43.334686)
		(stroke
			(width 0.04445)
			(type default)
		)
		(layer "F.Cu")
	)
	(gr_line
		(start 415.890202 -42.534586)
		(end 416.348164 -43.303952)
		(stroke
			(width 0.04445)
			(type default)
		)
		(layer "F.Cu")
	)
	(gr_line
		(start 415.960306 -47.005748)
		(end 415.97961 -46.986444)
		(stroke
			(width 0.04445)
			(type default)
		)
		(layer "F.Cu")
	)
	(gr_line
		(start 415.97961 -46.464728)
		(end 416.132264 -46.312074)
		(stroke
			(width 0.04445)
			(type default)
		)
		(layer "F.Cu")
	)
	(gr_line
		(start 416.068764 -46.092872)
		(end 416.132264 -46.156372)
		(stroke
			(width 0.04445)
			(type default)
		)
		(layer "F.Cu")
	)
	(gr_line
		(start 416.068764 -45.826172)
		(end 416.068764 -46.092872)
		(stroke
			(width 0.04445)
			(type default)
		)
		(layer "F.Cu")
	)
	(gr_line
		(start 416.068764 -45.826172)
		(end 416.155124 -45.739812)
		(stroke
			(width 0.04445)
			(type default)
		)
		(layer "F.Cu")
	)
	(gr_line
		(start 416.068764 -45.381672)
		(end 416.155124 -45.468032)
		(stroke
			(width 0.04445)
			(type default)
		)
		(layer "F.Cu")
	)
	(gr_line
		(start 416.068764 -45.114972)
		(end 416.068764 -45.381672)
		(stroke
			(width 0.04445)
			(type default)
		)
		(layer "F.Cu")
	)
	(gr_line
		(start 416.068764 -45.114972)
		(end 416.155124 -45.028612)
		(stroke
			(width 0.04445)
			(type default)
		)
		(layer "F.Cu")
	)
	(gr_line
		(start 416.068764 -44.670472)
		(end 416.155124 -44.756832)
		(stroke
			(width 0.04445)
			(type default)
		)
		(layer "F.Cu")
	)
	(gr_line
		(start 416.068764 -44.403772)
		(end 416.068764 -44.670472)
		(stroke
			(width 0.04445)
			(type default)
		)
		(layer "F.Cu")
	)
	(gr_line
		(start 416.068764 -44.403772)
		(end 416.155124 -44.317412)
		(stroke
			(width 0.04445)
			(type default)
		)
		(layer "F.Cu")
	)
	(gr_line
		(start 416.068764 -43.959272)
		(end 416.155124 -44.045632)
		(stroke
			(width 0.04445)
			(type default)
		)
		(layer "F.Cu")
	)
	(gr_line
		(start 416.068764 -43.692572)
		(end 416.068764 -43.959272)
		(stroke
			(width 0.04445)
			(type default)
		)
		(layer "F.Cu")
	)
	(gr_line
		(start 416.068764 -43.692572)
		(end 416.155124 -43.606212)
		(stroke
			(width 0.04445)
			(type default)
		)
		(layer "F.Cu")
	)
	(gr_line
		(start 416.068764 -43.334686)
		(end 416.155124 -43.421046)
		(stroke
			(width 0.04445)
			(type default)
		)
		(layer "F.Cu")
	)
	(gr_line
		(start 416.132264 -46.156372)
		(end 416.132264 -46.312074)
		(stroke
			(width 0.04445)
			(type default)
		)
		(layer "F.Cu")
	)
	(gr_line
		(start 416.17011 -46.946058)
		(end 416.2298 -47.005748)
		(stroke
			(width 0.04445)
			(type default)
		)
		(layer "F.Cu")
	)
	(gr_line
		(start 416.17265 -46.57725)
		(end 416.348164 -46.401736)
		(stroke
			(width 0.04445)
			(type default)
		)
		(layer "F.Cu")
	)
	(gr_line
		(start 416.231578 -47.007526)
		(end 416.371532 -47.14748)
		(stroke
			(width 0.04445)
			(type default)
		)
		(layer "F.Cu")
	)
	(gr_line
		(start 416.27171 -2.82067)
		(end 416.617658 -2.82067)
		(stroke
			(width 0.05715)
			(type default)
		)
		(layer "F.Cu")
	)
	(gr_line
		(start 416.348164 -45.930312)
		(end 416.348164 -46.401736)
		(stroke
			(width 0.04445)
			(type default)
		)
		(layer "F.Cu")
	)
	(gr_line
		(start 416.348164 -45.219112)
		(end 416.348164 -45.277532)
		(stroke
			(width 0.04445)
			(type default)
		)
		(layer "F.Cu")
	)
	(gr_line
		(start 416.348164 -44.507912)
		(end 416.348164 -44.566332)
		(stroke
			(width 0.04445)
			(type default)
		)
		(layer "F.Cu")
	)
	(gr_line
		(start 416.348164 -43.796712)
		(end 416.348164 -43.855132)
		(stroke
			(width 0.04445)
			(type default)
		)
		(layer "F.Cu")
	)
	(gr_line
		(start 416.473386 -3.683)
		(end 416.473386 -4.386072)
		(stroke
			(width 0.05715)
			(type default)
		)
		(layer "F.Cu")
	)
	(gr_line
		(start 416.473386 -3.683)
		(end 416.73907 -3.417316)
		(stroke
			(width 0.05715)
			(type default)
		)
		(layer "F.Cu")
	)
	(gr_line
		(start 416.617658 -2.82067)
		(end 416.718496 -2.921508)
		(stroke
			(width 0.05715)
			(type default)
		)
		(layer "F.Cu")
	)
	(gr_line
		(start 416.627564 -92.837)
		(end 416.86099 -92.603574)
		(stroke
			(width 0.0508)
			(type default)
		)
		(layer "F.Cu")
	)
	(gr_line
		(start 416.627564 -91.717622)
		(end 416.86099 -91.951048)
		(stroke
			(width 0.0508)
			(type default)
		)
		(layer "F.Cu")
	)
	(gr_line
		(start 416.627564 -91.567)
		(end 416.627564 -91.717622)
		(stroke
			(width 0.0508)
			(type default)
		)
		(layer "F.Cu")
	)
	(gr_line
		(start 417.029392 -10.023348)
		(end 417.357052 -10.023348)
		(stroke
			(width 0.05715)
			(type default)
		)
		(layer "F.Cu")
	)
	(gr_line
		(start 417.063428 -2.921508)
		(end 417.164266 -2.82067)
		(stroke
			(width 0.05715)
			(type default)
		)
		(layer "F.Cu")
	)
	(gr_line
		(start 417.084002 -3.417316)
		(end 417.273486 -3.6068)
		(stroke
			(width 0.05715)
			(type default)
		)
		(layer "F.Cu")
	)
	(gr_line
		(start 417.164266 -2.82067)
		(end 417.54171 -2.82067)
		(stroke
			(width 0.05715)
			(type default)
		)
		(layer "F.Cu")
	)
	(gr_line
		(start 417.273486 -8.657336)
		(end 417.50107 -8.88492)
		(stroke
			(width 0.05715)
			(type default)
		)
		(layer "F.Cu")
	)
	(gr_line
		(start 417.273486 -7.789672)
		(end 417.273486 -8.657336)
		(stroke
			(width 0.05715)
			(type default)
		)
		(layer "F.Cu")
	)
	(gr_line
		(start 417.273486 -3.6068)
		(end 417.273486 -4.386072)
		(stroke
			(width 0.05715)
			(type default)
		)
		(layer "F.Cu")
	)
	(gr_line
		(start 417.357052 -10.023348)
		(end 417.505134 -9.875266)
		(stroke
			(width 0.05715)
			(type default)
		)
		(layer "F.Cu")
	)
	(gr_line
		(start 417.382452 -92.553536)
		(end 417.500816 -92.6719)
		(stroke
			(width 0.0508)
			(type default)
		)
		(layer "F.Cu")
	)
	(gr_line
		(start 417.382452 -91.901264)
		(end 417.500816 -91.7829)
		(stroke
			(width 0.0508)
			(type default)
		)
		(layer "F.Cu")
	)
	(gr_line
		(start 417.500816 -92.6719)
		(end 417.9062 -92.6719)
		(stroke
			(width 0.0508)
			(type default)
		)
		(layer "F.Cu")
	)
	(gr_line
		(start 417.500816 -91.7829)
		(end 417.9062 -91.7829)
		(stroke
			(width 0.0508)
			(type default)
		)
		(layer "F.Cu")
	)
	(gr_line
		(start 417.846002 -8.88492)
		(end 418.073586 -8.657336)
		(stroke
			(width 0.05715)
			(type default)
		)
		(layer "F.Cu")
	)
	(gr_line
		(start 417.850066 -9.875266)
		(end 417.998148 -10.023348)
		(stroke
			(width 0.05715)
			(type default)
		)
		(layer "F.Cu")
	)
	(gr_line
		(start 417.998148 -10.023348)
		(end 418.299392 -10.023348)
		(stroke
			(width 0.05715)
			(type default)
		)
		(layer "F.Cu")
	)
	(gr_line
		(start 418.073586 -7.789672)
		(end 418.073586 -8.657336)
		(stroke
			(width 0.05715)
			(type default)
		)
		(layer "F.Cu")
	)
	(gr_line
		(start 418.781992 -1.60655)
		(end 419.182042 -1.60655)
		(stroke
			(width 0.05715)
			(type default)
		)
		(layer "F.Cu")
	)
	(gr_line
		(start 418.7952 -92.6719)
		(end 419.15588 -92.6719)
		(stroke
			(width 0.0508)
			(type default)
		)
		(layer "F.Cu")
	)
	(gr_line
		(start 418.7952 -91.7829)
		(end 419.166294 -91.7829)
		(stroke
			(width 0.0508)
			(type default)
		)
		(layer "F.Cu")
	)
	(gr_line
		(start 418.873686 -3.758184)
		(end 418.873686 -4.386072)
		(stroke
			(width 0.05715)
			(type default)
		)
		(layer "F.Cu")
	)
	(gr_line
		(start 418.873686 -3.758184)
		(end 419.10127 -3.5306)
		(stroke
			(width 0.05715)
			(type default)
		)
		(layer "F.Cu")
	)
	(gr_line
		(start 419.15588 -92.6719)
		(end 419.279324 -92.548456)
		(stroke
			(width 0.0508)
			(type default)
		)
		(layer "F.Cu")
	)
	(gr_line
		(start 419.166294 -91.7829)
		(end 419.279324 -91.89593)
		(stroke
			(width 0.0508)
			(type default)
		)
		(layer "F.Cu")
	)
	(gr_line
		(start 419.182042 -1.60655)
		(end 419.245796 -1.670304)
		(stroke
			(width 0.05715)
			(type default)
		)
		(layer "F.Cu")
	)
	(gr_line
		(start 419.429692 -10.023348)
		(end 419.829742 -10.023348)
		(stroke
			(width 0.05715)
			(type default)
		)
		(layer "F.Cu")
	)
	(gr_line
		(start 419.446202 -3.5306)
		(end 419.673786 -3.758184)
		(stroke
			(width 0.05715)
			(type default)
		)
		(layer "F.Cu")
	)
	(gr_line
		(start 419.590474 -1.670304)
		(end 419.654228 -1.60655)
		(stroke
			(width 0.05715)
			(type default)
		)
		(layer "F.Cu")
	)
	(gr_line
		(start 419.654228 -1.60655)
		(end 420.051992 -1.60655)
		(stroke
			(width 0.05715)
			(type default)
		)
		(layer "F.Cu")
	)
	(gr_line
		(start 419.655244 -92.531946)
		(end 419.655244 -92.8624)
		(stroke
			(width 0.0508)
			(type default)
		)
		(layer "F.Cu")
	)
	(gr_line
		(start 419.655244 -91.5924)
		(end 419.655244 -91.913456)
		(stroke
			(width 0.0508)
			(type default)
		)
		(layer "F.Cu")
	)
	(gr_line
		(start 419.673786 -8.657336)
		(end 419.90137 -8.88492)
		(stroke
			(width 0.05715)
			(type default)
		)
		(layer "F.Cu")
	)
	(gr_line
		(start 419.673786 -7.789672)
		(end 419.673786 -8.657336)
		(stroke
			(width 0.05715)
			(type default)
		)
		(layer "F.Cu")
	)
	(gr_line
		(start 419.673786 -3.758184)
		(end 419.673786 -4.386072)
		(stroke
			(width 0.05715)
			(type default)
		)
		(layer "F.Cu")
	)
	(gr_line
		(start 419.829742 -10.023348)
		(end 419.892226 -9.960864)
		(stroke
			(width 0.05715)
			(type default)
		)
		(layer "F.Cu")
	)
	(gr_line
		(start 420.237158 -9.960864)
		(end 420.299642 -10.023348)
		(stroke
			(width 0.05715)
			(type default)
		)
		(layer "F.Cu")
	)
	(gr_line
		(start 420.246302 -8.88492)
		(end 420.473886 -8.657336)
		(stroke
			(width 0.05715)
			(type default)
		)
		(layer "F.Cu")
	)
	(gr_line
		(start 420.299642 -10.023348)
		(end 420.699692 -10.023348)
		(stroke
			(width 0.05715)
			(type default)
		)
		(layer "F.Cu")
	)
	(gr_line
		(start 420.473886 -7.789672)
		(end 420.473886 -8.657336)
		(stroke
			(width 0.05715)
			(type default)
		)
		(layer "F.Cu")
	)
	(gr_arc
		(start 420.896542 -138.410442)
		(mid 420.95942 -138.393332)
		(end 421.010842 -138.353292)
		(stroke
			(width 0.05715)
			(type default)
		)
		(layer "F.Cu")
	)
	(gr_line
		(start 420.971726 -2.605532)
		(end 421.324786 -2.605532)
		(stroke
			(width 0.05715)
			(type default)
		)
		(layer "F.Cu")
	)
	(gr_arc
		(start 421.125142 -138.296142)
		(mid 421.062228 -138.313199)
		(end 421.010842 -138.353292)
		(stroke
			(width 0.05715)
			(type default)
		)
		(layer "F.Cu")
	)
	(gr_line
		(start 421.125142 -138.296142)
		(end 421.468042 -138.296142)
		(stroke
			(width 0.05715)
			(type default)
		)
		(layer "F.Cu")
	)
	(gr_line
		(start 421.140382 -138.651742)
		(end 421.452802 -138.651742)
		(stroke
			(width 0.05715)
			(type default)
		)
		(layer "F.Cu")
	)
	(gr_line
		(start 421.273986 -3.69824)
		(end 421.273986 -4.386072)
		(stroke
			(width 0.05715)
			(type default)
		)
		(layer "F.Cu")
	)
	(gr_line
		(start 421.273986 -3.69824)
		(end 421.50157 -3.470656)
		(stroke
			(width 0.05715)
			(type default)
		)
		(layer "F.Cu")
	)
	(gr_line
		(start 421.324786 -2.605532)
		(end 421.442388 -2.723134)
		(stroke
			(width 0.05715)
			(type default)
		)
		(layer "F.Cu")
	)
	(gr_arc
		(start 421.582342 -138.353292)
		(mid 421.530937 -138.313238)
		(end 421.468042 -138.296142)
		(stroke
			(width 0.05715)
			(type default)
		)
		(layer "F.Cu")
	)
	(gr_arc
		(start 421.582342 -138.353292)
		(mid 421.633729 -138.393397)
		(end 421.696642 -138.410442)
		(stroke
			(width 0.05715)
			(type default)
		)
		(layer "F.Cu")
	)
	(gr_line
		(start 421.787066 -2.723134)
		(end 421.931084 -2.579116)
		(stroke
			(width 0.05715)
			(type default)
		)
		(layer "F.Cu")
	)
	(gr_line
		(start 421.829992 -10.023348)
		(end 422.230042 -10.023348)
		(stroke
			(width 0.05715)
			(type default)
		)
		(layer "F.Cu")
	)
	(gr_line
		(start 421.846502 -3.470656)
		(end 422.074086 -3.69824)
		(stroke
			(width 0.05715)
			(type default)
		)
		(layer "F.Cu")
	)
	(gr_line
		(start 421.931084 -2.579116)
		(end 422.242742 -2.579116)
		(stroke
			(width 0.05715)
			(type default)
		)
		(layer "F.Cu")
	)
	(gr_arc
		(start 422.039542 -138.410442)
		(mid 422.10242 -138.393332)
		(end 422.153842 -138.353292)
		(stroke
			(width 0.05715)
			(type default)
		)
		(layer "F.Cu")
	)
	(gr_line
		(start 422.074086 -8.657336)
		(end 422.30167 -8.88492)
		(stroke
			(width 0.05715)
			(type default)
		)
		(layer "F.Cu")
	)
	(gr_line
		(start 422.074086 -7.789672)
		(end 422.074086 -8.657336)
		(stroke
			(width 0.05715)
			(type default)
		)
		(layer "F.Cu")
	)
	(gr_line
		(start 422.074086 -3.69824)
		(end 422.074086 -4.386072)
		(stroke
			(width 0.05715)
			(type default)
		)
		(layer "F.Cu")
	)
	(gr_line
		(start 422.230042 -10.023348)
		(end 422.292526 -9.960864)
		(stroke
			(width 0.05715)
			(type default)
		)
		(layer "F.Cu")
	)
	(gr_arc
		(start 422.268142 -138.296142)
		(mid 422.205228 -138.313199)
		(end 422.153842 -138.353292)
		(stroke
			(width 0.05715)
			(type default)
		)
		(layer "F.Cu")
	)
	(gr_line
		(start 422.268142 -138.296142)
		(end 422.611042 -138.296142)
		(stroke
			(width 0.05715)
			(type default)
		)
		(layer "F.Cu")
	)
	(gr_line
		(start 422.283382 -138.651742)
		(end 422.595802 -138.651742)
		(stroke
			(width 0.05715)
			(type default)
		)
		(layer "F.Cu")
	)
	(gr_line
		(start 422.637458 -9.960864)
		(end 422.699942 -10.023348)
		(stroke
			(width 0.05715)
			(type default)
		)
		(layer "F.Cu")
	)
	(gr_line
		(start 422.646602 -8.88492)
		(end 422.874186 -8.657336)
		(stroke
			(width 0.05715)
			(type default)
		)
		(layer "F.Cu")
	)
	(gr_line
		(start 422.699942 -10.023348)
		(end 423.099992 -10.023348)
		(stroke
			(width 0.05715)
			(type default)
		)
		(layer "F.Cu")
	)
	(gr_arc
		(start 422.725342 -138.353292)
		(mid 422.673937 -138.313238)
		(end 422.611042 -138.296142)
		(stroke
			(width 0.05715)
			(type default)
		)
		(layer "F.Cu")
	)
	(gr_arc
		(start 422.725342 -138.353292)
		(mid 422.776729 -138.393397)
		(end 422.839642 -138.410442)
		(stroke
			(width 0.05715)
			(type default)
		)
		(layer "F.Cu")
	)
	(gr_line
		(start 422.874186 -7.789672)
		(end 422.874186 -8.657336)
		(stroke
			(width 0.05715)
			(type default)
		)
		(layer "F.Cu")
	)
	(gr_line
		(start 423.412666 -1.583944)
		(end 423.812716 -1.583944)
		(stroke
			(width 0.05715)
			(type default)
		)
		(layer "F.Cu")
	)
	(gr_line
		(start 423.674286 -3.758184)
		(end 423.674286 -4.386072)
		(stroke
			(width 0.05715)
			(type default)
		)
		(layer "F.Cu")
	)
	(gr_line
		(start 423.674286 -3.758184)
		(end 423.90187 -3.5306)
		(stroke
			(width 0.05715)
			(type default)
		)
		(layer "F.Cu")
	)
	(gr_line
		(start 423.812716 -1.583944)
		(end 423.8752 -1.646428)
		(stroke
			(width 0.05715)
			(type default)
		)
		(layer "F.Cu")
	)
	(gr_arc
		(start 423.890186 -34.534602)
		(mid 424.143182 -34.662132)
		(end 424.423078 -34.706052)
		(stroke
			(width 0.050038)
			(type default)
		)
		(layer "F.Cu")
	)
	(gr_arc
		(start 423.890186 -32.934656)
		(mid 423.923349 -33.139222)
		(end 424.108118 -33.233106)
		(stroke
			(width 0.050038)
			(type default)
		)
		(layer "F.Cu")
	)
	(gr_line
		(start 423.890186 -31.33471)
		(end 423.993056 -31.23184)
		(stroke
			(width 0.050038)
			(type default)
		)
		(layer "F.Cu")
	)
	(gr_arc
		(start 423.890186 -30.53461)
		(mid 424.155802 -30.662228)
		(end 424.447208 -30.70606)
		(stroke
			(width 0.050038)
			(type default)
		)
		(layer "F.Cu")
	)
	(gr_arc
		(start 423.997628 -33.690306)
		(mid 423.93947 -33.701811)
		(end 423.890186 -33.734756)
		(stroke
			(width 0.050038)
			(type default)
		)
		(layer "F.Cu")
	)
	(gr_arc
		(start 424.15841 -31.16326)
		(mid 424.068917 -31.181108)
		(end 423.993056 -31.23184)
		(stroke
			(width 0.050038)
			(type default)
		)
		(layer "F.Cu")
	)
	(gr_line
		(start 424.220132 -1.646428)
		(end 424.282616 -1.583944)
		(stroke
			(width 0.05715)
			(type default)
		)
		(layer "F.Cu")
	)
	(gr_line
		(start 424.230292 -10.023348)
		(end 424.545252 -10.023348)
		(stroke
			(width 0.05715)
			(type default)
		)
		(layer "F.Cu")
	)
	(gr_line
		(start 424.246802 -3.5306)
		(end 424.474386 -3.758184)
		(stroke
			(width 0.05715)
			(type default)
		)
		(layer "F.Cu")
	)
	(gr_line
		(start 424.282616 -1.583944)
		(end 424.682666 -1.583944)
		(stroke
			(width 0.05715)
			(type default)
		)
		(layer "F.Cu")
	)
	(gr_arc
		(start 424.304206 -35.163252)
		(mid 424.080156 -35.207818)
		(end 423.890186 -35.334702)
		(stroke
			(width 0.050038)
			(type default)
		)
		(layer "F.Cu")
	)
	(gr_line
		(start 424.474386 -8.657336)
		(end 424.70197 -8.88492)
		(stroke
			(width 0.05715)
			(type default)
		)
		(layer "F.Cu")
	)
	(gr_line
		(start 424.474386 -7.789672)
		(end 424.474386 -8.657336)
		(stroke
			(width 0.05715)
			(type default)
		)
		(layer "F.Cu")
	)
	(gr_line
		(start 424.474386 -3.758184)
		(end 424.474386 -4.386072)
		(stroke
			(width 0.05715)
			(type default)
		)
		(layer "F.Cu")
	)
	(gr_line
		(start 424.545252 -10.023348)
		(end 424.693334 -9.875266)
		(stroke
			(width 0.05715)
			(type default)
		)
		(layer "F.Cu")
	)
	(gr_arc
		(start 425.037758 -136.676638)
		(mid 424.333544 -136.968353)
		(end 424.041824 -137.672572)
		(stroke
			(width 0.05715)
			(type default)
		)
		(layer "F.Cu")
	)
	(gr_arc
		(start 425.037758 -136.435338)
		(mid 424.162901 -136.797715)
		(end 423.800524 -137.672572)
		(stroke
			(width 0.05715)
			(type default)
		)
		(layer "F.Cu")
	)
	(gr_line
		(start 425.038266 -9.875266)
		(end 425.186348 -10.023348)
		(stroke
			(width 0.05715)
			(type default)
		)
		(layer "F.Cu")
	)
	(gr_line
		(start 425.046902 -8.88492)
		(end 425.274486 -8.657336)
		(stroke
			(width 0.05715)
			(type default)
		)
		(layer "F.Cu")
	)
	(gr_line
		(start 425.186348 -10.023348)
		(end 425.500292 -10.023348)
		(stroke
			(width 0.05715)
			(type default)
		)
		(layer "F.Cu")
	)
	(gr_line
		(start 425.274486 -7.789672)
		(end 425.274486 -8.657336)
		(stroke
			(width 0.05715)
			(type default)
		)
		(layer "F.Cu")
	)
	(gr_arc
		(start 425.406312 -30.70606)
		(mid 425.688853 -30.64994)
		(end 425.928536 -30.49016)
		(stroke
			(width 0.050038)
			(type default)
		)
		(layer "F.Cu")
	)
	(gr_line
		(start 425.812712 -2.890774)
		(end 426.212762 -2.890774)
		(stroke
			(width 0.05715)
			(type default)
		)
		(layer "F.Cu")
	)
	(gr_arc
		(start 425.928536 -31.289244)
		(mid 425.789464 -31.195993)
		(end 425.62526 -31.16326)
		(stroke
			(width 0.050038)
			(type default)
		)
		(layer "F.Cu")
	)
	(gr_line
		(start 425.928536 -31.289244)
		(end 425.929044 -31.289752)
		(stroke
			(width 0.050038)
			(type default)
		)
		(layer "F.Cu")
	)
	(gr_line
		(start 425.928536 -30.49016)
		(end 425.929044 -30.489652)
		(stroke
			(width 0.050038)
			(type default)
		)
		(layer "F.Cu")
	)
	(gr_arc
		(start 425.988734 -33.233106)
		(mid 426.138766 -33.12486)
		(end 426.083222 -32.948372)
		(stroke
			(width 0.050038)
			(type default)
		)
		(layer "F.Cu")
	)
	(gr_arc
		(start 426.056044 -33.728152)
		(mid 426.01408 -33.700162)
		(end 425.964604 -33.690306)
		(stroke
			(width 0.050038)
			(type default)
		)
		(layer "F.Cu")
	)
	(gr_line
		(start 426.056044 -32.928052)
		(end 426.083222 -32.948372)
		(stroke
			(width 0.050038)
			(type default)
		)
		(layer "F.Cu")
	)
	(gr_line
		(start 426.074586 -3.69824)
		(end 426.074586 -4.386072)
		(stroke
			(width 0.05715)
			(type default)
		)
		(layer "F.Cu")
	)
	(gr_line
		(start 426.074586 -3.69824)
		(end 426.30217 -3.470656)
		(stroke
			(width 0.05715)
			(type default)
		)
		(layer "F.Cu")
	)
	(gr_line
		(start 426.212762 -2.890774)
		(end 426.275246 -2.953258)
		(stroke
			(width 0.05715)
			(type default)
		)
		(layer "F.Cu")
	)
	(gr_line
		(start 426.620178 -2.953258)
		(end 426.682662 -2.890774)
		(stroke
			(width 0.05715)
			(type default)
		)
		(layer "F.Cu")
	)
	(gr_line
		(start 426.630592 -10.023348)
		(end 427.009052 -10.023348)
		(stroke
			(width 0.05715)
			(type default)
		)
		(layer "F.Cu")
	)
	(gr_line
		(start 426.647102 -3.470656)
		(end 426.874686 -3.69824)
		(stroke
			(width 0.05715)
			(type default)
		)
		(layer "F.Cu")
	)
	(gr_line
		(start 426.682662 -2.890774)
		(end 427.082712 -2.890774)
		(stroke
			(width 0.05715)
			(type default)
		)
		(layer "F.Cu")
	)
	(gr_line
		(start 426.874686 -8.657336)
		(end 427.10227 -8.88492)
		(stroke
			(width 0.05715)
			(type default)
		)
		(layer "F.Cu")
	)
	(gr_line
		(start 426.874686 -7.789672)
		(end 426.874686 -8.657336)
		(stroke
			(width 0.05715)
			(type default)
		)
		(layer "F.Cu")
	)
	(gr_line
		(start 426.874686 -3.69824)
		(end 426.874686 -4.386072)
		(stroke
			(width 0.05715)
			(type default)
		)
		(layer "F.Cu")
	)
	(gr_line
		(start 427.009052 -10.023348)
		(end 427.106334 -9.926066)
		(stroke
			(width 0.05715)
			(type default)
		)
		(layer "F.Cu")
	)
	(gr_line
		(start 427.447202 -8.88492)
		(end 427.674786 -8.657336)
		(stroke
			(width 0.05715)
			(type default)
		)
		(layer "F.Cu")
	)
	(gr_line
		(start 427.451266 -9.926066)
		(end 427.548548 -10.023348)
		(stroke
			(width 0.05715)
			(type default)
		)
		(layer "F.Cu")
	)
	(gr_line
		(start 427.548548 -10.023348)
		(end 427.900592 -10.023348)
		(stroke
			(width 0.05715)
			(type default)
		)
		(layer "F.Cu")
	)
	(gr_line
		(start 427.674786 -7.789672)
		(end 427.674786 -8.657336)
		(stroke
			(width 0.05715)
			(type default)
		)
		(layer "F.Cu")
	)
	(gr_line
		(start 428.230792 -2.72415)
		(end 428.631604 -2.72415)
		(stroke
			(width 0.05715)
			(type default)
		)
		(layer "F.Cu")
	)
	(gr_line
		(start 428.474886 -3.69824)
		(end 428.474886 -4.386072)
		(stroke
			(width 0.05715)
			(type default)
		)
		(layer "F.Cu")
	)
	(gr_line
		(start 428.474886 -3.69824)
		(end 428.70247 -3.470656)
		(stroke
			(width 0.05715)
			(type default)
		)
		(layer "F.Cu")
	)
	(gr_line
		(start 428.631604 -2.72415)
		(end 428.706534 -2.79908)
		(stroke
			(width 0.05715)
			(type default)
		)
		(layer "F.Cu")
	)
	(gr_line
		(start 429.030892 -10.023348)
		(end 429.371252 -10.023348)
		(stroke
			(width 0.05715)
			(type default)
		)
		(layer "F.Cu")
	)
	(gr_line
		(start 429.047402 -3.470656)
		(end 429.274986 -3.69824)
		(stroke
			(width 0.05715)
			(type default)
		)
		(layer "F.Cu")
	)
	(gr_line
		(start 429.051466 -2.79908)
		(end 429.126396 -2.72415)
		(stroke
			(width 0.05715)
			(type default)
		)
		(layer "F.Cu")
	)
	(gr_line
		(start 429.126396 -2.72415)
		(end 429.500792 -2.72415)
		(stroke
			(width 0.05715)
			(type default)
		)
		(layer "F.Cu")
	)
	(gr_line
		(start 429.274986 -8.657336)
		(end 429.50257 -8.88492)
		(stroke
			(width 0.05715)
			(type default)
		)
		(layer "F.Cu")
	)
	(gr_line
		(start 429.274986 -7.789672)
		(end 429.274986 -8.657336)
		(stroke
			(width 0.05715)
			(type default)
		)
		(layer "F.Cu")
	)
	(gr_line
		(start 429.274986 -3.69824)
		(end 429.274986 -4.386072)
		(stroke
			(width 0.05715)
			(type default)
		)
		(layer "F.Cu")
	)
	(gr_line
		(start 429.371252 -10.023348)
		(end 429.481234 -9.913366)
		(stroke
			(width 0.05715)
			(type default)
		)
		(layer "F.Cu")
	)
	(gr_line
		(start 429.826166 -9.913366)
		(end 429.936148 -10.023348)
		(stroke
			(width 0.05715)
			(type default)
		)
		(layer "F.Cu")
	)
	(gr_line
		(start 429.847502 -8.88492)
		(end 430.075086 -8.657336)
		(stroke
			(width 0.05715)
			(type default)
		)
		(layer "F.Cu")
	)
	(gr_line
		(start 429.936148 -10.023348)
		(end 430.300892 -10.023348)
		(stroke
			(width 0.05715)
			(type default)
		)
		(layer "F.Cu")
	)
	(gr_line
		(start 430.075086 -7.789672)
		(end 430.075086 -8.657336)
		(stroke
			(width 0.05715)
			(type default)
		)
		(layer "F.Cu")
	)
	(gr_arc
		(start 430.117758 -34.640774)
		(mid 430.365569 -34.602202)
		(end 430.589944 -34.490152)
		(stroke
			(width 0.050038)
			(type default)
		)
		(layer "F.Cu")
	)
	(gr_line
		(start 430.5808 -2.874518)
		(end 430.937162 -2.874518)
		(stroke
			(width 0.05715)
			(type default)
		)
		(layer "F.Cu")
	)
	(gr_arc
		(start 430.589944 -35.290252)
		(mid 430.372676 -35.14788)
		(end 430.117758 -35.097974)
		(stroke
			(width 0.050038)
			(type default)
		)
		(layer "F.Cu")
	)
	(gr_line
		(start 430.875186 -3.69316)
		(end 430.875186 -4.386072)
		(stroke
			(width 0.05715)
			(type default)
		)
		(layer "F.Cu")
	)
	(gr_line
		(start 430.875186 -3.69316)
		(end 431.070258 -3.498088)
		(stroke
			(width 0.05715)
			(type default)
		)
		(layer "F.Cu")
	)
	(gr_line
		(start 430.937162 -2.874518)
		(end 431.048922 -2.986278)
		(stroke
			(width 0.05715)
			(type default)
		)
		(layer "F.Cu")
	)
	(gr_line
		(start 431.393854 -2.986278)
		(end 431.505614 -2.874518)
		(stroke
			(width 0.05715)
			(type default)
		)
		(layer "F.Cu")
	)
	(gr_line
		(start 431.41519 -3.498088)
		(end 431.675286 -3.758184)
		(stroke
			(width 0.05715)
			(type default)
		)
		(layer "F.Cu")
	)
	(gr_line
		(start 431.505614 -2.874518)
		(end 431.8508 -2.874518)
		(stroke
			(width 0.05715)
			(type default)
		)
		(layer "F.Cu")
	)
	(gr_line
		(start 431.615342 -10.078466)
		(end 431.830734 -10.078466)
		(stroke
			(width 0.05715)
			(type default)
		)
		(layer "F.Cu")
	)
	(gr_line
		(start 431.675286 -8.657336)
		(end 431.90287 -8.88492)
		(stroke
			(width 0.05715)
			(type default)
		)
		(layer "F.Cu")
	)
	(gr_line
		(start 431.675286 -7.789672)
		(end 431.675286 -8.657336)
		(stroke
			(width 0.05715)
			(type default)
		)
		(layer "F.Cu")
	)
	(gr_line
		(start 431.675286 -3.758184)
		(end 431.675286 -4.386072)
		(stroke
			(width 0.05715)
			(type default)
		)
		(layer "F.Cu")
	)
	(gr_line
		(start 431.830734 -10.078466)
		(end 431.932334 -9.976866)
		(stroke
			(width 0.05715)
			(type default)
		)
		(layer "F.Cu")
	)
	(gr_line
		(start 431.888392 -138.844782)
		(end 432.080924 -138.844782)
		(stroke
			(width 0.05715)
			(type default)
		)
		(layer "F.Cu")
	)
	(gr_arc
		(start 431.990754 -139.9667)
		(mid 432.452698 -139.775356)
		(end 432.644042 -139.313412)
		(stroke
			(width 0.05715)
			(type default)
		)
		(layer "F.Cu")
	)
	(gr_arc
		(start 431.990754 -139.7254)
		(mid 432.282107 -139.604749)
		(end 432.402742 -139.313412)
		(stroke
			(width 0.05715)
			(type default)
		)
		(layer "F.Cu")
	)
	(gr_line
		(start 432.247802 -8.88492)
		(end 432.475386 -8.657336)
		(stroke
			(width 0.05715)
			(type default)
		)
		(layer "F.Cu")
	)
	(gr_line
		(start 432.277266 -9.976866)
		(end 432.378866 -10.078466)
		(stroke
			(width 0.05715)
			(type default)
		)
		(layer "F.Cu")
	)
	(gr_line
		(start 432.378866 -10.078466)
		(end 432.580542 -10.078466)
		(stroke
			(width 0.05715)
			(type default)
		)
		(layer "F.Cu")
	)
	(gr_arc
		(start 432.402742 -139.1666)
		(mid 432.308485 -138.939032)
		(end 432.080924 -138.844782)
		(stroke
			(width 0.05715)
			(type default)
		)
		(layer "F.Cu")
	)
	(gr_line
		(start 432.475386 -7.789672)
		(end 432.475386 -8.657336)
		(stroke
			(width 0.05715)
			(type default)
		)
		(layer "F.Cu")
	)
	(gr_arc
		(start 432.96586 -138.844782)
		(mid 432.738326 -138.939054)
		(end 432.644042 -139.1666)
		(stroke
			(width 0.05715)
			(type default)
		)
		(layer "F.Cu")
	)
	(gr_line
		(start 432.96586 -138.844782)
		(end 433.158392 -138.844782)
		(stroke
			(width 0.05715)
			(type default)
		)
		(layer "F.Cu")
	)
	(gr_line
		(start 433.011834 -2.860294)
		(end 433.37988 -2.860294)
		(stroke
			(width 0.05715)
			(type default)
		)
		(layer "F.Cu")
	)
	(gr_line
		(start 433.275486 -3.758184)
		(end 433.275486 -4.386072)
		(stroke
			(width 0.05715)
			(type default)
		)
		(layer "F.Cu")
	)
	(gr_line
		(start 433.275486 -3.758184)
		(end 433.50307 -3.5306)
		(stroke
			(width 0.05715)
			(type default)
		)
		(layer "F.Cu")
	)
	(gr_line
		(start 433.37988 -2.860294)
		(end 433.493926 -2.97434)
		(stroke
			(width 0.05715)
			(type default)
		)
		(layer "F.Cu")
	)
	(gr_line
		(start 433.838858 -2.97434)
		(end 433.952904 -2.860294)
		(stroke
			(width 0.05715)
			(type default)
		)
		(layer "F.Cu")
	)
	(gr_line
		(start 433.848002 -3.5306)
		(end 434.075586 -3.758184)
		(stroke
			(width 0.05715)
			(type default)
		)
		(layer "F.Cu")
	)
	(gr_line
		(start 433.952904 -2.860294)
		(end 434.281834 -2.860294)
		(stroke
			(width 0.05715)
			(type default)
		)
		(layer "F.Cu")
	)
	(gr_line
		(start 433.961032 -9.9949)
		(end 434.1241 -9.9949)
		(stroke
			(width 0.05715)
			(type default)
		)
		(layer "F.Cu")
	)
	(gr_line
		(start 434.075586 -8.657336)
		(end 434.30317 -8.88492)
		(stroke
			(width 0.05715)
			(type default)
		)
		(layer "F.Cu")
	)
	(gr_line
		(start 434.075586 -7.789672)
		(end 434.075586 -8.657336)
		(stroke
			(width 0.05715)
			(type default)
		)
		(layer "F.Cu")
	)
	(gr_line
		(start 434.075586 -3.758184)
		(end 434.075586 -4.386072)
		(stroke
			(width 0.05715)
			(type default)
		)
		(layer "F.Cu")
	)
	(gr_line
		(start 434.1241 -9.9949)
		(end 434.256434 -9.862566)
		(stroke
			(width 0.05715)
			(type default)
		)
		(layer "F.Cu")
	)
	(gr_line
		(start 434.601366 -9.862566)
		(end 434.7337 -9.9949)
		(stroke
			(width 0.05715)
			(type default)
		)
		(layer "F.Cu")
	)
	(gr_line
		(start 434.648102 -8.88492)
		(end 434.875686 -8.657336)
		(stroke
			(width 0.05715)
			(type default)
		)
		(layer "F.Cu")
	)
	(gr_line
		(start 434.7337 -9.9949)
		(end 434.926232 -9.9949)
		(stroke
			(width 0.05715)
			(type default)
		)
		(layer "F.Cu")
	)
	(gr_line
		(start 434.875686 -7.789672)
		(end 434.875686 -8.657336)
		(stroke
			(width 0.05715)
			(type default)
		)
		(layer "F.Cu")
	)
	(gr_line
		(start 435.431438 -2.83972)
		(end 435.818788 -2.83972)
		(stroke
			(width 0.05715)
			(type default)
		)
		(layer "F.Cu")
	)
	(gr_line
		(start 435.675786 -3.758184)
		(end 435.675786 -4.386072)
		(stroke
			(width 0.05715)
			(type default)
		)
		(layer "F.Cu")
	)
	(gr_line
		(start 435.675786 -3.758184)
		(end 435.90337 -3.5306)
		(stroke
			(width 0.05715)
			(type default)
		)
		(layer "F.Cu")
	)
	(gr_line
		(start 435.818788 -2.83972)
		(end 435.887622 -2.908554)
		(stroke
			(width 0.05715)
			(type default)
		)
		(layer "F.Cu")
	)
	(gr_line
		(start 436.232554 -2.908554)
		(end 436.301388 -2.83972)
		(stroke
			(width 0.05715)
			(type default)
		)
		(layer "F.Cu")
	)
	(gr_line
		(start 436.248302 -3.5306)
		(end 436.475886 -3.758184)
		(stroke
			(width 0.05715)
			(type default)
		)
		(layer "F.Cu")
	)
	(gr_line
		(start 436.301388 -2.83972)
		(end 436.701438 -2.83972)
		(stroke
			(width 0.05715)
			(type default)
		)
		(layer "F.Cu")
	)
	(gr_line
		(start 436.361332 -10.12952)
		(end 436.55488 -10.12952)
		(stroke
			(width 0.05715)
			(type default)
		)
		(layer "F.Cu")
	)
	(gr_line
		(start 436.475886 -8.657336)
		(end 436.70347 -8.88492)
		(stroke
			(width 0.05715)
			(type default)
		)
		(layer "F.Cu")
	)
	(gr_line
		(start 436.475886 -7.789672)
		(end 436.475886 -8.657336)
		(stroke
			(width 0.05715)
			(type default)
		)
		(layer "F.Cu")
	)
	(gr_line
		(start 436.475886 -3.758184)
		(end 436.475886 -4.386072)
		(stroke
			(width 0.05715)
			(type default)
		)
		(layer "F.Cu")
	)
	(gr_line
		(start 436.55488 -10.12952)
		(end 436.669434 -10.014966)
		(stroke
			(width 0.05715)
			(type default)
		)
		(layer "F.Cu")
	)
	(gr_line
		(start 437.014366 -10.014966)
		(end 437.12892 -10.12952)
		(stroke
			(width 0.05715)
			(type default)
		)
		(layer "F.Cu")
	)
	(gr_line
		(start 437.048402 -8.88492)
		(end 437.275986 -8.657336)
		(stroke
			(width 0.05715)
			(type default)
		)
		(layer "F.Cu")
	)
	(gr_line
		(start 437.12892 -10.12952)
		(end 437.326532 -10.12952)
		(stroke
			(width 0.05715)
			(type default)
		)
		(layer "F.Cu")
	)
	(gr_line
		(start 437.275986 -7.789672)
		(end 437.275986 -8.657336)
		(stroke
			(width 0.05715)
			(type default)
		)
		(layer "F.Cu")
	)
	(gr_line
		(start 437.32196 -32.632396)
		(end 437.721756 -33.0327)
		(stroke
			(width 0.050038)
			(type default)
		)
		(layer "F.Cu")
	)
	(gr_line
		(start 437.721756 -32.2326)
		(end 438.12206 -32.632396)
		(stroke
			(width 0.050038)
			(type default)
		)
		(layer "F.Cu")
	)
	(gr_line
		(start 437.721756 -25.8318)
		(end 438.12206 -26.232104)
		(stroke
			(width 0.0508)
			(type default)
		)
		(layer "F.Cu")
	)
	(gr_line
		(start 437.721756 -25.0317)
		(end 438.12206 -25.432004)
		(stroke
			(width 0.0508)
			(type default)
		)
		(layer "F.Cu")
	)
	(gr_line
		(start 437.814212 -2.890774)
		(end 438.195974 -2.890774)
		(stroke
			(width 0.05715)
			(type default)
		)
		(layer "F.Cu")
	)
	(gr_line
		(start 438.076086 -3.758184)
		(end 438.076086 -4.386072)
		(stroke
			(width 0.05715)
			(type default)
		)
		(layer "F.Cu")
	)
	(gr_line
		(start 438.076086 -3.758184)
		(end 438.30367 -3.5306)
		(stroke
			(width 0.05715)
			(type default)
		)
		(layer "F.Cu")
	)
	(gr_line
		(start 438.12206 -26.232104)
		(end 438.12206 -26.232612)
		(stroke
			(width 0.0508)
			(type default)
		)
		(layer "F.Cu")
	)
	(gr_line
		(start 438.12206 -25.432004)
		(end 438.12206 -25.432512)
		(stroke
			(width 0.0508)
			(type default)
		)
		(layer "F.Cu")
	)
	(gr_line
		(start 438.195974 -2.890774)
		(end 438.282334 -2.977134)
		(stroke
			(width 0.05715)
			(type default)
		)
		(layer "F.Cu")
	)
	(gr_line
		(start 438.627266 -2.977134)
		(end 438.713626 -2.890774)
		(stroke
			(width 0.05715)
			(type default)
		)
		(layer "F.Cu")
	)
	(gr_line
		(start 438.648602 -3.5306)
		(end 438.876186 -3.758184)
		(stroke
			(width 0.05715)
			(type default)
		)
		(layer "F.Cu")
	)
	(gr_line
		(start 438.707022 -44.83735)
		(end 439.040016 -44.83735)
		(stroke
			(width 0.05715)
			(type default)
		)
		(layer "F.Cu")
	)
	(gr_line
		(start 438.713626 -2.890774)
		(end 439.084212 -2.890774)
		(stroke
			(width 0.05715)
			(type default)
		)
		(layer "F.Cu")
	)
	(gr_line
		(start 438.755282 -10.02411)
		(end 438.98947 -10.02411)
		(stroke
			(width 0.05715)
			(type default)
		)
		(layer "F.Cu")
	)
	(gr_line
		(start 438.876186 -8.657336)
		(end 439.10377 -8.88492)
		(stroke
			(width 0.05715)
			(type default)
		)
		(layer "F.Cu")
	)
	(gr_line
		(start 438.876186 -7.789672)
		(end 438.876186 -8.657336)
		(stroke
			(width 0.05715)
			(type default)
		)
		(layer "F.Cu")
	)
	(gr_line
		(start 438.876186 -3.758184)
		(end 438.876186 -4.386072)
		(stroke
			(width 0.05715)
			(type default)
		)
		(layer "F.Cu")
	)
	(gr_line
		(start 438.940956 -46.26229)
		(end 438.940956 -47.481998)
		(stroke
			(width 0.05715)
			(type default)
		)
		(layer "F.Cu")
	)
	(gr_line
		(start 438.940956 -46.26229)
		(end 439.171334 -46.031912)
		(stroke
			(width 0.05715)
			(type default)
		)
		(layer "F.Cu")
	)
	(gr_line
		(start 438.98947 -10.02411)
		(end 439.101484 -9.912096)
		(stroke
			(width 0.05715)
			(type default)
		)
		(layer "F.Cu")
	)
	(gr_line
		(start 439.040016 -44.83735)
		(end 439.169556 -44.96689)
		(stroke
			(width 0.05715)
			(type default)
		)
		(layer "F.Cu")
	)
	(gr_line
		(start 439.446416 -9.912096)
		(end 439.55843 -10.02411)
		(stroke
			(width 0.05715)
			(type default)
		)
		(layer "F.Cu")
	)
	(gr_line
		(start 439.448702 -8.88492)
		(end 439.676286 -8.657336)
		(stroke
			(width 0.05715)
			(type default)
		)
		(layer "F.Cu")
	)
	(gr_line
		(start 439.514488 -44.96689)
		(end 439.644028 -44.83735)
		(stroke
			(width 0.05715)
			(type default)
		)
		(layer "F.Cu")
	)
	(gr_line
		(start 439.516266 -46.031912)
		(end 439.742072 -46.257718)
		(stroke
			(width 0.05715)
			(type default)
		)
		(layer "F.Cu")
	)
	(gr_line
		(start 439.55843 -10.02411)
		(end 439.720482 -10.02411)
		(stroke
			(width 0.05715)
			(type default)
		)
		(layer "F.Cu")
	)
	(gr_line
		(start 439.644028 -44.83735)
		(end 439.977022 -44.83735)
		(stroke
			(width 0.05715)
			(type default)
		)
		(layer "F.Cu")
	)
	(gr_line
		(start 439.676286 -7.789672)
		(end 439.676286 -8.657336)
		(stroke
			(width 0.05715)
			(type default)
		)
		(layer "F.Cu")
	)
	(gr_line
		(start 439.741056 -47.481998)
		(end 439.742072 -47.481998)
		(stroke
			(width 0.05715)
			(type default)
		)
		(layer "F.Cu")
	)
	(gr_line
		(start 439.742072 -46.257718)
		(end 439.742072 -47.481998)
		(stroke
			(width 0.05715)
			(type default)
		)
		(layer "F.Cu")
	)
	(gr_line
		(start 440.224672 -5.667248)
		(end 440.603132 -5.667248)
		(stroke
			(width 0.05715)
			(type default)
		)
		(layer "F.Cu")
	)
	(gr_line
		(start 440.325002 -49.981104)
		(end 440.714892 -49.981104)
		(stroke
			(width 0.05715)
			(type default)
		)
		(layer "F.Cu")
	)
	(gr_line
		(start 440.476386 -5.132832)
		(end 440.686952 -5.343398)
		(stroke
			(width 0.05715)
			(type default)
		)
		(layer "F.Cu")
	)
	(gr_line
		(start 440.476386 -4.386072)
		(end 440.476386 -5.132832)
		(stroke
			(width 0.05715)
			(type default)
		)
		(layer "F.Cu")
	)
	(gr_line
		(start 440.540902 -51.009804)
		(end 440.540902 -51.875944)
		(stroke
			(width 0.05715)
			(type default)
		)
		(layer "F.Cu")
	)
	(gr_line
		(start 440.540902 -51.009804)
		(end 440.762898 -50.787808)
		(stroke
			(width 0.05715)
			(type default)
		)
		(layer "F.Cu")
	)
	(gr_line
		(start 440.603132 -5.667248)
		(end 440.686952 -5.583428)
		(stroke
			(width 0.05715)
			(type default)
		)
		(layer "F.Cu")
	)
	(gr_line
		(start 440.686952 -5.343398)
		(end 440.686952 -5.583428)
		(stroke
			(width 0.05715)
			(type default)
		)
		(layer "F.Cu")
	)
	(gr_line
		(start 440.714892 -49.981104)
		(end 440.782456 -50.048668)
		(stroke
			(width 0.05715)
			(type default)
		)
		(layer "F.Cu")
	)
	(gr_line
		(start 440.922156 -29.8323)
		(end 441.321952 -30.232096)
		(stroke
			(width 0.0508)
			(type default)
		)
		(layer "F.Cu")
	)
	(gr_line
		(start 441.06211 -5.582158)
		(end 441.1472 -5.667248)
		(stroke
			(width 0.05715)
			(type default)
		)
		(layer "F.Cu")
	)
	(gr_line
		(start 441.06211 -5.36448)
		(end 441.06211 -5.582158)
		(stroke
			(width 0.05715)
			(type default)
		)
		(layer "F.Cu")
	)
	(gr_line
		(start 441.06211 -5.36448)
		(end 441.276486 -5.150104)
		(stroke
			(width 0.05715)
			(type default)
		)
		(layer "F.Cu")
	)
	(gr_line
		(start 441.10783 -50.787808)
		(end 441.341002 -51.02098)
		(stroke
			(width 0.05715)
			(type default)
		)
		(layer "F.Cu")
	)
	(gr_line
		(start 441.1218 -10.0584)
		(end 441.2742 -10.0584)
		(stroke
			(width 0.05715)
			(type default)
		)
		(layer "F.Cu")
	)
	(gr_line
		(start 441.127388 -50.048668)
		(end 441.194952 -49.981104)
		(stroke
			(width 0.05715)
			(type default)
		)
		(layer "F.Cu")
	)
	(gr_line
		(start 441.1472 -5.667248)
		(end 441.494672 -5.667248)
		(stroke
			(width 0.05715)
			(type default)
		)
		(layer "F.Cu")
	)
	(gr_line
		(start 441.1726 -123.88977)
		(end 441.57265 -123.88977)
		(stroke
			(width 0.05715)
			(type default)
		)
		(layer "F.Cu")
	)
	(gr_line
		(start 441.194952 -49.981104)
		(end 441.595002 -49.981104)
		(stroke
			(width 0.05715)
			(type default)
		)
		(layer "F.Cu")
	)
	(gr_line
		(start 441.2742 -10.0584)
		(end 441.470034 -9.862566)
		(stroke
			(width 0.05715)
			(type default)
		)
		(layer "F.Cu")
	)
	(gr_line
		(start 441.276486 -8.657336)
		(end 441.473082 -8.853932)
		(stroke
			(width 0.05715)
			(type default)
		)
		(layer "F.Cu")
	)
	(gr_line
		(start 441.276486 -7.789672)
		(end 441.276486 -8.657336)
		(stroke
			(width 0.05715)
			(type default)
		)
		(layer "F.Cu")
	)
	(gr_line
		(start 441.276486 -4.386072)
		(end 441.276486 -5.150104)
		(stroke
			(width 0.05715)
			(type default)
		)
		(layer "F.Cu")
	)
	(gr_line
		(start 441.321952 -30.232096)
		(end 441.321952 -30.232604)
		(stroke
			(width 0.0508)
			(type default)
		)
		(layer "F.Cu")
	)
	(gr_line
		(start 441.321952 -29.432504)
		(end 441.32246 -29.432504)
		(stroke
			(width 0.0508)
			(type default)
		)
		(layer "F.Cu")
	)
	(gr_line
		(start 441.32246 -29.432504)
		(end 441.722256 -29.8323)
		(stroke
			(width 0.0508)
			(type default)
		)
		(layer "F.Cu")
	)
	(gr_line
		(start 441.341002 -51.02098)
		(end 441.341002 -51.875944)
		(stroke
			(width 0.05715)
			(type default)
		)
		(layer "F.Cu")
	)
	(gr_line
		(start 441.39993 -118.343934)
		(end 441.400946 -118.342918)
		(stroke
			(width 0.05715)
			(type default)
		)
		(layer "F.Cu")
	)
	(gr_line
		(start 441.39993 -118.343934)
		(end 441.627514 -118.571518)
		(stroke
			(width 0.05715)
			(type default)
		)
		(layer "F.Cu")
	)
	(gr_line
		(start 441.400946 -116.993162)
		(end 441.400946 -118.342918)
		(stroke
			(width 0.05715)
			(type default)
		)
		(layer "F.Cu")
	)
	(gr_line
		(start 441.57265 -123.88977)
		(end 441.635134 -123.827286)
		(stroke
			(width 0.05715)
			(type default)
		)
		(layer "F.Cu")
	)
	(gr_line
		(start 441.814966 -9.862566)
		(end 441.981844 -10.029444)
		(stroke
			(width 0.05715)
			(type default)
		)
		(layer "F.Cu")
	)
	(gr_line
		(start 441.818014 -8.853932)
		(end 442.076586 -8.59536)
		(stroke
			(width 0.05715)
			(type default)
		)
		(layer "F.Cu")
	)
	(gr_line
		(start 441.907168 -44.83735)
		(end 442.240162 -44.83735)
		(stroke
			(width 0.05715)
			(type default)
		)
		(layer "F.Cu")
	)
	(gr_line
		(start 441.972446 -118.571518)
		(end 442.200792 -118.343172)
		(stroke
			(width 0.05715)
			(type default)
		)
		(layer "F.Cu")
	)
	(gr_line
		(start 441.980066 -123.827286)
		(end 442.04255 -123.88977)
		(stroke
			(width 0.05715)
			(type default)
		)
		(layer "F.Cu")
	)
	(gr_line
		(start 441.981844 -10.029444)
		(end 442.111892 -10.029444)
		(stroke
			(width 0.05715)
			(type default)
		)
		(layer "F.Cu")
	)
	(gr_line
		(start 442.04255 -123.88977)
		(end 442.4426 -123.88977)
		(stroke
			(width 0.05715)
			(type default)
		)
		(layer "F.Cu")
	)
	(gr_line
		(start 442.076586 -7.789672)
		(end 442.076586 -8.59536)
		(stroke
			(width 0.05715)
			(type default)
		)
		(layer "F.Cu")
	)
	(gr_line
		(start 442.141102 -47.481998)
		(end 442.142118 -47.481998)
		(stroke
			(width 0.05715)
			(type default)
		)
		(layer "F.Cu")
	)
	(gr_line
		(start 442.142118 -46.249082)
		(end 442.142118 -47.481998)
		(stroke
			(width 0.05715)
			(type default)
		)
		(layer "F.Cu")
	)
	(gr_line
		(start 442.142118 -46.249082)
		(end 442.365384 -46.025816)
		(stroke
			(width 0.05715)
			(type default)
		)
		(layer "F.Cu")
	)
	(gr_line
		(start 442.200792 -116.993162)
		(end 442.200792 -118.343172)
		(stroke
			(width 0.05715)
			(type default)
		)
		(layer "F.Cu")
	)
	(gr_line
		(start 442.240162 -44.83735)
		(end 442.369702 -44.96689)
		(stroke
			(width 0.05715)
			(type default)
		)
		(layer "F.Cu")
	)
	(gr_line
		(start 442.710316 -46.025816)
		(end 442.942218 -46.257718)
		(stroke
			(width 0.05715)
			(type default)
		)
		(layer "F.Cu")
	)
	(gr_line
		(start 442.714634 -44.96689)
		(end 442.844174 -44.83735)
		(stroke
			(width 0.05715)
			(type default)
		)
		(layer "F.Cu")
	)
	(gr_line
		(start 442.760608 -5.892038)
		(end 442.995304 -5.892038)
		(stroke
			(width 0.05715)
			(type default)
		)
		(layer "F.Cu")
	)
	(gr_line
		(start 442.764926 -114.403632)
		(end 443.164976 -114.403632)
		(stroke
			(width 0.05715)
			(type default)
		)
		(layer "F.Cu")
	)
	(gr_line
		(start 442.844174 -44.83735)
		(end 443.177168 -44.83735)
		(stroke
			(width 0.05715)
			(type default)
		)
		(layer "F.Cu")
	)
	(gr_line
		(start 442.876686 -4.8895)
		(end 443.128146 -5.14096)
		(stroke
			(width 0.05715)
			(type default)
		)
		(layer "F.Cu")
	)
	(gr_line
		(start 442.876686 -4.386072)
		(end 442.876686 -4.8895)
		(stroke
			(width 0.05715)
			(type default)
		)
		(layer "F.Cu")
	)
	(gr_line
		(start 442.940948 -47.481998)
		(end 442.942218 -47.480728)
		(stroke
			(width 0.05715)
			(type default)
		)
		(layer "F.Cu")
	)
	(gr_line
		(start 442.942218 -46.257718)
		(end 442.942218 -47.480728)
		(stroke
			(width 0.05715)
			(type default)
		)
		(layer "F.Cu")
	)
	(gr_line
		(start 442.995304 -5.892038)
		(end 443.184534 -5.702808)
		(stroke
			(width 0.05715)
			(type default)
		)
		(layer "F.Cu")
	)
	(gr_line
		(start 442.999876 -113.556288)
		(end 443.22746 -113.783872)
		(stroke
			(width 0.05715)
			(type default)
		)
		(layer "F.Cu")
	)
	(gr_line
		(start 442.999876 -112.205516)
		(end 442.999876 -113.556288)
		(stroke
			(width 0.05715)
			(type default)
		)
		(layer "F.Cu")
	)
	(gr_line
		(start 442.999876 -112.205516)
		(end 443.000892 -112.205516)
		(stroke
			(width 0.05715)
			(type default)
		)
		(layer "F.Cu")
	)
	(gr_line
		(start 443.164976 -114.403632)
		(end 443.22746 -114.341148)
		(stroke
			(width 0.05715)
			(type default)
		)
		(layer "F.Cu")
	)
	(gr_line
		(start 443.473078 -5.14096)
		(end 443.676786 -4.937252)
		(stroke
			(width 0.05715)
			(type default)
		)
		(layer "F.Cu")
	)
	(gr_line
		(start 443.504828 -49.998122)
		(end 443.904878 -49.998122)
		(stroke
			(width 0.05715)
			(type default)
		)
		(layer "F.Cu")
	)
	(gr_line
		(start 443.529466 -5.702808)
		(end 443.718696 -5.892038)
		(stroke
			(width 0.05715)
			(type default)
		)
		(layer "F.Cu")
	)
	(gr_line
		(start 443.572392 -114.341148)
		(end 443.634876 -114.403632)
		(stroke
			(width 0.05715)
			(type default)
		)
		(layer "F.Cu")
	)
	(gr_line
		(start 443.572392 -113.783872)
		(end 443.799976 -113.556288)
		(stroke
			(width 0.05715)
			(type default)
		)
		(layer "F.Cu")
	)
	(gr_line
		(start 443.6237 -9.12495)
		(end 443.83325 -9.12495)
		(stroke
			(width 0.05715)
			(type default)
		)
		(layer "F.Cu")
	)
	(gr_line
		(start 443.634876 -114.403632)
		(end 444.034926 -114.403632)
		(stroke
			(width 0.05715)
			(type default)
		)
		(layer "F.Cu")
	)
	(gr_line
		(start 443.676786 -8.47344)
		(end 443.883034 -8.679688)
		(stroke
			(width 0.05715)
			(type default)
		)
		(layer "F.Cu")
	)
	(gr_line
		(start 443.676786 -7.789672)
		(end 443.676786 -8.47344)
		(stroke
			(width 0.05715)
			(type default)
		)
		(layer "F.Cu")
	)
	(gr_line
		(start 443.676786 -4.386072)
		(end 443.676786 -4.937252)
		(stroke
			(width 0.05715)
			(type default)
		)
		(layer "F.Cu")
	)
	(gr_line
		(start 443.718696 -5.892038)
		(end 444.030608 -5.892038)
		(stroke
			(width 0.05715)
			(type default)
		)
		(layer "F.Cu")
	)
	(gr_line
		(start 443.741048 -51.875944)
		(end 443.742064 -51.875944)
		(stroke
			(width 0.05715)
			(type default)
		)
		(layer "F.Cu")
	)
	(gr_line
		(start 443.742064 -50.765202)
		(end 443.742064 -51.875944)
		(stroke
			(width 0.05715)
			(type default)
		)
		(layer "F.Cu")
	)
	(gr_line
		(start 443.742064 -50.765202)
		(end 443.955678 -50.551588)
		(stroke
			(width 0.05715)
			(type default)
		)
		(layer "F.Cu")
	)
	(gr_line
		(start 443.799976 -112.205516)
		(end 443.799976 -113.556288)
		(stroke
			(width 0.05715)
			(type default)
		)
		(layer "F.Cu")
	)
	(gr_line
		(start 443.799976 -112.205516)
		(end 443.800992 -112.205516)
		(stroke
			(width 0.05715)
			(type default)
		)
		(layer "F.Cu")
	)
	(gr_line
		(start 443.83325 -9.12495)
		(end 443.895734 -9.062466)
		(stroke
			(width 0.05715)
			(type default)
		)
		(layer "F.Cu")
	)
	(gr_line
		(start 443.904878 -49.998122)
		(end 443.967362 -50.060606)
		(stroke
			(width 0.05715)
			(type default)
		)
		(layer "F.Cu")
	)
	(gr_line
		(start 444.227966 -8.679688)
		(end 444.476886 -8.430768)
		(stroke
			(width 0.05715)
			(type default)
		)
		(layer "F.Cu")
	)
	(gr_line
		(start 444.240666 -9.062466)
		(end 444.30315 -9.12495)
		(stroke
			(width 0.05715)
			(type default)
		)
		(layer "F.Cu")
	)
	(gr_line
		(start 444.30061 -50.551588)
		(end 444.540894 -50.791872)
		(stroke
			(width 0.05715)
			(type default)
		)
		(layer "F.Cu")
	)
	(gr_line
		(start 444.30315 -9.12495)
		(end 444.5635 -9.12495)
		(stroke
			(width 0.05715)
			(type default)
		)
		(layer "F.Cu")
	)
	(gr_line
		(start 444.312294 -50.060606)
		(end 444.374778 -49.998122)
		(stroke
			(width 0.05715)
			(type default)
		)
		(layer "F.Cu")
	)
	(gr_line
		(start 444.3222 -123.91517)
		(end 444.616586 -123.91517)
		(stroke
			(width 0.05715)
			(type default)
		)
		(layer "F.Cu")
	)
	(gr_line
		(start 444.374778 -49.998122)
		(end 444.774828 -49.998122)
		(stroke
			(width 0.05715)
			(type default)
		)
		(layer "F.Cu")
	)
	(gr_line
		(start 444.476886 -7.789672)
		(end 444.476886 -8.430768)
		(stroke
			(width 0.05715)
			(type default)
		)
		(layer "F.Cu")
	)
	(gr_line
		(start 444.540894 -50.791872)
		(end 444.540894 -51.875944)
		(stroke
			(width 0.05715)
			(type default)
		)
		(layer "F.Cu")
	)
	(gr_line
		(start 444.599822 -118.343934)
		(end 444.600838 -118.342918)
		(stroke
			(width 0.05715)
			(type default)
		)
		(layer "F.Cu")
	)
	(gr_line
		(start 444.599822 -118.343934)
		(end 444.827406 -118.571518)
		(stroke
			(width 0.05715)
			(type default)
		)
		(layer "F.Cu")
	)
	(gr_line
		(start 444.600838 -116.993162)
		(end 444.600838 -118.342918)
		(stroke
			(width 0.05715)
			(type default)
		)
		(layer "F.Cu")
	)
	(gr_line
		(start 444.616586 -123.91517)
		(end 444.79591 -123.735846)
		(stroke
			(width 0.05715)
			(type default)
		)
		(layer "F.Cu")
	)
	(gr_line
		(start 445.008 -9.87171)
		(end 445.431672 -10.079482)
		(stroke
			(width 0.05715)
			(type default)
		)
		(layer "F.Cu")
	)
	(gr_line
		(start 445.10706 -44.83735)
		(end 445.440054 -44.83735)
		(stroke
			(width 0.05715)
			(type default)
		)
		(layer "F.Cu")
	)
	(gr_line
		(start 445.140842 -123.735846)
		(end 445.320166 -123.91517)
		(stroke
			(width 0.05715)
			(type default)
		)
		(layer "F.Cu")
	)
	(gr_line
		(start 445.172338 -118.571518)
		(end 445.400938 -118.342918)
		(stroke
			(width 0.05715)
			(type default)
		)
		(layer "F.Cu")
	)
	(gr_line
		(start 445.320166 -123.91517)
		(end 445.5922 -123.91517)
		(stroke
			(width 0.05715)
			(type default)
		)
		(layer "F.Cu")
	)
	(gr_line
		(start 445.340994 -47.481998)
		(end 445.34201 -47.481998)
		(stroke
			(width 0.05715)
			(type default)
		)
		(layer "F.Cu")
	)
	(gr_line
		(start 445.34201 -46.36389)
		(end 445.34201 -47.481998)
		(stroke
			(width 0.05715)
			(type default)
		)
		(layer "F.Cu")
	)
	(gr_line
		(start 445.34201 -46.36389)
		(end 445.628268 -46.077378)
		(stroke
			(width 0.05715)
			(type default)
		)
		(layer "F.Cu")
	)
	(gr_line
		(start 445.400938 -116.993162)
		(end 445.400938 -118.342918)
		(stroke
			(width 0.05715)
			(type default)
		)
		(layer "F.Cu")
	)
	(gr_line
		(start 445.440054 -44.83735)
		(end 445.569594 -44.96689)
		(stroke
			(width 0.05715)
			(type default)
		)
		(layer "F.Cu")
	)
	(gr_line
		(start 445.646048 -10.698734)
		(end 445.653414 -10.72007)
		(stroke
			(width 0.05715)
			(type default)
		)
		(layer "F.Cu")
	)
	(gr_line
		(start 445.653414 -10.72007)
		(end 445.669416 -10.736072)
		(stroke
			(width 0.05715)
			(type default)
		)
		(layer "F.Cu")
	)
	(gr_line
		(start 445.664336 -9.999472)
		(end 445.8716 -9.5758)
		(stroke
			(width 0.05715)
			(type default)
		)
		(layer "F.Cu")
	)
	(gr_line
		(start 445.848232 -10.914888)
		(end 446.055496 -11.122152)
		(stroke
			(width 0.05715)
			(type default)
		)
		(layer "F.Cu")
	)
	(gr_line
		(start 445.87414 -46.065186)
		(end 446.141094 -46.33214)
		(stroke
			(width 0.05715)
			(type default)
		)
		(layer "F.Cu")
	)
	(gr_line
		(start 445.910716 -60.378848)
		(end 446.216024 -60.378848)
		(stroke
			(width 0.0508)
			(type default)
		)
		(layer "F.Cu")
	)
	(gr_line
		(start 445.914526 -44.96689)
		(end 446.044066 -44.83735)
		(stroke
			(width 0.05715)
			(type default)
		)
		(layer "F.Cu")
	)
	(gr_line
		(start 445.964818 -114.403632)
		(end 446.375028 -114.403632)
		(stroke
			(width 0.05715)
			(type default)
		)
		(layer "F.Cu")
	)
	(gr_line
		(start 445.998092 -10.719816)
		(end 446.156334 -10.719816)
		(stroke
			(width 0.05715)
			(type default)
		)
		(layer "F.Cu")
	)
	(gr_line
		(start 446.044066 -44.83735)
		(end 446.37706 -44.83735)
		(stroke
			(width 0.05715)
			(type default)
		)
		(layer "F.Cu")
	)
	(gr_line
		(start 446.141094 -46.33214)
		(end 446.141094 -47.481998)
		(stroke
			(width 0.05715)
			(type default)
		)
		(layer "F.Cu")
	)
	(gr_line
		(start 446.149984 -60.965334)
		(end 446.149984 -62.00267)
		(stroke
			(width 0.0508)
			(type default)
		)
		(layer "F.Cu")
	)
	(gr_line
		(start 446.149984 -60.965334)
		(end 446.2272 -60.888118)
		(stroke
			(width 0.0508)
			(type default)
		)
		(layer "F.Cu")
	)
	(gr_line
		(start 446.156334 -10.719816)
		(end 446.39865 -10.962386)
		(stroke
			(width 0.05715)
			(type default)
		)
		(layer "F.Cu")
	)
	(gr_line
		(start 446.199768 -113.556288)
		(end 446.427352 -113.783872)
		(stroke
			(width 0.05715)
			(type default)
		)
		(layer "F.Cu")
	)
	(gr_line
		(start 446.199768 -112.205516)
		(end 446.199768 -113.556288)
		(stroke
			(width 0.05715)
			(type default)
		)
		(layer "F.Cu")
	)
	(gr_line
		(start 446.199768 -112.205516)
		(end 446.200784 -112.205516)
		(stroke
			(width 0.05715)
			(type default)
		)
		(layer "F.Cu")
	)
	(gr_line
		(start 446.216024 -60.378848)
		(end 446.221104 -60.383928)
		(stroke
			(width 0.0508)
			(type default)
		)
		(layer "F.Cu")
	)
	(gr_line
		(start 446.25133 -8.700008)
		(end 446.561464 -8.389874)
		(stroke
			(width 0.05715)
			(type default)
		)
		(layer "F.Cu")
	)
	(gr_line
		(start 446.25133 -7.734808)
		(end 446.561464 -8.044942)
		(stroke
			(width 0.05715)
			(type default)
		)
		(layer "F.Cu")
	)
	(gr_line
		(start 446.275968 -5.081778)
		(end 446.535556 -4.82219)
		(stroke
			(width 0.05715)
			(type default)
		)
		(layer "F.Cu")
	)
	(gr_line
		(start 446.375028 -114.403632)
		(end 446.427352 -114.351308)
		(stroke
			(width 0.05715)
			(type default)
		)
		(layer "F.Cu")
	)
	(gr_line
		(start 446.39865 -10.962386)
		(end 446.39865 -11.120374)
		(stroke
			(width 0.05715)
			(type default)
		)
		(layer "F.Cu")
	)
	(gr_line
		(start 446.701672 -49.998122)
		(end 447.09461 -49.998122)
		(stroke
			(width 0.05715)
			(type default)
		)
		(layer "F.Cu")
	)
	(gr_line
		(start 446.772284 -114.351308)
		(end 446.824608 -114.403632)
		(stroke
			(width 0.05715)
			(type default)
		)
		(layer "F.Cu")
	)
	(gr_line
		(start 446.772284 -113.783872)
		(end 446.999868 -113.556288)
		(stroke
			(width 0.05715)
			(type default)
		)
		(layer "F.Cu")
	)
	(gr_line
		(start 446.779396 -4.654804)
		(end 447.216022 -5.09143)
		(stroke
			(width 0.05715)
			(type default)
		)
		(layer "F.Cu")
	)
	(gr_line
		(start 446.824608 -114.403632)
		(end 447.234818 -114.403632)
		(stroke
			(width 0.05715)
			(type default)
		)
		(layer "F.Cu")
	)
	(gr_line
		(start 446.872868 -60.383928)
		(end 446.877948 -60.378848)
		(stroke
			(width 0.0508)
			(type default)
		)
		(layer "F.Cu")
	)
	(gr_line
		(start 446.877948 -60.378848)
		(end 447.180716 -60.378848)
		(stroke
			(width 0.0508)
			(type default)
		)
		(layer "F.Cu")
	)
	(gr_line
		(start 446.878964 -60.888118)
		(end 446.950084 -60.959238)
		(stroke
			(width 0.0508)
			(type default)
		)
		(layer "F.Cu")
	)
	(gr_line
		(start 446.88633 -8.095488)
		(end 446.932558 -8.141716)
		(stroke
			(width 0.05715)
			(type default)
		)
		(layer "F.Cu")
	)
	(gr_line
		(start 446.93078 -3.257804)
		(end 446.989962 -3.198622)
		(stroke
			(width 0.05715)
			(type default)
		)
		(layer "F.Cu")
	)
	(gr_line
		(start 446.932558 -3.600958)
		(end 447.0908 -3.600958)
		(stroke
			(width 0.05715)
			(type default)
		)
		(layer "F.Cu")
	)
	(gr_line
		(start 446.94094 -50.766472)
		(end 446.94094 -51.875944)
		(stroke
			(width 0.05715)
			(type default)
		)
		(layer "F.Cu")
	)
	(gr_line
		(start 446.94094 -50.766472)
		(end 447.155824 -50.551588)
		(stroke
			(width 0.05715)
			(type default)
		)
		(layer "F.Cu")
	)
	(gr_line
		(start 446.950084 -60.959238)
		(end 446.950084 -62.00267)
		(stroke
			(width 0.0508)
			(type default)
		)
		(layer "F.Cu")
	)
	(gr_line
		(start 446.98666 -11.36396)
		(end 447.09842 -11.2522)
		(stroke
			(width 0.05715)
			(type default)
		)
		(layer "F.Cu")
	)
	(gr_line
		(start 446.999868 -112.205516)
		(end 446.999868 -113.556288)
		(stroke
			(width 0.05715)
			(type default)
		)
		(layer "F.Cu")
	)
	(gr_line
		(start 446.999868 -112.205516)
		(end 447.000884 -112.205516)
		(stroke
			(width 0.05715)
			(type default)
		)
		(layer "F.Cu")
	)
	(gr_line
		(start 447.0908 -3.600958)
		(end 447.333116 -3.358388)
		(stroke
			(width 0.05715)
			(type default)
		)
		(layer "F.Cu")
	)
	(gr_line
		(start 447.09461 -49.998122)
		(end 447.16065 -50.064162)
		(stroke
			(width 0.05715)
			(type default)
		)
		(layer "F.Cu")
	)
	(gr_line
		(start 447.09842 -11.2522)
		(end 447.44132 -11.2522)
		(stroke
			(width 0.05715)
			(type default)
		)
		(layer "F.Cu")
	)
	(gr_line
		(start 447.21018 -8.761222)
		(end 447.565526 -9.116568)
		(stroke
			(width 0.05715)
			(type default)
		)
		(layer "F.Cu")
	)
	(gr_line
		(start 447.22796 -11.6078)
		(end 447.31178 -11.6078)
		(stroke
			(width 0.05715)
			(type default)
		)
		(layer "F.Cu")
	)
	(gr_line
		(start 447.333116 -3.2004)
		(end 447.333116 -3.358388)
		(stroke
			(width 0.05715)
			(type default)
		)
		(layer "F.Cu")
	)
	(gr_line
		(start 447.360294 -8.56615)
		(end 447.518282 -8.56615)
		(stroke
			(width 0.05715)
			(type default)
		)
		(layer "F.Cu")
	)
	(gr_line
		(start 447.44132 -11.2522)
		(end 447.55308 -11.36396)
		(stroke
			(width 0.05715)
			(type default)
		)
		(layer "F.Cu")
	)
	(gr_line
		(start 447.4718 -120.81637)
		(end 447.87185 -120.81637)
		(stroke
			(width 0.05715)
			(type default)
		)
		(layer "F.Cu")
	)
	(gr_line
		(start 447.500756 -50.551588)
		(end 447.74231 -50.793142)
		(stroke
			(width 0.05715)
			(type default)
		)
		(layer "F.Cu")
	)
	(gr_line
		(start 447.505582 -50.064162)
		(end 447.571622 -49.998122)
		(stroke
			(width 0.05715)
			(type default)
		)
		(layer "F.Cu")
	)
	(gr_line
		(start 447.518282 -8.56615)
		(end 447.760598 -8.80872)
		(stroke
			(width 0.05715)
			(type default)
		)
		(layer "F.Cu")
	)
	(gr_line
		(start 447.571622 -49.998122)
		(end 447.971672 -49.998122)
		(stroke
			(width 0.05715)
			(type default)
		)
		(layer "F.Cu")
	)
	(gr_line
		(start 447.577464 -2.61112)
		(end 447.636646 -2.551938)
		(stroke
			(width 0.05715)
			(type default)
		)
		(layer "F.Cu")
	)
	(gr_line
		(start 447.579242 -2.954274)
		(end 447.737484 -2.954274)
		(stroke
			(width 0.05715)
			(type default)
		)
		(layer "F.Cu")
	)
	(gr_line
		(start 447.737484 -2.954274)
		(end 447.9798 -2.711704)
		(stroke
			(width 0.05715)
			(type default)
		)
		(layer "F.Cu")
	)
	(gr_line
		(start 447.74104 -50.794412)
		(end 447.74104 -51.875944)
		(stroke
			(width 0.05715)
			(type default)
		)
		(layer "F.Cu")
	)
	(gr_line
		(start 447.74104 -50.794412)
		(end 447.74231 -50.793142)
		(stroke
			(width 0.05715)
			(type default)
		)
		(layer "F.Cu")
	)
	(gr_line
		(start 447.760598 -8.80872)
		(end 447.760598 -8.966962)
		(stroke
			(width 0.05715)
			(type default)
		)
		(layer "F.Cu")
	)
	(gr_line
		(start 447.799968 -118.343934)
		(end 447.800984 -118.342918)
		(stroke
			(width 0.05715)
			(type default)
		)
		(layer "F.Cu")
	)
	(gr_line
		(start 447.799968 -118.343934)
		(end 448.027552 -118.571518)
		(stroke
			(width 0.05715)
			(type default)
		)
		(layer "F.Cu")
	)
	(gr_line
		(start 447.800984 -116.993162)
		(end 447.800984 -118.342918)
		(stroke
			(width 0.05715)
			(type default)
		)
		(layer "F.Cu")
	)
	(gr_line
		(start 447.857626 -9.408668)
		(end 447.902838 -9.454134)
		(stroke
			(width 0.05715)
			(type default)
		)
		(layer "F.Cu")
	)
	(gr_line
		(start 447.87185 -120.81637)
		(end 447.934334 -120.753886)
		(stroke
			(width 0.05715)
			(type default)
		)
		(layer "F.Cu")
	)
	(gr_line
		(start 447.89344 -6.09854)
		(end 448.192144 -5.799836)
		(stroke
			(width 0.05715)
			(type default)
		)
		(layer "F.Cu")
	)
	(gr_line
		(start 447.90106 -11.36396)
		(end 448.01282 -11.2522)
		(stroke
			(width 0.05715)
			(type default)
		)
		(layer "F.Cu")
	)
	(gr_line
		(start 447.9798 -2.553716)
		(end 447.9798 -2.711704)
		(stroke
			(width 0.05715)
			(type default)
		)
		(layer "F.Cu")
	)
	(gr_line
		(start 447.98615 -119.692928)
		(end 447.990976 -119.68099)
		(stroke
			(width 0.05715)
			(type default)
		)
		(layer "F.Cu")
	)
	(gr_line
		(start 448.01282 -11.2522)
		(end 448.35572 -11.2522)
		(stroke
			(width 0.05715)
			(type default)
		)
		(layer "F.Cu")
	)
	(gr_line
		(start 448.14236 -11.6078)
		(end 448.22618 -11.6078)
		(stroke
			(width 0.05715)
			(type default)
		)
		(layer "F.Cu")
	)
	(gr_line
		(start 448.24523 -5.078984)
		(end 448.24523 -5.162804)
		(stroke
			(width 0.05715)
			(type default)
		)
		(layer "F.Cu")
	)
	(gr_line
		(start 448.24523 -4.164584)
		(end 448.24523 -4.248404)
		(stroke
			(width 0.05715)
			(type default)
		)
		(layer "F.Cu")
	)
	(gr_line
		(start 448.279266 -120.753886)
		(end 448.34175 -120.81637)
		(stroke
			(width 0.05715)
			(type default)
		)
		(layer "F.Cu")
	)
	(gr_line
		(start 448.306952 -44.83735)
		(end 448.639946 -44.83735)
		(stroke
			(width 0.05715)
			(type default)
		)
		(layer "F.Cu")
	)
	(gr_line
		(start 448.315842 -119.527574)
		(end 448.320668 -119.515636)
		(stroke
			(width 0.05715)
			(type default)
		)
		(layer "F.Cu")
	)
	(gr_line
		(start 448.34175 -120.81637)
		(end 448.7418 -120.81637)
		(stroke
			(width 0.05715)
			(type default)
		)
		(layer "F.Cu")
	)
	(gr_line
		(start 448.348354 -9.210294)
		(end 448.460114 -9.098534)
		(stroke
			(width 0.05715)
			(type default)
		)
		(layer "F.Cu")
	)
	(gr_line
		(start 448.35572 -11.2522)
		(end 448.46748 -11.36396)
		(stroke
			(width 0.05715)
			(type default)
		)
		(layer "F.Cu")
	)
	(gr_line
		(start 448.372484 -118.571518)
		(end 448.60083 -118.343172)
		(stroke
			(width 0.05715)
			(type default)
		)
		(layer "F.Cu")
	)
	(gr_line
		(start 448.386708 -2.31013)
		(end 448.498468 -2.42189)
		(stroke
			(width 0.05715)
			(type default)
		)
		(layer "F.Cu")
	)
	(gr_line
		(start 448.460114 -9.098534)
		(end 448.803014 -9.098534)
		(stroke
			(width 0.05715)
			(type default)
		)
		(layer "F.Cu")
	)
	(gr_line
		(start 448.48907 -5.404104)
		(end 448.60083 -5.292344)
		(stroke
			(width 0.05715)
			(type default)
		)
		(layer "F.Cu")
	)
	(gr_line
		(start 448.48907 -4.837684)
		(end 448.60083 -4.949444)
		(stroke
			(width 0.05715)
			(type default)
		)
		(layer "F.Cu")
	)
	(gr_line
		(start 448.48907 -4.489704)
		(end 448.60083 -4.377944)
		(stroke
			(width 0.05715)
			(type default)
		)
		(layer "F.Cu")
	)
	(gr_line
		(start 448.48907 -3.923284)
		(end 448.60083 -4.035044)
		(stroke
			(width 0.05715)
			(type default)
		)
		(layer "F.Cu")
	)
	(gr_line
		(start 448.498468 -2.42189)
		(end 448.841368 -2.42189)
		(stroke
			(width 0.05715)
			(type default)
		)
		(layer "F.Cu")
	)
	(gr_line
		(start 448.536822 -5.799836)
		(end 448.835526 -6.09854)
		(stroke
			(width 0.05715)
			(type default)
		)
		(layer "F.Cu")
	)
	(gr_line
		(start 448.540886 -46.163484)
		(end 448.540886 -47.481998)
		(stroke
			(width 0.05715)
			(type default)
		)
		(layer "F.Cu")
	)
	(gr_line
		(start 448.540886 -46.163484)
		(end 448.741546 -45.962824)
		(stroke
			(width 0.05715)
			(type default)
		)
		(layer "F.Cu")
	)
	(gr_line
		(start 448.589654 -9.454134)
		(end 448.673474 -9.454134)
		(stroke
			(width 0.05715)
			(type default)
		)
		(layer "F.Cu")
	)
	(gr_line
		(start 448.60083 -116.993162)
		(end 448.60083 -118.343172)
		(stroke
			(width 0.05715)
			(type default)
		)
		(layer "F.Cu")
	)
	(gr_line
		(start 448.60083 -4.949444)
		(end 448.60083 -5.292344)
		(stroke
			(width 0.05715)
			(type default)
		)
		(layer "F.Cu")
	)
	(gr_line
		(start 448.60083 -4.035044)
		(end 448.60083 -4.377944)
		(stroke
			(width 0.05715)
			(type default)
		)
		(layer "F.Cu")
	)
	(gr_line
		(start 448.628008 -2.06629)
		(end 448.711828 -2.06629)
		(stroke
			(width 0.05715)
			(type default)
		)
		(layer "F.Cu")
	)
	(gr_line
		(start 448.639946 -44.83735)
		(end 448.769486 -44.96689)
		(stroke
			(width 0.05715)
			(type default)
		)
		(layer "F.Cu")
	)
	(gr_line
		(start 448.730878 -3.150362)
		(end 448.888612 -2.992628)
		(stroke
			(width 0.05715)
			(type default)
		)
		(layer "F.Cu")
	)
	(gr_line
		(start 448.732656 -3.493516)
		(end 448.890644 -3.493516)
		(stroke
			(width 0.05715)
			(type default)
		)
		(layer "F.Cu")
	)
	(gr_line
		(start 448.803014 -9.098534)
		(end 448.914774 -9.210294)
		(stroke
			(width 0.05715)
			(type default)
		)
		(layer "F.Cu")
	)
	(gr_line
		(start 448.81546 -11.36396)
		(end 448.92722 -11.2522)
		(stroke
			(width 0.05715)
			(type default)
		)
		(layer "F.Cu")
	)
	(gr_line
		(start 448.841368 -2.42189)
		(end 448.953128 -2.31013)
		(stroke
			(width 0.05715)
			(type default)
		)
		(layer "F.Cu")
	)
	(gr_line
		(start 448.888612 -2.992628)
		(end 448.889374 -2.992628)
		(stroke
			(width 0.05715)
			(type default)
		)
		(layer "F.Cu")
	)
	(gr_line
		(start 448.890644 -3.493516)
		(end 449.133214 -3.2512)
		(stroke
			(width 0.05715)
			(type default)
		)
		(layer "F.Cu")
	)
	(gr_line
		(start 448.894454 -2.992628)
		(end 448.894962 -2.992628)
		(stroke
			(width 0.05715)
			(type default)
		)
		(layer "F.Cu")
	)
	(gr_line
		(start 448.92722 -11.2522)
		(end 449.27012 -11.2522)
		(stroke
			(width 0.05715)
			(type default)
		)
		(layer "F.Cu")
	)
	(gr_line
		(start 449.05676 -11.6078)
		(end 449.14058 -11.6078)
		(stroke
			(width 0.05715)
			(type default)
		)
		(layer "F.Cu")
	)
	(gr_line
		(start 449.086224 -45.962824)
		(end 449.342002 -46.218602)
		(stroke
			(width 0.05715)
			(type default)
		)
		(layer "F.Cu")
	)
	(gr_line
		(start 449.114418 -44.96689)
		(end 449.243958 -44.83735)
		(stroke
			(width 0.05715)
			(type default)
		)
		(layer "F.Cu")
	)
	(gr_line
		(start 449.133214 -3.236468)
		(end 449.133214 -3.2512)
		(stroke
			(width 0.05715)
			(type default)
		)
		(layer "F.Cu")
	)
	(gr_line
		(start 449.133214 -3.095752)
		(end 449.133214 -3.231388)
		(stroke
			(width 0.05715)
			(type default)
		)
		(layer "F.Cu")
	)
	(gr_line
		(start 449.164964 -114.403632)
		(end 449.542408 -114.403632)
		(stroke
			(width 0.05715)
			(type default)
		)
		(layer "F.Cu")
	)
	(gr_line
		(start 449.243958 -44.83735)
		(end 449.576952 -44.83735)
		(stroke
			(width 0.05715)
			(type default)
		)
		(layer "F.Cu")
	)
	(gr_line
		(start 449.262754 -9.210294)
		(end 449.374514 -9.098534)
		(stroke
			(width 0.05715)
			(type default)
		)
		(layer "F.Cu")
	)
	(gr_line
		(start 449.27012 -11.2522)
		(end 449.38188 -11.36396)
		(stroke
			(width 0.05715)
			(type default)
		)
		(layer "F.Cu")
	)
	(gr_line
		(start 449.301108 -2.31013)
		(end 449.412868 -2.42189)
		(stroke
			(width 0.05715)
			(type default)
		)
		(layer "F.Cu")
	)
	(gr_line
		(start 449.340986 -47.481998)
		(end 449.342002 -47.481998)
		(stroke
			(width 0.05715)
			(type default)
		)
		(layer "F.Cu")
	)
	(gr_line
		(start 449.342002 -46.218602)
		(end 449.342002 -47.481998)
		(stroke
			(width 0.05715)
			(type default)
		)
		(layer "F.Cu")
	)
	(gr_line
		(start 449.374514 -9.098534)
		(end 449.717414 -9.098534)
		(stroke
			(width 0.05715)
			(type default)
		)
		(layer "F.Cu")
	)
	(gr_line
		(start 449.399914 -113.556288)
		(end 449.627498 -113.783872)
		(stroke
			(width 0.05715)
			(type default)
		)
		(layer "F.Cu")
	)
	(gr_line
		(start 449.399914 -112.205516)
		(end 449.399914 -113.556288)
		(stroke
			(width 0.05715)
			(type default)
		)
		(layer "F.Cu")
	)
	(gr_line
		(start 449.399914 -112.205516)
		(end 449.40093 -112.205516)
		(stroke
			(width 0.05715)
			(type default)
		)
		(layer "F.Cu")
	)
	(gr_line
		(start 449.411852 -2.983992)
		(end 449.523612 -3.095752)
		(stroke
			(width 0.05715)
			(type default)
		)
		(layer "F.Cu")
	)
	(gr_line
		(start 449.412868 -2.42189)
		(end 449.755768 -2.42189)
		(stroke
			(width 0.05715)
			(type default)
		)
		(layer "F.Cu")
	)
	(gr_line
		(start 449.504054 -9.454134)
		(end 449.587874 -9.454134)
		(stroke
			(width 0.05715)
			(type default)
		)
		(layer "F.Cu")
	)
	(gr_line
		(start 449.523612 -3.095752)
		(end 449.866512 -3.095752)
		(stroke
			(width 0.05715)
			(type default)
		)
		(layer "F.Cu")
	)
	(gr_line
		(start 449.542408 -114.403632)
		(end 449.627498 -114.318542)
		(stroke
			(width 0.05715)
			(type default)
		)
		(layer "F.Cu")
	)
	(gr_line
		(start 449.542408 -2.06629)
		(end 449.626228 -2.06629)
		(stroke
			(width 0.05715)
			(type default)
		)
		(layer "F.Cu")
	)
	(gr_line
		(start 449.653152 -2.740152)
		(end 449.736972 -2.740152)
		(stroke
			(width 0.05715)
			(type default)
		)
		(layer "F.Cu")
	)
	(gr_line
		(start 449.717414 -9.098534)
		(end 449.829174 -9.210294)
		(stroke
			(width 0.05715)
			(type default)
		)
		(layer "F.Cu")
	)
	(gr_line
		(start 449.72986 -11.36396)
		(end 449.84162 -11.2522)
		(stroke
			(width 0.05715)
			(type default)
		)
		(layer "F.Cu")
	)
	(gr_line
		(start 449.755768 -2.42189)
		(end 449.867528 -2.31013)
		(stroke
			(width 0.05715)
			(type default)
		)
		(layer "F.Cu")
	)
	(gr_line
		(start 449.84162 -11.2522)
		(end 450.18452 -11.2522)
		(stroke
			(width 0.05715)
			(type default)
		)
		(layer "F.Cu")
	)
	(gr_line
		(start 449.866512 -3.095752)
		(end 449.978272 -2.983992)
		(stroke
			(width 0.05715)
			(type default)
		)
		(layer "F.Cu")
	)
	(gr_line
		(start 449.895214 -49.997614)
		(end 450.295264 -49.997614)
		(stroke
			(width 0.05715)
			(type default)
		)
		(layer "F.Cu")
	)
	(gr_line
		(start 449.97116 -11.6078)
		(end 450.05498 -11.6078)
		(stroke
			(width 0.05715)
			(type default)
		)
		(layer "F.Cu")
	)
	(gr_line
		(start 449.97243 -114.318542)
		(end 450.05752 -114.403632)
		(stroke
			(width 0.05715)
			(type default)
		)
		(layer "F.Cu")
	)
	(gr_line
		(start 449.97243 -113.783872)
		(end 450.200014 -113.556288)
		(stroke
			(width 0.05715)
			(type default)
		)
		(layer "F.Cu")
	)
	(gr_line
		(start 450.05752 -114.403632)
		(end 450.434964 -114.403632)
		(stroke
			(width 0.05715)
			(type default)
		)
		(layer "F.Cu")
	)
	(gr_line
		(start 450.077078 -3.638296)
		(end 450.077078 -4.386072)
		(stroke
			(width 0.05715)
			(type default)
		)
		(layer "F.Cu")
	)
	(gr_line
		(start 450.077078 -3.638296)
		(end 450.120512 -3.594862)
		(stroke
			(width 0.05715)
			(type default)
		)
		(layer "F.Cu")
	)
	(gr_line
		(start 450.120512 -3.594862)
		(end 450.488304 -3.594862)
		(stroke
			(width 0.05715)
			(type default)
		)
		(layer "F.Cu")
	)
	(gr_line
		(start 450.141086 -51.061366)
		(end 450.141086 -51.875944)
		(stroke
			(width 0.05715)
			(type default)
		)
		(layer "F.Cu")
	)
	(gr_line
		(start 450.141086 -51.061366)
		(end 450.364098 -50.838354)
		(stroke
			(width 0.05715)
			(type default)
		)
		(layer "F.Cu")
	)
	(gr_line
		(start 450.18452 -11.2522)
		(end 450.29628 -11.36396)
		(stroke
			(width 0.05715)
			(type default)
		)
		(layer "F.Cu")
	)
	(gr_line
		(start 450.200014 -112.205516)
		(end 450.200014 -113.556288)
		(stroke
			(width 0.05715)
			(type default)
		)
		(layer "F.Cu")
	)
	(gr_line
		(start 450.200014 -112.205516)
		(end 450.20103 -112.205516)
		(stroke
			(width 0.05715)
			(type default)
		)
		(layer "F.Cu")
	)
	(gr_line
		(start 450.215508 -2.31013)
		(end 450.327268 -2.42189)
		(stroke
			(width 0.05715)
			(type default)
		)
		(layer "F.Cu")
	)
	(gr_line
		(start 450.295264 -49.997614)
		(end 450.357748 -50.060098)
		(stroke
			(width 0.05715)
			(type default)
		)
		(layer "F.Cu")
	)
	(gr_line
		(start 450.327268 -2.42189)
		(end 450.670168 -2.42189)
		(stroke
			(width 0.05715)
			(type default)
		)
		(layer "F.Cu")
	)
	(gr_line
		(start 450.456808 -2.06629)
		(end 450.540628 -2.06629)
		(stroke
			(width 0.05715)
			(type default)
		)
		(layer "F.Cu")
	)
	(gr_line
		(start 450.488304 -3.594862)
		(end 450.56933 -3.513836)
		(stroke
			(width 0.05715)
			(type default)
		)
		(layer "F.Cu")
	)
	(gr_line
		(start 450.56933 -3.274568)
		(end 450.56933 -3.513836)
		(stroke
			(width 0.05715)
			(type default)
		)
		(layer "F.Cu")
	)
	(gr_line
		(start 450.670168 -2.42189)
		(end 450.781928 -2.31013)
		(stroke
			(width 0.05715)
			(type default)
		)
		(layer "F.Cu")
	)
	(gr_line
		(start 450.6722 -120.66397)
		(end 451.07225 -120.66397)
		(stroke
			(width 0.05715)
			(type default)
		)
		(layer "F.Cu")
	)
	(gr_line
		(start 450.70268 -50.060098)
		(end 450.765164 -49.997614)
		(stroke
			(width 0.05715)
			(type default)
		)
		(layer "F.Cu")
	)
	(gr_line
		(start 450.70903 -50.838354)
		(end 450.940932 -51.070256)
		(stroke
			(width 0.05715)
			(type default)
		)
		(layer "F.Cu")
	)
	(gr_line
		(start 450.765164 -49.997614)
		(end 451.165214 -49.997614)
		(stroke
			(width 0.05715)
			(type default)
		)
		(layer "F.Cu")
	)
	(gr_line
		(start 450.877178 -8.657336)
		(end 451.104762 -8.88492)
		(stroke
			(width 0.05715)
			(type default)
		)
		(layer "F.Cu")
	)
	(gr_line
		(start 450.877178 -7.789672)
		(end 450.877178 -8.657336)
		(stroke
			(width 0.05715)
			(type default)
		)
		(layer "F.Cu")
	)
	(gr_line
		(start 450.877178 -3.237484)
		(end 450.877178 -4.386072)
		(stroke
			(width 0.05715)
			(type default)
		)
		(layer "F.Cu")
	)
	(gr_line
		(start 450.940932 -51.070256)
		(end 450.940932 -51.875944)
		(stroke
			(width 0.05715)
			(type default)
		)
		(layer "F.Cu")
	)
	(gr_line
		(start 450.99986 -118.343934)
		(end 451.000876 -118.342918)
		(stroke
			(width 0.05715)
			(type default)
		)
		(layer "F.Cu")
	)
	(gr_line
		(start 450.99986 -118.343934)
		(end 451.227444 -118.571518)
		(stroke
			(width 0.05715)
			(type default)
		)
		(layer "F.Cu")
	)
	(gr_line
		(start 451.000876 -116.993162)
		(end 451.000876 -118.342918)
		(stroke
			(width 0.05715)
			(type default)
		)
		(layer "F.Cu")
	)
	(gr_line
		(start 451.07225 -120.66397)
		(end 451.134734 -120.601486)
		(stroke
			(width 0.05715)
			(type default)
		)
		(layer "F.Cu")
	)
	(gr_line
		(start 451.129908 -2.31013)
		(end 451.241668 -2.42189)
		(stroke
			(width 0.05715)
			(type default)
		)
		(layer "F.Cu")
	)
	(gr_line
		(start 451.18655 -119.678958)
		(end 451.191376 -119.66702)
		(stroke
			(width 0.05715)
			(type default)
		)
		(layer "F.Cu")
	)
	(gr_line
		(start 451.241668 -2.42189)
		(end 451.584568 -2.42189)
		(stroke
			(width 0.05715)
			(type default)
		)
		(layer "F.Cu")
	)
	(gr_line
		(start 451.371208 -2.06629)
		(end 451.455028 -2.06629)
		(stroke
			(width 0.05715)
			(type default)
		)
		(layer "F.Cu")
	)
	(gr_line
		(start 451.407022 -10.962386)
		(end 451.407022 -11.120374)
		(stroke
			(width 0.05715)
			(type default)
		)
		(layer "F.Cu")
	)
	(gr_line
		(start 451.407022 -10.962386)
		(end 451.649338 -10.719816)
		(stroke
			(width 0.05715)
			(type default)
		)
		(layer "F.Cu")
	)
	(gr_line
		(start 451.449694 -8.88492)
		(end 451.677278 -8.657336)
		(stroke
			(width 0.05715)
			(type default)
		)
		(layer "F.Cu")
	)
	(gr_line
		(start 451.479666 -120.601486)
		(end 451.54215 -120.66397)
		(stroke
			(width 0.05715)
			(type default)
		)
		(layer "F.Cu")
	)
	(gr_line
		(start 451.507098 -44.83735)
		(end 451.840092 -44.83735)
		(stroke
			(width 0.05715)
			(type default)
		)
		(layer "F.Cu")
	)
	(gr_line
		(start 451.515734 -119.514874)
		(end 451.52056 -119.502936)
		(stroke
			(width 0.05715)
			(type default)
		)
		(layer "F.Cu")
	)
	(gr_line
		(start 451.54215 -120.66397)
		(end 451.9422 -120.66397)
		(stroke
			(width 0.05715)
			(type default)
		)
		(layer "F.Cu")
	)
	(gr_line
		(start 451.572376 -118.571518)
		(end 451.800976 -118.342918)
		(stroke
			(width 0.05715)
			(type default)
		)
		(layer "F.Cu")
	)
	(gr_line
		(start 451.584568 -2.42189)
		(end 451.696328 -2.31013)
		(stroke
			(width 0.05715)
			(type default)
		)
		(layer "F.Cu")
	)
	(gr_line
		(start 451.649338 -10.719816)
		(end 451.80758 -10.719816)
		(stroke
			(width 0.05715)
			(type default)
		)
		(layer "F.Cu")
	)
	(gr_line
		(start 451.677278 -7.789672)
		(end 451.677278 -8.657336)
		(stroke
			(width 0.05715)
			(type default)
		)
		(layer "F.Cu")
	)
	(gr_line
		(start 451.741032 -46.163484)
		(end 451.741032 -47.481998)
		(stroke
			(width 0.05715)
			(type default)
		)
		(layer "F.Cu")
	)
	(gr_line
		(start 451.741032 -46.163484)
		(end 451.948042 -45.956474)
		(stroke
			(width 0.05715)
			(type default)
		)
		(layer "F.Cu")
	)
	(gr_line
		(start 451.750176 -11.122152)
		(end 451.809358 -11.06297)
		(stroke
			(width 0.05715)
			(type default)
		)
		(layer "F.Cu")
	)
	(gr_line
		(start 451.800976 -116.993162)
		(end 451.800976 -118.342918)
		(stroke
			(width 0.05715)
			(type default)
		)
		(layer "F.Cu")
	)
	(gr_line
		(start 451.840092 -44.83735)
		(end 451.969632 -44.96689)
		(stroke
			(width 0.05715)
			(type default)
		)
		(layer "F.Cu")
	)
	(gr_line
		(start 452.053452 -10.315702)
		(end 452.053452 -10.473944)
		(stroke
			(width 0.05715)
			(type default)
		)
		(layer "F.Cu")
	)
	(gr_line
		(start 452.053452 -10.315702)
		(end 452.296022 -10.073386)
		(stroke
			(width 0.05715)
			(type default)
		)
		(layer "F.Cu")
	)
	(gr_line
		(start 452.284338 -2.711704)
		(end 452.526654 -2.954274)
		(stroke
			(width 0.05715)
			(type default)
		)
		(layer "F.Cu")
	)
	(gr_line
		(start 452.284338 -2.553716)
		(end 452.284338 -2.711704)
		(stroke
			(width 0.05715)
			(type default)
		)
		(layer "F.Cu")
	)
	(gr_line
		(start 452.29272 -45.956474)
		(end 452.542148 -46.205902)
		(stroke
			(width 0.05715)
			(type default)
		)
		(layer "F.Cu")
	)
	(gr_line
		(start 452.296022 -10.073386)
		(end 452.45401 -10.073386)
		(stroke
			(width 0.05715)
			(type default)
		)
		(layer "F.Cu")
	)
	(gr_line
		(start 452.314564 -44.96689)
		(end 452.444104 -44.83735)
		(stroke
			(width 0.05715)
			(type default)
		)
		(layer "F.Cu")
	)
	(gr_line
		(start 452.364856 -114.403632)
		(end 452.72579 -114.403632)
		(stroke
			(width 0.05715)
			(type default)
		)
		(layer "F.Cu")
	)
	(gr_line
		(start 452.396606 -10.475722)
		(end 452.455788 -10.41654)
		(stroke
			(width 0.05715)
			(type default)
		)
		(layer "F.Cu")
	)
	(gr_line
		(start 452.444104 -44.83735)
		(end 452.777098 -44.83735)
		(stroke
			(width 0.05715)
			(type default)
		)
		(layer "F.Cu")
	)
	(gr_line
		(start 452.477378 -3.758184)
		(end 452.477378 -4.386072)
		(stroke
			(width 0.05715)
			(type default)
		)
		(layer "F.Cu")
	)
	(gr_line
		(start 452.477378 -3.758184)
		(end 452.704962 -3.5306)
		(stroke
			(width 0.05715)
			(type default)
		)
		(layer "F.Cu")
	)
	(gr_line
		(start 452.526654 -2.954274)
		(end 452.684896 -2.954274)
		(stroke
			(width 0.05715)
			(type default)
		)
		(layer "F.Cu")
	)
	(gr_line
		(start 452.541132 -47.481998)
		(end 452.542148 -47.481998)
		(stroke
			(width 0.05715)
			(type default)
		)
		(layer "F.Cu")
	)
	(gr_line
		(start 452.542148 -46.205902)
		(end 452.542148 -47.481998)
		(stroke
			(width 0.05715)
			(type default)
		)
		(layer "F.Cu")
	)
	(gr_line
		(start 452.599806 -113.556288)
		(end 452.82739 -113.783872)
		(stroke
			(width 0.05715)
			(type default)
		)
		(layer "F.Cu")
	)
	(gr_line
		(start 452.599806 -112.205516)
		(end 452.599806 -113.556288)
		(stroke
			(width 0.05715)
			(type default)
		)
		(layer "F.Cu")
	)
	(gr_line
		(start 452.599806 -112.205516)
		(end 452.600822 -112.205516)
		(stroke
			(width 0.05715)
			(type default)
		)
		(layer "F.Cu")
	)
	(gr_line
		(start 452.627492 -2.551938)
		(end 452.686674 -2.61112)
		(stroke
			(width 0.05715)
			(type default)
		)
		(layer "F.Cu")
	)
	(gr_line
		(start 452.700136 -9.669272)
		(end 452.700136 -9.82726)
		(stroke
			(width 0.05715)
			(type default)
		)
		(layer "F.Cu")
	)
	(gr_line
		(start 452.700136 -9.669272)
		(end 452.942452 -9.426702)
		(stroke
			(width 0.05715)
			(type default)
		)
		(layer "F.Cu")
	)
	(gr_line
		(start 452.72579 -114.403632)
		(end 452.82739 -114.302032)
		(stroke
			(width 0.05715)
			(type default)
		)
		(layer "F.Cu")
	)
	(gr_line
		(start 452.942452 -9.426702)
		(end 453.100694 -9.426702)
		(stroke
			(width 0.05715)
			(type default)
		)
		(layer "F.Cu")
	)
	(gr_line
		(start 453.04329 -9.829038)
		(end 453.102472 -9.769856)
		(stroke
			(width 0.05715)
			(type default)
		)
		(layer "F.Cu")
	)
	(gr_line
		(start 453.049894 -3.5306)
		(end 453.277478 -3.758184)
		(stroke
			(width 0.05715)
			(type default)
		)
		(layer "F.Cu")
	)
	(gr_line
		(start 453.095614 -49.997614)
		(end 453.495664 -49.997614)
		(stroke
			(width 0.05715)
			(type default)
		)
		(layer "F.Cu")
	)
	(gr_line
		(start 453.172322 -114.302032)
		(end 453.273922 -114.403632)
		(stroke
			(width 0.05715)
			(type default)
		)
		(layer "F.Cu")
	)
	(gr_line
		(start 453.172322 -113.783872)
		(end 453.399906 -113.556288)
		(stroke
			(width 0.05715)
			(type default)
		)
		(layer "F.Cu")
	)
	(gr_line
		(start 453.273922 -114.403632)
		(end 453.634856 -114.403632)
		(stroke
			(width 0.05715)
			(type default)
		)
		(layer "F.Cu")
	)
	(gr_line
		(start 453.277478 -8.657336)
		(end 453.486266 -8.866124)
		(stroke
			(width 0.05715)
			(type default)
		)
		(layer "F.Cu")
	)
	(gr_line
		(start 453.277478 -7.789672)
		(end 453.277478 -8.657336)
		(stroke
			(width 0.05715)
			(type default)
		)
		(layer "F.Cu")
	)
	(gr_line
		(start 453.277478 -3.758184)
		(end 453.277478 -4.386072)
		(stroke
			(width 0.05715)
			(type default)
		)
		(layer "F.Cu")
	)
	(gr_line
		(start 453.340978 -51.06162)
		(end 453.340978 -51.875944)
		(stroke
			(width 0.05715)
			(type default)
		)
		(layer "F.Cu")
	)
	(gr_line
		(start 453.340978 -51.06162)
		(end 453.564498 -50.8381)
		(stroke
			(width 0.05715)
			(type default)
		)
		(layer "F.Cu")
	)
	(gr_line
		(start 453.399906 -112.205516)
		(end 453.399906 -113.556288)
		(stroke
			(width 0.05715)
			(type default)
		)
		(layer "F.Cu")
	)
	(gr_line
		(start 453.399906 -112.205516)
		(end 453.400922 -112.205516)
		(stroke
			(width 0.05715)
			(type default)
		)
		(layer "F.Cu")
	)
	(gr_line
		(start 453.495664 -49.997614)
		(end 453.558148 -50.060098)
		(stroke
			(width 0.05715)
			(type default)
		)
		(layer "F.Cu")
	)
	(gr_line
		(start 453.760586 -8.974328)
		(end 454.077578 -8.657336)
		(stroke
			(width 0.05715)
			(type default)
		)
		(layer "F.Cu")
	)
	(gr_line
		(start 453.90308 -50.060098)
		(end 453.965564 -49.997614)
		(stroke
			(width 0.05715)
			(type default)
		)
		(layer "F.Cu")
	)
	(gr_line
		(start 453.909176 -50.8381)
		(end 454.141078 -51.070002)
		(stroke
			(width 0.05715)
			(type default)
		)
		(layer "F.Cu")
	)
	(gr_line
		(start 453.965564 -49.997614)
		(end 454.365614 -49.997614)
		(stroke
			(width 0.05715)
			(type default)
		)
		(layer "F.Cu")
	)
	(gr_line
		(start 454.077578 -7.789672)
		(end 454.077578 -8.657336)
		(stroke
			(width 0.05715)
			(type default)
		)
		(layer "F.Cu")
	)
	(gr_line
		(start 454.141078 -51.070002)
		(end 454.141078 -51.875944)
		(stroke
			(width 0.05715)
			(type default)
		)
		(layer "F.Cu")
	)
	(gr_line
		(start 454.200006 -118.343934)
		(end 454.201022 -118.342918)
		(stroke
			(width 0.05715)
			(type default)
		)
		(layer "F.Cu")
	)
	(gr_line
		(start 454.200006 -118.343934)
		(end 454.42759 -118.571518)
		(stroke
			(width 0.05715)
			(type default)
		)
		(layer "F.Cu")
	)
	(gr_line
		(start 454.201022 -116.993162)
		(end 454.201022 -118.342918)
		(stroke
			(width 0.05715)
			(type default)
		)
		(layer "F.Cu")
	)
	(gr_line
		(start 454.479406 -119.331232)
		(end 454.484232 -119.34317)
		(stroke
			(width 0.05715)
			(type default)
		)
		(layer "F.Cu")
	)
	(gr_line
		(start 454.65365 -121.7422)
		(end 454.99782 -121.7422)
		(stroke
			(width 0.05715)
			(type default)
		)
		(layer "F.Cu")
	)
	(gr_line
		(start 454.70699 -44.83735)
		(end 455.039984 -44.83735)
		(stroke
			(width 0.05715)
			(type default)
		)
		(layer "F.Cu")
	)
	(gr_line
		(start 454.772522 -118.571518)
		(end 455.000868 -118.343172)
		(stroke
			(width 0.05715)
			(type default)
		)
		(layer "F.Cu")
	)
	(gr_line
		(start 454.940924 -46.163484)
		(end 454.940924 -47.481998)
		(stroke
			(width 0.05715)
			(type default)
		)
		(layer "F.Cu")
	)
	(gr_line
		(start 454.940924 -46.163484)
		(end 455.141838 -45.96257)
		(stroke
			(width 0.05715)
			(type default)
		)
		(layer "F.Cu")
	)
	(gr_line
		(start 454.99782 -121.7422)
		(end 455.116438 -121.623582)
		(stroke
			(width 0.05715)
			(type default)
		)
		(layer "F.Cu")
	)
	(gr_line
		(start 455.000868 -116.993162)
		(end 455.000868 -118.343172)
		(stroke
			(width 0.05715)
			(type default)
		)
		(layer "F.Cu")
	)
	(gr_line
		(start 455.039984 -44.83735)
		(end 455.131424 -44.92879)
		(stroke
			(width 0.05715)
			(type default)
		)
		(layer "F.Cu")
	)
	(gr_line
		(start 455.403712 -120.93194)
		(end 455.408538 -120.943878)
		(stroke
			(width 0.05715)
			(type default)
		)
		(layer "F.Cu")
	)
	(gr_line
		(start 455.461116 -121.623582)
		(end 455.579734 -121.7422)
		(stroke
			(width 0.05715)
			(type default)
		)
		(layer "F.Cu")
	)
	(gr_line
		(start 455.476356 -44.92879)
		(end 455.567796 -44.83735)
		(stroke
			(width 0.05715)
			(type default)
		)
		(layer "F.Cu")
	)
	(gr_line
		(start 455.486516 -45.96257)
		(end 455.74204 -46.218094)
		(stroke
			(width 0.05715)
			(type default)
		)
		(layer "F.Cu")
	)
	(gr_line
		(start 455.519536 -63.626492)
		(end 455.822304 -63.626492)
		(stroke
			(width 0.0508)
			(type default)
		)
		(layer "F.Cu")
	)
	(gr_line
		(start 455.565002 -114.403632)
		(end 455.934064 -114.403632)
		(stroke
			(width 0.05715)
			(type default)
		)
		(layer "F.Cu")
	)
	(gr_line
		(start 455.567796 -44.83735)
		(end 455.97699 -44.83735)
		(stroke
			(width 0.05715)
			(type default)
		)
		(layer "F.Cu")
	)
	(gr_line
		(start 455.579734 -121.7422)
		(end 455.92365 -121.7422)
		(stroke
			(width 0.05715)
			(type default)
		)
		(layer "F.Cu")
	)
	(gr_line
		(start 455.741024 -47.481998)
		(end 455.74204 -47.481998)
		(stroke
			(width 0.05715)
			(type default)
		)
		(layer "F.Cu")
	)
	(gr_line
		(start 455.74204 -46.218094)
		(end 455.74204 -47.481998)
		(stroke
			(width 0.05715)
			(type default)
		)
		(layer "F.Cu")
	)
	(gr_line
		(start 455.750168 -63.046102)
		(end 455.8157 -63.111634)
		(stroke
			(width 0.0508)
			(type default)
		)
		(layer "F.Cu")
	)
	(gr_line
		(start 455.750168 -62.00267)
		(end 455.750168 -63.046102)
		(stroke
			(width 0.0508)
			(type default)
		)
		(layer "F.Cu")
	)
	(gr_line
		(start 455.799952 -113.556288)
		(end 456.027536 -113.783872)
		(stroke
			(width 0.05715)
			(type default)
		)
		(layer "F.Cu")
	)
	(gr_line
		(start 455.799952 -112.205516)
		(end 455.799952 -113.556288)
		(stroke
			(width 0.05715)
			(type default)
		)
		(layer "F.Cu")
	)
	(gr_line
		(start 455.799952 -112.205516)
		(end 455.800968 -112.205516)
		(stroke
			(width 0.05715)
			(type default)
		)
		(layer "F.Cu")
	)
	(gr_line
		(start 455.822304 -63.626492)
		(end 455.827384 -63.621412)
		(stroke
			(width 0.0508)
			(type default)
		)
		(layer "F.Cu")
	)
	(gr_line
		(start 455.934064 -114.403632)
		(end 456.027536 -114.31016)
		(stroke
			(width 0.05715)
			(type default)
		)
		(layer "F.Cu")
	)
	(gr_line
		(start 456.296014 -49.997614)
		(end 456.696064 -49.997614)
		(stroke
			(width 0.05715)
			(type default)
		)
		(layer "F.Cu")
	)
	(gr_line
		(start 456.372468 -114.31016)
		(end 456.46594 -114.403632)
		(stroke
			(width 0.05715)
			(type default)
		)
		(layer "F.Cu")
	)
	(gr_line
		(start 456.372468 -113.783872)
		(end 456.599798 -113.556542)
		(stroke
			(width 0.05715)
			(type default)
		)
		(layer "F.Cu")
	)
	(gr_line
		(start 456.46594 -114.403632)
		(end 456.835002 -114.403632)
		(stroke
			(width 0.05715)
			(type default)
		)
		(layer "F.Cu")
	)
	(gr_line
		(start 456.467464 -63.111634)
		(end 456.550014 -63.029084)
		(stroke
			(width 0.0508)
			(type default)
		)
		(layer "F.Cu")
	)
	(gr_line
		(start 456.479148 -63.621412)
		(end 456.484228 -63.626492)
		(stroke
			(width 0.0508)
			(type default)
		)
		(layer "F.Cu")
	)
	(gr_line
		(start 456.484228 -63.626492)
		(end 456.789536 -63.626492)
		(stroke
			(width 0.0508)
			(type default)
		)
		(layer "F.Cu")
	)
	(gr_line
		(start 456.541124 -50.714402)
		(end 456.541124 -51.875944)
		(stroke
			(width 0.05715)
			(type default)
		)
		(layer "F.Cu")
	)
	(gr_line
		(start 456.541124 -50.714402)
		(end 456.758548 -50.496978)
		(stroke
			(width 0.05715)
			(type default)
		)
		(layer "F.Cu")
	)
	(gr_line
		(start 456.550014 -62.00267)
		(end 456.550014 -63.029084)
		(stroke
			(width 0.050038)
			(type default)
		)
		(layer "F.Cu")
	)
	(gr_line
		(start 456.599798 -112.205516)
		(end 456.599798 -113.556542)
		(stroke
			(width 0.05715)
			(type default)
		)
		(layer "F.Cu")
	)
	(gr_line
		(start 456.599798 -112.205516)
		(end 456.600814 -112.205516)
		(stroke
			(width 0.05715)
			(type default)
		)
		(layer "F.Cu")
	)
	(gr_line
		(start 456.696064 -49.997614)
		(end 456.758548 -50.060098)
		(stroke
			(width 0.05715)
			(type default)
		)
		(layer "F.Cu")
	)
	(gr_line
		(start 457.10348 -50.496978)
		(end 457.34097 -50.734468)
		(stroke
			(width 0.05715)
			(type default)
		)
		(layer "F.Cu")
	)
	(gr_line
		(start 457.10348 -50.060098)
		(end 457.165964 -49.997614)
		(stroke
			(width 0.05715)
			(type default)
		)
		(layer "F.Cu")
	)
	(gr_line
		(start 457.165964 -49.997614)
		(end 457.566014 -49.997614)
		(stroke
			(width 0.05715)
			(type default)
		)
		(layer "F.Cu")
	)
	(gr_line
		(start 457.34097 -50.734468)
		(end 457.34097 -51.875944)
		(stroke
			(width 0.05715)
			(type default)
		)
		(layer "F.Cu")
	)
	(gr_line
		(start 457.399898 -118.242334)
		(end 457.400914 -118.241318)
		(stroke
			(width 0.05715)
			(type default)
		)
		(layer "F.Cu")
	)
	(gr_line
		(start 457.399898 -118.242334)
		(end 457.632054 -118.47449)
		(stroke
			(width 0.05715)
			(type default)
		)
		(layer "F.Cu")
	)
	(gr_line
		(start 457.400914 -116.993162)
		(end 457.400914 -118.241318)
		(stroke
			(width 0.05715)
			(type default)
		)
		(layer "F.Cu")
	)
	(gr_line
		(start 457.58735 -120.38457)
		(end 457.9874 -120.38457)
		(stroke
			(width 0.05715)
			(type default)
		)
		(layer "F.Cu")
	)
	(gr_line
		(start 457.679298 -118.769892)
		(end 457.684124 -118.78183)
		(stroke
			(width 0.05715)
			(type default)
		)
		(layer "F.Cu")
	)
	(gr_line
		(start 457.907136 -44.83735)
		(end 458.24013 -44.83735)
		(stroke
			(width 0.05715)
			(type default)
		)
		(layer "F.Cu")
	)
	(gr_line
		(start 457.976986 -118.47449)
		(end 458.201014 -118.250462)
		(stroke
			(width 0.05715)
			(type default)
		)
		(layer "F.Cu")
	)
	(gr_line
		(start 457.9874 -120.38457)
		(end 458.049884 -120.322086)
		(stroke
			(width 0.05715)
			(type default)
		)
		(layer "F.Cu")
	)
	(gr_line
		(start 458.14107 -46.135798)
		(end 458.14107 -47.481998)
		(stroke
			(width 0.05715)
			(type default)
		)
		(layer "F.Cu")
	)
	(gr_line
		(start 458.14107 -46.135798)
		(end 458.391006 -45.885862)
		(stroke
			(width 0.05715)
			(type default)
		)
		(layer "F.Cu")
	)
	(gr_line
		(start 458.201014 -116.993162)
		(end 458.201014 -118.250462)
		(stroke
			(width 0.05715)
			(type default)
		)
		(layer "F.Cu")
	)
	(gr_line
		(start 458.24013 -44.83735)
		(end 458.36967 -44.96689)
		(stroke
			(width 0.05715)
			(type default)
		)
		(layer "F.Cu")
	)
	(gr_line
		(start 458.358494 -119.77878)
		(end 458.36332 -119.790718)
		(stroke
			(width 0.05715)
			(type default)
		)
		(layer "F.Cu")
	)
	(gr_line
		(start 458.394816 -120.322086)
		(end 458.4573 -120.38457)
		(stroke
			(width 0.05715)
			(type default)
		)
		(layer "F.Cu")
	)
	(gr_line
		(start 458.4573 -120.38457)
		(end 458.85735 -120.38457)
		(stroke
			(width 0.05715)
			(type default)
		)
		(layer "F.Cu")
	)
	(gr_line
		(start 458.714602 -44.96689)
		(end 458.844142 -44.83735)
		(stroke
			(width 0.05715)
			(type default)
		)
		(layer "F.Cu")
	)
	(gr_line
		(start 458.735938 -45.885862)
		(end 458.942186 -46.09211)
		(stroke
			(width 0.05715)
			(type default)
		)
		(layer "F.Cu")
	)
	(gr_line
		(start 458.764894 -114.403632)
		(end 459.191614 -114.403632)
		(stroke
			(width 0.05715)
			(type default)
		)
		(layer "F.Cu")
	)
	(gr_line
		(start 458.844142 -44.83735)
		(end 459.177136 -44.83735)
		(stroke
			(width 0.05715)
			(type default)
		)
		(layer "F.Cu")
	)
	(gr_line
		(start 458.940916 -47.481998)
		(end 458.942186 -47.480728)
		(stroke
			(width 0.05715)
			(type default)
		)
		(layer "F.Cu")
	)
	(gr_line
		(start 458.942186 -46.09211)
		(end 458.942186 -47.480728)
		(stroke
			(width 0.05715)
			(type default)
		)
		(layer "F.Cu")
	)
	(gr_line
		(start 458.999844 -113.556288)
		(end 459.227428 -113.783872)
		(stroke
			(width 0.05715)
			(type default)
		)
		(layer "F.Cu")
	)
	(gr_line
		(start 458.999844 -112.205516)
		(end 458.999844 -113.556288)
		(stroke
			(width 0.05715)
			(type default)
		)
		(layer "F.Cu")
	)
	(gr_line
		(start 458.999844 -112.205516)
		(end 459.00086 -112.205516)
		(stroke
			(width 0.05715)
			(type default)
		)
		(layer "F.Cu")
	)
	(gr_line
		(start 459.191614 -114.403632)
		(end 459.227428 -114.367818)
		(stroke
			(width 0.05715)
			(type default)
		)
		(layer "F.Cu")
	)
	(gr_line
		(start 459.246478 -144.81175)
		(end 459.246478 -144.963896)
		(stroke
			(width 0.0635)
			(type default)
		)
		(layer "F.Cu")
	)
	(gr_line
		(start 459.496414 -49.997614)
		(end 459.896464 -49.997614)
		(stroke
			(width 0.05715)
			(type default)
		)
		(layer "F.Cu")
	)
	(gr_line
		(start 459.57236 -114.367818)
		(end 459.608174 -114.403632)
		(stroke
			(width 0.05715)
			(type default)
		)
		(layer "F.Cu")
	)
	(gr_line
		(start 459.57236 -113.783872)
		(end 459.799944 -113.556288)
		(stroke
			(width 0.05715)
			(type default)
		)
		(layer "F.Cu")
	)
	(gr_line
		(start 459.608174 -114.403632)
		(end 460.034894 -114.403632)
		(stroke
			(width 0.05715)
			(type default)
		)
		(layer "F.Cu")
	)
	(gr_line
		(start 459.741016 -50.71491)
		(end 459.741016 -51.875944)
		(stroke
			(width 0.05715)
			(type default)
		)
		(layer "F.Cu")
	)
	(gr_line
		(start 459.741016 -50.71491)
		(end 459.958948 -50.496978)
		(stroke
			(width 0.05715)
			(type default)
		)
		(layer "F.Cu")
	)
	(gr_line
		(start 459.799944 -112.205516)
		(end 459.799944 -113.556288)
		(stroke
			(width 0.05715)
			(type default)
		)
		(layer "F.Cu")
	)
	(gr_line
		(start 459.799944 -112.205516)
		(end 459.80096 -112.205516)
		(stroke
			(width 0.05715)
			(type default)
		)
		(layer "F.Cu")
	)
	(gr_line
		(start 459.896464 -49.997614)
		(end 459.958948 -50.060098)
		(stroke
			(width 0.05715)
			(type default)
		)
		(layer "F.Cu")
	)
	(gr_line
		(start 460.30388 -50.496978)
		(end 460.541116 -50.734214)
		(stroke
			(width 0.05715)
			(type default)
		)
		(layer "F.Cu")
	)
	(gr_line
		(start 460.30388 -50.060098)
		(end 460.366364 -49.997614)
		(stroke
			(width 0.05715)
			(type default)
		)
		(layer "F.Cu")
	)
	(gr_line
		(start 460.34325 -121.49328)
		(end 460.739998 -121.49328)
		(stroke
			(width 0.05715)
			(type default)
		)
		(layer "F.Cu")
	)
	(gr_line
		(start 460.366364 -49.997614)
		(end 460.766414 -49.997614)
		(stroke
			(width 0.05715)
			(type default)
		)
		(layer "F.Cu")
	)
	(gr_line
		(start 460.541116 -50.734214)
		(end 460.541116 -51.875944)
		(stroke
			(width 0.05715)
			(type default)
		)
		(layer "F.Cu")
	)
	(gr_line
		(start 460.59979 -118.343934)
		(end 460.600806 -118.342918)
		(stroke
			(width 0.05715)
			(type default)
		)
		(layer "F.Cu")
	)
	(gr_line
		(start 460.59979 -118.343934)
		(end 460.827374 -118.571518)
		(stroke
			(width 0.05715)
			(type default)
		)
		(layer "F.Cu")
	)
	(gr_line
		(start 460.600806 -116.993162)
		(end 460.600806 -118.342918)
		(stroke
			(width 0.05715)
			(type default)
		)
		(layer "F.Cu")
	)
	(gr_line
		(start 460.739998 -121.49328)
		(end 460.81188 -121.421398)
		(stroke
			(width 0.05715)
			(type default)
		)
		(layer "F.Cu")
	)
	(gr_line
		(start 461.107028 -44.83735)
		(end 461.440022 -44.83735)
		(stroke
			(width 0.05715)
			(type default)
		)
		(layer "F.Cu")
	)
	(gr_line
		(start 461.156558 -121.421398)
		(end 461.22844 -121.49328)
		(stroke
			(width 0.05715)
			(type default)
		)
		(layer "F.Cu")
	)
	(gr_line
		(start 461.172306 -118.571518)
		(end 461.400906 -118.342918)
		(stroke
			(width 0.05715)
			(type default)
		)
		(layer "F.Cu")
	)
	(gr_line
		(start 461.22844 -121.49328)
		(end 461.61325 -121.49328)
		(stroke
			(width 0.05715)
			(type default)
		)
		(layer "F.Cu")
	)
	(gr_line
		(start 461.340962 -46.227492)
		(end 461.340962 -47.481998)
		(stroke
			(width 0.05715)
			(type default)
		)
		(layer "F.Cu")
	)
	(gr_line
		(start 461.340962 -46.227492)
		(end 461.542638 -46.025816)
		(stroke
			(width 0.05715)
			(type default)
		)
		(layer "F.Cu")
	)
	(gr_line
		(start 461.400906 -116.993162)
		(end 461.400906 -118.342918)
		(stroke
			(width 0.05715)
			(type default)
		)
		(layer "F.Cu")
	)
	(gr_line
		(start 461.440022 -44.83735)
		(end 461.569562 -44.96689)
		(stroke
			(width 0.05715)
			(type default)
		)
		(layer "F.Cu")
	)
	(gr_line
		(start 461.887316 -46.025816)
		(end 462.142078 -46.280578)
		(stroke
			(width 0.05715)
			(type default)
		)
		(layer "F.Cu")
	)
	(gr_line
		(start 461.914494 -44.96689)
		(end 462.044034 -44.83735)
		(stroke
			(width 0.05715)
			(type default)
		)
		(layer "F.Cu")
	)
	(gr_line
		(start 461.96504 -114.403632)
		(end 462.342484 -114.403632)
		(stroke
			(width 0.05715)
			(type default)
		)
		(layer "F.Cu")
	)
	(gr_line
		(start 462.044034 -44.83735)
		(end 462.377028 -44.83735)
		(stroke
			(width 0.05715)
			(type default)
		)
		(layer "F.Cu")
	)
	(gr_line
		(start 462.141062 -47.481998)
		(end 462.142078 -47.481998)
		(stroke
			(width 0.05715)
			(type default)
		)
		(layer "F.Cu")
	)
	(gr_line
		(start 462.142078 -46.280578)
		(end 462.142078 -47.481998)
		(stroke
			(width 0.05715)
			(type default)
		)
		(layer "F.Cu")
	)
	(gr_line
		(start 462.19999 -113.556288)
		(end 462.427574 -113.783872)
		(stroke
			(width 0.05715)
			(type default)
		)
		(layer "F.Cu")
	)
	(gr_line
		(start 462.19999 -112.205516)
		(end 462.19999 -113.556288)
		(stroke
			(width 0.05715)
			(type default)
		)
		(layer "F.Cu")
	)
	(gr_line
		(start 462.19999 -112.205516)
		(end 462.201006 -112.205516)
		(stroke
			(width 0.05715)
			(type default)
		)
		(layer "F.Cu")
	)
	(gr_line
		(start 462.342484 -114.403632)
		(end 462.427574 -114.318542)
		(stroke
			(width 0.05715)
			(type default)
		)
		(layer "F.Cu")
	)
	(gr_line
		(start 462.707228 -49.997614)
		(end 463.107278 -49.997614)
		(stroke
			(width 0.05715)
			(type default)
		)
		(layer "F.Cu")
	)
	(gr_line
		(start 462.772506 -114.318542)
		(end 462.857596 -114.403632)
		(stroke
			(width 0.05715)
			(type default)
		)
		(layer "F.Cu")
	)
	(gr_line
		(start 462.772506 -113.783872)
		(end 462.999836 -113.556542)
		(stroke
			(width 0.05715)
			(type default)
		)
		(layer "F.Cu")
	)
	(gr_line
		(start 462.857596 -114.403632)
		(end 463.23504 -114.403632)
		(stroke
			(width 0.05715)
			(type default)
		)
		(layer "F.Cu")
	)
	(gr_line
		(start 462.940908 -50.987198)
		(end 462.940908 -51.875944)
		(stroke
			(width 0.05715)
			(type default)
		)
		(layer "F.Cu")
	)
	(gr_line
		(start 462.940908 -50.987198)
		(end 463.165698 -50.762408)
		(stroke
			(width 0.05715)
			(type default)
		)
		(layer "F.Cu")
	)
	(gr_line
		(start 462.999836 -112.205516)
		(end 462.999836 -113.556542)
		(stroke
			(width 0.05715)
			(type default)
		)
		(layer "F.Cu")
	)
	(gr_line
		(start 462.999836 -112.205516)
		(end 463.000852 -112.205516)
		(stroke
			(width 0.05715)
			(type default)
		)
		(layer "F.Cu")
	)
	(gr_line
		(start 463.107278 -49.997614)
		(end 463.169762 -50.060098)
		(stroke
			(width 0.05715)
			(type default)
		)
		(layer "F.Cu")
	)
	(gr_line
		(start 463.51063 -50.762408)
		(end 463.741008 -50.992786)
		(stroke
			(width 0.05715)
			(type default)
		)
		(layer "F.Cu")
	)
	(gr_line
		(start 463.514694 -50.060098)
		(end 463.577178 -49.997614)
		(stroke
			(width 0.05715)
			(type default)
		)
		(layer "F.Cu")
	)
	(gr_line
		(start 463.577178 -49.997614)
		(end 463.977228 -49.997614)
		(stroke
			(width 0.05715)
			(type default)
		)
		(layer "F.Cu")
	)
	(gr_line
		(start 463.625438 -121.139458)
		(end 463.871818 -121.139458)
		(stroke
			(width 0.05715)
			(type default)
		)
		(layer "F.Cu")
	)
	(gr_line
		(start 463.741008 -50.992786)
		(end 463.741008 -51.875944)
		(stroke
			(width 0.05715)
			(type default)
		)
		(layer "F.Cu")
	)
	(gr_line
		(start 463.799936 -118.343934)
		(end 463.800952 -118.342918)
		(stroke
			(width 0.05715)
			(type default)
		)
		(layer "F.Cu")
	)
	(gr_line
		(start 463.799936 -118.343934)
		(end 464.02752 -118.571518)
		(stroke
			(width 0.05715)
			(type default)
		)
		(layer "F.Cu")
	)
	(gr_line
		(start 463.800952 -116.993162)
		(end 463.800952 -118.342918)
		(stroke
			(width 0.05715)
			(type default)
		)
		(layer "F.Cu")
	)
	(gr_line
		(start 463.871818 -121.139458)
		(end 464.043522 -120.967754)
		(stroke
			(width 0.05715)
			(type default)
		)
		(layer "F.Cu")
	)
	(gr_line
		(start 464.372452 -118.571518)
		(end 464.600798 -118.343172)
		(stroke
			(width 0.05715)
			(type default)
		)
		(layer "F.Cu")
	)
	(gr_line
		(start 464.388454 -120.967754)
		(end 464.560158 -121.139458)
		(stroke
			(width 0.05715)
			(type default)
		)
		(layer "F.Cu")
	)
	(gr_line
		(start 464.560158 -121.139458)
		(end 464.811618 -121.139458)
		(stroke
			(width 0.05715)
			(type default)
		)
		(layer "F.Cu")
	)
	(gr_line
		(start 464.600798 -116.993162)
		(end 464.600798 -118.343172)
		(stroke
			(width 0.05715)
			(type default)
		)
		(layer "F.Cu")
	)
	(gr_line
		(start 465.19973 -114.4524)
		(end 465.551012 -114.4524)
		(stroke
			(width 0.05715)
			(type default)
		)
		(layer "F.Cu")
	)
	(gr_line
		(start 465.399882 -113.556288)
		(end 465.627466 -113.783872)
		(stroke
			(width 0.05715)
			(type default)
		)
		(layer "F.Cu")
	)
	(gr_line
		(start 465.399882 -112.205516)
		(end 465.399882 -113.556288)
		(stroke
			(width 0.05715)
			(type default)
		)
		(layer "F.Cu")
	)
	(gr_line
		(start 465.399882 -112.205516)
		(end 465.400898 -112.205516)
		(stroke
			(width 0.05715)
			(type default)
		)
		(layer "F.Cu")
	)
	(gr_line
		(start 465.551012 -114.4524)
		(end 465.627466 -114.375946)
		(stroke
			(width 0.05715)
			(type default)
		)
		(layer "F.Cu")
	)
	(gr_line
		(start 465.972398 -114.375946)
		(end 466.048852 -114.4524)
		(stroke
			(width 0.05715)
			(type default)
		)
		(layer "F.Cu")
	)
	(gr_line
		(start 465.972398 -113.783872)
		(end 466.199982 -113.556288)
		(stroke
			(width 0.05715)
			(type default)
		)
		(layer "F.Cu")
	)
	(gr_line
		(start 466.048852 -114.4524)
		(end 466.46973 -114.4524)
		(stroke
			(width 0.05715)
			(type default)
		)
		(layer "F.Cu")
	)
	(gr_line
		(start 466.199982 -112.205516)
		(end 466.199982 -113.556288)
		(stroke
			(width 0.05715)
			(type default)
		)
		(layer "F.Cu")
	)
	(gr_line
		(start 466.199982 -112.205516)
		(end 466.200998 -112.205516)
		(stroke
			(width 0.05715)
			(type default)
		)
		(layer "F.Cu")
	)
	(gr_line
		(start 475.15018 -12.322048)
		(end 475.15018 -12.408408)
		(stroke
			(width 0.05842)
			(type default)
		)
		(layer "F.Cu")
	)
	(gr_line
		(start 475.15018 -10.960608)
		(end 475.15018 -11.046968)
		(stroke
			(width 0.05842)
			(type default)
		)
		(layer "F.Cu")
	)
	(gr_line
		(start 475.61246 -12.868148)
		(end 475.94012 -12.540488)
		(stroke
			(width 0.05842)
			(type default)
		)
		(layer "F.Cu")
	)
	(gr_line
		(start 475.61246 -11.862308)
		(end 475.94012 -12.189968)
		(stroke
			(width 0.05842)
			(type default)
		)
		(layer "F.Cu")
	)
	(gr_line
		(start 475.61246 -11.506708)
		(end 475.94012 -11.179048)
		(stroke
			(width 0.05842)
			(type default)
		)
		(layer "F.Cu")
	)
	(gr_line
		(start 475.61246 -10.500868)
		(end 475.94012 -10.828528)
		(stroke
			(width 0.05842)
			(type default)
		)
		(layer "F.Cu")
	)
	(gr_line
		(start 475.94012 -12.189968)
		(end 475.94012 -12.540488)
		(stroke
			(width 0.05842)
			(type default)
		)
		(layer "F.Cu")
	)
	(gr_line
		(start 475.94012 -10.828528)
		(end 475.94012 -11.179048)
		(stroke
			(width 0.05842)
			(type default)
		)
		(layer "F.Cu")
	)
	(gr_line
		(start 476.192088 -8.481568)
		(end 476.253048 -8.420608)
		(stroke
			(width 0.05842)
			(type default)
		)
		(layer "F.Cu")
	)
	(gr_line
		(start 476.193866 -9.133586)
		(end 476.657162 -9.133586)
		(stroke
			(width 0.05842)
			(type default)
		)
		(layer "F.Cu")
	)
	(gr_line
		(start 476.485204 -14.376146)
		(end 477.033336 -13.828014)
		(stroke
			(width 0.05842)
			(type default)
		)
		(layer "F.Cu")
	)
	(gr_line
		(start 476.657162 -9.133586)
		(end 476.905066 -8.885682)
		(stroke
			(width 0.05842)
			(type default)
		)
		(layer "F.Cu")
	)
	(gr_line
		(start 476.69323 -7.96163)
		(end 476.69323 -7.980426)
		(stroke
			(width 0.05842)
			(type default)
		)
		(layer "F.Cu")
	)
	(gr_line
		(start 476.905066 -8.442706)
		(end 476.905066 -8.885682)
		(stroke
			(width 0.05842)
			(type default)
		)
		(layer "F.Cu")
	)
	(gr_line
		(start 476.905066 -8.41883)
		(end 476.905066 -8.437626)
		(stroke
			(width 0.05842)
			(type default)
		)
		(layer "F.Cu")
	)
	(gr_line
		(start 476.944944 -14.838426)
		(end 477.193864 -14.838426)
		(stroke
			(width 0.05842)
			(type default)
		)
		(layer "F.Cu")
	)
	(gr_line
		(start 477.033336 -13.828014)
		(end 477.391222 -13.828014)
		(stroke
			(width 0.05842)
			(type default)
		)
		(layer "F.Cu")
	)
	(gr_line
		(start 477.198944 -14.838426)
		(end 477.242632 -14.838426)
		(stroke
			(width 0.05842)
			(type default)
		)
		(layer "F.Cu")
	)
	(gr_line
		(start 477.242632 -14.838426)
		(end 477.656144 -15.251938)
		(stroke
			(width 0.05842)
			(type default)
		)
		(layer "F.Cu")
	)
	(gr_line
		(start 477.391222 -13.828014)
		(end 477.656144 -14.092936)
		(stroke
			(width 0.05842)
			(type default)
		)
		(layer "F.Cu")
	)
	(gr_line
		(start 477.656144 -14.381226)
		(end 477.656144 -14.478508)
		(stroke
			(width 0.05842)
			(type default)
		)
		(layer "F.Cu")
	)
	(gr_line
		(start 477.656144 -14.092936)
		(end 477.656144 -14.376146)
		(stroke
			(width 0.05842)
			(type default)
		)
		(layer "F.Cu")
	)
	(gr_line
		(start 477.68002 -12.474194)
		(end 478.167446 -12.96162)
		(stroke
			(width 0.05842)
			(type default)
		)
		(layer "F.Cu")
	)
	(gr_line
		(start 477.68002 -10.692384)
		(end 477.68002 -11.585194)
		(stroke
			(width 0.05842)
			(type default)
		)
		(layer "F.Cu")
	)
	(gr_line
		(start 478.1423 -10.232644)
		(end 478.322132 -10.412476)
		(stroke
			(width 0.05842)
			(type default)
		)
		(layer "F.Cu")
	)
	(gr_line
		(start 478.167446 -12.96162)
		(end 479.861372 -12.96162)
		(stroke
			(width 0.05842)
			(type default)
		)
		(layer "F.Cu")
	)
	(gr_line
		(start 478.322132 -10.412476)
		(end 478.912682 -10.412476)
		(stroke
			(width 0.05842)
			(type default)
		)
		(layer "F.Cu")
	)
	(gr_line
		(start 478.540572 -12.462256)
		(end 479.756216 -12.462256)
		(stroke
			(width 0.05842)
			(type default)
		)
		(layer "F.Cu")
	)
	(gr_line
		(start 478.540572 -11.573256)
		(end 478.917254 -11.573256)
		(stroke
			(width 0.05842)
			(type default)
		)
		(layer "F.Cu")
	)
	(gr_line
		(start 478.545144 -15.251938)
		(end 478.605088 -15.191994)
		(stroke
			(width 0.05842)
			(type default)
		)
		(layer "F.Cu")
	)
	(gr_line
		(start 478.545144 -14.478508)
		(end 478.605088 -14.538452)
		(stroke
			(width 0.05842)
			(type default)
		)
		(layer "F.Cu")
	)
	(gr_line
		(start 478.912682 -10.412476)
		(end 479.098356 -10.59815)
		(stroke
			(width 0.05842)
			(type default)
		)
		(layer "F.Cu")
	)
	(gr_line
		(start 478.917254 -11.573256)
		(end 479.098356 -11.392154)
		(stroke
			(width 0.05842)
			(type default)
		)
		(layer "F.Cu")
	)
	(gr_line
		(start 479.098356 -10.59815)
		(end 479.098356 -11.392154)
		(stroke
			(width 0.05842)
			(type default)
		)
		(layer "F.Cu")
	)
	(gr_line
		(start 479.145346 -5.582412)
		(end 479.39325 -5.830316)
		(stroke
			(width 0.05842)
			(type default)
		)
		(layer "F.Cu")
	)
	(gr_line
		(start 479.145346 -5.119116)
		(end 479.145346 -5.582412)
		(stroke
			(width 0.05842)
			(type default)
		)
		(layer "F.Cu")
	)
	(gr_line
		(start 479.39325 -5.830316)
		(end 479.856546 -5.830316)
		(stroke
			(width 0.05842)
			(type default)
		)
		(layer "F.Cu")
	)
	(gr_line
		(start 479.55327 -15.193518)
		(end 479.861372 -15.50162)
		(stroke
			(width 0.05842)
			(type default)
		)
		(layer "F.Cu")
	)
	(gr_line
		(start 479.55327 -14.539722)
		(end 479.861372 -14.23162)
		(stroke
			(width 0.05842)
			(type default)
		)
		(layer "F.Cu")
	)
	(gr_line
		(start 479.756216 -12.462256)
		(end 479.861372 -12.3571)
		(stroke
			(width 0.05842)
			(type default)
		)
		(layer "F.Cu")
	)
	(gr_line
		(start 479.797364 -5.117338)
		(end 479.858324 -5.178298)
		(stroke
			(width 0.05842)
			(type default)
		)
		(layer "F.Cu")
	)
	(gr_line
		(start 479.861372 -11.69162)
		(end 479.861372 -12.3571)
		(stroke
			(width 0.05842)
			(type default)
		)
		(layer "F.Cu")
	)
	(gr_line
		(start 480.108006 -6.545072)
		(end 480.35591 -6.792976)
		(stroke
			(width 0.05842)
			(type default)
		)
		(layer "F.Cu")
	)
	(gr_line
		(start 480.108006 -6.081776)
		(end 480.108006 -6.545072)
		(stroke
			(width 0.05842)
			(type default)
		)
		(layer "F.Cu")
	)
	(gr_line
		(start 480.35591 -6.792976)
		(end 480.732846 -6.792976)
		(stroke
			(width 0.05842)
			(type default)
		)
		(layer "F.Cu")
	)
	(gr_line
		(start 480.737926 -6.792976)
		(end 480.822762 -6.792976)
		(stroke
			(width 0.05842)
			(type default)
		)
		(layer "F.Cu")
	)
	(gr_line
		(start 480.760024 -6.079998)
		(end 480.820984 -6.140958)
		(stroke
			(width 0.05842)
			(type default)
		)
		(layer "F.Cu")
	)
	(gr_line
		(start 481.195126 -6.5151)
		(end 481.279962 -6.5151)
		(stroke
			(width 0.05842)
			(type default)
		)
		(layer "F.Cu")
	)
	(gr_line
		(start 481.57003 -9.560052)
		(end 481.822252 -9.30783)
		(stroke
			(width 0.05842)
			(type default)
		)
		(layer "F.Cu")
	)
	(gr_line
		(start 481.57003 -7.530084)
		(end 481.825554 -7.27456)
		(stroke
			(width 0.05842)
			(type default)
		)
		(layer "F.Cu")
	)
	(gr_line
		(start 481.69068 -9.01065)
		(end 481.822252 -9.142222)
		(stroke
			(width 0.05842)
			(type default)
		)
		(layer "F.Cu")
	)
	(gr_line
		(start 481.711254 -6.97738)
		(end 481.825554 -7.09168)
		(stroke
			(width 0.05842)
			(type default)
		)
		(layer "F.Cu")
	)
	(gr_line
		(start 481.731574 4.65709)
		(end 481.826316 4.562348)
		(stroke
			(width 0.050038)
			(type default)
		)
		(layer "F.Cu")
	)
	(gr_line
		(start 481.734876 3.820668)
		(end 481.826316 3.912108)
		(stroke
			(width 0.050038)
			(type default)
		)
		(layer "F.Cu")
	)
	(gr_line
		(start 481.822252 -9.142222)
		(end 481.822252 -9.30783)
		(stroke
			(width 0.05842)
			(type default)
		)
		(layer "F.Cu")
	)
	(gr_line
		(start 481.825554 -7.09168)
		(end 481.825554 -7.27456)
		(stroke
			(width 0.05842)
			(type default)
		)
		(layer "F.Cu")
	)
	(gr_line
		(start 482.15042 -8.54837)
		(end 482.836728 -8.54837)
		(stroke
			(width 0.05842)
			(type default)
		)
		(layer "F.Cu")
	)
	(gr_line
		(start 482.170994 -6.5151)
		(end 482.84003 -6.5151)
		(stroke
			(width 0.05842)
			(type default)
		)
		(layer "F.Cu")
	)
	(gr_line
		(start 482.46284 3.951224)
		(end 482.665024 3.74904)
		(stroke
			(width 0.050038)
			(type default)
		)
		(layer "F.Cu")
	)
	(gr_line
		(start 482.46284 4.60121)
		(end 482.665024 4.803394)
		(stroke
			(width 0.050038)
			(type default)
		)
		(layer "F.Cu")
	)
	(gr_line
		(start 482.836728 -8.54837)
		(end 482.84003 -8.545068)
		(stroke
			(width 0.05842)
			(type default)
		)
		(layer "F.Cu")
	)
	(gr_line
		(start 483.001066 -38.969442)
		(end 483.001066 -39.5986)
		(stroke
			(width 0.05842)
			(type default)
		)
		(layer "F.Cu")
	)
	(gr_line
		(start 483.500938 -38.969442)
		(end 483.500938 -39.5986)
		(stroke
			(width 0.05842)
			(type default)
		)
		(layer "F.Cu")
	)
	(gr_line
		(start 483.594918 -51.173888)
		(end 483.873048 -51.452018)
		(stroke
			(width 0.05715)
			(type default)
		)
		(layer "F.Cu")
	)
	(gr_line
		(start 483.626668 -52.04333)
		(end 483.873048 -51.79695)
		(stroke
			(width 0.05715)
			(type default)
		)
		(layer "F.Cu")
	)
	(gr_line
		(start 483.67061 -36.274248)
		(end 483.966774 -36.274248)
		(stroke
			(width 0.05842)
			(type default)
		)
		(layer "F.Cu")
	)
	(gr_line
		(start 483.966774 -36.274248)
		(end 483.98684 -36.294314)
		(stroke
			(width 0.05842)
			(type default)
		)
		(layer "F.Cu")
	)
	(gr_line
		(start 484.500936 -39.122604)
		(end 484.500936 -39.5986)
		(stroke
			(width 0.05842)
			(type default)
		)
		(layer "F.Cu")
	)
	(gr_line
		(start 484.500936 -39.122604)
		(end 484.510842 -39.112698)
		(stroke
			(width 0.05842)
			(type default)
		)
		(layer "F.Cu")
	)
	(gr_line
		(start 484.50119 -48.862234)
		(end 484.565706 -48.92675)
		(stroke
			(width 0.05715)
			(type default)
		)
		(layer "F.Cu")
	)
	(gr_line
		(start 484.50119 -48.3362)
		(end 484.50119 -48.862234)
		(stroke
			(width 0.05715)
			(type default)
		)
		(layer "F.Cu")
	)
	(gr_line
		(start 484.565706 -48.92675)
		(end 484.689912 -48.92675)
		(stroke
			(width 0.05715)
			(type default)
		)
		(layer "F.Cu")
	)
	(gr_line
		(start 484.640382 -36.294314)
		(end 484.660448 -36.274248)
		(stroke
			(width 0.05842)
			(type default)
		)
		(layer "F.Cu")
	)
	(gr_line
		(start 484.645462 -49.7967)
		(end 484.757222 -49.90846)
		(stroke
			(width 0.05715)
			(type default)
		)
		(layer "F.Cu")
	)
	(gr_line
		(start 484.645462 -49.4538)
		(end 484.645462 -49.7967)
		(stroke
			(width 0.05715)
			(type default)
		)
		(layer "F.Cu")
	)
	(gr_line
		(start 484.645462 -49.4538)
		(end 484.757222 -49.34204)
		(stroke
			(width 0.05715)
			(type default)
		)
		(layer "F.Cu")
	)
	(gr_line
		(start 484.660448 -36.274248)
		(end 484.940864 -36.274248)
		(stroke
			(width 0.05842)
			(type default)
		)
		(layer "F.Cu")
	)
	(gr_line
		(start 484.689912 -48.92675)
		(end 484.757222 -48.99406)
		(stroke
			(width 0.05715)
			(type default)
		)
		(layer "F.Cu")
	)
	(gr_line
		(start 484.715058 -37.935662)
		(end 485.011222 -37.935662)
		(stroke
			(width 0.05842)
			(type default)
		)
		(layer "F.Cu")
	)
	(gr_line
		(start 484.992934 -53.03647)
		(end 485.347264 -52.68214)
		(stroke
			(width 0.05715)
			(type default)
		)
		(layer "F.Cu")
	)
	(gr_line
		(start 484.997252 -52.265326)
		(end 485.170226 -52.4383)
		(stroke
			(width 0.05715)
			(type default)
		)
		(layer "F.Cu")
	)
	(gr_line
		(start 484.997252 -51.893978)
		(end 484.997252 -52.265326)
		(stroke
			(width 0.05715)
			(type default)
		)
		(layer "F.Cu")
	)
	(gr_line
		(start 485.001062 -49.58334)
		(end 485.001062 -49.66716)
		(stroke
			(width 0.05715)
			(type default)
		)
		(layer "F.Cu")
	)
	(gr_line
		(start 485.001062 -48.3362)
		(end 485.001062 -48.75276)
		(stroke
			(width 0.05715)
			(type default)
		)
		(layer "F.Cu")
	)
	(gr_line
		(start 485.001062 -39.14013)
		(end 485.001062 -39.5986)
		(stroke
			(width 0.05842)
			(type default)
		)
		(layer "F.Cu")
	)
	(gr_line
		(start 485.011222 -37.935662)
		(end 485.034082 -37.958522)
		(stroke
			(width 0.05842)
			(type default)
		)
		(layer "F.Cu")
	)
	(gr_line
		(start 485.4956 -51.559206)
		(end 485.6099 -51.673506)
		(stroke
			(width 0.05715)
			(type default)
		)
		(layer "F.Cu")
	)
	(gr_line
		(start 485.4956 -51.1429)
		(end 485.4956 -51.559206)
		(stroke
			(width 0.05715)
			(type default)
		)
		(layer "F.Cu")
	)
	(gr_line
		(start 485.4956 -50.2539)
		(end 485.767634 -49.981866)
		(stroke
			(width 0.05715)
			(type default)
		)
		(layer "F.Cu")
	)
	(gr_line
		(start 485.6099 -51.673506)
		(end 485.795066 -51.673506)
		(stroke
			(width 0.05715)
			(type default)
		)
		(layer "F.Cu")
	)
	(gr_line
		(start 485.687878 -37.958522)
		(end 485.703626 -37.942774)
		(stroke
			(width 0.05842)
			(type default)
		)
		(layer "F.Cu")
	)
	(gr_line
		(start 485.703626 -37.942774)
		(end 486.001568 -37.942774)
		(stroke
			(width 0.05842)
			(type default)
		)
		(layer "F.Cu")
	)
	(gr_line
		(start 485.795066 -51.673506)
		(end 485.824022 -51.702462)
		(stroke
			(width 0.05715)
			(type default)
		)
		(layer "F.Cu")
	)
	(gr_line
		(start 486.00106 -48.90008)
		(end 486.081324 -48.980344)
		(stroke
			(width 0.05715)
			(type default)
		)
		(layer "F.Cu")
	)
	(gr_line
		(start 486.00106 -48.3362)
		(end 486.00106 -48.90008)
		(stroke
			(width 0.05715)
			(type default)
		)
		(layer "F.Cu")
	)
	(gr_line
		(start 486.112566 -49.981866)
		(end 486.3846 -50.2539)
		(stroke
			(width 0.05715)
			(type default)
		)
		(layer "F.Cu")
	)
	(gr_line
		(start 486.168954 -51.702462)
		(end 486.3846 -51.486816)
		(stroke
			(width 0.05715)
			(type default)
		)
		(layer "F.Cu")
	)
	(gr_line
		(start 486.3846 -51.1429)
		(end 486.3846 -51.486816)
		(stroke
			(width 0.05715)
			(type default)
		)
		(layer "F.Cu")
	)
	(gr_line
		(start 486.426256 -48.980344)
		(end 486.501186 -48.905414)
		(stroke
			(width 0.05715)
			(type default)
		)
		(layer "F.Cu")
	)
	(gr_line
		(start 486.501186 -48.3362)
		(end 486.501186 -48.905414)
		(stroke
			(width 0.05715)
			(type default)
		)
		(layer "F.Cu")
	)
	(gr_line
		(start 499.11 -150.876)
		(end 499.11 -150.622)
		(stroke
			(width 0.2)
			(type default)
		)
		(layer "F.Cu")
	)
	(gr_line
		(start -3.899916 -104.76992)
		(end -3.370834 -104.76992)
		(stroke
			(width 0.05715)
			(type default)
		)
		(layer "B.Cu")
	)
	(gr_line
		(start -3.899916 -35.710114)
		(end -3.434842 -35.710114)
		(stroke
			(width 0.05715)
			(type default)
		)
		(layer "B.Cu")
	)
	(gr_line
		(start -3.434842 -35.710114)
		(end -3.372358 -35.772598)
		(stroke
			(width 0.05715)
			(type default)
		)
		(layer "B.Cu")
	)
	(gr_line
		(start -3.370834 -104.76992)
		(end -3.220466 -104.920288)
		(stroke
			(width 0.05715)
			(type default)
		)
		(layer "B.Cu")
	)
	(gr_line
		(start -3.027426 -35.772598)
		(end -2.964942 -35.710114)
		(stroke
			(width 0.05715)
			(type default)
		)
		(layer "B.Cu")
	)
	(gr_line
		(start -2.964942 -35.710114)
		(end -2.500122 -35.710114)
		(stroke
			(width 0.05715)
			(type default)
		)
		(layer "B.Cu")
	)
	(gr_line
		(start -2.875788 -104.920288)
		(end -2.72542 -104.76992)
		(stroke
			(width 0.05715)
			(type default)
		)
		(layer "B.Cu")
	)
	(gr_line
		(start -2.72542 -104.76992)
		(end -2.500122 -104.76992)
		(stroke
			(width 0.05715)
			(type default)
		)
		(layer "B.Cu")
	)
	(gr_line
		(start -2.599944 -90.769948)
		(end -2.169414 -90.769948)
		(stroke
			(width 0.05715)
			(type default)
		)
		(layer "B.Cu")
	)
	(gr_line
		(start -2.599944 -25.710134)
		(end -2.19964 -25.710134)
		(stroke
			(width 0.05715)
			(type default)
		)
		(layer "B.Cu")
	)
	(gr_line
		(start -2.19964 -25.710134)
		(end -2.023364 -25.533858)
		(stroke
			(width 0.05715)
			(type default)
		)
		(layer "B.Cu")
	)
	(gr_line
		(start -2.169414 -90.769948)
		(end -1.972818 -90.573352)
		(stroke
			(width 0.05715)
			(type default)
		)
		(layer "B.Cu")
	)
	(gr_line
		(start -1.678686 -25.533858)
		(end -1.50241 -25.710134)
		(stroke
			(width 0.05715)
			(type default)
		)
		(layer "B.Cu")
	)
	(gr_line
		(start -1.627886 -90.573352)
		(end -1.43129 -90.769948)
		(stroke
			(width 0.05715)
			(type default)
		)
		(layer "B.Cu")
	)
	(gr_line
		(start -1.50241 -25.710134)
		(end -1.20015 -25.710134)
		(stroke
			(width 0.05715)
			(type default)
		)
		(layer "B.Cu")
	)
	(gr_line
		(start -1.43129 -90.769948)
		(end -1.20015 -90.769948)
		(stroke
			(width 0.05715)
			(type default)
		)
		(layer "B.Cu")
	)
	(gr_line
		(start -0.025908 -24.93264)
		(end 0.085852 -25.0444)
		(stroke
			(width 0.05715)
			(type default)
		)
		(layer "B.Cu")
	)
	(gr_poly
		(pts
			(xy 368.2238 -96.2406) (xy 366.5982 -96.2406) (xy 366.5982 -100.9142) (xy 368.2238 -100.9142)
		)
		(stroke
			(width 0)
			(type solid)
		)
		(fill yes)
		(layer "B.Cu")
		(net "GND")
	)
	(gr_poly
		(pts
			(xy 486.1052 -31.115) (xy 483.467664 -31.115) (xy 483.4636 -31.119064) (xy 483.4636 -34.3535) (xy 486.1052 -34.3535)
		)
		(stroke
			(width 0)
			(type solid)
		)
		(fill yes)
		(layer "B.Cu")
		(net "GND")
	)
	(gr_poly
		(pts
			(xy 367.598198 -109.049312) (xy 367.598198 -106.062272) (xy 367.479326 -105.9434) (xy 364.998 -105.9434)
			(xy 364.998 -109.1438) (xy 367.50371 -109.1438)
		)
		(stroke
			(width 0)
			(type solid)
		)
		(fill yes)
		(layer "B.Cu")
		(net "GND")
	)
	(gr_poly
		(pts
			(xy 33.3248 -76.8096) (xy 33.3248 -72.223884) (xy 33.2994 -72.198484) (xy 32.553402 -72.198484) (xy 32.318452 -72.433434)
			(xy 32.318452 -73.550018) (xy 32.192214 -73.676256) (xy 31.787084 -73.676256) (xy 31.588202 -73.875138)
			(xy 31.588202 -74.887582) (xy 30.743144 -75.73264) (xy 30.743144 -76.734162) (xy 31.021782 -77.0128)
			(xy 33.1216 -77.0128)
		)
		(stroke
			(width 0)
			(type solid)
		)
		(fill yes)
		(layer "B.Cu")
		(net "VR_FET_SW_P12V_STBY_PVCCIN_CPU1")
	)
	(gr_poly
		(pts
			(xy 33.2994 -85.0138) (xy 33.2994 -80.453484) (xy 33.1724 -80.326484) (xy 32.666178 -80.326484)
			(arc
				(start 32.659828 -80.328262)
				(mid 32.610582 -80.337767)
				(end 32.560514 -80.340708)
			)
			(xy 32.539432 -80.340454) (xy 32.311594 -80.568292) (xy 32.311594 -81.653888) (xy 32.172402 -81.79308)
			(xy 31.770574 -81.79308) (xy 31.588202 -81.975452) (xy 31.588202 -82.901536) (xy 30.657292 -83.832446)
			(xy 30.657292 -84.941918) (xy 30.856174 -85.1408) (xy 33.1724 -85.1408)
		)
		(stroke
			(width 0)
			(type solid)
		)
		(fill yes)
		(layer "B.Cu")
		(net "VR_FET_SW_P12V_STBY_PVCCIN_CPU1")
	)
	(gr_poly
		(pts
			(arc
				(start 83.134708 -26.827734)
				(mid 82.779108 -26.827734)
				(end 83.134708 -26.827734)
			)
		)
		(stroke
			(width 0)
			(type solid)
		)
		(fill yes)
		(layer "B.Cu")
		(net "PVDDQ_GHJ")
	)
	(gr_poly
		(pts
			(arc
				(start 102.12705 -26.8732)
				(mid 101.77145 -26.8732)
				(end 102.12705 -26.8732)
			)
		)
		(stroke
			(width 0)
			(type solid)
		)
		(fill yes)
		(layer "B.Cu")
		(net "PVDDQ_GHJ")
	)
	(gr_poly
		(pts
			(arc
				(start 103.841804 -26.8605)
				(mid 103.486204 -26.8605)
				(end 103.841804 -26.8605)
			)
		)
		(stroke
			(width 0)
			(type solid)
		)
		(fill yes)
		(layer "B.Cu")
		(net "PVDDQ_GHJ")
	)
	(gr_poly
		(pts
			(arc
				(start 105.54208 -26.8732)
				(mid 105.18648 -26.8732)
				(end 105.54208 -26.8732)
			)
		)
		(stroke
			(width 0)
			(type solid)
		)
		(fill yes)
		(layer "B.Cu")
		(net "PVDDQ_GHJ")
	)
	(gr_poly
		(pts
			(arc
				(start 107.239562 -26.8732)
				(mid 106.883962 -26.8732)
				(end 107.239562 -26.8732)
			)
		)
		(stroke
			(width 0)
			(type solid)
		)
		(fill yes)
		(layer "B.Cu")
		(net "PVDDQ_GHJ")
	)
	(gr_poly
		(pts
			(arc
				(start 108.812584 -26.8732)
				(mid 108.456984 -26.8732)
				(end 108.812584 -26.8732)
			)
		)
		(stroke
			(width 0)
			(type solid)
		)
		(fill yes)
		(layer "B.Cu")
		(net "PVDDQ_GHJ")
	)
	(gr_poly
		(pts
			(arc
				(start 248.13514 -26.827734)
				(mid 247.77954 -26.827734)
				(end 248.13514 -26.827734)
			)
		)
		(stroke
			(width 0)
			(type solid)
		)
		(fill yes)
		(layer "B.Cu")
		(net "PVDDQ_ABC")
	)
	(gr_poly
		(pts
			(arc
				(start 267.127482 -26.8732)
				(mid 266.771882 -26.8732)
				(end 267.127482 -26.8732)
			)
		)
		(stroke
			(width 0)
			(type solid)
		)
		(fill yes)
		(layer "B.Cu")
		(net "PVDDQ_ABC")
	)
	(gr_poly
		(pts
			(arc
				(start 268.842236 -26.8605)
				(mid 268.486636 -26.8605)
				(end 268.842236 -26.8605)
			)
		)
		(stroke
			(width 0)
			(type solid)
		)
		(fill yes)
		(layer "B.Cu")
		(net "PVDDQ_ABC")
	)
	(gr_poly
		(pts
			(arc
				(start 270.542512 -26.8732)
				(mid 270.186912 -26.8732)
				(end 270.542512 -26.8732)
			)
		)
		(stroke
			(width 0)
			(type solid)
		)
		(fill yes)
		(layer "B.Cu")
		(net "PVDDQ_ABC")
	)
	(gr_poly
		(pts
			(arc
				(start 272.239994 -26.8732)
				(mid 271.884394 -26.8732)
				(end 272.239994 -26.8732)
			)
		)
		(stroke
			(width 0)
			(type solid)
		)
		(fill yes)
		(layer "B.Cu")
		(net "PVDDQ_ABC")
	)
	(gr_poly
		(pts
			(arc
				(start 273.813016 -26.8732)
				(mid 273.457416 -26.8732)
				(end 273.813016 -26.8732)
			)
		)
		(stroke
			(width 0)
			(type solid)
		)
		(fill yes)
		(layer "B.Cu")
		(net "PVDDQ_ABC")
	)
	(gr_poly
		(pts
			(xy 27.822652 -104.544114) (xy 27.786584 -104.508046) (xy 27.78633 -104.508046) (xy 27.766546 -104.487875)
			(xy 27.732171 -104.443037) (xy 27.704327 -104.393876) (xy 27.68355 -104.341336) (xy 27.670239 -104.286428)
			(xy 27.66465 -104.230206) (xy 27.66689 -104.173752) (xy 27.676917 -104.11815) (xy 27.694537 -104.064469)
			(xy 27.706574 -104.038908) (xy 27.711654 -104.02824) (xy 27.711654 -103.53675) (xy 27.708606 -103.528368)
			(xy 27.700224 -103.502714) (xy 27.696738 -103.492621) (xy 27.683015 -103.476295) (xy 27.663845 -103.466947)
			(xy 27.64253 -103.466188) (xy 27.622744 -103.47415) (xy 27.61488 -103.481378) (xy 27.594867 -103.501292)
			(xy 27.550311 -103.535965) (xy 27.501389 -103.564145) (xy 27.449041 -103.585291) (xy 27.394273 -103.598997)
			(xy 27.338135 -103.604999) (xy 27.281707 -103.603182) (xy 27.226072 -103.593581) (xy 27.172298 -103.57638)
			(xy 27.121419 -103.55191) (xy 27.074411 -103.520641) (xy 27.032178 -103.483174) (xy 26.995531 -103.440227)
			(xy 26.965173 -103.392626) (xy 26.941688 -103.341285) (xy 26.925526 -103.28719) (xy 26.916998 -103.231381)
			(xy 26.916268 -103.174928) (xy 26.92335 -103.118916) (xy 26.938108 -103.064421) (xy 26.960258 -103.01249)
			(xy 26.989375 -102.964121) (xy 27.0249 -102.920241) (xy 27.06615 -102.881694) (xy 27.112333 -102.84922)
			(xy 27.162563 -102.823443) (xy 27.215874 -102.804858) (xy 27.271242 -102.793821) (xy 27.327605 -102.790546)
			(xy 27.383879 -102.795095) (xy 27.438983 -102.807379) (xy 27.491861 -102.827165) (xy 27.541494 -102.854071)
			(xy 27.586932 -102.88758) (xy 27.6273 -102.92705) (xy 27.661824 -102.971722) (xy 27.68984 -103.020737)
			(xy 27.700732 -103.046784) (xy 27.706806 -103.060608) (xy 27.725655 -103.084178) (xy 27.750576 -103.101199)
			(xy 27.779388 -103.110181) (xy 27.809568 -103.110337) (xy 27.838471 -103.101654) (xy 27.851354 -103.093774)
			(xy 27.866365 -103.084128) (xy 27.897918 -103.067463) (xy 27.914346 -103.0605) (xy 27.923744 -103.056436)
			(xy 28.854654 -102.125526) (xy 28.864368 -102.115079) (xy 28.878106 -102.090091) (xy 28.88441 -102.062282)
			(xy 28.88279 -102.033813) (xy 28.873372 -102.006898) (xy 28.856889 -101.98363) (xy 28.834621 -101.965818)
			(xy 28.821634 -101.959918) (xy 28.795444 -101.948551) (xy 28.746267 -101.919549) (xy 28.701628 -101.883957)
			(xy 28.662402 -101.842473) (xy 28.629361 -101.795914) (xy 28.603153 -101.745192) (xy 28.584293 -101.691305)
			(xy 28.573151 -101.635311) (xy 28.569947 -101.578309) (xy 28.574742 -101.521419) (xy 28.587444 -101.465757)
			(xy 28.607802 -101.412418) (xy 28.635417 -101.362449) (xy 28.669746 -101.31683) (xy 28.710115 -101.276459)
			(xy 28.755731 -101.242128) (xy 28.805699 -101.214511) (xy 28.859037 -101.19415) (xy 28.914698 -101.181445)
			(xy 28.971588 -101.176647) (xy 29.028591 -101.179848) (xy 29.084586 -101.190987) (xy 29.138474 -101.209844)
			(xy 29.189196 -101.23605) (xy 29.235757 -101.269089) (xy 29.277243 -101.308312) (xy 29.312837 -101.35295)
			(xy 29.341842 -101.402126) (xy 29.353256 -101.428296) (xy 29.359136 -101.441322) (xy 29.376902 -101.463691)
			(xy 29.400175 -101.480256) (xy 29.427128 -101.489718) (xy 29.455649 -101.491334) (xy 29.483499 -101.484976)
			(xy 29.508493 -101.471145) (xy 29.518864 -101.461316) (xy 29.58338 -101.3968) (xy 33.204912 -101.3968)
			(xy 33.340294 -101.261418) (xy 33.340294 -96.650556) (xy 33.328356 -96.638618) (xy 32.33166 -96.638618)
			(xy 32.3088 -96.661478) (xy 32.3088 -97.6884) (xy 32.021272 -97.975928) (xy 30.258258 -97.975928)
			(xy 30.101794 -98.132392) (xy 30.098238 -98.132392) (xy 30.062678 -98.167952) (xy 29.15412 -98.167952)
			(xy 28.683712 -97.697544) (xy 28.683712 -96.868488) (xy 29.725366 -95.826834) (xy 29.725366 -94.45752)
			(xy 29.516324 -94.248478) (xy 29.516324 -93.490796) (xy 29.803598 -93.203522) (xy 33.212278 -93.203522)
			(xy 33.3248 -93.091) (xy 33.3248 -88.556084) (xy 33.283144 -88.514428) (xy 32.323786 -88.514428)
			(xy 32.29991 -88.538304) (xy 32.29991 -89.47023) (xy 32.0548 -89.71534) (xy 31.555944 -89.71534)
			(xy 31.214568 -90.056716) (xy 29.109924 -90.056716) (xy 27.59964 -91.567) (xy 29.645862 -91.567)
			(xy 29.649933 -91.511378) (xy 29.662059 -91.456941) (xy 29.681982 -91.40485) (xy 29.709278 -91.356215)
			(xy 29.743364 -91.312072) (xy 29.783513 -91.273363) (xy 29.828871 -91.240912) (xy 29.878471 -91.215411)
			(xy 29.931255 -91.197404) (xy 29.986098 -91.187274) (xy 30.041832 -91.185237) (xy 30.097269 -91.191337)
			(xy 30.151226 -91.205443) (xy 30.202555 -91.227255) (xy 30.250161 -91.256309) (xy 30.293029 -91.291984)
			(xy 30.330246 -91.333521) (xy 30.361019 -91.380034) (xy 30.384691 -91.430531) (xy 30.400759 -91.483938)
			(xy 30.408879 -91.539114) (xy 30.409388 -91.567) (xy 30.408879 -91.594886) (xy 30.400759 -91.650062)
			(xy 30.384691 -91.703469) (xy 30.361019 -91.753966) (xy 30.330246 -91.800479) (xy 30.293029 -91.842016)
			(xy 30.250161 -91.877691) (xy 30.202555 -91.906745) (xy 30.151226 -91.928557) (xy 30.097269 -91.942663)
			(xy 30.041832 -91.948763) (xy 29.986098 -91.946726) (xy 29.931255 -91.936596) (xy 29.878471 -91.918589)
			(xy 29.828871 -91.893088) (xy 29.783513 -91.860637) (xy 29.743364 -91.821928) (xy 29.709278 -91.777785)
			(xy 29.681982 -91.72915) (xy 29.662059 -91.677059) (xy 29.649933 -91.622622) (xy 29.645862 -91.567)
			(xy 27.59964 -91.567) (xy 26.796746 -92.369894) (xy 26.796746 -93.023746) (xy 28.244217 -93.023746)
			(xy 28.250701 -92.970577) (xy 28.265075 -92.91898) (xy 28.287017 -92.870118) (xy 28.31603 -92.825094)
			(xy 28.35146 -92.784924) (xy 28.392508 -92.750514) (xy 28.438247 -92.722642) (xy 28.487645 -92.701935)
			(xy 28.539587 -92.688861) (xy 28.592902 -92.683716) (xy 28.646386 -92.686615) (xy 28.698832 -92.697493)
			(xy 28.749057 -92.716104) (xy 28.795928 -92.742029) (xy 28.838386 -92.774682) (xy 28.875474 -92.813327)
			(xy 28.906355 -92.857091) (xy 28.930331 -92.904987) (xy 28.946863 -92.955935) (xy 28.955576 -93.008784)
			(xy 28.956275 -93.062342) (xy 28.948943 -93.1154) (xy 28.933746 -93.166761) (xy 28.911026 -93.215266)
			(xy 28.896564 -93.237812) (xy 28.888368 -93.250952) (xy 28.879642 -93.280653) (xy 28.880202 -93.311604)
			(xy 28.889997 -93.34097) (xy 28.908129 -93.36606) (xy 28.932938 -93.384576) (xy 28.947364 -93.390212)
			(xy 28.972461 -93.399571) (xy 29.01974 -93.424744) (xy 29.062714 -93.456715) (xy 29.100415 -93.494762)
			(xy 29.131991 -93.538027) (xy 29.156729 -93.585535) (xy 29.174072 -93.636211) (xy 29.183629 -93.688914)
			(xy 29.185183 -93.742454) (xy 29.178699 -93.795623) (xy 29.164325 -93.84722) (xy 29.142383 -93.896082)
			(xy 29.11337 -93.941106) (xy 29.07794 -93.981276) (xy 29.036892 -94.015686) (xy 28.991153 -94.043558)
			(xy 28.941755 -94.064265) (xy 28.889813 -94.077339) (xy 28.836498 -94.082484) (xy 28.783014 -94.079585)
			(xy 28.730568 -94.068707) (xy 28.680343 -94.050096) (xy 28.633472 -94.024171) (xy 28.591014 -93.991518)
			(xy 28.553926 -93.952873) (xy 28.523045 -93.909109) (xy 28.499069 -93.861213) (xy 28.482537 -93.810265)
			(xy 28.473824 -93.757416) (xy 28.473125 -93.703858) (xy 28.480457 -93.6508) (xy 28.495654 -93.599439)
			(xy 28.518374 -93.550934) (xy 28.532836 -93.528388) (xy 28.541032 -93.515248) (xy 28.549758 -93.485547)
			(xy 28.549198 -93.454596) (xy 28.539403 -93.42523) (xy 28.521271 -93.40014) (xy 28.496462 -93.381624)
			(xy 28.482036 -93.375988) (xy 28.456939 -93.366629) (xy 28.40966 -93.341456) (xy 28.366686 -93.309485)
			(xy 28.328985 -93.271438) (xy 28.297409 -93.228173) (xy 28.272671 -93.180665) (xy 28.255328 -93.129989)
			(xy 28.245771 -93.077286) (xy 28.244217 -93.023746) (xy 26.796746 -93.023746) (xy 26.796746 -93.98)
			(xy 27.405595 -93.98) (xy 27.40956 -93.9233) (xy 27.421377 -93.867704) (xy 27.440817 -93.814293)
			(xy 27.467501 -93.764108) (xy 27.50091 -93.718125) (xy 27.540393 -93.677239) (xy 27.585182 -93.642246)
			(xy 27.634405 -93.613827) (xy 27.687105 -93.592535) (xy 27.742255 -93.578784) (xy 27.798782 -93.572843)
			(xy 27.855585 -93.574827) (xy 27.91156 -93.584697) (xy 27.965617 -93.602261) (xy 28.016703 -93.627177)
			(xy 28.063824 -93.65896) (xy 28.106063 -93.696993) (xy 28.142598 -93.740533) (xy 28.172717 -93.788735)
			(xy 28.195835 -93.840659) (xy 28.211502 -93.895296) (xy 28.219413 -93.951581) (xy 28.219908 -93.98)
			(xy 28.219413 -94.008419) (xy 28.211502 -94.064704) (xy 28.195835 -94.119341) (xy 28.172717 -94.171265)
			(xy 28.142598 -94.219467) (xy 28.106063 -94.263007) (xy 28.063824 -94.30104) (xy 28.016703 -94.332823)
			(xy 27.965617 -94.357739) (xy 27.91156 -94.375303) (xy 27.855585 -94.385173) (xy 27.798782 -94.387157)
			(xy 27.742255 -94.381216) (xy 27.687105 -94.367465) (xy 27.634405 -94.346173) (xy 27.585182 -94.317754)
			(xy 27.540393 -94.282761) (xy 27.50091 -94.241875) (xy 27.467501 -94.195892) (xy 27.440817 -94.145707)
			(xy 27.421377 -94.092296) (xy 27.40956 -94.0367) (xy 27.405595 -93.98) (xy 26.796746 -93.98) (xy 26.796746 -95.548429)
			(xy 27.49295 -95.548429) (xy 27.49295 -95.495131) (xy 27.500893 -95.442427) (xy 27.516603 -95.391497)
			(xy 27.539729 -95.343476) (xy 27.569753 -95.299439) (xy 27.606005 -95.260368) (xy 27.647676 -95.227137)
			(xy 27.693834 -95.200488) (xy 27.743448 -95.181016) (xy 27.79541 -95.169156) (xy 27.84856 -95.165173)
			(xy 27.90171 -95.169156) (xy 27.953672 -95.181016) (xy 28.003286 -95.200488) (xy 28.049444 -95.227137)
			(xy 28.091115 -95.260368) (xy 28.127367 -95.299439) (xy 28.157391 -95.343476) (xy 28.180517 -95.391497)
			(xy 28.196227 -95.442427) (xy 28.20417 -95.495131) (xy 28.204668 -95.52178) (xy 28.20417 -95.548429)
			(xy 28.196227 -95.601133) (xy 28.180517 -95.652063) (xy 28.157391 -95.700084) (xy 28.127367 -95.744121)
			(xy 28.091115 -95.783192) (xy 28.049444 -95.816423) (xy 28.003286 -95.843072) (xy 27.953672 -95.862544)
			(xy 27.90171 -95.874404) (xy 27.84856 -95.878388) (xy 27.79541 -95.874404) (xy 27.743448 -95.862544)
			(xy 27.693834 -95.843072) (xy 27.647676 -95.816423) (xy 27.606005 -95.783192) (xy 27.569753 -95.744121)
			(xy 27.539729 -95.700084) (xy 27.516603 -95.652063) (xy 27.500893 -95.601133) (xy 27.49295 -95.548429)
			(xy 26.796746 -95.548429) (xy 26.796746 -98.23704) (xy 25.356566 -99.67722) (xy 25.356566 -100.014024)
			(xy 25.616419 -100.014024) (xy 25.620384 -99.957324) (xy 25.632201 -99.901728) (xy 25.651641 -99.848317)
			(xy 25.678325 -99.798132) (xy 25.711734 -99.752149) (xy 25.751217 -99.711263) (xy 25.796006 -99.67627)
			(xy 25.845229 -99.647851) (xy 25.897929 -99.626559) (xy 25.953079 -99.612808) (xy 26.009606 -99.606867)
			(xy 26.066409 -99.608851) (xy 26.122384 -99.618721) (xy 26.176441 -99.636285) (xy 26.227527 -99.661201)
			(xy 26.274648 -99.692984) (xy 26.316887 -99.731017) (xy 26.353422 -99.774557) (xy 26.383541 -99.822759)
			(xy 26.406659 -99.874683) (xy 26.422326 -99.92932) (xy 26.430237 -99.985605) (xy 26.43067 -100.010492)
			(xy 26.879288 -100.010492) (xy 26.887388 -99.957278) (xy 26.903405 -99.905888) (xy 26.926975 -99.857495)
			(xy 26.957558 -99.8132) (xy 26.994461 -99.774013) (xy 27.03684 -99.740826) (xy 27.083732 -99.714395)
			(xy 27.134068 -99.695323) (xy 27.1867 -99.684044) (xy 27.240431 -99.680814) (xy 27.294035 -99.685708)
			(xy 27.346293 -99.698615) (xy 27.396013 -99.719239) (xy 27.442062 -99.747111) (xy 27.483392 -99.781596)
			(xy 27.501596 -99.801426) (xy 27.511489 -99.811878) (xy 27.535787 -99.827276) (xy 27.563413 -99.835293)
			(xy 27.592179 -99.835293) (xy 27.619805 -99.827276) (xy 27.644103 -99.811878) (xy 27.653996 -99.801426)
			(xy 27.672207 -99.781603) (xy 27.713537 -99.747117) (xy 27.759585 -99.719245) (xy 27.809305 -99.69862)
			(xy 27.861562 -99.685714) (xy 27.915166 -99.680819) (xy 27.968896 -99.684048) (xy 28.021528 -99.695326)
			(xy 28.071864 -99.714398) (xy 28.118755 -99.740828) (xy 28.161135 -99.774015) (xy 28.198037 -99.813202)
			(xy 28.228621 -99.857496) (xy 28.25219 -99.905889) (xy 28.268207 -99.957278) (xy 28.276307 -100.010492)
			(xy 28.276307 -100.06432) (xy 28.268204 -100.117534) (xy 28.252185 -100.168922) (xy 28.228615 -100.217314)
			(xy 28.198029 -100.261608) (xy 28.161126 -100.300793) (xy 28.118745 -100.333978) (xy 28.071853 -100.360407)
			(xy 28.021517 -100.379477) (xy 27.968884 -100.390754) (xy 27.915154 -100.393981) (xy 27.86155 -100.389084)
			(xy 27.809293 -100.376176) (xy 27.759575 -100.35555) (xy 27.713527 -100.327676) (xy 27.672199 -100.293189)
			(xy 27.653996 -100.273358) (xy 27.644103 -100.262906) (xy 27.619805 -100.247508) (xy 27.592179 -100.239491)
			(xy 27.563413 -100.239491) (xy 27.535787 -100.247508) (xy 27.511489 -100.262906) (xy 27.501596 -100.273358)
			(xy 27.483401 -100.293195) (xy 27.442072 -100.327682) (xy 27.396023 -100.355556) (xy 27.346304 -100.376182)
			(xy 27.294047 -100.38909) (xy 27.240443 -100.393986) (xy 27.186712 -100.390758) (xy 27.134079 -100.379481)
			(xy 27.083743 -100.36041) (xy 27.03685 -100.333981) (xy 26.994469 -100.300795) (xy 26.957566 -100.261609)
			(xy 26.926981 -100.217315) (xy 26.90341 -100.168923) (xy 26.887391 -100.117534) (xy 26.879289 -100.06432)
			(xy 26.879288 -100.010492) (xy 26.43067 -100.010492) (xy 26.430732 -100.014024) (xy 26.430237 -100.042443)
			(xy 26.422326 -100.098728) (xy 26.406659 -100.153365) (xy 26.383541 -100.205289) (xy 26.353422 -100.253491)
			(xy 26.316887 -100.297031) (xy 26.274648 -100.335064) (xy 26.227527 -100.366847) (xy 26.176441 -100.391763)
			(xy 26.122384 -100.409327) (xy 26.066409 -100.419197) (xy 26.009606 -100.421181) (xy 25.953079 -100.41524)
			(xy 25.897929 -100.401489) (xy 25.845229 -100.380197) (xy 25.796006 -100.351778) (xy 25.751217 -100.316785)
			(xy 25.711734 -100.275899) (xy 25.678325 -100.229916) (xy 25.651641 -100.179731) (xy 25.632201 -100.12632)
			(xy 25.620384 -100.070724) (xy 25.616419 -100.014024) (xy 25.356566 -100.014024) (xy 25.356566 -102.261162)
			(xy 27.671537 -102.261162) (xy 27.675472 -102.207391) (xy 27.687195 -102.154767) (xy 27.706455 -102.10441)
			(xy 27.732841 -102.057393) (xy 27.765793 -102.01472) (xy 27.804606 -101.977299) (xy 27.848454 -101.945929)
			(xy 27.896402 -101.921277) (xy 27.947429 -101.903869) (xy 28.000447 -101.894076) (xy 28.054326 -101.892107)
			(xy 28.107917 -101.898004) (xy 28.160078 -101.91164) (xy 28.209698 -101.932727) (xy 28.255719 -101.960813)
			(xy 28.297161 -101.995301) (xy 28.333139 -102.035455) (xy 28.362887 -102.080419) (xy 28.385772 -102.129236)
			(xy 28.401304 -102.180865) (xy 28.409154 -102.234205) (xy 28.409646 -102.261162) (xy 28.409154 -102.288119)
			(xy 28.401304 -102.341459) (xy 28.385772 -102.393088) (xy 28.362887 -102.441905) (xy 28.333139 -102.486869)
			(xy 28.297161 -102.527023) (xy 28.255719 -102.561511) (xy 28.209698 -102.589597) (xy 28.160078 -102.610684)
			(xy 28.107917 -102.62432) (xy 28.054326 -102.630217) (xy 28.000447 -102.628248) (xy 27.947429 -102.618455)
			(xy 27.896402 -102.601047) (xy 27.848454 -102.576395) (xy 27.804606 -102.545025) (xy 27.765793 -102.507604)
			(xy 27.732841 -102.464931) (xy 27.706455 -102.417914) (xy 27.687195 -102.367557) (xy 27.675472 -102.314933)
			(xy 27.671537 -102.261162) (xy 25.356566 -102.261162) (xy 25.356566 -102.30231) (xy 25.730708 -103.206042)
			(xy 27.39136 -104.866694) (xy 27.500072 -104.866694)
		)
		(stroke
			(width 0)
			(type solid)
		)
		(fill yes)
		(layer "B.Cu")
		(net "VR_FET_SW_P12V_STBY_PVCCIN_CPU1")
	)
	(gr_poly
		(pts
			(xy 355.8286 -20.574) (xy 355.8286 -20.2438) (xy 356.3874 -19.685) (xy 356.3874 -13.437108) (xy 356.387005 -13.423784)
			(xy 356.38011 -13.398042) (xy 356.366786 -13.374963) (xy 356.347944 -13.356119) (xy 356.324865 -13.342793)
			(xy 356.299124 -13.335896) (xy 356.2858 -13.335508) (xy 356.259151 -13.33501) (xy 356.206447 -13.327067)
			(xy 356.155517 -13.311357) (xy 356.107496 -13.288231) (xy 356.063459 -13.258207) (xy 356.024388 -13.221955)
			(xy 355.991157 -13.180284) (xy 355.964508 -13.134126) (xy 355.945036 -13.084512) (xy 355.933176 -13.03255)
			(xy 355.929193 -12.9794) (xy 355.933176 -12.92625) (xy 355.945036 -12.874288) (xy 355.964508 -12.824674)
			(xy 355.991157 -12.778516) (xy 356.024388 -12.736845) (xy 356.063459 -12.700593) (xy 356.107496 -12.670569)
			(xy 356.155517 -12.647443) (xy 356.206447 -12.631733) (xy 356.259151 -12.62379) (xy 356.2858 -12.623292)
			(xy 356.299123 -12.622896) (xy 356.324862 -12.615999) (xy 356.347939 -12.602675) (xy 356.36678 -12.583832)
			(xy 356.380102 -12.560755) (xy 356.386997 -12.535015) (xy 356.3874 -12.521692) (xy 356.3874 -12.19962)
			(xy 356.341645 -12.166901) (xy 356.254553 -12.095695) (xy 356.172947 -12.018262) (xy 356.097272 -11.935024)
			(xy 356.027939 -11.846434) (xy 355.965325 -11.752974) (xy 355.909771 -11.655152) (xy 355.86158 -11.553501)
			(xy 355.821013 -11.448574) (xy 355.788292 -11.340942) (xy 355.763595 -11.23119) (xy 355.747056 -11.119917)
			(xy 355.738764 -11.007727) (xy 355.738766 -10.895231) (xy 355.74706 -10.783042) (xy 355.763603 -10.671769)
			(xy 355.788303 -10.562018) (xy 355.821027 -10.454387) (xy 355.861596 -10.349461) (xy 355.90979 -10.247812)
			(xy 355.965346 -10.149991) (xy 356.027963 -10.056533) (xy 356.097298 -9.967944) (xy 356.172976 -9.884709)
			(xy 356.254584 -9.807278) (xy 356.341678 -9.736074) (xy 356.3874 -9.703308) (xy 356.3874 -7.940802)
			(xy 354.928424 -6.481826) (xy 354.928424 -4.027932) (xy 354.09632 -3.195828) (xy 354.09632 -0.90932)
			(xy 352.9838 0.2032) (xy 352.9838 1.06172) (xy 352.983344 1.075471) (xy 352.975997 1.101973) (xy 352.961841 1.125552)
			(xy 352.941904 1.144496) (xy 352.917633 1.15743) (xy 352.89079 1.163415) (xy 352.863324 1.162017)
			(xy 352.837227 1.153337) (xy 352.825558 1.146048) (xy 352.803233 1.131615) (xy 352.755211 1.108818)
			(xy 352.704333 1.093412) (xy 352.651731 1.085739) (xy 352.598573 1.08597) (xy 352.54604 1.094101)
			(xy 352.495298 1.109949) (xy 352.447476 1.133164) (xy 352.403636 1.163229) (xy 352.364752 1.199476)
			(xy 352.331687 1.2411) (xy 352.305177 1.287177) (xy 352.28581 1.336683) (xy 352.274017 1.388517)
			(xy 352.27006 1.441528) (xy 352.274025 1.494539) (xy 352.285827 1.546371) (xy 352.305201 1.595873)
			(xy 352.331719 1.641946) (xy 352.36479 1.683565) (xy 352.40368 1.719806) (xy 352.447525 1.749864)
			(xy 352.49535 1.773072) (xy 352.546094 1.788912) (xy 352.598629 1.797034) (xy 352.651787 1.797257)
			(xy 352.704388 1.789576) (xy 352.755263 1.774162) (xy 352.803282 1.751357) (xy 352.825558 1.736852)
			(xy 352.837227 1.729562) (xy 352.863323 1.720881) (xy 352.89079 1.719483) (xy 352.917634 1.725468)
			(xy 352.941905 1.738402) (xy 352.961842 1.757347) (xy 352.975999 1.780926) (xy 352.983346 1.807429)
			(xy 352.9838 1.82118) (xy 352.9838 4.699) (xy 352.6282 5.0546) (xy 347.3958 5.0546) (xy 347.0402 4.699)
			(xy 347.0402 4.414541) (xy 351.588822 4.414541) (xy 351.588822 4.467839) (xy 351.596765 4.520543)
			(xy 351.612475 4.571473) (xy 351.635601 4.619494) (xy 351.665625 4.663531) (xy 351.701877 4.702602)
			(xy 351.743548 4.735833) (xy 351.789706 4.762482) (xy 351.83932 4.781954) (xy 351.891282 4.793814)
			(xy 351.944432 4.797798) (xy 351.997582 4.793814) (xy 352.049544 4.781954) (xy 352.099158 4.762482)
			(xy 352.145316 4.735833) (xy 352.186987 4.702602) (xy 352.223239 4.663531) (xy 352.253263 4.619494)
			(xy 352.276389 4.571473) (xy 352.292099 4.520543) (xy 352.300042 4.467839) (xy 352.30054 4.44119)
			(xy 352.300042 4.414541) (xy 352.292099 4.361837) (xy 352.276389 4.310907) (xy 352.253263 4.262886)
			(xy 352.223239 4.218849) (xy 352.186987 4.179778) (xy 352.145316 4.146547) (xy 352.099158 4.119898)
			(xy 352.049544 4.100426) (xy 351.997582 4.088566) (xy 351.944432 4.084583) (xy 351.891282 4.088566)
			(xy 351.83932 4.100426) (xy 351.789706 4.119898) (xy 351.743548 4.146547) (xy 351.701877 4.179778)
			(xy 351.665625 4.218849) (xy 351.635601 4.262886) (xy 351.612475 4.310907) (xy 351.596765 4.361837)
			(xy 351.588822 4.414541) (xy 347.0402 4.414541) (xy 347.0402 2.45941) (xy 349.840546 2.45941) (xy 349.840546 2.518482)
			(xy 349.84859 2.577004) (xy 349.864527 2.633886) (xy 349.888062 2.688068) (xy 349.918755 2.738541)
			(xy 349.956035 2.784364) (xy 349.999207 2.824684) (xy 350.047467 2.85875) (xy 350.099917 2.885927)
			(xy 350.155578 2.905709) (xy 350.213415 2.917728) (xy 350.27235 2.921759) (xy 350.331285 2.917728)
			(xy 350.389122 2.905709) (xy 350.444783 2.885927) (xy 350.497233 2.85875) (xy 350.545493 2.824684)
			(xy 350.588665 2.784364) (xy 350.625945 2.738541) (xy 350.656638 2.688068) (xy 350.680173 2.633886)
			(xy 350.69611 2.577004) (xy 350.704154 2.518482) (xy 350.704658 2.488946) (xy 350.704154 2.45941)
			(xy 350.69611 2.400888) (xy 350.680173 2.344006) (xy 350.656638 2.289824) (xy 350.625945 2.239351)
			(xy 350.588665 2.193528) (xy 350.545493 2.153208) (xy 350.497233 2.119142) (xy 350.444783 2.091965)
			(xy 350.389122 2.072183) (xy 350.331285 2.060164) (xy 350.27235 2.056133) (xy 350.213415 2.060164)
			(xy 350.155578 2.072183) (xy 350.099917 2.091965) (xy 350.047467 2.119142) (xy 349.999207 2.153208)
			(xy 349.956035 2.193528) (xy 349.918755 2.239351) (xy 349.888062 2.289824) (xy 349.864527 2.344006)
			(xy 349.84859 2.400888) (xy 349.840546 2.45941) (xy 347.0402 2.45941) (xy 347.0402 -0.298196) (xy 347.528896 -0.298196)
			(xy 347.550009 -0.26589) (xy 347.598195 -0.205598) (xy 347.652627 -0.150881) (xy 347.712665 -0.102381)
			(xy 347.777604 -0.060669) (xy 347.846678 -0.026237) (xy 347.919076 0.000512) (xy 347.956378 0.010414)
			(xy 347.969264 0.014087) (xy 347.992633 0.027178) (xy 348.01179 0.045899) (xy 348.025417 0.06896)
			(xy 348.032574 0.094772) (xy 348.032769 0.121557) (xy 348.029784 0.13462) (xy 348.023666 0.159877)
			(xy 348.017534 0.211482) (xy 348.01847 0.263441) (xy 348.026459 0.314791) (xy 348.041351 0.364579)
			(xy 348.062871 0.411882) (xy 348.090619 0.455821) (xy 348.107 0.475996) (xy 348.116085 0.487585)
			(xy 348.127795 0.514591) (xy 348.131317 0.543815) (xy 348.12636 0.57283) (xy 348.113335 0.599227)
			(xy 348.103698 0.610362) (xy 348.085057 0.631194) (xy 348.05345 0.677301) (xy 348.028913 0.727528)
			(xy 348.01197 0.7808) (xy 348.002986 0.835973) (xy 348.002152 0.891868) (xy 348.009487 0.947285)
			(xy 348.024834 1.001037) (xy 348.047863 1.051974) (xy 348.078081 1.099003) (xy 348.096078 1.120394)
			(xy 348.105317 1.13172) (xy 348.117498 1.158278) (xy 348.121673 1.187197) (xy 348.1175 1.216116)
			(xy 348.10532 1.242674) (xy 348.096078 1.253998) (xy 348.078497 1.274871) (xy 348.048859 1.320696)
			(xy 348.026055 1.370278) (xy 348.010549 1.422602) (xy 348.002657 1.476603) (xy 348.002542 1.531177)
			(xy 348.010205 1.58521) (xy 348.025489 1.6376) (xy 348.048084 1.687277) (xy 348.077527 1.733227)
			(xy 348.113217 1.774513) (xy 348.154427 1.810291) (xy 348.200315 1.839831) (xy 348.249944 1.862531)
			(xy 348.302302 1.877926) (xy 348.356319 1.885703) (xy 348.410893 1.885703) (xy 348.46491 1.877926)
			(xy 348.517268 1.862531) (xy 348.566897 1.839831) (xy 348.612785 1.810291) (xy 348.653995 1.774513)
			(xy 348.689685 1.733227) (xy 348.719128 1.687277) (xy 348.741723 1.6376) (xy 348.757007 1.58521)
			(xy 348.76467 1.531177) (xy 348.764555 1.476603) (xy 348.756663 1.422602) (xy 348.741157 1.370278)
			(xy 348.718353 1.320696) (xy 348.688715 1.274871) (xy 348.671134 1.253998) (xy 348.661895 1.242672)
			(xy 348.649715 1.216115) (xy 348.645541 1.187197) (xy 348.649716 1.158279) (xy 348.661898 1.131723)
			(xy 348.671134 1.120394) (xy 348.688559 1.099721) (xy 348.718009 1.054381) (xy 348.740759 1.005335)
			(xy 348.756354 0.953567) (xy 348.76448 0.900116) (xy 348.764975 0.846053) (xy 348.757828 0.792462)
			(xy 348.743183 0.740418) (xy 348.721334 0.690964) (xy 348.692719 0.645092) (xy 348.675706 0.624078)
			(xy 348.666624 0.612489) (xy 348.654921 0.585485) (xy 348.651404 0.556266) (xy 348.656366 0.527256)
			(xy 348.669395 0.500866) (xy 348.679008 0.489712) (xy 348.700302 0.465754) (xy 348.735406 0.412127)
			(xy 348.748858 0.383032) (xy 348.755331 0.369565) (xy 348.774716 0.346845) (xy 348.799844 0.330704)
			(xy 348.828566 0.322519) (xy 348.858428 0.322991) (xy 348.886877 0.332079) (xy 348.89948 0.340106)
			(xy 348.930412 0.360852) (xy 348.995804 0.396512) (xy 349.064562 0.425148) (xy 349.135935 0.446449)
			(xy 349.209141 0.460182) (xy 349.283381 0.466195) (xy 349.357844 0.464425) (xy 349.431714 0.454889)
			(xy 349.504185 0.437692) (xy 349.574464 0.413023) (xy 349.641784 0.38115) (xy 349.705407 0.342423)
			(xy 349.76464 0.297264) (xy 349.792036 0.272034) (xy 349.803239 0.262217) (xy 349.82989 0.248942)
			(xy 349.859235 0.243902) (xy 349.888788 0.247523) (xy 349.916048 0.259498) (xy 349.938706 0.278814)
			(xy 349.954845 0.303834) (xy 349.959422 0.318008) (xy 349.966778 0.3429) (xy 349.984449 0.39171)
			(xy 349.994728 0.415544) (xy 349.96667 0.443074) (xy 349.915769 0.50298) (xy 349.871301 0.567805)
			(xy 349.833738 0.636861) (xy 349.803478 0.709414) (xy 349.780843 0.784696) (xy 349.766072 0.861907)
			(xy 349.759323 0.940227) (xy 349.760666 1.018827) (xy 349.770089 1.096871) (xy 349.78749 1.173532)
			(xy 349.812685 1.247996) (xy 349.845408 1.319473) (xy 349.885309 1.387204) (xy 349.931967 1.450471)
			(xy 349.984886 1.508603) (xy 350.043504 1.560982) (xy 350.1072 1.607053) (xy 350.175297 1.646326)
			(xy 350.247073 1.678386) (xy 350.321767 1.702892) (xy 350.398585 1.719584) (xy 350.476713 1.728285)
			(xy 350.555322 1.728902) (xy 350.633577 1.721429) (xy 350.710648 1.705945) (xy 350.785717 1.682615)
			(xy 350.822006 1.66751) (xy 350.841731 1.685397) (xy 350.885505 1.715714) (xy 350.933304 1.739175)
			(xy 350.984064 1.755259) (xy 351.036652 1.763605) (xy 351.089897 1.764028) (xy 351.142612 1.756518)
			(xy 351.19362 1.741244) (xy 351.241786 1.718545) (xy 351.286036 1.688927) (xy 351.325382 1.653052)
			(xy 351.358948 1.611717) (xy 351.385986 1.565846) (xy 351.405893 1.516461) (xy 351.418224 1.464662)
			(xy 351.422706 1.411604) (xy 351.419238 1.35847) (xy 351.407898 1.306445) (xy 351.388937 1.256689)
			(xy 351.36278 1.21031) (xy 351.330009 1.168343) (xy 351.291355 1.131722) (xy 351.269808 1.116076)
			(xy 351.276977 1.077727) (xy 351.284387 1.000059) (xy 351.283829 0.92204) (xy 351.275309 0.844486)
			(xy 351.258916 0.768207) (xy 351.234821 0.694) (xy 351.219516 0.658114) (xy 351.247076 0.631064)
			(xy 351.297188 0.572303) (xy 351.341104 0.508777) (xy 351.378373 0.441137) (xy 351.408615 0.370076)
			(xy 351.431518 0.296323) (xy 351.446849 0.220632) (xy 351.45445 0.143779) (xy 351.454244 0.066552)
			(xy 351.446232 -0.010259) (xy 351.430497 -0.085867) (xy 351.407201 -0.159497) (xy 351.37658 -0.230396)
			(xy 351.33895 -0.297835) (xy 351.294696 -0.361126) (xy 351.269808 -0.390652) (xy 351.287233 -0.424469)
			(xy 351.316024 -0.49489) (xy 351.337657 -0.567828) (xy 351.351917 -0.642559) (xy 351.358662 -0.718338)
			(xy 351.357826 -0.794412) (xy 351.349416 -0.870025) (xy 351.333517 -0.944424) (xy 351.310286 -1.016869)
			(xy 351.279954 -1.08664) (xy 351.242824 -1.153043) (xy 351.199264 -1.215417) (xy 351.149708 -1.273142)
			(xy 351.134477 -1.288013) (xy 352.583232 -1.288013) (xy 352.583232 -1.234715) (xy 352.591175 -1.182011)
			(xy 352.606885 -1.131081) (xy 352.630011 -1.08306) (xy 352.660035 -1.039023) (xy 352.696287 -0.999952)
			(xy 352.737958 -0.966721) (xy 352.784116 -0.940072) (xy 352.83373 -0.9206) (xy 352.885692 -0.90874)
			(xy 352.938842 -0.904757) (xy 352.991992 -0.90874) (xy 353.043954 -0.9206) (xy 353.093568 -0.940072)
			(xy 353.139726 -0.966721) (xy 353.181397 -0.999952) (xy 353.217649 -1.039023) (xy 353.247673 -1.08306)
			(xy 353.270799 -1.131081) (xy 353.286509 -1.182011) (xy 353.294452 -1.234715) (xy 353.29495 -1.261364)
			(xy 353.294452 -1.288013) (xy 353.286509 -1.340717) (xy 353.270799 -1.391647) (xy 353.247673 -1.439668)
			(xy 353.217649 -1.483705) (xy 353.181397 -1.522776) (xy 353.139726 -1.556007) (xy 353.093568 -1.582656)
			(xy 353.043954 -1.602128) (xy 352.991992 -1.613988) (xy 352.938842 -1.617972) (xy 352.885692 -1.613988)
			(xy 352.83373 -1.602128) (xy 352.784116 -1.582656) (xy 352.737958 -1.556007) (xy 352.696287 -1.522776)
			(xy 352.660035 -1.483705) (xy 352.630011 -1.439668) (xy 352.606885 -1.391647) (xy 352.591175 -1.340717)
			(xy 352.583232 -1.288013) (xy 351.134477 -1.288013) (xy 351.122488 -1.299718) (xy 351.128977 -1.332105)
			(xy 351.135197 -1.397867) (xy 351.133627 -1.463903) (xy 351.124288 -1.529294) (xy 351.107311 -1.59313)
			(xy 351.082932 -1.654521) (xy 351.051491 -1.712613) (xy 351.013425 -1.766597) (xy 350.969265 -1.815721)
			(xy 350.919625 -1.8593) (xy 350.865197 -1.896728) (xy 350.80674 -1.927484) (xy 350.745066 -1.951139)
			(xy 350.681034 -1.967364) (xy 350.615538 -1.975933) (xy 350.549488 -1.976726) (xy 350.483804 -1.969733)
			(xy 350.419402 -1.955051) (xy 350.357177 -1.932885) (xy 350.297997 -1.903542) (xy 350.242686 -1.867433)
			(xy 350.192014 -1.825059) (xy 350.146686 -1.77701) (xy 350.126554 -1.750822) (xy 350.118223 -1.740391)
			(xy 350.097271 -1.723864) (xy 350.07276 -1.713315) (xy 350.046354 -1.709461) (xy 350.01985 -1.712563)
			(xy 349.995049 -1.722411) (xy 349.98406 -1.729994) (xy 349.950626 -1.754275) (xy 349.879472 -1.796291)
			(xy 349.804197 -1.830378) (xy 349.765112 -1.843786) (xy 349.771634 -1.869376) (xy 349.777929 -1.921805)
			(xy 349.776416 -1.97459) (xy 349.767125 -2.026572) (xy 349.750263 -2.076614) (xy 349.726197 -2.123617)
			(xy 349.695455 -2.166553) (xy 349.658711 -2.204479) (xy 349.616771 -2.236565) (xy 349.570553 -2.262108)
			(xy 349.521071 -2.280547) (xy 349.469408 -2.291479) (xy 349.416698 -2.294663) (xy 349.364096 -2.290031)
			(xy 349.312753 -2.277684) (xy 349.2881 -2.26822) (xy 349.274759 -2.26333) (xy 349.246515 -2.260342)
			(xy 349.21854 -2.26525) (xy 349.192999 -2.277672) (xy 349.171867 -2.296649) (xy 349.15678 -2.320712)
			(xy 349.148903 -2.348) (xy 349.1484 -2.3622) (xy 349.1484 -2.6924) (xy 348.6658 -3.175) (xy 347.066108 -3.175)
			(xy 347.066108 -4.496308) (xy 347.0529 -4.496308) (xy 347.0529 -4.876292) (xy 347.066108 -4.876292)
			(xy 347.066108 -6.147308) (xy 347.0529 -6.147308) (xy 347.0529 -6.527292) (xy 347.066108 -6.527292)
			(xy 347.066108 -7.798308) (xy 347.0529 -7.798308) (xy 347.0529 -8.0518) (xy 347.357192 -8.356092)
			(xy 347.649292 -8.356092) (xy 347.649292 -8.254492) (xy 347.788992 -8.254492) (xy 347.8022 -8.245094)
			(xy 347.836459 -8.221367) (xy 347.909558 -8.181344) (xy 347.986902 -8.150309) (xy 348.02699 -8.138922)
			(xy 348.040011 -8.134956) (xy 348.063476 -8.121182) (xy 348.082481 -8.101712) (xy 348.095685 -8.077921)
			(xy 348.102152 -8.051492) (xy 348.101425 -8.024293) (xy 348.097856 -8.01116) (xy 348.090225 -7.984575)
			(xy 348.081828 -7.929909) (xy 348.081414 -7.874603) (xy 348.08899 -7.819816) (xy 348.104399 -7.766698)
			(xy 348.127316 -7.716362) (xy 348.157263 -7.669863) (xy 348.175072 -7.648702) (xy 348.184311 -7.637376)
			(xy 348.196492 -7.610818) (xy 348.200666 -7.5819) (xy 348.196492 -7.552982) (xy 348.184311 -7.526424)
			(xy 348.175072 -7.515098) (xy 348.157442 -7.49416) (xy 348.127737 -7.448187) (xy 348.104907 -7.39844)
			(xy 348.089421 -7.345941) (xy 348.081598 -7.291768) (xy 348.081598 -7.237032) (xy 348.089421 -7.182859)
			(xy 348.104907 -7.13036) (xy 348.127737 -7.080613) (xy 348.157442 -7.03464) (xy 348.175072 -7.013702)
			(xy 348.184311 -7.002376) (xy 348.196492 -6.975818) (xy 348.200666 -6.9469) (xy 348.196492 -6.917982)
			(xy 348.184311 -6.891424) (xy 348.175072 -6.880098) (xy 348.157491 -6.859225) (xy 348.127853 -6.8134)
			(xy 348.105049 -6.763818) (xy 348.089543 -6.711494) (xy 348.081651 -6.657493) (xy 348.081536 -6.602919)
			(xy 348.089199 -6.548886) (xy 348.104483 -6.496496) (xy 348.127078 -6.446819) (xy 348.156521 -6.400869)
			(xy 348.192211 -6.359583) (xy 348.233421 -6.323805) (xy 348.279309 -6.294265) (xy 348.328938 -6.271565)
			(xy 348.381296 -6.25617) (xy 348.435313 -6.248393) (xy 348.489887 -6.248393) (xy 348.543904 -6.25617)
			(xy 348.596262 -6.271565) (xy 348.645891 -6.294265) (xy 348.691779 -6.323805) (xy 348.732989 -6.359583)
			(xy 348.768679 -6.400869) (xy 348.798122 -6.446819) (xy 348.820717 -6.496496) (xy 348.836001 -6.548886)
			(xy 348.843664 -6.602919) (xy 348.843549 -6.657493) (xy 348.835657 -6.711494) (xy 348.820151 -6.763818)
			(xy 348.797347 -6.8134) (xy 348.780967 -6.838726) (xy 349.554041 -6.838726) (xy 349.560019 -6.760677)
			(xy 349.573963 -6.683651) (xy 349.595725 -6.608459) (xy 349.625077 -6.535893) (xy 349.661709 -6.466715)
			(xy 349.705236 -6.401655) (xy 349.7552 -6.341397) (xy 349.811075 -6.286575) (xy 349.872273 -6.237767)
			(xy 349.938149 -6.195485) (xy 350.008011 -6.160176) (xy 350.081123 -6.13221) (xy 350.156715 -6.111882)
			(xy 350.233992 -6.099406) (xy 350.312141 -6.094914) (xy 350.390339 -6.098452) (xy 350.467763 -6.109983)
			(xy 350.543598 -6.129386) (xy 350.544822 -6.129837) (xy 352.847653 -6.129837) (xy 352.847653 -6.049971)
			(xy 352.855733 -5.970516) (xy 352.87181 -5.892286) (xy 352.895719 -5.816084) (xy 352.927214 -5.742691)
			(xy 352.965973 -5.672861) (xy 353.011597 -5.607311) (xy 353.063619 -5.546712) (xy 353.121504 -5.491688)
			(xy 353.18466 -5.442802) (xy 353.252437 -5.400556) (xy 353.32414 -5.365384) (xy 353.399034 -5.337647)
			(xy 353.476349 -5.317628) (xy 353.555293 -5.305535) (xy 353.635056 -5.30149) (xy 353.714819 -5.305535)
			(xy 353.793763 -5.317628) (xy 353.871078 -5.337647) (xy 353.945972 -5.365384) (xy 354.017675 -5.400556)
			(xy 354.085452 -5.442802) (xy 354.148608 -5.491688) (xy 354.206493 -5.546712) (xy 354.258515 -5.607311)
			(xy 354.304139 -5.672861) (xy 354.342898 -5.742691) (xy 354.374393 -5.816084) (xy 354.398302 -5.892286)
			(xy 354.414379 -5.970516) (xy 354.422459 -6.049971) (xy 354.422964 -6.089904) (xy 354.422459 -6.129837)
			(xy 354.414379 -6.209292) (xy 354.398302 -6.287522) (xy 354.374393 -6.363724) (xy 354.342898 -6.437117)
			(xy 354.304139 -6.506947) (xy 354.258515 -6.572497) (xy 354.206493 -6.633096) (xy 354.148608 -6.68812)
			(xy 354.085452 -6.737006) (xy 354.017675 -6.779252) (xy 353.945972 -6.814424) (xy 353.871078 -6.842161)
			(xy 353.793763 -6.86218) (xy 353.714819 -6.874273) (xy 353.635056 -6.878319) (xy 353.555293 -6.874273)
			(xy 353.476349 -6.86218) (xy 353.399034 -6.842161) (xy 353.32414 -6.814424) (xy 353.252437 -6.779252)
			(xy 353.18466 -6.737006) (xy 353.121504 -6.68812) (xy 353.063619 -6.633096) (xy 353.011597 -6.572497)
			(xy 352.965973 -6.506947) (xy 352.927214 -6.437117) (xy 352.895719 -6.363724) (xy 352.87181 -6.287522)
			(xy 352.855733 -6.209292) (xy 352.847653 -6.129837) (xy 350.544822 -6.129837) (xy 350.617046 -6.156457)
			(xy 350.687334 -6.190911) (xy 350.753721 -6.232385) (xy 350.784922 -6.25602) (xy 350.809514 -6.244987)
			(xy 350.861163 -6.229581) (xy 350.914543 -6.222133) (xy 350.968436 -6.222813) (xy 351.021611 -6.231606)
			(xy 351.072854 -6.248311) (xy 351.120995 -6.272547) (xy 351.164935 -6.30376) (xy 351.20367 -6.341237)
			(xy 351.236315 -6.384122) (xy 351.262126 -6.431437) (xy 351.280513 -6.482101) (xy 351.291056 -6.534957)
			(xy 351.293514 -6.588799) (xy 351.287832 -6.642395) (xy 351.274138 -6.694524) (xy 351.252747 -6.743994)
			(xy 351.224145 -6.789677) (xy 351.188986 -6.830528) (xy 351.148074 -6.865615) (xy 351.102342 -6.894136)
			(xy 351.077784 -6.905244) (xy 351.076467 -6.92438) (xy 351.072149 -6.962499) (xy 351.069148 -6.981444)
			(xy 351.104321 -6.997455) (xy 351.171506 -7.035657) (xy 351.234481 -7.08046) (xy 351.2926 -7.131404)
			(xy 351.345266 -7.187968) (xy 351.39194 -7.24957) (xy 351.432141 -7.315577) (xy 351.465458 -7.385314)
			(xy 351.491548 -7.458063) (xy 351.510144 -7.533079) (xy 351.521055 -7.609591) (xy 351.524168 -7.686815)
			(xy 351.519453 -7.763957) (xy 351.506957 -7.840226) (xy 351.486809 -7.91484) (xy 351.459215 -7.987032)
			(xy 351.424458 -8.056063) (xy 351.382896 -8.121222) (xy 351.334955 -8.181842) (xy 351.281126 -8.237301)
			(xy 351.221963 -8.287029) (xy 351.158072 -8.330516) (xy 351.090109 -8.367315) (xy 351.018772 -8.39705)
			(xy 350.944792 -8.419414) (xy 350.868929 -8.434179) (xy 350.791962 -8.441193) (xy 350.71468 -8.440384)
			(xy 350.637876 -8.431759) (xy 350.562339 -8.415409) (xy 350.488844 -8.3915) (xy 350.418145 -8.360278)
			(xy 350.350968 -8.322063) (xy 350.288002 -8.277247) (xy 350.229893 -8.226291) (xy 350.177237 -8.169717)
			(xy 350.130576 -8.108106) (xy 350.090388 -8.042091) (xy 350.057085 -7.972348) (xy 350.031009 -7.899593)
			(xy 350.012428 -7.824574) (xy 350.001532 -7.74806) (xy 349.998433 -7.670835) (xy 350.003164 -7.593694)
			(xy 350.008952 -7.555484) (xy 349.973345 -7.539228) (xy 349.905346 -7.500453) (xy 349.841677 -7.454915)
			(xy 349.783009 -7.403094) (xy 349.729959 -7.345534) (xy 349.683085 -7.282842) (xy 349.642882 -7.215677)
			(xy 349.609772 -7.144746) (xy 349.584103 -7.070797) (xy 349.566146 -6.994606) (xy 349.55609 -6.916977)
			(xy 349.554041 -6.838726) (xy 348.780967 -6.838726) (xy 348.767709 -6.859225) (xy 348.750128 -6.880098)
			(xy 348.740889 -6.891424) (xy 348.728708 -6.917982) (xy 348.724534 -6.9469) (xy 348.728708 -6.975818)
			(xy 348.740889 -7.002376) (xy 348.750128 -7.013702) (xy 348.767758 -7.03464) (xy 348.797463 -7.080613)
			(xy 348.820293 -7.13036) (xy 348.835779 -7.182859) (xy 348.843602 -7.237032) (xy 348.843602 -7.291768)
			(xy 348.835779 -7.345941) (xy 348.820293 -7.39844) (xy 348.797463 -7.448187) (xy 348.767758 -7.49416)
			(xy 348.750128 -7.515098) (xy 348.740889 -7.526424) (xy 348.728708 -7.552982) (xy 348.724534 -7.5819)
			(xy 348.728708 -7.610818) (xy 348.740889 -7.637376) (xy 348.750128 -7.648702) (xy 348.768539 -7.670595)
			(xy 348.799273 -7.71884) (xy 348.822458 -7.771133) (xy 348.837576 -7.826301) (xy 348.844287 -7.883108)
			(xy 348.842441 -7.940281) (xy 348.832079 -7.996537) (xy 348.813434 -8.050615) (xy 348.786923 -8.101303)
			(xy 348.753142 -8.147465) (xy 348.733364 -8.168132) (xy 348.718632 -8.182864) (xy 348.718632 -8.254492)
			(xy 348.767908 -8.254492) (xy 348.767908 -8.3947) (xy 348.791276 -8.42772) (xy 349.5929 -8.42772)
			(xy 349.83674 -8.67156) (xy 349.83674 -8.924777) (xy 352.355648 -8.924777) (xy 352.355648 -8.871479)
			(xy 352.363591 -8.818775) (xy 352.379301 -8.767845) (xy 352.402427 -8.719824) (xy 352.432451 -8.675787)
			(xy 352.468703 -8.636716) (xy 352.510374 -8.603485) (xy 352.556532 -8.576836) (xy 352.606146 -8.557364)
			(xy 352.658108 -8.545504) (xy 352.711258 -8.541521) (xy 352.764408 -8.545504) (xy 352.81637 -8.557364)
			(xy 352.865984 -8.576836) (xy 352.912142 -8.603485) (xy 352.953813 -8.636716) (xy 352.990065 -8.675787)
			(xy 353.020089 -8.719824) (xy 353.043215 -8.767845) (xy 353.058925 -8.818775) (xy 353.066868 -8.871479)
			(xy 353.067366 -8.898128) (xy 353.066868 -8.924777) (xy 353.058925 -8.977481) (xy 353.043215 -9.028411)
			(xy 353.020089 -9.076432) (xy 352.990065 -9.120469) (xy 352.953813 -9.15954) (xy 352.912142 -9.192771)
			(xy 352.865984 -9.21942) (xy 352.81637 -9.238892) (xy 352.764408 -9.250752) (xy 352.711258 -9.254736)
			(xy 352.658108 -9.250752) (xy 352.606146 -9.238892) (xy 352.556532 -9.21942) (xy 352.510374 -9.192771)
			(xy 352.468703 -9.15954) (xy 352.432451 -9.120469) (xy 352.402427 -9.076432) (xy 352.379301 -9.028411)
			(xy 352.363591 -8.977481) (xy 352.355648 -8.924777) (xy 349.83674 -8.924777) (xy 349.83674 -9.337294)
			(xy 349.879666 -9.344152) (xy 349.917825 -9.350682) (xy 349.992671 -9.370488) (xy 350.065125 -9.397776)
			(xy 350.13444 -9.432265) (xy 350.199904 -9.473601) (xy 350.260843 -9.521358) (xy 350.316628 -9.575044)
			(xy 350.366686 -9.634106) (xy 350.410501 -9.697937) (xy 350.447623 -9.76588) (xy 350.477669 -9.837234)
			(xy 350.500329 -9.911266) (xy 350.515371 -9.987212) (xy 350.52264 -10.064292) (xy 350.522061 -10.141712)
			(xy 350.513639 -10.218675) (xy 350.497462 -10.294388) (xy 350.473696 -10.368072) (xy 350.442586 -10.438969)
			(xy 350.404452 -10.506348) (xy 350.359686 -10.569516) (xy 350.30875 -10.627823) (xy 350.280732 -10.654538)
			(xy 350.270346 -10.664934) (xy 350.255506 -10.690285) (xy 350.24849 -10.718809) (xy 350.249878 -10.748151)
			(xy 350.259556 -10.775886) (xy 350.276724 -10.799721) (xy 350.299963 -10.817689) (xy 350.327352 -10.828303)
			(xy 350.341946 -10.830052) (xy 350.375504 -10.833144) (xy 350.4417 -10.845806) (xy 350.506096 -10.865688)
			(xy 350.567907 -10.892548) (xy 350.626381 -10.926058) (xy 350.680804 -10.96581) (xy 350.730514 -11.01132)
			(xy 350.774903 -11.062032) (xy 350.81343 -11.117329) (xy 350.845627 -11.176536) (xy 350.871101 -11.238932)
			(xy 350.889541 -11.303756) (xy 350.900722 -11.370217) (xy 350.903032 -11.403838) (xy 350.904 -11.413894)
			(xy 350.912778 -11.432072) (xy 350.927911 -11.445433) (xy 350.947036 -11.451891) (xy 350.957134 -11.45159)
			(xy 350.984302 -11.450235) (xy 351.038503 -11.454794) (xy 351.091381 -11.467544) (xy 351.141704 -11.488189)
			(xy 351.188301 -11.516247) (xy 351.230089 -11.551067) (xy 351.266094 -11.591837) (xy 351.29548 -11.637609)
			(xy 351.317562 -11.687318) (xy 351.331826 -11.739808) (xy 351.337941 -11.793856) (xy 351.335763 -11.848205)
			(xy 351.325345 -11.901591) (xy 351.306928 -11.952772) (xy 351.280941 -12.000555) (xy 351.247989 -12.04383)
			(xy 351.208837 -12.08159) (xy 351.164398 -12.112955) (xy 351.115706 -12.137196) (xy 351.089976 -12.146026)
			(xy 351.075963 -12.151059) (xy 351.051442 -12.167924) (xy 351.032819 -12.191139) (xy 351.021675 -12.218734)
			(xy 351.018953 -12.248371) (xy 351.024884 -12.277535) (xy 351.038967 -12.303753) (xy 351.049082 -12.314682)
			(xy 351.715049 -12.980649) (xy 354.60939 -12.980649) (xy 354.60939 -12.927351) (xy 354.617333 -12.874647)
			(xy 354.633043 -12.823717) (xy 354.656169 -12.775696) (xy 354.686193 -12.731659) (xy 354.722445 -12.692588)
			(xy 354.764116 -12.659357) (xy 354.810274 -12.632708) (xy 354.859888 -12.613236) (xy 354.91185 -12.601376)
			(xy 354.965 -12.597393) (xy 355.01815 -12.601376) (xy 355.070112 -12.613236) (xy 355.119726 -12.632708)
			(xy 355.165884 -12.659357) (xy 355.207555 -12.692588) (xy 355.243807 -12.731659) (xy 355.273831 -12.775696)
			(xy 355.296957 -12.823717) (xy 355.312667 -12.874647) (xy 355.32061 -12.927351) (xy 355.321108 -12.954)
			(xy 355.32061 -12.980649) (xy 355.312667 -13.033353) (xy 355.296957 -13.084283) (xy 355.273831 -13.132304)
			(xy 355.243807 -13.176341) (xy 355.207555 -13.215412) (xy 355.165884 -13.248643) (xy 355.119726 -13.275292)
			(xy 355.070112 -13.294764) (xy 355.01815 -13.306624) (xy 354.965 -13.310608) (xy 354.91185 -13.306624)
			(xy 354.859888 -13.294764) (xy 354.810274 -13.275292) (xy 354.764116 -13.248643) (xy 354.722445 -13.215412)
			(xy 354.686193 -13.176341) (xy 354.656169 -13.132304) (xy 354.633043 -13.084283) (xy 354.617333 -13.033353)
			(xy 354.60939 -12.980649) (xy 351.715049 -12.980649) (xy 351.7392 -13.0048) (xy 351.7646 -13.0048)
			(xy 352.187256 -13.427456) (xy 352.187256 -14.885395) (xy 352.485442 -14.885395) (xy 352.485442 -14.832097)
			(xy 352.493385 -14.779393) (xy 352.509095 -14.728463) (xy 352.532221 -14.680442) (xy 352.562245 -14.636405)
			(xy 352.598497 -14.597334) (xy 352.640168 -14.564103) (xy 352.686326 -14.537454) (xy 352.73594 -14.517982)
			(xy 352.787902 -14.506122) (xy 352.841052 -14.502139) (xy 352.894202 -14.506122) (xy 352.946164 -14.517982)
			(xy 352.995778 -14.537454) (xy 353.041936 -14.564103) (xy 353.083607 -14.597334) (xy 353.119859 -14.636405)
			(xy 353.149883 -14.680442) (xy 353.173009 -14.728463) (xy 353.188719 -14.779393) (xy 353.196662 -14.832097)
			(xy 353.19716 -14.858746) (xy 353.196662 -14.885395) (xy 353.188719 -14.938099) (xy 353.173009 -14.989029)
			(xy 353.149883 -15.03705) (xy 353.119859 -15.081087) (xy 353.083607 -15.120158) (xy 353.041936 -15.153389)
			(xy 352.995778 -15.180038) (xy 352.946164 -15.19951) (xy 352.894202 -15.21137) (xy 352.841052 -15.215354)
			(xy 352.787902 -15.21137) (xy 352.73594 -15.19951) (xy 352.686326 -15.180038) (xy 352.640168 -15.153389)
			(xy 352.598497 -15.120158) (xy 352.562245 -15.081087) (xy 352.532221 -15.03705) (xy 352.509095 -14.989029)
			(xy 352.493385 -14.938099) (xy 352.485442 -14.885395) (xy 352.187256 -14.885395) (xy 352.187256 -15.404592)
			(xy 351.4598 -16.132048) (xy 351.4598 -18.975049) (xy 352.47579 -18.975049) (xy 352.47579 -18.921751)
			(xy 352.483733 -18.869047) (xy 352.499443 -18.818117) (xy 352.522569 -18.770096) (xy 352.552593 -18.726059)
			(xy 352.588845 -18.686988) (xy 352.630516 -18.653757) (xy 352.676674 -18.627108) (xy 352.726288 -18.607636)
			(xy 352.77825 -18.595776) (xy 352.8314 -18.591793) (xy 352.88455 -18.595776) (xy 352.936512 -18.607636)
			(xy 352.986126 -18.627108) (xy 353.032284 -18.653757) (xy 353.073955 -18.686988) (xy 353.110207 -18.726059)
			(xy 353.140231 -18.770096) (xy 353.163357 -18.818117) (xy 353.179067 -18.869047) (xy 353.18701 -18.921751)
			(xy 353.187508 -18.9484) (xy 353.18701 -18.975049) (xy 353.179067 -19.027753) (xy 353.163357 -19.078683)
			(xy 353.140231 -19.126704) (xy 353.110207 -19.170741) (xy 353.073955 -19.209812) (xy 353.032284 -19.243043)
			(xy 352.986126 -19.269692) (xy 352.936512 -19.289164) (xy 352.88455 -19.301024) (xy 352.8314 -19.305008)
			(xy 352.77825 -19.301024) (xy 352.726288 -19.289164) (xy 352.676674 -19.269692) (xy 352.630516 -19.243043)
			(xy 352.588845 -19.209812) (xy 352.552593 -19.170741) (xy 352.522569 -19.126704) (xy 352.499443 -19.078683)
			(xy 352.483733 -19.027753) (xy 352.47579 -18.975049) (xy 351.4598 -18.975049) (xy 351.4598 -19.939)
			(xy 351.500673 -19.979873) (xy 352.467662 -19.979873) (xy 352.467662 -19.926575) (xy 352.475605 -19.873871)
			(xy 352.491315 -19.822941) (xy 352.514441 -19.77492) (xy 352.544465 -19.730883) (xy 352.580717 -19.691812)
			(xy 352.622388 -19.658581) (xy 352.668546 -19.631932) (xy 352.71816 -19.61246) (xy 352.770122 -19.6006)
			(xy 352.823272 -19.596617) (xy 352.876422 -19.6006) (xy 352.928384 -19.61246) (xy 352.977998 -19.631932)
			(xy 353.024156 -19.658581) (xy 353.065827 -19.691812) (xy 353.102079 -19.730883) (xy 353.132103 -19.77492)
			(xy 353.155229 -19.822941) (xy 353.170939 -19.873871) (xy 353.178882 -19.926575) (xy 353.17938 -19.953224)
			(xy 353.178882 -19.979873) (xy 353.170939 -20.032577) (xy 353.155229 -20.083507) (xy 353.132103 -20.131528)
			(xy 353.102079 -20.175565) (xy 353.065827 -20.214636) (xy 353.024156 -20.247867) (xy 352.977998 -20.274516)
			(xy 352.928384 -20.293988) (xy 352.876422 -20.305848) (xy 352.823272 -20.309832) (xy 352.770122 -20.305848)
			(xy 352.71816 -20.293988) (xy 352.668546 -20.274516) (xy 352.622388 -20.247867) (xy 352.580717 -20.214636)
			(xy 352.544465 -20.175565) (xy 352.514441 -20.131528) (xy 352.491315 -20.083507) (xy 352.475605 -20.032577)
			(xy 352.467662 -19.979873) (xy 351.500673 -19.979873) (xy 352.2218 -20.701) (xy 355.7016 -20.701)
		)
		(stroke
			(width 0)
			(type solid)
		)
		(fill yes)
		(layer "B.Cu")
		(net "VR_FET_SW_P12V_STBY_PVDDQ_ABC")
	)
	(gr_line
		(start 0.085852 -25.0444)
		(end 0.428752 -25.0444)
		(stroke
			(width 0.05715)
			(type default)
		)
		(layer "B.Cu")
	)
	(gr_line
		(start 0.215392 -24.6888)
		(end 0.299212 -24.6888)
		(stroke
			(width 0.05715)
			(type default)
		)
		(layer "B.Cu")
	)
	(gr_line
		(start 0.299974 -92.769944)
		(end 0.591566 -92.769944)
		(stroke
			(width 0.05715)
			(type default)
		)
		(layer "B.Cu")
	)
	(gr_line
		(start 0.299974 -27.71013)
		(end 0.765048 -27.71013)
		(stroke
			(width 0.05715)
			(type default)
		)
		(layer "B.Cu")
	)
	(gr_line
		(start 0.428752 -25.0444)
		(end 0.540512 -24.93264)
		(stroke
			(width 0.05715)
			(type default)
		)
		(layer "B.Cu")
	)
	(gr_line
		(start 0.51435 -107.9119)
		(end 0.9144 -107.9119)
		(stroke
			(width 0.05715)
			(type default)
		)
		(layer "B.Cu")
	)
	(gr_line
		(start 0.591566 -92.769944)
		(end 0.813816 -92.547694)
		(stroke
			(width 0.05715)
			(type default)
		)
		(layer "B.Cu")
	)
	(gr_line
		(start 0.765048 -27.71013)
		(end 0.907542 -27.852624)
		(stroke
			(width 0.05715)
			(type default)
		)
		(layer "B.Cu")
	)
	(gr_line
		(start 0.9144 -107.9119)
		(end 0.976884 -107.849416)
		(stroke
			(width 0.05715)
			(type default)
		)
		(layer "B.Cu")
	)
	(gr_line
		(start 1.158748 -92.547694)
		(end 1.380998 -92.769944)
		(stroke
			(width 0.05715)
			(type default)
		)
		(layer "B.Cu")
	)
	(gr_line
		(start 1.25222 -27.852624)
		(end 1.394714 -27.71013)
		(stroke
			(width 0.05715)
			(type default)
		)
		(layer "B.Cu")
	)
	(gr_line
		(start 1.321816 -107.849416)
		(end 1.3843 -107.9119)
		(stroke
			(width 0.05715)
			(type default)
		)
		(layer "B.Cu")
	)
	(gr_line
		(start 1.380998 -92.769944)
		(end 1.700022 -92.769944)
		(stroke
			(width 0.05715)
			(type default)
		)
		(layer "B.Cu")
	)
	(gr_line
		(start 1.3843 -107.9119)
		(end 1.78435 -107.9119)
		(stroke
			(width 0.05715)
			(type default)
		)
		(layer "B.Cu")
	)
	(gr_line
		(start 1.394714 -27.71013)
		(end 1.700022 -27.71013)
		(stroke
			(width 0.05715)
			(type default)
		)
		(layer "B.Cu")
	)
	(gr_line
		(start 1.599946 -102.769924)
		(end 2.061464 -102.769924)
		(stroke
			(width 0.05715)
			(type default)
		)
		(layer "B.Cu")
	)
	(gr_line
		(start 1.599946 -94.76994)
		(end 2.05994 -94.76994)
		(stroke
			(width 0.05715)
			(type default)
		)
		(layer "B.Cu")
	)
	(gr_line
		(start 1.599946 -29.710126)
		(end 2.022856 -29.710126)
		(stroke
			(width 0.05715)
			(type default)
		)
		(layer "B.Cu")
	)
	(gr_line
		(start 1.599946 -25.710134)
		(end 2.06502 -25.710134)
		(stroke
			(width 0.05715)
			(type default)
		)
		(layer "B.Cu")
	)
	(gr_line
		(start 2.022856 -29.710126)
		(end 2.131822 -29.819092)
		(stroke
			(width 0.05715)
			(type default)
		)
		(layer "B.Cu")
	)
	(gr_line
		(start 2.05994 -94.76994)
		(end 2.127504 -94.837504)
		(stroke
			(width 0.05715)
			(type default)
		)
		(layer "B.Cu")
	)
	(gr_line
		(start 2.061464 -102.769924)
		(end 2.154174 -102.862634)
		(stroke
			(width 0.05715)
			(type default)
		)
		(layer "B.Cu")
	)
	(gr_line
		(start 2.06502 -25.710134)
		(end 2.127504 -25.772618)
		(stroke
			(width 0.05715)
			(type default)
		)
		(layer "B.Cu")
	)
	(gr_line
		(start 2.472436 -94.837504)
		(end 2.54 -94.76994)
		(stroke
			(width 0.05715)
			(type default)
		)
		(layer "B.Cu")
	)
	(gr_line
		(start 2.472436 -25.772618)
		(end 2.53492 -25.710134)
		(stroke
			(width 0.05715)
			(type default)
		)
		(layer "B.Cu")
	)
	(gr_line
		(start 2.4765 -29.819092)
		(end 2.585466 -29.710126)
		(stroke
			(width 0.05715)
			(type default)
		)
		(layer "B.Cu")
	)
	(gr_line
		(start 2.499106 -102.862634)
		(end 2.591816 -102.769924)
		(stroke
			(width 0.05715)
			(type default)
		)
		(layer "B.Cu")
	)
	(gr_line
		(start 2.53492 -25.710134)
		(end 2.999994 -25.710134)
		(stroke
			(width 0.05715)
			(type default)
		)
		(layer "B.Cu")
	)
	(gr_line
		(start 2.54 -94.76994)
		(end 2.999994 -94.76994)
		(stroke
			(width 0.05715)
			(type default)
		)
		(layer "B.Cu")
	)
	(gr_line
		(start 2.585466 -29.710126)
		(end 2.999994 -29.710126)
		(stroke
			(width 0.05715)
			(type default)
		)
		(layer "B.Cu")
	)
	(gr_line
		(start 2.591816 -102.769924)
		(end 2.999994 -102.769924)
		(stroke
			(width 0.05715)
			(type default)
		)
		(layer "B.Cu")
	)
	(gr_line
		(start 2.739644 -112.21339)
		(end 3.139694 -112.21339)
		(stroke
			(width 0.05715)
			(type default)
		)
		(layer "B.Cu")
	)
	(gr_line
		(start 3.05435 -107.9119)
		(end 3.4544 -107.9119)
		(stroke
			(width 0.05715)
			(type default)
		)
		(layer "B.Cu")
	)
	(gr_line
		(start 3.139694 -112.21339)
		(end 3.202178 -112.275874)
		(stroke
			(width 0.05715)
			(type default)
		)
		(layer "B.Cu")
	)
	(gr_line
		(start 3.4544 -107.9119)
		(end 3.516884 -107.974384)
		(stroke
			(width 0.05715)
			(type default)
		)
		(layer "B.Cu")
	)
	(gr_line
		(start 3.54711 -112.275874)
		(end 3.609594 -112.21339)
		(stroke
			(width 0.05715)
			(type default)
		)
		(layer "B.Cu")
	)
	(gr_line
		(start 3.609594 -112.21339)
		(end 4.009644 -112.21339)
		(stroke
			(width 0.05715)
			(type default)
		)
		(layer "B.Cu")
	)
	(gr_line
		(start 3.861816 -107.974384)
		(end 3.9243 -107.9119)
		(stroke
			(width 0.05715)
			(type default)
		)
		(layer "B.Cu")
	)
	(gr_line
		(start 3.9243 -107.9119)
		(end 4.32435 -107.9119)
		(stroke
			(width 0.05715)
			(type default)
		)
		(layer "B.Cu")
	)
	(gr_line
		(start 4.30403 -24.93264)
		(end 4.41579 -25.0444)
		(stroke
			(width 0.05715)
			(type default)
		)
		(layer "B.Cu")
	)
	(gr_line
		(start 4.41579 -25.0444)
		(end 4.75869 -25.0444)
		(stroke
			(width 0.05715)
			(type default)
		)
		(layer "B.Cu")
	)
	(gr_line
		(start 4.499864 -104.76992)
		(end 4.965192 -104.76992)
		(stroke
			(width 0.05715)
			(type default)
		)
		(layer "B.Cu")
	)
	(gr_line
		(start 4.54533 -24.6888)
		(end 4.62915 -24.6888)
		(stroke
			(width 0.05715)
			(type default)
		)
		(layer "B.Cu")
	)
	(gr_line
		(start 4.62915 -106.8578)
		(end 4.648962 -106.86796)
		(stroke
			(width 0.05715)
			(type default)
		)
		(layer "B.Cu")
	)
	(gr_line
		(start 4.75869 -25.0444)
		(end 4.87045 -24.93264)
		(stroke
			(width 0.05715)
			(type default)
		)
		(layer "B.Cu")
	)
	(gr_line
		(start 4.800346 -105.860342)
		(end 4.820158 -105.870502)
		(stroke
			(width 0.05715)
			(type default)
		)
		(layer "B.Cu")
	)
	(gr_line
		(start 4.965192 -104.76992)
		(end 5.027676 -104.832404)
		(stroke
			(width 0.05715)
			(type default)
		)
		(layer "B.Cu")
	)
	(gr_line
		(start 5.18414 -28.586938)
		(end 5.2959 -28.475178)
		(stroke
			(width 0.05715)
			(type default)
		)
		(layer "B.Cu")
	)
	(gr_line
		(start 5.2959 -28.475178)
		(end 5.6388 -28.475178)
		(stroke
			(width 0.05715)
			(type default)
		)
		(layer "B.Cu")
	)
	(gr_line
		(start 5.372608 -104.832404)
		(end 5.435092 -104.76992)
		(stroke
			(width 0.05715)
			(type default)
		)
		(layer "B.Cu")
	)
	(gr_line
		(start 5.42544 -28.830778)
		(end 5.50926 -28.830778)
		(stroke
			(width 0.05715)
			(type default)
		)
		(layer "B.Cu")
	)
	(gr_line
		(start 5.435092 -104.76992)
		(end 5.899912 -104.76992)
		(stroke
			(width 0.05715)
			(type default)
		)
		(layer "B.Cu")
	)
	(gr_line
		(start 5.6388 -28.475178)
		(end 5.75056 -28.586938)
		(stroke
			(width 0.05715)
			(type default)
		)
		(layer "B.Cu")
	)
	(gr_line
		(start 5.80009 -102.769924)
		(end 6.326378 -102.769924)
		(stroke
			(width 0.05715)
			(type default)
		)
		(layer "B.Cu")
	)
	(gr_line
		(start 5.80009 -37.71011)
		(end 6.265164 -37.71011)
		(stroke
			(width 0.05715)
			(type default)
		)
		(layer "B.Cu")
	)
	(gr_line
		(start 6.071616 -105.390442)
		(end 6.091428 -105.400602)
		(stroke
			(width 0.05715)
			(type default)
		)
		(layer "B.Cu")
	)
	(gr_line
		(start 6.09854 -28.586938)
		(end 6.2103 -28.475178)
		(stroke
			(width 0.05715)
			(type default)
		)
		(layer "B.Cu")
	)
	(gr_line
		(start 6.098794 -26.704036)
		(end 6.210554 -26.592276)
		(stroke
			(width 0.05715)
			(type default)
		)
		(layer "B.Cu")
	)
	(gr_line
		(start 6.209538 -112.465866)
		(end 6.209538 -112.865916)
		(stroke
			(width 0.05715)
			(type default)
		)
		(layer "B.Cu")
	)
	(gr_line
		(start 6.209538 -112.465866)
		(end 6.272022 -112.403382)
		(stroke
			(width 0.05715)
			(type default)
		)
		(layer "B.Cu")
	)
	(gr_line
		(start 6.209538 -111.995966)
		(end 6.272022 -112.05845)
		(stroke
			(width 0.05715)
			(type default)
		)
		(layer "B.Cu")
	)
	(gr_line
		(start 6.209538 -111.595916)
		(end 6.209538 -111.995966)
		(stroke
			(width 0.05715)
			(type default)
		)
		(layer "B.Cu")
	)
	(gr_line
		(start 6.2103 -28.475178)
		(end 6.5532 -28.475178)
		(stroke
			(width 0.05715)
			(type default)
		)
		(layer "B.Cu")
	)
	(gr_line
		(start 6.210554 -26.592276)
		(end 6.553454 -26.592276)
		(stroke
			(width 0.05715)
			(type default)
		)
		(layer "B.Cu")
	)
	(gr_line
		(start 6.265164 -37.71011)
		(end 6.379464 -37.82441)
		(stroke
			(width 0.05715)
			(type default)
		)
		(layer "B.Cu")
	)
	(gr_line
		(start 6.326378 -102.769924)
		(end 6.43636 -102.659942)
		(stroke
			(width 0.05715)
			(type default)
		)
		(layer "B.Cu")
	)
	(gr_line
		(start 6.33984 -28.830778)
		(end 6.42366 -28.830778)
		(stroke
			(width 0.05715)
			(type default)
		)
		(layer "B.Cu")
	)
	(gr_line
		(start 6.340094 -26.947876)
		(end 6.423914 -26.947876)
		(stroke
			(width 0.05715)
			(type default)
		)
		(layer "B.Cu")
	)
	(gr_line
		(start 6.341618 -107.73283)
		(end 6.384036 -107.75442)
		(stroke
			(width 0.05715)
			(type default)
		)
		(layer "B.Cu")
	)
	(gr_line
		(start 6.384036 -107.75442)
		(end 6.40461 -107.797854)
		(stroke
			(width 0.05715)
			(type default)
		)
		(layer "B.Cu")
	)
	(gr_line
		(start 6.5532 -28.475178)
		(end 6.66496 -28.586938)
		(stroke
			(width 0.05715)
			(type default)
		)
		(layer "B.Cu")
	)
	(gr_line
		(start 6.553454 -26.592276)
		(end 6.665214 -26.704036)
		(stroke
			(width 0.05715)
			(type default)
		)
		(layer "B.Cu")
	)
	(gr_line
		(start 6.623304 -37.97935)
		(end 6.892544 -37.71011)
		(stroke
			(width 0.05715)
			(type default)
		)
		(layer "B.Cu")
	)
	(gr_line
		(start 6.6802 -102.5398)
		(end 6.910324 -102.769924)
		(stroke
			(width 0.05715)
			(type default)
		)
		(layer "B.Cu")
	)
	(gr_line
		(start 6.734556 -89.82202)
		(end 6.846316 -89.93378)
		(stroke
			(width 0.05715)
			(type default)
		)
		(layer "B.Cu")
	)
	(gr_line
		(start 6.846316 -89.93378)
		(end 7.189216 -89.93378)
		(stroke
			(width 0.05715)
			(type default)
		)
		(layer "B.Cu")
	)
	(gr_line
		(start 6.892544 -37.71011)
		(end 7.199884 -37.71011)
		(stroke
			(width 0.05715)
			(type default)
		)
		(layer "B.Cu")
	)
	(gr_line
		(start 6.910324 -102.769924)
		(end 7.199884 -102.769924)
		(stroke
			(width 0.05715)
			(type default)
		)
		(layer "B.Cu")
	)
	(gr_line
		(start 6.975856 -89.57818)
		(end 7.059676 -89.57818)
		(stroke
			(width 0.05715)
			(type default)
		)
		(layer "B.Cu")
	)
	(gr_line
		(start 7.01167 -109.650276)
		(end 7.014972 -109.657134)
		(stroke
			(width 0.05715)
			(type default)
		)
		(layer "B.Cu")
	)
	(gr_line
		(start 7.01294 -28.586938)
		(end 7.1247 -28.475178)
		(stroke
			(width 0.05715)
			(type default)
		)
		(layer "B.Cu")
	)
	(gr_line
		(start 7.013194 -26.704036)
		(end 7.124954 -26.592276)
		(stroke
			(width 0.05715)
			(type default)
		)
		(layer "B.Cu")
	)
	(gr_line
		(start 7.104126 -107.037378)
		(end 7.146544 -107.058968)
		(stroke
			(width 0.05715)
			(type default)
		)
		(layer "B.Cu")
	)
	(gr_line
		(start 7.1247 -28.475178)
		(end 7.4676 -28.475178)
		(stroke
			(width 0.05715)
			(type default)
		)
		(layer "B.Cu")
	)
	(gr_line
		(start 7.124954 -26.592276)
		(end 7.467854 -26.592276)
		(stroke
			(width 0.05715)
			(type default)
		)
		(layer "B.Cu")
	)
	(gr_line
		(start 7.146544 -107.058968)
		(end 7.167118 -107.102402)
		(stroke
			(width 0.05715)
			(type default)
		)
		(layer "B.Cu")
	)
	(gr_line
		(start 7.189216 -89.93378)
		(end 7.300976 -89.82202)
		(stroke
			(width 0.05715)
			(type default)
		)
		(layer "B.Cu")
	)
	(gr_line
		(start 7.25424 -28.830778)
		(end 7.33806 -28.830778)
		(stroke
			(width 0.05715)
			(type default)
		)
		(layer "B.Cu")
	)
	(gr_line
		(start 7.254494 -26.947876)
		(end 7.338314 -26.947876)
		(stroke
			(width 0.05715)
			(type default)
		)
		(layer "B.Cu")
	)
	(gr_line
		(start 7.4676 -28.475178)
		(end 7.57936 -28.586938)
		(stroke
			(width 0.05715)
			(type default)
		)
		(layer "B.Cu")
	)
	(gr_line
		(start 7.467854 -26.592276)
		(end 7.579614 -26.704036)
		(stroke
			(width 0.05715)
			(type default)
		)
		(layer "B.Cu")
	)
	(gr_line
		(start 7.523226 -113.037366)
		(end 7.536434 -113.042954)
		(stroke
			(width 0.05715)
			(type default)
		)
		(layer "B.Cu")
	)
	(gr_line
		(start 7.528052 -113.85804)
		(end 7.540498 -113.86312)
		(stroke
			(width 0.05715)
			(type default)
		)
		(layer "B.Cu")
	)
	(gr_line
		(start 7.554976 -91.654376)
		(end 7.601204 -91.700604)
		(stroke
			(width 0.05715)
			(type default)
		)
		(layer "B.Cu")
	)
	(gr_line
		(start 7.641336 -39.90594)
		(end 8.6106 -40.4622)
		(stroke
			(width 0.2)
			(type default)
		)
		(layer "B.Cu")
	)
	(gr_line
		(start 7.648956 -89.82202)
		(end 7.760716 -89.93378)
		(stroke
			(width 0.05715)
			(type default)
		)
		(layer "B.Cu")
	)
	(gr_line
		(start 7.760716 -89.93378)
		(end 8.103616 -89.93378)
		(stroke
			(width 0.05715)
			(type default)
		)
		(layer "B.Cu")
	)
	(gr_line
		(start 7.845806 -103.654352)
		(end 7.892034 -103.70058)
		(stroke
			(width 0.05715)
			(type default)
		)
		(layer "B.Cu")
	)
	(gr_line
		(start 7.855458 -109.125766)
		(end 7.85876 -109.132624)
		(stroke
			(width 0.05715)
			(type default)
		)
		(layer "B.Cu")
	)
	(gr_line
		(start 7.890256 -89.57818)
		(end 7.974076 -89.57818)
		(stroke
			(width 0.05715)
			(type default)
		)
		(layer "B.Cu")
	)
	(gr_line
		(start 7.92734 -28.586938)
		(end 8.0391 -28.475178)
		(stroke
			(width 0.05715)
			(type default)
		)
		(layer "B.Cu")
	)
	(gr_line
		(start 7.97306 -26.947876)
		(end 7.984998 -26.94305)
		(stroke
			(width 0.05715)
			(type default)
		)
		(layer "B.Cu")
	)
	(gr_line
		(start 8.022336 -106.38663)
		(end 8.070596 -106.411268)
		(stroke
			(width 0.05715)
			(type default)
		)
		(layer "B.Cu")
	)
	(gr_line
		(start 8.0391 -28.475178)
		(end 8.382 -28.475178)
		(stroke
			(width 0.05715)
			(type default)
		)
		(layer "B.Cu")
	)
	(gr_line
		(start 8.070596 -106.411268)
		(end 8.091424 -106.461306)
		(stroke
			(width 0.05715)
			(type default)
		)
		(layer "B.Cu")
	)
	(gr_line
		(start 8.103616 -89.93378)
		(end 8.215376 -89.82202)
		(stroke
			(width 0.05715)
			(type default)
		)
		(layer "B.Cu")
	)
	(gr_line
		(start 8.129016 -24.93264)
		(end 8.240776 -25.0444)
		(stroke
			(width 0.05715)
			(type default)
		)
		(layer "B.Cu")
	)
	(gr_line
		(start 8.156194 -112.219994)
		(end 8.166608 -112.230408)
		(stroke
			(width 0.05715)
			(type default)
		)
		(layer "B.Cu")
	)
	(gr_line
		(start 8.166608 -112.230408)
		(end 8.18007 -112.235996)
		(stroke
			(width 0.05715)
			(type default)
		)
		(layer "B.Cu")
	)
	(gr_line
		(start 8.16864 -28.830778)
		(end 8.25246 -28.830778)
		(stroke
			(width 0.05715)
			(type default)
		)
		(layer "B.Cu")
	)
	(gr_line
		(start 8.240776 -25.0444)
		(end 8.583676 -25.0444)
		(stroke
			(width 0.05715)
			(type default)
		)
		(layer "B.Cu")
	)
	(gr_line
		(start 8.370316 -24.6888)
		(end 8.454136 -24.6888)
		(stroke
			(width 0.05715)
			(type default)
		)
		(layer "B.Cu")
	)
	(gr_line
		(start 8.382 -28.475178)
		(end 8.49376 -28.586938)
		(stroke
			(width 0.05715)
			(type default)
		)
		(layer "B.Cu")
	)
	(gr_line
		(start 8.535924 -96.851724)
		(end 8.59536 -96.91116)
		(stroke
			(width 0.05715)
			(type default)
		)
		(layer "B.Cu")
	)
	(gr_line
		(start 8.537702 -96.50857)
		(end 8.695944 -96.50857)
		(stroke
			(width 0.05715)
			(type default)
		)
		(layer "B.Cu")
	)
	(gr_line
		(start 8.583676 -25.0444)
		(end 8.695436 -24.93264)
		(stroke
			(width 0.05715)
			(type default)
		)
		(layer "B.Cu")
	)
	(gr_line
		(start 8.620506 -31.988506)
		(end 8.679688 -32.047688)
		(stroke
			(width 0.05715)
			(type default)
		)
		(layer "B.Cu")
	)
	(gr_line
		(start 8.622284 -31.645352)
		(end 8.780272 -31.645352)
		(stroke
			(width 0.05715)
			(type default)
		)
		(layer "B.Cu")
	)
	(gr_line
		(start 8.664702 -89.57818)
		(end 8.71093 -89.624408)
		(stroke
			(width 0.05715)
			(type default)
		)
		(layer "B.Cu")
	)
	(gr_line
		(start 8.695944 -96.50857)
		(end 8.93826 -96.750886)
		(stroke
			(width 0.05715)
			(type default)
		)
		(layer "B.Cu")
	)
	(gr_line
		(start 8.72236 -108.61421)
		(end 8.727948 -108.627672)
		(stroke
			(width 0.05715)
			(type default)
		)
		(layer "B.Cu")
	)
	(gr_line
		(start 8.780272 -31.645352)
		(end 9.022842 -31.887668)
		(stroke
			(width 0.05715)
			(type default)
		)
		(layer "B.Cu")
	)
	(gr_line
		(start 8.797036 -111.439452)
		(end 8.80745 -111.449866)
		(stroke
			(width 0.05715)
			(type default)
		)
		(layer "B.Cu")
	)
	(gr_line
		(start 8.80745 -111.449866)
		(end 8.820912 -111.455454)
		(stroke
			(width 0.05715)
			(type default)
		)
		(layer "B.Cu")
	)
	(gr_line
		(start 8.93826 -96.750886)
		(end 8.938514 -96.909382)
		(stroke
			(width 0.05715)
			(type default)
		)
		(layer "B.Cu")
	)
	(gr_line
		(start 9.022842 -31.887668)
		(end 9.022842 -32.04591)
		(stroke
			(width 0.05715)
			(type default)
		)
		(layer "B.Cu")
	)
	(gr_line
		(start 9.02716 -26.247344)
		(end 9.087866 -26.10104)
		(stroke
			(width 0.05715)
			(type default)
		)
		(layer "B.Cu")
	)
	(gr_line
		(start 9.087866 -26.10104)
		(end 9.404604 -25.969976)
		(stroke
			(width 0.05715)
			(type default)
		)
		(layer "B.Cu")
	)
	(gr_line
		(start 9.150096 -26.460196)
		(end 9.6139 -26.268172)
		(stroke
			(width 0.05715)
			(type default)
		)
		(layer "B.Cu")
	)
	(gr_line
		(start 9.182354 -97.498154)
		(end 9.24179 -97.55759)
		(stroke
			(width 0.05715)
			(type default)
		)
		(layer "B.Cu")
	)
	(gr_line
		(start 9.184132 -97.155)
		(end 9.342628 -97.155)
		(stroke
			(width 0.05715)
			(type default)
		)
		(layer "B.Cu")
	)
	(gr_line
		(start 9.266936 -32.634936)
		(end 9.326118 -32.694118)
		(stroke
			(width 0.05715)
			(type default)
		)
		(layer "B.Cu")
	)
	(gr_line
		(start 9.268714 -32.291782)
		(end 9.426956 -32.291782)
		(stroke
			(width 0.05715)
			(type default)
		)
		(layer "B.Cu")
	)
	(gr_line
		(start 9.292082 -102.092506)
		(end 9.302496 -102.10292)
		(stroke
			(width 0.05715)
			(type default)
		)
		(layer "B.Cu")
	)
	(gr_line
		(start 9.302496 -102.10292)
		(end 9.308084 -102.116382)
		(stroke
			(width 0.05715)
			(type default)
		)
		(layer "B.Cu")
	)
	(gr_line
		(start 9.342628 -97.155)
		(end 9.584944 -97.39757)
		(stroke
			(width 0.05715)
			(type default)
		)
		(layer "B.Cu")
	)
	(gr_line
		(start 9.347454 -110.621572)
		(end 9.357868 -110.631986)
		(stroke
			(width 0.05715)
			(type default)
		)
		(layer "B.Cu")
	)
	(gr_line
		(start 9.357868 -110.631986)
		(end 9.37133 -110.637574)
		(stroke
			(width 0.05715)
			(type default)
		)
		(layer "B.Cu")
	)
	(gr_line
		(start 9.38657 -24.11603)
		(end 9.445752 -24.056848)
		(stroke
			(width 0.05715)
			(type default)
		)
		(layer "B.Cu")
	)
	(gr_line
		(start 9.388348 -24.459184)
		(end 9.54659 -24.459184)
		(stroke
			(width 0.05715)
			(type default)
		)
		(layer "B.Cu")
	)
	(gr_circle
		(center 9.398 -129.8448)
		(end 9.652 -129.8448)
		(stroke
			(width 0.2)
			(type default)
		)
		(fill no)
		(layer "B.Cu")
	)
	(gr_line
		(start 9.404604 -25.969976)
		(end 9.550654 -26.030428)
		(stroke
			(width 0.05715)
			(type default)
		)
		(layer "B.Cu")
	)
	(gr_line
		(start 9.420098 -93.519498)
		(end 9.430512 -93.529912)
		(stroke
			(width 0.05715)
			(type default)
		)
		(layer "B.Cu")
	)
	(gr_line
		(start 9.426956 -32.291782)
		(end 9.669272 -32.534352)
		(stroke
			(width 0.05715)
			(type default)
		)
		(layer "B.Cu")
	)
	(gr_line
		(start 9.430512 -93.529912)
		(end 9.4361 -93.543374)
		(stroke
			(width 0.05715)
			(type default)
		)
		(layer "B.Cu")
	)
	(gr_line
		(start 9.54659 -24.459184)
		(end 9.788906 -24.216614)
		(stroke
			(width 0.05715)
			(type default)
		)
		(layer "B.Cu")
	)
	(gr_line
		(start 9.584944 -97.39757)
		(end 9.584944 -97.555812)
		(stroke
			(width 0.05715)
			(type default)
		)
		(layer "B.Cu")
	)
	(gr_line
		(start 9.622028 -105.430574)
		(end 9.632442 -105.440988)
		(stroke
			(width 0.05715)
			(type default)
		)
		(layer "B.Cu")
	)
	(gr_line
		(start 9.628886 -29.72054)
		(end 9.688068 -29.779722)
		(stroke
			(width 0.05715)
			(type default)
		)
		(layer "B.Cu")
	)
	(gr_line
		(start 9.630664 -29.377386)
		(end 9.788652 -29.377386)
		(stroke
			(width 0.05715)
			(type default)
		)
		(layer "B.Cu")
	)
	(gr_line
		(start 9.632442 -105.440988)
		(end 9.63803 -105.45445)
		(stroke
			(width 0.05715)
			(type default)
		)
		(layer "B.Cu")
	)
	(gr_line
		(start 9.669272 -32.534352)
		(end 9.669272 -32.69234)
		(stroke
			(width 0.05715)
			(type default)
		)
		(layer "B.Cu")
	)
	(gr_line
		(start 9.769094 -91.423744)
		(end 9.8298 -91.277694)
		(stroke
			(width 0.05715)
			(type default)
		)
		(layer "B.Cu")
	)
	(gr_line
		(start 9.769094 -91.423744)
		(end 9.900412 -91.740482)
		(stroke
			(width 0.05715)
			(type default)
		)
		(layer "B.Cu")
	)
	(gr_line
		(start 9.788652 -29.377386)
		(end 10.031222 -29.619702)
		(stroke
			(width 0.05715)
			(type default)
		)
		(layer "B.Cu")
	)
	(gr_line
		(start 9.788906 -24.058626)
		(end 9.788906 -24.216614)
		(stroke
			(width 0.05715)
			(type default)
		)
		(layer "B.Cu")
	)
	(gr_line
		(start 9.83996 -97.81413)
		(end 9.845548 -97.827592)
		(stroke
			(width 0.05715)
			(type default)
		)
		(layer "B.Cu")
	)
	(gr_line
		(start 9.871964 -25.897332)
		(end 9.93267 -25.751028)
		(stroke
			(width 0.05715)
			(type default)
		)
		(layer "B.Cu")
	)
	(gr_line
		(start 9.900412 -91.740482)
		(end 10.046716 -91.801188)
		(stroke
			(width 0.05715)
			(type default)
		)
		(layer "B.Cu")
	)
	(gr_line
		(start 9.90219 -90.815414)
		(end 9.907778 -90.828876)
		(stroke
			(width 0.05715)
			(type default)
		)
		(layer "B.Cu")
	)
	(gr_line
		(start 9.903714 -109.803438)
		(end 9.917176 -109.809026)
		(stroke
			(width 0.05715)
			(type default)
		)
		(layer "B.Cu")
	)
	(gr_line
		(start 9.91362 -33.28162)
		(end 9.972802 -33.340802)
		(stroke
			(width 0.05715)
			(type default)
		)
		(layer "B.Cu")
	)
	(gr_line
		(start 9.915398 -32.938466)
		(end 10.073386 -32.938466)
		(stroke
			(width 0.05715)
			(type default)
		)
		(layer "B.Cu")
	)
	(gr_line
		(start 9.93267 -25.751028)
		(end 10.249408 -25.619964)
		(stroke
			(width 0.05715)
			(type default)
		)
		(layer "B.Cu")
	)
	(gr_line
		(start 9.995154 -26.110184)
		(end 10.458958 -25.917906)
		(stroke
			(width 0.05715)
			(type default)
		)
		(layer "B.Cu")
	)
	(gr_line
		(start 10.02411 -98.890074)
		(end 10.217658 -99.35718)
		(stroke
			(width 0.05715)
			(type default)
		)
		(layer "B.Cu")
	)
	(gr_line
		(start 10.031222 -29.619702)
		(end 10.031222 -29.777944)
		(stroke
			(width 0.05715)
			(type default)
		)
		(layer "B.Cu")
	)
	(gr_line
		(start 10.06729 -91.213686)
		(end 10.260584 -91.679776)
		(stroke
			(width 0.05715)
			(type default)
		)
		(layer "B.Cu")
	)
	(gr_line
		(start 10.073386 -32.938466)
		(end 10.315956 -33.180782)
		(stroke
			(width 0.05715)
			(type default)
		)
		(layer "B.Cu")
	)
	(gr_line
		(start 10.119106 -92.268548)
		(end 10.179812 -92.122244)
		(stroke
			(width 0.05715)
			(type default)
		)
		(layer "B.Cu")
	)
	(gr_line
		(start 10.119106 -92.268548)
		(end 10.250424 -92.585286)
		(stroke
			(width 0.05715)
			(type default)
		)
		(layer "B.Cu")
	)
	(gr_line
		(start 10.135108 -96.16059)
		(end 10.195814 -96.014286)
		(stroke
			(width 0.05715)
			(type default)
		)
		(layer "B.Cu")
	)
	(gr_line
		(start 10.135108 -96.16059)
		(end 10.266426 -96.477582)
		(stroke
			(width 0.05715)
			(type default)
		)
		(layer "B.Cu")
	)
	(gr_line
		(start 10.237724 -98.768662)
		(end 10.384282 -98.829368)
		(stroke
			(width 0.05715)
			(type default)
		)
		(layer "B.Cu")
	)
	(gr_line
		(start 10.249408 -25.619964)
		(end 10.395712 -25.680416)
		(stroke
			(width 0.05715)
			(type default)
		)
		(layer "B.Cu")
	)
	(gr_line
		(start 10.250424 -92.585286)
		(end 10.396728 -92.645992)
		(stroke
			(width 0.05715)
			(type default)
		)
		(layer "B.Cu")
	)
	(gr_line
		(start 10.266426 -96.477582)
		(end 10.41273 -96.538034)
		(stroke
			(width 0.05715)
			(type default)
		)
		(layer "B.Cu")
	)
	(gr_line
		(start 10.275316 -30.36697)
		(end 10.334498 -30.426152)
		(stroke
			(width 0.05715)
			(type default)
		)
		(layer "B.Cu")
	)
	(gr_line
		(start 10.277094 -30.023816)
		(end 10.435336 -30.023816)
		(stroke
			(width 0.05715)
			(type default)
		)
		(layer "B.Cu")
	)
	(gr_line
		(start 10.315956 -33.180782)
		(end 10.315956 -33.339024)
		(stroke
			(width 0.05715)
			(type default)
		)
		(layer "B.Cu")
	)
	(gr_circle
		(center 10.3378 -129.921)
		(end 10.5918 -129.921)
		(stroke
			(width 0.2)
			(type default)
		)
		(fill no)
		(layer "B.Cu")
	)
	(gr_line
		(start 10.374884 -99.736402)
		(end 10.567924 -100.202746)
		(stroke
			(width 0.05715)
			(type default)
		)
		(layer "B.Cu")
	)
	(gr_line
		(start 10.384282 -98.829368)
		(end 10.515346 -99.146106)
		(stroke
			(width 0.05715)
			(type default)
		)
		(layer "B.Cu")
	)
	(gr_line
		(start 10.417302 -92.05849)
		(end 10.610596 -92.524834)
		(stroke
			(width 0.05715)
			(type default)
		)
		(layer "B.Cu")
	)
	(gr_line
		(start 10.432542 -95.947484)
		(end 10.627614 -96.4184)
		(stroke
			(width 0.05715)
			(type default)
		)
		(layer "B.Cu")
	)
	(gr_line
		(start 10.435336 -30.023816)
		(end 10.677652 -30.266386)
		(stroke
			(width 0.05715)
			(type default)
		)
		(layer "B.Cu")
	)
	(gr_line
		(start 10.454894 -99.29241)
		(end 10.515346 -99.146106)
		(stroke
			(width 0.05715)
			(type default)
		)
		(layer "B.Cu")
	)
	(gr_line
		(start 10.469118 -93.113352)
		(end 10.529824 -92.967048)
		(stroke
			(width 0.05715)
			(type default)
		)
		(layer "B.Cu")
	)
	(gr_line
		(start 10.469118 -93.113352)
		(end 10.600436 -93.43009)
		(stroke
			(width 0.05715)
			(type default)
		)
		(layer "B.Cu")
	)
	(gr_line
		(start 10.48512 -97.005394)
		(end 10.545826 -96.85909)
		(stroke
			(width 0.05715)
			(type default)
		)
		(layer "B.Cu")
	)
	(gr_line
		(start 10.48512 -97.005394)
		(end 10.616438 -97.322132)
		(stroke
			(width 0.05715)
			(type default)
		)
		(layer "B.Cu")
	)
	(gr_line
		(start 10.56005 -33.92805)
		(end 10.619232 -33.987232)
		(stroke
			(width 0.05715)
			(type default)
		)
		(layer "B.Cu")
	)
	(gr_line
		(start 10.561828 -33.584896)
		(end 10.72007 -33.584896)
		(stroke
			(width 0.05715)
			(type default)
		)
		(layer "B.Cu")
	)
	(gr_line
		(start 10.56513 -23.81504)
		(end 10.67689 -23.9268)
		(stroke
			(width 0.05715)
			(type default)
		)
		(layer "B.Cu")
	)
	(gr_line
		(start 10.584688 -108.370624)
		(end 10.58926 -108.3818)
		(stroke
			(width 0.05715)
			(type default)
		)
		(layer "B.Cu")
	)
	(gr_line
		(start 10.587736 -99.613466)
		(end 10.73404 -99.674172)
		(stroke
			(width 0.05715)
			(type default)
		)
		(layer "B.Cu")
	)
	(gr_line
		(start 10.58926 -108.3818)
		(end 10.59815 -108.39069)
		(stroke
			(width 0.05715)
			(type default)
		)
		(layer "B.Cu")
	)
	(gr_line
		(start 10.600436 -93.43009)
		(end 10.74674 -93.490542)
		(stroke
			(width 0.05715)
			(type default)
		)
		(layer "B.Cu")
	)
	(gr_line
		(start 10.616438 -97.322132)
		(end 10.762742 -97.382838)
		(stroke
			(width 0.05715)
			(type default)
		)
		(layer "B.Cu")
	)
	(gr_line
		(start 10.67689 -23.9268)
		(end 11.01979 -23.9268)
		(stroke
			(width 0.05715)
			(type default)
		)
		(layer "B.Cu")
	)
	(gr_line
		(start 10.677652 -30.266386)
		(end 10.677652 -30.424374)
		(stroke
			(width 0.05715)
			(type default)
		)
		(layer "B.Cu")
	)
	(gr_line
		(start 10.72007 -33.584896)
		(end 10.962386 -33.827466)
		(stroke
			(width 0.05715)
			(type default)
		)
		(layer "B.Cu")
	)
	(gr_line
		(start 10.724388 -100.580444)
		(end 10.917174 -101.045772)
		(stroke
			(width 0.05715)
			(type default)
		)
		(layer "B.Cu")
	)
	(gr_line
		(start 10.73404 -99.674172)
		(end 10.865358 -99.99091)
		(stroke
			(width 0.05715)
			(type default)
		)
		(layer "B.Cu")
	)
	(gr_line
		(start 10.76706 -92.902024)
		(end 10.960354 -93.368622)
		(stroke
			(width 0.05715)
			(type default)
		)
		(layer "B.Cu")
	)
	(gr_line
		(start 10.782808 -96.793304)
		(end 10.977118 -97.262442)
		(stroke
			(width 0.05715)
			(type default)
		)
		(layer "B.Cu")
	)
	(gr_line
		(start 10.804906 -100.137468)
		(end 10.865358 -99.99091)
		(stroke
			(width 0.05715)
			(type default)
		)
		(layer "B.Cu")
	)
	(gr_line
		(start 10.80643 -23.5712)
		(end 10.89025 -23.5712)
		(stroke
			(width 0.05715)
			(type default)
		)
		(layer "B.Cu")
	)
	(gr_line
		(start 10.819384 -93.957902)
		(end 10.879836 -93.811598)
		(stroke
			(width 0.05715)
			(type default)
		)
		(layer "B.Cu")
	)
	(gr_line
		(start 10.819384 -93.957902)
		(end 10.950448 -94.274894)
		(stroke
			(width 0.05715)
			(type default)
		)
		(layer "B.Cu")
	)
	(gr_line
		(start 10.835132 -97.850198)
		(end 10.895584 -97.70364)
		(stroke
			(width 0.05715)
			(type default)
		)
		(layer "B.Cu")
	)
	(gr_line
		(start 10.835132 -97.850198)
		(end 10.96645 -98.166936)
		(stroke
			(width 0.05715)
			(type default)
		)
		(layer "B.Cu")
	)
	(gr_line
		(start 10.937748 -100.45827)
		(end 11.084052 -100.518976)
		(stroke
			(width 0.05715)
			(type default)
		)
		(layer "B.Cu")
	)
	(gr_line
		(start 10.950448 -94.274894)
		(end 11.096752 -94.335346)
		(stroke
			(width 0.05715)
			(type default)
		)
		(layer "B.Cu")
	)
	(gr_line
		(start 10.962386 -33.827466)
		(end 10.962386 -33.985454)
		(stroke
			(width 0.05715)
			(type default)
		)
		(layer "B.Cu")
	)
	(gr_line
		(start 10.96645 -98.166936)
		(end 11.112754 -98.227642)
		(stroke
			(width 0.05715)
			(type default)
		)
		(layer "B.Cu")
	)
	(gr_line
		(start 11.01979 -23.9268)
		(end 11.13155 -23.81504)
		(stroke
			(width 0.05715)
			(type default)
		)
		(layer "B.Cu")
	)
	(gr_line
		(start 11.0744 -101.425248)
		(end 11.079988 -101.43871)
		(stroke
			(width 0.05715)
			(type default)
		)
		(layer "B.Cu")
	)
	(gr_line
		(start 11.079988 -101.43871)
		(end 11.090402 -101.449124)
		(stroke
			(width 0.05715)
			(type default)
		)
		(layer "B.Cu")
	)
	(gr_line
		(start 11.084052 -100.518976)
		(end 11.21537 -100.835714)
		(stroke
			(width 0.05715)
			(type default)
		)
		(layer "B.Cu")
	)
	(gr_line
		(start 11.117326 -93.74759)
		(end 11.310112 -94.213172)
		(stroke
			(width 0.05715)
			(type default)
		)
		(layer "B.Cu")
	)
	(gr_line
		(start 11.132312 -97.637092)
		(end 11.326368 -98.105722)
		(stroke
			(width 0.05715)
			(type default)
		)
		(layer "B.Cu")
	)
	(gr_line
		(start 11.154664 -100.982018)
		(end 11.21537 -100.835714)
		(stroke
			(width 0.05715)
			(type default)
		)
		(layer "B.Cu")
	)
	(gr_line
		(start 11.185144 -98.695002)
		(end 11.245596 -98.548698)
		(stroke
			(width 0.05715)
			(type default)
		)
		(layer "B.Cu")
	)
	(gr_line
		(start 11.185144 -98.695002)
		(end 11.316208 -99.01174)
		(stroke
			(width 0.05715)
			(type default)
		)
		(layer "B.Cu")
	)
	(gr_line
		(start 11.208258 -25.346406)
		(end 11.220196 -25.34158)
		(stroke
			(width 0.05715)
			(type default)
		)
		(layer "B.Cu")
	)
	(gr_circle
		(center 11.303 -129.8956)
		(end 11.557 -129.8956)
		(stroke
			(width 0.2)
			(type default)
		)
		(fill no)
		(layer "B.Cu")
	)
	(gr_line
		(start 11.316208 -99.01174)
		(end 11.462766 -99.072446)
		(stroke
			(width 0.05715)
			(type default)
		)
		(layer "B.Cu")
	)
	(gr_line
		(start 11.412474 -107.82808)
		(end 11.418062 -107.841542)
		(stroke
			(width 0.05715)
			(type default)
		)
		(layer "B.Cu")
	)
	(gr_line
		(start 11.418062 -107.841542)
		(end 11.428476 -107.851956)
		(stroke
			(width 0.05715)
			(type default)
		)
		(layer "B.Cu")
	)
	(gr_line
		(start 11.46683 -95.74784)
		(end 11.533632 -96.084136)
		(stroke
			(width 0.05715)
			(type default)
		)
		(layer "B.Cu")
	)
	(gr_line
		(start 11.46683 -95.74784)
		(end 11.554714 -95.616268)
		(stroke
			(width 0.05715)
			(type default)
		)
		(layer "B.Cu")
	)
	(gr_line
		(start 11.47953 -23.81504)
		(end 11.59129 -23.9268)
		(stroke
			(width 0.05715)
			(type default)
		)
		(layer "B.Cu")
	)
	(gr_line
		(start 11.482578 -98.483166)
		(end 11.67638 -98.951034)
		(stroke
			(width 0.05715)
			(type default)
		)
		(layer "B.Cu")
	)
	(gr_line
		(start 11.533632 -96.084136)
		(end 11.665204 -96.17202)
		(stroke
			(width 0.05715)
			(type default)
		)
		(layer "B.Cu")
	)
	(gr_line
		(start 11.59129 -99.376992)
		(end 11.596878 -99.390454)
		(stroke
			(width 0.05715)
			(type default)
		)
		(layer "B.Cu")
	)
	(gr_line
		(start 11.59129 -23.9268)
		(end 11.93419 -23.9268)
		(stroke
			(width 0.05715)
			(type default)
		)
		(layer "B.Cu")
	)
	(gr_line
		(start 11.680952 -109.479588)
		(end 11.691874 -109.49051)
		(stroke
			(width 0.05715)
			(type default)
		)
		(layer "B.Cu")
	)
	(gr_line
		(start 11.691874 -109.49051)
		(end 11.706352 -109.496606)
		(stroke
			(width 0.05715)
			(type default)
		)
		(layer "B.Cu")
	)
	(gr_line
		(start 11.72083 -23.5712)
		(end 11.80465 -23.5712)
		(stroke
			(width 0.05715)
			(type default)
		)
		(layer "B.Cu")
	)
	(gr_line
		(start 11.739626 -102.098602)
		(end 11.785854 -102.14483)
		(stroke
			(width 0.05715)
			(type default)
		)
		(layer "B.Cu")
	)
	(gr_line
		(start 11.800078 -95.600266)
		(end 11.898122 -96.09328)
		(stroke
			(width 0.05715)
			(type default)
		)
		(layer "B.Cu")
	)
	(gr_line
		(start 11.850116 -25.635966)
		(end 11.9126 -25.69845)
		(stroke
			(width 0.05715)
			(type default)
		)
		(layer "B.Cu")
	)
	(gr_line
		(start 11.850116 -25.291034)
		(end 11.9126 -25.22855)
		(stroke
			(width 0.05715)
			(type default)
		)
		(layer "B.Cu")
	)
	(gr_line
		(start 11.855704 -97.118424)
		(end 11.863324 -97.156524)
		(stroke
			(width 0.05715)
			(type default)
		)
		(layer "B.Cu")
	)
	(gr_line
		(start 11.9126 -25.69845)
		(end 11.9126 -26.0985)
		(stroke
			(width 0.05715)
			(type default)
		)
		(layer "B.Cu")
	)
	(gr_line
		(start 11.9126 -24.8285)
		(end 11.9126 -25.22855)
		(stroke
			(width 0.05715)
			(type default)
		)
		(layer "B.Cu")
	)
	(gr_line
		(start 11.93419 -23.9268)
		(end 12.04595 -23.81504)
		(stroke
			(width 0.05715)
			(type default)
		)
		(layer "B.Cu")
	)
	(gr_circle
		(center 11.938 -129.8194)
		(end 12.192 -129.8194)
		(stroke
			(width 0.2)
			(type default)
		)
		(fill no)
		(layer "B.Cu")
	)
	(gr_line
		(start 12.016486 -39.206424)
		(end 12.289536 -39.206424)
		(stroke
			(width 0.05715)
			(type default)
		)
		(layer "B.Cu")
	)
	(gr_line
		(start 12.05611 -115.73383)
		(end 12.069572 -115.739418)
		(stroke
			(width 0.05715)
			(type default)
		)
		(layer "B.Cu")
	)
	(gr_line
		(start 12.130786 -102.196646)
		(end 12.40282 -102.46868)
		(stroke
			(width 0.05715)
			(type default)
		)
		(layer "B.Cu")
	)
	(gr_line
		(start 12.130786 -101.851714)
		(end 12.40282 -101.57968)
		(stroke
			(width 0.05715)
			(type default)
		)
		(layer "B.Cu")
	)
	(gr_line
		(start 12.238736 -108.661962)
		(end 12.24915 -108.672376)
		(stroke
			(width 0.05715)
			(type default)
		)
		(layer "B.Cu")
	)
	(gr_line
		(start 12.24915 -108.672376)
		(end 12.262612 -108.677964)
		(stroke
			(width 0.05715)
			(type default)
		)
		(layer "B.Cu")
	)
	(gr_line
		(start 12.289536 -39.206424)
		(end 12.403836 -39.092124)
		(stroke
			(width 0.05715)
			(type default)
		)
		(layer "B.Cu")
	)
	(gr_line
		(start 12.388088 -97.681288)
		(end 12.454128 -97.68078)
		(stroke
			(width 0.05715)
			(type default)
		)
		(layer "B.Cu")
	)
	(gr_line
		(start 12.51331 -107.37469)
		(end 12.51331 -107.69473)
		(stroke
			(width 0.05715)
			(type default)
		)
		(layer "B.Cu")
	)
	(gr_line
		(start 12.51331 -107.37469)
		(end 12.667234 -107.220766)
		(stroke
			(width 0.05715)
			(type default)
		)
		(layer "B.Cu")
	)
	(gr_line
		(start 12.51331 -106.72191)
		(end 12.667234 -106.875834)
		(stroke
			(width 0.05715)
			(type default)
		)
		(layer "B.Cu")
	)
	(gr_line
		(start 12.51331 -106.42473)
		(end 12.51331 -106.72191)
		(stroke
			(width 0.05715)
			(type default)
		)
		(layer "B.Cu")
	)
	(gr_line
		(start 12.647676 -38.987476)
		(end 12.866624 -39.206424)
		(stroke
			(width 0.05715)
			(type default)
		)
		(layer "B.Cu")
	)
	(gr_line
		(start 12.792456 -97.434908)
		(end 13.10894 -97.11436)
		(stroke
			(width 0.05715)
			(type default)
		)
		(layer "B.Cu")
	)
	(gr_line
		(start 12.792964 -97.681288)
		(end 13.11402 -97.99828)
		(stroke
			(width 0.05715)
			(type default)
		)
		(layer "B.Cu")
	)
	(gr_line
		(start 12.841986 -100.190046)
		(end 13.11402 -100.46208)
		(stroke
			(width 0.05715)
			(type default)
		)
		(layer "B.Cu")
	)
	(gr_line
		(start 12.841986 -99.845114)
		(end 13.11402 -99.57308)
		(stroke
			(width 0.05715)
			(type default)
		)
		(layer "B.Cu")
	)
	(gr_line
		(start 12.866624 -39.206424)
		(end 13.032486 -39.206424)
		(stroke
			(width 0.05715)
			(type default)
		)
		(layer "B.Cu")
	)
	(gr_line
		(start 12.926822 -31.00451)
		(end 13.098526 -31.176214)
		(stroke
			(width 0.05715)
			(type default)
		)
		(layer "B.Cu")
	)
	(gr_line
		(start 12.926822 -30.659578)
		(end 13.098526 -30.487874)
		(stroke
			(width 0.05715)
			(type default)
		)
		(layer "B.Cu")
	)
	(gr_line
		(start 12.957556 -23.861522)
		(end 13.050774 -23.95474)
		(stroke
			(width 0.05715)
			(type default)
		)
		(layer "B.Cu")
	)
	(gr_line
		(start 12.957556 -23.51659)
		(end 13.050774 -23.423372)
		(stroke
			(width 0.05715)
			(type default)
		)
		(layer "B.Cu")
	)
	(gr_line
		(start 12.998196 -34.514282)
		(end 13.098526 -34.614612)
		(stroke
			(width 0.05715)
			(type default)
		)
		(layer "B.Cu")
	)
	(gr_line
		(start 12.998196 -34.16935)
		(end 13.098526 -34.06902)
		(stroke
			(width 0.05715)
			(type default)
		)
		(layer "B.Cu")
	)
	(gr_line
		(start 13.050774 -23.95474)
		(end 13.050774 -24.3205)
		(stroke
			(width 0.05715)
			(type default)
		)
		(layer "B.Cu")
	)
	(gr_line
		(start 13.050774 -23.0505)
		(end 13.050774 -23.423372)
		(stroke
			(width 0.05715)
			(type default)
		)
		(layer "B.Cu")
	)
	(gr_line
		(start 13.098526 -34.614612)
		(end 13.098526 -34.9885)
		(stroke
			(width 0.05715)
			(type default)
		)
		(layer "B.Cu")
	)
	(gr_line
		(start 13.098526 -33.7185)
		(end 13.098526 -34.06902)
		(stroke
			(width 0.05715)
			(type default)
		)
		(layer "B.Cu")
	)
	(gr_line
		(start 13.098526 -31.176214)
		(end 13.098526 -31.4325)
		(stroke
			(width 0.05715)
			(type default)
		)
		(layer "B.Cu")
	)
	(gr_line
		(start 13.098526 -30.1625)
		(end 13.098526 -30.487874)
		(stroke
			(width 0.05715)
			(type default)
		)
		(layer "B.Cu")
	)
	(gr_line
		(start 13.29182 -102.46868)
		(end 13.69187 -102.06863)
		(stroke
			(width 0.05715)
			(type default)
		)
		(layer "B.Cu")
	)
	(gr_line
		(start 13.29182 -101.57968)
		(end 13.53693 -101.82479)
		(stroke
			(width 0.05715)
			(type default)
		)
		(layer "B.Cu")
	)
	(gr_line
		(start 13.568426 -107.213146)
		(end 13.84046 -107.48518)
		(stroke
			(width 0.05715)
			(type default)
		)
		(layer "B.Cu")
	)
	(gr_line
		(start 13.568426 -106.868214)
		(end 13.84046 -106.59618)
		(stroke
			(width 0.05715)
			(type default)
		)
		(layer "B.Cu")
	)
	(gr_line
		(start 13.777976 -103.3018)
		(end 13.777976 -103.371904)
		(stroke
			(width 0.05715)
			(type default)
		)
		(layer "B.Cu")
	)
	(gr_line
		(start 13.777976 -103.028496)
		(end 13.777976 -103.29672)
		(stroke
			(width 0.05715)
			(type default)
		)
		(layer "B.Cu")
	)
	(gr_line
		(start 13.8811 -104.79786)
		(end 13.892022 -104.808782)
		(stroke
			(width 0.05715)
			(type default)
		)
		(layer "B.Cu")
	)
	(gr_line
		(start 13.882878 -104.454706)
		(end 14.055344 -104.454706)
		(stroke
			(width 0.05715)
			(type default)
		)
		(layer "B.Cu")
	)
	(gr_line
		(start 13.950696 -103.54056)
		(end 14.016736 -103.54056)
		(stroke
			(width 0.05715)
			(type default)
		)
		(layer "B.Cu")
	)
	(gr_line
		(start 13.99794 -97.11436)
		(end 14.269974 -97.386394)
		(stroke
			(width 0.05715)
			(type default)
		)
		(layer "B.Cu")
	)
	(gr_line
		(start 14.00302 -100.46208)
		(end 14.275054 -100.190046)
		(stroke
			(width 0.05715)
			(type default)
		)
		(layer "B.Cu")
	)
	(gr_line
		(start 14.00302 -99.57308)
		(end 14.275054 -99.845114)
		(stroke
			(width 0.05715)
			(type default)
		)
		(layer "B.Cu")
	)
	(gr_line
		(start 14.00302 -97.99828)
		(end 14.269974 -97.731326)
		(stroke
			(width 0.05715)
			(type default)
		)
		(layer "B.Cu")
	)
	(gr_line
		(start 14.021816 -103.54056)
		(end 14.18844 -103.54056)
		(stroke
			(width 0.05715)
			(type default)
		)
		(layer "B.Cu")
	)
	(gr_line
		(start 14.055344 -104.454706)
		(end 14.235176 -104.634538)
		(stroke
			(width 0.05715)
			(type default)
		)
		(layer "B.Cu")
	)
	(gr_line
		(start 14.177772 -117.847872)
		(end 14.224 -117.8941)
		(stroke
			(width 0.05715)
			(type default)
		)
		(layer "B.Cu")
	)
	(gr_line
		(start 14.18844 -103.54056)
		(end 14.321282 -103.673402)
		(stroke
			(width 0.05715)
			(type default)
		)
		(layer "B.Cu")
	)
	(gr_line
		(start 14.235176 -104.634538)
		(end 14.235176 -104.807004)
		(stroke
			(width 0.05715)
			(type default)
		)
		(layer "B.Cu")
	)
	(gr_line
		(start 14.332966 -101.82479)
		(end 14.379194 -101.871018)
		(stroke
			(width 0.05715)
			(type default)
		)
		(layer "B.Cu")
	)
	(gr_line
		(start 14.416532 -105.333292)
		(end 14.427454 -105.344214)
		(stroke
			(width 0.05715)
			(type default)
		)
		(layer "B.Cu")
	)
	(gr_line
		(start 14.41831 -104.990138)
		(end 14.590776 -104.990138)
		(stroke
			(width 0.05715)
			(type default)
		)
		(layer "B.Cu")
	)
	(gr_line
		(start 14.590776 -104.990138)
		(end 14.770608 -105.16997)
		(stroke
			(width 0.05715)
			(type default)
		)
		(layer "B.Cu")
	)
	(gr_line
		(start 14.72946 -107.48518)
		(end 15.001494 -107.213146)
		(stroke
			(width 0.05715)
			(type default)
		)
		(layer "B.Cu")
	)
	(gr_line
		(start 14.72946 -106.59618)
		(end 15.001494 -106.868214)
		(stroke
			(width 0.05715)
			(type default)
		)
		(layer "B.Cu")
	)
	(gr_line
		(start 14.753336 -97.441258)
		(end 14.767306 -97.455228)
		(stroke
			(width 0.05715)
			(type default)
		)
		(layer "B.Cu")
	)
	(gr_line
		(start 14.770608 -105.16997)
		(end 14.770608 -105.342436)
		(stroke
			(width 0.05715)
			(type default)
		)
		(layer "B.Cu")
	)
	(gr_line
		(start 14.9098 -71.702422)
		(end 14.9098 -71.882)
		(stroke
			(width 0.1905)
			(type default)
		)
		(layer "B.Cu")
	)
	(gr_line
		(start 14.9098 -71.702422)
		(end 15.377922 -71.2343)
		(stroke
			(width 0.1905)
			(type default)
		)
		(layer "B.Cu")
	)
	(gr_line
		(start 15.118842 -115.922552)
		(end 15.132304 -115.92814)
		(stroke
			(width 0.05715)
			(type default)
		)
		(layer "B.Cu")
	)
	(gr_line
		(start 15.14094 -102.632764)
		(end 15.151354 -102.643178)
		(stroke
			(width 0.05715)
			(type default)
		)
		(layer "B.Cu")
	)
	(gr_line
		(start 15.151354 -102.643178)
		(end 15.156942 -102.65664)
		(stroke
			(width 0.05715)
			(type default)
		)
		(layer "B.Cu")
	)
	(gr_line
		(start 15.377922 -71.2343)
		(end 16.268954 -71.2343)
		(stroke
			(width 0.1905)
			(type default)
		)
		(layer "B.Cu")
	)
	(gr_line
		(start 15.470886 -104.001824)
		(end 15.472918 -104.005888)
		(stroke
			(width 0.05715)
			(type default)
		)
		(layer "B.Cu")
	)
	(gr_line
		(start 15.472918 -104.005888)
		(end 15.47622 -104.00919)
		(stroke
			(width 0.05715)
			(type default)
		)
		(layer "B.Cu")
	)
	(gr_line
		(start 15.49527 -108.76153)
		(end 15.49527 -109.04347)
		(stroke
			(width 0.05715)
			(type default)
		)
		(layer "B.Cu")
	)
	(gr_line
		(start 15.49527 -108.76153)
		(end 15.677134 -108.579666)
		(stroke
			(width 0.05715)
			(type default)
		)
		(layer "B.Cu")
	)
	(gr_line
		(start 15.49527 -108.05287)
		(end 15.677134 -108.234734)
		(stroke
			(width 0.05715)
			(type default)
		)
		(layer "B.Cu")
	)
	(gr_line
		(start 15.49527 -107.77347)
		(end 15.49527 -108.05287)
		(stroke
			(width 0.05715)
			(type default)
		)
		(layer "B.Cu")
	)
	(gr_line
		(start 15.640558 -115.065302)
		(end 15.65402 -115.07089)
		(stroke
			(width 0.05715)
			(type default)
		)
		(layer "B.Cu")
	)
	(gr_line
		(start 15.65402 -115.07089)
		(end 15.664434 -115.081304)
		(stroke
			(width 0.05715)
			(type default)
		)
		(layer "B.Cu")
	)
	(gr_line
		(start 15.7353 -105.52303)
		(end 15.85722 -105.40111)
		(stroke
			(width 0.05715)
			(type default)
		)
		(layer "B.Cu")
	)
	(gr_line
		(start 15.748 -70.3072)
		(end 15.748 -70.612)
		(stroke
			(width 0.1905)
			(type default)
		)
		(layer "B.Cu")
	)
	(gr_line
		(start 15.748 -70.3072)
		(end 16.0782 -69.977)
		(stroke
			(width 0.1905)
			(type default)
		)
		(layer "B.Cu")
	)
	(gr_line
		(start 15.786608 -104.31907)
		(end 15.796006 -104.328468)
		(stroke
			(width 0.05715)
			(type default)
		)
		(layer "B.Cu")
	)
	(gr_line
		(start 15.796006 -104.328468)
		(end 15.80769 -104.333294)
		(stroke
			(width 0.05715)
			(type default)
		)
		(layer "B.Cu")
	)
	(gr_line
		(start 15.85722 -105.40111)
		(end 16.11122 -105.40111)
		(stroke
			(width 0.05715)
			(type default)
		)
		(layer "B.Cu")
	)
	(gr_line
		(start 15.9766 -105.76687)
		(end 15.99184 -105.76687)
		(stroke
			(width 0.05715)
			(type default)
		)
		(layer "B.Cu")
	)
	(gr_line
		(start 15.990062 -104.40924)
		(end 16.001746 -104.41432)
		(stroke
			(width 0.05715)
			(type default)
		)
		(layer "B.Cu")
	)
	(gr_line
		(start 16.008096 -103.031544)
		(end 16.363696 -103.031544)
		(stroke
			(width 0.05715)
			(type default)
		)
		(layer "B.Cu")
	)
	(gr_line
		(start 16.026892 -38.474142)
		(end 16.426942 -38.474142)
		(stroke
			(width 0.05715)
			(type default)
		)
		(layer "B.Cu")
	)
	(gr_line
		(start 16.0782 -69.977)
		(end 16.8148 -69.977)
		(stroke
			(width 0.1905)
			(type default)
		)
		(layer "B.Cu")
	)
	(gr_line
		(start 16.11122 -105.40111)
		(end 16.23314 -105.52303)
		(stroke
			(width 0.05715)
			(type default)
		)
		(layer "B.Cu")
	)
	(gr_line
		(start 16.207232 -114.254026)
		(end 16.220694 -114.259614)
		(stroke
			(width 0.05715)
			(type default)
		)
		(layer "B.Cu")
	)
	(gr_line
		(start 16.268954 -71.2343)
		(end 16.7894 -71.754746)
		(stroke
			(width 0.1905)
			(type default)
		)
		(layer "B.Cu")
	)
	(gr_line
		(start 16.368776 -103.031544)
		(end 16.432022 -103.031544)
		(stroke
			(width 0.05715)
			(type default)
		)
		(layer "B.Cu")
	)
	(gr_line
		(start 16.40586 -104.41686)
		(end 16.51762 -104.52862)
		(stroke
			(width 0.05715)
			(type default)
		)
		(layer "B.Cu")
	)
	(gr_circle
		(center 16.4084 -131.5974)
		(end 16.6624 -131.5974)
		(stroke
			(width 0.2)
			(type default)
		)
		(fill no)
		(layer "B.Cu")
	)
	(gr_circle
		(center 16.4084 -130.9624)
		(end 16.6624 -130.9624)
		(stroke
			(width 0.2)
			(type default)
		)
		(fill no)
		(layer "B.Cu")
	)
	(gr_circle
		(center 16.4084 -130.3274)
		(end 16.6624 -130.3274)
		(stroke
			(width 0.2)
			(type default)
		)
		(fill no)
		(layer "B.Cu")
	)
	(gr_line
		(start 16.425418 -122.100594)
		(end 16.43761 -122.105674)
		(stroke
			(width 0.05715)
			(type default)
		)
		(layer "B.Cu")
	)
	(gr_line
		(start 16.426942 -38.474142)
		(end 16.489426 -38.411658)
		(stroke
			(width 0.05715)
			(type default)
		)
		(layer "B.Cu")
	)
	(gr_line
		(start 16.44015 -100.74783)
		(end 16.867124 -100.320856)
		(stroke
			(width 0.05715)
			(type default)
		)
		(layer "B.Cu")
	)
	(gr_line
		(start 16.44015 -99.54895)
		(end 16.867124 -99.975924)
		(stroke
			(width 0.05715)
			(type default)
		)
		(layer "B.Cu")
	)
	(gr_line
		(start 16.44015 -99.47783)
		(end 16.44015 -99.54895)
		(stroke
			(width 0.05715)
			(type default)
		)
		(layer "B.Cu")
	)
	(gr_line
		(start 16.49222 -105.52303)
		(end 16.61414 -105.40111)
		(stroke
			(width 0.05715)
			(type default)
		)
		(layer "B.Cu")
	)
	(gr_line
		(start 16.51762 -104.52862)
		(end 16.86052 -104.52862)
		(stroke
			(width 0.05715)
			(type default)
		)
		(layer "B.Cu")
	)
	(gr_line
		(start 16.550386 -108.561886)
		(end 16.82242 -108.83392)
		(stroke
			(width 0.05715)
			(type default)
		)
		(layer "B.Cu")
	)
	(gr_line
		(start 16.550386 -108.216954)
		(end 16.82242 -107.94492)
		(stroke
			(width 0.05715)
			(type default)
		)
		(layer "B.Cu")
	)
	(gr_circle
		(center 16.5862 -129.6924)
		(end 16.8402 -129.6924)
		(stroke
			(width 0.2)
			(type default)
		)
		(fill no)
		(layer "B.Cu")
	)
	(gr_line
		(start 16.607536 -102.792784)
		(end 16.607536 -102.865682)
		(stroke
			(width 0.05715)
			(type default)
		)
		(layer "B.Cu")
	)
	(gr_line
		(start 16.607536 -102.427532)
		(end 16.607536 -102.787704)
		(stroke
			(width 0.05715)
			(type default)
		)
		(layer "B.Cu")
	)
	(gr_line
		(start 16.61414 -105.40111)
		(end 16.86814 -105.40111)
		(stroke
			(width 0.05715)
			(type default)
		)
		(layer "B.Cu")
	)
	(gr_line
		(start 16.64716 -104.17302)
		(end 16.73098 -104.17302)
		(stroke
			(width 0.05715)
			(type default)
		)
		(layer "B.Cu")
	)
	(gr_line
		(start 16.73352 -105.76687)
		(end 16.74876 -105.76687)
		(stroke
			(width 0.05715)
			(type default)
		)
		(layer "B.Cu")
	)
	(gr_line
		(start 16.764 -113.438686)
		(end 16.777462 -113.444274)
		(stroke
			(width 0.05715)
			(type default)
		)
		(layer "B.Cu")
	)
	(gr_line
		(start 16.7894 -71.758048)
		(end 17.497552 -72.4662)
		(stroke
			(width 0.1905)
			(type default)
		)
		(layer "B.Cu")
	)
	(gr_line
		(start 16.7894 -71.754746)
		(end 16.7894 -71.758048)
		(stroke
			(width 0.1905)
			(type default)
		)
		(layer "B.Cu")
	)
	(gr_line
		(start 16.797274 -98.559874)
		(end 16.809212 -98.5647)
		(stroke
			(width 0.05715)
			(type default)
		)
		(layer "B.Cu")
	)
	(gr_line
		(start 16.8148 -69.977)
		(end 17.145 -70.3072)
		(stroke
			(width 0.1905)
			(type default)
		)
		(layer "B.Cu")
	)
	(gr_line
		(start 16.834358 -38.411658)
		(end 16.896842 -38.474142)
		(stroke
			(width 0.05715)
			(type default)
		)
		(layer "B.Cu")
	)
	(gr_line
		(start 16.86052 -104.52862)
		(end 16.97228 -104.41686)
		(stroke
			(width 0.05715)
			(type default)
		)
		(layer "B.Cu")
	)
	(gr_line
		(start 16.86814 -105.40111)
		(end 16.99006 -105.52303)
		(stroke
			(width 0.05715)
			(type default)
		)
		(layer "B.Cu")
	)
	(gr_line
		(start 16.896842 -38.474142)
		(end 17.296892 -38.474142)
		(stroke
			(width 0.05715)
			(type default)
		)
		(layer "B.Cu")
	)
	(gr_circle
		(center 16.9545 -131.9276)
		(end 17.2085 -131.9276)
		(stroke
			(width 0.2)
			(type default)
		)
		(fill no)
		(layer "B.Cu")
	)
	(gr_circle
		(center 16.9545 -131.2926)
		(end 17.2085 -131.2926)
		(stroke
			(width 0.2)
			(type default)
		)
		(fill no)
		(layer "B.Cu")
	)
	(gr_circle
		(center 16.9545 -130.6576)
		(end 17.2085 -130.6576)
		(stroke
			(width 0.2)
			(type default)
		)
		(fill no)
		(layer "B.Cu")
	)
	(gr_line
		(start 17.13992 -102.973632)
		(end 17.208246 -102.973632)
		(stroke
			(width 0.05715)
			(type default)
		)
		(layer "B.Cu")
	)
	(gr_line
		(start 17.145 -70.3072)
		(end 17.4498 -70.612)
		(stroke
			(width 0.1905)
			(type default)
		)
		(layer "B.Cu")
	)
	(gr_line
		(start 17.32026 -104.41686)
		(end 17.43202 -104.52862)
		(stroke
			(width 0.05715)
			(type default)
		)
		(layer "B.Cu")
	)
	(gr_line
		(start 17.330166 -112.61852)
		(end 17.343628 -112.624108)
		(stroke
			(width 0.05715)
			(type default)
		)
		(layer "B.Cu")
	)
	(gr_line
		(start 17.343628 -112.624108)
		(end 17.354042 -112.634522)
		(stroke
			(width 0.05715)
			(type default)
		)
		(layer "B.Cu")
	)
	(gr_line
		(start 17.3482 -71.5264)
		(end 17.4498 -71.4248)
		(stroke
			(width 0.1905)
			(type default)
		)
		(layer "B.Cu")
	)
	(gr_line
		(start 17.37868 -103.144574)
		(end 17.447006 -103.144574)
		(stroke
			(width 0.05715)
			(type default)
		)
		(layer "B.Cu")
	)
	(gr_line
		(start 17.43202 -104.52862)
		(end 17.77492 -104.52862)
		(stroke
			(width 0.05715)
			(type default)
		)
		(layer "B.Cu")
	)
	(gr_line
		(start 17.4498 -70.612)
		(end 17.4498 -71.4248)
		(stroke
			(width 0.1905)
			(type default)
		)
		(layer "B.Cu")
	)
	(gr_line
		(start 17.47647 -122.538236)
		(end 17.488662 -122.543316)
		(stroke
			(width 0.05715)
			(type default)
		)
		(layer "B.Cu")
	)
	(gr_line
		(start 17.497552 -72.4662)
		(end 18.415508 -72.4662)
		(stroke
			(width 0.1905)
			(type default)
		)
		(layer "B.Cu")
	)
	(gr_line
		(start 17.51711 -105.76941)
		(end 17.83842 -106.09072)
		(stroke
			(width 0.05715)
			(type default)
		)
		(layer "B.Cu")
	)
	(gr_line
		(start 17.56156 -104.17302)
		(end 17.64538 -104.17302)
		(stroke
			(width 0.05715)
			(type default)
		)
		(layer "B.Cu")
	)
	(gr_line
		(start 17.566386 -100.332286)
		(end 17.83842 -100.60432)
		(stroke
			(width 0.05715)
			(type default)
		)
		(layer "B.Cu")
	)
	(gr_line
		(start 17.566386 -99.987354)
		(end 17.83842 -99.71532)
		(stroke
			(width 0.05715)
			(type default)
		)
		(layer "B.Cu")
	)
	(gr_line
		(start 17.643094 -103.152194)
		(end 17.83842 -103.34752)
		(stroke
			(width 0.05715)
			(type default)
		)
		(layer "B.Cu")
	)
	(gr_line
		(start 17.643094 -102.807262)
		(end 17.83842 -102.611936)
		(stroke
			(width 0.05715)
			(type default)
		)
		(layer "B.Cu")
	)
	(gr_line
		(start 17.71142 -108.72978)
		(end 17.71142 -108.83392)
		(stroke
			(width 0.05715)
			(type default)
		)
		(layer "B.Cu")
	)
	(gr_line
		(start 17.71142 -108.72978)
		(end 17.931384 -108.509816)
		(stroke
			(width 0.05715)
			(type default)
		)
		(layer "B.Cu")
	)
	(gr_line
		(start 17.71142 -107.94492)
		(end 17.931384 -108.164884)
		(stroke
			(width 0.05715)
			(type default)
		)
		(layer "B.Cu")
	)
	(gr_line
		(start 17.72031 -105.52557)
		(end 17.83842 -105.40746)
		(stroke
			(width 0.05715)
			(type default)
		)
		(layer "B.Cu")
	)
	(gr_line
		(start 17.77492 -104.52862)
		(end 17.88668 -104.41686)
		(stroke
			(width 0.05715)
			(type default)
		)
		(layer "B.Cu")
	)
	(gr_line
		(start 17.798542 -106.90098)
		(end 17.810988 -106.90606)
		(stroke
			(width 0.05715)
			(type default)
		)
		(layer "B.Cu")
	)
	(gr_line
		(start 17.83842 -105.20172)
		(end 17.83842 -105.40746)
		(stroke
			(width 0.05715)
			(type default)
		)
		(layer "B.Cu")
	)
	(gr_line
		(start 17.83842 -102.45852)
		(end 17.83842 -102.611936)
		(stroke
			(width 0.05715)
			(type default)
		)
		(layer "B.Cu")
	)
	(gr_line
		(start 17.869916 -111.787686)
		(end 17.883378 -111.793274)
		(stroke
			(width 0.05715)
			(type default)
		)
		(layer "B.Cu")
	)
	(gr_line
		(start 17.883378 -111.793274)
		(end 17.893792 -111.803688)
		(stroke
			(width 0.05715)
			(type default)
		)
		(layer "B.Cu")
	)
	(gr_line
		(start 18.077688 4.695444)
		(end 18.089118 4.695444)
		(stroke
			(width 0.0635)
			(type default)
		)
		(layer "B.Cu")
	)
	(gr_line
		(start 18.089118 4.695444)
		(end 18.427446 5.033772)
		(stroke
			(width 0.0635)
			(type default)
		)
		(layer "B.Cu")
	)
	(gr_line
		(start 18.23466 -104.41686)
		(end 18.34642 -104.52862)
		(stroke
			(width 0.05715)
			(type default)
		)
		(layer "B.Cu")
	)
	(gr_line
		(start 18.306288 -109.591348)
		(end 18.352516 -109.637576)
		(stroke
			(width 0.05715)
			(type default)
		)
		(layer "B.Cu")
	)
	(gr_line
		(start 18.34642 -104.52862)
		(end 18.68932 -104.52862)
		(stroke
			(width 0.05715)
			(type default)
		)
		(layer "B.Cu")
	)
	(gr_line
		(start 18.415508 -72.4662)
		(end 18.517616 -72.364092)
		(stroke
			(width 0.1905)
			(type default)
		)
		(layer "B.Cu")
	)
	(gr_line
		(start 18.443194 -110.976156)
		(end 18.457164 -110.981744)
		(stroke
			(width 0.05715)
			(type default)
		)
		(layer "B.Cu")
	)
	(gr_line
		(start 18.457164 -110.981744)
		(end 18.468086 -110.992412)
		(stroke
			(width 0.05715)
			(type default)
		)
		(layer "B.Cu")
	)
	(gr_line
		(start 18.47596 -104.17302)
		(end 18.55978 -104.17302)
		(stroke
			(width 0.05715)
			(type default)
		)
		(layer "B.Cu")
	)
	(gr_circle
		(center 18.542 -128.7526)
		(end 18.796 -128.7526)
		(stroke
			(width 0.2)
			(type default)
		)
		(fill no)
		(layer "B.Cu")
	)
	(gr_circle
		(center 18.542 -127.0254)
		(end 18.796 -127.0254)
		(stroke
			(width 0.2)
			(type default)
		)
		(fill no)
		(layer "B.Cu")
	)
	(gr_line
		(start 18.68932 -104.52862)
		(end 18.80108 -104.41686)
		(stroke
			(width 0.05715)
			(type default)
		)
		(layer "B.Cu")
	)
	(gr_line
		(start 18.713196 4.864354)
		(end 18.894044 4.683506)
		(stroke
			(width 0.0635)
			(type default)
		)
		(layer "B.Cu")
	)
	(gr_line
		(start 18.72742 -106.09072)
		(end 18.999454 -105.818686)
		(stroke
			(width 0.05715)
			(type default)
		)
		(layer "B.Cu")
	)
	(gr_line
		(start 18.72742 -105.20172)
		(end 19.08048 -105.55478)
		(stroke
			(width 0.05715)
			(type default)
		)
		(layer "B.Cu")
	)
	(gr_line
		(start 18.72742 -103.34752)
		(end 18.999454 -103.075486)
		(stroke
			(width 0.05715)
			(type default)
		)
		(layer "B.Cu")
	)
	(gr_line
		(start 18.72742 -102.45852)
		(end 18.999454 -102.730554)
		(stroke
			(width 0.05715)
			(type default)
		)
		(layer "B.Cu")
	)
	(gr_line
		(start 18.72742 -100.60432)
		(end 18.999454 -100.332286)
		(stroke
			(width 0.05715)
			(type default)
		)
		(layer "B.Cu")
	)
	(gr_line
		(start 18.72742 -99.71532)
		(end 18.999454 -99.987354)
		(stroke
			(width 0.05715)
			(type default)
		)
		(layer "B.Cu")
	)
	(gr_line
		(start 18.79092 -107.312206)
		(end 18.804382 -107.317794)
		(stroke
			(width 0.05715)
			(type default)
		)
		(layer "B.Cu")
	)
	(gr_line
		(start 18.804382 -107.317794)
		(end 18.814796 -107.328208)
		(stroke
			(width 0.05715)
			(type default)
		)
		(layer "B.Cu")
	)
	(gr_circle
		(center 19.3548 -128.7526)
		(end 19.6088 -128.7526)
		(stroke
			(width 0.2)
			(type default)
		)
		(fill no)
		(layer "B.Cu")
	)
	(gr_circle
		(center 19.3548 -127.0254)
		(end 19.6088 -127.0254)
		(stroke
			(width 0.2)
			(type default)
		)
		(fill no)
		(layer "B.Cu")
	)
	(gr_line
		(start 19.792442 -122.302016)
		(end 19.80438 -122.306842)
		(stroke
			(width 0.05715)
			(type default)
		)
		(layer "B.Cu")
	)
	(gr_line
		(start 20.159218 -102.748588)
		(end 20.20443 -102.794054)
		(stroke
			(width 0.05715)
			(type default)
		)
		(layer "B.Cu")
	)
	(gr_circle
		(center 20.1676 -128.7526)
		(end 20.4216 -128.7526)
		(stroke
			(width 0.2)
			(type default)
		)
		(fill no)
		(layer "B.Cu")
	)
	(gr_circle
		(center 20.1676 -127.0254)
		(end 20.4216 -127.0254)
		(stroke
			(width 0.2)
			(type default)
		)
		(fill no)
		(layer "B.Cu")
	)
	(gr_line
		(start 20.440904 -120.19915)
		(end 20.454366 -120.212612)
		(stroke
			(width 0.05715)
			(type default)
		)
		(layer "B.Cu")
	)
	(gr_line
		(start 20.454366 -120.212612)
		(end 20.472146 -120.219216)
		(stroke
			(width 0.05715)
			(type default)
		)
		(layer "B.Cu")
	)
	(gr_line
		(start 20.47113 -101.6889)
		(end 20.517358 -101.735128)
		(stroke
			(width 0.05715)
			(type default)
		)
		(layer "B.Cu")
	)
	(gr_line
		(start 20.73783 -98.3234)
		(end 20.784058 -98.369628)
		(stroke
			(width 0.05715)
			(type default)
		)
		(layer "B.Cu")
	)
	(gr_line
		(start 20.79371 -121.931176)
		(end 20.807172 -121.936764)
		(stroke
			(width 0.05715)
			(type default)
		)
		(layer "B.Cu")
	)
	(gr_line
		(start 20.98548 -119.36603)
		(end 20.99945 -119.38)
		(stroke
			(width 0.05715)
			(type default)
		)
		(layer "B.Cu")
	)
	(gr_line
		(start 20.99945 -119.38)
		(end 21.017992 -119.386604)
		(stroke
			(width 0.05715)
			(type default)
		)
		(layer "B.Cu")
	)
	(gr_line
		(start 21.36267 -108.72978)
		(end 21.408898 -108.776008)
		(stroke
			(width 0.05715)
			(type default)
		)
		(layer "B.Cu")
	)
	(gr_line
		(start 21.453602 -104.044496)
		(end 21.463254 -104.054148)
		(stroke
			(width 0.05715)
			(type default)
		)
		(layer "B.Cu")
	)
	(gr_line
		(start 21.463254 -104.054148)
		(end 21.468588 -104.066848)
		(stroke
			(width 0.05715)
			(type default)
		)
		(layer "B.Cu")
	)
	(gr_line
		(start 21.497036 -118.505478)
		(end 21.511006 -118.519448)
		(stroke
			(width 0.05715)
			(type default)
		)
		(layer "B.Cu")
	)
	(gr_line
		(start 21.511006 -118.519448)
		(end 21.529548 -118.526052)
		(stroke
			(width 0.05715)
			(type default)
		)
		(layer "B.Cu")
	)
	(gr_line
		(start 21.899626 -105.737914)
		(end 21.905214 -105.751376)
		(stroke
			(width 0.05715)
			(type default)
		)
		(layer "B.Cu")
	)
	(gr_line
		(start 21.90242 -157.5435)
		(end 22.253702 -157.894782)
		(stroke
			(width 0.0635)
			(type default)
		)
		(layer "B.Cu")
	)
	(gr_line
		(start 21.905214 -105.751376)
		(end 21.915628 -105.76179)
		(stroke
			(width 0.05715)
			(type default)
		)
		(layer "B.Cu")
	)
	(gr_line
		(start 22.049232 -117.67185)
		(end 22.063202 -117.68582)
		(stroke
			(width 0.05715)
			(type default)
		)
		(layer "B.Cu")
	)
	(gr_line
		(start 22.063202 -117.68582)
		(end 22.081744 -117.692424)
		(stroke
			(width 0.05715)
			(type default)
		)
		(layer "B.Cu")
	)
	(gr_line
		(start 22.253702 -157.901894)
		(end 22.336252 -157.984444)
		(stroke
			(width 0.0635)
			(type default)
		)
		(layer "B.Cu")
	)
	(gr_line
		(start 22.253702 -157.894782)
		(end 22.253702 -157.901894)
		(stroke
			(width 0.0635)
			(type default)
		)
		(layer "B.Cu")
	)
	(gr_line
		(start 22.296374 -103.514398)
		(end 22.306788 -103.524812)
		(stroke
			(width 0.05715)
			(type default)
		)
		(layer "B.Cu")
	)
	(gr_line
		(start 22.306788 -103.524812)
		(end 22.312376 -103.538274)
		(stroke
			(width 0.05715)
			(type default)
		)
		(layer "B.Cu")
	)
	(gr_line
		(start 22.354286 -108.344716)
		(end 22.400514 -108.390944)
		(stroke
			(width 0.05715)
			(type default)
		)
		(layer "B.Cu")
	)
	(gr_line
		(start 22.543008 -116.794788)
		(end 22.556978 -116.808758)
		(stroke
			(width 0.05715)
			(type default)
		)
		(layer "B.Cu")
	)
	(gr_line
		(start 22.556978 -116.808758)
		(end 22.57552 -116.815362)
		(stroke
			(width 0.05715)
			(type default)
		)
		(layer "B.Cu")
	)
	(gr_line
		(start 22.626066 -101.761544)
		(end 22.631654 -101.775006)
		(stroke
			(width 0.05715)
			(type default)
		)
		(layer "B.Cu")
	)
	(gr_line
		(start 22.69744 -157.55874)
		(end 22.69744 -157.98292)
		(stroke
			(width 0.0635)
			(type default)
		)
		(layer "B.Cu")
	)
	(gr_line
		(start 22.729698 -105.17632)
		(end 22.735286 -105.189782)
		(stroke
			(width 0.05715)
			(type default)
		)
		(layer "B.Cu")
	)
	(gr_line
		(start 22.735286 -105.189782)
		(end 22.7457 -105.200196)
		(stroke
			(width 0.05715)
			(type default)
		)
		(layer "B.Cu")
	)
	(gr_line
		(start 23.0505 -114.33556)
		(end 23.060914 -114.345974)
		(stroke
			(width 0.05715)
			(type default)
		)
		(layer "B.Cu")
	)
	(gr_line
		(start 23.060914 -114.345974)
		(end 23.074376 -114.351562)
		(stroke
			(width 0.05715)
			(type default)
		)
		(layer "B.Cu")
	)
	(gr_line
		(start 23.123652 -115.975638)
		(end 23.138638 -115.990624)
		(stroke
			(width 0.05715)
			(type default)
		)
		(layer "B.Cu")
	)
	(gr_line
		(start 23.138638 -115.990624)
		(end 23.15845 -115.997736)
		(stroke
			(width 0.05715)
			(type default)
		)
		(layer "B.Cu")
	)
	(gr_line
		(start 23.339806 -107.908344)
		(end 23.386034 -107.954572)
		(stroke
			(width 0.05715)
			(type default)
		)
		(layer "B.Cu")
	)
	(gr_line
		(start 23.345902 -100.931472)
		(end 23.356316 -100.941886)
		(stroke
			(width 0.05715)
			(type default)
		)
		(layer "B.Cu")
	)
	(gr_line
		(start 23.356316 -100.941886)
		(end 23.361904 -100.955348)
		(stroke
			(width 0.05715)
			(type default)
		)
		(layer "B.Cu")
	)
	(gr_line
		(start 23.534878 -107.03941)
		(end 23.581106 -107.085638)
		(stroke
			(width 0.05715)
			(type default)
		)
		(layer "B.Cu")
	)
	(gr_line
		(start 23.553928 -104.633522)
		(end 23.559516 -104.646984)
		(stroke
			(width 0.05715)
			(type default)
		)
		(layer "B.Cu")
	)
	(gr_line
		(start 23.559516 -104.646984)
		(end 23.56993 -104.657398)
		(stroke
			(width 0.05715)
			(type default)
		)
		(layer "B.Cu")
	)
	(gr_line
		(start 23.600156 -113.51514)
		(end 23.61057 -113.525554)
		(stroke
			(width 0.05715)
			(type default)
		)
		(layer "B.Cu")
	)
	(gr_line
		(start 23.61057 -113.525554)
		(end 23.624032 -113.531142)
		(stroke
			(width 0.05715)
			(type default)
		)
		(layer "B.Cu")
	)
	(gr_line
		(start 24.321008 -107.517692)
		(end 24.367236 -107.56392)
		(stroke
			(width 0.05715)
			(type default)
		)
		(layer "B.Cu")
	)
	(gr_line
		(start 24.406606 -104.10952)
		(end 24.412194 -104.122982)
		(stroke
			(width 0.05715)
			(type default)
		)
		(layer "B.Cu")
	)
	(gr_line
		(start 24.412194 -104.122982)
		(end 24.422608 -104.133396)
		(stroke
			(width 0.05715)
			(type default)
		)
		(layer "B.Cu")
	)
	(gr_line
		(start 24.51608 -106.628946)
		(end 24.562308 -106.675174)
		(stroke
			(width 0.05715)
			(type default)
		)
		(layer "B.Cu")
	)
	(gr_line
		(start 25.024334 -106.111548)
		(end 25.024334 -106.111802)
		(stroke
			(width 0.05715)
			(type default)
		)
		(layer "B.Cu")
	)
	(gr_line
		(start 25.195022 -105.94086)
		(end 25.195022 -105.941114)
		(stroke
			(width 0.05715)
			(type default)
		)
		(layer "B.Cu")
	)
	(gr_line
		(start 25.395936 -107.195366)
		(end 25.442164 -107.241594)
		(stroke
			(width 0.05715)
			(type default)
		)
		(layer "B.Cu")
	)
	(gr_line
		(start 25.916382 -113.283746)
		(end 25.929844 -113.289334)
		(stroke
			(width 0.05715)
			(type default)
		)
		(layer "B.Cu")
	)
	(gr_line
		(start 26.0985 -112.089692)
		(end 26.137616 -112.097058)
		(stroke
			(width 0.05715)
			(type default)
		)
		(layer "B.Cu")
	)
	(gr_line
		(start 26.555446 -111.122714)
		(end 26.582116 -111.149384)
		(stroke
			(width 0.05715)
			(type default)
		)
		(layer "B.Cu")
	)
	(gr_line
		(start 26.562304 -105.931462)
		(end 26.608532 -105.97769)
		(stroke
			(width 0.05715)
			(type default)
		)
		(layer "B.Cu")
	)
	(gr_line
		(start 26.582116 -111.149384)
		(end 26.618692 -111.157004)
		(stroke
			(width 0.05715)
			(type default)
		)
		(layer "B.Cu")
	)
	(gr_line
		(start 27.025092 -110.22076)
		(end 27.051762 -110.24743)
		(stroke
			(width 0.05715)
			(type default)
		)
		(layer "B.Cu")
	)
	(gr_line
		(start 27.051762 -110.24743)
		(end 27.088338 -110.25505)
		(stroke
			(width 0.05715)
			(type default)
		)
		(layer "B.Cu")
	)
	(gr_line
		(start 27.303984 -125.674374)
		(end 27.315922 -125.6792)
		(stroke
			(width 0.05715)
			(type default)
		)
		(layer "B.Cu")
	)
	(gr_line
		(start 27.469084 -124.696474)
		(end 27.481022 -124.7013)
		(stroke
			(width 0.05715)
			(type default)
		)
		(layer "B.Cu")
	)
	(gr_line
		(start 27.503628 -109.30255)
		(end 27.530298 -109.32922)
		(stroke
			(width 0.05715)
			(type default)
		)
		(layer "B.Cu")
	)
	(gr_line
		(start 27.530298 -109.32922)
		(end 27.566874 -109.33684)
		(stroke
			(width 0.05715)
			(type default)
		)
		(layer "B.Cu")
	)
	(gr_line
		(start 28.015438 -108.443014)
		(end 28.052014 -108.450634)
		(stroke
			(width 0.05715)
			(type default)
		)
		(layer "B.Cu")
	)
	(gr_line
		(start 28.601416 -112.33023)
		(end 28.61437 -112.332516)
		(stroke
			(width 0.05715)
			(type default)
		)
		(layer "B.Cu")
	)
	(gr_line
		(start 28.61437 -112.332516)
		(end 28.6258 -112.340136)
		(stroke
			(width 0.05715)
			(type default)
		)
		(layer "B.Cu")
	)
	(gr_line
		(start 29.040074 -111.413036)
		(end 29.052266 -111.415576)
		(stroke
			(width 0.05715)
			(type default)
		)
		(layer "B.Cu")
	)
	(gr_line
		(start 29.052266 -111.415576)
		(end 29.06268 -111.422434)
		(stroke
			(width 0.05715)
			(type default)
		)
		(layer "B.Cu")
	)
	(gr_line
		(start 29.772356 -110.565438)
		(end 29.798772 -110.571026)
		(stroke
			(width 0.05715)
			(type default)
		)
		(layer "B.Cu")
	)
	(gr_line
		(start 29.798772 -110.571026)
		(end 29.819346 -110.588552)
		(stroke
			(width 0.05715)
			(type default)
		)
		(layer "B.Cu")
	)
	(gr_line
		(start 30.10027 -123.72086)
		(end 30.107382 -123.7234)
		(stroke
			(width 0.05715)
			(type default)
		)
		(layer "B.Cu")
	)
	(gr_line
		(start 30.35173 -109.668564)
		(end 30.389322 -109.676438)
		(stroke
			(width 0.05715)
			(type default)
		)
		(layer "B.Cu")
	)
	(gr_line
		(start 30.361636 -122.730514)
		(end 30.367986 -122.7328)
		(stroke
			(width 0.05715)
			(type default)
		)
		(layer "B.Cu")
	)
	(gr_line
		(start 30.387544 -118.58498)
		(end 30.393894 -118.587266)
		(stroke
			(width 0.05715)
			(type default)
		)
		(layer "B.Cu")
	)
	(gr_line
		(start 30.48 -117.419374)
		(end 30.491938 -117.4242)
		(stroke
			(width 0.05715)
			(type default)
		)
		(layer "B.Cu")
	)
	(gr_line
		(start 30.509464 -121.739914)
		(end 30.515814 -121.7422)
		(stroke
			(width 0.05715)
			(type default)
		)
		(layer "B.Cu")
	)
	(gr_line
		(start 30.551628 -119.669814)
		(end 30.557978 -119.6721)
		(stroke
			(width 0.05715)
			(type default)
		)
		(layer "B.Cu")
	)
	(gr_line
		(start 30.619446 -116.428774)
		(end 30.631384 -116.4336)
		(stroke
			(width 0.05715)
			(type default)
		)
		(layer "B.Cu")
	)
	(gr_line
		(start 30.625288 -120.749314)
		(end 30.631638 -120.7516)
		(stroke
			(width 0.05715)
			(type default)
		)
		(layer "B.Cu")
	)
	(gr_line
		(start 30.628082 -111.593122)
		(end 30.631638 -111.59617)
		(stroke
			(width 0.05715)
			(type default)
		)
		(layer "B.Cu")
	)
	(gr_line
		(start 30.631638 -111.59617)
		(end 30.635956 -111.597948)
		(stroke
			(width 0.05715)
			(type default)
		)
		(layer "B.Cu")
	)
	(gr_line
		(start 30.840934 -108.782358)
		(end 30.87751 -108.789978)
		(stroke
			(width 0.05715)
			(type default)
		)
		(layer "B.Cu")
	)
	(gr_line
		(start 30.87751 -108.789978)
		(end 30.90418 -108.816648)
		(stroke
			(width 0.05715)
			(type default)
		)
		(layer "B.Cu")
	)
	(gr_line
		(start 31.056326 -115.412774)
		(end 31.068264 -115.4176)
		(stroke
			(width 0.05715)
			(type default)
		)
		(layer "B.Cu")
	)
	(gr_line
		(start 31.077408 -110.706154)
		(end 31.09087 -110.711742)
		(stroke
			(width 0.05715)
			(type default)
		)
		(layer "B.Cu")
	)
	(gr_line
		(start 31.576264 -109.830108)
		(end 31.586678 -109.840522)
		(stroke
			(width 0.05715)
			(type default)
		)
		(layer "B.Cu")
	)
	(gr_line
		(start 31.586678 -109.840522)
		(end 31.60014 -109.84611)
		(stroke
			(width 0.05715)
			(type default)
		)
		(layer "B.Cu")
	)
	(gr_line
		(start 32.31261 -114.42192)
		(end 32.324548 -114.426746)
		(stroke
			(width 0.05715)
			(type default)
		)
		(layer "B.Cu")
	)
	(gr_line
		(start 32.457644 -113.43132)
		(end 32.47009 -113.4364)
		(stroke
			(width 0.05715)
			(type default)
		)
		(layer "B.Cu")
	)
	(gr_line
		(start 32.52597 -112.38103)
		(end 32.537908 -112.385856)
		(stroke
			(width 0.05715)
			(type default)
		)
		(layer "B.Cu")
	)
	(gr_line
		(start 32.783272 -111.413036)
		(end 32.795718 -111.418116)
		(stroke
			(width 0.05715)
			(type default)
		)
		(layer "B.Cu")
	)
	(gr_line
		(start 33.05048 -110.447074)
		(end 33.062926 -110.452154)
		(stroke
			(width 0.05715)
			(type default)
		)
		(layer "B.Cu")
	)
	(gr_line
		(start 60.17006 -120.004078)
		(end 60.171838 -120.003824)
		(stroke
			(width 0.05715)
			(type default)
		)
		(layer "B.Cu")
	)
	(gr_line
		(start 60.171838 -120.003824)
		(end 60.173362 -120.004332)
		(stroke
			(width 0.05715)
			(type default)
		)
		(layer "B.Cu")
	)
	(gr_line
		(start 60.274962 -121.030746)
		(end 60.27674 -121.030492)
		(stroke
			(width 0.05715)
			(type default)
		)
		(layer "B.Cu")
	)
	(gr_line
		(start 60.27674 -121.030492)
		(end 60.278264 -121.031)
		(stroke
			(width 0.05715)
			(type default)
		)
		(layer "B.Cu")
	)
	(gr_line
		(start 60.37961 -122.0724)
		(end 60.381388 -122.072146)
		(stroke
			(width 0.05715)
			(type default)
		)
		(layer "B.Cu")
	)
	(gr_line
		(start 60.381388 -123.124722)
		(end 60.383166 -123.124468)
		(stroke
			(width 0.05715)
			(type default)
		)
		(layer "B.Cu")
	)
	(gr_line
		(start 60.381388 -122.072146)
		(end 60.382912 -122.072654)
		(stroke
			(width 0.05715)
			(type default)
		)
		(layer "B.Cu")
	)
	(gr_line
		(start 60.383166 -123.124468)
		(end 60.38469 -123.124976)
		(stroke
			(width 0.05715)
			(type default)
		)
		(layer "B.Cu")
	)
	(gr_line
		(start 60.41009 -118.927118)
		(end 60.411868 -118.926864)
		(stroke
			(width 0.05715)
			(type default)
		)
		(layer "B.Cu")
	)
	(gr_line
		(start 60.411868 -118.926864)
		(end 60.413392 -118.927372)
		(stroke
			(width 0.05715)
			(type default)
		)
		(layer "B.Cu")
	)
	(gr_line
		(start 60.742322 -117.920008)
		(end 60.7441 -117.919754)
		(stroke
			(width 0.05715)
			(type default)
		)
		(layer "B.Cu")
	)
	(gr_line
		(start 60.7441 -117.919754)
		(end 60.745624 -117.920262)
		(stroke
			(width 0.05715)
			(type default)
		)
		(layer "B.Cu")
	)
	(gr_line
		(start 63.828422 -118.782846)
		(end 63.84163 -118.785386)
		(stroke
			(width 0.05715)
			(type default)
		)
		(layer "B.Cu")
	)
	(gr_line
		(start 63.84163 -118.785386)
		(end 63.854838 -118.782846)
		(stroke
			(width 0.05715)
			(type default)
		)
		(layer "B.Cu")
	)
	(gr_line
		(start 64.03721 -116.99748)
		(end 64.04991 -117.061488)
		(stroke
			(width 0.05715)
			(type default)
		)
		(layer "B.Cu")
	)
	(gr_line
		(start 64.03721 -116.99748)
		(end 64.073786 -116.942616)
		(stroke
			(width 0.05715)
			(type default)
		)
		(layer "B.Cu")
	)
	(gr_line
		(start 64.073532 -116.94287)
		(end 64.073786 -116.942362)
		(stroke
			(width 0.05715)
			(type default)
		)
		(layer "B.Cu")
	)
	(gr_line
		(start 64.185546 -119.928132)
		(end 64.198754 -119.930672)
		(stroke
			(width 0.05715)
			(type default)
		)
		(layer "B.Cu")
	)
	(gr_line
		(start 64.198754 -119.930672)
		(end 64.211962 -119.928132)
		(stroke
			(width 0.05715)
			(type default)
		)
		(layer "B.Cu")
	)
	(gr_line
		(start 64.200532 -116.752624)
		(end 64.237616 -116.696998)
		(stroke
			(width 0.05715)
			(type default)
		)
		(layer "B.Cu")
	)
	(gr_line
		(start 64.237616 -116.696998)
		(end 64.302386 -116.684044)
		(stroke
			(width 0.05715)
			(type default)
		)
		(layer "B.Cu")
	)
	(gr_line
		(start 64.295274 -118.694708)
		(end 64.360044 -118.681754)
		(stroke
			(width 0.05715)
			(type default)
		)
		(layer "B.Cu")
	)
	(gr_line
		(start 64.297052 -121.075196)
		(end 64.31026 -121.077736)
		(stroke
			(width 0.05715)
			(type default)
		)
		(layer "B.Cu")
	)
	(gr_line
		(start 64.31026 -121.077736)
		(end 64.323468 -121.075196)
		(stroke
			(width 0.05715)
			(type default)
		)
		(layer "B.Cu")
	)
	(gr_line
		(start 64.360044 -118.681754)
		(end 64.39662 -118.626636)
		(stroke
			(width 0.05715)
			(type default)
		)
		(layer "B.Cu")
	)
	(gr_line
		(start 64.524128 -118.435628)
		(end 64.56045 -118.381018)
		(stroke
			(width 0.05715)
			(type default)
		)
		(layer "B.Cu")
	)
	(gr_line
		(start 64.547496 -118.316248)
		(end 64.54775 -118.31701)
		(stroke
			(width 0.05715)
			(type default)
		)
		(layer "B.Cu")
	)
	(gr_line
		(start 64.54775 -118.316756)
		(end 64.56045 -118.381018)
		(stroke
			(width 0.05715)
			(type default)
		)
		(layer "B.Cu")
	)
	(gr_line
		(start 64.644016 -124.222764)
		(end 64.657224 -124.225304)
		(stroke
			(width 0.05715)
			(type default)
		)
		(layer "B.Cu")
	)
	(gr_line
		(start 64.657224 -124.225304)
		(end 64.670432 -124.222764)
		(stroke
			(width 0.05715)
			(type default)
		)
		(layer "B.Cu")
	)
	(gr_line
		(start 64.703452 -122.162316)
		(end 64.71666 -122.164856)
		(stroke
			(width 0.05715)
			(type default)
		)
		(layer "B.Cu")
	)
	(gr_line
		(start 64.71666 -122.164856)
		(end 64.729868 -122.162316)
		(stroke
			(width 0.05715)
			(type default)
		)
		(layer "B.Cu")
	)
	(gr_line
		(start 64.74079 -123.190254)
		(end 64.753998 -123.192794)
		(stroke
			(width 0.05715)
			(type default)
		)
		(layer "B.Cu")
	)
	(gr_line
		(start 64.753998 -123.192794)
		(end 64.767206 -123.190254)
		(stroke
			(width 0.05715)
			(type default)
		)
		(layer "B.Cu")
	)
	(gr_line
		(start 65.054734 -117.675914)
		(end 65.067942 -117.741954)
		(stroke
			(width 0.05715)
			(type default)
		)
		(layer "B.Cu")
	)
	(gr_line
		(start 65.054734 -117.675914)
		(end 65.091818 -117.620288)
		(stroke
			(width 0.05715)
			(type default)
		)
		(layer "B.Cu")
	)
	(gr_line
		(start 65.158366 -118.193312)
		(end 65.171574 -118.25859)
		(stroke
			(width 0.05715)
			(type default)
		)
		(layer "B.Cu")
	)
	(gr_line
		(start 65.171574 -118.25859)
		(end 65.226692 -118.295166)
		(stroke
			(width 0.05715)
			(type default)
		)
		(layer "B.Cu")
	)
	(gr_line
		(start 65.219072 -117.429788)
		(end 65.255648 -117.375178)
		(stroke
			(width 0.05715)
			(type default)
		)
		(layer "B.Cu")
	)
	(gr_line
		(start 65.255648 -117.375178)
		(end 65.320164 -117.362224)
		(stroke
			(width 0.05715)
			(type default)
		)
		(layer "B.Cu")
	)
	(gr_line
		(start 65.4177 -118.422674)
		(end 65.47231 -118.458996)
		(stroke
			(width 0.05715)
			(type default)
		)
		(layer "B.Cu")
	)
	(gr_line
		(start 65.47231 -118.458996)
		(end 65.536318 -118.446296)
		(stroke
			(width 0.05715)
			(type default)
		)
		(layer "B.Cu")
	)
	(gr_line
		(start 69.14515 -115.715288)
		(end 69.209158 -115.702588)
		(stroke
			(width 0.05715)
			(type default)
		)
		(layer "B.Cu")
	)
	(gr_line
		(start 69.209158 -115.702588)
		(end 69.263768 -115.73891)
		(stroke
			(width 0.05715)
			(type default)
		)
		(layer "B.Cu")
	)
	(gr_line
		(start 69.361558 -116.800376)
		(end 69.426328 -116.787422)
		(stroke
			(width 0.05715)
			(type default)
		)
		(layer "B.Cu")
	)
	(gr_line
		(start 69.449442 -114.45621)
		(end 69.462396 -114.45367)
		(stroke
			(width 0.05715)
			(type default)
		)
		(layer "B.Cu")
	)
	(gr_line
		(start 69.454014 -115.86591)
		(end 69.50964 -115.902994)
		(stroke
			(width 0.05715)
			(type default)
		)
		(layer "B.Cu")
	)
	(gr_line
		(start 69.462396 -114.45367)
		(end 69.47535 -114.45621)
		(stroke
			(width 0.05715)
			(type default)
		)
		(layer "B.Cu")
	)
	(gr_line
		(start 69.50964 -115.902994)
		(end 69.522848 -115.968272)
		(stroke
			(width 0.05715)
			(type default)
		)
		(layer "B.Cu")
	)
	(gr_line
		(start 69.613526 -116.421916)
		(end 69.626734 -116.48694)
		(stroke
			(width 0.05715)
			(type default)
		)
		(layer "B.Cu")
	)
	(gr_line
		(start 69.800978 -113.399062)
		(end 69.813932 -113.396522)
		(stroke
			(width 0.05715)
			(type default)
		)
		(layer "B.Cu")
	)
	(gr_line
		(start 69.813932 -113.396522)
		(end 69.826886 -113.399062)
		(stroke
			(width 0.05715)
			(type default)
		)
		(layer "B.Cu")
	)
	(gr_line
		(start 70.589648 -112.102646)
		(end 70.602856 -112.100106)
		(stroke
			(width 0.05715)
			(type default)
		)
		(layer "B.Cu")
	)
	(gr_line
		(start 70.602856 -112.100106)
		(end 70.616064 -112.102646)
		(stroke
			(width 0.05715)
			(type default)
		)
		(layer "B.Cu")
	)
	(gr_line
		(start 73.692004 -116.568982)
		(end 73.705212 -116.566442)
		(stroke
			(width 0.05715)
			(type default)
		)
		(layer "B.Cu")
	)
	(gr_line
		(start 73.705212 -116.566442)
		(end 73.71842 -116.568982)
		(stroke
			(width 0.05715)
			(type default)
		)
		(layer "B.Cu")
	)
	(gr_line
		(start 73.859644 -122.138948)
		(end 73.872852 -122.136408)
		(stroke
			(width 0.05715)
			(type default)
		)
		(layer "B.Cu")
	)
	(gr_line
		(start 73.872852 -122.136408)
		(end 73.88606 -122.138948)
		(stroke
			(width 0.05715)
			(type default)
		)
		(layer "B.Cu")
	)
	(gr_line
		(start 73.91273 -121.115074)
		(end 73.925938 -121.112534)
		(stroke
			(width 0.05715)
			(type default)
		)
		(layer "B.Cu")
	)
	(gr_line
		(start 73.925938 -121.112534)
		(end 73.939146 -121.115074)
		(stroke
			(width 0.05715)
			(type default)
		)
		(layer "B.Cu")
	)
	(gr_line
		(start 73.943718 -117.73535)
		(end 73.956926 -117.73281)
		(stroke
			(width 0.05715)
			(type default)
		)
		(layer "B.Cu")
	)
	(gr_line
		(start 73.956926 -117.73281)
		(end 73.970134 -117.73535)
		(stroke
			(width 0.05715)
			(type default)
		)
		(layer "B.Cu")
	)
	(gr_line
		(start 73.979024 -118.897908)
		(end 73.992232 -118.895368)
		(stroke
			(width 0.05715)
			(type default)
		)
		(layer "B.Cu")
	)
	(gr_line
		(start 73.992232 -118.895368)
		(end 74.00544 -118.897908)
		(stroke
			(width 0.05715)
			(type default)
		)
		(layer "B.Cu")
	)
	(gr_line
		(start 74.020426 -120.057672)
		(end 74.033634 -120.055132)
		(stroke
			(width 0.05715)
			(type default)
		)
		(layer "B.Cu")
	)
	(gr_line
		(start 74.033634 -120.055132)
		(end 74.046842 -120.057672)
		(stroke
			(width 0.05715)
			(type default)
		)
		(layer "B.Cu")
	)
	(gr_line
		(start 81.513426 -115.982496)
		(end 81.526634 -115.985036)
		(stroke
			(width 0.05715)
			(type default)
		)
		(layer "B.Cu")
	)
	(gr_line
		(start 81.526634 -115.985036)
		(end 81.539842 -115.982496)
		(stroke
			(width 0.05715)
			(type default)
		)
		(layer "B.Cu")
	)
	(gr_line
		(start 81.86039 -117.179852)
		(end 81.873598 -117.182392)
		(stroke
			(width 0.05715)
			(type default)
		)
		(layer "B.Cu")
	)
	(gr_line
		(start 81.873598 -117.182392)
		(end 81.886806 -117.179852)
		(stroke
			(width 0.05715)
			(type default)
		)
		(layer "B.Cu")
	)
	(gr_line
		(start 82.067146 -122.9868)
		(end 82.080354 -122.98934)
		(stroke
			(width 0.05715)
			(type default)
		)
		(layer "B.Cu")
	)
	(gr_line
		(start 82.080354 -122.98934)
		(end 82.093562 -122.9868)
		(stroke
			(width 0.05715)
			(type default)
		)
		(layer "B.Cu")
	)
	(gr_line
		(start 82.142584 -121.923048)
		(end 82.155792 -121.925588)
		(stroke
			(width 0.05715)
			(type default)
		)
		(layer "B.Cu")
	)
	(gr_line
		(start 82.155792 -121.925588)
		(end 82.169 -121.923048)
		(stroke
			(width 0.05715)
			(type default)
		)
		(layer "B.Cu")
	)
	(gr_line
		(start 82.235802 -124.055378)
		(end 82.24901 -124.057918)
		(stroke
			(width 0.05715)
			(type default)
		)
		(layer "B.Cu")
	)
	(gr_line
		(start 82.24012 -118.519702)
		(end 82.253328 -118.522242)
		(stroke
			(width 0.05715)
			(type default)
		)
		(layer "B.Cu")
	)
	(gr_line
		(start 82.24901 -124.057918)
		(end 82.262218 -124.055378)
		(stroke
			(width 0.05715)
			(type default)
		)
		(layer "B.Cu")
	)
	(gr_line
		(start 82.253328 -118.522242)
		(end 82.266536 -118.519702)
		(stroke
			(width 0.05715)
			(type default)
		)
		(layer "B.Cu")
	)
	(gr_line
		(start 82.320638 -114.690398)
		(end 82.333846 -114.692938)
		(stroke
			(width 0.05715)
			(type default)
		)
		(layer "B.Cu")
	)
	(gr_line
		(start 82.333846 -114.692938)
		(end 82.347054 -114.690398)
		(stroke
			(width 0.05715)
			(type default)
		)
		(layer "B.Cu")
	)
	(gr_line
		(start 82.52841 -120.848882)
		(end 82.541618 -120.851422)
		(stroke
			(width 0.05715)
			(type default)
		)
		(layer "B.Cu")
	)
	(gr_line
		(start 82.541618 -120.851422)
		(end 82.554826 -120.848882)
		(stroke
			(width 0.05715)
			(type default)
		)
		(layer "B.Cu")
	)
	(gr_line
		(start 82.909664 -119.769636)
		(end 82.922872 -119.772176)
		(stroke
			(width 0.05715)
			(type default)
		)
		(layer "B.Cu")
	)
	(gr_line
		(start 82.922872 -119.772176)
		(end 82.93608 -119.769636)
		(stroke
			(width 0.05715)
			(type default)
		)
		(layer "B.Cu")
	)
	(gr_line
		(start 83.429094 -108.475018)
		(end 83.442302 -108.472478)
		(stroke
			(width 0.05715)
			(type default)
		)
		(layer "B.Cu")
	)
	(gr_line
		(start 83.442302 -108.472478)
		(end 83.45551 -108.475018)
		(stroke
			(width 0.05715)
			(type default)
		)
		(layer "B.Cu")
	)
	(gr_line
		(start 83.574128 -106.41711)
		(end 83.587336 -106.41457)
		(stroke
			(width 0.05715)
			(type default)
		)
		(layer "B.Cu")
	)
	(gr_line
		(start 83.587336 -106.41457)
		(end 83.600544 -106.41711)
		(stroke
			(width 0.05715)
			(type default)
		)
		(layer "B.Cu")
	)
	(gr_line
		(start 83.625436 -107.429808)
		(end 83.638644 -107.427268)
		(stroke
			(width 0.05715)
			(type default)
		)
		(layer "B.Cu")
	)
	(gr_line
		(start 83.638644 -107.427268)
		(end 83.651852 -107.429808)
		(stroke
			(width 0.05715)
			(type default)
		)
		(layer "B.Cu")
	)
	(gr_line
		(start 83.787996 -105.367836)
		(end 83.801204 -105.365296)
		(stroke
			(width 0.05715)
			(type default)
		)
		(layer "B.Cu")
	)
	(gr_line
		(start 83.801204 -105.365296)
		(end 83.814412 -105.367836)
		(stroke
			(width 0.05715)
			(type default)
		)
		(layer "B.Cu")
	)
	(gr_line
		(start 83.867244 -104.360472)
		(end 83.880452 -104.357932)
		(stroke
			(width 0.05715)
			(type default)
		)
		(layer "B.Cu")
	)
	(gr_line
		(start 83.874864 -103.362506)
		(end 83.888072 -103.359966)
		(stroke
			(width 0.05715)
			(type default)
		)
		(layer "B.Cu")
	)
	(gr_line
		(start 83.880452 -104.357932)
		(end 83.89366 -104.360472)
		(stroke
			(width 0.05715)
			(type default)
		)
		(layer "B.Cu")
	)
	(gr_line
		(start 83.888072 -103.359966)
		(end 83.90128 -103.362506)
		(stroke
			(width 0.05715)
			(type default)
		)
		(layer "B.Cu")
	)
	(gr_line
		(start 83.978242 -102.333806)
		(end 83.99145 -102.331266)
		(stroke
			(width 0.05715)
			(type default)
		)
		(layer "B.Cu")
	)
	(gr_line
		(start 83.99145 -102.331266)
		(end 84.004658 -102.333806)
		(stroke
			(width 0.05715)
			(type default)
		)
		(layer "B.Cu")
	)
	(gr_line
		(start 85.18652 -108.821474)
		(end 85.198966 -108.82376)
		(stroke
			(width 0.05715)
			(type default)
		)
		(layer "B.Cu")
	)
	(gr_line
		(start 85.198966 -108.82376)
		(end 85.210142 -108.831126)
		(stroke
			(width 0.05715)
			(type default)
		)
		(layer "B.Cu")
	)
	(gr_line
		(start 85.547708 -125.99162)
		(end 86.436708 -125.99162)
		(stroke
			(width 0.0635)
			(type default)
		)
		(layer "B.Cu")
	)
	(gr_line
		(start 86.020656 -107.903518)
		(end 86.033102 -107.905804)
		(stroke
			(width 0.05715)
			(type default)
		)
		(layer "B.Cu")
	)
	(gr_line
		(start 86.436708 -125.815852)
		(end 86.436708 -125.99162)
		(stroke
			(width 0.0635)
			(type default)
		)
		(layer "B.Cu")
	)
	(gr_line
		(start 86.436708 -125.815852)
		(end 86.754208 -125.498352)
		(stroke
			(width 0.0635)
			(type default)
		)
		(layer "B.Cu")
	)
	(gr_line
		(start 86.663276 -107.030012)
		(end 86.675722 -107.032298)
		(stroke
			(width 0.05715)
			(type default)
		)
		(layer "B.Cu")
	)
	(gr_line
		(start 86.675722 -107.032298)
		(end 86.686898 -107.039664)
		(stroke
			(width 0.05715)
			(type default)
		)
		(layer "B.Cu")
	)
	(gr_line
		(start 86.754208 -125.026166)
		(end 86.754208 -125.498352)
		(stroke
			(width 0.0635)
			(type default)
		)
		(layer "B.Cu")
	)
	(gr_line
		(start 86.754208 -125.026166)
		(end 87.035894 -124.74448)
		(stroke
			(width 0.0635)
			(type default)
		)
		(layer "B.Cu")
	)
	(gr_line
		(start 87.046816 -125.553216)
		(end 87.325708 -125.832108)
		(stroke
			(width 0.0635)
			(type default)
		)
		(layer "B.Cu")
	)
	(gr_line
		(start 87.046816 -125.12548)
		(end 87.046816 -125.553216)
		(stroke
			(width 0.0635)
			(type default)
		)
		(layer "B.Cu")
	)
	(gr_line
		(start 87.046816 -125.12548)
		(end 87.171276 -125.00102)
		(stroke
			(width 0.0635)
			(type default)
		)
		(layer "B.Cu")
	)
	(gr_line
		(start 87.088472 -106.02341)
		(end 87.100918 -106.025696)
		(stroke
			(width 0.05715)
			(type default)
		)
		(layer "B.Cu")
	)
	(gr_line
		(start 87.100918 -106.025696)
		(end 87.112094 -106.033062)
		(stroke
			(width 0.05715)
			(type default)
		)
		(layer "B.Cu")
	)
	(gr_line
		(start 87.325708 -125.99162)
		(end 88.214708 -125.99162)
		(stroke
			(width 0.0635)
			(type default)
		)
		(layer "B.Cu")
	)
	(gr_line
		(start 87.325708 -125.832108)
		(end 87.325708 -125.99162)
		(stroke
			(width 0.0635)
			(type default)
		)
		(layer "B.Cu")
	)
	(gr_line
		(start 87.399876 -110.58144)
		(end 87.411052 -110.588806)
		(stroke
			(width 0.05715)
			(type default)
		)
		(layer "B.Cu")
	)
	(gr_line
		(start 87.411052 -110.588806)
		(end 87.423498 -110.591092)
		(stroke
			(width 0.05715)
			(type default)
		)
		(layer "B.Cu")
	)
	(gr_line
		(start 87.72652 -105.129076)
		(end 87.738966 -105.131362)
		(stroke
			(width 0.05715)
			(type default)
		)
		(layer "B.Cu")
	)
	(gr_line
		(start 87.738966 -105.131362)
		(end 87.750142 -105.138728)
		(stroke
			(width 0.05715)
			(type default)
		)
		(layer "B.Cu")
	)
	(gr_line
		(start 87.936324 -109.464856)
		(end 87.9475 -109.472222)
		(stroke
			(width 0.05715)
			(type default)
		)
		(layer "B.Cu")
	)
	(gr_line
		(start 87.9475 -109.472222)
		(end 87.959946 -109.474508)
		(stroke
			(width 0.05715)
			(type default)
		)
		(layer "B.Cu")
	)
	(gr_line
		(start 88.43518 -108.495592)
		(end 88.446356 -108.502958)
		(stroke
			(width 0.05715)
			(type default)
		)
		(layer "B.Cu")
	)
	(gr_line
		(start 88.500712 -104.28224)
		(end 88.513158 -104.284526)
		(stroke
			(width 0.05715)
			(type default)
		)
		(layer "B.Cu")
	)
	(gr_line
		(start 88.513158 -104.284526)
		(end 88.524334 -104.291892)
		(stroke
			(width 0.05715)
			(type default)
		)
		(layer "B.Cu")
	)
	(gr_line
		(start 88.77808 -107.434634)
		(end 88.789256 -107.442)
		(stroke
			(width 0.05715)
			(type default)
		)
		(layer "B.Cu")
	)
	(gr_line
		(start 88.789256 -107.442)
		(end 88.801702 -107.444286)
		(stroke
			(width 0.05715)
			(type default)
		)
		(layer "B.Cu")
	)
	(gr_line
		(start 88.93683 -110.8964)
		(end 89.02446 -111.028226)
		(stroke
			(width 0.05715)
			(type default)
		)
		(layer "B.Cu")
	)
	(gr_line
		(start 89.01557 -110.663482)
		(end 89.508076 -110.762034)
		(stroke
			(width 0.05715)
			(type default)
		)
		(layer "B.Cu")
	)
	(gr_line
		(start 89.01557 -103.33609)
		(end 89.028016 -103.338376)
		(stroke
			(width 0.05715)
			(type default)
		)
		(layer "B.Cu")
	)
	(gr_line
		(start 89.02446 -111.028226)
		(end 89.360756 -111.095282)
		(stroke
			(width 0.05715)
			(type default)
		)
		(layer "B.Cu")
	)
	(gr_line
		(start 89.028016 -103.338376)
		(end 89.039192 -103.345742)
		(stroke
			(width 0.05715)
			(type default)
		)
		(layer "B.Cu")
	)
	(gr_line
		(start 89.093548 -106.324908)
		(end 89.104724 -106.332274)
		(stroke
			(width 0.05715)
			(type default)
		)
		(layer "B.Cu")
	)
	(gr_line
		(start 89.104724 -106.332274)
		(end 89.11717 -106.33456)
		(stroke
			(width 0.05715)
			(type default)
		)
		(layer "B.Cu")
	)
	(gr_line
		(start 89.360756 -111.095282)
		(end 89.492074 -111.007652)
		(stroke
			(width 0.05715)
			(type default)
		)
		(layer "B.Cu")
	)
	(gr_line
		(start 89.83345 -111.075724)
		(end 89.92108 -111.20755)
		(stroke
			(width 0.05715)
			(type default)
		)
		(layer "B.Cu")
	)
	(gr_line
		(start 89.902538 -105.501186)
		(end 89.913714 -105.508552)
		(stroke
			(width 0.05715)
			(type default)
		)
		(layer "B.Cu")
	)
	(gr_line
		(start 89.91219 -110.842806)
		(end 90.404696 -110.941358)
		(stroke
			(width 0.05715)
			(type default)
		)
		(layer "B.Cu")
	)
	(gr_line
		(start 89.913714 -105.508552)
		(end 89.92616 -105.510838)
		(stroke
			(width 0.05715)
			(type default)
		)
		(layer "B.Cu")
	)
	(gr_line
		(start 89.92108 -111.20755)
		(end 90.257376 -111.274606)
		(stroke
			(width 0.05715)
			(type default)
		)
		(layer "B.Cu")
	)
	(gr_line
		(start 90.242644 -121.110756)
		(end 90.255852 -121.113296)
		(stroke
			(width 0.05715)
			(type default)
		)
		(layer "B.Cu")
	)
	(gr_line
		(start 90.257376 -111.274606)
		(end 90.388694 -111.186976)
		(stroke
			(width 0.05715)
			(type default)
		)
		(layer "B.Cu")
	)
	(gr_line
		(start 90.352626 -120.040146)
		(end 90.365834 -120.037606)
		(stroke
			(width 0.05715)
			(type default)
		)
		(layer "B.Cu")
	)
	(gr_line
		(start 90.365834 -120.037606)
		(end 90.379042 -120.040146)
		(stroke
			(width 0.05715)
			(type default)
		)
		(layer "B.Cu")
	)
	(gr_line
		(start 90.419174 -122.177556)
		(end 90.432382 -122.175016)
		(stroke
			(width 0.05715)
			(type default)
		)
		(layer "B.Cu")
	)
	(gr_line
		(start 90.432382 -122.175016)
		(end 90.44559 -122.177556)
		(stroke
			(width 0.05715)
			(type default)
		)
		(layer "B.Cu")
	)
	(gr_line
		(start 90.47353 -104.59212)
		(end 90.484706 -104.599486)
		(stroke
			(width 0.05715)
			(type default)
		)
		(layer "B.Cu")
	)
	(gr_line
		(start 90.484706 -104.599486)
		(end 90.497152 -104.601772)
		(stroke
			(width 0.05715)
			(type default)
		)
		(layer "B.Cu")
	)
	(gr_line
		(start 90.584274 -113.927128)
		(end 90.597482 -113.924588)
		(stroke
			(width 0.05715)
			(type default)
		)
		(layer "B.Cu")
	)
	(gr_line
		(start 90.597482 -113.924588)
		(end 90.61069 -113.927128)
		(stroke
			(width 0.05715)
			(type default)
		)
		(layer "B.Cu")
	)
	(gr_line
		(start 90.791792 -116.568474)
		(end 90.805 -116.565934)
		(stroke
			(width 0.05715)
			(type default)
		)
		(layer "B.Cu")
	)
	(gr_line
		(start 90.805 -116.565934)
		(end 90.818208 -116.568474)
		(stroke
			(width 0.05715)
			(type default)
		)
		(layer "B.Cu")
	)
	(gr_line
		(start 90.858086 -118.94185)
		(end 90.871294 -118.93931)
		(stroke
			(width 0.05715)
			(type default)
		)
		(layer "B.Cu")
	)
	(gr_line
		(start 90.871294 -118.93931)
		(end 90.884502 -118.94185)
		(stroke
			(width 0.05715)
			(type default)
		)
		(layer "B.Cu")
	)
	(gr_line
		(start 90.883486 -115.134136)
		(end 90.896694 -115.131596)
		(stroke
			(width 0.05715)
			(type default)
		)
		(layer "B.Cu")
	)
	(gr_line
		(start 90.896694 -115.131596)
		(end 90.909902 -115.134136)
		(stroke
			(width 0.05715)
			(type default)
		)
		(layer "B.Cu")
	)
	(gr_line
		(start 91.237816 -117.863112)
		(end 91.251024 -117.860572)
		(stroke
			(width 0.05715)
			(type default)
		)
		(layer "B.Cu")
	)
	(gr_line
		(start 91.251024 -117.860572)
		(end 91.264232 -117.863112)
		(stroke
			(width 0.05715)
			(type default)
		)
		(layer "B.Cu")
	)
	(gr_line
		(start 91.404186 -112.63249)
		(end 91.417394 -112.62995)
		(stroke
			(width 0.05715)
			(type default)
		)
		(layer "B.Cu")
	)
	(gr_line
		(start 91.416378 -107.967272)
		(end 91.907106 -108.065316)
		(stroke
			(width 0.05715)
			(type default)
		)
		(layer "B.Cu")
	)
	(gr_line
		(start 91.417394 -112.62995)
		(end 91.430602 -112.63249)
		(stroke
			(width 0.05715)
			(type default)
		)
		(layer "B.Cu")
	)
	(gr_line
		(start 91.431618 -107.721654)
		(end 91.56319 -107.634024)
		(stroke
			(width 0.05715)
			(type default)
		)
		(layer "B.Cu")
	)
	(gr_line
		(start 91.56319 -107.634024)
		(end 91.899232 -107.701334)
		(stroke
			(width 0.05715)
			(type default)
		)
		(layer "B.Cu")
	)
	(gr_line
		(start 91.899232 -107.701334)
		(end 91.986862 -107.832906)
		(stroke
			(width 0.05715)
			(type default)
		)
		(layer "B.Cu")
	)
	(gr_line
		(start 92.311982 -108.146596)
		(end 92.80398 -108.244894)
		(stroke
			(width 0.05715)
			(type default)
		)
		(layer "B.Cu")
	)
	(gr_line
		(start 92.328238 -107.900978)
		(end 92.45981 -107.813348)
		(stroke
			(width 0.05715)
			(type default)
		)
		(layer "B.Cu")
	)
	(gr_line
		(start 92.45981 -107.813348)
		(end 92.795852 -107.880658)
		(stroke
			(width 0.05715)
			(type default)
		)
		(layer "B.Cu")
	)
	(gr_line
		(start 92.795852 -107.880658)
		(end 92.883482 -108.011976)
		(stroke
			(width 0.05715)
			(type default)
		)
		(layer "B.Cu")
	)
	(gr_line
		(start 96.350074 -113.862612)
		(end 96.363282 -113.865152)
		(stroke
			(width 0.05715)
			(type default)
		)
		(layer "B.Cu")
	)
	(gr_line
		(start 96.363282 -113.865152)
		(end 96.37649 -113.862612)
		(stroke
			(width 0.05715)
			(type default)
		)
		(layer "B.Cu")
	)
	(gr_line
		(start 96.918272 -123.71832)
		(end 96.93148 -123.72086)
		(stroke
			(width 0.05715)
			(type default)
		)
		(layer "B.Cu")
	)
	(gr_line
		(start 96.93148 -123.72086)
		(end 96.944688 -123.71832)
		(stroke
			(width 0.05715)
			(type default)
		)
		(layer "B.Cu")
	)
	(gr_line
		(start 96.962214 -122.700796)
		(end 96.975422 -122.698256)
		(stroke
			(width 0.05715)
			(type default)
		)
		(layer "B.Cu")
	)
	(gr_line
		(start 97.129092 -121.636536)
		(end 97.1423 -121.639076)
		(stroke
			(width 0.05715)
			(type default)
		)
		(layer "B.Cu")
	)
	(gr_line
		(start 97.1423 -121.639076)
		(end 97.155508 -121.636536)
		(stroke
			(width 0.05715)
			(type default)
		)
		(layer "B.Cu")
	)
	(gr_line
		(start 97.195894 -105.941622)
		(end 97.209102 -105.944162)
		(stroke
			(width 0.05715)
			(type default)
		)
		(layer "B.Cu")
	)
	(gr_line
		(start 97.209102 -105.944162)
		(end 97.22231 -105.941622)
		(stroke
			(width 0.05715)
			(type default)
		)
		(layer "B.Cu")
	)
	(gr_line
		(start 97.22104 -112.55121)
		(end 97.234248 -112.55375)
		(stroke
			(width 0.05715)
			(type default)
		)
		(layer "B.Cu")
	)
	(gr_line
		(start 97.258632 -110.265464)
		(end 97.27184 -110.268004)
		(stroke
			(width 0.05715)
			(type default)
		)
		(layer "B.Cu")
	)
	(gr_line
		(start 97.268538 -106.979212)
		(end 97.281746 -106.981752)
		(stroke
			(width 0.05715)
			(type default)
		)
		(layer "B.Cu")
	)
	(gr_line
		(start 97.27184 -110.268004)
		(end 97.285048 -110.265464)
		(stroke
			(width 0.05715)
			(type default)
		)
		(layer "B.Cu")
	)
	(gr_line
		(start 97.281746 -106.981752)
		(end 97.294954 -106.979212)
		(stroke
			(width 0.05715)
			(type default)
		)
		(layer "B.Cu")
	)
	(gr_line
		(start 97.308924 -109.145832)
		(end 97.322132 -109.148372)
		(stroke
			(width 0.05715)
			(type default)
		)
		(layer "B.Cu")
	)
	(gr_line
		(start 97.322132 -109.148372)
		(end 97.33534 -109.145832)
		(stroke
			(width 0.05715)
			(type default)
		)
		(layer "B.Cu")
	)
	(gr_line
		(start 97.373186 -111.357156)
		(end 97.386394 -111.359696)
		(stroke
			(width 0.05715)
			(type default)
		)
		(layer "B.Cu")
	)
	(gr_line
		(start 97.41662 -120.494552)
		(end 97.429828 -120.497092)
		(stroke
			(width 0.05715)
			(type default)
		)
		(layer "B.Cu")
	)
	(gr_line
		(start 97.429828 -120.497092)
		(end 97.443036 -120.494552)
		(stroke
			(width 0.05715)
			(type default)
		)
		(layer "B.Cu")
	)
	(gr_line
		(start 97.432114 -119.342916)
		(end 97.445322 -119.345456)
		(stroke
			(width 0.05715)
			(type default)
		)
		(layer "B.Cu")
	)
	(gr_line
		(start 97.445322 -119.345456)
		(end 97.45853 -119.342916)
		(stroke
			(width 0.05715)
			(type default)
		)
		(layer "B.Cu")
	)
	(gr_line
		(start 97.55886 -118.162832)
		(end 97.572068 -118.165372)
		(stroke
			(width 0.05715)
			(type default)
		)
		(layer "B.Cu")
	)
	(gr_line
		(start 97.572068 -118.165372)
		(end 97.585276 -118.162832)
		(stroke
			(width 0.05715)
			(type default)
		)
		(layer "B.Cu")
	)
	(gr_line
		(start 97.771712 -108.065316)
		(end 97.78492 -108.067856)
		(stroke
			(width 0.05715)
			(type default)
		)
		(layer "B.Cu")
	)
	(gr_line
		(start 97.78492 -108.067856)
		(end 97.798128 -108.065316)
		(stroke
			(width 0.05715)
			(type default)
		)
		(layer "B.Cu")
	)
	(gr_line
		(start 97.864676 -105.564432)
		(end 97.95256 -105.432606)
		(stroke
			(width 0.05715)
			(type default)
		)
		(layer "B.Cu")
	)
	(gr_line
		(start 97.94367 -105.79735)
		(end 98.436684 -105.698798)
		(stroke
			(width 0.05715)
			(type default)
		)
		(layer "B.Cu")
	)
	(gr_line
		(start 97.95256 -105.432606)
		(end 98.288856 -105.36555)
		(stroke
			(width 0.05715)
			(type default)
		)
		(layer "B.Cu")
	)
	(gr_line
		(start 98.007424 -116.799868)
		(end 98.020632 -116.802408)
		(stroke
			(width 0.05715)
			(type default)
		)
		(layer "B.Cu")
	)
	(gr_line
		(start 98.020632 -116.802408)
		(end 98.03384 -116.799868)
		(stroke
			(width 0.05715)
			(type default)
		)
		(layer "B.Cu")
	)
	(gr_line
		(start 98.28149 -115.707414)
		(end 98.294698 -115.709954)
		(stroke
			(width 0.05715)
			(type default)
		)
		(layer "B.Cu")
	)
	(gr_line
		(start 98.288856 -105.36555)
		(end 98.420428 -105.45318)
		(stroke
			(width 0.05715)
			(type default)
		)
		(layer "B.Cu")
	)
	(gr_line
		(start 98.294698 -115.709954)
		(end 98.307906 -115.707414)
		(stroke
			(width 0.05715)
			(type default)
		)
		(layer "B.Cu")
	)
	(gr_line
		(start 98.761296 -105.385108)
		(end 98.84918 -105.253536)
		(stroke
			(width 0.05715)
			(type default)
		)
		(layer "B.Cu")
	)
	(gr_line
		(start 98.840544 -105.617772)
		(end 99.333304 -105.519474)
		(stroke
			(width 0.05715)
			(type default)
		)
		(layer "B.Cu")
	)
	(gr_line
		(start 98.84918 -105.253536)
		(end 99.185476 -105.186226)
		(stroke
			(width 0.05715)
			(type default)
		)
		(layer "B.Cu")
	)
	(gr_line
		(start 99.185476 -105.186226)
		(end 99.317048 -105.273856)
		(stroke
			(width 0.05715)
			(type default)
		)
		(layer "B.Cu")
	)
	(gr_line
		(start 100.565966 -107.26293)
		(end 100.653596 -107.131612)
		(stroke
			(width 0.05715)
			(type default)
		)
		(layer "B.Cu")
	)
	(gr_line
		(start 100.644706 -107.496102)
		(end 101.137466 -107.39755)
		(stroke
			(width 0.05715)
			(type default)
		)
		(layer "B.Cu")
	)
	(gr_line
		(start 100.653596 -107.131612)
		(end 100.989892 -107.064302)
		(stroke
			(width 0.05715)
			(type default)
		)
		(layer "B.Cu")
	)
	(gr_line
		(start 100.989892 -107.064302)
		(end 101.12121 -107.151932)
		(stroke
			(width 0.05715)
			(type default)
		)
		(layer "B.Cu")
	)
	(gr_line
		(start 101.461824 -122.568462)
		(end 101.475032 -122.565922)
		(stroke
			(width 0.05715)
			(type default)
		)
		(layer "B.Cu")
	)
	(gr_line
		(start 101.462586 -107.08386)
		(end 101.550216 -106.952288)
		(stroke
			(width 0.05715)
			(type default)
		)
		(layer "B.Cu")
	)
	(gr_line
		(start 101.475032 -122.565922)
		(end 101.48824 -122.568462)
		(stroke
			(width 0.05715)
			(type default)
		)
		(layer "B.Cu")
	)
	(gr_line
		(start 101.541326 -107.316778)
		(end 102.034086 -107.218226)
		(stroke
			(width 0.05715)
			(type default)
		)
		(layer "B.Cu")
	)
	(gr_line
		(start 101.550216 -106.952288)
		(end 101.886512 -106.884978)
		(stroke
			(width 0.05715)
			(type default)
		)
		(layer "B.Cu")
	)
	(gr_line
		(start 101.886512 -106.884978)
		(end 102.01783 -106.972608)
		(stroke
			(width 0.05715)
			(type default)
		)
		(layer "B.Cu")
	)
	(gr_line
		(start 101.934264 -121.46026)
		(end 101.947472 -121.4628)
		(stroke
			(width 0.05715)
			(type default)
		)
		(layer "B.Cu")
	)
	(gr_line
		(start 102.117652 -104.716326)
		(end 102.13086 -104.713786)
		(stroke
			(width 0.05715)
			(type default)
		)
		(layer "B.Cu")
	)
	(gr_line
		(start 102.13086 -104.713786)
		(end 102.144068 -104.716326)
		(stroke
			(width 0.05715)
			(type default)
		)
		(layer "B.Cu")
	)
	(gr_line
		(start 102.131368 -120.394984)
		(end 102.144576 -120.392444)
		(stroke
			(width 0.05715)
			(type default)
		)
		(layer "B.Cu")
	)
	(gr_line
		(start 102.144576 -120.392444)
		(end 102.157784 -120.394984)
		(stroke
			(width 0.05715)
			(type default)
		)
		(layer "B.Cu")
	)
	(gr_line
		(start 102.19817 -105.752392)
		(end 102.211378 -105.749852)
		(stroke
			(width 0.05715)
			(type default)
		)
		(layer "B.Cu")
	)
	(gr_line
		(start 102.211378 -105.749852)
		(end 102.224586 -105.752392)
		(stroke
			(width 0.05715)
			(type default)
		)
		(layer "B.Cu")
	)
	(gr_line
		(start 102.454202 -105.024682)
		(end 102.945946 -105.12298)
		(stroke
			(width 0.05715)
			(type default)
		)
		(layer "B.Cu")
	)
	(gr_line
		(start 102.45598 -111.263176)
		(end 102.469188 -111.260636)
		(stroke
			(width 0.05715)
			(type default)
		)
		(layer "B.Cu")
	)
	(gr_line
		(start 102.469188 -111.260636)
		(end 102.482396 -111.263176)
		(stroke
			(width 0.05715)
			(type default)
		)
		(layer "B.Cu")
	)
	(gr_line
		(start 102.470204 -104.779064)
		(end 102.601522 -104.691434)
		(stroke
			(width 0.05715)
			(type default)
		)
		(layer "B.Cu")
	)
	(gr_line
		(start 102.564692 -107.853734)
		(end 102.5779 -107.851194)
		(stroke
			(width 0.05715)
			(type default)
		)
		(layer "B.Cu")
	)
	(gr_line
		(start 102.5779 -107.851194)
		(end 102.591108 -107.853734)
		(stroke
			(width 0.05715)
			(type default)
		)
		(layer "B.Cu")
	)
	(gr_line
		(start 102.59695 -106.859324)
		(end 102.610158 -106.856784)
		(stroke
			(width 0.05715)
			(type default)
		)
		(layer "B.Cu")
	)
	(gr_line
		(start 102.601522 -104.691434)
		(end 102.937818 -104.758744)
		(stroke
			(width 0.05715)
			(type default)
		)
		(layer "B.Cu")
	)
	(gr_line
		(start 102.610158 -106.856784)
		(end 102.623366 -106.859324)
		(stroke
			(width 0.05715)
			(type default)
		)
		(layer "B.Cu")
	)
	(gr_line
		(start 102.681786 -110.05439)
		(end 102.694994 -110.05185)
		(stroke
			(width 0.05715)
			(type default)
		)
		(layer "B.Cu")
	)
	(gr_line
		(start 102.683056 -119.200168)
		(end 102.696264 -119.197628)
		(stroke
			(width 0.05715)
			(type default)
		)
		(layer "B.Cu")
	)
	(gr_line
		(start 102.694994 -110.05185)
		(end 102.708202 -110.05439)
		(stroke
			(width 0.05715)
			(type default)
		)
		(layer "B.Cu")
	)
	(gr_line
		(start 102.696264 -119.197628)
		(end 102.709472 -119.200168)
		(stroke
			(width 0.05715)
			(type default)
		)
		(layer "B.Cu")
	)
	(gr_line
		(start 102.707948 -118.046754)
		(end 102.721156 -118.044214)
		(stroke
			(width 0.05715)
			(type default)
		)
		(layer "B.Cu")
	)
	(gr_line
		(start 102.719378 -108.932218)
		(end 102.732586 -108.929678)
		(stroke
			(width 0.05715)
			(type default)
		)
		(layer "B.Cu")
	)
	(gr_line
		(start 102.721156 -118.044214)
		(end 102.734364 -118.046754)
		(stroke
			(width 0.05715)
			(type default)
		)
		(layer "B.Cu")
	)
	(gr_line
		(start 102.732586 -108.929678)
		(end 102.745794 -108.932218)
		(stroke
			(width 0.05715)
			(type default)
		)
		(layer "B.Cu")
	)
	(gr_line
		(start 102.76713 -112.338104)
		(end 102.780338 -112.335564)
		(stroke
			(width 0.05715)
			(type default)
		)
		(layer "B.Cu")
	)
	(gr_line
		(start 102.780338 -112.335564)
		(end 102.793546 -112.338104)
		(stroke
			(width 0.05715)
			(type default)
		)
		(layer "B.Cu")
	)
	(gr_line
		(start 102.937818 -104.758744)
		(end 103.025448 -104.890316)
		(stroke
			(width 0.05715)
			(type default)
		)
		(layer "B.Cu")
	)
	(gr_line
		(start 102.946708 -116.844064)
		(end 102.959916 -116.841524)
		(stroke
			(width 0.05715)
			(type default)
		)
		(layer "B.Cu")
	)
	(gr_line
		(start 102.959916 -116.841524)
		(end 102.973124 -116.844064)
		(stroke
			(width 0.05715)
			(type default)
		)
		(layer "B.Cu")
	)
	(gr_line
		(start 103.35006 -105.204006)
		(end 103.843328 -105.302558)
		(stroke
			(width 0.05715)
			(type default)
		)
		(layer "B.Cu")
	)
	(gr_line
		(start 103.36657 -104.958388)
		(end 103.498142 -104.870758)
		(stroke
			(width 0.05715)
			(type default)
		)
		(layer "B.Cu")
	)
	(gr_line
		(start 103.498142 -104.870758)
		(end 103.834438 -104.938068)
		(stroke
			(width 0.05715)
			(type default)
		)
		(layer "B.Cu")
	)
	(gr_line
		(start 103.834438 -104.938068)
		(end 103.922322 -105.06964)
		(stroke
			(width 0.05715)
			(type default)
		)
		(layer "B.Cu")
	)
	(gr_line
		(start 104.138476 -114.29238)
		(end 104.226106 -114.161062)
		(stroke
			(width 0.05715)
			(type default)
		)
		(layer "B.Cu")
	)
	(gr_line
		(start 104.217978 -114.525298)
		(end 104.709722 -114.427)
		(stroke
			(width 0.05715)
			(type default)
		)
		(layer "B.Cu")
	)
	(gr_line
		(start 104.226106 -114.161062)
		(end 104.562402 -114.093752)
		(stroke
			(width 0.05715)
			(type default)
		)
		(layer "B.Cu")
	)
	(gr_line
		(start 104.530652 -115.254278)
		(end 104.54386 -115.251738)
		(stroke
			(width 0.05715)
			(type default)
		)
		(layer "B.Cu")
	)
	(gr_line
		(start 104.54386 -115.251738)
		(end 104.557068 -115.254278)
		(stroke
			(width 0.05715)
			(type default)
		)
		(layer "B.Cu")
	)
	(gr_line
		(start 104.562402 -114.093752)
		(end 104.69372 -114.181382)
		(stroke
			(width 0.05715)
			(type default)
		)
		(layer "B.Cu")
	)
	(gr_line
		(start 105.126536 -113.051082)
		(end 105.139744 -113.053622)
		(stroke
			(width 0.05715)
			(type default)
		)
		(layer "B.Cu")
	)
	(gr_line
		(start 105.139744 -113.053622)
		(end 105.152952 -113.051082)
		(stroke
			(width 0.05715)
			(type default)
		)
		(layer "B.Cu")
	)
	(gr_line
		(start 105.14965 -112.042702)
		(end 105.162858 -112.045242)
		(stroke
			(width 0.05715)
			(type default)
		)
		(layer "B.Cu")
	)
	(gr_line
		(start 105.162858 -112.045242)
		(end 105.176066 -112.042702)
		(stroke
			(width 0.05715)
			(type default)
		)
		(layer "B.Cu")
	)
	(gr_line
		(start 105.238296 -114.074956)
		(end 105.251504 -114.072416)
		(stroke
			(width 0.05715)
			(type default)
		)
		(layer "B.Cu")
	)
	(gr_line
		(start 105.251504 -114.072416)
		(end 105.264712 -114.074956)
		(stroke
			(width 0.05715)
			(type default)
		)
		(layer "B.Cu")
	)
	(gr_line
		(start 105.405936 -110.84052)
		(end 105.419144 -110.84306)
		(stroke
			(width 0.05715)
			(type default)
		)
		(layer "B.Cu")
	)
	(gr_line
		(start 105.419144 -110.84306)
		(end 105.432352 -110.84052)
		(stroke
			(width 0.05715)
			(type default)
		)
		(layer "B.Cu")
	)
	(gr_line
		(start 105.614216 -105.656888)
		(end 105.627424 -105.659428)
		(stroke
			(width 0.05715)
			(type default)
		)
		(layer "B.Cu")
	)
	(gr_line
		(start 105.627424 -105.659428)
		(end 105.640632 -105.656888)
		(stroke
			(width 0.05715)
			(type default)
		)
		(layer "B.Cu")
	)
	(gr_line
		(start 105.704386 -108.722668)
		(end 105.717594 -108.725208)
		(stroke
			(width 0.05715)
			(type default)
		)
		(layer "B.Cu")
	)
	(gr_line
		(start 105.712006 -109.771688)
		(end 105.725214 -109.774228)
		(stroke
			(width 0.05715)
			(type default)
		)
		(layer "B.Cu")
	)
	(gr_line
		(start 105.717594 -108.725208)
		(end 105.730802 -108.722668)
		(stroke
			(width 0.05715)
			(type default)
		)
		(layer "B.Cu")
	)
	(gr_line
		(start 105.725214 -109.774228)
		(end 105.738422 -109.771688)
		(stroke
			(width 0.05715)
			(type default)
		)
		(layer "B.Cu")
	)
	(gr_line
		(start 105.730548 -107.727242)
		(end 105.743756 -107.729782)
		(stroke
			(width 0.05715)
			(type default)
		)
		(layer "B.Cu")
	)
	(gr_line
		(start 105.743756 -107.729782)
		(end 105.756964 -107.727242)
		(stroke
			(width 0.05715)
			(type default)
		)
		(layer "B.Cu")
	)
	(gr_line
		(start 105.817924 -106.717338)
		(end 105.831132 -106.719878)
		(stroke
			(width 0.05715)
			(type default)
		)
		(layer "B.Cu")
	)
	(gr_line
		(start 105.831132 -106.719878)
		(end 105.84434 -106.717338)
		(stroke
			(width 0.05715)
			(type default)
		)
		(layer "B.Cu")
	)
	(gr_line
		(start 105.965752 -105.343198)
		(end 106.053382 -105.211626)
		(stroke
			(width 0.05715)
			(type default)
		)
		(layer "B.Cu")
	)
	(gr_line
		(start 106.045508 -105.575608)
		(end 106.536744 -105.477564)
		(stroke
			(width 0.05715)
			(type default)
		)
		(layer "B.Cu")
	)
	(gr_line
		(start 106.053382 -105.211626)
		(end 106.389678 -105.144316)
		(stroke
			(width 0.05715)
			(type default)
		)
		(layer "B.Cu")
	)
	(gr_line
		(start 106.389678 -105.144316)
		(end 106.520996 -105.231946)
		(stroke
			(width 0.05715)
			(type default)
		)
		(layer "B.Cu")
	)
	(gr_line
		(start 106.862372 -105.163874)
		(end 106.950002 -105.032302)
		(stroke
			(width 0.05715)
			(type default)
		)
		(layer "B.Cu")
	)
	(gr_line
		(start 106.901996 -114.648742)
		(end 107.394756 -114.747294)
		(stroke
			(width 0.05715)
			(type default)
		)
		(layer "B.Cu")
	)
	(gr_line
		(start 106.917998 -114.403124)
		(end 107.04957 -114.315494)
		(stroke
			(width 0.05715)
			(type default)
		)
		(layer "B.Cu")
	)
	(gr_line
		(start 106.941112 -105.396792)
		(end 107.433618 -105.29824)
		(stroke
			(width 0.05715)
			(type default)
		)
		(layer "B.Cu")
	)
	(gr_line
		(start 106.950002 -105.032302)
		(end 107.286298 -104.964992)
		(stroke
			(width 0.05715)
			(type default)
		)
		(layer "B.Cu")
	)
	(gr_line
		(start 107.04957 -114.315494)
		(end 107.385866 -114.382804)
		(stroke
			(width 0.05715)
			(type default)
		)
		(layer "B.Cu")
	)
	(gr_line
		(start 107.286298 -104.964992)
		(end 107.417616 -105.052622)
		(stroke
			(width 0.05715)
			(type default)
		)
		(layer "B.Cu")
	)
	(gr_line
		(start 107.385866 -114.382804)
		(end 107.473496 -114.514376)
		(stroke
			(width 0.05715)
			(type default)
		)
		(layer "B.Cu")
	)
	(gr_line
		(start 107.798616 -114.828066)
		(end 108.291376 -114.926618)
		(stroke
			(width 0.05715)
			(type default)
		)
		(layer "B.Cu")
	)
	(gr_line
		(start 107.814618 -114.582448)
		(end 107.94619 -114.494818)
		(stroke
			(width 0.05715)
			(type default)
		)
		(layer "B.Cu")
	)
	(gr_line
		(start 107.94619 -114.494818)
		(end 108.282486 -114.562128)
		(stroke
			(width 0.05715)
			(type default)
		)
		(layer "B.Cu")
	)
	(gr_line
		(start 108.282486 -114.562128)
		(end 108.370116 -114.6937)
		(stroke
			(width 0.05715)
			(type default)
		)
		(layer "B.Cu")
	)
	(gr_line
		(start 108.348526 -114.814858)
		(end 108.684822 -114.882168)
		(stroke
			(width 0.127)
			(type default)
		)
		(layer "B.Cu")
	)
	(gr_line
		(start 108.608114 -109.959394)
		(end 108.621322 -109.956854)
		(stroke
			(width 0.05715)
			(type default)
		)
		(layer "B.Cu")
	)
	(gr_line
		(start 108.621322 -109.956854)
		(end 108.63453 -109.959394)
		(stroke
			(width 0.05715)
			(type default)
		)
		(layer "B.Cu")
	)
	(gr_line
		(start 108.684822 -114.882168)
		(end 109.245146 -114.994182)
		(stroke
			(width 0.127)
			(type default)
		)
		(layer "B.Cu")
	)
	(gr_line
		(start 108.693458 -112.096804)
		(end 108.706666 -112.094264)
		(stroke
			(width 0.05715)
			(type default)
		)
		(layer "B.Cu")
	)
	(gr_line
		(start 108.69549 -115.00739)
		(end 109.187742 -115.105942)
		(stroke
			(width 0.05715)
			(type default)
		)
		(layer "B.Cu")
	)
	(gr_line
		(start 108.706666 -112.094264)
		(end 108.719874 -112.096804)
		(stroke
			(width 0.05715)
			(type default)
		)
		(layer "B.Cu")
	)
	(gr_line
		(start 108.711492 -114.761772)
		(end 108.84281 -114.674142)
		(stroke
			(width 0.05715)
			(type default)
		)
		(layer "B.Cu")
	)
	(gr_line
		(start 108.72978 -107.877356)
		(end 108.742988 -107.874816)
		(stroke
			(width 0.05715)
			(type default)
		)
		(layer "B.Cu")
	)
	(gr_line
		(start 108.742988 -107.874816)
		(end 108.756196 -107.877356)
		(stroke
			(width 0.05715)
			(type default)
		)
		(layer "B.Cu")
	)
	(gr_line
		(start 108.84281 -114.674142)
		(end 109.179106 -114.741452)
		(stroke
			(width 0.05715)
			(type default)
		)
		(layer "B.Cu")
	)
	(gr_line
		(start 108.874306 -118.270528)
		(end 108.887514 -118.273068)
		(stroke
			(width 0.05715)
			(type default)
		)
		(layer "B.Cu")
	)
	(gr_line
		(start 108.877862 -108.89742)
		(end 108.89107 -108.89488)
		(stroke
			(width 0.05715)
			(type default)
		)
		(layer "B.Cu")
	)
	(gr_line
		(start 108.887514 -118.273068)
		(end 108.900722 -118.270528)
		(stroke
			(width 0.05715)
			(type default)
		)
		(layer "B.Cu")
	)
	(gr_line
		(start 108.89107 -108.89488)
		(end 108.904278 -108.89742)
		(stroke
			(width 0.05715)
			(type default)
		)
		(layer "B.Cu")
	)
	(gr_line
		(start 108.946442 -104.749346)
		(end 108.95965 -104.746806)
		(stroke
			(width 0.05715)
			(type default)
		)
		(layer "B.Cu")
	)
	(gr_line
		(start 108.95965 -104.746806)
		(end 108.972858 -104.749346)
		(stroke
			(width 0.05715)
			(type default)
		)
		(layer "B.Cu")
	)
	(gr_line
		(start 108.968032 -111.038132)
		(end 108.98251 -111.035084)
		(stroke
			(width 0.05715)
			(type default)
		)
		(layer "B.Cu")
	)
	(gr_line
		(start 108.98251 -111.035084)
		(end 108.997242 -111.038132)
		(stroke
			(width 0.05715)
			(type default)
		)
		(layer "B.Cu")
	)
	(gr_line
		(start 109.031786 -122.016012)
		(end 109.044994 -122.018552)
		(stroke
			(width 0.05715)
			(type default)
		)
		(layer "B.Cu")
	)
	(gr_line
		(start 109.044994 -122.018552)
		(end 109.058202 -122.016012)
		(stroke
			(width 0.05715)
			(type default)
		)
		(layer "B.Cu")
	)
	(gr_line
		(start 109.066076 -108.185712)
		(end 109.55782 -108.28401)
		(stroke
			(width 0.05715)
			(type default)
		)
		(layer "B.Cu")
	)
	(gr_line
		(start 109.082332 -107.940094)
		(end 109.21365 -107.852464)
		(stroke
			(width 0.05715)
			(type default)
		)
		(layer "B.Cu")
	)
	(gr_line
		(start 109.11205 -106.80954)
		(end 109.125258 -106.807)
		(stroke
			(width 0.05715)
			(type default)
		)
		(layer "B.Cu")
	)
	(gr_line
		(start 109.125258 -106.807)
		(end 109.138466 -106.80954)
		(stroke
			(width 0.05715)
			(type default)
		)
		(layer "B.Cu")
	)
	(gr_line
		(start 109.131862 -119.572786)
		(end 109.14507 -119.575326)
		(stroke
			(width 0.05715)
			(type default)
		)
		(layer "B.Cu")
	)
	(gr_line
		(start 109.142276 -105.811828)
		(end 109.155484 -105.809288)
		(stroke
			(width 0.05715)
			(type default)
		)
		(layer "B.Cu")
	)
	(gr_line
		(start 109.14507 -119.575326)
		(end 109.158278 -119.572786)
		(stroke
			(width 0.05715)
			(type default)
		)
		(layer "B.Cu")
	)
	(gr_line
		(start 109.179106 -114.741452)
		(end 109.266736 -114.873024)
		(stroke
			(width 0.05715)
			(type default)
		)
		(layer "B.Cu")
	)
	(gr_line
		(start 109.21365 -107.852464)
		(end 109.549946 -107.91952)
		(stroke
			(width 0.05715)
			(type default)
		)
		(layer "B.Cu")
	)
	(gr_line
		(start 109.231684 -123.16587)
		(end 109.244892 -123.16333)
		(stroke
			(width 0.05715)
			(type default)
		)
		(layer "B.Cu")
	)
	(gr_line
		(start 109.245146 -114.994182)
		(end 109.841792 -115.113562)
		(stroke
			(width 0.127)
			(type default)
		)
		(layer "B.Cu")
	)
	(gr_line
		(start 109.33811 -120.772174)
		(end 109.351318 -120.774714)
		(stroke
			(width 0.05715)
			(type default)
		)
		(layer "B.Cu")
	)
	(gr_line
		(start 109.351318 -120.774714)
		(end 109.364526 -120.772174)
		(stroke
			(width 0.05715)
			(type default)
		)
		(layer "B.Cu")
	)
	(gr_line
		(start 109.533182 -124.423678)
		(end 109.54639 -124.426218)
		(stroke
			(width 0.05715)
			(type default)
		)
		(layer "B.Cu")
	)
	(gr_line
		(start 109.54639 -124.426218)
		(end 109.559598 -124.423678)
		(stroke
			(width 0.05715)
			(type default)
		)
		(layer "B.Cu")
	)
	(gr_line
		(start 109.549946 -107.91952)
		(end 109.637576 -108.051092)
		(stroke
			(width 0.05715)
			(type default)
		)
		(layer "B.Cu")
	)
	(gr_line
		(start 109.596936 -110.398306)
		(end 110.08995 -110.496858)
		(stroke
			(width 0.05715)
			(type default)
		)
		(layer "B.Cu")
	)
	(gr_line
		(start 109.613446 -110.152688)
		(end 109.744764 -110.065058)
		(stroke
			(width 0.05715)
			(type default)
		)
		(layer "B.Cu")
	)
	(gr_line
		(start 109.744764 -110.065058)
		(end 110.08106 -110.132114)
		(stroke
			(width 0.05715)
			(type default)
		)
		(layer "B.Cu")
	)
	(gr_line
		(start 109.781848 -116.545614)
		(end 109.795056 -116.548154)
		(stroke
			(width 0.05715)
			(type default)
		)
		(layer "B.Cu")
	)
	(gr_line
		(start 109.795056 -116.548154)
		(end 109.808264 -116.545614)
		(stroke
			(width 0.05715)
			(type default)
		)
		(layer "B.Cu")
	)
	(gr_line
		(start 109.841792 -115.113562)
		(end 109.889036 -115.113562)
		(stroke
			(width 0.127)
			(type default)
		)
		(layer "B.Cu")
	)
	(gr_line
		(start 109.852206 -115.238784)
		(end 109.865414 -115.241324)
		(stroke
			(width 0.05715)
			(type default)
		)
		(layer "B.Cu")
	)
	(gr_line
		(start 109.865414 -115.241324)
		(end 109.878622 -115.238784)
		(stroke
			(width 0.05715)
			(type default)
		)
		(layer "B.Cu")
	)
	(gr_line
		(start 109.889036 -115.113562)
		(end 110.86592 -114.918236)
		(stroke
			(width 0.127)
			(type default)
		)
		(layer "B.Cu")
	)
	(gr_line
		(start 109.963204 -108.365036)
		(end 110.453932 -108.46308)
		(stroke
			(width 0.05715)
			(type default)
		)
		(layer "B.Cu")
	)
	(gr_line
		(start 109.978952 -108.119418)
		(end 110.11027 -108.031534)
		(stroke
			(width 0.05715)
			(type default)
		)
		(layer "B.Cu")
	)
	(gr_line
		(start 110.08106 -110.132114)
		(end 110.16869 -110.26394)
		(stroke
			(width 0.05715)
			(type default)
		)
		(layer "B.Cu")
	)
	(gr_line
		(start 110.11027 -108.031534)
		(end 110.446566 -108.098844)
		(stroke
			(width 0.05715)
			(type default)
		)
		(layer "B.Cu")
	)
	(gr_line
		(start 110.230412 -105.246932)
		(end 110.724696 -105.345992)
		(stroke
			(width 0.05715)
			(type default)
		)
		(layer "B.Cu")
	)
	(gr_line
		(start 110.247176 -105.001822)
		(end 110.379002 -104.913938)
		(stroke
			(width 0.05715)
			(type default)
		)
		(layer "B.Cu")
	)
	(gr_line
		(start 110.379002 -104.913938)
		(end 110.715044 -104.981248)
		(stroke
			(width 0.05715)
			(type default)
		)
		(layer "B.Cu")
	)
	(gr_line
		(start 110.446566 -108.098844)
		(end 110.534196 -108.230416)
		(stroke
			(width 0.05715)
			(type default)
		)
		(layer "B.Cu")
	)
	(gr_line
		(start 110.493556 -110.57763)
		(end 110.987332 -110.676436)
		(stroke
			(width 0.05715)
			(type default)
		)
		(layer "B.Cu")
	)
	(gr_line
		(start 110.510066 -110.332012)
		(end 110.641384 -110.244382)
		(stroke
			(width 0.05715)
			(type default)
		)
		(layer "B.Cu")
	)
	(gr_line
		(start 110.641384 -110.244382)
		(end 110.97768 -110.311692)
		(stroke
			(width 0.05715)
			(type default)
		)
		(layer "B.Cu")
	)
	(gr_line
		(start 110.715044 -104.981248)
		(end 110.802928 -105.11282)
		(stroke
			(width 0.05715)
			(type default)
		)
		(layer "B.Cu")
	)
	(gr_line
		(start 110.84433 -114.796824)
		(end 110.93196 -114.665252)
		(stroke
			(width 0.05715)
			(type default)
		)
		(layer "B.Cu")
	)
	(gr_line
		(start 110.85957 -108.544106)
		(end 111.35106 -108.642404)
		(stroke
			(width 0.05715)
			(type default)
		)
		(layer "B.Cu")
	)
	(gr_line
		(start 110.86592 -114.918236)
		(end 111.426498 -114.805968)
		(stroke
			(width 0.127)
			(type default)
		)
		(layer "B.Cu")
	)
	(gr_line
		(start 110.875318 -108.298742)
		(end 111.007144 -108.210858)
		(stroke
			(width 0.05715)
			(type default)
		)
		(layer "B.Cu")
	)
	(gr_line
		(start 110.923832 -115.029742)
		(end 111.416846 -114.930936)
		(stroke
			(width 0.05715)
			(type default)
		)
		(layer "B.Cu")
	)
	(gr_line
		(start 110.93196 -114.665252)
		(end 111.268256 -114.597942)
		(stroke
			(width 0.05715)
			(type default)
		)
		(layer "B.Cu")
	)
	(gr_line
		(start 110.97768 -110.311692)
		(end 111.06531 -110.443264)
		(stroke
			(width 0.05715)
			(type default)
		)
		(layer "B.Cu")
	)
	(gr_line
		(start 111.007144 -108.210858)
		(end 111.343186 -108.278168)
		(stroke
			(width 0.05715)
			(type default)
		)
		(layer "B.Cu")
	)
	(gr_line
		(start 111.094012 -29.94152)
		(end 111.983012 -29.94152)
		(stroke
			(width 0.0635)
			(type default)
		)
		(layer "B.Cu")
	)
	(gr_line
		(start 111.128048 -105.42651)
		(end 111.620808 -105.525062)
		(stroke
			(width 0.05715)
			(type default)
		)
		(layer "B.Cu")
	)
	(gr_line
		(start 111.143796 -105.181146)
		(end 111.275622 -105.093262)
		(stroke
			(width 0.05715)
			(type default)
		)
		(layer "B.Cu")
	)
	(gr_line
		(start 111.268256 -114.597942)
		(end 111.400082 -114.685826)
		(stroke
			(width 0.05715)
			(type default)
		)
		(layer "B.Cu")
	)
	(gr_line
		(start 111.275622 -105.093262)
		(end 111.611918 -105.160572)
		(stroke
			(width 0.05715)
			(type default)
		)
		(layer "B.Cu")
	)
	(gr_line
		(start 111.343186 -108.278168)
		(end 111.430816 -108.40974)
		(stroke
			(width 0.05715)
			(type default)
		)
		(layer "B.Cu")
	)
	(gr_line
		(start 111.368586 -112.875314)
		(end 111.456216 -113.006886)
		(stroke
			(width 0.05715)
			(type default)
		)
		(layer "B.Cu")
	)
	(gr_line
		(start 111.390684 -110.756954)
		(end 111.88319 -110.855506)
		(stroke
			(width 0.05715)
			(type default)
		)
		(layer "B.Cu")
	)
	(gr_line
		(start 111.406432 -110.511336)
		(end 111.538004 -110.423706)
		(stroke
			(width 0.05715)
			(type default)
		)
		(layer "B.Cu")
	)
	(gr_line
		(start 111.426498 -114.805968)
		(end 111.76254 -114.738658)
		(stroke
			(width 0.127)
			(type default)
		)
		(layer "B.Cu")
	)
	(gr_line
		(start 111.448088 -112.642396)
		(end 111.939578 -112.740694)
		(stroke
			(width 0.05715)
			(type default)
		)
		(layer "B.Cu")
	)
	(gr_line
		(start 111.456216 -113.006886)
		(end 111.792258 -113.073942)
		(stroke
			(width 0.05715)
			(type default)
		)
		(layer "B.Cu")
	)
	(gr_line
		(start 111.538004 -110.423706)
		(end 111.8743 -110.491016)
		(stroke
			(width 0.05715)
			(type default)
		)
		(layer "B.Cu")
	)
	(gr_line
		(start 111.611918 -105.160572)
		(end 111.699802 -105.292144)
		(stroke
			(width 0.05715)
			(type default)
		)
		(layer "B.Cu")
	)
	(gr_line
		(start 111.74095 -114.6175)
		(end 111.82858 -114.485928)
		(stroke
			(width 0.05715)
			(type default)
		)
		(layer "B.Cu")
	)
	(gr_line
		(start 111.75492 -108.723176)
		(end 112.249458 -108.822236)
		(stroke
			(width 0.05715)
			(type default)
		)
		(layer "B.Cu")
	)
	(gr_line
		(start 111.76254 -114.738658)
		(end 112.323118 -114.626644)
		(stroke
			(width 0.127)
			(type default)
		)
		(layer "B.Cu")
	)
	(gr_line
		(start 111.771938 -108.477812)
		(end 111.903764 -108.390182)
		(stroke
			(width 0.05715)
			(type default)
		)
		(layer "B.Cu")
	)
	(gr_line
		(start 111.792258 -113.073942)
		(end 111.92383 -112.986312)
		(stroke
			(width 0.05715)
			(type default)
		)
		(layer "B.Cu")
	)
	(gr_line
		(start 111.81969 -114.850672)
		(end 112.314482 -114.751612)
		(stroke
			(width 0.05715)
			(type default)
		)
		(layer "B.Cu")
	)
	(gr_line
		(start 111.82858 -114.485928)
		(end 112.164876 -114.418618)
		(stroke
			(width 0.05715)
			(type default)
		)
		(layer "B.Cu")
	)
	(gr_line
		(start 111.8743 -110.491016)
		(end 111.962184 -110.622588)
		(stroke
			(width 0.05715)
			(type default)
		)
		(layer "B.Cu")
	)
	(gr_line
		(start 111.903764 -108.390182)
		(end 112.239806 -108.457492)
		(stroke
			(width 0.05715)
			(type default)
		)
		(layer "B.Cu")
	)
	(gr_line
		(start 111.983012 -30.348936)
		(end 112.246156 -30.61208)
		(stroke
			(width 0.0635)
			(type default)
		)
		(layer "B.Cu")
	)
	(gr_line
		(start 111.983012 -29.94152)
		(end 111.983012 -30.348936)
		(stroke
			(width 0.0635)
			(type default)
		)
		(layer "B.Cu")
	)
	(gr_line
		(start 112.164876 -114.418618)
		(end 112.296702 -114.506502)
		(stroke
			(width 0.05715)
			(type default)
		)
		(layer "B.Cu")
	)
	(gr_line
		(start 112.239806 -108.457492)
		(end 112.327944 -108.589064)
		(stroke
			(width 0.05715)
			(type default)
		)
		(layer "B.Cu")
	)
	(gr_line
		(start 112.265206 -113.054384)
		(end 112.352836 -113.18621)
		(stroke
			(width 0.05715)
			(type default)
		)
		(layer "B.Cu")
	)
	(gr_line
		(start 112.28705 -110.936278)
		(end 112.779048 -111.034576)
		(stroke
			(width 0.05715)
			(type default)
		)
		(layer "B.Cu")
	)
	(gr_line
		(start 112.303052 -110.69066)
		(end 112.434624 -110.60303)
		(stroke
			(width 0.05715)
			(type default)
		)
		(layer "B.Cu")
	)
	(gr_line
		(start 112.323118 -114.626644)
		(end 112.659414 -114.559334)
		(stroke
			(width 0.127)
			(type default)
		)
		(layer "B.Cu")
	)
	(gr_line
		(start 112.343946 -112.821466)
		(end 112.836706 -112.920018)
		(stroke
			(width 0.05715)
			(type default)
		)
		(layer "B.Cu")
	)
	(gr_line
		(start 112.352836 -113.18621)
		(end 112.688878 -113.253266)
		(stroke
			(width 0.05715)
			(type default)
		)
		(layer "B.Cu")
	)
	(gr_line
		(start 112.404144 -105.68178)
		(end 112.417098 -105.68432)
		(stroke
			(width 0.05715)
			(type default)
		)
		(layer "B.Cu")
	)
	(gr_line
		(start 112.417098 -105.68432)
		(end 112.43056 -105.68178)
		(stroke
			(width 0.05715)
			(type default)
		)
		(layer "B.Cu")
	)
	(gr_line
		(start 112.434624 -110.60303)
		(end 112.77092 -110.67034)
		(stroke
			(width 0.05715)
			(type default)
		)
		(layer "B.Cu")
	)
	(gr_line
		(start 112.608868 -30.61208)
		(end 112.872012 -30.348936)
		(stroke
			(width 0.0635)
			(type default)
		)
		(layer "B.Cu")
	)
	(gr_line
		(start 112.637824 -114.438176)
		(end 112.725454 -114.306604)
		(stroke
			(width 0.05715)
			(type default)
		)
		(layer "B.Cu")
	)
	(gr_line
		(start 112.659414 -114.559334)
		(end 113.219738 -114.44732)
		(stroke
			(width 0.127)
			(type default)
		)
		(layer "B.Cu")
	)
	(gr_line
		(start 112.688878 -113.253266)
		(end 112.82045 -113.165636)
		(stroke
			(width 0.05715)
			(type default)
		)
		(layer "B.Cu")
	)
	(gr_line
		(start 112.718088 -114.67084)
		(end 113.209578 -114.572542)
		(stroke
			(width 0.05715)
			(type default)
		)
		(layer "B.Cu")
	)
	(gr_line
		(start 112.725454 -114.306604)
		(end 113.061496 -114.239294)
		(stroke
			(width 0.05715)
			(type default)
		)
		(layer "B.Cu")
	)
	(gr_line
		(start 112.77092 -110.67034)
		(end 112.858804 -110.801912)
		(stroke
			(width 0.05715)
			(type default)
		)
		(layer "B.Cu")
	)
	(gr_line
		(start 112.830356 -106.79049)
		(end 112.843564 -106.79303)
		(stroke
			(width 0.05715)
			(type default)
		)
		(layer "B.Cu")
	)
	(gr_line
		(start 112.843564 -106.79303)
		(end 112.856772 -106.79049)
		(stroke
			(width 0.05715)
			(type default)
		)
		(layer "B.Cu")
	)
	(gr_line
		(start 112.872012 -29.94152)
		(end 112.872012 -30.348936)
		(stroke
			(width 0.0635)
			(type default)
		)
		(layer "B.Cu")
	)
	(gr_line
		(start 112.872012 -29.94152)
		(end 113.761012 -29.94152)
		(stroke
			(width 0.0635)
			(type default)
		)
		(layer "B.Cu")
	)
	(gr_line
		(start 113.061496 -114.239294)
		(end 113.193322 -114.327178)
		(stroke
			(width 0.05715)
			(type default)
		)
		(layer "B.Cu")
	)
	(gr_line
		(start 113.077752 -107.843574)
		(end 113.09096 -107.846114)
		(stroke
			(width 0.05715)
			(type default)
		)
		(layer "B.Cu")
	)
	(gr_line
		(start 113.089182 -109.980984)
		(end 113.10239 -109.983524)
		(stroke
			(width 0.05715)
			(type default)
		)
		(layer "B.Cu")
	)
	(gr_line
		(start 113.09096 -107.846114)
		(end 113.104422 -107.843574)
		(stroke
			(width 0.05715)
			(type default)
		)
		(layer "B.Cu")
	)
	(gr_line
		(start 113.099596 -108.992162)
		(end 113.112804 -108.994702)
		(stroke
			(width 0.05715)
			(type default)
		)
		(layer "B.Cu")
	)
	(gr_line
		(start 113.10239 -109.983524)
		(end 113.115598 -109.980984)
		(stroke
			(width 0.05715)
			(type default)
		)
		(layer "B.Cu")
	)
	(gr_line
		(start 113.112804 -108.994702)
		(end 113.126012 -108.992162)
		(stroke
			(width 0.05715)
			(type default)
		)
		(layer "B.Cu")
	)
	(gr_line
		(start 113.181638 -106.4768)
		(end 113.269522 -106.345228)
		(stroke
			(width 0.05715)
			(type default)
		)
		(layer "B.Cu")
	)
	(gr_line
		(start 113.183416 -111.115602)
		(end 113.196624 -111.118142)
		(stroke
			(width 0.05715)
			(type default)
		)
		(layer "B.Cu")
	)
	(gr_line
		(start 113.196624 -111.118142)
		(end 113.209832 -111.115602)
		(stroke
			(width 0.05715)
			(type default)
		)
		(layer "B.Cu")
	)
	(gr_line
		(start 113.219738 -114.44732)
		(end 113.556034 -114.38001)
		(stroke
			(width 0.127)
			(type default)
		)
		(layer "B.Cu")
	)
	(gr_line
		(start 113.260886 -106.709718)
		(end 113.753138 -106.611166)
		(stroke
			(width 0.05715)
			(type default)
		)
		(layer "B.Cu")
	)
	(gr_line
		(start 113.269522 -106.345228)
		(end 113.605818 -106.277918)
		(stroke
			(width 0.05715)
			(type default)
		)
		(layer "B.Cu")
	)
	(gr_line
		(start 113.285016 -113.25606)
		(end 113.298224 -113.2586)
		(stroke
			(width 0.05715)
			(type default)
		)
		(layer "B.Cu")
	)
	(gr_line
		(start 113.298224 -113.2586)
		(end 113.311432 -113.25606)
		(stroke
			(width 0.05715)
			(type default)
		)
		(layer "B.Cu")
	)
	(gr_line
		(start 113.429288 -107.530138)
		(end 113.517172 -107.39882)
		(stroke
			(width 0.05715)
			(type default)
		)
		(layer "B.Cu")
	)
	(gr_line
		(start 113.509044 -107.762802)
		(end 114.000788 -107.665266)
		(stroke
			(width 0.05715)
			(type default)
		)
		(layer "B.Cu")
	)
	(gr_line
		(start 113.517172 -107.39882)
		(end 113.853468 -107.331764)
		(stroke
			(width 0.05715)
			(type default)
		)
		(layer "B.Cu")
	)
	(gr_line
		(start 113.534444 -114.258852)
		(end 113.622074 -114.12728)
		(stroke
			(width 0.05715)
			(type default)
		)
		(layer "B.Cu")
	)
	(gr_line
		(start 113.556034 -114.38001)
		(end 114.116358 -114.267996)
		(stroke
			(width 0.127)
			(type default)
		)
		(layer "B.Cu")
	)
	(gr_line
		(start 113.59515 -112.209072)
		(end 113.608358 -112.211612)
		(stroke
			(width 0.05715)
			(type default)
		)
		(layer "B.Cu")
	)
	(gr_line
		(start 113.605818 -106.277918)
		(end 113.73739 -106.365802)
		(stroke
			(width 0.05715)
			(type default)
		)
		(layer "B.Cu")
	)
	(gr_line
		(start 113.608358 -112.211612)
		(end 113.621566 -112.209072)
		(stroke
			(width 0.05715)
			(type default)
		)
		(layer "B.Cu")
	)
	(gr_line
		(start 113.614454 -114.491516)
		(end 114.105944 -114.393218)
		(stroke
			(width 0.05715)
			(type default)
		)
		(layer "B.Cu")
	)
	(gr_line
		(start 113.622074 -114.12728)
		(end 113.958116 -114.05997)
		(stroke
			(width 0.05715)
			(type default)
		)
		(layer "B.Cu")
	)
	(gr_line
		(start 113.853468 -107.331764)
		(end 113.984786 -107.419648)
		(stroke
			(width 0.05715)
			(type default)
		)
		(layer "B.Cu")
	)
	(gr_line
		(start 113.958116 -114.05997)
		(end 114.089942 -114.147854)
		(stroke
			(width 0.05715)
			(type default)
		)
		(layer "B.Cu")
	)
	(gr_line
		(start 114.078258 -106.297476)
		(end 114.166142 -106.165904)
		(stroke
			(width 0.05715)
			(type default)
		)
		(layer "B.Cu")
	)
	(gr_line
		(start 114.116358 -114.267996)
		(end 116.121688 -113.86693)
		(stroke
			(width 0.127)
			(type default)
		)
		(layer "B.Cu")
	)
	(gr_line
		(start 114.157252 -106.530394)
		(end 114.650012 -106.431842)
		(stroke
			(width 0.05715)
			(type default)
		)
		(layer "B.Cu")
	)
	(gr_line
		(start 114.166142 -106.165904)
		(end 114.502438 -106.098594)
		(stroke
			(width 0.05715)
			(type default)
		)
		(layer "B.Cu")
	)
	(gr_line
		(start 114.202718 -105.089198)
		(end 114.291364 -104.958134)
		(stroke
			(width 0.05715)
			(type default)
		)
		(layer "B.Cu")
	)
	(gr_line
		(start 114.279426 -105.322878)
		(end 114.775234 -105.226612)
		(stroke
			(width 0.05715)
			(type default)
		)
		(layer "B.Cu")
	)
	(gr_line
		(start 114.291364 -104.958134)
		(end 114.628168 -104.892602)
		(stroke
			(width 0.05715)
			(type default)
		)
		(layer "B.Cu")
	)
	(gr_line
		(start 114.325908 -107.35183)
		(end 114.413792 -107.220258)
		(stroke
			(width 0.05715)
			(type default)
		)
		(layer "B.Cu")
	)
	(gr_line
		(start 114.404902 -107.584748)
		(end 114.898678 -107.48645)
		(stroke
			(width 0.05715)
			(type default)
		)
		(layer "B.Cu")
	)
	(gr_line
		(start 114.413792 -107.220258)
		(end 114.750342 -107.153456)
		(stroke
			(width 0.05715)
			(type default)
		)
		(layer "B.Cu")
	)
	(gr_line
		(start 114.426238 -108.484924)
		(end 114.514122 -108.353352)
		(stroke
			(width 0.05715)
			(type default)
		)
		(layer "B.Cu")
	)
	(gr_line
		(start 114.502438 -106.098594)
		(end 114.63401 -106.186478)
		(stroke
			(width 0.05715)
			(type default)
		)
		(layer "B.Cu")
	)
	(gr_line
		(start 114.50447 -108.718096)
		(end 114.998246 -108.619798)
		(stroke
			(width 0.05715)
			(type default)
		)
		(layer "B.Cu")
	)
	(gr_line
		(start 114.514122 -108.353352)
		(end 114.850418 -108.286296)
		(stroke
			(width 0.05715)
			(type default)
		)
		(layer "B.Cu")
	)
	(gr_line
		(start 114.628168 -104.892602)
		(end 114.759486 -104.981248)
		(stroke
			(width 0.05715)
			(type default)
		)
		(layer "B.Cu")
	)
	(gr_line
		(start 114.750342 -107.153456)
		(end 114.881914 -107.24134)
		(stroke
			(width 0.05715)
			(type default)
		)
		(layer "B.Cu")
	)
	(gr_line
		(start 114.850418 -108.286296)
		(end 114.98199 -108.374434)
		(stroke
			(width 0.05715)
			(type default)
		)
		(layer "B.Cu")
	)
	(gr_line
		(start 115.100354 -104.914954)
		(end 115.189 -104.78389)
		(stroke
			(width 0.05715)
			(type default)
		)
		(layer "B.Cu")
	)
	(gr_line
		(start 115.177316 -105.148634)
		(end 115.673124 -105.052368)
		(stroke
			(width 0.05715)
			(type default)
		)
		(layer "B.Cu")
	)
	(gr_line
		(start 115.189 -104.78389)
		(end 115.525804 -104.718358)
		(stroke
			(width 0.05715)
			(type default)
		)
		(layer "B.Cu")
	)
	(gr_line
		(start 115.223036 -107.173522)
		(end 115.310666 -107.04195)
		(stroke
			(width 0.05715)
			(type default)
		)
		(layer "B.Cu")
	)
	(gr_line
		(start 115.30203 -107.40644)
		(end 115.795552 -107.308142)
		(stroke
			(width 0.05715)
			(type default)
		)
		(layer "B.Cu")
	)
	(gr_line
		(start 115.310666 -107.04195)
		(end 115.646962 -106.975148)
		(stroke
			(width 0.05715)
			(type default)
		)
		(layer "B.Cu")
	)
	(gr_line
		(start 115.323112 -108.306362)
		(end 115.410996 -108.17479)
		(stroke
			(width 0.05715)
			(type default)
		)
		(layer "B.Cu")
	)
	(gr_line
		(start 115.33124 -110.444788)
		(end 115.419124 -110.31347)
		(stroke
			(width 0.05715)
			(type default)
		)
		(layer "B.Cu")
	)
	(gr_line
		(start 115.401852 -108.539534)
		(end 115.894866 -108.44149)
		(stroke
			(width 0.05715)
			(type default)
		)
		(layer "B.Cu")
	)
	(gr_line
		(start 115.40998 -110.67796)
		(end 115.902994 -110.579916)
		(stroke
			(width 0.05715)
			(type default)
		)
		(layer "B.Cu")
	)
	(gr_line
		(start 115.410996 -108.17479)
		(end 115.747292 -108.107988)
		(stroke
			(width 0.05715)
			(type default)
		)
		(layer "B.Cu")
	)
	(gr_line
		(start 115.419124 -110.31347)
		(end 115.75542 -110.246414)
		(stroke
			(width 0.05715)
			(type default)
		)
		(layer "B.Cu")
	)
	(gr_line
		(start 115.525804 -104.718358)
		(end 115.657122 -104.807004)
		(stroke
			(width 0.05715)
			(type default)
		)
		(layer "B.Cu")
	)
	(gr_line
		(start 115.646962 -106.975148)
		(end 115.778788 -107.062778)
		(stroke
			(width 0.05715)
			(type default)
		)
		(layer "B.Cu")
	)
	(gr_line
		(start 115.747292 -108.107988)
		(end 115.87861 -108.195872)
		(stroke
			(width 0.05715)
			(type default)
		)
		(layer "B.Cu")
	)
	(gr_line
		(start 115.75542 -110.246414)
		(end 115.886738 -110.334298)
		(stroke
			(width 0.05715)
			(type default)
		)
		(layer "B.Cu")
	)
	(gr_line
		(start 115.998244 -104.74071)
		(end 116.08689 -104.609646)
		(stroke
			(width 0.05715)
			(type default)
		)
		(layer "B.Cu")
	)
	(gr_line
		(start 116.075714 -104.974136)
		(end 116.571522 -104.87787)
		(stroke
			(width 0.05715)
			(type default)
		)
		(layer "B.Cu")
	)
	(gr_line
		(start 116.08689 -104.609646)
		(end 116.42344 -104.544114)
		(stroke
			(width 0.05715)
			(type default)
		)
		(layer "B.Cu")
	)
	(gr_line
		(start 116.087906 -105.895648)
		(end 116.176044 -105.764076)
		(stroke
			(width 0.05715)
			(type default)
		)
		(layer "B.Cu")
	)
	(gr_line
		(start 116.11991 -106.99496)
		(end 116.20754 -106.863642)
		(stroke
			(width 0.05715)
			(type default)
		)
		(layer "B.Cu")
	)
	(gr_line
		(start 116.121688 -113.86693)
		(end 116.168932 -113.86693)
		(stroke
			(width 0.127)
			(type default)
		)
		(layer "B.Cu")
	)
	(gr_line
		(start 116.132102 -113.741708)
		(end 116.14531 -113.739168)
		(stroke
			(width 0.05715)
			(type default)
		)
		(layer "B.Cu")
	)
	(gr_line
		(start 116.14531 -113.739168)
		(end 116.158518 -113.741708)
		(stroke
			(width 0.05715)
			(type default)
		)
		(layer "B.Cu")
	)
	(gr_line
		(start 116.167154 -106.128566)
		(end 116.660676 -106.02976)
		(stroke
			(width 0.05715)
			(type default)
		)
		(layer "B.Cu")
	)
	(gr_line
		(start 116.168932 -113.86693)
		(end 116.457984 -113.924842)
		(stroke
			(width 0.127)
			(type default)
		)
		(layer "B.Cu")
	)
	(gr_line
		(start 116.176044 -105.764076)
		(end 116.512086 -105.696766)
		(stroke
			(width 0.05715)
			(type default)
		)
		(layer "B.Cu")
	)
	(gr_line
		(start 116.199666 -107.227624)
		(end 116.691156 -107.130088)
		(stroke
			(width 0.05715)
			(type default)
		)
		(layer "B.Cu")
	)
	(gr_line
		(start 116.20754 -106.863642)
		(end 116.543836 -106.796586)
		(stroke
			(width 0.05715)
			(type default)
		)
		(layer "B.Cu")
	)
	(gr_line
		(start 116.42344 -104.544114)
		(end 116.554504 -104.63276)
		(stroke
			(width 0.05715)
			(type default)
		)
		(layer "B.Cu")
	)
	(gr_line
		(start 116.448586 -114.971322)
		(end 116.461794 -114.973862)
		(stroke
			(width 0.05715)
			(type default)
		)
		(layer "B.Cu")
	)
	(gr_line
		(start 116.457984 -113.924842)
		(end 117.018308 -114.036856)
		(stroke
			(width 0.127)
			(type default)
		)
		(layer "B.Cu")
	)
	(gr_line
		(start 116.468652 -114.050064)
		(end 116.961158 -114.148616)
		(stroke
			(width 0.05715)
			(type default)
		)
		(layer "B.Cu")
	)
	(gr_line
		(start 116.484654 -113.804446)
		(end 116.615972 -113.716816)
		(stroke
			(width 0.05715)
			(type default)
		)
		(layer "B.Cu")
	)
	(gr_line
		(start 116.512086 -105.696766)
		(end 116.643912 -105.78465)
		(stroke
			(width 0.05715)
			(type default)
		)
		(layer "B.Cu")
	)
	(gr_line
		(start 116.543836 -106.796586)
		(end 116.675408 -106.88447)
		(stroke
			(width 0.05715)
			(type default)
		)
		(layer "B.Cu")
	)
	(gr_line
		(start 116.615972 -113.716816)
		(end 116.952268 -113.784126)
		(stroke
			(width 0.05715)
			(type default)
		)
		(layer "B.Cu")
	)
	(gr_line
		(start 116.661692 -116.472208)
		(end 116.6749 -116.469668)
		(stroke
			(width 0.05715)
			(type default)
		)
		(layer "B.Cu")
	)
	(gr_line
		(start 116.6749 -116.469668)
		(end 116.688108 -116.472208)
		(stroke
			(width 0.05715)
			(type default)
		)
		(layer "B.Cu")
	)
	(gr_line
		(start 116.849144 -117.788182)
		(end 116.862352 -117.785642)
		(stroke
			(width 0.05715)
			(type default)
		)
		(layer "B.Cu")
	)
	(gr_line
		(start 116.862352 -117.785642)
		(end 116.87556 -117.788182)
		(stroke
			(width 0.05715)
			(type default)
		)
		(layer "B.Cu")
	)
	(gr_line
		(start 116.89588 -104.566466)
		(end 116.984526 -104.435402)
		(stroke
			(width 0.05715)
			(type default)
		)
		(layer "B.Cu")
	)
	(gr_line
		(start 116.952268 -113.784126)
		(end 117.039898 -113.915698)
		(stroke
			(width 0.05715)
			(type default)
		)
		(layer "B.Cu")
	)
	(gr_line
		(start 116.973858 -104.799638)
		(end 117.468142 -104.70388)
		(stroke
			(width 0.05715)
			(type default)
		)
		(layer "B.Cu")
	)
	(gr_line
		(start 116.984526 -104.435402)
		(end 117.321076 -104.36987)
		(stroke
			(width 0.05715)
			(type default)
		)
		(layer "B.Cu")
	)
	(gr_line
		(start 116.985034 -105.716324)
		(end 117.072664 -105.584752)
		(stroke
			(width 0.05715)
			(type default)
		)
		(layer "B.Cu")
	)
	(gr_line
		(start 117.004592 -120.180354)
		(end 117.017546 -120.177814)
		(stroke
			(width 0.05715)
			(type default)
		)
		(layer "B.Cu")
	)
	(gr_line
		(start 117.014752 -118.995698)
		(end 117.02796 -118.993158)
		(stroke
			(width 0.05715)
			(type default)
		)
		(layer "B.Cu")
	)
	(gr_line
		(start 117.017546 -120.177814)
		(end 117.0305 -120.180354)
		(stroke
			(width 0.05715)
			(type default)
		)
		(layer "B.Cu")
	)
	(gr_line
		(start 117.018308 -114.036856)
		(end 117.354604 -114.104166)
		(stroke
			(width 0.127)
			(type default)
		)
		(layer "B.Cu")
	)
	(gr_line
		(start 117.02796 -118.993158)
		(end 117.041168 -118.995698)
		(stroke
			(width 0.05715)
			(type default)
		)
		(layer "B.Cu")
	)
	(gr_line
		(start 117.063774 -105.949496)
		(end 117.559074 -105.850436)
		(stroke
			(width 0.05715)
			(type default)
		)
		(layer "B.Cu")
	)
	(gr_line
		(start 117.072664 -105.584752)
		(end 117.408706 -105.517442)
		(stroke
			(width 0.05715)
			(type default)
		)
		(layer "B.Cu")
	)
	(gr_line
		(start 117.082062 -121.34977)
		(end 117.09527 -121.34723)
		(stroke
			(width 0.05715)
			(type default)
		)
		(layer "B.Cu")
	)
	(gr_line
		(start 117.09527 -121.34723)
		(end 117.108478 -121.34977)
		(stroke
			(width 0.05715)
			(type default)
		)
		(layer "B.Cu")
	)
	(gr_line
		(start 117.321076 -104.36987)
		(end 117.45214 -104.458516)
		(stroke
			(width 0.05715)
			(type default)
		)
		(layer "B.Cu")
	)
	(gr_line
		(start 117.354604 -114.104166)
		(end 117.914928 -114.21618)
		(stroke
			(width 0.127)
			(type default)
		)
		(layer "B.Cu")
	)
	(gr_line
		(start 117.365272 -114.229388)
		(end 117.857778 -114.32794)
		(stroke
			(width 0.05715)
			(type default)
		)
		(layer "B.Cu")
	)
	(gr_line
		(start 117.381274 -113.98377)
		(end 117.512592 -113.89614)
		(stroke
			(width 0.05715)
			(type default)
		)
		(layer "B.Cu")
	)
	(gr_line
		(start 117.408706 -105.517442)
		(end 117.540532 -105.605326)
		(stroke
			(width 0.05715)
			(type default)
		)
		(layer "B.Cu")
	)
	(gr_line
		(start 117.463824 -107.880658)
		(end 117.551708 -107.749086)
		(stroke
			(width 0.05715)
			(type default)
		)
		(layer "B.Cu")
	)
	(gr_line
		(start 117.512592 -113.89614)
		(end 117.848888 -113.96345)
		(stroke
			(width 0.05715)
			(type default)
		)
		(layer "B.Cu")
	)
	(gr_line
		(start 117.52961 -122.583448)
		(end 117.54231 -122.580908)
		(stroke
			(width 0.05715)
			(type default)
		)
		(layer "B.Cu")
	)
	(gr_line
		(start 117.54231 -122.580908)
		(end 117.542818 -122.580908)
		(stroke
			(width 0.05715)
			(type default)
		)
		(layer "B.Cu")
	)
	(gr_line
		(start 117.542818 -122.580908)
		(end 117.556026 -122.583448)
		(stroke
			(width 0.05715)
			(type default)
		)
		(layer "B.Cu")
	)
	(gr_line
		(start 117.542818 -108.113576)
		(end 118.035578 -108.015532)
		(stroke
			(width 0.05715)
			(type default)
		)
		(layer "B.Cu")
	)
	(gr_line
		(start 117.551708 -107.749086)
		(end 117.888004 -107.682284)
		(stroke
			(width 0.05715)
			(type default)
		)
		(layer "B.Cu")
	)
	(gr_line
		(start 117.848888 -113.96345)
		(end 117.936518 -114.095022)
		(stroke
			(width 0.05715)
			(type default)
		)
		(layer "B.Cu")
	)
	(gr_line
		(start 117.881654 -105.537254)
		(end 117.969284 -105.405428)
		(stroke
			(width 0.05715)
			(type default)
		)
		(layer "B.Cu")
	)
	(gr_line
		(start 117.888004 -107.682284)
		(end 118.019576 -107.770168)
		(stroke
			(width 0.05715)
			(type default)
		)
		(layer "B.Cu")
	)
	(gr_line
		(start 117.912642 -106.638344)
		(end 118.000272 -106.507026)
		(stroke
			(width 0.05715)
			(type default)
		)
		(layer "B.Cu")
	)
	(gr_line
		(start 117.914928 -114.21618)
		(end 118.251224 -114.28349)
		(stroke
			(width 0.127)
			(type default)
		)
		(layer "B.Cu")
	)
	(gr_line
		(start 117.96141 -105.769664)
		(end 118.4529 -105.67162)
		(stroke
			(width 0.05715)
			(type default)
		)
		(layer "B.Cu")
	)
	(gr_line
		(start 117.969284 -105.405428)
		(end 118.30558 -105.338118)
		(stroke
			(width 0.05715)
			(type default)
		)
		(layer "B.Cu")
	)
	(gr_line
		(start 117.992398 -106.871008)
		(end 118.485158 -106.773218)
		(stroke
			(width 0.05715)
			(type default)
		)
		(layer "B.Cu")
	)
	(gr_line
		(start 117.997732 -119.43334)
		(end 118.491762 -119.532146)
		(stroke
			(width 0.05715)
			(type default)
		)
		(layer "B.Cu")
	)
	(gr_line
		(start 118.000272 -106.507026)
		(end 118.336568 -106.440224)
		(stroke
			(width 0.05715)
			(type default)
		)
		(layer "B.Cu")
	)
	(gr_line
		(start 118.013988 -119.187722)
		(end 118.145814 -119.100092)
		(stroke
			(width 0.05715)
			(type default)
		)
		(layer "B.Cu")
	)
	(gr_line
		(start 118.145814 -119.100092)
		(end 118.48211 -119.167402)
		(stroke
			(width 0.05715)
			(type default)
		)
		(layer "B.Cu")
	)
	(gr_line
		(start 118.251224 -114.28349)
		(end 118.811294 -114.39525)
		(stroke
			(width 0.127)
			(type default)
		)
		(layer "B.Cu")
	)
	(gr_line
		(start 118.261892 -114.408712)
		(end 118.754398 -114.507264)
		(stroke
			(width 0.05715)
			(type default)
		)
		(layer "B.Cu")
	)
	(gr_line
		(start 118.277894 -114.163094)
		(end 118.409212 -114.075464)
		(stroke
			(width 0.05715)
			(type default)
		)
		(layer "B.Cu")
	)
	(gr_line
		(start 118.30558 -105.338118)
		(end 118.437152 -105.426002)
		(stroke
			(width 0.05715)
			(type default)
		)
		(layer "B.Cu")
	)
	(gr_line
		(start 118.336568 -106.440224)
		(end 118.46814 -106.527854)
		(stroke
			(width 0.05715)
			(type default)
		)
		(layer "B.Cu")
	)
	(gr_line
		(start 118.360952 -107.70235)
		(end 118.448582 -107.570778)
		(stroke
			(width 0.05715)
			(type default)
		)
		(layer "B.Cu")
	)
	(gr_line
		(start 118.409212 -114.075464)
		(end 118.745508 -114.142774)
		(stroke
			(width 0.05715)
			(type default)
		)
		(layer "B.Cu")
	)
	(gr_line
		(start 118.439946 -107.935014)
		(end 118.932706 -107.837224)
		(stroke
			(width 0.05715)
			(type default)
		)
		(layer "B.Cu")
	)
	(gr_line
		(start 118.448582 -107.570778)
		(end 118.784878 -107.503722)
		(stroke
			(width 0.05715)
			(type default)
		)
		(layer "B.Cu")
	)
	(gr_line
		(start 118.48211 -119.167402)
		(end 118.569994 -119.298974)
		(stroke
			(width 0.05715)
			(type default)
		)
		(layer "B.Cu")
	)
	(gr_line
		(start 118.579646 -104.242108)
		(end 118.601236 -104.238044)
		(stroke
			(width 0.04445)
			(type default)
		)
		(layer "B.Cu")
	)
	(gr_line
		(start 118.601236 -104.238044)
		(end 118.627906 -104.256332)
		(stroke
			(width 0.04445)
			(type default)
		)
		(layer "B.Cu")
	)
	(gr_line
		(start 118.62562 -104.47909)
		(end 118.64721 -104.475026)
		(stroke
			(width 0.04445)
			(type default)
		)
		(layer "B.Cu")
	)
	(gr_line
		(start 118.64721 -104.475026)
		(end 118.665498 -104.447848)
		(stroke
			(width 0.04445)
			(type default)
		)
		(layer "B.Cu")
	)
	(gr_line
		(start 118.745508 -114.142774)
		(end 118.833138 -114.274346)
		(stroke
			(width 0.05715)
			(type default)
		)
		(layer "B.Cu")
	)
	(gr_line
		(start 118.757446 -111.926878)
		(end 119.249698 -111.829088)
		(stroke
			(width 0.05715)
			(type default)
		)
		(layer "B.Cu")
	)
	(gr_line
		(start 118.77294 -112.172496)
		(end 118.904512 -112.260126)
		(stroke
			(width 0.05715)
			(type default)
		)
		(layer "B.Cu")
	)
	(gr_line
		(start 118.77802 -105.35793)
		(end 118.865904 -105.226104)
		(stroke
			(width 0.05715)
			(type default)
		)
		(layer "B.Cu")
	)
	(gr_line
		(start 118.784878 -107.503722)
		(end 118.91645 -107.59186)
		(stroke
			(width 0.05715)
			(type default)
		)
		(layer "B.Cu")
	)
	(gr_line
		(start 118.809262 -106.460036)
		(end 118.897146 -106.328718)
		(stroke
			(width 0.05715)
			(type default)
		)
		(layer "B.Cu")
	)
	(gr_line
		(start 118.811294 -114.39525)
		(end 123.042172 -115.241578)
		(stroke
			(width 0.127)
			(type default)
		)
		(layer "B.Cu")
	)
	(gr_line
		(start 118.857268 -105.590594)
		(end 119.350028 -105.492296)
		(stroke
			(width 0.05715)
			(type default)
		)
		(layer "B.Cu")
	)
	(gr_line
		(start 118.865904 -105.226104)
		(end 119.2022 -105.159048)
		(stroke
			(width 0.05715)
			(type default)
		)
		(layer "B.Cu")
	)
	(gr_line
		(start 118.888002 -106.693208)
		(end 119.380762 -106.595164)
		(stroke
			(width 0.05715)
			(type default)
		)
		(layer "B.Cu")
	)
	(gr_line
		(start 118.894606 -119.612664)
		(end 119.388128 -119.71147)
		(stroke
			(width 0.05715)
			(type default)
		)
		(layer "B.Cu")
	)
	(gr_line
		(start 118.897146 -106.328718)
		(end 119.233442 -106.261662)
		(stroke
			(width 0.05715)
			(type default)
		)
		(layer "B.Cu")
	)
	(gr_line
		(start 118.904512 -112.260126)
		(end 119.241062 -112.193324)
		(stroke
			(width 0.05715)
			(type default)
		)
		(layer "B.Cu")
	)
	(gr_line
		(start 118.910608 -119.367046)
		(end 119.042434 -119.279416)
		(stroke
			(width 0.05715)
			(type default)
		)
		(layer "B.Cu")
	)
	(gr_line
		(start 119.042434 -119.279416)
		(end 119.37873 -119.346726)
		(stroke
			(width 0.05715)
			(type default)
		)
		(layer "B.Cu")
	)
	(gr_line
		(start 119.2022 -105.159048)
		(end 119.333772 -105.246932)
		(stroke
			(width 0.05715)
			(type default)
		)
		(layer "B.Cu")
	)
	(gr_line
		(start 119.233442 -106.261662)
		(end 119.36476 -106.349546)
		(stroke
			(width 0.05715)
			(type default)
		)
		(layer "B.Cu")
	)
	(gr_line
		(start 119.241062 -112.193324)
		(end 119.328692 -112.061752)
		(stroke
			(width 0.05715)
			(type default)
		)
		(layer "B.Cu")
	)
	(gr_line
		(start 119.257572 -107.523788)
		(end 119.345456 -107.39247)
		(stroke
			(width 0.05715)
			(type default)
		)
		(layer "B.Cu")
	)
	(gr_line
		(start 119.337074 -107.756706)
		(end 119.828564 -107.658916)
		(stroke
			(width 0.05715)
			(type default)
		)
		(layer "B.Cu")
	)
	(gr_line
		(start 119.345456 -107.39247)
		(end 119.681752 -107.325414)
		(stroke
			(width 0.05715)
			(type default)
		)
		(layer "B.Cu")
	)
	(gr_line
		(start 119.37873 -119.346726)
		(end 119.466614 -119.478298)
		(stroke
			(width 0.05715)
			(type default)
		)
		(layer "B.Cu")
	)
	(gr_line
		(start 119.555768 -104.225598)
		(end 119.577104 -104.22001)
		(stroke
			(width 0.04445)
			(type default)
		)
		(layer "B.Cu")
	)
	(gr_line
		(start 119.653558 -111.74857)
		(end 120.146572 -111.650526)
		(stroke
			(width 0.05715)
			(type default)
		)
		(layer "B.Cu")
	)
	(gr_line
		(start 119.669814 -111.993934)
		(end 119.801386 -112.081818)
		(stroke
			(width 0.05715)
			(type default)
		)
		(layer "B.Cu")
	)
	(gr_line
		(start 119.681752 -107.325414)
		(end 119.81307 -107.413298)
		(stroke
			(width 0.05715)
			(type default)
		)
		(layer "B.Cu")
	)
	(gr_line
		(start 119.752872 -105.411778)
		(end 119.791988 -105.403904)
		(stroke
			(width 0.05715)
			(type default)
		)
		(layer "B.Cu")
	)
	(gr_line
		(start 119.801386 -112.081818)
		(end 120.137682 -112.015016)
		(stroke
			(width 0.05715)
			(type default)
		)
		(layer "B.Cu")
	)
	(gr_line
		(start 120.137682 -112.015016)
		(end 120.22582 -111.883444)
		(stroke
			(width 0.05715)
			(type default)
		)
		(layer "B.Cu")
	)
	(gr_line
		(start 120.154192 -107.34548)
		(end 120.24233 -107.213908)
		(stroke
			(width 0.05715)
			(type default)
		)
		(layer "B.Cu")
	)
	(gr_line
		(start 120.204738 -103.595678)
		(end 120.32361 -103.595678)
		(stroke
			(width 0.04445)
			(type default)
		)
		(layer "B.Cu")
	)
	(gr_line
		(start 120.21947 -106.18216)
		(end 120.24106 -106.177842)
		(stroke
			(width 0.04445)
			(type default)
		)
		(layer "B.Cu")
	)
	(gr_line
		(start 120.232424 -107.578652)
		(end 120.727724 -107.4801)
		(stroke
			(width 0.05715)
			(type default)
		)
		(layer "B.Cu")
	)
	(gr_line
		(start 120.24106 -106.177842)
		(end 120.267476 -106.195622)
		(stroke
			(width 0.04445)
			(type default)
		)
		(layer "B.Cu")
	)
	(gr_line
		(start 120.24233 -107.213908)
		(end 120.578626 -107.147106)
		(stroke
			(width 0.05715)
			(type default)
		)
		(layer "B.Cu")
	)
	(gr_line
		(start 120.26646 -106.418888)
		(end 120.28805 -106.41457)
		(stroke
			(width 0.04445)
			(type default)
		)
		(layer "B.Cu")
	)
	(gr_line
		(start 120.28805 -106.41457)
		(end 120.306338 -106.387392)
		(stroke
			(width 0.04445)
			(type default)
		)
		(layer "B.Cu")
	)
	(gr_line
		(start 120.32361 -103.595678)
		(end 120.449594 -103.469694)
		(stroke
			(width 0.04445)
			(type default)
		)
		(layer "B.Cu")
	)
	(gr_line
		(start 120.449594 -103.350822)
		(end 120.449594 -103.469694)
		(stroke
			(width 0.04445)
			(type default)
		)
		(layer "B.Cu")
	)
	(gr_line
		(start 120.54967 -111.570516)
		(end 121.044462 -111.471964)
		(stroke
			(width 0.05715)
			(type default)
		)
		(layer "B.Cu")
	)
	(gr_line
		(start 120.566688 -111.815626)
		(end 120.69826 -111.90351)
		(stroke
			(width 0.05715)
			(type default)
		)
		(layer "B.Cu")
	)
	(gr_line
		(start 120.578372 -103.222044)
		(end 120.697244 -103.222044)
		(stroke
			(width 0.04445)
			(type default)
		)
		(layer "B.Cu")
	)
	(gr_line
		(start 120.578626 -107.147106)
		(end 120.710198 -107.23499)
		(stroke
			(width 0.05715)
			(type default)
		)
		(layer "B.Cu")
	)
	(gr_line
		(start 120.606566 -104.24795)
		(end 120.62206 -104.232456)
		(stroke
			(width 0.04445)
			(type default)
		)
		(layer "B.Cu")
	)
	(gr_line
		(start 120.62206 -104.232456)
		(end 120.65762 -104.232456)
		(stroke
			(width 0.04445)
			(type default)
		)
		(layer "B.Cu")
	)
	(gr_line
		(start 120.669304 -106.312716)
		(end 120.696228 -106.307382)
		(stroke
			(width 0.04445)
			(type default)
		)
		(layer "B.Cu")
	)
	(gr_line
		(start 120.697244 -103.222044)
		(end 120.823228 -103.09606)
		(stroke
			(width 0.04445)
			(type default)
		)
		(layer "B.Cu")
	)
	(gr_line
		(start 120.69826 -111.90351)
		(end 121.034556 -111.836708)
		(stroke
			(width 0.05715)
			(type default)
		)
		(layer "B.Cu")
	)
	(gr_line
		(start 120.777254 -104.418638)
		(end 120.785382 -104.41051)
		(stroke
			(width 0.04445)
			(type default)
		)
		(layer "B.Cu")
	)
	(gr_line
		(start 120.785128 -104.37749)
		(end 120.785382 -104.39527)
		(stroke
			(width 0.04445)
			(type default)
		)
		(layer "B.Cu")
	)
	(gr_line
		(start 120.785382 -104.39527)
		(end 120.785382 -104.41051)
		(stroke
			(width 0.04445)
			(type default)
		)
		(layer "B.Cu")
	)
	(gr_line
		(start 120.823228 -102.977188)
		(end 120.823228 -103.09606)
		(stroke
			(width 0.04445)
			(type default)
		)
		(layer "B.Cu")
	)
	(gr_line
		(start 120.952006 -102.84841)
		(end 121.070878 -102.84841)
		(stroke
			(width 0.04445)
			(type default)
		)
		(layer "B.Cu")
	)
	(gr_line
		(start 121.034556 -111.836708)
		(end 121.122694 -111.705136)
		(stroke
			(width 0.05715)
			(type default)
		)
		(layer "B.Cu")
	)
	(gr_line
		(start 121.070878 -102.84841)
		(end 121.196862 -102.722426)
		(stroke
			(width 0.04445)
			(type default)
		)
		(layer "B.Cu")
	)
	(gr_line
		(start 121.11101 -105.622852)
		(end 121.201688 -105.532174)
		(stroke
			(width 0.04445)
			(type default)
		)
		(layer "B.Cu")
	)
	(gr_line
		(start 121.112788 -105.894124)
		(end 121.23166 -105.89387)
		(stroke
			(width 0.04445)
			(type default)
		)
		(layer "B.Cu")
	)
	(gr_line
		(start 121.13006 -107.40009)
		(end 121.16816 -107.39247)
		(stroke
			(width 0.05715)
			(type default)
		)
		(layer "B.Cu")
	)
	(gr_line
		(start 121.196862 -102.603554)
		(end 121.196862 -102.722426)
		(stroke
			(width 0.04445)
			(type default)
		)
		(layer "B.Cu")
	)
	(gr_line
		(start 121.23166 -105.89387)
		(end 121.357644 -105.767886)
		(stroke
			(width 0.04445)
			(type default)
		)
		(layer "B.Cu")
	)
	(gr_line
		(start 121.32564 -102.474776)
		(end 121.444512 -102.474776)
		(stroke
			(width 0.04445)
			(type default)
		)
		(layer "B.Cu")
	)
	(gr_line
		(start 121.357644 -105.649268)
		(end 121.357644 -105.767886)
		(stroke
			(width 0.04445)
			(type default)
		)
		(layer "B.Cu")
	)
	(gr_line
		(start 121.37009 -105.363772)
		(end 121.59615 -105.137712)
		(stroke
			(width 0.04445)
			(type default)
		)
		(layer "B.Cu")
	)
	(gr_line
		(start 121.444512 -102.474776)
		(end 121.570496 -102.348792)
		(stroke
			(width 0.04445)
			(type default)
		)
		(layer "B.Cu")
	)
	(gr_line
		(start 121.486676 -105.520236)
		(end 121.626376 -105.520236)
		(stroke
			(width 0.04445)
			(type default)
		)
		(layer "B.Cu")
	)
	(gr_line
		(start 121.570496 -102.22992)
		(end 121.570496 -102.348792)
		(stroke
			(width 0.04445)
			(type default)
		)
		(layer "B.Cu")
	)
	(gr_line
		(start 121.57456 -106.644694)
		(end 121.590054 -106.6292)
		(stroke
			(width 0.04445)
			(type default)
		)
		(layer "B.Cu")
	)
	(gr_line
		(start 121.590054 -106.6292)
		(end 121.625614 -106.6292)
		(stroke
			(width 0.04445)
			(type default)
		)
		(layer "B.Cu")
	)
	(gr_line
		(start 121.626376 -105.520236)
		(end 121.752106 -105.394506)
		(stroke
			(width 0.04445)
			(type default)
		)
		(layer "B.Cu")
	)
	(gr_line
		(start 121.67108 -108.27893)
		(end 121.70918 -108.27131)
		(stroke
			(width 0.05715)
			(type default)
		)
		(layer "B.Cu")
	)
	(gr_line
		(start 121.699274 -102.101142)
		(end 121.839228 -102.101142)
		(stroke
			(width 0.04445)
			(type default)
		)
		(layer "B.Cu")
	)
	(gr_line
		(start 121.745248 -106.815382)
		(end 121.760742 -106.799888)
		(stroke
			(width 0.04445)
			(type default)
		)
		(layer "B.Cu")
	)
	(gr_line
		(start 121.752106 -105.254806)
		(end 121.752106 -105.394506)
		(stroke
			(width 0.04445)
			(type default)
		)
		(layer "B.Cu")
	)
	(gr_line
		(start 121.760742 -106.76382)
		(end 121.760742 -106.799888)
		(stroke
			(width 0.04445)
			(type default)
		)
		(layer "B.Cu")
	)
	(gr_line
		(start 121.764552 -104.96931)
		(end 121.990612 -104.74325)
		(stroke
			(width 0.04445)
			(type default)
		)
		(layer "B.Cu")
	)
	(gr_line
		(start 121.83745 -103.052626)
		(end 122.06351 -102.826566)
		(stroke
			(width 0.04445)
			(type default)
		)
		(layer "B.Cu")
	)
	(gr_line
		(start 121.839228 -102.101142)
		(end 121.964958 -101.975412)
		(stroke
			(width 0.04445)
			(type default)
		)
		(layer "B.Cu")
	)
	(gr_line
		(start 121.881138 -105.125774)
		(end 122.020838 -105.125774)
		(stroke
			(width 0.04445)
			(type default)
		)
		(layer "B.Cu")
	)
	(gr_line
		(start 121.954036 -103.20909)
		(end 122.093736 -103.20909)
		(stroke
			(width 0.04445)
			(type default)
		)
		(layer "B.Cu")
	)
	(gr_line
		(start 121.964958 -101.835458)
		(end 121.964958 -101.975412)
		(stroke
			(width 0.04445)
			(type default)
		)
		(layer "B.Cu")
	)
	(gr_line
		(start 121.991882 -109.36859)
		(end 122.029982 -109.36097)
		(stroke
			(width 0.05715)
			(type default)
		)
		(layer "B.Cu")
	)
	(gr_line
		(start 122.01779 -119.063008)
		(end 122.030998 -119.065548)
		(stroke
			(width 0.05715)
			(type default)
		)
		(layer "B.Cu")
	)
	(gr_line
		(start 122.020838 -105.125774)
		(end 122.146568 -105.000044)
		(stroke
			(width 0.04445)
			(type default)
		)
		(layer "B.Cu")
	)
	(gr_line
		(start 122.030998 -119.065548)
		(end 122.044206 -119.063008)
		(stroke
			(width 0.05715)
			(type default)
		)
		(layer "B.Cu")
	)
	(gr_line
		(start 122.093736 -103.20909)
		(end 122.219466 -103.08336)
		(stroke
			(width 0.04445)
			(type default)
		)
		(layer "B.Cu")
	)
	(gr_line
		(start 122.093736 -101.70668)
		(end 122.23369 -101.70668)
		(stroke
			(width 0.04445)
			(type default)
		)
		(layer "B.Cu")
	)
	(gr_line
		(start 122.146568 -104.860344)
		(end 122.146568 -105.000044)
		(stroke
			(width 0.04445)
			(type default)
		)
		(layer "B.Cu")
	)
	(gr_line
		(start 122.159014 -104.574848)
		(end 122.385074 -104.348788)
		(stroke
			(width 0.04445)
			(type default)
		)
		(layer "B.Cu")
	)
	(gr_line
		(start 122.219466 -102.94366)
		(end 122.219466 -103.08336)
		(stroke
			(width 0.04445)
			(type default)
		)
		(layer "B.Cu")
	)
	(gr_line
		(start 122.231912 -102.658164)
		(end 122.457972 -102.432104)
		(stroke
			(width 0.04445)
			(type default)
		)
		(layer "B.Cu")
	)
	(gr_line
		(start 122.23369 -101.70668)
		(end 122.35942 -101.58095)
		(stroke
			(width 0.04445)
			(type default)
		)
		(layer "B.Cu")
	)
	(gr_line
		(start 122.2756 -104.731312)
		(end 122.4153 -104.731312)
		(stroke
			(width 0.04445)
			(type default)
		)
		(layer "B.Cu")
	)
	(gr_line
		(start 122.278394 -110.48746)
		(end 122.316494 -110.47984)
		(stroke
			(width 0.05715)
			(type default)
		)
		(layer "B.Cu")
	)
	(gr_line
		(start 122.338338 -117.848126)
		(end 122.351546 -117.850666)
		(stroke
			(width 0.05715)
			(type default)
		)
		(layer "B.Cu")
	)
	(gr_line
		(start 122.348498 -102.814628)
		(end 122.488198 -102.814628)
		(stroke
			(width 0.04445)
			(type default)
		)
		(layer "B.Cu")
	)
	(gr_line
		(start 122.351546 -117.850666)
		(end 122.364754 -117.848126)
		(stroke
			(width 0.05715)
			(type default)
		)
		(layer "B.Cu")
	)
	(gr_line
		(start 122.35942 -101.440996)
		(end 122.35942 -101.58095)
		(stroke
			(width 0.04445)
			(type default)
		)
		(layer "B.Cu")
	)
	(gr_line
		(start 122.4153 -104.731312)
		(end 122.54103 -104.605582)
		(stroke
			(width 0.04445)
			(type default)
		)
		(layer "B.Cu")
	)
	(gr_line
		(start 122.42673 -122.659648)
		(end 122.439938 -122.657108)
		(stroke
			(width 0.05715)
			(type default)
		)
		(layer "B.Cu")
	)
	(gr_line
		(start 122.488198 -102.814628)
		(end 122.613928 -102.688898)
		(stroke
			(width 0.04445)
			(type default)
		)
		(layer "B.Cu")
	)
	(gr_line
		(start 122.488198 -101.312218)
		(end 122.628152 -101.312218)
		(stroke
			(width 0.04445)
			(type default)
		)
		(layer "B.Cu")
	)
	(gr_line
		(start 122.54103 -104.465882)
		(end 122.54103 -104.605582)
		(stroke
			(width 0.04445)
			(type default)
		)
		(layer "B.Cu")
	)
	(gr_line
		(start 122.553476 -104.180386)
		(end 122.758708 -103.975154)
		(stroke
			(width 0.04445)
			(type default)
		)
		(layer "B.Cu")
	)
	(gr_line
		(start 122.606816 -120.355106)
		(end 122.620024 -120.357646)
		(stroke
			(width 0.05715)
			(type default)
		)
		(layer "B.Cu")
	)
	(gr_line
		(start 122.613928 -102.549198)
		(end 122.613928 -102.688898)
		(stroke
			(width 0.04445)
			(type default)
		)
		(layer "B.Cu")
	)
	(gr_line
		(start 122.620024 -120.357646)
		(end 122.633232 -120.355106)
		(stroke
			(width 0.05715)
			(type default)
		)
		(layer "B.Cu")
	)
	(gr_line
		(start 122.626374 -102.263702)
		(end 122.852434 -102.037642)
		(stroke
			(width 0.04445)
			(type default)
		)
		(layer "B.Cu")
	)
	(gr_line
		(start 122.628152 -101.312218)
		(end 122.753882 -101.186488)
		(stroke
			(width 0.04445)
			(type default)
		)
		(layer "B.Cu")
	)
	(gr_line
		(start 122.670062 -104.33685)
		(end 122.78868 -104.33685)
		(stroke
			(width 0.04445)
			(type default)
		)
		(layer "B.Cu")
	)
	(gr_line
		(start 122.70486 -121.561098)
		(end 122.71756 -121.563638)
		(stroke
			(width 0.05715)
			(type default)
		)
		(layer "B.Cu")
	)
	(gr_line
		(start 122.710194 -123.861068)
		(end 122.723402 -123.863608)
		(stroke
			(width 0.05715)
			(type default)
		)
		(layer "B.Cu")
	)
	(gr_line
		(start 122.71756 -121.563638)
		(end 122.730514 -121.561098)
		(stroke
			(width 0.05715)
			(type default)
		)
		(layer "B.Cu")
	)
	(gr_line
		(start 122.723402 -123.863608)
		(end 122.73661 -123.861068)
		(stroke
			(width 0.05715)
			(type default)
		)
		(layer "B.Cu")
	)
	(gr_line
		(start 122.74296 -102.420166)
		(end 122.88266 -102.420166)
		(stroke
			(width 0.04445)
			(type default)
		)
		(layer "B.Cu")
	)
	(gr_line
		(start 122.753882 -101.046534)
		(end 122.753882 -101.186488)
		(stroke
			(width 0.04445)
			(type default)
		)
		(layer "B.Cu")
	)
	(gr_line
		(start 122.765058 -105.76306)
		(end 122.901964 -105.76306)
		(stroke
			(width 0.04445)
			(type default)
		)
		(layer "B.Cu")
	)
	(gr_line
		(start 122.78868 -104.33685)
		(end 122.914664 -104.210866)
		(stroke
			(width 0.04445)
			(type default)
		)
		(layer "B.Cu")
	)
	(gr_line
		(start 122.88266 -102.420166)
		(end 123.00839 -102.294436)
		(stroke
			(width 0.04445)
			(type default)
		)
		(layer "B.Cu")
	)
	(gr_line
		(start 122.901964 -105.76306)
		(end 123.027694 -105.63733)
		(stroke
			(width 0.04445)
			(type default)
		)
		(layer "B.Cu")
	)
	(gr_line
		(start 122.914664 -104.092248)
		(end 122.914664 -104.210866)
		(stroke
			(width 0.04445)
			(type default)
		)
		(layer "B.Cu")
	)
	(gr_line
		(start 122.92711 -103.806752)
		(end 123.017026 -103.716836)
		(stroke
			(width 0.04445)
			(type default)
		)
		(layer "B.Cu")
	)
	(gr_line
		(start 122.958352 -120.041416)
		(end 123.045982 -119.909844)
		(stroke
			(width 0.05715)
			(type default)
		)
		(layer "B.Cu")
	)
	(gr_line
		(start 122.986546 -111.33201)
		(end 123.024646 -111.32439)
		(stroke
			(width 0.05715)
			(type default)
		)
		(layer "B.Cu")
	)
	(gr_line
		(start 122.988832 -116.525548)
		(end 123.00204 -116.528088)
		(stroke
			(width 0.05715)
			(type default)
		)
		(layer "B.Cu")
	)
	(gr_line
		(start 123.00204 -116.528088)
		(end 123.015248 -116.525548)
		(stroke
			(width 0.05715)
			(type default)
		)
		(layer "B.Cu")
	)
	(gr_line
		(start 123.00839 -102.154736)
		(end 123.00839 -102.294436)
		(stroke
			(width 0.04445)
			(type default)
		)
		(layer "B.Cu")
	)
	(gr_line
		(start 123.020836 -101.86924)
		(end 123.13158 -101.758496)
		(stroke
			(width 0.04445)
			(type default)
		)
		(layer "B.Cu")
	)
	(gr_line
		(start 123.024646 -111.32439)
		(end 123.052078 -111.296958)
		(stroke
			(width 0.05715)
			(type default)
		)
		(layer "B.Cu")
	)
	(gr_line
		(start 123.027694 -105.500424)
		(end 123.027694 -105.63733)
		(stroke
			(width 0.04445)
			(type default)
		)
		(layer "B.Cu")
	)
	(gr_line
		(start 123.037092 -120.274334)
		(end 123.529852 -120.175782)
		(stroke
			(width 0.05715)
			(type default)
		)
		(layer "B.Cu")
	)
	(gr_line
		(start 123.042172 -115.241578)
		(end 123.089416 -115.241832)
		(stroke
			(width 0.127)
			(type default)
		)
		(layer "B.Cu")
	)
	(gr_line
		(start 123.043696 -103.963216)
		(end 123.162314 -103.963216)
		(stroke
			(width 0.04445)
			(type default)
		)
		(layer "B.Cu")
	)
	(gr_line
		(start 123.045982 -119.909844)
		(end 123.382278 -119.842534)
		(stroke
			(width 0.05715)
			(type default)
		)
		(layer "B.Cu")
	)
	(gr_line
		(start 123.053856 -115.367054)
		(end 123.066302 -115.369594)
		(stroke
			(width 0.05715)
			(type default)
		)
		(layer "B.Cu")
	)
	(gr_line
		(start 123.066302 -115.369594)
		(end 123.079002 -115.367054)
		(stroke
			(width 0.05715)
			(type default)
		)
		(layer "B.Cu")
	)
	(gr_line
		(start 123.089416 -115.241832)
		(end 128.73736 -114.11204)
		(stroke
			(width 0.127)
			(type default)
		)
		(layer "B.Cu")
	)
	(gr_line
		(start 123.137422 -102.025704)
		(end 123.277122 -102.025704)
		(stroke
			(width 0.04445)
			(type default)
		)
		(layer "B.Cu")
	)
	(gr_line
		(start 123.156726 -105.371392)
		(end 123.293632 -105.371392)
		(stroke
			(width 0.04445)
			(type default)
		)
		(layer "B.Cu")
	)
	(gr_line
		(start 123.162314 -103.963216)
		(end 123.288298 -103.837232)
		(stroke
			(width 0.04445)
			(type default)
		)
		(layer "B.Cu")
	)
	(gr_line
		(start 123.243086 -106.396028)
		(end 123.25858 -106.380534)
		(stroke
			(width 0.04445)
			(type default)
		)
		(layer "B.Cu")
	)
	(gr_line
		(start 123.25858 -106.380534)
		(end 123.29414 -106.380534)
		(stroke
			(width 0.04445)
			(type default)
		)
		(layer "B.Cu")
	)
	(gr_line
		(start 123.277122 -102.025704)
		(end 123.402852 -101.899974)
		(stroke
			(width 0.04445)
			(type default)
		)
		(layer "B.Cu")
	)
	(gr_line
		(start 123.288298 -103.718614)
		(end 123.288298 -103.837232)
		(stroke
			(width 0.04445)
			(type default)
		)
		(layer "B.Cu")
	)
	(gr_line
		(start 123.293632 -105.371392)
		(end 123.419362 -105.245662)
		(stroke
			(width 0.04445)
			(type default)
		)
		(layer "B.Cu")
	)
	(gr_line
		(start 123.382278 -119.842534)
		(end 123.513596 -119.930164)
		(stroke
			(width 0.05715)
			(type default)
		)
		(layer "B.Cu")
	)
	(gr_line
		(start 123.402852 -101.760274)
		(end 123.402852 -101.899974)
		(stroke
			(width 0.04445)
			(type default)
		)
		(layer "B.Cu")
	)
	(gr_line
		(start 123.413774 -106.566716)
		(end 123.429268 -106.551222)
		(stroke
			(width 0.04445)
			(type default)
		)
		(layer "B.Cu")
	)
	(gr_line
		(start 123.41733 -103.589582)
		(end 123.535948 -103.589582)
		(stroke
			(width 0.04445)
			(type default)
		)
		(layer "B.Cu")
	)
	(gr_line
		(start 123.419362 -105.108756)
		(end 123.419362 -105.245662)
		(stroke
			(width 0.04445)
			(type default)
		)
		(layer "B.Cu")
	)
	(gr_line
		(start 123.422918 -94.242636)
		(end 123.427744 -94.234)
		(stroke
			(width 0.04445)
			(type default)
		)
		(layer "B.Cu")
	)
	(gr_line
		(start 123.429268 -106.515154)
		(end 123.429268 -106.551222)
		(stroke
			(width 0.04445)
			(type default)
		)
		(layer "B.Cu")
	)
	(gr_line
		(start 123.535948 -103.589582)
		(end 123.661932 -103.463598)
		(stroke
			(width 0.04445)
			(type default)
		)
		(layer "B.Cu")
	)
	(gr_line
		(start 123.548394 -104.979724)
		(end 123.6853 -104.979724)
		(stroke
			(width 0.04445)
			(type default)
		)
		(layer "B.Cu")
	)
	(gr_line
		(start 123.583192 -95.337122)
		(end 123.588018 -95.328486)
		(stroke
			(width 0.04445)
			(type default)
		)
		(layer "B.Cu")
	)
	(gr_line
		(start 123.661932 -103.34498)
		(end 123.661932 -103.463598)
		(stroke
			(width 0.04445)
			(type default)
		)
		(layer "B.Cu")
	)
	(gr_line
		(start 123.6853 -104.979724)
		(end 123.81103 -104.853994)
		(stroke
			(width 0.04445)
			(type default)
		)
		(layer "B.Cu")
	)
	(gr_line
		(start 123.81103 -104.717088)
		(end 123.81103 -104.853994)
		(stroke
			(width 0.04445)
			(type default)
		)
		(layer "B.Cu")
	)
	(gr_line
		(start 123.854972 -119.862092)
		(end 123.942602 -119.73052)
		(stroke
			(width 0.05715)
			(type default)
		)
		(layer "B.Cu")
	)
	(gr_line
		(start 123.93295 -120.095264)
		(end 124.427234 -119.996204)
		(stroke
			(width 0.05715)
			(type default)
		)
		(layer "B.Cu")
	)
	(gr_line
		(start 123.940062 -104.588056)
		(end 124.076968 -104.588056)
		(stroke
			(width 0.04445)
			(type default)
		)
		(layer "B.Cu")
	)
	(gr_line
		(start 123.942602 -119.73052)
		(end 124.278898 -119.66321)
		(stroke
			(width 0.05715)
			(type default)
		)
		(layer "B.Cu")
	)
	(gr_arc
		(start 123.949206 -100.881688)
		(mid 123.950984 -100.881565)
		(end 123.952762 -100.881434)
		(stroke
			(width 0.04445)
			(type default)
		)
		(layer "B.Cu")
	)
	(gr_line
		(start 124.076968 -104.588056)
		(end 124.202698 -104.462326)
		(stroke
			(width 0.04445)
			(type default)
		)
		(layer "B.Cu")
	)
	(gr_line
		(start 124.202698 -104.32542)
		(end 124.202698 -104.462326)
		(stroke
			(width 0.04445)
			(type default)
		)
		(layer "B.Cu")
	)
	(gr_line
		(start 124.278898 -119.66321)
		(end 124.41047 -119.75084)
		(stroke
			(width 0.05715)
			(type default)
		)
		(layer "B.Cu")
	)
	(gr_line
		(start 124.281438 -95.328486)
		(end 124.286264 -95.337122)
		(stroke
			(width 0.04445)
			(type default)
		)
		(layer "B.Cu")
	)
	(gr_line
		(start 124.33173 -104.196388)
		(end 124.468636 -104.196388)
		(stroke
			(width 0.04445)
			(type default)
		)
		(layer "B.Cu")
	)
	(gr_line
		(start 124.441712 -100.1776)
		(end 124.446538 -100.186236)
		(stroke
			(width 0.04445)
			(type default)
		)
		(layer "B.Cu")
	)
	(gr_line
		(start 124.441712 -94.234)
		(end 124.446538 -94.242636)
		(stroke
			(width 0.04445)
			(type default)
		)
		(layer "B.Cu")
	)
	(gr_line
		(start 124.468636 -104.196388)
		(end 124.594366 -104.070658)
		(stroke
			(width 0.04445)
			(type default)
		)
		(layer "B.Cu")
	)
	(gr_line
		(start 124.594366 -103.933752)
		(end 124.594366 -104.070658)
		(stroke
			(width 0.04445)
			(type default)
		)
		(layer "B.Cu")
	)
	(gr_line
		(start 124.723398 -103.80472)
		(end 124.860304 -103.80472)
		(stroke
			(width 0.04445)
			(type default)
		)
		(layer "B.Cu")
	)
	(gr_line
		(start 124.751592 -119.682768)
		(end 124.839222 -119.551196)
		(stroke
			(width 0.05715)
			(type default)
		)
		(layer "B.Cu")
	)
	(gr_line
		(start 124.828808 -119.916194)
		(end 125.32487 -119.81688)
		(stroke
			(width 0.05715)
			(type default)
		)
		(layer "B.Cu")
	)
	(gr_line
		(start 124.839222 -119.551196)
		(end 125.175518 -119.483886)
		(stroke
			(width 0.05715)
			(type default)
		)
		(layer "B.Cu")
	)
	(gr_line
		(start 124.860304 -103.80472)
		(end 124.986034 -103.67899)
		(stroke
			(width 0.04445)
			(type default)
		)
		(layer "B.Cu")
	)
	(gr_line
		(start 124.876052 -106.173524)
		(end 124.891546 -106.15803)
		(stroke
			(width 0.04445)
			(type default)
		)
		(layer "B.Cu")
	)
	(gr_line
		(start 124.891546 -106.15803)
		(end 124.927106 -106.15803)
		(stroke
			(width 0.04445)
			(type default)
		)
		(layer "B.Cu")
	)
	(gr_line
		(start 124.986034 -103.542084)
		(end 124.986034 -103.67899)
		(stroke
			(width 0.04445)
			(type default)
		)
		(layer "B.Cu")
	)
	(gr_line
		(start 124.988066 -104.959658)
		(end 125.125226 -104.959658)
		(stroke
			(width 0.04445)
			(type default)
		)
		(layer "B.Cu")
	)
	(gr_line
		(start 125.04674 -106.344212)
		(end 125.062234 -106.328718)
		(stroke
			(width 0.04445)
			(type default)
		)
		(layer "B.Cu")
	)
	(gr_line
		(start 125.062234 -106.29265)
		(end 125.062234 -106.328718)
		(stroke
			(width 0.04445)
			(type default)
		)
		(layer "B.Cu")
	)
	(gr_line
		(start 125.115066 -103.413052)
		(end 125.251972 -103.413052)
		(stroke
			(width 0.04445)
			(type default)
		)
		(layer "B.Cu")
	)
	(gr_line
		(start 125.125226 -104.959658)
		(end 125.250956 -104.833928)
		(stroke
			(width 0.04445)
			(type default)
		)
		(layer "B.Cu")
	)
	(gr_line
		(start 125.139958 -100.186236)
		(end 125.144784 -100.1776)
		(stroke
			(width 0.04445)
			(type default)
		)
		(layer "B.Cu")
	)
	(gr_line
		(start 125.139958 -94.242636)
		(end 125.144784 -94.234)
		(stroke
			(width 0.04445)
			(type default)
		)
		(layer "B.Cu")
	)
	(gr_line
		(start 125.175518 -119.483886)
		(end 125.30709 -119.571516)
		(stroke
			(width 0.05715)
			(type default)
		)
		(layer "B.Cu")
	)
	(gr_line
		(start 125.250956 -104.696768)
		(end 125.250956 -104.833928)
		(stroke
			(width 0.04445)
			(type default)
		)
		(layer "B.Cu")
	)
	(gr_line
		(start 125.251972 -103.413052)
		(end 125.377702 -103.287322)
		(stroke
			(width 0.04445)
			(type default)
		)
		(layer "B.Cu")
	)
	(gr_line
		(start 125.300232 -95.337122)
		(end 125.305058 -95.328486)
		(stroke
			(width 0.04445)
			(type default)
		)
		(layer "B.Cu")
	)
	(gr_line
		(start 125.31471 -106.043476)
		(end 125.45187 -106.043476)
		(stroke
			(width 0.04445)
			(type default)
		)
		(layer "B.Cu")
	)
	(gr_line
		(start 125.372368 -101.788976)
		(end 125.382274 -101.806248)
		(stroke
			(width 0.04445)
			(type default)
		)
		(layer "B.Cu")
	)
	(gr_line
		(start 125.377702 -103.150416)
		(end 125.377702 -103.287322)
		(stroke
			(width 0.04445)
			(type default)
		)
		(layer "B.Cu")
	)
	(gr_line
		(start 125.379734 -104.56799)
		(end 125.516894 -104.56799)
		(stroke
			(width 0.04445)
			(type default)
		)
		(layer "B.Cu")
	)
	(gr_line
		(start 125.45187 -106.043476)
		(end 125.5776 -105.917746)
		(stroke
			(width 0.04445)
			(type default)
		)
		(layer "B.Cu")
	)
	(gr_line
		(start 125.506734 -103.021384)
		(end 125.64364 -103.021384)
		(stroke
			(width 0.04445)
			(type default)
		)
		(layer "B.Cu")
	)
	(gr_line
		(start 125.516894 -104.56799)
		(end 125.642624 -104.44226)
		(stroke
			(width 0.04445)
			(type default)
		)
		(layer "B.Cu")
	)
	(gr_line
		(start 125.5776 -105.780586)
		(end 125.5776 -105.917746)
		(stroke
			(width 0.04445)
			(type default)
		)
		(layer "B.Cu")
	)
	(gr_line
		(start 125.642624 -104.3051)
		(end 125.642624 -104.44226)
		(stroke
			(width 0.04445)
			(type default)
		)
		(layer "B.Cu")
	)
	(gr_line
		(start 125.64364 -103.021384)
		(end 125.76937 -102.895654)
		(stroke
			(width 0.04445)
			(type default)
		)
		(layer "B.Cu")
	)
	(gr_line
		(start 125.647958 -119.503444)
		(end 125.735842 -119.371618)
		(stroke
			(width 0.05715)
			(type default)
		)
		(layer "B.Cu")
	)
	(gr_line
		(start 125.706378 -105.651808)
		(end 125.843538 -105.651808)
		(stroke
			(width 0.04445)
			(type default)
		)
		(layer "B.Cu")
	)
	(gr_line
		(start 125.726444 -119.736616)
		(end 126.220728 -119.637556)
		(stroke
			(width 0.05715)
			(type default)
		)
		(layer "B.Cu")
	)
	(gr_line
		(start 125.735842 -119.371618)
		(end 126.072138 -119.304562)
		(stroke
			(width 0.05715)
			(type default)
		)
		(layer "B.Cu")
	)
	(gr_line
		(start 125.76937 -102.758748)
		(end 125.76937 -102.895654)
		(stroke
			(width 0.04445)
			(type default)
		)
		(layer "B.Cu")
	)
	(gr_line
		(start 125.771402 -104.176322)
		(end 125.908562 -104.176322)
		(stroke
			(width 0.04445)
			(type default)
		)
		(layer "B.Cu")
	)
	(gr_line
		(start 125.843538 -105.651808)
		(end 125.969268 -105.526078)
		(stroke
			(width 0.04445)
			(type default)
		)
		(layer "B.Cu")
	)
	(gr_line
		(start 125.898402 -102.629716)
		(end 126.035308 -102.629716)
		(stroke
			(width 0.04445)
			(type default)
		)
		(layer "B.Cu")
	)
	(gr_line
		(start 125.908562 -104.176322)
		(end 126.034292 -104.050592)
		(stroke
			(width 0.04445)
			(type default)
		)
		(layer "B.Cu")
	)
	(gr_line
		(start 125.969268 -105.388918)
		(end 125.969268 -105.526078)
		(stroke
			(width 0.04445)
			(type default)
		)
		(layer "B.Cu")
	)
	(gr_line
		(start 125.998478 -95.328486)
		(end 126.003304 -95.337122)
		(stroke
			(width 0.04445)
			(type default)
		)
		(layer "B.Cu")
	)
	(gr_line
		(start 126.034292 -103.913432)
		(end 126.034292 -104.050592)
		(stroke
			(width 0.04445)
			(type default)
		)
		(layer "B.Cu")
	)
	(gr_line
		(start 126.035308 -102.629716)
		(end 126.161038 -102.503986)
		(stroke
			(width 0.04445)
			(type default)
		)
		(layer "B.Cu")
	)
	(gr_line
		(start 126.072138 -119.304562)
		(end 126.20371 -119.392192)
		(stroke
			(width 0.05715)
			(type default)
		)
		(layer "B.Cu")
	)
	(gr_line
		(start 126.098046 -105.26014)
		(end 126.235206 -105.26014)
		(stroke
			(width 0.04445)
			(type default)
		)
		(layer "B.Cu")
	)
	(gr_line
		(start 126.158752 -100.1776)
		(end 126.163578 -100.186236)
		(stroke
			(width 0.04445)
			(type default)
		)
		(layer "B.Cu")
	)
	(gr_line
		(start 126.158752 -94.234)
		(end 126.163578 -94.242636)
		(stroke
			(width 0.04445)
			(type default)
		)
		(layer "B.Cu")
	)
	(gr_line
		(start 126.161038 -102.36708)
		(end 126.161038 -102.503986)
		(stroke
			(width 0.04445)
			(type default)
		)
		(layer "B.Cu")
	)
	(gr_line
		(start 126.16307 -103.784654)
		(end 126.30023 -103.784654)
		(stroke
			(width 0.04445)
			(type default)
		)
		(layer "B.Cu")
	)
	(gr_line
		(start 126.235206 -105.26014)
		(end 126.360936 -105.13441)
		(stroke
			(width 0.04445)
			(type default)
		)
		(layer "B.Cu")
	)
	(gr_line
		(start 126.265686 -115.626642)
		(end 126.35357 -115.49507)
		(stroke
			(width 0.05715)
			(type default)
		)
		(layer "B.Cu")
	)
	(gr_line
		(start 126.276608 -101.372924)
		(end 126.286514 -101.390196)
		(stroke
			(width 0.04445)
			(type default)
		)
		(layer "B.Cu")
	)
	(gr_line
		(start 126.30023 -103.784654)
		(end 126.42596 -103.658924)
		(stroke
			(width 0.04445)
			(type default)
		)
		(layer "B.Cu")
	)
	(gr_line
		(start 126.344934 -115.859306)
		(end 126.836932 -115.761008)
		(stroke
			(width 0.05715)
			(type default)
		)
		(layer "B.Cu")
	)
	(gr_line
		(start 126.35357 -115.49507)
		(end 126.689866 -115.42776)
		(stroke
			(width 0.05715)
			(type default)
		)
		(layer "B.Cu")
	)
	(gr_line
		(start 126.360936 -104.99725)
		(end 126.360936 -105.13441)
		(stroke
			(width 0.04445)
			(type default)
		)
		(layer "B.Cu")
	)
	(gr_line
		(start 126.42596 -103.521764)
		(end 126.42596 -103.658924)
		(stroke
			(width 0.04445)
			(type default)
		)
		(layer "B.Cu")
	)
	(gr_line
		(start 126.489714 -104.868472)
		(end 126.626874 -104.868472)
		(stroke
			(width 0.04445)
			(type default)
		)
		(layer "B.Cu")
	)
	(gr_line
		(start 126.554738 -103.392986)
		(end 126.691898 -103.392986)
		(stroke
			(width 0.04445)
			(type default)
		)
		(layer "B.Cu")
	)
	(gr_line
		(start 126.626874 -104.868472)
		(end 126.752604 -104.742742)
		(stroke
			(width 0.04445)
			(type default)
		)
		(layer "B.Cu")
	)
	(gr_line
		(start 126.689866 -115.42776)
		(end 126.821692 -115.51539)
		(stroke
			(width 0.05715)
			(type default)
		)
		(layer "B.Cu")
	)
	(gr_line
		(start 126.691898 -103.392986)
		(end 126.817628 -103.267256)
		(stroke
			(width 0.04445)
			(type default)
		)
		(layer "B.Cu")
	)
	(gr_line
		(start 126.693168 -116.733828)
		(end 126.781052 -116.602256)
		(stroke
			(width 0.05715)
			(type default)
		)
		(layer "B.Cu")
	)
	(gr_line
		(start 126.752604 -104.605582)
		(end 126.752604 -104.742742)
		(stroke
			(width 0.04445)
			(type default)
		)
		(layer "B.Cu")
	)
	(gr_line
		(start 126.770892 -101.34473)
		(end 126.785624 -101.322378)
		(stroke
			(width 0.04445)
			(type default)
		)
		(layer "B.Cu")
	)
	(gr_line
		(start 126.772162 -116.966746)
		(end 127.264922 -116.868194)
		(stroke
			(width 0.05715)
			(type default)
		)
		(layer "B.Cu")
	)
	(gr_line
		(start 126.781052 -116.602256)
		(end 127.117348 -116.534946)
		(stroke
			(width 0.05715)
			(type default)
		)
		(layer "B.Cu")
	)
	(gr_line
		(start 126.808738 -121.536714)
		(end 127.30226 -121.437908)
		(stroke
			(width 0.05715)
			(type default)
		)
		(layer "B.Cu")
	)
	(gr_line
		(start 126.817628 -103.24084)
		(end 126.817628 -103.267256)
		(stroke
			(width 0.04445)
			(type default)
		)
		(layer "B.Cu")
	)
	(gr_line
		(start 126.82474 -121.782078)
		(end 126.956312 -121.869962)
		(stroke
			(width 0.05715)
			(type default)
		)
		(layer "B.Cu")
	)
	(gr_line
		(start 126.856998 -100.186236)
		(end 126.861824 -100.1776)
		(stroke
			(width 0.04445)
			(type default)
		)
		(layer "B.Cu")
	)
	(gr_line
		(start 126.856998 -94.242636)
		(end 126.861824 -94.234)
		(stroke
			(width 0.04445)
			(type default)
		)
		(layer "B.Cu")
	)
	(gr_line
		(start 126.881382 -104.476804)
		(end 127.018542 -104.476804)
		(stroke
			(width 0.04445)
			(type default)
		)
		(layer "B.Cu")
	)
	(gr_line
		(start 126.956312 -121.869962)
		(end 127.292608 -121.802652)
		(stroke
			(width 0.05715)
			(type default)
		)
		(layer "B.Cu")
	)
	(gr_line
		(start 127.017272 -95.337122)
		(end 127.022098 -95.328486)
		(stroke
			(width 0.04445)
			(type default)
		)
		(layer "B.Cu")
	)
	(gr_line
		(start 127.018542 -104.476804)
		(end 127.144272 -104.351074)
		(stroke
			(width 0.04445)
			(type default)
		)
		(layer "B.Cu")
	)
	(gr_line
		(start 127.117348 -116.534946)
		(end 127.24892 -116.62283)
		(stroke
			(width 0.05715)
			(type default)
		)
		(layer "B.Cu")
	)
	(gr_line
		(start 127.144272 -104.213914)
		(end 127.144272 -104.351074)
		(stroke
			(width 0.04445)
			(type default)
		)
		(layer "B.Cu")
	)
	(gr_line
		(start 127.162306 -115.447318)
		(end 127.25019 -115.315492)
		(stroke
			(width 0.05715)
			(type default)
		)
		(layer "B.Cu")
	)
	(gr_line
		(start 127.242062 -115.679982)
		(end 127.73406 -115.581684)
		(stroke
			(width 0.05715)
			(type default)
		)
		(layer "B.Cu")
	)
	(gr_line
		(start 127.25019 -115.315492)
		(end 127.586486 -115.248436)
		(stroke
			(width 0.05715)
			(type default)
		)
		(layer "B.Cu")
	)
	(gr_line
		(start 127.27305 -104.085136)
		(end 127.41021 -104.085136)
		(stroke
			(width 0.04445)
			(type default)
		)
		(layer "B.Cu")
	)
	(gr_line
		(start 127.292608 -121.802652)
		(end 127.380492 -121.67108)
		(stroke
			(width 0.05715)
			(type default)
		)
		(layer "B.Cu")
	)
	(gr_line
		(start 127.41021 -104.085136)
		(end 127.53594 -103.959406)
		(stroke
			(width 0.04445)
			(type default)
		)
		(layer "B.Cu")
	)
	(gr_line
		(start 127.53594 -103.93299)
		(end 127.53594 -103.959406)
		(stroke
			(width 0.04445)
			(type default)
		)
		(layer "B.Cu")
	)
	(gr_line
		(start 127.586486 -115.248436)
		(end 127.718312 -115.336066)
		(stroke
			(width 0.05715)
			(type default)
		)
		(layer "B.Cu")
	)
	(gr_line
		(start 127.589788 -116.554504)
		(end 127.677672 -116.422932)
		(stroke
			(width 0.05715)
			(type default)
		)
		(layer "B.Cu")
	)
	(gr_line
		(start 127.66802 -116.787676)
		(end 128.162304 -116.688616)
		(stroke
			(width 0.05715)
			(type default)
		)
		(layer "B.Cu")
	)
	(gr_line
		(start 127.677672 -116.422932)
		(end 128.013968 -116.355622)
		(stroke
			(width 0.05715)
			(type default)
		)
		(layer "B.Cu")
	)
	(gr_line
		(start 127.705104 -121.35739)
		(end 128.197356 -121.258838)
		(stroke
			(width 0.05715)
			(type default)
		)
		(layer "B.Cu")
	)
	(gr_line
		(start 127.715518 -95.328486)
		(end 127.720344 -95.337122)
		(stroke
			(width 0.04445)
			(type default)
		)
		(layer "B.Cu")
	)
	(gr_line
		(start 127.72136 -121.602754)
		(end 127.852932 -121.690638)
		(stroke
			(width 0.05715)
			(type default)
		)
		(layer "B.Cu")
	)
	(gr_line
		(start 127.780542 -104.674416)
		(end 127.81661 -104.674416)
		(stroke
			(width 0.04445)
			(type default)
		)
		(layer "B.Cu")
	)
	(gr_line
		(start 127.852932 -121.690638)
		(end 128.189228 -121.623328)
		(stroke
			(width 0.05715)
			(type default)
		)
		(layer "B.Cu")
	)
	(gr_line
		(start 127.875792 -94.234)
		(end 127.880618 -94.242636)
		(stroke
			(width 0.04445)
			(type default)
		)
		(layer "B.Cu")
	)
	(gr_line
		(start 127.916178 -102.22992)
		(end 127.926084 -102.247192)
		(stroke
			(width 0.04445)
			(type default)
		)
		(layer "B.Cu")
	)
	(gr_line
		(start 127.95123 -104.845104)
		(end 127.959358 -104.836976)
		(stroke
			(width 0.04445)
			(type default)
		)
		(layer "B.Cu")
	)
	(gr_line
		(start 127.959104 -104.804972)
		(end 127.959358 -104.821736)
		(stroke
			(width 0.04445)
			(type default)
		)
		(layer "B.Cu")
	)
	(gr_line
		(start 127.959104 -104.801416)
		(end 127.959104 -104.80167)
		(stroke
			(width 0.04445)
			(type default)
		)
		(layer "B.Cu")
	)
	(gr_line
		(start 127.959358 -104.821736)
		(end 127.959358 -104.836976)
		(stroke
			(width 0.04445)
			(type default)
		)
		(layer "B.Cu")
	)
	(gr_line
		(start 128.013968 -116.355622)
		(end 128.14554 -116.443506)
		(stroke
			(width 0.05715)
			(type default)
		)
		(layer "B.Cu")
	)
	(gr_line
		(start 128.058926 -115.267994)
		(end 128.14681 -115.136168)
		(stroke
			(width 0.05715)
			(type default)
		)
		(layer "B.Cu")
	)
	(gr_line
		(start 128.13792 -115.500912)
		(end 128.631188 -115.40236)
		(stroke
			(width 0.05715)
			(type default)
		)
		(layer "B.Cu")
	)
	(gr_line
		(start 128.14681 -115.136168)
		(end 128.483106 -115.069112)
		(stroke
			(width 0.05715)
			(type default)
		)
		(layer "B.Cu")
	)
	(gr_line
		(start 128.189228 -121.623328)
		(end 128.276858 -121.491502)
		(stroke
			(width 0.05715)
			(type default)
		)
		(layer "B.Cu")
	)
	(gr_line
		(start 128.483106 -115.069112)
		(end 128.614932 -115.156742)
		(stroke
			(width 0.05715)
			(type default)
		)
		(layer "B.Cu")
	)
	(gr_line
		(start 128.486408 -116.37518)
		(end 128.574292 -116.243608)
		(stroke
			(width 0.05715)
			(type default)
		)
		(layer "B.Cu")
	)
	(gr_line
		(start 128.563878 -116.608606)
		(end 129.059178 -116.509292)
		(stroke
			(width 0.05715)
			(type default)
		)
		(layer "B.Cu")
	)
	(gr_line
		(start 128.567688 -100.766118)
		(end 128.574038 -100.776786)
		(stroke
			(width 0.04445)
			(type default)
		)
		(layer "B.Cu")
	)
	(gr_line
		(start 128.574038 -100.186236)
		(end 128.578864 -100.1776)
		(stroke
			(width 0.04445)
			(type default)
		)
		(layer "B.Cu")
	)
	(gr_line
		(start 128.574038 -94.242636)
		(end 128.578864 -94.234)
		(stroke
			(width 0.04445)
			(type default)
		)
		(layer "B.Cu")
	)
	(gr_line
		(start 128.574292 -116.243608)
		(end 128.910588 -116.176298)
		(stroke
			(width 0.05715)
			(type default)
		)
		(layer "B.Cu")
	)
	(gr_line
		(start 128.599692 -121.17832)
		(end 129.094738 -121.07926)
		(stroke
			(width 0.05715)
			(type default)
		)
		(layer "B.Cu")
	)
	(gr_line
		(start 128.617726 -121.42343)
		(end 128.749552 -121.511314)
		(stroke
			(width 0.05715)
			(type default)
		)
		(layer "B.Cu")
	)
	(gr_line
		(start 128.63322 -122.432826)
		(end 128.72085 -122.301)
		(stroke
			(width 0.05715)
			(type default)
		)
		(layer "B.Cu")
	)
	(gr_line
		(start 128.71196 -122.665744)
		(end 129.206498 -122.566684)
		(stroke
			(width 0.05715)
			(type default)
		)
		(layer "B.Cu")
	)
	(gr_line
		(start 128.72085 -122.301)
		(end 129.057146 -122.23369)
		(stroke
			(width 0.05715)
			(type default)
		)
		(layer "B.Cu")
	)
	(gr_line
		(start 128.734312 -95.337122)
		(end 128.739138 -95.328486)
		(stroke
			(width 0.04445)
			(type default)
		)
		(layer "B.Cu")
	)
	(gr_line
		(start 128.73736 -114.11204)
		(end 128.799082 -114.07902)
		(stroke
			(width 0.127)
			(type default)
		)
		(layer "B.Cu")
	)
	(gr_line
		(start 128.749552 -121.511314)
		(end 129.085848 -121.444004)
		(stroke
			(width 0.05715)
			(type default)
		)
		(layer "B.Cu")
	)
	(gr_line
		(start 128.793748 -114.224054)
		(end 128.832864 -114.21618)
		(stroke
			(width 0.05715)
			(type default)
		)
		(layer "B.Cu")
	)
	(gr_line
		(start 128.799082 -114.07902)
		(end 129.765044 -113.113058)
		(stroke
			(width 0.127)
			(type default)
		)
		(layer "B.Cu")
	)
	(gr_line
		(start 128.910588 -116.176298)
		(end 129.04216 -116.264182)
		(stroke
			(width 0.05715)
			(type default)
		)
		(layer "B.Cu")
	)
	(gr_line
		(start 129.057146 -122.23369)
		(end 129.188718 -122.321574)
		(stroke
			(width 0.05715)
			(type default)
		)
		(layer "B.Cu")
	)
	(gr_line
		(start 129.085848 -121.444004)
		(end 129.173732 -121.312178)
		(stroke
			(width 0.05715)
			(type default)
		)
		(layer "B.Cu")
	)
	(gr_line
		(start 129.191512 -115.290092)
		(end 129.22885 -115.282726)
		(stroke
			(width 0.05715)
			(type default)
		)
		(layer "B.Cu")
	)
	(gr_line
		(start 129.233676 -101.41331)
		(end 129.332228 -101.511862)
		(stroke
			(width 0.04445)
			(type default)
		)
		(layer "B.Cu")
	)
	(gr_line
		(start 129.233676 -101.23551)
		(end 129.233676 -101.41331)
		(stroke
			(width 0.04445)
			(type default)
		)
		(layer "B.Cu")
	)
	(gr_line
		(start 129.233676 -101.23551)
		(end 129.332228 -101.136958)
		(stroke
			(width 0.04445)
			(type default)
		)
		(layer "B.Cu")
	)
	(gr_line
		(start 129.309368 -104.396286)
		(end 129.309368 -104.418384)
		(stroke
			(width 0.04445)
			(type default)
		)
		(layer "B.Cu")
	)
	(gr_line
		(start 129.309368 -104.396286)
		(end 129.334768 -104.370886)
		(stroke
			(width 0.04445)
			(type default)
		)
		(layer "B.Cu")
	)
	(gr_line
		(start 129.334768 -100.851462)
		(end 129.344674 -100.83419)
		(stroke
			(width 0.04445)
			(type default)
		)
		(layer "B.Cu")
	)
	(gr_line
		(start 129.432558 -95.328486)
		(end 129.437384 -95.337122)
		(stroke
			(width 0.04445)
			(type default)
		)
		(layer "B.Cu")
	)
	(gr_line
		(start 129.46126 -116.429028)
		(end 129.500376 -116.421154)
		(stroke
			(width 0.05715)
			(type default)
		)
		(layer "B.Cu")
	)
	(gr_line
		(start 129.498852 -120.998488)
		(end 129.991866 -120.899682)
		(stroke
			(width 0.05715)
			(type default)
		)
		(layer "B.Cu")
	)
	(gr_line
		(start 129.500376 -116.421154)
		(end 129.52857 -116.39296)
		(stroke
			(width 0.05715)
			(type default)
		)
		(layer "B.Cu")
	)
	(gr_line
		(start 129.50444 -104.844342)
		(end 129.550668 -104.798114)
		(stroke
			(width 0.05715)
			(type default)
		)
		(layer "B.Cu")
	)
	(gr_line
		(start 129.5146 -121.243852)
		(end 129.646172 -121.331736)
		(stroke
			(width 0.05715)
			(type default)
		)
		(layer "B.Cu")
	)
	(gr_line
		(start 129.525268 -104.370886)
		(end 129.550668 -104.396286)
		(stroke
			(width 0.04445)
			(type default)
		)
		(layer "B.Cu")
	)
	(gr_line
		(start 129.529586 -122.253502)
		(end 129.61747 -122.121676)
		(stroke
			(width 0.05715)
			(type default)
		)
		(layer "B.Cu")
	)
	(gr_line
		(start 129.550668 -104.396286)
		(end 129.550668 -104.418384)
		(stroke
			(width 0.04445)
			(type default)
		)
		(layer "B.Cu")
	)
	(gr_line
		(start 129.592832 -100.1776)
		(end 129.597658 -100.186236)
		(stroke
			(width 0.04445)
			(type default)
		)
		(layer "B.Cu")
	)
	(gr_line
		(start 129.592832 -94.234)
		(end 129.597658 -94.242636)
		(stroke
			(width 0.04445)
			(type default)
		)
		(layer "B.Cu")
	)
	(gr_line
		(start 129.607564 -122.48642)
		(end 130.101594 -122.387614)
		(stroke
			(width 0.05715)
			(type default)
		)
		(layer "B.Cu")
	)
	(gr_line
		(start 129.61747 -122.121676)
		(end 129.953766 -122.054366)
		(stroke
			(width 0.05715)
			(type default)
		)
		(layer "B.Cu")
	)
	(gr_line
		(start 129.646172 -121.331736)
		(end 129.982468 -121.264426)
		(stroke
			(width 0.05715)
			(type default)
		)
		(layer "B.Cu")
	)
	(gr_line
		(start 129.6797 -106.1974)
		(end 129.6797 -106.219498)
		(stroke
			(width 0.04445)
			(type default)
		)
		(layer "B.Cu")
	)
	(gr_line
		(start 129.6797 -106.1974)
		(end 129.7051 -106.172)
		(stroke
			(width 0.04445)
			(type default)
		)
		(layer "B.Cu")
	)
	(gr_line
		(start 129.752852 -118.931182)
		(end 129.791968 -118.923308)
		(stroke
			(width 0.05715)
			(type default)
		)
		(layer "B.Cu")
	)
	(gr_line
		(start 129.753106 -117.521228)
		(end 129.792222 -117.513354)
		(stroke
			(width 0.05715)
			(type default)
		)
		(layer "B.Cu")
	)
	(gr_line
		(start 129.765044 -113.113058)
		(end 129.80035 -113.027714)
		(stroke
			(width 0.127)
			(type default)
		)
		(layer "B.Cu")
	)
	(gr_line
		(start 129.791968 -118.923308)
		(end 129.820162 -118.895114)
		(stroke
			(width 0.05715)
			(type default)
		)
		(layer "B.Cu")
	)
	(gr_line
		(start 129.80035 -113.027714)
		(end 129.80035 -106.219498)
		(stroke
			(width 0.127)
			(type default)
		)
		(layer "B.Cu")
	)
	(gr_line
		(start 129.80035 -106.219498)
		(end 129.80035 -106.1974)
		(stroke
			(width 0.127)
			(type default)
		)
		(layer "B.Cu")
	)
	(gr_line
		(start 129.80035 -106.172)
		(end 129.80035 -105.795572)
		(stroke
			(width 0.127)
			(type default)
		)
		(layer "B.Cu")
	)
	(gr_line
		(start 129.80035 -105.795572)
		(end 129.82829 -105.728262)
		(stroke
			(width 0.127)
			(type default)
		)
		(layer "B.Cu")
	)
	(gr_line
		(start 129.82829 -105.728262)
		(end 130.31851 -105.237788)
		(stroke
			(width 0.127)
			(type default)
		)
		(layer "B.Cu")
	)
	(gr_line
		(start 129.874772 -113.174018)
		(end 129.921 -113.12779)
		(stroke
			(width 0.05715)
			(type default)
		)
		(layer "B.Cu")
	)
	(gr_line
		(start 129.8956 -106.172)
		(end 129.921 -106.1974)
		(stroke
			(width 0.04445)
			(type default)
		)
		(layer "B.Cu")
	)
	(gr_line
		(start 129.921 -106.1974)
		(end 129.921 -106.219498)
		(stroke
			(width 0.04445)
			(type default)
		)
		(layer "B.Cu")
	)
	(gr_line
		(start 129.95275 -120.117108)
		(end 129.991866 -120.109234)
		(stroke
			(width 0.05715)
			(type default)
		)
		(layer "B.Cu")
	)
	(gr_line
		(start 129.953766 -122.054366)
		(end 130.085338 -122.14225)
		(stroke
			(width 0.05715)
			(type default)
		)
		(layer "B.Cu")
	)
	(gr_line
		(start 129.982468 -121.264426)
		(end 130.070352 -121.132854)
		(stroke
			(width 0.05715)
			(type default)
		)
		(layer "B.Cu")
	)
	(gr_line
		(start 129.991866 -120.109234)
		(end 130.02006 -120.08104)
		(stroke
			(width 0.05715)
			(type default)
		)
		(layer "B.Cu")
	)
	(gr_line
		(start 130.2512 -103.284274)
		(end 130.258058 -103.270812)
		(stroke
			(width 0.04445)
			(type default)
		)
		(layer "B.Cu")
	)
	(gr_line
		(start 130.291078 -102.757986)
		(end 130.291332 -102.75824)
		(stroke
			(width 0.04445)
			(type default)
		)
		(layer "B.Cu")
	)
	(gr_line
		(start 130.291078 -100.186236)
		(end 130.295904 -100.1776)
		(stroke
			(width 0.04445)
			(type default)
		)
		(layer "B.Cu")
	)
	(gr_line
		(start 130.291078 -94.242636)
		(end 130.295904 -94.234)
		(stroke
			(width 0.04445)
			(type default)
		)
		(layer "B.Cu")
	)
	(gr_line
		(start 130.31851 -105.237788)
		(end 130.34645 -105.170478)
		(stroke
			(width 0.127)
			(type default)
		)
		(layer "B.Cu")
	)
	(gr_line
		(start 130.34645 -105.170478)
		(end 130.34645 -104.437942)
		(stroke
			(width 0.127)
			(type default)
		)
		(layer "B.Cu")
	)
	(gr_line
		(start 130.34645 -104.437942)
		(end 130.34645 -104.062022)
		(stroke
			(width 0.127)
			(type default)
		)
		(layer "B.Cu")
	)
	(gr_line
		(start 130.34645 -104.062022)
		(end 130.34645 -103.884222)
		(stroke
			(width 0.127)
			(type default)
		)
		(layer "B.Cu")
	)
	(gr_line
		(start 130.34645 -103.884222)
		(end 130.34645 -103.508302)
		(stroke
			(width 0.127)
			(type default)
		)
		(layer "B.Cu")
	)
	(gr_line
		(start 130.34645 -103.508302)
		(end 130.34645 -103.330502)
		(stroke
			(width 0.127)
			(type default)
		)
		(layer "B.Cu")
	)
	(gr_line
		(start 130.34645 -103.330502)
		(end 130.356864 -103.286814)
		(stroke
			(width 0.127)
			(type default)
		)
		(layer "B.Cu")
	)
	(gr_line
		(start 130.356864 -103.286814)
		(end 130.410966 -103.181404)
		(stroke
			(width 0.127)
			(type default)
		)
		(layer "B.Cu")
	)
	(gr_line
		(start 130.36931 -121.070624)
		(end 130.408426 -121.06275)
		(stroke
			(width 0.05715)
			(type default)
		)
		(layer "B.Cu")
	)
	(gr_line
		(start 130.373628 -102.710488)
		(end 130.373882 -102.253034)
		(stroke
			(width 0.127)
			(type default)
		)
		(layer "B.Cu")
	)
	(gr_line
		(start 130.410966 -103.181404)
		(end 130.42011 -103.154988)
		(stroke
			(width 0.127)
			(type default)
		)
		(layer "B.Cu")
	)
	(gr_line
		(start 130.42011 -103.154988)
		(end 130.435858 -103.068628)
		(stroke
			(width 0.127)
			(type default)
		)
		(layer "B.Cu")
	)
	(gr_line
		(start 130.44424 -104.435402)
		(end 130.54076 -104.338882)
		(stroke
			(width 0.04445)
			(type default)
		)
		(layer "B.Cu")
	)
	(gr_line
		(start 130.44424 -104.064562)
		(end 130.54076 -104.161082)
		(stroke
			(width 0.04445)
			(type default)
		)
		(layer "B.Cu")
	)
	(gr_line
		(start 130.44424 -103.881682)
		(end 130.54076 -103.785162)
		(stroke
			(width 0.04445)
			(type default)
		)
		(layer "B.Cu")
	)
	(gr_line
		(start 130.44424 -103.510842)
		(end 130.54076 -103.607362)
		(stroke
			(width 0.04445)
			(type default)
		)
		(layer "B.Cu")
	)
	(gr_line
		(start 130.451352 -101.280722)
		(end 130.456178 -101.272086)
		(stroke
			(width 0.04445)
			(type default)
		)
		(layer "B.Cu")
	)
	(gr_line
		(start 130.451352 -95.337122)
		(end 130.456178 -95.328486)
		(stroke
			(width 0.04445)
			(type default)
		)
		(layer "B.Cu")
	)
	(gr_line
		(start 130.504438 -122.307096)
		(end 130.543554 -122.299222)
		(stroke
			(width 0.05715)
			(type default)
		)
		(layer "B.Cu")
	)
	(gr_line
		(start 130.54076 -104.161082)
		(end 130.54076 -104.338882)
		(stroke
			(width 0.04445)
			(type default)
		)
		(layer "B.Cu")
	)
	(gr_line
		(start 130.54076 -103.607362)
		(end 130.54076 -103.785162)
		(stroke
			(width 0.04445)
			(type default)
		)
		(layer "B.Cu")
	)
	(gr_line
		(start 130.543554 -122.299222)
		(end 130.571748 -122.271028)
		(stroke
			(width 0.05715)
			(type default)
		)
		(layer "B.Cu")
	)
	(gr_line
		(start 130.6576 -106.797602)
		(end 130.6576 -106.8197)
		(stroke
			(width 0.04445)
			(type default)
		)
		(layer "B.Cu")
	)
	(gr_line
		(start 130.6576 -106.797602)
		(end 130.683 -106.772202)
		(stroke
			(width 0.04445)
			(type default)
		)
		(layer "B.Cu")
	)
	(gr_line
		(start 130.8735 -106.772202)
		(end 130.8989 -106.797602)
		(stroke
			(width 0.04445)
			(type default)
		)
		(layer "B.Cu")
	)
	(gr_line
		(start 130.8989 -106.797602)
		(end 130.8989 -106.8197)
		(stroke
			(width 0.04445)
			(type default)
		)
		(layer "B.Cu")
	)
	(gr_line
		(start 131.0513 -103.411274)
		(end 131.05384 -103.41737)
		(stroke
			(width 0.04445)
			(type default)
		)
		(layer "B.Cu")
	)
	(gr_line
		(start 131.0513 -102.832916)
		(end 131.06146 -102.815136)
		(stroke
			(width 0.04445)
			(type default)
		)
		(layer "B.Cu")
	)
	(gr_line
		(start 131.05384 -104.111552)
		(end 131.15036 -104.208072)
		(stroke
			(width 0.04445)
			(type default)
		)
		(layer "B.Cu")
	)
	(gr_line
		(start 131.05384 -103.933752)
		(end 131.05384 -104.111552)
		(stroke
			(width 0.04445)
			(type default)
		)
		(layer "B.Cu")
	)
	(gr_line
		(start 131.05384 -103.933752)
		(end 131.15036 -103.837232)
		(stroke
			(width 0.04445)
			(type default)
		)
		(layer "B.Cu")
	)
	(gr_line
		(start 131.149598 -101.272086)
		(end 131.154424 -101.280722)
		(stroke
			(width 0.04445)
			(type default)
		)
		(layer "B.Cu")
	)
	(gr_line
		(start 131.149598 -95.328486)
		(end 131.154424 -95.337122)
		(stroke
			(width 0.04445)
			(type default)
		)
		(layer "B.Cu")
	)
	(gr_line
		(start 131.309872 -100.1776)
		(end 131.314698 -100.186236)
		(stroke
			(width 0.04445)
			(type default)
		)
		(layer "B.Cu")
	)
	(gr_line
		(start 131.309872 -94.234)
		(end 131.314698 -94.242636)
		(stroke
			(width 0.04445)
			(type default)
		)
		(layer "B.Cu")
	)
	(gr_line
		(start 131.34086 -103.61295)
		(end 131.3434 -103.619046)
		(stroke
			(width 0.04445)
			(type default)
		)
		(layer "B.Cu")
	)
	(gr_line
		(start 131.636008 -106.845608)
		(end 131.636008 -106.867706)
		(stroke
			(width 0.04445)
			(type default)
		)
		(layer "B.Cu")
	)
	(gr_line
		(start 131.636008 -106.845608)
		(end 131.661408 -106.820208)
		(stroke
			(width 0.04445)
			(type default)
		)
		(layer "B.Cu")
	)
	(gr_line
		(start 131.83108 -114.09045)
		(end 131.877308 -114.044222)
		(stroke
			(width 0.05715)
			(type default)
		)
		(layer "B.Cu")
	)
	(gr_line
		(start 131.851908 -106.820208)
		(end 131.877308 -106.845608)
		(stroke
			(width 0.04445)
			(type default)
		)
		(layer "B.Cu")
	)
	(gr_line
		(start 131.877308 -106.845608)
		(end 131.877308 -106.867706)
		(stroke
			(width 0.04445)
			(type default)
		)
		(layer "B.Cu")
	)
	(gr_line
		(start 131.967224 -104.821228)
		(end 132.063744 -104.917748)
		(stroke
			(width 0.04445)
			(type default)
		)
		(layer "B.Cu")
	)
	(gr_line
		(start 131.967224 -104.643428)
		(end 131.967224 -104.821228)
		(stroke
			(width 0.04445)
			(type default)
		)
		(layer "B.Cu")
	)
	(gr_line
		(start 131.967224 -104.643428)
		(end 132.063744 -104.546908)
		(stroke
			(width 0.04445)
			(type default)
		)
		(layer "B.Cu")
	)
	(gr_line
		(start 131.967224 -104.267508)
		(end 132.063744 -104.364028)
		(stroke
			(width 0.04445)
			(type default)
		)
		(layer "B.Cu")
	)
	(gr_line
		(start 131.967224 -104.089708)
		(end 131.967224 -104.267508)
		(stroke
			(width 0.04445)
			(type default)
		)
		(layer "B.Cu")
	)
	(gr_line
		(start 131.967224 -104.089708)
		(end 132.063744 -103.993188)
		(stroke
			(width 0.04445)
			(type default)
		)
		(layer "B.Cu")
	)
	(gr_line
		(start 131.967224 -103.713788)
		(end 132.063744 -103.810308)
		(stroke
			(width 0.04445)
			(type default)
		)
		(layer "B.Cu")
	)
	(gr_line
		(start 131.967224 -103.535988)
		(end 131.967224 -103.713788)
		(stroke
			(width 0.04445)
			(type default)
		)
		(layer "B.Cu")
	)
	(gr_line
		(start 131.967224 -103.535988)
		(end 132.063744 -103.439468)
		(stroke
			(width 0.04445)
			(type default)
		)
		(layer "B.Cu")
	)
	(gr_line
		(start 132.173218 -100.681536)
		(end 132.179568 -100.692204)
		(stroke
			(width 0.04445)
			(type default)
		)
		(layer "B.Cu")
	)
	(gr_line
		(start 132.173218 -100.28174)
		(end 132.179568 -100.271072)
		(stroke
			(width 0.04445)
			(type default)
		)
		(layer "B.Cu")
	)
	(gr_line
		(start 132.519674 -95.528384)
		(end 132.81279 -95.697548)
		(stroke
			(width 0.04445)
			(type default)
		)
		(layer "B.Cu")
	)
	(gr_line
		(start 132.519674 -92.556584)
		(end 132.89026 -92.409518)
		(stroke
			(width 0.04445)
			(type default)
		)
		(layer "B.Cu")
	)
	(gr_line
		(start 132.577586 -92.037408)
		(end 132.948934 -91.813634)
		(stroke
			(width 0.127)
			(type default)
		)
		(layer "B.Cu")
	)
	(gr_line
		(start 132.6261 -107.093766)
		(end 132.6261 -107.115864)
		(stroke
			(width 0.04445)
			(type default)
		)
		(layer "B.Cu")
	)
	(gr_line
		(start 132.6261 -107.093766)
		(end 132.6515 -107.068366)
		(stroke
			(width 0.04445)
			(type default)
		)
		(layer "B.Cu")
	)
	(gr_line
		(start 132.81279 -95.697548)
		(end 132.836158 -95.784924)
		(stroke
			(width 0.04445)
			(type default)
		)
		(layer "B.Cu")
	)
	(gr_line
		(start 132.821172 -114.48415)
		(end 132.8674 -114.437922)
		(stroke
			(width 0.05715)
			(type default)
		)
		(layer "B.Cu")
	)
	(gr_line
		(start 132.842 -107.068366)
		(end 132.8674 -107.093766)
		(stroke
			(width 0.04445)
			(type default)
		)
		(layer "B.Cu")
	)
	(gr_line
		(start 132.866384 -101.272086)
		(end 132.87121 -101.280722)
		(stroke
			(width 0.04445)
			(type default)
		)
		(layer "B.Cu")
	)
	(gr_line
		(start 132.8674 -107.093766)
		(end 132.8674 -107.115864)
		(stroke
			(width 0.04445)
			(type default)
		)
		(layer "B.Cu")
	)
	(gr_line
		(start 132.948934 -91.813634)
		(end 133.359906 -91.566238)
		(stroke
			(width 0.127)
			(type default)
		)
		(layer "B.Cu")
	)
	(gr_line
		(start 133.008116 -95.875602)
		(end 133.085078 -95.854774)
		(stroke
			(width 0.04445)
			(type default)
		)
		(layer "B.Cu")
	)
	(gr_line
		(start 133.026658 -100.1776)
		(end 133.031484 -100.186236)
		(stroke
			(width 0.04445)
			(type default)
		)
		(layer "B.Cu")
	)
	(gr_line
		(start 133.062218 -92.31884)
		(end 133.378194 -92.061538)
		(stroke
			(width 0.04445)
			(type default)
		)
		(layer "B.Cu")
	)
	(gr_line
		(start 133.085078 -95.854774)
		(end 133.378194 -96.023938)
		(stroke
			(width 0.04445)
			(type default)
		)
		(layer "B.Cu")
	)
	(gr_line
		(start 133.14045 -103.342186)
		(end 133.1722 -103.373936)
		(stroke
			(width 0.04445)
			(type default)
		)
		(layer "B.Cu")
	)
	(gr_line
		(start 133.174232 -104.003602)
		(end 133.270752 -103.907082)
		(stroke
			(width 0.04445)
			(type default)
		)
		(layer "B.Cu")
	)
	(gr_line
		(start 133.174232 -103.632762)
		(end 133.270752 -103.729282)
		(stroke
			(width 0.04445)
			(type default)
		)
		(layer "B.Cu")
	)
	(gr_line
		(start 133.270752 -103.729282)
		(end 133.270752 -103.907082)
		(stroke
			(width 0.04445)
			(type default)
		)
		(layer "B.Cu")
	)
	(gr_line
		(start 133.359906 -91.566238)
		(end 133.363208 -91.566238)
		(stroke
			(width 0.127)
			(type default)
		)
		(layer "B.Cu")
	)
	(gr_line
		(start 133.363208 -91.566238)
		(end 133.38937 -91.566238)
		(stroke
			(width 0.127)
			(type default)
		)
		(layer "B.Cu")
	)
	(gr_line
		(start 133.378194 -95.033084)
		(end 133.545072 -94.937072)
		(stroke
			(width 0.04445)
			(type default)
		)
		(layer "B.Cu")
	)
	(gr_line
		(start 133.378194 -93.704664)
		(end 133.378194 -94.042738)
		(stroke
			(width 0.04445)
			(type default)
		)
		(layer "B.Cu")
	)
	(gr_line
		(start 133.378194 -93.704664)
		(end 133.399022 -93.683836)
		(stroke
			(width 0.04445)
			(type default)
		)
		(layer "B.Cu")
	)
	(gr_line
		(start 133.378194 -93.390212)
		(end 133.399022 -93.41104)
		(stroke
			(width 0.04445)
			(type default)
		)
		(layer "B.Cu")
	)
	(gr_line
		(start 133.378194 -93.052138)
		(end 133.378194 -93.390212)
		(stroke
			(width 0.04445)
			(type default)
		)
		(layer "B.Cu")
	)
	(gr_line
		(start 133.378194 -91.070938)
		(end 133.67131 -91.239848)
		(stroke
			(width 0.04445)
			(type default)
		)
		(layer "B.Cu")
	)
	(gr_line
		(start 133.4008 -93.682058)
		(end 133.436106 -93.646752)
		(stroke
			(width 0.04445)
			(type default)
		)
		(layer "B.Cu")
	)
	(gr_line
		(start 133.4008 -93.412818)
		(end 133.443218 -93.455236)
		(stroke
			(width 0.04445)
			(type default)
		)
		(layer "B.Cu")
	)
	(gr_line
		(start 133.545072 -94.937072)
		(end 133.67131 -94.864174)
		(stroke
			(width 0.04445)
			(type default)
		)
		(layer "B.Cu")
	)
	(gr_line
		(start 133.622542 -107.435142)
		(end 133.622542 -107.45724)
		(stroke
			(width 0.04445)
			(type default)
		)
		(layer "B.Cu")
	)
	(gr_line
		(start 133.622542 -107.435142)
		(end 133.647942 -107.409742)
		(stroke
			(width 0.04445)
			(type default)
		)
		(layer "B.Cu")
	)
	(gr_line
		(start 133.67131 -94.864174)
		(end 133.748526 -94.885002)
		(stroke
			(width 0.04445)
			(type default)
		)
		(layer "B.Cu")
	)
	(gr_line
		(start 133.67131 -91.239848)
		(end 133.691884 -91.31681)
		(stroke
			(width 0.04445)
			(type default)
		)
		(layer "B.Cu")
	)
	(gr_line
		(start 133.724904 -100.186236)
		(end 133.72973 -100.1776)
		(stroke
			(width 0.04445)
			(type default)
		)
		(layer "B.Cu")
	)
	(gr_line
		(start 133.78434 -104.403652)
		(end 133.88086 -104.500172)
		(stroke
			(width 0.04445)
			(type default)
		)
		(layer "B.Cu")
	)
	(gr_line
		(start 133.78434 -104.225852)
		(end 133.78434 -104.403652)
		(stroke
			(width 0.04445)
			(type default)
		)
		(layer "B.Cu")
	)
	(gr_line
		(start 133.78434 -104.225852)
		(end 133.88086 -104.129332)
		(stroke
			(width 0.04445)
			(type default)
		)
		(layer "B.Cu")
	)
	(gr_line
		(start 133.817614 -114.897662)
		(end 133.863842 -114.851434)
		(stroke
			(width 0.05715)
			(type default)
		)
		(layer "B.Cu")
	)
	(gr_line
		(start 133.838442 -107.409742)
		(end 133.863842 -107.435142)
		(stroke
			(width 0.04445)
			(type default)
		)
		(layer "B.Cu")
	)
	(gr_line
		(start 133.856222 -91.420696)
		(end 133.943598 -91.397074)
		(stroke
			(width 0.04445)
			(type default)
		)
		(layer "B.Cu")
	)
	(gr_line
		(start 133.863842 -107.435142)
		(end 133.863842 -107.45724)
		(stroke
			(width 0.04445)
			(type default)
		)
		(layer "B.Cu")
	)
	(gr_line
		(start 133.885178 -101.280722)
		(end 133.890004 -101.272086)
		(stroke
			(width 0.04445)
			(type default)
		)
		(layer "B.Cu")
	)
	(gr_line
		(start 133.885178 -95.337122)
		(end 133.890004 -95.328486)
		(stroke
			(width 0.04445)
			(type default)
		)
		(layer "B.Cu")
	)
	(gr_line
		(start 133.92023 -94.794324)
		(end 133.943598 -94.706948)
		(stroke
			(width 0.04445)
			(type default)
		)
		(layer "B.Cu")
	)
	(gr_line
		(start 133.943598 -94.706948)
		(end 134.236714 -94.538038)
		(stroke
			(width 0.04445)
			(type default)
		)
		(layer "B.Cu")
	)
	(gr_line
		(start 133.943598 -91.397074)
		(end 134.236714 -91.565984)
		(stroke
			(width 0.04445)
			(type default)
		)
		(layer "B.Cu")
	)
	(gr_line
		(start 134.063994 -102.964234)
		(end 134.0739 -102.981506)
		(stroke
			(width 0.04445)
			(type default)
		)
		(layer "B.Cu")
	)
	(gr_line
		(start 134.236714 -93.547184)
		(end 134.52983 -93.716348)
		(stroke
			(width 0.04445)
			(type default)
		)
		(layer "B.Cu")
	)
	(gr_line
		(start 134.236714 -90.575384)
		(end 134.52983 -90.406474)
		(stroke
			(width 0.04445)
			(type default)
		)
		(layer "B.Cu")
	)
	(gr_line
		(start 134.52983 -93.716348)
		(end 134.553198 -93.803724)
		(stroke
			(width 0.04445)
			(type default)
		)
		(layer "B.Cu")
	)
	(gr_line
		(start 134.52983 -90.406474)
		(end 134.607046 -90.427302)
		(stroke
			(width 0.04445)
			(type default)
		)
		(layer "B.Cu")
	)
	(gr_line
		(start 134.583424 -101.272086)
		(end 134.58825 -101.280722)
		(stroke
			(width 0.04445)
			(type default)
		)
		(layer "B.Cu")
	)
	(gr_line
		(start 134.583424 -95.328486)
		(end 134.58825 -95.337122)
		(stroke
			(width 0.04445)
			(type default)
		)
		(layer "B.Cu")
	)
	(gr_line
		(start 134.725156 -93.894402)
		(end 134.802118 -93.873574)
		(stroke
			(width 0.04445)
			(type default)
		)
		(layer "B.Cu")
	)
	(gr_line
		(start 134.743698 -100.1776)
		(end 134.748524 -100.186236)
		(stroke
			(width 0.04445)
			(type default)
		)
		(layer "B.Cu")
	)
	(gr_line
		(start 134.743698 -94.234)
		(end 134.748524 -94.242636)
		(stroke
			(width 0.04445)
			(type default)
		)
		(layer "B.Cu")
	)
	(gr_line
		(start 134.77875 -90.336624)
		(end 134.802118 -90.249248)
		(stroke
			(width 0.04445)
			(type default)
		)
		(layer "B.Cu")
	)
	(gr_line
		(start 134.792212 -106.262678)
		(end 134.792212 -106.284776)
		(stroke
			(width 0.04445)
			(type default)
		)
		(layer "B.Cu")
	)
	(gr_line
		(start 134.792212 -106.262678)
		(end 134.817612 -106.237278)
		(stroke
			(width 0.04445)
			(type default)
		)
		(layer "B.Cu")
	)
	(gr_line
		(start 134.802118 -93.873574)
		(end 135.095234 -94.042738)
		(stroke
			(width 0.04445)
			(type default)
		)
		(layer "B.Cu")
	)
	(gr_line
		(start 134.802118 -90.249248)
		(end 135.095234 -90.080338)
		(stroke
			(width 0.04445)
			(type default)
		)
		(layer "B.Cu")
	)
	(gr_line
		(start 134.987284 -115.113816)
		(end 135.033512 -115.067588)
		(stroke
			(width 0.05715)
			(type default)
		)
		(layer "B.Cu")
	)
	(gr_line
		(start 134.998206 -103.590852)
		(end 135.008112 -103.608124)
		(stroke
			(width 0.04445)
			(type default)
		)
		(layer "B.Cu")
	)
	(gr_line
		(start 135.008112 -106.237278)
		(end 135.033512 -106.262678)
		(stroke
			(width 0.04445)
			(type default)
		)
		(layer "B.Cu")
	)
	(gr_line
		(start 135.010652 -104.159304)
		(end 135.107172 -104.062784)
		(stroke
			(width 0.04445)
			(type default)
		)
		(layer "B.Cu")
	)
	(gr_line
		(start 135.010652 -103.788464)
		(end 135.107172 -103.884984)
		(stroke
			(width 0.04445)
			(type default)
		)
		(layer "B.Cu")
	)
	(gr_line
		(start 135.033512 -106.262678)
		(end 135.033512 -106.284776)
		(stroke
			(width 0.04445)
			(type default)
		)
		(layer "B.Cu")
	)
	(gr_line
		(start 135.080248 -82.746088)
		(end 135.11022 -82.746088)
		(stroke
			(width 0.04445)
			(type default)
		)
		(layer "B.Cu")
	)
	(gr_line
		(start 135.095234 -89.089738)
		(end 135.38835 -89.258648)
		(stroke
			(width 0.04445)
			(type default)
		)
		(layer "B.Cu")
	)
	(gr_line
		(start 135.107172 -103.884984)
		(end 135.107172 -104.062784)
		(stroke
			(width 0.04445)
			(type default)
		)
		(layer "B.Cu")
	)
	(gr_line
		(start 135.38835 -89.258648)
		(end 135.411718 -89.346024)
		(stroke
			(width 0.04445)
			(type default)
		)
		(layer "B.Cu")
	)
	(gr_line
		(start 135.441944 -100.186236)
		(end 135.44677 -100.1776)
		(stroke
			(width 0.04445)
			(type default)
		)
		(layer "B.Cu")
	)
	(gr_line
		(start 135.441944 -94.242636)
		(end 135.44677 -94.234)
		(stroke
			(width 0.04445)
			(type default)
		)
		(layer "B.Cu")
	)
	(gr_line
		(start 135.583422 -89.436702)
		(end 135.660638 -89.415874)
		(stroke
			(width 0.04445)
			(type default)
		)
		(layer "B.Cu")
	)
	(gr_line
		(start 135.602218 -101.280722)
		(end 135.607044 -101.272086)
		(stroke
			(width 0.04445)
			(type default)
		)
		(layer "B.Cu")
	)
	(gr_line
		(start 135.602218 -95.337122)
		(end 135.607044 -95.328486)
		(stroke
			(width 0.04445)
			(type default)
		)
		(layer "B.Cu")
	)
	(gr_line
		(start 135.660638 -89.415874)
		(end 135.953754 -89.584784)
		(stroke
			(width 0.04445)
			(type default)
		)
		(layer "B.Cu")
	)
	(gr_line
		(start 135.720582 -105.306368)
		(end 135.817102 -105.402888)
		(stroke
			(width 0.04445)
			(type default)
		)
		(layer "B.Cu")
	)
	(gr_line
		(start 135.720582 -105.128568)
		(end 135.720582 -105.306368)
		(stroke
			(width 0.04445)
			(type default)
		)
		(layer "B.Cu")
	)
	(gr_line
		(start 135.720582 -105.128568)
		(end 135.817102 -105.032048)
		(stroke
			(width 0.04445)
			(type default)
		)
		(layer "B.Cu")
	)
	(gr_line
		(start 135.720582 -104.752648)
		(end 135.817102 -104.849168)
		(stroke
			(width 0.04445)
			(type default)
		)
		(layer "B.Cu")
	)
	(gr_line
		(start 135.720582 -104.574848)
		(end 135.720582 -104.752648)
		(stroke
			(width 0.04445)
			(type default)
		)
		(layer "B.Cu")
	)
	(gr_line
		(start 135.720582 -104.574848)
		(end 135.817102 -104.478328)
		(stroke
			(width 0.04445)
			(type default)
		)
		(layer "B.Cu")
	)
	(gr_line
		(start 135.794242 -105.959656)
		(end 135.794242 -105.981754)
		(stroke
			(width 0.04445)
			(type default)
		)
		(layer "B.Cu")
	)
	(gr_line
		(start 135.794242 -105.959656)
		(end 135.819642 -105.934256)
		(stroke
			(width 0.04445)
			(type default)
		)
		(layer "B.Cu")
	)
	(gr_line
		(start 135.989314 -115.481608)
		(end 136.035542 -115.43538)
		(stroke
			(width 0.05715)
			(type default)
		)
		(layer "B.Cu")
	)
	(gr_line
		(start 136.000236 -103.343964)
		(end 136.010142 -103.361236)
		(stroke
			(width 0.04445)
			(type default)
		)
		(layer "B.Cu")
	)
	(gr_line
		(start 136.010142 -105.934256)
		(end 136.035542 -105.959656)
		(stroke
			(width 0.04445)
			(type default)
		)
		(layer "B.Cu")
	)
	(gr_line
		(start 136.035542 -105.959656)
		(end 136.035542 -105.981754)
		(stroke
			(width 0.04445)
			(type default)
		)
		(layer "B.Cu")
	)
	(gr_line
		(start 136.296146 -100.274628)
		(end 136.296654 -100.275136)
		(stroke
			(width 0.04445)
			(type default)
		)
		(layer "B.Cu")
	)
	(gr_line
		(start 136.300464 -95.328486)
		(end 136.30529 -95.337122)
		(stroke
			(width 0.04445)
			(type default)
		)
		(layer "B.Cu")
	)
	(gr_line
		(start 136.460738 -94.234)
		(end 136.465564 -94.242636)
		(stroke
			(width 0.04445)
			(type default)
		)
		(layer "B.Cu")
	)
	(gr_line
		(start 137.158984 -94.242636)
		(end 137.16381 -94.234)
		(stroke
			(width 0.04445)
			(type default)
		)
		(layer "B.Cu")
	)
	(gr_line
		(start 137.23874 -104.11079)
		(end 137.23874 -104.132888)
		(stroke
			(width 0.04445)
			(type default)
		)
		(layer "B.Cu")
	)
	(gr_line
		(start 137.23874 -104.11079)
		(end 137.26414 -104.08539)
		(stroke
			(width 0.04445)
			(type default)
		)
		(layer "B.Cu")
	)
	(gr_line
		(start 137.319258 -95.337122)
		(end 137.324084 -95.328486)
		(stroke
			(width 0.04445)
			(type default)
		)
		(layer "B.Cu")
	)
	(gr_line
		(start 137.433812 -115.408964)
		(end 137.48004 -115.362736)
		(stroke
			(width 0.05715)
			(type default)
		)
		(layer "B.Cu")
	)
	(gr_line
		(start 137.45464 -104.08539)
		(end 137.48004 -104.11079)
		(stroke
			(width 0.04445)
			(type default)
		)
		(layer "B.Cu")
	)
	(gr_line
		(start 137.45718 -102.532434)
		(end 137.5537 -102.435914)
		(stroke
			(width 0.04445)
			(type default)
		)
		(layer "B.Cu")
	)
	(gr_line
		(start 137.45718 -102.161594)
		(end 137.5537 -102.258114)
		(stroke
			(width 0.04445)
			(type default)
		)
		(layer "B.Cu")
	)
	(gr_line
		(start 137.48004 -104.11079)
		(end 137.48004 -104.132888)
		(stroke
			(width 0.04445)
			(type default)
		)
		(layer "B.Cu")
	)
	(gr_line
		(start 137.5537 -102.258114)
		(end 137.5537 -102.435914)
		(stroke
			(width 0.04445)
			(type default)
		)
		(layer "B.Cu")
	)
	(gr_line
		(start 137.670794 -96.518984)
		(end 137.96391 -96.688148)
		(stroke
			(width 0.04445)
			(type default)
		)
		(layer "B.Cu")
	)
	(gr_line
		(start 137.96391 -96.688148)
		(end 137.987278 -96.775524)
		(stroke
			(width 0.04445)
			(type default)
		)
		(layer "B.Cu")
	)
	(gr_line
		(start 138.159236 -96.866202)
		(end 138.236198 -96.845374)
		(stroke
			(width 0.04445)
			(type default)
		)
		(layer "B.Cu")
	)
	(gr_line
		(start 138.177778 -94.234)
		(end 138.182604 -94.242636)
		(stroke
			(width 0.04445)
			(type default)
		)
		(layer "B.Cu")
	)
	(gr_line
		(start 138.236198 -96.845374)
		(end 138.529314 -97.014538)
		(stroke
			(width 0.04445)
			(type default)
		)
		(layer "B.Cu")
	)
	(gr_line
		(start 138.529314 -96.023938)
		(end 138.82243 -95.854774)
		(stroke
			(width 0.04445)
			(type default)
		)
		(layer "B.Cu")
	)
	(gr_line
		(start 138.529314 -94.380812)
		(end 138.587226 -94.438724)
		(stroke
			(width 0.04445)
			(type default)
		)
		(layer "B.Cu")
	)
	(gr_line
		(start 138.529314 -94.042738)
		(end 138.529314 -94.380812)
		(stroke
			(width 0.04445)
			(type default)
		)
		(layer "B.Cu")
	)
	(gr_line
		(start 138.529314 -92.061538)
		(end 138.82243 -92.230448)
		(stroke
			(width 0.04445)
			(type default)
		)
		(layer "B.Cu")
	)
	(gr_arc
		(start 138.782298 -94.58071)
		(mid 138.596826 -94.77392)
		(end 138.529314 -95.033084)
		(stroke
			(width 0.04445)
			(type default)
		)
		(layer "B.Cu")
	)
	(gr_line
		(start 138.782298 -94.58071)
		(end 138.83894 -94.545912)
		(stroke
			(width 0.04445)
			(type default)
		)
		(layer "B.Cu")
	)
	(gr_line
		(start 138.82243 -95.854774)
		(end 138.899392 -95.875602)
		(stroke
			(width 0.04445)
			(type default)
		)
		(layer "B.Cu")
	)
	(gr_line
		(start 138.82243 -92.230448)
		(end 138.899646 -92.20962)
		(stroke
			(width 0.04445)
			(type default)
		)
		(layer "B.Cu")
	)
	(gr_line
		(start 139.07135 -95.784924)
		(end 139.094718 -95.697548)
		(stroke
			(width 0.04445)
			(type default)
		)
		(layer "B.Cu")
	)
	(gr_line
		(start 139.07135 -92.300298)
		(end 139.094718 -92.387674)
		(stroke
			(width 0.04445)
			(type default)
		)
		(layer "B.Cu")
	)
	(gr_line
		(start 139.094718 -95.697548)
		(end 139.387834 -95.528384)
		(stroke
			(width 0.04445)
			(type default)
		)
		(layer "B.Cu")
	)
	(gr_line
		(start 139.094718 -92.387674)
		(end 139.387834 -92.556584)
		(stroke
			(width 0.04445)
			(type default)
		)
		(layer "B.Cu")
	)
	(gr_line
		(start 139.376658 -95.12808)
		(end 139.376658 -95.128334)
		(stroke
			(width 0.04445)
			(type default)
		)
		(layer "B.Cu")
	)
	(gr_line
		(start 139.387834 -97.17151)
		(end 139.387834 -97.509584)
		(stroke
			(width 0.04445)
			(type default)
		)
		(layer "B.Cu")
	)
	(gr_line
		(start 139.387834 -97.17151)
		(end 139.408662 -97.150682)
		(stroke
			(width 0.04445)
			(type default)
		)
		(layer "B.Cu")
	)
	(gr_line
		(start 139.387834 -96.857058)
		(end 139.408662 -96.877886)
		(stroke
			(width 0.04445)
			(type default)
		)
		(layer "B.Cu")
	)
	(gr_line
		(start 139.387834 -96.518984)
		(end 139.387834 -96.857058)
		(stroke
			(width 0.04445)
			(type default)
		)
		(layer "B.Cu")
	)
	(gr_line
		(start 139.387834 -91.565984)
		(end 139.68095 -91.397074)
		(stroke
			(width 0.04445)
			(type default)
		)
		(layer "B.Cu")
	)
	(gr_line
		(start 139.387834 -90.23731)
		(end 139.387834 -90.575384)
		(stroke
			(width 0.04445)
			(type default)
		)
		(layer "B.Cu")
	)
	(gr_line
		(start 139.387834 -90.23731)
		(end 139.408662 -90.216482)
		(stroke
			(width 0.04445)
			(type default)
		)
		(layer "B.Cu")
	)
	(gr_line
		(start 139.387834 -89.922858)
		(end 139.408662 -89.943686)
		(stroke
			(width 0.04445)
			(type default)
		)
		(layer "B.Cu")
	)
	(gr_line
		(start 139.387834 -89.584784)
		(end 139.387834 -89.922858)
		(stroke
			(width 0.04445)
			(type default)
		)
		(layer "B.Cu")
	)
	(gr_line
		(start 139.41044 -97.148904)
		(end 139.452858 -97.106486)
		(stroke
			(width 0.04445)
			(type default)
		)
		(layer "B.Cu")
	)
	(gr_line
		(start 139.41044 -96.879664)
		(end 139.445746 -96.91497)
		(stroke
			(width 0.04445)
			(type default)
		)
		(layer "B.Cu")
	)
	(gr_line
		(start 139.41044 -90.214704)
		(end 139.452858 -90.172286)
		(stroke
			(width 0.04445)
			(type default)
		)
		(layer "B.Cu")
	)
	(gr_line
		(start 139.41044 -89.945464)
		(end 139.445746 -89.98077)
		(stroke
			(width 0.04445)
			(type default)
		)
		(layer "B.Cu")
	)
	(gr_line
		(start 139.68095 -91.397074)
		(end 139.701524 -91.320112)
		(stroke
			(width 0.04445)
			(type default)
		)
		(layer "B.Cu")
	)
	(gr_line
		(start 139.865862 -91.216226)
		(end 139.953238 -91.239848)
		(stroke
			(width 0.04445)
			(type default)
		)
		(layer "B.Cu")
	)
	(gr_line
		(start 139.953238 -91.239848)
		(end 140.246354 -91.070938)
		(stroke
			(width 0.04445)
			(type default)
		)
		(layer "B.Cu")
	)
	(gr_arc
		(start 140.246354 -95.033084)
		(mid 140.016565 -94.775926)
		(end 139.704318 -94.922086)
		(stroke
			(width 0.04445)
			(type default)
		)
		(layer "B.Cu")
	)
	(gr_line
		(start 140.585952 -92.839286)
		(end 140.586714 -92.841318)
		(stroke
			(width 0.04445)
			(type default)
		)
		(layer "B.Cu")
	)
	(gr_line
		(start 140.593064 -89.289636)
		(end 140.59789 -89.281)
		(stroke
			(width 0.04445)
			(type default)
		)
		(layer "B.Cu")
	)
	(gr_arc
		(start 140.602716 -89.897458)
		(mid 140.597923 -89.88893)
		(end 140.593064 -89.88044)
		(stroke
			(width 0.04445)
			(type default)
		)
		(layer "B.Cu")
	)
	(gr_line
		(start 140.602716 -89.897204)
		(end 140.602716 -89.897458)
		(stroke
			(width 0.04445)
			(type default)
		)
		(layer "B.Cu")
	)
	(gr_arc
		(start 140.753338 -92.7481)
		(mid 140.755721 -92.752434)
		(end 140.758164 -92.756736)
		(stroke
			(width 0.04445)
			(type default)
		)
		(layer "B.Cu")
	)
	(gr_line
		(start 141.28623 -93.287596)
		(end 141.37005 -93.371416)
		(stroke
			(width 0.04445)
			(type default)
		)
		(layer "B.Cu")
	)
	(gr_line
		(start 141.28623 -93.109796)
		(end 141.28623 -93.287596)
		(stroke
			(width 0.04445)
			(type default)
		)
		(layer "B.Cu")
	)
	(gr_line
		(start 141.28623 -93.109796)
		(end 141.37005 -93.025976)
		(stroke
			(width 0.04445)
			(type default)
		)
		(layer "B.Cu")
	)
	(gr_line
		(start 141.28623 -92.759276)
		(end 141.37005 -92.843096)
		(stroke
			(width 0.04445)
			(type default)
		)
		(layer "B.Cu")
	)
	(gr_line
		(start 141.28623 -92.581476)
		(end 141.28623 -92.759276)
		(stroke
			(width 0.04445)
			(type default)
		)
		(layer "B.Cu")
	)
	(gr_line
		(start 141.28623 -92.581476)
		(end 141.37005 -92.497656)
		(stroke
			(width 0.04445)
			(type default)
		)
		(layer "B.Cu")
	)
	(gr_line
		(start 141.28623 -92.230956)
		(end 141.37005 -92.314776)
		(stroke
			(width 0.04445)
			(type default)
		)
		(layer "B.Cu")
	)
	(gr_line
		(start 141.28623 -92.053156)
		(end 141.28623 -92.230956)
		(stroke
			(width 0.04445)
			(type default)
		)
		(layer "B.Cu")
	)
	(gr_line
		(start 141.28623 -92.053156)
		(end 141.37005 -91.969336)
		(stroke
			(width 0.04445)
			(type default)
		)
		(layer "B.Cu")
	)
	(gr_line
		(start 141.28623 -91.702636)
		(end 141.37005 -91.786456)
		(stroke
			(width 0.04445)
			(type default)
		)
		(layer "B.Cu")
	)
	(gr_line
		(start 141.28623 -91.524836)
		(end 141.28623 -91.702636)
		(stroke
			(width 0.04445)
			(type default)
		)
		(layer "B.Cu")
	)
	(gr_line
		(start 141.28623 -91.524836)
		(end 141.37005 -91.441016)
		(stroke
			(width 0.04445)
			(type default)
		)
		(layer "B.Cu")
	)
	(gr_line
		(start 141.28623 -91.174316)
		(end 141.37005 -91.258136)
		(stroke
			(width 0.04445)
			(type default)
		)
		(layer "B.Cu")
	)
	(gr_line
		(start 141.28623 -90.996516)
		(end 141.28623 -91.174316)
		(stroke
			(width 0.04445)
			(type default)
		)
		(layer "B.Cu")
	)
	(gr_line
		(start 141.28623 -90.996516)
		(end 141.37005 -90.912696)
		(stroke
			(width 0.04445)
			(type default)
		)
		(layer "B.Cu")
	)
	(gr_line
		(start 141.294612 -90.645996)
		(end 141.37005 -90.721434)
		(stroke
			(width 0.04445)
			(type default)
		)
		(layer "B.Cu")
	)
	(gr_line
		(start 141.294612 -90.468196)
		(end 141.294612 -90.645996)
		(stroke
			(width 0.04445)
			(type default)
		)
		(layer "B.Cu")
	)
	(gr_line
		(start 141.294612 -90.468196)
		(end 141.37005 -90.392758)
		(stroke
			(width 0.04445)
			(type default)
		)
		(layer "B.Cu")
	)
	(gr_line
		(start 141.37259 -94.080076)
		(end 141.376654 -94.08922)
		(stroke
			(width 0.04445)
			(type default)
		)
		(layer "B.Cu")
	)
	(gr_line
		(start 141.656562 -95.23603)
		(end 141.662404 -95.246952)
		(stroke
			(width 0.04445)
			(type default)
		)
		(layer "B.Cu")
	)
	(gr_line
		(start 142.342108 -95.776796)
		(end 142.44066 -95.875348)
		(stroke
			(width 0.04445)
			(type default)
		)
		(layer "B.Cu")
	)
	(gr_line
		(start 142.342108 -95.598996)
		(end 142.342108 -95.776796)
		(stroke
			(width 0.04445)
			(type default)
		)
		(layer "B.Cu")
	)
	(gr_line
		(start 142.342108 -95.598996)
		(end 142.44066 -95.500444)
		(stroke
			(width 0.04445)
			(type default)
		)
		(layer "B.Cu")
	)
	(gr_line
		(start 142.35684 -94.68739)
		(end 142.44066 -94.77121)
		(stroke
			(width 0.04445)
			(type default)
		)
		(layer "B.Cu")
	)
	(gr_line
		(start 142.35684 -94.50959)
		(end 142.35684 -94.68739)
		(stroke
			(width 0.04445)
			(type default)
		)
		(layer "B.Cu")
	)
	(gr_line
		(start 142.35684 -94.50959)
		(end 142.44066 -94.42577)
		(stroke
			(width 0.04445)
			(type default)
		)
		(layer "B.Cu")
	)
	(gr_line
		(start 142.35684 -93.73362)
		(end 142.44066 -93.81744)
		(stroke
			(width 0.04445)
			(type default)
		)
		(layer "B.Cu")
	)
	(gr_line
		(start 142.35684 -93.55582)
		(end 142.35684 -93.73362)
		(stroke
			(width 0.04445)
			(type default)
		)
		(layer "B.Cu")
	)
	(gr_line
		(start 142.35684 -93.55582)
		(end 142.44066 -93.472)
		(stroke
			(width 0.04445)
			(type default)
		)
		(layer "B.Cu")
	)
	(gr_line
		(start 142.35684 -92.67698)
		(end 142.44066 -92.7608)
		(stroke
			(width 0.04445)
			(type default)
		)
		(layer "B.Cu")
	)
	(gr_line
		(start 142.35684 -92.49918)
		(end 142.35684 -92.67698)
		(stroke
			(width 0.04445)
			(type default)
		)
		(layer "B.Cu")
	)
	(gr_line
		(start 142.35684 -92.49918)
		(end 142.44066 -92.41536)
		(stroke
			(width 0.04445)
			(type default)
		)
		(layer "B.Cu")
	)
	(gr_line
		(start 142.35684 -92.14866)
		(end 142.44066 -92.23248)
		(stroke
			(width 0.04445)
			(type default)
		)
		(layer "B.Cu")
	)
	(gr_line
		(start 142.35684 -91.97086)
		(end 142.35684 -92.14866)
		(stroke
			(width 0.04445)
			(type default)
		)
		(layer "B.Cu")
	)
	(gr_line
		(start 142.35684 -91.97086)
		(end 142.44066 -91.88704)
		(stroke
			(width 0.04445)
			(type default)
		)
		(layer "B.Cu")
	)
	(gr_line
		(start 142.35684 -91.62034)
		(end 142.44066 -91.70416)
		(stroke
			(width 0.04445)
			(type default)
		)
		(layer "B.Cu")
	)
	(gr_line
		(start 142.35684 -91.44254)
		(end 142.35684 -91.62034)
		(stroke
			(width 0.04445)
			(type default)
		)
		(layer "B.Cu")
	)
	(gr_line
		(start 142.35684 -91.44254)
		(end 142.44066 -91.35872)
		(stroke
			(width 0.04445)
			(type default)
		)
		(layer "B.Cu")
	)
	(gr_line
		(start 142.35684 -91.09202)
		(end 142.44066 -91.17584)
		(stroke
			(width 0.04445)
			(type default)
		)
		(layer "B.Cu")
	)
	(gr_line
		(start 142.35684 -90.91422)
		(end 142.35684 -91.09202)
		(stroke
			(width 0.04445)
			(type default)
		)
		(layer "B.Cu")
	)
	(gr_line
		(start 142.35684 -90.91422)
		(end 142.44066 -90.8304)
		(stroke
			(width 0.04445)
			(type default)
		)
		(layer "B.Cu")
	)
	(gr_line
		(start 142.62354 -90.033856)
		(end 142.6337 -90.051382)
		(stroke
			(width 0.04445)
			(type default)
		)
		(layer "B.Cu")
	)
	(gr_line
		(start 163.3474 -64.4398)
		(end 163.6268 -64.1604)
		(stroke
			(width 0.0635)
			(type default)
		)
		(layer "B.Cu")
	)
	(gr_line
		(start 163.6268 -64.1604)
		(end 165.0492 -64.1604)
		(stroke
			(width 0.0635)
			(type default)
		)
		(layer "B.Cu")
	)
	(gr_circle
		(center 169.214546 -0.980694)
		(end 169.468546 -0.980694)
		(stroke
			(width 0.2)
			(type default)
		)
		(fill no)
		(layer "B.Cu")
	)
	(gr_circle
		(center 170.3324 -74.3204)
		(end 170.5864 -74.3204)
		(stroke
			(width 0.2)
			(type default)
		)
		(fill no)
		(layer "B.Cu")
	)
	(gr_circle
		(center 176.9999 -94.7293)
		(end 177.2539 -94.7293)
		(stroke
			(width 0.2)
			(type default)
		)
		(fill no)
		(layer "B.Cu")
	)
	(gr_circle
		(center 181.3306 -89.6112)
		(end 181.5846 -89.6112)
		(stroke
			(width 0.2)
			(type default)
		)
		(fill no)
		(layer "B.Cu")
	)
	(gr_circle
		(center 181.3306 -88.9762)
		(end 181.5846 -88.9762)
		(stroke
			(width 0.2)
			(type default)
		)
		(fill no)
		(layer "B.Cu")
	)
	(gr_circle
		(center 181.3306 -88.3412)
		(end 181.5846 -88.3412)
		(stroke
			(width 0.2)
			(type default)
		)
		(fill no)
		(layer "B.Cu")
	)
	(gr_line
		(start 203.0222 -50.5714)
		(end 203.285344 -50.308256)
		(stroke
			(width 0.0635)
			(type default)
		)
		(layer "B.Cu")
	)
	(gr_line
		(start 203.0222 -49.6824)
		(end 203.285344 -49.945544)
		(stroke
			(width 0.0635)
			(type default)
		)
		(layer "B.Cu")
	)
	(gr_line
		(start 228.4603 -64.6557)
		(end 228.748844 -64.367156)
		(stroke
			(width 0.0635)
			(type default)
		)
		(layer "B.Cu")
	)
	(gr_line
		(start 229.111556 -64.367156)
		(end 229.3747 -64.6303)
		(stroke
			(width 0.0635)
			(type default)
		)
		(layer "B.Cu")
	)
	(gr_line
		(start 264.1346 -124.6886)
		(end 264.9982 -124.6886)
		(stroke
			(width 0.0635)
			(type default)
		)
		(layer "B.Cu")
	)
	(gr_line
		(start 264.38733 -134.9121)
		(end 265.254232 -134.9121)
		(stroke
			(width 0.2)
			(type default)
		)
		(layer "B.Cu")
	)
	(gr_line
		(start 264.67054 -124.03074)
		(end 264.9982 -124.3584)
		(stroke
			(width 0.0635)
			(type default)
		)
		(layer "B.Cu")
	)
	(gr_line
		(start 264.92454 -123.7742)
		(end 265.062716 -123.7742)
		(stroke
			(width 0.0635)
			(type default)
		)
		(layer "B.Cu")
	)
	(gr_line
		(start 264.9982 -124.3584)
		(end 264.9982 -124.6886)
		(stroke
			(width 0.0635)
			(type default)
		)
		(layer "B.Cu")
	)
	(gr_line
		(start 265.062716 -123.7742)
		(end 265.8872 -124.598684)
		(stroke
			(width 0.0635)
			(type default)
		)
		(layer "B.Cu")
	)
	(gr_line
		(start 265.8872 -124.6886)
		(end 266.7762 -124.6886)
		(stroke
			(width 0.0635)
			(type default)
		)
		(layer "B.Cu")
	)
	(gr_line
		(start 265.8872 -124.598684)
		(end 265.8872 -124.6886)
		(stroke
			(width 0.0635)
			(type default)
		)
		(layer "B.Cu")
	)
	(gr_line
		(start 276.0472 -29.337)
		(end 276.9362 -29.337)
		(stroke
			(width 0.0635)
			(type default)
		)
		(layer "B.Cu")
	)
	(gr_line
		(start 276.811486 -29.858208)
		(end 276.9362 -29.733494)
		(stroke
			(width 0.0635)
			(type default)
		)
		(layer "B.Cu")
	)
	(gr_line
		(start 276.9362 -29.337)
		(end 276.9362 -29.733494)
		(stroke
			(width 0.0635)
			(type default)
		)
		(layer "B.Cu")
	)
	(gr_line
		(start 277.065486 -30.114748)
		(end 277.448772 -30.114748)
		(stroke
			(width 0.0635)
			(type default)
		)
		(layer "B.Cu")
	)
	(gr_line
		(start 277.448772 -30.114748)
		(end 277.8252 -29.73832)
		(stroke
			(width 0.0635)
			(type default)
		)
		(layer "B.Cu")
	)
	(gr_line
		(start 277.8252 -29.337)
		(end 277.8252 -29.73832)
		(stroke
			(width 0.0635)
			(type default)
		)
		(layer "B.Cu")
	)
	(gr_line
		(start 277.8252 -29.337)
		(end 278.7142 -29.337)
		(stroke
			(width 0.0635)
			(type default)
		)
		(layer "B.Cu")
	)
	(gr_circle
		(center 321.0052 -154.1272)
		(end 321.2592 -154.1272)
		(stroke
			(width 0.2)
			(type default)
		)
		(fill no)
		(layer "B.Cu")
	)
	(gr_line
		(start 328.048112 4.018534)
		(end 328.629264 3.437382)
		(stroke
			(width 0.0635)
			(type default)
		)
		(layer "B.Cu")
	)
	(gr_line
		(start 328.048112 4.06146)
		(end 328.048112 4.018534)
		(stroke
			(width 0.0635)
			(type default)
		)
		(layer "B.Cu")
	)
	(gr_line
		(start 328.048112 4.097274)
		(end 328.048112 4.06654)
		(stroke
			(width 0.0635)
			(type default)
		)
		(layer "B.Cu")
	)
	(gr_line
		(start 328.186796 4.318)
		(end 328.299572 4.318)
		(stroke
			(width 0.0635)
			(type default)
		)
		(layer "B.Cu")
	)
	(gr_line
		(start 328.304652 4.318)
		(end 328.5744 4.318)
		(stroke
			(width 0.0635)
			(type default)
		)
		(layer "B.Cu")
	)
	(gr_line
		(start 333.346806 -61.257434)
		(end 334.04302 -61.953648)
		(stroke
			(width 0.05715)
			(type default)
		)
		(layer "B.Cu")
	)
	(gr_line
		(start 333.346806 -60.368434)
		(end 334.01 -60.368434)
		(stroke
			(width 0.05715)
			(type default)
		)
		(layer "B.Cu")
	)
	(gr_line
		(start 333.346806 -59.479434)
		(end 333.463138 -59.479434)
		(stroke
			(width 0.05715)
			(type default)
		)
		(layer "B.Cu")
	)
	(gr_line
		(start 333.463138 -59.479434)
		(end 333.9846 -58.957972)
		(stroke
			(width 0.05715)
			(type default)
		)
		(layer "B.Cu")
	)
	(gr_line
		(start 334.01 -60.36183)
		(end 334.01 -60.368434)
		(stroke
			(width 0.05715)
			(type default)
		)
		(layer "B.Cu")
	)
	(gr_line
		(start 334.01 -60.36183)
		(end 334.0354 -60.36183)
		(stroke
			(width 0.05715)
			(type default)
		)
		(layer "B.Cu")
	)
	(gr_line
		(start 334.28686 -61.71438)
		(end 334.743806 -61.257434)
		(stroke
			(width 0.05715)
			(type default)
		)
		(layer "B.Cu")
	)
	(gr_line
		(start 334.743806 -60.368434)
		(end 335.353406 -60.368434)
		(stroke
			(width 0.05715)
			(type default)
		)
		(layer "B.Cu")
	)
	(gr_line
		(start 334.743806 -59.479434)
		(end 334.860138 -59.479434)
		(stroke
			(width 0.05715)
			(type default)
		)
		(layer "B.Cu")
	)
	(gr_line
		(start 334.860138 -59.479434)
		(end 335.3816 -58.957972)
		(stroke
			(width 0.05715)
			(type default)
		)
		(layer "B.Cu")
	)
	(gr_line
		(start 334.962754 -71.81342)
		(end 335.236058 -71.540116)
		(stroke
			(width 0.05715)
			(type default)
		)
		(layer "B.Cu")
	)
	(gr_line
		(start 335.580736 -71.540116)
		(end 335.85404 -71.81342)
		(stroke
			(width 0.05715)
			(type default)
		)
		(layer "B.Cu")
	)
	(gr_line
		(start 336.140806 -61.541406)
		(end 336.695034 -62.095634)
		(stroke
			(width 0.05715)
			(type default)
		)
		(layer "B.Cu")
	)
	(gr_line
		(start 336.140806 -61.257434)
		(end 336.140806 -61.541406)
		(stroke
			(width 0.05715)
			(type default)
		)
		(layer "B.Cu")
	)
	(gr_line
		(start 336.140806 -60.368434)
		(end 336.720434 -60.368434)
		(stroke
			(width 0.05715)
			(type default)
		)
		(layer "B.Cu")
	)
	(gr_line
		(start 336.140806 -59.479434)
		(end 336.257138 -59.479434)
		(stroke
			(width 0.05715)
			(type default)
		)
		(layer "B.Cu")
	)
	(gr_line
		(start 336.228436 -71.034402)
		(end 336.4992 -70.763638)
		(stroke
			(width 0.05715)
			(type default)
		)
		(layer "B.Cu")
	)
	(gr_line
		(start 336.257138 -59.479434)
		(end 336.7786 -58.957972)
		(stroke
			(width 0.05715)
			(type default)
		)
		(layer "B.Cu")
	)
	(gr_line
		(start 336.720434 -60.368434)
		(end 336.7786 -60.4266)
		(stroke
			(width 0.05715)
			(type default)
		)
		(layer "B.Cu")
	)
	(gr_line
		(start 336.74304 -70.65772)
		(end 337.119722 -71.034402)
		(stroke
			(width 0.05715)
			(type default)
		)
		(layer "B.Cu")
	)
	(gr_line
		(start 337.039966 -62.095634)
		(end 337.537806 -61.597794)
		(stroke
			(width 0.05715)
			(type default)
		)
		(layer "B.Cu")
	)
	(gr_line
		(start 337.537806 -61.257434)
		(end 337.537806 -61.597794)
		(stroke
			(width 0.05715)
			(type default)
		)
		(layer "B.Cu")
	)
	(gr_line
		(start 337.537806 -60.368434)
		(end 338.117434 -60.368434)
		(stroke
			(width 0.05715)
			(type default)
		)
		(layer "B.Cu")
	)
	(gr_line
		(start 337.537806 -59.479434)
		(end 337.654138 -59.479434)
		(stroke
			(width 0.05715)
			(type default)
		)
		(layer "B.Cu")
	)
	(gr_line
		(start 337.654138 -59.479434)
		(end 338.1756 -58.957972)
		(stroke
			(width 0.05715)
			(type default)
		)
		(layer "B.Cu")
	)
	(gr_line
		(start 337.863434 -70.11289)
		(end 338.138262 -69.837808)
		(stroke
			(width 0.05715)
			(type default)
		)
		(layer "B.Cu")
	)
	(gr_line
		(start 338.117434 -60.368434)
		(end 338.1756 -60.4266)
		(stroke
			(width 0.05715)
			(type default)
		)
		(layer "B.Cu")
	)
	(gr_line
		(start 338.481416 -69.839586)
		(end 338.75472 -70.11289)
		(stroke
			(width 0.05715)
			(type default)
		)
		(layer "B.Cu")
	)
	(gr_line
		(start 338.709 -90.551)
		(end 339.210396 -90.049604)
		(stroke
			(width 0.0635)
			(type default)
		)
		(layer "B.Cu")
	)
	(gr_line
		(start 338.709 -90.551)
		(end 339.691472 -91.533472)
		(stroke
			(width 0.0635)
			(type default)
		)
		(layer "B.Cu")
	)
	(gr_line
		(start 338.76996 -78.72476)
		(end 339.279484 -79.234284)
		(stroke
			(width 0.05715)
			(type default)
		)
		(layer "B.Cu")
	)
	(gr_line
		(start 338.76996 -78.583536)
		(end 338.76996 -78.72476)
		(stroke
			(width 0.05715)
			(type default)
		)
		(layer "B.Cu")
	)
	(gr_line
		(start 338.76996 -77.694536)
		(end 339.18906 -77.694536)
		(stroke
			(width 0.05715)
			(type default)
		)
		(layer "B.Cu")
	)
	(gr_line
		(start 338.76996 -76.805536)
		(end 339.115146 -76.805536)
		(stroke
			(width 0.05715)
			(type default)
		)
		(layer "B.Cu")
	)
	(gr_line
		(start 338.934806 -61.257434)
		(end 339.46084 -61.783468)
		(stroke
			(width 0.05715)
			(type default)
		)
		(layer "B.Cu")
	)
	(gr_line
		(start 338.934806 -60.368434)
		(end 339.514434 -60.368434)
		(stroke
			(width 0.05715)
			(type default)
		)
		(layer "B.Cu")
	)
	(gr_line
		(start 338.934806 -59.479434)
		(end 339.051138 -59.479434)
		(stroke
			(width 0.05715)
			(type default)
		)
		(layer "B.Cu")
	)
	(gr_line
		(start 339.051138 -59.479434)
		(end 339.5726 -58.957972)
		(stroke
			(width 0.05715)
			(type default)
		)
		(layer "B.Cu")
	)
	(gr_line
		(start 339.115146 -76.805536)
		(end 339.40496 -76.515722)
		(stroke
			(width 0.05715)
			(type default)
		)
		(layer "B.Cu")
	)
	(gr_line
		(start 339.18906 -77.694536)
		(end 339.40496 -77.910436)
		(stroke
			(width 0.05715)
			(type default)
		)
		(layer "B.Cu")
	)
	(gr_line
		(start 339.210396 -90.049604)
		(end 339.717126 -90.049604)
		(stroke
			(width 0.0635)
			(type default)
		)
		(layer "B.Cu")
	)
	(gr_line
		(start 339.40496 -77.910436)
		(end 339.40496 -77.91704)
		(stroke
			(width 0.05715)
			(type default)
		)
		(layer "B.Cu")
	)
	(gr_line
		(start 339.457792 -69.02577)
		(end 339.767926 -68.715636)
		(stroke
			(width 0.05715)
			(type default)
		)
		(layer "B.Cu")
	)
	(gr_line
		(start 339.514434 -60.368434)
		(end 339.5726 -60.4266)
		(stroke
			(width 0.05715)
			(type default)
		)
		(layer "B.Cu")
	)
	(gr_line
		(start 339.624416 -79.234284)
		(end 339.69706 -79.16164)
		(stroke
			(width 0.05715)
			(type default)
		)
		(layer "B.Cu")
	)
	(gr_line
		(start 339.691472 -91.533472)
		(end 340.856316 -91.533472)
		(stroke
			(width 0.0635)
			(type default)
		)
		(layer "B.Cu")
	)
	(gr_line
		(start 339.69706 -79.16164)
		(end 340.05266 -79.16164)
		(stroke
			(width 0.05715)
			(type default)
		)
		(layer "B.Cu")
	)
	(gr_line
		(start 339.805772 -61.783468)
		(end 340.331806 -61.257434)
		(stroke
			(width 0.05715)
			(type default)
		)
		(layer "B.Cu")
	)
	(gr_line
		(start 340.05266 -79.16164)
		(end 340.16696 -79.04734)
		(stroke
			(width 0.05715)
			(type default)
		)
		(layer "B.Cu")
	)
	(gr_line
		(start 340.112858 -68.715636)
		(end 340.422992 -69.02577)
		(stroke
			(width 0.05715)
			(type default)
		)
		(layer "B.Cu")
	)
	(gr_line
		(start 340.16696 -78.583536)
		(end 340.16696 -79.04734)
		(stroke
			(width 0.05715)
			(type default)
		)
		(layer "B.Cu")
	)
	(gr_line
		(start 340.16696 -77.694536)
		(end 340.58606 -77.694536)
		(stroke
			(width 0.05715)
			(type default)
		)
		(layer "B.Cu")
	)
	(gr_line
		(start 340.16696 -76.805536)
		(end 340.512146 -76.805536)
		(stroke
			(width 0.05715)
			(type default)
		)
		(layer "B.Cu")
	)
	(gr_line
		(start 340.331806 -60.368434)
		(end 340.911434 -60.368434)
		(stroke
			(width 0.05715)
			(type default)
		)
		(layer "B.Cu")
	)
	(gr_line
		(start 340.331806 -59.479434)
		(end 340.448138 -59.479434)
		(stroke
			(width 0.05715)
			(type default)
		)
		(layer "B.Cu")
	)
	(gr_line
		(start 340.448138 -59.479434)
		(end 340.9696 -58.957972)
		(stroke
			(width 0.05715)
			(type default)
		)
		(layer "B.Cu")
	)
	(gr_line
		(start 340.512146 -76.805536)
		(end 340.80196 -76.515722)
		(stroke
			(width 0.05715)
			(type default)
		)
		(layer "B.Cu")
	)
	(gr_line
		(start 340.58606 -77.694536)
		(end 340.80196 -77.910436)
		(stroke
			(width 0.05715)
			(type default)
		)
		(layer "B.Cu")
	)
	(gr_line
		(start 340.607904 -80.80375)
		(end 340.70925 -80.905096)
		(stroke
			(width 0.05715)
			(type default)
		)
		(layer "B.Cu")
	)
	(gr_line
		(start 340.607904 -80.459072)
		(end 340.70925 -80.357726)
		(stroke
			(width 0.05715)
			(type default)
		)
		(layer "B.Cu")
	)
	(gr_line
		(start 340.70925 -80.905096)
		(end 340.70925 -81.19745)
		(stroke
			(width 0.05715)
			(type default)
		)
		(layer "B.Cu")
	)
	(gr_line
		(start 340.70925 -79.92745)
		(end 340.70925 -80.357726)
		(stroke
			(width 0.05715)
			(type default)
		)
		(layer "B.Cu")
	)
	(gr_line
		(start 340.80196 -77.910436)
		(end 340.80196 -77.91704)
		(stroke
			(width 0.05715)
			(type default)
		)
		(layer "B.Cu")
	)
	(gr_line
		(start 340.911434 -60.368434)
		(end 340.9696 -60.4266)
		(stroke
			(width 0.05715)
			(type default)
		)
		(layer "B.Cu")
	)
	(gr_line
		(start 341.291672 -68.09613)
		(end 341.601806 -67.785996)
		(stroke
			(width 0.05715)
			(type default)
		)
		(layer "B.Cu")
	)
	(gr_line
		(start 341.561674 -90.850212)
		(end 341.561674 -91.330018)
		(stroke
			(width 0.0635)
			(type default)
		)
		(layer "B.Cu")
	)
	(gr_line
		(start 341.561674 -90.850212)
		(end 342.222328 -90.189558)
		(stroke
			(width 0.0635)
			(type default)
		)
		(layer "B.Cu")
	)
	(gr_line
		(start 341.666068 -78.583536)
		(end 341.8332 -78.750668)
		(stroke
			(width 0.05715)
			(type default)
		)
		(layer "B.Cu")
	)
	(gr_line
		(start 341.666068 -77.694536)
		(end 342.085168 -77.694536)
		(stroke
			(width 0.05715)
			(type default)
		)
		(layer "B.Cu")
	)
	(gr_line
		(start 341.666068 -76.805536)
		(end 341.996014 -76.805536)
		(stroke
			(width 0.05715)
			(type default)
		)
		(layer "B.Cu")
	)
	(gr_line
		(start 341.7189 -80.507586)
		(end 341.83066 -80.619346)
		(stroke
			(width 0.05715)
			(type default)
		)
		(layer "B.Cu")
	)
	(gr_line
		(start 341.7189 -80.164686)
		(end 341.7189 -80.507586)
		(stroke
			(width 0.05715)
			(type default)
		)
		(layer "B.Cu")
	)
	(gr_line
		(start 341.7189 -80.164686)
		(end 341.83066 -80.052926)
		(stroke
			(width 0.05715)
			(type default)
		)
		(layer "B.Cu")
	)
	(gr_line
		(start 341.7189 -79.593186)
		(end 341.83066 -79.704946)
		(stroke
			(width 0.05715)
			(type default)
		)
		(layer "B.Cu")
	)
	(gr_line
		(start 341.7189 -79.250286)
		(end 341.7189 -79.593186)
		(stroke
			(width 0.05715)
			(type default)
		)
		(layer "B.Cu")
	)
	(gr_line
		(start 341.7189 -79.250286)
		(end 341.8332 -79.135986)
		(stroke
			(width 0.05715)
			(type default)
		)
		(layer "B.Cu")
	)
	(gr_line
		(start 341.728806 -61.257434)
		(end 342.25484 -61.783468)
		(stroke
			(width 0.05715)
			(type default)
		)
		(layer "B.Cu")
	)
	(gr_line
		(start 341.728806 -60.368434)
		(end 342.308434 -60.368434)
		(stroke
			(width 0.05715)
			(type default)
		)
		(layer "B.Cu")
	)
	(gr_line
		(start 341.728806 -59.479434)
		(end 341.845138 -59.479434)
		(stroke
			(width 0.05715)
			(type default)
		)
		(layer "B.Cu")
	)
	(gr_line
		(start 341.8332 -78.750668)
		(end 341.8332 -79.03972)
		(stroke
			(width 0.05715)
			(type default)
		)
		(layer "B.Cu")
	)
	(gr_line
		(start 341.845138 -59.479434)
		(end 342.3666 -58.957972)
		(stroke
			(width 0.05715)
			(type default)
		)
		(layer "B.Cu")
	)
	(gr_line
		(start 341.946738 -67.785996)
		(end 342.256872 -68.09613)
		(stroke
			(width 0.05715)
			(type default)
		)
		(layer "B.Cu")
	)
	(gr_line
		(start 341.996014 -76.805536)
		(end 342.364568 -76.436982)
		(stroke
			(width 0.05715)
			(type default)
		)
		(layer "B.Cu")
	)
	(gr_line
		(start 342.0745 -80.294226)
		(end 342.0745 -80.378046)
		(stroke
			(width 0.05715)
			(type default)
		)
		(layer "B.Cu")
	)
	(gr_line
		(start 342.0745 -79.379826)
		(end 342.0745 -79.463646)
		(stroke
			(width 0.05715)
			(type default)
		)
		(layer "B.Cu")
	)
	(gr_line
		(start 342.0745 -79.28356)
		(end 342.1888 -79.16926)
		(stroke
			(width 0.05715)
			(type default)
		)
		(layer "B.Cu")
	)
	(gr_line
		(start 342.085168 -77.694536)
		(end 342.301068 -77.910436)
		(stroke
			(width 0.05715)
			(type default)
		)
		(layer "B.Cu")
	)
	(gr_line
		(start 342.1888 -79.16926)
		(end 342.59266 -79.16926)
		(stroke
			(width 0.05715)
			(type default)
		)
		(layer "B.Cu")
	)
	(gr_line
		(start 342.222328 -90.189558)
		(end 342.642952 -90.189558)
		(stroke
			(width 0.0635)
			(type default)
		)
		(layer "B.Cu")
	)
	(gr_line
		(start 342.301068 -77.910436)
		(end 342.301068 -77.91704)
		(stroke
			(width 0.05715)
			(type default)
		)
		(layer "B.Cu")
	)
	(gr_line
		(start 342.308434 -60.368434)
		(end 342.3666 -60.4266)
		(stroke
			(width 0.05715)
			(type default)
		)
		(layer "B.Cu")
	)
	(gr_line
		(start 342.364568 -76.134214)
		(end 342.364568 -76.436982)
		(stroke
			(width 0.05715)
			(type default)
		)
		(layer "B.Cu")
	)
	(gr_line
		(start 342.381332 -81.272126)
		(end 342.680036 -81.57083)
		(stroke
			(width 0.05715)
			(type default)
		)
		(layer "B.Cu")
	)
	(gr_line
		(start 342.381332 -80.927448)
		(end 342.680036 -80.628744)
		(stroke
			(width 0.05715)
			(type default)
		)
		(layer "B.Cu")
	)
	(gr_line
		(start 342.536526 -53.07584)
		(end 342.900254 -53.07584)
		(stroke
			(width 0.0635)
			(type default)
		)
		(layer "B.Cu")
	)
	(gr_line
		(start 342.59266 -79.16926)
		(end 342.5952 -79.1718)
		(stroke
			(width 0.05715)
			(type default)
		)
		(layer "B.Cu")
	)
	(gr_line
		(start 342.5952 -79.1718)
		(end 343.063068 -78.703932)
		(stroke
			(width 0.05715)
			(type default)
		)
		(layer "B.Cu")
	)
	(gr_line
		(start 342.599772 -61.783468)
		(end 343.125806 -61.257434)
		(stroke
			(width 0.05715)
			(type default)
		)
		(layer "B.Cu")
	)
	(gr_line
		(start 342.642952 -90.189558)
		(end 342.88984 -90.189558)
		(stroke
			(width 0.0635)
			(type default)
		)
		(layer "B.Cu")
	)
	(gr_line
		(start 342.88984 -90.189558)
		(end 343.8271 -89.252298)
		(stroke
			(width 0.0635)
			(type default)
		)
		(layer "B.Cu")
	)
	(gr_line
		(start 342.900254 -53.07584)
		(end 343.021412 -52.954682)
		(stroke
			(width 0.0635)
			(type default)
		)
		(layer "B.Cu")
	)
	(gr_line
		(start 343.02319 -52.952904)
		(end 343.07018 -52.905914)
		(stroke
			(width 0.0635)
			(type default)
		)
		(layer "B.Cu")
	)
	(gr_line
		(start 343.063068 -78.583536)
		(end 343.063068 -78.703932)
		(stroke
			(width 0.05715)
			(type default)
		)
		(layer "B.Cu")
	)
	(gr_line
		(start 343.063068 -77.694536)
		(end 343.482168 -77.694536)
		(stroke
			(width 0.05715)
			(type default)
		)
		(layer "B.Cu")
	)
	(gr_line
		(start 343.063068 -76.805536)
		(end 343.393014 -76.805536)
		(stroke
			(width 0.05715)
			(type default)
		)
		(layer "B.Cu")
	)
	(gr_line
		(start 343.125806 -60.368434)
		(end 343.705434 -60.368434)
		(stroke
			(width 0.05715)
			(type default)
		)
		(layer "B.Cu")
	)
	(gr_line
		(start 343.125806 -59.479434)
		(end 343.242138 -59.479434)
		(stroke
			(width 0.05715)
			(type default)
		)
		(layer "B.Cu")
	)
	(gr_line
		(start 343.242138 -59.479434)
		(end 343.7636 -58.957972)
		(stroke
			(width 0.05715)
			(type default)
		)
		(layer "B.Cu")
	)
	(gr_line
		(start 343.29878 -52.905406)
		(end 343.346278 -52.952904)
		(stroke
			(width 0.0635)
			(type default)
		)
		(layer "B.Cu")
	)
	(gr_line
		(start 343.348056 -52.954682)
		(end 343.469214 -53.07584)
		(stroke
			(width 0.0635)
			(type default)
		)
		(layer "B.Cu")
	)
	(gr_line
		(start 343.393014 -76.805536)
		(end 343.832688 -76.365862)
		(stroke
			(width 0.05715)
			(type default)
		)
		(layer "B.Cu")
	)
	(gr_line
		(start 343.469214 -53.07584)
		(end 343.806526 -53.07584)
		(stroke
			(width 0.0635)
			(type default)
		)
		(layer "B.Cu")
	)
	(gr_line
		(start 343.482168 -77.694536)
		(end 343.698068 -77.910436)
		(stroke
			(width 0.05715)
			(type default)
		)
		(layer "B.Cu")
	)
	(gr_line
		(start 343.526872 -67.48653)
		(end 343.837006 -67.176396)
		(stroke
			(width 0.05715)
			(type default)
		)
		(layer "B.Cu")
	)
	(gr_line
		(start 343.698068 -77.910436)
		(end 343.698068 -77.91704)
		(stroke
			(width 0.05715)
			(type default)
		)
		(layer "B.Cu")
	)
	(gr_line
		(start 343.705434 -60.368434)
		(end 343.7636 -60.4266)
		(stroke
			(width 0.05715)
			(type default)
		)
		(layer "B.Cu")
	)
	(gr_line
		(start 343.8271 -89.252298)
		(end 344.0811 -89.252298)
		(stroke
			(width 0.0635)
			(type default)
		)
		(layer "B.Cu")
	)
	(gr_line
		(start 343.832688 -76.09967)
		(end 343.832688 -76.365862)
		(stroke
			(width 0.05715)
			(type default)
		)
		(layer "B.Cu")
	)
	(gr_line
		(start 344.181938 -67.176396)
		(end 344.492072 -67.48653)
		(stroke
			(width 0.05715)
			(type default)
		)
		(layer "B.Cu")
	)
	(gr_circle
		(center 344.1954 -36.83)
		(end 344.4494 -36.83)
		(stroke
			(width 0.2)
			(type default)
		)
		(fill no)
		(layer "B.Cu")
	)
	(gr_line
		(start 344.43416 -79.906876)
		(end 344.54592 -80.018636)
		(stroke
			(width 0.05715)
			(type default)
		)
		(layer "B.Cu")
	)
	(gr_line
		(start 344.43416 -79.563976)
		(end 344.43416 -79.906876)
		(stroke
			(width 0.05715)
			(type default)
		)
		(layer "B.Cu")
	)
	(gr_line
		(start 344.43416 -79.563976)
		(end 344.54592 -79.452216)
		(stroke
			(width 0.05715)
			(type default)
		)
		(layer "B.Cu")
	)
	(gr_line
		(start 344.435176 -78.697836)
		(end 344.671396 -78.934056)
		(stroke
			(width 0.05715)
			(type default)
		)
		(layer "B.Cu")
	)
	(gr_line
		(start 344.435176 -78.583536)
		(end 344.435176 -78.697836)
		(stroke
			(width 0.05715)
			(type default)
		)
		(layer "B.Cu")
	)
	(gr_line
		(start 344.435176 -77.694536)
		(end 344.872056 -77.694536)
		(stroke
			(width 0.05715)
			(type default)
		)
		(layer "B.Cu")
	)
	(gr_line
		(start 344.435176 -76.805536)
		(end 344.808556 -76.805536)
		(stroke
			(width 0.05715)
			(type default)
		)
		(layer "B.Cu")
	)
	(gr_line
		(start 344.522806 -61.257434)
		(end 345.04884 -61.783468)
		(stroke
			(width 0.05715)
			(type default)
		)
		(layer "B.Cu")
	)
	(gr_line
		(start 344.522806 -60.368434)
		(end 345.102434 -60.368434)
		(stroke
			(width 0.05715)
			(type default)
		)
		(layer "B.Cu")
	)
	(gr_line
		(start 344.522806 -59.479434)
		(end 344.639138 -59.479434)
		(stroke
			(width 0.05715)
			(type default)
		)
		(layer "B.Cu")
	)
	(gr_line
		(start 344.639138 -59.479434)
		(end 345.1606 -58.957972)
		(stroke
			(width 0.05715)
			(type default)
		)
		(layer "B.Cu")
	)
	(gr_line
		(start 344.671396 -79.09052)
		(end 344.671396 -79.106268)
		(stroke
			(width 0.05715)
			(type default)
		)
		(layer "B.Cu")
	)
	(gr_line
		(start 344.671396 -78.934056)
		(end 344.671396 -78.96098)
		(stroke
			(width 0.05715)
			(type default)
		)
		(layer "B.Cu")
	)
	(gr_line
		(start 344.78976 -79.693516)
		(end 344.78976 -79.777336)
		(stroke
			(width 0.05715)
			(type default)
		)
		(layer "B.Cu")
	)
	(gr_line
		(start 344.78976 -79.32928)
		(end 344.78976 -79.345028)
		(stroke
			(width 0.05715)
			(type default)
		)
		(layer "B.Cu")
	)
	(gr_line
		(start 344.808556 -76.805536)
		(end 345.062556 -76.551536)
		(stroke
			(width 0.05715)
			(type default)
		)
		(layer "B.Cu")
	)
	(gr_line
		(start 344.872056 -77.694536)
		(end 345.070176 -77.892656)
		(stroke
			(width 0.05715)
			(type default)
		)
		(layer "B.Cu")
	)
	(gr_line
		(start 344.915236 -79.20482)
		(end 345.278964 -79.20482)
		(stroke
			(width 0.05715)
			(type default)
		)
		(layer "B.Cu")
	)
	(gr_line
		(start 345.062556 -76.40701)
		(end 345.062556 -76.551536)
		(stroke
			(width 0.05715)
			(type default)
		)
		(layer "B.Cu")
	)
	(gr_line
		(start 345.070176 -77.892656)
		(end 345.070176 -77.89926)
		(stroke
			(width 0.05715)
			(type default)
		)
		(layer "B.Cu")
	)
	(gr_line
		(start 345.102434 -60.368434)
		(end 345.1606 -60.4266)
		(stroke
			(width 0.05715)
			(type default)
		)
		(layer "B.Cu")
	)
	(gr_line
		(start 345.204542 -80.671416)
		(end 345.514676 -80.98155)
		(stroke
			(width 0.05715)
			(type default)
		)
		(layer "B.Cu")
	)
	(gr_line
		(start 345.204542 -80.326484)
		(end 345.514676 -80.01635)
		(stroke
			(width 0.05715)
			(type default)
		)
		(layer "B.Cu")
	)
	(gr_line
		(start 345.278964 -79.20482)
		(end 345.832176 -78.651608)
		(stroke
			(width 0.05715)
			(type default)
		)
		(layer "B.Cu")
	)
	(gr_line
		(start 345.393772 -61.783468)
		(end 345.919806 -61.257434)
		(stroke
			(width 0.05715)
			(type default)
		)
		(layer "B.Cu")
	)
	(gr_circle
		(center 345.4654 -36.83)
		(end 345.7194 -36.83)
		(stroke
			(width 0.2)
			(type default)
		)
		(fill no)
		(layer "B.Cu")
	)
	(gr_circle
		(center 345.62542 -32.766)
		(end 345.87942 -32.766)
		(stroke
			(width 0.2)
			(type default)
		)
		(fill no)
		(layer "B.Cu")
	)
	(gr_line
		(start 345.628214 -123.576842)
		(end 346.079064 -123.125992)
		(stroke
			(width 0.05715)
			(type default)
		)
		(layer "B.Cu")
	)
	(gr_line
		(start 345.659202 -122.344942)
		(end 346.196412 -122.882152)
		(stroke
			(width 0.05715)
			(type default)
		)
		(layer "B.Cu")
	)
	(gr_line
		(start 345.832176 -78.583536)
		(end 345.832176 -78.651608)
		(stroke
			(width 0.05715)
			(type default)
		)
		(layer "B.Cu")
	)
	(gr_line
		(start 345.832176 -77.694536)
		(end 346.262452 -77.694536)
		(stroke
			(width 0.05715)
			(type default)
		)
		(layer "B.Cu")
	)
	(gr_line
		(start 345.832176 -76.805536)
		(end 346.144088 -76.805536)
		(stroke
			(width 0.05715)
			(type default)
		)
		(layer "B.Cu")
	)
	(gr_line
		(start 345.919806 -60.368434)
		(end 346.499434 -60.368434)
		(stroke
			(width 0.05715)
			(type default)
		)
		(layer "B.Cu")
	)
	(gr_line
		(start 345.919806 -59.479434)
		(end 346.036138 -59.479434)
		(stroke
			(width 0.05715)
			(type default)
		)
		(layer "B.Cu")
	)
	(gr_line
		(start 346.036138 -59.479434)
		(end 346.5576 -58.957972)
		(stroke
			(width 0.05715)
			(type default)
		)
		(layer "B.Cu")
	)
	(gr_line
		(start 346.144088 -76.805536)
		(end 346.459556 -76.490068)
		(stroke
			(width 0.05715)
			(type default)
		)
		(layer "B.Cu")
	)
	(gr_line
		(start 346.151962 -67.44335)
		(end 346.371672 -67.66306)
		(stroke
			(width 0.05715)
			(type default)
		)
		(layer "B.Cu")
	)
	(gr_line
		(start 346.161614 -125.177042)
		(end 346.595192 -125.61062)
		(stroke
			(width 0.05715)
			(type default)
		)
		(layer "B.Cu")
	)
	(gr_line
		(start 346.17152 -126.379224)
		(end 346.595192 -125.955552)
		(stroke
			(width 0.05715)
			(type default)
		)
		(layer "B.Cu")
	)
	(gr_line
		(start 346.262452 -77.694536)
		(end 346.467176 -77.89926)
		(stroke
			(width 0.05715)
			(type default)
		)
		(layer "B.Cu")
	)
	(gr_circle
		(center 346.38742 -32.766)
		(end 346.64142 -32.766)
		(stroke
			(width 0.2)
			(type default)
		)
		(fill no)
		(layer "B.Cu")
	)
	(gr_line
		(start 346.459556 -76.40701)
		(end 346.459556 -76.490068)
		(stroke
			(width 0.05715)
			(type default)
		)
		(layer "B.Cu")
	)
	(gr_line
		(start 346.499434 -60.368434)
		(end 346.5576 -60.4266)
		(stroke
			(width 0.05715)
			(type default)
		)
		(layer "B.Cu")
	)
	(gr_line
		(start 346.615512 -67.541394)
		(end 346.713556 -67.44335)
		(stroke
			(width 0.05715)
			(type default)
		)
		(layer "B.Cu")
	)
	(gr_line
		(start 346.713556 -67.44335)
		(end 347.043248 -67.44335)
		(stroke
			(width 0.05715)
			(type default)
		)
		(layer "B.Cu")
	)
	(gr_circle
		(center 346.7354 -36.83)
		(end 346.9894 -36.83)
		(stroke
			(width 0.2)
			(type default)
		)
		(fill no)
		(layer "B.Cu")
	)
	(gr_line
		(start 346.86494 -79.909162)
		(end 346.9767 -80.020922)
		(stroke
			(width 0.05715)
			(type default)
		)
		(layer "B.Cu")
	)
	(gr_line
		(start 346.86494 -79.566262)
		(end 346.86494 -79.909162)
		(stroke
			(width 0.05715)
			(type default)
		)
		(layer "B.Cu")
	)
	(gr_line
		(start 346.86494 -79.566262)
		(end 346.941394 -79.489808)
		(stroke
			(width 0.05715)
			(type default)
		)
		(layer "B.Cu")
	)
	(gr_line
		(start 347.042486 -123.600972)
		(end 347.066616 -123.576842)
		(stroke
			(width 0.053848)
			(type default)
		)
		(layer "B.Cu")
	)
	(gr_line
		(start 347.050614 -122.383042)
		(end 347.126814 -122.459242)
		(stroke
			(width 0.053848)
			(type default)
		)
		(layer "B.Cu")
	)
	(gr_line
		(start 347.066616 -123.576842)
		(end 347.685614 -123.576842)
		(stroke
			(width 0.053848)
			(type default)
		)
		(layer "B.Cu")
	)
	(gr_line
		(start 347.114876 -68.34632)
		(end 347.226636 -68.23456)
		(stroke
			(width 0.05715)
			(type default)
		)
		(layer "B.Cu")
	)
	(gr_line
		(start 347.126814 -122.459242)
		(end 347.711014 -122.459242)
		(stroke
			(width 0.053848)
			(type default)
		)
		(layer "B.Cu")
	)
	(gr_circle
		(center 347.14942 -32.766)
		(end 347.40342 -32.766)
		(stroke
			(width 0.2)
			(type default)
		)
		(fill no)
		(layer "B.Cu")
	)
	(gr_line
		(start 347.17736 -79.051912)
		(end 347.17736 -79.12608)
		(stroke
			(width 0.05715)
			(type default)
		)
		(layer "B.Cu")
	)
	(gr_line
		(start 347.17736 -78.677516)
		(end 347.17736 -79.046832)
		(stroke
			(width 0.05715)
			(type default)
		)
		(layer "B.Cu")
	)
	(gr_line
		(start 347.17736 -77.788516)
		(end 347.59646 -77.788516)
		(stroke
			(width 0.05715)
			(type default)
		)
		(layer "B.Cu")
	)
	(gr_line
		(start 347.17736 -76.899516)
		(end 347.504512 -76.899516)
		(stroke
			(width 0.05715)
			(type default)
		)
		(layer "B.Cu")
	)
	(gr_line
		(start 347.22054 -79.695802)
		(end 347.22054 -79.779622)
		(stroke
			(width 0.05715)
			(type default)
		)
		(layer "B.Cu")
	)
	(gr_line
		(start 347.226636 -68.23456)
		(end 347.569536 -68.23456)
		(stroke
			(width 0.05715)
			(type default)
		)
		(layer "B.Cu")
	)
	(gr_line
		(start 347.316806 -61.257434)
		(end 347.84284 -61.783468)
		(stroke
			(width 0.05715)
			(type default)
		)
		(layer "B.Cu")
	)
	(gr_line
		(start 347.316806 -60.368434)
		(end 347.896434 -60.368434)
		(stroke
			(width 0.05715)
			(type default)
		)
		(layer "B.Cu")
	)
	(gr_line
		(start 347.316806 -59.479434)
		(end 347.433138 -59.479434)
		(stroke
			(width 0.05715)
			(type default)
		)
		(layer "B.Cu")
	)
	(gr_line
		(start 347.354144 -79.290672)
		(end 347.41612 -79.290672)
		(stroke
			(width 0.05715)
			(type default)
		)
		(layer "B.Cu")
	)
	(gr_line
		(start 347.356176 -68.59016)
		(end 347.439996 -68.59016)
		(stroke
			(width 0.05715)
			(type default)
		)
		(layer "B.Cu")
	)
	(gr_line
		(start 347.4212 -79.290672)
		(end 348.029276 -79.290672)
		(stroke
			(width 0.05715)
			(type default)
		)
		(layer "B.Cu")
	)
	(gr_line
		(start 347.433138 -59.479434)
		(end 347.9546 -58.957972)
		(stroke
			(width 0.05715)
			(type default)
		)
		(layer "B.Cu")
	)
	(gr_line
		(start 347.504512 -76.899516)
		(end 347.80728 -76.596748)
		(stroke
			(width 0.05715)
			(type default)
		)
		(layer "B.Cu")
	)
	(gr_line
		(start 347.569536 -68.23456)
		(end 347.681296 -68.34632)
		(stroke
			(width 0.05715)
			(type default)
		)
		(layer "B.Cu")
	)
	(gr_line
		(start 347.584014 -126.370842)
		(end 347.609414 -126.345442)
		(stroke
			(width 0.053848)
			(type default)
		)
		(layer "B.Cu")
	)
	(gr_line
		(start 347.584014 -125.151642)
		(end 347.660214 -125.227842)
		(stroke
			(width 0.053848)
			(type default)
		)
		(layer "B.Cu")
	)
	(gr_line
		(start 347.59646 -77.788516)
		(end 347.81236 -78.004416)
		(stroke
			(width 0.05715)
			(type default)
		)
		(layer "B.Cu")
	)
	(gr_line
		(start 347.609414 -126.345442)
		(end 348.244414 -126.345442)
		(stroke
			(width 0.053848)
			(type default)
		)
		(layer "B.Cu")
	)
	(gr_line
		(start 347.660214 -125.227842)
		(end 348.244414 -125.227842)
		(stroke
			(width 0.053848)
			(type default)
		)
		(layer "B.Cu")
	)
	(gr_line
		(start 347.80728 -76.509626)
		(end 347.80728 -76.596748)
		(stroke
			(width 0.05715)
			(type default)
		)
		(layer "B.Cu")
	)
	(gr_line
		(start 347.81236 -78.004416)
		(end 347.81236 -78.01102)
		(stroke
			(width 0.05715)
			(type default)
		)
		(layer "B.Cu")
	)
	(gr_line
		(start 347.896434 -60.368434)
		(end 347.9546 -60.4266)
		(stroke
			(width 0.05715)
			(type default)
		)
		(layer "B.Cu")
	)
	(gr_circle
		(center 347.91142 -32.766)
		(end 348.16542 -32.766)
		(stroke
			(width 0.2)
			(type default)
		)
		(fill no)
		(layer "B.Cu")
	)
	(gr_line
		(start 347.99905 -80.36814)
		(end 348.25686 -80.11033)
		(stroke
			(width 0.05715)
			(type default)
		)
		(layer "B.Cu")
	)
	(gr_circle
		(center 348.0054 -36.83)
		(end 348.2594 -36.83)
		(stroke
			(width 0.2)
			(type default)
		)
		(fill no)
		(layer "B.Cu")
	)
	(gr_line
		(start 348.029276 -79.290672)
		(end 348.57436 -78.745588)
		(stroke
			(width 0.05715)
			(type default)
		)
		(layer "B.Cu")
	)
	(gr_line
		(start 348.13748 -80.61198)
		(end 348.25686 -80.73136)
		(stroke
			(width 0.05715)
			(type default)
		)
		(layer "B.Cu")
	)
	(gr_line
		(start 348.187772 -61.783468)
		(end 348.713806 -61.257434)
		(stroke
			(width 0.05715)
			(type default)
		)
		(layer "B.Cu")
	)
	(gr_line
		(start 348.25686 -80.73136)
		(end 348.25686 -81.07553)
		(stroke
			(width 0.05715)
			(type default)
		)
		(layer "B.Cu")
	)
	(gr_line
		(start 348.510098 -123.17603)
		(end 348.574614 -123.240546)
		(stroke
			(width 0.05715)
			(type default)
		)
		(layer "B.Cu")
	)
	(gr_line
		(start 348.510098 -122.831098)
		(end 348.600014 -122.741182)
		(stroke
			(width 0.05715)
			(type default)
		)
		(layer "B.Cu")
	)
	(gr_line
		(start 348.57436 -78.677516)
		(end 348.57436 -78.745588)
		(stroke
			(width 0.05715)
			(type default)
		)
		(layer "B.Cu")
	)
	(gr_line
		(start 348.57436 -77.788516)
		(end 348.99346 -77.788516)
		(stroke
			(width 0.05715)
			(type default)
		)
		(layer "B.Cu")
	)
	(gr_line
		(start 348.57436 -76.899516)
		(end 348.946724 -76.899516)
		(stroke
			(width 0.05715)
			(type default)
		)
		(layer "B.Cu")
	)
	(gr_line
		(start 348.574614 -123.240546)
		(end 348.574614 -123.576842)
		(stroke
			(width 0.05715)
			(type default)
		)
		(layer "B.Cu")
	)
	(gr_line
		(start 348.600014 -122.459242)
		(end 348.600014 -122.741182)
		(stroke
			(width 0.05715)
			(type default)
		)
		(layer "B.Cu")
	)
	(gr_line
		(start 348.713806 -60.368434)
		(end 349.293434 -60.368434)
		(stroke
			(width 0.05715)
			(type default)
		)
		(layer "B.Cu")
	)
	(gr_line
		(start 348.713806 -59.479434)
		(end 349.235268 -58.957972)
		(stroke
			(width 0.05715)
			(type default)
		)
		(layer "B.Cu")
	)
	(gr_line
		(start 348.946724 -76.899516)
		(end 349.20428 -76.64196)
		(stroke
			(width 0.05715)
			(type default)
		)
		(layer "B.Cu")
	)
	(gr_line
		(start 348.99346 -77.788516)
		(end 349.20936 -78.004416)
		(stroke
			(width 0.05715)
			(type default)
		)
		(layer "B.Cu")
	)
	(gr_line
		(start 349.070676 -125.946408)
		(end 349.133414 -126.009146)
		(stroke
			(width 0.05715)
			(type default)
		)
		(layer "B.Cu")
	)
	(gr_line
		(start 349.070676 -125.601476)
		(end 349.133414 -125.538738)
		(stroke
			(width 0.05715)
			(type default)
		)
		(layer "B.Cu")
	)
	(gr_line
		(start 349.133414 -126.009146)
		(end 349.133414 -126.345442)
		(stroke
			(width 0.05715)
			(type default)
		)
		(layer "B.Cu")
	)
	(gr_line
		(start 349.133414 -125.227842)
		(end 349.133414 -125.538738)
		(stroke
			(width 0.05715)
			(type default)
		)
		(layer "B.Cu")
	)
	(gr_line
		(start 349.20428 -76.509626)
		(end 349.20428 -76.64196)
		(stroke
			(width 0.05715)
			(type default)
		)
		(layer "B.Cu")
	)
	(gr_line
		(start 349.20936 -78.004416)
		(end 349.20936 -78.01102)
		(stroke
			(width 0.05715)
			(type default)
		)
		(layer "B.Cu")
	)
	(gr_line
		(start 349.235268 -58.957972)
		(end 349.3516 -58.957972)
		(stroke
			(width 0.05715)
			(type default)
		)
		(layer "B.Cu")
	)
	(gr_circle
		(center 349.2754 -36.83)
		(end 349.5294 -36.83)
		(stroke
			(width 0.2)
			(type default)
		)
		(fill no)
		(layer "B.Cu")
	)
	(gr_line
		(start 349.293434 -60.368434)
		(end 349.3516 -60.4266)
		(stroke
			(width 0.05715)
			(type default)
		)
		(layer "B.Cu")
	)
	(gr_line
		(start 349.463614 -123.250198)
		(end 349.463614 -123.576842)
		(stroke
			(width 0.05715)
			(type default)
		)
		(layer "B.Cu")
	)
	(gr_line
		(start 349.463614 -123.250198)
		(end 349.545402 -123.16841)
		(stroke
			(width 0.05715)
			(type default)
		)
		(layer "B.Cu")
	)
	(gr_line
		(start 349.489014 -122.76709)
		(end 349.545402 -122.823478)
		(stroke
			(width 0.05715)
			(type default)
		)
		(layer "B.Cu")
	)
	(gr_line
		(start 349.489014 -122.459242)
		(end 349.489014 -122.76709)
		(stroke
			(width 0.05715)
			(type default)
		)
		(layer "B.Cu")
	)
	(gr_line
		(start 349.8469 -80.238346)
		(end 349.95866 -80.350106)
		(stroke
			(width 0.05715)
			(type default)
		)
		(layer "B.Cu")
	)
	(gr_line
		(start 349.8469 -79.895446)
		(end 349.8469 -80.238346)
		(stroke
			(width 0.05715)
			(type default)
		)
		(layer "B.Cu")
	)
	(gr_line
		(start 349.8469 -79.895446)
		(end 349.95866 -79.783686)
		(stroke
			(width 0.05715)
			(type default)
		)
		(layer "B.Cu")
	)
	(gr_line
		(start 349.890588 -67.4624)
		(end 350.163892 -67.189096)
		(stroke
			(width 0.05715)
			(type default)
		)
		(layer "B.Cu")
	)
	(gr_line
		(start 350.001332 -121.949718)
		(end 350.015302 -121.925334)
		(stroke
			(width 0.05715)
			(type default)
		)
		(layer "B.Cu")
	)
	(gr_line
		(start 350.022414 -126.03099)
		(end 350.022414 -126.345442)
		(stroke
			(width 0.05715)
			(type default)
		)
		(layer "B.Cu")
	)
	(gr_line
		(start 350.022414 -126.03099)
		(end 350.085152 -125.968252)
		(stroke
			(width 0.05715)
			(type default)
		)
		(layer "B.Cu")
	)
	(gr_line
		(start 350.022414 -125.560836)
		(end 350.085152 -125.623574)
		(stroke
			(width 0.05715)
			(type default)
		)
		(layer "B.Cu")
	)
	(gr_line
		(start 350.022414 -125.227842)
		(end 350.022414 -125.560836)
		(stroke
			(width 0.05715)
			(type default)
		)
		(layer "B.Cu")
	)
	(gr_line
		(start 350.024192 -78.851252)
		(end 350.218756 -79.045816)
		(stroke
			(width 0.05715)
			(type default)
		)
		(layer "B.Cu")
	)
	(gr_line
		(start 350.024192 -78.723236)
		(end 350.024192 -78.851252)
		(stroke
			(width 0.05715)
			(type default)
		)
		(layer "B.Cu")
	)
	(gr_line
		(start 350.024192 -77.834236)
		(end 350.443292 -77.834236)
		(stroke
			(width 0.05715)
			(type default)
		)
		(layer "B.Cu")
	)
	(gr_line
		(start 350.024192 -76.945236)
		(end 350.299528 -76.945236)
		(stroke
			(width 0.05715)
			(type default)
		)
		(layer "B.Cu")
	)
	(gr_line
		(start 350.110806 -61.257434)
		(end 350.53143 -61.678058)
		(stroke
			(width 0.05715)
			(type default)
		)
		(layer "B.Cu")
	)
	(gr_line
		(start 350.110806 -60.368434)
		(end 350.690434 -60.368434)
		(stroke
			(width 0.05715)
			(type default)
		)
		(layer "B.Cu")
	)
	(gr_line
		(start 350.110806 -59.479434)
		(end 350.227138 -59.479434)
		(stroke
			(width 0.05715)
			(type default)
		)
		(layer "B.Cu")
	)
	(gr_line
		(start 350.2025 -80.024986)
		(end 350.2025 -80.108806)
		(stroke
			(width 0.05715)
			(type default)
		)
		(layer "B.Cu")
	)
	(gr_line
		(start 350.218756 -79.045816)
		(end 350.218756 -79.20736)
		(stroke
			(width 0.05715)
			(type default)
		)
		(layer "B.Cu")
	)
	(gr_line
		(start 350.227138 -59.479434)
		(end 350.7486 -58.957972)
		(stroke
			(width 0.05715)
			(type default)
		)
		(layer "B.Cu")
	)
	(gr_line
		(start 350.299528 -76.945236)
		(end 350.672654 -76.57211)
		(stroke
			(width 0.05715)
			(type default)
		)
		(layer "B.Cu")
	)
	(gr_line
		(start 350.335088 -121.36374)
		(end 350.36633 -121.308876)
		(stroke
			(width 0.05715)
			(type default)
		)
		(layer "B.Cu")
	)
	(gr_line
		(start 350.36633 -121.308876)
		(end 350.427036 -121.291096)
		(stroke
			(width 0.05715)
			(type default)
		)
		(layer "B.Cu")
	)
	(gr_line
		(start 350.397318 -80.86344)
		(end 350.749616 -81.215738)
		(stroke
			(width 0.05715)
			(type default)
		)
		(layer "B.Cu")
	)
	(gr_line
		(start 350.439482 -80.905604)
		(end 350.749616 -81.215738)
		(stroke
			(width 0.05715)
			(type default)
		)
		(layer "B.Cu")
	)
	(gr_line
		(start 350.439482 -80.560672)
		(end 350.749616 -80.250538)
		(stroke
			(width 0.05715)
			(type default)
		)
		(layer "B.Cu")
	)
	(gr_line
		(start 350.443292 -77.834236)
		(end 350.659192 -78.050136)
		(stroke
			(width 0.05715)
			(type default)
		)
		(layer "B.Cu")
	)
	(gr_line
		(start 350.462596 -79.4512)
		(end 350.7994 -79.4512)
		(stroke
			(width 0.05715)
			(type default)
		)
		(layer "B.Cu")
	)
	(gr_line
		(start 350.50857 -67.189096)
		(end 350.781874 -67.4624)
		(stroke
			(width 0.05715)
			(type default)
		)
		(layer "B.Cu")
	)
	(gr_line
		(start 350.53143 -61.678058)
		(end 350.731582 -61.678058)
		(stroke
			(width 0.05715)
			(type default)
		)
		(layer "B.Cu")
	)
	(gr_circle
		(center 350.5454 -36.83)
		(end 350.7994 -36.83)
		(stroke
			(width 0.2)
			(type default)
		)
		(fill no)
		(layer "B.Cu")
	)
	(gr_line
		(start 350.659192 -78.050136)
		(end 350.659192 -78.05674)
		(stroke
			(width 0.05715)
			(type default)
		)
		(layer "B.Cu")
	)
	(gr_line
		(start 350.690434 -60.368434)
		(end 350.7486 -60.4266)
		(stroke
			(width 0.05715)
			(type default)
		)
		(layer "B.Cu")
	)
	(gr_circle
		(center 350.6978 -32.6263)
		(end 350.9518 -32.6263)
		(stroke
			(width 0.2)
			(type default)
		)
		(fill no)
		(layer "B.Cu")
	)
	(gr_line
		(start 350.708214 -123.79833)
		(end 350.708214 -123.822206)
		(stroke
			(width 0.05715)
			(type default)
		)
		(layer "B.Cu")
	)
	(gr_line
		(start 350.708214 -123.79833)
		(end 351.171002 -123.335542)
		(stroke
			(width 0.05715)
			(type default)
		)
		(layer "B.Cu")
	)
	(gr_line
		(start 350.731582 -62.68339)
		(end 350.843342 -62.79515)
		(stroke
			(width 0.05715)
			(type default)
		)
		(layer "B.Cu")
	)
	(gr_line
		(start 350.731582 -62.34049)
		(end 350.731582 -62.68339)
		(stroke
			(width 0.05715)
			(type default)
		)
		(layer "B.Cu")
	)
	(gr_line
		(start 350.731582 -62.34049)
		(end 350.843342 -62.22873)
		(stroke
			(width 0.05715)
			(type default)
		)
		(layer "B.Cu")
	)
	(gr_line
		(start 350.731582 -61.678058)
		(end 350.843342 -61.789818)
		(stroke
			(width 0.05715)
			(type default)
		)
		(layer "B.Cu")
	)
	(gr_line
		(start 350.784414 -122.57405)
		(end 351.302066 -123.091702)
		(stroke
			(width 0.05715)
			(type default)
		)
		(layer "B.Cu")
	)
	(gr_line
		(start 350.7994 -79.4512)
		(end 351.421192 -78.829408)
		(stroke
			(width 0.05715)
			(type default)
		)
		(layer "B.Cu")
	)
	(gr_line
		(start 351.087182 -62.47003)
		(end 351.087182 -62.55385)
		(stroke
			(width 0.05715)
			(type default)
		)
		(layer "B.Cu")
	)
	(gr_line
		(start 351.087182 -61.678058)
		(end 351.507806 -61.257434)
		(stroke
			(width 0.05715)
			(type default)
		)
		(layer "B.Cu")
	)
	(gr_line
		(start 351.343214 -126.64313)
		(end 351.793302 -126.193042)
		(stroke
			(width 0.05715)
			(type default)
		)
		(layer "B.Cu")
	)
	(gr_line
		(start 351.348802 -125.392942)
		(end 351.805748 -125.849888)
		(stroke
			(width 0.05715)
			(type default)
		)
		(layer "B.Cu")
	)
	(gr_line
		(start 351.421192 -78.723236)
		(end 351.421192 -78.829408)
		(stroke
			(width 0.05715)
			(type default)
		)
		(layer "B.Cu")
	)
	(gr_line
		(start 351.421192 -77.834236)
		(end 351.840292 -77.834236)
		(stroke
			(width 0.05715)
			(type default)
		)
		(layer "B.Cu")
	)
	(gr_line
		(start 351.421192 -76.945236)
		(end 351.696528 -76.945236)
		(stroke
			(width 0.05715)
			(type default)
		)
		(layer "B.Cu")
	)
	(gr_circle
		(center 351.4598 -32.6263)
		(end 351.7138 -32.6263)
		(stroke
			(width 0.2)
			(type default)
		)
		(fill no)
		(layer "B.Cu")
	)
	(gr_line
		(start 351.507806 -60.368434)
		(end 352.087434 -60.368434)
		(stroke
			(width 0.05715)
			(type default)
		)
		(layer "B.Cu")
	)
	(gr_line
		(start 351.507806 -59.479434)
		(end 351.624138 -59.479434)
		(stroke
			(width 0.05715)
			(type default)
		)
		(layer "B.Cu")
	)
	(gr_line
		(start 351.624138 -59.479434)
		(end 352.1456 -58.957972)
		(stroke
			(width 0.05715)
			(type default)
		)
		(layer "B.Cu")
	)
	(gr_line
		(start 351.696528 -76.945236)
		(end 352.069654 -76.57211)
		(stroke
			(width 0.05715)
			(type default)
		)
		(layer "B.Cu")
	)
	(gr_line
		(start 351.793302 -126.193042)
		(end 351.807526 -126.193042)
		(stroke
			(width 0.05715)
			(type default)
		)
		(layer "B.Cu")
	)
	(gr_circle
		(center 351.8154 -36.83)
		(end 352.0694 -36.83)
		(stroke
			(width 0.2)
			(type default)
		)
		(fill no)
		(layer "B.Cu")
	)
	(gr_line
		(start 351.840292 -77.834236)
		(end 352.056192 -78.050136)
		(stroke
			(width 0.05715)
			(type default)
		)
		(layer "B.Cu")
	)
	(gr_line
		(start 351.913952 -125.958092)
		(end 352.046286 -125.958092)
		(stroke
			(width 0.05715)
			(type default)
		)
		(layer "B.Cu")
	)
	(gr_line
		(start 352.056192 -78.050136)
		(end 352.056192 -78.05674)
		(stroke
			(width 0.05715)
			(type default)
		)
		(layer "B.Cu")
	)
	(gr_line
		(start 352.087434 -60.368434)
		(end 352.1456 -60.4266)
		(stroke
			(width 0.05715)
			(type default)
		)
		(layer "B.Cu")
	)
	(gr_line
		(start 352.105214 -123.780042)
		(end 352.765614 -123.780042)
		(stroke
			(width 0.053848)
			(type default)
		)
		(layer "B.Cu")
	)
	(gr_line
		(start 352.105214 -122.586242)
		(end 352.181414 -122.662442)
		(stroke
			(width 0.053848)
			(type default)
		)
		(layer "B.Cu")
	)
	(gr_line
		(start 352.13544 -80.164178)
		(end 352.2472 -80.275938)
		(stroke
			(width 0.05715)
			(type default)
		)
		(layer "B.Cu")
	)
	(gr_line
		(start 352.13544 -79.821278)
		(end 352.13544 -80.164178)
		(stroke
			(width 0.05715)
			(type default)
		)
		(layer "B.Cu")
	)
	(gr_line
		(start 352.13544 -79.821278)
		(end 352.21418 -79.742538)
		(stroke
			(width 0.05715)
			(type default)
		)
		(layer "B.Cu")
	)
	(gr_line
		(start 352.181414 -122.662442)
		(end 352.765614 -122.662442)
		(stroke
			(width 0.053848)
			(type default)
		)
		(layer "B.Cu")
	)
	(gr_line
		(start 352.277934 -157.655006)
		(end 352.595688 -157.97276)
		(stroke
			(width 0.0635)
			(type default)
		)
		(layer "B.Cu")
	)
	(gr_line
		(start 352.49104 -79.950818)
		(end 352.49104 -80.034638)
		(stroke
			(width 0.05715)
			(type default)
		)
		(layer "B.Cu")
	)
	(gr_line
		(start 352.734626 -126.68123)
		(end 352.791014 -126.624842)
		(stroke
			(width 0.053848)
			(type default)
		)
		(layer "B.Cu")
	)
	(gr_line
		(start 352.740214 -125.380242)
		(end 352.892614 -125.532642)
		(stroke
			(width 0.053848)
			(type default)
		)
		(layer "B.Cu")
	)
	(gr_line
		(start 352.791014 -126.624842)
		(end 353.400614 -126.624842)
		(stroke
			(width 0.053848)
			(type default)
		)
		(layer "B.Cu")
	)
	(gr_line
		(start 352.892614 -125.532642)
		(end 353.400614 -125.532642)
		(stroke
			(width 0.053848)
			(type default)
		)
		(layer "B.Cu")
	)
	(gr_line
		(start 352.904806 -61.257434)
		(end 353.43084 -61.783468)
		(stroke
			(width 0.05715)
			(type default)
		)
		(layer "B.Cu")
	)
	(gr_line
		(start 352.904806 -60.368434)
		(end 353.484434 -60.368434)
		(stroke
			(width 0.05715)
			(type default)
		)
		(layer "B.Cu")
	)
	(gr_line
		(start 352.904806 -59.479434)
		(end 353.021138 -59.479434)
		(stroke
			(width 0.05715)
			(type default)
		)
		(layer "B.Cu")
	)
	(gr_line
		(start 352.9584 -157.97276)
		(end 353.276154 -157.655006)
		(stroke
			(width 0.0635)
			(type default)
		)
		(layer "B.Cu")
	)
	(gr_line
		(start 352.96729 -78.804516)
		(end 353.13874 -78.975966)
		(stroke
			(width 0.05715)
			(type default)
		)
		(layer "B.Cu")
	)
	(gr_line
		(start 352.96729 -77.915516)
		(end 353.38639 -77.915516)
		(stroke
			(width 0.05715)
			(type default)
		)
		(layer "B.Cu")
	)
	(gr_line
		(start 352.96729 -77.026516)
		(end 353.296728 -77.026516)
		(stroke
			(width 0.05715)
			(type default)
		)
		(layer "B.Cu")
	)
	(gr_line
		(start 353.021138 -59.479434)
		(end 353.5426 -58.957972)
		(stroke
			(width 0.05715)
			(type default)
		)
		(layer "B.Cu")
	)
	(gr_line
		(start 353.13874 -79.12354)
		(end 353.13874 -79.182214)
		(stroke
			(width 0.05715)
			(type default)
		)
		(layer "B.Cu")
	)
	(gr_line
		(start 353.13874 -78.975966)
		(end 353.13874 -79.11846)
		(stroke
			(width 0.05715)
			(type default)
		)
		(layer "B.Cu")
	)
	(gr_line
		(start 353.248976 -80.55356)
		(end 353.625404 -80.177132)
		(stroke
			(width 0.05715)
			(type default)
		)
		(layer "B.Cu")
	)
	(gr_line
		(start 353.296728 -77.026516)
		(end 353.60229 -76.720954)
		(stroke
			(width 0.05715)
			(type default)
		)
		(layer "B.Cu")
	)
	(gr_line
		(start 353.30003 -79.3623)
		(end 353.3775 -79.3623)
		(stroke
			(width 0.05715)
			(type default)
		)
		(layer "B.Cu")
	)
	(gr_line
		(start 353.38258 -79.3623)
		(end 353.846638 -79.3623)
		(stroke
			(width 0.05715)
			(type default)
		)
		(layer "B.Cu")
	)
	(gr_line
		(start 353.38639 -77.915516)
		(end 353.60229 -78.131416)
		(stroke
			(width 0.05715)
			(type default)
		)
		(layer "B.Cu")
	)
	(gr_line
		(start 353.484434 -60.368434)
		(end 353.5426 -60.4266)
		(stroke
			(width 0.05715)
			(type default)
		)
		(layer "B.Cu")
	)
	(gr_line
		(start 353.487228 -80.7974)
		(end 353.625404 -80.935576)
		(stroke
			(width 0.05715)
			(type default)
		)
		(layer "B.Cu")
	)
	(gr_line
		(start 353.497134 -123.406662)
		(end 353.654614 -123.564142)
		(stroke
			(width 0.05715)
			(type default)
		)
		(layer "B.Cu")
	)
	(gr_line
		(start 353.497134 -123.06173)
		(end 353.654614 -122.90425)
		(stroke
			(width 0.05715)
			(type default)
		)
		(layer "B.Cu")
	)
	(gr_line
		(start 353.52863 -88.47455)
		(end 353.6442 -88.59012)
		(stroke
			(width 0.0635)
			(type default)
		)
		(layer "B.Cu")
	)
	(gr_line
		(start 353.60229 -78.131416)
		(end 353.60229 -78.13802)
		(stroke
			(width 0.05715)
			(type default)
		)
		(layer "B.Cu")
	)
	(gr_line
		(start 353.625404 -80.935576)
		(end 353.625404 -81.142332)
		(stroke
			(width 0.05715)
			(type default)
		)
		(layer "B.Cu")
	)
	(gr_line
		(start 353.6442 -88.59012)
		(end 353.991164 -88.59012)
		(stroke
			(width 0.0635)
			(type default)
		)
		(layer "B.Cu")
	)
	(gr_line
		(start 353.654614 -123.564142)
		(end 353.654614 -123.780042)
		(stroke
			(width 0.05715)
			(type default)
		)
		(layer "B.Cu")
	)
	(gr_line
		(start 353.654614 -122.662442)
		(end 353.654614 -122.90425)
		(stroke
			(width 0.05715)
			(type default)
		)
		(layer "B.Cu")
	)
	(gr_line
		(start 353.775772 -61.783468)
		(end 354.301806 -61.257434)
		(stroke
			(width 0.05715)
			(type default)
		)
		(layer "B.Cu")
	)
	(gr_line
		(start 353.846638 -79.3623)
		(end 354.36429 -78.844648)
		(stroke
			(width 0.05715)
			(type default)
		)
		(layer "B.Cu")
	)
	(gr_line
		(start 354.141278 -88.768936)
		(end 354.14204 -89.19718)
		(stroke
			(width 0.0635)
			(type default)
		)
		(layer "B.Cu")
	)
	(gr_line
		(start 354.202492 -126.226824)
		(end 354.289614 -126.313946)
		(stroke
			(width 0.05715)
			(type default)
		)
		(layer "B.Cu")
	)
	(gr_line
		(start 354.202492 -125.881892)
		(end 354.289614 -125.79477)
		(stroke
			(width 0.05715)
			(type default)
		)
		(layer "B.Cu")
	)
	(gr_line
		(start 354.289614 -126.313946)
		(end 354.289614 -126.624842)
		(stroke
			(width 0.05715)
			(type default)
		)
		(layer "B.Cu")
	)
	(gr_line
		(start 354.289614 -125.532642)
		(end 354.289614 -125.79477)
		(stroke
			(width 0.05715)
			(type default)
		)
		(layer "B.Cu")
	)
	(gr_line
		(start 354.301806 -60.368434)
		(end 354.881434 -60.368434)
		(stroke
			(width 0.05715)
			(type default)
		)
		(layer "B.Cu")
	)
	(gr_line
		(start 354.301806 -59.479434)
		(end 354.418138 -59.479434)
		(stroke
			(width 0.05715)
			(type default)
		)
		(layer "B.Cu")
	)
	(gr_line
		(start 354.36429 -78.804516)
		(end 354.36429 -78.844648)
		(stroke
			(width 0.05715)
			(type default)
		)
		(layer "B.Cu")
	)
	(gr_line
		(start 354.36429 -77.915516)
		(end 354.78339 -77.915516)
		(stroke
			(width 0.05715)
			(type default)
		)
		(layer "B.Cu")
	)
	(gr_line
		(start 354.36429 -77.026516)
		(end 354.693728 -77.026516)
		(stroke
			(width 0.05715)
			(type default)
		)
		(layer "B.Cu")
	)
	(gr_line
		(start 354.418138 -59.479434)
		(end 354.9396 -58.957972)
		(stroke
			(width 0.05715)
			(type default)
		)
		(layer "B.Cu")
	)
	(gr_line
		(start 354.460048 -87.46744)
		(end 354.741226 -87.748618)
		(stroke
			(width 0.0635)
			(type default)
		)
		(layer "B.Cu")
	)
	(gr_line
		(start 354.460048 -86.312248)
		(end 354.460048 -86.93404)
		(stroke
			(width 0.0635)
			(type default)
		)
		(layer "B.Cu")
	)
	(gr_line
		(start 354.460048 -85.975952)
		(end 354.460048 -86.312248)
		(stroke
			(width 0.0635)
			(type default)
		)
		(layer "B.Cu")
	)
	(gr_line
		(start 354.460048 -85.975952)
		(end 354.738178 -85.697822)
		(stroke
			(width 0.0635)
			(type default)
		)
		(layer "B.Cu")
	)
	(gr_line
		(start 354.543614 -123.780042)
		(end 354.929948 -123.393708)
		(stroke
			(width 0.05715)
			(type default)
		)
		(layer "B.Cu")
	)
	(gr_line
		(start 354.543614 -122.662442)
		(end 354.929948 -123.048776)
		(stroke
			(width 0.05715)
			(type default)
		)
		(layer "B.Cu")
	)
	(gr_line
		(start 354.693728 -77.026516)
		(end 354.99929 -76.720954)
		(stroke
			(width 0.05715)
			(type default)
		)
		(layer "B.Cu")
	)
	(gr_line
		(start 354.739956 -85.696044)
		(end 354.7872 -85.6488)
		(stroke
			(width 0.0635)
			(type default)
		)
		(layer "B.Cu")
	)
	(gr_line
		(start 354.743004 -87.750396)
		(end 354.7872 -87.794592)
		(stroke
			(width 0.0635)
			(type default)
		)
		(layer "B.Cu")
	)
	(gr_line
		(start 354.78339 -77.915516)
		(end 354.99929 -78.131416)
		(stroke
			(width 0.05715)
			(type default)
		)
		(layer "B.Cu")
	)
	(gr_line
		(start 354.881434 -60.368434)
		(end 354.9396 -60.4266)
		(stroke
			(width 0.05715)
			(type default)
		)
		(layer "B.Cu")
	)
	(gr_line
		(start 354.99929 -78.131416)
		(end 354.99929 -78.13802)
		(stroke
			(width 0.05715)
			(type default)
		)
		(layer "B.Cu")
	)
	(gr_line
		(start 355.0158 -87.800688)
		(end 355.066092 -87.750396)
		(stroke
			(width 0.0635)
			(type default)
		)
		(layer "B.Cu")
	)
	(gr_line
		(start 355.0158 -85.6488)
		(end 355.063044 -85.696044)
		(stroke
			(width 0.0635)
			(type default)
		)
		(layer "B.Cu")
	)
	(gr_line
		(start 355.064822 -85.697822)
		(end 355.348794 -85.981794)
		(stroke
			(width 0.0635)
			(type default)
		)
		(layer "B.Cu")
	)
	(gr_line
		(start 355.06787 -87.748618)
		(end 355.349048 -87.46744)
		(stroke
			(width 0.0635)
			(type default)
		)
		(layer "B.Cu")
	)
	(gr_line
		(start 355.178614 -126.624842)
		(end 355.552248 -126.251208)
		(stroke
			(width 0.05715)
			(type default)
		)
		(layer "B.Cu")
	)
	(gr_line
		(start 355.178614 -125.532642)
		(end 355.552248 -125.906276)
		(stroke
			(width 0.05715)
			(type default)
		)
		(layer "B.Cu")
	)
	(gr_circle
		(center 355.229668 -26.552652)
		(end 355.483668 -26.552652)
		(stroke
			(width 0.2)
			(type default)
		)
		(fill no)
		(layer "B.Cu")
	)
	(gr_circle
		(center 355.3333 -28.7274)
		(end 355.5873 -28.7274)
		(stroke
			(width 0.2)
			(type default)
		)
		(fill no)
		(layer "B.Cu")
	)
	(gr_circle
		(center 355.346 -28.0924)
		(end 355.6 -28.0924)
		(stroke
			(width 0.2)
			(type default)
		)
		(fill no)
		(layer "B.Cu")
	)
	(gr_line
		(start 355.34854 -123.297442)
		(end 355.379274 -123.277122)
		(stroke
			(width 0.05715)
			(type default)
		)
		(layer "B.Cu")
	)
	(gr_line
		(start 355.348794 -85.981794)
		(end 355.349048 -86.312248)
		(stroke
			(width 0.0635)
			(type default)
		)
		(layer "B.Cu")
	)
	(gr_line
		(start 355.349048 -86.312248)
		(end 355.349048 -86.93404)
		(stroke
			(width 0.0635)
			(type default)
		)
		(layer "B.Cu")
	)
	(gr_line
		(start 355.736398 -79.115158)
		(end 355.981 -79.35976)
		(stroke
			(width 0.05715)
			(type default)
		)
		(layer "B.Cu")
	)
	(gr_line
		(start 355.736398 -78.804516)
		(end 355.736398 -79.115158)
		(stroke
			(width 0.05715)
			(type default)
		)
		(layer "B.Cu")
	)
	(gr_line
		(start 355.736398 -77.915516)
		(end 356.155498 -77.915516)
		(stroke
			(width 0.05715)
			(type default)
		)
		(layer "B.Cu")
	)
	(gr_line
		(start 355.736398 -77.026516)
		(end 356.064566 -77.026516)
		(stroke
			(width 0.05715)
			(type default)
		)
		(layer "B.Cu")
	)
	(gr_line
		(start 355.741732 -81.319878)
		(end 356.051866 -81.009744)
		(stroke
			(width 0.05715)
			(type default)
		)
		(layer "B.Cu")
	)
	(gr_line
		(start 355.741732 -80.354678)
		(end 356.051866 -80.664812)
		(stroke
			(width 0.05715)
			(type default)
		)
		(layer "B.Cu")
	)
	(gr_line
		(start 355.981 -79.35976)
		(end 356.333552 -79.35976)
		(stroke
			(width 0.05715)
			(type default)
		)
		(layer "B.Cu")
	)
	(gr_line
		(start 356.064566 -77.026516)
		(end 356.371398 -76.719684)
		(stroke
			(width 0.05715)
			(type default)
		)
		(layer "B.Cu")
	)
	(gr_line
		(start 356.155498 -77.915516)
		(end 356.371398 -78.131416)
		(stroke
			(width 0.05715)
			(type default)
		)
		(layer "B.Cu")
	)
	(gr_line
		(start 356.333552 -79.35976)
		(end 356.595172 -79.62138)
		(stroke
			(width 0.05715)
			(type default)
		)
		(layer "B.Cu")
	)
	(gr_line
		(start 356.371398 -78.131416)
		(end 356.371398 -78.13802)
		(stroke
			(width 0.05715)
			(type default)
		)
		(layer "B.Cu")
	)
	(gr_line
		(start 356.839012 -79.352902)
		(end 356.839012 -79.38008)
		(stroke
			(width 0.05715)
			(type default)
		)
		(layer "B.Cu")
	)
	(gr_line
		(start 356.839012 -79.352902)
		(end 357.133398 -79.058516)
		(stroke
			(width 0.05715)
			(type default)
		)
		(layer "B.Cu")
	)
	(gr_line
		(start 356.915212 -122.268234)
		(end 356.954836 -122.242072)
		(stroke
			(width 0.05715)
			(type default)
		)
		(layer "B.Cu")
	)
	(gr_line
		(start 356.954836 -122.242072)
		(end 356.970838 -122.197876)
		(stroke
			(width 0.05715)
			(type default)
		)
		(layer "B.Cu")
	)
	(gr_line
		(start 357.133398 -78.804516)
		(end 357.133398 -79.058516)
		(stroke
			(width 0.05715)
			(type default)
		)
		(layer "B.Cu")
	)
	(gr_line
		(start 357.133398 -77.915516)
		(end 357.552498 -77.915516)
		(stroke
			(width 0.05715)
			(type default)
		)
		(layer "B.Cu")
	)
	(gr_line
		(start 357.133398 -77.026516)
		(end 357.461566 -77.026516)
		(stroke
			(width 0.05715)
			(type default)
		)
		(layer "B.Cu")
	)
	(gr_line
		(start 357.349044 -120.43537)
		(end 357.379778 -120.35028)
		(stroke
			(width 0.05715)
			(type default)
		)
		(layer "B.Cu")
	)
	(gr_line
		(start 357.379778 -120.35028)
		(end 357.467408 -120.325388)
		(stroke
			(width 0.05715)
			(type default)
		)
		(layer "B.Cu")
	)
	(gr_line
		(start 357.461566 -77.026516)
		(end 357.768398 -76.719684)
		(stroke
			(width 0.05715)
			(type default)
		)
		(layer "B.Cu")
	)
	(gr_line
		(start 357.552498 -77.915516)
		(end 357.768398 -78.131416)
		(stroke
			(width 0.05715)
			(type default)
		)
		(layer "B.Cu")
	)
	(gr_line
		(start 357.768398 -78.131416)
		(end 357.768398 -78.13802)
		(stroke
			(width 0.05715)
			(type default)
		)
		(layer "B.Cu")
	)
	(gr_line
		(start 358.112568 -127.504444)
		(end 358.147874 -127.512572)
		(stroke
			(width 0.05715)
			(type default)
		)
		(layer "B.Cu")
	)
	(gr_line
		(start 358.44988 -79.036164)
		(end 358.721406 -79.30769)
		(stroke
			(width 0.05715)
			(type default)
		)
		(layer "B.Cu")
	)
	(gr_line
		(start 358.44988 -78.812136)
		(end 358.44988 -79.036164)
		(stroke
			(width 0.05715)
			(type default)
		)
		(layer "B.Cu")
	)
	(gr_line
		(start 358.44988 -77.923136)
		(end 358.86898 -77.923136)
		(stroke
			(width 0.05715)
			(type default)
		)
		(layer "B.Cu")
	)
	(gr_line
		(start 358.44988 -77.034136)
		(end 358.754426 -77.034136)
		(stroke
			(width 0.05715)
			(type default)
		)
		(layer "B.Cu")
	)
	(gr_line
		(start 358.563164 -80.760316)
		(end 359.000298 -80.323182)
		(stroke
			(width 0.05715)
			(type default)
		)
		(layer "B.Cu")
	)
	(gr_line
		(start 358.616758 -126.588266)
		(end 358.651556 -126.59614)
		(stroke
			(width 0.05715)
			(type default)
		)
		(layer "B.Cu")
	)
	(gr_line
		(start 358.64292 -79.54772)
		(end 358.721406 -79.469234)
		(stroke
			(width 0.05715)
			(type default)
		)
		(layer "B.Cu")
	)
	(gr_line
		(start 358.716072 -81.004156)
		(end 359.000298 -81.288382)
		(stroke
			(width 0.05715)
			(type default)
		)
		(layer "B.Cu")
	)
	(gr_line
		(start 358.721406 -79.30769)
		(end 358.721406 -79.469234)
		(stroke
			(width 0.05715)
			(type default)
		)
		(layer "B.Cu")
	)
	(gr_line
		(start 358.754426 -77.034136)
		(end 359.08488 -76.703682)
		(stroke
			(width 0.05715)
			(type default)
		)
		(layer "B.Cu")
	)
	(gr_line
		(start 358.836214 -125.532642)
		(end 359.26268 -125.106176)
		(stroke
			(width 0.05715)
			(type default)
		)
		(layer "B.Cu")
	)
	(gr_line
		(start 358.86898 -77.923136)
		(end 359.08488 -78.139036)
		(stroke
			(width 0.05715)
			(type default)
		)
		(layer "B.Cu")
	)
	(gr_line
		(start 358.88422 -79.79156)
		(end 358.91724 -79.79156)
		(stroke
			(width 0.05715)
			(type default)
		)
		(layer "B.Cu")
	)
	(gr_line
		(start 358.887014 -124.338842)
		(end 359.410508 -124.862336)
		(stroke
			(width 0.05715)
			(type default)
		)
		(layer "B.Cu")
	)
	(gr_line
		(start 358.912414 -121.265442)
		(end 359.408222 -121.76125)
		(stroke
			(width 0.05715)
			(type default)
		)
		(layer "B.Cu")
	)
	(gr_line
		(start 358.91724 -79.79156)
		(end 359.84688 -78.86192)
		(stroke
			(width 0.05715)
			(type default)
		)
		(layer "B.Cu")
	)
	(gr_line
		(start 358.951022 -122.563128)
		(end 359.408222 -122.105928)
		(stroke
			(width 0.05715)
			(type default)
		)
		(layer "B.Cu")
	)
	(gr_line
		(start 359.08869 -100.33381)
		(end 359.08869 -100.660708)
		(stroke
			(width 0.05715)
			(type default)
		)
		(layer "B.Cu")
	)
	(gr_line
		(start 359.08869 -100.33381)
		(end 359.229152 -100.193348)
		(stroke
			(width 0.05715)
			(type default)
		)
		(layer "B.Cu")
	)
	(gr_line
		(start 359.08869 -99.707954)
		(end 359.229152 -99.848416)
		(stroke
			(width 0.05715)
			(type default)
		)
		(layer "B.Cu")
	)
	(gr_line
		(start 359.08869 -99.390708)
		(end 359.08869 -99.707954)
		(stroke
			(width 0.05715)
			(type default)
		)
		(layer "B.Cu")
	)
	(gr_line
		(start 359.5624 -99.905566)
		(end 359.6132 -99.971352)
		(stroke
			(width 0.05715)
			(type default)
		)
		(layer "B.Cu")
	)
	(gr_line
		(start 359.629202 -109.812582)
		(end 359.635552 -109.781086)
		(stroke
			(width 0.05715)
			(type default)
		)
		(layer "B.Cu")
	)
	(gr_line
		(start 359.629202 -109.812582)
		(end 359.639616 -109.842808)
		(stroke
			(width 0.05715)
			(type default)
		)
		(layer "B.Cu")
	)
	(gr_line
		(start 359.84688 -78.812136)
		(end 359.84688 -78.86192)
		(stroke
			(width 0.05715)
			(type default)
		)
		(layer "B.Cu")
	)
	(gr_line
		(start 359.84688 -77.923136)
		(end 360.303826 -77.923136)
		(stroke
			(width 0.05715)
			(type default)
		)
		(layer "B.Cu")
	)
	(gr_line
		(start 359.84688 -77.034136)
		(end 360.151426 -77.034136)
		(stroke
			(width 0.05715)
			(type default)
		)
		(layer "B.Cu")
	)
	(gr_line
		(start 359.84815 -102.607618)
		(end 359.850944 -102.593648)
		(stroke
			(width 0.05715)
			(type default)
		)
		(layer "B.Cu")
	)
	(gr_line
		(start 360.144822 -100.659946)
		(end 360.15168 -100.668836)
		(stroke
			(width 0.05715)
			(type default)
		)
		(layer "B.Cu")
	)
	(gr_line
		(start 360.151426 -77.034136)
		(end 360.48188 -76.703682)
		(stroke
			(width 0.05715)
			(type default)
		)
		(layer "B.Cu")
	)
	(gr_line
		(start 360.15168 -100.668836)
		(end 360.154474 -100.67925)
		(stroke
			(width 0.05715)
			(type default)
		)
		(layer "B.Cu")
	)
	(gr_line
		(start 360.233214 -124.338842)
		(end 360.334814 -124.440442)
		(stroke
			(width 0.05715)
			(type default)
		)
		(layer "B.Cu")
	)
	(gr_line
		(start 360.258614 -125.583442)
		(end 360.284014 -125.558042)
		(stroke
			(width 0.05715)
			(type default)
		)
		(layer "B.Cu")
	)
	(gr_line
		(start 360.258614 -121.240042)
		(end 360.411014 -121.392442)
		(stroke
			(width 0.05715)
			(type default)
		)
		(layer "B.Cu")
	)
	(gr_line
		(start 360.284014 -125.558042)
		(end 360.893614 -125.558042)
		(stroke
			(width 0.05715)
			(type default)
		)
		(layer "B.Cu")
	)
	(gr_line
		(start 360.284014 -122.560842)
		(end 360.334814 -122.510042)
		(stroke
			(width 0.05715)
			(type default)
		)
		(layer "B.Cu")
	)
	(gr_line
		(start 360.303826 -77.923136)
		(end 360.510582 -78.129892)
		(stroke
			(width 0.05715)
			(type default)
		)
		(layer "B.Cu")
	)
	(gr_line
		(start 360.334814 -124.440442)
		(end 360.893614 -124.440442)
		(stroke
			(width 0.05715)
			(type default)
		)
		(layer "B.Cu")
	)
	(gr_line
		(start 360.334814 -122.510042)
		(end 360.937556 -122.510042)
		(stroke
			(width 0.05715)
			(type default)
		)
		(layer "B.Cu")
	)
	(gr_line
		(start 360.33964 -101.321108)
		(end 360.346752 -101.345746)
		(stroke
			(width 0.05715)
			(type default)
		)
		(layer "B.Cu")
	)
	(gr_line
		(start 360.341672 -101.370384)
		(end 360.346752 -101.345746)
		(stroke
			(width 0.05715)
			(type default)
		)
		(layer "B.Cu")
	)
	(gr_line
		(start 360.411014 -121.392442)
		(end 360.937556 -121.392442)
		(stroke
			(width 0.05715)
			(type default)
		)
		(layer "B.Cu")
	)
	(gr_line
		(start 360.69905 -99.553268)
		(end 360.69905 -99.924108)
		(stroke
			(width 0.05715)
			(type default)
		)
		(layer "B.Cu")
	)
	(gr_line
		(start 360.69905 -99.553268)
		(end 360.776266 -99.476052)
		(stroke
			(width 0.05715)
			(type default)
		)
		(layer "B.Cu")
	)
	(gr_line
		(start 360.69905 -99.054158)
		(end 360.776266 -99.131374)
		(stroke
			(width 0.05715)
			(type default)
		)
		(layer "B.Cu")
	)
	(gr_line
		(start 360.69905 -98.654108)
		(end 360.69905 -99.054158)
		(stroke
			(width 0.05715)
			(type default)
		)
		(layer "B.Cu")
	)
	(gr_line
		(start 360.69905 -96.9772)
		(end 360.69905 -97.37725)
		(stroke
			(width 0.05715)
			(type default)
		)
		(layer "B.Cu")
	)
	(gr_line
		(start 360.69905 -96.9772)
		(end 360.761534 -96.914716)
		(stroke
			(width 0.05715)
			(type default)
		)
		(layer "B.Cu")
	)
	(gr_line
		(start 360.69905 -96.5073)
		(end 360.761534 -96.569784)
		(stroke
			(width 0.05715)
			(type default)
		)
		(layer "B.Cu")
	)
	(gr_line
		(start 360.69905 -96.10725)
		(end 360.69905 -96.5073)
		(stroke
			(width 0.05715)
			(type default)
		)
		(layer "B.Cu")
	)
	(gr_line
		(start 360.702606 -105.649268)
		(end 360.7054 -105.663238)
		(stroke
			(width 0.05715)
			(type default)
		)
		(layer "B.Cu")
	)
	(gr_line
		(start 360.784648 -113.166906)
		(end 360.797094 -113.203482)
		(stroke
			(width 0.05715)
			(type default)
		)
		(layer "B.Cu")
	)
	(gr_line
		(start 360.787442 -109.883194)
		(end 360.791252 -109.860334)
		(stroke
			(width 0.05715)
			(type default)
		)
		(layer "B.Cu")
	)
	(gr_line
		(start 360.787442 -109.883194)
		(end 360.7943 -109.905292)
		(stroke
			(width 0.05715)
			(type default)
		)
		(layer "B.Cu")
	)
	(gr_line
		(start 360.791252 -109.859572)
		(end 360.791252 -109.86008)
		(stroke
			(width 0.05715)
			(type default)
		)
		(layer "B.Cu")
	)
	(gr_line
		(start 360.797094 -113.203482)
		(end 360.827574 -113.226596)
		(stroke
			(width 0.05715)
			(type default)
		)
		(layer "B.Cu")
	)
	(gr_line
		(start 360.81081 -94.553786)
		(end 360.81081 -94.89059)
		(stroke
			(width 0.05715)
			(type default)
		)
		(layer "B.Cu")
	)
	(gr_line
		(start 360.81081 -94.553786)
		(end 360.931714 -94.432882)
		(stroke
			(width 0.05715)
			(type default)
		)
		(layer "B.Cu")
	)
	(gr_line
		(start 360.81081 -93.9673)
		(end 360.931714 -94.088204)
		(stroke
			(width 0.05715)
			(type default)
		)
		(layer "B.Cu")
	)
	(gr_line
		(start 360.81081 -93.62059)
		(end 360.81081 -93.9673)
		(stroke
			(width 0.05715)
			(type default)
		)
		(layer "B.Cu")
	)
	(gr_line
		(start 360.990642 -102.926896)
		(end 360.992928 -102.93858)
		(stroke
			(width 0.05715)
			(type default)
		)
		(layer "B.Cu")
	)
	(gr_line
		(start 360.990642 -102.926896)
		(end 360.993182 -102.914196)
		(stroke
			(width 0.05715)
			(type default)
		)
		(layer "B.Cu")
	)
	(gr_line
		(start 361.255564 -96.6216)
		(end 361.28452 -96.639634)
		(stroke
			(width 0.05715)
			(type default)
		)
		(layer "B.Cu")
	)
	(gr_line
		(start 361.32389 -99.215194)
		(end 361.361736 -99.24542)
		(stroke
			(width 0.05715)
			(type default)
		)
		(layer "B.Cu")
	)
	(gr_line
		(start 361.465114 -112.035082)
		(end 361.47248 -112.058958)
		(stroke
			(width 0.05715)
			(type default)
		)
		(layer "B.Cu")
	)
	(gr_line
		(start 361.47248 -112.058958)
		(end 361.490768 -112.077246)
		(stroke
			(width 0.05715)
			(type default)
		)
		(layer "B.Cu")
	)
	(gr_line
		(start 361.528106 -94.13621)
		(end 361.58043 -94.214696)
		(stroke
			(width 0.05715)
			(type default)
		)
		(layer "B.Cu")
	)
	(gr_line
		(start 361.570524 -99.41052)
		(end 361.585764 -99.422458)
		(stroke
			(width 0.05715)
			(type default)
		)
		(layer "B.Cu")
	)
	(gr_line
		(start 361.585764 -99.422458)
		(end 361.594654 -99.439984)
		(stroke
			(width 0.05715)
			(type default)
		)
		(layer "B.Cu")
	)
	(gr_line
		(start 361.609132 -125.157484)
		(end 361.782614 -125.330966)
		(stroke
			(width 0.05715)
			(type default)
		)
		(layer "B.Cu")
	)
	(gr_line
		(start 361.609132 -124.812552)
		(end 361.782614 -124.63907)
		(stroke
			(width 0.05715)
			(type default)
		)
		(layer "B.Cu")
	)
	(gr_line
		(start 361.621832 -122.129042)
		(end 361.826556 -122.333766)
		(stroke
			(width 0.05715)
			(type default)
		)
		(layer "B.Cu")
	)
	(gr_line
		(start 361.621832 -121.784364)
		(end 361.826556 -121.57964)
		(stroke
			(width 0.05715)
			(type default)
		)
		(layer "B.Cu")
	)
	(gr_line
		(start 361.7468 -105.625646)
		(end 361.748578 -105.635552)
		(stroke
			(width 0.05715)
			(type default)
		)
		(layer "B.Cu")
	)
	(gr_line
		(start 361.747054 -105.645204)
		(end 361.748578 -105.635552)
		(stroke
			(width 0.05715)
			(type default)
		)
		(layer "B.Cu")
	)
	(gr_line
		(start 361.782614 -125.330966)
		(end 361.782614 -125.558042)
		(stroke
			(width 0.05715)
			(type default)
		)
		(layer "B.Cu")
	)
	(gr_line
		(start 361.782614 -124.440442)
		(end 361.782614 -124.63907)
		(stroke
			(width 0.05715)
			(type default)
		)
		(layer "B.Cu")
	)
	(gr_line
		(start 361.815634 -99.879912)
		(end 361.815888 -99.88042)
		(stroke
			(width 0.05715)
			(type default)
		)
		(layer "B.Cu")
	)
	(gr_line
		(start 361.815888 -99.880674)
		(end 361.837478 -99.9236)
		(stroke
			(width 0.05715)
			(type default)
		)
		(layer "B.Cu")
	)
	(gr_line
		(start 361.826556 -122.333766)
		(end 361.826556 -122.510042)
		(stroke
			(width 0.05715)
			(type default)
		)
		(layer "B.Cu")
	)
	(gr_line
		(start 361.826556 -121.392442)
		(end 361.826556 -121.57964)
		(stroke
			(width 0.05715)
			(type default)
		)
		(layer "B.Cu")
	)
	(gr_line
		(start 361.82808 -99.971098)
		(end 361.837478 -99.9236)
		(stroke
			(width 0.05715)
			(type default)
		)
		(layer "B.Cu")
	)
	(gr_line
		(start 361.86237 -109.34446)
		(end 361.86491 -109.357668)
		(stroke
			(width 0.05715)
			(type default)
		)
		(layer "B.Cu")
	)
	(gr_line
		(start 361.86237 -109.34446)
		(end 361.865164 -109.33049)
		(stroke
			(width 0.05715)
			(type default)
		)
		(layer "B.Cu")
	)
	(gr_line
		(start 361.933236 -97.043494)
		(end 361.962446 -97.061782)
		(stroke
			(width 0.05715)
			(type default)
		)
		(layer "B.Cu")
	)
	(gr_line
		(start 361.962446 -97.061782)
		(end 361.97794 -97.093024)
		(stroke
			(width 0.05715)
			(type default)
		)
		(layer "B.Cu")
	)
	(gr_line
		(start 362.063284 -102.914704)
		(end 362.065824 -102.927912)
		(stroke
			(width 0.05715)
			(type default)
		)
		(layer "B.Cu")
	)
	(gr_line
		(start 362.063284 -102.914704)
		(end 362.066078 -102.900734)
		(stroke
			(width 0.05715)
			(type default)
		)
		(layer "B.Cu")
	)
	(gr_line
		(start 362.39196 -111.521748)
		(end 362.39577 -111.529622)
		(stroke
			(width 0.05715)
			(type default)
		)
		(layer "B.Cu")
	)
	(gr_line
		(start 362.39577 -111.529622)
		(end 362.401866 -111.535718)
		(stroke
			(width 0.05715)
			(type default)
		)
		(layer "B.Cu")
	)
	(gr_line
		(start 362.595922 -114.582702)
		(end 362.633006 -114.61115)
		(stroke
			(width 0.05715)
			(type default)
		)
		(layer "B.Cu")
	)
	(gr_line
		(start 362.66247 -111.796322)
		(end 362.708952 -111.84255)
		(stroke
			(width 0.05715)
			(type default)
		)
		(layer "B.Cu")
	)
	(gr_line
		(start 362.671614 -125.558042)
		(end 363.057948 -125.171708)
		(stroke
			(width 0.05715)
			(type default)
		)
		(layer "B.Cu")
	)
	(gr_line
		(start 362.671614 -124.440442)
		(end 363.057948 -124.826776)
		(stroke
			(width 0.05715)
			(type default)
		)
		(layer "B.Cu")
	)
	(gr_line
		(start 362.715556 -122.510042)
		(end 363.10189 -122.123708)
		(stroke
			(width 0.05715)
			(type default)
		)
		(layer "B.Cu")
	)
	(gr_line
		(start 362.715556 -121.392442)
		(end 363.10189 -121.778776)
		(stroke
			(width 0.05715)
			(type default)
		)
		(layer "B.Cu")
	)
	(gr_line
		(start 362.84916 -105.6132)
		(end 362.851954 -105.62717)
		(stroke
			(width 0.05715)
			(type default)
		)
		(layer "B.Cu")
	)
	(gr_line
		(start 363.02061 -99.212908)
		(end 363.041438 -99.255072)
		(stroke
			(width 0.05715)
			(type default)
		)
		(layer "B.Cu")
	)
	(gr_line
		(start 363.02061 -99.2124)
		(end 363.02061 -99.212654)
		(stroke
			(width 0.05715)
			(type default)
		)
		(layer "B.Cu")
	)
	(gr_line
		(start 363.032294 -99.3013)
		(end 363.041438 -99.255072)
		(stroke
			(width 0.05715)
			(type default)
		)
		(layer "B.Cu")
	)
	(gr_line
		(start 363.106208 -103.169212)
		(end 363.108748 -103.18242)
		(stroke
			(width 0.05715)
			(type default)
		)
		(layer "B.Cu")
	)
	(gr_line
		(start 363.106208 -103.169212)
		(end 363.109002 -103.155242)
		(stroke
			(width 0.05715)
			(type default)
		)
		(layer "B.Cu")
	)
	(gr_line
		(start 363.260132 -107.950508)
		(end 363.262672 -107.963716)
		(stroke
			(width 0.05715)
			(type default)
		)
		(layer "B.Cu")
	)
	(gr_line
		(start 363.260132 -107.950508)
		(end 363.262672 -107.937046)
		(stroke
			(width 0.05715)
			(type default)
		)
		(layer "B.Cu")
	)
	(gr_line
		(start 363.262672 -107.9373)
		(end 363.262926 -107.936538)
		(stroke
			(width 0.05715)
			(type default)
		)
		(layer "B.Cu")
	)
	(gr_line
		(start 363.48035 -109.05109)
		(end 363.482636 -109.063536)
		(stroke
			(width 0.05715)
			(type default)
		)
		(layer "B.Cu")
	)
	(gr_line
		(start 363.482636 -109.063536)
		(end 363.490002 -109.074712)
		(stroke
			(width 0.05715)
			(type default)
		)
		(layer "B.Cu")
	)
	(gr_line
		(start 363.636814 -120.97131)
		(end 363.71022 -120.91924)
		(stroke
			(width 0.05715)
			(type default)
		)
		(layer "B.Cu")
	)
	(gr_line
		(start 363.715554 -97.417128)
		(end 363.72292 -97.428304)
		(stroke
			(width 0.05715)
			(type default)
		)
		(layer "B.Cu")
	)
	(gr_line
		(start 363.72292 -97.428304)
		(end 363.725206 -97.44075)
		(stroke
			(width 0.05715)
			(type default)
		)
		(layer "B.Cu")
	)
	(gr_line
		(start 363.904784 -105.931208)
		(end 363.907578 -105.945178)
		(stroke
			(width 0.05715)
			(type default)
		)
		(layer "B.Cu")
	)
	(gr_line
		(start 363.905038 -105.958386)
		(end 363.907578 -105.945178)
		(stroke
			(width 0.05715)
			(type default)
		)
		(layer "B.Cu")
	)
	(gr_line
		(start 364.064042 -109.935264)
		(end 364.102142 -109.992414)
		(stroke
			(width 0.05715)
			(type default)
		)
		(layer "B.Cu")
	)
	(gr_line
		(start 364.102142 -109.992414)
		(end 364.16996 -110.004352)
		(stroke
			(width 0.05715)
			(type default)
		)
		(layer "B.Cu")
	)
	(gr_line
		(start 364.109 -99.358958)
		(end 364.111794 -99.372928)
		(stroke
			(width 0.05715)
			(type default)
		)
		(layer "B.Cu")
	)
	(gr_line
		(start 364.132114 -118.434866)
		(end 364.152434 -118.429024)
		(stroke
			(width 0.05715)
			(type default)
		)
		(layer "B.Cu")
	)
	(gr_line
		(start 364.152434 -118.429024)
		(end 364.174024 -118.433088)
		(stroke
			(width 0.05715)
			(type default)
		)
		(layer "B.Cu")
	)
	(gr_line
		(start 364.541816 -111.881666)
		(end 364.617 -111.95685)
		(stroke
			(width 0.05715)
			(type default)
		)
		(layer "B.Cu")
	)
	(gr_line
		(start 364.541816 -111.536734)
		(end 364.617 -111.46155)
		(stroke
			(width 0.05715)
			(type default)
		)
		(layer "B.Cu")
	)
	(gr_line
		(start 364.554516 -114.662966)
		(end 364.617 -114.72545)
		(stroke
			(width 0.05715)
			(type default)
		)
		(layer "B.Cu")
	)
	(gr_line
		(start 364.554516 -114.318034)
		(end 364.617 -114.25555)
		(stroke
			(width 0.05715)
			(type default)
		)
		(layer "B.Cu")
	)
	(gr_line
		(start 364.617 -114.72545)
		(end 364.617 -115.189)
		(stroke
			(width 0.05715)
			(type default)
		)
		(layer "B.Cu")
	)
	(gr_line
		(start 364.617 -113.792)
		(end 364.617 -114.25555)
		(stroke
			(width 0.05715)
			(type default)
		)
		(layer "B.Cu")
	)
	(gr_line
		(start 364.617 -111.95685)
		(end 364.617 -112.395)
		(stroke
			(width 0.05715)
			(type default)
		)
		(layer "B.Cu")
	)
	(gr_line
		(start 364.617 -110.998)
		(end 364.617 -111.46155)
		(stroke
			(width 0.05715)
			(type default)
		)
		(layer "B.Cu")
	)
	(gr_line
		(start 364.810548 -120.141492)
		(end 364.826042 -120.13057)
		(stroke
			(width 0.05715)
			(type default)
		)
		(layer "B.Cu")
	)
	(gr_line
		(start 364.826042 -120.13057)
		(end 364.82655 -120.13057)
		(stroke
			(width 0.05715)
			(type default)
		)
		(layer "B.Cu")
	)
	(gr_line
		(start 364.82655 -120.13057)
		(end 364.84433 -120.127268)
		(stroke
			(width 0.05715)
			(type default)
		)
		(layer "B.Cu")
	)
	(gr_line
		(start 364.844584 -121.333514)
		(end 365.359696 -121.848626)
		(stroke
			(width 0.05715)
			(type default)
		)
		(layer "B.Cu")
	)
	(gr_line
		(start 364.856014 -124.288042)
		(end 365.399574 -124.831602)
		(stroke
			(width 0.05715)
			(type default)
		)
		(layer "B.Cu")
	)
	(gr_line
		(start 364.881414 -125.481842)
		(end 364.881414 -125.583442)
		(stroke
			(width 0.05715)
			(type default)
		)
		(layer "B.Cu")
	)
	(gr_line
		(start 364.881414 -125.481842)
		(end 365.287814 -125.075442)
		(stroke
			(width 0.05715)
			(type default)
		)
		(layer "B.Cu")
	)
	(gr_line
		(start 364.8964 -122.6566)
		(end 365.359696 -122.193304)
		(stroke
			(width 0.05715)
			(type default)
		)
		(layer "B.Cu")
	)
	(gr_line
		(start 365.506 -114.7064)
		(end 365.506 -115.189)
		(stroke
			(width 0.05715)
			(type default)
		)
		(layer "B.Cu")
	)
	(gr_line
		(start 365.506 -114.7064)
		(end 365.568484 -114.643916)
		(stroke
			(width 0.05715)
			(type default)
		)
		(layer "B.Cu")
	)
	(gr_line
		(start 365.506 -114.2365)
		(end 365.568484 -114.298984)
		(stroke
			(width 0.05715)
			(type default)
		)
		(layer "B.Cu")
	)
	(gr_line
		(start 365.506 -113.792)
		(end 365.506 -114.2365)
		(stroke
			(width 0.05715)
			(type default)
		)
		(layer "B.Cu")
	)
	(gr_line
		(start 365.506 -111.9505)
		(end 365.506 -112.395)
		(stroke
			(width 0.05715)
			(type default)
		)
		(layer "B.Cu")
	)
	(gr_line
		(start 365.506 -111.9505)
		(end 365.592868 -111.863632)
		(stroke
			(width 0.05715)
			(type default)
		)
		(layer "B.Cu")
	)
	(gr_line
		(start 365.506 -111.431832)
		(end 365.592868 -111.5187)
		(stroke
			(width 0.05715)
			(type default)
		)
		(layer "B.Cu")
	)
	(gr_line
		(start 365.506 -110.998)
		(end 365.506 -111.431832)
		(stroke
			(width 0.05715)
			(type default)
		)
		(layer "B.Cu")
	)
	(gr_line
		(start 366.227868 -122.662696)
		(end 366.329722 -122.560842)
		(stroke
			(width 0.0508)
			(type default)
		)
		(layer "B.Cu")
	)
	(gr_line
		(start 366.278414 -125.583442)
		(end 366.354614 -125.507242)
		(stroke
			(width 0.05715)
			(type default)
		)
		(layer "B.Cu")
	)
	(gr_line
		(start 366.278414 -124.262642)
		(end 366.405414 -124.389642)
		(stroke
			(width 0.05715)
			(type default)
		)
		(layer "B.Cu")
	)
	(gr_line
		(start 366.303814 -121.316242)
		(end 366.430814 -121.443242)
		(stroke
			(width 0.0508)
			(type default)
		)
		(layer "B.Cu")
	)
	(gr_line
		(start 366.329722 -122.560842)
		(end 366.931956 -122.560842)
		(stroke
			(width 0.0508)
			(type default)
		)
		(layer "B.Cu")
	)
	(gr_line
		(start 366.347756 -119.08028)
		(end 366.362234 -119.083074)
		(stroke
			(width 0.05715)
			(type default)
		)
		(layer "B.Cu")
	)
	(gr_line
		(start 366.354614 -125.507242)
		(end 366.938814 -125.507242)
		(stroke
			(width 0.05715)
			(type default)
		)
		(layer "B.Cu")
	)
	(gr_line
		(start 366.362234 -119.083074)
		(end 366.376966 -119.079772)
		(stroke
			(width 0.05715)
			(type default)
		)
		(layer "B.Cu")
	)
	(gr_line
		(start 366.405414 -124.389642)
		(end 366.938814 -124.389642)
		(stroke
			(width 0.05715)
			(type default)
		)
		(layer "B.Cu")
	)
	(gr_line
		(start 366.430814 -121.443242)
		(end 366.931956 -121.443242)
		(stroke
			(width 0.0508)
			(type default)
		)
		(layer "B.Cu")
	)
	(gr_line
		(start 366.770158 -114.3635)
		(end 366.782096 -114.368326)
		(stroke
			(width 0.05715)
			(type default)
		)
		(layer "B.Cu")
	)
	(gr_line
		(start 367.284 -131.318)
		(end 367.284 -120.777)
		(stroke
			(width 0.2)
			(type default)
		)
		(layer "B.Cu")
	)
	(gr_line
		(start 367.284 -120.777)
		(end 371.983 -120.777)
		(stroke
			(width 0.2)
			(type default)
		)
		(layer "B.Cu")
	)
	(gr_line
		(start 367.520982 -114.935762)
		(end 367.53292 -114.940588)
		(stroke
			(width 0.05715)
			(type default)
		)
		(layer "B.Cu")
	)
	(gr_line
		(start 367.583212 -126.66726)
		(end 367.694972 -126.5555)
		(stroke
			(width 0.05715)
			(type default)
		)
		(layer "B.Cu")
	)
	(gr_line
		(start 367.627408 -118.549674)
		(end 367.642394 -118.546372)
		(stroke
			(width 0.05715)
			(type default)
		)
		(layer "B.Cu")
	)
	(gr_line
		(start 367.642394 -118.546372)
		(end 367.65738 -118.549166)
		(stroke
			(width 0.05715)
			(type default)
		)
		(layer "B.Cu")
	)
	(gr_line
		(start 367.665 -131.445)
		(end 367.665 -119.38)
		(stroke
			(width 0.2)
			(type default)
		)
		(layer "B.Cu")
	)
	(gr_line
		(start 367.665 -119.38)
		(end 371.856 -119.38)
		(stroke
			(width 0.2)
			(type default)
		)
		(layer "B.Cu")
	)
	(gr_line
		(start 367.694972 -126.5555)
		(end 368.037872 -126.5555)
		(stroke
			(width 0.05715)
			(type default)
		)
		(layer "B.Cu")
	)
	(gr_line
		(start 367.700306 -122.173746)
		(end 367.820956 -122.294396)
		(stroke
			(width 0.05715)
			(type default)
		)
		(layer "B.Cu")
	)
	(gr_line
		(start 367.700306 -121.828814)
		(end 367.820956 -121.708164)
		(stroke
			(width 0.05715)
			(type default)
		)
		(layer "B.Cu")
	)
	(gr_line
		(start 367.70818 -125.108208)
		(end 367.827814 -125.227842)
		(stroke
			(width 0.05715)
			(type default)
		)
		(layer "B.Cu")
	)
	(gr_line
		(start 367.70818 -124.763276)
		(end 367.827814 -124.643642)
		(stroke
			(width 0.05715)
			(type default)
		)
		(layer "B.Cu")
	)
	(gr_line
		(start 367.708434 -119.596916)
		(end 367.721642 -119.594376)
		(stroke
			(width 0.05715)
			(type default)
		)
		(layer "B.Cu")
	)
	(gr_line
		(start 367.721642 -119.594376)
		(end 367.735104 -119.59717)
		(stroke
			(width 0.05715)
			(type default)
		)
		(layer "B.Cu")
	)
	(gr_line
		(start 367.820956 -122.294396)
		(end 367.820956 -122.560842)
		(stroke
			(width 0.05715)
			(type default)
		)
		(layer "B.Cu")
	)
	(gr_line
		(start 367.820956 -121.443242)
		(end 367.820956 -121.708164)
		(stroke
			(width 0.05715)
			(type default)
		)
		(layer "B.Cu")
	)
	(gr_line
		(start 367.824512 -126.9111)
		(end 367.908332 -126.9111)
		(stroke
			(width 0.05715)
			(type default)
		)
		(layer "B.Cu")
	)
	(gr_line
		(start 367.827814 -125.227842)
		(end 367.827814 -125.507242)
		(stroke
			(width 0.05715)
			(type default)
		)
		(layer "B.Cu")
	)
	(gr_line
		(start 367.827814 -124.389642)
		(end 367.827814 -124.643642)
		(stroke
			(width 0.05715)
			(type default)
		)
		(layer "B.Cu")
	)
	(gr_line
		(start 367.8682 -114.940588)
		(end 367.890298 -114.940588)
		(stroke
			(width 0.04445)
			(type default)
		)
		(layer "B.Cu")
	)
	(gr_line
		(start 367.8682 -114.699288)
		(end 367.890298 -114.699288)
		(stroke
			(width 0.04445)
			(type default)
		)
		(layer "B.Cu")
	)
	(gr_line
		(start 367.890298 -114.940588)
		(end 367.915698 -114.915188)
		(stroke
			(width 0.04445)
			(type default)
		)
		(layer "B.Cu")
	)
	(gr_line
		(start 367.890298 -114.699288)
		(end 367.915698 -114.724688)
		(stroke
			(width 0.04445)
			(type default)
		)
		(layer "B.Cu")
	)
	(gr_line
		(start 368.037872 -126.5555)
		(end 368.149632 -126.66726)
		(stroke
			(width 0.05715)
			(type default)
		)
		(layer "B.Cu")
	)
	(gr_line
		(start 368.266472 -128.752854)
		(end 368.287554 -128.75768)
		(stroke
			(width 0.05715)
			(type default)
		)
		(layer "B.Cu")
	)
	(gr_line
		(start 368.276632 -129.784348)
		(end 368.297714 -129.789174)
		(stroke
			(width 0.05715)
			(type default)
		)
		(layer "B.Cu")
	)
	(gr_line
		(start 368.287554 -128.75768)
		(end 368.308128 -128.7526)
		(stroke
			(width 0.05715)
			(type default)
		)
		(layer "B.Cu")
	)
	(gr_line
		(start 368.297714 -129.789174)
		(end 368.318288 -129.784094)
		(stroke
			(width 0.05715)
			(type default)
		)
		(layer "B.Cu")
	)
	(gr_line
		(start 368.48415 -113.262664)
		(end 368.554 -113.332514)
		(stroke
			(width 0.05715)
			(type default)
		)
		(layer "B.Cu")
	)
	(gr_line
		(start 368.48415 -112.917732)
		(end 368.554 -112.847882)
		(stroke
			(width 0.05715)
			(type default)
		)
		(layer "B.Cu")
	)
	(gr_line
		(start 368.491516 -110.471966)
		(end 368.554 -110.53445)
		(stroke
			(width 0.05715)
			(type default)
		)
		(layer "B.Cu")
	)
	(gr_line
		(start 368.491516 -110.127034)
		(end 368.554 -110.06455)
		(stroke
			(width 0.05715)
			(type default)
		)
		(layer "B.Cu")
	)
	(gr_line
		(start 368.554 -113.332514)
		(end 368.554 -113.792)
		(stroke
			(width 0.05715)
			(type default)
		)
		(layer "B.Cu")
	)
	(gr_line
		(start 368.554 -112.395)
		(end 368.554 -112.847882)
		(stroke
			(width 0.05715)
			(type default)
		)
		(layer "B.Cu")
	)
	(gr_line
		(start 368.554 -110.53445)
		(end 368.554 -110.998)
		(stroke
			(width 0.05715)
			(type default)
		)
		(layer "B.Cu")
	)
	(gr_line
		(start 368.554 -109.601)
		(end 368.554 -110.06455)
		(stroke
			(width 0.05715)
			(type default)
		)
		(layer "B.Cu")
	)
	(gr_line
		(start 368.709956 -122.560842)
		(end 369.09629 -122.174508)
		(stroke
			(width 0.05715)
			(type default)
		)
		(layer "B.Cu")
	)
	(gr_line
		(start 368.709956 -121.443242)
		(end 369.09629 -121.829576)
		(stroke
			(width 0.05715)
			(type default)
		)
		(layer "B.Cu")
	)
	(gr_line
		(start 368.716814 -125.507242)
		(end 369.103148 -125.120908)
		(stroke
			(width 0.05715)
			(type default)
		)
		(layer "B.Cu")
	)
	(gr_line
		(start 368.716814 -124.389642)
		(end 369.103148 -124.775976)
		(stroke
			(width 0.05715)
			(type default)
		)
		(layer "B.Cu")
	)
	(gr_line
		(start 369.443 -113.3348)
		(end 369.443 -113.792)
		(stroke
			(width 0.05715)
			(type default)
		)
		(layer "B.Cu")
	)
	(gr_line
		(start 369.443 -113.3348)
		(end 369.511834 -113.265966)
		(stroke
			(width 0.05715)
			(type default)
		)
		(layer "B.Cu")
	)
	(gr_line
		(start 369.443 -112.852454)
		(end 369.511834 -112.921288)
		(stroke
			(width 0.05715)
			(type default)
		)
		(layer "B.Cu")
	)
	(gr_line
		(start 369.443 -112.395)
		(end 369.443 -112.852454)
		(stroke
			(width 0.05715)
			(type default)
		)
		(layer "B.Cu")
	)
	(gr_line
		(start 369.443 -110.5408)
		(end 369.443 -110.998)
		(stroke
			(width 0.05715)
			(type default)
		)
		(layer "B.Cu")
	)
	(gr_line
		(start 369.443 -110.5408)
		(end 369.500658 -110.483142)
		(stroke
			(width 0.05715)
			(type default)
		)
		(layer "B.Cu")
	)
	(gr_line
		(start 369.443 -110.080552)
		(end 369.500658 -110.13821)
		(stroke
			(width 0.05715)
			(type default)
		)
		(layer "B.Cu")
	)
	(gr_line
		(start 369.443 -109.601)
		(end 369.443 -110.080552)
		(stroke
			(width 0.05715)
			(type default)
		)
		(layer "B.Cu")
	)
	(gr_line
		(start 369.833652 -119.185944)
		(end 369.844066 -119.187976)
		(stroke
			(width 0.05715)
			(type default)
		)
		(layer "B.Cu")
	)
	(gr_line
		(start 369.844066 -119.187976)
		(end 369.854988 -119.185944)
		(stroke
			(width 0.05715)
			(type default)
		)
		(layer "B.Cu")
	)
	(gr_line
		(start 369.876832 -110.218474)
		(end 369.88877 -110.2233)
		(stroke
			(width 0.05715)
			(type default)
		)
		(layer "B.Cu")
	)
	(gr_line
		(start 369.976654 -112.9792)
		(end 369.988592 -112.984026)
		(stroke
			(width 0.05715)
			(type default)
		)
		(layer "B.Cu")
	)
	(gr_line
		(start 370.247164 -117.64772)
		(end 370.269262 -117.64772)
		(stroke
			(width 0.04445)
			(type default)
		)
		(layer "B.Cu")
	)
	(gr_line
		(start 370.247164 -117.40642)
		(end 370.269262 -117.40642)
		(stroke
			(width 0.04445)
			(type default)
		)
		(layer "B.Cu")
	)
	(gr_line
		(start 370.269262 -117.64772)
		(end 370.294662 -117.62232)
		(stroke
			(width 0.04445)
			(type default)
		)
		(layer "B.Cu")
	)
	(gr_line
		(start 370.269262 -117.40642)
		(end 370.294662 -117.43182)
		(stroke
			(width 0.04445)
			(type default)
		)
		(layer "B.Cu")
	)
	(gr_line
		(start 370.486686 -110.732316)
		(end 370.498624 -110.737142)
		(stroke
			(width 0.05715)
			(type default)
		)
		(layer "B.Cu")
	)
	(gr_line
		(start 370.521484 -128.21031)
		(end 370.553488 -128.202436)
		(stroke
			(width 0.05715)
			(type default)
		)
		(layer "B.Cu")
	)
	(gr_line
		(start 370.538502 -117.62486)
		(end 370.624862 -117.71122)
		(stroke
			(width 0.04445)
			(type default)
		)
		(layer "B.Cu")
	)
	(gr_line
		(start 370.624862 -117.71122)
		(end 370.904262 -117.71122)
		(stroke
			(width 0.04445)
			(type default)
		)
		(layer "B.Cu")
	)
	(gr_line
		(start 370.729002 -117.43182)
		(end 370.800122 -117.43182)
		(stroke
			(width 0.04445)
			(type default)
		)
		(layer "B.Cu")
	)
	(gr_line
		(start 370.904262 -117.71122)
		(end 370.990622 -117.62486)
		(stroke
			(width 0.04445)
			(type default)
		)
		(layer "B.Cu")
	)
	(gr_line
		(start 370.98986 -113.660174)
		(end 371.001798 -113.665)
		(stroke
			(width 0.05715)
			(type default)
		)
		(layer "B.Cu")
	)
	(gr_line
		(start 371.007132 -122.144282)
		(end 371.118892 -122.256042)
		(stroke
			(width 0.05715)
			(type default)
		)
		(layer "B.Cu")
	)
	(gr_line
		(start 371.113304 -129.09931)
		(end 371.145308 -129.091436)
		(stroke
			(width 0.05715)
			(type default)
		)
		(layer "B.Cu")
	)
	(gr_line
		(start 371.117114 -110.739682)
		(end 371.17274 -110.795308)
		(stroke
			(width 0.05715)
			(type default)
		)
		(layer "B.Cu")
	)
	(gr_line
		(start 371.118892 -122.256042)
		(end 371.474492 -122.256042)
		(stroke
			(width 0.05715)
			(type default)
		)
		(layer "B.Cu")
	)
	(gr_line
		(start 371.17274 -110.795562)
		(end 371.230906 -110.853728)
		(stroke
			(width 0.05715)
			(type default)
		)
		(layer "B.Cu")
	)
	(gr_line
		(start 371.17274 -110.795308)
		(end 371.17274 -110.795562)
		(stroke
			(width 0.05715)
			(type default)
		)
		(layer "B.Cu")
	)
	(gr_line
		(start 371.230906 -110.853728)
		(end 371.573806 -110.853728)
		(stroke
			(width 0.05715)
			(type default)
		)
		(layer "B.Cu")
	)
	(gr_line
		(start 371.248432 -121.900442)
		(end 371.344952 -121.900442)
		(stroke
			(width 0.05715)
			(type default)
		)
		(layer "B.Cu")
	)
	(gr_line
		(start 371.275102 -117.62486)
		(end 371.361462 -117.71122)
		(stroke
			(width 0.04445)
			(type default)
		)
		(layer "B.Cu")
	)
	(gr_line
		(start 371.358414 -110.495842)
		(end 371.446298 -110.495842)
		(stroke
			(width 0.05715)
			(type default)
		)
		(layer "B.Cu")
	)
	(gr_line
		(start 371.361462 -117.71122)
		(end 371.640862 -117.71122)
		(stroke
			(width 0.04445)
			(type default)
		)
		(layer "B.Cu")
	)
	(gr_line
		(start 371.465602 -117.43182)
		(end 371.536722 -117.43182)
		(stroke
			(width 0.04445)
			(type default)
		)
		(layer "B.Cu")
	)
	(gr_line
		(start 371.474492 -122.256042)
		(end 371.586252 -122.144282)
		(stroke
			(width 0.05715)
			(type default)
		)
		(layer "B.Cu")
	)
	(gr_line
		(start 371.573806 -110.853728)
		(end 371.631972 -110.795562)
		(stroke
			(width 0.05715)
			(type default)
		)
		(layer "B.Cu")
	)
	(gr_line
		(start 371.576854 -118.611396)
		(end 371.59438 -118.608094)
		(stroke
			(width 0.05715)
			(type default)
		)
		(layer "B.Cu")
	)
	(gr_line
		(start 371.59438 -118.608094)
		(end 371.611652 -118.612158)
		(stroke
			(width 0.05715)
			(type default)
		)
		(layer "B.Cu")
	)
	(gr_line
		(start 371.631972 -110.795308)
		(end 371.631972 -110.795562)
		(stroke
			(width 0.05715)
			(type default)
		)
		(layer "B.Cu")
	)
	(gr_line
		(start 371.631972 -110.795308)
		(end 371.687598 -110.739682)
		(stroke
			(width 0.05715)
			(type default)
		)
		(layer "B.Cu")
	)
	(gr_line
		(start 371.640862 -117.71122)
		(end 371.727222 -117.62486)
		(stroke
			(width 0.04445)
			(type default)
		)
		(layer "B.Cu")
	)
	(gr_line
		(start 371.856 -131.445)
		(end 367.665 -131.445)
		(stroke
			(width 0.2)
			(type default)
		)
		(layer "B.Cu")
	)
	(gr_line
		(start 371.856 -119.38)
		(end 371.856 -131.445)
		(stroke
			(width 0.2)
			(type default)
		)
		(layer "B.Cu")
	)
	(gr_line
		(start 371.983 -131.318)
		(end 367.284 -131.318)
		(stroke
			(width 0.2)
			(type default)
		)
		(layer "B.Cu")
	)
	(gr_line
		(start 371.983 -120.777)
		(end 371.983 -131.318)
		(stroke
			(width 0.2)
			(type default)
		)
		(layer "B.Cu")
	)
	(gr_line
		(start 372.011702 -117.62486)
		(end 372.098062 -117.71122)
		(stroke
			(width 0.04445)
			(type default)
		)
		(layer "B.Cu")
	)
	(gr_line
		(start 372.034816 -112.594136)
		(end 372.056914 -112.594136)
		(stroke
			(width 0.04445)
			(type default)
		)
		(layer "B.Cu")
	)
	(gr_line
		(start 372.034816 -112.352836)
		(end 372.056914 -112.352836)
		(stroke
			(width 0.04445)
			(type default)
		)
		(layer "B.Cu")
	)
	(gr_line
		(start 372.035578 -110.739682)
		(end 372.091204 -110.795308)
		(stroke
			(width 0.05715)
			(type default)
		)
		(layer "B.Cu")
	)
	(gr_line
		(start 372.056914 -112.594136)
		(end 372.082314 -112.568736)
		(stroke
			(width 0.04445)
			(type default)
		)
		(layer "B.Cu")
	)
	(gr_line
		(start 372.056914 -112.352836)
		(end 372.082314 -112.378236)
		(stroke
			(width 0.04445)
			(type default)
		)
		(layer "B.Cu")
	)
	(gr_line
		(start 372.091204 -110.795562)
		(end 372.14937 -110.853728)
		(stroke
			(width 0.05715)
			(type default)
		)
		(layer "B.Cu")
	)
	(gr_line
		(start 372.091204 -110.795308)
		(end 372.091204 -110.795562)
		(stroke
			(width 0.05715)
			(type default)
		)
		(layer "B.Cu")
	)
	(gr_line
		(start 372.098062 -117.71122)
		(end 372.377462 -117.71122)
		(stroke
			(width 0.04445)
			(type default)
		)
		(layer "B.Cu")
	)
	(gr_line
		(start 372.14937 -110.853728)
		(end 372.49227 -110.853728)
		(stroke
			(width 0.05715)
			(type default)
		)
		(layer "B.Cu")
	)
	(gr_line
		(start 372.202202 -117.43182)
		(end 372.273322 -117.43182)
		(stroke
			(width 0.04445)
			(type default)
		)
		(layer "B.Cu")
	)
	(gr_line
		(start 372.276878 -110.495842)
		(end 372.364762 -110.495842)
		(stroke
			(width 0.05715)
			(type default)
		)
		(layer "B.Cu")
	)
	(gr_line
		(start 372.377462 -117.71122)
		(end 372.463822 -117.62486)
		(stroke
			(width 0.04445)
			(type default)
		)
		(layer "B.Cu")
	)
	(gr_line
		(start 372.49227 -110.853728)
		(end 372.550436 -110.795562)
		(stroke
			(width 0.05715)
			(type default)
		)
		(layer "B.Cu")
	)
	(gr_line
		(start 372.550436 -110.795308)
		(end 372.550436 -110.795562)
		(stroke
			(width 0.05715)
			(type default)
		)
		(layer "B.Cu")
	)
	(gr_line
		(start 372.550436 -110.795308)
		(end 372.606062 -110.739682)
		(stroke
			(width 0.05715)
			(type default)
		)
		(layer "B.Cu")
	)
	(gr_line
		(start 372.591838 -112.571276)
		(end 372.68023 -112.659668)
		(stroke
			(width 0.04445)
			(type default)
		)
		(layer "B.Cu")
	)
	(gr_line
		(start 372.68023 -112.659668)
		(end 372.94693 -112.659668)
		(stroke
			(width 0.04445)
			(type default)
		)
		(layer "B.Cu")
	)
	(gr_line
		(start 372.782338 -112.378236)
		(end 372.844822 -112.378236)
		(stroke
			(width 0.04445)
			(type default)
		)
		(layer "B.Cu")
	)
	(gr_line
		(start 372.94693 -112.659668)
		(end 373.035322 -112.571276)
		(stroke
			(width 0.04445)
			(type default)
		)
		(layer "B.Cu")
	)
	(gr_line
		(start 372.954042 -110.739682)
		(end 373.009668 -110.795308)
		(stroke
			(width 0.05715)
			(type default)
		)
		(layer "B.Cu")
	)
	(gr_line
		(start 373.009668 -110.795562)
		(end 373.067834 -110.853728)
		(stroke
			(width 0.05715)
			(type default)
		)
		(layer "B.Cu")
	)
	(gr_line
		(start 373.009668 -110.795308)
		(end 373.009668 -110.795562)
		(stroke
			(width 0.05715)
			(type default)
		)
		(layer "B.Cu")
	)
	(gr_line
		(start 373.067834 -110.853728)
		(end 373.410734 -110.853728)
		(stroke
			(width 0.05715)
			(type default)
		)
		(layer "B.Cu")
	)
	(gr_line
		(start 373.080788 -120.662446)
		(end 373.102886 -120.662446)
		(stroke
			(width 0.04445)
			(type default)
		)
		(layer "B.Cu")
	)
	(gr_line
		(start 373.080788 -120.421146)
		(end 373.102886 -120.421146)
		(stroke
			(width 0.04445)
			(type default)
		)
		(layer "B.Cu")
	)
	(gr_line
		(start 373.102886 -120.662446)
		(end 373.128286 -120.637046)
		(stroke
			(width 0.04445)
			(type default)
		)
		(layer "B.Cu")
	)
	(gr_line
		(start 373.102886 -120.421146)
		(end 373.128286 -120.446546)
		(stroke
			(width 0.04445)
			(type default)
		)
		(layer "B.Cu")
	)
	(gr_line
		(start 373.195342 -110.495842)
		(end 373.283226 -110.495842)
		(stroke
			(width 0.05715)
			(type default)
		)
		(layer "B.Cu")
	)
	(gr_line
		(start 373.213122 -119.199406)
		(end 373.23522 -119.199406)
		(stroke
			(width 0.04445)
			(type default)
		)
		(layer "B.Cu")
	)
	(gr_line
		(start 373.213122 -118.958106)
		(end 373.23522 -118.958106)
		(stroke
			(width 0.04445)
			(type default)
		)
		(layer "B.Cu")
	)
	(gr_line
		(start 373.218202 -114.724688)
		(end 373.22379 -114.727228)
		(stroke
			(width 0.04445)
			(type default)
		)
		(layer "B.Cu")
	)
	(gr_line
		(start 373.23522 -119.199406)
		(end 373.26062 -119.174006)
		(stroke
			(width 0.04445)
			(type default)
		)
		(layer "B.Cu")
	)
	(gr_line
		(start 373.23522 -118.958106)
		(end 373.26062 -118.983506)
		(stroke
			(width 0.04445)
			(type default)
		)
		(layer "B.Cu")
	)
	(gr_line
		(start 373.307102 -112.571276)
		(end 373.395494 -112.659668)
		(stroke
			(width 0.04445)
			(type default)
		)
		(layer "B.Cu")
	)
	(gr_line
		(start 373.395494 -112.659668)
		(end 373.662194 -112.659668)
		(stroke
			(width 0.04445)
			(type default)
		)
		(layer "B.Cu")
	)
	(gr_line
		(start 373.410734 -110.853728)
		(end 373.4689 -110.795562)
		(stroke
			(width 0.05715)
			(type default)
		)
		(layer "B.Cu")
	)
	(gr_line
		(start 373.4689 -110.795308)
		(end 373.4689 -110.795562)
		(stroke
			(width 0.05715)
			(type default)
		)
		(layer "B.Cu")
	)
	(gr_line
		(start 373.4689 -110.795308)
		(end 373.524526 -110.739682)
		(stroke
			(width 0.05715)
			(type default)
		)
		(layer "B.Cu")
	)
	(gr_line
		(start 373.497602 -112.378236)
		(end 373.560086 -112.378236)
		(stroke
			(width 0.04445)
			(type default)
		)
		(layer "B.Cu")
	)
	(gr_line
		(start 373.657876 -119.176546)
		(end 373.744236 -119.262906)
		(stroke
			(width 0.04445)
			(type default)
		)
		(layer "B.Cu")
	)
	(gr_line
		(start 373.662194 -112.659668)
		(end 373.750586 -112.571276)
		(stroke
			(width 0.04445)
			(type default)
		)
		(layer "B.Cu")
	)
	(gr_line
		(start 373.662956 -118.182644)
		(end 373.749316 -118.269004)
		(stroke
			(width 0.04445)
			(type default)
		)
		(layer "B.Cu")
	)
	(gr_line
		(start 373.744236 -119.262906)
		(end 374.023636 -119.262906)
		(stroke
			(width 0.04445)
			(type default)
		)
		(layer "B.Cu")
	)
	(gr_line
		(start 373.749316 -118.269004)
		(end 374.028716 -118.269004)
		(stroke
			(width 0.04445)
			(type default)
		)
		(layer "B.Cu")
	)
	(gr_line
		(start 373.848376 -118.983506)
		(end 373.919496 -118.983506)
		(stroke
			(width 0.04445)
			(type default)
		)
		(layer "B.Cu")
	)
	(gr_line
		(start 373.853456 -117.989604)
		(end 373.924576 -117.989604)
		(stroke
			(width 0.04445)
			(type default)
		)
		(layer "B.Cu")
	)
	(gr_line
		(start 373.872506 -110.739682)
		(end 373.928132 -110.795308)
		(stroke
			(width 0.05715)
			(type default)
		)
		(layer "B.Cu")
	)
	(gr_line
		(start 373.9134 -113.665)
		(end 373.935498 -113.665)
		(stroke
			(width 0.04445)
			(type default)
		)
		(layer "B.Cu")
	)
	(gr_line
		(start 373.9134 -113.4237)
		(end 373.935498 -113.4237)
		(stroke
			(width 0.04445)
			(type default)
		)
		(layer "B.Cu")
	)
	(gr_line
		(start 373.928132 -110.795562)
		(end 373.986298 -110.853728)
		(stroke
			(width 0.05715)
			(type default)
		)
		(layer "B.Cu")
	)
	(gr_line
		(start 373.928132 -110.795308)
		(end 373.928132 -110.795562)
		(stroke
			(width 0.05715)
			(type default)
		)
		(layer "B.Cu")
	)
	(gr_line
		(start 373.935498 -113.665)
		(end 373.960898 -113.6396)
		(stroke
			(width 0.04445)
			(type default)
		)
		(layer "B.Cu")
	)
	(gr_line
		(start 373.935498 -113.4237)
		(end 373.960898 -113.4491)
		(stroke
			(width 0.04445)
			(type default)
		)
		(layer "B.Cu")
	)
	(gr_line
		(start 373.986298 -110.853728)
		(end 374.329198 -110.853728)
		(stroke
			(width 0.05715)
			(type default)
		)
		(layer "B.Cu")
	)
	(gr_line
		(start 374.022366 -112.571276)
		(end 374.110758 -112.659668)
		(stroke
			(width 0.04445)
			(type default)
		)
		(layer "B.Cu")
	)
	(gr_line
		(start 374.023636 -119.262906)
		(end 374.109996 -119.176546)
		(stroke
			(width 0.04445)
			(type default)
		)
		(layer "B.Cu")
	)
	(gr_line
		(start 374.028716 -118.269004)
		(end 374.115076 -118.182644)
		(stroke
			(width 0.04445)
			(type default)
		)
		(layer "B.Cu")
	)
	(gr_line
		(start 374.046242 -120.639586)
		(end 374.132602 -120.725946)
		(stroke
			(width 0.04445)
			(type default)
		)
		(layer "B.Cu")
	)
	(gr_line
		(start 374.110758 -112.659668)
		(end 374.377458 -112.659668)
		(stroke
			(width 0.04445)
			(type default)
		)
		(layer "B.Cu")
	)
	(gr_line
		(start 374.113806 -110.495842)
		(end 374.20169 -110.495842)
		(stroke
			(width 0.05715)
			(type default)
		)
		(layer "B.Cu")
	)
	(gr_line
		(start 374.132602 -120.725946)
		(end 374.412002 -120.725946)
		(stroke
			(width 0.04445)
			(type default)
		)
		(layer "B.Cu")
	)
	(gr_line
		(start 374.181116 -124.071888)
		(end 374.185688 -124.071888)
		(stroke
			(width 0.05715)
			(type default)
		)
		(layer "B.Cu")
	)
	(gr_line
		(start 374.212866 -112.378236)
		(end 374.27535 -112.378236)
		(stroke
			(width 0.04445)
			(type default)
		)
		(layer "B.Cu")
	)
	(gr_line
		(start 374.236742 -120.446546)
		(end 374.307862 -120.446546)
		(stroke
			(width 0.04445)
			(type default)
		)
		(layer "B.Cu")
	)
	(gr_line
		(start 374.329198 -110.853728)
		(end 374.387364 -110.795562)
		(stroke
			(width 0.05715)
			(type default)
		)
		(layer "B.Cu")
	)
	(gr_line
		(start 374.377458 -112.659668)
		(end 374.46585 -112.571276)
		(stroke
			(width 0.04445)
			(type default)
		)
		(layer "B.Cu")
	)
	(gr_line
		(start 374.387364 -110.795308)
		(end 374.387364 -110.795562)
		(stroke
			(width 0.05715)
			(type default)
		)
		(layer "B.Cu")
	)
	(gr_line
		(start 374.387364 -110.795308)
		(end 374.44299 -110.739682)
		(stroke
			(width 0.05715)
			(type default)
		)
		(layer "B.Cu")
	)
	(gr_line
		(start 374.394476 -119.176546)
		(end 374.480836 -119.262906)
		(stroke
			(width 0.04445)
			(type default)
		)
		(layer "B.Cu")
	)
	(gr_line
		(start 374.399556 -118.182644)
		(end 374.485916 -118.269004)
		(stroke
			(width 0.04445)
			(type default)
		)
		(layer "B.Cu")
	)
	(gr_line
		(start 374.412002 -120.725946)
		(end 374.498362 -120.639586)
		(stroke
			(width 0.04445)
			(type default)
		)
		(layer "B.Cu")
	)
	(gr_line
		(start 374.419876 -123.9647)
		(end 374.424448 -123.9647)
		(stroke
			(width 0.05715)
			(type default)
		)
		(layer "B.Cu")
	)
	(gr_line
		(start 374.480836 -119.262906)
		(end 374.760236 -119.262906)
		(stroke
			(width 0.04445)
			(type default)
		)
		(layer "B.Cu")
	)
	(gr_line
		(start 374.485916 -118.269004)
		(end 374.765316 -118.269004)
		(stroke
			(width 0.04445)
			(type default)
		)
		(layer "B.Cu")
	)
	(gr_line
		(start 374.584976 -118.983506)
		(end 374.656096 -118.983506)
		(stroke
			(width 0.04445)
			(type default)
		)
		(layer "B.Cu")
	)
	(gr_line
		(start 374.590056 -117.989604)
		(end 374.661176 -117.989604)
		(stroke
			(width 0.04445)
			(type default)
		)
		(layer "B.Cu")
	)
	(gr_line
		(start 374.701308 -114.224308)
		(end 374.71604 -114.23904)
		(stroke
			(width 0.04445)
			(type default)
		)
		(layer "B.Cu")
	)
	(gr_line
		(start 374.703086 -113.953036)
		(end 374.843548 -113.953036)
		(stroke
			(width 0.04445)
			(type default)
		)
		(layer "B.Cu")
	)
	(gr_line
		(start 374.760236 -119.262906)
		(end 374.846596 -119.176546)
		(stroke
			(width 0.04445)
			(type default)
		)
		(layer "B.Cu")
	)
	(gr_line
		(start 374.765316 -118.269004)
		(end 374.851676 -118.182644)
		(stroke
			(width 0.04445)
			(type default)
		)
		(layer "B.Cu")
	)
	(gr_line
		(start 374.782842 -120.639586)
		(end 374.869202 -120.725946)
		(stroke
			(width 0.04445)
			(type default)
		)
		(layer "B.Cu")
	)
	(gr_line
		(start 374.843548 -113.953036)
		(end 374.987312 -114.097054)
		(stroke
			(width 0.04445)
			(type default)
		)
		(layer "B.Cu")
	)
	(gr_line
		(start 374.869202 -120.725946)
		(end 375.148602 -120.725946)
		(stroke
			(width 0.04445)
			(type default)
		)
		(layer "B.Cu")
	)
	(gr_line
		(start 374.973342 -120.446546)
		(end 375.044462 -120.446546)
		(stroke
			(width 0.04445)
			(type default)
		)
		(layer "B.Cu")
	)
	(gr_line
		(start 374.987312 -114.097054)
		(end 374.987312 -114.237262)
		(stroke
			(width 0.04445)
			(type default)
		)
		(layer "B.Cu")
	)
	(gr_line
		(start 375.013982 -113.145316)
		(end 375.202704 -113.334038)
		(stroke
			(width 0.04445)
			(type default)
		)
		(layer "B.Cu")
	)
	(gr_line
		(start 375.013982 -113.019332)
		(end 375.013982 -113.145316)
		(stroke
			(width 0.04445)
			(type default)
		)
		(layer "B.Cu")
	)
	(gr_line
		(start 375.131076 -119.176546)
		(end 375.217436 -119.262906)
		(stroke
			(width 0.04445)
			(type default)
		)
		(layer "B.Cu")
	)
	(gr_line
		(start 375.1326 -114.6556)
		(end 375.147332 -114.670332)
		(stroke
			(width 0.04445)
			(type default)
		)
		(layer "B.Cu")
	)
	(gr_line
		(start 375.134378 -114.384328)
		(end 375.27484 -114.384328)
		(stroke
			(width 0.04445)
			(type default)
		)
		(layer "B.Cu")
	)
	(gr_line
		(start 375.136156 -118.182644)
		(end 375.222516 -118.269004)
		(stroke
			(width 0.04445)
			(type default)
		)
		(layer "B.Cu")
	)
	(gr_line
		(start 375.148602 -120.725946)
		(end 375.234962 -120.639586)
		(stroke
			(width 0.04445)
			(type default)
		)
		(layer "B.Cu")
	)
	(gr_line
		(start 375.202704 -113.334038)
		(end 375.328688 -113.334038)
		(stroke
			(width 0.04445)
			(type default)
		)
		(layer "B.Cu")
	)
	(gr_line
		(start 375.217436 -119.262906)
		(end 375.496836 -119.262906)
		(stroke
			(width 0.04445)
			(type default)
		)
		(layer "B.Cu")
	)
	(gr_line
		(start 375.222516 -118.269004)
		(end 375.501916 -118.269004)
		(stroke
			(width 0.04445)
			(type default)
		)
		(layer "B.Cu")
	)
	(gr_line
		(start 375.247662 -124.206)
		(end 375.26976 -124.206)
		(stroke
			(width 0.04445)
			(type default)
		)
		(layer "B.Cu")
	)
	(gr_line
		(start 375.247662 -123.9647)
		(end 375.270014 -123.9647)
		(stroke
			(width 0.04445)
			(type default)
		)
		(layer "B.Cu")
	)
	(gr_line
		(start 375.26976 -124.206)
		(end 375.29262 -124.18314)
		(stroke
			(width 0.04445)
			(type default)
		)
		(layer "B.Cu")
	)
	(gr_line
		(start 375.270014 -123.9647)
		(end 375.270014 -123.98756)
		(stroke
			(width 0.04445)
			(type default)
		)
		(layer "B.Cu")
	)
	(gr_line
		(start 375.27484 -114.384328)
		(end 375.418604 -114.528346)
		(stroke
			(width 0.04445)
			(type default)
		)
		(layer "B.Cu")
	)
	(gr_line
		(start 375.285254 -113.017554)
		(end 375.330466 -113.062766)
		(stroke
			(width 0.04445)
			(type default)
		)
		(layer "B.Cu")
	)
	(gr_line
		(start 375.2977 -111.7092)
		(end 375.3231 -111.7346)
		(stroke
			(width 0.04445)
			(type default)
		)
		(layer "B.Cu")
	)
	(gr_line
		(start 375.2977 -111.687102)
		(end 375.2977 -111.7092)
		(stroke
			(width 0.04445)
			(type default)
		)
		(layer "B.Cu")
	)
	(gr_line
		(start 375.321576 -118.983506)
		(end 375.392696 -118.983506)
		(stroke
			(width 0.04445)
			(type default)
		)
		(layer "B.Cu")
	)
	(gr_line
		(start 375.326656 -117.989604)
		(end 375.397776 -117.989604)
		(stroke
			(width 0.04445)
			(type default)
		)
		(layer "B.Cu")
	)
	(gr_line
		(start 375.418604 -114.528346)
		(end 375.418604 -114.668554)
		(stroke
			(width 0.04445)
			(type default)
		)
		(layer "B.Cu")
	)
	(gr_line
		(start 375.496836 -119.262906)
		(end 375.583196 -119.176546)
		(stroke
			(width 0.04445)
			(type default)
		)
		(layer "B.Cu")
	)
	(gr_line
		(start 375.501916 -118.269004)
		(end 375.588276 -118.182644)
		(stroke
			(width 0.04445)
			(type default)
		)
		(layer "B.Cu")
	)
	(gr_line
		(start 375.5136 -111.7346)
		(end 375.539 -111.7092)
		(stroke
			(width 0.04445)
			(type default)
		)
		(layer "B.Cu")
	)
	(gr_line
		(start 375.520966 -113.6523)
		(end 375.709688 -113.841022)
		(stroke
			(width 0.04445)
			(type default)
		)
		(layer "B.Cu")
	)
	(gr_line
		(start 375.520966 -113.526316)
		(end 375.520966 -113.6523)
		(stroke
			(width 0.04445)
			(type default)
		)
		(layer "B.Cu")
	)
	(gr_line
		(start 375.539 -111.687102)
		(end 375.539 -111.7092)
		(stroke
			(width 0.04445)
			(type default)
		)
		(layer "B.Cu")
	)
	(gr_line
		(start 375.5644 -124.18314)
		(end 375.65076 -124.2695)
		(stroke
			(width 0.04445)
			(type default)
		)
		(layer "B.Cu")
	)
	(gr_line
		(start 375.65076 -124.2695)
		(end 375.91746 -124.2695)
		(stroke
			(width 0.04445)
			(type default)
		)
		(layer "B.Cu")
	)
	(gr_line
		(start 375.679716 -123.02109)
		(end 375.701814 -123.02109)
		(stroke
			(width 0.04445)
			(type default)
		)
		(layer "B.Cu")
	)
	(gr_line
		(start 375.679716 -122.77979)
		(end 375.701814 -122.77979)
		(stroke
			(width 0.04445)
			(type default)
		)
		(layer "B.Cu")
	)
	(gr_line
		(start 375.701814 -123.02109)
		(end 375.727214 -122.99569)
		(stroke
			(width 0.04445)
			(type default)
		)
		(layer "B.Cu")
	)
	(gr_line
		(start 375.701814 -122.77979)
		(end 375.727214 -122.80519)
		(stroke
			(width 0.04445)
			(type default)
		)
		(layer "B.Cu")
	)
	(gr_line
		(start 375.709688 -113.841022)
		(end 375.835672 -113.841022)
		(stroke
			(width 0.04445)
			(type default)
		)
		(layer "B.Cu")
	)
	(gr_line
		(start 375.750582 -112.444276)
		(end 375.793254 -112.486948)
		(stroke
			(width 0.04445)
			(type default)
		)
		(layer "B.Cu")
	)
	(gr_line
		(start 375.75236 -112.173004)
		(end 375.875804 -112.173004)
		(stroke
			(width 0.04445)
			(type default)
		)
		(layer "B.Cu")
	)
	(gr_line
		(start 375.7549 -123.9901)
		(end 375.81332 -123.9901)
		(stroke
			(width 0.04445)
			(type default)
		)
		(layer "B.Cu")
	)
	(gr_line
		(start 375.792238 -113.524538)
		(end 375.83745 -113.56975)
		(stroke
			(width 0.04445)
			(type default)
		)
		(layer "B.Cu")
	)
	(gr_line
		(start 375.82094 -114.81308)
		(end 375.92 -114.71402)
		(stroke
			(width 0.04445)
			(type default)
		)
		(layer "B.Cu")
	)
	(gr_line
		(start 375.82856 -116.01196)
		(end 375.834148 -116.0145)
		(stroke
			(width 0.04445)
			(type default)
		)
		(layer "B.Cu")
	)
	(gr_line
		(start 375.872756 -118.182644)
		(end 375.959116 -118.269004)
		(stroke
			(width 0.04445)
			(type default)
		)
		(layer "B.Cu")
	)
	(gr_line
		(start 375.875804 -112.173004)
		(end 376.064526 -112.361726)
		(stroke
			(width 0.04445)
			(type default)
		)
		(layer "B.Cu")
	)
	(gr_line
		(start 375.91746 -124.2695)
		(end 376.00382 -124.18314)
		(stroke
			(width 0.04445)
			(type default)
		)
		(layer "B.Cu")
	)
	(gr_line
		(start 375.92 -114.71402)
		(end 376.1232 -114.71402)
		(stroke
			(width 0.04445)
			(type default)
		)
		(layer "B.Cu")
	)
	(gr_line
		(start 375.959116 -118.269004)
		(end 376.238516 -118.269004)
		(stroke
			(width 0.04445)
			(type default)
		)
		(layer "B.Cu")
	)
	(gr_line
		(start 376.01144 -115.00612)
		(end 376.03176 -115.00612)
		(stroke
			(width 0.04445)
			(type default)
		)
		(layer "B.Cu")
	)
	(gr_line
		(start 376.06097 -116.01704)
		(end 376.148854 -116.104924)
		(stroke
			(width 0.04445)
			(type default)
		)
		(layer "B.Cu")
	)
	(gr_line
		(start 376.063256 -117.989604)
		(end 376.134376 -117.989604)
		(stroke
			(width 0.04445)
			(type default)
		)
		(layer "B.Cu")
	)
	(gr_line
		(start 376.064526 -112.361726)
		(end 376.064526 -112.48517)
		(stroke
			(width 0.04445)
			(type default)
		)
		(layer "B.Cu")
	)
	(gr_line
		(start 376.067066 -113.799366)
		(end 376.074686 -113.806986)
		(stroke
			(width 0.04445)
			(type default)
		)
		(layer "B.Cu")
	)
	(gr_line
		(start 376.1232 -114.71402)
		(end 376.22226 -114.81308)
		(stroke
			(width 0.04445)
			(type default)
		)
		(layer "B.Cu")
	)
	(gr_line
		(start 376.13844 -113.997486)
		(end 376.14606 -114.005106)
		(stroke
			(width 0.04445)
			(type default)
		)
		(layer "B.Cu")
	)
	(gr_line
		(start 376.147838 -114.006884)
		(end 376.227848 -114.086894)
		(stroke
			(width 0.04445)
			(type default)
		)
		(layer "B.Cu")
	)
	(gr_line
		(start 376.148854 -116.104924)
		(end 376.415554 -116.104924)
		(stroke
			(width 0.04445)
			(type default)
		)
		(layer "B.Cu")
	)
	(gr_line
		(start 376.227848 -114.086894)
		(end 376.494548 -114.086894)
		(stroke
			(width 0.04445)
			(type default)
		)
		(layer "B.Cu")
	)
	(gr_line
		(start 376.238516 -118.269004)
		(end 376.324876 -118.182644)
		(stroke
			(width 0.04445)
			(type default)
		)
		(layer "B.Cu")
	)
	(gr_line
		(start 376.25147 -115.824)
		(end 376.312938 -115.824)
		(stroke
			(width 0.04445)
			(type default)
		)
		(layer "B.Cu")
	)
	(gr_line
		(start 376.2756 -124.18314)
		(end 376.36196 -124.2695)
		(stroke
			(width 0.04445)
			(type default)
		)
		(layer "B.Cu")
	)
	(gr_line
		(start 376.33148 -113.806986)
		(end 376.390916 -113.806986)
		(stroke
			(width 0.04445)
			(type default)
		)
		(layer "B.Cu")
	)
	(gr_line
		(start 376.36196 -124.2695)
		(end 376.62866 -124.2695)
		(stroke
			(width 0.04445)
			(type default)
		)
		(layer "B.Cu")
	)
	(gr_line
		(start 376.415554 -116.104924)
		(end 376.503438 -116.01704)
		(stroke
			(width 0.04445)
			(type default)
		)
		(layer "B.Cu")
	)
	(gr_line
		(start 376.4661 -123.9901)
		(end 376.52452 -123.9901)
		(stroke
			(width 0.04445)
			(type default)
		)
		(layer "B.Cu")
	)
	(gr_line
		(start 376.494548 -114.086894)
		(end 376.581416 -114.000026)
		(stroke
			(width 0.04445)
			(type default)
		)
		(layer "B.Cu")
	)
	(gr_line
		(start 376.554492 -119.950738)
		(end 376.629676 -119.950738)
		(stroke
			(width 0.04445)
			(type default)
		)
		(layer "B.Cu")
	)
	(gr_line
		(start 376.62866 -124.2695)
		(end 376.705622 -124.192538)
		(stroke
			(width 0.04445)
			(type default)
		)
		(layer "B.Cu")
	)
	(gr_line
		(start 376.675904 -112.9665)
		(end 376.752358 -112.9665)
		(stroke
			(width 0.04445)
			(type default)
		)
		(layer "B.Cu")
	)
	(gr_line
		(start 376.7074 -124.19076)
		(end 376.71756 -124.1806)
		(stroke
			(width 0.04445)
			(type default)
		)
		(layer "B.Cu")
	)
	(gr_line
		(start 376.744992 -119.796306)
		(end 376.820176 -119.796306)
		(stroke
			(width 0.04445)
			(type default)
		)
		(layer "B.Cu")
	)
	(gr_line
		(start 376.77598 -123.9901)
		(end 376.78614 -123.97994)
		(stroke
			(width 0.04445)
			(type default)
		)
		(layer "B.Cu")
	)
	(gr_line
		(start 376.866404 -112.80775)
		(end 376.866404 -112.810798)
		(stroke
			(width 0.04445)
			(type default)
		)
		(layer "B.Cu")
	)
	(gr_line
		(start 376.958098 -113.17224)
		(end 376.958352 -113.17224)
		(stroke
			(width 0.04445)
			(type default)
		)
		(layer "B.Cu")
	)
	(gr_line
		(start 377.09729 -119.989346)
		(end 377.18365 -120.075706)
		(stroke
			(width 0.04445)
			(type default)
		)
		(layer "B.Cu")
	)
	(gr_line
		(start 377.098814 -118.405402)
		(end 377.185174 -118.491762)
		(stroke
			(width 0.04445)
			(type default)
		)
		(layer "B.Cu")
	)
	(gr_line
		(start 377.107958 -123.658122)
		(end 377.14936 -123.61672)
		(stroke
			(width 0.04445)
			(type default)
		)
		(layer "B.Cu")
	)
	(gr_line
		(start 377.109736 -123.929394)
		(end 377.23191 -123.929394)
		(stroke
			(width 0.04445)
			(type default)
		)
		(layer "B.Cu")
	)
	(gr_line
		(start 377.123706 -113.0681)
		(end 377.148852 -113.0681)
		(stroke
			(width 0.04445)
			(type default)
		)
		(layer "B.Cu")
	)
	(gr_line
		(start 377.18365 -120.075706)
		(end 377.46305 -120.075706)
		(stroke
			(width 0.04445)
			(type default)
		)
		(layer "B.Cu")
	)
	(gr_line
		(start 377.185174 -118.491762)
		(end 377.451874 -118.491762)
		(stroke
			(width 0.04445)
			(type default)
		)
		(layer "B.Cu")
	)
	(gr_line
		(start 377.23191 -123.929394)
		(end 377.420632 -123.740672)
		(stroke
			(width 0.04445)
			(type default)
		)
		(layer "B.Cu")
	)
	(gr_line
		(start 377.28779 -119.796306)
		(end 377.35891 -119.796306)
		(stroke
			(width 0.04445)
			(type default)
		)
		(layer "B.Cu")
	)
	(gr_line
		(start 377.289314 -118.212362)
		(end 377.347734 -118.212362)
		(stroke
			(width 0.04445)
			(type default)
		)
		(layer "B.Cu")
	)
	(gr_line
		(start 377.420632 -123.618498)
		(end 377.420632 -123.740672)
		(stroke
			(width 0.04445)
			(type default)
		)
		(layer "B.Cu")
	)
	(gr_line
		(start 377.451874 -118.491762)
		(end 377.538234 -118.405402)
		(stroke
			(width 0.04445)
			(type default)
		)
		(layer "B.Cu")
	)
	(gr_line
		(start 377.46305 -120.075706)
		(end 377.54941 -119.989346)
		(stroke
			(width 0.04445)
			(type default)
		)
		(layer "B.Cu")
	)
	(gr_line
		(start 377.465336 -122.995182)
		(end 377.481592 -122.985784)
		(stroke
			(width 0.04445)
			(type default)
		)
		(layer "B.Cu")
	)
	(gr_line
		(start 377.572778 -113.06556)
		(end 377.615958 -113.02238)
		(stroke
			(width 0.04445)
			(type default)
		)
		(layer "B.Cu")
	)
	(gr_line
		(start 377.615958 -113.022126)
		(end 377.615958 -113.02238)
		(stroke
			(width 0.04445)
			(type default)
		)
		(layer "B.Cu")
	)
	(gr_line
		(start 377.615958 -113.022126)
		(end 377.661678 -112.976406)
		(stroke
			(width 0.04445)
			(type default)
		)
		(layer "B.Cu")
	)
	(gr_line
		(start 377.661678 -112.976406)
		(end 377.928378 -112.976406)
		(stroke
			(width 0.04445)
			(type default)
		)
		(layer "B.Cu")
	)
	(gr_line
		(start 377.763278 -113.2586)
		(end 377.826778 -113.2586)
		(stroke
			(width 0.04445)
			(type default)
		)
		(layer "B.Cu")
	)
	(gr_line
		(start 377.928378 -112.976406)
		(end 377.974098 -113.022126)
		(stroke
			(width 0.04445)
			(type default)
		)
		(layer "B.Cu")
	)
	(gr_line
		(start 377.974098 -113.02238)
		(end 378.017278 -113.06556)
		(stroke
			(width 0.04445)
			(type default)
		)
		(layer "B.Cu")
	)
	(gr_line
		(start 377.974098 -113.022126)
		(end 377.974098 -113.02238)
		(stroke
			(width 0.04445)
			(type default)
		)
		(layer "B.Cu")
	)
	(gr_line
		(start 378.057918 -113.85042)
		(end 378.075444 -113.840514)
		(stroke
			(width 0.04445)
			(type default)
		)
		(layer "B.Cu")
	)
	(gr_line
		(start 378.080524 -114.91468)
		(end 378.080524 -114.914934)
		(stroke
			(width 0.04445)
			(type default)
		)
		(layer "B.Cu")
	)
	(gr_line
		(start 378.126498 -115.748054)
		(end 378.126752 -115.748054)
		(stroke
			(width 0.04445)
			(type default)
		)
		(layer "B.Cu")
	)
	(gr_line
		(start 378.181362 -126.1745)
		(end 378.20346 -126.1745)
		(stroke
			(width 0.04445)
			(type default)
		)
		(layer "B.Cu")
	)
	(gr_line
		(start 378.181362 -125.9332)
		(end 378.20346 -125.9332)
		(stroke
			(width 0.04445)
			(type default)
		)
		(layer "B.Cu")
	)
	(gr_line
		(start 378.20346 -126.1745)
		(end 378.22886 -126.1491)
		(stroke
			(width 0.04445)
			(type default)
		)
		(layer "B.Cu")
	)
	(gr_line
		(start 378.20346 -125.9332)
		(end 378.22886 -125.9586)
		(stroke
			(width 0.04445)
			(type default)
		)
		(layer "B.Cu")
	)
	(gr_line
		(start 378.32665 -116.094764)
		(end 378.49556 -115.801648)
		(stroke
			(width 0.04445)
			(type default)
		)
		(layer "B.Cu")
	)
	(gr_line
		(start 378.32665 -114.377724)
		(end 378.664724 -114.377724)
		(stroke
			(width 0.04445)
			(type default)
		)
		(layer "B.Cu")
	)
	(gr_line
		(start 378.472446 -113.2586)
		(end 378.489718 -113.248694)
		(stroke
			(width 0.04445)
			(type default)
		)
		(layer "B.Cu")
	)
	(gr_line
		(start 378.474732 -115.724686)
		(end 378.481082 -115.7478)
		(stroke
			(width 0.04445)
			(type default)
		)
		(layer "B.Cu")
	)
	(gr_line
		(start 378.481082 -115.7478)
		(end 378.49556 -115.801648)
		(stroke
			(width 0.04445)
			(type default)
		)
		(layer "B.Cu")
	)
	(gr_line
		(start 378.49556 -125.95606)
		(end 378.58192 -125.8697)
		(stroke
			(width 0.04445)
			(type default)
		)
		(layer "B.Cu")
	)
	(gr_line
		(start 378.526548 -119.18188)
		(end 378.526548 -119.182134)
		(stroke
			(width 0.04445)
			(type default)
		)
		(layer "B.Cu")
	)
	(gr_line
		(start 378.531882 -125.31598)
		(end 378.55398 -125.31598)
		(stroke
			(width 0.04445)
			(type default)
		)
		(layer "B.Cu")
	)
	(gr_line
		(start 378.531882 -125.07468)
		(end 378.55398 -125.07468)
		(stroke
			(width 0.04445)
			(type default)
		)
		(layer "B.Cu")
	)
	(gr_line
		(start 378.55398 -125.31598)
		(end 378.57938 -125.29058)
		(stroke
			(width 0.04445)
			(type default)
		)
		(layer "B.Cu")
	)
	(gr_line
		(start 378.55398 -125.07468)
		(end 378.57938 -125.10008)
		(stroke
			(width 0.04445)
			(type default)
		)
		(layer "B.Cu")
	)
	(gr_line
		(start 378.56541 -115.552728)
		(end 378.65304 -115.52936)
		(stroke
			(width 0.04445)
			(type default)
		)
		(layer "B.Cu")
	)
	(gr_line
		(start 378.58192 -125.8697)
		(end 378.84862 -125.8697)
		(stroke
			(width 0.04445)
			(type default)
		)
		(layer "B.Cu")
	)
	(gr_line
		(start 378.65304 -115.52936)
		(end 378.82195 -115.236244)
		(stroke
			(width 0.04445)
			(type default)
		)
		(layer "B.Cu")
	)
	(gr_line
		(start 378.664724 -114.377724)
		(end 378.685552 -114.398552)
		(stroke
			(width 0.04445)
			(type default)
		)
		(layer "B.Cu")
	)
	(gr_line
		(start 378.68606 -126.1491)
		(end 378.74448 -126.1491)
		(stroke
			(width 0.04445)
			(type default)
		)
		(layer "B.Cu")
	)
	(gr_line
		(start 378.68733 -114.40033)
		(end 378.722636 -114.435636)
		(stroke
			(width 0.04445)
			(type default)
		)
		(layer "B.Cu")
	)
	(gr_line
		(start 378.82195 -123.821444)
		(end 379.160024 -123.821444)
		(stroke
			(width 0.04445)
			(type default)
		)
		(layer "B.Cu")
	)
	(gr_line
		(start 378.84862 -125.8697)
		(end 378.93498 -125.95606)
		(stroke
			(width 0.04445)
			(type default)
		)
		(layer "B.Cu")
	)
	(gr_line
		(start 378.914152 -114.442748)
		(end 378.95657 -114.40033)
		(stroke
			(width 0.04445)
			(type default)
		)
		(layer "B.Cu")
	)
	(gr_line
		(start 378.935742 -127.33528)
		(end 378.95784 -127.33528)
		(stroke
			(width 0.04445)
			(type default)
		)
		(layer "B.Cu")
	)
	(gr_line
		(start 378.935742 -127.09398)
		(end 378.95784 -127.09398)
		(stroke
			(width 0.04445)
			(type default)
		)
		(layer "B.Cu")
	)
	(gr_line
		(start 378.95784 -127.33528)
		(end 378.98324 -127.30988)
		(stroke
			(width 0.04445)
			(type default)
		)
		(layer "B.Cu")
	)
	(gr_line
		(start 378.95784 -127.09398)
		(end 378.98324 -127.11938)
		(stroke
			(width 0.04445)
			(type default)
		)
		(layer "B.Cu")
	)
	(gr_line
		(start 378.958348 -114.398552)
		(end 378.979176 -114.377724)
		(stroke
			(width 0.04445)
			(type default)
		)
		(layer "B.Cu")
	)
	(gr_line
		(start 378.979176 -114.377724)
		(end 379.31725 -114.377724)
		(stroke
			(width 0.04445)
			(type default)
		)
		(layer "B.Cu")
	)
	(gr_line
		(start 379.160024 -123.821444)
		(end 379.180852 -123.800616)
		(stroke
			(width 0.04445)
			(type default)
		)
		(layer "B.Cu")
	)
	(gr_line
		(start 379.18263 -123.798838)
		(end 379.217936 -123.763532)
		(stroke
			(width 0.04445)
			(type default)
		)
		(layer "B.Cu")
	)
	(gr_line
		(start 379.20676 -125.95606)
		(end 379.29312 -125.8697)
		(stroke
			(width 0.04445)
			(type default)
		)
		(layer "B.Cu")
	)
	(gr_line
		(start 379.29312 -125.8697)
		(end 379.57252 -125.8697)
		(stroke
			(width 0.04445)
			(type default)
		)
		(layer "B.Cu")
	)
	(gr_line
		(start 379.31725 -122.962924)
		(end 379.4125 -122.93727)
		(stroke
			(width 0.04445)
			(type default)
		)
		(layer "B.Cu")
	)
	(gr_line
		(start 379.31725 -116.094764)
		(end 379.485906 -116.387626)
		(stroke
			(width 0.04445)
			(type default)
		)
		(layer "B.Cu")
	)
	(gr_line
		(start 379.39726 -126.1491)
		(end 379.46838 -126.1491)
		(stroke
			(width 0.04445)
			(type default)
		)
		(layer "B.Cu")
	)
	(gr_line
		(start 379.409452 -123.75642)
		(end 379.45187 -123.798838)
		(stroke
			(width 0.04445)
			(type default)
		)
		(layer "B.Cu")
	)
	(gr_line
		(start 379.4125 -122.93727)
		(end 379.511814 -122.764804)
		(stroke
			(width 0.04445)
			(type default)
		)
		(layer "B.Cu")
	)
	(gr_line
		(start 379.453648 -123.800616)
		(end 379.474476 -123.821444)
		(stroke
			(width 0.04445)
			(type default)
		)
		(layer "B.Cu")
	)
	(gr_line
		(start 379.465332 -122.592592)
		(end 379.511814 -122.764804)
		(stroke
			(width 0.04445)
			(type default)
		)
		(layer "B.Cu")
	)
	(gr_line
		(start 379.474476 -123.821444)
		(end 379.81255 -123.821444)
		(stroke
			(width 0.04445)
			(type default)
		)
		(layer "B.Cu")
	)
	(gr_line
		(start 379.485906 -116.387626)
		(end 379.58776 -116.414804)
		(stroke
			(width 0.04445)
			(type default)
		)
		(layer "B.Cu")
	)
	(gr_line
		(start 379.49124 -127.11684)
		(end 379.5776 -127.03048)
		(stroke
			(width 0.04445)
			(type default)
		)
		(layer "B.Cu")
	)
	(gr_line
		(start 379.517148 -113.007394)
		(end 379.517402 -113.00714)
		(stroke
			(width 0.04445)
			(type default)
		)
		(layer "B.Cu")
	)
	(gr_line
		(start 379.517402 -113.00714)
		(end 379.517402 -113.007394)
		(stroke
			(width 0.04445)
			(type default)
		)
		(layer "B.Cu")
	)
	(gr_line
		(start 379.55601 -122.420888)
		(end 379.64364 -122.39752)
		(stroke
			(width 0.04445)
			(type default)
		)
		(layer "B.Cu")
	)
	(gr_line
		(start 379.57252 -125.8697)
		(end 379.65888 -125.95606)
		(stroke
			(width 0.04445)
			(type default)
		)
		(layer "B.Cu")
	)
	(gr_line
		(start 379.5776 -127.03048)
		(end 379.857 -127.03048)
		(stroke
			(width 0.04445)
			(type default)
		)
		(layer "B.Cu")
	)
	(gr_line
		(start 379.616716 -115.585494)
		(end 379.624336 -115.589812)
		(stroke
			(width 0.04445)
			(type default)
		)
		(layer "B.Cu")
	)
	(gr_line
		(start 379.64364 -122.39752)
		(end 379.81255 -122.104404)
		(stroke
			(width 0.04445)
			(type default)
		)
		(layer "B.Cu")
	)
	(gr_line
		(start 379.64364 -116.660168)
		(end 379.685042 -116.597938)
		(stroke
			(width 0.04445)
			(type default)
		)
		(layer "B.Cu")
	)
	(gr_line
		(start 379.64364 -116.660168)
		(end 379.81255 -116.953284)
		(stroke
			(width 0.04445)
			(type default)
		)
		(layer "B.Cu")
	)
	(gr_line
		(start 379.68174 -127.30988)
		(end 379.75286 -127.30988)
		(stroke
			(width 0.04445)
			(type default)
		)
		(layer "B.Cu")
	)
	(gr_line
		(start 379.685042 -116.597938)
		(end 379.722634 -116.55425)
		(stroke
			(width 0.04445)
			(type default)
		)
		(layer "B.Cu")
	)
	(gr_line
		(start 379.746764 -116.526056)
		(end 379.757178 -116.513864)
		(stroke
			(width 0.04445)
			(type default)
		)
		(layer "B.Cu")
	)
	(gr_line
		(start 379.857 -127.03048)
		(end 379.94336 -127.11684)
		(stroke
			(width 0.04445)
			(type default)
		)
		(layer "B.Cu")
	)
	(gr_line
		(start 379.94336 -125.95606)
		(end 380.02972 -125.8697)
		(stroke
			(width 0.04445)
			(type default)
		)
		(layer "B.Cu")
	)
	(gr_line
		(start 380.02972 -125.8697)
		(end 380.30912 -125.8697)
		(stroke
			(width 0.04445)
			(type default)
		)
		(layer "B.Cu")
	)
	(gr_line
		(start 380.1237 -124.612146)
		(end 380.21006 -124.698506)
		(stroke
			(width 0.04445)
			(type default)
		)
		(layer "B.Cu")
	)
	(gr_line
		(start 380.1237 -124.345446)
		(end 380.1237 -124.612146)
		(stroke
			(width 0.04445)
			(type default)
		)
		(layer "B.Cu")
	)
	(gr_line
		(start 380.1237 -124.345446)
		(end 380.21006 -124.259086)
		(stroke
			(width 0.04445)
			(type default)
		)
		(layer "B.Cu")
	)
	(gr_line
		(start 380.13386 -126.1491)
		(end 380.20498 -126.1491)
		(stroke
			(width 0.04445)
			(type default)
		)
		(layer "B.Cu")
	)
	(gr_line
		(start 380.22784 -127.11684)
		(end 380.3142 -127.03048)
		(stroke
			(width 0.04445)
			(type default)
		)
		(layer "B.Cu")
	)
	(gr_line
		(start 380.30785 -122.962924)
		(end 380.47676 -123.25604)
		(stroke
			(width 0.04445)
			(type default)
		)
		(layer "B.Cu")
	)
	(gr_line
		(start 380.30785 -117.811804)
		(end 380.47676 -117.518688)
		(stroke
			(width 0.04445)
			(type default)
		)
		(layer "B.Cu")
	)
	(gr_line
		(start 380.30912 -125.8697)
		(end 380.39548 -125.95606)
		(stroke
			(width 0.04445)
			(type default)
		)
		(layer "B.Cu")
	)
	(gr_line
		(start 380.3142 -127.03048)
		(end 380.5936 -127.03048)
		(stroke
			(width 0.04445)
			(type default)
		)
		(layer "B.Cu")
	)
	(gr_line
		(start 380.4031 -124.449586)
		(end 380.4031 -124.508006)
		(stroke
			(width 0.04445)
			(type default)
		)
		(layer "B.Cu")
	)
	(gr_line
		(start 380.41834 -127.30988)
		(end 380.48946 -127.30988)
		(stroke
			(width 0.04445)
			(type default)
		)
		(layer "B.Cu")
	)
	(gr_line
		(start 380.453138 -123.34367)
		(end 380.47676 -123.25604)
		(stroke
			(width 0.04445)
			(type default)
		)
		(layer "B.Cu")
	)
	(gr_line
		(start 380.453138 -117.431058)
		(end 380.47676 -117.518688)
		(stroke
			(width 0.04445)
			(type default)
		)
		(layer "B.Cu")
	)
	(gr_line
		(start 380.557278 -123.507754)
		(end 380.63424 -123.528328)
		(stroke
			(width 0.04445)
			(type default)
		)
		(layer "B.Cu")
	)
	(gr_line
		(start 380.557278 -117.266974)
		(end 380.63424 -117.2464)
		(stroke
			(width 0.04445)
			(type default)
		)
		(layer "B.Cu")
	)
	(gr_line
		(start 380.5936 -127.03048)
		(end 380.67996 -127.11684)
		(stroke
			(width 0.04445)
			(type default)
		)
		(layer "B.Cu")
	)
	(gr_line
		(start 380.63424 -123.528328)
		(end 380.80315 -123.821444)
		(stroke
			(width 0.04445)
			(type default)
		)
		(layer "B.Cu")
	)
	(gr_line
		(start 380.63424 -117.2464)
		(end 380.80315 -116.953284)
		(stroke
			(width 0.04445)
			(type default)
		)
		(layer "B.Cu")
	)
	(gr_line
		(start 380.67996 -125.95606)
		(end 380.76632 -125.8697)
		(stroke
			(width 0.04445)
			(type default)
		)
		(layer "B.Cu")
	)
	(gr_line
		(start 380.76632 -125.8697)
		(end 381.04572 -125.8697)
		(stroke
			(width 0.04445)
			(type default)
		)
		(layer "B.Cu")
	)
	(gr_line
		(start 380.87046 -126.1491)
		(end 380.94158 -126.1491)
		(stroke
			(width 0.04445)
			(type default)
		)
		(layer "B.Cu")
	)
	(gr_line
		(start 380.96444 -127.11684)
		(end 381.0508 -127.03048)
		(stroke
			(width 0.04445)
			(type default)
		)
		(layer "B.Cu")
	)
	(gr_line
		(start 381.04572 -125.8697)
		(end 381.13208 -125.95606)
		(stroke
			(width 0.04445)
			(type default)
		)
		(layer "B.Cu")
	)
	(gr_line
		(start 381.0508 -127.03048)
		(end 381.3302 -127.03048)
		(stroke
			(width 0.04445)
			(type default)
		)
		(layer "B.Cu")
	)
	(gr_line
		(start 381.15494 -127.30988)
		(end 381.22606 -127.30988)
		(stroke
			(width 0.04445)
			(type default)
		)
		(layer "B.Cu")
	)
	(gr_line
		(start 381.29845 -122.962924)
		(end 381.636524 -122.962924)
		(stroke
			(width 0.04445)
			(type default)
		)
		(layer "B.Cu")
	)
	(gr_line
		(start 381.3302 -127.03048)
		(end 381.41656 -127.11684)
		(stroke
			(width 0.04445)
			(type default)
		)
		(layer "B.Cu")
	)
	(gr_line
		(start 381.41656 -125.95606)
		(end 381.50292 -125.8697)
		(stroke
			(width 0.04445)
			(type default)
		)
		(layer "B.Cu")
	)
	(gr_line
		(start 381.50292 -125.8697)
		(end 381.78232 -125.8697)
		(stroke
			(width 0.04445)
			(type default)
		)
		(layer "B.Cu")
	)
	(gr_line
		(start 381.60706 -126.1491)
		(end 381.67818 -126.1491)
		(stroke
			(width 0.04445)
			(type default)
		)
		(layer "B.Cu")
	)
	(gr_line
		(start 381.636524 -122.962924)
		(end 381.657352 -122.942096)
		(stroke
			(width 0.04445)
			(type default)
		)
		(layer "B.Cu")
	)
	(gr_line
		(start 381.65913 -122.940318)
		(end 381.694436 -122.905012)
		(stroke
			(width 0.04445)
			(type default)
		)
		(layer "B.Cu")
	)
	(gr_line
		(start 381.70104 -127.11684)
		(end 381.7874 -127.03048)
		(stroke
			(width 0.04445)
			(type default)
		)
		(layer "B.Cu")
	)
	(gr_line
		(start 381.78232 -125.8697)
		(end 381.86868 -125.95606)
		(stroke
			(width 0.04445)
			(type default)
		)
		(layer "B.Cu")
	)
	(gr_line
		(start 381.7874 -127.03048)
		(end 382.0668 -127.03048)
		(stroke
			(width 0.04445)
			(type default)
		)
		(layer "B.Cu")
	)
	(gr_line
		(start 381.79375 -122.104404)
		(end 381.96266 -121.811288)
		(stroke
			(width 0.04445)
			(type default)
		)
		(layer "B.Cu")
	)
	(gr_line
		(start 381.79375 -120.387364)
		(end 381.827786 -120.4214)
		(stroke
			(width 0.04445)
			(type default)
		)
		(layer "B.Cu")
	)
	(gr_line
		(start 381.827786 -120.4214)
		(end 382.097788 -120.4214)
		(stroke
			(width 0.04445)
			(type default)
		)
		(layer "B.Cu")
	)
	(gr_line
		(start 381.885952 -122.8979)
		(end 381.92837 -122.940318)
		(stroke
			(width 0.04445)
			(type default)
		)
		(layer "B.Cu")
	)
	(gr_line
		(start 381.89154 -127.30988)
		(end 381.96266 -127.30988)
		(stroke
			(width 0.04445)
			(type default)
		)
		(layer "B.Cu")
	)
	(gr_line
		(start 381.930148 -122.942096)
		(end 381.950976 -122.962924)
		(stroke
			(width 0.04445)
			(type default)
		)
		(layer "B.Cu")
	)
	(gr_line
		(start 381.950976 -122.962924)
		(end 382.28905 -122.962924)
		(stroke
			(width 0.04445)
			(type default)
		)
		(layer "B.Cu")
	)
	(gr_line
		(start 381.96266 -121.811288)
		(end 382.05029 -121.78792)
		(stroke
			(width 0.04445)
			(type default)
		)
		(layer "B.Cu")
	)
	(gr_line
		(start 382.0668 -127.03048)
		(end 382.15316 -127.11684)
		(stroke
			(width 0.04445)
			(type default)
		)
		(layer "B.Cu")
	)
	(gr_line
		(start 382.097788 -120.4214)
		(end 382.152652 -120.366536)
		(stroke
			(width 0.04445)
			(type default)
		)
		(layer "B.Cu")
	)
	(gr_line
		(start 382.12014 -121.539)
		(end 382.140968 -121.616216)
		(stroke
			(width 0.04445)
			(type default)
		)
		(layer "B.Cu")
	)
	(gr_line
		(start 382.12014 -121.539)
		(end 382.28905 -121.245884)
		(stroke
			(width 0.04445)
			(type default)
		)
		(layer "B.Cu")
	)
	(gr_line
		(start 382.15316 -125.95606)
		(end 382.23952 -125.8697)
		(stroke
			(width 0.04445)
			(type default)
		)
		(layer "B.Cu")
	)
	(gr_line
		(start 382.15443 -120.364758)
		(end 382.189736 -120.329452)
		(stroke
			(width 0.04445)
			(type default)
		)
		(layer "B.Cu")
	)
	(gr_line
		(start 382.23952 -125.8697)
		(end 382.51892 -125.8697)
		(stroke
			(width 0.04445)
			(type default)
		)
		(layer "B.Cu")
	)
	(gr_line
		(start 382.34366 -126.1491)
		(end 382.41478 -126.1491)
		(stroke
			(width 0.04445)
			(type default)
		)
		(layer "B.Cu")
	)
	(gr_line
		(start 382.381252 -120.32234)
		(end 382.42367 -120.364758)
		(stroke
			(width 0.04445)
			(type default)
		)
		(layer "B.Cu")
	)
	(gr_line
		(start 382.425448 -120.366536)
		(end 382.446276 -120.387364)
		(stroke
			(width 0.04445)
			(type default)
		)
		(layer "B.Cu")
	)
	(gr_line
		(start 382.43764 -127.11684)
		(end 382.524 -127.03048)
		(stroke
			(width 0.04445)
			(type default)
		)
		(layer "B.Cu")
	)
	(gr_line
		(start 382.446276 -120.387364)
		(end 382.78435 -120.387364)
		(stroke
			(width 0.04445)
			(type default)
		)
		(layer "B.Cu")
	)
	(gr_line
		(start 382.51892 -125.8697)
		(end 382.60528 -125.95606)
		(stroke
			(width 0.04445)
			(type default)
		)
		(layer "B.Cu")
	)
	(gr_line
		(start 382.524 -127.03048)
		(end 382.8034 -127.03048)
		(stroke
			(width 0.04445)
			(type default)
		)
		(layer "B.Cu")
	)
	(gr_line
		(start 382.62814 -127.30988)
		(end 382.69926 -127.30988)
		(stroke
			(width 0.04445)
			(type default)
		)
		(layer "B.Cu")
	)
	(gr_line
		(start 382.78435 -122.104404)
		(end 382.95326 -122.39752)
		(stroke
			(width 0.04445)
			(type default)
		)
		(layer "B.Cu")
	)
	(gr_line
		(start 382.8034 -127.03048)
		(end 382.88976 -127.11684)
		(stroke
			(width 0.04445)
			(type default)
		)
		(layer "B.Cu")
	)
	(gr_line
		(start 382.95326 -122.39752)
		(end 383.04089 -122.420888)
		(stroke
			(width 0.04445)
			(type default)
		)
		(layer "B.Cu")
	)
	(gr_line
		(start 383.08788 -122.682)
		(end 383.13106 -122.592846)
		(stroke
			(width 0.04445)
			(type default)
		)
		(layer "B.Cu")
	)
	(gr_line
		(start 383.08788 -122.682)
		(end 383.27965 -122.962924)
		(stroke
			(width 0.04445)
			(type default)
		)
		(layer "B.Cu")
	)
	(gr_line
		(start 383.0955 -125.29312)
		(end 383.18186 -125.37948)
		(stroke
			(width 0.04445)
			(type default)
		)
		(layer "B.Cu")
	)
	(gr_line
		(start 383.0955 -125.01372)
		(end 383.0955 -125.29312)
		(stroke
			(width 0.04445)
			(type default)
		)
		(layer "B.Cu")
	)
	(gr_line
		(start 383.0955 -125.01372)
		(end 383.18186 -124.92736)
		(stroke
			(width 0.04445)
			(type default)
		)
		(layer "B.Cu")
	)
	(gr_line
		(start 383.0955 -124.55652)
		(end 383.18186 -124.64288)
		(stroke
			(width 0.04445)
			(type default)
		)
		(layer "B.Cu")
	)
	(gr_line
		(start 383.0955 -124.27712)
		(end 383.0955 -124.55652)
		(stroke
			(width 0.04445)
			(type default)
		)
		(layer "B.Cu")
	)
	(gr_line
		(start 383.0955 -124.27712)
		(end 383.18186 -124.19076)
		(stroke
			(width 0.04445)
			(type default)
		)
		(layer "B.Cu")
	)
	(gr_line
		(start 383.3749 -125.11786)
		(end 383.3749 -125.18898)
		(stroke
			(width 0.04445)
			(type default)
		)
		(layer "B.Cu")
	)
	(gr_line
		(start 383.3749 -124.38126)
		(end 383.3749 -124.45238)
		(stroke
			(width 0.04445)
			(type default)
		)
		(layer "B.Cu")
	)
	(gr_line
		(start 383.77495 -123.821444)
		(end 383.94386 -123.528328)
		(stroke
			(width 0.04445)
			(type default)
		)
		(layer "B.Cu")
	)
	(gr_line
		(start 383.8702 -122.941334)
		(end 383.8702 -122.984514)
		(stroke
			(width 0.04445)
			(type default)
		)
		(layer "B.Cu")
	)
	(gr_line
		(start 383.94386 -123.528328)
		(end 384.020822 -123.507754)
		(stroke
			(width 0.04445)
			(type default)
		)
		(layer "B.Cu")
	)
	(gr_line
		(start 384.0861 -125.438154)
		(end 384.17246 -125.524514)
		(stroke
			(width 0.04445)
			(type default)
		)
		(layer "B.Cu")
	)
	(gr_line
		(start 384.0861 -125.158754)
		(end 384.0861 -125.438154)
		(stroke
			(width 0.04445)
			(type default)
		)
		(layer "B.Cu")
	)
	(gr_line
		(start 384.0861 -125.158754)
		(end 384.17246 -125.072394)
		(stroke
			(width 0.04445)
			(type default)
		)
		(layer "B.Cu")
	)
	(gr_line
		(start 384.0861 -124.701554)
		(end 384.17246 -124.787914)
		(stroke
			(width 0.04445)
			(type default)
		)
		(layer "B.Cu")
	)
	(gr_line
		(start 384.0861 -124.422154)
		(end 384.0861 -124.701554)
		(stroke
			(width 0.04445)
			(type default)
		)
		(layer "B.Cu")
	)
	(gr_line
		(start 384.0861 -124.422154)
		(end 384.17246 -124.335794)
		(stroke
			(width 0.04445)
			(type default)
		)
		(layer "B.Cu")
	)
	(gr_line
		(start 384.10134 -123.25604)
		(end 384.124962 -123.34367)
		(stroke
			(width 0.04445)
			(type default)
		)
		(layer "B.Cu")
	)
	(gr_line
		(start 384.10134 -123.25604)
		(end 384.27025 -122.962924)
		(stroke
			(width 0.04445)
			(type default)
		)
		(layer "B.Cu")
	)
	(gr_line
		(start 384.305302 -24.522684)
		(end 384.668522 -24.885904)
		(stroke
			(width 0.05715)
			(type default)
		)
		(layer "B.Cu")
	)
	(gr_line
		(start 384.3655 -125.262894)
		(end 384.3655 -125.334014)
		(stroke
			(width 0.04445)
			(type default)
		)
		(layer "B.Cu")
	)
	(gr_line
		(start 384.3655 -124.526294)
		(end 384.3655 -124.597414)
		(stroke
			(width 0.04445)
			(type default)
		)
		(layer "B.Cu")
	)
	(gr_line
		(start 384.38709 -23.601934)
		(end 384.65506 -23.869904)
		(stroke
			(width 0.05715)
			(type default)
		)
		(layer "B.Cu")
	)
	(gr_line
		(start 384.53949 -30.516322)
		(end 384.849624 -30.206188)
		(stroke
			(width 0.05715)
			(type default)
		)
		(layer "B.Cu")
	)
	(gr_line
		(start 384.53949 -29.551122)
		(end 384.849624 -29.861256)
		(stroke
			(width 0.05715)
			(type default)
		)
		(layer "B.Cu")
	)
	(gr_line
		(start 384.53949 -27.516328)
		(end 384.849624 -27.206194)
		(stroke
			(width 0.05715)
			(type default)
		)
		(layer "B.Cu")
	)
	(gr_line
		(start 384.53949 -26.551128)
		(end 384.849624 -26.861262)
		(stroke
			(width 0.05715)
			(type default)
		)
		(layer "B.Cu")
	)
	(gr_line
		(start 384.65506 -23.869904)
		(end 385.217924 -23.869904)
		(stroke
			(width 0.05715)
			(type default)
		)
		(layer "B.Cu")
	)
	(gr_line
		(start 384.668522 -24.885904)
		(end 385.217924 -24.885904)
		(stroke
			(width 0.05715)
			(type default)
		)
		(layer "B.Cu")
	)
	(gr_line
		(start 385.115054 -30.206188)
		(end 385.34594 -30.437074)
		(stroke
			(width 0.05715)
			(type default)
		)
		(layer "B.Cu")
	)
	(gr_line
		(start 385.115054 -29.861256)
		(end 385.34594 -29.63037)
		(stroke
			(width 0.05715)
			(type default)
		)
		(layer "B.Cu")
	)
	(gr_line
		(start 385.1275 -27.187398)
		(end 385.463034 -27.522932)
		(stroke
			(width 0.05715)
			(type default)
		)
		(layer "B.Cu")
	)
	(gr_line
		(start 385.1275 -26.842466)
		(end 385.463034 -26.506932)
		(stroke
			(width 0.05715)
			(type default)
		)
		(layer "B.Cu")
	)
	(gr_line
		(start 385.34594 -30.437074)
		(end 385.34594 -30.571694)
		(stroke
			(width 0.05715)
			(type default)
		)
		(layer "B.Cu")
	)
	(gr_line
		(start 385.34594 -29.555694)
		(end 385.34594 -29.63037)
		(stroke
			(width 0.05715)
			(type default)
		)
		(layer "B.Cu")
	)
	(gr_line
		(start 386.106924 -24.885904)
		(end 386.442458 -24.55037)
		(stroke
			(width 0.05715)
			(type default)
		)
		(layer "B.Cu")
	)
	(gr_line
		(start 386.106924 -23.869904)
		(end 386.442458 -24.205438)
		(stroke
			(width 0.05715)
			(type default)
		)
		(layer "B.Cu")
	)
	(gr_line
		(start 386.23494 -30.571694)
		(end 386.570474 -30.23616)
		(stroke
			(width 0.05715)
			(type default)
		)
		(layer "B.Cu")
	)
	(gr_line
		(start 386.23494 -29.555694)
		(end 386.570474 -29.891228)
		(stroke
			(width 0.05715)
			(type default)
		)
		(layer "B.Cu")
	)
	(gr_line
		(start 386.352034 -27.522932)
		(end 386.73659 -27.138376)
		(stroke
			(width 0.05715)
			(type default)
		)
		(layer "B.Cu")
	)
	(gr_line
		(start 386.352034 -26.506932)
		(end 386.720334 -26.875232)
		(stroke
			(width 0.05715)
			(type default)
		)
		(layer "B.Cu")
	)
	(gr_line
		(start 386.720334 -26.875232)
		(end 387.264402 -26.875232)
		(stroke
			(width 0.05715)
			(type default)
		)
		(layer "B.Cu")
	)
	(gr_line
		(start 386.73659 -27.138376)
		(end 387.273546 -27.138376)
		(stroke
			(width 0.05715)
			(type default)
		)
		(layer "B.Cu")
	)
	(gr_line
		(start 387.202172 -24.280114)
		(end 387.792976 -23.68931)
		(stroke
			(width 0.05715)
			(type default)
		)
		(layer "B.Cu")
	)
	(gr_line
		(start 387.263894 -29.875734)
		(end 387.275578 -29.875734)
		(stroke
			(width 0.05715)
			(type default)
		)
		(layer "B.Cu")
	)
	(gr_line
		(start 387.264402 -26.875232)
		(end 387.734302 -26.405332)
		(stroke
			(width 0.05715)
			(type default)
		)
		(layer "B.Cu")
	)
	(gr_line
		(start 387.271768 -30.212792)
		(end 387.734302 -30.675326)
		(stroke
			(width 0.05715)
			(type default)
		)
		(layer "B.Cu")
	)
	(gr_line
		(start 387.273546 -27.138376)
		(end 387.810502 -27.675332)
		(stroke
			(width 0.05715)
			(type default)
		)
		(layer "B.Cu")
	)
	(gr_line
		(start 387.275578 -29.875734)
		(end 387.524752 -29.62656)
		(stroke
			(width 0.05715)
			(type default)
		)
		(layer "B.Cu")
	)
	(gr_line
		(start 387.35762 -24.523954)
		(end 387.792976 -24.95931)
		(stroke
			(width 0.05715)
			(type default)
		)
		(layer "B.Cu")
	)
	(gr_line
		(start 387.524752 -29.614876)
		(end 387.524752 -29.62656)
		(stroke
			(width 0.05715)
			(type default)
		)
		(layer "B.Cu")
	)
	(gr_line
		(start 387.524752 -29.614876)
		(end 387.734302 -29.405326)
		(stroke
			(width 0.05715)
			(type default)
		)
		(layer "B.Cu")
	)
	(gr_line
		(start 387.5278 -129.99974)
		(end 387.63702 -129.89052)
		(stroke
			(width 0.05715)
			(type default)
		)
		(layer "B.Cu")
	)
	(gr_line
		(start 387.981952 -129.89052)
		(end 388.091172 -129.99974)
		(stroke
			(width 0.05715)
			(type default)
		)
		(layer "B.Cu")
	)
	(gr_line
		(start 388.091172 -129.99974)
		(end 388.366 -129.99974)
		(stroke
			(width 0.05715)
			(type default)
		)
		(layer "B.Cu")
	)
	(gr_line
		(start 388.200138 -129.167128)
		(end 388.205472 -129.167128)
		(stroke
			(width 0.05715)
			(type default)
		)
		(layer "B.Cu")
	)
	(gr_line
		(start 388.202678 -129.164334)
		(end 388.205472 -129.167128)
		(stroke
			(width 0.05715)
			(type default)
		)
		(layer "B.Cu")
	)
	(gr_line
		(start 388.2136 -128.23825)
		(end 388.2136 -128.32207)
		(stroke
			(width 0.05715)
			(type default)
		)
		(layer "B.Cu")
	)
	(gr_line
		(start 388.2136 -127.635)
		(end 388.2136 -127.727964)
		(stroke
			(width 0.05715)
			(type default)
		)
		(layer "B.Cu")
	)
	(gr_line
		(start 388.2136 -127.334772)
		(end 388.2136 -127.635)
		(stroke
			(width 0.05715)
			(type default)
		)
		(layer "B.Cu")
	)
	(gr_line
		(start 388.45744 -128.56337)
		(end 388.5692 -128.45161)
		(stroke
			(width 0.05715)
			(type default)
		)
		(layer "B.Cu")
	)
	(gr_line
		(start 388.45744 -127.99695)
		(end 388.5692 -128.10871)
		(stroke
			(width 0.05715)
			(type default)
		)
		(layer "B.Cu")
	)
	(gr_line
		(start 388.45744 -127.969264)
		(end 388.46125 -127.965454)
		(stroke
			(width 0.05715)
			(type default)
		)
		(layer "B.Cu")
	)
	(gr_line
		(start 388.46125 -127.432054)
		(end 388.46125 -127.965454)
		(stroke
			(width 0.05715)
			(type default)
		)
		(layer "B.Cu")
	)
	(gr_line
		(start 388.5692 -128.10871)
		(end 388.5692 -128.45161)
		(stroke
			(width 0.05715)
			(type default)
		)
		(layer "B.Cu")
	)
	(gr_line
		(start 388.902956 -127.373126)
		(end 389.04799 -127.51816)
		(stroke
			(width 0.05715)
			(type default)
		)
		(layer "B.Cu")
	)
	(gr_line
		(start 388.902956 -127.028194)
		(end 389.04799 -126.88316)
		(stroke
			(width 0.05715)
			(type default)
		)
		(layer "B.Cu")
	)
	(gr_line
		(start 390.75995 -129.837942)
		(end 390.75995 -130.074162)
		(stroke
			(width 0.04445)
			(type default)
		)
		(layer "B.Cu")
	)
	(gr_line
		(start 390.75995 -128.948942)
		(end 390.75995 -129.185162)
		(stroke
			(width 0.04445)
			(type default)
		)
		(layer "B.Cu")
	)
	(gr_line
		(start 390.75995 -128.059942)
		(end 390.75995 -128.296162)
		(stroke
			(width 0.04445)
			(type default)
		)
		(layer "B.Cu")
	)
	(gr_line
		(start 390.75995 -127.170942)
		(end 390.75995 -127.407162)
		(stroke
			(width 0.04445)
			(type default)
		)
		(layer "B.Cu")
	)
	(gr_line
		(start 390.75995 -126.281942)
		(end 390.75995 -126.518162)
		(stroke
			(width 0.04445)
			(type default)
		)
		(layer "B.Cu")
	)
	(gr_line
		(start 390.75995 -125.392942)
		(end 390.75995 -125.629162)
		(stroke
			(width 0.04445)
			(type default)
		)
		(layer "B.Cu")
	)
	(gr_arc
		(start 390.95045 -129.644902)
		(mid 390.96449 -129.693442)
		(end 390.9949 -129.733802)
		(stroke
			(width 0.04445)
			(type default)
		)
		(layer "B.Cu")
	)
	(gr_arc
		(start 390.95045 -128.755902)
		(mid 390.96449 -128.804442)
		(end 390.9949 -128.844802)
		(stroke
			(width 0.04445)
			(type default)
		)
		(layer "B.Cu")
	)
	(gr_arc
		(start 390.95045 -127.866902)
		(mid 390.96449 -127.915442)
		(end 390.9949 -127.955802)
		(stroke
			(width 0.04445)
			(type default)
		)
		(layer "B.Cu")
	)
	(gr_arc
		(start 390.95045 -126.977902)
		(mid 390.96449 -127.026442)
		(end 390.9949 -127.066802)
		(stroke
			(width 0.04445)
			(type default)
		)
		(layer "B.Cu")
	)
	(gr_arc
		(start 390.95045 -126.088902)
		(mid 390.96449 -126.137442)
		(end 390.9949 -126.177802)
		(stroke
			(width 0.04445)
			(type default)
		)
		(layer "B.Cu")
	)
	(gr_arc
		(start 390.95045 -125.199902)
		(mid 390.96449 -125.248442)
		(end 390.9949 -125.288802)
		(stroke
			(width 0.04445)
			(type default)
		)
		(layer "B.Cu")
	)
	(gr_arc
		(start 390.9949 -130.178302)
		(mid 390.964507 -130.218671)
		(end 390.95045 -130.267202)
		(stroke
			(width 0.04445)
			(type default)
		)
		(layer "B.Cu")
	)
	(gr_arc
		(start 390.9949 -130.178302)
		(mid 391.025321 -130.137946)
		(end 391.03935 -130.089402)
		(stroke
			(width 0.04445)
			(type default)
		)
		(layer "B.Cu")
	)
	(gr_arc
		(start 390.9949 -129.289302)
		(mid 390.964507 -129.329671)
		(end 390.95045 -129.378202)
		(stroke
			(width 0.04445)
			(type default)
		)
		(layer "B.Cu")
	)
	(gr_arc
		(start 390.9949 -129.289302)
		(mid 391.025321 -129.248946)
		(end 391.03935 -129.200402)
		(stroke
			(width 0.04445)
			(type default)
		)
		(layer "B.Cu")
	)
	(gr_arc
		(start 390.9949 -128.400302)
		(mid 390.964507 -128.440671)
		(end 390.95045 -128.489202)
		(stroke
			(width 0.04445)
			(type default)
		)
		(layer "B.Cu")
	)
	(gr_arc
		(start 390.9949 -128.400302)
		(mid 391.025321 -128.359946)
		(end 391.03935 -128.311402)
		(stroke
			(width 0.04445)
			(type default)
		)
		(layer "B.Cu")
	)
	(gr_arc
		(start 390.9949 -127.511302)
		(mid 390.964507 -127.551671)
		(end 390.95045 -127.600202)
		(stroke
			(width 0.04445)
			(type default)
		)
		(layer "B.Cu")
	)
	(gr_arc
		(start 390.9949 -127.511302)
		(mid 391.025321 -127.470946)
		(end 391.03935 -127.422402)
		(stroke
			(width 0.04445)
			(type default)
		)
		(layer "B.Cu")
	)
	(gr_arc
		(start 390.9949 -126.622302)
		(mid 390.964507 -126.662671)
		(end 390.95045 -126.711202)
		(stroke
			(width 0.04445)
			(type default)
		)
		(layer "B.Cu")
	)
	(gr_arc
		(start 390.9949 -126.622302)
		(mid 391.025321 -126.581946)
		(end 391.03935 -126.533402)
		(stroke
			(width 0.04445)
			(type default)
		)
		(layer "B.Cu")
	)
	(gr_arc
		(start 390.9949 -125.733302)
		(mid 390.964507 -125.773671)
		(end 390.95045 -125.822202)
		(stroke
			(width 0.04445)
			(type default)
		)
		(layer "B.Cu")
	)
	(gr_arc
		(start 390.9949 -125.733302)
		(mid 391.025321 -125.692946)
		(end 391.03935 -125.644402)
		(stroke
			(width 0.04445)
			(type default)
		)
		(layer "B.Cu")
	)
	(gr_arc
		(start 391.03935 -129.822702)
		(mid 391.025285 -129.774176)
		(end 390.9949 -129.733802)
		(stroke
			(width 0.04445)
			(type default)
		)
		(layer "B.Cu")
	)
	(gr_line
		(start 391.03935 -129.822702)
		(end 391.03935 -130.089402)
		(stroke
			(width 0.04445)
			(type default)
		)
		(layer "B.Cu")
	)
	(gr_arc
		(start 391.03935 -128.933702)
		(mid 391.025285 -128.885176)
		(end 390.9949 -128.844802)
		(stroke
			(width 0.04445)
			(type default)
		)
		(layer "B.Cu")
	)
	(gr_line
		(start 391.03935 -128.933702)
		(end 391.03935 -129.200402)
		(stroke
			(width 0.04445)
			(type default)
		)
		(layer "B.Cu")
	)
	(gr_arc
		(start 391.03935 -128.044702)
		(mid 391.025285 -127.996176)
		(end 390.9949 -127.955802)
		(stroke
			(width 0.04445)
			(type default)
		)
		(layer "B.Cu")
	)
	(gr_line
		(start 391.03935 -128.044702)
		(end 391.03935 -128.311402)
		(stroke
			(width 0.04445)
			(type default)
		)
		(layer "B.Cu")
	)
	(gr_arc
		(start 391.03935 -127.155702)
		(mid 391.025285 -127.107176)
		(end 390.9949 -127.066802)
		(stroke
			(width 0.04445)
			(type default)
		)
		(layer "B.Cu")
	)
	(gr_line
		(start 391.03935 -127.155702)
		(end 391.03935 -127.422402)
		(stroke
			(width 0.04445)
			(type default)
		)
		(layer "B.Cu")
	)
	(gr_arc
		(start 391.03935 -126.266702)
		(mid 391.025285 -126.218176)
		(end 390.9949 -126.177802)
		(stroke
			(width 0.04445)
			(type default)
		)
		(layer "B.Cu")
	)
	(gr_line
		(start 391.03935 -126.266702)
		(end 391.03935 -126.533402)
		(stroke
			(width 0.04445)
			(type default)
		)
		(layer "B.Cu")
	)
	(gr_arc
		(start 391.03935 -125.377702)
		(mid 391.025285 -125.329176)
		(end 390.9949 -125.288802)
		(stroke
			(width 0.04445)
			(type default)
		)
		(layer "B.Cu")
	)
	(gr_line
		(start 391.03935 -125.377702)
		(end 391.03935 -125.644402)
		(stroke
			(width 0.04445)
			(type default)
		)
		(layer "B.Cu")
	)
	(gr_arc
		(start 391.201656 -131.192016)
		(mid 391.245985 -131.216511)
		(end 391.296144 -131.223512)
		(stroke
			(width 0.04445)
			(type default)
		)
		(layer "B.Cu")
	)
	(gr_line
		(start 391.20318 -131.463288)
		(end 391.370566 -131.630674)
		(stroke
			(width 0.04445)
			(type default)
		)
		(layer "B.Cu")
	)
	(gr_arc
		(start 391.390378 -131.255008)
		(mid 391.346147 -131.230656)
		(end 391.296144 -131.223512)
		(stroke
			(width 0.04445)
			(type default)
		)
		(layer "B.Cu")
	)
	(gr_line
		(start 391.390378 -131.255008)
		(end 391.578846 -131.443476)
		(stroke
			(width 0.04445)
			(type default)
		)
		(layer "B.Cu")
	)
	(gr_arc
		(start 391.610342 -131.537964)
		(mid 391.603336 -131.4878)
		(end 391.578846 -131.443476)
		(stroke
			(width 0.04445)
			(type default)
		)
		(layer "B.Cu")
	)
	(gr_arc
		(start 391.610342 -131.537964)
		(mid 391.617486 -131.587957)
		(end 391.641838 -131.632198)
		(stroke
			(width 0.04445)
			(type default)
		)
		(layer "B.Cu")
	)
	(gr_arc
		(start 391.830306 -131.820666)
		(mid 391.874635 -131.845154)
		(end 391.924794 -131.852162)
		(stroke
			(width 0.04445)
			(type default)
		)
		(layer "B.Cu")
	)
	(gr_line
		(start 391.83183 -132.091938)
		(end 391.999216 -132.259324)
		(stroke
			(width 0.04445)
			(type default)
		)
		(layer "B.Cu")
	)
	(gr_arc
		(start 392.019028 -131.883658)
		(mid 391.974797 -131.859306)
		(end 391.924794 -131.852162)
		(stroke
			(width 0.04445)
			(type default)
		)
		(layer "B.Cu")
	)
	(gr_line
		(start 392.019028 -131.883658)
		(end 392.207496 -132.072126)
		(stroke
			(width 0.04445)
			(type default)
		)
		(layer "B.Cu")
	)
	(gr_arc
		(start 392.238992 -132.166614)
		(mid 392.231986 -132.11645)
		(end 392.207496 -132.072126)
		(stroke
			(width 0.04445)
			(type default)
		)
		(layer "B.Cu")
	)
	(gr_arc
		(start 392.238992 -132.166614)
		(mid 392.246122 -132.216614)
		(end 392.270488 -132.260848)
		(stroke
			(width 0.04445)
			(type default)
		)
		(layer "B.Cu")
	)
	(gr_arc
		(start 392.458956 -132.449316)
		(mid 392.503285 -132.473811)
		(end 392.553444 -132.480812)
		(stroke
			(width 0.04445)
			(type default)
		)
		(layer "B.Cu")
	)
	(gr_line
		(start 392.46048 -132.720588)
		(end 392.627866 -132.887974)
		(stroke
			(width 0.04445)
			(type default)
		)
		(layer "B.Cu")
	)
	(gr_arc
		(start 392.647678 -132.512308)
		(mid 392.603447 -132.487956)
		(end 392.553444 -132.480812)
		(stroke
			(width 0.04445)
			(type default)
		)
		(layer "B.Cu")
	)
	(gr_line
		(start 392.647678 -132.512308)
		(end 392.836146 -132.700776)
		(stroke
			(width 0.04445)
			(type default)
		)
		(layer "B.Cu")
	)
	(gr_line
		(start 392.674602 -120.61952)
		(end 392.69035 -120.387364)
		(stroke
			(width 0.04445)
			(type default)
		)
		(layer "B.Cu")
	)
	(gr_arc
		(start 392.674602 -120.61952)
		(mid 392.724391 -120.767591)
		(end 392.86434 -120.836944)
		(stroke
			(width 0.04445)
			(type default)
		)
		(layer "B.Cu")
	)
	(gr_line
		(start 392.86434 -120.836944)
		(end 392.864594 -120.836944)
		(stroke
			(width 0.04445)
			(type default)
		)
		(layer "B.Cu")
	)
	(gr_arc
		(start 392.864594 -120.836944)
		(mid 393.012763 -120.787174)
		(end 393.082272 -120.647206)
		(stroke
			(width 0.04445)
			(type default)
		)
		(layer "B.Cu")
	)
	(gr_arc
		(start 392.867642 -132.795264)
		(mid 392.860636 -132.7451)
		(end 392.836146 -132.700776)
		(stroke
			(width 0.04445)
			(type default)
		)
		(layer "B.Cu")
	)
	(gr_arc
		(start 392.867642 -132.795264)
		(mid 392.874786 -132.845257)
		(end 392.899138 -132.889498)
		(stroke
			(width 0.04445)
			(type default)
		)
		(layer "B.Cu")
	)
	(gr_line
		(start 393.082272 -120.646698)
		(end 393.082272 -120.647206)
		(stroke
			(width 0.04445)
			(type default)
		)
		(layer "B.Cu")
	)
	(gr_arc
		(start 393.087606 -133.077966)
		(mid 393.131935 -133.102454)
		(end 393.182094 -133.109462)
		(stroke
			(width 0.04445)
			(type default)
		)
		(layer "B.Cu")
	)
	(gr_line
		(start 393.08913 -133.349238)
		(end 393.256516 -133.516624)
		(stroke
			(width 0.04445)
			(type default)
		)
		(layer "B.Cu")
	)
	(gr_arc
		(start 393.276328 -133.140958)
		(mid 393.232097 -133.116606)
		(end 393.182094 -133.109462)
		(stroke
			(width 0.04445)
			(type default)
		)
		(layer "B.Cu")
	)
	(gr_line
		(start 393.276328 -133.140958)
		(end 393.464796 -133.329426)
		(stroke
			(width 0.04445)
			(type default)
		)
		(layer "B.Cu")
	)
	(gr_arc
		(start 393.496292 -133.423914)
		(mid 393.489286 -133.37375)
		(end 393.464796 -133.329426)
		(stroke
			(width 0.04445)
			(type default)
		)
		(layer "B.Cu")
	)
	(gr_arc
		(start 393.496292 -133.423914)
		(mid 393.503422 -133.473914)
		(end 393.527788 -133.518148)
		(stroke
			(width 0.04445)
			(type default)
		)
		(layer "B.Cu")
	)
	(gr_arc
		(start 393.716256 -133.706616)
		(mid 393.760585 -133.731111)
		(end 393.810744 -133.738112)
		(stroke
			(width 0.04445)
			(type default)
		)
		(layer "B.Cu")
	)
	(gr_line
		(start 393.71778 -133.977888)
		(end 393.885166 -134.145274)
		(stroke
			(width 0.04445)
			(type default)
		)
		(layer "B.Cu")
	)
	(gr_arc
		(start 393.904978 -133.769608)
		(mid 393.860747 -133.745256)
		(end 393.810744 -133.738112)
		(stroke
			(width 0.04445)
			(type default)
		)
		(layer "B.Cu")
	)
	(gr_line
		(start 393.904978 -133.769608)
		(end 394.093446 -133.958076)
		(stroke
			(width 0.04445)
			(type default)
		)
		(layer "B.Cu")
	)
	(gr_arc
		(start 394.124942 -134.052564)
		(mid 394.117936 -134.0024)
		(end 394.093446 -133.958076)
		(stroke
			(width 0.04445)
			(type default)
		)
		(layer "B.Cu")
	)
	(gr_arc
		(start 394.124942 -134.052564)
		(mid 394.132086 -134.102557)
		(end 394.156438 -134.146798)
		(stroke
			(width 0.04445)
			(type default)
		)
		(layer "B.Cu")
	)
	(gr_arc
		(start 394.344906 -134.335266)
		(mid 394.389235 -134.359754)
		(end 394.439394 -134.366762)
		(stroke
			(width 0.04445)
			(type default)
		)
		(layer "B.Cu")
	)
	(gr_line
		(start 394.34643 -134.606538)
		(end 394.513816 -134.773924)
		(stroke
			(width 0.04445)
			(type default)
		)
		(layer "B.Cu")
	)
	(gr_arc
		(start 394.533628 -134.398258)
		(mid 394.489397 -134.373906)
		(end 394.439394 -134.366762)
		(stroke
			(width 0.04445)
			(type default)
		)
		(layer "B.Cu")
	)
	(gr_line
		(start 394.533628 -134.398258)
		(end 394.722096 -134.586726)
		(stroke
			(width 0.04445)
			(type default)
		)
		(layer "B.Cu")
	)
	(gr_arc
		(start 394.753592 -134.681214)
		(mid 394.746586 -134.63105)
		(end 394.722096 -134.586726)
		(stroke
			(width 0.04445)
			(type default)
		)
		(layer "B.Cu")
	)
	(gr_arc
		(start 394.753592 -134.681214)
		(mid 394.760722 -134.731214)
		(end 394.785088 -134.775448)
		(stroke
			(width 0.04445)
			(type default)
		)
		(layer "B.Cu")
	)
	(gr_arc
		(start 394.973556 -134.963916)
		(mid 395.017885 -134.988411)
		(end 395.068044 -134.995412)
		(stroke
			(width 0.04445)
			(type default)
		)
		(layer "B.Cu")
	)
	(gr_line
		(start 394.97508 -135.235188)
		(end 395.142466 -135.402574)
		(stroke
			(width 0.04445)
			(type default)
		)
		(layer "B.Cu")
	)
	(gr_arc
		(start 395.162278 -135.026908)
		(mid 395.118047 -135.002556)
		(end 395.068044 -134.995412)
		(stroke
			(width 0.04445)
			(type default)
		)
		(layer "B.Cu")
	)
	(gr_line
		(start 395.162278 -135.026908)
		(end 395.350746 -135.215376)
		(stroke
			(width 0.04445)
			(type default)
		)
		(layer "B.Cu")
	)
	(gr_arc
		(start 395.382242 -135.309864)
		(mid 395.375236 -135.2597)
		(end 395.350746 -135.215376)
		(stroke
			(width 0.04445)
			(type default)
		)
		(layer "B.Cu")
	)
	(gr_arc
		(start 395.382242 -135.309864)
		(mid 395.389386 -135.359857)
		(end 395.413738 -135.404098)
		(stroke
			(width 0.04445)
			(type default)
		)
		(layer "B.Cu")
	)
	(gr_line
		(start 395.461998 -123.474734)
		(end 395.462252 -123.474734)
		(stroke
			(width 0.04445)
			(type default)
		)
		(layer "B.Cu")
	)
	(gr_line
		(start 395.558518 -124.332238)
		(end 395.69517 -124.332238)
		(stroke
			(width 0.04445)
			(type default)
		)
		(layer "B.Cu")
	)
	(gr_line
		(start 395.66215 -123.821444)
		(end 395.887702 -123.821444)
		(stroke
			(width 0.04445)
			(type default)
		)
		(layer "B.Cu")
	)
	(gr_line
		(start 395.69517 -124.332238)
		(end 395.8209 -124.457968)
		(stroke
			(width 0.04445)
			(type default)
		)
		(layer "B.Cu")
	)
	(gr_line
		(start 395.8209 -124.457968)
		(end 395.8209 -124.59462)
		(stroke
			(width 0.04445)
			(type default)
		)
		(layer "B.Cu")
	)
	(gr_line
		(start 395.887702 -123.821444)
		(end 395.94409 -123.877832)
		(stroke
			(width 0.04445)
			(type default)
		)
		(layer "B.Cu")
	)
	(gr_line
		(start 395.945868 -123.87961)
		(end 396.003526 -123.937268)
		(stroke
			(width 0.04445)
			(type default)
		)
		(layer "B.Cu")
	)
	(gr_line
		(start 395.949932 -124.723652)
		(end 396.086838 -124.723652)
		(stroke
			(width 0.04445)
			(type default)
		)
		(layer "B.Cu")
	)
	(gr_line
		(start 396.060168 -135.69442)
		(end 396.085568 -135.71982)
		(stroke
			(width 0.04445)
			(type default)
		)
		(layer "B.Cu")
	)
	(gr_line
		(start 396.060168 -135.50392)
		(end 396.085568 -135.47852)
		(stroke
			(width 0.04445)
			(type default)
		)
		(layer "B.Cu")
	)
	(gr_line
		(start 396.085568 -135.71982)
		(end 396.107666 -135.71982)
		(stroke
			(width 0.04445)
			(type default)
		)
		(layer "B.Cu")
	)
	(gr_line
		(start 396.085568 -135.47852)
		(end 396.107666 -135.47852)
		(stroke
			(width 0.04445)
			(type default)
		)
		(layer "B.Cu")
	)
	(gr_line
		(start 396.086838 -124.723652)
		(end 396.212568 -124.849382)
		(stroke
			(width 0.04445)
			(type default)
		)
		(layer "B.Cu")
	)
	(gr_line
		(start 396.119858 -122.373136)
		(end 396.119858 -122.37339)
		(stroke
			(width 0.04445)
			(type default)
		)
		(layer "B.Cu")
	)
	(gr_line
		(start 396.119858 -122.373136)
		(end 396.65275 -122.104404)
		(stroke
			(width 0.04445)
			(type default)
		)
		(layer "B.Cu")
	)
	(gr_line
		(start 396.15745 -122.962924)
		(end 396.329916 -122.916442)
		(stroke
			(width 0.04445)
			(type default)
		)
		(layer "B.Cu")
	)
	(gr_line
		(start 396.194026 -123.900692)
		(end 396.215108 -123.87961)
		(stroke
			(width 0.04445)
			(type default)
		)
		(layer "B.Cu")
	)
	(gr_line
		(start 396.212568 -124.849382)
		(end 396.212568 -124.986288)
		(stroke
			(width 0.04445)
			(type default)
		)
		(layer "B.Cu")
	)
	(gr_line
		(start 396.216886 -123.877832)
		(end 396.273274 -123.821444)
		(stroke
			(width 0.04445)
			(type default)
		)
		(layer "B.Cu")
	)
	(gr_line
		(start 396.273274 -123.821444)
		(end 396.65275 -123.821444)
		(stroke
			(width 0.04445)
			(type default)
		)
		(layer "B.Cu")
	)
	(gr_line
		(start 396.329916 -122.916442)
		(end 396.366746 -122.852434)
		(stroke
			(width 0.04445)
			(type default)
		)
		(layer "B.Cu")
	)
	(gr_line
		(start 396.3416 -125.11532)
		(end 396.478506 -125.11532)
		(stroke
			(width 0.04445)
			(type default)
		)
		(layer "B.Cu")
	)
	(gr_line
		(start 396.366746 -122.731784)
		(end 396.366746 -122.852434)
		(stroke
			(width 0.04445)
			(type default)
		)
		(layer "B.Cu")
	)
	(gr_line
		(start 396.478506 -125.11532)
		(end 396.604236 -125.24105)
		(stroke
			(width 0.04445)
			(type default)
		)
		(layer "B.Cu")
	)
	(gr_line
		(start 396.604236 -125.24105)
		(end 396.604236 -125.377956)
		(stroke
			(width 0.04445)
			(type default)
		)
		(layer "B.Cu")
	)
	(gr_line
		(start 396.733268 -125.506988)
		(end 396.870174 -125.506988)
		(stroke
			(width 0.04445)
			(type default)
		)
		(layer "B.Cu")
	)
	(gr_line
		(start 396.870174 -125.506988)
		(end 396.995904 -125.632718)
		(stroke
			(width 0.04445)
			(type default)
		)
		(layer "B.Cu")
	)
	(gr_line
		(start 396.995904 -125.632718)
		(end 396.995904 -125.769624)
		(stroke
			(width 0.04445)
			(type default)
		)
		(layer "B.Cu")
	)
	(gr_line
		(start 397.124936 -125.898656)
		(end 397.261842 -125.898656)
		(stroke
			(width 0.04445)
			(type default)
		)
		(layer "B.Cu")
	)
	(gr_line
		(start 397.261842 -125.898656)
		(end 397.387572 -126.024386)
		(stroke
			(width 0.04445)
			(type default)
		)
		(layer "B.Cu")
	)
	(gr_line
		(start 397.387572 -126.024386)
		(end 397.387572 -126.161292)
		(stroke
			(width 0.04445)
			(type default)
		)
		(layer "B.Cu")
	)
	(gr_line
		(start 397.442944 -124.976128)
		(end 397.542004 -124.877068)
		(stroke
			(width 0.04445)
			(type default)
		)
		(layer "B.Cu")
	)
	(gr_line
		(start 397.542004 -124.877068)
		(end 397.719804 -124.877068)
		(stroke
			(width 0.04445)
			(type default)
		)
		(layer "B.Cu")
	)
	(gr_line
		(start 397.719804 -124.877068)
		(end 397.818864 -124.976128)
		(stroke
			(width 0.04445)
			(type default)
		)
		(layer "B.Cu")
	)
	(gr_line
		(start 397.789908 -126.324614)
		(end 397.886428 -126.228094)
		(stroke
			(width 0.04445)
			(type default)
		)
		(layer "B.Cu")
	)
	(gr_line
		(start 397.886428 -126.228094)
		(end 398.064228 -126.228094)
		(stroke
			(width 0.04445)
			(type default)
		)
		(layer "B.Cu")
	)
	(gr_line
		(start 398.001744 -124.976128)
		(end 398.100804 -124.877068)
		(stroke
			(width 0.04445)
			(type default)
		)
		(layer "B.Cu")
	)
	(gr_line
		(start 398.064228 -126.228094)
		(end 398.160748 -126.324614)
		(stroke
			(width 0.04445)
			(type default)
		)
		(layer "B.Cu")
	)
	(gr_line
		(start 398.100804 -124.877068)
		(end 398.278604 -124.877068)
		(stroke
			(width 0.04445)
			(type default)
		)
		(layer "B.Cu")
	)
	(gr_line
		(start 398.278604 -124.877068)
		(end 398.377664 -124.976128)
		(stroke
			(width 0.04445)
			(type default)
		)
		(layer "B.Cu")
	)
	(gr_line
		(start 399.160238 -125.10897)
		(end 399.220944 -125.048264)
		(stroke
			(width 0.04445)
			(type default)
		)
		(layer "B.Cu")
	)
	(gr_line
		(start 399.20291 -125.29947)
		(end 399.220944 -125.317504)
		(stroke
			(width 0.04445)
			(type default)
		)
		(layer "B.Cu")
	)
	(gr_line
		(start 399.222722 -125.319282)
		(end 399.530824 -125.627384)
		(stroke
			(width 0.04445)
			(type default)
		)
		(layer "B.Cu")
	)
	(gr_line
		(start 399.222722 -125.046486)
		(end 399.530824 -124.738384)
		(stroke
			(width 0.04445)
			(type default)
		)
		(layer "B.Cu")
	)
	(gr_line
		(start 399.5928 -127.137922)
		(end 399.6182 -127.163322)
		(stroke
			(width 0.04445)
			(type default)
		)
		(layer "B.Cu")
	)
	(gr_line
		(start 399.5928 -126.947422)
		(end 399.6182 -126.922022)
		(stroke
			(width 0.04445)
			(type default)
		)
		(layer "B.Cu")
	)
	(gr_line
		(start 399.6182 -127.163322)
		(end 399.640298 -127.163322)
		(stroke
			(width 0.04445)
			(type default)
		)
		(layer "B.Cu")
	)
	(gr_line
		(start 399.6182 -126.922022)
		(end 399.640298 -126.922022)
		(stroke
			(width 0.04445)
			(type default)
		)
		(layer "B.Cu")
	)
	(gr_line
		(start 400.419824 -125.627384)
		(end 400.691858 -125.35535)
		(stroke
			(width 0.05715)
			(type default)
		)
		(layer "B.Cu")
	)
	(gr_line
		(start 400.419824 -124.738384)
		(end 400.691858 -125.010418)
		(stroke
			(width 0.05715)
			(type default)
		)
		(layer "B.Cu")
	)
	(gr_line
		(start 400.795236 -127.19685)
		(end 401.25777 -127.659384)
		(stroke
			(width 0.05715)
			(type default)
		)
		(layer "B.Cu")
	)
	(gr_line
		(start 400.795236 -126.851918)
		(end 401.25777 -126.389384)
		(stroke
			(width 0.05715)
			(type default)
		)
		(layer "B.Cu")
	)
	(gr_line
		(start 401.092416 -125.302772)
		(end 401.204176 -125.414532)
		(stroke
			(width 0.05715)
			(type default)
		)
		(layer "B.Cu")
	)
	(gr_line
		(start 401.204176 -125.414532)
		(end 401.547076 -125.414532)
		(stroke
			(width 0.05715)
			(type default)
		)
		(layer "B.Cu")
	)
	(gr_line
		(start 401.333716 -125.058932)
		(end 401.417536 -125.058932)
		(stroke
			(width 0.05715)
			(type default)
		)
		(layer "B.Cu")
	)
	(gr_line
		(start 401.547076 -125.414532)
		(end 401.658836 -125.302772)
		(stroke
			(width 0.05715)
			(type default)
		)
		(layer "B.Cu")
	)
	(gr_line
		(start 402.14677 -127.659384)
		(end 402.609304 -127.19685)
		(stroke
			(width 0.05715)
			(type default)
		)
		(layer "B.Cu")
	)
	(gr_line
		(start 402.14677 -126.389384)
		(end 402.609304 -126.851918)
		(stroke
			(width 0.05715)
			(type default)
		)
		(layer "B.Cu")
	)
	(gr_line
		(start 402.254974 -125.302772)
		(end 402.366734 -125.414532)
		(stroke
			(width 0.05715)
			(type default)
		)
		(layer "B.Cu")
	)
	(gr_line
		(start 402.366734 -125.414532)
		(end 402.709634 -125.414532)
		(stroke
			(width 0.05715)
			(type default)
		)
		(layer "B.Cu")
	)
	(gr_line
		(start 402.496274 -125.058932)
		(end 402.580094 -125.058932)
		(stroke
			(width 0.05715)
			(type default)
		)
		(layer "B.Cu")
	)
	(gr_line
		(start 402.709634 -125.414532)
		(end 402.821394 -125.302772)
		(stroke
			(width 0.05715)
			(type default)
		)
		(layer "B.Cu")
	)
	(gr_line
		(start 403.021038 -126.915672)
		(end 403.132798 -126.803912)
		(stroke
			(width 0.05715)
			(type default)
		)
		(layer "B.Cu")
	)
	(gr_line
		(start 403.132798 -126.803912)
		(end 403.475698 -126.803912)
		(stroke
			(width 0.05715)
			(type default)
		)
		(layer "B.Cu")
	)
	(gr_line
		(start 403.262338 -127.159512)
		(end 403.346158 -127.159512)
		(stroke
			(width 0.05715)
			(type default)
		)
		(layer "B.Cu")
	)
	(gr_line
		(start 403.475698 -126.803912)
		(end 403.587458 -126.915672)
		(stroke
			(width 0.05715)
			(type default)
		)
		(layer "B.Cu")
	)
	(gr_line
		(start 403.61235 -125.97765)
		(end 403.9743 -125.6157)
		(stroke
			(width 0.05715)
			(type default)
		)
		(layer "B.Cu")
	)
	(gr_line
		(start 403.935438 -126.915672)
		(end 404.047198 -126.803912)
		(stroke
			(width 0.05715)
			(type default)
		)
		(layer "B.Cu")
	)
	(gr_line
		(start 404.047198 -126.803912)
		(end 404.390098 -126.803912)
		(stroke
			(width 0.05715)
			(type default)
		)
		(layer "B.Cu")
	)
	(gr_line
		(start 404.176738 -127.159512)
		(end 404.260558 -127.159512)
		(stroke
			(width 0.05715)
			(type default)
		)
		(layer "B.Cu")
	)
	(gr_line
		(start 404.21814 -125.82144)
		(end 404.37435 -125.97765)
		(stroke
			(width 0.05715)
			(type default)
		)
		(layer "B.Cu")
	)
	(gr_line
		(start 404.390098 -126.803912)
		(end 404.501858 -126.915672)
		(stroke
			(width 0.05715)
			(type default)
		)
		(layer "B.Cu")
	)
	(gr_line
		(start 405.73452 -125.835664)
		(end 405.946864 -125.835664)
		(stroke
			(width 0.05715)
			(type default)
		)
		(layer "B.Cu")
	)
	(gr_line
		(start 405.946864 -125.835664)
		(end 406.100026 -125.988826)
		(stroke
			(width 0.05715)
			(type default)
		)
		(layer "B.Cu")
	)
	(gr_line
		(start 406.444958 -125.988826)
		(end 406.59812 -125.835664)
		(stroke
			(width 0.05715)
			(type default)
		)
		(layer "B.Cu")
	)
	(gr_line
		(start 406.86355 -145.0975)
		(end 406.86355 -145.37055)
		(stroke
			(width 0.05715)
			(type default)
		)
		(layer "B.Cu")
	)
	(gr_arc
		(start 406.86355 -144.6276)
		(mid 406.897025 -144.70844)
		(end 406.97785 -144.7419)
		(stroke
			(width 0.05715)
			(type default)
		)
		(layer "B.Cu")
	)
	(gr_line
		(start 406.86355 -144.35455)
		(end 406.86355 -144.6276)
		(stroke
			(width 0.05715)
			(type default)
		)
		(layer "B.Cu")
	)
	(gr_arc
		(start 406.97785 -144.9832)
		(mid 406.897028 -145.016678)
		(end 406.86355 -145.0975)
		(stroke
			(width 0.05715)
			(type default)
		)
		(layer "B.Cu")
	)
	(gr_line
		(start 407.382726 -154.27325)
		(end 407.382726 -154.5463)
		(stroke
			(width 0.05715)
			(type default)
		)
		(layer "B.Cu")
	)
	(gr_arc
		(start 407.382726 -153.80335)
		(mid 407.416223 -153.884131)
		(end 407.497026 -153.91765)
		(stroke
			(width 0.05715)
			(type default)
		)
		(layer "B.Cu")
	)
	(gr_line
		(start 407.382726 -153.5303)
		(end 407.382726 -153.80335)
		(stroke
			(width 0.05715)
			(type default)
		)
		(layer "B.Cu")
	)
	(gr_line
		(start 407.395426 -151.30145)
		(end 407.395426 -151.5745)
		(stroke
			(width 0.05715)
			(type default)
		)
		(layer "B.Cu")
	)
	(gr_arc
		(start 407.395426 -150.83155)
		(mid 407.428923 -150.912331)
		(end 407.509726 -150.94585)
		(stroke
			(width 0.05715)
			(type default)
		)
		(layer "B.Cu")
	)
	(gr_line
		(start 407.395426 -150.5585)
		(end 407.395426 -150.83155)
		(stroke
			(width 0.05715)
			(type default)
		)
		(layer "B.Cu")
	)
	(gr_arc
		(start 407.497026 -154.15895)
		(mid 407.416204 -154.192428)
		(end 407.382726 -154.27325)
		(stroke
			(width 0.05715)
			(type default)
		)
		(layer "B.Cu")
	)
	(gr_arc
		(start 407.509726 -151.18715)
		(mid 407.428869 -151.220615)
		(end 407.395426 -151.30145)
		(stroke
			(width 0.05715)
			(type default)
		)
		(layer "B.Cu")
	)
	(gr_arc
		(start 407.617168 -153.91765)
		(mid 407.812791 -153.878666)
		(end 407.97861 -153.76779)
		(stroke
			(width 0.05715)
			(type default)
		)
		(layer "B.Cu")
	)
	(gr_line
		(start 407.922476 -147.68195)
		(end 407.922476 -147.955)
		(stroke
			(width 0.05715)
			(type default)
		)
		(layer "B.Cu")
	)
	(gr_arc
		(start 407.922476 -147.21205)
		(mid 407.95597 -147.292848)
		(end 408.036776 -147.32635)
		(stroke
			(width 0.05715)
			(type default)
		)
		(layer "B.Cu")
	)
	(gr_line
		(start 407.922476 -146.939)
		(end 407.922476 -147.21205)
		(stroke
			(width 0.05715)
			(type default)
		)
		(layer "B.Cu")
	)
	(gr_arc
		(start 407.933906 -150.94585)
		(mid 407.977602 -150.93707)
		(end 408.014678 -150.912322)
		(stroke
			(width 0.05715)
			(type default)
		)
		(layer "B.Cu")
	)
	(gr_arc
		(start 407.97861 -154.30881)
		(mid 407.812794 -154.197922)
		(end 407.617168 -154.15895)
		(stroke
			(width 0.05715)
			(type default)
		)
		(layer "B.Cu")
	)
	(gr_line
		(start 407.97861 -154.30881)
		(end 408.1526 -154.4828)
		(stroke
			(width 0.05715)
			(type default)
		)
		(layer "B.Cu")
	)
	(gr_line
		(start 407.97861 -153.76779)
		(end 408.1526 -153.5938)
		(stroke
			(width 0.05715)
			(type default)
		)
		(layer "B.Cu")
	)
	(gr_arc
		(start 408.014678 -151.220678)
		(mid 407.977639 -151.195852)
		(end 407.933906 -151.18715)
		(stroke
			(width 0.05715)
			(type default)
		)
		(layer "B.Cu")
	)
	(gr_line
		(start 408.014678 -151.220678)
		(end 408.305 -151.511)
		(stroke
			(width 0.05715)
			(type default)
		)
		(layer "B.Cu")
	)
	(gr_line
		(start 408.014678 -150.912322)
		(end 408.305 -150.622)
		(stroke
			(width 0.05715)
			(type default)
		)
		(layer "B.Cu")
	)
	(gr_arc
		(start 408.036776 -147.56765)
		(mid 407.955954 -147.601128)
		(end 407.922476 -147.68195)
		(stroke
			(width 0.05715)
			(type default)
		)
		(layer "B.Cu")
	)
	(gr_arc
		(start 408.276806 -147.32635)
		(mid 408.320502 -147.31757)
		(end 408.357578 -147.292822)
		(stroke
			(width 0.05715)
			(type default)
		)
		(layer "B.Cu")
	)
	(gr_line
		(start 408.313382 -142.57782)
		(end 408.313382 -142.657576)
		(stroke
			(width 0.05715)
			(type default)
		)
		(layer "B.Cu")
	)
	(gr_arc
		(start 408.313382 -141.765274)
		(mid 408.34686 -141.846096)
		(end 408.427682 -141.879574)
		(stroke
			(width 0.05715)
			(type default)
		)
		(layer "B.Cu")
	)
	(gr_line
		(start 408.313382 -141.641576)
		(end 408.313382 -141.765274)
		(stroke
			(width 0.05715)
			(type default)
		)
		(layer "B.Cu")
	)
	(gr_arc
		(start 408.34691 -142.497048)
		(mid 408.322148 -142.534107)
		(end 408.313382 -142.57782)
		(stroke
			(width 0.05715)
			(type default)
		)
		(layer "B.Cu")
	)
	(gr_line
		(start 408.34691 -142.497048)
		(end 408.689556 -142.154402)
		(stroke
			(width 0.05715)
			(type default)
		)
		(layer "B.Cu")
	)
	(gr_arc
		(start 408.357578 -147.601178)
		(mid 408.320519 -147.576416)
		(end 408.276806 -147.56765)
		(stroke
			(width 0.05715)
			(type default)
		)
		(layer "B.Cu")
	)
	(gr_line
		(start 408.357578 -147.601178)
		(end 408.7114 -147.955)
		(stroke
			(width 0.05715)
			(type default)
		)
		(layer "B.Cu")
	)
	(gr_line
		(start 408.357578 -147.292822)
		(end 408.7114 -146.939)
		(stroke
			(width 0.05715)
			(type default)
		)
		(layer "B.Cu")
	)
	(gr_line
		(start 408.427682 -141.879574)
		(end 408.526742 -141.879574)
		(stroke
			(width 0.05715)
			(type default)
		)
		(layer "B.Cu")
	)
	(gr_arc
		(start 408.770582 -142.120874)
		(mid 408.726744 -142.129594)
		(end 408.689556 -142.154402)
		(stroke
			(width 0.05715)
			(type default)
		)
		(layer "B.Cu")
	)
	(gr_line
		(start 409.0416 -154.4828)
		(end 409.351734 -154.172666)
		(stroke
			(width 0.05715)
			(type default)
		)
		(layer "B.Cu")
	)
	(gr_line
		(start 409.0416 -153.5938)
		(end 409.31211 -153.86431)
		(stroke
			(width 0.05715)
			(type default)
		)
		(layer "B.Cu")
	)
	(gr_line
		(start 409.194 -151.511)
		(end 409.485592 -151.219408)
		(stroke
			(width 0.05715)
			(type default)
		)
		(layer "B.Cu")
	)
	(gr_line
		(start 409.194 -150.622)
		(end 409.452572 -150.880572)
		(stroke
			(width 0.05715)
			(type default)
		)
		(layer "B.Cu")
	)
	(gr_arc
		(start 409.31211 -153.86431)
		(mid 409.349147 -153.889143)
		(end 409.392882 -153.897838)
		(stroke
			(width 0.05715)
			(type default)
		)
		(layer "B.Cu")
	)
	(gr_arc
		(start 409.452572 -150.880572)
		(mid 409.489747 -150.905412)
		(end 409.533598 -150.9141)
		(stroke
			(width 0.05715)
			(type default)
		)
		(layer "B.Cu")
	)
	(gr_line
		(start 409.579826 -149.62759)
		(end 409.579826 -149.861016)
		(stroke
			(width 0.05715)
			(type default)
		)
		(layer "B.Cu")
	)
	(gr_arc
		(start 409.579826 -149.15769)
		(mid 409.613302 -149.23851)
		(end 409.694126 -149.27199)
		(stroke
			(width 0.05715)
			(type default)
		)
		(layer "B.Cu")
	)
	(gr_line
		(start 409.579826 -148.845016)
		(end 409.579826 -149.15769)
		(stroke
			(width 0.05715)
			(type default)
		)
		(layer "B.Cu")
	)
	(gr_line
		(start 409.6004 -147.955)
		(end 409.954222 -147.601178)
		(stroke
			(width 0.05715)
			(type default)
		)
		(layer "B.Cu")
	)
	(gr_line
		(start 409.6004 -146.939)
		(end 409.954222 -147.292822)
		(stroke
			(width 0.05715)
			(type default)
		)
		(layer "B.Cu")
	)
	(gr_arc
		(start 409.640024 -151.1554)
		(mid 409.556429 -151.172013)
		(end 409.485592 -151.219408)
		(stroke
			(width 0.05715)
			(type default)
		)
		(layer "B.Cu")
	)
	(gr_arc
		(start 409.694126 -149.51329)
		(mid 409.613304 -149.546768)
		(end 409.579826 -149.62759)
		(stroke
			(width 0.05715)
			(type default)
		)
		(layer "B.Cu")
	)
	(gr_arc
		(start 409.707334 -141.476222)
		(mid 409.751075 -141.467521)
		(end 409.788106 -141.442694)
		(stroke
			(width 0.05715)
			(type default)
		)
		(layer "B.Cu")
	)
	(gr_line
		(start 409.788106 -141.442694)
		(end 410.21 -141.0208)
		(stroke
			(width 0.05715)
			(type default)
		)
		(layer "B.Cu")
	)
	(gr_line
		(start 409.790646 -152.95245)
		(end 409.790646 -153.2255)
		(stroke
			(width 0.05715)
			(type default)
		)
		(layer "B.Cu")
	)
	(gr_arc
		(start 409.790646 -152.48255)
		(mid 409.824144 -152.563324)
		(end 409.904946 -152.59685)
		(stroke
			(width 0.05715)
			(type default)
		)
		(layer "B.Cu")
	)
	(gr_line
		(start 409.790646 -152.2095)
		(end 409.790646 -152.48255)
		(stroke
			(width 0.05715)
			(type default)
		)
		(layer "B.Cu")
	)
	(gr_arc
		(start 409.904946 -152.83815)
		(mid 409.824076 -152.871608)
		(end 409.790646 -152.95245)
		(stroke
			(width 0.05715)
			(type default)
		)
		(layer "B.Cu")
	)
	(gr_line
		(start 409.92425 -141.75105)
		(end 410.21 -142.0368)
		(stroke
			(width 0.05715)
			(type default)
		)
		(layer "B.Cu")
	)
	(gr_arc
		(start 409.954222 -147.292822)
		(mid 409.991281 -147.317584)
		(end 410.034994 -147.32635)
		(stroke
			(width 0.05715)
			(type default)
		)
		(layer "B.Cu")
	)
	(gr_line
		(start 410.02331 -149.51583)
		(end 410.464 -149.95652)
		(stroke
			(width 0.05715)
			(type default)
		)
		(layer "B.Cu")
	)
	(gr_arc
		(start 410.034994 -147.56765)
		(mid 409.991298 -147.57643)
		(end 409.954222 -147.601178)
		(stroke
			(width 0.05715)
			(type default)
		)
		(layer "B.Cu")
	)
	(gr_arc
		(start 410.09443 -152.59685)
		(mid 410.121823 -152.593096)
		(end 410.147516 -152.58288)
		(stroke
			(width 0.05715)
			(type default)
		)
		(layer "B.Cu")
	)
	(gr_line
		(start 410.147516 -152.85212)
		(end 410.173678 -152.871678)
		(stroke
			(width 0.05715)
			(type default)
		)
		(layer "B.Cu")
	)
	(gr_line
		(start 410.147516 -152.58288)
		(end 410.173678 -152.563322)
		(stroke
			(width 0.05715)
			(type default)
		)
		(layer "B.Cu")
	)
	(gr_line
		(start 410.173678 -152.871678)
		(end 410.464 -153.162)
		(stroke
			(width 0.05715)
			(type default)
		)
		(layer "B.Cu")
	)
	(gr_line
		(start 410.173678 -152.563322)
		(end 410.464 -152.273)
		(stroke
			(width 0.05715)
			(type default)
		)
		(layer "B.Cu")
	)
	(gr_line
		(start 410.25953 -149.27199)
		(end 410.464 -149.06752)
		(stroke
			(width 0.05715)
			(type default)
		)
		(layer "B.Cu")
	)
	(gr_arc
		(start 410.492194 -147.6248)
		(mid 410.440809 -147.584686)
		(end 410.377894 -147.56765)
		(stroke
			(width 0.05715)
			(type default)
		)
		(layer "B.Cu")
	)
	(gr_arc
		(start 410.492194 -147.6248)
		(mid 410.543599 -147.664854)
		(end 410.606494 -147.68195)
		(stroke
			(width 0.05715)
			(type default)
		)
		(layer "B.Cu")
	)
	(gr_arc
		(start 410.529786 -145.80997)
		(mid 410.573487 -145.801198)
		(end 410.610558 -145.776442)
		(stroke
			(width 0.05715)
			(type default)
		)
		(layer "B.Cu")
	)
	(gr_arc
		(start 410.579824 -139.78509)
		(mid 410.642738 -139.768033)
		(end 410.694124 -139.72794)
		(stroke
			(width 0.05715)
			(type default)
		)
		(layer "B.Cu")
	)
	(gr_line
		(start 410.606494 -147.68195)
		(end 410.949394 -147.68195)
		(stroke
			(width 0.05715)
			(type default)
		)
		(layer "B.Cu")
	)
	(gr_line
		(start 410.610558 -145.776442)
		(end 410.972 -145.415)
		(stroke
			(width 0.05715)
			(type default)
		)
		(layer "B.Cu")
	)
	(gr_line
		(start 410.621734 -147.32635)
		(end 410.934154 -147.32635)
		(stroke
			(width 0.05715)
			(type default)
		)
		(layer "B.Cu")
	)
	(gr_arc
		(start 410.625798 -146.084798)
		(mid 410.588739 -146.060036)
		(end 410.545026 -146.05127)
		(stroke
			(width 0.05715)
			(type default)
		)
		(layer "B.Cu")
	)
	(gr_line
		(start 410.625798 -146.084798)
		(end 410.972 -146.431)
		(stroke
			(width 0.05715)
			(type default)
		)
		(layer "B.Cu")
	)
	(gr_arc
		(start 410.808424 -139.67079)
		(mid 410.745525 -139.687874)
		(end 410.694124 -139.72794)
		(stroke
			(width 0.05715)
			(type default)
		)
		(layer "B.Cu")
	)
	(gr_line
		(start 410.808424 -139.67079)
		(end 411.151324 -139.67079)
		(stroke
			(width 0.05715)
			(type default)
		)
		(layer "B.Cu")
	)
	(gr_line
		(start 410.823664 -140.02639)
		(end 411.136084 -140.02639)
		(stroke
			(width 0.05715)
			(type default)
		)
		(layer "B.Cu")
	)
	(gr_arc
		(start 410.949394 -147.68195)
		(mid 411.012308 -147.664893)
		(end 411.063694 -147.6248)
		(stroke
			(width 0.05715)
			(type default)
		)
		(layer "B.Cu")
	)
	(gr_arc
		(start 410.955744 -154.85745)
		(mid 410.904339 -154.817396)
		(end 410.841444 -154.8003)
		(stroke
			(width 0.05715)
			(type default)
		)
		(layer "B.Cu")
	)
	(gr_arc
		(start 410.955744 -154.85745)
		(mid 411.007136 -154.897541)
		(end 411.070044 -154.9146)
		(stroke
			(width 0.05715)
			(type default)
		)
		(layer "B.Cu")
	)
	(gr_line
		(start 411.070044 -154.9146)
		(end 411.412944 -154.9146)
		(stroke
			(width 0.05715)
			(type default)
		)
		(layer "B.Cu")
	)
	(gr_line
		(start 411.085284 -154.559)
		(end 411.397704 -154.559)
		(stroke
			(width 0.05715)
			(type default)
		)
		(layer "B.Cu")
	)
	(gr_line
		(start 411.099 -142.0368)
		(end 411.448504 -141.687296)
		(stroke
			(width 0.05715)
			(type default)
		)
		(layer "B.Cu")
	)
	(gr_line
		(start 411.099 -141.0208)
		(end 411.45714 -141.37894)
		(stroke
			(width 0.05715)
			(type default)
		)
		(layer "B.Cu")
	)
	(gr_arc
		(start 411.177994 -147.56765)
		(mid 411.115107 -147.584748)
		(end 411.063694 -147.6248)
		(stroke
			(width 0.05715)
			(type default)
		)
		(layer "B.Cu")
	)
	(gr_arc
		(start 411.265624 -139.72794)
		(mid 411.214229 -139.687861)
		(end 411.151324 -139.67079)
		(stroke
			(width 0.05715)
			(type default)
		)
		(layer "B.Cu")
	)
	(gr_arc
		(start 411.265624 -139.72794)
		(mid 411.317029 -139.767994)
		(end 411.379924 -139.78509)
		(stroke
			(width 0.05715)
			(type default)
		)
		(layer "B.Cu")
	)
	(gr_arc
		(start 411.35046 -151.21255)
		(mid 411.299069 -151.172458)
		(end 411.23616 -151.1554)
		(stroke
			(width 0.05715)
			(type default)
		)
		(layer "B.Cu")
	)
	(gr_arc
		(start 411.35046 -151.21255)
		(mid 411.401865 -151.252604)
		(end 411.46476 -151.2697)
		(stroke
			(width 0.05715)
			(type default)
		)
		(layer "B.Cu")
	)
	(gr_line
		(start 411.353 -153.162)
		(end 411.643322 -152.871678)
		(stroke
			(width 0.05715)
			(type default)
		)
		(layer "B.Cu")
	)
	(gr_line
		(start 411.353 -152.273)
		(end 411.643322 -152.563322)
		(stroke
			(width 0.05715)
			(type default)
		)
		(layer "B.Cu")
	)
	(gr_line
		(start 411.353 -149.95652)
		(end 411.645862 -149.663658)
		(stroke
			(width 0.05715)
			(type default)
		)
		(layer "B.Cu")
	)
	(gr_line
		(start 411.353 -149.06752)
		(end 411.640782 -149.355302)
		(stroke
			(width 0.05715)
			(type default)
		)
		(layer "B.Cu")
	)
	(gr_arc
		(start 411.412944 -154.9146)
		(mid 411.475826 -154.897494)
		(end 411.527244 -154.85745)
		(stroke
			(width 0.05715)
			(type default)
		)
		(layer "B.Cu")
	)
	(gr_arc
		(start 411.45714 -141.37894)
		(mid 411.494199 -141.403702)
		(end 411.537912 -141.412468)
		(stroke
			(width 0.05715)
			(type default)
		)
		(layer "B.Cu")
	)
	(gr_line
		(start 411.46476 -151.2697)
		(end 411.80766 -151.2697)
		(stroke
			(width 0.05715)
			(type default)
		)
		(layer "B.Cu")
	)
	(gr_line
		(start 411.48 -150.9141)
		(end 411.79242 -150.9141)
		(stroke
			(width 0.05715)
			(type default)
		)
		(layer "B.Cu")
	)
	(gr_arc
		(start 411.529276 -141.653768)
		(mid 411.485535 -141.662469)
		(end 411.448504 -141.687296)
		(stroke
			(width 0.05715)
			(type default)
		)
		(layer "B.Cu")
	)
	(gr_arc
		(start 411.640782 -149.355302)
		(mid 411.677841 -149.380064)
		(end 411.721554 -149.38883)
		(stroke
			(width 0.05715)
			(type default)
		)
		(layer "B.Cu")
	)
	(gr_arc
		(start 411.641544 -154.8003)
		(mid 411.57863 -154.817357)
		(end 411.527244 -154.85745)
		(stroke
			(width 0.05715)
			(type default)
		)
		(layer "B.Cu")
	)
	(gr_arc
		(start 411.643322 -152.563322)
		(mid 411.680381 -152.588084)
		(end 411.724094 -152.59685)
		(stroke
			(width 0.05715)
			(type default)
		)
		(layer "B.Cu")
	)
	(gr_arc
		(start 411.722824 -139.78509)
		(mid 411.785738 -139.768033)
		(end 411.837124 -139.72794)
		(stroke
			(width 0.05715)
			(type default)
		)
		(layer "B.Cu")
	)
	(gr_arc
		(start 411.724094 -152.83815)
		(mid 411.680398 -152.84693)
		(end 411.643322 -152.871678)
		(stroke
			(width 0.05715)
			(type default)
		)
		(layer "B.Cu")
	)
	(gr_arc
		(start 411.726634 -149.63013)
		(mid 411.682929 -149.638895)
		(end 411.645862 -149.663658)
		(stroke
			(width 0.05715)
			(type default)
		)
		(layer "B.Cu")
	)
	(gr_arc
		(start 411.80766 -151.2697)
		(mid 411.870574 -151.252643)
		(end 411.92196 -151.21255)
		(stroke
			(width 0.05715)
			(type default)
		)
		(layer "B.Cu")
	)
	(gr_line
		(start 411.861 -146.431)
		(end 412.222188 -146.069812)
		(stroke
			(width 0.05715)
			(type default)
		)
		(layer "B.Cu")
	)
	(gr_line
		(start 411.861 -145.415)
		(end 412.207456 -145.761456)
		(stroke
			(width 0.05715)
			(type default)
		)
		(layer "B.Cu")
	)
	(gr_line
		(start 411.895798 -151.941784)
		(end 411.607 -152.019)
		(stroke
			(width 0.2)
			(type default)
		)
		(layer "B.Cu")
	)
	(gr_arc
		(start 411.951424 -139.67079)
		(mid 411.888525 -139.687874)
		(end 411.837124 -139.72794)
		(stroke
			(width 0.05715)
			(type default)
		)
		(layer "B.Cu")
	)
	(gr_line
		(start 411.951424 -139.67079)
		(end 412.294324 -139.67079)
		(stroke
			(width 0.05715)
			(type default)
		)
		(layer "B.Cu")
	)
	(gr_line
		(start 411.966664 -140.02639)
		(end 412.279084 -140.02639)
		(stroke
			(width 0.05715)
			(type default)
		)
		(layer "B.Cu")
	)
	(gr_arc
		(start 412.03626 -151.1554)
		(mid 411.973377 -151.172504)
		(end 411.92196 -151.21255)
		(stroke
			(width 0.05715)
			(type default)
		)
		(layer "B.Cu")
	)
	(gr_arc
		(start 412.207456 -145.761456)
		(mid 412.244515 -145.786218)
		(end 412.288228 -145.794984)
		(stroke
			(width 0.05715)
			(type default)
		)
		(layer "B.Cu")
	)
	(gr_arc
		(start 412.30296 -146.036284)
		(mid 412.259219 -146.044985)
		(end 412.222188 -146.069812)
		(stroke
			(width 0.05715)
			(type default)
		)
		(layer "B.Cu")
	)
	(gr_arc
		(start 412.408624 -139.72794)
		(mid 412.357229 -139.687861)
		(end 412.294324 -139.67079)
		(stroke
			(width 0.05715)
			(type default)
		)
		(layer "B.Cu")
	)
	(gr_arc
		(start 412.408624 -139.72794)
		(mid 412.460029 -139.767994)
		(end 412.522924 -139.78509)
		(stroke
			(width 0.05715)
			(type default)
		)
		(layer "B.Cu")
	)
	(gr_arc
		(start 412.76016 -146.093434)
		(mid 412.708755 -146.05338)
		(end 412.64586 -146.036284)
		(stroke
			(width 0.05715)
			(type default)
		)
		(layer "B.Cu")
	)
	(gr_arc
		(start 412.76016 -146.093434)
		(mid 412.811552 -146.133524)
		(end 412.87446 -146.150584)
		(stroke
			(width 0.05715)
			(type default)
		)
		(layer "B.Cu")
	)
	(gr_line
		(start 412.773876 -141.76375)
		(end 412.773876 -142.0368)
		(stroke
			(width 0.05715)
			(type default)
		)
		(layer "B.Cu")
	)
	(gr_arc
		(start 412.773876 -141.29385)
		(mid 412.807354 -141.374672)
		(end 412.888176 -141.40815)
		(stroke
			(width 0.05715)
			(type default)
		)
		(layer "B.Cu")
	)
	(gr_line
		(start 412.773876 -141.0208)
		(end 412.773876 -141.29385)
		(stroke
			(width 0.05715)
			(type default)
		)
		(layer "B.Cu")
	)
	(gr_arc
		(start 412.865824 -139.78509)
		(mid 412.928738 -139.768033)
		(end 412.980124 -139.72794)
		(stroke
			(width 0.05715)
			(type default)
		)
		(layer "B.Cu")
	)
	(gr_line
		(start 412.87446 -146.150584)
		(end 413.21736 -146.150584)
		(stroke
			(width 0.05715)
			(type default)
		)
		(layer "B.Cu")
	)
	(gr_arc
		(start 412.888176 -141.64945)
		(mid 412.807352 -141.682933)
		(end 412.773876 -141.76375)
		(stroke
			(width 0.05715)
			(type default)
		)
		(layer "B.Cu")
	)
	(gr_line
		(start 412.8897 -145.794984)
		(end 413.20212 -145.794984)
		(stroke
			(width 0.05715)
			(type default)
		)
		(layer "B.Cu")
	)
	(gr_line
		(start 412.996126 -144.107408)
		(end 412.996888 -144.10817)
		(stroke
			(width 0.05715)
			(type default)
		)
		(layer "B.Cu")
	)
	(gr_line
		(start 412.996888 -144.10817)
		(end 412.99765 -144.108678)
		(stroke
			(width 0.05715)
			(type default)
		)
		(layer "B.Cu")
	)
	(gr_line
		(start 413.026098 -156.340048)
		(end 413.290004 -155.847034)
		(stroke
			(width 0.05715)
			(type default)
		)
		(layer "B.Cu")
	)
	(gr_line
		(start 413.026098 -152.539954)
		(end 413.290004 -152.04694)
		(stroke
			(width 0.05715)
			(type default)
		)
		(layer "B.Cu")
	)
	(gr_line
		(start 413.026098 -148.740114)
		(end 413.290004 -148.2471)
		(stroke
			(width 0.05715)
			(type default)
		)
		(layer "B.Cu")
	)
	(gr_line
		(start 413.026098 -144.94002)
		(end 413.3088 -144.411954)
		(stroke
			(width 0.05715)
			(type default)
		)
		(layer "B.Cu")
	)
	(gr_arc
		(start 413.094424 -139.67079)
		(mid 413.031525 -139.687874)
		(end 412.980124 -139.72794)
		(stroke
			(width 0.05715)
			(type default)
		)
		(layer "B.Cu")
	)
	(gr_line
		(start 413.094424 -139.67079)
		(end 413.437324 -139.67079)
		(stroke
			(width 0.05715)
			(type default)
		)
		(layer "B.Cu")
	)
	(gr_line
		(start 413.109664 -140.02639)
		(end 413.422084 -140.02639)
		(stroke
			(width 0.05715)
			(type default)
		)
		(layer "B.Cu")
	)
	(gr_arc
		(start 413.21736 -146.150584)
		(mid 413.28026 -146.133503)
		(end 413.33166 -146.093434)
		(stroke
			(width 0.05715)
			(type default)
		)
		(layer "B.Cu")
	)
	(gr_arc
		(start 413.229806 -141.40815)
		(mid 413.273547 -141.399449)
		(end 413.310578 -141.374622)
		(stroke
			(width 0.05715)
			(type default)
		)
		(layer "B.Cu")
	)
	(gr_arc
		(start 413.290004 -155.847034)
		(mid 413.298578 -155.760066)
		(end 413.243268 -155.692348)
		(stroke
			(width 0.05715)
			(type default)
		)
		(layer "B.Cu")
	)
	(gr_arc
		(start 413.290004 -152.04694)
		(mid 413.298651 -151.959935)
		(end 413.243268 -151.892254)
		(stroke
			(width 0.05715)
			(type default)
		)
		(layer "B.Cu")
	)
	(gr_arc
		(start 413.290004 -148.2471)
		(mid 413.298689 -148.160066)
		(end 413.243268 -148.092414)
		(stroke
			(width 0.05715)
			(type default)
		)
		(layer "B.Cu")
	)
	(gr_arc
		(start 413.3088 -144.411954)
		(mid 413.317902 -144.320107)
		(end 413.25927 -144.248886)
		(stroke
			(width 0.05715)
			(type default)
		)
		(layer "B.Cu")
	)
	(gr_arc
		(start 413.310578 -141.682978)
		(mid 413.273539 -141.658152)
		(end 413.229806 -141.64945)
		(stroke
			(width 0.05715)
			(type default)
		)
		(layer "B.Cu")
	)
	(gr_line
		(start 413.310578 -141.682978)
		(end 413.6644 -142.0368)
		(stroke
			(width 0.05715)
			(type default)
		)
		(layer "B.Cu")
	)
	(gr_line
		(start 413.310578 -141.374622)
		(end 413.6644 -141.0208)
		(stroke
			(width 0.05715)
			(type default)
		)
		(layer "B.Cu")
	)
	(gr_arc
		(start 413.357314 -155.479496)
		(mid 413.444478 -155.488315)
		(end 413.512254 -155.43276)
		(stroke
			(width 0.05715)
			(type default)
		)
		(layer "B.Cu")
	)
	(gr_arc
		(start 413.357314 -151.679402)
		(mid 413.444448 -151.688148)
		(end 413.512254 -151.632666)
		(stroke
			(width 0.05715)
			(type default)
		)
		(layer "B.Cu")
	)
	(gr_arc
		(start 413.357314 -147.879562)
		(mid 413.444448 -147.888308)
		(end 413.512254 -147.832826)
		(stroke
			(width 0.05715)
			(type default)
		)
		(layer "B.Cu")
	)
	(gr_arc
		(start 413.379158 -144.038828)
		(mid 413.466322 -144.047524)
		(end 413.534098 -143.992092)
		(stroke
			(width 0.05715)
			(type default)
		)
		(layer "B.Cu")
	)
	(gr_arc
		(start 413.44596 -146.036284)
		(mid 413.383046 -146.053341)
		(end 413.33166 -146.093434)
		(stroke
			(width 0.05715)
			(type default)
		)
		(layer "B.Cu")
	)
	(gr_line
		(start 413.512254 -155.43276)
		(end 413.775906 -154.94)
		(stroke
			(width 0.05715)
			(type default)
		)
		(layer "B.Cu")
	)
	(gr_line
		(start 413.512254 -151.632666)
		(end 413.775906 -151.139906)
		(stroke
			(width 0.05715)
			(type default)
		)
		(layer "B.Cu")
	)
	(gr_line
		(start 413.512254 -147.832826)
		(end 413.775906 -147.340066)
		(stroke
			(width 0.05715)
			(type default)
		)
		(layer "B.Cu")
	)
	(gr_line
		(start 413.534098 -143.992092)
		(end 413.775906 -143.539972)
		(stroke
			(width 0.05715)
			(type default)
		)
		(layer "B.Cu")
	)
	(gr_arc
		(start 413.551624 -139.72794)
		(mid 413.500229 -139.687861)
		(end 413.437324 -139.67079)
		(stroke
			(width 0.05715)
			(type default)
		)
		(layer "B.Cu")
	)
	(gr_arc
		(start 413.551624 -139.72794)
		(mid 413.603029 -139.767994)
		(end 413.665924 -139.78509)
		(stroke
			(width 0.05715)
			(type default)
		)
		(layer "B.Cu")
	)
	(gr_arc
		(start 414.167828 -150.203408)
		(mid 414.159816 -150.138771)
		(end 414.127442 -150.08225)
		(stroke
			(width 0.05715)
			(type default)
		)
		(layer "B.Cu")
	)
	(gr_arc
		(start 414.167828 -150.203408)
		(mid 414.175829 -150.268051)
		(end 414.208214 -150.324566)
		(stroke
			(width 0.05715)
			(type default)
		)
		(layer "B.Cu")
	)
	(gr_line
		(start 414.208214 -150.324566)
		(end 414.45053 -150.567136)
		(stroke
			(width 0.05715)
			(type default)
		)
		(layer "B.Cu")
	)
	(gr_line
		(start 414.32226 -149.935692)
		(end 414.840166 -150.453344)
		(stroke
			(width 0.05715)
			(type default)
		)
		(layer "B.Cu")
	)
	(gr_arc
		(start 414.45053 -150.567136)
		(mid 414.507165 -150.599561)
		(end 414.571942 -150.607522)
		(stroke
			(width 0.05715)
			(type default)
		)
		(layer "B.Cu")
	)
	(gr_line
		(start 414.5534 -142.0368)
		(end 414.907222 -141.682978)
		(stroke
			(width 0.05715)
			(type default)
		)
		(layer "B.Cu")
	)
	(gr_line
		(start 414.5534 -141.0208)
		(end 414.907222 -141.374622)
		(stroke
			(width 0.05715)
			(type default)
		)
		(layer "B.Cu")
	)
	(gr_arc
		(start 414.6931 -150.647908)
		(mid 414.636585 -150.615524)
		(end 414.571942 -150.607522)
		(stroke
			(width 0.05715)
			(type default)
		)
		(layer "B.Cu")
	)
	(gr_arc
		(start 414.907222 -141.374622)
		(mid 414.944281 -141.399384)
		(end 414.987994 -141.40815)
		(stroke
			(width 0.05715)
			(type default)
		)
		(layer "B.Cu")
	)
	(gr_arc
		(start 414.98774 -141.64945)
		(mid 414.944136 -141.658199)
		(end 414.907222 -141.682978)
		(stroke
			(width 0.05715)
			(type default)
		)
		(layer "B.Cu")
	)
	(gr_line
		(start 415.27603 -156.340048)
		(end 415.54019 -155.847796)
		(stroke
			(width 0.05715)
			(type default)
		)
		(layer "B.Cu")
	)
	(gr_line
		(start 415.27603 -152.539954)
		(end 415.54019 -152.047702)
		(stroke
			(width 0.05715)
			(type default)
		)
		(layer "B.Cu")
	)
	(gr_line
		(start 415.27603 -148.740114)
		(end 415.54019 -148.247862)
		(stroke
			(width 0.05715)
			(type default)
		)
		(layer "B.Cu")
	)
	(gr_line
		(start 415.27603 -144.94002)
		(end 415.565336 -144.400778)
		(stroke
			(width 0.05715)
			(type default)
		)
		(layer "B.Cu")
	)
	(gr_line
		(start 415.431224 -144.198086)
		(end 415.515806 -144.243298)
		(stroke
			(width 0.05715)
			(type default)
		)
		(layer "B.Cu")
	)
	(gr_arc
		(start 415.54019 -155.847796)
		(mid 415.549016 -155.760627)
		(end 415.493454 -155.692856)
		(stroke
			(width 0.05715)
			(type default)
		)
		(layer "B.Cu")
	)
	(gr_arc
		(start 415.54019 -152.047702)
		(mid 415.54902 -151.96053)
		(end 415.493454 -151.892762)
		(stroke
			(width 0.05715)
			(type default)
		)
		(layer "B.Cu")
	)
	(gr_arc
		(start 415.54019 -148.247862)
		(mid 415.548936 -148.160728)
		(end 415.493454 -148.092922)
		(stroke
			(width 0.05715)
			(type default)
		)
		(layer "B.Cu")
	)
	(gr_arc
		(start 415.565336 -144.400778)
		(mid 415.573776 -144.311584)
		(end 415.515806 -144.243298)
		(stroke
			(width 0.05715)
			(type default)
		)
		(layer "B.Cu")
	)
	(gr_arc
		(start 415.606738 -155.479496)
		(mid 415.693872 -155.488242)
		(end 415.761678 -155.43276)
		(stroke
			(width 0.05715)
			(type default)
		)
		(layer "B.Cu")
	)
	(gr_arc
		(start 415.606738 -151.679402)
		(mid 415.693872 -151.688148)
		(end 415.761678 -151.632666)
		(stroke
			(width 0.05715)
			(type default)
		)
		(layer "B.Cu")
	)
	(gr_arc
		(start 415.606738 -147.879562)
		(mid 415.693872 -147.888308)
		(end 415.761678 -147.832826)
		(stroke
			(width 0.05715)
			(type default)
		)
		(layer "B.Cu")
	)
	(gr_arc
		(start 415.64687 -144.039336)
		(mid 415.720296 -144.047058)
		(end 415.778442 -144.00149)
		(stroke
			(width 0.05715)
			(type default)
		)
		(layer "B.Cu")
	)
	(gr_line
		(start 415.761678 -155.43276)
		(end 416.026092 -154.94)
		(stroke
			(width 0.05715)
			(type default)
		)
		(layer "B.Cu")
	)
	(gr_line
		(start 415.761678 -151.632666)
		(end 416.026092 -151.139906)
		(stroke
			(width 0.05715)
			(type default)
		)
		(layer "B.Cu")
	)
	(gr_line
		(start 415.761678 -147.832826)
		(end 416.026092 -147.340066)
		(stroke
			(width 0.05715)
			(type default)
		)
		(layer "B.Cu")
	)
	(gr_line
		(start 415.778442 -144.00149)
		(end 416.026092 -143.539972)
		(stroke
			(width 0.05715)
			(type default)
		)
		(layer "B.Cu")
	)
	(gr_line
		(start 419.320726 -155.61945)
		(end 419.320726 -156.0068)
		(stroke
			(width 0.05715)
			(type default)
		)
		(layer "B.Cu")
	)
	(gr_arc
		(start 419.320726 -155.14955)
		(mid 419.354204 -155.230372)
		(end 419.435026 -155.26385)
		(stroke
			(width 0.05715)
			(type default)
		)
		(layer "B.Cu")
	)
	(gr_line
		(start 419.320726 -154.7368)
		(end 419.320726 -155.14955)
		(stroke
			(width 0.05715)
			(type default)
		)
		(layer "B.Cu")
	)
	(gr_arc
		(start 419.435026 -155.50515)
		(mid 419.354169 -155.538615)
		(end 419.320726 -155.61945)
		(stroke
			(width 0.05715)
			(type default)
		)
		(layer "B.Cu")
	)
	(gr_line
		(start 419.734746 -151.571452)
		(end 419.734746 -151.8793)
		(stroke
			(width 0.05715)
			(type default)
		)
		(layer "B.Cu")
	)
	(gr_arc
		(start 419.734746 -151.101552)
		(mid 419.76821 -151.182389)
		(end 419.849046 -151.215852)
		(stroke
			(width 0.05715)
			(type default)
		)
		(layer "B.Cu")
	)
	(gr_line
		(start 419.734746 -150.8633)
		(end 419.734746 -151.101552)
		(stroke
			(width 0.05715)
			(type default)
		)
		(layer "B.Cu")
	)
	(gr_line
		(start 419.777926 -147.61845)
		(end 419.777926 -147.9169)
		(stroke
			(width 0.05715)
			(type default)
		)
		(layer "B.Cu")
	)
	(gr_arc
		(start 419.777926 -147.14855)
		(mid 419.811404 -147.229372)
		(end 419.892226 -147.26285)
		(stroke
			(width 0.05715)
			(type default)
		)
		(layer "B.Cu")
	)
	(gr_line
		(start 419.777926 -146.9009)
		(end 419.777926 -147.14855)
		(stroke
			(width 0.05715)
			(type default)
		)
		(layer "B.Cu")
	)
	(gr_arc
		(start 419.849046 -151.457152)
		(mid 419.768177 -151.490611)
		(end 419.734746 -151.571452)
		(stroke
			(width 0.05715)
			(type default)
		)
		(layer "B.Cu")
	)
	(gr_arc
		(start 419.892226 -147.50415)
		(mid 419.811369 -147.537615)
		(end 419.777926 -147.61845)
		(stroke
			(width 0.05715)
			(type default)
		)
		(layer "B.Cu")
	)
	(gr_arc
		(start 420.23665 -151.215852)
		(mid 420.280508 -151.207169)
		(end 420.317676 -151.182324)
		(stroke
			(width 0.05715)
			(type default)
		)
		(layer "B.Cu")
	)
	(gr_arc
		(start 420.252906 -155.26385)
		(mid 420.296647 -155.255149)
		(end 420.333678 -155.230322)
		(stroke
			(width 0.05715)
			(type default)
		)
		(layer "B.Cu")
	)
	(gr_arc
		(start 420.252906 -147.26285)
		(mid 420.296647 -147.254149)
		(end 420.333678 -147.229322)
		(stroke
			(width 0.05715)
			(type default)
		)
		(layer "B.Cu")
	)
	(gr_line
		(start 420.317676 -151.182324)
		(end 420.624 -150.876)
		(stroke
			(width 0.05715)
			(type default)
		)
		(layer "B.Cu")
	)
	(gr_arc
		(start 420.333678 -155.538678)
		(mid 420.296639 -155.513852)
		(end 420.252906 -155.50515)
		(stroke
			(width 0.05715)
			(type default)
		)
		(layer "B.Cu")
	)
	(gr_line
		(start 420.333678 -155.538678)
		(end 420.624 -155.829)
		(stroke
			(width 0.05715)
			(type default)
		)
		(layer "B.Cu")
	)
	(gr_line
		(start 420.333678 -155.230322)
		(end 420.624 -154.94)
		(stroke
			(width 0.05715)
			(type default)
		)
		(layer "B.Cu")
	)
	(gr_arc
		(start 420.333678 -147.537678)
		(mid 420.296639 -147.512852)
		(end 420.252906 -147.50415)
		(stroke
			(width 0.05715)
			(type default)
		)
		(layer "B.Cu")
	)
	(gr_line
		(start 420.333678 -147.537678)
		(end 420.624 -147.828)
		(stroke
			(width 0.05715)
			(type default)
		)
		(layer "B.Cu")
	)
	(gr_line
		(start 420.333678 -147.229322)
		(end 420.624 -146.939)
		(stroke
			(width 0.05715)
			(type default)
		)
		(layer "B.Cu")
	)
	(gr_arc
		(start 420.34968 -151.49068)
		(mid 420.312497 -151.465864)
		(end 420.268654 -151.457152)
		(stroke
			(width 0.05715)
			(type default)
		)
		(layer "B.Cu")
	)
	(gr_line
		(start 420.34968 -151.49068)
		(end 420.624 -151.765)
		(stroke
			(width 0.05715)
			(type default)
		)
		(layer "B.Cu")
	)
	(gr_line
		(start 421.225726 -153.71445)
		(end 421.225726 -153.9875)
		(stroke
			(width 0.05715)
			(type default)
		)
		(layer "B.Cu")
	)
	(gr_arc
		(start 421.225726 -153.24455)
		(mid 421.259223 -153.325331)
		(end 421.340026 -153.35885)
		(stroke
			(width 0.05715)
			(type default)
		)
		(layer "B.Cu")
	)
	(gr_line
		(start 421.225726 -152.9715)
		(end 421.225726 -153.24455)
		(stroke
			(width 0.05715)
			(type default)
		)
		(layer "B.Cu")
	)
	(gr_line
		(start 421.323516 -139.954)
		(end 421.710612 -139.954)
		(stroke
			(width 0.05715)
			(type default)
		)
		(layer "B.Cu")
	)
	(gr_arc
		(start 421.340026 -153.60015)
		(mid 421.259204 -153.633628)
		(end 421.225726 -153.71445)
		(stroke
			(width 0.05715)
			(type default)
		)
		(layer "B.Cu")
	)
	(gr_line
		(start 421.513 -155.829)
		(end 421.803322 -155.538678)
		(stroke
			(width 0.05715)
			(type default)
		)
		(layer "B.Cu")
	)
	(gr_line
		(start 421.513 -154.94)
		(end 421.803322 -155.230322)
		(stroke
			(width 0.05715)
			(type default)
		)
		(layer "B.Cu")
	)
	(gr_line
		(start 421.513 -151.765)
		(end 421.809672 -151.468328)
		(stroke
			(width 0.05715)
			(type default)
		)
		(layer "B.Cu")
	)
	(gr_line
		(start 421.513 -150.876)
		(end 421.796972 -151.159972)
		(stroke
			(width 0.05715)
			(type default)
		)
		(layer "B.Cu")
	)
	(gr_line
		(start 421.513 -147.828)
		(end 421.803322 -147.537678)
		(stroke
			(width 0.05715)
			(type default)
		)
		(layer "B.Cu")
	)
	(gr_line
		(start 421.513 -146.939)
		(end 421.803322 -147.229322)
		(stroke
			(width 0.05715)
			(type default)
		)
		(layer "B.Cu")
	)
	(gr_line
		(start 421.513 -141.9606)
		(end 421.799766 -142.247366)
		(stroke
			(width 0.05715)
			(type default)
		)
		(layer "B.Cu")
	)
	(gr_line
		(start 421.513 -141.0716)
		(end 421.800528 -140.784072)
		(stroke
			(width 0.05715)
			(type default)
		)
		(layer "B.Cu")
	)
	(gr_arc
		(start 421.796972 -151.159972)
		(mid 421.834031 -151.184734)
		(end 421.877744 -151.1935)
		(stroke
			(width 0.05715)
			(type default)
		)
		(layer "B.Cu")
	)
	(gr_arc
		(start 421.800528 -140.784072)
		(mid 421.827983 -140.742926)
		(end 421.837612 -140.69441)
		(stroke
			(width 0.05715)
			(type default)
		)
		(layer "B.Cu")
	)
	(gr_arc
		(start 421.803322 -155.230322)
		(mid 421.840381 -155.255084)
		(end 421.884094 -155.26385)
		(stroke
			(width 0.05715)
			(type default)
		)
		(layer "B.Cu")
	)
	(gr_arc
		(start 421.803322 -147.229322)
		(mid 421.840263 -147.254035)
		(end 421.88384 -147.26285)
		(stroke
			(width 0.05715)
			(type default)
		)
		(layer "B.Cu")
	)
	(gr_line
		(start 421.81272 -149.776942)
		(end 421.81272 -150.0505)
		(stroke
			(width 0.05715)
			(type default)
		)
		(layer "B.Cu")
	)
	(gr_arc
		(start 421.81272 -149.307042)
		(mid 421.846198 -149.387864)
		(end 421.92702 -149.421342)
		(stroke
			(width 0.05715)
			(type default)
		)
		(layer "B.Cu")
	)
	(gr_line
		(start 421.81272 -149.0345)
		(end 421.81272 -149.307042)
		(stroke
			(width 0.05715)
			(type default)
		)
		(layer "B.Cu")
	)
	(gr_arc
		(start 421.83685 -142.337028)
		(mid 421.827202 -142.288517)
		(end 421.799766 -142.247366)
		(stroke
			(width 0.05715)
			(type default)
		)
		(layer "B.Cu")
	)
	(gr_arc
		(start 421.837612 -140.081)
		(mid 421.800415 -139.991193)
		(end 421.710612 -139.954)
		(stroke
			(width 0.05715)
			(type default)
		)
		(layer "B.Cu")
	)
	(gr_arc
		(start 421.884094 -155.50515)
		(mid 421.840353 -155.513851)
		(end 421.803322 -155.538678)
		(stroke
			(width 0.05715)
			(type default)
		)
		(layer "B.Cu")
	)
	(gr_arc
		(start 421.884094 -147.50415)
		(mid 421.840398 -147.51293)
		(end 421.803322 -147.537678)
		(stroke
			(width 0.05715)
			(type default)
		)
		(layer "B.Cu")
	)
	(gr_arc
		(start 421.890444 -151.4348)
		(mid 421.846703 -151.443501)
		(end 421.809672 -151.468328)
		(stroke
			(width 0.05715)
			(type default)
		)
		(layer "B.Cu")
	)
	(gr_arc
		(start 421.92702 -149.662642)
		(mid 421.8462 -149.696115)
		(end 421.81272 -149.776942)
		(stroke
			(width 0.05715)
			(type default)
		)
		(layer "B.Cu")
	)
	(gr_arc
		(start 422.078912 -140.695934)
		(mid 422.088545 -140.744452)
		(end 422.115996 -140.785596)
		(stroke
			(width 0.05715)
			(type default)
		)
		(layer "B.Cu")
	)
	(gr_arc
		(start 422.115234 -142.247366)
		(mid 422.087801 -142.288517)
		(end 422.07815 -142.337028)
		(stroke
			(width 0.05715)
			(type default)
		)
		(layer "B.Cu")
	)
	(gr_line
		(start 422.115234 -142.247366)
		(end 422.402 -141.9606)
		(stroke
			(width 0.05715)
			(type default)
		)
		(layer "B.Cu")
	)
	(gr_line
		(start 422.115996 -140.785596)
		(end 422.402 -141.0716)
		(stroke
			(width 0.05715)
			(type default)
		)
		(layer "B.Cu")
	)
	(gr_arc
		(start 422.205912 -139.954)
		(mid 422.116109 -139.991197)
		(end 422.078912 -140.081)
		(stroke
			(width 0.05715)
			(type default)
		)
		(layer "B.Cu")
	)
	(gr_line
		(start 422.205912 -139.954)
		(end 422.593516 -139.954)
		(stroke
			(width 0.05715)
			(type default)
		)
		(layer "B.Cu")
	)
	(gr_arc
		(start 422.284906 -153.35885)
		(mid 422.328602 -153.35007)
		(end 422.365678 -153.325322)
		(stroke
			(width 0.05715)
			(type default)
		)
		(layer "B.Cu")
	)
	(gr_arc
		(start 422.331134 -149.421342)
		(mid 422.374875 -149.412641)
		(end 422.411906 -149.387814)
		(stroke
			(width 0.05715)
			(type default)
		)
		(layer "B.Cu")
	)
	(gr_arc
		(start 422.341294 -155.5623)
		(mid 422.289889 -155.522246)
		(end 422.226994 -155.50515)
		(stroke
			(width 0.05715)
			(type default)
		)
		(layer "B.Cu")
	)
	(gr_arc
		(start 422.341294 -155.5623)
		(mid 422.392685 -155.602387)
		(end 422.455594 -155.61945)
		(stroke
			(width 0.05715)
			(type default)
		)
		(layer "B.Cu")
	)
	(gr_arc
		(start 422.341294 -147.5613)
		(mid 422.289909 -147.521186)
		(end 422.226994 -147.50415)
		(stroke
			(width 0.05715)
			(type default)
		)
		(layer "B.Cu")
	)
	(gr_arc
		(start 422.341294 -147.5613)
		(mid 422.392699 -147.601354)
		(end 422.455594 -147.61845)
		(stroke
			(width 0.05715)
			(type default)
		)
		(layer "B.Cu")
	)
	(gr_arc
		(start 422.347644 -151.49195)
		(mid 422.296239 -151.451896)
		(end 422.233344 -151.4348)
		(stroke
			(width 0.05715)
			(type default)
		)
		(layer "B.Cu")
	)
	(gr_arc
		(start 422.347644 -151.49195)
		(mid 422.399036 -151.532041)
		(end 422.461944 -151.5491)
		(stroke
			(width 0.05715)
			(type default)
		)
		(layer "B.Cu")
	)
	(gr_arc
		(start 422.354502 -142.733014)
		(mid 422.411017 -142.765399)
		(end 422.47566 -142.7734)
		(stroke
			(width 0.05715)
			(type default)
		)
		(layer "B.Cu")
	)
	(gr_line
		(start 422.35628 -143.076168)
		(end 422.664636 -143.384524)
		(stroke
			(width 0.05715)
			(type default)
		)
		(layer "B.Cu")
	)
	(gr_arc
		(start 422.365678 -153.633678)
		(mid 422.328619 -153.608916)
		(end 422.284906 -153.60015)
		(stroke
			(width 0.05715)
			(type default)
		)
		(layer "B.Cu")
	)
	(gr_line
		(start 422.365678 -153.633678)
		(end 422.656 -153.924)
		(stroke
			(width 0.05715)
			(type default)
		)
		(layer "B.Cu")
	)
	(gr_line
		(start 422.365678 -153.325322)
		(end 422.656 -153.035)
		(stroke
			(width 0.05715)
			(type default)
		)
		(layer "B.Cu")
	)
	(gr_arc
		(start 422.41089 -149.69617)
		(mid 422.373852 -149.671341)
		(end 422.330118 -149.662642)
		(stroke
			(width 0.05715)
			(type default)
		)
		(layer "B.Cu")
	)
	(gr_line
		(start 422.41089 -149.69617)
		(end 422.70172 -149.987)
		(stroke
			(width 0.05715)
			(type default)
		)
		(layer "B.Cu")
	)
	(gr_line
		(start 422.411906 -149.387814)
		(end 422.70172 -149.098)
		(stroke
			(width 0.05715)
			(type default)
		)
		(layer "B.Cu")
	)
	(gr_line
		(start 422.455594 -155.61945)
		(end 422.798494 -155.61945)
		(stroke
			(width 0.05715)
			(type default)
		)
		(layer "B.Cu")
	)
	(gr_line
		(start 422.455594 -147.61845)
		(end 422.798494 -147.61845)
		(stroke
			(width 0.05715)
			(type default)
		)
		(layer "B.Cu")
	)
	(gr_line
		(start 422.461944 -151.5491)
		(end 422.804844 -151.5491)
		(stroke
			(width 0.05715)
			(type default)
		)
		(layer "B.Cu")
	)
	(gr_line
		(start 422.470834 -155.26385)
		(end 422.783254 -155.26385)
		(stroke
			(width 0.05715)
			(type default)
		)
		(layer "B.Cu")
	)
	(gr_line
		(start 422.470834 -147.26285)
		(end 422.783254 -147.26285)
		(stroke
			(width 0.05715)
			(type default)
		)
		(layer "B.Cu")
	)
	(gr_line
		(start 422.477184 -151.1935)
		(end 422.789604 -151.1935)
		(stroke
			(width 0.05715)
			(type default)
		)
		(layer "B.Cu")
	)
	(gr_arc
		(start 422.596818 -142.813786)
		(mid 422.540303 -142.7814)
		(end 422.47566 -142.7734)
		(stroke
			(width 0.05715)
			(type default)
		)
		(layer "B.Cu")
	)
	(gr_line
		(start 422.596818 -142.813786)
		(end 422.839388 -143.056102)
		(stroke
			(width 0.05715)
			(type default)
		)
		(layer "B.Cu")
	)
	(gr_line
		(start 422.664382 -143.384524)
		(end 422.664636 -143.384524)
		(stroke
			(width 0.05715)
			(type default)
		)
		(layer "B.Cu")
	)
	(gr_line
		(start 422.664382 -143.384524)
		(end 422.72585 -143.445992)
		(stroke
			(width 0.05715)
			(type default)
		)
		(layer "B.Cu")
	)
	(gr_arc
		(start 422.798494 -155.61945)
		(mid 422.861384 -155.602356)
		(end 422.912794 -155.5623)
		(stroke
			(width 0.05715)
			(type default)
		)
		(layer "B.Cu")
	)
	(gr_arc
		(start 422.798494 -147.61845)
		(mid 422.861408 -147.601393)
		(end 422.912794 -147.5613)
		(stroke
			(width 0.05715)
			(type default)
		)
		(layer "B.Cu")
	)
	(gr_arc
		(start 422.804844 -151.5491)
		(mid 422.867726 -151.531994)
		(end 422.919144 -151.49195)
		(stroke
			(width 0.05715)
			(type default)
		)
		(layer "B.Cu")
	)
	(gr_arc
		(start 422.879774 -143.177514)
		(mid 422.871805 -143.112744)
		(end 422.839388 -143.056102)
		(stroke
			(width 0.05715)
			(type default)
		)
		(layer "B.Cu")
	)
	(gr_arc
		(start 422.879774 -143.177514)
		(mid 422.887775 -143.242157)
		(end 422.92016 -143.298672)
		(stroke
			(width 0.05715)
			(type default)
		)
		(layer "B.Cu")
	)
	(gr_arc
		(start 423.027094 -155.50515)
		(mid 422.96418 -155.522207)
		(end 422.912794 -155.5623)
		(stroke
			(width 0.05715)
			(type default)
		)
		(layer "B.Cu")
	)
	(gr_arc
		(start 423.027094 -147.50415)
		(mid 422.964207 -147.521248)
		(end 422.912794 -147.5613)
		(stroke
			(width 0.05715)
			(type default)
		)
		(layer "B.Cu")
	)
	(gr_arc
		(start 423.033444 -151.4348)
		(mid 422.97053 -151.451857)
		(end 422.919144 -151.49195)
		(stroke
			(width 0.05715)
			(type default)
		)
		(layer "B.Cu")
	)
	(gr_line
		(start 423.545 -153.924)
		(end 423.854372 -153.614628)
		(stroke
			(width 0.05715)
			(type default)
		)
		(layer "B.Cu")
	)
	(gr_line
		(start 423.545 -153.035)
		(end 423.816272 -153.306272)
		(stroke
			(width 0.05715)
			(type default)
		)
		(layer "B.Cu")
	)
	(gr_line
		(start 423.59072 -149.987)
		(end 423.881042 -149.696678)
		(stroke
			(width 0.05715)
			(type default)
		)
		(layer "B.Cu")
	)
	(gr_line
		(start 423.59072 -149.098)
		(end 423.881042 -149.388322)
		(stroke
			(width 0.05715)
			(type default)
		)
		(layer "B.Cu")
	)
	(gr_arc
		(start 423.69613 -145.095214)
		(mid 423.752645 -145.127599)
		(end 423.817288 -145.1356)
		(stroke
			(width 0.05715)
			(type default)
		)
		(layer "B.Cu")
	)
	(gr_line
		(start 423.697908 -145.438368)
		(end 423.918634 -145.659094)
		(stroke
			(width 0.05715)
			(type default)
		)
		(layer "B.Cu")
	)
	(gr_arc
		(start 423.816272 -153.306272)
		(mid 423.853331 -153.331034)
		(end 423.897044 -153.3398)
		(stroke
			(width 0.05715)
			(type default)
		)
		(layer "B.Cu")
	)
	(gr_arc
		(start 423.881042 -149.388322)
		(mid 423.918082 -149.413142)
		(end 423.961814 -149.42185)
		(stroke
			(width 0.05715)
			(type default)
		)
		(layer "B.Cu")
	)
	(gr_arc
		(start 423.935144 -153.5811)
		(mid 423.891403 -153.589801)
		(end 423.854372 -153.614628)
		(stroke
			(width 0.05715)
			(type default)
		)
		(layer "B.Cu")
	)
	(gr_arc
		(start 423.9387 -145.175986)
		(mid 423.882068 -145.143547)
		(end 423.817288 -145.1356)
		(stroke
			(width 0.05715)
			(type default)
		)
		(layer "B.Cu")
	)
	(gr_line
		(start 423.9387 -145.175986)
		(end 424.181016 -145.418556)
		(stroke
			(width 0.05715)
			(type default)
		)
		(layer "B.Cu")
	)
	(gr_line
		(start 424.0784 -139.838176)
		(end 424.46575 -139.838176)
		(stroke
			(width 0.05715)
			(type default)
		)
		(layer "B.Cu")
	)
	(gr_line
		(start 424.18 -141.986)
		(end 424.530266 -142.336266)
		(stroke
			(width 0.05715)
			(type default)
		)
		(layer "B.Cu")
	)
	(gr_line
		(start 424.18 -141.097)
		(end 424.556174 -140.720826)
		(stroke
			(width 0.05715)
			(type default)
		)
		(layer "B.Cu")
	)
	(gr_arc
		(start 424.221402 -145.539714)
		(mid 424.213391 -145.475077)
		(end 424.181016 -145.418556)
		(stroke
			(width 0.05715)
			(type default)
		)
		(layer "B.Cu")
	)
	(gr_arc
		(start 424.221402 -145.539714)
		(mid 424.229403 -145.604357)
		(end 424.261788 -145.660872)
		(stroke
			(width 0.05715)
			(type default)
		)
		(layer "B.Cu")
	)
	(gr_arc
		(start 424.392344 -153.63825)
		(mid 424.340939 -153.598196)
		(end 424.278044 -153.5811)
		(stroke
			(width 0.05715)
			(type default)
		)
		(layer "B.Cu")
	)
	(gr_arc
		(start 424.392344 -153.63825)
		(mid 424.443736 -153.678341)
		(end 424.506644 -153.6954)
		(stroke
			(width 0.05715)
			(type default)
		)
		(layer "B.Cu")
	)
	(gr_line
		(start 424.506644 -153.6954)
		(end 424.849544 -153.6954)
		(stroke
			(width 0.05715)
			(type default)
		)
		(layer "B.Cu")
	)
	(gr_line
		(start 424.521884 -153.3398)
		(end 424.834304 -153.3398)
		(stroke
			(width 0.05715)
			(type default)
		)
		(layer "B.Cu")
	)
	(gr_arc
		(start 424.556174 -140.720826)
		(mid 424.583607 -140.679675)
		(end 424.593258 -140.631164)
		(stroke
			(width 0.05715)
			(type default)
		)
		(layer "B.Cu")
	)
	(gr_arc
		(start 424.56735 -142.425928)
		(mid 424.557717 -142.37741)
		(end 424.530266 -142.336266)
		(stroke
			(width 0.05715)
			(type default)
		)
		(layer "B.Cu")
	)
	(gr_arc
		(start 424.59275 -139.965176)
		(mid 424.555553 -139.875373)
		(end 424.46575 -139.838176)
		(stroke
			(width 0.05715)
			(type default)
		)
		(layer "B.Cu")
	)
	(gr_arc
		(start 424.834558 -140.68298)
		(mid 424.844209 -140.731489)
		(end 424.871642 -140.772642)
		(stroke
			(width 0.05715)
			(type default)
		)
		(layer "B.Cu")
	)
	(gr_arc
		(start 424.845734 -142.336266)
		(mid 424.818278 -142.377411)
		(end 424.80865 -142.425928)
		(stroke
			(width 0.05715)
			(type default)
		)
		(layer "B.Cu")
	)
	(gr_line
		(start 424.845734 -142.336266)
		(end 425.196 -141.986)
		(stroke
			(width 0.05715)
			(type default)
		)
		(layer "B.Cu")
	)
	(gr_arc
		(start 424.849544 -153.6954)
		(mid 424.912426 -153.678294)
		(end 424.963844 -153.63825)
		(stroke
			(width 0.05715)
			(type default)
		)
		(layer "B.Cu")
	)
	(gr_line
		(start 424.871642 -140.772642)
		(end 425.196 -141.097)
		(stroke
			(width 0.05715)
			(type default)
		)
		(layer "B.Cu")
	)
	(gr_arc
		(start 424.958764 -145.94078)
		(mid 425.021678 -145.923723)
		(end 425.073064 -145.88363)
		(stroke
			(width 0.05715)
			(type default)
		)
		(layer "B.Cu")
	)
	(gr_arc
		(start 424.96105 -139.838176)
		(mid 424.871207 -139.875354)
		(end 424.83405 -139.965176)
		(stroke
			(width 0.05715)
			(type default)
		)
		(layer "B.Cu")
	)
	(gr_line
		(start 424.96105 -139.838176)
		(end 425.3484 -139.838176)
		(stroke
			(width 0.05715)
			(type default)
		)
		(layer "B.Cu")
	)
	(gr_line
		(start 425.026074 -156.340048)
		(end 425.28998 -155.847034)
		(stroke
			(width 0.05715)
			(type default)
		)
		(layer "B.Cu")
	)
	(gr_line
		(start 425.026074 -152.539954)
		(end 425.28998 -152.04694)
		(stroke
			(width 0.05715)
			(type default)
		)
		(layer "B.Cu")
	)
	(gr_line
		(start 425.026074 -148.740114)
		(end 425.305728 -148.21789)
		(stroke
			(width 0.05715)
			(type default)
		)
		(layer "B.Cu")
	)
	(gr_line
		(start 425.026074 -144.94002)
		(end 425.183046 -144.646904)
		(stroke
			(width 0.05715)
			(type default)
		)
		(layer "B.Cu")
	)
	(gr_arc
		(start 425.078144 -153.5811)
		(mid 425.01523 -153.598157)
		(end 424.963844 -153.63825)
		(stroke
			(width 0.05715)
			(type default)
		)
		(layer "B.Cu")
	)
	(gr_arc
		(start 425.14647 -150.051516)
		(mid 425.095065 -150.011462)
		(end 425.03217 -149.994366)
		(stroke
			(width 0.05715)
			(type default)
		)
		(layer "B.Cu")
	)
	(gr_arc
		(start 425.14647 -150.051516)
		(mid 425.197861 -150.091607)
		(end 425.26077 -150.108666)
		(stroke
			(width 0.05715)
			(type default)
		)
		(layer "B.Cu")
	)
	(gr_arc
		(start 425.183046 -144.646904)
		(mid 425.200705 -144.471649)
		(end 425.08932 -144.335246)
		(stroke
			(width 0.05715)
			(type default)
		)
		(layer "B.Cu")
	)
	(gr_arc
		(start 425.187364 -145.82648)
		(mid 425.124478 -145.843582)
		(end 425.073064 -145.88363)
		(stroke
			(width 0.05715)
			(type default)
		)
		(layer "B.Cu")
	)
	(gr_line
		(start 425.187364 -145.82648)
		(end 425.530264 -145.82648)
		(stroke
			(width 0.05715)
			(type default)
		)
		(layer "B.Cu")
	)
	(gr_line
		(start 425.202604 -146.18208)
		(end 425.515024 -146.18208)
		(stroke
			(width 0.05715)
			(type default)
		)
		(layer "B.Cu")
	)
	(gr_arc
		(start 425.24299 -144.14373)
		(mid 425.238055 -144.14103)
		(end 425.233084 -144.138396)
		(stroke
			(width 0.05715)
			(type default)
		)
		(layer "B.Cu")
	)
	(gr_arc
		(start 425.24299 -144.14373)
		(mid 425.254491 -144.149464)
		(end 425.266358 -144.154398)
		(stroke
			(width 0.05715)
			(type default)
		)
		(layer "B.Cu")
	)
	(gr_line
		(start 425.26077 -150.108666)
		(end 425.60367 -150.108666)
		(stroke
			(width 0.05715)
			(type default)
		)
		(layer "B.Cu")
	)
	(gr_line
		(start 425.266358 -144.154398)
		(end 425.31411 -144.172178)
		(stroke
			(width 0.05715)
			(type default)
		)
		(layer "B.Cu")
	)
	(gr_line
		(start 425.27601 -149.753066)
		(end 425.58843 -149.753066)
		(stroke
			(width 0.05715)
			(type default)
		)
		(layer "B.Cu")
	)
	(gr_arc
		(start 425.28998 -155.847034)
		(mid 425.298554 -155.760066)
		(end 425.243244 -155.692348)
		(stroke
			(width 0.05715)
			(type default)
		)
		(layer "B.Cu")
	)
	(gr_arc
		(start 425.28998 -152.04694)
		(mid 425.298554 -151.959972)
		(end 425.243244 -151.892254)
		(stroke
			(width 0.05715)
			(type default)
		)
		(layer "B.Cu")
	)
	(gr_arc
		(start 425.305728 -148.21789)
		(mid 425.314401 -148.13077)
		(end 425.258738 -148.063204)
		(stroke
			(width 0.05715)
			(type default)
		)
		(layer "B.Cu")
	)
	(gr_arc
		(start 425.31411 -144.172178)
		(mid 425.402112 -144.171795)
		(end 425.468288 -144.113758)
		(stroke
			(width 0.05715)
			(type default)
		)
		(layer "B.Cu")
	)
	(gr_arc
		(start 425.35729 -155.479496)
		(mid 425.444424 -155.488242)
		(end 425.51223 -155.43276)
		(stroke
			(width 0.05715)
			(type default)
		)
		(layer "B.Cu")
	)
	(gr_arc
		(start 425.35729 -151.679402)
		(mid 425.444424 -151.688148)
		(end 425.51223 -151.632666)
		(stroke
			(width 0.05715)
			(type default)
		)
		(layer "B.Cu")
	)
	(gr_arc
		(start 425.372022 -147.849844)
		(mid 425.459417 -147.858552)
		(end 425.527978 -147.803616)
		(stroke
			(width 0.05715)
			(type default)
		)
		(layer "B.Cu")
	)
	(gr_line
		(start 425.468288 -144.113758)
		(end 425.775882 -143.539972)
		(stroke
			(width 0.05715)
			(type default)
		)
		(layer "B.Cu")
	)
	(gr_line
		(start 425.51223 -155.43276)
		(end 425.775882 -154.94)
		(stroke
			(width 0.05715)
			(type default)
		)
		(layer "B.Cu")
	)
	(gr_line
		(start 425.51223 -151.632666)
		(end 425.775882 -151.139906)
		(stroke
			(width 0.05715)
			(type default)
		)
		(layer "B.Cu")
	)
	(gr_line
		(start 425.527978 -147.803616)
		(end 425.775882 -147.340066)
		(stroke
			(width 0.05715)
			(type default)
		)
		(layer "B.Cu")
	)
	(gr_arc
		(start 425.60367 -150.108666)
		(mid 425.666567 -150.091581)
		(end 425.71797 -150.051516)
		(stroke
			(width 0.05715)
			(type default)
		)
		(layer "B.Cu")
	)
	(gr_arc
		(start 425.644564 -145.88363)
		(mid 425.593172 -145.843541)
		(end 425.530264 -145.82648)
		(stroke
			(width 0.05715)
			(type default)
		)
		(layer "B.Cu")
	)
	(gr_arc
		(start 425.644564 -145.88363)
		(mid 425.695969 -145.923684)
		(end 425.758864 -145.94078)
		(stroke
			(width 0.05715)
			(type default)
		)
		(layer "B.Cu")
	)
	(gr_arc
		(start 425.83227 -149.994366)
		(mid 425.769356 -150.011423)
		(end 425.71797 -150.051516)
		(stroke
			(width 0.05715)
			(type default)
		)
		(layer "B.Cu")
	)
	(gr_arc
		(start 425.929044 -30.489652)
		(mid 426.119009 -30.616538)
		(end 426.343064 -30.661102)
		(stroke
			(width 0.050038)
			(type default)
		)
		(layer "B.Cu")
	)
	(gr_line
		(start 426.056044 -33.728152)
		(end 426.11167 -33.632902)
		(stroke
			(width 0.050038)
			(type default)
		)
		(layer "B.Cu")
	)
	(gr_arc
		(start 426.056044 -33.022286)
		(mid 426.085728 -33.093948)
		(end 426.15739 -33.123632)
		(stroke
			(width 0.050038)
			(type default)
		)
		(layer "B.Cu")
	)
	(gr_line
		(start 426.056044 -32.928052)
		(end 426.056044 -33.022286)
		(stroke
			(width 0.050038)
			(type default)
		)
		(layer "B.Cu")
	)
	(gr_arc
		(start 426.202856 -33.580832)
		(mid 426.150357 -33.594776)
		(end 426.11167 -33.632902)
		(stroke
			(width 0.050038)
			(type default)
		)
		(layer "B.Cu")
	)
	(gr_arc
		(start 426.343064 -31.118302)
		(mid 426.118995 -31.162831)
		(end 425.929044 -31.289752)
		(stroke
			(width 0.050038)
			(type default)
		)
		(layer "B.Cu")
	)
	(gr_line
		(start 426.72 -142.0876)
		(end 427.070266 -142.437866)
		(stroke
			(width 0.05715)
			(type default)
		)
		(layer "B.Cu")
	)
	(gr_line
		(start 426.72 -141.1986)
		(end 427.070266 -140.848334)
		(stroke
			(width 0.05715)
			(type default)
		)
		(layer "B.Cu")
	)
	(gr_line
		(start 426.72 -139.838176)
		(end 427.10735 -139.838176)
		(stroke
			(width 0.05715)
			(type default)
		)
		(layer "B.Cu")
	)
	(gr_arc
		(start 427.070266 -140.848334)
		(mid 427.097699 -140.807183)
		(end 427.10735 -140.758672)
		(stroke
			(width 0.05715)
			(type default)
		)
		(layer "B.Cu")
	)
	(gr_arc
		(start 427.10735 -142.527528)
		(mid 427.097717 -142.47901)
		(end 427.070266 -142.437866)
		(stroke
			(width 0.05715)
			(type default)
		)
		(layer "B.Cu")
	)
	(gr_line
		(start 427.180502 -137.256266)
		(end 427.6979 -137.773664)
		(stroke
			(width 0.05715)
			(type default)
		)
		(layer "B.Cu")
	)
	(gr_line
		(start 427.23435 -140.31849)
		(end 427.23435 -140.330174)
		(stroke
			(width 0.05715)
			(type default)
		)
		(layer "B.Cu")
	)
	(gr_arc
		(start 427.23435 -139.965176)
		(mid 427.197153 -139.875373)
		(end 427.10735 -139.838176)
		(stroke
			(width 0.05715)
			(type default)
		)
		(layer "B.Cu")
	)
	(gr_line
		(start 427.276006 -156.340048)
		(end 427.54042 -155.847288)
		(stroke
			(width 0.05715)
			(type default)
		)
		(layer "B.Cu")
	)
	(gr_line
		(start 427.276006 -152.539954)
		(end 427.540166 -152.047702)
		(stroke
			(width 0.05715)
			(type default)
		)
		(layer "B.Cu")
	)
	(gr_line
		(start 427.276006 -148.740114)
		(end 427.53407 -148.258784)
		(stroke
			(width 0.05715)
			(type default)
		)
		(layer "B.Cu")
	)
	(gr_line
		(start 427.276006 -144.94002)
		(end 427.433232 -144.646904)
		(stroke
			(width 0.05715)
			(type default)
		)
		(layer "B.Cu")
	)
	(gr_arc
		(start 427.326298 -137.060686)
		(mid 427.382933 -137.093111)
		(end 427.44771 -137.101072)
		(stroke
			(width 0.05715)
			(type default)
		)
		(layer "B.Cu")
	)
	(gr_arc
		(start 427.34865 -140.758672)
		(mid 427.358298 -140.807183)
		(end 427.385734 -140.848334)
		(stroke
			(width 0.05715)
			(type default)
		)
		(layer "B.Cu")
	)
	(gr_line
		(start 427.34865 -140.55725)
		(end 427.34865 -140.568934)
		(stroke
			(width 0.05715)
			(type default)
		)
		(layer "B.Cu")
	)
	(gr_arc
		(start 427.385734 -142.437866)
		(mid 427.358301 -142.479017)
		(end 427.34865 -142.527528)
		(stroke
			(width 0.05715)
			(type default)
		)
		(layer "B.Cu")
	)
	(gr_line
		(start 427.385734 -142.437866)
		(end 427.736 -142.0876)
		(stroke
			(width 0.05715)
			(type default)
		)
		(layer "B.Cu")
	)
	(gr_line
		(start 427.385734 -140.848334)
		(end 427.736 -141.1986)
		(stroke
			(width 0.05715)
			(type default)
		)
		(layer "B.Cu")
	)
	(gr_arc
		(start 427.433232 -144.646904)
		(mid 427.450891 -144.471649)
		(end 427.339506 -144.335246)
		(stroke
			(width 0.05715)
			(type default)
		)
		(layer "B.Cu")
	)
	(gr_arc
		(start 427.493176 -144.14373)
		(mid 427.50467 -144.149481)
		(end 427.516544 -144.154398)
		(stroke
			(width 0.05715)
			(type default)
		)
		(layer "B.Cu")
	)
	(gr_line
		(start 427.516544 -144.154398)
		(end 427.564296 -144.172178)
		(stroke
			(width 0.05715)
			(type default)
		)
		(layer "B.Cu")
	)
	(gr_arc
		(start 427.53407 -148.258784)
		(mid 427.54358 -148.162254)
		(end 427.482254 -148.08708)
		(stroke
			(width 0.05715)
			(type default)
		)
		(layer "B.Cu")
	)
	(gr_arc
		(start 427.540166 -152.047702)
		(mid 427.548912 -151.960568)
		(end 427.49343 -151.892762)
		(stroke
			(width 0.05715)
			(type default)
		)
		(layer "B.Cu")
	)
	(gr_arc
		(start 427.54042 -155.847288)
		(mid 427.549166 -155.760154)
		(end 427.493684 -155.692348)
		(stroke
			(width 0.05715)
			(type default)
		)
		(layer "B.Cu")
	)
	(gr_arc
		(start 427.564296 -144.172178)
		(mid 427.652376 -144.171914)
		(end 427.718474 -144.113758)
		(stroke
			(width 0.05715)
			(type default)
		)
		(layer "B.Cu")
	)
	(gr_arc
		(start 427.568868 -137.141458)
		(mid 427.51235 -137.109095)
		(end 427.44771 -137.101072)
		(stroke
			(width 0.05715)
			(type default)
		)
		(layer "B.Cu")
	)
	(gr_line
		(start 427.568868 -137.141458)
		(end 427.811184 -137.384028)
		(stroke
			(width 0.05715)
			(type default)
		)
		(layer "B.Cu")
	)
	(gr_arc
		(start 427.595538 -147.87372)
		(mid 427.69236 -147.883503)
		(end 427.76775 -147.821904)
		(stroke
			(width 0.05715)
			(type default)
		)
		(layer "B.Cu")
	)
	(gr_arc
		(start 427.60265 -139.838176)
		(mid 427.512807 -139.875354)
		(end 427.47565 -139.965176)
		(stroke
			(width 0.05715)
			(type default)
		)
		(layer "B.Cu")
	)
	(gr_line
		(start 427.60265 -139.838176)
		(end 427.99 -139.838176)
		(stroke
			(width 0.05715)
			(type default)
		)
		(layer "B.Cu")
	)
	(gr_arc
		(start 427.606714 -151.679402)
		(mid 427.693879 -151.68822)
		(end 427.761654 -151.632666)
		(stroke
			(width 0.05715)
			(type default)
		)
		(layer "B.Cu")
	)
	(gr_arc
		(start 427.606968 -155.478988)
		(mid 427.694119 -155.487931)
		(end 427.761908 -155.432506)
		(stroke
			(width 0.05715)
			(type default)
		)
		(layer "B.Cu")
	)
	(gr_line
		(start 427.718474 -144.113758)
		(end 428.026068 -143.539972)
		(stroke
			(width 0.05715)
			(type default)
		)
		(layer "B.Cu")
	)
	(gr_line
		(start 427.761654 -151.632666)
		(end 428.026068 -151.139906)
		(stroke
			(width 0.05715)
			(type default)
		)
		(layer "B.Cu")
	)
	(gr_line
		(start 427.761908 -155.432506)
		(end 428.026068 -154.94)
		(stroke
			(width 0.05715)
			(type default)
		)
		(layer "B.Cu")
	)
	(gr_line
		(start 427.76775 -147.821904)
		(end 428.026068 -147.340066)
		(stroke
			(width 0.05715)
			(type default)
		)
		(layer "B.Cu")
	)
	(gr_arc
		(start 427.85157 -137.505186)
		(mid 427.843583 -137.440536)
		(end 427.811184 -137.384028)
		(stroke
			(width 0.05715)
			(type default)
		)
		(layer "B.Cu")
	)
	(gr_arc
		(start 427.85157 -137.505186)
		(mid 427.859686 -137.569859)
		(end 427.89221 -137.626344)
		(stroke
			(width 0.05715)
			(type default)
		)
		(layer "B.Cu")
	)
	(gr_line
		(start 427.986698 -138.062716)
		(end 428.506128 -138.5824)
		(stroke
			(width 0.05715)
			(type default)
		)
		(layer "B.Cu")
	)
	(gr_arc
		(start 428.134526 -137.868914)
		(mid 428.191012 -137.901434)
		(end 428.255684 -137.909554)
		(stroke
			(width 0.05715)
			(type default)
		)
		(layer "B.Cu")
	)
	(gr_arc
		(start 428.376842 -137.94994)
		(mid 428.320326 -137.917555)
		(end 428.255684 -137.909554)
		(stroke
			(width 0.05715)
			(type default)
		)
		(layer "B.Cu")
	)
	(gr_line
		(start 428.376842 -137.94994)
		(end 428.619412 -138.19251)
		(stroke
			(width 0.05715)
			(type default)
		)
		(layer "B.Cu")
	)
	(gr_arc
		(start 428.659798 -138.313668)
		(mid 428.651805 -138.24902)
		(end 428.619412 -138.19251)
		(stroke
			(width 0.05715)
			(type default)
		)
		(layer "B.Cu")
	)
	(gr_arc
		(start 428.659798 -138.313668)
		(mid 428.667799 -138.378311)
		(end 428.700184 -138.434826)
		(stroke
			(width 0.05715)
			(type default)
		)
		(layer "B.Cu")
	)
	(gr_line
		(start 429.795686 -140.422122)
		(end 429.795686 -140.734542)
		(stroke
			(width 0.05715)
			(type default)
		)
		(layer "B.Cu")
	)
	(gr_line
		(start 429.795686 -139.279122)
		(end 429.795686 -139.591542)
		(stroke
			(width 0.05715)
			(type default)
		)
		(layer "B.Cu")
	)
	(gr_line
		(start 429.795686 -138.136122)
		(end 429.795686 -138.448542)
		(stroke
			(width 0.05715)
			(type default)
		)
		(layer "B.Cu")
	)
	(gr_line
		(start 429.82007 -136.344914)
		(end 430.297336 -136.82218)
		(stroke
			(width 0.05715)
			(type default)
		)
		(layer "B.Cu")
	)
	(gr_arc
		(start 430.036986 -140.178282)
		(mid 430.054071 -140.24118)
		(end 430.094136 -140.292582)
		(stroke
			(width 0.05715)
			(type default)
		)
		(layer "B.Cu")
	)
	(gr_arc
		(start 430.036986 -139.035282)
		(mid 430.054071 -139.09818)
		(end 430.094136 -139.149582)
		(stroke
			(width 0.05715)
			(type default)
		)
		(layer "B.Cu")
	)
	(gr_arc
		(start 430.036986 -137.892282)
		(mid 430.054071 -137.95518)
		(end 430.094136 -138.006582)
		(stroke
			(width 0.05715)
			(type default)
		)
		(layer "B.Cu")
	)
	(gr_arc
		(start 430.074578 -137.625074)
		(mid 430.046879 -137.666309)
		(end 430.036986 -137.71499)
		(stroke
			(width 0.05715)
			(type default)
		)
		(layer "B.Cu")
	)
	(gr_arc
		(start 430.094136 -140.864082)
		(mid 430.05406 -140.915478)
		(end 430.036986 -140.978382)
		(stroke
			(width 0.05715)
			(type default)
		)
		(layer "B.Cu")
	)
	(gr_arc
		(start 430.094136 -140.864082)
		(mid 430.13419 -140.812677)
		(end 430.151286 -140.749782)
		(stroke
			(width 0.05715)
			(type default)
		)
		(layer "B.Cu")
	)
	(gr_arc
		(start 430.094136 -139.721082)
		(mid 430.05406 -139.772478)
		(end 430.036986 -139.835382)
		(stroke
			(width 0.05715)
			(type default)
		)
		(layer "B.Cu")
	)
	(gr_arc
		(start 430.094136 -139.721082)
		(mid 430.13419 -139.669677)
		(end 430.151286 -139.606782)
		(stroke
			(width 0.05715)
			(type default)
		)
		(layer "B.Cu")
	)
	(gr_arc
		(start 430.094136 -138.578082)
		(mid 430.05406 -138.629478)
		(end 430.036986 -138.692382)
		(stroke
			(width 0.05715)
			(type default)
		)
		(layer "B.Cu")
	)
	(gr_arc
		(start 430.094136 -138.578082)
		(mid 430.13419 -138.526677)
		(end 430.151286 -138.463782)
		(stroke
			(width 0.05715)
			(type default)
		)
		(layer "B.Cu")
	)
	(gr_arc
		(start 430.151286 -140.406882)
		(mid 430.134229 -140.343968)
		(end 430.094136 -140.292582)
		(stroke
			(width 0.05715)
			(type default)
		)
		(layer "B.Cu")
	)
	(gr_line
		(start 430.151286 -140.406882)
		(end 430.151286 -140.749782)
		(stroke
			(width 0.05715)
			(type default)
		)
		(layer "B.Cu")
	)
	(gr_arc
		(start 430.151286 -139.263882)
		(mid 430.134229 -139.200968)
		(end 430.094136 -139.149582)
		(stroke
			(width 0.05715)
			(type default)
		)
		(layer "B.Cu")
	)
	(gr_line
		(start 430.151286 -139.263882)
		(end 430.151286 -139.606782)
		(stroke
			(width 0.05715)
			(type default)
		)
		(layer "B.Cu")
	)
	(gr_arc
		(start 430.151286 -138.120882)
		(mid 430.134229 -138.057968)
		(end 430.094136 -138.006582)
		(stroke
			(width 0.05715)
			(type default)
		)
		(layer "B.Cu")
	)
	(gr_line
		(start 430.151286 -138.120882)
		(end 430.151286 -138.463782)
		(stroke
			(width 0.05715)
			(type default)
		)
		(layer "B.Cu")
	)
	(gr_arc
		(start 430.297082 -137.06094)
		(mid 430.324691 -137.019562)
		(end 430.33442 -136.97077)
		(stroke
			(width 0.05715)
			(type default)
		)
		(layer "B.Cu")
	)
	(gr_arc
		(start 430.33442 -136.911842)
		(mid 430.324775 -136.86333)
		(end 430.297336 -136.82218)
		(stroke
			(width 0.05715)
			(type default)
		)
		(layer "B.Cu")
	)
	(gr_arc
		(start 430.467262 -141.436598)
		(mid 430.515772 -141.426951)
		(end 430.556924 -141.399514)
		(stroke
			(width 0.05715)
			(type default)
		)
		(layer "B.Cu")
	)
	(gr_arc
		(start 430.46777 -137.231628)
		(mid 430.547686 -137.111931)
		(end 430.57572 -136.97077)
		(stroke
			(width 0.05715)
			(type default)
		)
		(layer "B.Cu")
	)
	(gr_line
		(start 430.556924 -141.399514)
		(end 430.85512 -141.101318)
		(stroke
			(width 0.05715)
			(type default)
		)
		(layer "B.Cu")
	)
	(gr_line
		(start 430.589944 -35.290252)
		(end 430.622456 -35.25774)
		(stroke
			(width 0.050038)
			(type default)
		)
		(layer "B.Cu")
	)
	(gr_arc
		(start 430.589944 -34.490152)
		(mid 430.826219 -34.594246)
		(end 431.081942 -34.629852)
		(stroke
			(width 0.050038)
			(type default)
		)
		(layer "B.Cu")
	)
	(gr_arc
		(start 430.630584 -141.714982)
		(mid 430.589439 -141.687521)
		(end 430.540922 -141.677898)
		(stroke
			(width 0.05715)
			(type default)
		)
		(layer "B.Cu")
	)
	(gr_line
		(start 430.630584 -141.714982)
		(end 430.85512 -141.939518)
		(stroke
			(width 0.05715)
			(type default)
		)
		(layer "B.Cu")
	)
	(gr_arc
		(start 431.006504 -142.6718)
		(mid 431.069418 -142.654743)
		(end 431.120804 -142.61465)
		(stroke
			(width 0.05715)
			(type default)
		)
		(layer "B.Cu")
	)
	(gr_arc
		(start 431.034444 -35.087052)
		(mid 430.811487 -35.131446)
		(end 430.622456 -35.25774)
		(stroke
			(width 0.050038)
			(type default)
		)
		(layer "B.Cu")
	)
	(gr_arc
		(start 431.09007 -136.344914)
		(mid 430.731629 -136.445716)
		(end 430.57572 -136.783826)
		(stroke
			(width 0.05715)
			(type default)
		)
		(layer "B.Cu")
	)
	(gr_arc
		(start 431.235104 -142.5575)
		(mid 431.172211 -142.574591)
		(end 431.120804 -142.61465)
		(stroke
			(width 0.05715)
			(type default)
		)
		(layer "B.Cu")
	)
	(gr_line
		(start 431.235104 -142.5575)
		(end 431.578004 -142.5575)
		(stroke
			(width 0.05715)
			(type default)
		)
		(layer "B.Cu")
	)
	(gr_line
		(start 431.250344 -142.9131)
		(end 431.562764 -142.9131)
		(stroke
			(width 0.05715)
			(type default)
		)
		(layer "B.Cu")
	)
	(gr_arc
		(start 431.692304 -142.61465)
		(mid 431.640908 -142.574575)
		(end 431.578004 -142.5575)
		(stroke
			(width 0.05715)
			(type default)
		)
		(layer "B.Cu")
	)
	(gr_arc
		(start 431.692304 -142.61465)
		(mid 431.743709 -142.654704)
		(end 431.806604 -142.6718)
		(stroke
			(width 0.05715)
			(type default)
		)
		(layer "B.Cu")
	)
	(gr_line
		(start 431.74412 -141.939518)
		(end 431.950876 -141.732762)
		(stroke
			(width 0.05715)
			(type default)
		)
		(layer "B.Cu")
	)
	(gr_line
		(start 431.74412 -141.101318)
		(end 432.022758 -141.379956)
		(stroke
			(width 0.05715)
			(type default)
		)
		(layer "B.Cu")
	)
	(gr_line
		(start 431.888392 -138.844782)
		(end 432.412394 -138.844782)
		(stroke
			(width 0.05715)
			(type default)
		)
		(layer "B.Cu")
	)
	(gr_arc
		(start 432.022758 -141.379956)
		(mid 432.105139 -141.435043)
		(end 432.202336 -141.454378)
		(stroke
			(width 0.05715)
			(type default)
		)
		(layer "B.Cu")
	)
	(gr_arc
		(start 432.040538 -141.695678)
		(mid 431.992026 -141.705324)
		(end 431.950876 -141.732762)
		(stroke
			(width 0.05715)
			(type default)
		)
		(layer "B.Cu")
	)
	(gr_arc
		(start 432.539394 -139.124182)
		(mid 432.567464 -139.265207)
		(end 432.647344 -139.384786)
		(stroke
			(width 0.05715)
			(type default)
		)
		(layer "B.Cu")
	)
	(gr_arc
		(start 432.539394 -138.971782)
		(mid 432.50219 -138.881993)
		(end 432.412394 -138.844782)
		(stroke
			(width 0.05715)
			(type default)
		)
		(layer "B.Cu")
	)
	(gr_arc
		(start 432.780948 -139.124182)
		(mid 432.790535 -139.172837)
		(end 432.818032 -139.214098)
		(stroke
			(width 0.05715)
			(type default)
		)
		(layer "B.Cu")
	)
	(gr_arc
		(start 432.907694 -138.844782)
		(mid 432.817889 -138.88198)
		(end 432.780694 -138.971782)
		(stroke
			(width 0.05715)
			(type default)
		)
		(layer "B.Cu")
	)
	(gr_line
		(start 432.907694 -138.844782)
		(end 433.158392 -138.844782)
		(stroke
			(width 0.05715)
			(type default)
		)
		(layer "B.Cu")
	)
	(gr_arc
		(start 432.920394 -141.695678)
		(mid 433.227519 -141.568463)
		(end 433.354734 -141.261338)
		(stroke
			(width 0.05715)
			(type default)
		)
		(layer "B.Cu")
	)
	(gr_arc
		(start 432.920394 -141.454378)
		(mid 433.056911 -141.397842)
		(end 433.113434 -141.261338)
		(stroke
			(width 0.05715)
			(type default)
		)
		(layer "B.Cu")
	)
	(gr_arc
		(start 432.999134 -140.87729)
		(mid 433.016191 -140.940204)
		(end 433.056284 -140.99159)
		(stroke
			(width 0.05715)
			(type default)
		)
		(layer "B.Cu")
	)
	(gr_line
		(start 432.999134 -140.53439)
		(end 432.999134 -140.87729)
		(stroke
			(width 0.05715)
			(type default)
		)
		(layer "B.Cu")
	)
	(gr_arc
		(start 433.056284 -140.42009)
		(mid 433.01623 -140.471495)
		(end 432.999134 -140.53439)
		(stroke
			(width 0.05715)
			(type default)
		)
		(layer "B.Cu")
	)
	(gr_arc
		(start 433.056284 -140.42009)
		(mid 433.096401 -140.368706)
		(end 433.113434 -140.30579)
		(stroke
			(width 0.05715)
			(type default)
		)
		(layer "B.Cu")
	)
	(gr_arc
		(start 433.113434 -141.10589)
		(mid 433.096334 -141.043005)
		(end 433.056284 -140.99159)
		(stroke
			(width 0.05715)
			(type default)
		)
		(layer "B.Cu")
	)
	(gr_arc
		(start 433.113434 -139.903454)
		(mid 433.103794 -139.854938)
		(end 433.07635 -139.813792)
		(stroke
			(width 0.05715)
			(type default)
		)
		(layer "B.Cu")
	)
	(gr_line
		(start 433.354734 -140.54963)
		(end 433.354734 -140.86205)
		(stroke
			(width 0.05715)
			(type default)
		)
		(layer "B.Cu")
	)
	(gr_arc
		(start 433.354734 -139.9032)
		(mid 433.326802 -139.762507)
		(end 433.247292 -139.643104)
		(stroke
			(width 0.05715)
			(type default)
		)
		(layer "B.Cu")
	)
	(gr_line
		(start 433.63007 -136.344914)
		(end 434.110892 -136.825736)
		(stroke
			(width 0.05715)
			(type default)
		)
		(layer "B.Cu")
	)
	(gr_arc
		(start 434.14442 -136.906508)
		(mid 434.135704 -136.862782)
		(end 434.110892 -136.825736)
		(stroke
			(width 0.05715)
			(type default)
		)
		(layer "B.Cu")
	)
	(gr_line
		(start 434.365654 -141.891512)
		(end 434.368194 -141.891512)
		(stroke
			(width 0.05715)
			(type default)
		)
		(layer "B.Cu")
	)
	(gr_line
		(start 434.365654 -141.002512)
		(end 434.719476 -140.64869)
		(stroke
			(width 0.05715)
			(type default)
		)
		(layer "B.Cu")
	)
	(gr_arc
		(start 434.419248 -136.825736)
		(mid 434.394442 -136.862783)
		(end 434.38572 -136.906508)
		(stroke
			(width 0.05715)
			(type default)
		)
		(layer "B.Cu")
	)
	(gr_line
		(start 434.419248 -136.825736)
		(end 434.90007 -136.344914)
		(stroke
			(width 0.05715)
			(type default)
		)
		(layer "B.Cu")
	)
	(gr_arc
		(start 434.719476 -140.64869)
		(mid 434.744238 -140.611631)
		(end 434.753004 -140.567918)
		(stroke
			(width 0.05715)
			(type default)
		)
		(layer "B.Cu")
	)
	(gr_arc
		(start 434.994304 -140.567918)
		(mid 435.003052 -140.611635)
		(end 435.027832 -140.64869)
		(stroke
			(width 0.05715)
			(type default)
		)
		(layer "B.Cu")
	)
	(gr_line
		(start 435.027832 -140.64869)
		(end 435.381654 -141.002512)
		(stroke
			(width 0.05715)
			(type default)
		)
		(layer "B.Cu")
	)
	(gr_arc
		(start 435.314852 -141.891512)
		(mid 435.065578 -141.994787)
		(end 434.9623 -142.244064)
		(stroke
			(width 0.05715)
			(type default)
		)
		(layer "B.Cu")
	)
	(gr_line
		(start 435.314852 -141.891512)
		(end 435.381654 -141.891512)
		(stroke
			(width 0.05715)
			(type default)
		)
		(layer "B.Cu")
	)
	(gr_arc
		(start 436.865776 -32.5882)
		(mid 437.329232 -32.495769)
		(end 437.721756 -32.2326)
		(stroke
			(width 0.050038)
			(type default)
		)
		(layer "B.Cu")
	)
	(gr_line
		(start 437.325516 -33.0454)
		(end 437.709056 -33.0454)
		(stroke
			(width 0.050038)
			(type default)
		)
		(layer "B.Cu")
	)
	(gr_arc
		(start 437.465978 -25.20315)
		(mid 437.54391 -25.1876)
		(end 437.609996 -25.14346)
		(stroke
			(width 0.050038)
			(type default)
		)
		(layer "B.Cu")
	)
	(gr_line
		(start 437.609996 -25.14346)
		(end 437.721756 -25.0317)
		(stroke
			(width 0.050038)
			(type default)
		)
		(layer "B.Cu")
	)
	(gr_line
		(start 437.709056 -33.0454)
		(end 437.721756 -33.0327)
		(stroke
			(width 0.050038)
			(type default)
		)
		(layer "B.Cu")
	)
	(gr_arc
		(start 437.721248 -25.831292)
		(mid 437.531868 -25.704792)
		(end 437.308498 -25.66035)
		(stroke
			(width 0.050038)
			(type default)
		)
		(layer "B.Cu")
	)
	(gr_line
		(start 437.721248 -25.831292)
		(end 437.721756 -25.8318)
		(stroke
			(width 0.050038)
			(type default)
		)
		(layer "B.Cu")
	)
	(gr_line
		(start 439.074306 -127.02159)
		(end 439.474356 -127.02159)
		(stroke
			(width 0.05715)
			(type default)
		)
		(layer "B.Cu")
	)
	(gr_line
		(start 439.265568 -124.52985)
		(end 439.27776 -124.577094)
		(stroke
			(width 0.05715)
			(type default)
		)
		(layer "B.Cu")
	)
	(gr_line
		(start 439.265568 -124.52985)
		(end 439.284872 -124.484892)
		(stroke
			(width 0.05715)
			(type default)
		)
		(layer "B.Cu")
	)
	(gr_line
		(start 439.474356 -127.02159)
		(end 439.53684 -126.959106)
		(stroke
			(width 0.05715)
			(type default)
		)
		(layer "B.Cu")
	)
	(gr_line
		(start 439.881772 -126.959106)
		(end 439.944256 -127.02159)
		(stroke
			(width 0.05715)
			(type default)
		)
		(layer "B.Cu")
	)
	(gr_line
		(start 439.944256 -127.02159)
		(end 440.344306 -127.02159)
		(stroke
			(width 0.05715)
			(type default)
		)
		(layer "B.Cu")
	)
	(gr_line
		(start 440.304936 -53.754274)
		(end 440.76747 -53.29174)
		(stroke
			(width 0.05715)
			(type default)
		)
		(layer "B.Cu")
	)
	(gr_line
		(start 440.325002 -49.981104)
		(end 440.443112 -49.862994)
		(stroke
			(width 0.05715)
			(type default)
		)
		(layer "B.Cu")
	)
	(gr_line
		(start 440.443112 -49.862994)
		(end 440.67095 -49.862994)
		(stroke
			(width 0.05715)
			(type default)
		)
		(layer "B.Cu")
	)
	(gr_line
		(start 440.4614 -52.703476)
		(end 440.733434 -52.97551)
		(stroke
			(width 0.05715)
			(type default)
		)
		(layer "B.Cu")
	)
	(gr_line
		(start 440.4614 -52.2986)
		(end 440.4614 -52.703476)
		(stroke
			(width 0.05715)
			(type default)
		)
		(layer "B.Cu")
	)
	(gr_line
		(start 440.4614 -51.063144)
		(end 440.4614 -51.4096)
		(stroke
			(width 0.05715)
			(type default)
		)
		(layer "B.Cu")
	)
	(gr_line
		(start 440.4614 -51.063144)
		(end 440.762644 -50.7619)
		(stroke
			(width 0.05715)
			(type default)
		)
		(layer "B.Cu")
	)
	(gr_line
		(start 440.67095 -49.862994)
		(end 440.750198 -49.942242)
		(stroke
			(width 0.05715)
			(type default)
		)
		(layer "B.Cu")
	)
	(gr_arc
		(start 440.992006 -30.159452)
		(mid 441.036038 -29.978977)
		(end 440.922156 -29.8323)
		(stroke
			(width 0.050038)
			(type default)
		)
		(layer "B.Cu")
	)
	(gr_line
		(start 441.078366 -52.97551)
		(end 441.3504 -52.703476)
		(stroke
			(width 0.05715)
			(type default)
		)
		(layer "B.Cu")
	)
	(gr_line
		(start 441.094876 -49.942242)
		(end 441.174124 -49.862994)
		(stroke
			(width 0.05715)
			(type default)
		)
		(layer "B.Cu")
	)
	(gr_line
		(start 441.107576 -50.7619)
		(end 441.3504 -51.004724)
		(stroke
			(width 0.05715)
			(type default)
		)
		(layer "B.Cu")
	)
	(gr_line
		(start 441.112402 -53.29174)
		(end 441.574936 -53.754274)
		(stroke
			(width 0.05715)
			(type default)
		)
		(layer "B.Cu")
	)
	(gr_line
		(start 441.174124 -49.862994)
		(end 441.476892 -49.862994)
		(stroke
			(width 0.05715)
			(type default)
		)
		(layer "B.Cu")
	)
	(gr_arc
		(start 441.34532 -30.449774)
		(mid 441.555421 -30.154243)
		(end 441.722256 -29.8323)
		(stroke
			(width 0.050038)
			(type default)
		)
		(layer "B.Cu")
	)
	(gr_line
		(start 441.3504 -52.2986)
		(end 441.3504 -52.703476)
		(stroke
			(width 0.05715)
			(type default)
		)
		(layer "B.Cu")
	)
	(gr_line
		(start 441.3504 -51.004724)
		(end 441.3504 -51.4096)
		(stroke
			(width 0.05715)
			(type default)
		)
		(layer "B.Cu")
	)
	(gr_line
		(start 441.476892 -49.862994)
		(end 441.595002 -49.981104)
		(stroke
			(width 0.05715)
			(type default)
		)
		(layer "B.Cu")
	)
	(gr_line
		(start 441.879736 -118.445026)
		(end 441.891674 -118.417594)
		(stroke
			(width 0.05715)
			(type default)
		)
		(layer "B.Cu")
	)
	(gr_line
		(start 441.891674 -118.417594)
		(end 441.914788 -118.400068)
		(stroke
			(width 0.05715)
			(type default)
		)
		(layer "B.Cu")
	)
	(gr_line
		(start 442.75375 -126.0856)
		(end 443.1538 -126.0856)
		(stroke
			(width 0.05715)
			(type default)
		)
		(layer "B.Cu")
	)
	(gr_line
		(start 442.764926 -114.403632)
		(end 443.140846 -114.403632)
		(stroke
			(width 0.05715)
			(type default)
		)
		(layer "B.Cu")
	)
	(gr_line
		(start 442.849 -116.49202)
		(end 443.184534 -116.827554)
		(stroke
			(width 0.05715)
			(type default)
		)
		(layer "B.Cu")
	)
	(gr_line
		(start 442.849 -115.60302)
		(end 443.184534 -115.267486)
		(stroke
			(width 0.05715)
			(type default)
		)
		(layer "B.Cu")
	)
	(gr_line
		(start 443.032134 -124.785374)
		(end 443.034674 -124.769372)
		(stroke
			(width 0.05715)
			(type default)
		)
		(layer "B.Cu")
	)
	(gr_line
		(start 443.032134 -124.785374)
		(end 443.036198 -124.800868)
		(stroke
			(width 0.05715)
			(type default)
		)
		(layer "B.Cu")
	)
	(gr_line
		(start 443.034674 -124.769118)
		(end 443.034674 -124.769372)
		(stroke
			(width 0.05715)
			(type default)
		)
		(layer "B.Cu")
	)
	(gr_line
		(start 443.140846 -114.403632)
		(end 443.215522 -114.478308)
		(stroke
			(width 0.05715)
			(type default)
		)
		(layer "B.Cu")
	)
	(gr_line
		(start 443.1538 -126.0856)
		(end 443.216284 -126.023116)
		(stroke
			(width 0.05715)
			(type default)
		)
		(layer "B.Cu")
	)
	(gr_line
		(start 443.227968 -117.703854)
		(end 443.236858 -117.696996)
		(stroke
			(width 0.05715)
			(type default)
		)
		(layer "B.Cu")
	)
	(gr_line
		(start 443.236858 -117.696996)
		(end 443.242192 -117.688106)
		(stroke
			(width 0.05715)
			(type default)
		)
		(layer "B.Cu")
	)
	(gr_line
		(start 443.291722 -123.173744)
		(end 443.29604 -123.147074)
		(stroke
			(width 0.05715)
			(type default)
		)
		(layer "B.Cu")
	)
	(gr_line
		(start 443.29604 -123.147074)
		(end 443.312804 -123.125484)
		(stroke
			(width 0.05715)
			(type default)
		)
		(layer "B.Cu")
	)
	(gr_line
		(start 443.459616 -117.33784)
		(end 443.47765 -117.30863)
		(stroke
			(width 0.05715)
			(type default)
		)
		(layer "B.Cu")
	)
	(gr_line
		(start 443.504828 -49.998122)
		(end 443.872874 -49.998122)
		(stroke
			(width 0.05715)
			(type default)
		)
		(layer "B.Cu")
	)
	(gr_line
		(start 443.51575 -53.754274)
		(end 443.978284 -53.29174)
		(stroke
			(width 0.05715)
			(type default)
		)
		(layer "B.Cu")
	)
	(gr_line
		(start 443.529466 -116.827554)
		(end 443.865 -116.49202)
		(stroke
			(width 0.05715)
			(type default)
		)
		(layer "B.Cu")
	)
	(gr_line
		(start 443.529466 -115.267486)
		(end 443.865 -115.60302)
		(stroke
			(width 0.05715)
			(type default)
		)
		(layer "B.Cu")
	)
	(gr_line
		(start 443.5602 -114.478308)
		(end 443.634876 -114.403632)
		(stroke
			(width 0.05715)
			(type default)
		)
		(layer "B.Cu")
	)
	(gr_line
		(start 443.561216 -126.023116)
		(end 443.6237 -126.0856)
		(stroke
			(width 0.05715)
			(type default)
		)
		(layer "B.Cu")
	)
	(gr_line
		(start 443.6237 -126.0856)
		(end 444.02375 -126.0856)
		(stroke
			(width 0.05715)
			(type default)
		)
		(layer "B.Cu")
	)
	(gr_line
		(start 443.633606 -52.74691)
		(end 443.747906 -52.86121)
		(stroke
			(width 0.05715)
			(type default)
		)
		(layer "B.Cu")
	)
	(gr_line
		(start 443.633606 -52.342034)
		(end 443.633606 -52.74691)
		(stroke
			(width 0.05715)
			(type default)
		)
		(layer "B.Cu")
	)
	(gr_line
		(start 443.633606 -51.048158)
		(end 443.633606 -51.453034)
		(stroke
			(width 0.05715)
			(type default)
		)
		(layer "B.Cu")
	)
	(gr_line
		(start 443.633606 -51.048158)
		(end 443.747906 -50.933858)
		(stroke
			(width 0.05715)
			(type default)
		)
		(layer "B.Cu")
	)
	(gr_line
		(start 443.634876 -114.403632)
		(end 444.034926 -114.403632)
		(stroke
			(width 0.05715)
			(type default)
		)
		(layer "B.Cu")
	)
	(gr_line
		(start 443.747906 -52.86121)
		(end 443.906656 -52.86121)
		(stroke
			(width 0.05715)
			(type default)
		)
		(layer "B.Cu")
	)
	(gr_line
		(start 443.747906 -50.933858)
		(end 443.872874 -50.933858)
		(stroke
			(width 0.05715)
			(type default)
		)
		(layer "B.Cu")
	)
	(gr_line
		(start 443.872874 -50.933858)
		(end 443.952376 -50.854356)
		(stroke
			(width 0.05715)
			(type default)
		)
		(layer "B.Cu")
	)
	(gr_line
		(start 443.872874 -49.998122)
		(end 443.94628 -50.071528)
		(stroke
			(width 0.05715)
			(type default)
		)
		(layer "B.Cu")
	)
	(gr_line
		(start 443.906656 -52.86121)
		(end 443.96914 -52.923694)
		(stroke
			(width 0.05715)
			(type default)
		)
		(layer "B.Cu")
	)
	(gr_line
		(start 444.290958 -50.071528)
		(end 444.364364 -49.998122)
		(stroke
			(width 0.05715)
			(type default)
		)
		(layer "B.Cu")
	)
	(gr_line
		(start 444.297054 -50.854356)
		(end 444.376556 -50.933858)
		(stroke
			(width 0.05715)
			(type default)
		)
		(layer "B.Cu")
	)
	(gr_line
		(start 444.314072 -52.923694)
		(end 444.376556 -52.86121)
		(stroke
			(width 0.05715)
			(type default)
		)
		(layer "B.Cu")
	)
	(gr_line
		(start 444.323216 -53.29174)
		(end 444.78575 -53.754274)
		(stroke
			(width 0.05715)
			(type default)
		)
		(layer "B.Cu")
	)
	(gr_line
		(start 444.364364 -49.998122)
		(end 444.774828 -49.998122)
		(stroke
			(width 0.05715)
			(type default)
		)
		(layer "B.Cu")
	)
	(gr_line
		(start 444.376556 -52.86121)
		(end 444.535306 -52.86121)
		(stroke
			(width 0.05715)
			(type default)
		)
		(layer "B.Cu")
	)
	(gr_line
		(start 444.376556 -50.933858)
		(end 444.535306 -50.933858)
		(stroke
			(width 0.05715)
			(type default)
		)
		(layer "B.Cu")
	)
	(gr_line
		(start 444.535306 -52.86121)
		(end 444.649606 -52.74691)
		(stroke
			(width 0.05715)
			(type default)
		)
		(layer "B.Cu")
	)
	(gr_line
		(start 444.535306 -50.933858)
		(end 444.649606 -51.048158)
		(stroke
			(width 0.05715)
			(type default)
		)
		(layer "B.Cu")
	)
	(gr_line
		(start 444.649606 -52.342034)
		(end 444.649606 -52.74691)
		(stroke
			(width 0.05715)
			(type default)
		)
		(layer "B.Cu")
	)
	(gr_line
		(start 444.649606 -51.048158)
		(end 444.649606 -51.453034)
		(stroke
			(width 0.05715)
			(type default)
		)
		(layer "B.Cu")
	)
	(gr_line
		(start 444.703454 -121.74093)
		(end 444.712344 -121.7295)
		(stroke
			(width 0.05715)
			(type default)
		)
		(layer "B.Cu")
	)
	(gr_line
		(start 444.712344 -121.7295)
		(end 444.716154 -121.715784)
		(stroke
			(width 0.05715)
			(type default)
		)
		(layer "B.Cu")
	)
	(gr_line
		(start 445.40805 -126.087124)
		(end 445.8081 -126.087124)
		(stroke
			(width 0.05715)
			(type default)
		)
		(layer "B.Cu")
	)
	(gr_line
		(start 445.44234 -118.169436)
		(end 445.455548 -118.121684)
		(stroke
			(width 0.05715)
			(type default)
		)
		(layer "B.Cu")
	)
	(gr_line
		(start 445.455548 -118.121684)
		(end 445.495172 -118.092982)
		(stroke
			(width 0.05715)
			(type default)
		)
		(layer "B.Cu")
	)
	(gr_line
		(start 445.8081 -126.087124)
		(end 445.870584 -126.02464)
		(stroke
			(width 0.05715)
			(type default)
		)
		(layer "B.Cu")
	)
	(gr_circle
		(center 445.897 -40.1828)
		(end 446.151 -40.1828)
		(stroke
			(width 0.2)
			(type default)
		)
		(fill no)
		(layer "B.Cu")
	)
	(gr_line
		(start 445.9224 -125.129798)
		(end 445.927226 -125.118622)
		(stroke
			(width 0.05715)
			(type default)
		)
		(layer "B.Cu")
	)
	(gr_line
		(start 445.964818 -114.403632)
		(end 446.323212 -114.403632)
		(stroke
			(width 0.05715)
			(type default)
		)
		(layer "B.Cu")
	)
	(gr_line
		(start 446.024 -116.49202)
		(end 446.359534 -116.827554)
		(stroke
			(width 0.05715)
			(type default)
		)
		(layer "B.Cu")
	)
	(gr_line
		(start 446.024 -115.60302)
		(end 446.359534 -115.267486)
		(stroke
			(width 0.05715)
			(type default)
		)
		(layer "B.Cu")
	)
	(gr_line
		(start 446.215516 -126.02464)
		(end 446.278 -126.087124)
		(stroke
			(width 0.05715)
			(type default)
		)
		(layer "B.Cu")
	)
	(gr_line
		(start 446.278 -126.087124)
		(end 446.67805 -126.087124)
		(stroke
			(width 0.05715)
			(type default)
		)
		(layer "B.Cu")
	)
	(gr_line
		(start 446.323212 -114.403632)
		(end 446.406524 -114.486944)
		(stroke
			(width 0.05715)
			(type default)
		)
		(layer "B.Cu")
	)
	(gr_line
		(start 446.332102 -120.471946)
		(end 446.3415 -120.515888)
		(stroke
			(width 0.05715)
			(type default)
		)
		(layer "B.Cu")
	)
	(gr_line
		(start 446.332102 -120.471946)
		(end 446.350644 -120.431052)
		(stroke
			(width 0.05715)
			(type default)
		)
		(layer "B.Cu")
	)
	(gr_line
		(start 446.350644 -120.430798)
		(end 446.350898 -120.430036)
		(stroke
			(width 0.05715)
			(type default)
		)
		(layer "B.Cu")
	)
	(gr_line
		(start 446.398396 -117.73154)
		(end 446.411604 -117.721888)
		(stroke
			(width 0.05715)
			(type default)
		)
		(layer "B.Cu")
	)
	(gr_circle
		(center 446.405 -38.608)
		(end 446.659 -38.608)
		(stroke
			(width 0.2)
			(type default)
		)
		(fill no)
		(layer "B.Cu")
	)
	(gr_line
		(start 446.411604 -117.721888)
		(end 446.419732 -117.707664)
		(stroke
			(width 0.05715)
			(type default)
		)
		(layer "B.Cu")
	)
	(gr_line
		(start 446.637664 -117.33022)
		(end 446.65265 -117.304566)
		(stroke
			(width 0.05715)
			(type default)
		)
		(layer "B.Cu")
	)
	(gr_line
		(start 446.701672 -49.998122)
		(end 447.09461 -49.998122)
		(stroke
			(width 0.05715)
			(type default)
		)
		(layer "B.Cu")
	)
	(gr_line
		(start 446.704466 -116.827554)
		(end 447.04 -116.49202)
		(stroke
			(width 0.05715)
			(type default)
		)
		(layer "B.Cu")
	)
	(gr_line
		(start 446.704466 -115.267486)
		(end 447.04 -115.60302)
		(stroke
			(width 0.05715)
			(type default)
		)
		(layer "B.Cu")
	)
	(gr_line
		(start 446.71615 -53.754274)
		(end 447.178684 -53.29174)
		(stroke
			(width 0.05715)
			(type default)
		)
		(layer "B.Cu")
	)
	(gr_line
		(start 446.73266 -119.589042)
		(end 446.743836 -119.56415)
		(stroke
			(width 0.05715)
			(type default)
		)
		(layer "B.Cu")
	)
	(gr_line
		(start 446.743836 -119.56415)
		(end 446.765934 -119.547386)
		(stroke
			(width 0.05715)
			(type default)
		)
		(layer "B.Cu")
	)
	(gr_line
		(start 446.751456 -114.486944)
		(end 446.834768 -114.403632)
		(stroke
			(width 0.05715)
			(type default)
		)
		(layer "B.Cu")
	)
	(gr_line
		(start 446.834768 -114.403632)
		(end 447.234818 -114.403632)
		(stroke
			(width 0.05715)
			(type default)
		)
		(layer "B.Cu")
	)
	(gr_line
		(start 446.912238 -52.811934)
		(end 447.026538 -52.926234)
		(stroke
			(width 0.05715)
			(type default)
		)
		(layer "B.Cu")
	)
	(gr_line
		(start 446.912238 -52.407058)
		(end 446.912238 -52.811934)
		(stroke
			(width 0.05715)
			(type default)
		)
		(layer "B.Cu")
	)
	(gr_line
		(start 446.912238 -51.113182)
		(end 446.912238 -51.518058)
		(stroke
			(width 0.05715)
			(type default)
		)
		(layer "B.Cu")
	)
	(gr_line
		(start 446.912238 -51.113182)
		(end 447.026538 -50.998882)
		(stroke
			(width 0.05715)
			(type default)
		)
		(layer "B.Cu")
	)
	(gr_line
		(start 447.026538 -52.926234)
		(end 447.185288 -52.926234)
		(stroke
			(width 0.05715)
			(type default)
		)
		(layer "B.Cu")
	)
	(gr_line
		(start 447.026538 -50.998882)
		(end 447.185288 -50.998882)
		(stroke
			(width 0.05715)
			(type default)
		)
		(layer "B.Cu")
	)
	(gr_line
		(start 447.087498 -122.942096)
		(end 447.103246 -122.903996)
		(stroke
			(width 0.05715)
			(type default)
		)
		(layer "B.Cu")
	)
	(gr_line
		(start 447.094356 -122.863102)
		(end 447.103246 -122.903996)
		(stroke
			(width 0.05715)
			(type default)
		)
		(layer "B.Cu")
	)
	(gr_line
		(start 447.09461 -49.998122)
		(end 447.169794 -50.073306)
		(stroke
			(width 0.05715)
			(type default)
		)
		(layer "B.Cu")
	)
	(gr_line
		(start 447.185288 -52.926234)
		(end 447.247772 -52.988718)
		(stroke
			(width 0.05715)
			(type default)
		)
		(layer "B.Cu")
	)
	(gr_line
		(start 447.185288 -50.998882)
		(end 447.247772 -50.936398)
		(stroke
			(width 0.05715)
			(type default)
		)
		(layer "B.Cu")
	)
	(gr_line
		(start 447.284348 -50.587402)
		(end 447.284348 -50.650648)
		(stroke
			(width 0.05715)
			(type default)
		)
		(layer "B.Cu")
	)
	(gr_line
		(start 447.45021 -50.348642)
		(end 447.45021 -50.411888)
		(stroke
			(width 0.05715)
			(type default)
		)
		(layer "B.Cu")
	)
	(gr_line
		(start 447.514726 -50.073306)
		(end 447.58991 -49.998122)
		(stroke
			(width 0.05715)
			(type default)
		)
		(layer "B.Cu")
	)
	(gr_line
		(start 447.523616 -53.29174)
		(end 447.98615 -53.754274)
		(stroke
			(width 0.05715)
			(type default)
		)
		(layer "B.Cu")
	)
	(gr_line
		(start 447.58991 -49.998122)
		(end 447.971672 -49.998122)
		(stroke
			(width 0.05715)
			(type default)
		)
		(layer "B.Cu")
	)
	(gr_line
		(start 447.592704 -52.988718)
		(end 447.655188 -52.926234)
		(stroke
			(width 0.05715)
			(type default)
		)
		(layer "B.Cu")
	)
	(gr_line
		(start 447.592704 -50.936398)
		(end 447.655188 -50.998882)
		(stroke
			(width 0.05715)
			(type default)
		)
		(layer "B.Cu")
	)
	(gr_line
		(start 447.655188 -52.926234)
		(end 447.813938 -52.926234)
		(stroke
			(width 0.05715)
			(type default)
		)
		(layer "B.Cu")
	)
	(gr_line
		(start 447.655188 -50.998882)
		(end 447.813938 -50.998882)
		(stroke
			(width 0.05715)
			(type default)
		)
		(layer "B.Cu")
	)
	(gr_line
		(start 447.813938 -52.926234)
		(end 447.928238 -52.811934)
		(stroke
			(width 0.05715)
			(type default)
		)
		(layer "B.Cu")
	)
	(gr_line
		(start 447.813938 -50.998882)
		(end 447.928238 -51.113182)
		(stroke
			(width 0.05715)
			(type default)
		)
		(layer "B.Cu")
	)
	(gr_line
		(start 447.928238 -52.407058)
		(end 447.928238 -52.811934)
		(stroke
			(width 0.05715)
			(type default)
		)
		(layer "B.Cu")
	)
	(gr_line
		(start 447.928238 -51.113182)
		(end 447.928238 -51.518058)
		(stroke
			(width 0.05715)
			(type default)
		)
		(layer "B.Cu")
	)
	(gr_line
		(start 448.39255 -123.78817)
		(end 448.7926 -123.78817)
		(stroke
			(width 0.05715)
			(type default)
		)
		(layer "B.Cu")
	)
	(gr_line
		(start 448.7926 -123.78817)
		(end 448.855084 -123.725686)
		(stroke
			(width 0.05715)
			(type default)
		)
		(layer "B.Cu")
	)
	(gr_line
		(start 448.9069 -123.239784)
		(end 448.91325 -123.225306)
		(stroke
			(width 0.05715)
			(type default)
		)
		(layer "B.Cu")
	)
	(gr_line
		(start 449.164964 -114.403632)
		(end 449.533772 -114.403632)
		(stroke
			(width 0.05715)
			(type default)
		)
		(layer "B.Cu")
	)
	(gr_line
		(start 449.199 -116.49202)
		(end 449.534534 -116.827554)
		(stroke
			(width 0.05715)
			(type default)
		)
		(layer "B.Cu")
	)
	(gr_line
		(start 449.199 -115.60302)
		(end 449.645532 -115.156488)
		(stroke
			(width 0.05715)
			(type default)
		)
		(layer "B.Cu")
	)
	(gr_line
		(start 449.200016 -123.725686)
		(end 449.2625 -123.78817)
		(stroke
			(width 0.05715)
			(type default)
		)
		(layer "B.Cu")
	)
	(gr_line
		(start 449.2625 -123.78817)
		(end 449.66255 -123.78817)
		(stroke
			(width 0.05715)
			(type default)
		)
		(layer "B.Cu")
	)
	(gr_line
		(start 449.490592 -120.129046)
		(end 449.508626 -120.196102)
		(stroke
			(width 0.05715)
			(type default)
		)
		(layer "B.Cu")
	)
	(gr_line
		(start 449.490592 -120.129046)
		(end 449.527168 -120.070118)
		(stroke
			(width 0.05715)
			(type default)
		)
		(layer "B.Cu")
	)
	(gr_line
		(start 449.512436 -117.774212)
		(end 449.5165 -117.771418)
		(stroke
			(width 0.05715)
			(type default)
		)
		(layer "B.Cu")
	)
	(gr_line
		(start 449.5165 -117.771418)
		(end 449.519802 -117.766592)
		(stroke
			(width 0.05715)
			(type default)
		)
		(layer "B.Cu")
	)
	(gr_line
		(start 449.527168 -120.06961)
		(end 449.527168 -120.069864)
		(stroke
			(width 0.05715)
			(type default)
		)
		(layer "B.Cu")
	)
	(gr_line
		(start 449.533772 -114.403632)
		(end 449.612004 -114.481864)
		(stroke
			(width 0.05715)
			(type default)
		)
		(layer "B.Cu")
	)
	(gr_line
		(start 449.805552 -117.346984)
		(end 449.82765 -117.314218)
		(stroke
			(width 0.05715)
			(type default)
		)
		(layer "B.Cu")
	)
	(gr_line
		(start 449.879466 -116.827554)
		(end 450.215 -116.49202)
		(stroke
			(width 0.05715)
			(type default)
		)
		(layer "B.Cu")
	)
	(gr_line
		(start 449.889372 -115.277392)
		(end 450.215 -115.60302)
		(stroke
			(width 0.05715)
			(type default)
		)
		(layer "B.Cu")
	)
	(gr_line
		(start 449.895214 -49.997614)
		(end 450.295264 -49.997614)
		(stroke
			(width 0.05715)
			(type default)
		)
		(layer "B.Cu")
	)
	(gr_line
		(start 449.91655 -53.754274)
		(end 450.3547 -53.316124)
		(stroke
			(width 0.05715)
			(type default)
		)
		(layer "B.Cu")
	)
	(gr_line
		(start 449.949316 -119.38762)
		(end 449.958714 -119.372634)
		(stroke
			(width 0.05715)
			(type default)
		)
		(layer "B.Cu")
	)
	(gr_line
		(start 449.956682 -114.481864)
		(end 450.034914 -114.403632)
		(stroke
			(width 0.05715)
			(type default)
		)
		(layer "B.Cu")
	)
	(gr_line
		(start 449.958714 -119.372634)
		(end 449.972684 -119.36349)
		(stroke
			(width 0.05715)
			(type default)
		)
		(layer "B.Cu")
	)
	(gr_line
		(start 449.96735 -52.811934)
		(end 450.08165 -52.926234)
		(stroke
			(width 0.05715)
			(type default)
		)
		(layer "B.Cu")
	)
	(gr_line
		(start 449.96735 -52.407058)
		(end 449.96735 -52.811934)
		(stroke
			(width 0.05715)
			(type default)
		)
		(layer "B.Cu")
	)
	(gr_line
		(start 449.96735 -51.113182)
		(end 449.96735 -51.518058)
		(stroke
			(width 0.05715)
			(type default)
		)
		(layer "B.Cu")
	)
	(gr_line
		(start 449.96735 -51.113182)
		(end 450.08165 -50.998882)
		(stroke
			(width 0.05715)
			(type default)
		)
		(layer "B.Cu")
	)
	(gr_line
		(start 450.02196 -121.30278)
		(end 450.042026 -121.25706)
		(stroke
			(width 0.05715)
			(type default)
		)
		(layer "B.Cu")
	)
	(gr_line
		(start 450.029072 -121.209054)
		(end 450.042026 -121.25706)
		(stroke
			(width 0.05715)
			(type default)
		)
		(layer "B.Cu")
	)
	(gr_line
		(start 450.034914 -114.403632)
		(end 450.434964 -114.403632)
		(stroke
			(width 0.05715)
			(type default)
		)
		(layer "B.Cu")
	)
	(gr_circle
		(center 450.0626 -43.18)
		(end 450.3166 -43.18)
		(stroke
			(width 0.2)
			(type default)
		)
		(fill no)
		(layer "B.Cu")
	)
	(gr_circle
		(center 450.0626 -42.545)
		(end 450.3166 -42.545)
		(stroke
			(width 0.2)
			(type default)
		)
		(fill no)
		(layer "B.Cu")
	)
	(gr_circle
		(center 450.0626 -41.91)
		(end 450.3166 -41.91)
		(stroke
			(width 0.2)
			(type default)
		)
		(fill no)
		(layer "B.Cu")
	)
	(gr_line
		(start 450.08165 -52.926234)
		(end 450.2404 -52.926234)
		(stroke
			(width 0.05715)
			(type default)
		)
		(layer "B.Cu")
	)
	(gr_line
		(start 450.08165 -50.998882)
		(end 450.2404 -50.998882)
		(stroke
			(width 0.05715)
			(type default)
		)
		(layer "B.Cu")
	)
	(gr_circle
		(center 450.149722 -41.283128)
		(end 450.403722 -41.283128)
		(stroke
			(width 0.2)
			(type default)
		)
		(fill no)
		(layer "B.Cu")
	)
	(gr_line
		(start 450.2404 -52.926234)
		(end 450.302884 -52.988718)
		(stroke
			(width 0.05715)
			(type default)
		)
		(layer "B.Cu")
	)
	(gr_line
		(start 450.2404 -50.998882)
		(end 450.335904 -50.903378)
		(stroke
			(width 0.05715)
			(type default)
		)
		(layer "B.Cu")
	)
	(gr_line
		(start 450.295264 -49.997614)
		(end 450.363336 -50.065686)
		(stroke
			(width 0.05715)
			(type default)
		)
		(layer "B.Cu")
	)
	(gr_line
		(start 450.59854 -53.204872)
		(end 451.147942 -53.754274)
		(stroke
			(width 0.05715)
			(type default)
		)
		(layer "B.Cu")
	)
	(gr_line
		(start 450.647816 -52.988718)
		(end 450.7103 -52.926234)
		(stroke
			(width 0.05715)
			(type default)
		)
		(layer "B.Cu")
	)
	(gr_circle
		(center 450.6722 -38.608)
		(end 450.9262 -38.608)
		(stroke
			(width 0.2)
			(type default)
		)
		(fill no)
		(layer "B.Cu")
	)
	(gr_line
		(start 450.680836 -50.903378)
		(end 450.77634 -50.998882)
		(stroke
			(width 0.05715)
			(type default)
		)
		(layer "B.Cu")
	)
	(gr_circle
		(center 450.6976 -43.0022)
		(end 450.9516 -43.0022)
		(stroke
			(width 0.2)
			(type default)
		)
		(fill no)
		(layer "B.Cu")
	)
	(gr_circle
		(center 450.6976 -42.3672)
		(end 450.9516 -42.3672)
		(stroke
			(width 0.2)
			(type default)
		)
		(fill no)
		(layer "B.Cu")
	)
	(gr_circle
		(center 450.6976 -41.7322)
		(end 450.9516 -41.7322)
		(stroke
			(width 0.2)
			(type default)
		)
		(fill no)
		(layer "B.Cu")
	)
	(gr_line
		(start 450.708268 -50.065686)
		(end 450.77634 -49.997614)
		(stroke
			(width 0.05715)
			(type default)
		)
		(layer "B.Cu")
	)
	(gr_line
		(start 450.7103 -52.926234)
		(end 450.86905 -52.926234)
		(stroke
			(width 0.05715)
			(type default)
		)
		(layer "B.Cu")
	)
	(gr_circle
		(center 450.7484 -41.0718)
		(end 451.0024 -41.0718)
		(stroke
			(width 0.2)
			(type default)
		)
		(fill no)
		(layer "B.Cu")
	)
	(gr_line
		(start 450.77634 -50.998882)
		(end 450.86905 -50.998882)
		(stroke
			(width 0.05715)
			(type default)
		)
		(layer "B.Cu")
	)
	(gr_line
		(start 450.77634 -49.997614)
		(end 451.165214 -49.997614)
		(stroke
			(width 0.05715)
			(type default)
		)
		(layer "B.Cu")
	)
	(gr_line
		(start 450.830442 -148.365464)
		(end 451.104 -148.336)
		(stroke
			(width 0.2)
			(type default)
		)
		(layer "B.Cu")
	)
	(gr_line
		(start 450.86905 -52.926234)
		(end 450.98335 -52.811934)
		(stroke
			(width 0.05715)
			(type default)
		)
		(layer "B.Cu")
	)
	(gr_line
		(start 450.86905 -50.998882)
		(end 450.98335 -51.113182)
		(stroke
			(width 0.05715)
			(type default)
		)
		(layer "B.Cu")
	)
	(gr_line
		(start 450.98335 -52.407058)
		(end 450.98335 -52.811934)
		(stroke
			(width 0.05715)
			(type default)
		)
		(layer "B.Cu")
	)
	(gr_line
		(start 450.98335 -51.113182)
		(end 450.98335 -51.518058)
		(stroke
			(width 0.05715)
			(type default)
		)
		(layer "B.Cu")
	)
	(gr_line
		(start 451.147942 -53.754274)
		(end 451.18655 -53.754274)
		(stroke
			(width 0.05715)
			(type default)
		)
		(layer "B.Cu")
	)
	(gr_line
		(start 452.364856 -114.403632)
		(end 452.764906 -114.403632)
		(stroke
			(width 0.05715)
			(type default)
		)
		(layer "B.Cu")
	)
	(gr_line
		(start 452.501 -116.49202)
		(end 452.836534 -116.827554)
		(stroke
			(width 0.05715)
			(type default)
		)
		(layer "B.Cu")
	)
	(gr_line
		(start 452.501 -115.60302)
		(end 452.836534 -115.267486)
		(stroke
			(width 0.05715)
			(type default)
		)
		(layer "B.Cu")
	)
	(gr_line
		(start 452.764906 -114.403632)
		(end 452.82739 -114.466116)
		(stroke
			(width 0.05715)
			(type default)
		)
		(layer "B.Cu")
	)
	(gr_line
		(start 452.836534 -117.747034)
		(end 452.84898 -117.738906)
		(stroke
			(width 0.05715)
			(type default)
		)
		(layer "B.Cu")
	)
	(gr_line
		(start 452.84898 -117.738906)
		(end 452.857362 -117.726206)
		(stroke
			(width 0.05715)
			(type default)
		)
		(layer "B.Cu")
	)
	(gr_line
		(start 453.095614 -49.997614)
		(end 453.495664 -49.997614)
		(stroke
			(width 0.05715)
			(type default)
		)
		(layer "B.Cu")
	)
	(gr_line
		(start 453.109076 -117.343682)
		(end 453.12965 -117.312186)
		(stroke
			(width 0.05715)
			(type default)
		)
		(layer "B.Cu")
	)
	(gr_line
		(start 453.11695 -53.754274)
		(end 453.579484 -53.29174)
		(stroke
			(width 0.05715)
			(type default)
		)
		(layer "B.Cu")
	)
	(gr_line
		(start 453.172322 -114.466116)
		(end 453.234806 -114.403632)
		(stroke
			(width 0.05715)
			(type default)
		)
		(layer "B.Cu")
	)
	(gr_line
		(start 453.181466 -116.827554)
		(end 453.517 -116.49202)
		(stroke
			(width 0.05715)
			(type default)
		)
		(layer "B.Cu")
	)
	(gr_line
		(start 453.181466 -115.267486)
		(end 453.517 -115.60302)
		(stroke
			(width 0.05715)
			(type default)
		)
		(layer "B.Cu")
	)
	(gr_line
		(start 453.2122 -52.735734)
		(end 453.3265 -52.850034)
		(stroke
			(width 0.05715)
			(type default)
		)
		(layer "B.Cu")
	)
	(gr_line
		(start 453.2122 -52.330858)
		(end 453.2122 -52.735734)
		(stroke
			(width 0.05715)
			(type default)
		)
		(layer "B.Cu")
	)
	(gr_line
		(start 453.2122 -51.036982)
		(end 453.2122 -51.441858)
		(stroke
			(width 0.05715)
			(type default)
		)
		(layer "B.Cu")
	)
	(gr_line
		(start 453.2122 -51.036982)
		(end 453.3265 -50.922682)
		(stroke
			(width 0.05715)
			(type default)
		)
		(layer "B.Cu")
	)
	(gr_line
		(start 453.234806 -114.403632)
		(end 453.634856 -114.403632)
		(stroke
			(width 0.05715)
			(type default)
		)
		(layer "B.Cu")
	)
	(gr_line
		(start 453.26935 -124.18822)
		(end 453.6694 -124.18822)
		(stroke
			(width 0.05715)
			(type default)
		)
		(layer "B.Cu")
	)
	(gr_line
		(start 453.3265 -52.850034)
		(end 453.48525 -52.850034)
		(stroke
			(width 0.05715)
			(type default)
		)
		(layer "B.Cu")
	)
	(gr_line
		(start 453.3265 -50.922682)
		(end 453.48525 -50.922682)
		(stroke
			(width 0.05715)
			(type default)
		)
		(layer "B.Cu")
	)
	(gr_line
		(start 453.48525 -52.850034)
		(end 453.547734 -52.912518)
		(stroke
			(width 0.05715)
			(type default)
		)
		(layer "B.Cu")
	)
	(gr_line
		(start 453.48525 -50.922682)
		(end 453.553068 -50.854864)
		(stroke
			(width 0.05715)
			(type default)
		)
		(layer "B.Cu")
	)
	(gr_line
		(start 453.495664 -49.997614)
		(end 453.558148 -50.060098)
		(stroke
			(width 0.05715)
			(type default)
		)
		(layer "B.Cu")
	)
	(gr_line
		(start 453.51192 -122.839988)
		(end 453.519794 -122.807476)
		(stroke
			(width 0.05715)
			(type default)
		)
		(layer "B.Cu")
	)
	(gr_line
		(start 453.51192 -122.839988)
		(end 453.521826 -122.871738)
		(stroke
			(width 0.05715)
			(type default)
		)
		(layer "B.Cu")
	)
	(gr_line
		(start 453.520556 -121.213372)
		(end 453.538082 -121.274586)
		(stroke
			(width 0.05715)
			(type default)
		)
		(layer "B.Cu")
	)
	(gr_line
		(start 453.520556 -121.213372)
		(end 453.550782 -121.157238)
		(stroke
			(width 0.05715)
			(type default)
		)
		(layer "B.Cu")
	)
	(gr_line
		(start 453.550528 -121.157492)
		(end 453.551036 -121.15673)
		(stroke
			(width 0.05715)
			(type default)
		)
		(layer "B.Cu")
	)
	(gr_line
		(start 453.6694 -124.18822)
		(end 453.731884 -124.125736)
		(stroke
			(width 0.05715)
			(type default)
		)
		(layer "B.Cu")
	)
	(gr_line
		(start 453.892666 -52.912518)
		(end 453.95515 -52.850034)
		(stroke
			(width 0.05715)
			(type default)
		)
		(layer "B.Cu")
	)
	(gr_line
		(start 453.897746 -50.854864)
		(end 453.965564 -50.922682)
		(stroke
			(width 0.05715)
			(type default)
		)
		(layer "B.Cu")
	)
	(gr_line
		(start 453.90308 -50.060098)
		(end 453.965564 -49.997614)
		(stroke
			(width 0.05715)
			(type default)
		)
		(layer "B.Cu")
	)
	(gr_line
		(start 453.924416 -53.29174)
		(end 454.38695 -53.754274)
		(stroke
			(width 0.05715)
			(type default)
		)
		(layer "B.Cu")
	)
	(gr_line
		(start 453.95515 -52.850034)
		(end 454.1139 -52.850034)
		(stroke
			(width 0.05715)
			(type default)
		)
		(layer "B.Cu")
	)
	(gr_line
		(start 453.965564 -50.922682)
		(end 454.1139 -50.922682)
		(stroke
			(width 0.05715)
			(type default)
		)
		(layer "B.Cu")
	)
	(gr_line
		(start 453.965564 -49.997614)
		(end 454.365614 -49.997614)
		(stroke
			(width 0.05715)
			(type default)
		)
		(layer "B.Cu")
	)
	(gr_line
		(start 453.969882 -121.905014)
		(end 453.978264 -121.934478)
		(stroke
			(width 0.05715)
			(type default)
		)
		(layer "B.Cu")
	)
	(gr_line
		(start 453.971406 -121.962926)
		(end 453.978264 -121.934478)
		(stroke
			(width 0.05715)
			(type default)
		)
		(layer "B.Cu")
	)
	(gr_line
		(start 454.024492 -123.671838)
		(end 454.025 -123.673616)
		(stroke
			(width 0.05715)
			(type default)
		)
		(layer "B.Cu")
	)
	(gr_line
		(start 454.076816 -124.125736)
		(end 454.1393 -124.18822)
		(stroke
			(width 0.05715)
			(type default)
		)
		(layer "B.Cu")
	)
	(gr_line
		(start 454.1139 -52.850034)
		(end 454.2282 -52.735734)
		(stroke
			(width 0.05715)
			(type default)
		)
		(layer "B.Cu")
	)
	(gr_line
		(start 454.1139 -50.922682)
		(end 454.2282 -51.036982)
		(stroke
			(width 0.05715)
			(type default)
		)
		(layer "B.Cu")
	)
	(gr_line
		(start 454.1393 -124.18822)
		(end 454.53935 -124.18822)
		(stroke
			(width 0.05715)
			(type default)
		)
		(layer "B.Cu")
	)
	(gr_line
		(start 454.2282 -52.330858)
		(end 454.2282 -52.735734)
		(stroke
			(width 0.05715)
			(type default)
		)
		(layer "B.Cu")
	)
	(gr_line
		(start 454.2282 -51.036982)
		(end 454.2282 -51.441858)
		(stroke
			(width 0.05715)
			(type default)
		)
		(layer "B.Cu")
	)
	(gr_line
		(start 455.135488 -118.215156)
		(end 455.144632 -118.198392)
		(stroke
			(width 0.05715)
			(type default)
		)
		(layer "B.Cu")
	)
	(gr_line
		(start 455.144632 -118.198392)
		(end 455.159872 -118.186962)
		(stroke
			(width 0.05715)
			(type default)
		)
		(layer "B.Cu")
	)
	(gr_line
		(start 455.565002 -114.403632)
		(end 455.965052 -114.403632)
		(stroke
			(width 0.05715)
			(type default)
		)
		(layer "B.Cu")
	)
	(gr_line
		(start 455.676 -116.49202)
		(end 456.011534 -116.827554)
		(stroke
			(width 0.05715)
			(type default)
		)
		(layer "B.Cu")
	)
	(gr_line
		(start 455.676 -115.60302)
		(end 456.011534 -115.267486)
		(stroke
			(width 0.05715)
			(type default)
		)
		(layer "B.Cu")
	)
	(gr_line
		(start 455.965052 -114.403632)
		(end 456.027536 -114.466116)
		(stroke
			(width 0.05715)
			(type default)
		)
		(layer "B.Cu")
	)
	(gr_line
		(start 456.002136 -117.860318)
		(end 456.018392 -117.848126)
		(stroke
			(width 0.05715)
			(type default)
		)
		(layer "B.Cu")
	)
	(gr_line
		(start 456.018392 -117.848126)
		(end 456.02779 -117.830092)
		(stroke
			(width 0.05715)
			(type default)
		)
		(layer "B.Cu")
	)
	(gr_line
		(start 456.21575 -124.18822)
		(end 456.6158 -124.18822)
		(stroke
			(width 0.05715)
			(type default)
		)
		(layer "B.Cu")
	)
	(gr_line
		(start 456.293474 -117.32006)
		(end 456.30465 -117.298978)
		(stroke
			(width 0.05715)
			(type default)
		)
		(layer "B.Cu")
	)
	(gr_line
		(start 456.296014 -49.997614)
		(end 456.696064 -49.997614)
		(stroke
			(width 0.05715)
			(type default)
		)
		(layer "B.Cu")
	)
	(gr_line
		(start 456.317604 -53.906674)
		(end 456.360276 -53.906674)
		(stroke
			(width 0.05715)
			(type default)
		)
		(layer "B.Cu")
	)
	(gr_line
		(start 456.356466 -116.827554)
		(end 456.692 -116.49202)
		(stroke
			(width 0.05715)
			(type default)
		)
		(layer "B.Cu")
	)
	(gr_line
		(start 456.356466 -115.267486)
		(end 456.692 -115.60302)
		(stroke
			(width 0.05715)
			(type default)
		)
		(layer "B.Cu")
	)
	(gr_line
		(start 456.360276 -53.906674)
		(end 456.801474 -53.465476)
		(stroke
			(width 0.05715)
			(type default)
		)
		(layer "B.Cu")
	)
	(gr_line
		(start 456.372468 -114.466116)
		(end 456.434952 -114.403632)
		(stroke
			(width 0.05715)
			(type default)
		)
		(layer "B.Cu")
	)
	(gr_line
		(start 456.434952 -114.403632)
		(end 456.835002 -114.403632)
		(stroke
			(width 0.05715)
			(type default)
		)
		(layer "B.Cu")
	)
	(gr_line
		(start 456.4888 -52.888134)
		(end 456.6031 -53.002434)
		(stroke
			(width 0.05715)
			(type default)
		)
		(layer "B.Cu")
	)
	(gr_line
		(start 456.4888 -52.483258)
		(end 456.4888 -52.888134)
		(stroke
			(width 0.05715)
			(type default)
		)
		(layer "B.Cu")
	)
	(gr_line
		(start 456.4888 -51.189382)
		(end 456.4888 -51.594258)
		(stroke
			(width 0.05715)
			(type default)
		)
		(layer "B.Cu")
	)
	(gr_line
		(start 456.4888 -51.189382)
		(end 456.6031 -51.075082)
		(stroke
			(width 0.05715)
			(type default)
		)
		(layer "B.Cu")
	)
	(gr_line
		(start 456.530964 -120.511062)
		(end 456.546458 -120.462802)
		(stroke
			(width 0.05715)
			(type default)
		)
		(layer "B.Cu")
	)
	(gr_line
		(start 456.530964 -120.511062)
		(end 456.549506 -120.55856)
		(stroke
			(width 0.05715)
			(type default)
		)
		(layer "B.Cu")
	)
	(gr_line
		(start 456.546458 -120.462548)
		(end 456.546712 -120.461786)
		(stroke
			(width 0.05715)
			(type default)
		)
		(layer "B.Cu")
	)
	(gr_line
		(start 456.6031 -53.002434)
		(end 456.76185 -53.002434)
		(stroke
			(width 0.05715)
			(type default)
		)
		(layer "B.Cu")
	)
	(gr_line
		(start 456.6031 -51.075082)
		(end 456.74788 -51.075082)
		(stroke
			(width 0.05715)
			(type default)
		)
		(layer "B.Cu")
	)
	(gr_line
		(start 456.6158 -124.18822)
		(end 456.678284 -124.125736)
		(stroke
			(width 0.05715)
			(type default)
		)
		(layer "B.Cu")
	)
	(gr_line
		(start 456.696064 -49.997614)
		(end 456.784456 -50.086006)
		(stroke
			(width 0.05715)
			(type default)
		)
		(layer "B.Cu")
	)
	(gr_line
		(start 456.74788 -51.075082)
		(end 456.817476 -51.005486)
		(stroke
			(width 0.05715)
			(type default)
		)
		(layer "B.Cu")
	)
	(gr_line
		(start 456.76185 -53.002434)
		(end 456.824334 -53.064918)
		(stroke
			(width 0.05715)
			(type default)
		)
		(layer "B.Cu")
	)
	(gr_line
		(start 457.01712 -118.999762)
		(end 457.033376 -118.94947)
		(stroke
			(width 0.05715)
			(type default)
		)
		(layer "B.Cu")
	)
	(gr_line
		(start 457.023216 -124.125736)
		(end 457.0857 -124.18822)
		(stroke
			(width 0.05715)
			(type default)
		)
		(layer "B.Cu")
	)
	(gr_line
		(start 457.033376 -118.94947)
		(end 457.077572 -118.921022)
		(stroke
			(width 0.05715)
			(type default)
		)
		(layer "B.Cu")
	)
	(gr_line
		(start 457.0857 -124.18822)
		(end 457.48575 -124.18822)
		(stroke
			(width 0.05715)
			(type default)
		)
		(layer "B.Cu")
	)
	(gr_line
		(start 457.129388 -50.086006)
		(end 457.21778 -49.997614)
		(stroke
			(width 0.05715)
			(type default)
		)
		(layer "B.Cu")
	)
	(gr_line
		(start 457.146406 -53.465476)
		(end 457.587604 -53.906674)
		(stroke
			(width 0.05715)
			(type default)
		)
		(layer "B.Cu")
	)
	(gr_line
		(start 457.162154 -51.005486)
		(end 457.23175 -51.075082)
		(stroke
			(width 0.05715)
			(type default)
		)
		(layer "B.Cu")
	)
	(gr_line
		(start 457.169266 -53.064918)
		(end 457.23175 -53.002434)
		(stroke
			(width 0.05715)
			(type default)
		)
		(layer "B.Cu")
	)
	(gr_line
		(start 457.21778 -49.997614)
		(end 457.566014 -49.997614)
		(stroke
			(width 0.05715)
			(type default)
		)
		(layer "B.Cu")
	)
	(gr_line
		(start 457.23175 -53.002434)
		(end 457.3905 -53.002434)
		(stroke
			(width 0.05715)
			(type default)
		)
		(layer "B.Cu")
	)
	(gr_line
		(start 457.23175 -51.075082)
		(end 457.3905 -51.075082)
		(stroke
			(width 0.05715)
			(type default)
		)
		(layer "B.Cu")
	)
	(gr_line
		(start 457.385674 -122.034554)
		(end 457.403708 -122.080274)
		(stroke
			(width 0.05715)
			(type default)
		)
		(layer "B.Cu")
	)
	(gr_line
		(start 457.389992 -122.127264)
		(end 457.403708 -122.080274)
		(stroke
			(width 0.05715)
			(type default)
		)
		(layer "B.Cu")
	)
	(gr_line
		(start 457.3905 -53.002434)
		(end 457.5048 -52.888134)
		(stroke
			(width 0.05715)
			(type default)
		)
		(layer "B.Cu")
	)
	(gr_line
		(start 457.3905 -51.075082)
		(end 457.5048 -51.189382)
		(stroke
			(width 0.05715)
			(type default)
		)
		(layer "B.Cu")
	)
	(gr_line
		(start 457.5048 -52.483258)
		(end 457.5048 -52.888134)
		(stroke
			(width 0.05715)
			(type default)
		)
		(layer "B.Cu")
	)
	(gr_line
		(start 457.5048 -51.189382)
		(end 457.5048 -51.594258)
		(stroke
			(width 0.05715)
			(type default)
		)
		(layer "B.Cu")
	)
	(gr_circle
		(center 458.540612 -36.455604)
		(end 458.794612 -36.455604)
		(stroke
			(width 0.2)
			(type default)
		)
		(fill no)
		(layer "B.Cu")
	)
	(gr_line
		(start 458.764894 -114.403632)
		(end 459.151736 -114.403632)
		(stroke
			(width 0.05715)
			(type default)
		)
		(layer "B.Cu")
	)
	(gr_line
		(start 458.851 -116.49202)
		(end 459.186534 -116.827554)
		(stroke
			(width 0.05715)
			(type default)
		)
		(layer "B.Cu")
	)
	(gr_line
		(start 458.851 -115.60302)
		(end 459.186534 -115.267486)
		(stroke
			(width 0.05715)
			(type default)
		)
		(layer "B.Cu")
	)
	(gr_line
		(start 458.97165 -124.13742)
		(end 459.3717 -124.13742)
		(stroke
			(width 0.05715)
			(type default)
		)
		(layer "B.Cu")
	)
	(gr_line
		(start 459.018132 -117.95887)
		(end 459.027784 -117.95252)
		(stroke
			(width 0.05715)
			(type default)
		)
		(layer "B.Cu")
	)
	(gr_line
		(start 459.027784 -117.95252)
		(end 459.034134 -117.943376)
		(stroke
			(width 0.05715)
			(type default)
		)
		(layer "B.Cu")
	)
	(gr_line
		(start 459.10627 -122.597926)
		(end 459.11389 -122.565414)
		(stroke
			(width 0.05715)
			(type default)
		)
		(layer "B.Cu")
	)
	(gr_line
		(start 459.10627 -122.597926)
		(end 459.116684 -122.629422)
		(stroke
			(width 0.05715)
			(type default)
		)
		(layer "B.Cu")
	)
	(gr_line
		(start 459.113636 -122.565668)
		(end 459.11389 -122.564652)
		(stroke
			(width 0.05715)
			(type default)
		)
		(layer "B.Cu")
	)
	(gr_line
		(start 459.151736 -114.403632)
		(end 459.220824 -114.47272)
		(stroke
			(width 0.05715)
			(type default)
		)
		(layer "B.Cu")
	)
	(gr_line
		(start 459.3717 -124.13742)
		(end 459.434184 -124.074936)
		(stroke
			(width 0.05715)
			(type default)
		)
		(layer "B.Cu")
	)
	(gr_line
		(start 459.455266 -117.351302)
		(end 459.47965 -117.317012)
		(stroke
			(width 0.05715)
			(type default)
		)
		(layer "B.Cu")
	)
	(gr_line
		(start 459.496414 -49.997614)
		(end 459.896464 -49.997614)
		(stroke
			(width 0.05715)
			(type default)
		)
		(layer "B.Cu")
	)
	(gr_line
		(start 459.51775 -53.906674)
		(end 459.605126 -53.906674)
		(stroke
			(width 0.05715)
			(type default)
		)
		(layer "B.Cu")
	)
	(gr_line
		(start 459.531466 -116.827554)
		(end 459.867 -116.49202)
		(stroke
			(width 0.05715)
			(type default)
		)
		(layer "B.Cu")
	)
	(gr_line
		(start 459.531466 -115.267486)
		(end 459.867 -115.60302)
		(stroke
			(width 0.05715)
			(type default)
		)
		(layer "B.Cu")
	)
	(gr_line
		(start 459.565756 -114.47272)
		(end 459.634844 -114.403632)
		(stroke
			(width 0.05715)
			(type default)
		)
		(layer "B.Cu")
	)
	(gr_line
		(start 459.605126 -53.906674)
		(end 460.015082 -53.496718)
		(stroke
			(width 0.05715)
			(type default)
		)
		(layer "B.Cu")
	)
	(gr_line
		(start 459.634844 -114.403632)
		(end 460.034894 -114.403632)
		(stroke
			(width 0.05715)
			(type default)
		)
		(layer "B.Cu")
	)
	(gr_line
		(start 459.6384 -52.862734)
		(end 459.7527 -52.977034)
		(stroke
			(width 0.05715)
			(type default)
		)
		(layer "B.Cu")
	)
	(gr_line
		(start 459.6384 -52.457858)
		(end 459.6384 -52.862734)
		(stroke
			(width 0.05715)
			(type default)
		)
		(layer "B.Cu")
	)
	(gr_line
		(start 459.6384 -51.163982)
		(end 459.6384 -51.568858)
		(stroke
			(width 0.05715)
			(type default)
		)
		(layer "B.Cu")
	)
	(gr_line
		(start 459.6384 -51.163982)
		(end 459.7527 -51.049682)
		(stroke
			(width 0.05715)
			(type default)
		)
		(layer "B.Cu")
	)
	(gr_line
		(start 459.72603 -123.702318)
		(end 459.7273 -123.706128)
		(stroke
			(width 0.05715)
			(type default)
		)
		(layer "B.Cu")
	)
	(gr_line
		(start 459.7527 -52.977034)
		(end 459.900782 -52.977034)
		(stroke
			(width 0.05715)
			(type default)
		)
		(layer "B.Cu")
	)
	(gr_line
		(start 459.7527 -51.049682)
		(end 459.896464 -51.049682)
		(stroke
			(width 0.05715)
			(type default)
		)
		(layer "B.Cu")
	)
	(gr_line
		(start 459.779116 -124.074936)
		(end 459.8416 -124.13742)
		(stroke
			(width 0.05715)
			(type default)
		)
		(layer "B.Cu")
	)
	(gr_line
		(start 459.8416 -124.13742)
		(end 460.24165 -124.13742)
		(stroke
			(width 0.05715)
			(type default)
		)
		(layer "B.Cu")
	)
	(gr_line
		(start 459.896464 -51.049682)
		(end 459.966568 -50.979578)
		(stroke
			(width 0.05715)
			(type default)
		)
		(layer "B.Cu")
	)
	(gr_line
		(start 459.896464 -49.997614)
		(end 459.958948 -50.060098)
		(stroke
			(width 0.05715)
			(type default)
		)
		(layer "B.Cu")
	)
	(gr_line
		(start 459.900782 -52.977034)
		(end 459.9686 -53.044852)
		(stroke
			(width 0.05715)
			(type default)
		)
		(layer "B.Cu")
	)
	(gr_line
		(start 460.258922 -53.377846)
		(end 460.78775 -53.906674)
		(stroke
			(width 0.05715)
			(type default)
		)
		(layer "B.Cu")
	)
	(gr_line
		(start 460.30388 -50.060098)
		(end 460.366364 -49.997614)
		(stroke
			(width 0.05715)
			(type default)
		)
		(layer "B.Cu")
	)
	(gr_line
		(start 460.311246 -50.979578)
		(end 460.38135 -51.049682)
		(stroke
			(width 0.05715)
			(type default)
		)
		(layer "B.Cu")
	)
	(gr_line
		(start 460.313532 -53.044852)
		(end 460.38135 -52.977034)
		(stroke
			(width 0.05715)
			(type default)
		)
		(layer "B.Cu")
	)
	(gr_line
		(start 460.366364 -49.997614)
		(end 460.766414 -49.997614)
		(stroke
			(width 0.05715)
			(type default)
		)
		(layer "B.Cu")
	)
	(gr_line
		(start 460.38135 -52.977034)
		(end 460.5401 -52.977034)
		(stroke
			(width 0.05715)
			(type default)
		)
		(layer "B.Cu")
	)
	(gr_line
		(start 460.38135 -51.049682)
		(end 460.5401 -51.049682)
		(stroke
			(width 0.05715)
			(type default)
		)
		(layer "B.Cu")
	)
	(gr_line
		(start 460.5401 -52.977034)
		(end 460.6544 -52.862734)
		(stroke
			(width 0.05715)
			(type default)
		)
		(layer "B.Cu")
	)
	(gr_line
		(start 460.5401 -51.049682)
		(end 460.6544 -51.163982)
		(stroke
			(width 0.05715)
			(type default)
		)
		(layer "B.Cu")
	)
	(gr_line
		(start 460.628238 -118.68277)
		(end 460.638906 -118.662958)
		(stroke
			(width 0.05715)
			(type default)
		)
		(layer "B.Cu")
	)
	(gr_line
		(start 460.638906 -118.662958)
		(end 460.657702 -118.64975)
		(stroke
			(width 0.05715)
			(type default)
		)
		(layer "B.Cu")
	)
	(gr_line
		(start 460.6544 -52.457858)
		(end 460.6544 -52.862734)
		(stroke
			(width 0.05715)
			(type default)
		)
		(layer "B.Cu")
	)
	(gr_line
		(start 460.6544 -51.163982)
		(end 460.6544 -51.568858)
		(stroke
			(width 0.05715)
			(type default)
		)
		(layer "B.Cu")
	)
	(gr_line
		(start 461.96504 -114.403632)
		(end 462.334102 -114.403632)
		(stroke
			(width 0.05715)
			(type default)
		)
		(layer "B.Cu")
	)
	(gr_line
		(start 462.026 -116.49202)
		(end 462.361534 -116.827554)
		(stroke
			(width 0.05715)
			(type default)
		)
		(layer "B.Cu")
	)
	(gr_line
		(start 462.026 -115.60302)
		(end 462.361534 -115.267486)
		(stroke
			(width 0.05715)
			(type default)
		)
		(layer "B.Cu")
	)
	(gr_line
		(start 462.05775 -124.18822)
		(end 462.4578 -124.18822)
		(stroke
			(width 0.05715)
			(type default)
		)
		(layer "B.Cu")
	)
	(gr_line
		(start 462.258156 -122.4407)
		(end 462.265776 -122.410982)
		(stroke
			(width 0.05715)
			(type default)
		)
		(layer "B.Cu")
	)
	(gr_line
		(start 462.258156 -122.4407)
		(end 462.266284 -122.46991)
		(stroke
			(width 0.05715)
			(type default)
		)
		(layer "B.Cu")
	)
	(gr_line
		(start 462.334102 -114.403632)
		(end 462.41208 -114.48161)
		(stroke
			(width 0.05715)
			(type default)
		)
		(layer "B.Cu")
	)
	(gr_line
		(start 462.42224 -117.710712)
		(end 462.44129 -117.697504)
		(stroke
			(width 0.05715)
			(type default)
		)
		(layer "B.Cu")
	)
	(gr_line
		(start 462.44129 -117.697504)
		(end 462.441544 -117.69725)
		(stroke
			(width 0.05715)
			(type default)
		)
		(layer "B.Cu")
	)
	(gr_line
		(start 462.44129 -117.69725)
		(end 462.441544 -117.69725)
		(stroke
			(width 0.05715)
			(type default)
		)
		(layer "B.Cu")
	)
	(gr_line
		(start 462.44129 -117.69725)
		(end 462.452212 -117.677184)
		(stroke
			(width 0.05715)
			(type default)
		)
		(layer "B.Cu")
	)
	(gr_line
		(start 462.4578 -124.18822)
		(end 462.520284 -124.125736)
		(stroke
			(width 0.05715)
			(type default)
		)
		(layer "B.Cu")
	)
	(gr_line
		(start 462.642712 -117.322854)
		(end 462.65465 -117.300756)
		(stroke
			(width 0.05715)
			(type default)
		)
		(layer "B.Cu")
	)
	(gr_line
		(start 462.706466 -116.827554)
		(end 463.042 -116.49202)
		(stroke
			(width 0.05715)
			(type default)
		)
		(layer "B.Cu")
	)
	(gr_line
		(start 462.706466 -115.267486)
		(end 463.042 -115.60302)
		(stroke
			(width 0.05715)
			(type default)
		)
		(layer "B.Cu")
	)
	(gr_line
		(start 462.707228 -49.997614)
		(end 463.107278 -49.997614)
		(stroke
			(width 0.05715)
			(type default)
		)
		(layer "B.Cu")
	)
	(gr_line
		(start 462.70799 -53.888894)
		(end 463.151728 -53.445156)
		(stroke
			(width 0.05715)
			(type default)
		)
		(layer "B.Cu")
	)
	(gr_line
		(start 462.757012 -114.48161)
		(end 462.83499 -114.403632)
		(stroke
			(width 0.05715)
			(type default)
		)
		(layer "B.Cu")
	)
	(gr_line
		(start 462.8134 -52.837334)
		(end 462.9277 -52.951634)
		(stroke
			(width 0.05715)
			(type default)
		)
		(layer "B.Cu")
	)
	(gr_line
		(start 462.8134 -52.432458)
		(end 462.8134 -52.837334)
		(stroke
			(width 0.05715)
			(type default)
		)
		(layer "B.Cu")
	)
	(gr_line
		(start 462.8134 -51.138582)
		(end 462.8134 -51.543458)
		(stroke
			(width 0.05715)
			(type default)
		)
		(layer "B.Cu")
	)
	(gr_line
		(start 462.8134 -51.138582)
		(end 462.9277 -51.024282)
		(stroke
			(width 0.05715)
			(type default)
		)
		(layer "B.Cu")
	)
	(gr_line
		(start 462.83499 -114.403632)
		(end 463.23504 -114.403632)
		(stroke
			(width 0.05715)
			(type default)
		)
		(layer "B.Cu")
	)
	(gr_line
		(start 462.865216 -124.125736)
		(end 462.9277 -124.18822)
		(stroke
			(width 0.05715)
			(type default)
		)
		(layer "B.Cu")
	)
	(gr_line
		(start 462.9277 -124.18822)
		(end 463.32775 -124.18822)
		(stroke
			(width 0.05715)
			(type default)
		)
		(layer "B.Cu")
	)
	(gr_line
		(start 462.9277 -52.951634)
		(end 463.08645 -52.951634)
		(stroke
			(width 0.05715)
			(type default)
		)
		(layer "B.Cu")
	)
	(gr_line
		(start 462.9277 -51.024282)
		(end 463.08645 -51.024282)
		(stroke
			(width 0.05715)
			(type default)
		)
		(layer "B.Cu")
	)
	(gr_line
		(start 462.970118 -119.673878)
		(end 462.982564 -119.625618)
		(stroke
			(width 0.05715)
			(type default)
		)
		(layer "B.Cu")
	)
	(gr_line
		(start 462.982564 -119.625364)
		(end 462.982564 -119.625618)
		(stroke
			(width 0.05715)
			(type default)
		)
		(layer "B.Cu")
	)
	(gr_line
		(start 462.982564 -119.625364)
		(end 463.022442 -119.594884)
		(stroke
			(width 0.05715)
			(type default)
		)
		(layer "B.Cu")
	)
	(gr_line
		(start 463.08645 -52.951634)
		(end 463.148934 -53.014118)
		(stroke
			(width 0.05715)
			(type default)
		)
		(layer "B.Cu")
	)
	(gr_line
		(start 463.08645 -51.024282)
		(end 463.159348 -50.951384)
		(stroke
			(width 0.05715)
			(type default)
		)
		(layer "B.Cu")
	)
	(gr_line
		(start 463.107278 -49.997614)
		(end 463.169762 -50.060098)
		(stroke
			(width 0.05715)
			(type default)
		)
		(layer "B.Cu")
	)
	(gr_line
		(start 463.493866 -53.014118)
		(end 463.55635 -52.951634)
		(stroke
			(width 0.05715)
			(type default)
		)
		(layer "B.Cu")
	)
	(gr_line
		(start 463.496406 -53.445156)
		(end 463.940144 -53.888894)
		(stroke
			(width 0.05715)
			(type default)
		)
		(layer "B.Cu")
	)
	(gr_line
		(start 463.50428 -50.951384)
		(end 463.577178 -51.024282)
		(stroke
			(width 0.05715)
			(type default)
		)
		(layer "B.Cu")
	)
	(gr_line
		(start 463.514694 -50.060098)
		(end 463.577178 -49.997614)
		(stroke
			(width 0.05715)
			(type default)
		)
		(layer "B.Cu")
	)
	(gr_line
		(start 463.55635 -52.951634)
		(end 463.7151 -52.951634)
		(stroke
			(width 0.05715)
			(type default)
		)
		(layer "B.Cu")
	)
	(gr_line
		(start 463.577178 -51.024282)
		(end 463.7151 -51.024282)
		(stroke
			(width 0.05715)
			(type default)
		)
		(layer "B.Cu")
	)
	(gr_line
		(start 463.577178 -49.997614)
		(end 463.977228 -49.997614)
		(stroke
			(width 0.05715)
			(type default)
		)
		(layer "B.Cu")
	)
	(gr_line
		(start 463.7151 -52.951634)
		(end 463.8294 -52.837334)
		(stroke
			(width 0.05715)
			(type default)
		)
		(layer "B.Cu")
	)
	(gr_line
		(start 463.7151 -51.024282)
		(end 463.8294 -51.138582)
		(stroke
			(width 0.05715)
			(type default)
		)
		(layer "B.Cu")
	)
	(gr_line
		(start 463.8294 -52.432458)
		(end 463.8294 -52.837334)
		(stroke
			(width 0.05715)
			(type default)
		)
		(layer "B.Cu")
	)
	(gr_line
		(start 463.8294 -51.138582)
		(end 463.8294 -51.543458)
		(stroke
			(width 0.05715)
			(type default)
		)
		(layer "B.Cu")
	)
	(gr_line
		(start 463.940144 -53.888894)
		(end 463.97799 -53.888894)
		(stroke
			(width 0.05715)
			(type default)
		)
		(layer "B.Cu")
	)
	(gr_line
		(start 464.203034 -118.998746)
		(end 464.219036 -118.986808)
		(stroke
			(width 0.05715)
			(type default)
		)
		(layer "B.Cu")
	)
	(gr_line
		(start 464.219036 -118.986808)
		(end 464.228434 -118.96852)
		(stroke
			(width 0.05715)
			(type default)
		)
		(layer "B.Cu")
	)
	(gr_line
		(start 464.301586 -118.298214)
		(end 464.319874 -118.262908)
		(stroke
			(width 0.05715)
			(type default)
		)
		(layer "B.Cu")
	)
	(gr_line
		(start 464.319874 -118.262908)
		(end 464.354418 -118.243858)
		(stroke
			(width 0.05715)
			(type default)
		)
		(layer "B.Cu")
	)
	(gr_line
		(start 465.19973 -114.4524)
		(end 465.59978 -114.4524)
		(stroke
			(width 0.05715)
			(type default)
		)
		(layer "B.Cu")
	)
	(gr_line
		(start 465.328 -116.49202)
		(end 465.663534 -116.827554)
		(stroke
			(width 0.05715)
			(type default)
		)
		(layer "B.Cu")
	)
	(gr_line
		(start 465.328 -115.60302)
		(end 465.663534 -115.267486)
		(stroke
			(width 0.05715)
			(type default)
		)
		(layer "B.Cu")
	)
	(gr_line
		(start 465.572094 -117.842538)
		(end 465.589874 -117.832632)
		(stroke
			(width 0.05715)
			(type default)
		)
		(layer "B.Cu")
	)
	(gr_line
		(start 465.589874 -117.832632)
		(end 465.601304 -117.816376)
		(stroke
			(width 0.05715)
			(type default)
		)
		(layer "B.Cu")
	)
	(gr_line
		(start 465.59978 -114.4524)
		(end 465.662264 -114.514884)
		(stroke
			(width 0.05715)
			(type default)
		)
		(layer "B.Cu")
	)
	(gr_line
		(start 465.932266 -117.351302)
		(end 465.95665 -117.317012)
		(stroke
			(width 0.05715)
			(type default)
		)
		(layer "B.Cu")
	)
	(gr_line
		(start 466.007196 -114.514884)
		(end 466.06968 -114.4524)
		(stroke
			(width 0.05715)
			(type default)
		)
		(layer "B.Cu")
	)
	(gr_line
		(start 466.008466 -116.827554)
		(end 466.344 -116.49202)
		(stroke
			(width 0.05715)
			(type default)
		)
		(layer "B.Cu")
	)
	(gr_line
		(start 466.008466 -115.267486)
		(end 466.344 -115.60302)
		(stroke
			(width 0.05715)
			(type default)
		)
		(layer "B.Cu")
	)
	(gr_line
		(start 466.06968 -114.4524)
		(end 466.46973 -114.4524)
		(stroke
			(width 0.05715)
			(type default)
		)
		(layer "B.Cu")
	)
	(gr_line
		(start 469.015318 -64.389)
		(end 469.271096 -64.644778)
		(stroke
			(width 0.05715)
			(type default)
		)
		(layer "B.Cu")
	)
	(gr_line
		(start 469.288368 -65.013332)
		(end 469.306656 -65.042288)
		(stroke
			(width 0.05715)
			(type default)
		)
		(layer "B.Cu")
	)
	(gr_line
		(start 469.615774 -64.644778)
		(end 469.871552 -64.389)
		(stroke
			(width 0.05715)
			(type default)
		)
		(layer "B.Cu")
	)
	(gr_line
		(start 469.61933 -65.542922)
		(end 469.885776 -65.969642)
		(stroke
			(width 0.05715)
			(type default)
		)
		(layer "B.Cu")
	)
	(gr_line
		(start 469.80856 -65.38595)
		(end 469.962738 -65.42151)
		(stroke
			(width 0.05715)
			(type default)
		)
		(layer "B.Cu")
	)
	(gr_line
		(start 469.871552 -64.389)
		(end 469.95588 -64.389)
		(stroke
			(width 0.05715)
			(type default)
		)
		(layer "B.Cu")
	)
	(gr_line
		(start 469.962738 -65.42151)
		(end 470.144602 -65.71234)
		(stroke
			(width 0.05715)
			(type default)
		)
		(layer "B.Cu")
	)
	(gr_line
		(start 470.102438 -66.316606)
		(end 470.137998 -66.373502)
		(stroke
			(width 0.05715)
			(type default)
		)
		(layer "B.Cu")
	)
	(gr_line
		(start 470.109042 -65.866772)
		(end 470.144602 -65.71234)
		(stroke
			(width 0.05715)
			(type default)
		)
		(layer "B.Cu")
	)
	(gr_line
		(start 470.137998 -66.373502)
		(end 470.203022 -66.388488)
		(stroke
			(width 0.05715)
			(type default)
		)
		(layer "B.Cu")
	)
	(gr_line
		(start 470.590626 -124.714)
		(end 470.590626 -125.11405)
		(stroke
			(width 0.05715)
			(type default)
		)
		(layer "B.Cu")
	)
	(gr_line
		(start 470.590626 -124.714)
		(end 470.65311 -124.651516)
		(stroke
			(width 0.05715)
			(type default)
		)
		(layer "B.Cu")
	)
	(gr_line
		(start 470.590626 -124.2441)
		(end 470.65311 -124.306584)
		(stroke
			(width 0.05715)
			(type default)
		)
		(layer "B.Cu")
	)
	(gr_line
		(start 470.590626 -123.84405)
		(end 470.590626 -124.2441)
		(stroke
			(width 0.05715)
			(type default)
		)
		(layer "B.Cu")
	)
	(gr_line
		(start 470.603072 -66.480944)
		(end 471.094054 -66.594228)
		(stroke
			(width 0.05715)
			(type default)
		)
		(layer "B.Cu")
	)
	(gr_line
		(start 470.626694 -66.236088)
		(end 470.76106 -66.152268)
		(stroke
			(width 0.05715)
			(type default)
		)
		(layer "B.Cu")
	)
	(gr_line
		(start 470.76106 -66.152268)
		(end 471.09507 -66.22923)
		(stroke
			(width 0.05715)
			(type default)
		)
		(layer "B.Cu")
	)
	(gr_line
		(start 470.961212 -124.657866)
		(end 471.182446 -124.8791)
		(stroke
			(width 0.05715)
			(type default)
		)
		(layer "B.Cu")
	)
	(gr_line
		(start 470.961212 -124.312934)
		(end 471.195146 -124.079)
		(stroke
			(width 0.05715)
			(type default)
		)
		(layer "B.Cu")
	)
	(gr_line
		(start 471.09507 -66.22923)
		(end 471.179144 -66.363596)
		(stroke
			(width 0.05715)
			(type default)
		)
		(layer "B.Cu")
	)
	(gr_line
		(start 471.09888 -64.4398)
		(end 471.365834 -64.706754)
		(stroke
			(width 0.05715)
			(type default)
		)
		(layer "B.Cu")
	)
	(gr_line
		(start 471.182446 -124.8791)
		(end 471.6653 -124.8791)
		(stroke
			(width 0.05715)
			(type default)
		)
		(layer "B.Cu")
	)
	(gr_line
		(start 471.195146 -124.079)
		(end 471.6653 -124.079)
		(stroke
			(width 0.05715)
			(type default)
		)
		(layer "B.Cu")
	)
	(gr_line
		(start 471.42908 -65.052702)
		(end 471.447368 -65.081658)
		(stroke
			(width 0.05715)
			(type default)
		)
		(layer "B.Cu")
	)
	(gr_line
		(start 471.494358 -66.686684)
		(end 471.983054 -66.799206)
		(stroke
			(width 0.05715)
			(type default)
		)
		(layer "B.Cu")
	)
	(gr_line
		(start 471.51798 -66.441828)
		(end 471.652092 -66.358008)
		(stroke
			(width 0.05715)
			(type default)
		)
		(layer "B.Cu")
	)
	(gr_line
		(start 471.6018 -65.3288)
		(end 471.61323 -65.347342)
		(stroke
			(width 0.05715)
			(type default)
		)
		(layer "B.Cu")
	)
	(gr_line
		(start 471.61323 -65.347342)
		(end 471.631772 -65.358772)
		(stroke
			(width 0.05715)
			(type default)
		)
		(layer "B.Cu")
	)
	(gr_line
		(start 471.652092 -66.358008)
		(end 471.986102 -66.43497)
		(stroke
			(width 0.05715)
			(type default)
		)
		(layer "B.Cu")
	)
	(gr_line
		(start 471.710766 -64.706754)
		(end 471.97772 -64.4398)
		(stroke
			(width 0.05715)
			(type default)
		)
		(layer "B.Cu")
	)
	(gr_line
		(start 471.885264 -65.517014)
		(end 471.889836 -65.520062)
		(stroke
			(width 0.05715)
			(type default)
		)
		(layer "B.Cu")
	)
	(gr_line
		(start 471.889836 -65.520062)
		(end 471.89517 -65.521332)
		(stroke
			(width 0.05715)
			(type default)
		)
		(layer "B.Cu")
	)
	(gr_line
		(start 471.97772 -64.4398)
		(end 472.03868 -64.4398)
		(stroke
			(width 0.05715)
			(type default)
		)
		(layer "B.Cu")
	)
	(gr_line
		(start 471.986102 -66.43497)
		(end 472.069922 -66.569082)
		(stroke
			(width 0.05715)
			(type default)
		)
		(layer "B.Cu")
	)
	(gr_line
		(start 472.2876 -65.612264)
		(end 472.309698 -65.617344)
		(stroke
			(width 0.05715)
			(type default)
		)
		(layer "B.Cu")
	)
	(gr_line
		(start 472.309698 -65.617344)
		(end 472.331034 -65.612518)
		(stroke
			(width 0.05715)
			(type default)
		)
		(layer "B.Cu")
	)
	(gr_line
		(start 472.405964 -66.896996)
		(end 472.42603 -66.901568)
		(stroke
			(width 0.05715)
			(type default)
		)
		(layer "B.Cu")
	)
	(gr_line
		(start 472.42603 -66.901822)
		(end 472.44762 -66.896742)
		(stroke
			(width 0.05715)
			(type default)
		)
		(layer "B.Cu")
	)
	(gr_line
		(start 472.42603 -66.901568)
		(end 472.42603 -66.901822)
		(stroke
			(width 0.05715)
			(type default)
		)
		(layer "B.Cu")
	)
	(gr_line
		(start 472.646248 -65.28943)
		(end 472.730322 -65.155064)
		(stroke
			(width 0.05715)
			(type default)
		)
		(layer "B.Cu")
	)
	(gr_line
		(start 472.730322 -65.155064)
		(end 473.064332 -65.078102)
		(stroke
			(width 0.05715)
			(type default)
		)
		(layer "B.Cu")
	)
	(gr_line
		(start 472.733116 -65.5193)
		(end 473.220542 -65.406778)
		(stroke
			(width 0.05715)
			(type default)
		)
		(layer "B.Cu")
	)
	(gr_line
		(start 473.064332 -65.078102)
		(end 473.198444 -65.161668)
		(stroke
			(width 0.05715)
			(type default)
		)
		(layer "B.Cu")
	)
	(gr_line
		(start 473.6973 -124.8791)
		(end 474.1799 -124.8791)
		(stroke
			(width 0.05715)
			(type default)
		)
		(layer "B.Cu")
	)
	(gr_line
		(start 473.6973 -124.079)
		(end 474.1672 -124.079)
		(stroke
			(width 0.05715)
			(type default)
		)
		(layer "B.Cu")
	)
	(gr_line
		(start 473.892118 -65.251838)
		(end 473.899484 -65.25006)
		(stroke
			(width 0.05715)
			(type default)
		)
		(layer "B.Cu")
	)
	(gr_line
		(start 473.899484 -65.25006)
		(end 473.905834 -65.245996)
		(stroke
			(width 0.05715)
			(type default)
		)
		(layer "B.Cu")
	)
	(gr_line
		(start 473.92336 -66.556128)
		(end 473.93225 -66.554096)
		(stroke
			(width 0.05715)
			(type default)
		)
		(layer "B.Cu")
	)
	(gr_line
		(start 473.93225 -66.554096)
		(end 473.940124 -66.549016)
		(stroke
			(width 0.05715)
			(type default)
		)
		(layer "B.Cu")
	)
	(gr_line
		(start 474.1672 -124.079)
		(end 474.401134 -124.312934)
		(stroke
			(width 0.05715)
			(type default)
		)
		(layer "B.Cu")
	)
	(gr_line
		(start 474.1799 -124.8791)
		(end 474.401134 -124.657866)
		(stroke
			(width 0.05715)
			(type default)
		)
		(layer "B.Cu")
	)
	(gr_line
		(start 474.544644 -3.263392)
		(end 474.625924 -3.182112)
		(stroke
			(width 0.050546)
			(type default)
		)
		(layer "B.Cu")
	)
	(gr_line
		(start 475.275402 -3.183636)
		(end 475.275402 -3.349244)
		(stroke
			(width 0.050038)
			(type default)
		)
		(layer "B.Cu")
	)
	(gr_line
		(start 475.299024 -124.679202)
		(end 475.376748 -124.756926)
		(stroke
			(width 0.05715)
			(type default)
		)
		(layer "B.Cu")
	)
	(gr_line
		(start 475.299024 -124.334524)
		(end 475.376748 -124.2568)
		(stroke
			(width 0.05715)
			(type default)
		)
		(layer "B.Cu")
	)
	(gr_line
		(start 475.376748 -124.756926)
		(end 475.726252 -124.756926)
		(stroke
			(width 0.05715)
			(type default)
		)
		(layer "B.Cu")
	)
	(gr_line
		(start 475.376748 -124.2568)
		(end 475.726252 -124.2568)
		(stroke
			(width 0.05715)
			(type default)
		)
		(layer "B.Cu")
	)
	(gr_line
		(start 475.726252 -124.756926)
		(end 476.310198 -124.756926)
		(stroke
			(width 0.05715)
			(type default)
		)
		(layer "B.Cu")
	)
	(gr_line
		(start 475.726252 -124.2568)
		(end 476.310198 -124.2568)
		(stroke
			(width 0.05715)
			(type default)
		)
		(layer "B.Cu")
	)
	(gr_line
		(start 476.310198 -124.756926)
		(end 476.537274 -124.756926)
		(stroke
			(width 0.05715)
			(type default)
		)
		(layer "B.Cu")
	)
	(gr_line
		(start 476.310198 -124.2568)
		(end 476.5548 -124.2568)
		(stroke
			(width 0.05715)
			(type default)
		)
		(layer "B.Cu")
	)
	(gr_line
		(start 476.352616 -2.974594)
		(end 476.756222 -3.3782)
		(stroke
			(width 0.050546)
			(type default)
		)
		(layer "B.Cu")
	)
	(gr_line
		(start 476.537274 -124.756926)
		(end 476.623634 -124.670566)
		(stroke
			(width 0.05715)
			(type default)
		)
		(layer "B.Cu")
	)
	(gr_line
		(start 476.5548 -124.2568)
		(end 476.623634 -124.325634)
		(stroke
			(width 0.05715)
			(type default)
		)
		(layer "B.Cu")
	)
	(gr_line
		(start 476.67291 -63.96609)
		(end 476.728282 -63.94958)
		(stroke
			(width 0.05715)
			(type default)
		)
		(layer "B.Cu")
	)
	(gr_line
		(start 476.728282 -63.94958)
		(end 476.759016 -63.900558)
		(stroke
			(width 0.05715)
			(type default)
		)
		(layer "B.Cu")
	)
	(gr_line
		(start 477.498664 -64.93383)
		(end 477.554036 -64.91732)
		(stroke
			(width 0.05715)
			(type default)
		)
		(layer "B.Cu")
	)
	(gr_line
		(start 477.554036 -64.91732)
		(end 477.58477 -64.868298)
		(stroke
			(width 0.05715)
			(type default)
		)
		(layer "B.Cu")
	)
	(gr_line
		(start 478.041208 -61.392816)
		(end 478.052638 -61.374274)
		(stroke
			(width 0.05715)
			(type default)
		)
		(layer "B.Cu")
	)
	(gr_line
		(start 478.052638 -61.374274)
		(end 478.07118 -61.362844)
		(stroke
			(width 0.05715)
			(type default)
		)
		(layer "B.Cu")
	)
	(gr_line
		(start 478.34423 -61.189362)
		(end 478.37979 -61.035184)
		(stroke
			(width 0.05715)
			(type default)
		)
		(layer "B.Cu")
	)
	(gr_line
		(start 478.37979 -61.035184)
		(end 478.67062 -60.853574)
		(stroke
			(width 0.05715)
			(type default)
		)
		(layer "B.Cu")
	)
	(gr_line
		(start 478.499932 -61.379862)
		(end 478.92843 -61.1124)
		(stroke
			(width 0.05715)
			(type default)
		)
		(layer "B.Cu")
	)
	(gr_line
		(start 478.67062 -60.853574)
		(end 478.825052 -60.889134)
		(stroke
			(width 0.05715)
			(type default)
		)
		(layer "B.Cu")
	)
	(gr_line
		(start 479.003106 -62.141862)
		(end 479.014282 -62.124082)
		(stroke
			(width 0.05715)
			(type default)
		)
		(layer "B.Cu")
	)
	(gr_line
		(start 479.014282 -62.124082)
		(end 479.031808 -62.11316)
		(stroke
			(width 0.05715)
			(type default)
		)
		(layer "B.Cu")
	)
	(gr_line
		(start 479.226626 -60.640976)
		(end 479.232976 -60.637166)
		(stroke
			(width 0.05715)
			(type default)
		)
		(layer "B.Cu")
	)
	(gr_line
		(start 479.232976 -60.637166)
		(end 479.240342 -60.635388)
		(stroke
			(width 0.05715)
			(type default)
		)
		(layer "B.Cu")
	)
	(gr_line
		(start 479.56851 -60.55741)
		(end 479.652838 -60.423044)
		(stroke
			(width 0.05715)
			(type default)
		)
		(layer "B.Cu")
	)
	(gr_line
		(start 479.652838 -60.423044)
		(end 479.986848 -60.345828)
		(stroke
			(width 0.05715)
			(type default)
		)
		(layer "B.Cu")
	)
	(gr_line
		(start 479.653854 -60.787788)
		(end 480.144836 -60.674504)
		(stroke
			(width 0.05715)
			(type default)
		)
		(layer "B.Cu")
	)
	(gr_line
		(start 479.683064 -61.705744)
		(end 479.687636 -61.702696)
		(stroke
			(width 0.05715)
			(type default)
		)
		(layer "B.Cu")
	)
	(gr_line
		(start 479.687636 -61.702696)
		(end 479.69297 -61.701426)
		(stroke
			(width 0.05715)
			(type default)
		)
		(layer "B.Cu")
	)
	(gr_line
		(start 479.986848 -60.345828)
		(end 480.121214 -60.429648)
		(stroke
			(width 0.05715)
			(type default)
		)
		(layer "B.Cu")
	)
	(gr_line
		(start 481.011992 -60.226448)
		(end 481.033582 -60.221368)
		(stroke
			(width 0.05715)
			(type default)
		)
		(layer "B.Cu")
	)
	(gr_line
		(start 481.033582 -60.221368)
		(end 481.055172 -60.226448)
		(stroke
			(width 0.05715)
			(type default)
		)
		(layer "B.Cu")
	)
	(gr_line
		(start 481.081842 -61.381132)
		(end 481.101908 -61.37656)
		(stroke
			(width 0.05715)
			(type default)
		)
		(layer "B.Cu")
	)
	(gr_line
		(start 481.101908 -61.37656)
		(end 481.121974 -61.381132)
		(stroke
			(width 0.05715)
			(type default)
		)
		(layer "B.Cu")
	)
	(gr_line
		(start 481.6729 -60.616592)
		(end 481.692966 -60.621164)
		(stroke
			(width 0.05715)
			(type default)
		)
		(layer "B.Cu")
	)
	(gr_line
		(start 481.692966 -60.621164)
		(end 481.713032 -60.616592)
		(stroke
			(width 0.05715)
			(type default)
		)
		(layer "B.Cu")
	)
	(gr_line
		(start 481.781104 -61.780928)
		(end 481.801424 -61.7855)
		(stroke
			(width 0.05715)
			(type default)
		)
		(layer "B.Cu")
	)
	(gr_line
		(start 481.801424 -61.7855)
		(end 481.82149 -61.780928)
		(stroke
			(width 0.05715)
			(type default)
		)
		(layer "B.Cu")
	)
	(gr_line
		(start 482.6381 -132.171186)
		(end 482.684328 -132.217668)
		(stroke
			(width 0.05715)
			(type default)
		)
		(layer "B.Cu")
	)
	(gr_line
		(start 482.6381 -130.552952)
		(end 482.6381 -130.636772)
		(stroke
			(width 0.05715)
			(type default)
		)
		(layer "B.Cu")
	)
	(gr_line
		(start 482.6381 -129.638552)
		(end 482.6381 -129.722372)
		(stroke
			(width 0.05715)
			(type default)
		)
		(layer "B.Cu")
	)
	(gr_line
		(start 482.6381 -128.724152)
		(end 482.6381 -128.807972)
		(stroke
			(width 0.05715)
			(type default)
		)
		(layer "B.Cu")
	)
	(gr_line
		(start 482.6381 -127.809752)
		(end 482.6381 -127.893572)
		(stroke
			(width 0.05715)
			(type default)
		)
		(layer "B.Cu")
	)
	(gr_line
		(start 482.88194 -130.878072)
		(end 482.9937 -130.766312)
		(stroke
			(width 0.05715)
			(type default)
		)
		(layer "B.Cu")
	)
	(gr_line
		(start 482.88194 -130.311652)
		(end 482.9937 -130.423412)
		(stroke
			(width 0.05715)
			(type default)
		)
		(layer "B.Cu")
	)
	(gr_line
		(start 482.88194 -129.963672)
		(end 482.9937 -129.851912)
		(stroke
			(width 0.05715)
			(type default)
		)
		(layer "B.Cu")
	)
	(gr_line
		(start 482.88194 -129.397252)
		(end 482.9937 -129.509012)
		(stroke
			(width 0.05715)
			(type default)
		)
		(layer "B.Cu")
	)
	(gr_line
		(start 482.88194 -129.049272)
		(end 482.9937 -128.937512)
		(stroke
			(width 0.05715)
			(type default)
		)
		(layer "B.Cu")
	)
	(gr_line
		(start 482.88194 -128.482852)
		(end 482.9937 -128.594612)
		(stroke
			(width 0.05715)
			(type default)
		)
		(layer "B.Cu")
	)
	(gr_line
		(start 482.88194 -128.134872)
		(end 482.9937 -128.023112)
		(stroke
			(width 0.05715)
			(type default)
		)
		(layer "B.Cu")
	)
	(gr_line
		(start 482.88194 -127.568452)
		(end 482.9937 -127.680212)
		(stroke
			(width 0.05715)
			(type default)
		)
		(layer "B.Cu")
	)
	(gr_line
		(start 482.96068 -132.49402)
		(end 482.971094 -132.504434)
		(stroke
			(width 0.05715)
			(type default)
		)
		(layer "B.Cu")
	)
	(gr_line
		(start 482.971094 -132.504434)
		(end 482.984556 -132.510022)
		(stroke
			(width 0.05715)
			(type default)
		)
		(layer "B.Cu")
	)
	(gr_line
		(start 482.9937 -130.423412)
		(end 482.9937 -130.766312)
		(stroke
			(width 0.05715)
			(type default)
		)
		(layer "B.Cu")
	)
	(gr_line
		(start 482.9937 -129.509012)
		(end 482.9937 -129.851912)
		(stroke
			(width 0.05715)
			(type default)
		)
		(layer "B.Cu")
	)
	(gr_line
		(start 482.9937 -128.594612)
		(end 482.9937 -128.937512)
		(stroke
			(width 0.05715)
			(type default)
		)
		(layer "B.Cu")
	)
	(gr_line
		(start 482.9937 -127.680212)
		(end 482.9937 -128.023112)
		(stroke
			(width 0.05715)
			(type default)
		)
		(layer "B.Cu")
	)
	(gr_line
		(start 483.066852 -60.304426)
		(end 483.06736 -60.305188)
		(stroke
			(width 0.05715)
			(type default)
		)
		(layer "B.Cu")
	)
	(gr_line
		(start 483.067106 -60.305442)
		(end 483.06736 -60.305188)
		(stroke
			(width 0.05715)
			(type default)
		)
		(layer "B.Cu")
	)
	(gr_line
		(start 483.067106 -60.305442)
		(end 483.072948 -60.301886)
		(stroke
			(width 0.05715)
			(type default)
		)
		(layer "B.Cu")
	)
	(gr_line
		(start 483.412038 -61.416438)
		(end 483.418642 -61.414914)
		(stroke
			(width 0.05715)
			(type default)
		)
		(layer "B.Cu")
	)
	(gr_line
		(start 483.418642 -61.414914)
		(end 483.423976 -61.411612)
		(stroke
			(width 0.05715)
			(type default)
		)
		(layer "B.Cu")
	)
	(gr_line
		(start 483.599236 -132.76453)
		(end 483.611174 -132.769356)
		(stroke
			(width 0.05715)
			(type default)
		)
		(layer "B.Cu")
	)
	(gr_line
		(start 483.751128 -131.655312)
		(end 484.514398 -131.655312)
		(stroke
			(width 0.05715)
			(type default)
		)
		(layer "B.Cu")
	)
	(gr_line
		(start 483.772718 -59.864498)
		(end 483.790498 -59.853322)
		(stroke
			(width 0.05715)
			(type default)
		)
		(layer "B.Cu")
	)
	(gr_line
		(start 483.790498 -59.853322)
		(end 483.80142 -59.835796)
		(stroke
			(width 0.05715)
			(type default)
		)
		(layer "B.Cu")
	)
	(gr_line
		(start 484.128318 -59.313318)
		(end 484.146098 -59.285124)
		(stroke
			(width 0.05715)
			(type default)
		)
		(layer "B.Cu")
	)
	(gr_line
		(start 484.514398 -131.655312)
		(end 484.514906 -131.654804)
		(stroke
			(width 0.05715)
			(type default)
		)
		(layer "B.Cu")
	)
	(gr_line
		(start 484.514906 -131.654804)
		(end 484.577644 -131.717542)
		(stroke
			(width 0.05715)
			(type default)
		)
		(layer "B.Cu")
	)
	(gr_line
		(start 484.612442 -58.71591)
		(end 484.799894 -58.903362)
		(stroke
			(width 0.05715)
			(type default)
		)
		(layer "B.Cu")
	)
	(gr_line
		(start 484.612442 -58.370978)
		(end 484.880158 -58.103262)
		(stroke
			(width 0.05715)
			(type default)
		)
		(layer "B.Cu")
	)
	(gr_line
		(start 484.721154 -60.31611)
		(end 484.75011 -60.297822)
		(stroke
			(width 0.05715)
			(type default)
		)
		(layer "B.Cu")
	)
	(gr_line
		(start 484.799894 -58.903362)
		(end 485.58577 -58.903362)
		(stroke
			(width 0.05715)
			(type default)
		)
		(layer "B.Cu")
	)
	(gr_line
		(start 484.880158 -58.103262)
		(end 485.58577 -58.103262)
		(stroke
			(width 0.05715)
			(type default)
		)
		(layer "B.Cu")
	)
	(gr_line
		(start 484.922576 -131.717542)
		(end 484.98506 -131.655058)
		(stroke
			(width 0.05715)
			(type default)
		)
		(layer "B.Cu")
	)
	(gr_line
		(start 484.98506 -131.655058)
		(end 485.750108 -131.655058)
		(stroke
			(width 0.05715)
			(type default)
		)
		(layer "B.Cu")
	)
	(gr_line
		(start 485.023922 -60.586874)
		(end 485.25938 -60.822332)
		(stroke
			(width 0.05715)
			(type default)
		)
		(layer "B.Cu")
	)
	(gr_line
		(start 485.023922 -60.242196)
		(end 485.256586 -60.009532)
		(stroke
			(width 0.05715)
			(type default)
		)
		(layer "B.Cu")
	)
	(gr_line
		(start 485.180386 -61.101732)
		(end 485.415844 -61.33719)
		(stroke
			(width 0.05715)
			(type default)
		)
		(layer "B.Cu")
	)
	(gr_line
		(start 485.18318 -61.914532)
		(end 485.415844 -61.681868)
		(stroke
			(width 0.05715)
			(type default)
		)
		(layer "B.Cu")
	)
	(gr_line
		(start 485.750108 -131.655058)
		(end 485.751124 -131.655312)
		(stroke
			(width 0.05715)
			(type default)
		)
		(layer "B.Cu")
	)
	(gr_line
		(start 486.652824 -61.119004)
		(end 486.858564 -61.324744)
		(stroke
			(width 0.05715)
			(type default)
		)
		(layer "B.Cu")
	)
	(gr_line
		(start 486.652824 -60.774072)
		(end 486.902252 -60.524644)
		(stroke
			(width 0.05715)
			(type default)
		)
		(layer "B.Cu")
	)
	(gr_line
		(start 486.858564 -61.324744)
		(end 487.49712 -61.324744)
		(stroke
			(width 0.05715)
			(type default)
		)
		(layer "B.Cu")
	)
	(gr_line
		(start 486.902252 -60.524644)
		(end 487.49712 -60.524644)
		(stroke
			(width 0.05715)
			(type default)
		)
		(layer "B.Cu")
	)
	(gr_line
		(start 489.925868 -55.880762)
		(end 489.925868 -56.464708)
		(stroke
			(width 0.05715)
			(type default)
		)
		(layer "B.Cu")
	)
	(gr_line
		(start 490.42574 -55.880762)
		(end 490.42574 -56.464708)
		(stroke
			(width 0.05715)
			(type default)
		)
		(layer "B.Cu")
	)
	(gr_line
		(start 491.425738 -55.880762)
		(end 491.425738 -56.464708)
		(stroke
			(width 0.05715)
			(type default)
		)
		(layer "B.Cu")
	)
	(gr_line
		(start 491.925864 -55.880762)
		(end 491.925864 -56.464708)
		(stroke
			(width 0.05715)
			(type default)
		)
		(layer "B.Cu")
	)
	(gr_line
		(start 1.1684 -67.0052)
		(end 2.8702 -68.707)
		(stroke
			(width 1.27)
			(type default)
		)
		(layer "In1.Cu")
	)
	(gr_line
		(start 1.1684 -60.1218)
		(end 1.1684 -67.0052)
		(stroke
			(width 1.27)
			(type default)
		)
		(layer "In1.Cu")
	)
	(gr_line
		(start 2.4384 -58.8518)
		(end 1.1684 -60.1218)
		(stroke
			(width 1.27)
			(type default)
		)
		(layer "In1.Cu")
	)
	(gr_line
		(start 2.4384 -50.0634)
		(end 2.4384 -58.8518)
		(stroke
			(width 1.27)
			(type default)
		)
		(layer "In1.Cu")
	)
	(gr_line
		(start 2.8702 -85.8266)
		(end 3.8608 -86.8172)
		(stroke
			(width 1.27)
			(type default)
		)
		(layer "In1.Cu")
	)
	(gr_line
		(start 2.8702 -68.707)
		(end 2.8702 -85.8266)
		(stroke
			(width 1.27)
			(type default)
		)
		(layer "In1.Cu")
	)
	(gr_line
		(start 3.0988 -49.403)
		(end 2.4384 -50.0634)
		(stroke
			(width 1.27)
			(type default)
		)
		(layer "In1.Cu")
	)
	(gr_line
		(start 3.8608 -86.8172)
		(end 10.107422 -86.8172)
		(stroke
			(width 1.27)
			(type default)
		)
		(layer "In1.Cu")
	)
	(gr_line
		(start 9.7282 -49.403)
		(end 3.0988 -49.403)
		(stroke
			(width 1.27)
			(type default)
		)
		(layer "In1.Cu")
	)
	(gr_line
		(start 10.107422 -86.8172)
		(end 10.727436 -86.197186)
		(stroke
			(width 1.27)
			(type default)
		)
		(layer "In1.Cu")
	)
	(gr_line
		(start 10.727436 -86.197186)
		(end 10.727436 -50.402236)
		(stroke
			(width 1.27)
			(type default)
		)
		(layer "In1.Cu")
	)
	(gr_line
		(start 10.727436 -50.402236)
		(end 9.7282 -49.403)
		(stroke
			(width 1.27)
			(type default)
		)
		(layer "In1.Cu")
	)
	(gr_line
		(start 12.611862 -65.975992)
		(end 14.99743 -68.36156)
		(stroke
			(width 1.016)
			(type default)
		)
		(layer "In1.Cu")
	)
	(gr_line
		(start 12.611862 -56.814466)
		(end 12.611862 -65.975992)
		(stroke
			(width 1.016)
			(type default)
		)
		(layer "In1.Cu")
	)
	(gr_line
		(start 13.243814 -56.182514)
		(end 12.611862 -56.814466)
		(stroke
			(width 1.016)
			(type default)
		)
		(layer "In1.Cu")
	)
	(gr_line
		(start 14.99743 -68.36156)
		(end 16.521684 -68.36156)
		(stroke
			(width 1.016)
			(type default)
		)
		(layer "In1.Cu")
	)
	(gr_line
		(start 16.521684 -68.36156)
		(end 18.74901 -68.36156)
		(stroke
			(width 1.016)
			(type default)
		)
		(layer "In1.Cu")
	)
	(gr_line
		(start 18.74901 -68.36156)
		(end 19.578066 -67.532504)
		(stroke
			(width 1.016)
			(type default)
		)
		(layer "In1.Cu")
	)
	(gr_line
		(start 18.906998 -56.182514)
		(end 13.243814 -56.182514)
		(stroke
			(width 1.016)
			(type default)
		)
		(layer "In1.Cu")
	)
	(gr_line
		(start 19.578066 -67.532504)
		(end 19.578066 -56.853582)
		(stroke
			(width 1.016)
			(type default)
		)
		(layer "In1.Cu")
	)
	(gr_line
		(start 19.578066 -56.853582)
		(end 18.906998 -56.182514)
		(stroke
			(width 1.016)
			(type default)
		)
		(layer "In1.Cu")
	)
	(gr_line
		(start 336.296 -24.257)
		(end 336.931 -24.892)
		(stroke
			(width 0.508)
			(type default)
		)
		(layer "In1.Cu")
	)
	(gr_line
		(start 336.296 -22.86)
		(end 336.296 -24.257)
		(stroke
			(width 0.508)
			(type default)
		)
		(layer "In1.Cu")
	)
	(gr_line
		(start 336.931 -24.892)
		(end 339.979 -24.892)
		(stroke
			(width 0.508)
			(type default)
		)
		(layer "In1.Cu")
	)
	(gr_line
		(start 337.82 -22.86)
		(end 336.296 -22.86)
		(stroke
			(width 0.508)
			(type default)
		)
		(layer "In1.Cu")
	)
	(gr_line
		(start 338.455 -23.368)
		(end 337.82 -22.86)
		(stroke
			(width 0.508)
			(type default)
		)
		(layer "In1.Cu")
	)
	(gr_line
		(start 339.979 -24.892)
		(end 340.36 -25.273)
		(stroke
			(width 0.508)
			(type default)
		)
		(layer "In1.Cu")
	)
	(gr_line
		(start 339.979 -22.225)
		(end 340.233 -22.479)
		(stroke
			(width 0.508)
			(type default)
		)
		(layer "In1.Cu")
	)
	(gr_line
		(start 339.979 -21.59)
		(end 339.979 -22.225)
		(stroke
			(width 0.508)
			(type default)
		)
		(layer "In1.Cu")
	)
	(gr_line
		(start 340.233 -22.479)
		(end 340.487 -22.479)
		(stroke
			(width 0.508)
			(type default)
		)
		(layer "In1.Cu")
	)
	(gr_line
		(start 340.233 -21.336)
		(end 339.979 -21.59)
		(stroke
			(width 0.508)
			(type default)
		)
		(layer "In1.Cu")
	)
	(gr_line
		(start 340.36 -25.781)
		(end 340.741 -26.162)
		(stroke
			(width 0.508)
			(type default)
		)
		(layer "In1.Cu")
	)
	(gr_line
		(start 340.36 -25.273)
		(end 340.36 -25.781)
		(stroke
			(width 0.508)
			(type default)
		)
		(layer "In1.Cu")
	)
	(gr_line
		(start 340.487 -22.479)
		(end 340.741 -22.733)
		(stroke
			(width 0.508)
			(type default)
		)
		(layer "In1.Cu")
	)
	(gr_line
		(start 340.614 -23.368)
		(end 338.455 -23.368)
		(stroke
			(width 0.508)
			(type default)
		)
		(layer "In1.Cu")
	)
	(gr_line
		(start 340.741 -26.162)
		(end 345.313 -26.162)
		(stroke
			(width 0.508)
			(type default)
		)
		(layer "In1.Cu")
	)
	(gr_line
		(start 340.741 -23.241)
		(end 340.614 -23.368)
		(stroke
			(width 0.508)
			(type default)
		)
		(layer "In1.Cu")
	)
	(gr_line
		(start 340.741 -22.733)
		(end 340.741 -23.241)
		(stroke
			(width 0.508)
			(type default)
		)
		(layer "In1.Cu")
	)
	(gr_line
		(start 340.995 -21.336)
		(end 340.233 -21.336)
		(stroke
			(width 0.508)
			(type default)
		)
		(layer "In1.Cu")
	)
	(gr_line
		(start 341.376 -21.717)
		(end 340.995 -21.336)
		(stroke
			(width 0.508)
			(type default)
		)
		(layer "In1.Cu")
	)
	(gr_line
		(start 342.646 -21.717)
		(end 341.376 -21.717)
		(stroke
			(width 0.508)
			(type default)
		)
		(layer "In1.Cu")
	)
	(gr_line
		(start 343.281 -22.352)
		(end 342.646 -21.717)
		(stroke
			(width 0.508)
			(type default)
		)
		(layer "In1.Cu")
	)
	(gr_line
		(start 345.059 -22.352)
		(end 343.281 -22.352)
		(stroke
			(width 0.508)
			(type default)
		)
		(layer "In1.Cu")
	)
	(gr_line
		(start 345.186 -22.225)
		(end 345.059 -22.352)
		(stroke
			(width 0.508)
			(type default)
		)
		(layer "In1.Cu")
	)
	(gr_line
		(start 345.186 -21.59)
		(end 345.186 -22.225)
		(stroke
			(width 0.508)
			(type default)
		)
		(layer "In1.Cu")
	)
	(gr_line
		(start 345.313 -26.162)
		(end 346.329 -25.146)
		(stroke
			(width 0.508)
			(type default)
		)
		(layer "In1.Cu")
	)
	(gr_line
		(start 345.313 -21.463)
		(end 345.186 -21.59)
		(stroke
			(width 0.508)
			(type default)
		)
		(layer "In1.Cu")
	)
	(gr_line
		(start 345.821 -21.463)
		(end 345.313 -21.463)
		(stroke
			(width 0.508)
			(type default)
		)
		(layer "In1.Cu")
	)
	(gr_line
		(start 346.202 -23.495)
		(end 346.202 -21.844)
		(stroke
			(width 0.508)
			(type default)
		)
		(layer "In1.Cu")
	)
	(gr_line
		(start 346.202 -21.844)
		(end 345.821 -21.463)
		(stroke
			(width 0.508)
			(type default)
		)
		(layer "In1.Cu")
	)
	(gr_line
		(start 346.329 -25.146)
		(end 346.329 -23.622)
		(stroke
			(width 0.508)
			(type default)
		)
		(layer "In1.Cu")
	)
	(gr_line
		(start 346.329 -23.622)
		(end 346.202 -23.495)
		(stroke
			(width 0.508)
			(type default)
		)
		(layer "In1.Cu")
	)
	(gr_line
		(start 429.82007 -137.109454)
		(end 431.09007 -137.109454)
		(stroke
			(width 0.2)
			(type default)
		)
		(layer "In1.Cu")
	)
	(gr_arc
		(start 429.82007 -135.580374)
		(mid 429.05553 -136.344914)
		(end 429.82007 -137.109454)
		(stroke
			(width 0.2)
			(type default)
		)
		(layer "In1.Cu")
	)
	(gr_arc
		(start 431.09007 -137.109454)
		(mid 431.629783 -136.886423)
		(end 431.85461 -136.347454)
		(stroke
			(width 0.2)
			(type default)
		)
		(layer "In1.Cu")
	)
	(gr_line
		(start 431.09007 -135.580374)
		(end 429.82007 -135.580374)
		(stroke
			(width 0.2)
			(type default)
		)
		(layer "In1.Cu")
	)
	(gr_line
		(start 431.666142 -136.347454)
		(end 431.666142 -136.344914)
		(stroke
			(width 0.2)
			(type default)
		)
		(layer "In1.Cu")
	)
	(gr_line
		(start 431.666142 -136.344914)
		(end 431.85461 -136.344914)
		(stroke
			(width 0.2)
			(type default)
		)
		(layer "In1.Cu")
	)
	(gr_line
		(start 431.85461 -136.347454)
		(end 431.666142 -136.347454)
		(stroke
			(width 0.2)
			(type default)
		)
		(layer "In1.Cu")
	)
	(gr_arc
		(start 431.85461 -136.344914)
		(mid 431.630681 -135.804303)
		(end 431.09007 -135.580374)
		(stroke
			(width 0.2)
			(type default)
		)
		(layer "In1.Cu")
	)
	(gr_line
		(start 433.63007 -137.109454)
		(end 434.90007 -137.109454)
		(stroke
			(width 0.2)
			(type default)
		)
		(layer "In1.Cu")
	)
	(gr_arc
		(start 433.63007 -135.580374)
		(mid 432.86553 -136.344914)
		(end 433.63007 -137.109454)
		(stroke
			(width 0.2)
			(type default)
		)
		(layer "In1.Cu")
	)
	(gr_arc
		(start 434.90007 -137.109454)
		(mid 435.439783 -136.886423)
		(end 435.66461 -136.347454)
		(stroke
			(width 0.2)
			(type default)
		)
		(layer "In1.Cu")
	)
	(gr_line
		(start 434.90007 -135.580374)
		(end 433.63007 -135.580374)
		(stroke
			(width 0.2)
			(type default)
		)
		(layer "In1.Cu")
	)
	(gr_line
		(start 435.473856 -136.347454)
		(end 435.473856 -136.344914)
		(stroke
			(width 0.2)
			(type default)
		)
		(layer "In1.Cu")
	)
	(gr_line
		(start 435.473856 -136.344914)
		(end 435.66461 -136.344914)
		(stroke
			(width 0.2)
			(type default)
		)
		(layer "In1.Cu")
	)
	(gr_line
		(start 435.66461 -136.347454)
		(end 435.473856 -136.347454)
		(stroke
			(width 0.2)
			(type default)
		)
		(layer "In1.Cu")
	)
	(gr_arc
		(start 435.66461 -136.344914)
		(mid 435.440681 -135.804303)
		(end 434.90007 -135.580374)
		(stroke
			(width 0.2)
			(type default)
		)
		(layer "In1.Cu")
	)
	(gr_rect
		(start 485.2416 -49.9999)
		(end 485.7496 -51.3969)
		(stroke
			(width 0)
			(type default)
		)
		(fill no)
		(layer "In1.Cu")
	)
	(gr_rect
		(start 486.1306 -49.9999)
		(end 486.6386 -51.3969)
		(stroke
			(width 0)
			(type default)
		)
		(fill no)
		(layer "In1.Cu")
	)
	(gr_poly
		(pts
			(xy 367.6396 -105.9434) (xy 364.9726 -105.9434) (xy 364.9726 -108.9152) (xy 365.252 -109.1946) (xy 367.6396 -109.1946)
		)
		(stroke
			(width 0)
			(type solid)
		)
		(fill yes)
		(layer "In2.Cu")
		(net "GND")
	)
	(gr_poly
		(pts
			(xy 65.480184 -98.931222) (xy 65.448688 -98.899726) (xy 65.249552 -98.826066) (xy 65.087754 -98.987864)
			(xy 65.161414 -99.187) (xy 65.19291 -99.218496)
		)
		(stroke
			(width 0)
			(type solid)
		)
		(fill yes)
		(layer "In2.Cu")
		(net "M_K_DQ<18>")
	)
	(gr_poly
		(pts
			(xy 65.55486 -95.351346) (xy 65.523364 -95.320104) (xy 65.323974 -95.246444) (xy 65.16243 -95.407988)
			(xy 65.23609 -95.607378) (xy 65.267332 -95.638874)
		)
		(stroke
			(width 0)
			(type solid)
		)
		(fill yes)
		(layer "In2.Cu")
		(net "M_K_DQS_DN<2>")
	)
	(gr_poly
		(pts
			(xy 65.719706 -99.29622) (xy 65.646046 -99.097084) (xy 65.61455 -99.065588) (xy 65.327276 -99.352862)
			(xy 65.358772 -99.384358) (xy 65.557908 -99.458018)
		)
		(stroke
			(width 0)
			(type solid)
		)
		(fill yes)
		(layer "In2.Cu")
		(net "M_K_DQ<19>")
	)
	(gr_poly
		(pts
			(xy 65.794636 -95.716852) (xy 65.720976 -95.517716) (xy 65.68948 -95.48622) (xy 65.402206 -95.773494)
			(xy 65.433702 -95.80499) (xy 65.632838 -95.87865)
		)
		(stroke
			(width 0)
			(type solid)
		)
		(fill yes)
		(layer "In2.Cu")
		(net "M_K_DQS_DP<2>")
	)
	(gr_poly
		(pts
			(xy 65.893188 -101.921818) (xy 65.861692 -101.890322) (xy 65.662556 -101.816662) (xy 65.500758 -101.97846)
			(xy 65.574418 -102.177596) (xy 65.605914 -102.209092)
		)
		(stroke
			(width 0)
			(type solid)
		)
		(fill yes)
		(layer "In2.Cu")
		(net "M_K_DQ<28>")
	)
	(gr_poly
		(pts
			(xy 66.13271 -102.286816) (xy 66.05905 -102.08768) (xy 66.027554 -102.056184) (xy 65.74028 -102.343458)
			(xy 65.771776 -102.374954) (xy 65.970912 -102.448614)
		)
		(stroke
			(width 0)
			(type solid)
		)
		(fill yes)
		(layer "In2.Cu")
		(net "M_K_DQ<29>")
	)
	(gr_poly
		(pts
			(xy 66.180716 -98.23069) (xy 66.14922 -98.199194) (xy 65.94983 -98.125534) (xy 65.788286 -98.287332)
			(xy 65.861946 -98.486722) (xy 65.893442 -98.517964)
		)
		(stroke
			(width 0)
			(type solid)
		)
		(fill yes)
		(layer "In2.Cu")
		(net "M_K_DQ<18>")
	)
	(gr_poly
		(pts
			(xy 66.255392 -94.650814) (xy 66.223896 -94.619572) (xy 66.024506 -94.545912) (xy 65.862962 -94.707456)
			(xy 65.936622 -94.906846) (xy 65.967864 -94.938342)
		)
		(stroke
			(width 0)
			(type solid)
		)
		(fill yes)
		(layer "In2.Cu")
		(net "M_K_DQS_DN<2>")
	)
	(gr_poly
		(pts
			(xy 66.310256 -95.71101) (xy 66.27876 -95.679514) (xy 66.07937 -95.605854) (xy 65.917826 -95.767652)
			(xy 65.991486 -95.967042) (xy 66.022982 -95.998284)
		)
		(stroke
			(width 0)
			(type solid)
		)
		(fill yes)
		(layer "In2.Cu")
		(net "M_K_DQ<22>")
	)
	(gr_poly
		(pts
			(xy 66.333116 -56.729122) (xy 66.364612 -56.69788) (xy 66.077338 -56.410098) (xy 66.046096 -56.441594)
			(xy 65.972182 -56.640984) (xy 66.133726 -56.802782)
		)
		(stroke
			(width 0)
			(type solid)
		)
		(fill yes)
		(layer "In2.Cu")
		(net "M_G_DQS_DP<11>")
	)
	(gr_poly
		(pts
			(xy 66.420238 -98.595942) (xy 66.346578 -98.396552) (xy 66.315082 -98.365056) (xy 66.027808 -98.65233)
			(xy 66.05905 -98.683826) (xy 66.25844 -98.757486)
		)
		(stroke
			(width 0)
			(type solid)
		)
		(fill yes)
		(layer "In2.Cu")
		(net "M_K_DQ<19>")
	)
	(gr_poly
		(pts
			(xy 66.495168 -95.01632) (xy 66.421508 -94.817184) (xy 66.390012 -94.785688) (xy 66.102738 -95.072962)
			(xy 66.134234 -95.104458) (xy 66.33337 -95.178118)
		)
		(stroke
			(width 0)
			(type solid)
		)
		(fill yes)
		(layer "In2.Cu")
		(net "M_K_DQS_DP<2>")
	)
	(gr_poly
		(pts
			(xy 66.530982 -56.53151) (xy 66.604896 -56.332374) (xy 66.443352 -56.170576) (xy 66.243962 -56.243982)
			(xy 66.212466 -56.275478) (xy 66.499486 -56.563006)
		)
		(stroke
			(width 0)
			(type solid)
		)
		(fill yes)
		(layer "In2.Cu")
		(net "M_G_DQS_DN<11>")
	)
	(gr_poly
		(pts
			(xy 66.549524 -96.076262) (xy 66.476118 -95.876872) (xy 66.444622 -95.845376) (xy 66.157094 -96.13265)
			(xy 66.18859 -96.164146) (xy 66.38798 -96.237806)
		)
		(stroke
			(width 0)
			(type solid)
		)
		(fill yes)
		(layer "In2.Cu")
		(net "M_K_DQ<23>")
	)
	(gr_poly
		(pts
			(xy 66.554096 -97.374964) (xy 66.554096 -96.968818) (xy 66.509392 -96.968818) (xy 66.316352 -97.057718)
			(xy 66.316606 -97.286318) (xy 66.509646 -97.375218)
		)
		(stroke
			(width 0)
			(type solid)
		)
		(fill yes)
		(layer "In2.Cu")
		(net "M_K_DQ<18>")
	)
	(gr_poly
		(pts
			(xy 66.774822 -93.844364) (xy 66.774822 -93.799914) (xy 66.368422 -93.799914) (xy 66.368422 -93.844364)
			(xy 66.457322 -94.037404) (xy 66.685922 -94.037404)
		)
		(stroke
			(width 0)
			(type solid)
		)
		(fill yes)
		(layer "In2.Cu")
		(net "M_K_DQS_DN<11>")
	)
	(gr_poly
		(pts
			(xy 66.774822 -93.564964) (xy 66.685922 -93.371924) (xy 66.457322 -93.371924) (xy 66.368422 -93.564964)
			(xy 66.368422 -93.609414) (xy 66.774822 -93.609414)
		)
		(stroke
			(width 0)
			(type solid)
		)
		(fill yes)
		(layer "In2.Cu")
		(net "M_K_DQS_DP<11>")
	)
	(gr_poly
		(pts
			(xy 66.795142 -102.818184) (xy 66.7639 -102.786688) (xy 66.56451 -102.713028) (xy 66.402712 -102.874572)
			(xy 66.476372 -103.073962) (xy 66.507868 -103.105458)
		)
		(stroke
			(width 0)
			(type solid)
		)
		(fill yes)
		(layer "In2.Cu")
		(net "M_K_DQ<24>")
	)
	(gr_poly
		(pts
			(xy 66.981578 -97.286318) (xy 66.981578 -97.057718) (xy 66.788538 -96.968818) (xy 66.744088 -96.968818)
			(xy 66.744088 -97.374964) (xy 66.788538 -97.375218)
		)
		(stroke
			(width 0)
			(type solid)
		)
		(fill yes)
		(layer "In2.Cu")
		(net "M_K_DQ<19>")
	)
	(gr_poly
		(pts
			(xy 67.034664 -103.183182) (xy 66.961004 -102.983792) (xy 66.929508 -102.95255) (xy 66.642234 -103.239824)
			(xy 66.67373 -103.27132) (xy 66.87312 -103.34498)
		)
		(stroke
			(width 0)
			(type solid)
		)
		(fill yes)
		(layer "In2.Cu")
		(net "M_K_DQ<25>")
	)
	(gr_poly
		(pts
			(xy 67.171824 -100.942648) (xy 67.140328 -100.911406) (xy 66.940938 -100.837746) (xy 66.779394 -100.99929)
			(xy 66.853054 -101.19868) (xy 66.88455 -101.230176)
		)
		(stroke
			(width 0)
			(type solid)
		)
		(fill yes)
		(layer "In2.Cu")
		(net "M_K_DQ<28>")
	)
	(gr_poly
		(pts
			(xy 67.263772 -59.109102) (xy 67.263772 -59.064652) (xy 66.857372 -59.064652) (xy 66.857372 -59.109102)
			(xy 66.946272 -59.302142) (xy 67.174872 -59.302142)
		)
		(stroke
			(width 0)
			(type solid)
		)
		(fill yes)
		(layer "In2.Cu")
		(net "M_G_DQ<20>")
	)
	(gr_poly
		(pts
			(xy 67.263772 -58.829702) (xy 67.174872 -58.636662) (xy 66.946272 -58.636662) (xy 66.857372 -58.829702)
			(xy 66.857372 -58.874152) (xy 67.263772 -58.874152)
		)
		(stroke
			(width 0)
			(type solid)
		)
		(fill yes)
		(layer "In2.Cu")
		(net "M_G_DQ<21>")
	)
	(gr_poly
		(pts
			(xy 67.286886 -95.469456) (xy 67.286886 -95.425006) (xy 66.880486 -95.425006) (xy 66.880486 -95.469456)
			(xy 66.969386 -95.662496) (xy 67.197986 -95.662496)
		)
		(stroke
			(width 0)
			(type solid)
		)
		(fill yes)
		(layer "In2.Cu")
		(net "M_K_DQ<23>")
	)
	(gr_poly
		(pts
			(xy 67.286886 -95.190564) (xy 67.197986 -94.997524) (xy 66.969386 -94.997524) (xy 66.880486 -95.190564)
			(xy 66.880486 -95.235014) (xy 67.286886 -95.235014)
		)
		(stroke
			(width 0)
			(type solid)
		)
		(fill yes)
		(layer "In2.Cu")
		(net "M_K_DQ<22>")
	)
	(gr_poly
		(pts
			(xy 67.411346 -101.3079) (xy 67.337686 -101.10851) (xy 67.30619 -101.077014) (xy 67.018916 -101.364542)
			(xy 67.050412 -101.395784) (xy 67.249802 -101.469444)
		)
		(stroke
			(width 0)
			(type solid)
		)
		(fill yes)
		(layer "In2.Cu")
		(net "M_K_DQ<29>")
	)
	(gr_poly
		(pts
			(xy 67.495674 -102.117652) (xy 67.464178 -102.086156) (xy 67.265042 -102.012496) (xy 67.103244 -102.174294)
			(xy 67.176904 -102.37343) (xy 67.2084 -102.404926)
		)
		(stroke
			(width 0)
			(type solid)
		)
		(fill yes)
		(layer "In2.Cu")
		(net "M_K_DQ<24>")
	)
	(gr_poly
		(pts
			(xy 67.499992 -94.682564) (xy 67.499992 -94.638114) (xy 67.093592 -94.638114) (xy 67.093592 -94.682564)
			(xy 67.182492 -94.875604) (xy 67.411092 -94.875604)
		)
		(stroke
			(width 0)
			(type solid)
		)
		(fill yes)
		(layer "In2.Cu")
		(net "M_K_DQS_DP<2>")
	)
	(gr_poly
		(pts
			(xy 67.499992 -94.403164) (xy 67.411092 -94.210124) (xy 67.182492 -94.210124) (xy 67.093592 -94.403164)
			(xy 67.093592 -94.447614) (xy 67.499992 -94.447614)
		)
		(stroke
			(width 0)
			(type solid)
		)
		(fill yes)
		(layer "In2.Cu")
		(net "M_K_DQS_DN<2>")
	)
	(gr_poly
		(pts
			(xy 67.666362 -91.341956) (xy 67.666362 -91.297506) (xy 67.259962 -91.297506) (xy 67.259962 -91.341956)
			(xy 67.348862 -91.534996) (xy 67.577462 -91.534996)
		)
		(stroke
			(width 0)
			(type solid)
		)
		(fill yes)
		(layer "In2.Cu")
		(net "M_K_DQ<21>")
	)
	(gr_poly
		(pts
			(xy 67.677792 -58.297064) (xy 67.677792 -58.252614) (xy 67.271392 -58.252614) (xy 67.271392 -58.297064)
			(xy 67.360292 -58.490104) (xy 67.588892 -58.490104)
		)
		(stroke
			(width 0)
			(type solid)
		)
		(fill yes)
		(layer "In2.Cu")
		(net "M_G_DQ<16>")
	)
	(gr_poly
		(pts
			(xy 67.715638 -92.102686) (xy 67.626738 -91.909646) (xy 67.398138 -91.909646) (xy 67.309238 -92.102686)
			(xy 67.309238 -92.147136) (xy 67.715638 -92.147136)
		)
		(stroke
			(width 0)
			(type solid)
		)
		(fill yes)
		(layer "In2.Cu")
		(net "M_K_DQ<16>")
	)
	(gr_poly
		(pts
			(xy 67.735196 -102.48265) (xy 67.661536 -102.283514) (xy 67.63004 -102.252018) (xy 67.342766 -102.539292)
			(xy 67.374262 -102.570788) (xy 67.573398 -102.644448)
		)
		(stroke
			(width 0)
			(type solid)
		)
		(fill yes)
		(layer "In2.Cu")
		(net "M_K_DQ<25>")
	)
	(gr_poly
		(pts
			(xy 67.791584 -96.231456) (xy 67.791584 -96.187006) (xy 67.385184 -96.187006) (xy 67.385184 -96.231456)
			(xy 67.474084 -96.424496) (xy 67.702684 -96.424496)
		)
		(stroke
			(width 0)
			(type solid)
		)
		(fill yes)
		(layer "In2.Cu")
		(net "M_K_DQ<19>")
	)
	(gr_poly
		(pts
			(xy 67.791584 -95.952564) (xy 67.702684 -95.759524) (xy 67.474084 -95.759524) (xy 67.385184 -95.952564)
			(xy 67.385184 -95.997014) (xy 67.791584 -95.997014)
		)
		(stroke
			(width 0)
			(type solid)
		)
		(fill yes)
		(layer "In2.Cu")
		(net "M_K_DQ<18>")
	)
	(gr_poly
		(pts
			(xy 67.804792 -58.017664) (xy 67.715892 -57.824624) (xy 67.487292 -57.824624) (xy 67.398392 -58.017664)
			(xy 67.398392 -58.062114) (xy 67.804792 -58.062114)
		)
		(stroke
			(width 0)
			(type solid)
		)
		(fill yes)
		(layer "In2.Cu")
		(net "M_G_DQ<17>")
	)
	(gr_poly
		(pts
			(xy 67.817238 -92.382086) (xy 67.817238 -92.337636) (xy 67.410838 -92.337636) (xy 67.410838 -92.382086)
			(xy 67.499738 -92.575126) (xy 67.728338 -92.575126)
		)
		(stroke
			(width 0)
			(type solid)
		)
		(fill yes)
		(layer "In2.Cu")
		(net "M_K_DQ<17>")
	)
	(gr_poly
		(pts
			(xy 67.842384 -57.21604) (xy 67.842384 -57.17159) (xy 67.435984 -57.17159) (xy 67.435984 -57.21604)
			(xy 67.524884 -57.40908) (xy 67.753484 -57.40908)
		)
		(stroke
			(width 0)
			(type solid)
		)
		(fill yes)
		(layer "In2.Cu")
		(net "M_G_DQS_DP<11>")
	)
	(gr_poly
		(pts
			(xy 67.842384 -56.93664) (xy 67.753484 -56.7436) (xy 67.524884 -56.7436) (xy 67.435984 -56.93664)
			(xy 67.435984 -56.98109) (xy 67.842384 -56.98109)
		)
		(stroke
			(width 0)
			(type solid)
		)
		(fill yes)
		(layer "In2.Cu")
		(net "M_G_DQS_DN<11>")
	)
	(gr_poly
		(pts
			(xy 67.872356 -100.242116) (xy 67.84086 -100.210874) (xy 67.64147 -100.137214) (xy 67.479926 -100.298758)
			(xy 67.553586 -100.498148) (xy 67.585082 -100.529644)
		)
		(stroke
			(width 0)
			(type solid)
		)
		(fill yes)
		(layer "In2.Cu")
		(net "M_K_DQ<28>")
	)
	(gr_poly
		(pts
			(xy 68.015358 -59.53125) (xy 68.046854 -59.500008) (xy 67.759326 -59.21248) (xy 67.728084 -59.243976)
			(xy 67.654424 -59.443366) (xy 67.815968 -59.60491)
		)
		(stroke
			(width 0)
			(type solid)
		)
		(fill yes)
		(layer "In2.Cu")
		(net "M_G_DQ<20>")
	)
	(gr_poly
		(pts
			(xy 68.111878 -100.607368) (xy 68.038218 -100.407978) (xy 68.006722 -100.376482) (xy 67.719448 -100.66401)
			(xy 67.750944 -100.695252) (xy 67.950334 -100.768912)
		)
		(stroke
			(width 0)
			(type solid)
		)
		(fill yes)
		(layer "In2.Cu")
		(net "M_K_DQ<29>")
	)
	(gr_poly
		(pts
			(xy 68.196206 -101.41712) (xy 68.16471 -101.385624) (xy 67.96532 -101.311964) (xy 67.803776 -101.473762)
			(xy 67.877436 -101.673152) (xy 67.908932 -101.704394)
		)
		(stroke
			(width 0)
			(type solid)
		)
		(fill yes)
		(layer "In2.Cu")
		(net "M_K_DQ<24>")
	)
	(gr_poly
		(pts
			(xy 68.212462 -59.334146) (xy 68.286122 -59.134756) (xy 68.124578 -58.973212) (xy 67.925188 -59.046872)
			(xy 67.893692 -59.078114) (xy 68.18122 -59.365642)
		)
		(stroke
			(width 0)
			(type solid)
		)
		(fill yes)
		(layer "In2.Cu")
		(net "M_G_DQ<21>")
	)
	(gr_poly
		(pts
			(xy 68.256912 -58.630058) (xy 68.288408 -58.598562) (xy 68.001134 -58.311288) (xy 67.969638 -58.342784)
			(xy 67.895978 -58.54192) (xy 68.057776 -58.703718)
		)
		(stroke
			(width 0)
			(type solid)
		)
		(fill yes)
		(layer "In2.Cu")
		(net "M_G_DQ<16>")
	)
	(gr_poly
		(pts
			(xy 68.277486 -95.469456) (xy 68.277486 -95.425006) (xy 67.871086 -95.425006) (xy 67.871086 -95.469456)
			(xy 67.959986 -95.662496) (xy 68.188586 -95.662496)
		)
		(stroke
			(width 0)
			(type solid)
		)
		(fill yes)
		(layer "In2.Cu")
		(net "M_K_DQ<23>")
	)
	(gr_poly
		(pts
			(xy 68.277486 -95.190564) (xy 68.188586 -94.997524) (xy 67.959986 -94.997524) (xy 67.871086 -95.190564)
			(xy 67.871086 -95.235014) (xy 68.277486 -95.235014)
		)
		(stroke
			(width 0)
			(type solid)
		)
		(fill yes)
		(layer "In2.Cu")
		(net "M_K_DQ<22>")
	)
	(gr_poly
		(pts
			(xy 68.326254 -54.570122) (xy 68.357496 -54.538626) (xy 68.070222 -54.251352) (xy 68.038726 -54.282848)
			(xy 67.965066 -54.482238) (xy 68.126864 -54.643782)
		)
		(stroke
			(width 0)
			(type solid)
		)
		(fill yes)
		(layer "In2.Cu")
		(net "M_G_DQ<22>")
	)
	(gr_poly
		(pts
			(xy 68.435728 -101.782372) (xy 68.362068 -101.582982) (xy 68.330572 -101.551486) (xy 68.043298 -101.83876)
			(xy 68.07454 -101.870256) (xy 68.27393 -101.943916)
		)
		(stroke
			(width 0)
			(type solid)
		)
		(fill yes)
		(layer "In2.Cu")
		(net "M_K_DQ<25>")
	)
	(gr_poly
		(pts
			(xy 68.45427 -58.4327) (xy 68.52793 -58.233564) (xy 68.366132 -58.071766) (xy 68.166996 -58.145426)
			(xy 68.1355 -58.176922) (xy 68.422774 -58.464196)
		)
		(stroke
			(width 0)
			(type solid)
		)
		(fill yes)
		(layer "In2.Cu")
		(net "M_G_DQ<17>")
	)
	(gr_poly
		(pts
			(xy 68.468494 -104.053894) (xy 68.436998 -104.022652) (xy 68.237354 -103.9495) (xy 68.076064 -104.111552)
			(xy 68.150232 -104.310688) (xy 68.181728 -104.34193)
		)
		(stroke
			(width 0)
			(type solid)
		)
		(fill yes)
		(layer "In2.Cu")
		(net "M_K_DQS_DN<3>")
	)
	(gr_poly
		(pts
			(xy 68.490592 -94.682564) (xy 68.490592 -94.638114) (xy 68.084192 -94.638114) (xy 68.084192 -94.682564)
			(xy 68.173092 -94.875604) (xy 68.401692 -94.875604)
		)
		(stroke
			(width 0)
			(type solid)
		)
		(fill yes)
		(layer "In2.Cu")
		(net "M_K_DQS_DP<2>")
	)
	(gr_poly
		(pts
			(xy 68.490592 -94.403164) (xy 68.401692 -94.210124) (xy 68.173092 -94.210124) (xy 68.084192 -94.403164)
			(xy 68.084192 -94.447614) (xy 68.490592 -94.447614)
		)
		(stroke
			(width 0)
			(type solid)
		)
		(fill yes)
		(layer "In2.Cu")
		(net "M_K_DQS_DN<2>")
	)
	(gr_poly
		(pts
			(xy 68.523358 -54.373018) (xy 68.597018 -54.173628) (xy 68.435474 -54.01183) (xy 68.236084 -54.08549)
			(xy 68.204588 -54.116986) (xy 68.491862 -54.40426)
		)
		(stroke
			(width 0)
			(type solid)
		)
		(fill yes)
		(layer "In2.Cu")
		(net "M_G_DQ<23>")
	)
	(gr_poly
		(pts
			(xy 68.543932 -57.571386) (xy 68.575174 -57.53989) (xy 68.2879 -57.252616) (xy 68.256404 -57.284112)
			(xy 68.182744 -57.483502) (xy 68.344542 -57.645046)
		)
		(stroke
			(width 0)
			(type solid)
		)
		(fill yes)
		(layer "In2.Cu")
		(net "M_G_DQS_DP<11>")
	)
	(gr_poly
		(pts
			(xy 68.656962 -91.341956) (xy 68.656962 -91.297506) (xy 68.250562 -91.297506) (xy 68.250562 -91.341956)
			(xy 68.339462 -91.534996) (xy 68.568062 -91.534996)
		)
		(stroke
			(width 0)
			(type solid)
		)
		(fill yes)
		(layer "In2.Cu")
		(net "M_K_DQ<21>")
	)
	(gr_poly
		(pts
			(xy 68.656962 -91.063064) (xy 68.568062 -90.870024) (xy 68.339462 -90.870024) (xy 68.250562 -91.063064)
			(xy 68.250562 -91.107514) (xy 68.656962 -91.107514)
		)
		(stroke
			(width 0)
			(type solid)
		)
		(fill yes)
		(layer "In2.Cu")
		(net "M_K_DQ<20>")
	)
	(gr_poly
		(pts
			(xy 68.670424 -56.173878) (xy 68.70192 -56.142636) (xy 68.414392 -55.855108) (xy 68.38315 -55.886604)
			(xy 68.30949 -56.085994) (xy 68.471034 -56.247538)
		)
		(stroke
			(width 0)
			(type solid)
		)
		(fill yes)
		(layer "In2.Cu")
		(net "M_G_DQS_DN<2>")
	)
	(gr_poly
		(pts
			(xy 68.706238 -92.102686) (xy 68.617338 -91.909646) (xy 68.388738 -91.909646) (xy 68.299838 -92.102686)
			(xy 68.299838 -92.147136) (xy 68.706238 -92.147136)
		)
		(stroke
			(width 0)
			(type solid)
		)
		(fill yes)
		(layer "In2.Cu")
		(net "M_K_DQ<16>")
	)
	(gr_poly
		(pts
			(xy 68.708524 -57.340754) (xy 68.782184 -57.141618) (xy 68.620386 -56.97982) (xy 68.42125 -57.05348)
			(xy 68.389754 -57.084976) (xy 68.677028 -57.37225)
		)
		(stroke
			(width 0)
			(type solid)
		)
		(fill yes)
		(layer "In2.Cu")
		(net "M_G_DQS_DN<11>")
	)
	(gr_poly
		(pts
			(xy 68.709286 -104.4194) (xy 68.635118 -104.22001) (xy 68.603622 -104.188768) (xy 68.316856 -104.476804)
			(xy 68.348352 -104.508046) (xy 68.547996 -104.581198)
		)
		(stroke
			(width 0)
			(type solid)
		)
		(fill yes)
		(layer "In2.Cu")
		(net "M_K_DQS_DP<3>")
	)
	(gr_poly
		(pts
			(xy 68.732908 -93.2688) (xy 68.732908 -93.22435) (xy 68.326508 -93.22435) (xy 68.326508 -93.2688)
			(xy 68.415408 -93.46184) (xy 68.644008 -93.46184)
		)
		(stroke
			(width 0)
			(type solid)
		)
		(fill yes)
		(layer "In2.Cu")
		(net "M_K_DQS_DN<11>")
	)
	(gr_poly
		(pts
			(xy 68.732908 -92.9894) (xy 68.644008 -92.79636) (xy 68.415408 -92.79636) (xy 68.326508 -92.9894)
			(xy 68.326508 -93.03385) (xy 68.732908 -93.03385)
		)
		(stroke
			(width 0)
			(type solid)
		)
		(fill yes)
		(layer "In2.Cu")
		(net "M_K_DQS_DP<11>")
	)
	(gr_poly
		(pts
			(xy 68.744084 -53.26507) (xy 68.766436 -53.226462) (xy 68.420996 -53.027072) (xy 68.398898 -53.06568)
			(xy 68.39077 -53.25745) (xy 68.582032 -53.36794)
		)
		(stroke
			(width 0)
			(type solid)
		)
		(fill yes)
		(layer "In2.Cu")
		(net "M_G_DQ<18>")
	)
	(gr_poly
		(pts
			(xy 68.76415 -99.56038) (xy 68.741798 -99.522026) (xy 68.579746 -99.419156) (xy 68.388484 -99.529646)
			(xy 68.396612 -99.721416) (xy 68.41871 -99.75977)
		)
		(stroke
			(width 0)
			(type solid)
		)
		(fill yes)
		(layer "In2.Cu")
		(net "M_K_DQ<28>")
	)
	(gr_poly
		(pts
			(xy 68.782184 -96.231456) (xy 68.782184 -96.187006) (xy 68.375784 -96.187006) (xy 68.375784 -96.231456)
			(xy 68.464684 -96.424496) (xy 68.693284 -96.424496)
		)
		(stroke
			(width 0)
			(type solid)
		)
		(fill yes)
		(layer "In2.Cu")
		(net "M_K_DQ<19>")
	)
	(gr_poly
		(pts
			(xy 68.782184 -95.952564) (xy 68.693284 -95.759524) (xy 68.464684 -95.759524) (xy 68.375784 -95.952564)
			(xy 68.375784 -95.997014) (xy 68.782184 -95.997014)
		)
		(stroke
			(width 0)
			(type solid)
		)
		(fill yes)
		(layer "In2.Cu")
		(net "M_K_DQ<18>")
	)
	(gr_poly
		(pts
			(xy 68.807838 -92.382086) (xy 68.807838 -92.337636) (xy 68.401438 -92.337636) (xy 68.401438 -92.382086)
			(xy 68.490338 -92.575126) (xy 68.718938 -92.575126)
		)
		(stroke
			(width 0)
			(type solid)
		)
		(fill yes)
		(layer "In2.Cu")
		(net "M_K_DQ<17>")
	)
	(gr_poly
		(pts
			(xy 68.868036 -55.976266) (xy 68.941696 -55.77713) (xy 68.779898 -55.615332) (xy 68.580762 -55.688992)
			(xy 68.549266 -55.720488) (xy 68.83654 -56.007762)
		)
		(stroke
			(width 0)
			(type solid)
		)
		(fill yes)
		(layer "In2.Cu")
		(net "M_G_DQS_DP<2>")
	)
	(gr_poly
		(pts
			(xy 69.026532 -55.270654) (xy 69.058028 -55.239158) (xy 68.770754 -54.951884) (xy 68.739258 -54.98338)
			(xy 68.665598 -55.182516) (xy 68.827396 -55.344314)
		)
		(stroke
			(width 0)
			(type solid)
		)
		(fill yes)
		(layer "In2.Cu")
		(net "M_G_DQ<22>")
	)
	(gr_poly
		(pts
			(xy 69.167248 -103.351838) (xy 69.135752 -103.320596) (xy 68.936108 -103.24719) (xy 68.774818 -103.409242)
			(xy 68.848986 -103.608632) (xy 68.880482 -103.639874)
		)
		(stroke
			(width 0)
			(type solid)
		)
		(fill yes)
		(layer "In2.Cu")
		(net "M_K_DQS_DN<3>")
	)
	(gr_poly
		(pts
			(xy 69.180964 -58.701686) (xy 69.180964 -58.657236) (xy 68.774564 -58.657236) (xy 68.774564 -58.701686)
			(xy 68.863464 -58.894726) (xy 69.092064 -58.894726)
		)
		(stroke
			(width 0)
			(type solid)
		)
		(fill yes)
		(layer "In2.Cu")
		(net "M_G_DQ<16>")
	)
	(gr_poly
		(pts
			(xy 69.180964 -58.422286) (xy 69.092064 -58.229246) (xy 68.863464 -58.229246) (xy 68.774564 -58.422286)
			(xy 68.774564 -58.466736) (xy 69.180964 -58.466736)
		)
		(stroke
			(width 0)
			(type solid)
		)
		(fill yes)
		(layer "In2.Cu")
		(net "M_G_DQ<17>")
	)
	(gr_poly
		(pts
			(xy 69.182742 -59.692286) (xy 69.182742 -59.647836) (xy 68.776342 -59.647836) (xy 68.776342 -59.692286)
			(xy 68.865242 -59.885326) (xy 69.093842 -59.885326)
		)
		(stroke
			(width 0)
			(type solid)
		)
		(fill yes)
		(layer "In2.Cu")
		(net "M_G_DQ<20>")
	)
	(gr_poly
		(pts
			(xy 69.182742 -59.412886) (xy 69.093842 -59.219846) (xy 68.865242 -59.219846) (xy 68.776342 -59.412886)
			(xy 68.776342 -59.457336) (xy 69.182742 -59.457336)
		)
		(stroke
			(width 0)
			(type solid)
		)
		(fill yes)
		(layer "In2.Cu")
		(net "M_G_DQ<21>")
	)
	(gr_poly
		(pts
			(xy 69.22389 -55.073296) (xy 69.29755 -54.87416) (xy 69.135752 -54.712362) (xy 68.936616 -54.786022)
			(xy 68.90512 -54.817518) (xy 69.192394 -55.104792)
		)
		(stroke
			(width 0)
			(type solid)
		)
		(fill yes)
		(layer "In2.Cu")
		(net "M_G_DQ<23>")
	)
	(gr_poly
		(pts
			(xy 69.268086 -95.469456) (xy 69.268086 -95.425006) (xy 68.861686 -95.425006) (xy 68.861686 -95.469456)
			(xy 68.950586 -95.662496) (xy 69.179186 -95.662496)
		)
		(stroke
			(width 0)
			(type solid)
		)
		(fill yes)
		(layer "In2.Cu")
		(net "M_K_DQ<23>")
	)
	(gr_poly
		(pts
			(xy 69.268086 -95.190564) (xy 69.179186 -94.997524) (xy 68.950586 -94.997524) (xy 68.861686 -95.190564)
			(xy 68.861686 -95.235014) (xy 69.268086 -95.235014)
		)
		(stroke
			(width 0)
			(type solid)
		)
		(fill yes)
		(layer "In2.Cu")
		(net "M_K_DQ<22>")
	)
	(gr_poly
		(pts
			(xy 69.321934 -101.891084) (xy 69.26453 -101.70795) (xy 69.233034 -101.676454) (xy 68.951094 -101.958648)
			(xy 68.98259 -101.98989) (xy 69.165724 -102.047294)
		)
		(stroke
			(width 0)
			(type solid)
		)
		(fill yes)
		(layer "In2.Cu")
		(net "M_K_DQS_DN<12>")
	)
	(gr_poly
		(pts
			(xy 69.390514 -53.161946) (xy 69.398642 -52.970176) (xy 69.20738 -52.859686) (xy 69.045328 -52.962556)
			(xy 69.022976 -53.00091) (xy 69.368416 -53.200554)
		)
		(stroke
			(width 0)
			(type solid)
		)
		(fill yes)
		(layer "In2.Cu")
		(net "M_G_DQ<19>")
	)
	(gr_poly
		(pts
			(xy 69.398642 -100.80625) (xy 69.390514 -100.61448) (xy 69.368416 -100.575872) (xy 69.022976 -100.775262)
			(xy 69.045328 -100.81387) (xy 69.20738 -100.91674)
		)
		(stroke
			(width 0)
			(type solid)
		)
		(fill yes)
		(layer "In2.Cu")
		(net "M_K_DQ<25>")
	)
	(gr_poly
		(pts
			(xy 69.402452 -99.813618) (xy 69.394324 -99.621848) (xy 69.372226 -99.583494) (xy 69.026786 -99.78263)
			(xy 69.049138 -99.821238) (xy 69.21119 -99.924108)
		)
		(stroke
			(width 0)
			(type solid)
		)
		(fill yes)
		(layer "In2.Cu")
		(net "M_K_DQ<29>")
	)
	(gr_poly
		(pts
			(xy 69.40804 -103.71709) (xy 69.333872 -103.517954) (xy 69.302376 -103.486712) (xy 69.01561 -103.774748)
			(xy 69.047106 -103.80599) (xy 69.24675 -103.879142)
		)
		(stroke
			(width 0)
			(type solid)
		)
		(fill yes)
		(layer "In2.Cu")
		(net "M_K_DQS_DP<3>")
	)
	(gr_poly
		(pts
			(xy 69.47662 -57.711086) (xy 69.47662 -57.666636) (xy 69.07022 -57.666636) (xy 69.07022 -57.711086)
			(xy 69.15912 -57.904126) (xy 69.38772 -57.904126)
		)
		(stroke
			(width 0)
			(type solid)
		)
		(fill yes)
		(layer "In2.Cu")
		(net "M_G_DQS_DP<11>")
	)
	(gr_poly
		(pts
			(xy 69.47662 -57.431686) (xy 69.38772 -57.238646) (xy 69.15912 -57.238646) (xy 69.07022 -57.431686)
			(xy 69.07022 -57.476136) (xy 69.47662 -57.476136)
		)
		(stroke
			(width 0)
			(type solid)
		)
		(fill yes)
		(layer "In2.Cu")
		(net "M_G_DQS_DN<11>")
	)
	(gr_poly
		(pts
			(xy 69.482716 -94.36354) (xy 69.482716 -94.31909) (xy 69.076316 -94.31909) (xy 69.076316 -94.36354)
			(xy 69.165216 -94.55658) (xy 69.393816 -94.55658)
		)
		(stroke
			(width 0)
			(type solid)
		)
		(fill yes)
		(layer "In2.Cu")
		(net "M_K_DQS_DP<2>")
	)
	(gr_poly
		(pts
			(xy 69.482716 -94.08414) (xy 69.393816 -93.8911) (xy 69.165216 -93.8911) (xy 69.076316 -94.08414)
			(xy 69.076316 -94.12859) (xy 69.482716 -94.12859)
		)
		(stroke
			(width 0)
			(type solid)
		)
		(fill yes)
		(layer "In2.Cu")
		(net "M_K_DQS_DN<2>")
	)
	(gr_poly
		(pts
			(xy 69.598794 -53.758084) (xy 69.621146 -53.71973) (xy 69.275706 -53.520086) (xy 69.253608 -53.558694)
			(xy 69.24548 -53.750464) (xy 69.436742 -53.860954)
		)
		(stroke
			(width 0)
			(type solid)
		)
		(fill yes)
		(layer "In2.Cu")
		(net "M_G_DQ<18>")
	)
	(gr_poly
		(pts
			(xy 69.602604 -51.77917) (xy 69.624956 -51.740562) (xy 69.279516 -51.541172) (xy 69.257418 -51.57978)
			(xy 69.24929 -51.77155) (xy 69.440552 -51.88204)
		)
		(stroke
			(width 0)
			(type solid)
		)
		(fill yes)
		(layer "In2.Cu")
		(net "M_G_DQ<28>")
	)
	(gr_poly
		(pts
			(xy 69.621146 -100.056442) (xy 69.598794 -100.018088) (xy 69.436742 -99.915218) (xy 69.24548 -100.025708)
			(xy 69.253608 -100.217478) (xy 69.275706 -100.256086)
		)
		(stroke
			(width 0)
			(type solid)
		)
		(fill yes)
		(layer "In2.Cu")
		(net "M_K_DQ<24>")
	)
	(gr_poly
		(pts
			(xy 69.621146 -99.06635) (xy 69.598794 -99.027742) (xy 69.436742 -98.924872) (xy 69.24548 -99.035362)
			(xy 69.253608 -99.227132) (xy 69.275706 -99.26574)
		)
		(stroke
			(width 0)
			(type solid)
		)
		(fill yes)
		(layer "In2.Cu")
		(net "M_K_DQ<28>")
	)
	(gr_poly
		(pts
			(xy 69.62267 -101.04628) (xy 69.600318 -101.007926) (xy 69.438266 -100.905056) (xy 69.247004 -101.015546)
			(xy 69.255132 -101.207316) (xy 69.27723 -101.24567)
		)
		(stroke
			(width 0)
			(type solid)
		)
		(fill yes)
		(layer "In2.Cu")
		(net "M_K_DQS_DP<12>")
	)
	(gr_poly
		(pts
			(xy 69.866002 -102.649782) (xy 69.834506 -102.618286) (xy 69.634862 -102.545134) (xy 69.473572 -102.707186)
			(xy 69.54774 -102.906322) (xy 69.579236 -102.937818)
		)
		(stroke
			(width 0)
			(type solid)
		)
		(fill yes)
		(layer "In2.Cu")
		(net "M_K_DQS_DN<3>")
	)
	(gr_poly
		(pts
			(xy 70.020688 -54.39156) (xy 69.976492 -54.391814) (xy 69.806312 -54.480714) (xy 69.806312 -54.70144)
			(xy 69.976492 -54.79034) (xy 70.020942 -54.790594)
		)
		(stroke
			(width 0)
			(type solid)
		)
		(fill yes)
		(layer "In2.Cu")
		(net "M_G_DQ<18>")
	)
	(gr_poly
		(pts
			(xy 70.106794 -103.015034) (xy 70.032626 -102.815898) (xy 70.00113 -102.784402) (xy 69.714364 -103.072438)
			(xy 69.74586 -103.103934) (xy 69.945504 -103.177086)
		)
		(stroke
			(width 0)
			(type solid)
		)
		(fill yes)
		(layer "In2.Cu")
		(net "M_K_DQS_DP<3>")
	)
	(gr_poly
		(pts
			(xy 70.249034 -93.281246) (xy 70.257162 -93.089476) (xy 70.0659 -92.978986) (xy 69.903848 -93.081856)
			(xy 69.881496 -93.12021) (xy 70.226936 -93.319854)
		)
		(stroke
			(width 0)
			(type solid)
		)
		(fill yes)
		(layer "In2.Cu")
		(net "M_K_DQS_DP<11>")
	)
	(gr_poly
		(pts
			(xy 70.249034 -51.676046) (xy 70.257162 -51.484276) (xy 70.0659 -51.373786) (xy 69.903848 -51.476656)
			(xy 69.881496 -51.51501) (xy 70.226936 -51.714654)
		)
		(stroke
			(width 0)
			(type solid)
		)
		(fill yes)
		(layer "In2.Cu")
		(net "M_G_DQ<29>")
	)
	(gr_poly
		(pts
			(xy 70.251066 -53.658008) (xy 70.259194 -53.466238) (xy 70.067932 -53.356002) (xy 69.90588 -53.458872)
			(xy 69.883528 -53.497226) (xy 70.229222 -53.696616)
		)
		(stroke
			(width 0)
			(type solid)
		)
		(fill yes)
		(layer "In2.Cu")
		(net "M_G_DQ<19>")
	)
	(gr_poly
		(pts
			(xy 70.25132 -91.301316) (xy 70.259448 -91.109546) (xy 70.068186 -90.999056) (xy 69.906134 -91.101926)
			(xy 69.883782 -91.14028) (xy 70.229222 -91.33967)
		)
		(stroke
			(width 0)
			(type solid)
		)
		(fill yes)
		(layer "In2.Cu")
		(net "M_K_DQ<20>")
	)
	(gr_poly
		(pts
			(xy 70.25132 -59.602116) (xy 70.259448 -59.410346) (xy 70.068186 -59.299856) (xy 69.906134 -59.402726)
			(xy 69.883782 -59.441334) (xy 70.229222 -59.640724)
		)
		(stroke
			(width 0)
			(type solid)
		)
		(fill yes)
		(layer "In2.Cu")
		(net "M_G_DQ<21>")
	)
	(gr_poly
		(pts
			(xy 70.25132 -56.630316) (xy 70.259448 -56.438546) (xy 70.068186 -56.328056) (xy 69.906134 -56.430926)
			(xy 69.883782 -56.469534) (xy 70.229222 -56.668924)
		)
		(stroke
			(width 0)
			(type solid)
		)
		(fill yes)
		(layer "In2.Cu")
		(net "M_G_DQS_DP<2>")
	)
	(gr_poly
		(pts
			(xy 70.25132 -55.639716) (xy 70.259448 -55.447946) (xy 70.068186 -55.337456) (xy 69.906134 -55.440326)
			(xy 69.883782 -55.478934) (xy 70.229222 -55.678324)
		)
		(stroke
			(width 0)
			(type solid)
		)
		(fill yes)
		(layer "In2.Cu")
		(net "M_G_DQ<23>")
	)
	(gr_poly
		(pts
			(xy 70.259448 -100.30968) (xy 70.25132 -100.11791) (xy 70.229222 -100.079302) (xy 69.883782 -100.278946)
			(xy 69.906134 -100.3173) (xy 70.068186 -100.42017)
		)
		(stroke
			(width 0)
			(type solid)
		)
		(fill yes)
		(layer "In2.Cu")
		(net "M_K_DQ<25>")
	)
	(gr_poly
		(pts
			(xy 70.260972 -101.299264) (xy 70.252844 -101.107494) (xy 70.230746 -101.068886) (xy 69.885306 -101.26853)
			(xy 69.907658 -101.306884) (xy 70.06971 -101.409754)
		)
		(stroke
			(width 0)
			(type solid)
		)
		(fill yes)
		(layer "In2.Cu")
		(net "M_K_DQS_DN<12>")
	)
	(gr_poly
		(pts
			(xy 70.260972 -99.318318) (xy 70.252844 -99.126548) (xy 70.230746 -99.088194) (xy 69.885306 -99.28733)
			(xy 69.907658 -99.325938) (xy 70.06971 -99.428808)
		)
		(stroke
			(width 0)
			(type solid)
		)
		(fill yes)
		(layer "In2.Cu")
		(net "M_K_DQ<29>")
	)
	(gr_poly
		(pts
			(xy 70.379082 -103.713534) (xy 70.347586 -103.682292) (xy 70.148196 -103.608632) (xy 69.986652 -103.770176)
			(xy 70.060312 -103.969566) (xy 70.091554 -104.001062)
		)
		(stroke
			(width 0)
			(type solid)
		)
		(fill yes)
		(layer "In2.Cu")
		(net "M_K_DQ<30>")
	)
	(gr_poly
		(pts
			(xy 70.38848 -54.312312) (xy 70.55866 -54.223412) (xy 70.55866 -54.002686) (xy 70.38848 -53.913786)
			(xy 70.34403 -53.913532) (xy 70.344284 -54.312566)
		)
		(stroke
			(width 0)
			(type solid)
		)
		(fill yes)
		(layer "In2.Cu")
		(net "M_G_DQ<19>")
	)
	(gr_poly
		(pts
			(xy 70.457314 -52.272438) (xy 70.479666 -52.23383) (xy 70.134226 -52.034694) (xy 70.112128 -52.073048)
			(xy 70.104 -52.264818) (xy 70.295262 -52.375308)
		)
		(stroke
			(width 0)
			(type solid)
		)
		(fill yes)
		(layer "In2.Cu")
		(net "M_G_DQ<28>")
	)
	(gr_poly
		(pts
			(xy 70.458838 -92.8878) (xy 70.48119 -92.849446) (xy 70.13575 -92.649802) (xy 70.113652 -92.68841)
			(xy 70.105524 -92.88018) (xy 70.296786 -92.99067)
		)
		(stroke
			(width 0)
			(type solid)
		)
		(fill yes)
		(layer "In2.Cu")
		(net "M_K_DQ<17>")
	)
	(gr_poly
		(pts
			(xy 70.458838 -91.8972) (xy 70.48119 -91.858846) (xy 70.13575 -91.659202) (xy 70.113652 -91.69781)
			(xy 70.105524 -91.88958) (xy 70.296786 -92.00007)
		)
		(stroke
			(width 0)
			(type solid)
		)
		(fill yes)
		(layer "In2.Cu")
		(net "M_K_DQ<21>")
	)
	(gr_poly
		(pts
			(xy 70.458838 -60.198) (xy 70.48119 -60.159646) (xy 70.13575 -59.960002) (xy 70.113652 -59.99861)
			(xy 70.105524 -60.19038) (xy 70.296786 -60.30087)
		)
		(stroke
			(width 0)
			(type solid)
		)
		(fill yes)
		(layer "In2.Cu")
		(net "M_G_DQ<20>")
	)
	(gr_poly
		(pts
			(xy 70.458838 -57.2262) (xy 70.48119 -57.187846) (xy 70.13575 -56.988202) (xy 70.113652 -57.02681)
			(xy 70.105524 -57.21858) (xy 70.296786 -57.32907)
		)
		(stroke
			(width 0)
			(type solid)
		)
		(fill yes)
		(layer "In2.Cu")
		(net "M_G_DQS_DN<2>")
	)
	(gr_poly
		(pts
			(xy 70.458838 -56.2356) (xy 70.48119 -56.197246) (xy 70.13575 -55.997602) (xy 70.113652 -56.03621)
			(xy 70.105524 -56.22798) (xy 70.296786 -56.33847)
		)
		(stroke
			(width 0)
			(type solid)
		)
		(fill yes)
		(layer "In2.Cu")
		(net "M_G_DQ<22>")
	)
	(gr_poly
		(pts
			(xy 70.459092 -55.245254) (xy 70.481444 -55.2069) (xy 70.13575 -55.00751) (xy 70.113906 -55.046118)
			(xy 70.105778 -55.237888) (xy 70.29704 -55.348124)
		)
		(stroke
			(width 0)
			(type solid)
		)
		(fill yes)
		(layer "In2.Cu")
		(net "M_G_DQ<18>")
	)
	(gr_poly
		(pts
			(xy 70.46722 -93.884496) (xy 70.489572 -93.846142) (xy 70.144132 -93.646498) (xy 70.122034 -93.685106)
			(xy 70.113906 -93.876876) (xy 70.305168 -93.987366)
		)
		(stroke
			(width 0)
			(type solid)
		)
		(fill yes)
		(layer "In2.Cu")
		(net "M_K_DQS_DN<11>")
	)
	(gr_poly
		(pts
			(xy 70.479666 -98.57105) (xy 70.457314 -98.532442) (xy 70.295262 -98.429572) (xy 70.104 -98.540062)
			(xy 70.112128 -98.731832) (xy 70.134226 -98.77044)
		)
		(stroke
			(width 0)
			(type solid)
		)
		(fill yes)
		(layer "In2.Cu")
		(net "M_K_DQ<28>")
	)
	(gr_poly
		(pts
			(xy 70.48119 -99.56038) (xy 70.458838 -99.522026) (xy 70.296786 -99.419156) (xy 70.105524 -99.529646)
			(xy 70.113652 -99.721416) (xy 70.13575 -99.75977)
		)
		(stroke
			(width 0)
			(type solid)
		)
		(fill yes)
		(layer "In2.Cu")
		(net "M_K_DQ<24>")
	)
	(gr_poly
		(pts
			(xy 70.483476 -100.54971) (xy 70.461124 -100.511356) (xy 70.299072 -100.408486) (xy 70.10781 -100.518976)
			(xy 70.115938 -100.710746) (xy 70.138036 -100.749354)
		)
		(stroke
			(width 0)
			(type solid)
		)
		(fill yes)
		(layer "In2.Cu")
		(net "M_K_DQS_DP<12>")
	)
	(gr_poly
		(pts
			(xy 70.49643 -51.219354) (xy 70.52183 -51.182778) (xy 70.195186 -50.954178) (xy 70.169786 -50.9905)
			(xy 70.144894 -51.181) (xy 70.325996 -51.307746)
		)
		(stroke
			(width 0)
			(type solid)
		)
		(fill yes)
		(layer "In2.Cu")
		(net "M_G_DQ<24>")
	)
	(gr_poly
		(pts
			(xy 70.566534 -101.94925) (xy 70.535038 -101.917754) (xy 70.335394 -101.844602) (xy 70.174104 -102.006654)
			(xy 70.248272 -102.20579) (xy 70.279768 -102.237286)
		)
		(stroke
			(width 0)
			(type solid)
		)
		(fill yes)
		(layer "In2.Cu")
		(net "M_K_DQS_DN<3>")
	)
	(gr_poly
		(pts
			(xy 70.61835 -104.078786) (xy 70.54469 -103.879396) (xy 70.513448 -103.8479) (xy 70.22592 -104.135428)
			(xy 70.257416 -104.16667) (xy 70.456806 -104.24033)
		)
		(stroke
			(width 0)
			(type solid)
		)
		(fill yes)
		(layer "In2.Cu")
		(net "M_K_DQ<31>")
	)
	(gr_poly
		(pts
			(xy 70.807326 -102.314502) (xy 70.733158 -102.115366) (xy 70.701662 -102.08387) (xy 70.414896 -102.371906)
			(xy 70.446392 -102.403402) (xy 70.646036 -102.476554)
		)
		(stroke
			(width 0)
			(type solid)
		)
		(fill yes)
		(layer "In2.Cu")
		(net "M_K_DQS_DP<3>")
	)
	(gr_poly
		(pts
			(xy 70.811136 -59.00674) (xy 70.811136 -58.96229) (xy 70.412356 -58.96229) (xy 70.412356 -59.00674)
			(xy 70.501256 -59.17692) (xy 70.722236 -59.17692)
		)
		(stroke
			(width 0)
			(type solid)
		)
		(fill yes)
		(layer "In2.Cu")
		(net "M_G_DQ<16>")
	)
	(gr_poly
		(pts
			(xy 71.079614 -103.013002) (xy 71.048118 -102.98176) (xy 70.848728 -102.9081) (xy 70.687184 -103.069644)
			(xy 70.760844 -103.269034) (xy 70.792086 -103.30053)
		)
		(stroke
			(width 0)
			(type solid)
		)
		(fill yes)
		(layer "In2.Cu")
		(net "M_K_DQ<30>")
	)
	(gr_poly
		(pts
			(xy 71.094346 -55.13832) (xy 71.102474 -54.94655) (xy 70.911212 -54.83606) (xy 70.74916 -54.93893)
			(xy 70.726808 -54.977538) (xy 71.072248 -55.176674)
		)
		(stroke
			(width 0)
			(type solid)
		)
		(fill yes)
		(layer "In2.Cu")
		(net "M_G_DQ<19>")
	)
	(gr_poly
		(pts
			(xy 71.10984 -93.777816) (xy 71.117968 -93.586046) (xy 70.926706 -93.475556) (xy 70.764654 -93.578426)
			(xy 70.742302 -93.61678) (xy 71.087742 -93.81617)
		)
		(stroke
			(width 0)
			(type solid)
		)
		(fill yes)
		(layer "In2.Cu")
		(net "M_K_DQS_DP<11>")
	)
	(gr_poly
		(pts
			(xy 71.10984 -52.172616) (xy 71.117968 -51.980846) (xy 70.926706 -51.870356) (xy 70.764654 -51.973226)
			(xy 70.742302 -52.011834) (xy 71.087742 -52.211224)
		)
		(stroke
			(width 0)
			(type solid)
		)
		(fill yes)
		(layer "In2.Cu")
		(net "M_G_DQ<29>")
	)
	(gr_poly
		(pts
			(xy 71.111364 -92.788232) (xy 71.119492 -92.596462) (xy 70.92823 -92.485972) (xy 70.766178 -92.588842)
			(xy 70.743826 -92.62745) (xy 71.089266 -92.82684)
		)
		(stroke
			(width 0)
			(type solid)
		)
		(fill yes)
		(layer "In2.Cu")
		(net "M_K_DQ<16>")
	)
	(gr_poly
		(pts
			(xy 71.111364 -91.797632) (xy 71.119492 -91.605862) (xy 70.92823 -91.495372) (xy 70.766178 -91.598242)
			(xy 70.743826 -91.63685) (xy 71.089266 -91.83624)
		)
		(stroke
			(width 0)
			(type solid)
		)
		(fill yes)
		(layer "In2.Cu")
		(net "M_K_DQ<20>")
	)
	(gr_poly
		(pts
			(xy 71.115682 -100.80625) (xy 71.107554 -100.61448) (xy 71.085456 -100.575872) (xy 70.740016 -100.775262)
			(xy 70.762368 -100.81387) (xy 70.92442 -100.91674)
		)
		(stroke
			(width 0)
			(type solid)
		)
		(fill yes)
		(layer "In2.Cu")
		(net "M_K_DQS_DN<12>")
	)
	(gr_poly
		(pts
			(xy 71.11619 -57.219596) (xy 71.108062 -57.027826) (xy 71.085964 -56.989218) (xy 70.740524 -57.188862)
			(xy 70.762876 -57.227216) (xy 70.924928 -57.330086)
		)
		(stroke
			(width 0)
			(type solid)
		)
		(fill yes)
		(layer "In2.Cu")
		(net "M_G_DQS_DN<2>")
	)
	(gr_poly
		(pts
			(xy 71.117968 -98.82378) (xy 71.10984 -98.63201) (xy 71.087742 -98.593402) (xy 70.742302 -98.793046)
			(xy 70.764654 -98.8314) (xy 70.926706 -98.93427)
		)
		(stroke
			(width 0)
			(type solid)
		)
		(fill yes)
		(layer "In2.Cu")
		(net "M_K_DQ<29>")
	)
	(gr_poly
		(pts
			(xy 71.119492 -99.813618) (xy 71.111364 -99.621848) (xy 71.089266 -99.583494) (xy 70.743826 -99.78263)
			(xy 70.766178 -99.821238) (xy 70.92823 -99.924108)
		)
		(stroke
			(width 0)
			(type solid)
		)
		(fill yes)
		(layer "In2.Cu")
		(net "M_K_DQ<25>")
	)
	(gr_poly
		(pts
			(xy 71.119492 -58.208418) (xy 71.111364 -58.016648) (xy 71.089266 -57.978294) (xy 70.743826 -58.17743)
			(xy 70.766178 -58.216038) (xy 70.92823 -58.318908)
		)
		(stroke
			(width 0)
			(type solid)
		)
		(fill yes)
		(layer "In2.Cu")
		(net "M_G_DQ<17>")
	)
	(gr_poly
		(pts
			(xy 71.315834 -95.363284) (xy 71.338186 -95.32493) (xy 70.992746 -95.125286) (xy 70.970648 -95.163894)
			(xy 70.96252 -95.355664) (xy 71.153782 -95.466154)
		)
		(stroke
			(width 0)
			(type solid)
		)
		(fill yes)
		(layer "In2.Cu")
		(net "M_K_DQ<22>")
	)
	(gr_poly
		(pts
			(xy 71.315834 -92.391484) (xy 71.338186 -92.35313) (xy 70.992746 -92.153486) (xy 70.970648 -92.192094)
			(xy 70.96252 -92.383864) (xy 71.153782 -92.494354)
		)
		(stroke
			(width 0)
			(type solid)
		)
		(fill yes)
		(layer "In2.Cu")
		(net "M_K_DQ<21>")
	)
	(gr_poly
		(pts
			(xy 71.317358 -94.3737) (xy 71.33971 -94.335346) (xy 70.99427 -94.135702) (xy 70.972172 -94.17431)
			(xy 70.964044 -94.36608) (xy 71.155306 -94.47657)
		)
		(stroke
			(width 0)
			(type solid)
		)
		(fill yes)
		(layer "In2.Cu")
		(net "M_K_DQS_DN<11>")
	)
	(gr_poly
		(pts
			(xy 71.317358 -52.7685) (xy 71.33971 -52.730146) (xy 70.99427 -52.530502) (xy 70.972172 -52.56911)
			(xy 70.964044 -52.76088) (xy 71.155306 -52.87137)
		)
		(stroke
			(width 0)
			(type solid)
		)
		(fill yes)
		(layer "In2.Cu")
		(net "M_G_DQ<28>")
	)
	(gr_poly
		(pts
			(xy 71.318882 -103.378254) (xy 71.245222 -103.178864) (xy 71.21398 -103.147368) (xy 70.926452 -103.434896)
			(xy 70.957948 -103.466138) (xy 71.157338 -103.539798)
		)
		(stroke
			(width 0)
			(type solid)
		)
		(fill yes)
		(layer "In2.Cu")
		(net "M_K_DQ<31>")
	)
	(gr_poly
		(pts
			(xy 71.319644 -51.77917) (xy 71.341996 -51.740562) (xy 70.996556 -51.541172) (xy 70.974458 -51.57978)
			(xy 70.96633 -51.77155) (xy 71.157592 -51.88204)
		)
		(stroke
			(width 0)
			(type solid)
		)
		(fill yes)
		(layer "In2.Cu")
		(net "M_G_DQ<24>")
	)
	(gr_poly
		(pts
			(xy 71.338186 -100.056442) (xy 71.315834 -100.018088) (xy 71.153782 -99.915218) (xy 70.96252 -100.025708)
			(xy 70.970648 -100.217478) (xy 70.992746 -100.256086)
		)
		(stroke
			(width 0)
			(type solid)
		)
		(fill yes)
		(layer "In2.Cu")
		(net "M_K_DQS_DP<12>")
	)
	(gr_poly
		(pts
			(xy 71.33971 -101.046026) (xy 71.317358 -101.007672) (xy 71.155306 -100.904802) (xy 70.964044 -101.015292)
			(xy 70.972172 -101.207062) (xy 70.99427 -101.24567)
		)
		(stroke
			(width 0)
			(type solid)
		)
		(fill yes)
		(layer "In2.Cu")
		(net "M_K_DQS_DN<3>")
	)
	(gr_poly
		(pts
			(xy 71.33971 -98.07448) (xy 71.317358 -98.036126) (xy 71.155306 -97.933256) (xy 70.964044 -98.043746)
			(xy 70.972172 -98.235516) (xy 70.99427 -98.27387)
		)
		(stroke
			(width 0)
			(type solid)
		)
		(fill yes)
		(layer "In2.Cu")
		(net "M_K_DQ<28>")
	)
	(gr_poly
		(pts
			(xy 71.33971 -59.441334) (xy 71.317358 -59.402726) (xy 71.155306 -59.299856) (xy 70.964044 -59.410346)
			(xy 70.972172 -59.602116) (xy 70.99427 -59.640724)
		)
		(stroke
			(width 0)
			(type solid)
		)
		(fill yes)
		(layer "In2.Cu")
		(net "M_G_DQ<21>")
	)
	(gr_poly
		(pts
			(xy 71.341996 -99.06381) (xy 71.319644 -99.025456) (xy 71.157592 -98.922586) (xy 70.96633 -99.033076)
			(xy 70.974458 -99.224846) (xy 70.996556 -99.263454)
		)
		(stroke
			(width 0)
			(type solid)
		)
		(fill yes)
		(layer "In2.Cu")
		(net "M_K_DQ<24>")
	)
	(gr_poly
		(pts
			(xy 71.341996 -57.45861) (xy 71.319644 -57.420256) (xy 71.157592 -57.317386) (xy 70.96633 -57.427876)
			(xy 70.974458 -57.619646) (xy 70.996556 -57.658254)
		)
		(stroke
			(width 0)
			(type solid)
		)
		(fill yes)
		(layer "In2.Cu")
		(net "M_G_DQS_DP<11>")
	)
	(gr_poly
		(pts
			(xy 71.58355 -49.929034) (xy 71.615046 -49.897792) (xy 71.327518 -49.610264) (xy 71.296276 -49.64176)
			(xy 71.222616 -49.84115) (xy 71.38416 -50.002694)
		)
		(stroke
			(width 0)
			(type solid)
		)
		(fill yes)
		(layer "In2.Cu")
		(net "M_G_DQS_DP<12>")
	)
	(gr_poly
		(pts
			(xy 71.676006 -104.2543) (xy 71.64451 -104.223058) (xy 71.44512 -104.149398) (xy 71.283576 -104.310942)
			(xy 71.357236 -104.510332) (xy 71.388478 -104.541828)
		)
		(stroke
			(width 0)
			(type solid)
		)
		(fill yes)
		(layer "In2.Cu")
		(net "M_K_DQ<26>")
	)
	(gr_poly
		(pts
			(xy 71.736712 -50.2031) (xy 71.692262 -50.2031) (xy 71.499222 -50.292) (xy 71.499222 -50.5206) (xy 71.692262 -50.6095)
			(xy 71.736712 -50.6095)
		)
		(stroke
			(width 0)
			(type solid)
		)
		(fill yes)
		(layer "In2.Cu")
		(net "M_G_DQS_DP<12>")
	)
	(gr_poly
		(pts
			(xy 71.780146 -102.31247) (xy 71.74865 -102.281228) (xy 71.54926 -102.207568) (xy 71.387716 -102.369112)
			(xy 71.461376 -102.568502) (xy 71.492618 -102.599998)
		)
		(stroke
			(width 0)
			(type solid)
		)
		(fill yes)
		(layer "In2.Cu")
		(net "M_K_DQ<30>")
	)
	(gr_poly
		(pts
			(xy 71.781162 -49.731422) (xy 71.854822 -49.532286) (xy 71.693024 -49.370488) (xy 71.493888 -49.444148)
			(xy 71.462392 -49.475644) (xy 71.749666 -49.762918)
		)
		(stroke
			(width 0)
			(type solid)
		)
		(fill yes)
		(layer "In2.Cu")
		(net "M_G_DQS_DN<12>")
	)
	(gr_poly
		(pts
			(xy 71.915274 -104.619552) (xy 71.841614 -104.420162) (xy 71.810372 -104.388666) (xy 71.522844 -104.676194)
			(xy 71.55434 -104.707436) (xy 71.75373 -104.781096)
		)
		(stroke
			(width 0)
			(type solid)
		)
		(fill yes)
		(layer "In2.Cu")
		(net "M_K_DQ<27>")
	)
	(gr_poly
		(pts
			(xy 71.96074 -56.625744) (xy 71.968868 -56.433974) (xy 71.777606 -56.323484) (xy 71.615554 -56.426354)
			(xy 71.593202 -56.464962) (xy 71.938642 -56.664098)
		)
		(stroke
			(width 0)
			(type solid)
		)
		(fill yes)
		(layer "In2.Cu")
		(net "M_G_DQS_DP<2>")
	)
	(gr_poly
		(pts
			(xy 71.966074 -93.281246) (xy 71.974202 -93.089476) (xy 71.78294 -92.978986) (xy 71.620888 -93.081856)
			(xy 71.598536 -93.12021) (xy 71.943976 -93.319854)
		)
		(stroke
			(width 0)
			(type solid)
		)
		(fill yes)
		(layer "In2.Cu")
		(net "M_K_DQ<16>")
	)
	(gr_poly
		(pts
			(xy 71.966074 -51.676046) (xy 71.974202 -51.484276) (xy 71.78294 -51.373786) (xy 71.620888 -51.476656)
			(xy 71.598536 -51.51501) (xy 71.943976 -51.714654)
		)
		(stroke
			(width 0)
			(type solid)
		)
		(fill yes)
		(layer "In2.Cu")
		(net "M_G_DQ<25>")
	)
	(gr_poly
		(pts
			(xy 71.96836 -92.291916) (xy 71.976488 -92.100146) (xy 71.785226 -91.989656) (xy 71.623174 -92.092526)
			(xy 71.600822 -92.13088) (xy 71.946262 -92.33027)
		)
		(stroke
			(width 0)
			(type solid)
		)
		(fill yes)
		(layer "In2.Cu")
		(net "M_K_DQ<20>")
	)
	(gr_poly
		(pts
			(xy 71.969884 -94.273878) (xy 71.978012 -94.082108) (xy 71.78675 -93.971618) (xy 71.624698 -94.074488)
			(xy 71.602346 -94.112842) (xy 71.947786 -94.312486)
		)
		(stroke
			(width 0)
			(type solid)
		)
		(fill yes)
		(layer "In2.Cu")
		(net "M_K_DQS_DP<11>")
	)
	(gr_poly
		(pts
			(xy 71.969884 -52.668678) (xy 71.978012 -52.476908) (xy 71.78675 -52.366418) (xy 71.624698 -52.469288)
			(xy 71.602346 -52.507642) (xy 71.947786 -52.707286)
		)
		(stroke
			(width 0)
			(type solid)
		)
		(fill yes)
		(layer "In2.Cu")
		(net "M_G_DQ<29>")
	)
	(gr_poly
		(pts
			(xy 71.974202 -99.32035) (xy 71.966074 -99.12858) (xy 71.943976 -99.089972) (xy 71.598536 -99.289362)
			(xy 71.620888 -99.32797) (xy 71.78294 -99.43084)
		)
		(stroke
			(width 0)
			(type solid)
		)
		(fill yes)
		(layer "In2.Cu")
		(net "M_K_DQ<25>")
	)
	(gr_poly
		(pts
			(xy 71.976488 -100.30968) (xy 71.96836 -100.11791) (xy 71.946262 -100.079302) (xy 71.600822 -100.278946)
			(xy 71.623174 -100.3173) (xy 71.785226 -100.42017)
		)
		(stroke
			(width 0)
			(type solid)
		)
		(fill yes)
		(layer "In2.Cu")
		(net "M_K_DQS_DN<12>")
	)
	(gr_poly
		(pts
			(xy 71.978012 -101.299264) (xy 71.969884 -101.107494) (xy 71.947786 -101.068886) (xy 71.602346 -101.26853)
			(xy 71.624698 -101.306884) (xy 71.78675 -101.409754)
		)
		(stroke
			(width 0)
			(type solid)
		)
		(fill yes)
		(layer "In2.Cu")
		(net "M_K_DQS_DP<3>")
	)
	(gr_poly
		(pts
			(xy 71.978012 -98.327464) (xy 71.969884 -98.135694) (xy 71.947786 -98.097086) (xy 71.602346 -98.29673)
			(xy 71.624698 -98.335084) (xy 71.78675 -98.437954)
		)
		(stroke
			(width 0)
			(type solid)
		)
		(fill yes)
		(layer "In2.Cu")
		(net "M_K_DQ<29>")
	)
	(gr_poly
		(pts
			(xy 71.978012 -59.694064) (xy 71.969884 -59.502294) (xy 71.947786 -59.463686) (xy 71.602346 -59.66333)
			(xy 71.624698 -59.701684) (xy 71.78675 -59.804554)
		)
		(stroke
			(width 0)
			(type solid)
		)
		(fill yes)
		(layer "In2.Cu")
		(net "M_G_DQ<20>")
	)
	(gr_poly
		(pts
			(xy 72.019414 -102.677722) (xy 71.945754 -102.478332) (xy 71.914512 -102.446836) (xy 71.626984 -102.734364)
			(xy 71.65848 -102.765606) (xy 71.85787 -102.839266)
		)
		(stroke
			(width 0)
			(type solid)
		)
		(fill yes)
		(layer "In2.Cu")
		(net "M_K_DQ<31>")
	)
	(gr_poly
		(pts
			(xy 72.164702 -50.2666) (xy 72.164702 -50.038) (xy 71.971662 -49.9491) (xy 71.927212 -49.9491) (xy 71.927212 -50.3555)
			(xy 71.971662 -50.3555)
		)
		(stroke
			(width 0)
			(type solid)
		)
		(fill yes)
		(layer "In2.Cu")
		(net "M_G_DQS_DN<12>")
	)
	(gr_poly
		(pts
			(xy 72.174354 -52.272438) (xy 72.196706 -52.23383) (xy 71.851266 -52.034694) (xy 71.829168 -52.073048)
			(xy 71.82104 -52.264818) (xy 72.012302 -52.375308)
		)
		(stroke
			(width 0)
			(type solid)
		)
		(fill yes)
		(layer "In2.Cu")
		(net "M_G_DQ<24>")
	)
	(gr_poly
		(pts
			(xy 72.177656 -51.283616) (xy 72.200008 -51.245262) (xy 71.854568 -51.045618) (xy 71.83247 -51.084226)
			(xy 71.824342 -51.275996) (xy 72.015604 -51.386486)
		)
		(stroke
			(width 0)
			(type solid)
		)
		(fill yes)
		(layer "In2.Cu")
		(net "M_G_DQS_DP<12>")
	)
	(gr_poly
		(pts
			(xy 72.178164 -94.87027) (xy 72.200516 -94.831662) (xy 71.855076 -94.632272) (xy 71.832978 -94.67088)
			(xy 71.82485 -94.86265) (xy 72.016112 -94.97314)
		)
		(stroke
			(width 0)
			(type solid)
		)
		(fill yes)
		(layer "In2.Cu")
		(net "M_K_DQS_DN<11>")
	)
	(gr_poly
		(pts
			(xy 72.178164 -53.26507) (xy 72.200516 -53.226462) (xy 71.855076 -53.027072) (xy 71.832978 -53.06568)
			(xy 71.82485 -53.25745) (xy 72.016112 -53.36794)
		)
		(stroke
			(width 0)
			(type solid)
		)
		(fill yes)
		(layer "In2.Cu")
		(net "M_G_DQ<28>")
	)
	(gr_poly
		(pts
			(xy 72.196706 -98.57105) (xy 72.174354 -98.532442) (xy 72.012302 -98.429572) (xy 71.82104 -98.540062)
			(xy 71.829168 -98.731832) (xy 71.851266 -98.77044)
		)
		(stroke
			(width 0)
			(type solid)
		)
		(fill yes)
		(layer "In2.Cu")
		(net "M_K_DQ<24>")
	)
	(gr_poly
		(pts
			(xy 72.196706 -97.58045) (xy 72.174354 -97.541842) (xy 72.012302 -97.438972) (xy 71.82104 -97.549462)
			(xy 71.829168 -97.741232) (xy 71.851266 -97.77984)
		)
		(stroke
			(width 0)
			(type solid)
		)
		(fill yes)
		(layer "In2.Cu")
		(net "M_K_DQ<28>")
	)
	(gr_poly
		(pts
			(xy 72.19823 -99.56038) (xy 72.175878 -99.522026) (xy 72.013826 -99.419156) (xy 71.822564 -99.529646)
			(xy 71.830692 -99.721416) (xy 71.85279 -99.75977)
		)
		(stroke
			(width 0)
			(type solid)
		)
		(fill yes)
		(layer "In2.Cu")
		(net "M_K_DQS_DP<12>")
	)
	(gr_poly
		(pts
			(xy 72.200516 -100.54971) (xy 72.178164 -100.511356) (xy 72.016112 -100.408486) (xy 71.82485 -100.518976)
			(xy 71.832978 -100.710746) (xy 71.855076 -100.749354)
		)
		(stroke
			(width 0)
			(type solid)
		)
		(fill yes)
		(layer "In2.Cu")
		(net "M_K_DQS_DN<3>")
	)
	(gr_poly
		(pts
			(xy 72.376538 -103.553768) (xy 72.345042 -103.522526) (xy 72.145652 -103.448866) (xy 71.984108 -103.61041)
			(xy 72.057768 -103.8098) (xy 72.08901 -103.841296)
		)
		(stroke
			(width 0)
			(type solid)
		)
		(fill yes)
		(layer "In2.Cu")
		(net "M_K_DQ<26>")
	)
	(gr_poly
		(pts
			(xy 72.480678 -101.611938) (xy 72.449182 -101.580696) (xy 72.249792 -101.507036) (xy 72.088248 -101.66858)
			(xy 72.161908 -101.86797) (xy 72.19315 -101.899466)
		)
		(stroke
			(width 0)
			(type solid)
		)
		(fill yes)
		(layer "In2.Cu")
		(net "M_K_DQ<30>")
	)
	(gr_poly
		(pts
			(xy 72.615806 -103.91902) (xy 72.542146 -103.71963) (xy 72.510904 -103.688134) (xy 72.223376 -103.975662)
			(xy 72.254872 -104.006904) (xy 72.454262 -104.080564)
		)
		(stroke
			(width 0)
			(type solid)
		)
		(fill yes)
		(layer "In2.Cu")
		(net "M_K_DQ<27>")
	)
	(gr_poly
		(pts
			(xy 72.719946 -101.97719) (xy 72.646286 -101.7778) (xy 72.615044 -101.746304) (xy 72.327516 -102.033832)
			(xy 72.359012 -102.065074) (xy 72.558402 -102.138734)
		)
		(stroke
			(width 0)
			(type solid)
		)
		(fill yes)
		(layer "In2.Cu")
		(net "M_K_DQ<31>")
	)
	(gr_poly
		(pts
			(xy 72.824594 -53.161946) (xy 72.832722 -52.970176) (xy 72.64146 -52.859686) (xy 72.479408 -52.962556)
			(xy 72.457056 -53.00091) (xy 72.802496 -53.200554)
		)
		(stroke
			(width 0)
			(type solid)
		)
		(fill yes)
		(layer "In2.Cu")
		(net "M_G_DQ<29>")
	)
	(gr_poly
		(pts
			(xy 72.82688 -93.777816) (xy 72.835008 -93.586046) (xy 72.643746 -93.475556) (xy 72.481694 -93.578426)
			(xy 72.459342 -93.61678) (xy 72.804782 -93.81617)
		)
		(stroke
			(width 0)
			(type solid)
		)
		(fill yes)
		(layer "In2.Cu")
		(net "M_K_DQ<16>")
	)
	(gr_poly
		(pts
			(xy 72.82688 -52.172616) (xy 72.835008 -51.980846) (xy 72.643746 -51.870356) (xy 72.481694 -51.973226)
			(xy 72.459342 -52.011834) (xy 72.804782 -52.211224)
		)
		(stroke
			(width 0)
			(type solid)
		)
		(fill yes)
		(layer "In2.Cu")
		(net "M_G_DQ<25>")
	)
	(gr_poly
		(pts
			(xy 72.828404 -92.788232) (xy 72.836532 -92.596462) (xy 72.64527 -92.485972) (xy 72.483218 -92.588842)
			(xy 72.460866 -92.62745) (xy 72.806306 -92.82684)
		)
		(stroke
			(width 0)
			(type solid)
		)
		(fill yes)
		(layer "In2.Cu")
		(net "M_K_DQ<20>")
	)
	(gr_poly
		(pts
			(xy 72.828404 -51.183032) (xy 72.836532 -50.991262) (xy 72.64527 -50.880772) (xy 72.483218 -50.983642)
			(xy 72.460866 -51.02225) (xy 72.806306 -51.22164)
		)
		(stroke
			(width 0)
			(type solid)
		)
		(fill yes)
		(layer "In2.Cu")
		(net "M_G_DQS_DN<12>")
	)
	(gr_poly
		(pts
			(xy 72.832722 -100.80625) (xy 72.824594 -100.61448) (xy 72.802496 -100.575872) (xy 72.457056 -100.775262)
			(xy 72.479408 -100.81387) (xy 72.64146 -100.91674)
		)
		(stroke
			(width 0)
			(type solid)
		)
		(fill yes)
		(layer "In2.Cu")
		(net "M_K_DQS_DP<3>")
	)
	(gr_poly
		(pts
			(xy 72.835008 -98.82378) (xy 72.82688 -98.63201) (xy 72.804782 -98.593402) (xy 72.459342 -98.793046)
			(xy 72.481694 -98.8314) (xy 72.643746 -98.93427)
		)
		(stroke
			(width 0)
			(type solid)
		)
		(fill yes)
		(layer "In2.Cu")
		(net "M_K_DQ<25>")
	)
	(gr_poly
		(pts
			(xy 72.835008 -97.83318) (xy 72.82688 -97.64141) (xy 72.804782 -97.602802) (xy 72.459342 -97.802446)
			(xy 72.481694 -97.8408) (xy 72.643746 -97.94367)
		)
		(stroke
			(width 0)
			(type solid)
		)
		(fill yes)
		(layer "In2.Cu")
		(net "M_K_DQ<29>")
	)
	(gr_poly
		(pts
			(xy 72.836532 -99.813618) (xy 72.828404 -99.621848) (xy 72.806306 -99.583494) (xy 72.460866 -99.78263)
			(xy 72.483218 -99.821238) (xy 72.64527 -99.924108)
		)
		(stroke
			(width 0)
			(type solid)
		)
		(fill yes)
		(layer "In2.Cu")
		(net "M_K_DQS_DN<12>")
	)
	(gr_poly
		(pts
			(xy 72.897492 -102.35184) (xy 72.86625 -102.320344) (xy 72.66686 -102.246938) (xy 72.505062 -102.408482)
			(xy 72.578722 -102.607872) (xy 72.610218 -102.639368)
		)
		(stroke
			(width 0)
			(type solid)
		)
		(fill yes)
		(layer "In2.Cu")
		(net "M_K_DQ<26>")
	)
	(gr_poly
		(pts
			(xy 73.032874 -53.758084) (xy 73.055226 -53.71973) (xy 72.709786 -53.520086) (xy 72.687688 -53.558694)
			(xy 72.67956 -53.750464) (xy 72.870822 -53.860954)
		)
		(stroke
			(width 0)
			(type solid)
		)
		(fill yes)
		(layer "In2.Cu")
		(net "M_G_DQ<28>")
	)
	(gr_poly
		(pts
			(xy 73.032874 -50.786284) (xy 73.055226 -50.74793) (xy 72.709786 -50.548286) (xy 72.687688 -50.586894)
			(xy 72.67956 -50.778664) (xy 72.870822 -50.889154)
		)
		(stroke
			(width 0)
			(type solid)
		)
		(fill yes)
		(layer "In2.Cu")
		(net "M_G_DQS_DN<3>")
	)
	(gr_poly
		(pts
			(xy 73.034398 -52.7685) (xy 73.05675 -52.730146) (xy 72.71131 -52.530502) (xy 72.689212 -52.56911)
			(xy 72.681084 -52.76088) (xy 72.872346 -52.87137)
		)
		(stroke
			(width 0)
			(type solid)
		)
		(fill yes)
		(layer "In2.Cu")
		(net "M_G_DQ<24>")
	)
	(gr_poly
		(pts
			(xy 73.036684 -51.77917) (xy 73.059036 -51.740562) (xy 72.713596 -51.541172) (xy 72.691498 -51.57978)
			(xy 72.68337 -51.77155) (xy 72.874632 -51.88204)
		)
		(stroke
			(width 0)
			(type solid)
		)
		(fill yes)
		(layer "In2.Cu")
		(net "M_G_DQS_DP<12>")
	)
	(gr_poly
		(pts
			(xy 73.055226 -100.056442) (xy 73.032874 -100.018088) (xy 72.870822 -99.915218) (xy 72.67956 -100.025708)
			(xy 72.687688 -100.217478) (xy 72.709786 -100.256086)
		)
		(stroke
			(width 0)
			(type solid)
		)
		(fill yes)
		(layer "In2.Cu")
		(net "M_K_DQS_DN<3>")
	)
	(gr_poly
		(pts
			(xy 73.05675 -98.07448) (xy 73.034398 -98.036126) (xy 72.872346 -97.933256) (xy 72.681084 -98.043746)
			(xy 72.689212 -98.235516) (xy 72.71131 -98.27387)
		)
		(stroke
			(width 0)
			(type solid)
		)
		(fill yes)
		(layer "In2.Cu")
		(net "M_K_DQ<24>")
	)
	(gr_poly
		(pts
			(xy 73.05675 -97.08388) (xy 73.034398 -97.045526) (xy 72.872346 -96.942656) (xy 72.681084 -97.053146)
			(xy 72.689212 -97.244916) (xy 72.71131 -97.28327)
		)
		(stroke
			(width 0)
			(type solid)
		)
		(fill yes)
		(layer "In2.Cu")
		(net "M_K_DQ<28>")
	)
	(gr_poly
		(pts
			(xy 73.057258 -101.045772) (xy 73.034906 -101.007418) (xy 72.872854 -100.904548) (xy 72.681592 -101.015038)
			(xy 72.68972 -101.206808) (xy 72.711818 -101.245162)
		)
		(stroke
			(width 0)
			(type solid)
		)
		(fill yes)
		(layer "In2.Cu")
		(net "M_K_DQ<30>")
	)
	(gr_poly
		(pts
			(xy 73.059036 -99.06381) (xy 73.036684 -99.025456) (xy 72.874632 -98.922586) (xy 72.68337 -99.033076)
			(xy 72.691498 -99.224846) (xy 72.713596 -99.263454)
		)
		(stroke
			(width 0)
			(type solid)
		)
		(fill yes)
		(layer "In2.Cu")
		(net "M_K_DQS_DP<12>")
	)
	(gr_poly
		(pts
			(xy 73.137014 -102.717092) (xy 73.063354 -102.517702) (xy 73.032112 -102.486206) (xy 72.744584 -102.773734)
			(xy 72.77608 -102.804976) (xy 72.97547 -102.878636)
		)
		(stroke
			(width 0)
			(type solid)
		)
		(fill yes)
		(layer "In2.Cu")
		(net "M_K_DQ<27>")
	)
	(gr_poly
		(pts
			(xy 73.683114 -51.676046) (xy 73.691242 -51.484276) (xy 73.49998 -51.373786) (xy 73.337928 -51.476656)
			(xy 73.315576 -51.51501) (xy 73.661016 -51.714654)
		)
		(stroke
			(width 0)
			(type solid)
		)
		(fill yes)
		(layer "In2.Cu")
		(net "M_G_DQS_DN<12>")
	)
	(gr_poly
		(pts
			(xy 73.6854 -53.658516) (xy 73.693528 -53.466746) (xy 73.502266 -53.356256) (xy 73.340214 -53.459126)
			(xy 73.317862 -53.497734) (xy 73.663302 -53.697124)
		)
		(stroke
			(width 0)
			(type solid)
		)
		(fill yes)
		(layer "In2.Cu")
		(net "M_G_DQ<29>")
	)
	(gr_poly
		(pts
			(xy 73.6854 -50.686716) (xy 73.693528 -50.494946) (xy 73.502266 -50.384456) (xy 73.340214 -50.487326)
			(xy 73.317862 -50.525934) (xy 73.663302 -50.725324)
		)
		(stroke
			(width 0)
			(type solid)
		)
		(fill yes)
		(layer "In2.Cu")
		(net "M_G_DQS_DP<3>")
	)
	(gr_poly
		(pts
			(xy 73.686924 -52.668678) (xy 73.695052 -52.476908) (xy 73.50379 -52.366418) (xy 73.341738 -52.469288)
			(xy 73.319386 -52.507642) (xy 73.664826 -52.707286)
		)
		(stroke
			(width 0)
			(type solid)
		)
		(fill yes)
		(layer "In2.Cu")
		(net "M_G_DQ<25>")
	)
	(gr_poly
		(pts
			(xy 73.691242 -99.32035) (xy 73.683114 -99.12858) (xy 73.661016 -99.089972) (xy 73.315576 -99.289362)
			(xy 73.337928 -99.32797) (xy 73.49998 -99.43084)
		)
		(stroke
			(width 0)
			(type solid)
		)
		(fill yes)
		(layer "In2.Cu")
		(net "M_K_DQS_DN<12>")
	)
	(gr_poly
		(pts
			(xy 73.693528 -100.30968) (xy 73.6854 -100.11791) (xy 73.663302 -100.079302) (xy 73.317862 -100.278946)
			(xy 73.340214 -100.3173) (xy 73.502266 -100.42017)
		)
		(stroke
			(width 0)
			(type solid)
		)
		(fill yes)
		(layer "In2.Cu")
		(net "M_K_DQS_DP<3>")
	)
	(gr_poly
		(pts
			(xy 73.695052 -101.299264) (xy 73.686924 -101.107494) (xy 73.664826 -101.068886) (xy 73.319386 -101.26853)
			(xy 73.341738 -101.306884) (xy 73.50379 -101.409754)
		)
		(stroke
			(width 0)
			(type solid)
		)
		(fill yes)
		(layer "In2.Cu")
		(net "M_K_DQ<31>")
	)
	(gr_poly
		(pts
			(xy 73.695052 -98.327464) (xy 73.686924 -98.135694) (xy 73.664826 -98.097086) (xy 73.319386 -98.29673)
			(xy 73.341738 -98.335084) (xy 73.50379 -98.437954)
		)
		(stroke
			(width 0)
			(type solid)
		)
		(fill yes)
		(layer "In2.Cu")
		(net "M_K_DQ<25>")
	)
	(gr_poly
		(pts
			(xy 73.695052 -97.336864) (xy 73.686924 -97.145094) (xy 73.664826 -97.106486) (xy 73.319386 -97.30613)
			(xy 73.341738 -97.344484) (xy 73.50379 -97.447354)
		)
		(stroke
			(width 0)
			(type solid)
		)
		(fill yes)
		(layer "In2.Cu")
		(net "M_K_DQ<29>")
	)
	(gr_poly
		(pts
			(xy 73.891394 -52.272438) (xy 73.913746 -52.23383) (xy 73.568306 -52.034694) (xy 73.546208 -52.073048)
			(xy 73.53808 -52.264818) (xy 73.729342 -52.375308)
		)
		(stroke
			(width 0)
			(type solid)
		)
		(fill yes)
		(layer "In2.Cu")
		(net "M_G_DQS_DP<12>")
	)
	(gr_poly
		(pts
			(xy 73.892918 -54.2544) (xy 73.91527 -54.216046) (xy 73.56983 -54.016402) (xy 73.547732 -54.05501)
			(xy 73.539604 -54.24678) (xy 73.730866 -54.35727)
		)
		(stroke
			(width 0)
			(type solid)
		)
		(fill yes)
		(layer "In2.Cu")
		(net "M_G_DQ<28>")
	)
	(gr_poly
		(pts
			(xy 73.892918 -51.2826) (xy 73.91527 -51.244246) (xy 73.56983 -51.044602) (xy 73.547732 -51.08321)
			(xy 73.539604 -51.27498) (xy 73.730866 -51.38547)
		)
		(stroke
			(width 0)
			(type solid)
		)
		(fill yes)
		(layer "In2.Cu")
		(net "M_G_DQS_DN<3>")
	)
	(gr_poly
		(pts
			(xy 73.895204 -53.26507) (xy 73.917556 -53.226462) (xy 73.572116 -53.027072) (xy 73.550018 -53.06568)
			(xy 73.54189 -53.25745) (xy 73.733152 -53.36794)
		)
		(stroke
			(width 0)
			(type solid)
		)
		(fill yes)
		(layer "In2.Cu")
		(net "M_G_DQ<24>")
	)
	(gr_poly
		(pts
			(xy 73.913746 -98.57105) (xy 73.891394 -98.532442) (xy 73.729342 -98.429572) (xy 73.53808 -98.540062)
			(xy 73.546208 -98.731832) (xy 73.568306 -98.77044)
		)
		(stroke
			(width 0)
			(type solid)
		)
		(fill yes)
		(layer "In2.Cu")
		(net "M_K_DQS_DP<12>")
	)
	(gr_poly
		(pts
			(xy 73.913746 -97.58045) (xy 73.891394 -97.541842) (xy 73.729342 -97.438972) (xy 73.53808 -97.549462)
			(xy 73.546208 -97.741232) (xy 73.568306 -97.77984)
		)
		(stroke
			(width 0)
			(type solid)
		)
		(fill yes)
		(layer "In2.Cu")
		(net "M_K_DQ<24>")
	)
	(gr_poly
		(pts
			(xy 73.913746 -96.58985) (xy 73.891394 -96.551242) (xy 73.729342 -96.448372) (xy 73.53808 -96.558862)
			(xy 73.546208 -96.750632) (xy 73.568306 -96.78924)
		)
		(stroke
			(width 0)
			(type solid)
		)
		(fill yes)
		(layer "In2.Cu")
		(net "M_K_DQ<28>")
	)
	(gr_poly
		(pts
			(xy 73.91527 -99.56038) (xy 73.892918 -99.522026) (xy 73.730866 -99.419156) (xy 73.539604 -99.529646)
			(xy 73.547732 -99.721416) (xy 73.56983 -99.75977)
		)
		(stroke
			(width 0)
			(type solid)
		)
		(fill yes)
		(layer "In2.Cu")
		(net "M_K_DQS_DN<3>")
	)
	(gr_poly
		(pts
			(xy 73.917556 -100.54971) (xy 73.895204 -100.511356) (xy 73.733152 -100.408486) (xy 73.54189 -100.518976)
			(xy 73.550018 -100.710746) (xy 73.572116 -100.749354)
		)
		(stroke
			(width 0)
			(type solid)
		)
		(fill yes)
		(layer "In2.Cu")
		(net "M_K_DQ<30>")
	)
	(gr_poly
		(pts
			(xy 74.064114 -101.74351) (xy 74.032618 -101.712014) (xy 73.833482 -101.638354) (xy 73.671684 -101.800152)
			(xy 73.745344 -101.999288) (xy 73.77684 -102.030784)
		)
		(stroke
			(width 0)
			(type solid)
		)
		(fill yes)
		(layer "In2.Cu")
		(net "M_K_DQ<26>")
	)
	(gr_poly
		(pts
			(xy 74.180192 -49.512728) (xy 74.135742 -49.512728) (xy 73.942702 -49.601628) (xy 73.942702 -49.830228)
			(xy 74.135742 -49.919128) (xy 74.180192 -49.919128)
		)
		(stroke
			(width 0)
			(type solid)
		)
		(fill yes)
		(layer "In2.Cu")
		(net "M_G_DQ<30>")
	)
	(gr_poly
		(pts
			(xy 74.304144 -102.109016) (xy 74.230484 -101.90988) (xy 74.198988 -101.878384) (xy 73.911714 -102.165658)
			(xy 73.94321 -102.197154) (xy 74.142346 -102.270814)
		)
		(stroke
			(width 0)
			(type solid)
		)
		(fill yes)
		(layer "In2.Cu")
		(net "M_K_DQ<27>")
	)
	(gr_poly
		(pts
			(xy 74.541634 -53.161946) (xy 74.549762 -52.970176) (xy 74.3585 -52.859686) (xy 74.196448 -52.962556)
			(xy 74.174096 -53.00091) (xy 74.519536 -53.200554)
		)
		(stroke
			(width 0)
			(type solid)
		)
		(fill yes)
		(layer "In2.Cu")
		(net "M_G_DQ<25>")
	)
	(gr_poly
		(pts
			(xy 74.54392 -52.172616) (xy 74.552048 -51.980846) (xy 74.360786 -51.870356) (xy 74.198734 -51.973226)
			(xy 74.176382 -52.011834) (xy 74.521822 -52.211224)
		)
		(stroke
			(width 0)
			(type solid)
		)
		(fill yes)
		(layer "In2.Cu")
		(net "M_G_DQS_DN<12>")
	)
	(gr_poly
		(pts
			(xy 74.545444 -54.154832) (xy 74.553572 -53.963062) (xy 74.36231 -53.852572) (xy 74.200258 -53.955442)
			(xy 74.177906 -53.99405) (xy 74.523346 -54.19344)
		)
		(stroke
			(width 0)
			(type solid)
		)
		(fill yes)
		(layer "In2.Cu")
		(net "M_G_DQ<29>")
	)
	(gr_poly
		(pts
			(xy 74.545444 -51.183032) (xy 74.553572 -50.991262) (xy 74.36231 -50.880772) (xy 74.200258 -50.983642)
			(xy 74.177906 -51.02225) (xy 74.523346 -51.22164)
		)
		(stroke
			(width 0)
			(type solid)
		)
		(fill yes)
		(layer "In2.Cu")
		(net "M_G_DQS_DP<3>")
	)
	(gr_poly
		(pts
			(xy 74.549762 -100.80625) (xy 74.541634 -100.61448) (xy 74.519536 -100.575872) (xy 74.174096 -100.775262)
			(xy 74.196448 -100.81387) (xy 74.3585 -100.91674)
		)
		(stroke
			(width 0)
			(type solid)
		)
		(fill yes)
		(layer "In2.Cu")
		(net "M_K_DQ<31>")
	)
	(gr_poly
		(pts
			(xy 74.552048 -98.82378) (xy 74.54392 -98.63201) (xy 74.521822 -98.593402) (xy 74.176382 -98.793046)
			(xy 74.198734 -98.8314) (xy 74.360786 -98.93427)
		)
		(stroke
			(width 0)
			(type solid)
		)
		(fill yes)
		(layer "In2.Cu")
		(net "M_K_DQS_DN<12>")
	)
	(gr_poly
		(pts
			(xy 74.552048 -97.83318) (xy 74.54392 -97.64141) (xy 74.521822 -97.602802) (xy 74.176382 -97.802446)
			(xy 74.198734 -97.8408) (xy 74.360786 -97.94367)
		)
		(stroke
			(width 0)
			(type solid)
		)
		(fill yes)
		(layer "In2.Cu")
		(net "M_K_DQ<25>")
	)
	(gr_poly
		(pts
			(xy 74.552048 -96.84258) (xy 74.54392 -96.65081) (xy 74.521822 -96.612202) (xy 74.176382 -96.811846)
			(xy 74.198734 -96.8502) (xy 74.360786 -96.95307)
		)
		(stroke
			(width 0)
			(type solid)
		)
		(fill yes)
		(layer "In2.Cu")
		(net "M_K_DQ<29>")
	)
	(gr_poly
		(pts
			(xy 74.553572 -99.813618) (xy 74.545444 -99.621848) (xy 74.523346 -99.583494) (xy 74.177906 -99.78263)
			(xy 74.200258 -99.821238) (xy 74.36231 -99.924108)
		)
		(stroke
			(width 0)
			(type solid)
		)
		(fill yes)
		(layer "In2.Cu")
		(net "M_K_DQS_DP<3>")
	)
	(gr_poly
		(pts
			(xy 74.608182 -49.830228) (xy 74.608182 -49.601628) (xy 74.415142 -49.512728) (xy 74.370692 -49.512728)
			(xy 74.370692 -49.919128) (xy 74.415142 -49.919128)
		)
		(stroke
			(width 0)
			(type solid)
		)
		(fill yes)
		(layer "In2.Cu")
		(net "M_G_DQ<31>")
	)
	(gr_poly
		(pts
			(xy 74.749914 -53.758084) (xy 74.772266 -53.71973) (xy 74.426826 -53.520086) (xy 74.404728 -53.558694)
			(xy 74.3966 -53.750464) (xy 74.587862 -53.860954)
		)
		(stroke
			(width 0)
			(type solid)
		)
		(fill yes)
		(layer "In2.Cu")
		(net "M_G_DQ<24>")
	)
	(gr_poly
		(pts
			(xy 74.749914 -51.776884) (xy 74.772266 -51.73853) (xy 74.426826 -51.538886) (xy 74.404728 -51.577494)
			(xy 74.3966 -51.769264) (xy 74.587862 -51.879754)
		)
		(stroke
			(width 0)
			(type solid)
		)
		(fill yes)
		(layer "In2.Cu")
		(net "M_G_DQS_DN<3>")
	)
	(gr_poly
		(pts
			(xy 74.749914 -50.786284) (xy 74.772266 -50.74793) (xy 74.426826 -50.548286) (xy 74.404728 -50.586894)
			(xy 74.3966 -50.778664) (xy 74.587862 -50.889154)
		)
		(stroke
			(width 0)
			(type solid)
		)
		(fill yes)
		(layer "In2.Cu")
		(net "M_G_DQ<30>")
	)
	(gr_poly
		(pts
			(xy 74.751438 -52.7685) (xy 74.77379 -52.730146) (xy 74.42835 -52.530502) (xy 74.406252 -52.56911)
			(xy 74.398124 -52.76088) (xy 74.589386 -52.87137)
		)
		(stroke
			(width 0)
			(type solid)
		)
		(fill yes)
		(layer "In2.Cu")
		(net "M_G_DQS_DP<12>")
	)
	(gr_poly
		(pts
			(xy 74.772266 -101.046788) (xy 74.749914 -101.008434) (xy 74.587862 -100.905564) (xy 74.3966 -101.016054)
			(xy 74.404728 -101.207824) (xy 74.426826 -101.246178)
		)
		(stroke
			(width 0)
			(type solid)
		)
		(fill yes)
		(layer "In2.Cu")
		(net "M_K_DQ<26>")
	)
	(gr_poly
		(pts
			(xy 74.772266 -100.056442) (xy 74.749914 -100.018088) (xy 74.587862 -99.915218) (xy 74.3966 -100.025708)
			(xy 74.404728 -100.217478) (xy 74.426826 -100.256086)
		)
		(stroke
			(width 0)
			(type solid)
		)
		(fill yes)
		(layer "In2.Cu")
		(net "M_K_DQ<30>")
	)
	(gr_poly
		(pts
			(xy 74.77379 -98.07448) (xy 74.751438 -98.036126) (xy 74.589386 -97.933256) (xy 74.398124 -98.043746)
			(xy 74.406252 -98.235516) (xy 74.42835 -98.27387)
		)
		(stroke
			(width 0)
			(type solid)
		)
		(fill yes)
		(layer "In2.Cu")
		(net "M_K_DQS_DP<12>")
	)
	(gr_poly
		(pts
			(xy 74.77379 -97.08388) (xy 74.751438 -97.045526) (xy 74.589386 -96.942656) (xy 74.398124 -97.053146)
			(xy 74.406252 -97.244916) (xy 74.42835 -97.28327)
		)
		(stroke
			(width 0)
			(type solid)
		)
		(fill yes)
		(layer "In2.Cu")
		(net "M_K_DQ<24>")
	)
	(gr_poly
		(pts
			(xy 74.774806 -96.0882) (xy 74.749406 -96.051624) (xy 74.578972 -95.963232) (xy 74.39787 -96.089978)
			(xy 74.422762 -96.280478) (xy 74.448162 -96.3168)
		)
		(stroke
			(width 0)
			(type solid)
		)
		(fill yes)
		(layer "In2.Cu")
		(net "M_K_DQ<28>")
	)
	(gr_poly
		(pts
			(xy 74.776076 -99.06381) (xy 74.753724 -99.025456) (xy 74.591672 -98.922586) (xy 74.40041 -99.033076)
			(xy 74.408538 -99.224846) (xy 74.430636 -99.263454)
		)
		(stroke
			(width 0)
			(type solid)
		)
		(fill yes)
		(layer "In2.Cu")
		(net "M_K_DQS_DN<3>")
	)
	(gr_poly
		(pts
			(xy 75.158092 -48.523652) (xy 75.113642 -48.523652) (xy 74.920602 -48.612552) (xy 74.920602 -48.841152)
			(xy 75.113642 -48.930052) (xy 75.158092 -48.930052)
		)
		(stroke
			(width 0)
			(type solid)
		)
		(fill yes)
		(layer "In2.Cu")
		(net "M_G_DQ<26>")
	)
	(gr_poly
		(pts
			(xy 75.40244 -53.658516) (xy 75.410568 -53.466746) (xy 75.219306 -53.356256) (xy 75.057254 -53.459126)
			(xy 75.034902 -53.497734) (xy 75.380342 -53.697124)
		)
		(stroke
			(width 0)
			(type solid)
		)
		(fill yes)
		(layer "In2.Cu")
		(net "M_G_DQ<25>")
	)
	(gr_poly
		(pts
			(xy 75.40244 -51.677316) (xy 75.410568 -51.485546) (xy 75.219306 -51.375056) (xy 75.057254 -51.477926)
			(xy 75.034902 -51.516534) (xy 75.380342 -51.715924)
		)
		(stroke
			(width 0)
			(type solid)
		)
		(fill yes)
		(layer "In2.Cu")
		(net "M_G_DQS_DP<3>")
	)
	(gr_poly
		(pts
			(xy 75.40244 -50.686716) (xy 75.410568 -50.494946) (xy 75.219306 -50.384456) (xy 75.057254 -50.487326)
			(xy 75.034902 -50.525934) (xy 75.380342 -50.725324)
		)
		(stroke
			(width 0)
			(type solid)
		)
		(fill yes)
		(layer "In2.Cu")
		(net "M_G_DQ<31>")
	)
	(gr_poly
		(pts
			(xy 75.403964 -52.668678) (xy 75.412092 -52.476908) (xy 75.22083 -52.366418) (xy 75.058778 -52.469288)
			(xy 75.036426 -52.507642) (xy 75.381866 -52.707286)
		)
		(stroke
			(width 0)
			(type solid)
		)
		(fill yes)
		(layer "In2.Cu")
		(net "M_G_DQS_DN<12>")
	)
	(gr_poly
		(pts
			(xy 75.408282 -99.32035) (xy 75.400154 -99.12858) (xy 75.378056 -99.089972) (xy 75.032616 -99.289362)
			(xy 75.054968 -99.32797) (xy 75.21702 -99.43084)
		)
		(stroke
			(width 0)
			(type solid)
		)
		(fill yes)
		(layer "In2.Cu")
		(net "M_K_DQS_DP<3>")
	)
	(gr_poly
		(pts
			(xy 75.410568 -101.300026) (xy 75.40244 -101.108256) (xy 75.380342 -101.069648) (xy 75.034902 -101.269038)
			(xy 75.057254 -101.307646) (xy 75.219306 -101.410516)
		)
		(stroke
			(width 0)
			(type solid)
		)
		(fill yes)
		(layer "In2.Cu")
		(net "M_K_DQ<27>")
	)
	(gr_poly
		(pts
			(xy 75.410568 -100.30968) (xy 75.40244 -100.11791) (xy 75.380342 -100.079302) (xy 75.034902 -100.278946)
			(xy 75.057254 -100.3173) (xy 75.219306 -100.42017)
		)
		(stroke
			(width 0)
			(type solid)
		)
		(fill yes)
		(layer "In2.Cu")
		(net "M_K_DQ<31>")
	)
	(gr_poly
		(pts
			(xy 75.412092 -98.327464) (xy 75.403964 -98.135694) (xy 75.381866 -98.097086) (xy 75.036426 -98.29673)
			(xy 75.058778 -98.335084) (xy 75.22083 -98.437954)
		)
		(stroke
			(width 0)
			(type solid)
		)
		(fill yes)
		(layer "In2.Cu")
		(net "M_K_DQS_DN<12>")
	)
	(gr_poly
		(pts
			(xy 75.518772 -96.809814) (xy 75.519534 -96.589088) (xy 75.349608 -96.49968) (xy 75.304904 -96.499426)
			(xy 75.303888 -96.898206) (xy 75.348338 -96.898206)
		)
		(stroke
			(width 0)
			(type solid)
		)
		(fill yes)
		(layer "In2.Cu")
		(net "M_K_DQ<24>")
	)
	(gr_poly
		(pts
			(xy 75.585066 -95.432372) (xy 75.548998 -95.406464) (xy 75.359006 -95.378778) (xy 75.22972 -95.557848)
			(xy 75.315572 -95.729552) (xy 75.35164 -95.755714)
		)
		(stroke
			(width 0)
			(type solid)
		)
		(fill yes)
		(layer "In2.Cu")
		(net "M_K_DQ<24>")
	)
	(gr_poly
		(pts
			(xy 75.586082 -48.841152) (xy 75.586082 -48.612552) (xy 75.393042 -48.523652) (xy 75.348592 -48.523652)
			(xy 75.348592 -48.930052) (xy 75.393042 -48.930052)
		)
		(stroke
			(width 0)
			(type solid)
		)
		(fill yes)
		(layer "In2.Cu")
		(net "M_G_DQ<27>")
	)
	(gr_poly
		(pts
			(xy 75.609958 -52.2732) (xy 75.63231 -52.234846) (xy 75.28687 -52.035202) (xy 75.264772 -52.07381)
			(xy 75.256644 -52.26558) (xy 75.447906 -52.37607)
		)
		(stroke
			(width 0)
			(type solid)
		)
		(fill yes)
		(layer "In2.Cu")
		(net "M_G_DQS_DN<3>")
	)
	(gr_poly
		(pts
			(xy 75.609958 -51.2826) (xy 75.63231 -51.244246) (xy 75.28687 -51.044602) (xy 75.264772 -51.08321)
			(xy 75.256644 -51.27498) (xy 75.447906 -51.38547)
		)
		(stroke
			(width 0)
			(type solid)
		)
		(fill yes)
		(layer "In2.Cu")
		(net "M_G_DQ<30>")
	)
	(gr_poly
		(pts
			(xy 75.612244 -53.26507) (xy 75.634596 -53.226462) (xy 75.289156 -53.027072) (xy 75.267058 -53.06568)
			(xy 75.25893 -53.25745) (xy 75.450192 -53.36794)
		)
		(stroke
			(width 0)
			(type solid)
		)
		(fill yes)
		(layer "In2.Cu")
		(net "M_G_DQS_DP<12>")
	)
	(gr_poly
		(pts
			(xy 75.630786 -98.57105) (xy 75.608434 -98.532442) (xy 75.446382 -98.429572) (xy 75.25512 -98.540062)
			(xy 75.263248 -98.731832) (xy 75.285346 -98.77044)
		)
		(stroke
			(width 0)
			(type solid)
		)
		(fill yes)
		(layer "In2.Cu")
		(net "M_K_DQS_DN<3>")
	)
	(gr_poly
		(pts
			(xy 75.630786 -97.58045) (xy 75.608434 -97.541842) (xy 75.446382 -97.438972) (xy 75.25512 -97.549462)
			(xy 75.263248 -97.741232) (xy 75.285346 -97.77984)
		)
		(stroke
			(width 0)
			(type solid)
		)
		(fill yes)
		(layer "In2.Cu")
		(net "M_K_DQS_DP<12>")
	)
	(gr_poly
		(pts
			(xy 75.63231 -100.550726) (xy 75.609958 -100.512372) (xy 75.447906 -100.409502) (xy 75.256644 -100.519992)
			(xy 75.264772 -100.711762) (xy 75.28687 -100.75037)
		)
		(stroke
			(width 0)
			(type solid)
		)
		(fill yes)
		(layer "In2.Cu")
		(net "M_K_DQ<26>")
	)
	(gr_poly
		(pts
			(xy 75.63231 -99.56038) (xy 75.609958 -99.522026) (xy 75.447906 -99.419156) (xy 75.256644 -99.529646)
			(xy 75.264772 -99.721416) (xy 75.28687 -99.75977)
		)
		(stroke
			(width 0)
			(type solid)
		)
		(fill yes)
		(layer "In2.Cu")
		(net "M_K_DQ<30>")
	)
	(gr_poly
		(pts
			(xy 75.770486 -49.88687) (xy 75.801982 -49.855374) (xy 75.514708 -49.5681) (xy 75.483212 -49.599596)
			(xy 75.409552 -49.798732) (xy 75.57135 -49.96053)
		)
		(stroke
			(width 0)
			(type solid)
		)
		(fill yes)
		(layer "In2.Cu")
		(net "M_G_DQ<26>")
	)
	(gr_poly
		(pts
			(xy 75.968098 -49.689258) (xy 76.041758 -49.489868) (xy 75.880214 -49.328324) (xy 75.680824 -49.401984)
			(xy 75.649328 -49.433226) (xy 75.936856 -49.720754)
		)
		(stroke
			(width 0)
			(type solid)
		)
		(fill yes)
		(layer "In2.Cu")
		(net "M_G_DQ<27>")
	)
	(gr_poly
		(pts
			(xy 76.030328 -96.507046) (xy 75.985878 -96.507046) (xy 75.815698 -96.595946) (xy 75.815698 -96.816926)
			(xy 75.985878 -96.905826) (xy 76.030328 -96.905826)
		)
		(stroke
			(width 0)
			(type solid)
		)
		(fill yes)
		(layer "In2.Cu")
		(net "M_K_DQS_DP<12>")
	)
	(gr_poly
		(pts
			(xy 76.030328 -95.516446) (xy 75.985878 -95.516446) (xy 75.815698 -95.605346) (xy 75.815698 -95.826326)
			(xy 75.985878 -95.915226) (xy 76.030328 -95.915226)
		)
		(stroke
			(width 0)
			(type solid)
		)
		(fill yes)
		(layer "In2.Cu")
		(net "M_K_DQS_DP<12>")
	)
	(gr_poly
		(pts
			(xy 76.153264 -55.084218) (xy 76.145136 -54.892194) (xy 76.122784 -54.85384) (xy 75.777598 -55.05323)
			(xy 75.799696 -55.091838) (xy 75.961748 -55.194708)
		)
		(stroke
			(width 0)
			(type solid)
		)
		(fill yes)
		(layer "In2.Cu")
		(net "M_G_DQ<25>")
	)
	(gr_poly
		(pts
			(xy 76.258674 -53.161946) (xy 76.266802 -52.970176) (xy 76.07554 -52.859686) (xy 75.913488 -52.962556)
			(xy 75.891136 -53.00091) (xy 76.236576 -53.200554)
		)
		(stroke
			(width 0)
			(type solid)
		)
		(fill yes)
		(layer "In2.Cu")
		(net "M_G_DQS_DN<12>")
	)
	(gr_poly
		(pts
			(xy 76.262484 -52.173632) (xy 76.270612 -51.981862) (xy 76.07935 -51.871372) (xy 75.917298 -51.974242)
			(xy 75.894946 -52.01285) (xy 76.240386 -52.21224)
		)
		(stroke
			(width 0)
			(type solid)
		)
		(fill yes)
		(layer "In2.Cu")
		(net "M_G_DQS_DP<3>")
	)
	(gr_poly
		(pts
			(xy 76.268834 -97.833688) (xy 76.260706 -97.641664) (xy 76.238862 -97.60331) (xy 75.893168 -97.8027)
			(xy 75.91552 -97.841054) (xy 76.077572 -97.943924)
		)
		(stroke
			(width 0)
			(type solid)
		)
		(fill yes)
		(layer "In2.Cu")
		(net "M_K_DQS_DN<12>")
	)
	(gr_poly
		(pts
			(xy 76.269088 -99.81438) (xy 76.26096 -99.62261) (xy 76.238862 -99.584002) (xy 75.893422 -99.783646)
			(xy 75.915774 -99.822) (xy 76.077826 -99.92487)
		)
		(stroke
			(width 0)
			(type solid)
		)
		(fill yes)
		(layer "In2.Cu")
		(net "M_K_DQ<31>")
	)
	(gr_poly
		(pts
			(xy 76.269088 -98.82378) (xy 76.26096 -98.63201) (xy 76.238862 -98.593402) (xy 75.893422 -98.793046)
			(xy 75.915774 -98.8314) (xy 76.077826 -98.93427)
		)
		(stroke
			(width 0)
			(type solid)
		)
		(fill yes)
		(layer "In2.Cu")
		(net "M_K_DQS_DP<3>")
	)
	(gr_poly
		(pts
			(xy 76.270612 -100.803964) (xy 76.262484 -100.612194) (xy 76.240386 -100.573586) (xy 75.894946 -100.77323)
			(xy 75.917298 -100.811584) (xy 76.07935 -100.914454)
		)
		(stroke
			(width 0)
			(type solid)
		)
		(fill yes)
		(layer "In2.Cu")
		(net "M_K_DQ<27>")
	)
	(gr_poly
		(pts
			(xy 76.466954 -52.767484) (xy 76.489306 -52.72913) (xy 76.143866 -52.529486) (xy 76.121768 -52.568094)
			(xy 76.11364 -52.759864) (xy 76.304902 -52.870354)
		)
		(stroke
			(width 0)
			(type solid)
		)
		(fill yes)
		(layer "In2.Cu")
		(net "M_G_DQS_DN<3>")
	)
	(gr_poly
		(pts
			(xy 76.48575 -95.0976) (xy 76.460096 -95.061024) (xy 76.289916 -94.972632) (xy 76.108814 -95.099378)
			(xy 76.133706 -95.289624) (xy 76.159106 -95.325946)
		)
		(stroke
			(width 0)
			(type solid)
		)
		(fill yes)
		(layer "In2.Cu")
		(net "M_K_DQS_DP<12>")
	)
	(gr_poly
		(pts
			(xy 76.493116 -100.054156) (xy 76.470764 -100.015802) (xy 76.308712 -99.912932) (xy 76.11745 -100.023422)
			(xy 76.125578 -100.215192) (xy 76.147676 -100.253546)
		)
		(stroke
			(width 0)
			(type solid)
		)
		(fill yes)
		(layer "In2.Cu")
		(net "M_K_DQ<26>")
	)
	(gr_poly
		(pts
			(xy 76.497434 -99.065588) (xy 76.475082 -99.02698) (xy 76.31303 -98.92411) (xy 76.121768 -99.0346)
			(xy 76.129896 -99.22637) (xy 76.151994 -99.264724)
		)
		(stroke
			(width 0)
			(type solid)
		)
		(fill yes)
		(layer "In2.Cu")
		(net "M_K_DQ<30>")
	)
	(gr_poly
		(pts
			(xy 76.50607 -55.47106) (xy 76.483718 -55.432706) (xy 76.321666 -55.329836) (xy 76.130404 -55.440326)
			(xy 76.138532 -55.632096) (xy 76.16063 -55.67045)
		)
		(stroke
			(width 0)
			(type solid)
		)
		(fill yes)
		(layer "In2.Cu")
		(net "M_G_DQS_DN<3>")
	)
	(gr_poly
		(pts
			(xy 76.568554 -96.30918) (xy 76.568554 -96.0882) (xy 76.398374 -95.9993) (xy 76.353924 -95.9993)
			(xy 76.353924 -96.39808) (xy 76.398374 -96.39808)
		)
		(stroke
			(width 0)
			(type solid)
		)
		(fill yes)
		(layer "In2.Cu")
		(net "M_K_DQS_DN<12>")
	)
	(gr_poly
		(pts
			(xy 76.888848 -54.3941) (xy 76.844398 -54.3941) (xy 76.674218 -54.483) (xy 76.674218 -54.70398) (xy 76.844398 -54.79288)
			(xy 76.888848 -54.79288)
		)
		(stroke
			(width 0)
			(type solid)
		)
		(fill yes)
		(layer "In2.Cu")
		(net "M_G_DQS_DN<3>")
	)
	(gr_poly
		(pts
			(xy 76.888848 -53.4035) (xy 76.844398 -53.4035) (xy 76.674218 -53.4924) (xy 76.674218 -53.71338)
			(xy 76.844398 -53.80228) (xy 76.888848 -53.80228)
		)
		(stroke
			(width 0)
			(type solid)
		)
		(fill yes)
		(layer "In2.Cu")
		(net "M_G_DQS_DN<3>")
	)
	(gr_poly
		(pts
			(xy 76.901802 -50.802032) (xy 76.933044 -50.770536) (xy 76.64577 -50.483262) (xy 76.614274 -50.514758)
			(xy 76.540614 -50.714148) (xy 76.702412 -50.875692)
		)
		(stroke
			(width 0)
			(type solid)
		)
		(fill yes)
		(layer "In2.Cu")
		(net "M_G_DQ<26>")
	)
	(gr_poly
		(pts
			(xy 76.95057 -51.937158) (xy 76.982066 -51.905916) (xy 76.694538 -51.618388) (xy 76.663296 -51.649884)
			(xy 76.589636 -51.849274) (xy 76.75118 -52.010818)
		)
		(stroke
			(width 0)
			(type solid)
		)
		(fill yes)
		(layer "In2.Cu")
		(net "M_G_DQ<30>")
	)
	(gr_poly
		(pts
			(xy 77.079602 -96.00057) (xy 77.035152 -96.00057) (xy 76.864972 -96.08947) (xy 76.864972 -96.31045)
			(xy 77.035152 -96.39935) (xy 77.079602 -96.39935)
		)
		(stroke
			(width 0)
			(type solid)
		)
		(fill yes)
		(layer "In2.Cu")
		(net "M_K_DQ<30>")
	)
	(gr_poly
		(pts
			(xy 77.099414 -50.60442) (xy 77.173074 -50.40503) (xy 77.011276 -50.243486) (xy 76.811886 -50.317146)
			(xy 76.780644 -50.348642) (xy 77.067918 -50.635916)
		)
		(stroke
			(width 0)
			(type solid)
		)
		(fill yes)
		(layer "In2.Cu")
		(net "M_G_DQ<27>")
	)
	(gr_poly
		(pts
			(xy 77.123798 -55.73522) (xy 77.11567 -55.54345) (xy 77.093572 -55.504842) (xy 76.747878 -55.704232)
			(xy 76.770484 -55.742586) (xy 76.932282 -55.845456)
		)
		(stroke
			(width 0)
			(type solid)
		)
		(fill yes)
		(layer "In2.Cu")
		(net "M_G_DQS_DP<3>")
	)
	(gr_poly
		(pts
			(xy 77.125322 -100.310696) (xy 77.117194 -100.118926) (xy 77.095096 -100.080318) (xy 76.749656 -100.279962)
			(xy 76.772008 -100.318316) (xy 76.93406 -100.421186)
		)
		(stroke
			(width 0)
			(type solid)
		)
		(fill yes)
		(layer "In2.Cu")
		(net "M_K_DQ<27>")
	)
	(gr_poly
		(pts
			(xy 77.148182 -51.739546) (xy 77.221842 -51.54041) (xy 77.060044 -51.378612) (xy 76.860908 -51.452272)
			(xy 76.829412 -51.483768) (xy 77.116686 -51.771042)
		)
		(stroke
			(width 0)
			(type solid)
		)
		(fill yes)
		(layer "In2.Cu")
		(net "M_G_DQ<31>")
	)
	(gr_poly
		(pts
			(xy 77.256894 -55.289704) (xy 77.42682 -55.200804) (xy 77.427074 -54.980078) (xy 77.256894 -54.891178)
			(xy 77.212444 -54.890924) (xy 77.21219 -55.289958)
		)
		(stroke
			(width 0)
			(type solid)
		)
		(fill yes)
		(layer "In2.Cu")
		(net "M_G_DQS_DP<3>")
	)
	(gr_poly
		(pts
			(xy 77.256894 -53.321712) (xy 77.42682 -53.232812) (xy 77.42682 -53.012086) (xy 77.25664 -52.923186)
			(xy 77.21219 -52.922932) (xy 77.212444 -53.321966)
		)
		(stroke
			(width 0)
			(type solid)
		)
		(fill yes)
		(layer "In2.Cu")
		(net "M_G_DQS_DP<3>")
	)
	(gr_poly
		(pts
			(xy 77.276706 -99.165156) (xy 77.219302 -98.982022) (xy 77.187806 -98.950526) (xy 76.905866 -99.232466)
			(xy 76.937362 -99.263962) (xy 77.120496 -99.321366)
		)
		(stroke
			(width 0)
			(type solid)
		)
		(fill yes)
		(layer "In2.Cu")
		(net "M_K_DQ<31>")
	)
	(gr_poly
		(pts
			(xy 77.347826 -99.561142) (xy 77.325474 -99.522788) (xy 77.163422 -99.419918) (xy 76.97216 -99.530408)
			(xy 76.980288 -99.722178) (xy 77.002386 -99.760786)
		)
		(stroke
			(width 0)
			(type solid)
		)
		(fill yes)
		(layer "In2.Cu")
		(net "M_K_DQ<26>")
	)
	(gr_poly
		(pts
			(xy 77.427074 -96.816926) (xy 77.427074 -96.595946) (xy 77.256894 -96.507046) (xy 77.212444 -96.507046)
			(xy 77.212444 -96.905826) (xy 77.256894 -96.905826)
		)
		(stroke
			(width 0)
			(type solid)
		)
		(fill yes)
		(layer "In2.Cu")
		(net "M_K_DQ<30>")
	)
	(gr_poly
		(pts
			(xy 77.427074 -54.221126) (xy 77.427074 -54.000146) (xy 77.256894 -53.911246) (xy 77.212444 -53.911246)
			(xy 77.212444 -54.310026) (xy 77.256894 -54.310026)
		)
		(stroke
			(width 0)
			(type solid)
		)
		(fill yes)
		(layer "In2.Cu")
		(net "M_G_DQS_DP<3>")
	)
	(gr_poly
		(pts
			(xy 77.509878 -98.300794) (xy 77.60335 -98.100642) (xy 77.48651 -97.948242) (xy 77.446378 -97.929446)
			(xy 77.277722 -98.290634) (xy 77.318108 -98.30943)
		)
		(stroke
			(width 0)
			(type solid)
		)
		(fill yes)
		(layer "In2.Cu")
		(net "M_K_DQ<31>")
	)
	(gr_poly
		(pts
			(xy 77.58557 -52.572158) (xy 77.617066 -52.540916) (xy 77.329538 -52.253388) (xy 77.298296 -52.284884)
			(xy 77.224636 -52.484274) (xy 77.38618 -52.645818)
		)
		(stroke
			(width 0)
			(type solid)
		)
		(fill yes)
		(layer "In2.Cu")
		(net "M_G_DQ<30>")
	)
	(gr_poly
		(pts
			(xy 77.60208 -51.502564) (xy 77.633576 -51.471068) (xy 77.346302 -51.183794) (xy 77.314806 -51.21529)
			(xy 77.241146 -51.414426) (xy 77.402944 -51.576224)
		)
		(stroke
			(width 0)
			(type solid)
		)
		(fill yes)
		(layer "In2.Cu")
		(net "M_G_DQ<26>")
	)
	(gr_poly
		(pts
			(xy 77.747114 -98.49104) (xy 77.702664 -98.49104) (xy 77.532484 -98.57994) (xy 77.532484 -98.80092)
			(xy 77.702664 -98.88982) (xy 77.747114 -98.88982)
		)
		(stroke
			(width 0)
			(type solid)
		)
		(fill yes)
		(layer "In2.Cu")
		(net "M_K_DQ<26>")
	)
	(gr_poly
		(pts
			(xy 77.75448 -96.500188) (xy 77.71003 -96.500442) (xy 77.53985 -96.589342) (xy 77.53985 -96.810068)
			(xy 77.71003 -96.898968) (xy 77.754226 -96.898968)
		)
		(stroke
			(width 0)
			(type solid)
		)
		(fill yes)
		(layer "In2.Cu")
		(net "M_K_DQ<26>")
	)
	(gr_poly
		(pts
			(xy 77.783182 -52.374546) (xy 77.856842 -52.17541) (xy 77.695044 -52.013612) (xy 77.495908 -52.087272)
			(xy 77.464412 -52.118768) (xy 77.751686 -52.406042)
		)
		(stroke
			(width 0)
			(type solid)
		)
		(fill yes)
		(layer "In2.Cu")
		(net "M_G_DQ<31>")
	)
	(gr_poly
		(pts
			(xy 77.799692 -51.304952) (xy 77.873352 -51.105562) (xy 77.711808 -50.944018) (xy 77.512418 -51.017678)
			(xy 77.480922 -51.04892) (xy 77.76845 -51.336448)
		)
		(stroke
			(width 0)
			(type solid)
		)
		(fill yes)
		(layer "In2.Cu")
		(net "M_G_DQ<27>")
	)
	(gr_poly
		(pts
			(xy 77.88021 -52.95646) (xy 77.83576 -52.95646) (xy 77.64272 -53.045106) (xy 77.642466 -53.273706)
			(xy 77.835506 -53.36286) (xy 77.879956 -53.36286)
		)
		(stroke
			(width 0)
			(type solid)
		)
		(fill yes)
		(layer "In2.Cu")
		(net "M_G_DQ<30>")
	)
	(gr_poly
		(pts
			(xy 78.05674 -50.340768) (xy 78.088236 -50.309272) (xy 77.800962 -50.021998) (xy 77.769466 -50.05324)
			(xy 77.695806 -50.25263) (xy 77.85735 -50.414428)
		)
		(stroke
			(width 0)
			(type solid)
		)
		(fill yes)
		(layer "In2.Cu")
		(net "M_G_ECC<4>")
	)
	(gr_poly
		(pts
			(xy 78.205584 -96.089216) (xy 78.180184 -96.052894) (xy 78.00975 -95.964502) (xy 77.828648 -96.090994)
			(xy 77.85354 -96.281494) (xy 77.87894 -96.317816)
		)
		(stroke
			(width 0)
			(type solid)
		)
		(fill yes)
		(layer "In2.Cu")
		(net "M_K_DQ<26>")
	)
	(gr_poly
		(pts
			(xy 78.23708 -99.476052) (xy 78.13421 -99.314) (xy 78.095856 -99.291648) (xy 77.896212 -99.637088)
			(xy 77.93482 -99.659186) (xy 78.12659 -99.667314)
		)
		(stroke
			(width 0)
			(type solid)
		)
		(fill yes)
		(layer "In2.Cu")
		(net "M_K_DQ<27>")
	)
	(gr_poly
		(pts
			(xy 78.255622 -50.141886) (xy 78.329282 -49.942496) (xy 78.167484 -49.780952) (xy 77.968094 -49.854612)
			(xy 77.936852 -49.886108) (xy 78.224126 -50.173382)
		)
		(stroke
			(width 0)
			(type solid)
		)
		(fill yes)
		(layer "In2.Cu")
		(net "M_G_ECC<5>")
	)
	(gr_poly
		(pts
			(xy 78.28534 -54.71033) (xy 78.28534 -54.48935) (xy 78.11516 -54.40045) (xy 78.07071 -54.40045) (xy 78.07071 -54.79923)
			(xy 78.11516 -54.79923)
		)
		(stroke
			(width 0)
			(type solid)
		)
		(fill yes)
		(layer "In2.Cu")
		(net "M_G_DQ<31>")
	)
	(gr_poly
		(pts
			(xy 78.285594 -98.287586) (xy 78.285594 -98.066606) (xy 78.115414 -97.977706) (xy 78.070964 -97.977706)
			(xy 78.070964 -98.376486) (xy 78.115414 -98.376486)
		)
		(stroke
			(width 0)
			(type solid)
		)
		(fill yes)
		(layer "In2.Cu")
		(net "M_K_DQ<27>")
	)
	(gr_poly
		(pts
			(xy 78.285594 -97.296986) (xy 78.285594 -97.076006) (xy 78.115414 -96.987106) (xy 78.070964 -96.987106)
			(xy 78.070964 -97.385886) (xy 78.115414 -97.385886)
		)
		(stroke
			(width 0)
			(type solid)
		)
		(fill yes)
		(layer "In2.Cu")
		(net "M_K_DQ<27>")
	)
	(gr_poly
		(pts
			(xy 78.302612 -52.203096) (xy 78.334108 -52.1716) (xy 78.046834 -51.884326) (xy 78.015338 -51.915568)
			(xy 77.941678 -52.114958) (xy 78.103222 -52.276756)
		)
		(stroke
			(width 0)
			(type solid)
		)
		(fill yes)
		(layer "In2.Cu")
		(net "M_G_DQ<26>")
	)
	(gr_poly
		(pts
			(xy 78.3082 -53.27396) (xy 78.308454 -53.04536) (xy 78.115414 -52.95646) (xy 78.070964 -52.95646)
			(xy 78.07071 -53.36286) (xy 78.11516 -53.36286)
		)
		(stroke
			(width 0)
			(type solid)
		)
		(fill yes)
		(layer "In2.Cu")
		(net "M_G_DQ<31>")
	)
	(gr_poly
		(pts
			(xy 78.500224 -52.005484) (xy 78.573884 -51.806094) (xy 78.41234 -51.644296) (xy 78.21295 -51.717956)
			(xy 78.181454 -51.749452) (xy 78.468728 -52.036726)
		)
		(stroke
			(width 0)
			(type solid)
		)
		(fill yes)
		(layer "In2.Cu")
		(net "M_G_DQ<27>")
	)
	(gr_poly
		(pts
			(xy 78.60538 -52.623466) (xy 78.56093 -52.623466) (xy 78.36789 -52.712366) (xy 78.36789 -52.940966)
			(xy 78.56093 -53.029866) (xy 78.60538 -53.029866)
		)
		(stroke
			(width 0)
			(type solid)
		)
		(fill yes)
		(layer "In2.Cu")
		(net "M_G_DQ<26>")
	)
	(gr_poly
		(pts
			(xy 78.619096 -100.375974) (xy 78.574392 -100.375974) (xy 78.381606 -100.46462) (xy 78.381606 -100.693474)
			(xy 78.574392 -100.78212) (xy 78.619096 -100.78212)
		)
		(stroke
			(width 0)
			(type solid)
		)
		(fill yes)
		(layer "In2.Cu")
		(net "M_K_ECC<4>")
	)
	(gr_poly
		(pts
			(xy 78.8543 -100.78212) (xy 79.04734 -100.69322) (xy 79.04734 -100.464874) (xy 78.8543 -100.375974)
			(xy 78.80985 -100.37572) (xy 78.80985 -100.782374)
		)
		(stroke
			(width 0)
			(type solid)
		)
		(fill yes)
		(layer "In2.Cu")
		(net "M_K_ECC<5>")
	)
	(gr_poly
		(pts
			(xy 78.9559 -50.842418) (xy 79.02956 -50.643028) (xy 78.868016 -50.481484) (xy 78.668626 -50.555144)
			(xy 78.63713 -50.586386) (xy 78.924658 -50.873914)
		)
		(stroke
			(width 0)
			(type solid)
		)
		(fill yes)
		(layer "In2.Cu")
		(net "M_G_ECC<5>")
	)
	(gr_poly
		(pts
			(xy 79.03337 -52.940966) (xy 79.03337 -52.712366) (xy 78.84033 -52.623466) (xy 78.79588 -52.623466)
			(xy 78.79588 -53.029866) (xy 78.84033 -53.029866)
		)
		(stroke
			(width 0)
			(type solid)
		)
		(fill yes)
		(layer "In2.Cu")
		(net "M_G_DQ<27>")
	)
	(gr_poly
		(pts
			(xy 79.062072 -51.345846) (xy 79.093568 -51.314604) (xy 78.80604 -51.027076) (xy 78.774798 -51.058572)
			(xy 78.701138 -51.257962) (xy 78.862682 -51.419506)
		)
		(stroke
			(width 0)
			(type solid)
		)
		(fill yes)
		(layer "In2.Cu")
		(net "M_G_ECC<4>")
	)
	(gr_poly
		(pts
			(xy 79.072232 -51.821334) (xy 79.027782 -51.821334) (xy 78.834742 -51.910234) (xy 78.834742 -52.138834)
			(xy 79.027782 -52.227734) (xy 79.072232 -52.227734)
		)
		(stroke
			(width 0)
			(type solid)
		)
		(fill yes)
		(layer "In2.Cu")
		(net "M_G_ECC<4>")
	)
	(gr_poly
		(pts
			(xy 79.14386 -54.220872) (xy 79.14386 -53.999892) (xy 78.97368 -53.910992) (xy 78.92923 -53.910992)
			(xy 78.92923 -54.309772) (xy 78.97368 -54.309772)
		)
		(stroke
			(width 0)
			(type solid)
		)
		(fill yes)
		(layer "In2.Cu")
		(net "M_G_DQ<27>")
	)
	(gr_poly
		(pts
			(xy 79.27721 -99.459796) (xy 79.245714 -99.4283) (xy 79.046578 -99.35464) (xy 78.88478 -99.516438)
			(xy 78.95844 -99.715574) (xy 78.989936 -99.74707)
		)
		(stroke
			(width 0)
			(type solid)
		)
		(fill yes)
		(layer "In2.Cu")
		(net "M_K_ECC<4>")
	)
	(gr_poly
		(pts
			(xy 79.360268 -50.546762) (xy 79.391764 -50.515266) (xy 79.10449 -50.227992) (xy 79.072994 -50.259234)
			(xy 78.999334 -50.458624) (xy 79.160878 -50.620422)
		)
		(stroke
			(width 0)
			(type solid)
		)
		(fill yes)
		(layer "In2.Cu")
		(net "M_G_ECC<0>")
	)
	(gr_poly
		(pts
			(xy 79.395066 -52.680616) (xy 79.350616 -52.680616) (xy 79.157576 -52.769516) (xy 79.157576 -52.998116)
			(xy 79.350616 -53.087016) (xy 79.395066 -53.087016)
		)
		(stroke
			(width 0)
			(type solid)
		)
		(fill yes)
		(layer "In2.Cu")
		(net "M_G_ECC<4>")
	)
	(gr_poly
		(pts
			(xy 79.464154 -57.8612) (xy 79.419704 -57.8612) (xy 79.249524 -57.9501) (xy 79.249524 -58.17108)
			(xy 79.419704 -58.25998) (xy 79.464154 -58.25998)
		)
		(stroke
			(width 0)
			(type solid)
		)
		(fill yes)
		(layer "In2.Cu")
		(net "M_G_ECC<4>")
	)
	(gr_poly
		(pts
			(xy 79.464154 -56.883046) (xy 79.419704 -56.883046) (xy 79.249524 -56.971946) (xy 79.249524 -57.192926)
			(xy 79.419704 -57.281826) (xy 79.464154 -57.281826)
		)
		(stroke
			(width 0)
			(type solid)
		)
		(fill yes)
		(layer "In2.Cu")
		(net "M_G_ECC<4>")
	)
	(gr_poly
		(pts
			(xy 79.464154 -55.892446) (xy 79.419704 -55.892446) (xy 79.249524 -55.981346) (xy 79.249524 -56.202326)
			(xy 79.419704 -56.291226) (xy 79.464154 -56.291226)
		)
		(stroke
			(width 0)
			(type solid)
		)
		(fill yes)
		(layer "In2.Cu")
		(net "M_G_ECC<4>")
	)
	(gr_poly
		(pts
			(xy 79.464154 -54.901846) (xy 79.419704 -54.901846) (xy 79.249524 -54.990746) (xy 79.249524 -55.211726)
			(xy 79.419704 -55.300626) (xy 79.464154 -55.300626)
		)
		(stroke
			(width 0)
			(type solid)
		)
		(fill yes)
		(layer "In2.Cu")
		(net "M_G_ECC<4>")
	)
	(gr_poly
		(pts
			(xy 79.464154 -53.911246) (xy 79.419704 -53.911246) (xy 79.249524 -54.000146) (xy 79.249524 -54.221126)
			(xy 79.419704 -54.310026) (xy 79.464154 -54.310026)
		)
		(stroke
			(width 0)
			(type solid)
		)
		(fill yes)
		(layer "In2.Cu")
		(net "M_G_ECC<4>")
	)
	(gr_poly
		(pts
			(xy 79.464408 -58.846974) (xy 79.419958 -58.846974) (xy 79.249778 -58.935874) (xy 79.249778 -59.156854)
			(xy 79.419958 -59.245754) (xy 79.464154 -59.245754)
		)
		(stroke
			(width 0)
			(type solid)
		)
		(fill yes)
		(layer "In2.Cu")
		(net "M_G_ECC<4>")
	)
	(gr_poly
		(pts
			(xy 79.51724 -99.825556) (xy 79.44358 -99.626166) (xy 79.412338 -99.59467) (xy 79.12481 -99.882198)
			(xy 79.156306 -99.91344) (xy 79.355696 -99.9871)
		)
		(stroke
			(width 0)
			(type solid)
		)
		(fill yes)
		(layer "In2.Cu")
		(net "M_K_ECC<5>")
	)
	(gr_poly
		(pts
			(xy 79.557626 -50.349404) (xy 79.631286 -50.150014) (xy 79.469488 -49.98847) (xy 79.270098 -50.06213)
			(xy 79.238856 -50.093626) (xy 79.52613 -50.3809)
		)
		(stroke
			(width 0)
			(type solid)
		)
		(fill yes)
		(layer "In2.Cu")
		(net "M_G_ECC<1>")
	)
	(gr_poly
		(pts
			(xy 79.656178 -51.54295) (xy 79.729838 -51.34356) (xy 79.568294 -51.182016) (xy 79.368904 -51.255676)
			(xy 79.337408 -51.286918) (xy 79.624936 -51.574446)
		)
		(stroke
			(width 0)
			(type solid)
		)
		(fill yes)
		(layer "In2.Cu")
		(net "M_G_ECC<5>")
	)
	(gr_poly
		(pts
			(xy 79.779876 -100.759514) (xy 79.735426 -100.759514) (xy 79.542386 -100.848414) (xy 79.542386 -101.077014)
			(xy 79.735426 -101.165914) (xy 79.779876 -101.165914)
		)
		(stroke
			(width 0)
			(type solid)
		)
		(fill yes)
		(layer "In2.Cu")
		(net "M_K_ECC<0>")
	)
	(gr_poly
		(pts
			(xy 79.90078 -59.701684) (xy 79.922878 -59.66333) (xy 79.577692 -59.463686) (xy 79.555594 -59.502294)
			(xy 79.547466 -59.694064) (xy 79.738728 -59.804554)
		)
		(stroke
			(width 0)
			(type solid)
		)
		(fill yes)
		(layer "In2.Cu")
		(net "M_G_ECC<4>")
	)
	(gr_poly
		(pts
			(xy 80.00238 -58.678826) (xy 80.00238 -58.457846) (xy 79.8322 -58.368946) (xy 79.78775 -58.368946)
			(xy 79.78775 -58.767726) (xy 79.8322 -58.767726)
		)
		(stroke
			(width 0)
			(type solid)
		)
		(fill yes)
		(layer "In2.Cu")
		(net "M_G_ECC<5>")
	)
	(gr_poly
		(pts
			(xy 80.00238 -57.68213) (xy 80.00238 -57.46115) (xy 79.8322 -57.37225) (xy 79.78775 -57.37225) (xy 79.78775 -57.77103)
			(xy 79.8322 -57.77103)
		)
		(stroke
			(width 0)
			(type solid)
		)
		(fill yes)
		(layer "In2.Cu")
		(net "M_G_ECC<5>")
	)
	(gr_poly
		(pts
			(xy 80.00238 -56.68518) (xy 80.00238 -56.4642) (xy 79.8322 -56.3753) (xy 79.78775 -56.3753) (xy 79.78775 -56.77408)
			(xy 79.8322 -56.77408)
		)
		(stroke
			(width 0)
			(type solid)
		)
		(fill yes)
		(layer "In2.Cu")
		(net "M_G_ECC<5>")
	)
	(gr_poly
		(pts
			(xy 80.00238 -55.69458) (xy 80.00238 -55.4736) (xy 79.8322 -55.3847) (xy 79.78775 -55.3847) (xy 79.78775 -55.78348)
			(xy 79.8322 -55.78348)
		)
		(stroke
			(width 0)
			(type solid)
		)
		(fill yes)
		(layer "In2.Cu")
		(net "M_G_ECC<5>")
	)
	(gr_poly
		(pts
			(xy 80.00238 -54.70398) (xy 80.00238 -54.483) (xy 79.8322 -54.3941) (xy 79.78775 -54.3941) (xy 79.78775 -54.79288)
			(xy 79.8322 -54.79288)
		)
		(stroke
			(width 0)
			(type solid)
		)
		(fill yes)
		(layer "In2.Cu")
		(net "M_G_ECC<5>")
	)
	(gr_poly
		(pts
			(xy 80.00238 -53.71338) (xy 80.00238 -53.4924) (xy 79.8322 -53.4035) (xy 79.78775 -53.4035) (xy 79.78775 -53.80228)
			(xy 79.8322 -53.80228)
		)
		(stroke
			(width 0)
			(type solid)
		)
		(fill yes)
		(layer "In2.Cu")
		(net "M_G_ECC<5>")
	)
	(gr_poly
		(pts
			(xy 80.0608 -51.24704) (xy 80.092296 -51.215798) (xy 79.804768 -50.92827) (xy 79.773526 -50.959766)
			(xy 79.699866 -51.159156) (xy 79.86141 -51.3207)
		)
		(stroke
			(width 0)
			(type solid)
		)
		(fill yes)
		(layer "In2.Cu")
		(net "M_G_ECC<0>")
	)
	(gr_poly
		(pts
			(xy 80.119982 -52.215034) (xy 80.119982 -51.986434) (xy 79.926942 -51.897534) (xy 79.882492 -51.897534)
			(xy 79.882492 -52.303934) (xy 79.926942 -52.303934)
		)
		(stroke
			(width 0)
			(type solid)
		)
		(fill yes)
		(layer "In2.Cu")
		(net "M_G_ECC<5>")
	)
	(gr_poly
		(pts
			(xy 80.207358 -101.077014) (xy 80.207358 -100.848414) (xy 80.014318 -100.759514) (xy 79.969868 -100.759514)
			(xy 79.969868 -101.165914) (xy 80.014318 -101.165914)
		)
		(stroke
			(width 0)
			(type solid)
		)
		(fill yes)
		(layer "In2.Cu")
		(net "M_K_ECC<1>")
	)
	(gr_poly
		(pts
			(xy 80.257904 -51.049936) (xy 80.331564 -50.850546) (xy 80.17002 -50.689002) (xy 79.97063 -50.762662)
			(xy 79.939134 -50.793904) (xy 80.226662 -51.081432)
		)
		(stroke
			(width 0)
			(type solid)
		)
		(fill yes)
		(layer "In2.Cu")
		(net "M_G_ECC<1>")
	)
	(gr_poly
		(pts
			(xy 80.322674 -97.9805) (xy 80.278224 -97.9805) (xy 80.108044 -98.0694) (xy 80.108044 -98.29038)
			(xy 80.278224 -98.37928) (xy 80.322674 -98.37928)
		)
		(stroke
			(width 0)
			(type solid)
		)
		(fill yes)
		(layer "In2.Cu")
		(net "M_K_ECC<4>")
	)
	(gr_poly
		(pts
			(xy 80.322674 -96.9899) (xy 80.278224 -96.9899) (xy 80.108044 -97.0788) (xy 80.108044 -97.29978)
			(xy 80.278224 -97.38868) (xy 80.322674 -97.38868)
		)
		(stroke
			(width 0)
			(type solid)
		)
		(fill yes)
		(layer "In2.Cu")
		(net "M_K_ECC<4>")
	)
	(gr_poly
		(pts
			(xy 80.322674 -95.9993) (xy 80.278224 -95.9993) (xy 80.108044 -96.0882) (xy 80.108044 -96.30918)
			(xy 80.278224 -96.39808) (xy 80.322674 -96.39808)
		)
		(stroke
			(width 0)
			(type solid)
		)
		(fill yes)
		(layer "In2.Cu")
		(net "M_K_ECC<4>")
	)
	(gr_poly
		(pts
			(xy 80.322674 -95.0087) (xy 80.278224 -95.0087) (xy 80.108044 -95.0976) (xy 80.108044 -95.31858)
			(xy 80.278224 -95.40748) (xy 80.322674 -95.40748)
		)
		(stroke
			(width 0)
			(type solid)
		)
		(fill yes)
		(layer "In2.Cu")
		(net "M_K_ECC<4>")
	)
	(gr_poly
		(pts
			(xy 80.322674 -94.030546) (xy 80.278224 -94.030546) (xy 80.108044 -94.119446) (xy 80.108044 -94.340426)
			(xy 80.278224 -94.429326) (xy 80.322674 -94.429326)
		)
		(stroke
			(width 0)
			(type solid)
		)
		(fill yes)
		(layer "In2.Cu")
		(net "M_K_ECC<4>")
	)
	(gr_poly
		(pts
			(xy 80.322674 -93.03385) (xy 80.278224 -93.03385) (xy 80.108044 -93.12275) (xy 80.108044 -93.34373)
			(xy 80.278224 -93.43263) (xy 80.322674 -93.43263)
		)
		(stroke
			(width 0)
			(type solid)
		)
		(fill yes)
		(layer "In2.Cu")
		(net "M_K_ECC<4>")
	)
	(gr_poly
		(pts
			(xy 80.322674 -92.047568) (xy 80.278224 -92.047822) (xy 80.108298 -92.136722) (xy 80.108044 -92.357448)
			(xy 80.278224 -92.446348) (xy 80.322928 -92.446602)
		)
		(stroke
			(width 0)
			(type solid)
		)
		(fill yes)
		(layer "In2.Cu")
		(net "M_K_ECC<4>")
	)
	(gr_poly
		(pts
			(xy 80.322674 -58.362342) (xy 80.278224 -58.362596) (xy 80.108298 -58.451496) (xy 80.108298 -58.672476)
			(xy 80.278478 -58.761122) (xy 80.322928 -58.761376)
		)
		(stroke
			(width 0)
			(type solid)
		)
		(fill yes)
		(layer "In2.Cu")
		(net "M_G_ECC<0>")
	)
	(gr_poly
		(pts
			(xy 80.322674 -57.37225) (xy 80.278224 -57.37225) (xy 80.108044 -57.46115) (xy 80.108044 -57.68213)
			(xy 80.278224 -57.77103) (xy 80.322674 -57.77103)
		)
		(stroke
			(width 0)
			(type solid)
		)
		(fill yes)
		(layer "In2.Cu")
		(net "M_G_ECC<0>")
	)
	(gr_poly
		(pts
			(xy 80.322674 -56.3753) (xy 80.278224 -56.3753) (xy 80.108044 -56.4642) (xy 80.108044 -56.68518)
			(xy 80.278224 -56.77408) (xy 80.322674 -56.77408)
		)
		(stroke
			(width 0)
			(type solid)
		)
		(fill yes)
		(layer "In2.Cu")
		(net "M_G_ECC<0>")
	)
	(gr_poly
		(pts
			(xy 80.322928 -55.39105) (xy 80.278478 -55.39105) (xy 80.108298 -55.47995) (xy 80.108298 -55.70093)
			(xy 80.278478 -55.78983) (xy 80.322928 -55.78983)
		)
		(stroke
			(width 0)
			(type solid)
		)
		(fill yes)
		(layer "In2.Cu")
		(net "M_G_ECC<0>")
	)
	(gr_poly
		(pts
			(xy 80.485742 -54.381146) (xy 80.441292 -54.381146) (xy 80.248252 -54.470046) (xy 80.248252 -54.698646)
			(xy 80.441292 -54.787546) (xy 80.485742 -54.787546)
		)
		(stroke
			(width 0)
			(type solid)
		)
		(fill yes)
		(layer "In2.Cu")
		(net "M_G_ECC<0>")
	)
	(gr_poly
		(pts
			(xy 80.485742 -53.390546) (xy 80.441292 -53.390546) (xy 80.248252 -53.479446) (xy 80.248252 -53.708046)
			(xy 80.441292 -53.796946) (xy 80.485742 -53.796946)
		)
		(stroke
			(width 0)
			(type solid)
		)
		(fill yes)
		(layer "In2.Cu")
		(net "M_G_ECC<0>")
	)
	(gr_poly
		(pts
			(xy 80.496156 -50.097944) (xy 80.527398 -50.066448) (xy 80.240124 -49.779174) (xy 80.208628 -49.81067)
			(xy 80.134968 -50.01006) (xy 80.296766 -50.171604)
		)
		(stroke
			(width 0)
			(type solid)
		)
		(fill yes)
		(layer "In2.Cu")
		(net "M_G_DQS_DP<17>")
	)
	(gr_poly
		(pts
			(xy 80.552036 -100.381562) (xy 80.478376 -100.182172) (xy 80.447134 -100.150676) (xy 80.159606 -100.438204)
			(xy 80.191102 -100.469446) (xy 80.390492 -100.543106)
		)
		(stroke
			(width 0)
			(type solid)
		)
		(fill yes)
		(layer "In2.Cu")
		(net "M_K_ECC<1>")
	)
	(gr_poly
		(pts
			(xy 80.553306 -59.602116) (xy 80.561434 -59.410346) (xy 80.370172 -59.299856) (xy 80.20812 -59.402726)
			(xy 80.185768 -59.441334) (xy 80.531208 -59.640724)
		)
		(stroke
			(width 0)
			(type solid)
		)
		(fill yes)
		(layer "In2.Cu")
		(net "M_G_ECC<5>")
	)
	(gr_poly
		(pts
			(xy 80.5561 -99.322382) (xy 80.547972 -99.130612) (xy 80.526128 -99.092258) (xy 80.180434 -99.291394)
			(xy 80.202786 -99.330002) (xy 80.364838 -99.432872)
		)
		(stroke
			(width 0)
			(type solid)
		)
		(fill yes)
		(layer "In2.Cu")
		(net "M_K_ECC<5>")
	)
	(gr_poly
		(pts
			(xy 80.603852 -52.008024) (xy 80.559402 -52.008024) (xy 80.366362 -52.096924) (xy 80.366362 -52.325524)
			(xy 80.559402 -52.414424) (xy 80.603852 -52.414424)
		)
		(stroke
			(width 0)
			(type solid)
		)
		(fill yes)
		(layer "In2.Cu")
		(net "M_G_ECC<0>")
	)
	(gr_poly
		(pts
			(xy 80.760824 -60.198) (xy 80.783176 -60.159646) (xy 80.437736 -59.960002) (xy 80.415638 -59.99861)
			(xy 80.40751 -60.19038) (xy 80.598772 -60.30087)
		)
		(stroke
			(width 0)
			(type solid)
		)
		(fill yes)
		(layer "In2.Cu")
		(net "M_G_ECC<4>")
	)
	(gr_poly
		(pts
			(xy 80.768698 -59.211718) (xy 80.79105 -59.173364) (xy 80.445356 -58.973974) (xy 80.423258 -59.012582)
			(xy 80.415384 -59.204352) (xy 80.606646 -59.314842)
		)
		(stroke
			(width 0)
			(type solid)
		)
		(fill yes)
		(layer "In2.Cu")
		(net "M_G_ECC<0>")
	)
	(gr_poly
		(pts
			(xy 80.783176 -99.56038) (xy 80.760824 -99.522026) (xy 80.598772 -99.419156) (xy 80.40751 -99.529646)
			(xy 80.415638 -99.721416) (xy 80.437736 -99.75977)
		)
		(stroke
			(width 0)
			(type solid)
		)
		(fill yes)
		(layer "In2.Cu")
		(net "M_K_ECC<0>")
	)
	(gr_poly
		(pts
			(xy 80.78724 -91.633294) (xy 80.764634 -91.59494) (xy 80.602836 -91.49207) (xy 80.41132 -91.602306)
			(xy 80.419448 -91.794076) (xy 80.4418 -91.832938)
		)
		(stroke
			(width 0)
			(type solid)
		)
		(fill yes)
		(layer "In2.Cu")
		(net "M_K_ECC<4>")
	)
	(gr_poly
		(pts
			(xy 80.8609 -98.788982) (xy 80.8609 -98.568002) (xy 80.69072 -98.479102) (xy 80.646524 -98.478848)
			(xy 80.64627 -98.877882) (xy 80.69072 -98.877882)
		)
		(stroke
			(width 0)
			(type solid)
		)
		(fill yes)
		(layer "In2.Cu")
		(net "M_K_ECC<5>")
	)
	(gr_poly
		(pts
			(xy 80.8609 -97.807526) (xy 80.8609 -97.586546) (xy 80.69072 -97.497646) (xy 80.64627 -97.497646)
			(xy 80.64627 -97.896426) (xy 80.69072 -97.896426)
		)
		(stroke
			(width 0)
			(type solid)
		)
		(fill yes)
		(layer "In2.Cu")
		(net "M_K_ECC<5>")
	)
	(gr_poly
		(pts
			(xy 80.8609 -96.816926) (xy 80.8609 -96.595946) (xy 80.69072 -96.507046) (xy 80.64627 -96.507046)
			(xy 80.64627 -96.905826) (xy 80.69072 -96.905826)
		)
		(stroke
			(width 0)
			(type solid)
		)
		(fill yes)
		(layer "In2.Cu")
		(net "M_K_ECC<5>")
	)
	(gr_poly
		(pts
			(xy 80.8609 -95.826326) (xy 80.8609 -95.605346) (xy 80.69072 -95.516446) (xy 80.64627 -95.516446)
			(xy 80.64627 -95.915226) (xy 80.69072 -95.915226)
		)
		(stroke
			(width 0)
			(type solid)
		)
		(fill yes)
		(layer "In2.Cu")
		(net "M_K_ECC<5>")
	)
	(gr_poly
		(pts
			(xy 80.8609 -94.829376) (xy 80.8609 -94.608396) (xy 80.69072 -94.519496) (xy 80.64627 -94.519496)
			(xy 80.64627 -94.918276) (xy 80.69072 -94.918276)
		)
		(stroke
			(width 0)
			(type solid)
		)
		(fill yes)
		(layer "In2.Cu")
		(net "M_K_ECC<5>")
	)
	(gr_poly
		(pts
			(xy 80.8609 -93.83268) (xy 80.8609 -93.6117) (xy 80.69072 -93.5228) (xy 80.64627 -93.5228) (xy 80.64627 -93.92158)
			(xy 80.69072 -93.92158)
		)
		(stroke
			(width 0)
			(type solid)
		)
		(fill yes)
		(layer "In2.Cu")
		(net "M_K_ECC<5>")
	)
	(gr_poly
		(pts
			(xy 80.8609 -92.854526) (xy 80.8609 -92.633546) (xy 80.69072 -92.544646) (xy 80.64627 -92.544646)
			(xy 80.64627 -92.943426) (xy 80.69072 -92.943426)
		)
		(stroke
			(width 0)
			(type solid)
		)
		(fill yes)
		(layer "In2.Cu")
		(net "M_K_ECC<5>")
	)
	(gr_poly
		(pts
			(xy 80.8609 -58.17108) (xy 80.8609 -57.9501) (xy 80.69072 -57.8612) (xy 80.64627 -57.8612) (xy 80.64627 -58.25998)
			(xy 80.69072 -58.25998)
		)
		(stroke
			(width 0)
			(type solid)
		)
		(fill yes)
		(layer "In2.Cu")
		(net "M_G_ECC<1>")
	)
	(gr_poly
		(pts
			(xy 80.8609 -57.192926) (xy 80.8609 -56.971946) (xy 80.69072 -56.883046) (xy 80.64627 -56.883046)
			(xy 80.64627 -57.281826) (xy 80.69072 -57.281826)
		)
		(stroke
			(width 0)
			(type solid)
		)
		(fill yes)
		(layer "In2.Cu")
		(net "M_G_ECC<1>")
	)
	(gr_poly
		(pts
			(xy 80.8609 -56.202326) (xy 80.8609 -55.981346) (xy 80.69072 -55.892446) (xy 80.64627 -55.892446)
			(xy 80.64627 -56.291226) (xy 80.69072 -56.291226)
		)
		(stroke
			(width 0)
			(type solid)
		)
		(fill yes)
		(layer "In2.Cu")
		(net "M_G_ECC<1>")
	)
	(gr_poly
		(pts
			(xy 80.878172 -101.402642) (xy 80.833722 -101.402642) (xy 80.640682 -101.491542) (xy 80.640682 -101.720142)
			(xy 80.833722 -101.809042) (xy 80.878172 -101.809042)
		)
		(stroke
			(width 0)
			(type solid)
		)
		(fill yes)
		(layer "In2.Cu")
		(net "M_K_DQS_DP<17>")
	)
	(gr_poly
		(pts
			(xy 80.913732 -54.698646) (xy 80.913732 -54.470046) (xy 80.720692 -54.381146) (xy 80.676242 -54.381146)
			(xy 80.676242 -54.787546) (xy 80.720692 -54.787546)
		)
		(stroke
			(width 0)
			(type solid)
		)
		(fill yes)
		(layer "In2.Cu")
		(net "M_G_ECC<1>")
	)
	(gr_poly
		(pts
			(xy 80.913732 -53.708046) (xy 80.913732 -53.479446) (xy 80.720692 -53.390546) (xy 80.676242 -53.390546)
			(xy 80.676242 -53.796946) (xy 80.720692 -53.796946)
		)
		(stroke
			(width 0)
			(type solid)
		)
		(fill yes)
		(layer "In2.Cu")
		(net "M_G_ECC<1>")
	)
	(gr_poly
		(pts
			(xy 81.031334 -52.325524) (xy 81.031334 -52.096924) (xy 80.838294 -52.008024) (xy 80.793844 -52.008024)
			(xy 80.793844 -52.414424) (xy 80.838294 -52.414424)
		)
		(stroke
			(width 0)
			(type solid)
		)
		(fill yes)
		(layer "In2.Cu")
		(net "M_G_ECC<1>")
	)
	(gr_poly
		(pts
			(xy 81.140046 -50.346864) (xy 81.213706 -50.147474) (xy 81.052162 -49.98593) (xy 80.852772 -50.05959)
			(xy 80.821276 -50.090832) (xy 81.108804 -50.37836)
		)
		(stroke
			(width 0)
			(type solid)
		)
		(fill yes)
		(layer "In2.Cu")
		(net "M_G_DQS_DN<17>")
	)
	(gr_poly
		(pts
			(xy 81.181194 -98.488246) (xy 81.136744 -98.488246) (xy 80.966564 -98.577146) (xy 80.966564 -98.798126)
			(xy 81.136744 -98.887026) (xy 81.181194 -98.887026)
		)
		(stroke
			(width 0)
			(type solid)
		)
		(fill yes)
		(layer "In2.Cu")
		(net "M_K_ECC<0>")
	)
	(gr_poly
		(pts
			(xy 81.181194 -97.491296) (xy 81.136744 -97.491296) (xy 80.966564 -97.580196) (xy 80.966564 -97.801176)
			(xy 81.136744 -97.890076) (xy 81.181194 -97.890076)
		)
		(stroke
			(width 0)
			(type solid)
		)
		(fill yes)
		(layer "In2.Cu")
		(net "M_K_ECC<0>")
	)
	(gr_poly
		(pts
			(xy 81.181194 -96.507046) (xy 81.136744 -96.507046) (xy 80.966564 -96.595946) (xy 80.966564 -96.816926)
			(xy 81.136744 -96.905826) (xy 81.181194 -96.905826)
		)
		(stroke
			(width 0)
			(type solid)
		)
		(fill yes)
		(layer "In2.Cu")
		(net "M_K_ECC<0>")
	)
	(gr_poly
		(pts
			(xy 81.181194 -95.516446) (xy 81.136744 -95.516446) (xy 80.966564 -95.605346) (xy 80.966564 -95.826326)
			(xy 81.136744 -95.915226) (xy 81.181194 -95.915226)
		)
		(stroke
			(width 0)
			(type solid)
		)
		(fill yes)
		(layer "In2.Cu")
		(net "M_K_ECC<0>")
	)
	(gr_poly
		(pts
			(xy 81.181194 -94.519496) (xy 81.136744 -94.519496) (xy 80.966564 -94.608396) (xy 80.966564 -94.829376)
			(xy 81.136744 -94.918276) (xy 81.181194 -94.918276)
		)
		(stroke
			(width 0)
			(type solid)
		)
		(fill yes)
		(layer "In2.Cu")
		(net "M_K_ECC<0>")
	)
	(gr_poly
		(pts
			(xy 81.181194 -93.5228) (xy 81.136744 -93.5228) (xy 80.966564 -93.6117) (xy 80.966564 -93.83268)
			(xy 81.136744 -93.92158) (xy 81.181194 -93.92158)
		)
		(stroke
			(width 0)
			(type solid)
		)
		(fill yes)
		(layer "In2.Cu")
		(net "M_K_ECC<0>")
	)
	(gr_poly
		(pts
			(xy 81.181194 -92.547186) (xy 81.136998 -92.547186) (xy 80.966818 -92.636086) (xy 80.966818 -92.856812)
			(xy 81.136744 -92.945712) (xy 81.181448 -92.945966)
		)
		(stroke
			(width 0)
			(type solid)
		)
		(fill yes)
		(layer "In2.Cu")
		(net "M_K_ECC<0>")
	)
	(gr_poly
		(pts
			(xy 81.181194 -56.883046) (xy 81.136744 -56.883046) (xy 80.966564 -56.971946) (xy 80.966564 -57.192926)
			(xy 81.136744 -57.281826) (xy 81.181194 -57.281826)
		)
		(stroke
			(width 0)
			(type solid)
		)
		(fill yes)
		(layer "In2.Cu")
		(net "M_G_DQS_DP<17>")
	)
	(gr_poly
		(pts
			(xy 81.181194 -55.893462) (xy 81.136744 -55.893462) (xy 80.966564 -55.982362) (xy 80.966564 -56.203342)
			(xy 81.136744 -56.292242) (xy 81.181194 -56.292242)
		)
		(stroke
			(width 0)
			(type solid)
		)
		(fill yes)
		(layer "In2.Cu")
		(net "M_G_DQS_DP<17>")
	)
	(gr_poly
		(pts
			(xy 81.181448 -57.85866) (xy 81.136998 -57.858914) (xy 80.966818 -57.947814) (xy 80.966818 -58.16854)
			(xy 81.136998 -58.25744) (xy 81.181194 -58.25744)
		)
		(stroke
			(width 0)
			(type solid)
		)
		(fill yes)
		(layer "In2.Cu")
		(net "M_G_DQS_DP<17>")
	)
	(gr_poly
		(pts
			(xy 81.182464 -90.546428) (xy 81.13776 -90.546428) (xy 80.96758 -90.634312) (xy 80.966564 -90.855546)
			(xy 81.13649 -90.9447) (xy 81.18094 -90.944954)
		)
		(stroke
			(width 0)
			(type solid)
		)
		(fill yes)
		(layer "In2.Cu")
		(net "M_K_ECC<4>")
	)
	(gr_poly
		(pts
			(xy 81.196434 -50.798476) (xy 81.22793 -50.76698) (xy 80.940656 -50.479706) (xy 80.90916 -50.511202)
			(xy 80.8355 -50.710338) (xy 80.997298 -50.872136)
		)
		(stroke
			(width 0)
			(type solid)
		)
		(fill yes)
		(layer "In2.Cu")
		(net "M_G_DQS_DP<17>")
	)
	(gr_poly
		(pts
			(xy 81.266792 -54.827424) (xy 81.222342 -54.827424) (xy 81.029302 -54.916324) (xy 81.029302 -55.144924)
			(xy 81.222342 -55.233824) (xy 81.266792 -55.233824)
		)
		(stroke
			(width 0)
			(type solid)
		)
		(fill yes)
		(layer "In2.Cu")
		(net "M_G_DQS_DP<17>")
	)
	(gr_poly
		(pts
			(xy 81.266792 -53.836824) (xy 81.222342 -53.836824) (xy 81.029302 -53.925724) (xy 81.029302 -54.154324)
			(xy 81.222342 -54.243224) (xy 81.266792 -54.243224)
		)
		(stroke
			(width 0)
			(type solid)
		)
		(fill yes)
		(layer "In2.Cu")
		(net "M_G_DQS_DP<17>")
	)
	(gr_poly
		(pts
			(xy 81.266792 -52.846224) (xy 81.222342 -52.846224) (xy 81.029302 -52.935124) (xy 81.029302 -53.163724)
			(xy 81.222342 -53.252624) (xy 81.266792 -53.252624)
		)
		(stroke
			(width 0)
			(type solid)
		)
		(fill yes)
		(layer "In2.Cu")
		(net "M_G_DQS_DP<17>")
	)
	(gr_poly
		(pts
			(xy 81.306162 -101.720142) (xy 81.306162 -101.491542) (xy 81.113122 -101.402642) (xy 81.068672 -101.402642)
			(xy 81.068672 -101.809042) (xy 81.113122 -101.809042)
		)
		(stroke
			(width 0)
			(type solid)
		)
		(fill yes)
		(layer "In2.Cu")
		(net "M_K_DQS_DN<17>")
	)
	(gr_poly
		(pts
			(xy 81.40954 -59.105546) (xy 81.417668 -58.913776) (xy 81.226406 -58.803286) (xy 81.064354 -58.906156)
			(xy 81.042002 -58.94451) (xy 81.387442 -59.144154)
		)
		(stroke
			(width 0)
			(type solid)
		)
		(fill yes)
		(layer "In2.Cu")
		(net "M_G_ECC<1>")
	)
	(gr_poly
		(pts
			(xy 81.41335 -60.098432) (xy 81.421478 -59.906662) (xy 81.230216 -59.796172) (xy 81.068164 -59.899042)
			(xy 81.045812 -59.93765) (xy 81.391252 -60.13704)
		)
		(stroke
			(width 0)
			(type solid)
		)
		(fill yes)
		(layer "In2.Cu")
		(net "M_G_ECC<5>")
	)
	(gr_poly
		(pts
			(xy 81.4197 -91.890088) (xy 81.411572 -91.698064) (xy 81.389474 -91.659456) (xy 81.044288 -91.8591)
			(xy 81.066386 -91.897454) (xy 81.228438 -92.000324)
		)
		(stroke
			(width 0)
			(type solid)
		)
		(fill yes)
		(layer "In2.Cu")
		(net "M_K_ECC<5>")
	)
	(gr_poly
		(pts
			(xy 81.61782 -59.701684) (xy 81.640172 -59.66333) (xy 81.294732 -59.463686) (xy 81.272634 -59.502294)
			(xy 81.264506 -59.694064) (xy 81.455768 -59.804554)
		)
		(stroke
			(width 0)
			(type solid)
		)
		(fill yes)
		(layer "In2.Cu")
		(net "M_G_ECC<0>")
	)
	(gr_poly
		(pts
			(xy 81.619598 -58.712354) (xy 81.641696 -58.674) (xy 81.29651 -58.474356) (xy 81.274412 -58.513218)
			(xy 81.266284 -58.704988) (xy 81.457546 -58.815224)
		)
		(stroke
			(width 0)
			(type solid)
		)
		(fill yes)
		(layer "In2.Cu")
		(net "M_G_DQS_DP<17>")
	)
	(gr_poly
		(pts
			(xy 81.641696 -92.130626) (xy 81.619598 -92.092272) (xy 81.457546 -91.989402) (xy 81.266284 -92.099638)
			(xy 81.274412 -92.291408) (xy 81.29651 -92.33027)
		)
		(stroke
			(width 0)
			(type solid)
		)
		(fill yes)
		(layer "In2.Cu")
		(net "M_K_ECC<0>")
	)
	(gr_poly
		(pts
			(xy 81.642966 -90.136472) (xy 81.617312 -90.099896) (xy 81.447132 -90.011504) (xy 81.26603 -90.13825)
			(xy 81.290922 -90.328496) (xy 81.316322 -90.364818)
		)
		(stroke
			(width 0)
			(type solid)
		)
		(fill yes)
		(layer "In2.Cu")
		(net "M_K_ECC<4>")
	)
	(gr_poly
		(pts
			(xy 81.654142 -100.221542) (xy 81.622646 -100.1903) (xy 81.423256 -100.11664) (xy 81.261712 -100.278184)
			(xy 81.335372 -100.477574) (xy 81.366614 -100.50907)
		)
		(stroke
			(width 0)
			(type solid)
		)
		(fill yes)
		(layer "In2.Cu")
		(net "M_K_DQS_DP<17>")
	)
	(gr_poly
		(pts
			(xy 81.694782 -55.017924) (xy 81.694782 -54.789324) (xy 81.501742 -54.700424) (xy 81.457292 -54.700424)
			(xy 81.457292 -55.106824) (xy 81.501742 -55.106824)
		)
		(stroke
			(width 0)
			(type solid)
		)
		(fill yes)
		(layer "In2.Cu")
		(net "M_G_DQS_DN<17>")
	)
	(gr_poly
		(pts
			(xy 81.694782 -54.154324) (xy 81.694782 -53.925724) (xy 81.501742 -53.836824) (xy 81.457292 -53.836824)
			(xy 81.457292 -54.243224) (xy 81.501742 -54.243224)
		)
		(stroke
			(width 0)
			(type solid)
		)
		(fill yes)
		(layer "In2.Cu")
		(net "M_G_DQS_DN<17>")
	)
	(gr_poly
		(pts
			(xy 81.71815 -52.355496) (xy 81.686654 -52.324254) (xy 81.487264 -52.250594) (xy 81.32572 -52.412138)
			(xy 81.39938 -52.611528) (xy 81.430622 -52.643024)
		)
		(stroke
			(width 0)
			(type solid)
		)
		(fill yes)
		(layer "In2.Cu")
		(net "M_G_DQS_DP<17>")
	)
	(gr_poly
		(pts
			(xy 81.719166 -91.35364) (xy 81.719166 -91.132914) (xy 81.548986 -91.044014) (xy 81.504536 -91.04376)
			(xy 81.50479 -91.44254) (xy 81.548986 -91.44254)
		)
		(stroke
			(width 0)
			(type solid)
		)
		(fill yes)
		(layer "In2.Cu")
		(net "M_K_ECC<5>")
	)
	(gr_poly
		(pts
			(xy 81.719166 -57.675272) (xy 81.719166 -57.454292) (xy 81.548986 -57.365392) (xy 81.504536 -57.365392)
			(xy 81.504536 -57.764172) (xy 81.548986 -57.764172)
		)
		(stroke
			(width 0)
			(type solid)
		)
		(fill yes)
		(layer "In2.Cu")
		(net "M_G_DQS_DN<17>")
	)
	(gr_poly
		(pts
			(xy 81.719166 -56.684672) (xy 81.719166 -56.463692) (xy 81.548986 -56.374792) (xy 81.504536 -56.374792)
			(xy 81.504536 -56.773572) (xy 81.548986 -56.773572)
		)
		(stroke
			(width 0)
			(type solid)
		)
		(fill yes)
		(layer "In2.Cu")
		(net "M_G_DQS_DN<17>")
	)
	(gr_poly
		(pts
			(xy 81.71942 -99.28098) (xy 81.71942 -99.06) (xy 81.54924 -98.9711) (xy 81.50479 -98.9711) (xy 81.50479 -99.36988)
			(xy 81.54924 -99.36988)
		)
		(stroke
			(width 0)
			(type solid)
		)
		(fill yes)
		(layer "In2.Cu")
		(net "M_K_ECC<1>")
	)
	(gr_poly
		(pts
			(xy 81.71942 -98.29038) (xy 81.71942 -98.0694) (xy 81.54924 -97.9805) (xy 81.50479 -97.9805) (xy 81.50479 -98.37928)
			(xy 81.54924 -98.37928)
		)
		(stroke
			(width 0)
			(type solid)
		)
		(fill yes)
		(layer "In2.Cu")
		(net "M_K_ECC<1>")
	)
	(gr_poly
		(pts
			(xy 81.71942 -97.312226) (xy 81.71942 -97.091246) (xy 81.54924 -97.002346) (xy 81.50479 -97.002346)
			(xy 81.50479 -97.401126) (xy 81.54924 -97.401126)
		)
		(stroke
			(width 0)
			(type solid)
		)
		(fill yes)
		(layer "In2.Cu")
		(net "M_K_ECC<1>")
	)
	(gr_poly
		(pts
			(xy 81.71942 -96.30918) (xy 81.71942 -96.0882) (xy 81.54924 -95.9993) (xy 81.50479 -95.9993) (xy 81.50479 -96.39808)
			(xy 81.54924 -96.39808)
		)
		(stroke
			(width 0)
			(type solid)
		)
		(fill yes)
		(layer "In2.Cu")
		(net "M_K_ECC<1>")
	)
	(gr_poly
		(pts
			(xy 81.71942 -95.31858) (xy 81.71942 -95.0976) (xy 81.54924 -95.0087) (xy 81.50479 -95.0087) (xy 81.50479 -95.40748)
			(xy 81.54924 -95.40748)
		)
		(stroke
			(width 0)
			(type solid)
		)
		(fill yes)
		(layer "In2.Cu")
		(net "M_K_ECC<1>")
	)
	(gr_poly
		(pts
			(xy 81.71942 -94.340426) (xy 81.71942 -94.119446) (xy 81.54924 -94.030546) (xy 81.50479 -94.030546)
			(xy 81.50479 -94.429326) (xy 81.54924 -94.429326)
		)
		(stroke
			(width 0)
			(type solid)
		)
		(fill yes)
		(layer "In2.Cu")
		(net "M_K_ECC<1>")
	)
	(gr_poly
		(pts
			(xy 81.71942 -93.34373) (xy 81.71942 -93.12275) (xy 81.54924 -93.03385) (xy 81.50479 -93.03385) (xy 81.50479 -93.43263)
			(xy 81.54924 -93.43263)
		)
		(stroke
			(width 0)
			(type solid)
		)
		(fill yes)
		(layer "In2.Cu")
		(net "M_K_ECC<1>")
	)
	(gr_poly
		(pts
			(xy 81.792318 -100.688648) (xy 81.718658 -100.489512) (xy 81.687162 -100.458016) (xy 81.399888 -100.74529)
			(xy 81.431384 -100.776786) (xy 81.63052 -100.850446)
		)
		(stroke
			(width 0)
			(type solid)
		)
		(fill yes)
		(layer "In2.Cu")
		(net "M_K_DQS_DN<17>")
	)
	(gr_poly
		(pts
			(xy 81.840578 -51.047396) (xy 81.914238 -50.848006) (xy 81.752694 -50.686208) (xy 81.553304 -50.759868)
			(xy 81.521808 -50.791364) (xy 81.809082 -51.078638)
		)
		(stroke
			(width 0)
			(type solid)
		)
		(fill yes)
		(layer "In2.Cu")
		(net "M_G_DQS_DN<17>")
	)
	(gr_poly
		(pts
			(xy 81.884774 -102.419912) (xy 81.840324 -102.419912) (xy 81.647284 -102.508812) (xy 81.647284 -102.737412)
			(xy 81.840324 -102.826312) (xy 81.884774 -102.826312)
		)
		(stroke
			(width 0)
			(type solid)
		)
		(fill yes)
		(layer "In2.Cu")
		(net "M_K_DQS_DN<8>")
	)
	(gr_poly
		(pts
			(xy 81.939384 -98.465894) (xy 81.894934 -98.465894) (xy 81.701894 -98.554794) (xy 81.701894 -98.783394)
			(xy 81.894934 -98.872294) (xy 81.939384 -98.872294)
		)
		(stroke
			(width 0)
			(type solid)
		)
		(fill yes)
		(layer "In2.Cu")
		(net "M_K_DQS_DP<17>")
	)
	(gr_poly
		(pts
			(xy 81.939384 -97.475294) (xy 81.894934 -97.475294) (xy 81.701894 -97.564194) (xy 81.701894 -97.792794)
			(xy 81.894934 -97.881694) (xy 81.939384 -97.881694)
		)
		(stroke
			(width 0)
			(type solid)
		)
		(fill yes)
		(layer "In2.Cu")
		(net "M_K_DQS_DP<17>")
	)
	(gr_poly
		(pts
			(xy 81.957926 -52.721002) (xy 81.884266 -52.521866) (xy 81.85277 -52.49037) (xy 81.565496 -52.777644)
			(xy 81.596992 -52.80914) (xy 81.796128 -52.8828)
		)
		(stroke
			(width 0)
			(type solid)
		)
		(fill yes)
		(layer "In2.Cu")
		(net "M_G_DQS_DN<17>")
	)
	(gr_poly
		(pts
			(xy 82.03946 -55.23865) (xy 81.99501 -55.23865) (xy 81.80197 -55.32755) (xy 81.80197 -55.55615) (xy 81.99501 -55.64505)
			(xy 82.03946 -55.64505)
		)
		(stroke
			(width 0)
			(type solid)
		)
		(fill yes)
		(layer "In2.Cu")
		(net "M_G_DQS_DN<8>")
	)
	(gr_poly
		(pts
			(xy 82.03946 -54.24805) (xy 81.99501 -54.24805) (xy 81.80197 -54.33695) (xy 81.80197 -54.56555) (xy 81.99501 -54.65445)
			(xy 82.03946 -54.65445)
		)
		(stroke
			(width 0)
			(type solid)
		)
		(fill yes)
		(layer "In2.Cu")
		(net "M_G_DQS_DN<8>")
	)
	(gr_poly
		(pts
			(xy 82.03946 -53.25745) (xy 81.99501 -53.25745) (xy 81.80197 -53.34635) (xy 81.80197 -53.57495) (xy 81.99501 -53.66385)
			(xy 82.03946 -53.66385)
		)
		(stroke
			(width 0)
			(type solid)
		)
		(fill yes)
		(layer "In2.Cu")
		(net "M_G_DQS_DN<8>")
	)
	(gr_poly
		(pts
			(xy 82.039714 -95.9993) (xy 81.995264 -95.9993) (xy 81.825084 -96.0882) (xy 81.825084 -96.30918)
			(xy 81.995264 -96.39808) (xy 82.039714 -96.39808)
		)
		(stroke
			(width 0)
			(type solid)
		)
		(fill yes)
		(layer "In2.Cu")
		(net "M_K_DQS_DP<17>")
	)
	(gr_poly
		(pts
			(xy 82.039714 -95.0087) (xy 81.995264 -95.0087) (xy 81.825084 -95.0976) (xy 81.825084 -95.31858)
			(xy 81.995264 -95.40748) (xy 82.039714 -95.40748)
		)
		(stroke
			(width 0)
			(type solid)
		)
		(fill yes)
		(layer "In2.Cu")
		(net "M_K_DQS_DP<17>")
	)
	(gr_poly
		(pts
			(xy 82.039714 -94.030546) (xy 81.995264 -94.030546) (xy 81.825084 -94.119446) (xy 81.825084 -94.340426)
			(xy 81.995264 -94.429326) (xy 82.039714 -94.429326)
		)
		(stroke
			(width 0)
			(type solid)
		)
		(fill yes)
		(layer "In2.Cu")
		(net "M_K_DQS_DP<17>")
	)
	(gr_poly
		(pts
			(xy 82.039714 -91.0463) (xy 81.995264 -91.0463) (xy 81.825084 -91.1352) (xy 81.825084 -91.35618)
			(xy 81.995264 -91.44508) (xy 82.039714 -91.44508)
		)
		(stroke
			(width 0)
			(type solid)
		)
		(fill yes)
		(layer "In2.Cu")
		(net "M_K_ECC<0>")
	)
	(gr_poly
		(pts
			(xy 82.039714 -56.3753) (xy 81.995264 -56.3753) (xy 81.825084 -56.4642) (xy 81.825084 -56.68518)
			(xy 81.995264 -56.77408) (xy 82.039714 -56.77408)
		)
		(stroke
			(width 0)
			(type solid)
		)
		(fill yes)
		(layer "In2.Cu")
		(net "M_G_DQS_DN<8>")
	)
	(gr_poly
		(pts
			(xy 82.039968 -93.044518) (xy 81.995518 -93.044772) (xy 81.825338 -93.133672) (xy 81.825338 -93.354652)
			(xy 81.995518 -93.443298) (xy 82.039968 -93.443552)
		)
		(stroke
			(width 0)
			(type solid)
		)
		(fill yes)
		(layer "In2.Cu")
		(net "M_K_DQS_DP<17>")
	)
	(gr_poly
		(pts
			(xy 82.039968 -57.361328) (xy 81.995518 -57.361328) (xy 81.825338 -57.450228) (xy 81.825338 -57.671208)
			(xy 81.995518 -57.760108) (xy 82.039968 -57.760362)
		)
		(stroke
			(width 0)
			(type solid)
		)
		(fill yes)
		(layer "In2.Cu")
		(net "M_G_DQS_DN<8>")
	)
	(gr_poly
		(pts
			(xy 82.22488 -50.50282) (xy 82.256376 -50.471578) (xy 81.968848 -50.18405) (xy 81.937606 -50.215546)
			(xy 81.863946 -50.414936) (xy 82.02549 -50.57648)
		)
		(stroke
			(width 0)
			(type solid)
		)
		(fill yes)
		(layer "In2.Cu")
		(net "M_G_DQS_DN<8>")
	)
	(gr_poly
		(pts
			(xy 82.270346 -59.601862) (xy 82.278474 -59.410092) (xy 82.087212 -59.299602) (xy 81.92516 -59.402472)
			(xy 81.902808 -59.440826) (xy 82.248248 -59.64047)
		)
		(stroke
			(width 0)
			(type solid)
		)
		(fill yes)
		(layer "In2.Cu")
		(net "M_G_ECC<1>")
	)
	(gr_poly
		(pts
			(xy 82.272124 -58.612532) (xy 82.280252 -58.420762) (xy 82.08899 -58.310272) (xy 81.926938 -58.413142)
			(xy 81.904586 -58.45175) (xy 82.250026 -58.65114)
		)
		(stroke
			(width 0)
			(type solid)
		)
		(fill yes)
		(layer "In2.Cu")
		(net "M_G_DQS_DN<17>")
	)
	(gr_poly
		(pts
			(xy 82.279998 -92.383864) (xy 82.27187 -92.192094) (xy 82.249772 -92.153486) (xy 81.904332 -92.35313)
			(xy 81.926684 -92.391484) (xy 82.088736 -92.494354)
		)
		(stroke
			(width 0)
			(type solid)
		)
		(fill yes)
		(layer "In2.Cu")
		(net "M_K_ECC<1>")
	)
	(gr_poly
		(pts
			(xy 82.30997 -51.96713) (xy 82.30997 -51.73853) (xy 82.11693 -51.64963) (xy 82.07248 -51.64963) (xy 82.07248 -52.05603)
			(xy 82.11693 -52.05603)
		)
		(stroke
			(width 0)
			(type solid)
		)
		(fill yes)
		(layer "In2.Cu")
		(net "M_G_DQS_DN<17>")
	)
	(gr_poly
		(pts
			(xy 82.312764 -102.737412) (xy 82.312764 -102.508812) (xy 82.119724 -102.419912) (xy 82.075274 -102.419912)
			(xy 82.075274 -102.826312) (xy 82.119724 -102.826312)
		)
		(stroke
			(width 0)
			(type solid)
		)
		(fill yes)
		(layer "In2.Cu")
		(net "M_K_DQS_DP<8>")
	)
	(gr_poly
		(pts
			(xy 82.367374 -98.783394) (xy 82.367374 -98.554794) (xy 82.174334 -98.465894) (xy 82.129884 -98.465894)
			(xy 82.129884 -98.872294) (xy 82.174334 -98.872294)
		)
		(stroke
			(width 0)
			(type solid)
		)
		(fill yes)
		(layer "In2.Cu")
		(net "M_K_DQS_DN<17>")
	)
	(gr_poly
		(pts
			(xy 82.367374 -97.792794) (xy 82.367374 -97.564194) (xy 82.174334 -97.475294) (xy 82.129884 -97.475294)
			(xy 82.129884 -97.881694) (xy 82.174334 -97.881694)
		)
		(stroke
			(width 0)
			(type solid)
		)
		(fill yes)
		(layer "In2.Cu")
		(net "M_K_DQS_DN<17>")
	)
	(gr_poly
		(pts
			(xy 82.387186 -90.872056) (xy 82.387186 -90.651076) (xy 82.217006 -90.562176) (xy 82.172556 -90.562176)
			(xy 82.172556 -90.960956) (xy 82.217006 -90.960956)
		)
		(stroke
			(width 0)
			(type solid)
		)
		(fill yes)
		(layer "In2.Cu")
		(net "M_K_ECC<0>")
	)
	(gr_poly
		(pts
			(xy 82.422492 -50.305208) (xy 82.496152 -50.106072) (xy 82.334354 -49.944274) (xy 82.135218 -50.017934)
			(xy 82.103722 -50.04943) (xy 82.390996 -50.336704)
		)
		(stroke
			(width 0)
			(type solid)
		)
		(fill yes)
		(layer "In2.Cu")
		(net "M_G_DQS_DP<8>")
	)
	(gr_poly
		(pts
			(xy 82.46745 -55.30215) (xy 82.46745 -55.07355) (xy 82.27441 -54.98465) (xy 82.22996 -54.98465) (xy 82.22996 -55.39105)
			(xy 82.27441 -55.39105)
		)
		(stroke
			(width 0)
			(type solid)
		)
		(fill yes)
		(layer "In2.Cu")
		(net "M_G_DQS_DP<8>")
	)
	(gr_poly
		(pts
			(xy 82.46745 -54.31155) (xy 82.46745 -54.08295) (xy 82.27441 -53.99405) (xy 82.22996 -53.99405) (xy 82.22996 -54.40045)
			(xy 82.27441 -54.40045)
		)
		(stroke
			(width 0)
			(type solid)
		)
		(fill yes)
		(layer "In2.Cu")
		(net "M_G_DQS_DP<8>")
	)
	(gr_poly
		(pts
			(xy 82.47634 -58.216038) (xy 82.498692 -58.177684) (xy 82.153252 -57.97804) (xy 82.131154 -58.016648)
			(xy 82.123026 -58.208418) (xy 82.314288 -58.318908)
		)
		(stroke
			(width 0)
			(type solid)
		)
		(fill yes)
		(layer "In2.Cu")
		(net "M_G_DQS_DN<8>")
	)
	(gr_poly
		(pts
			(xy 82.48015 -59.20867) (xy 82.502502 -59.170062) (xy 82.157062 -58.970672) (xy 82.134964 -59.00928)
			(xy 82.126836 -59.20105) (xy 82.318098 -59.31154)
		)
		(stroke
			(width 0)
			(type solid)
		)
		(fill yes)
		(layer "In2.Cu")
		(net "M_G_DQS_DP<17>")
	)
	(gr_poly
		(pts
			(xy 82.498692 -92.627196) (xy 82.47634 -92.588842) (xy 82.314288 -92.485972) (xy 82.123026 -92.596462)
			(xy 82.131154 -92.788232) (xy 82.153252 -92.82684)
		)
		(stroke
			(width 0)
			(type solid)
		)
		(fill yes)
		(layer "In2.Cu")
		(net "M_K_DQS_DP<17>")
	)
	(gr_poly
		(pts
			(xy 82.57794 -96.816926) (xy 82.57794 -96.595946) (xy 82.40776 -96.507046) (xy 82.36331 -96.507046)
			(xy 82.36331 -96.905826) (xy 82.40776 -96.905826)
		)
		(stroke
			(width 0)
			(type solid)
		)
		(fill yes)
		(layer "In2.Cu")
		(net "M_K_DQS_DN<17>")
	)
	(gr_poly
		(pts
			(xy 82.57794 -95.826326) (xy 82.57794 -95.605346) (xy 82.40776 -95.516446) (xy 82.36331 -95.516446)
			(xy 82.36331 -95.915226) (xy 82.40776 -95.915226)
		)
		(stroke
			(width 0)
			(type solid)
		)
		(fill yes)
		(layer "In2.Cu")
		(net "M_K_DQS_DN<17>")
	)
	(gr_poly
		(pts
			(xy 82.57794 -94.829376) (xy 82.57794 -94.608396) (xy 82.40776 -94.519496) (xy 82.36331 -94.519496)
			(xy 82.36331 -94.918276) (xy 82.40776 -94.918276)
		)
		(stroke
			(width 0)
			(type solid)
		)
		(fill yes)
		(layer "In2.Cu")
		(net "M_K_DQS_DN<17>")
	)
	(gr_poly
		(pts
			(xy 82.57794 -93.83268) (xy 82.57794 -93.6117) (xy 82.40776 -93.5228) (xy 82.36331 -93.5228) (xy 82.36331 -93.92158)
			(xy 82.40776 -93.92158)
		)
		(stroke
			(width 0)
			(type solid)
		)
		(fill yes)
		(layer "In2.Cu")
		(net "M_K_DQS_DN<17>")
	)
	(gr_poly
		(pts
			(xy 82.57794 -57.192926) (xy 82.57794 -56.971946) (xy 82.40776 -56.883046) (xy 82.36331 -56.883046)
			(xy 82.36331 -57.281826) (xy 82.40776 -57.281826)
		)
		(stroke
			(width 0)
			(type solid)
		)
		(fill yes)
		(layer "In2.Cu")
		(net "M_G_DQS_DP<8>")
	)
	(gr_poly
		(pts
			(xy 82.57794 -56.202326) (xy 82.57794 -55.981346) (xy 82.40776 -55.892446) (xy 82.36331 -55.892446)
			(xy 82.36331 -56.291226) (xy 82.40776 -56.291226)
		)
		(stroke
			(width 0)
			(type solid)
		)
		(fill yes)
		(layer "In2.Cu")
		(net "M_G_DQS_DP<8>")
	)
	(gr_poly
		(pts
			(xy 82.706464 -100.342954) (xy 82.674968 -100.311458) (xy 82.475578 -100.237798) (xy 82.31378 -100.399596)
			(xy 82.38744 -100.598986) (xy 82.418936 -100.630228)
		)
		(stroke
			(width 0)
			(type solid)
		)
		(fill yes)
		(layer "In2.Cu")
		(net "M_K_DQS_DN<8>")
	)
	(gr_poly
		(pts
			(xy 82.750152 -51.863244) (xy 82.705702 -51.863244) (xy 82.512662 -51.952144) (xy 82.512662 -52.180744)
			(xy 82.705702 -52.269644) (xy 82.750152 -52.269644)
		)
		(stroke
			(width 0)
			(type solid)
		)
		(fill yes)
		(layer "In2.Cu")
		(net "M_G_DQS_DN<8>")
	)
	(gr_poly
		(pts
			(xy 82.778346 -52.982622) (xy 82.704686 -52.783486) (xy 82.67319 -52.75199) (xy 82.385916 -53.039264)
			(xy 82.417412 -53.07076) (xy 82.616548 -53.14442)
		)
		(stroke
			(width 0)
			(type solid)
		)
		(fill yes)
		(layer "In2.Cu")
		(net "M_G_DQS_DP<8>")
	)
	(gr_poly
		(pts
			(xy 82.898234 -95.516192) (xy 82.853784 -95.516192) (xy 82.683604 -95.605092) (xy 82.683604 -95.826072)
			(xy 82.853784 -95.914972) (xy 82.898234 -95.914972)
		)
		(stroke
			(width 0)
			(type solid)
		)
		(fill yes)
		(layer "In2.Cu")
		(net "M_K_DQS_DN<8>")
	)
	(gr_poly
		(pts
			(xy 82.898234 -94.519496) (xy 82.853784 -94.519496) (xy 82.683604 -94.608396) (xy 82.683604 -94.829376)
			(xy 82.853784 -94.918276) (xy 82.898234 -94.918276)
		)
		(stroke
			(width 0)
			(type solid)
		)
		(fill yes)
		(layer "In2.Cu")
		(net "M_K_DQS_DN<8>")
	)
	(gr_poly
		(pts
			(xy 82.898234 -93.52915) (xy 82.853784 -93.529404) (xy 82.683604 -93.618304) (xy 82.68335 -93.83903)
			(xy 82.85353 -93.928184) (xy 82.898234 -93.928184)
		)
		(stroke
			(width 0)
			(type solid)
		)
		(fill yes)
		(layer "In2.Cu")
		(net "M_K_DQS_DN<8>")
	)
	(gr_poly
		(pts
			(xy 82.898234 -91.554046) (xy 82.853784 -91.554046) (xy 82.683604 -91.642946) (xy 82.683604 -91.863926)
			(xy 82.853784 -91.952826) (xy 82.898234 -91.952826)
		)
		(stroke
			(width 0)
			(type solid)
		)
		(fill yes)
		(layer "In2.Cu")
		(net "M_K_DQS_DP<17>")
	)
	(gr_poly
		(pts
			(xy 82.898234 -90.563446) (xy 82.853784 -90.563446) (xy 82.683604 -90.652346) (xy 82.683604 -90.873326)
			(xy 82.853784 -90.962226) (xy 82.898234 -90.962226)
		)
		(stroke
			(width 0)
			(type solid)
		)
		(fill yes)
		(layer "In2.Cu")
		(net "M_K_DQS_DP<17>")
	)
	(gr_poly
		(pts
			(xy 82.898234 -89.572846) (xy 82.853784 -89.572846) (xy 82.683604 -89.661746) (xy 82.683604 -89.882726)
			(xy 82.853784 -89.971626) (xy 82.898234 -89.971626)
		)
		(stroke
			(width 0)
			(type solid)
		)
		(fill yes)
		(layer "In2.Cu")
		(net "M_K_DQS_DP<17>")
	)
	(gr_poly
		(pts
			(xy 82.898234 -56.876442) (xy 82.85353 -56.876696) (xy 82.683604 -56.965596) (xy 82.683604 -57.186322)
			(xy 82.853784 -57.275222) (xy 82.898234 -57.275476)
		)
		(stroke
			(width 0)
			(type solid)
		)
		(fill yes)
		(layer "In2.Cu")
		(net "M_G_ECC<6>")
	)
	(gr_poly
		(pts
			(xy 82.898234 -55.892446) (xy 82.853784 -55.892446) (xy 82.683604 -55.981346) (xy 82.683604 -56.202326)
			(xy 82.853784 -56.291226) (xy 82.898234 -56.291226)
		)
		(stroke
			(width 0)
			(type solid)
		)
		(fill yes)
		(layer "In2.Cu")
		(net "M_G_ECC<6>")
	)
	(gr_poly
		(pts
			(xy 82.94624 -100.708714) (xy 82.87258 -100.509324) (xy 82.841084 -100.477828) (xy 82.55381 -100.765102)
			(xy 82.585052 -100.796598) (xy 82.784442 -100.870258)
		)
		(stroke
			(width 0)
			(type solid)
		)
		(fill yes)
		(layer "In2.Cu")
		(net "M_K_DQS_DP<8>")
	)
	(gr_poly
		(pts
			(xy 83.043268 -99.42957) (xy 82.998818 -99.42957) (xy 82.805778 -99.51847) (xy 82.805778 -99.74707)
			(xy 82.998818 -99.83597) (xy 83.043268 -99.83597)
		)
		(stroke
			(width 0)
			(type solid)
		)
		(fill yes)
		(layer "In2.Cu")
		(net "M_K_DQS_DN<8>")
	)
	(gr_poly
		(pts
			(xy 83.043268 -98.43897) (xy 82.998818 -98.43897) (xy 82.805778 -98.52787) (xy 82.805778 -98.75647)
			(xy 82.998818 -98.84537) (xy 83.043268 -98.84537)
		)
		(stroke
			(width 0)
			(type solid)
		)
		(fill yes)
		(layer "In2.Cu")
		(net "M_K_DQS_DN<8>")
	)
	(gr_poly
		(pts
			(xy 83.043268 -97.44837) (xy 82.998818 -97.44837) (xy 82.805778 -97.53727) (xy 82.805778 -97.76587)
			(xy 82.998818 -97.85477) (xy 83.043268 -97.85477)
		)
		(stroke
			(width 0)
			(type solid)
		)
		(fill yes)
		(layer "In2.Cu")
		(net "M_K_DQS_DN<8>")
	)
	(gr_poly
		(pts
			(xy 83.043268 -96.45777) (xy 82.998818 -96.45777) (xy 82.805778 -96.54667) (xy 82.805778 -96.77527)
			(xy 82.998818 -96.86417) (xy 83.043268 -96.86417)
		)
		(stroke
			(width 0)
			(type solid)
		)
		(fill yes)
		(layer "In2.Cu")
		(net "M_K_DQS_DN<8>")
	)
	(gr_poly
		(pts
			(xy 83.060794 -50.058574) (xy 83.09229 -50.027332) (xy 82.804762 -49.739804) (xy 82.77352 -49.7713)
			(xy 82.69986 -49.97069) (xy 82.861404 -50.132234)
		)
		(stroke
			(width 0)
			(type solid)
		)
		(fill yes)
		(layer "In2.Cu")
		(net "M_G_ECC<6>")
	)
	(gr_poly
		(pts
			(xy 83.06562 -102.01402) (xy 83.02117 -102.01402) (xy 82.82813 -102.10292) (xy 82.82813 -102.33152)
			(xy 83.02117 -102.42042) (xy 83.06562 -102.42042)
		)
		(stroke
			(width 0)
			(type solid)
		)
		(fill yes)
		(layer "In2.Cu")
		(net "M_K_ECC<6>")
	)
	(gr_poly
		(pts
			(xy 83.128866 -59.10707) (xy 83.136994 -58.9153) (xy 82.945732 -58.80481) (xy 82.78368 -58.90768)
			(xy 82.761328 -58.946034) (xy 83.106768 -59.145678)
		)
		(stroke
			(width 0)
			(type solid)
		)
		(fill yes)
		(layer "In2.Cu")
		(net "M_G_DQS_DN<17>")
	)
	(gr_poly
		(pts
			(xy 83.128866 -58.116216) (xy 83.136994 -57.924446) (xy 82.945732 -57.813956) (xy 82.78368 -57.916826)
			(xy 82.761328 -57.955434) (xy 83.106768 -58.154824)
		)
		(stroke
			(width 0)
			(type solid)
		)
		(fill yes)
		(layer "In2.Cu")
		(net "M_G_DQS_DP<8>")
	)
	(gr_poly
		(pts
			(xy 83.13674 -92.880688) (xy 83.128612 -92.688664) (xy 83.106514 -92.650056) (xy 82.761328 -92.8497)
			(xy 82.783426 -92.888054) (xy 82.945478 -92.990924)
		)
		(stroke
			(width 0)
			(type solid)
		)
		(fill yes)
		(layer "In2.Cu")
		(net "M_K_DQS_DN<17>")
	)
	(gr_poly
		(pts
			(xy 83.171792 -54.703218) (xy 83.127342 -54.703218) (xy 82.934302 -54.792118) (xy 82.934302 -55.020718)
			(xy 83.127342 -55.109618) (xy 83.171792 -55.109618)
		)
		(stroke
			(width 0)
			(type solid)
		)
		(fill yes)
		(layer "In2.Cu")
		(net "M_G_ECC<6>")
	)
	(gr_poly
		(pts
			(xy 83.178142 -52.180744) (xy 83.178142 -51.952144) (xy 82.985102 -51.863244) (xy 82.940652 -51.863244)
			(xy 82.940652 -52.269644) (xy 82.985102 -52.269644)
		)
		(stroke
			(width 0)
			(type solid)
		)
		(fill yes)
		(layer "In2.Cu")
		(net "M_G_DQS_DP<8>")
	)
	(gr_poly
		(pts
			(xy 83.258406 -49.860962) (xy 83.332066 -49.661826) (xy 83.170268 -49.500028) (xy 82.971132 -49.573688)
			(xy 82.939636 -49.605184) (xy 83.22691 -49.892458)
		)
		(stroke
			(width 0)
			(type solid)
		)
		(fill yes)
		(layer "In2.Cu")
		(net "M_G_ECC<7>")
	)
	(gr_poly
		(pts
			(xy 83.336384 -58.7121) (xy 83.358736 -58.673746) (xy 83.013296 -58.474102) (xy 82.991198 -58.51271)
			(xy 82.98307 -58.70448) (xy 83.174332 -58.81497)
		)
		(stroke
			(width 0)
			(type solid)
		)
		(fill yes)
		(layer "In2.Cu")
		(net "M_G_DQS_DN<8>")
	)
	(gr_poly
		(pts
			(xy 83.344004 -57.726072) (xy 83.366356 -57.687718) (xy 83.020916 -57.488074) (xy 82.998564 -57.526936)
			(xy 82.99069 -57.718706) (xy 83.181952 -57.828942)
		)
		(stroke
			(width 0)
			(type solid)
		)
		(fill yes)
		(layer "In2.Cu")
		(net "M_G_ECC<6>")
	)
	(gr_poly
		(pts
			(xy 83.366356 -93.116908) (xy 83.344004 -93.078554) (xy 83.181952 -92.975684) (xy 82.99069 -93.08592)
			(xy 82.998564 -93.27769) (xy 83.020916 -93.316552)
		)
		(stroke
			(width 0)
			(type solid)
		)
		(fill yes)
		(layer "In2.Cu")
		(net "M_K_DQS_DN<8>")
	)
	(gr_poly
		(pts
			(xy 83.38058 -61.41593) (xy 83.358228 -61.377576) (xy 83.196176 -61.274706) (xy 83.004914 -61.385196)
			(xy 83.013042 -61.576966) (xy 83.03514 -61.61532)
		)
		(stroke
			(width 0)
			(type solid)
		)
		(fill yes)
		(layer "In2.Cu")
		(net "M_G_DQS_DN<8>")
	)
	(gr_poly
		(pts
			(xy 83.436206 -92.34424) (xy 83.436206 -92.123514) (xy 83.266026 -92.034614) (xy 83.221576 -92.03436)
			(xy 83.22183 -92.43314) (xy 83.266026 -92.43314)
		)
		(stroke
			(width 0)
			(type solid)
		)
		(fill yes)
		(layer "In2.Cu")
		(net "M_K_DQS_DN<17>")
	)
	(gr_poly
		(pts
			(xy 83.43646 -95.31858) (xy 83.43646 -95.0976) (xy 83.26628 -95.0087) (xy 83.22183 -95.0087) (xy 83.22183 -95.40748)
			(xy 83.26628 -95.40748)
		)
		(stroke
			(width 0)
			(type solid)
		)
		(fill yes)
		(layer "In2.Cu")
		(net "M_K_DQS_DP<8>")
	)
	(gr_poly
		(pts
			(xy 83.43646 -94.340426) (xy 83.43646 -94.119446) (xy 83.26628 -94.030546) (xy 83.22183 -94.030546)
			(xy 83.22183 -94.429326) (xy 83.26628 -94.429326)
		)
		(stroke
			(width 0)
			(type solid)
		)
		(fill yes)
		(layer "In2.Cu")
		(net "M_K_DQS_DP<8>")
	)
	(gr_poly
		(pts
			(xy 83.43646 -91.35618) (xy 83.43646 -91.1352) (xy 83.26628 -91.0463) (xy 83.22183 -91.0463) (xy 83.22183 -91.44508)
			(xy 83.26628 -91.44508)
		)
		(stroke
			(width 0)
			(type solid)
		)
		(fill yes)
		(layer "In2.Cu")
		(net "M_K_DQS_DN<17>")
	)
	(gr_poly
		(pts
			(xy 83.43646 -90.36558) (xy 83.43646 -90.1446) (xy 83.26628 -90.0557) (xy 83.22183 -90.0557) (xy 83.22183 -90.45448)
			(xy 83.26628 -90.45448)
		)
		(stroke
			(width 0)
			(type solid)
		)
		(fill yes)
		(layer "In2.Cu")
		(net "M_K_DQS_DN<17>")
	)
	(gr_poly
		(pts
			(xy 83.43646 -56.68518) (xy 83.43646 -56.4642) (xy 83.26628 -56.3753) (xy 83.22183 -56.3753) (xy 83.22183 -56.77408)
			(xy 83.26628 -56.77408)
		)
		(stroke
			(width 0)
			(type solid)
		)
		(fill yes)
		(layer "In2.Cu")
		(net "M_G_ECC<7>")
	)
	(gr_poly
		(pts
			(xy 83.466432 -53.307234) (xy 83.421982 -53.307234) (xy 83.228942 -53.396134) (xy 83.228942 -53.624734)
			(xy 83.421982 -53.713634) (xy 83.466432 -53.713634)
		)
		(stroke
			(width 0)
			(type solid)
		)
		(fill yes)
		(layer "In2.Cu")
		(net "M_G_ECC<6>")
	)
	(gr_poly
		(pts
			(xy 83.466432 -52.316634) (xy 83.421982 -52.316634) (xy 83.228942 -52.405534) (xy 83.228942 -52.634134)
			(xy 83.421982 -52.723034) (xy 83.466432 -52.723034)
		)
		(stroke
			(width 0)
			(type solid)
		)
		(fill yes)
		(layer "In2.Cu")
		(net "M_G_ECC<6>")
	)
	(gr_poly
		(pts
			(xy 83.466432 -51.326034) (xy 83.421982 -51.326034) (xy 83.228942 -51.414934) (xy 83.228942 -51.643534)
			(xy 83.421982 -51.732434) (xy 83.466432 -51.732434)
		)
		(stroke
			(width 0)
			(type solid)
		)
		(fill yes)
		(layer "In2.Cu")
		(net "M_G_ECC<6>")
	)
	(gr_poly
		(pts
			(xy 83.471258 -99.74707) (xy 83.471258 -99.51847) (xy 83.278218 -99.42957) (xy 83.233768 -99.42957)
			(xy 83.233768 -99.83597) (xy 83.278218 -99.83597)
		)
		(stroke
			(width 0)
			(type solid)
		)
		(fill yes)
		(layer "In2.Cu")
		(net "M_K_DQS_DP<8>")
	)
	(gr_poly
		(pts
			(xy 83.471258 -98.75647) (xy 83.471258 -98.52787) (xy 83.278218 -98.43897) (xy 83.233768 -98.43897)
			(xy 83.233768 -98.84537) (xy 83.278218 -98.84537)
		)
		(stroke
			(width 0)
			(type solid)
		)
		(fill yes)
		(layer "In2.Cu")
		(net "M_K_DQS_DP<8>")
	)
	(gr_poly
		(pts
			(xy 83.471258 -97.76587) (xy 83.471258 -97.53727) (xy 83.278218 -97.44837) (xy 83.233768 -97.44837)
			(xy 83.233768 -97.85477) (xy 83.278218 -97.85477)
		)
		(stroke
			(width 0)
			(type solid)
		)
		(fill yes)
		(layer "In2.Cu")
		(net "M_K_DQS_DP<8>")
	)
	(gr_poly
		(pts
			(xy 83.471258 -96.77527) (xy 83.471258 -96.54667) (xy 83.278218 -96.45777) (xy 83.233768 -96.45777)
			(xy 83.233768 -96.86417) (xy 83.278218 -96.86417)
		)
		(stroke
			(width 0)
			(type solid)
		)
		(fill yes)
		(layer "In2.Cu")
		(net "M_K_DQS_DP<8>")
	)
	(gr_poly
		(pts
			(xy 83.493102 -102.33152) (xy 83.493102 -102.10292) (xy 83.300062 -102.01402) (xy 83.255612 -102.01402)
			(xy 83.255612 -102.42042) (xy 83.300062 -102.42042)
		)
		(stroke
			(width 0)
			(type solid)
		)
		(fill yes)
		(layer "In2.Cu")
		(net "M_K_ECC<7>")
	)
	(gr_poly
		(pts
			(xy 83.599782 -55.198518) (xy 83.599782 -54.969918) (xy 83.406742 -54.881018) (xy 83.362292 -54.881018)
			(xy 83.362292 -55.287418) (xy 83.406742 -55.287418)
		)
		(stroke
			(width 0)
			(type solid)
		)
		(fill yes)
		(layer "In2.Cu")
		(net "M_G_ECC<7>")
	)
	(gr_poly
		(pts
			(xy 83.60537 -100.848922) (xy 83.573874 -100.817426) (xy 83.374738 -100.743766) (xy 83.21294 -100.90531)
			(xy 83.2866 -101.1047) (xy 83.318096 -101.136196)
		)
		(stroke
			(width 0)
			(type solid)
		)
		(fill yes)
		(layer "In2.Cu")
		(net "M_K_ECC<6>")
	)
	(gr_poly
		(pts
			(xy 83.756754 -95.0087) (xy 83.712304 -95.0087) (xy 83.542124 -95.0976) (xy 83.542124 -95.31858)
			(xy 83.712304 -95.40748) (xy 83.756754 -95.40748)
		)
		(stroke
			(width 0)
			(type solid)
		)
		(fill yes)
		(layer "In2.Cu")
		(net "M_K_ECC<6>")
	)
	(gr_poly
		(pts
			(xy 83.756754 -94.033086) (xy 83.712558 -94.033086) (xy 83.542378 -94.121986) (xy 83.542378 -94.342712)
			(xy 83.712304 -94.431612) (xy 83.757008 -94.431866)
		)
		(stroke
			(width 0)
			(type solid)
		)
		(fill yes)
		(layer "In2.Cu")
		(net "M_K_ECC<6>")
	)
	(gr_poly
		(pts
			(xy 83.756754 -60.3377) (xy 83.712304 -60.3377) (xy 83.542124 -60.4266) (xy 83.542124 -60.64758)
			(xy 83.712304 -60.73648) (xy 83.756754 -60.73648)
		)
		(stroke
			(width 0)
			(type solid)
		)
		(fill yes)
		(layer "In2.Cu")
		(net "M_G_DQS_DN<8>")
	)
	(gr_poly
		(pts
			(xy 83.756754 -59.3471) (xy 83.712304 -59.3471) (xy 83.542124 -59.436) (xy 83.542124 -59.65698) (xy 83.712304 -59.74588)
			(xy 83.756754 -59.74588)
		)
		(stroke
			(width 0)
			(type solid)
		)
		(fill yes)
		(layer "In2.Cu")
		(net "M_G_DQS_DN<8>")
	)
	(gr_poly
		(pts
			(xy 83.757008 -56.37276) (xy 83.712558 -56.373014) (xy 83.542378 -56.461914) (xy 83.542378 -56.68264)
			(xy 83.712558 -56.77154) (xy 83.756754 -56.77154)
		)
		(stroke
			(width 0)
			(type solid)
		)
		(fill yes)
		(layer "In2.Cu")
		(net "M_G_ECC<2>")
	)
	(gr_poly
		(pts
			(xy 83.757008 -55.39105) (xy 83.712558 -55.39105) (xy 83.542378 -55.47995) (xy 83.542378 -55.70093)
			(xy 83.712558 -55.78983) (xy 83.757008 -55.78983)
		)
		(stroke
			(width 0)
			(type solid)
		)
		(fill yes)
		(layer "In2.Cu")
		(net "M_G_ECC<2>")
	)
	(gr_poly
		(pts
			(xy 83.81492 -99.873816) (xy 83.77047 -99.873816) (xy 83.57743 -99.962716) (xy 83.57743 -100.191316)
			(xy 83.77047 -100.280216) (xy 83.81492 -100.280216)
		)
		(stroke
			(width 0)
			(type solid)
		)
		(fill yes)
		(layer "In2.Cu")
		(net "M_K_ECC<6>")
	)
	(gr_poly
		(pts
			(xy 83.81492 -98.883216) (xy 83.77047 -98.883216) (xy 83.57743 -98.972116) (xy 83.57743 -99.200716)
			(xy 83.77047 -99.289616) (xy 83.81492 -99.289616)
		)
		(stroke
			(width 0)
			(type solid)
		)
		(fill yes)
		(layer "In2.Cu")
		(net "M_K_ECC<6>")
	)
	(gr_poly
		(pts
			(xy 83.81492 -97.892616) (xy 83.77047 -97.892616) (xy 83.57743 -97.981516) (xy 83.57743 -98.210116)
			(xy 83.77047 -98.299016) (xy 83.81492 -98.299016)
		)
		(stroke
			(width 0)
			(type solid)
		)
		(fill yes)
		(layer "In2.Cu")
		(net "M_K_ECC<6>")
	)
	(gr_poly
		(pts
			(xy 83.81492 -96.902016) (xy 83.77047 -96.902016) (xy 83.57743 -96.990916) (xy 83.57743 -97.219516)
			(xy 83.77047 -97.308416) (xy 83.81492 -97.308416)
		)
		(stroke
			(width 0)
			(type solid)
		)
		(fill yes)
		(layer "In2.Cu")
		(net "M_K_ECC<6>")
	)
	(gr_poly
		(pts
			(xy 83.844892 -101.21392) (xy 83.771232 -101.01453) (xy 83.739736 -100.983288) (xy 83.452462 -101.270562)
			(xy 83.483704 -101.302058) (xy 83.683094 -101.375718)
		)
		(stroke
			(width 0)
			(type solid)
		)
		(fill yes)
		(layer "In2.Cu")
		(net "M_K_ECC<7>")
	)
	(gr_poly
		(pts
			(xy 83.893914 -53.624734) (xy 83.893914 -53.396134) (xy 83.700874 -53.307234) (xy 83.656424 -53.307234)
			(xy 83.656424 -53.713634) (xy 83.700874 -53.713634)
		)
		(stroke
			(width 0)
			(type solid)
		)
		(fill yes)
		(layer "In2.Cu")
		(net "M_G_ECC<7>")
	)
	(gr_poly
		(pts
			(xy 83.893914 -52.634134) (xy 83.893914 -52.405534) (xy 83.700874 -52.316634) (xy 83.656424 -52.316634)
			(xy 83.656424 -52.723034) (xy 83.700874 -52.723034)
		)
		(stroke
			(width 0)
			(type solid)
		)
		(fill yes)
		(layer "In2.Cu")
		(net "M_G_ECC<7>")
	)
	(gr_poly
		(pts
			(xy 83.893914 -51.745134) (xy 83.893914 -51.516534) (xy 83.700874 -51.427634) (xy 83.656424 -51.427634)
			(xy 83.656424 -51.834034) (xy 83.700874 -51.834034)
		)
		(stroke
			(width 0)
			(type solid)
		)
		(fill yes)
		(layer "In2.Cu")
		(net "M_G_ECC<7>")
	)
	(gr_poly
		(pts
			(xy 83.951318 -90.474546) (xy 83.95208 -90.07602) (xy 83.90763 -90.07602) (xy 83.737196 -90.164412)
			(xy 83.736688 -90.385392) (xy 83.906614 -90.4748)
		)
		(stroke
			(width 0)
			(type solid)
		)
		(fill yes)
		(layer "In2.Cu")
		(net "M_K_ECC<6>")
	)
	(gr_poly
		(pts
			(xy 83.956144 -49.71288) (xy 83.911694 -49.71288) (xy 83.718654 -49.80178) (xy 83.718654 -50.03038)
			(xy 83.911694 -50.11928) (xy 83.956144 -50.11928)
		)
		(stroke
			(width 0)
			(type solid)
		)
		(fill yes)
		(layer "In2.Cu")
		(net "M_G_ECC<2>")
	)
	(gr_poly
		(pts
			(xy 83.9851 -57.619646) (xy 83.993228 -57.427876) (xy 83.801966 -57.317386) (xy 83.639914 -57.420256)
			(xy 83.617562 -57.45861) (xy 83.963002 -57.658254)
		)
		(stroke
			(width 0)
			(type solid)
		)
		(fill yes)
		(layer "In2.Cu")
		(net "M_G_ECC<7>")
	)
	(gr_poly
		(pts
			(xy 83.987894 -93.380306) (xy 83.979766 -93.188536) (xy 83.957668 -93.149674) (xy 83.612228 -93.349318)
			(xy 83.63458 -93.387672) (xy 83.796632 -93.490542)
		)
		(stroke
			(width 0)
			(type solid)
		)
		(fill yes)
		(layer "In2.Cu")
		(net "M_K_DQS_DP<8>")
	)
	(gr_poly
		(pts
			(xy 83.98891 -58.612278) (xy 83.997038 -58.420508) (xy 83.805776 -58.310018) (xy 83.643724 -58.412888)
			(xy 83.621626 -58.451242) (xy 83.967066 -58.650632)
		)
		(stroke
			(width 0)
			(type solid)
		)
		(fill yes)
		(layer "In2.Cu")
		(net "M_G_DQS_DP<8>")
	)
	(gr_poly
		(pts
			(xy 84.1248 -92.936822) (xy 84.29498 -92.847922) (xy 84.29498 -92.627196) (xy 84.125054 -92.538296)
			(xy 84.08035 -92.538042) (xy 84.08035 -92.937076)
		)
		(stroke
			(width 0)
			(type solid)
		)
		(fill yes)
		(layer "In2.Cu")
		(net "M_K_DQS_DP<8>")
	)
	(gr_poly
		(pts
			(xy 84.1248 -61.233304) (xy 84.294726 -61.144404) (xy 84.29498 -60.923678) (xy 84.1248 -60.834778)
			(xy 84.080096 -60.834524) (xy 84.080096 -61.233558)
		)
		(stroke
			(width 0)
			(type solid)
		)
		(fill yes)
		(layer "In2.Cu")
		(net "M_G_DQS_DP<8>")
	)
	(gr_poly
		(pts
			(xy 84.19338 -58.216038) (xy 84.215732 -58.17743) (xy 83.870292 -57.978294) (xy 83.848194 -58.016648)
			(xy 83.840066 -58.208418) (xy 84.031328 -58.318908)
		)
		(stroke
			(width 0)
			(type solid)
		)
		(fill yes)
		(layer "In2.Cu")
		(net "M_G_ECC<6>")
	)
	(gr_poly
		(pts
			(xy 84.195158 -57.226454) (xy 84.217256 -57.1881) (xy 83.87207 -56.988456) (xy 83.849972 -57.027318)
			(xy 83.841844 -57.219088) (xy 84.033106 -57.329324)
		)
		(stroke
			(width 0)
			(type solid)
		)
		(fill yes)
		(layer "In2.Cu")
		(net "M_G_ECC<2>")
	)
	(gr_poly
		(pts
			(xy 84.217256 -93.616526) (xy 84.195158 -93.578172) (xy 84.033106 -93.475302) (xy 83.841844 -93.585538)
			(xy 83.849972 -93.777308) (xy 83.87207 -93.81617)
		)
		(stroke
			(width 0)
			(type solid)
		)
		(fill yes)
		(layer "In2.Cu")
		(net "M_K_ECC<6>")
	)
	(gr_poly
		(pts
			(xy 84.233004 -53.92928) (xy 84.188554 -53.92928) (xy 83.995514 -54.01818) (xy 83.995514 -54.24678)
			(xy 84.188554 -54.33568) (xy 84.233004 -54.33568)
		)
		(stroke
			(width 0)
			(type solid)
		)
		(fill yes)
		(layer "In2.Cu")
		(net "M_G_ECC<2>")
	)
	(gr_poly
		(pts
			(xy 84.233004 -52.93868) (xy 84.188554 -52.93868) (xy 83.995514 -53.02758) (xy 83.995514 -53.25618)
			(xy 84.188554 -53.34508) (xy 84.233004 -53.34508)
		)
		(stroke
			(width 0)
			(type solid)
		)
		(fill yes)
		(layer "In2.Cu")
		(net "M_G_ECC<2>")
	)
	(gr_poly
		(pts
			(xy 84.233004 -51.94808) (xy 84.188554 -51.94808) (xy 83.995514 -52.03698) (xy 83.995514 -52.26558)
			(xy 84.188554 -52.35448) (xy 84.233004 -52.35448)
		)
		(stroke
			(width 0)
			(type solid)
		)
		(fill yes)
		(layer "In2.Cu")
		(net "M_G_ECC<2>")
	)
	(gr_poly
		(pts
			(xy 84.242402 -100.191316) (xy 84.242402 -99.962716) (xy 84.049362 -99.873816) (xy 84.004912 -99.873816)
			(xy 84.004912 -100.280216) (xy 84.049362 -100.280216)
		)
		(stroke
			(width 0)
			(type solid)
		)
		(fill yes)
		(layer "In2.Cu")
		(net "M_K_ECC<7>")
	)
	(gr_poly
		(pts
			(xy 84.242402 -99.200716) (xy 84.242402 -98.972116) (xy 84.049362 -98.883216) (xy 84.004912 -98.883216)
			(xy 84.004912 -99.289616) (xy 84.049362 -99.289616)
		)
		(stroke
			(width 0)
			(type solid)
		)
		(fill yes)
		(layer "In2.Cu")
		(net "M_K_ECC<7>")
	)
	(gr_poly
		(pts
			(xy 84.242402 -98.210116) (xy 84.242402 -97.981516) (xy 84.049362 -97.892616) (xy 84.004912 -97.892616)
			(xy 84.004912 -98.299016) (xy 84.049362 -98.299016)
		)
		(stroke
			(width 0)
			(type solid)
		)
		(fill yes)
		(layer "In2.Cu")
		(net "M_K_ECC<7>")
	)
	(gr_poly
		(pts
			(xy 84.242402 -97.219516) (xy 84.242402 -96.990916) (xy 84.049362 -96.902016) (xy 84.004912 -96.902016)
			(xy 84.004912 -97.308416) (xy 84.049362 -97.308416)
		)
		(stroke
			(width 0)
			(type solid)
		)
		(fill yes)
		(layer "In2.Cu")
		(net "M_K_ECC<7>")
	)
	(gr_poly
		(pts
			(xy 84.294726 -59.178698) (xy 84.294726 -58.957718) (xy 84.124546 -58.868818) (xy 84.08035 -58.868818)
			(xy 84.08035 -59.267598) (xy 84.124546 -59.267598)
		)
		(stroke
			(width 0)
			(type solid)
		)
		(fill yes)
		(layer "In2.Cu")
		(net "M_G_DQS_DP<8>")
	)
	(gr_poly
		(pts
			(xy 84.29498 -95.826326) (xy 84.29498 -95.605346) (xy 84.1248 -95.516446) (xy 84.08035 -95.516446)
			(xy 84.08035 -95.915226) (xy 84.1248 -95.915226)
		)
		(stroke
			(width 0)
			(type solid)
		)
		(fill yes)
		(layer "In2.Cu")
		(net "M_K_ECC<7>")
	)
	(gr_poly
		(pts
			(xy 84.29498 -94.829376) (xy 84.29498 -94.608396) (xy 84.1248 -94.519496) (xy 84.08035 -94.519496)
			(xy 84.08035 -94.918276) (xy 84.1248 -94.918276)
		)
		(stroke
			(width 0)
			(type solid)
		)
		(fill yes)
		(layer "In2.Cu")
		(net "M_K_ECC<7>")
	)
	(gr_poly
		(pts
			(xy 84.29498 -60.164726) (xy 84.29498 -59.943746) (xy 84.1248 -59.854846) (xy 84.08035 -59.854846)
			(xy 84.08035 -60.253626) (xy 84.1248 -60.253626)
		)
		(stroke
			(width 0)
			(type solid)
		)
		(fill yes)
		(layer "In2.Cu")
		(net "M_G_DQS_DP<8>")
	)
	(gr_poly
		(pts
			(xy 84.29498 -56.202326) (xy 84.29498 -55.981346) (xy 84.1248 -55.892446) (xy 84.08035 -55.892446)
			(xy 84.08035 -56.291226) (xy 84.1248 -56.291226)
		)
		(stroke
			(width 0)
			(type solid)
		)
		(fill yes)
		(layer "In2.Cu")
		(net "M_G_ECC<3>")
	)
	(gr_poly
		(pts
			(xy 84.340192 -102.316026) (xy 84.295742 -102.316026) (xy 84.102702 -102.404926) (xy 84.102702 -102.633526)
			(xy 84.295742 -102.722426) (xy 84.340192 -102.722426)
		)
		(stroke
			(width 0)
			(type solid)
		)
		(fill yes)
		(layer "In2.Cu")
		(net "M_K_ECC<2>")
	)
	(gr_poly
		(pts
			(xy 84.384134 -50.03038) (xy 84.384134 -49.80178) (xy 84.191094 -49.71288) (xy 84.146644 -49.71288)
			(xy 84.146644 -50.11928) (xy 84.191094 -50.11928)
		)
		(stroke
			(width 0)
			(type solid)
		)
		(fill yes)
		(layer "In2.Cu")
		(net "M_G_ECC<3>")
	)
	(gr_poly
		(pts
			(xy 84.60232 -100.938076) (xy 84.55787 -100.938076) (xy 84.36483 -101.026976) (xy 84.36483 -101.255576)
			(xy 84.55787 -101.344476) (xy 84.60232 -101.344476)
		)
		(stroke
			(width 0)
			(type solid)
		)
		(fill yes)
		(layer "In2.Cu")
		(net "M_K_ECC<2>")
	)
	(gr_poly
		(pts
			(xy 84.60232 -99.947476) (xy 84.55787 -99.947476) (xy 84.36483 -100.036376) (xy 84.36483 -100.264976)
			(xy 84.55787 -100.353876) (xy 84.60232 -100.353876)
		)
		(stroke
			(width 0)
			(type solid)
		)
		(fill yes)
		(layer "In2.Cu")
		(net "M_K_ECC<2>")
	)
	(gr_poly
		(pts
			(xy 84.60232 -98.956876) (xy 84.55787 -98.956876) (xy 84.36483 -99.045776) (xy 84.36483 -99.274376)
			(xy 84.55787 -99.363276) (xy 84.60232 -99.363276)
		)
		(stroke
			(width 0)
			(type solid)
		)
		(fill yes)
		(layer "In2.Cu")
		(net "M_K_ECC<2>")
	)
	(gr_poly
		(pts
			(xy 84.60232 -97.966276) (xy 84.55787 -97.966276) (xy 84.36483 -98.055176) (xy 84.36483 -98.283776)
			(xy 84.55787 -98.372676) (xy 84.60232 -98.372676)
		)
		(stroke
			(width 0)
			(type solid)
		)
		(fill yes)
		(layer "In2.Cu")
		(net "M_K_ECC<2>")
	)
	(gr_poly
		(pts
			(xy 84.60232 -96.975676) (xy 84.55787 -96.975676) (xy 84.36483 -97.064576) (xy 84.36483 -97.293176)
			(xy 84.55787 -97.382076) (xy 84.60232 -97.382076)
		)
		(stroke
			(width 0)
			(type solid)
		)
		(fill yes)
		(layer "In2.Cu")
		(net "M_K_ECC<2>")
	)
	(gr_poly
		(pts
			(xy 84.615274 -95.516446) (xy 84.570824 -95.516446) (xy 84.400644 -95.605346) (xy 84.400644 -95.826326)
			(xy 84.570824 -95.915226) (xy 84.615274 -95.915226)
		)
		(stroke
			(width 0)
			(type solid)
		)
		(fill yes)
		(layer "In2.Cu")
		(net "M_K_ECC<2>")
	)
	(gr_poly
		(pts
			(xy 84.615274 -94.530418) (xy 84.571078 -94.530418) (xy 84.400898 -94.619318) (xy 84.400898 -94.840298)
			(xy 84.571078 -94.928944) (xy 84.615274 -94.929198)
		)
		(stroke
			(width 0)
			(type solid)
		)
		(fill yes)
		(layer "In2.Cu")
		(net "M_K_ECC<2>")
	)
	(gr_poly
		(pts
			(xy 84.615274 -92.544646) (xy 84.570824 -92.544646) (xy 84.400644 -92.633546) (xy 84.400644 -92.854526)
			(xy 84.570824 -92.943426) (xy 84.615274 -92.943426)
		)
		(stroke
			(width 0)
			(type solid)
		)
		(fill yes)
		(layer "In2.Cu")
		(net "M_K_ECC<6>")
	)
	(gr_poly
		(pts
			(xy 84.615274 -58.857896) (xy 84.570824 -58.857896) (xy 84.400644 -58.946796) (xy 84.400644 -59.167776)
			(xy 84.570824 -59.256676) (xy 84.615274 -59.256676)
		)
		(stroke
			(width 0)
			(type solid)
		)
		(fill yes)
		(layer "In2.Cu")
		(net "M_G_ECC<6>")
	)
	(gr_poly
		(pts
			(xy 84.660994 -54.24678) (xy 84.660994 -54.01818) (xy 84.467954 -53.92928) (xy 84.423504 -53.92928)
			(xy 84.423504 -54.33568) (xy 84.467954 -54.33568)
		)
		(stroke
			(width 0)
			(type solid)
		)
		(fill yes)
		(layer "In2.Cu")
		(net "M_G_ECC<3>")
	)
	(gr_poly
		(pts
			(xy 84.660994 -53.25618) (xy 84.660994 -53.02758) (xy 84.467954 -52.93868) (xy 84.423504 -52.93868)
			(xy 84.423504 -53.34508) (xy 84.467954 -53.34508)
		)
		(stroke
			(width 0)
			(type solid)
		)
		(fill yes)
		(layer "In2.Cu")
		(net "M_G_ECC<3>")
	)
	(gr_poly
		(pts
			(xy 84.660994 -52.26558) (xy 84.660994 -52.03698) (xy 84.467954 -51.94808) (xy 84.423504 -51.94808)
			(xy 84.423504 -52.35448) (xy 84.467954 -52.35448)
		)
		(stroke
			(width 0)
			(type solid)
		)
		(fill yes)
		(layer "In2.Cu")
		(net "M_G_ECC<3>")
	)
	(gr_poly
		(pts
			(xy 84.767674 -102.633526) (xy 84.767674 -102.404926) (xy 84.574634 -102.316026) (xy 84.530184 -102.316026)
			(xy 84.530184 -102.722426) (xy 84.574634 -102.722426)
		)
		(stroke
			(width 0)
			(type solid)
		)
		(fill yes)
		(layer "In2.Cu")
		(net "M_K_ECC<3>")
	)
	(gr_poly
		(pts
			(xy 84.845652 -58.115708) (xy 84.85378 -57.923938) (xy 84.662518 -57.813702) (xy 84.500466 -57.916572)
			(xy 84.478368 -57.954926) (xy 84.823554 -58.15457)
		)
		(stroke
			(width 0)
			(type solid)
		)
		(fill yes)
		(layer "In2.Cu")
		(net "M_G_ECC<7>")
	)
	(gr_poly
		(pts
			(xy 84.84743 -57.126632) (xy 84.855558 -56.934862) (xy 84.664296 -56.824372) (xy 84.502244 -56.927242)
			(xy 84.479892 -56.965596) (xy 84.825332 -57.16524)
		)
		(stroke
			(width 0)
			(type solid)
		)
		(fill yes)
		(layer "In2.Cu")
		(net "M_G_ECC<3>")
	)
	(gr_poly
		(pts
			(xy 84.855558 -93.870018) (xy 84.847684 -93.678248) (xy 84.825332 -93.63964) (xy 84.479892 -93.839284)
			(xy 84.502244 -93.877638) (xy 84.664296 -93.980508)
		)
		(stroke
			(width 0)
			(type solid)
		)
		(fill yes)
		(layer "In2.Cu")
		(net "M_K_ECC<7>")
	)
	(gr_poly
		(pts
			(xy 84.983066 -93.421708) (xy 85.153246 -93.332808) (xy 85.153246 -93.111828) (xy 84.983066 -93.022928)
			(xy 84.938616 -93.022928) (xy 84.938616 -93.421962)
		)
		(stroke
			(width 0)
			(type solid)
		)
		(fill yes)
		(layer "In2.Cu")
		(net "M_K_ECC<7>")
	)
	(gr_poly
		(pts
			(xy 84.983066 -58.770012) (xy 85.153246 -58.681112) (xy 85.153246 -58.460386) (xy 84.983066 -58.371486)
			(xy 84.93887 -58.371486) (xy 84.938616 -58.770266)
		)
		(stroke
			(width 0)
			(type solid)
		)
		(fill yes)
		(layer "In2.Cu")
		(net "M_G_ECC<7>")
	)
	(gr_poly
		(pts
			(xy 85.029802 -101.255576) (xy 85.029802 -101.026976) (xy 84.836762 -100.938076) (xy 84.792312 -100.938076)
			(xy 84.792312 -101.344476) (xy 84.836762 -101.344476)
		)
		(stroke
			(width 0)
			(type solid)
		)
		(fill yes)
		(layer "In2.Cu")
		(net "M_K_ECC<3>")
	)
	(gr_poly
		(pts
			(xy 85.029802 -100.264976) (xy 85.029802 -100.036376) (xy 84.836762 -99.947476) (xy 84.792312 -99.947476)
			(xy 84.792312 -100.353876) (xy 84.836762 -100.353876)
		)
		(stroke
			(width 0)
			(type solid)
		)
		(fill yes)
		(layer "In2.Cu")
		(net "M_K_ECC<3>")
	)
	(gr_poly
		(pts
			(xy 85.029802 -99.274376) (xy 85.029802 -99.045776) (xy 84.836762 -98.956876) (xy 84.792312 -98.956876)
			(xy 84.792312 -99.363276) (xy 84.836762 -99.363276)
		)
		(stroke
			(width 0)
			(type solid)
		)
		(fill yes)
		(layer "In2.Cu")
		(net "M_K_ECC<3>")
	)
	(gr_poly
		(pts
			(xy 85.029802 -98.283776) (xy 85.029802 -98.055176) (xy 84.836762 -97.966276) (xy 84.792312 -97.966276)
			(xy 84.792312 -98.372676) (xy 84.836762 -98.372676)
		)
		(stroke
			(width 0)
			(type solid)
		)
		(fill yes)
		(layer "In2.Cu")
		(net "M_K_ECC<3>")
	)
	(gr_poly
		(pts
			(xy 85.029802 -97.293176) (xy 85.029802 -97.064576) (xy 84.836762 -96.975676) (xy 84.792312 -96.975676)
			(xy 84.792312 -97.382076) (xy 84.836762 -97.382076)
		)
		(stroke
			(width 0)
			(type solid)
		)
		(fill yes)
		(layer "In2.Cu")
		(net "M_K_ECC<3>")
	)
	(gr_poly
		(pts
			(xy 85.05571 -57.72277) (xy 85.078062 -57.684162) (xy 84.732622 -57.484772) (xy 84.710524 -57.52338)
			(xy 84.702396 -57.71515) (xy 84.893658 -57.82564)
		)
		(stroke
			(width 0)
			(type solid)
		)
		(fill yes)
		(layer "In2.Cu")
		(net "M_G_ECC<2>")
	)
	(gr_poly
		(pts
			(xy 85.073998 -94.112842) (xy 85.0519 -94.074488) (xy 84.889848 -93.971618) (xy 84.698586 -94.082108)
			(xy 84.706714 -94.273878) (xy 84.728558 -94.312232)
		)
		(stroke
			(width 0)
			(type solid)
		)
		(fill yes)
		(layer "In2.Cu")
		(net "M_K_ECC<2>")
	)
	(gr_poly
		(pts
			(xy 85.149944 -91.237562) (xy 85.172296 -91.198954) (xy 84.826856 -90.999564) (xy 84.804758 -91.038172)
			(xy 84.79663 -91.229942) (xy 84.987892 -91.340432)
		)
		(stroke
			(width 0)
			(type solid)
		)
		(fill yes)
		(layer "In2.Cu")
		(net "M_K_ECC<2>")
	)
	(gr_poly
		(pts
			(xy 85.1535 -96.30918) (xy 85.1535 -96.0882) (xy 84.98332 -95.9993) (xy 84.93887 -95.9993) (xy 84.93887 -96.39808)
			(xy 84.98332 -96.39808)
		)
		(stroke
			(width 0)
			(type solid)
		)
		(fill yes)
		(layer "In2.Cu")
		(net "M_K_ECC<3>")
	)
	(gr_poly
		(pts
			(xy 85.1535 -95.31858) (xy 85.1535 -95.0976) (xy 84.98332 -95.0087) (xy 84.93887 -95.0087) (xy 84.93887 -95.40748)
			(xy 84.98332 -95.40748)
		)
		(stroke
			(width 0)
			(type solid)
		)
		(fill yes)
		(layer "In2.Cu")
		(net "M_K_ECC<3>")
	)
	(gr_poly
		(pts
			(xy 85.1535 -92.34678) (xy 85.1535 -92.1258) (xy 84.98332 -92.0369) (xy 84.93887 -92.0369) (xy 84.93887 -92.43568)
			(xy 84.98332 -92.43568)
		)
		(stroke
			(width 0)
			(type solid)
		)
		(fill yes)
		(layer "In2.Cu")
		(net "M_K_ECC<7>")
	)
	(gr_poly
		(pts
			(xy 85.1535 -60.64758) (xy 85.1535 -60.4266) (xy 84.98332 -60.3377) (xy 84.93887 -60.3377) (xy 84.93887 -60.73648)
			(xy 84.98332 -60.73648)
		)
		(stroke
			(width 0)
			(type solid)
		)
		(fill yes)
		(layer "In2.Cu")
		(net "M_G_ECC<7>")
	)
	(gr_poly
		(pts
			(xy 85.1535 -59.65698) (xy 85.1535 -59.436) (xy 84.98332 -59.3471) (xy 84.93887 -59.3471) (xy 84.93887 -59.74588)
			(xy 84.98332 -59.74588)
		)
		(stroke
			(width 0)
			(type solid)
		)
		(fill yes)
		(layer "In2.Cu")
		(net "M_G_ECC<7>")
	)
	(gr_poly
		(pts
			(xy 85.473794 -93.03385) (xy 85.429344 -93.03385) (xy 85.259164 -93.12275) (xy 85.259164 -93.34373)
			(xy 85.429344 -93.43263) (xy 85.473794 -93.43263)
		)
		(stroke
			(width 0)
			(type solid)
		)
		(fill yes)
		(layer "In2.Cu")
		(net "M_K_ECC<2>")
	)
	(gr_poly
		(pts
			(xy 85.473794 -92.0369) (xy 85.429344 -92.0369) (xy 85.259164 -92.1258) (xy 85.259164 -92.34678)
			(xy 85.429344 -92.43568) (xy 85.473794 -92.43568)
		)
		(stroke
			(width 0)
			(type solid)
		)
		(fill yes)
		(layer "In2.Cu")
		(net "M_K_ECC<2>")
	)
	(gr_poly
		(pts
			(xy 85.473794 -59.3471) (xy 85.429344 -59.3471) (xy 85.259164 -59.436) (xy 85.259164 -59.65698) (xy 85.429344 -59.74588)
			(xy 85.473794 -59.74588)
		)
		(stroke
			(width 0)
			(type solid)
		)
		(fill yes)
		(layer "In2.Cu")
		(net "M_G_ECC<2>")
	)
	(gr_poly
		(pts
			(xy 85.473794 -58.368946) (xy 85.429344 -58.368946) (xy 85.259164 -58.457846) (xy 85.259164 -58.678826)
			(xy 85.429344 -58.767726) (xy 85.473794 -58.767726)
		)
		(stroke
			(width 0)
			(type solid)
		)
		(fill yes)
		(layer "In2.Cu")
		(net "M_G_ECC<2>")
	)
	(gr_poly
		(pts
			(xy 85.7123 -94.366588) (xy 85.704172 -94.174564) (xy 85.682074 -94.135956) (xy 85.336888 -94.3356)
			(xy 85.358986 -94.373954) (xy 85.521038 -94.476824)
		)
		(stroke
			(width 0)
			(type solid)
		)
		(fill yes)
		(layer "In2.Cu")
		(net "M_K_ECC<3>")
	)
	(gr_poly
		(pts
			(xy 85.76818 -57.709308) (xy 85.809836 -57.521856) (xy 85.640672 -57.379616) (xy 85.463126 -57.452768)
			(xy 85.434424 -57.48655) (xy 85.739478 -57.743344)
		)
		(stroke
			(width 0)
			(type solid)
		)
		(fill yes)
		(layer "In2.Cu")
		(net "M_G_ECC<3>")
	)
	(gr_poly
		(pts
			(xy 86.011512 -61.156596) (xy 86.012528 -60.935616) (xy 85.842856 -60.8457) (xy 85.798152 -60.8457)
			(xy 85.796374 -61.244226) (xy 85.84057 -61.24448)
		)
		(stroke
			(width 0)
			(type solid)
		)
		(fill yes)
		(layer "In2.Cu")
		(net "M_G_ECC<3>")
	)
	(gr_poly
		(pts
			(xy 86.011766 -93.83014) (xy 86.011766 -93.609414) (xy 85.841586 -93.520514) (xy 85.797136 -93.52026)
			(xy 85.79739 -93.91904) (xy 85.841586 -93.91904)
		)
		(stroke
			(width 0)
			(type solid)
		)
		(fill yes)
		(layer "In2.Cu")
		(net "M_K_ECC<3>")
	)
	(gr_poly
		(pts
			(xy 86.01202 -92.854526) (xy 86.01202 -92.633546) (xy 85.84184 -92.544646) (xy 85.79739 -92.544646)
			(xy 85.79739 -92.943426) (xy 85.84184 -92.943426)
		)
		(stroke
			(width 0)
			(type solid)
		)
		(fill yes)
		(layer "In2.Cu")
		(net "M_K_ECC<3>")
	)
	(gr_poly
		(pts
			(xy 86.01202 -91.863926) (xy 86.01202 -91.642946) (xy 85.84184 -91.554046) (xy 85.79739 -91.554046)
			(xy 85.79739 -91.952826) (xy 85.84184 -91.952826)
		)
		(stroke
			(width 0)
			(type solid)
		)
		(fill yes)
		(layer "In2.Cu")
		(net "M_K_ECC<3>")
	)
	(gr_poly
		(pts
			(xy 86.01202 -60.164726) (xy 86.01202 -59.943746) (xy 85.84184 -59.854846) (xy 85.79739 -59.854846)
			(xy 85.79739 -60.253626) (xy 85.84184 -60.253626)
		)
		(stroke
			(width 0)
			(type solid)
		)
		(fill yes)
		(layer "In2.Cu")
		(net "M_G_ECC<3>")
	)
	(gr_poly
		(pts
			(xy 86.01202 -59.167776) (xy 86.01202 -58.946796) (xy 85.84184 -58.857896) (xy 85.79739 -58.857896)
			(xy 85.79739 -59.256676) (xy 85.84184 -59.256676)
		)
		(stroke
			(width 0)
			(type solid)
		)
		(fill yes)
		(layer "In2.Cu")
		(net "M_G_ECC<3>")
	)
	(gr_poly
		(pts
			(xy 86.012274 -58.175398) (xy 86.011512 -57.954418) (xy 85.841078 -57.866026) (xy 85.796628 -57.866026)
			(xy 85.797644 -58.264806) (xy 85.842348 -58.264806)
		)
		(stroke
			(width 0)
			(type solid)
		)
		(fill yes)
		(layer "In2.Cu")
		(net "M_G_ECC<3>")
	)
	(gr_poly
		(pts
			(xy 107.256072 -104.670606) (xy 107.211622 -104.670606) (xy 107.018582 -104.759506) (xy 107.018582 -104.988106)
			(xy 107.211622 -105.077006) (xy 107.256072 -105.077006)
		)
		(stroke
			(width 0)
			(type solid)
		)
		(fill yes)
		(layer "In2.Cu")
		(net "M_K_DQ<44>")
	)
	(gr_poly
		(pts
			(xy 107.575604 -50.12055) (xy 107.531154 -50.12055) (xy 107.338114 -50.20945) (xy 107.338114 -50.43805)
			(xy 107.531154 -50.52695) (xy 107.575604 -50.52695)
		)
		(stroke
			(width 0)
			(type solid)
		)
		(fill yes)
		(layer "In2.Cu")
		(net "M_G_DQ<44>")
	)
	(gr_poly
		(pts
			(xy 107.575604 -49.12995) (xy 107.531154 -49.12995) (xy 107.338114 -49.21885) (xy 107.338114 -49.44745)
			(xy 107.531154 -49.53635) (xy 107.575604 -49.53635)
		)
		(stroke
			(width 0)
			(type solid)
		)
		(fill yes)
		(layer "In2.Cu")
		(net "M_G_DQ<44>")
	)
	(gr_poly
		(pts
			(xy 107.575604 -48.13935) (xy 107.531154 -48.13935) (xy 107.338114 -48.22825) (xy 107.338114 -48.45685)
			(xy 107.531154 -48.54575) (xy 107.575604 -48.54575)
		)
		(stroke
			(width 0)
			(type solid)
		)
		(fill yes)
		(layer "In2.Cu")
		(net "M_G_DQ<44>")
	)
	(gr_poly
		(pts
			(xy 107.683554 -104.988106) (xy 107.683554 -104.759506) (xy 107.490514 -104.670606) (xy 107.446064 -104.670606)
			(xy 107.446064 -105.077006) (xy 107.490514 -105.077006)
		)
		(stroke
			(width 0)
			(type solid)
		)
		(fill yes)
		(layer "In2.Cu")
		(net "M_K_DQ<45>")
	)
	(gr_poly
		(pts
			(xy 107.95889 -103.388668) (xy 107.927648 -103.357172) (xy 107.728258 -103.283512) (xy 107.56646 -103.445056)
			(xy 107.64012 -103.644446) (xy 107.671616 -103.675942)
		)
		(stroke
			(width 0)
			(type solid)
		)
		(fill yes)
		(layer "In2.Cu")
		(net "M_K_DQ<44>")
	)
	(gr_poly
		(pts
			(xy 108.003594 -50.43805) (xy 108.003594 -50.20945) (xy 107.810554 -50.12055) (xy 107.766104 -50.12055)
			(xy 107.766104 -50.52695) (xy 107.810554 -50.52695)
		)
		(stroke
			(width 0)
			(type solid)
		)
		(fill yes)
		(layer "In2.Cu")
		(net "M_G_DQ<45>")
	)
	(gr_poly
		(pts
			(xy 108.003594 -49.44745) (xy 108.003594 -49.21885) (xy 107.810554 -49.12995) (xy 107.766104 -49.12995)
			(xy 107.766104 -49.53635) (xy 107.810554 -49.53635)
		)
		(stroke
			(width 0)
			(type solid)
		)
		(fill yes)
		(layer "In2.Cu")
		(net "M_G_DQ<45>")
	)
	(gr_poly
		(pts
			(xy 108.003594 -48.45685) (xy 108.003594 -48.22825) (xy 107.810554 -48.13935) (xy 107.766104 -48.13935)
			(xy 107.766104 -48.54575) (xy 107.810554 -48.54575)
		)
		(stroke
			(width 0)
			(type solid)
		)
		(fill yes)
		(layer "In2.Cu")
		(net "M_G_DQ<45>")
	)
	(gr_poly
		(pts
			(xy 108.198412 -103.753666) (xy 108.124752 -103.554276) (xy 108.093256 -103.523034) (xy 107.805982 -103.810308)
			(xy 107.837478 -103.841804) (xy 108.036868 -103.915464)
		)
		(stroke
			(width 0)
			(type solid)
		)
		(fill yes)
		(layer "In2.Cu")
		(net "M_K_DQ<45>")
	)
	(gr_poly
		(pts
			(xy 108.314236 -51.474116) (xy 108.345732 -51.442874) (xy 108.058204 -51.155346) (xy 108.026962 -51.186842)
			(xy 107.953302 -51.386232) (xy 108.114846 -51.547776)
		)
		(stroke
			(width 0)
			(type solid)
		)
		(fill yes)
		(layer "In2.Cu")
		(net "M_G_DQ<44>")
	)
	(gr_poly
		(pts
			(xy 108.324904 -49.51984) (xy 108.280454 -49.51984) (xy 108.087414 -49.60874) (xy 108.087414 -49.83734)
			(xy 108.280454 -49.92624) (xy 108.324904 -49.92624)
		)
		(stroke
			(width 0)
			(type solid)
		)
		(fill yes)
		(layer "In2.Cu")
		(net "M_G_DQ<40>")
	)
	(gr_poly
		(pts
			(xy 108.324904 -48.52924) (xy 108.280454 -48.52924) (xy 108.087414 -48.61814) (xy 108.087414 -48.84674)
			(xy 108.280454 -48.93564) (xy 108.324904 -48.93564)
		)
		(stroke
			(width 0)
			(type solid)
		)
		(fill yes)
		(layer "In2.Cu")
		(net "M_G_DQ<40>")
	)
	(gr_poly
		(pts
			(xy 108.435648 -51.200304) (xy 108.509308 -51.001168) (xy 108.34751 -50.83937) (xy 108.148374 -50.91303)
			(xy 108.116878 -50.944526) (xy 108.404152 -51.2318)
		)
		(stroke
			(width 0)
			(type solid)
		)
		(fill yes)
		(layer "In2.Cu")
		(net "M_G_DQ<45>")
	)
	(gr_poly
		(pts
			(xy 108.659422 -102.688136) (xy 108.627926 -102.65664) (xy 108.42879 -102.58298) (xy 108.266992 -102.744778)
			(xy 108.340652 -102.943914) (xy 108.372148 -102.97541)
		)
		(stroke
			(width 0)
			(type solid)
		)
		(fill yes)
		(layer "In2.Cu")
		(net "M_K_DQ<44>")
	)
	(gr_poly
		(pts
			(xy 108.752894 -49.83734) (xy 108.752894 -49.60874) (xy 108.559854 -49.51984) (xy 108.515404 -49.51984)
			(xy 108.515404 -49.92624) (xy 108.559854 -49.92624)
		)
		(stroke
			(width 0)
			(type solid)
		)
		(fill yes)
		(layer "In2.Cu")
		(net "M_G_DQ<41>")
	)
	(gr_poly
		(pts
			(xy 108.752894 -48.84674) (xy 108.752894 -48.61814) (xy 108.559854 -48.52924) (xy 108.515404 -48.52924)
			(xy 108.515404 -48.93564) (xy 108.559854 -48.93564)
		)
		(stroke
			(width 0)
			(type solid)
		)
		(fill yes)
		(layer "In2.Cu")
		(net "M_G_DQ<41>")
	)
	(gr_poly
		(pts
			(xy 108.898944 -103.053134) (xy 108.825284 -102.853998) (xy 108.793788 -102.822502) (xy 108.506514 -103.109776)
			(xy 108.53801 -103.141272) (xy 108.737146 -103.214932)
		)
		(stroke
			(width 0)
			(type solid)
		)
		(fill yes)
		(layer "In2.Cu")
		(net "M_K_DQ<45>")
	)
	(gr_poly
		(pts
			(xy 109.042454 -104.482392) (xy 109.010958 -104.450896) (xy 108.811822 -104.377236) (xy 108.650024 -104.539034)
			(xy 108.723684 -104.73817) (xy 108.75518 -104.769666)
		)
		(stroke
			(width 0)
			(type solid)
		)
		(fill yes)
		(layer "In2.Cu")
		(net "M_K_DQ<40>")
	)
	(gr_poly
		(pts
			(xy 109.050582 -51.186588) (xy 109.082078 -51.155346) (xy 108.79455 -50.867818) (xy 108.763308 -50.899314)
			(xy 108.689648 -51.098704) (xy 108.851192 -51.260248)
		)
		(stroke
			(width 0)
			(type solid)
		)
		(fill yes)
		(layer "In2.Cu")
		(net "M_G_DQ<40>")
	)
	(gr_poly
		(pts
			(xy 109.079792 -53.349652) (xy 109.111288 -53.31841) (xy 108.82376 -53.030882) (xy 108.792264 -53.062378)
			(xy 108.718858 -53.261768) (xy 108.880402 -53.423312)
		)
		(stroke
			(width 0)
			(type solid)
		)
		(fill yes)
		(layer "In2.Cu")
		(net "M_G_DQ<44>")
	)
	(gr_poly
		(pts
			(xy 109.106716 -49.417224) (xy 109.062266 -49.417224) (xy 108.869226 -49.506124) (xy 108.869226 -49.734724)
			(xy 109.062266 -49.823624) (xy 109.106716 -49.823624)
		)
		(stroke
			(width 0)
			(type solid)
		)
		(fill yes)
		(layer "In2.Cu")
		(net "M_G_DQS_DP<14>")
	)
	(gr_poly
		(pts
			(xy 109.106716 -48.426624) (xy 109.062266 -48.426624) (xy 108.869226 -48.515524) (xy 108.869226 -48.744124)
			(xy 109.062266 -48.833024) (xy 109.106716 -48.833024)
		)
		(stroke
			(width 0)
			(type solid)
		)
		(fill yes)
		(layer "In2.Cu")
		(net "M_G_DQS_DP<14>")
	)
	(gr_poly
		(pts
			(xy 109.144816 -52.483258) (xy 109.144816 -52.254658) (xy 108.951776 -52.165758) (xy 108.907326 -52.165758)
			(xy 108.907326 -52.572158) (xy 108.951776 -52.572158)
		)
		(stroke
			(width 0)
			(type solid)
		)
		(fill yes)
		(layer "In2.Cu")
		(net "M_G_DQ<45>")
	)
	(gr_poly
		(pts
			(xy 109.171994 -50.912776) (xy 109.245654 -50.71364) (xy 109.083856 -50.551842) (xy 108.88472 -50.625502)
			(xy 108.853224 -50.656998) (xy 109.140498 -50.944272)
		)
		(stroke
			(width 0)
			(type solid)
		)
		(fill yes)
		(layer "In2.Cu")
		(net "M_G_DQ<41>")
	)
	(gr_poly
		(pts
			(xy 109.277404 -53.15204) (xy 109.351064 -52.95265) (xy 109.189266 -52.791106) (xy 108.989876 -52.864766)
			(xy 108.958634 -52.896262) (xy 109.245908 -53.183536)
		)
		(stroke
			(width 0)
			(type solid)
		)
		(fill yes)
		(layer "In2.Cu")
		(net "M_G_DQ<45>")
	)
	(gr_poly
		(pts
			(xy 109.281976 -104.84739) (xy 109.208316 -104.648254) (xy 109.17682 -104.616758) (xy 108.889546 -104.904032)
			(xy 108.921042 -104.935528) (xy 109.120178 -105.009188)
		)
		(stroke
			(width 0)
			(type solid)
		)
		(fill yes)
		(layer "In2.Cu")
		(net "M_K_DQ<41>")
	)
	(gr_poly
		(pts
			(xy 109.323124 -55.199026) (xy 109.278674 -55.199026) (xy 109.108494 -55.287926) (xy 109.108494 -55.508906)
			(xy 109.278674 -55.597806) (xy 109.323124 -55.597806)
		)
		(stroke
			(width 0)
			(type solid)
		)
		(fill yes)
		(layer "In2.Cu")
		(net "M_G_DQ<44>")
	)
	(gr_poly
		(pts
			(xy 109.323124 -54.208426) (xy 109.278674 -54.208426) (xy 109.108494 -54.297326) (xy 109.108494 -54.518306)
			(xy 109.278674 -54.607206) (xy 109.323124 -54.607206)
		)
		(stroke
			(width 0)
			(type solid)
		)
		(fill yes)
		(layer "In2.Cu")
		(net "M_G_DQ<44>")
	)
	(gr_poly
		(pts
			(xy 109.359954 -101.987604) (xy 109.328458 -101.956108) (xy 109.129068 -101.882448) (xy 108.967524 -102.044246)
			(xy 109.041184 -102.243636) (xy 109.07268 -102.274878)
		)
		(stroke
			(width 0)
			(type solid)
		)
		(fill yes)
		(layer "In2.Cu")
		(net "M_K_DQ<44>")
	)
	(gr_poly
		(pts
			(xy 109.440726 -51.784758) (xy 109.396276 -51.784758) (xy 109.203236 -51.873658) (xy 109.203236 -52.102258)
			(xy 109.396276 -52.191158) (xy 109.440726 -52.191158)
		)
		(stroke
			(width 0)
			(type solid)
		)
		(fill yes)
		(layer "In2.Cu")
		(net "M_G_DQ<40>")
	)
	(gr_poly
		(pts
			(xy 109.534198 -49.734724) (xy 109.534198 -49.506124) (xy 109.341158 -49.417224) (xy 109.296708 -49.417224)
			(xy 109.296708 -49.823624) (xy 109.341158 -49.823624)
		)
		(stroke
			(width 0)
			(type solid)
		)
		(fill yes)
		(layer "In2.Cu")
		(net "M_G_DQS_DN<14>")
	)
	(gr_poly
		(pts
			(xy 109.534198 -48.744124) (xy 109.534198 -48.515524) (xy 109.341158 -48.426624) (xy 109.296708 -48.426624)
			(xy 109.296708 -48.833024) (xy 109.341158 -48.833024)
		)
		(stroke
			(width 0)
			(type solid)
		)
		(fill yes)
		(layer "In2.Cu")
		(net "M_G_DQS_DN<14>")
	)
	(gr_poly
		(pts
			(xy 109.599476 -102.352856) (xy 109.525816 -102.153466) (xy 109.49432 -102.12197) (xy 109.207046 -102.409244)
			(xy 109.238288 -102.44074) (xy 109.437678 -102.5144)
		)
		(stroke
			(width 0)
			(type solid)
		)
		(fill yes)
		(layer "In2.Cu")
		(net "M_K_DQ<45>")
	)
	(gr_poly
		(pts
			(xy 109.67212 -105.290366) (xy 109.62767 -105.290366) (xy 109.43463 -105.379012) (xy 109.43463 -105.607866)
			(xy 109.62767 -105.696766) (xy 109.67212 -105.696766)
		)
		(stroke
			(width 0)
			(type solid)
		)
		(fill yes)
		(layer "In2.Cu")
		(net "M_K_DQS_DP<14>")
	)
	(gr_poly
		(pts
			(xy 109.742986 -103.78186) (xy 109.71149 -103.750364) (xy 109.512354 -103.676704) (xy 109.350556 -103.838502)
			(xy 109.424216 -104.037638) (xy 109.455712 -104.069134)
		)
		(stroke
			(width 0)
			(type solid)
		)
		(fill yes)
		(layer "In2.Cu")
		(net "M_K_DQ<40>")
	)
	(gr_poly
		(pts
			(xy 109.747812 -50.860198) (xy 109.779308 -50.828702) (xy 109.492034 -50.541428) (xy 109.460538 -50.572924)
			(xy 109.386878 -50.77206) (xy 109.548676 -50.933858)
		)
		(stroke
			(width 0)
			(type solid)
		)
		(fill yes)
		(layer "In2.Cu")
		(net "M_G_DQS_DP<14>")
	)
	(gr_poly
		(pts
			(xy 109.861604 -55.033418) (xy 109.861604 -54.812438) (xy 109.691424 -54.723538) (xy 109.646974 -54.723538)
			(xy 109.646974 -55.122318) (xy 109.691424 -55.122318)
		)
		(stroke
			(width 0)
			(type solid)
		)
		(fill yes)
		(layer "In2.Cu")
		(net "M_G_DQ<45>")
	)
	(gr_poly
		(pts
			(xy 109.868716 -52.102258) (xy 109.868716 -51.873658) (xy 109.675676 -51.784758) (xy 109.631226 -51.784758)
			(xy 109.631226 -52.191158) (xy 109.675676 -52.191158)
		)
		(stroke
			(width 0)
			(type solid)
		)
		(fill yes)
		(layer "In2.Cu")
		(net "M_G_DQ<41>")
	)
	(gr_poly
		(pts
			(xy 109.908848 -53.155088) (xy 109.940344 -53.123846) (xy 109.652816 -52.836318) (xy 109.62132 -52.867814)
			(xy 109.547914 -53.067204) (xy 109.709458 -53.228748)
		)
		(stroke
			(width 0)
			(type solid)
		)
		(fill yes)
		(layer "In2.Cu")
		(net "M_G_DQ<40>")
	)
	(gr_poly
		(pts
			(xy 109.908848 -48.498506) (xy 109.864398 -48.498506) (xy 109.671358 -48.587406) (xy 109.671358 -48.816006)
			(xy 109.864398 -48.904906) (xy 109.908848 -48.904906)
		)
		(stroke
			(width 0)
			(type solid)
		)
		(fill yes)
		(layer "In2.Cu")
		(net "M_G_DQS_DN<5>")
	)
	(gr_poly
		(pts
			(xy 109.945424 -50.662586) (xy 110.019084 -50.463196) (xy 109.85754 -50.301652) (xy 109.65815 -50.375312)
			(xy 109.626654 -50.406554) (xy 109.914182 -50.694082)
		)
		(stroke
			(width 0)
			(type solid)
		)
		(fill yes)
		(layer "In2.Cu")
		(net "M_G_DQS_DN<14>")
	)
	(gr_poly
		(pts
			(xy 109.982508 -104.146858) (xy 109.908848 -103.947722) (xy 109.877352 -103.916226) (xy 109.590078 -104.2035)
			(xy 109.621574 -104.234996) (xy 109.82071 -104.308656)
		)
		(stroke
			(width 0)
			(type solid)
		)
		(fill yes)
		(layer "In2.Cu")
		(net "M_K_DQ<41>")
	)
	(gr_poly
		(pts
			(xy 110.10011 -105.607866) (xy 110.10011 -105.379266) (xy 109.90707 -105.290366) (xy 109.86262 -105.290112)
			(xy 109.86262 -105.696766) (xy 109.90707 -105.696766)
		)
		(stroke
			(width 0)
			(type solid)
		)
		(fill yes)
		(layer "In2.Cu")
		(net "M_K_DQS_DN<14>")
	)
	(gr_poly
		(pts
			(xy 110.10646 -52.957476) (xy 110.18012 -52.758086) (xy 110.018322 -52.596542) (xy 109.818932 -52.670202)
			(xy 109.78769 -52.701698) (xy 110.074964 -52.988972)
		)
		(stroke
			(width 0)
			(type solid)
		)
		(fill yes)
		(layer "In2.Cu")
		(net "M_G_DQ<41>")
	)
	(gr_poly
		(pts
			(xy 110.146084 -53.406802) (xy 110.101634 -53.406802) (xy 109.908594 -53.495702) (xy 109.908594 -53.724302)
			(xy 110.101634 -53.813202) (xy 110.146084 -53.813202)
		)
		(stroke
			(width 0)
			(type solid)
		)
		(fill yes)
		(layer "In2.Cu")
		(net "M_G_DQ<40>")
	)
	(gr_poly
		(pts
			(xy 110.164626 -51.403758) (xy 110.120176 -51.403758) (xy 109.927136 -51.492658) (xy 109.927136 -51.721258)
			(xy 110.120176 -51.810158) (xy 110.164626 -51.810158)
		)
		(stroke
			(width 0)
			(type solid)
		)
		(fill yes)
		(layer "In2.Cu")
		(net "M_G_DQS_DP<14>")
	)
	(gr_poly
		(pts
			(xy 110.181644 -54.714648) (xy 110.137194 -54.714648) (xy 109.967014 -54.803548) (xy 109.967014 -55.024528)
			(xy 110.137194 -55.113428) (xy 110.181644 -55.113428)
		)
		(stroke
			(width 0)
			(type solid)
		)
		(fill yes)
		(layer "In2.Cu")
		(net "M_G_DQ<40>")
	)
	(gr_poly
		(pts
			(xy 110.220252 -100.252784) (xy 110.181898 -100.230432) (xy 109.970062 -100.210874) (xy 109.855762 -100.40874)
			(xy 109.978444 -100.582222) (xy 110.016798 -100.604574)
		)
		(stroke
			(width 0)
			(type solid)
		)
		(fill yes)
		(layer "In2.Cu")
		(net "M_K_DQ<44>")
	)
	(gr_poly
		(pts
			(xy 110.2741 -104.403652) (xy 110.242604 -104.372156) (xy 110.043468 -104.298496) (xy 109.88167 -104.460294)
			(xy 109.95533 -104.65943) (xy 109.986826 -104.690926)
		)
		(stroke
			(width 0)
			(type solid)
		)
		(fill yes)
		(layer "In2.Cu")
		(net "M_K_DQS_DP<14>")
	)
	(gr_poly
		(pts
			(xy 110.33633 -48.816006) (xy 110.33633 -48.587406) (xy 110.14329 -48.498506) (xy 110.09884 -48.498506)
			(xy 110.09884 -48.904906) (xy 110.14329 -48.904906)
		)
		(stroke
			(width 0)
			(type solid)
		)
		(fill yes)
		(layer "In2.Cu")
		(net "M_G_DQS_DP<5>")
	)
	(gr_poly
		(pts
			(xy 110.443518 -103.081328) (xy 110.412022 -103.049832) (xy 110.212886 -102.976172) (xy 110.051088 -103.13797)
			(xy 110.124748 -103.337106) (xy 110.156244 -103.368602)
		)
		(stroke
			(width 0)
			(type solid)
		)
		(fill yes)
		(layer "In2.Cu")
		(net "M_K_DQ<40>")
	)
	(gr_poly
		(pts
			(xy 110.513876 -104.769158) (xy 110.440216 -104.569768) (xy 110.408974 -104.538272) (xy 110.121446 -104.8258)
			(xy 110.152942 -104.857042) (xy 110.352332 -104.930702)
		)
		(stroke
			(width 0)
			(type solid)
		)
		(fill yes)
		(layer "In2.Cu")
		(net "M_K_DQS_DN<14>")
	)
	(gr_poly
		(pts
			(xy 110.532418 -101.791008) (xy 110.487968 -101.791008) (xy 110.294928 -101.879908) (xy 110.294928 -102.108508)
			(xy 110.487968 -102.197408) (xy 110.532418 -102.197408)
		)
		(stroke
			(width 0)
			(type solid)
		)
		(fill yes)
		(layer "In2.Cu")
		(net "M_K_DQ<40>")
	)
	(gr_poly
		(pts
			(xy 110.546896 -100.544122) (xy 110.424214 -100.37064) (xy 110.38586 -100.348288) (xy 110.182406 -100.700332)
			(xy 110.221014 -100.72243) (xy 110.432596 -100.742242)
		)
		(stroke
			(width 0)
			(type solid)
		)
		(fill yes)
		(layer "In2.Cu")
		(net "M_K_DQ<45>")
	)
	(gr_poly
		(pts
			(xy 110.566454 -50.040032) (xy 110.59795 -50.00879) (xy 110.310422 -49.721262) (xy 110.27918 -49.752758)
			(xy 110.20552 -49.952148) (xy 110.367064 -50.113692)
		)
		(stroke
			(width 0)
			(type solid)
		)
		(fill yes)
		(layer "In2.Cu")
		(net "M_G_DQS_DN<5>")
	)
	(gr_poly
		(pts
			(xy 110.574074 -53.622702) (xy 110.574074 -53.394102) (xy 110.381034 -53.305202) (xy 110.336584 -53.305202)
			(xy 110.336584 -53.711602) (xy 110.381034 -53.711602)
		)
		(stroke
			(width 0)
			(type solid)
		)
		(fill yes)
		(layer "In2.Cu")
		(net "M_G_DQ<41>")
	)
	(gr_poly
		(pts
			(xy 110.592616 -51.721258) (xy 110.592616 -51.492658) (xy 110.399576 -51.403758) (xy 110.355126 -51.403758)
			(xy 110.355126 -51.810158) (xy 110.399576 -51.810158)
		)
		(stroke
			(width 0)
			(type solid)
		)
		(fill yes)
		(layer "In2.Cu")
		(net "M_G_DQS_DN<14>")
	)
	(gr_poly
		(pts
			(xy 110.68304 -103.446326) (xy 110.60938 -103.24719) (xy 110.577884 -103.215694) (xy 110.29061 -103.502968)
			(xy 110.322106 -103.534464) (xy 110.521242 -103.608124)
		)
		(stroke
			(width 0)
			(type solid)
		)
		(fill yes)
		(layer "In2.Cu")
		(net "M_K_DQ<41>")
	)
	(gr_poly
		(pts
			(xy 110.68304 -48.349916) (xy 110.63859 -48.349916) (xy 110.44555 -48.438816) (xy 110.44555 -48.667416)
			(xy 110.63859 -48.756316) (xy 110.68304 -48.756316)
		)
		(stroke
			(width 0)
			(type solid)
		)
		(fill yes)
		(layer "In2.Cu")
		(net "M_G_DQ<46>")
	)
	(gr_poly
		(pts
			(xy 110.702344 -52.917598) (xy 110.73384 -52.886102) (xy 110.446566 -52.598828) (xy 110.41507 -52.630324)
			(xy 110.34141 -52.82946) (xy 110.503208 -52.991258)
		)
		(stroke
			(width 0)
			(type solid)
		)
		(fill yes)
		(layer "In2.Cu")
		(net "M_G_DQS_DP<14>")
	)
	(gr_poly
		(pts
			(xy 110.719616 -54.529228) (xy 110.719616 -54.308248) (xy 110.549436 -54.219348) (xy 110.504986 -54.219348)
			(xy 110.504986 -54.618128) (xy 110.549436 -54.618128)
		)
		(stroke
			(width 0)
			(type solid)
		)
		(fill yes)
		(layer "In2.Cu")
		(net "M_G_DQ<41>")
	)
	(gr_poly
		(pts
			(xy 110.764066 -49.84242) (xy 110.837726 -49.643284) (xy 110.675928 -49.481486) (xy 110.476792 -49.555146)
			(xy 110.445296 -49.586642) (xy 110.73257 -49.873916)
		)
		(stroke
			(width 0)
			(type solid)
		)
		(fill yes)
		(layer "In2.Cu")
		(net "M_G_DQS_DP<5>")
	)
	(gr_poly
		(pts
			(xy 110.888526 -50.95113) (xy 110.844076 -50.95113) (xy 110.651036 -51.04003) (xy 110.651036 -51.26863)
			(xy 110.844076 -51.35753) (xy 110.888526 -51.35753)
		)
		(stroke
			(width 0)
			(type solid)
		)
		(fill yes)
		(layer "In2.Cu")
		(net "M_G_DQS_DN<5>")
	)
	(gr_poly
		(pts
			(xy 110.899956 -52.719986) (xy 110.973616 -52.520596) (xy 110.812072 -52.359052) (xy 110.612682 -52.432712)
			(xy 110.581186 -52.463954) (xy 110.868714 -52.751482)
		)
		(stroke
			(width 0)
			(type solid)
		)
		(fill yes)
		(layer "In2.Cu")
		(net "M_G_DQS_DN<14>")
	)
	(gr_poly
		(pts
			(xy 110.931452 -99.386136) (xy 110.9091 -99.347782) (xy 110.747048 -99.244912) (xy 110.555786 -99.355402)
			(xy 110.563914 -99.547172) (xy 110.586012 -99.585526)
		)
		(stroke
			(width 0)
			(type solid)
		)
		(fill yes)
		(layer "In2.Cu")
		(net "M_K_DQ<44>")
	)
	(gr_poly
		(pts
			(xy 110.9599 -102.108508) (xy 110.9599 -101.879908) (xy 110.76686 -101.791008) (xy 110.72241 -101.791008)
			(xy 110.72241 -102.197408) (xy 110.76686 -102.197408)
		)
		(stroke
			(width 0)
			(type solid)
		)
		(fill yes)
		(layer "In2.Cu")
		(net "M_K_DQ<41>")
	)
	(gr_poly
		(pts
			(xy 110.974632 -103.70312) (xy 110.943136 -103.671624) (xy 110.744 -103.597964) (xy 110.582202 -103.759762)
			(xy 110.655862 -103.958898) (xy 110.687358 -103.990394)
		)
		(stroke
			(width 0)
			(type solid)
		)
		(fill yes)
		(layer "In2.Cu")
		(net "M_K_DQS_DP<14>")
	)
	(gr_poly
		(pts
			(xy 111.040164 -54.212998) (xy 110.995714 -54.212998) (xy 110.825534 -54.301898) (xy 110.825534 -54.522878)
			(xy 110.995714 -54.611778) (xy 111.040164 -54.611778)
		)
		(stroke
			(width 0)
			(type solid)
		)
		(fill yes)
		(layer "In2.Cu")
		(net "M_G_DQS_DP<14>")
	)
	(gr_poly
		(pts
			(xy 111.11103 -48.667416) (xy 111.11103 -48.438816) (xy 110.91799 -48.349916) (xy 110.87354 -48.349916)
			(xy 110.87354 -48.756316) (xy 110.91799 -48.756316)
		)
		(stroke
			(width 0)
			(type solid)
		)
		(fill yes)
		(layer "In2.Cu")
		(net "M_G_DQ<47>")
	)
	(gr_poly
		(pts
			(xy 111.11611 -56.4388) (xy 111.074962 -56.251094) (xy 111.04626 -56.217058) (xy 110.740952 -56.473598)
			(xy 110.7694 -56.507634) (xy 110.946946 -56.580786)
		)
		(stroke
			(width 0)
			(type solid)
		)
		(fill yes)
		(layer "In2.Cu")
		(net "M_G_DQ<41>")
	)
	(gr_poly
		(pts
			(xy 111.142526 -100.53447) (xy 111.103918 -100.512372) (xy 110.892336 -100.49256) (xy 110.778036 -100.69068)
			(xy 110.900718 -100.864162) (xy 110.939072 -100.886514)
		)
		(stroke
			(width 0)
			(type solid)
		)
		(fill yes)
		(layer "In2.Cu")
		(net "M_K_DQ<40>")
	)
	(gr_poly
		(pts
			(xy 111.214408 -104.068626) (xy 111.140748 -103.869236) (xy 111.109506 -103.83774) (xy 110.821978 -104.125268)
			(xy 110.853474 -104.15651) (xy 111.052864 -104.23017)
		)
		(stroke
			(width 0)
			(type solid)
		)
		(fill yes)
		(layer "In2.Cu")
		(net "M_K_DQS_DN<14>")
	)
	(gr_poly
		(pts
			(xy 111.315246 -49.765458) (xy 111.346742 -49.733962) (xy 111.059468 -49.446688) (xy 111.027972 -49.478184)
			(xy 110.954312 -49.67732) (xy 111.11611 -49.839118)
		)
		(stroke
			(width 0)
			(type solid)
		)
		(fill yes)
		(layer "In2.Cu")
		(net "M_G_DQ<46>")
	)
	(gr_poly
		(pts
			(xy 111.316516 -51.26863) (xy 111.316516 -51.04003) (xy 111.123476 -50.95113) (xy 111.079026 -50.95113)
			(xy 111.079026 -51.35753) (xy 111.123476 -51.35753)
		)
		(stroke
			(width 0)
			(type solid)
		)
		(fill yes)
		(layer "In2.Cu")
		(net "M_G_DQS_DP<5>")
	)
	(gr_poly
		(pts
			(xy 111.323628 -102.70998) (xy 111.279178 -102.70998) (xy 111.086392 -102.79888) (xy 111.086392 -103.027734)
			(xy 111.279178 -103.11638) (xy 111.323628 -103.11638)
		)
		(stroke
			(width 0)
			(type solid)
		)
		(fill yes)
		(layer "In2.Cu")
		(net "M_K_DQS_DP<14>")
	)
	(gr_poly
		(pts
			(xy 111.33201 -98.299524) (xy 111.28756 -98.299778) (xy 111.117634 -98.388424) (xy 111.11738 -98.609404)
			(xy 111.28756 -98.69805) (xy 111.33201 -98.69805)
		)
		(stroke
			(width 0)
			(type solid)
		)
		(fill yes)
		(layer "In2.Cu")
		(net "M_K_DQ<44>")
	)
	(gr_poly
		(pts
			(xy 111.46917 -100.826062) (xy 111.346488 -100.65258) (xy 111.30788 -100.630228) (xy 111.10468 -100.982018)
			(xy 111.143034 -101.00437) (xy 111.354616 -101.023928)
		)
		(stroke
			(width 0)
			(type solid)
		)
		(fill yes)
		(layer "In2.Cu")
		(net "M_K_DQ<41>")
	)
	(gr_poly
		(pts
			(xy 111.505492 -105.303574) (xy 111.461042 -105.303574) (xy 111.268002 -105.392474) (xy 111.268002 -105.621074)
			(xy 111.461042 -105.709974) (xy 111.505492 -105.709974)
		)
		(stroke
			(width 0)
			(type solid)
		)
		(fill yes)
		(layer "In2.Cu")
		(net "M_K_DQS_DN<5>")
	)
	(gr_poly
		(pts
			(xy 111.509048 -56.785764) (xy 111.486696 -56.74741) (xy 111.324644 -56.644286) (xy 111.133382 -56.754776)
			(xy 111.141256 -56.9468) (xy 111.163608 -56.985154)
		)
		(stroke
			(width 0)
			(type solid)
		)
		(fill yes)
		(layer "In2.Cu")
		(net "M_G_DQS_DN<5>")
	)
	(gr_poly
		(pts
			(xy 111.510572 -48.238156) (xy 111.466122 -48.238156) (xy 111.273082 -48.327056) (xy 111.273082 -48.555656)
			(xy 111.466122 -48.644556) (xy 111.510572 -48.644556)
		)
		(stroke
			(width 0)
			(type solid)
		)
		(fill yes)
		(layer "In2.Cu")
		(net "M_G_DQ<42>")
	)
	(gr_poly
		(pts
			(xy 111.512858 -49.567846) (xy 111.586518 -49.368456) (xy 111.424974 -49.206912) (xy 111.225584 -49.280572)
			(xy 111.194088 -49.311814) (xy 111.481616 -49.599342)
		)
		(stroke
			(width 0)
			(type solid)
		)
		(fill yes)
		(layer "In2.Cu")
		(net "M_G_DQ<47>")
	)
	(gr_poly
		(pts
			(xy 111.558578 -103.11638) (xy 111.751618 -103.02748) (xy 111.751618 -102.79888) (xy 111.558578 -102.70998)
			(xy 111.514382 -102.70998) (xy 111.514382 -103.116634)
		)
		(stroke
			(width 0)
			(type solid)
		)
		(fill yes)
		(layer "In2.Cu")
		(net "M_K_DQS_DN<14>")
	)
	(gr_poly
		(pts
			(xy 111.56315 -99.633786) (xy 111.555022 -99.441762) (xy 111.533178 -99.403408) (xy 111.187484 -99.602798)
			(xy 111.209836 -99.641152) (xy 111.371888 -99.744022)
		)
		(stroke
			(width 0)
			(type solid)
		)
		(fill yes)
		(layer "In2.Cu")
		(net "M_K_DQ<45>")
	)
	(gr_poly
		(pts
			(xy 111.578136 -54.033928) (xy 111.578136 -53.812948) (xy 111.407956 -53.724048) (xy 111.363506 -53.724048)
			(xy 111.363506 -54.122828) (xy 111.407956 -54.122828)
		)
		(stroke
			(width 0)
			(type solid)
		)
		(fill yes)
		(layer "In2.Cu")
		(net "M_G_DQS_DN<14>")
	)
	(gr_poly
		(pts
			(xy 111.612172 -50.572924) (xy 111.567722 -50.572924) (xy 111.374682 -50.661824) (xy 111.374682 -50.890424)
			(xy 111.567722 -50.979324) (xy 111.612172 -50.979324)
		)
		(stroke
			(width 0)
			(type solid)
		)
		(fill yes)
		(layer "In2.Cu")
		(net "M_G_DQ<46>")
	)
	(gr_poly
		(pts
			(xy 111.692436 -99.186238) (xy 111.862616 -99.097338) (xy 111.862616 -98.876612) (xy 111.692436 -98.787712)
			(xy 111.64824 -98.787458) (xy 111.647986 -99.186492)
		)
		(stroke
			(width 0)
			(type solid)
		)
		(fill yes)
		(layer "In2.Cu")
		(net "M_K_DQ<45>")
	)
	(gr_poly
		(pts
			(xy 111.75365 -52.937664) (xy 111.785146 -52.906168) (xy 111.497872 -52.618894) (xy 111.466376 -52.65039)
			(xy 111.392716 -52.849526) (xy 111.554514 -53.011324)
		)
		(stroke
			(width 0)
			(type solid)
		)
		(fill yes)
		(layer "In2.Cu")
		(net "M_G_DQS_DN<5>")
	)
	(gr_poly
		(pts
			(xy 111.807244 -97.880932) (xy 111.78159 -97.844356) (xy 111.61141 -97.755964) (xy 111.430308 -97.88271)
			(xy 111.4552 -98.072956) (xy 111.4806 -98.109278)
		)
		(stroke
			(width 0)
			(type solid)
		)
		(fill yes)
		(layer "In2.Cu")
		(net "M_K_DQ<44>")
	)
	(gr_poly
		(pts
			(xy 111.895128 -101.317552) (xy 111.856774 -101.2952) (xy 111.645192 -101.275642) (xy 111.530892 -101.473762)
			(xy 111.653574 -101.647244) (xy 111.692182 -101.669342)
		)
		(stroke
			(width 0)
			(type solid)
		)
		(fill yes)
		(layer "In2.Cu")
		(net "M_K_DQS_DP<14>")
	)
	(gr_poly
		(pts
			(xy 111.898684 -55.705248) (xy 111.854234 -55.705248) (xy 111.684054 -55.794148) (xy 111.684054 -56.015128)
			(xy 111.854234 -56.104028) (xy 111.898684 -56.104028)
		)
		(stroke
			(width 0)
			(type solid)
		)
		(fill yes)
		(layer "In2.Cu")
		(net "M_G_DQS_DN<5>")
	)
	(gr_poly
		(pts
			(xy 111.933482 -105.621074) (xy 111.933482 -105.392474) (xy 111.740442 -105.303574) (xy 111.695992 -105.303574)
			(xy 111.695992 -105.709974) (xy 111.740442 -105.709974)
		)
		(stroke
			(width 0)
			(type solid)
		)
		(fill yes)
		(layer "In2.Cu")
		(net "M_K_DQS_DP<5>")
	)
	(gr_poly
		(pts
			(xy 111.938562 -48.555656) (xy 111.938562 -48.327056) (xy 111.745522 -48.238156) (xy 111.701072 -48.238156)
			(xy 111.701072 -48.644556) (xy 111.745522 -48.644556)
		)
		(stroke
			(width 0)
			(type solid)
		)
		(fill yes)
		(layer "In2.Cu")
		(net "M_G_DQ<43>")
	)
	(gr_poly
		(pts
			(xy 111.951262 -52.740052) (xy 112.024922 -52.540662) (xy 111.863378 -52.379118) (xy 111.663988 -52.452778)
			(xy 111.632492 -52.48402) (xy 111.92002 -52.771548)
		)
		(stroke
			(width 0)
			(type solid)
		)
		(fill yes)
		(layer "In2.Cu")
		(net "M_G_DQS_DP<5>")
	)
	(gr_poly
		(pts
			(xy 111.972852 -52.133754) (xy 112.004348 -52.102258) (xy 111.717074 -51.814984) (xy 111.685578 -51.84648)
			(xy 111.611918 -52.045616) (xy 111.773716 -52.207414)
		)
		(stroke
			(width 0)
			(type solid)
		)
		(fill yes)
		(layer "In2.Cu")
		(net "M_G_DQ<46>")
	)
	(gr_poly
		(pts
			(xy 112.016286 -104.100376) (xy 111.98479 -104.06888) (xy 111.7854 -103.99522) (xy 111.623856 -104.157018)
			(xy 111.697516 -104.356408) (xy 111.728758 -104.38765)
		)
		(stroke
			(width 0)
			(type solid)
		)
		(fill yes)
		(layer "In2.Cu")
		(net "M_K_DQS_DN<5>")
	)
	(gr_poly
		(pts
			(xy 112.038892 -53.709824) (xy 111.994442 -53.709824) (xy 111.801402 -53.798724) (xy 111.801402 -54.027324)
			(xy 111.994442 -54.116224) (xy 112.038892 -54.116224)
		)
		(stroke
			(width 0)
			(type solid)
		)
		(fill yes)
		(layer "In2.Cu")
		(net "M_G_DQS_DN<5>")
	)
	(gr_poly
		(pts
			(xy 112.040162 -51.373024) (xy 112.040162 -51.144424) (xy 111.847122 -51.055524) (xy 111.802672 -51.055524)
			(xy 111.802672 -51.461924) (xy 111.847122 -51.461924)
		)
		(stroke
			(width 0)
			(type solid)
		)
		(fill yes)
		(layer "In2.Cu")
		(net "M_G_DQ<47>")
	)
	(gr_poly
		(pts
			(xy 112.138968 -57.036716) (xy 112.13084 -56.844946) (xy 112.108996 -56.806592) (xy 111.763302 -57.005982)
			(xy 111.785654 -57.044336) (xy 111.947706 -57.147206)
		)
		(stroke
			(width 0)
			(type solid)
		)
		(fill yes)
		(layer "In2.Cu")
		(net "M_G_DQS_DP<5>")
	)
	(gr_poly
		(pts
			(xy 112.16259 -103.27259) (xy 112.11814 -103.27259) (xy 111.9251 -103.36149) (xy 111.9251 -103.59009)
			(xy 112.11814 -103.67899) (xy 112.16259 -103.67899)
		)
		(stroke
			(width 0)
			(type solid)
		)
		(fill yes)
		(layer "In2.Cu")
		(net "M_K_DQS_DN<5>")
	)
	(gr_poly
		(pts
			(xy 112.183164 -98.789998) (xy 112.138714 -98.789998) (xy 111.968534 -98.878898) (xy 111.968534 -99.099878)
			(xy 112.138714 -99.188778) (xy 112.183164 -99.188778)
		)
		(stroke
			(width 0)
			(type solid)
		)
		(fill yes)
		(layer "In2.Cu")
		(net "M_K_DQ<40>")
	)
	(gr_poly
		(pts
			(xy 112.221518 -101.608382) (xy 112.098836 -101.4349) (xy 112.060228 -101.412802) (xy 111.857282 -101.764592)
			(xy 111.895636 -101.786944) (xy 112.107218 -101.806502)
		)
		(stroke
			(width 0)
			(type solid)
		)
		(fill yes)
		(layer "In2.Cu")
		(net "M_K_DQS_DN<14>")
	)
	(gr_poly
		(pts
			(xy 112.256062 -104.465882) (xy 112.182402 -104.266492) (xy 112.150906 -104.234996) (xy 111.863632 -104.522524)
			(xy 111.894874 -104.553766) (xy 112.094264 -104.627426)
		)
		(stroke
			(width 0)
			(type solid)
		)
		(fill yes)
		(layer "In2.Cu")
		(net "M_K_DQS_DP<5>")
	)
	(gr_poly
		(pts
			(xy 112.266476 -56.588406) (xy 112.436656 -56.499506) (xy 112.436656 -56.278526) (xy 112.266476 -56.189626)
			(xy 112.22228 -56.189626) (xy 112.222026 -56.58866)
		)
		(stroke
			(width 0)
			(type solid)
		)
		(fill yes)
		(layer "In2.Cu")
		(net "M_G_DQS_DP<5>")
	)
	(gr_poly
		(pts
			(xy 112.273842 -49.699926) (xy 112.305338 -49.668684) (xy 112.01781 -49.381156) (xy 111.986568 -49.412652)
			(xy 111.912908 -49.612042) (xy 112.074452 -49.773586)
		)
		(stroke
			(width 0)
			(type solid)
		)
		(fill yes)
		(layer "In2.Cu")
		(net "M_G_DQ<42>")
	)
	(gr_poly
		(pts
			(xy 112.421924 -100.128324) (xy 112.413796 -99.936554) (xy 112.391698 -99.897946) (xy 112.046258 -100.09759)
			(xy 112.06861 -100.135944) (xy 112.230662 -100.238814)
		)
		(stroke
			(width 0)
			(type solid)
		)
		(fill yes)
		(layer "In2.Cu")
		(net "M_K_DQ<41>")
	)
	(gr_poly
		(pts
			(xy 112.43691 -55.519828) (xy 112.43691 -55.298848) (xy 112.26673 -55.209948) (xy 112.22228 -55.209948)
			(xy 112.22228 -55.608728) (xy 112.26673 -55.608728)
		)
		(stroke
			(width 0)
			(type solid)
		)
		(fill yes)
		(layer "In2.Cu")
		(net "M_G_DQS_DP<5>")
	)
	(gr_poly
		(pts
			(xy 112.466882 -54.027324) (xy 112.466882 -53.798724) (xy 112.273842 -53.709824) (xy 112.229392 -53.709824)
			(xy 112.229392 -54.116224) (xy 112.273842 -54.116224)
		)
		(stroke
			(width 0)
			(type solid)
		)
		(fill yes)
		(layer "In2.Cu")
		(net "M_G_DQS_DP<5>")
	)
	(gr_poly
		(pts
			(xy 112.471454 -49.502314) (xy 112.545114 -49.303178) (xy 112.383316 -49.14138) (xy 112.18418 -49.21504)
			(xy 112.152684 -49.246536) (xy 112.439958 -49.53381)
		)
		(stroke
			(width 0)
			(type solid)
		)
		(fill yes)
		(layer "In2.Cu")
		(net "M_G_DQ<43>")
	)
	(gr_poly
		(pts
			(xy 112.487456 -102.407466) (xy 112.45596 -102.37597) (xy 112.25657 -102.30231) (xy 112.095026 -102.463854)
			(xy 112.168686 -102.663244) (xy 112.199928 -102.69474)
		)
		(stroke
			(width 0)
			(type solid)
		)
		(fill yes)
		(layer "In2.Cu")
		(net "M_K_DQS_DN<5>")
	)
	(gr_poly
		(pts
			(xy 112.530636 -98.615754) (xy 112.530636 -98.394774) (xy 112.360456 -98.305874) (xy 112.316006 -98.305874)
			(xy 112.316006 -98.704654) (xy 112.360456 -98.704654)
		)
		(stroke
			(width 0)
			(type solid)
		)
		(fill yes)
		(layer "In2.Cu")
		(net "M_K_DQ<40>")
	)
	(gr_poly
		(pts
			(xy 112.59058 -103.59009) (xy 112.59058 -103.36149) (xy 112.39754 -103.27259) (xy 112.35309 -103.27259)
			(xy 112.35309 -103.67899) (xy 112.39754 -103.67899)
		)
		(stroke
			(width 0)
			(type solid)
		)
		(fill yes)
		(layer "In2.Cu")
		(net "M_K_DQS_DP<5>")
	)
	(gr_poly
		(pts
			(xy 112.608868 -97.243138) (xy 112.573308 -97.216468) (xy 112.38357 -97.185988) (xy 112.25149 -97.36328)
			(xy 112.334802 -97.536254) (xy 112.370362 -97.56267)
		)
		(stroke
			(width 0)
			(type solid)
		)
		(fill yes)
		(layer "In2.Cu")
		(net "M_K_DQ<40>")
	)
	(gr_poly
		(pts
			(xy 112.616488 -52.380642) (xy 112.690148 -52.181252) (xy 112.528604 -52.019708) (xy 112.329214 -52.093368)
			(xy 112.297718 -52.12461) (xy 112.585246 -52.412138)
		)
		(stroke
			(width 0)
			(type solid)
		)
		(fill yes)
		(layer "In2.Cu")
		(net "M_G_DQ<47>")
	)
	(gr_poly
		(pts
			(xy 112.641888 -100.370386) (xy 112.619536 -100.332032) (xy 112.457484 -100.229162) (xy 112.266222 -100.339652)
			(xy 112.27435 -100.531422) (xy 112.296448 -100.57003)
		)
		(stroke
			(width 0)
			(type solid)
		)
		(fill yes)
		(layer "In2.Cu")
		(net "M_K_DQS_DP<14>")
	)
	(gr_poly
		(pts
			(xy 112.673384 -52.834286) (xy 112.70488 -52.80279) (xy 112.417606 -52.515516) (xy 112.38611 -52.547012)
			(xy 112.31245 -52.746148) (xy 112.474248 -52.907946)
		)
		(stroke
			(width 0)
			(type solid)
		)
		(fill yes)
		(layer "In2.Cu")
		(net "M_G_DQ<46>")
	)
	(gr_poly
		(pts
			(xy 112.698784 -105.292652) (xy 112.654334 -105.292906) (xy 112.461294 -105.381806) (xy 112.461294 -105.610152)
			(xy 112.654334 -105.699052) (xy 112.698784 -105.699306)
		)
		(stroke
			(width 0)
			(type solid)
		)
		(fill yes)
		(layer "In2.Cu")
		(net "M_K_DQ<46>")
	)
	(gr_poly
		(pts
			(xy 112.765078 -50.185828) (xy 112.720628 -50.185828) (xy 112.527588 -50.274728) (xy 112.527588 -50.503328)
			(xy 112.720628 -50.592228) (xy 112.765078 -50.592228)
		)
		(stroke
			(width 0)
			(type solid)
		)
		(fill yes)
		(layer "In2.Cu")
		(net "M_G_DQ<42>")
	)
	(gr_poly
		(pts
			(xy 112.890046 -54.222142) (xy 112.845596 -54.222142) (xy 112.652556 -54.311042) (xy 112.652556 -54.539642)
			(xy 112.845596 -54.628542) (xy 112.890046 -54.628542)
		)
		(stroke
			(width 0)
			(type solid)
		)
		(fill yes)
		(layer "In2.Cu")
		(net "M_G_DQ<46>")
	)
	(gr_poly
		(pts
			(xy 112.890046 -53.231542) (xy 112.845596 -53.231542) (xy 112.652556 -53.320442) (xy 112.652556 -53.549042)
			(xy 112.845596 -53.637942) (xy 112.890046 -53.637942)
		)
		(stroke
			(width 0)
			(type solid)
		)
		(fill yes)
		(layer "In2.Cu")
		(net "M_G_DQ<46>")
	)
	(gr_poly
		(pts
			(xy 112.932972 -105.699052) (xy 113.126012 -105.610152) (xy 113.126012 -105.381806) (xy 112.932972 -105.292906)
			(xy 112.888776 -105.292652) (xy 112.888776 -105.699306)
		)
		(stroke
			(width 0)
			(type solid)
		)
		(fill yes)
		(layer "In2.Cu")
		(net "M_K_DQ<47>")
	)
	(gr_poly
		(pts
			(xy 113.041684 -99.297744) (xy 112.997234 -99.297744) (xy 112.827054 -99.386644) (xy 112.827054 -99.607624)
			(xy 112.997234 -99.696524) (xy 113.041684 -99.696524)
		)
		(stroke
			(width 0)
			(type solid)
		)
		(fill yes)
		(layer "In2.Cu")
		(net "M_K_DQS_DP<14>")
	)
	(gr_poly
		(pts
			(xy 113.041684 -98.307144) (xy 112.997234 -98.307144) (xy 112.827054 -98.396044) (xy 112.827054 -98.617024)
			(xy 112.997234 -98.705924) (xy 113.041684 -98.705924)
		)
		(stroke
			(width 0)
			(type solid)
		)
		(fill yes)
		(layer "In2.Cu")
		(net "M_K_DQS_DP<14>")
	)
	(gr_poly
		(pts
			(xy 113.075974 -57.111138) (xy 113.114328 -56.89346) (xy 112.962182 -56.776366) (xy 112.91824 -56.768746)
			(xy 112.849152 -57.16143) (xy 112.89284 -57.16905)
		)
		(stroke
			(width 0)
			(type solid)
		)
		(fill yes)
		(layer "In2.Cu")
		(net "M_G_DQ<47>")
	)
	(gr_poly
		(pts
			(xy 113.193068 -50.630328) (xy 113.193068 -50.401728) (xy 113.000028 -50.312828) (xy 112.955578 -50.312828)
			(xy 112.955578 -50.719228) (xy 113.000028 -50.719228)
		)
		(stroke
			(width 0)
			(type solid)
		)
		(fill yes)
		(layer "In2.Cu")
		(net "M_G_DQ<43>")
	)
	(gr_poly
		(pts
			(xy 113.29543 -56.015128) (xy 113.29543 -55.794148) (xy 113.12525 -55.705248) (xy 113.0808 -55.705248)
			(xy 113.0808 -56.104028) (xy 113.12525 -56.104028)
		)
		(stroke
			(width 0)
			(type solid)
		)
		(fill yes)
		(layer "In2.Cu")
		(net "M_G_DQ<47>")
	)
	(gr_poly
		(pts
			(xy 113.318036 -54.895242) (xy 113.318036 -54.666642) (xy 113.124996 -54.577742) (xy 113.080546 -54.577742)
			(xy 113.080546 -54.984142) (xy 113.124996 -54.984142)
		)
		(stroke
			(width 0)
			(type solid)
		)
		(fill yes)
		(layer "In2.Cu")
		(net "M_G_DQ<47>")
	)
	(gr_poly
		(pts
			(xy 113.318036 -53.904642) (xy 113.318036 -53.676042) (xy 113.124996 -53.587142) (xy 113.080546 -53.587142)
			(xy 113.080546 -53.993542) (xy 113.124996 -53.993542)
		)
		(stroke
			(width 0)
			(type solid)
		)
		(fill yes)
		(layer "In2.Cu")
		(net "M_G_DQ<47>")
	)
	(gr_poly
		(pts
			(xy 113.390172 -51.965606) (xy 113.421668 -51.93411) (xy 113.134394 -51.646836) (xy 113.102898 -51.678332)
			(xy 113.029238 -51.877468) (xy 113.191036 -52.039266)
		)
		(stroke
			(width 0)
			(type solid)
		)
		(fill yes)
		(layer "In2.Cu")
		(net "M_G_DQ<42>")
	)
	(gr_poly
		(pts
			(xy 113.409222 -104.305608) (xy 113.377726 -104.274366) (xy 113.178336 -104.200706) (xy 113.016792 -104.36225)
			(xy 113.090452 -104.56164) (xy 113.121694 -104.593136)
		)
		(stroke
			(width 0)
			(type solid)
		)
		(fill yes)
		(layer "In2.Cu")
		(net "M_K_DQ<46>")
	)
	(gr_poly
		(pts
			(xy 113.486692 -101.391974) (xy 113.442242 -101.391974) (xy 113.249202 -101.480874) (xy 113.249202 -101.709474)
			(xy 113.442242 -101.798374) (xy 113.486692 -101.798374)
		)
		(stroke
			(width 0)
			(type solid)
		)
		(fill yes)
		(layer "In2.Cu")
		(net "M_K_DQS_DN<5>")
	)
	(gr_poly
		(pts
			(xy 113.529364 -100.289106) (xy 113.426494 -100.127054) (xy 113.38814 -100.104702) (xy 113.188496 -100.450142)
			(xy 113.227104 -100.47224) (xy 113.418874 -100.480368)
		)
		(stroke
			(width 0)
			(type solid)
		)
		(fill yes)
		(layer "In2.Cu")
		(net "M_K_DQS_DN<14>")
	)
	(gr_poly
		(pts
			(xy 113.57991 -99.099878) (xy 113.57991 -98.878898) (xy 113.40973 -98.789998) (xy 113.36528 -98.789998)
			(xy 113.36528 -99.188778) (xy 113.40973 -99.188778)
		)
		(stroke
			(width 0)
			(type solid)
		)
		(fill yes)
		(layer "In2.Cu")
		(net "M_K_DQS_DN<14>")
	)
	(gr_poly
		(pts
			(xy 113.57991 -98.109278) (xy 113.57991 -97.888298) (xy 113.40973 -97.799398) (xy 113.36528 -97.799398)
			(xy 113.36528 -98.198178) (xy 113.40973 -98.198178)
		)
		(stroke
			(width 0)
			(type solid)
		)
		(fill yes)
		(layer "In2.Cu")
		(net "M_K_DQS_DN<14>")
	)
	(gr_poly
		(pts
			(xy 113.59007 -51.769518) (xy 113.66373 -51.570382) (xy 113.501932 -51.408584) (xy 113.302796 -51.482244)
			(xy 113.2713 -51.51374) (xy 113.558574 -51.801014)
		)
		(stroke
			(width 0)
			(type solid)
		)
		(fill yes)
		(layer "In2.Cu")
		(net "M_G_DQ<43>")
	)
	(gr_poly
		(pts
			(xy 113.595658 -102.350316) (xy 113.521998 -102.150926) (xy 113.490502 -102.11943) (xy 113.203228 -102.406704)
			(xy 113.234724 -102.4382) (xy 113.434114 -102.51186)
		)
		(stroke
			(width 0)
			(type solid)
		)
		(fill yes)
		(layer "In2.Cu")
		(net "M_K_DQS_DP<5>")
	)
	(gr_poly
		(pts
			(xy 113.615724 -55.711344) (xy 113.571274 -55.711344) (xy 113.401094 -55.800244) (xy 113.401094 -56.021224)
			(xy 113.571274 -56.110124) (xy 113.615724 -56.110124)
		)
		(stroke
			(width 0)
			(type solid)
		)
		(fill yes)
		(layer "In2.Cu")
		(net "M_G_DQ<42>")
	)
	(gr_poly
		(pts
			(xy 113.616232 -54.213506) (xy 113.571782 -54.213506) (xy 113.378742 -54.302406) (xy 113.378742 -54.531006)
			(xy 113.571782 -54.619906) (xy 113.616232 -54.619906)
		)
		(stroke
			(width 0)
			(type solid)
		)
		(fill yes)
		(layer "In2.Cu")
		(net "M_G_DQ<42>")
	)
	(gr_poly
		(pts
			(xy 113.616232 -53.222906) (xy 113.571782 -53.222906) (xy 113.378742 -53.311806) (xy 113.378742 -53.540406)
			(xy 113.571782 -53.629306) (xy 113.616232 -53.629306)
		)
		(stroke
			(width 0)
			(type solid)
		)
		(fill yes)
		(layer "In2.Cu")
		(net "M_G_DQ<42>")
	)
	(gr_poly
		(pts
			(xy 113.64849 -104.67086) (xy 113.57483 -104.47147) (xy 113.543588 -104.439974) (xy 113.25606 -104.727502)
			(xy 113.287556 -104.758744) (xy 113.486946 -104.832404)
		)
		(stroke
			(width 0)
			(type solid)
		)
		(fill yes)
		(layer "In2.Cu")
		(net "M_K_DQ<47>")
	)
	(gr_poly
		(pts
			(xy 113.895886 -100.722176) (xy 113.86439 -100.69068) (xy 113.665 -100.61702) (xy 113.503456 -100.778818)
			(xy 113.577116 -100.978208) (xy 113.608358 -101.00945)
		)
		(stroke
			(width 0)
			(type solid)
		)
		(fill yes)
		(layer "In2.Cu")
		(net "M_K_DQS_DN<5>")
	)
	(gr_poly
		(pts
			(xy 113.926874 -100.295202) (xy 113.966244 -100.275136) (xy 113.78057 -99.91344) (xy 113.740946 -99.93376)
			(xy 113.609882 -100.101146) (xy 113.71453 -100.304346)
		)
		(stroke
			(width 0)
			(type solid)
		)
		(fill yes)
		(layer "In2.Cu")
		(net "M_K_DQS_DN<5>")
	)
	(gr_poly
		(pts
			(xy 114.036094 -105.141776) (xy 113.991644 -105.141776) (xy 113.798604 -105.230676) (xy 113.798604 -105.459276)
			(xy 113.991644 -105.548176) (xy 114.036094 -105.548176)
		)
		(stroke
			(width 0)
			(type solid)
		)
		(fill yes)
		(layer "In2.Cu")
		(net "M_K_DQ<42>")
	)
	(gr_poly
		(pts
			(xy 114.044222 -54.531006) (xy 114.044222 -54.302406) (xy 113.851182 -54.213506) (xy 113.806732 -54.213506)
			(xy 113.806732 -54.619906) (xy 113.851182 -54.619906)
		)
		(stroke
			(width 0)
			(type solid)
		)
		(fill yes)
		(layer "In2.Cu")
		(net "M_G_DQ<43>")
	)
	(gr_poly
		(pts
			(xy 114.044222 -53.540406) (xy 114.044222 -53.311806) (xy 113.851182 -53.222906) (xy 113.806732 -53.222906)
			(xy 113.806732 -53.629306) (xy 113.851182 -53.629306)
		)
		(stroke
			(width 0)
			(type solid)
		)
		(fill yes)
		(layer "In2.Cu")
		(net "M_G_DQ<43>")
	)
	(gr_poly
		(pts
			(xy 114.046 -102.76713) (xy 114.00155 -102.76713) (xy 113.80851 -102.85603) (xy 113.80851 -103.08463)
			(xy 114.00155 -103.17353) (xy 114.046 -103.17353)
		)
		(stroke
			(width 0)
			(type solid)
		)
		(fill yes)
		(layer "In2.Cu")
		(net "M_K_DQ<46>")
	)
	(gr_poly
		(pts
			(xy 114.090958 -97.800668) (xy 114.046508 -97.800668) (xy 113.876328 -97.889568) (xy 113.876328 -98.110548)
			(xy 114.046508 -98.199448) (xy 114.090958 -98.199448)
		)
		(stroke
			(width 0)
			(type solid)
		)
		(fill yes)
		(layer "In2.Cu")
		(net "M_K_DQ<46>")
	)
	(gr_poly
		(pts
			(xy 114.135662 -101.087682) (xy 114.062002 -100.888292) (xy 114.030506 -100.856796) (xy 113.743232 -101.144324)
			(xy 113.774474 -101.175566) (xy 113.973864 -101.249226)
		)
		(stroke
			(width 0)
			(type solid)
		)
		(fill yes)
		(layer "In2.Cu")
		(net "M_K_DQS_DP<5>")
	)
	(gr_poly
		(pts
			(xy 114.144044 -50.056034) (xy 114.17554 -50.024792) (xy 113.888012 -49.737264) (xy 113.85677 -49.76876)
			(xy 113.78311 -49.96815) (xy 113.944654 -50.129694)
		)
		(stroke
			(width 0)
			(type solid)
		)
		(fill yes)
		(layer "In2.Cu")
		(net "M_G_DQ<52>")
	)
	(gr_poly
		(pts
			(xy 114.15395 -56.504078) (xy 114.15395 -56.283098) (xy 113.98377 -56.194198) (xy 113.93932 -56.194198)
			(xy 113.93932 -56.592978) (xy 113.98377 -56.592978)
		)
		(stroke
			(width 0)
			(type solid)
		)
		(fill yes)
		(layer "In2.Cu")
		(net "M_G_DQ<43>")
	)
	(gr_poly
		(pts
			(xy 114.15395 -55.513478) (xy 114.15395 -55.292498) (xy 113.98377 -55.203598) (xy 113.93932 -55.203598)
			(xy 113.93932 -55.602378) (xy 113.98377 -55.602378)
		)
		(stroke
			(width 0)
			(type solid)
		)
		(fill yes)
		(layer "In2.Cu")
		(net "M_G_DQ<43>")
	)
	(gr_poly
		(pts
			(xy 114.243104 -50.531014) (xy 114.198654 -50.531014) (xy 114.005614 -50.619914) (xy 114.005614 -50.848514)
			(xy 114.198654 -50.937414) (xy 114.243104 -50.937414)
		)
		(stroke
			(width 0)
			(type solid)
		)
		(fill yes)
		(layer "In2.Cu")
		(net "M_G_DQ<52>")
	)
	(gr_poly
		(pts
			(xy 114.40287 -49.919382) (xy 114.47653 -49.719992) (xy 114.314986 -49.558448) (xy 114.115596 -49.632108)
			(xy 114.0841 -49.66335) (xy 114.371628 -49.950878)
		)
		(stroke
			(width 0)
			(type solid)
		)
		(fill yes)
		(layer "In2.Cu")
		(net "M_G_DQ<53>")
	)
	(gr_poly
		(pts
			(xy 114.429032 -100.599748) (xy 114.429794 -100.378768) (xy 114.259614 -100.28936) (xy 114.215164 -100.28936)
			(xy 114.214148 -100.687886) (xy 114.258598 -100.68814)
		)
		(stroke
			(width 0)
			(type solid)
		)
		(fill yes)
		(layer "In2.Cu")
		(net "M_K_DQS_DP<5>")
	)
	(gr_poly
		(pts
			(xy 114.43843 -98.617024) (xy 114.43843 -98.396044) (xy 114.26825 -98.307144) (xy 114.2238 -98.307144)
			(xy 114.2238 -98.705924) (xy 114.26825 -98.705924)
		)
		(stroke
			(width 0)
			(type solid)
		)
		(fill yes)
		(layer "In2.Cu")
		(net "M_K_DQ<46>")
	)
	(gr_poly
		(pts
			(xy 114.438684 -51.353974) (xy 114.394234 -51.353974) (xy 114.201194 -51.442874) (xy 114.201194 -51.671474)
			(xy 114.394234 -51.760374) (xy 114.438684 -51.760374)
		)
		(stroke
			(width 0)
			(type solid)
		)
		(fill yes)
		(layer "In2.Cu")
		(net "M_G_DQ<52>")
	)
	(gr_poly
		(pts
			(xy 114.463576 -105.459276) (xy 114.463576 -105.230676) (xy 114.270536 -105.141776) (xy 114.226086 -105.141776)
			(xy 114.226086 -105.548176) (xy 114.270536 -105.548176)
		)
		(stroke
			(width 0)
			(type solid)
		)
		(fill yes)
		(layer "In2.Cu")
		(net "M_K_DQ<43>")
	)
	(gr_poly
		(pts
			(xy 114.473482 -103.08463) (xy 114.473482 -102.85603) (xy 114.280442 -102.76713) (xy 114.235992 -102.76713)
			(xy 114.235992 -103.17353) (xy 114.280442 -103.17353)
		)
		(stroke
			(width 0)
			(type solid)
		)
		(fill yes)
		(layer "In2.Cu")
		(net "M_K_DQ<47>")
	)
	(gr_poly
		(pts
			(xy 114.474244 -55.203598) (xy 114.429794 -55.203598) (xy 114.259614 -55.292498) (xy 114.259614 -55.513478)
			(xy 114.429794 -55.602378) (xy 114.474244 -55.602378)
		)
		(stroke
			(width 0)
			(type solid)
		)
		(fill yes)
		(layer "In2.Cu")
		(net "M_G_DQ<52>")
	)
	(gr_poly
		(pts
			(xy 114.474244 -54.212998) (xy 114.429794 -54.212998) (xy 114.259614 -54.301898) (xy 114.259614 -54.522878)
			(xy 114.429794 -54.611778) (xy 114.474244 -54.611778)
		)
		(stroke
			(width 0)
			(type solid)
		)
		(fill yes)
		(layer "In2.Cu")
		(net "M_G_DQ<52>")
	)
	(gr_poly
		(pts
			(xy 114.611404 -104.158796) (xy 114.579908 -104.127554) (xy 114.380518 -104.053894) (xy 114.218974 -104.215438)
			(xy 114.292634 -104.414828) (xy 114.323876 -104.446324)
		)
		(stroke
			(width 0)
			(type solid)
		)
		(fill yes)
		(layer "In2.Cu")
		(net "M_K_DQ<42>")
	)
	(gr_poly
		(pts
			(xy 114.618008 -53.212492) (xy 114.573558 -53.212492) (xy 114.380518 -53.301392) (xy 114.380518 -53.529992)
			(xy 114.573558 -53.618892) (xy 114.618008 -53.618892)
		)
		(stroke
			(width 0)
			(type solid)
		)
		(fill yes)
		(layer "In2.Cu")
		(net "M_G_DQ<52>")
	)
	(gr_poly
		(pts
			(xy 114.618008 -52.221892) (xy 114.573558 -52.221892) (xy 114.380518 -52.310792) (xy 114.380518 -52.539392)
			(xy 114.573558 -52.628292) (xy 114.618008 -52.628292)
		)
		(stroke
			(width 0)
			(type solid)
		)
		(fill yes)
		(layer "In2.Cu")
		(net "M_G_DQ<52>")
	)
	(gr_poly
		(pts
			(xy 114.671094 -50.594514) (xy 114.671094 -50.365914) (xy 114.478054 -50.277014) (xy 114.433604 -50.277014)
			(xy 114.433604 -50.683414) (xy 114.478054 -50.683414)
		)
		(stroke
			(width 0)
			(type solid)
		)
		(fill yes)
		(layer "In2.Cu")
		(net "M_G_DQ<53>")
	)
	(gr_poly
		(pts
			(xy 114.680492 -101.723698) (xy 114.648996 -101.692202) (xy 114.44986 -101.618542) (xy 114.288062 -101.78034)
			(xy 114.361722 -101.979476) (xy 114.393218 -102.010972)
		)
		(stroke
			(width 0)
			(type solid)
		)
		(fill yes)
		(layer "In2.Cu")
		(net "M_K_DQ<46>")
	)
	(gr_poly
		(pts
			(xy 114.823494 -103.363776) (xy 114.779044 -103.363776) (xy 114.586004 -103.452676) (xy 114.586004 -103.681276)
			(xy 114.779044 -103.770176) (xy 114.823494 -103.770176)
		)
		(stroke
			(width 0)
			(type solid)
		)
		(fill yes)
		(layer "In2.Cu")
		(net "M_K_DQ<42>")
	)
	(gr_poly
		(pts
			(xy 114.850672 -104.524048) (xy 114.777012 -104.324658) (xy 114.74577 -104.293162) (xy 114.458242 -104.58069)
			(xy 114.489738 -104.612186) (xy 114.689128 -104.685592)
		)
		(stroke
			(width 0)
			(type solid)
		)
		(fill yes)
		(layer "In2.Cu")
		(net "M_K_DQ<43>")
	)
	(gr_poly
		(pts
			(xy 114.866674 -51.671474) (xy 114.866674 -51.442874) (xy 114.673634 -51.353974) (xy 114.629184 -51.353974)
			(xy 114.629184 -51.760374) (xy 114.673634 -51.760374)
		)
		(stroke
			(width 0)
			(type solid)
		)
		(fill yes)
		(layer "In2.Cu")
		(net "M_G_DQ<53>")
	)
	(gr_poly
		(pts
			(xy 114.891312 -100.26142) (xy 114.846862 -100.26142) (xy 114.653822 -100.35032) (xy 114.653822 -100.57892)
			(xy 114.846862 -100.66782) (xy 114.891312 -100.66782)
		)
		(stroke
			(width 0)
			(type solid)
		)
		(fill yes)
		(layer "In2.Cu")
		(net "M_K_DQ<46>")
	)
	(gr_poly
		(pts
			(xy 114.920014 -102.088696) (xy 114.846354 -101.88956) (xy 114.814858 -101.858064) (xy 114.527584 -102.145338)
			(xy 114.55908 -102.176834) (xy 114.758216 -102.250494)
		)
		(stroke
			(width 0)
			(type solid)
		)
		(fill yes)
		(layer "In2.Cu")
		(net "M_K_DQ<47>")
	)
	(gr_poly
		(pts
			(xy 114.949478 -98.305874) (xy 114.905028 -98.305874) (xy 114.734848 -98.394774) (xy 114.734848 -98.615754)
			(xy 114.905028 -98.704654) (xy 114.949478 -98.704654)
		)
		(stroke
			(width 0)
			(type solid)
		)
		(fill yes)
		(layer "In2.Cu")
		(net "M_K_DQ<42>")
	)
	(gr_poly
		(pts
			(xy 115.01247 -55.030624) (xy 115.01247 -54.809644) (xy 114.84229 -54.720744) (xy 114.79784 -54.720744)
			(xy 114.79784 -55.119524) (xy 114.84229 -55.119524)
		)
		(stroke
			(width 0)
			(type solid)
		)
		(fill yes)
		(layer "In2.Cu")
		(net "M_G_DQ<53>")
	)
	(gr_poly
		(pts
			(xy 115.045998 -53.529992) (xy 115.045998 -53.301392) (xy 114.852958 -53.212492) (xy 114.808508 -53.212492)
			(xy 114.808508 -53.618892) (xy 114.852958 -53.618892)
		)
		(stroke
			(width 0)
			(type solid)
		)
		(fill yes)
		(layer "In2.Cu")
		(net "M_G_DQ<53>")
	)
	(gr_poly
		(pts
			(xy 115.045998 -52.539392) (xy 115.045998 -52.310792) (xy 114.852958 -52.221892) (xy 114.808508 -52.221892)
			(xy 114.808508 -52.628292) (xy 114.852958 -52.628292)
		)
		(stroke
			(width 0)
			(type solid)
		)
		(fill yes)
		(layer "In2.Cu")
		(net "M_G_DQ<53>")
	)
	(gr_poly
		(pts
			(xy 115.086892 -49.354486) (xy 115.042442 -49.354486) (xy 114.849402 -49.443386) (xy 114.849402 -49.671986)
			(xy 115.042442 -49.760886) (xy 115.086892 -49.760886)
		)
		(stroke
			(width 0)
			(type solid)
		)
		(fill yes)
		(layer "In2.Cu")
		(net "M_G_DQ<48>")
	)
	(gr_poly
		(pts
			(xy 115.086892 -48.363886) (xy 115.042442 -48.363886) (xy 114.849402 -48.452786) (xy 114.849402 -48.681386)
			(xy 115.042442 -48.770286) (xy 115.086892 -48.770286)
		)
		(stroke
			(width 0)
			(type solid)
		)
		(fill yes)
		(layer "In2.Cu")
		(net "M_G_DQ<48>")
	)
	(gr_poly
		(pts
			(xy 115.162076 -50.974752) (xy 115.117626 -50.974752) (xy 114.924586 -51.063652) (xy 114.924586 -51.292252)
			(xy 115.117626 -51.381152) (xy 115.162076 -51.381152)
		)
		(stroke
			(width 0)
			(type solid)
		)
		(fill yes)
		(layer "In2.Cu")
		(net "M_G_DQ<48>")
	)
	(gr_poly
		(pts
			(xy 115.250976 -103.681276) (xy 115.250976 -103.452676) (xy 115.057936 -103.363776) (xy 115.013486 -103.363776)
			(xy 115.013486 -103.770176) (xy 115.057936 -103.770176)
		)
		(stroke
			(width 0)
			(type solid)
		)
		(fill yes)
		(layer "In2.Cu")
		(net "M_K_DQ<43>")
	)
	(gr_poly
		(pts
			(xy 115.318794 -101.18852) (xy 115.318794 -100.95992) (xy 115.125754 -100.87102) (xy 115.081304 -100.87102)
			(xy 115.081304 -101.27742) (xy 115.125754 -101.27742)
		)
		(stroke
			(width 0)
			(type solid)
		)
		(fill yes)
		(layer "In2.Cu")
		(net "M_K_DQ<47>")
	)
	(gr_poly
		(pts
			(xy 115.318794 -100.19792) (xy 115.318794 -99.96932) (xy 115.125754 -99.88042) (xy 115.081304 -99.88042)
			(xy 115.081304 -100.28682) (xy 115.125754 -100.28682)
		)
		(stroke
			(width 0)
			(type solid)
		)
		(fill yes)
		(layer "In2.Cu")
		(net "M_K_DQ<47>")
	)
	(gr_poly
		(pts
			(xy 115.322604 -102.329996) (xy 115.291108 -102.298754) (xy 115.091718 -102.225094) (xy 114.930174 -102.386638)
			(xy 115.003834 -102.586028) (xy 115.035076 -102.617524)
		)
		(stroke
			(width 0)
			(type solid)
		)
		(fill yes)
		(layer "In2.Cu")
		(net "M_K_DQ<42>")
	)
	(gr_poly
		(pts
			(xy 115.332764 -54.720744) (xy 115.288314 -54.720744) (xy 115.118134 -54.809644) (xy 115.118134 -55.030624)
			(xy 115.288314 -55.119524) (xy 115.332764 -55.119524)
		)
		(stroke
			(width 0)
			(type solid)
		)
		(fill yes)
		(layer "In2.Cu")
		(net "M_G_DQ<48>")
	)
	(gr_poly
		(pts
			(xy 115.385088 -53.079904) (xy 115.340638 -53.079904) (xy 115.147598 -53.168804) (xy 115.147598 -53.397404)
			(xy 115.340638 -53.486304) (xy 115.385088 -53.486304)
		)
		(stroke
			(width 0)
			(type solid)
		)
		(fill yes)
		(layer "In2.Cu")
		(net "M_G_DQ<48>")
	)
	(gr_poly
		(pts
			(xy 115.385088 -52.089304) (xy 115.340638 -52.089304) (xy 115.147598 -52.178204) (xy 115.147598 -52.406804)
			(xy 115.340638 -52.495704) (xy 115.385088 -52.495704)
		)
		(stroke
			(width 0)
			(type solid)
		)
		(fill yes)
		(layer "In2.Cu")
		(net "M_G_DQ<48>")
	)
	(gr_poly
		(pts
			(xy 115.514882 -49.671986) (xy 115.514882 -49.443386) (xy 115.321842 -49.354486) (xy 115.277392 -49.354486)
			(xy 115.277392 -49.760886) (xy 115.321842 -49.760886)
		)
		(stroke
			(width 0)
			(type solid)
		)
		(fill yes)
		(layer "In2.Cu")
		(net "M_G_DQ<49>")
	)
	(gr_poly
		(pts
			(xy 115.514882 -48.681386) (xy 115.514882 -48.452786) (xy 115.321842 -48.363886) (xy 115.277392 -48.363886)
			(xy 115.277392 -48.770286) (xy 115.321842 -48.770286)
		)
		(stroke
			(width 0)
			(type solid)
		)
		(fill yes)
		(layer "In2.Cu")
		(net "M_G_DQ<49>")
	)
	(gr_poly
		(pts
			(xy 115.561364 -104.536494) (xy 115.516914 -104.536494) (xy 115.323874 -104.625394) (xy 115.323874 -104.853994)
			(xy 115.516914 -104.942894) (xy 115.561364 -104.942894)
		)
		(stroke
			(width 0)
			(type solid)
		)
		(fill yes)
		(layer "In2.Cu")
		(net "M_K_DQ<52>")
	)
	(gr_poly
		(pts
			(xy 115.561872 -102.695248) (xy 115.488212 -102.495858) (xy 115.45697 -102.464362) (xy 115.169442 -102.75189)
			(xy 115.200938 -102.783386) (xy 115.400328 -102.856792)
		)
		(stroke
			(width 0)
			(type solid)
		)
		(fill yes)
		(layer "In2.Cu")
		(net "M_K_DQ<43>")
	)
	(gr_poly
		(pts
			(xy 115.590066 -51.292252) (xy 115.590066 -51.063652) (xy 115.397026 -50.974752) (xy 115.352576 -50.974752)
			(xy 115.352576 -51.381152) (xy 115.397026 -51.381152)
		)
		(stroke
			(width 0)
			(type solid)
		)
		(fill yes)
		(layer "In2.Cu")
		(net "M_G_DQ<49>")
	)
	(gr_poly
		(pts
			(xy 115.666774 -101.495606) (xy 115.622324 -101.495606) (xy 115.429284 -101.584506) (xy 115.429284 -101.813106)
			(xy 115.622324 -101.902006) (xy 115.666774 -101.902006)
		)
		(stroke
			(width 0)
			(type solid)
		)
		(fill yes)
		(layer "In2.Cu")
		(net "M_K_DQ<42>")
	)
	(gr_poly
		(pts
			(xy 115.666774 -100.505006) (xy 115.622324 -100.505006) (xy 115.429284 -100.593906) (xy 115.429284 -100.822506)
			(xy 115.622324 -100.911406) (xy 115.666774 -100.911406)
		)
		(stroke
			(width 0)
			(type solid)
		)
		(fill yes)
		(layer "In2.Cu")
		(net "M_K_DQ<42>")
	)
	(gr_poly
		(pts
			(xy 115.813078 -53.397404) (xy 115.813078 -53.168804) (xy 115.620038 -53.079904) (xy 115.575588 -53.079904)
			(xy 115.575588 -53.486304) (xy 115.620038 -53.486304)
		)
		(stroke
			(width 0)
			(type solid)
		)
		(fill yes)
		(layer "In2.Cu")
		(net "M_G_DQ<49>")
	)
	(gr_poly
		(pts
			(xy 115.813078 -52.406804) (xy 115.813078 -52.178204) (xy 115.620038 -52.089304) (xy 115.575588 -52.089304)
			(xy 115.575588 -52.495704) (xy 115.620038 -52.495704)
		)
		(stroke
			(width 0)
			(type solid)
		)
		(fill yes)
		(layer "In2.Cu")
		(net "M_G_DQ<49>")
	)
	(gr_poly
		(pts
			(xy 115.87099 -54.522878) (xy 115.87099 -54.301898) (xy 115.70081 -54.212998) (xy 115.65636 -54.212998)
			(xy 115.65636 -54.611778) (xy 115.70081 -54.611778)
		)
		(stroke
			(width 0)
			(type solid)
		)
		(fill yes)
		(layer "In2.Cu")
		(net "M_G_DQ<49>")
	)
	(gr_poly
		(pts
			(xy 115.989354 -104.853994) (xy 115.989354 -104.625394) (xy 115.796314 -104.536494) (xy 115.751864 -104.536494)
			(xy 115.751864 -104.942894) (xy 115.796314 -104.942894)
		)
		(stroke
			(width 0)
			(type solid)
		)
		(fill yes)
		(layer "In2.Cu")
		(net "M_K_DQ<53>")
	)
	(gr_poly
		(pts
			(xy 116.094256 -101.813106) (xy 116.094256 -101.584506) (xy 115.901216 -101.495606) (xy 115.856766 -101.495606)
			(xy 115.856766 -101.902006) (xy 115.901216 -101.902006)
		)
		(stroke
			(width 0)
			(type solid)
		)
		(fill yes)
		(layer "In2.Cu")
		(net "M_K_DQ<43>")
	)
	(gr_poly
		(pts
			(xy 116.094256 -100.822506) (xy 116.094256 -100.593906) (xy 115.901216 -100.505006) (xy 115.856766 -100.505006)
			(xy 115.856766 -100.911406) (xy 115.901216 -100.911406)
		)
		(stroke
			(width 0)
			(type solid)
		)
		(fill yes)
		(layer "In2.Cu")
		(net "M_K_DQ<43>")
	)
	(gr_poly
		(pts
			(xy 116.153946 -99.973638) (xy 116.154454 -99.752658) (xy 115.984274 -99.663504) (xy 115.939824 -99.663504)
			(xy 115.939062 -100.06203) (xy 115.983512 -100.062284)
		)
		(stroke
			(width 0)
			(type solid)
		)
		(fill yes)
		(layer "In2.Cu")
		(net "M_K_DQ<43>")
	)
	(gr_poly
		(pts
			(xy 116.162074 -103.694484) (xy 116.130578 -103.662988) (xy 115.931442 -103.589328) (xy 115.769644 -103.751126)
			(xy 115.843304 -103.950262) (xy 115.8748 -103.981758)
		)
		(stroke
			(width 0)
			(type solid)
		)
		(fill yes)
		(layer "In2.Cu")
		(net "M_K_DQ<52>")
	)
	(gr_poly
		(pts
			(xy 116.191284 -54.212998) (xy 116.146834 -54.212998) (xy 115.976654 -54.301898) (xy 115.976654 -54.522878)
			(xy 116.146834 -54.611778) (xy 116.191284 -54.611778)
		)
		(stroke
			(width 0)
			(type solid)
		)
		(fill yes)
		(layer "In2.Cu")
		(net "M_G_DQS_DP<15>")
	)
	(gr_poly
		(pts
			(xy 116.219732 -51.776884) (xy 116.251228 -51.745642) (xy 115.9637 -51.458114) (xy 115.932458 -51.48961)
			(xy 115.858798 -51.689) (xy 116.020342 -51.850544)
		)
		(stroke
			(width 0)
			(type solid)
		)
		(fill yes)
		(layer "In2.Cu")
		(net "M_G_DQS_DP<15>")
	)
	(gr_poly
		(pts
			(xy 116.229638 -49.558194) (xy 116.185188 -49.558194) (xy 115.992148 -49.647094) (xy 115.992148 -49.875694)
			(xy 116.185188 -49.964594) (xy 116.229638 -49.964594)
		)
		(stroke
			(width 0)
			(type solid)
		)
		(fill yes)
		(layer "In2.Cu")
		(net "M_G_DQS_DP<15>")
	)
	(gr_poly
		(pts
			(xy 116.229638 -48.567594) (xy 116.185188 -48.567594) (xy 115.992148 -48.656494) (xy 115.992148 -48.885094)
			(xy 116.185188 -48.973994) (xy 116.229638 -48.973994)
		)
		(stroke
			(width 0)
			(type solid)
		)
		(fill yes)
		(layer "In2.Cu")
		(net "M_G_DQS_DP<15>")
	)
	(gr_poly
		(pts
			(xy 116.326666 -56.374538) (xy 116.285264 -56.187086) (xy 116.256816 -56.15305) (xy 115.951254 -56.409336)
			(xy 115.979956 -56.443372) (xy 116.157502 -56.516524)
		)
		(stroke
			(width 0)
			(type solid)
		)
		(fill yes)
		(layer "In2.Cu")
		(net "M_G_DQ<49>")
	)
	(gr_poly
		(pts
			(xy 116.328952 -53.056028) (xy 116.284502 -53.056028) (xy 116.091462 -53.144928) (xy 116.091462 -53.373528)
			(xy 116.284502 -53.462428) (xy 116.328952 -53.462428)
		)
		(stroke
			(width 0)
			(type solid)
		)
		(fill yes)
		(layer "In2.Cu")
		(net "M_G_DQS_DP<15>")
	)
	(gr_poly
		(pts
			(xy 116.328952 -52.192428) (xy 116.284502 -52.192428) (xy 116.091462 -52.281328) (xy 116.091462 -52.509928)
			(xy 116.284502 -52.598828) (xy 116.328952 -52.598828)
		)
		(stroke
			(width 0)
			(type solid)
		)
		(fill yes)
		(layer "In2.Cu")
		(net "M_G_DQS_DP<15>")
	)
	(gr_poly
		(pts
			(xy 116.401596 -104.059482) (xy 116.327936 -103.860346) (xy 116.29644 -103.82885) (xy 116.009166 -104.116124)
			(xy 116.040662 -104.14762) (xy 116.239798 -104.22128)
		)
		(stroke
			(width 0)
			(type solid)
		)
		(fill yes)
		(layer "In2.Cu")
		(net "M_K_DQ<53>")
	)
	(gr_poly
		(pts
			(xy 116.47551 -102.757478) (xy 116.43106 -102.757478) (xy 116.23802 -102.846378) (xy 116.23802 -103.074978)
			(xy 116.43106 -103.163878) (xy 116.47551 -103.163878)
		)
		(stroke
			(width 0)
			(type solid)
		)
		(fill yes)
		(layer "In2.Cu")
		(net "M_K_DQ<52>")
	)
	(gr_poly
		(pts
			(xy 116.475764 -101.281484) (xy 116.431314 -101.281484) (xy 116.261134 -101.370384) (xy 116.261134 -101.591364)
			(xy 116.431314 -101.680264) (xy 116.475764 -101.680264)
		)
		(stroke
			(width 0)
			(type solid)
		)
		(fill yes)
		(layer "In2.Cu")
		(net "M_K_DQ<52>")
	)
	(gr_poly
		(pts
			(xy 116.475764 -100.290884) (xy 116.431314 -100.290884) (xy 116.261134 -100.379784) (xy 116.261134 -100.600764)
			(xy 116.431314 -100.689664) (xy 116.475764 -100.689664)
		)
		(stroke
			(width 0)
			(type solid)
		)
		(fill yes)
		(layer "In2.Cu")
		(net "M_K_DQ<52>")
	)
	(gr_poly
		(pts
			(xy 116.475764 -99.300284) (xy 116.431314 -99.300284) (xy 116.261134 -99.389184) (xy 116.261134 -99.610164)
			(xy 116.431314 -99.699064) (xy 116.475764 -99.699064)
		)
		(stroke
			(width 0)
			(type solid)
		)
		(fill yes)
		(layer "In2.Cu")
		(net "M_K_DQ<52>")
	)
	(gr_poly
		(pts
			(xy 116.475764 -98.309684) (xy 116.431314 -98.309684) (xy 116.261134 -98.398584) (xy 116.261134 -98.619564)
			(xy 116.431314 -98.708464) (xy 116.475764 -98.708464)
		)
		(stroke
			(width 0)
			(type solid)
		)
		(fill yes)
		(layer "In2.Cu")
		(net "M_K_DQ<52>")
	)
	(gr_poly
		(pts
			(xy 116.507006 -51.669188) (xy 116.580666 -51.469798) (xy 116.419122 -51.308254) (xy 116.219732 -51.381914)
			(xy 116.188236 -51.413156) (xy 116.475764 -51.700684)
		)
		(stroke
			(width 0)
			(type solid)
		)
		(fill yes)
		(layer "In2.Cu")
		(net "M_G_DQS_DN<15>")
	)
	(gr_poly
		(pts
			(xy 116.657628 -49.875694) (xy 116.657628 -49.647094) (xy 116.464588 -49.558194) (xy 116.420138 -49.558194)
			(xy 116.420138 -49.964594) (xy 116.464588 -49.964594)
		)
		(stroke
			(width 0)
			(type solid)
		)
		(fill yes)
		(layer "In2.Cu")
		(net "M_G_DQS_DN<15>")
	)
	(gr_poly
		(pts
			(xy 116.657628 -48.885094) (xy 116.657628 -48.656494) (xy 116.464588 -48.567594) (xy 116.420138 -48.567594)
			(xy 116.420138 -48.973994) (xy 116.464588 -48.973994)
		)
		(stroke
			(width 0)
			(type solid)
		)
		(fill yes)
		(layer "In2.Cu")
		(net "M_G_DQS_DN<15>")
	)
	(gr_poly
		(pts
			(xy 116.756942 -53.881528) (xy 116.756942 -53.652928) (xy 116.563902 -53.564028) (xy 116.519452 -53.564028)
			(xy 116.519452 -53.970428) (xy 116.563902 -53.970428)
		)
		(stroke
			(width 0)
			(type solid)
		)
		(fill yes)
		(layer "In2.Cu")
		(net "M_G_DQS_DN<15>")
	)
	(gr_poly
		(pts
			(xy 116.756942 -52.890928) (xy 116.756942 -52.662328) (xy 116.563902 -52.573428) (xy 116.519452 -52.573428)
			(xy 116.519452 -52.979828) (xy 116.563902 -52.979828)
		)
		(stroke
			(width 0)
			(type solid)
		)
		(fill yes)
		(layer "In2.Cu")
		(net "M_G_DQS_DN<15>")
	)
	(gr_poly
		(pts
			(xy 116.903754 -103.074978) (xy 116.903754 -102.846378) (xy 116.710714 -102.757478) (xy 116.666264 -102.757478)
			(xy 116.666264 -103.163878) (xy 116.710714 -103.163878)
		)
		(stroke
			(width 0)
			(type solid)
		)
		(fill yes)
		(layer "In2.Cu")
		(net "M_K_DQ<53>")
	)
	(gr_poly
		(pts
			(xy 117.01399 -102.068884) (xy 117.01399 -101.847904) (xy 116.84381 -101.759004) (xy 116.79936 -101.759004)
			(xy 116.79936 -102.157784) (xy 116.84381 -102.157784)
		)
		(stroke
			(width 0)
			(type solid)
		)
		(fill yes)
		(layer "In2.Cu")
		(net "M_K_DQ<53>")
	)
	(gr_poly
		(pts
			(xy 117.01399 -101.078284) (xy 117.01399 -100.857304) (xy 116.84381 -100.768404) (xy 116.79936 -100.768404)
			(xy 116.79936 -101.167184) (xy 116.84381 -101.167184)
		)
		(stroke
			(width 0)
			(type solid)
		)
		(fill yes)
		(layer "In2.Cu")
		(net "M_K_DQ<53>")
	)
	(gr_poly
		(pts
			(xy 117.01399 -100.090478) (xy 117.01399 -99.869498) (xy 116.84381 -99.780598) (xy 116.79936 -99.780598)
			(xy 116.79936 -100.179378) (xy 116.84381 -100.179378)
		)
		(stroke
			(width 0)
			(type solid)
		)
		(fill yes)
		(layer "In2.Cu")
		(net "M_K_DQ<53>")
	)
	(gr_poly
		(pts
			(xy 117.049804 -55.705248) (xy 117.005354 -55.705248) (xy 116.835174 -55.794148) (xy 116.835174 -56.015128)
			(xy 117.005354 -56.104028) (xy 117.049804 -56.104028)
		)
		(stroke
			(width 0)
			(type solid)
		)
		(fill yes)
		(layer "In2.Cu")
		(net "M_G_DQS_DN<6>")
	)
	(gr_poly
		(pts
			(xy 117.049804 -54.714648) (xy 117.005354 -54.714648) (xy 116.835174 -54.803548) (xy 116.835174 -55.024528)
			(xy 117.005354 -55.113428) (xy 117.049804 -55.113428)
		)
		(stroke
			(width 0)
			(type solid)
		)
		(fill yes)
		(layer "In2.Cu")
		(net "M_G_DQS_DN<6>")
	)
	(gr_poly
		(pts
			(xy 117.141498 -53.47589) (xy 117.097048 -53.47589) (xy 116.904008 -53.56479) (xy 116.904008 -53.79339)
			(xy 117.097048 -53.88229) (xy 117.141498 -53.88229)
		)
		(stroke
			(width 0)
			(type solid)
		)
		(fill yes)
		(layer "In2.Cu")
		(net "M_G_DQS_DN<6>")
	)
	(gr_poly
		(pts
			(xy 117.141498 -52.48529) (xy 117.097048 -52.48529) (xy 116.904008 -52.57419) (xy 116.904008 -52.80279)
			(xy 117.097048 -52.89169) (xy 117.141498 -52.89169)
		)
		(stroke
			(width 0)
			(type solid)
		)
		(fill yes)
		(layer "In2.Cu")
		(net "M_G_DQS_DN<6>")
	)
	(gr_poly
		(pts
			(xy 117.141498 -51.49469) (xy 117.097048 -51.49469) (xy 116.904008 -51.58359) (xy 116.904008 -51.81219)
			(xy 117.097048 -51.90109) (xy 117.141498 -51.90109)
		)
		(stroke
			(width 0)
			(type solid)
		)
		(fill yes)
		(layer "In2.Cu")
		(net "M_G_DQS_DN<6>")
	)
	(gr_poly
		(pts
			(xy 117.188742 -104.686354) (xy 117.157246 -104.655112) (xy 116.957856 -104.581452) (xy 116.796312 -104.742996)
			(xy 116.869972 -104.942386) (xy 116.901214 -104.973882)
		)
		(stroke
			(width 0)
			(type solid)
		)
		(fill yes)
		(layer "In2.Cu")
		(net "M_K_DQ<48>")
	)
	(gr_poly
		(pts
			(xy 117.334284 -103.33101) (xy 117.289834 -103.33101) (xy 117.096794 -103.41991) (xy 117.096794 -103.64851)
			(xy 117.289834 -103.73741) (xy 117.334284 -103.73741)
		)
		(stroke
			(width 0)
			(type solid)
		)
		(fill yes)
		(layer "In2.Cu")
		(net "M_K_DQ<48>")
	)
	(gr_poly
		(pts
			(xy 117.334284 -101.76764) (xy 117.289834 -101.76764) (xy 117.119654 -101.85654) (xy 117.119654 -102.07752)
			(xy 117.289834 -102.16642) (xy 117.334284 -102.16642)
		)
		(stroke
			(width 0)
			(type solid)
		)
		(fill yes)
		(layer "In2.Cu")
		(net "M_K_DQ<48>")
	)
	(gr_poly
		(pts
			(xy 117.334284 -100.783136) (xy 117.289834 -100.783136) (xy 117.119654 -100.872036) (xy 117.119654 -101.093016)
			(xy 117.289834 -101.181916) (xy 117.334284 -101.181916)
		)
		(stroke
			(width 0)
			(type solid)
		)
		(fill yes)
		(layer "In2.Cu")
		(net "M_K_DQ<48>")
	)
	(gr_poly
		(pts
			(xy 117.334284 -99.792536) (xy 117.289834 -99.792536) (xy 117.119654 -99.881436) (xy 117.119654 -100.102416)
			(xy 117.289834 -100.191316) (xy 117.334284 -100.191316)
		)
		(stroke
			(width 0)
			(type solid)
		)
		(fill yes)
		(layer "In2.Cu")
		(net "M_K_DQ<48>")
	)
	(gr_poly
		(pts
			(xy 117.334284 -98.801936) (xy 117.289834 -98.801936) (xy 117.119654 -98.890836) (xy 117.119654 -99.111816)
			(xy 117.289834 -99.200716) (xy 117.334284 -99.200716)
		)
		(stroke
			(width 0)
			(type solid)
		)
		(fill yes)
		(layer "In2.Cu")
		(net "M_K_DQ<48>")
	)
	(gr_poly
		(pts
			(xy 117.417596 -56.588406) (xy 117.587776 -56.499506) (xy 117.587776 -56.278526) (xy 117.417596 -56.189626)
			(xy 117.3734 -56.189626) (xy 117.373146 -56.58866)
		)
		(stroke
			(width 0)
			(type solid)
		)
		(fill yes)
		(layer "In2.Cu")
		(net "M_G_DQS_DP<6>")
	)
	(gr_poly
		(pts
			(xy 117.482112 -48.857662) (xy 117.437662 -48.857662) (xy 117.244622 -48.946562) (xy 117.244622 -49.175162)
			(xy 117.437662 -49.264062) (xy 117.482112 -49.264062)
		)
		(stroke
			(width 0)
			(type solid)
		)
		(fill yes)
		(layer "In2.Cu")
		(net "M_G_DQS_DN<6>")
	)
	(gr_poly
		(pts
			(xy 117.518434 -104.962452) (xy 117.444774 -104.763062) (xy 117.413532 -104.731566) (xy 117.126004 -105.019094)
			(xy 117.1575 -105.050336) (xy 117.35689 -105.123996)
		)
		(stroke
			(width 0)
			(type solid)
		)
		(fill yes)
		(layer "In2.Cu")
		(net "M_K_DQ<49>")
	)
	(gr_poly
		(pts
			(xy 117.531134 -97.766886) (xy 117.486684 -97.766886) (xy 117.316504 -97.855786) (xy 117.316504 -98.076766)
			(xy 117.486684 -98.165666) (xy 117.531134 -98.165666)
		)
		(stroke
			(width 0)
			(type solid)
		)
		(fill yes)
		(layer "In2.Cu")
		(net "M_K_DQ<48>")
	)
	(gr_poly
		(pts
			(xy 117.569488 -53.79339) (xy 117.569488 -53.56479) (xy 117.376448 -53.47589) (xy 117.331998 -53.47589)
			(xy 117.331998 -53.88229) (xy 117.376448 -53.88229)
		)
		(stroke
			(width 0)
			(type solid)
		)
		(fill yes)
		(layer "In2.Cu")
		(net "M_G_DQS_DP<6>")
	)
	(gr_poly
		(pts
			(xy 117.569488 -52.80279) (xy 117.569488 -52.57419) (xy 117.376448 -52.48529) (xy 117.331998 -52.48529)
			(xy 117.331998 -52.89169) (xy 117.376448 -52.89169)
		)
		(stroke
			(width 0)
			(type solid)
		)
		(fill yes)
		(layer "In2.Cu")
		(net "M_G_DQS_DP<6>")
	)
	(gr_poly
		(pts
			(xy 117.569488 -51.81219) (xy 117.569488 -51.58359) (xy 117.376448 -51.49469) (xy 117.331998 -51.49469)
			(xy 117.331998 -51.90109) (xy 117.376448 -51.90109)
		)
		(stroke
			(width 0)
			(type solid)
		)
		(fill yes)
		(layer "In2.Cu")
		(net "M_G_DQS_DP<6>")
	)
	(gr_poly
		(pts
			(xy 117.58803 -55.519828) (xy 117.58803 -55.298848) (xy 117.41785 -55.209948) (xy 117.3734 -55.209948)
			(xy 117.3734 -55.608728) (xy 117.41785 -55.608728)
		)
		(stroke
			(width 0)
			(type solid)
		)
		(fill yes)
		(layer "In2.Cu")
		(net "M_G_DQS_DP<6>")
	)
	(gr_poly
		(pts
			(xy 117.762528 -103.64851) (xy 117.762528 -103.41991) (xy 117.569488 -103.33101) (xy 117.525038 -103.33101)
			(xy 117.525038 -103.73741) (xy 117.569488 -103.73741)
		)
		(stroke
			(width 0)
			(type solid)
		)
		(fill yes)
		(layer "In2.Cu")
		(net "M_K_DQ<49>")
	)
	(gr_poly
		(pts
			(xy 117.87251 -102.57917) (xy 117.87251 -102.35819) (xy 117.70233 -102.26929) (xy 117.65788 -102.26929)
			(xy 117.65788 -102.66807) (xy 117.70233 -102.66807)
		)
		(stroke
			(width 0)
			(type solid)
		)
		(fill yes)
		(layer "In2.Cu")
		(net "M_K_DQ<49>")
	)
	(gr_poly
		(pts
			(xy 117.87251 -101.58222) (xy 117.87251 -101.36124) (xy 117.70233 -101.27234) (xy 117.65788 -101.27234)
			(xy 117.65788 -101.67112) (xy 117.70233 -101.67112)
		)
		(stroke
			(width 0)
			(type solid)
		)
		(fill yes)
		(layer "In2.Cu")
		(net "M_K_DQ<49>")
	)
	(gr_poly
		(pts
			(xy 117.87251 -100.58527) (xy 117.87251 -100.36429) (xy 117.70233 -100.27539) (xy 117.65788 -100.27539)
			(xy 117.65788 -100.67417) (xy 117.70233 -100.67417)
		)
		(stroke
			(width 0)
			(type solid)
		)
		(fill yes)
		(layer "In2.Cu")
		(net "M_K_DQ<49>")
	)
	(gr_poly
		(pts
			(xy 117.908578 -52.69357) (xy 117.864128 -52.69357) (xy 117.671088 -52.78247) (xy 117.671088 -53.01107)
			(xy 117.864128 -53.09997) (xy 117.908578 -53.09997)
		)
		(stroke
			(width 0)
			(type solid)
		)
		(fill yes)
		(layer "In2.Cu")
		(net "M_G_DQ<54>")
	)
	(gr_poly
		(pts
			(xy 117.908578 -51.80457) (xy 117.864128 -51.80457) (xy 117.671088 -51.89347) (xy 117.671088 -52.12207)
			(xy 117.864128 -52.21097) (xy 117.908578 -52.21097)
		)
		(stroke
			(width 0)
			(type solid)
		)
		(fill yes)
		(layer "In2.Cu")
		(net "M_G_DQ<54>")
	)
	(gr_poly
		(pts
			(xy 117.910102 -49.175162) (xy 117.910102 -48.946562) (xy 117.717062 -48.857662) (xy 117.672612 -48.857662)
			(xy 117.672612 -49.264062) (xy 117.717062 -49.264062)
		)
		(stroke
			(width 0)
			(type solid)
		)
		(fill yes)
		(layer "In2.Cu")
		(net "M_G_DQS_DP<6>")
	)
	(gr_poly
		(pts
			(xy 118.041166 -54.00421) (xy 117.996716 -54.00421) (xy 117.803676 -54.09311) (xy 117.803676 -54.32171)
			(xy 117.996716 -54.41061) (xy 118.041166 -54.41061)
		)
		(stroke
			(width 0)
			(type solid)
		)
		(fill yes)
		(layer "In2.Cu")
		(net "M_G_DQ<54>")
	)
	(gr_poly
		(pts
			(xy 118.12143 -103.880666) (xy 118.07698 -103.880666) (xy 117.88394 -103.969566) (xy 117.88394 -104.198166)
			(xy 118.07698 -104.287066) (xy 118.12143 -104.287066)
		)
		(stroke
			(width 0)
			(type solid)
		)
		(fill yes)
		(layer "In2.Cu")
		(net "M_K_DQS_DP<15>")
	)
	(gr_poly
		(pts
			(xy 118.192804 -102.263194) (xy 118.148354 -102.263194) (xy 117.978174 -102.352094) (xy 117.978174 -102.573074)
			(xy 118.148354 -102.661974) (xy 118.192804 -102.661974)
		)
		(stroke
			(width 0)
			(type solid)
		)
		(fill yes)
		(layer "In2.Cu")
		(net "M_K_DQS_DP<15>")
	)
	(gr_poly
		(pts
			(xy 118.192804 -101.26345) (xy 118.148354 -101.26345) (xy 117.978174 -101.35235) (xy 117.978174 -101.57333)
			(xy 118.148354 -101.66223) (xy 118.192804 -101.66223)
		)
		(stroke
			(width 0)
			(type solid)
		)
		(fill yes)
		(layer "In2.Cu")
		(net "M_K_DQS_DP<15>")
	)
	(gr_poly
		(pts
			(xy 118.192804 -100.275644) (xy 118.148354 -100.275644) (xy 117.978174 -100.364544) (xy 117.978174 -100.585524)
			(xy 118.148354 -100.674424) (xy 118.192804 -100.674424)
		)
		(stroke
			(width 0)
			(type solid)
		)
		(fill yes)
		(layer "In2.Cu")
		(net "M_K_DQS_DP<15>")
	)
	(gr_poly
		(pts
			(xy 118.192804 -98.307144) (xy 118.148354 -98.307144) (xy 117.978174 -98.396044) (xy 117.978174 -98.617024)
			(xy 118.148354 -98.705924) (xy 118.192804 -98.705924)
		)
		(stroke
			(width 0)
			(type solid)
		)
		(fill yes)
		(layer "In2.Cu")
		(net "M_K_DQS_DP<15>")
	)
	(gr_poly
		(pts
			(xy 118.193058 -99.291394) (xy 118.148608 -99.291394) (xy 117.978428 -99.380294) (xy 117.978428 -99.601274)
			(xy 118.148608 -99.690174) (xy 118.193058 -99.690174)
		)
		(stroke
			(width 0)
			(type solid)
		)
		(fill yes)
		(layer "In2.Cu")
		(net "M_K_DQS_DP<15>")
	)
	(gr_poly
		(pts
			(xy 118.227094 -57.111138) (xy 118.265448 -56.89346) (xy 118.113302 -56.776366) (xy 118.06936 -56.768746)
			(xy 118.000272 -57.16143) (xy 118.04396 -57.16905)
		)
		(stroke
			(width 0)
			(type solid)
		)
		(fill yes)
		(layer "In2.Cu")
		(net "M_G_DQ<55>")
	)
	(gr_poly
		(pts
			(xy 118.336822 -53.01107) (xy 118.336822 -52.78247) (xy 118.143782 -52.69357) (xy 118.099332 -52.69357)
			(xy 118.099332 -53.09997) (xy 118.143782 -53.09997)
		)
		(stroke
			(width 0)
			(type solid)
		)
		(fill yes)
		(layer "In2.Cu")
		(net "M_G_DQ<55>")
	)
	(gr_poly
		(pts
			(xy 118.349268 -51.13528) (xy 118.318026 -51.103784) (xy 118.118636 -51.030124) (xy 117.956838 -51.191668)
			(xy 118.030498 -51.391058) (xy 118.061994 -51.422554)
		)
		(stroke
			(width 0)
			(type solid)
		)
		(fill yes)
		(layer "In2.Cu")
		(net "M_G_DQ<54>")
	)
	(gr_poly
		(pts
			(xy 118.44655 -56.015128) (xy 118.44655 -55.794148) (xy 118.27637 -55.705248) (xy 118.23192 -55.705248)
			(xy 118.23192 -56.104028) (xy 118.27637 -56.104028)
		)
		(stroke
			(width 0)
			(type solid)
		)
		(fill yes)
		(layer "In2.Cu")
		(net "M_G_DQ<55>")
	)
	(gr_poly
		(pts
			(xy 118.46941 -54.11851) (xy 118.46941 -53.88991) (xy 118.27637 -53.80101) (xy 118.23192 -53.80101)
			(xy 118.23192 -54.20741) (xy 118.27637 -54.20741)
		)
		(stroke
			(width 0)
			(type solid)
		)
		(fill yes)
		(layer "In2.Cu")
		(net "M_G_DQ<55>")
	)
	(gr_poly
		(pts
			(xy 118.54942 -104.198166) (xy 118.54942 -103.969566) (xy 118.35638 -103.880666) (xy 118.31193 -103.880666)
			(xy 118.31193 -104.287066) (xy 118.35638 -104.287066)
		)
		(stroke
			(width 0)
			(type solid)
		)
		(fill yes)
		(layer "In2.Cu")
		(net "M_K_DQS_DN<15>")
	)
	(gr_poly
		(pts
			(xy 118.57609 -50.048668) (xy 118.53164 -50.048668) (xy 118.3386 -50.137568) (xy 118.3386 -50.366168)
			(xy 118.53164 -50.455068) (xy 118.57609 -50.455068)
		)
		(stroke
			(width 0)
			(type solid)
		)
		(fill yes)
		(layer "In2.Cu")
		(net "M_G_DQ<54>")
	)
	(gr_poly
		(pts
			(xy 118.57609 -49.058068) (xy 118.53164 -49.058068) (xy 118.3386 -49.146968) (xy 118.3386 -49.375568)
			(xy 118.53164 -49.464468) (xy 118.57609 -49.464468)
		)
		(stroke
			(width 0)
			(type solid)
		)
		(fill yes)
		(layer "In2.Cu")
		(net "M_G_DQ<54>")
	)
	(gr_poly
		(pts
			(xy 118.59006 -51.507898) (xy 118.5164 -51.308762) (xy 118.484904 -51.277266) (xy 118.19763 -51.56454)
			(xy 118.229126 -51.596036) (xy 118.428262 -51.669696)
		)
		(stroke
			(width 0)
			(type solid)
		)
		(fill yes)
		(layer "In2.Cu")
		(net "M_G_DQ<55>")
	)
	(gr_poly
		(pts
			(xy 118.655592 -97.891854) (xy 118.63324 -97.853246) (xy 118.471188 -97.750376) (xy 118.279926 -97.860866)
			(xy 118.288054 -98.052636) (xy 118.310152 -98.091244)
		)
		(stroke
			(width 0)
			(type solid)
		)
		(fill yes)
		(layer "In2.Cu")
		(net "M_K_DQS_DP<15>")
	)
	(gr_poly
		(pts
			(xy 118.730776 -103.06177) (xy 118.730776 -102.84079) (xy 118.560596 -102.75189) (xy 118.516146 -102.75189)
			(xy 118.516146 -103.15067) (xy 118.560596 -103.15067)
		)
		(stroke
			(width 0)
			(type solid)
		)
		(fill yes)
		(layer "In2.Cu")
		(net "M_K_DQS_DN<15>")
	)
	(gr_poly
		(pts
			(xy 118.73103 -102.08387) (xy 118.73103 -101.86289) (xy 118.56085 -101.77399) (xy 118.5164 -101.77399)
			(xy 118.5164 -102.17277) (xy 118.56085 -102.17277)
		)
		(stroke
			(width 0)
			(type solid)
		)
		(fill yes)
		(layer "In2.Cu")
		(net "M_K_DQS_DN<15>")
	)
	(gr_poly
		(pts
			(xy 118.73103 -101.09581) (xy 118.73103 -100.87483) (xy 118.56085 -100.78593) (xy 118.5164 -100.78593)
			(xy 118.5164 -101.18471) (xy 118.56085 -101.18471)
		)
		(stroke
			(width 0)
			(type solid)
		)
		(fill yes)
		(layer "In2.Cu")
		(net "M_K_DQS_DN<15>")
	)
	(gr_poly
		(pts
			(xy 118.73103 -100.10267) (xy 118.73103 -99.88169) (xy 118.56085 -99.79279) (xy 118.5164 -99.79279)
			(xy 118.5164 -100.19157) (xy 118.56085 -100.19157)
		)
		(stroke
			(width 0)
			(type solid)
		)
		(fill yes)
		(layer "In2.Cu")
		(net "M_K_DQS_DN<15>")
	)
	(gr_poly
		(pts
			(xy 118.73103 -99.099878) (xy 118.73103 -98.878898) (xy 118.56085 -98.789998) (xy 118.5164 -98.789998)
			(xy 118.5164 -99.188778) (xy 118.56085 -99.188778)
		)
		(stroke
			(width 0)
			(type solid)
		)
		(fill yes)
		(layer "In2.Cu")
		(net "M_K_DQS_DN<15>")
	)
	(gr_poly
		(pts
			(xy 118.756176 -54.23281) (xy 118.711726 -54.23281) (xy 118.518686 -54.32171) (xy 118.518686 -54.55031)
			(xy 118.711726 -54.63921) (xy 118.756176 -54.63921)
		)
		(stroke
			(width 0)
			(type solid)
		)
		(fill yes)
		(layer "In2.Cu")
		(net "M_G_DQ<50>")
	)
	(gr_poly
		(pts
			(xy 118.922292 -52.893976) (xy 118.877842 -52.893976) (xy 118.684802 -52.982876) (xy 118.684802 -53.211476)
			(xy 118.877842 -53.300376) (xy 118.922292 -53.300376)
		)
		(stroke
			(width 0)
			(type solid)
		)
		(fill yes)
		(layer "In2.Cu")
		(net "M_G_DQ<50>")
	)
	(gr_poly
		(pts
			(xy 118.922292 -51.776376) (xy 118.877842 -51.776376) (xy 118.684802 -51.865276) (xy 118.684802 -52.093876)
			(xy 118.877842 -52.182776) (xy 118.922292 -52.182776)
		)
		(stroke
			(width 0)
			(type solid)
		)
		(fill yes)
		(layer "In2.Cu")
		(net "M_G_DQ<50>")
	)
	(gr_poly
		(pts
			(xy 119.00408 -50.366168) (xy 119.00408 -50.137568) (xy 118.81104 -50.048668) (xy 118.76659 -50.048668)
			(xy 118.76659 -50.455068) (xy 118.81104 -50.455068)
		)
		(stroke
			(width 0)
			(type solid)
		)
		(fill yes)
		(layer "In2.Cu")
		(net "M_G_DQ<55>")
	)
	(gr_poly
		(pts
			(xy 119.00408 -49.375568) (xy 119.00408 -49.146968) (xy 118.81104 -49.058068) (xy 118.76659 -49.058068)
			(xy 118.76659 -49.464468) (xy 118.81104 -49.464468)
		)
		(stroke
			(width 0)
			(type solid)
		)
		(fill yes)
		(layer "In2.Cu")
		(net "M_G_DQ<55>")
	)
	(gr_poly
		(pts
			(xy 119.051324 -105.135172) (xy 119.006874 -105.135172) (xy 118.813834 -105.224072) (xy 118.813834 -105.452672)
			(xy 119.006874 -105.541572) (xy 119.051324 -105.541572)
		)
		(stroke
			(width 0)
			(type solid)
		)
		(fill yes)
		(layer "In2.Cu")
		(net "M_K_DQS_DN<6>")
	)
	(gr_poly
		(pts
			(xy 119.051324 -104.144572) (xy 119.006874 -104.144572) (xy 118.813834 -104.233472) (xy 118.813834 -104.462072)
			(xy 119.006874 -104.550972) (xy 119.051324 -104.550972)
		)
		(stroke
			(width 0)
			(type solid)
		)
		(fill yes)
		(layer "In2.Cu")
		(net "M_K_DQS_DN<6>")
	)
	(gr_poly
		(pts
			(xy 119.051324 -102.752398) (xy 119.006874 -102.752398) (xy 118.836694 -102.841298) (xy 118.836694 -103.062278)
			(xy 119.006874 -103.151178) (xy 119.051324 -103.151178)
		)
		(stroke
			(width 0)
			(type solid)
		)
		(fill yes)
		(layer "In2.Cu")
		(net "M_K_DQS_DN<6>")
	)
	(gr_poly
		(pts
			(xy 119.051324 -101.761798) (xy 119.006874 -101.761798) (xy 118.836694 -101.850698) (xy 118.836694 -102.071678)
			(xy 119.006874 -102.160578) (xy 119.051324 -102.160578)
		)
		(stroke
			(width 0)
			(type solid)
		)
		(fill yes)
		(layer "In2.Cu")
		(net "M_K_DQS_DN<6>")
	)
	(gr_poly
		(pts
			(xy 119.051324 -100.771198) (xy 119.006874 -100.771198) (xy 118.836694 -100.860098) (xy 118.836694 -101.081078)
			(xy 119.006874 -101.169978) (xy 119.051324 -101.169978)
		)
		(stroke
			(width 0)
			(type solid)
		)
		(fill yes)
		(layer "In2.Cu")
		(net "M_K_DQS_DN<6>")
	)
	(gr_poly
		(pts
			(xy 119.149622 -100.364544) (xy 118.966488 -100.010214) (xy 118.927118 -100.030534) (xy 118.816628 -100.18776)
			(xy 118.918228 -100.384102) (xy 119.110252 -100.384864)
		)
		(stroke
			(width 0)
			(type solid)
		)
		(fill yes)
		(layer "In2.Cu")
		(net "M_K_DQS_DN<6>")
	)
	(gr_poly
		(pts
			(xy 119.184166 -54.55031) (xy 119.184166 -54.32171) (xy 118.991126 -54.23281) (xy 118.946676 -54.23281)
			(xy 118.946676 -54.63921) (xy 118.991126 -54.63921)
		)
		(stroke
			(width 0)
			(type solid)
		)
		(fill yes)
		(layer "In2.Cu")
		(net "M_G_DQ<51>")
	)
	(gr_poly
		(pts
			(xy 119.276368 -51.301142) (xy 119.244872 -51.269646) (xy 119.045736 -51.195986) (xy 118.883938 -51.357784)
			(xy 118.957598 -51.55692) (xy 118.989094 -51.588416)
		)
		(stroke
			(width 0)
			(type solid)
		)
		(fill yes)
		(layer "In2.Cu")
		(net "M_G_DQ<50>")
	)
	(gr_poly
		(pts
			(xy 119.30507 -56.504078) (xy 119.30507 -56.283098) (xy 119.13489 -56.194198) (xy 119.09044 -56.194198)
			(xy 119.09044 -56.592978) (xy 119.13489 -56.592978)
		)
		(stroke
			(width 0)
			(type solid)
		)
		(fill yes)
		(layer "In2.Cu")
		(net "M_G_DQ<51>")
	)
	(gr_poly
		(pts
			(xy 119.30507 -55.513478) (xy 119.30507 -55.292498) (xy 119.13489 -55.203598) (xy 119.09044 -55.203598)
			(xy 119.09044 -55.602378) (xy 119.13489 -55.602378)
		)
		(stroke
			(width 0)
			(type solid)
		)
		(fill yes)
		(layer "In2.Cu")
		(net "M_G_DQ<51>")
	)
	(gr_poly
		(pts
			(xy 119.34317 -50.494438) (xy 119.29872 -50.494438) (xy 119.10568 -50.583338) (xy 119.10568 -50.811938)
			(xy 119.29872 -50.900838) (xy 119.34317 -50.900838)
		)
		(stroke
			(width 0)
			(type solid)
		)
		(fill yes)
		(layer "In2.Cu")
		(net "M_G_DQ<50>")
	)
	(gr_poly
		(pts
			(xy 119.350282 -53.211476) (xy 119.350282 -52.982876) (xy 119.157242 -52.893976) (xy 119.112792 -52.893976)
			(xy 119.112792 -53.300376) (xy 119.157242 -53.300376)
		)
		(stroke
			(width 0)
			(type solid)
		)
		(fill yes)
		(layer "In2.Cu")
		(net "M_G_DQ<51>")
	)
	(gr_poly
		(pts
			(xy 119.350282 -52.220876) (xy 119.350282 -51.992276) (xy 119.157242 -51.903376) (xy 119.112792 -51.903376)
			(xy 119.112792 -52.309776) (xy 119.157242 -52.309776)
		)
		(stroke
			(width 0)
			(type solid)
		)
		(fill yes)
		(layer "In2.Cu")
		(net "M_G_DQ<51>")
	)
	(gr_poly
		(pts
			(xy 119.479314 -105.452672) (xy 119.479314 -105.224072) (xy 119.286274 -105.135172) (xy 119.241824 -105.135172)
			(xy 119.241824 -105.541572) (xy 119.286274 -105.541572)
		)
		(stroke
			(width 0)
			(type solid)
		)
		(fill yes)
		(layer "In2.Cu")
		(net "M_K_DQS_DP<6>")
	)
	(gr_poly
		(pts
			(xy 119.479314 -104.462072) (xy 119.479314 -104.233472) (xy 119.286274 -104.144572) (xy 119.241824 -104.144572)
			(xy 119.241824 -104.550972) (xy 119.286274 -104.550972)
		)
		(stroke
			(width 0)
			(type solid)
		)
		(fill yes)
		(layer "In2.Cu")
		(net "M_K_DQS_DP<6>")
	)
	(gr_poly
		(pts
			(xy 119.58955 -103.570024) (xy 119.58955 -103.349044) (xy 119.41937 -103.260144) (xy 119.37492 -103.260144)
			(xy 119.37492 -103.658924) (xy 119.41937 -103.658924)
		)
		(stroke
			(width 0)
			(type solid)
		)
		(fill yes)
		(layer "In2.Cu")
		(net "M_K_DQS_DP<6>")
	)
	(gr_poly
		(pts
			(xy 119.58955 -102.579424) (xy 119.58955 -102.358444) (xy 119.41937 -102.269544) (xy 119.37492 -102.269544)
			(xy 119.37492 -102.668324) (xy 119.41937 -102.668324)
		)
		(stroke
			(width 0)
			(type solid)
		)
		(fill yes)
		(layer "In2.Cu")
		(net "M_K_DQS_DP<6>")
	)
	(gr_poly
		(pts
			(xy 119.58955 -101.588824) (xy 119.58955 -101.367844) (xy 119.41937 -101.278944) (xy 119.37492 -101.278944)
			(xy 119.37492 -101.677724) (xy 119.41937 -101.677724)
		)
		(stroke
			(width 0)
			(type solid)
		)
		(fill yes)
		(layer "In2.Cu")
		(net "M_K_DQS_DP<6>")
	)
	(gr_poly
		(pts
			(xy 119.58955 -100.598224) (xy 119.58955 -100.377244) (xy 119.41937 -100.288344) (xy 119.37492 -100.288344)
			(xy 119.37492 -100.687124) (xy 119.41937 -100.687124)
		)
		(stroke
			(width 0)
			(type solid)
		)
		(fill yes)
		(layer "In2.Cu")
		(net "M_K_DQS_DP<6>")
	)
	(gr_poly
		(pts
			(xy 119.58955 -97.613724) (xy 119.58955 -97.392744) (xy 119.41937 -97.303844) (xy 119.37492 -97.303844)
			(xy 119.37492 -97.702624) (xy 119.41937 -97.702624)
		)
		(stroke
			(width 0)
			(type solid)
		)
		(fill yes)
		(layer "In2.Cu")
		(net "M_K_DQS_DN<15>")
	)
	(gr_poly
		(pts
			(xy 119.599456 -98.445828) (xy 119.56796 -98.414586) (xy 119.384826 -98.356928) (xy 119.228616 -98.513138)
			(xy 119.28602 -98.696526) (xy 119.317516 -98.727768)
		)
		(stroke
			(width 0)
			(type solid)
		)
		(fill yes)
		(layer "In2.Cu")
		(net "M_K_DQ<54>")
	)
	(gr_poly
		(pts
			(xy 119.62511 -55.203598) (xy 119.58066 -55.203598) (xy 119.41048 -55.292498) (xy 119.41048 -55.513478)
			(xy 119.58066 -55.602378) (xy 119.62511 -55.602378)
		)
		(stroke
			(width 0)
			(type solid)
		)
		(fill yes)
		(layer "In2.Cu")
		(net "M_G_DQ<60>")
	)
	(gr_poly
		(pts
			(xy 119.62511 -54.212998) (xy 119.58066 -54.212998) (xy 119.41048 -54.301898) (xy 119.41048 -54.522878)
			(xy 119.58066 -54.611778) (xy 119.62511 -54.611778)
		)
		(stroke
			(width 0)
			(type solid)
		)
		(fill yes)
		(layer "In2.Cu")
		(net "M_G_DQ<60>")
	)
	(gr_poly
		(pts
			(xy 119.741188 -49.762918) (xy 119.709692 -49.731422) (xy 119.510556 -49.657762) (xy 119.348758 -49.81956)
			(xy 119.422418 -50.018696) (xy 119.453914 -50.050192)
		)
		(stroke
			(width 0)
			(type solid)
		)
		(fill yes)
		(layer "In2.Cu")
		(net "M_G_DQ<50>")
	)
	(gr_poly
		(pts
			(xy 119.77116 -51.065938) (xy 119.77116 -50.837338) (xy 119.57812 -50.748438) (xy 119.53367 -50.748438)
			(xy 119.53367 -51.154838) (xy 119.57812 -51.154838)
		)
		(stroke
			(width 0)
			(type solid)
		)
		(fill yes)
		(layer "In2.Cu")
		(net "M_G_DQ<51>")
	)
	(gr_poly
		(pts
			(xy 119.909844 -103.260144) (xy 119.865394 -103.260144) (xy 119.695214 -103.349044) (xy 119.695214 -103.570024)
			(xy 119.865394 -103.658924) (xy 119.909844 -103.658924)
		)
		(stroke
			(width 0)
			(type solid)
		)
		(fill yes)
		(layer "In2.Cu")
		(net "M_K_DQ<54>")
	)
	(gr_poly
		(pts
			(xy 119.909844 -102.269544) (xy 119.865394 -102.269544) (xy 119.695214 -102.358444) (xy 119.695214 -102.579424)
			(xy 119.865394 -102.668324) (xy 119.909844 -102.668324)
		)
		(stroke
			(width 0)
			(type solid)
		)
		(fill yes)
		(layer "In2.Cu")
		(net "M_K_DQ<54>")
	)
	(gr_poly
		(pts
			(xy 119.909844 -101.278944) (xy 119.865394 -101.278944) (xy 119.695214 -101.367844) (xy 119.695214 -101.588824)
			(xy 119.865394 -101.677724) (xy 119.909844 -101.677724)
		)
		(stroke
			(width 0)
			(type solid)
		)
		(fill yes)
		(layer "In2.Cu")
		(net "M_K_DQ<54>")
	)
	(gr_poly
		(pts
			(xy 119.909844 -100.288344) (xy 119.865394 -100.288344) (xy 119.695214 -100.377244) (xy 119.695214 -100.598224)
			(xy 119.865394 -100.687124) (xy 119.909844 -100.687124)
		)
		(stroke
			(width 0)
			(type solid)
		)
		(fill yes)
		(layer "In2.Cu")
		(net "M_K_DQ<54>")
	)
	(gr_poly
		(pts
			(xy 119.970042 -105.492042) (xy 119.925592 -105.492042) (xy 119.732552 -105.580942) (xy 119.732552 -105.809542)
			(xy 119.925592 -105.898442) (xy 119.970042 -105.898442)
		)
		(stroke
			(width 0)
			(type solid)
		)
		(fill yes)
		(layer "In2.Cu")
		(net "M_K_DQ<54>")
	)
	(gr_poly
		(pts
			(xy 119.970042 -104.501442) (xy 119.925592 -104.501442) (xy 119.732552 -104.590342) (xy 119.732552 -104.818942)
			(xy 119.925592 -104.907842) (xy 119.970042 -104.907842)
		)
		(stroke
			(width 0)
			(type solid)
		)
		(fill yes)
		(layer "In2.Cu")
		(net "M_K_DQ<54>")
	)
	(gr_poly
		(pts
			(xy 120.012714 -50.096928) (xy 119.939054 -49.897792) (xy 119.907558 -49.866296) (xy 119.620284 -50.15357)
			(xy 119.65178 -50.185066) (xy 119.850916 -50.258726)
		)
		(stroke
			(width 0)
			(type solid)
		)
		(fill yes)
		(layer "In2.Cu")
		(net "M_G_DQ<51>")
	)
	(gr_poly
		(pts
			(xy 120.163336 -55.030624) (xy 120.163336 -54.809644) (xy 119.993156 -54.720744) (xy 119.948706 -54.720744)
			(xy 119.948706 -55.119524) (xy 119.993156 -55.119524)
		)
		(stroke
			(width 0)
			(type solid)
		)
		(fill yes)
		(layer "In2.Cu")
		(net "M_G_DQ<61>")
	)
	(gr_poly
		(pts
			(xy 120.373648 -52.764944) (xy 120.342152 -52.733702) (xy 120.142762 -52.660042) (xy 119.981218 -52.821586)
			(xy 120.054878 -53.020976) (xy 120.08612 -53.052472)
		)
		(stroke
			(width 0)
			(type solid)
		)
		(fill yes)
		(layer "In2.Cu")
		(net "M_G_DQ<60>")
	)
	(gr_poly
		(pts
			(xy 120.398032 -105.809542) (xy 120.398032 -105.580942) (xy 120.204992 -105.492042) (xy 120.160542 -105.492042)
			(xy 120.160542 -105.898442) (xy 120.204992 -105.898442)
		)
		(stroke
			(width 0)
			(type solid)
		)
		(fill yes)
		(layer "In2.Cu")
		(net "M_K_DQ<55>")
	)
	(gr_poly
		(pts
			(xy 120.398032 -104.818942) (xy 120.398032 -104.590342) (xy 120.204992 -104.501442) (xy 120.160542 -104.501442)
			(xy 120.160542 -104.907842) (xy 120.204992 -104.907842)
		)
		(stroke
			(width 0)
			(type solid)
		)
		(fill yes)
		(layer "In2.Cu")
		(net "M_K_DQ<55>")
	)
	(gr_poly
		(pts
			(xy 120.44807 -104.052878) (xy 120.44807 -103.831898) (xy 120.27789 -103.742998) (xy 120.23344 -103.742998)
			(xy 120.23344 -104.141778) (xy 120.27789 -104.141778)
		)
		(stroke
			(width 0)
			(type solid)
		)
		(fill yes)
		(layer "In2.Cu")
		(net "M_K_DQ<55>")
	)
	(gr_poly
		(pts
			(xy 120.44807 -103.062278) (xy 120.44807 -102.841298) (xy 120.27789 -102.752398) (xy 120.23344 -102.752398)
			(xy 120.23344 -103.151178) (xy 120.27789 -103.151178)
		)
		(stroke
			(width 0)
			(type solid)
		)
		(fill yes)
		(layer "In2.Cu")
		(net "M_K_DQ<55>")
	)
	(gr_poly
		(pts
			(xy 120.44807 -102.071678) (xy 120.44807 -101.850698) (xy 120.27789 -101.761798) (xy 120.23344 -101.761798)
			(xy 120.23344 -102.160578) (xy 120.27789 -102.160578)
		)
		(stroke
			(width 0)
			(type solid)
		)
		(fill yes)
		(layer "In2.Cu")
		(net "M_K_DQ<55>")
	)
	(gr_poly
		(pts
			(xy 120.44807 -101.081078) (xy 120.44807 -100.860098) (xy 120.27789 -100.771198) (xy 120.23344 -100.771198)
			(xy 120.23344 -101.169978) (xy 120.27789 -101.169978)
		)
		(stroke
			(width 0)
			(type solid)
		)
		(fill yes)
		(layer "In2.Cu")
		(net "M_K_DQ<55>")
	)
	(gr_poly
		(pts
			(xy 120.44807 -100.090478) (xy 120.44807 -99.869498) (xy 120.27789 -99.780598) (xy 120.23344 -99.780598)
			(xy 120.23344 -100.179378) (xy 120.27789 -100.179378)
		)
		(stroke
			(width 0)
			(type solid)
		)
		(fill yes)
		(layer "In2.Cu")
		(net "M_K_DQ<55>")
	)
	(gr_poly
		(pts
			(xy 120.48363 -54.720744) (xy 120.43918 -54.720744) (xy 120.269 -54.809644) (xy 120.269 -55.030624)
			(xy 120.43918 -55.119524) (xy 120.48363 -55.119524)
		)
		(stroke
			(width 0)
			(type solid)
		)
		(fill yes)
		(layer "In2.Cu")
		(net "M_G_DQ<56>")
	)
	(gr_poly
		(pts
			(xy 120.484646 -99.003358) (xy 120.506744 -98.96475) (xy 120.161304 -98.76536) (xy 120.139206 -98.803968)
			(xy 120.131078 -98.995738) (xy 120.32234 -99.106228)
		)
		(stroke
			(width 0)
			(type solid)
		)
		(fill yes)
		(layer "In2.Cu")
		(net "M_K_DQ<50>")
	)
	(gr_poly
		(pts
			(xy 120.613424 -53.13045) (xy 120.539764 -52.931314) (xy 120.508268 -52.899818) (xy 120.220994 -53.187092)
			(xy 120.25249 -53.218588) (xy 120.451626 -53.292248)
		)
		(stroke
			(width 0)
			(type solid)
		)
		(fill yes)
		(layer "In2.Cu")
		(net "M_G_DQ<61>")
	)
	(gr_poly
		(pts
			(xy 120.614694 -51.943) (xy 120.570244 -51.943) (xy 120.377204 -52.0319) (xy 120.377204 -52.2605)
			(xy 120.570244 -52.3494) (xy 120.614694 -52.3494)
		)
		(stroke
			(width 0)
			(type solid)
		)
		(fill yes)
		(layer "In2.Cu")
		(net "M_G_DQ<60>")
	)
	(gr_poly
		(pts
			(xy 120.705372 -56.44388) (xy 120.834912 -56.302148) (xy 120.75922 -56.094376) (xy 120.568974 -56.068976)
			(xy 120.527318 -56.084216) (xy 120.663462 -56.45912)
		)
		(stroke
			(width 0)
			(type solid)
		)
		(fill yes)
		(layer "In2.Cu")
		(net "M_G_DQ<61>")
	)
	(gr_poly
		(pts
			(xy 120.76811 -103.740204) (xy 120.72366 -103.740204) (xy 120.55348 -103.829104) (xy 120.55348 -104.050084)
			(xy 120.72366 -104.138984) (xy 120.76811 -104.138984)
		)
		(stroke
			(width 0)
			(type solid)
		)
		(fill yes)
		(layer "In2.Cu")
		(net "M_K_DQ<50>")
	)
	(gr_poly
		(pts
			(xy 120.76811 -102.749604) (xy 120.72366 -102.749604) (xy 120.55348 -102.838504) (xy 120.55348 -103.059484)
			(xy 120.72366 -103.148384) (xy 120.76811 -103.148384)
		)
		(stroke
			(width 0)
			(type solid)
		)
		(fill yes)
		(layer "In2.Cu")
		(net "M_K_DQ<50>")
	)
	(gr_poly
		(pts
			(xy 120.76811 -101.759004) (xy 120.72366 -101.759004) (xy 120.55348 -101.847904) (xy 120.55348 -102.068884)
			(xy 120.72366 -102.157784) (xy 120.76811 -102.157784)
		)
		(stroke
			(width 0)
			(type solid)
		)
		(fill yes)
		(layer "In2.Cu")
		(net "M_K_DQ<50>")
	)
	(gr_poly
		(pts
			(xy 120.76811 -100.768404) (xy 120.72366 -100.768404) (xy 120.55348 -100.857304) (xy 120.55348 -101.078284)
			(xy 120.72366 -101.167184) (xy 120.76811 -101.167184)
		)
		(stroke
			(width 0)
			(type solid)
		)
		(fill yes)
		(layer "In2.Cu")
		(net "M_K_DQ<50>")
	)
	(gr_poly
		(pts
			(xy 120.76811 -99.777804) (xy 120.72366 -99.777804) (xy 120.55348 -99.866704) (xy 120.55348 -100.087684)
			(xy 120.72366 -100.176584) (xy 120.76811 -100.176584)
		)
		(stroke
			(width 0)
			(type solid)
		)
		(fill yes)
		(layer "In2.Cu")
		(net "M_K_DQ<50>")
	)
	(gr_poly
		(pts
			(xy 120.939814 -104.83977) (xy 120.895364 -104.83977) (xy 120.702324 -104.92867) (xy 120.702324 -105.15727)
			(xy 120.895364 -105.24617) (xy 120.939814 -105.24617)
		)
		(stroke
			(width 0)
			(type solid)
		)
		(fill yes)
		(layer "In2.Cu")
		(net "M_K_DQ<50>")
	)
	(gr_poly
		(pts
			(xy 121.021856 -54.522878) (xy 121.021856 -54.301898) (xy 120.851676 -54.212998) (xy 120.807226 -54.212998)
			(xy 120.807226 -54.611778) (xy 120.851676 -54.611778)
		)
		(stroke
			(width 0)
			(type solid)
		)
		(fill yes)
		(layer "In2.Cu")
		(net "M_G_DQ<57>")
	)
	(gr_poly
		(pts
			(xy 121.021856 -51.32451) (xy 120.99036 -51.293268) (xy 120.79097 -51.219608) (xy 120.629426 -51.381152)
			(xy 120.703086 -51.580542) (xy 120.734328 -51.612038)
		)
		(stroke
			(width 0)
			(type solid)
		)
		(fill yes)
		(layer "In2.Cu")
		(net "M_G_DQ<60>")
	)
	(gr_poly
		(pts
			(xy 121.042684 -52.2605) (xy 121.042684 -52.0319) (xy 120.849644 -51.943) (xy 120.805194 -51.943)
			(xy 120.805194 -52.3494) (xy 120.849644 -52.3494)
		)
		(stroke
			(width 0)
			(type solid)
		)
		(fill yes)
		(layer "In2.Cu")
		(net "M_G_DQ<61>")
	)
	(gr_poly
		(pts
			(xy 121.105168 -53.038756) (xy 121.073672 -53.00726) (xy 120.874536 -52.9336) (xy 120.712738 -53.095398)
			(xy 120.786398 -53.294534) (xy 120.817894 -53.32603)
		)
		(stroke
			(width 0)
			(type solid)
		)
		(fill yes)
		(layer "In2.Cu")
		(net "M_G_DQ<56>")
	)
	(gr_poly
		(pts
			(xy 121.30659 -103.572818) (xy 121.30659 -103.351838) (xy 121.13641 -103.262938) (xy 121.09196 -103.262938)
			(xy 121.09196 -103.661718) (xy 121.13641 -103.661718)
		)
		(stroke
			(width 0)
			(type solid)
		)
		(fill yes)
		(layer "In2.Cu")
		(net "M_K_DQ<51>")
	)
	(gr_poly
		(pts
			(xy 121.30659 -102.582218) (xy 121.30659 -102.361238) (xy 121.13641 -102.272338) (xy 121.09196 -102.272338)
			(xy 121.09196 -102.671118) (xy 121.13641 -102.671118)
		)
		(stroke
			(width 0)
			(type solid)
		)
		(fill yes)
		(layer "In2.Cu")
		(net "M_K_DQ<51>")
	)
	(gr_poly
		(pts
			(xy 121.30659 -101.591618) (xy 121.30659 -101.370638) (xy 121.13641 -101.281738) (xy 121.09196 -101.281738)
			(xy 121.09196 -101.680518) (xy 121.13641 -101.680518)
		)
		(stroke
			(width 0)
			(type solid)
		)
		(fill yes)
		(layer "In2.Cu")
		(net "M_K_DQ<51>")
	)
	(gr_poly
		(pts
			(xy 121.30659 -100.601018) (xy 121.30659 -100.380038) (xy 121.13641 -100.291138) (xy 121.09196 -100.291138)
			(xy 121.09196 -100.689918) (xy 121.13641 -100.689918)
		)
		(stroke
			(width 0)
			(type solid)
		)
		(fill yes)
		(layer "In2.Cu")
		(net "M_K_DQ<51>")
	)
	(gr_poly
		(pts
			(xy 121.30659 -99.610418) (xy 121.30659 -99.389438) (xy 121.13641 -99.300538) (xy 121.09196 -99.300538)
			(xy 121.09196 -99.699318) (xy 121.13641 -99.699318)
		)
		(stroke
			(width 0)
			(type solid)
		)
		(fill yes)
		(layer "In2.Cu")
		(net "M_K_DQ<51>")
	)
	(gr_poly
		(pts
			(xy 121.33961 -52.33543) (xy 121.29516 -52.33543) (xy 121.10212 -52.42433) (xy 121.10212 -52.65293)
			(xy 121.29516 -52.74183) (xy 121.33961 -52.74183)
		)
		(stroke
			(width 0)
			(type solid)
		)
		(fill yes)
		(layer "In2.Cu")
		(net "M_G_DQ<56>")
	)
	(gr_poly
		(pts
			(xy 121.34215 -56.194198) (xy 121.2977 -56.194198) (xy 121.12752 -56.283098) (xy 121.12752 -56.504078)
			(xy 121.2977 -56.592978) (xy 121.34215 -56.592978)
		)
		(stroke
			(width 0)
			(type solid)
		)
		(fill yes)
		(layer "In2.Cu")
		(net "M_G_DQ<57>")
	)
	(gr_poly
		(pts
			(xy 121.34215 -54.212998) (xy 121.2977 -54.212998) (xy 121.12752 -54.301898) (xy 121.12752 -54.522878)
			(xy 121.2977 -54.611778) (xy 121.34215 -54.611778)
		)
		(stroke
			(width 0)
			(type solid)
		)
		(fill yes)
		(layer "In2.Cu")
		(net "M_G_DQS_DP<16>")
	)
	(gr_poly
		(pts
			(xy 121.367804 -105.15727) (xy 121.367804 -104.92867) (xy 121.174764 -104.83977) (xy 121.130314 -104.83977)
			(xy 121.130314 -105.24617) (xy 121.174764 -105.24617)
		)
		(stroke
			(width 0)
			(type solid)
		)
		(fill yes)
		(layer "In2.Cu")
		(net "M_K_DQ<51>")
	)
	(gr_poly
		(pts
			(xy 121.420382 -53.328824) (xy 121.346722 -53.129688) (xy 121.315226 -53.098192) (xy 121.027952 -53.385466)
			(xy 121.059448 -53.416962) (xy 121.258584 -53.490622)
		)
		(stroke
			(width 0)
			(type solid)
		)
		(fill yes)
		(layer "In2.Cu")
		(net "M_G_DQ<57>")
	)
	(gr_poly
		(pts
			(xy 121.515632 -51.436016) (xy 121.441972 -51.23688) (xy 121.410476 -51.205384) (xy 121.123202 -51.492658)
			(xy 121.154698 -51.524154) (xy 121.353834 -51.597814)
		)
		(stroke
			(width 0)
			(type solid)
		)
		(fill yes)
		(layer "In2.Cu")
		(net "M_G_DQ<61>")
	)
	(gr_poly
		(pts
			(xy 121.62663 -100.288344) (xy 121.58218 -100.288344) (xy 121.412 -100.377244) (xy 121.412 -100.598224)
			(xy 121.58218 -100.687124) (xy 121.62663 -100.687124)
		)
		(stroke
			(width 0)
			(type solid)
		)
		(fill yes)
		(layer "In2.Cu")
		(net "M_K_DQ<60>")
	)
	(gr_poly
		(pts
			(xy 121.62663 -99.297744) (xy 121.58218 -99.297744) (xy 121.412 -99.386644) (xy 121.412 -99.607624)
			(xy 121.58218 -99.696524) (xy 121.62663 -99.696524)
		)
		(stroke
			(width 0)
			(type solid)
		)
		(fill yes)
		(layer "In2.Cu")
		(net "M_K_DQ<60>")
	)
	(gr_poly
		(pts
			(xy 121.62663 -98.307144) (xy 121.58218 -98.307144) (xy 121.412 -98.396044) (xy 121.412 -98.617024)
			(xy 121.58218 -98.705924) (xy 121.62663 -98.705924)
		)
		(stroke
			(width 0)
			(type solid)
		)
		(fill yes)
		(layer "In2.Cu")
		(net "M_K_DQ<60>")
	)
	(gr_poly
		(pts
			(xy 121.762266 -103.162862) (xy 121.717816 -103.162862) (xy 121.524776 -103.251762) (xy 121.524776 -103.480362)
			(xy 121.71807 -103.569262) (xy 121.762266 -103.569262)
		)
		(stroke
			(width 0)
			(type solid)
		)
		(fill yes)
		(layer "In2.Cu")
		(net "M_K_DQ<60>")
	)
	(gr_poly
		(pts
			(xy 121.804938 -53.810662) (xy 121.782586 -53.772054) (xy 121.620534 -53.669184) (xy 121.429272 -53.779674)
			(xy 121.4374 -53.971444) (xy 121.459498 -54.009798)
		)
		(stroke
			(width 0)
			(type solid)
		)
		(fill yes)
		(layer "In2.Cu")
		(net "M_G_DQS_DP<16>")
	)
	(gr_poly
		(pts
			(xy 121.880122 -55.01894) (xy 121.880122 -54.79796) (xy 121.709942 -54.70906) (xy 121.665492 -54.70906)
			(xy 121.665238 -55.10784) (xy 121.709942 -55.10784)
		)
		(stroke
			(width 0)
			(type solid)
		)
		(fill yes)
		(layer "In2.Cu")
		(net "M_G_DQS_DN<16>")
	)
	(gr_poly
		(pts
			(xy 121.893584 -101.501448) (xy 121.849134 -101.501448) (xy 121.656094 -101.590348) (xy 121.656094 -101.818948)
			(xy 121.849388 -101.907848) (xy 121.893584 -101.907848)
		)
		(stroke
			(width 0)
			(type solid)
		)
		(fill yes)
		(layer "In2.Cu")
		(net "M_K_DQ<60>")
	)
	(gr_poly
		(pts
			(xy 121.897902 -51.555904) (xy 121.866406 -51.524408) (xy 121.66727 -51.450748) (xy 121.505472 -51.612546)
			(xy 121.579132 -51.811682) (xy 121.610628 -51.843178)
		)
		(stroke
			(width 0)
			(type solid)
		)
		(fill yes)
		(layer "In2.Cu")
		(net "M_G_DQ<56>")
	)
	(gr_poly
		(pts
			(xy 122.138186 -51.921918) (xy 122.064526 -51.722528) (xy 122.033284 -51.691032) (xy 121.745756 -51.97856)
			(xy 121.777252 -52.009802) (xy 121.976642 -52.083462)
		)
		(stroke
			(width 0)
			(type solid)
		)
		(fill yes)
		(layer "In2.Cu")
		(net "M_G_DQ<57>")
	)
	(gr_poly
		(pts
			(xy 122.164856 -100.090478) (xy 122.164856 -99.869498) (xy 121.994676 -99.780598) (xy 121.950226 -99.780598)
			(xy 121.950226 -100.179378) (xy 121.994676 -100.179378)
		)
		(stroke
			(width 0)
			(type solid)
		)
		(fill yes)
		(layer "In2.Cu")
		(net "M_K_DQ<61>")
	)
	(gr_poly
		(pts
			(xy 122.164856 -99.099878) (xy 122.164856 -98.878898) (xy 121.994676 -98.789998) (xy 121.950226 -98.789998)
			(xy 121.950226 -99.188778) (xy 121.994676 -99.188778)
		)
		(stroke
			(width 0)
			(type solid)
		)
		(fill yes)
		(layer "In2.Cu")
		(net "M_K_DQ<61>")
	)
	(gr_poly
		(pts
			(xy 122.19051 -103.495094) (xy 122.190256 -103.266494) (xy 121.997216 -103.177594) (xy 121.952766 -103.177848)
			(xy 121.952766 -103.583994) (xy 121.997216 -103.583994)
		)
		(stroke
			(width 0)
			(type solid)
		)
		(fill yes)
		(layer "In2.Cu")
		(net "M_K_DQ<61>")
	)
	(gr_poly
		(pts
			(xy 122.20067 -56.701944) (xy 122.15622 -56.701944) (xy 121.98604 -56.790844) (xy 121.98604 -57.011824)
			(xy 122.15622 -57.100724) (xy 122.20067 -57.100724)
		)
		(stroke
			(width 0)
			(type solid)
		)
		(fill yes)
		(layer "In2.Cu")
		(net "M_G_DQS_DN<7>")
	)
	(gr_poly
		(pts
			(xy 122.20067 -55.711344) (xy 122.15622 -55.711344) (xy 121.98604 -55.800244) (xy 121.98604 -56.021224)
			(xy 122.15622 -56.110124) (xy 122.20067 -56.110124)
		)
		(stroke
			(width 0)
			(type solid)
		)
		(fill yes)
		(layer "In2.Cu")
		(net "M_G_DQS_DN<7>")
	)
	(gr_poly
		(pts
			(xy 122.20067 -52.733194) (xy 122.15622 -52.733194) (xy 121.98604 -52.822094) (xy 121.98604 -53.043074)
			(xy 122.15622 -53.131974) (xy 122.20067 -53.131974)
		)
		(stroke
			(width 0)
			(type solid)
		)
		(fill yes)
		(layer "In2.Cu")
		(net "M_G_DQS_DP<16>")
	)
	(gr_poly
		(pts
			(xy 122.322082 -101.832918) (xy 122.321828 -101.604318) (xy 122.128788 -101.515418) (xy 122.084338 -101.515672)
			(xy 122.084338 -101.921818) (xy 122.128788 -101.921818)
		)
		(stroke
			(width 0)
			(type solid)
		)
		(fill yes)
		(layer "In2.Cu")
		(net "M_K_DQ<61>")
	)
	(gr_poly
		(pts
			(xy 122.437144 -54.066948) (xy 122.429016 -53.875178) (xy 122.406918 -53.83657) (xy 122.061478 -54.036214)
			(xy 122.08383 -54.074568) (xy 122.245882 -54.177438)
		)
		(stroke
			(width 0)
			(type solid)
		)
		(fill yes)
		(layer "In2.Cu")
		(net "M_G_DQS_DN<16>")
	)
	(gr_poly
		(pts
			(xy 122.48515 -99.780598) (xy 122.4407 -99.780598) (xy 122.27052 -99.869498) (xy 122.27052 -100.090478)
			(xy 122.4407 -100.179378) (xy 122.48515 -100.179378)
		)
		(stroke
			(width 0)
			(type solid)
		)
		(fill yes)
		(layer "In2.Cu")
		(net "M_K_DQ<56>")
	)
	(gr_poly
		(pts
			(xy 122.48515 -98.789998) (xy 122.4407 -98.789998) (xy 122.27052 -98.878898) (xy 122.27052 -99.099878)
			(xy 122.4407 -99.188778) (xy 122.48515 -99.188778)
		)
		(stroke
			(width 0)
			(type solid)
		)
		(fill yes)
		(layer "In2.Cu")
		(net "M_K_DQ<56>")
	)
	(gr_poly
		(pts
			(xy 122.609102 -50.844704) (xy 122.577606 -50.813208) (xy 122.37847 -50.739548) (xy 122.216672 -50.901346)
			(xy 122.290332 -51.100482) (xy 122.321828 -51.131978)
		)
		(stroke
			(width 0)
			(type solid)
		)
		(fill yes)
		(layer "In2.Cu")
		(net "M_G_DQ<56>")
	)
	(gr_poly
		(pts
			(xy 122.617992 -102.051358) (xy 122.573288 -102.051358) (xy 122.380248 -102.140258) (xy 122.380502 -102.368858)
			(xy 122.573542 -102.457758) (xy 122.617992 -102.457758)
		)
		(stroke
			(width 0)
			(type solid)
		)
		(fill yes)
		(layer "In2.Cu")
		(net "M_K_DQ<56>")
	)
	(gr_poly
		(pts
			(xy 122.617992 -101.060758) (xy 122.573288 -101.060758) (xy 122.380248 -101.149658) (xy 122.380502 -101.378258)
			(xy 122.573542 -101.467158) (xy 122.617992 -101.467158)
		)
		(stroke
			(width 0)
			(type solid)
		)
		(fill yes)
		(layer "In2.Cu")
		(net "M_K_DQ<56>")
	)
	(gr_poly
		(pts
			(xy 122.661172 -54.306978) (xy 122.63882 -54.268624) (xy 122.476768 -54.165754) (xy 122.285506 -54.276244)
			(xy 122.293634 -54.468014) (xy 122.315732 -54.506622)
		)
		(stroke
			(width 0)
			(type solid)
		)
		(fill yes)
		(layer "In2.Cu")
		(net "M_G_DQS_DN<7>")
	)
	(gr_poly
		(pts
			(xy 122.706892 -105.146856) (xy 122.738134 -105.11536) (xy 122.45086 -104.828086) (xy 122.419364 -104.859582)
			(xy 122.345704 -105.058972) (xy 122.507502 -105.220516)
		)
		(stroke
			(width 0)
			(type solid)
		)
		(fill yes)
		(layer "In2.Cu")
		(net "M_K_DQ<60>")
	)
	(gr_poly
		(pts
			(xy 122.738896 -57.494678) (xy 122.738896 -57.273698) (xy 122.568716 -57.184798) (xy 122.524266 -57.184798)
			(xy 122.524266 -57.583578) (xy 122.568716 -57.583578)
		)
		(stroke
			(width 0)
			(type solid)
		)
		(fill yes)
		(layer "In2.Cu")
		(net "M_G_DQS_DP<7>")
	)
	(gr_poly
		(pts
			(xy 122.738896 -56.504078) (xy 122.738896 -56.283098) (xy 122.568716 -56.194198) (xy 122.524266 -56.194198)
			(xy 122.524266 -56.592978) (xy 122.568716 -56.592978)
		)
		(stroke
			(width 0)
			(type solid)
		)
		(fill yes)
		(layer "In2.Cu")
		(net "M_G_DQS_DP<7>")
	)
	(gr_poly
		(pts
			(xy 122.738896 -53.538374) (xy 122.738896 -53.317394) (xy 122.568716 -53.228494) (xy 122.524266 -53.228494)
			(xy 122.524266 -53.627274) (xy 122.568716 -53.627274)
		)
		(stroke
			(width 0)
			(type solid)
		)
		(fill yes)
		(layer "In2.Cu")
		(net "M_G_DQS_DN<16>")
	)
	(gr_poly
		(pts
			(xy 122.849386 -51.210718) (xy 122.775726 -51.011328) (xy 122.744484 -50.979832) (xy 122.456956 -51.26736)
			(xy 122.488452 -51.298602) (xy 122.687842 -51.372262)
		)
		(stroke
			(width 0)
			(type solid)
		)
		(fill yes)
		(layer "In2.Cu")
		(net "M_G_DQ<57>")
	)
	(gr_poly
		(pts
			(xy 122.877326 -51.929284) (xy 122.84583 -51.898042) (xy 122.64644 -51.824382) (xy 122.484896 -51.985926)
			(xy 122.558556 -52.185316) (xy 122.589798 -52.216812)
		)
		(stroke
			(width 0)
			(type solid)
		)
		(fill yes)
		(layer "In2.Cu")
		(net "M_G_DQS_DP<16>")
	)
	(gr_poly
		(pts
			(xy 122.904504 -104.949244) (xy 122.978164 -104.749854) (xy 122.816366 -104.58831) (xy 122.616976 -104.66197)
			(xy 122.585734 -104.693466) (xy 122.873008 -104.98074)
		)
		(stroke
			(width 0)
			(type solid)
		)
		(fill yes)
		(layer "In2.Cu")
		(net "M_K_DQ<61>")
	)
	(gr_poly
		(pts
			(xy 123.045982 -102.001828) (xy 123.045728 -101.773228) (xy 122.852688 -101.684328) (xy 122.808238 -101.684582)
			(xy 122.808238 -102.090728) (xy 122.852688 -102.090728)
		)
		(stroke
			(width 0)
			(type solid)
		)
		(fill yes)
		(layer "In2.Cu")
		(net "M_K_DQ<57>")
	)
	(gr_poly
		(pts
			(xy 123.045982 -101.011228) (xy 123.045728 -100.782628) (xy 122.852688 -100.693728) (xy 122.808238 -100.693982)
			(xy 122.808238 -101.100128) (xy 122.852688 -101.100128)
		)
		(stroke
			(width 0)
			(type solid)
		)
		(fill yes)
		(layer "In2.Cu")
		(net "M_K_DQ<57>")
	)
	(gr_poly
		(pts
			(xy 123.05919 -53.233574) (xy 123.01474 -53.233574) (xy 122.84456 -53.322474) (xy 122.84456 -53.543454)
			(xy 123.01474 -53.632354) (xy 123.05919 -53.632354)
		)
		(stroke
			(width 0)
			(type solid)
		)
		(fill yes)
		(layer "In2.Cu")
		(net "M_G_DQS_DN<7>")
	)
	(gr_poly
		(pts
			(xy 123.117102 -52.29479) (xy 123.043442 -52.095654) (xy 123.011946 -52.064158) (xy 122.724672 -52.351432)
			(xy 122.756168 -52.382928) (xy 122.955304 -52.456588)
		)
		(stroke
			(width 0)
			(type solid)
		)
		(fill yes)
		(layer "In2.Cu")
		(net "M_G_DQS_DN<16>")
	)
	(gr_poly
		(pts
			(xy 123.281186 -55.461662) (xy 123.296172 -55.270146) (xy 123.10872 -55.153052) (xy 122.943112 -55.25008)
			(xy 122.919744 -55.287926) (xy 123.257818 -55.499254)
		)
		(stroke
			(width 0)
			(type solid)
		)
		(fill yes)
		(layer "In2.Cu")
		(net "M_G_DQ<62>")
	)
	(gr_poly
		(pts
			(xy 123.299474 -54.559962) (xy 123.291346 -54.368192) (xy 123.269248 -54.329584) (xy 122.923808 -54.528974)
			(xy 122.94616 -54.567582) (xy 123.108212 -54.670452)
		)
		(stroke
			(width 0)
			(type solid)
		)
		(fill yes)
		(layer "In2.Cu")
		(net "M_G_DQS_DP<7>")
	)
	(gr_poly
		(pts
			(xy 123.34367 -102.269544) (xy 123.29922 -102.269544) (xy 123.12904 -102.358444) (xy 123.12904 -102.579424)
			(xy 123.29922 -102.668324) (xy 123.34367 -102.668324)
		)
		(stroke
			(width 0)
			(type solid)
		)
		(fill yes)
		(layer "In2.Cu")
		(net "M_K_DQS_DP<16>")
	)
	(gr_poly
		(pts
			(xy 123.34367 -101.272594) (xy 123.29922 -101.272594) (xy 123.12904 -101.361494) (xy 123.12904 -101.582474)
			(xy 123.29922 -101.671374) (xy 123.34367 -101.671374)
		)
		(stroke
			(width 0)
			(type solid)
		)
		(fill yes)
		(layer "In2.Cu")
		(net "M_K_DQS_DP<16>")
	)
	(gr_poly
		(pts
			(xy 123.34367 -100.275898) (xy 123.29922 -100.275898) (xy 123.12904 -100.364798) (xy 123.12904 -100.585778)
			(xy 123.29922 -100.674678) (xy 123.34367 -100.674678)
		)
		(stroke
			(width 0)
			(type solid)
		)
		(fill yes)
		(layer "In2.Cu")
		(net "M_K_DQS_DP<16>")
	)
	(gr_poly
		(pts
			(xy 123.34367 -99.285298) (xy 123.29922 -99.285298) (xy 123.12904 -99.374198) (xy 123.12904 -99.595178)
			(xy 123.29922 -99.684078) (xy 123.34367 -99.684078)
		)
		(stroke
			(width 0)
			(type solid)
		)
		(fill yes)
		(layer "In2.Cu")
		(net "M_K_DQS_DP<16>")
	)
	(gr_poly
		(pts
			(xy 123.40717 -105.847388) (xy 123.438666 -105.815892) (xy 123.151392 -105.528618) (xy 123.119896 -105.560114)
			(xy 123.046236 -105.75925) (xy 123.208034 -105.921048)
		)
		(stroke
			(width 0)
			(type solid)
		)
		(fill yes)
		(layer "In2.Cu")
		(net "M_K_DQ<60>")
	)
	(gr_poly
		(pts
			(xy 123.49734 -56.054498) (xy 123.519692 -56.016144) (xy 123.174252 -55.816754) (xy 123.152154 -55.855108)
			(xy 123.144026 -56.046878) (xy 123.335288 -56.157368)
		)
		(stroke
			(width 0)
			(type solid)
		)
		(fill yes)
		(layer "In2.Cu")
		(net "M_G_DQ<63>")
	)
	(gr_poly
		(pts
			(xy 123.502166 -104.351582) (xy 123.533408 -104.320086) (xy 123.246134 -104.032812) (xy 123.214638 -104.064308)
			(xy 123.140978 -104.263698) (xy 123.302776 -104.425242)
		)
		(stroke
			(width 0)
			(type solid)
		)
		(fill yes)
		(layer "In2.Cu")
		(net "M_K_DQ<56>")
	)
	(gr_poly
		(pts
			(xy 123.526296 -56.77154) (xy 123.502674 -56.733948) (xy 123.337066 -56.636666) (xy 123.149614 -56.754014)
			(xy 123.1646 -56.945022) (xy 123.187968 -56.983122)
		)
		(stroke
			(width 0)
			(type solid)
		)
		(fill yes)
		(layer "In2.Cu")
		(net "M_G_DQ<58>")
	)
	(gr_poly
		(pts
			(xy 123.588526 -51.218084) (xy 123.55703 -51.186842) (xy 123.35764 -51.113182) (xy 123.196096 -51.274726)
			(xy 123.269756 -51.474116) (xy 123.300998 -51.505612)
		)
		(stroke
			(width 0)
			(type solid)
		)
		(fill yes)
		(layer "In2.Cu")
		(net "M_G_DQS_DP<16>")
	)
	(gr_poly
		(pts
			(xy 123.597416 -58.002424) (xy 123.597416 -57.781444) (xy 123.427236 -57.692544) (xy 123.382786 -57.692544)
			(xy 123.382786 -58.091324) (xy 123.427236 -58.091324)
		)
		(stroke
			(width 0)
			(type solid)
		)
		(fill yes)
		(layer "In2.Cu")
		(net "M_G_DQ<59>")
	)
	(gr_poly
		(pts
			(xy 123.597416 -54.033674) (xy 123.597416 -53.812694) (xy 123.427236 -53.723794) (xy 123.382786 -53.723794)
			(xy 123.382786 -54.122574) (xy 123.427236 -54.122574)
		)
		(stroke
			(width 0)
			(type solid)
		)
		(fill yes)
		(layer "In2.Cu")
		(net "M_G_DQS_DP<7>")
	)
	(gr_poly
		(pts
			(xy 123.604782 -105.649776) (xy 123.678442 -105.450386) (xy 123.516898 -105.288842) (xy 123.317508 -105.362502)
			(xy 123.286012 -105.393744) (xy 123.57354 -105.681272)
		)
		(stroke
			(width 0)
			(type solid)
		)
		(fill yes)
		(layer "In2.Cu")
		(net "M_K_DQ<61>")
	)
	(gr_poly
		(pts
			(xy 123.699778 -104.15397) (xy 123.773438 -103.95458) (xy 123.61164 -103.793036) (xy 123.41225 -103.866696)
			(xy 123.381008 -103.898192) (xy 123.668282 -104.185466)
		)
		(stroke
			(width 0)
			(type solid)
		)
		(fill yes)
		(layer "In2.Cu")
		(net "M_K_DQ<57>")
	)
	(gr_poly
		(pts
			(xy 123.813316 -52.46243) (xy 123.78182 -52.431188) (xy 123.58243 -52.357528) (xy 123.420886 -52.519072)
			(xy 123.494546 -52.718462) (xy 123.525788 -52.749958)
		)
		(stroke
			(width 0)
			(type solid)
		)
		(fill yes)
		(layer "In2.Cu")
		(net "M_G_DQS_DN<7>")
	)
	(gr_poly
		(pts
			(xy 123.828302 -51.58359) (xy 123.754642 -51.384454) (xy 123.723146 -51.352958) (xy 123.435872 -51.640232)
			(xy 123.467368 -51.671728) (xy 123.666504 -51.745388)
		)
		(stroke
			(width 0)
			(type solid)
		)
		(fill yes)
		(layer "In2.Cu")
		(net "M_G_DQS_DN<16>")
	)
	(gr_poly
		(pts
			(xy 123.881896 -102.071678) (xy 123.881896 -101.850698) (xy 123.711716 -101.761798) (xy 123.667266 -101.761798)
			(xy 123.667266 -102.160578) (xy 123.711716 -102.160578)
		)
		(stroke
			(width 0)
			(type solid)
		)
		(fill yes)
		(layer "In2.Cu")
		(net "M_K_DQS_DN<16>")
	)
	(gr_poly
		(pts
			(xy 123.881896 -101.093524) (xy 123.881896 -100.872544) (xy 123.711716 -100.783644) (xy 123.667266 -100.783644)
			(xy 123.667266 -101.182424) (xy 123.711716 -101.182424)
		)
		(stroke
			(width 0)
			(type solid)
		)
		(fill yes)
		(layer "In2.Cu")
		(net "M_K_DQS_DN<16>")
	)
	(gr_poly
		(pts
			(xy 123.881896 -100.096828) (xy 123.881896 -99.875848) (xy 123.711716 -99.786948) (xy 123.667266 -99.786948)
			(xy 123.667266 -100.185728) (xy 123.711716 -100.185728)
		)
		(stroke
			(width 0)
			(type solid)
		)
		(fill yes)
		(layer "In2.Cu")
		(net "M_K_DQS_DN<16>")
	)
	(gr_poly
		(pts
			(xy 124.053092 -52.827936) (xy 123.979432 -52.6288) (xy 123.947936 -52.597304) (xy 123.660662 -52.884578)
			(xy 123.692158 -52.916074) (xy 123.891294 -52.989734)
		)
		(stroke
			(width 0)
			(type solid)
		)
		(fill yes)
		(layer "In2.Cu")
		(net "M_G_DQS_DP<7>")
	)
	(gr_poly
		(pts
			(xy 124.063252 -54.769004) (xy 124.018802 -54.769004) (xy 123.825762 -54.857904) (xy 123.825762 -55.086504)
			(xy 124.018802 -55.175404) (xy 124.063252 -55.175404)
		)
		(stroke
			(width 0)
			(type solid)
		)
		(fill yes)
		(layer "In2.Cu")
		(net "M_G_DQ<62>")
	)
	(gr_poly
		(pts
			(xy 124.063252 -53.778404) (xy 124.018802 -53.778404) (xy 123.825762 -53.867304) (xy 123.825762 -54.095904)
			(xy 124.018802 -54.184804) (xy 124.063252 -54.184804)
		)
		(stroke
			(width 0)
			(type solid)
		)
		(fill yes)
		(layer "In2.Cu")
		(net "M_G_DQ<62>")
	)
	(gr_poly
		(pts
			(xy 124.107702 -106.54792) (xy 124.139198 -106.516424) (xy 123.851924 -106.22915) (xy 123.820428 -106.260392)
			(xy 123.746768 -106.459782) (xy 123.908312 -106.62158)
		)
		(stroke
			(width 0)
			(type solid)
		)
		(fill yes)
		(layer "In2.Cu")
		(net "M_K_DQ<60>")
	)
	(gr_poly
		(pts
			(xy 124.122942 -103.728266) (xy 124.154438 -103.69677) (xy 123.867164 -103.409496) (xy 123.835668 -103.440992)
			(xy 123.762008 -103.640128) (xy 123.923806 -103.801926)
		)
		(stroke
			(width 0)
			(type solid)
		)
		(fill yes)
		(layer "In2.Cu")
		(net "M_K_DQS_DP<16>")
	)
	(gr_poly
		(pts
			(xy 124.20219 -100.783644) (xy 124.15774 -100.783644) (xy 123.98756 -100.872544) (xy 123.98756 -101.093524)
			(xy 124.15774 -101.182424) (xy 124.20219 -101.182424)
		)
		(stroke
			(width 0)
			(type solid)
		)
		(fill yes)
		(layer "In2.Cu")
		(net "M_K_DQS_DN<7>")
	)
	(gr_poly
		(pts
			(xy 124.20219 -99.786948) (xy 124.15774 -99.786948) (xy 123.98756 -99.875848) (xy 123.98756 -100.096828)
			(xy 124.15774 -100.185728) (xy 124.20219 -100.185728)
		)
		(stroke
			(width 0)
			(type solid)
		)
		(fill yes)
		(layer "In2.Cu")
		(net "M_K_DQS_DN<7>")
	)
	(gr_poly
		(pts
			(xy 124.202444 -105.052114) (xy 124.23394 -105.020618) (xy 123.946666 -104.733344) (xy 123.91517 -104.76484)
			(xy 123.84151 -104.963976) (xy 124.003308 -105.125774)
		)
		(stroke
			(width 0)
			(type solid)
		)
		(fill yes)
		(layer "In2.Cu")
		(net "M_K_DQ<56>")
	)
	(gr_poly
		(pts
			(xy 124.305314 -106.350308) (xy 124.378974 -106.150918) (xy 124.21743 -105.98912) (xy 124.01804 -106.06278)
			(xy 123.986544 -106.094276) (xy 124.273818 -106.38155)
		)
		(stroke
			(width 0)
			(type solid)
		)
		(fill yes)
		(layer "In2.Cu")
		(net "M_K_DQ<61>")
	)
	(gr_poly
		(pts
			(xy 124.320808 -103.5304) (xy 124.394468 -103.331264) (xy 124.23267 -103.169466) (xy 124.033534 -103.243126)
			(xy 124.002038 -103.274622) (xy 124.289312 -103.561896)
		)
		(stroke
			(width 0)
			(type solid)
		)
		(fill yes)
		(layer "In2.Cu")
		(net "M_K_DQS_DN<16>")
	)
	(gr_poly
		(pts
			(xy 124.400056 -104.854502) (xy 124.473716 -104.655112) (xy 124.312172 -104.493568) (xy 124.112782 -104.567228)
			(xy 124.081286 -104.59847) (xy 124.368814 -104.885998)
		)
		(stroke
			(width 0)
			(type solid)
		)
		(fill yes)
		(layer "In2.Cu")
		(net "M_K_DQ<57>")
	)
	(gr_poly
		(pts
			(xy 124.491242 -55.086504) (xy 124.491242 -54.857904) (xy 124.298202 -54.769004) (xy 124.253752 -54.769004)
			(xy 124.253752 -55.175404) (xy 124.298202 -55.175404)
		)
		(stroke
			(width 0)
			(type solid)
		)
		(fill yes)
		(layer "In2.Cu")
		(net "M_G_DQ<63>")
	)
	(gr_poly
		(pts
			(xy 124.491242 -54.095904) (xy 124.491242 -53.867304) (xy 124.298202 -53.778404) (xy 124.253752 -53.778404)
			(xy 124.253752 -54.184804) (xy 124.298202 -54.184804)
		)
		(stroke
			(width 0)
			(type solid)
		)
		(fill yes)
		(layer "In2.Cu")
		(net "M_G_DQ<63>")
	)
	(gr_poly
		(pts
			(xy 124.600716 -53.026056) (xy 124.56922 -52.99456) (xy 124.36983 -52.921154) (xy 124.208286 -53.082698)
			(xy 124.281946 -53.282088) (xy 124.313188 -53.313584)
		)
		(stroke
			(width 0)
			(type solid)
		)
		(fill yes)
		(layer "In2.Cu")
		(net "M_G_DQ<62>")
	)
	(gr_poly
		(pts
			(xy 124.666502 -56.348884) (xy 124.635006 -56.317388) (xy 124.43587 -56.243728) (xy 124.274072 -56.405526)
			(xy 124.347732 -56.604662) (xy 124.379228 -56.636158)
		)
		(stroke
			(width 0)
			(type solid)
		)
		(fill yes)
		(layer "In2.Cu")
		(net "M_G_DQ<58>")
	)
	(gr_poly
		(pts
			(xy 124.739908 -99.593908) (xy 124.739908 -99.372928) (xy 124.569728 -99.284028) (xy 124.525278 -99.284028)
			(xy 124.525278 -99.682808) (xy 124.569728 -99.682808)
		)
		(stroke
			(width 0)
			(type solid)
		)
		(fill yes)
		(layer "In2.Cu")
		(net "M_K_DQS_DP<7>")
	)
	(gr_poly
		(pts
			(xy 124.740416 -101.582474) (xy 124.740416 -101.361494) (xy 124.570236 -101.272594) (xy 124.525786 -101.272594)
			(xy 124.525786 -101.671374) (xy 124.570236 -101.671374)
		)
		(stroke
			(width 0)
			(type solid)
		)
		(fill yes)
		(layer "In2.Cu")
		(net "M_K_DQS_DP<7>")
	)
	(gr_poly
		(pts
			(xy 124.740416 -100.585778) (xy 124.740416 -100.364798) (xy 124.570236 -100.275898) (xy 124.525786 -100.275898)
			(xy 124.525786 -100.674678) (xy 124.570236 -100.674678)
		)
		(stroke
			(width 0)
			(type solid)
		)
		(fill yes)
		(layer "In2.Cu")
		(net "M_K_DQS_DP<7>")
	)
	(gr_poly
		(pts
			(xy 124.830332 -55.213504) (xy 124.785882 -55.213504) (xy 124.592842 -55.302404) (xy 124.592842 -55.531004)
			(xy 124.785882 -55.619904) (xy 124.830332 -55.619904)
		)
		(stroke
			(width 0)
			(type solid)
		)
		(fill yes)
		(layer "In2.Cu")
		(net "M_G_DQ<58>")
	)
	(gr_poly
		(pts
			(xy 124.830332 -54.222904) (xy 124.785882 -54.222904) (xy 124.592842 -54.311804) (xy 124.592842 -54.540404)
			(xy 124.785882 -54.629304) (xy 124.830332 -54.629304)
		)
		(stroke
			(width 0)
			(type solid)
		)
		(fill yes)
		(layer "In2.Cu")
		(net "M_G_DQ<58>")
	)
	(gr_poly
		(pts
			(xy 124.834142 -104.439466) (xy 124.865638 -104.40797) (xy 124.578364 -104.120696) (xy 124.546868 -104.152192)
			(xy 124.473208 -104.351328) (xy 124.635006 -104.513126)
		)
		(stroke
			(width 0)
			(type solid)
		)
		(fill yes)
		(layer "In2.Cu")
		(net "M_K_DQS_DP<16>")
	)
	(gr_poly
		(pts
			(xy 124.839222 -53.393086) (xy 124.765562 -53.193696) (xy 124.734066 -53.1622) (xy 124.446792 -53.449728)
			(xy 124.478034 -53.481224) (xy 124.677424 -53.554884)
		)
		(stroke
			(width 0)
			(type solid)
		)
		(fill yes)
		(layer "In2.Cu")
		(net "M_G_DQ<63>")
	)
	(gr_poly
		(pts
			(xy 124.902976 -105.752646) (xy 124.934472 -105.72115) (xy 124.647198 -105.433876) (xy 124.615702 -105.465118)
			(xy 124.542042 -105.664508) (xy 124.703586 -105.826306)
		)
		(stroke
			(width 0)
			(type solid)
		)
		(fill yes)
		(layer "In2.Cu")
		(net "M_K_DQ<56>")
	)
	(gr_poly
		(pts
			(xy 124.906278 -56.71439) (xy 124.832618 -56.515) (xy 124.801376 -56.483504) (xy 124.513848 -56.771032)
			(xy 124.545344 -56.802274) (xy 124.744734 -56.875934)
		)
		(stroke
			(width 0)
			(type solid)
		)
		(fill yes)
		(layer "In2.Cu")
		(net "M_G_DQ<59>")
	)
	(gr_poly
		(pts
			(xy 125.032008 -104.2416) (xy 125.105668 -104.042464) (xy 124.94387 -103.880666) (xy 124.744734 -103.954326)
			(xy 124.713238 -103.985822) (xy 125.000512 -104.273096)
		)
		(stroke
			(width 0)
			(type solid)
		)
		(fill yes)
		(layer "In2.Cu")
		(net "M_K_DQS_DN<16>")
	)
	(gr_poly
		(pts
			(xy 125.04293 -103.55961) (xy 125.074426 -103.528114) (xy 124.787152 -103.24084) (xy 124.755656 -103.272336)
			(xy 124.681996 -103.471472) (xy 124.843794 -103.63327)
		)
		(stroke
			(width 0)
			(type solid)
		)
		(fill yes)
		(layer "In2.Cu")
		(net "M_K_DQS_DN<7>")
	)
	(gr_poly
		(pts
			(xy 125.06071 -101.272594) (xy 125.01626 -101.272594) (xy 124.84608 -101.361494) (xy 124.84608 -101.582474)
			(xy 125.01626 -101.671374) (xy 125.06071 -101.671374)
		)
		(stroke
			(width 0)
			(type solid)
		)
		(fill yes)
		(layer "In2.Cu")
		(net "M_K_DQ<63>")
	)
	(gr_poly
		(pts
			(xy 125.100588 -105.555034) (xy 125.174248 -105.355644) (xy 125.012704 -105.193846) (xy 124.813314 -105.267506)
			(xy 124.781818 -105.299002) (xy 125.069092 -105.586276)
		)
		(stroke
			(width 0)
			(type solid)
		)
		(fill yes)
		(layer "In2.Cu")
		(net "M_K_DQ<57>")
	)
	(gr_poly
		(pts
			(xy 125.240542 -103.361998) (xy 125.314202 -103.162608) (xy 125.152658 -103.001064) (xy 124.953268 -103.074724)
			(xy 124.921772 -103.105966) (xy 125.2093 -103.393494)
		)
		(stroke
			(width 0)
			(type solid)
		)
		(fill yes)
		(layer "In2.Cu")
		(net "M_K_DQS_DP<7>")
	)
	(gr_poly
		(pts
			(xy 125.258322 -55.531004) (xy 125.258322 -55.302404) (xy 125.065282 -55.213504) (xy 125.020832 -55.213504)
			(xy 125.020832 -55.619904) (xy 125.065282 -55.619904)
		)
		(stroke
			(width 0)
			(type solid)
		)
		(fill yes)
		(layer "In2.Cu")
		(net "M_G_DQ<59>")
	)
	(gr_poly
		(pts
			(xy 125.258322 -54.540404) (xy 125.258322 -54.311804) (xy 125.065282 -54.222904) (xy 125.020832 -54.222904)
			(xy 125.020832 -54.629304) (xy 125.065282 -54.629304)
		)
		(stroke
			(width 0)
			(type solid)
		)
		(fill yes)
		(layer "In2.Cu")
		(net "M_G_DQ<59>")
	)
	(gr_poly
		(pts
			(xy 125.311916 -52.314856) (xy 125.28042 -52.28336) (xy 125.08103 -52.209954) (xy 124.919486 -52.371498)
			(xy 124.993146 -52.570888) (xy 125.024388 -52.602384)
		)
		(stroke
			(width 0)
			(type solid)
		)
		(fill yes)
		(layer "In2.Cu")
		(net "M_G_DQ<62>")
	)
	(gr_poly
		(pts
			(xy 125.479302 -53.231542) (xy 125.447806 -53.2003) (xy 125.248416 -53.12664) (xy 125.086872 -53.288184)
			(xy 125.160532 -53.487574) (xy 125.191774 -53.51907)
		)
		(stroke
			(width 0)
			(type solid)
		)
		(fill yes)
		(layer "In2.Cu")
		(net "M_G_DQ<58>")
	)
	(gr_poly
		(pts
			(xy 125.550422 -52.681886) (xy 125.476762 -52.482496) (xy 125.445266 -52.451) (xy 125.157992 -52.738528)
			(xy 125.189234 -52.770024) (xy 125.388624 -52.843684)
		)
		(stroke
			(width 0)
			(type solid)
		)
		(fill yes)
		(layer "In2.Cu")
		(net "M_G_DQ<63>")
	)
	(gr_poly
		(pts
			(xy 125.614176 -106.463846) (xy 125.645672 -106.43235) (xy 125.358398 -106.145076) (xy 125.326902 -106.176318)
			(xy 125.253242 -106.375708) (xy 125.414786 -106.537506)
		)
		(stroke
			(width 0)
			(type solid)
		)
		(fill yes)
		(layer "In2.Cu")
		(net "M_K_DQ<56>")
	)
	(gr_poly
		(pts
			(xy 125.75413 -104.27081) (xy 125.785626 -104.239314) (xy 125.498352 -103.95204) (xy 125.466856 -103.983536)
			(xy 125.393196 -104.182672) (xy 125.554994 -104.34447)
		)
		(stroke
			(width 0)
			(type solid)
		)
		(fill yes)
		(layer "In2.Cu")
		(net "M_K_DQS_DN<7>")
	)
	(gr_poly
		(pts
			(xy 125.811788 -106.266234) (xy 125.885448 -106.066844) (xy 125.723904 -105.905046) (xy 125.524514 -105.978706)
			(xy 125.493018 -106.010202) (xy 125.780292 -106.297476)
		)
		(stroke
			(width 0)
			(type solid)
		)
		(fill yes)
		(layer "In2.Cu")
		(net "M_K_DQ<57>")
	)
	(gr_poly
		(pts
			(xy 125.81763 -103.29291) (xy 125.849126 -103.261414) (xy 125.561852 -102.97414) (xy 125.530356 -103.005636)
			(xy 125.456696 -103.204772) (xy 125.618494 -103.36657)
		)
		(stroke
			(width 0)
			(type solid)
		)
		(fill yes)
		(layer "In2.Cu")
		(net "M_K_DQ<62>")
	)
	(gr_poly
		(pts
			(xy 125.951742 -104.073198) (xy 126.025402 -103.873808) (xy 125.863858 -103.712264) (xy 125.664468 -103.785924)
			(xy 125.632972 -103.817166) (xy 125.9205 -104.104694)
		)
		(stroke
			(width 0)
			(type solid)
		)
		(fill yes)
		(layer "In2.Cu")
		(net "M_K_DQS_DP<7>")
	)
	(gr_poly
		(pts
			(xy 125.973078 -53.343302) (xy 125.899418 -53.143912) (xy 125.868176 -53.112416) (xy 125.580648 -53.399944)
			(xy 125.612144 -53.431186) (xy 125.811534 -53.504846)
		)
		(stroke
			(width 0)
			(type solid)
		)
		(fill yes)
		(layer "In2.Cu")
		(net "M_G_DQ<59>")
	)
	(gr_poly
		(pts
			(xy 126.015496 -103.095044) (xy 126.089156 -102.895908) (xy 125.927358 -102.73411) (xy 125.728222 -102.80777)
			(xy 125.696726 -102.839266) (xy 125.984 -103.12654)
		)
		(stroke
			(width 0)
			(type solid)
		)
		(fill yes)
		(layer "In2.Cu")
		(net "M_K_DQ<63>")
	)
	(gr_poly
		(pts
			(xy 126.685548 -105.20045) (xy 126.685548 -105.156) (xy 126.279148 -105.156) (xy 126.279148 -105.20045)
			(xy 126.368048 -105.39349) (xy 126.596648 -105.39349)
		)
		(stroke
			(width 0)
			(type solid)
		)
		(fill yes)
		(layer "In2.Cu")
		(net "M_K_DQS_DP<16>")
	)
	(gr_poly
		(pts
			(xy 126.685548 -104.92105) (xy 126.596648 -104.72801) (xy 126.368048 -104.72801) (xy 126.279148 -104.92105)
			(xy 126.279148 -104.9655) (xy 126.685548 -104.9655)
		)
		(stroke
			(width 0)
			(type solid)
		)
		(fill yes)
		(layer "In2.Cu")
		(net "M_K_DQS_DN<16>")
	)
	(gr_poly
		(pts
			(xy 127.066548 -104.457754) (xy 127.066548 -104.413304) (xy 126.660148 -104.413304) (xy 126.660148 -104.457754)
			(xy 126.749048 -104.650794) (xy 126.977648 -104.650794)
		)
		(stroke
			(width 0)
			(type solid)
		)
		(fill yes)
		(layer "In2.Cu")
		(net "M_K_DQS_DN<7>")
	)
	(gr_poly
		(pts
			(xy 127.066548 -104.178354) (xy 126.977648 -103.985314) (xy 126.749048 -103.985314) (xy 126.660148 -104.178354)
			(xy 126.660148 -104.222804) (xy 127.066548 -104.222804)
		)
		(stroke
			(width 0)
			(type solid)
		)
		(fill yes)
		(layer "In2.Cu")
		(net "M_K_DQS_DP<7>")
	)
	(gr_poly
		(pts
			(xy 127.479044 -103.002842) (xy 127.479044 -102.958392) (xy 127.072644 -102.958392) (xy 127.072644 -103.002842)
			(xy 127.161544 -103.195882) (xy 127.390144 -103.195882)
		)
		(stroke
			(width 0)
			(type solid)
		)
		(fill yes)
		(layer "In2.Cu")
		(net "M_K_DQ<58>")
	)
	(gr_poly
		(pts
			(xy 127.479044 -102.723442) (xy 127.390144 -102.530402) (xy 127.161544 -102.530402) (xy 127.072644 -102.723442)
			(xy 127.072644 -102.767892) (xy 127.479044 -102.767892)
		)
		(stroke
			(width 0)
			(type solid)
		)
		(fill yes)
		(layer "In2.Cu")
		(net "M_K_DQ<59>")
	)
	(gr_poly
		(pts
			(xy 127.930148 -103.72725) (xy 127.930148 -103.6828) (xy 127.523748 -103.6828) (xy 127.523748 -103.72725)
			(xy 127.612648 -103.92029) (xy 127.841248 -103.92029)
		)
		(stroke
			(width 0)
			(type solid)
		)
		(fill yes)
		(layer "In2.Cu")
		(net "M_K_DQ<62>")
	)
	(gr_poly
		(pts
			(xy 127.930148 -103.44785) (xy 127.841248 -103.25481) (xy 127.612648 -103.25481) (xy 127.523748 -103.44785)
			(xy 127.523748 -103.4923) (xy 127.930148 -103.4923)
		)
		(stroke
			(width 0)
			(type solid)
		)
		(fill yes)
		(layer "In2.Cu")
		(net "M_K_DQ<63>")
	)
	(gr_poly
		(pts
			(xy 127.948182 -105.8164) (xy 127.979678 -105.784904) (xy 127.692404 -105.49763) (xy 127.660908 -105.529126)
			(xy 127.587248 -105.728262) (xy 127.749046 -105.89006)
		)
		(stroke
			(width 0)
			(type solid)
		)
		(fill yes)
		(layer "In2.Cu")
		(net "M_K_DQS_DP<16>")
	)
	(gr_poly
		(pts
			(xy 128.145794 -105.618788) (xy 128.219454 -105.419398) (xy 128.05791 -105.257854) (xy 127.85852 -105.331514)
			(xy 127.827024 -105.362756) (xy 128.114552 -105.650284)
		)
		(stroke
			(width 0)
			(type solid)
		)
		(fill yes)
		(layer "In2.Cu")
		(net "M_K_DQS_DN<16>")
	)
	(gr_poly
		(pts
			(xy 128.246632 -105.00995) (xy 128.278128 -104.978454) (xy 127.990854 -104.69118) (xy 127.959358 -104.722676)
			(xy 127.885698 -104.921812) (xy 128.047496 -105.08361)
		)
		(stroke
			(width 0)
			(type solid)
		)
		(fill yes)
		(layer "In2.Cu")
		(net "M_K_DQS_DN<7>")
	)
	(gr_poly
		(pts
			(xy 128.444244 -104.812338) (xy 128.517904 -104.612948) (xy 128.35636 -104.451404) (xy 128.15697 -104.525064)
			(xy 128.125474 -104.556306) (xy 128.413002 -104.843834)
		)
		(stroke
			(width 0)
			(type solid)
		)
		(fill yes)
		(layer "In2.Cu")
		(net "M_K_DQS_DP<7>")
	)
	(gr_poly
		(pts
			(xy 128.469644 -103.002842) (xy 128.469644 -102.958392) (xy 128.063244 -102.958392) (xy 128.063244 -103.002842)
			(xy 128.152144 -103.195882) (xy 128.380744 -103.195882)
		)
		(stroke
			(width 0)
			(type solid)
		)
		(fill yes)
		(layer "In2.Cu")
		(net "M_K_DQ<58>")
	)
	(gr_poly
		(pts
			(xy 128.469644 -102.723442) (xy 128.380744 -102.530402) (xy 128.152144 -102.530402) (xy 128.063244 -102.723442)
			(xy 128.063244 -102.767892) (xy 128.469644 -102.767892)
		)
		(stroke
			(width 0)
			(type solid)
		)
		(fill yes)
		(layer "In2.Cu")
		(net "M_K_DQ<59>")
	)
	(gr_poly
		(pts
			(xy 128.920748 -103.72725) (xy 128.920748 -103.6828) (xy 128.514348 -103.6828) (xy 128.514348 -103.72725)
			(xy 128.603248 -103.92029) (xy 128.831848 -103.92029)
		)
		(stroke
			(width 0)
			(type solid)
		)
		(fill yes)
		(layer "In2.Cu")
		(net "M_K_DQ<62>")
	)
	(gr_poly
		(pts
			(xy 128.920748 -103.44785) (xy 128.831848 -103.25481) (xy 128.603248 -103.25481) (xy 128.514348 -103.44785)
			(xy 128.514348 -103.4923) (xy 128.920748 -103.4923)
		)
		(stroke
			(width 0)
			(type solid)
		)
		(fill yes)
		(layer "In2.Cu")
		(net "M_K_DQ<63>")
	)
	(gr_poly
		(pts
			(xy 129.460244 -103.002842) (xy 129.460244 -102.958392) (xy 129.053844 -102.958392) (xy 129.053844 -103.002842)
			(xy 129.142744 -103.195882) (xy 129.371344 -103.195882)
		)
		(stroke
			(width 0)
			(type solid)
		)
		(fill yes)
		(layer "In2.Cu")
		(net "M_K_DQ<58>")
	)
	(gr_poly
		(pts
			(xy 129.460244 -102.723442) (xy 129.371344 -102.530402) (xy 129.142744 -102.530402) (xy 129.053844 -102.723442)
			(xy 129.053844 -102.767892) (xy 129.460244 -102.767892)
		)
		(stroke
			(width 0)
			(type solid)
		)
		(fill yes)
		(layer "In2.Cu")
		(net "M_K_DQ<59>")
	)
	(gr_poly
		(pts
			(xy 129.941066 -104.227884) (xy 129.972562 -104.196642) (xy 129.685034 -103.909114) (xy 129.653792 -103.94061)
			(xy 129.580132 -104.14) (xy 129.741676 -104.301544)
		)
		(stroke
			(width 0)
			(type solid)
		)
		(fill yes)
		(layer "In2.Cu")
		(net "M_K_DQ<62>")
	)
	(gr_poly
		(pts
			(xy 130.138678 -104.030272) (xy 130.212338 -103.830882) (xy 130.050794 -103.669338) (xy 129.851404 -103.742998)
			(xy 129.819908 -103.77424) (xy 130.107436 -104.061768)
		)
		(stroke
			(width 0)
			(type solid)
		)
		(fill yes)
		(layer "In2.Cu")
		(net "M_K_DQ<63>")
	)
	(gr_poly
		(pts
			(xy 130.278124 -103.497126) (xy 130.30962 -103.465884) (xy 130.022092 -103.178356) (xy 129.99085 -103.209852)
			(xy 129.91719 -103.409242) (xy 130.078734 -103.570786)
		)
		(stroke
			(width 0)
			(type solid)
		)
		(fill yes)
		(layer "In2.Cu")
		(net "M_K_DQ<58>")
	)
	(gr_poly
		(pts
			(xy 130.475736 -103.299514) (xy 130.549396 -103.100124) (xy 130.387852 -102.93858) (xy 130.188462 -103.01224)
			(xy 130.156966 -103.043482) (xy 130.444494 -103.33101)
		)
		(stroke
			(width 0)
			(type solid)
		)
		(fill yes)
		(layer "In2.Cu")
		(net "M_K_DQ<59>")
	)
	(gr_poly
		(pts
			(xy 130.641598 -104.928416) (xy 130.67284 -104.89692) (xy 130.385566 -104.609646) (xy 130.35407 -104.641142)
			(xy 130.28041 -104.840532) (xy 130.442208 -105.002076)
		)
		(stroke
			(width 0)
			(type solid)
		)
		(fill yes)
		(layer "In2.Cu")
		(net "M_K_DQ<62>")
	)
	(gr_poly
		(pts
			(xy 130.849878 -104.741472) (xy 130.923538 -104.542082) (xy 130.761994 -104.380538) (xy 130.562604 -104.454198)
			(xy 130.531108 -104.48544) (xy 130.818636 -104.772968)
		)
		(stroke
			(width 0)
			(type solid)
		)
		(fill yes)
		(layer "In2.Cu")
		(net "M_K_DQ<63>")
	)
	(gr_poly
		(pts
			(xy 130.989324 -104.208326) (xy 131.02082 -104.177084) (xy 130.733292 -103.889556) (xy 130.70205 -103.921052)
			(xy 130.62839 -104.120442) (xy 130.789934 -104.281986)
		)
		(stroke
			(width 0)
			(type solid)
		)
		(fill yes)
		(layer "In2.Cu")
		(net "M_K_DQ<58>")
	)
	(gr_poly
		(pts
			(xy 131.186936 -104.010714) (xy 131.260596 -103.811324) (xy 131.099052 -103.64978) (xy 130.899662 -103.72344)
			(xy 130.868166 -103.754682) (xy 131.155694 -104.04221)
		)
		(stroke
			(width 0)
			(type solid)
		)
		(fill yes)
		(layer "In2.Cu")
		(net "M_K_DQ<59>")
	)
	(gr_poly
		(pts
			(xy 132.076952 -104.46385) (xy 132.076952 -104.4194) (xy 131.670552 -104.4194) (xy 131.670552 -104.46385)
			(xy 131.759452 -104.65689) (xy 131.988052 -104.65689)
		)
		(stroke
			(width 0)
			(type solid)
		)
		(fill yes)
		(layer "In2.Cu")
		(net "M_K_DQ<58>")
	)
	(gr_poly
		(pts
			(xy 132.122926 -104.18445) (xy 132.034026 -103.99141) (xy 131.805426 -103.99141) (xy 131.716526 -104.18445)
			(xy 131.716526 -104.2289) (xy 132.122926 -104.2289)
		)
		(stroke
			(width 0)
			(type solid)
		)
		(fill yes)
		(layer "In2.Cu")
		(net "M_K_DQ<59>")
	)
	(gr_poly
		(pts
			(xy 132.165344 -105.55605) (xy 132.165344 -105.5116) (xy 131.758944 -105.5116) (xy 131.758944 -105.55605)
			(xy 131.847844 -105.74909) (xy 132.076444 -105.74909)
		)
		(stroke
			(width 0)
			(type solid)
		)
		(fill yes)
		(layer "In2.Cu")
		(net "M_K_DQ<62>")
	)
	(gr_poly
		(pts
			(xy 132.165344 -105.27665) (xy 132.076444 -105.08361) (xy 131.847844 -105.08361) (xy 131.758944 -105.27665)
			(xy 131.758944 -105.3211) (xy 132.165344 -105.3211)
		)
		(stroke
			(width 0)
			(type solid)
		)
		(fill yes)
		(layer "In2.Cu")
		(net "M_K_DQ<63>")
	)
	(gr_poly
		(pts
			(xy 230.480616 -98.931222) (xy 230.44912 -98.899726) (xy 230.249984 -98.826066) (xy 230.088186 -98.987864)
			(xy 230.161846 -99.187) (xy 230.193342 -99.218496)
		)
		(stroke
			(width 0)
			(type solid)
		)
		(fill yes)
		(layer "In2.Cu")
		(net "M_D_DQ<18>")
	)
	(gr_poly
		(pts
			(xy 230.56596 -95.340424) (xy 230.534464 -95.309182) (xy 230.335074 -95.235522) (xy 230.17353 -95.397066)
			(xy 230.24719 -95.596456) (xy 230.278432 -95.627952)
		)
		(stroke
			(width 0)
			(type solid)
		)
		(fill yes)
		(layer "In2.Cu")
		(net "M_D_DQS_DN<2>")
	)
	(gr_poly
		(pts
			(xy 230.720138 -99.29622) (xy 230.646478 -99.097084) (xy 230.614982 -99.065588) (xy 230.327708 -99.352862)
			(xy 230.359204 -99.384358) (xy 230.55834 -99.458018)
		)
		(stroke
			(width 0)
			(type solid)
		)
		(fill yes)
		(layer "In2.Cu")
		(net "M_D_DQ<19>")
	)
	(gr_poly
		(pts
			(xy 230.811832 -95.700088) (xy 230.738172 -95.500952) (xy 230.706676 -95.469456) (xy 230.419402 -95.75673)
			(xy 230.450898 -95.788226) (xy 230.650034 -95.861886)
		)
		(stroke
			(width 0)
			(type solid)
		)
		(fill yes)
		(layer "In2.Cu")
		(net "M_D_DQS_DP<2>")
	)
	(gr_poly
		(pts
			(xy 230.89362 -101.921818) (xy 230.862124 -101.890322) (xy 230.662988 -101.816662) (xy 230.50119 -101.97846)
			(xy 230.57485 -102.177596) (xy 230.606346 -102.209092)
		)
		(stroke
			(width 0)
			(type solid)
		)
		(fill yes)
		(layer "In2.Cu")
		(net "M_D_DQ<28>")
	)
	(gr_poly
		(pts
			(xy 231.133142 -102.286816) (xy 231.059482 -102.08768) (xy 231.027986 -102.056184) (xy 230.740712 -102.343458)
			(xy 230.772208 -102.374954) (xy 230.971344 -102.448614)
		)
		(stroke
			(width 0)
			(type solid)
		)
		(fill yes)
		(layer "In2.Cu")
		(net "M_D_DQ<29>")
	)
	(gr_poly
		(pts
			(xy 231.181148 -98.23069) (xy 231.149652 -98.199194) (xy 230.950262 -98.125534) (xy 230.788718 -98.287332)
			(xy 230.862378 -98.486722) (xy 230.893874 -98.517964)
		)
		(stroke
			(width 0)
			(type solid)
		)
		(fill yes)
		(layer "In2.Cu")
		(net "M_D_DQ<18>")
	)
	(gr_poly
		(pts
			(xy 231.266492 -94.639892) (xy 231.234996 -94.60865) (xy 231.035606 -94.53499) (xy 230.874062 -94.696534)
			(xy 230.947722 -94.895924) (xy 230.978964 -94.92742)
		)
		(stroke
			(width 0)
			(type solid)
		)
		(fill yes)
		(layer "In2.Cu")
		(net "M_D_DQS_DN<2>")
	)
	(gr_poly
		(pts
			(xy 231.310688 -95.71101) (xy 231.279192 -95.679514) (xy 231.079802 -95.605854) (xy 230.918258 -95.767652)
			(xy 230.991918 -95.967042) (xy 231.023414 -95.998284)
		)
		(stroke
			(width 0)
			(type solid)
		)
		(fill yes)
		(layer "In2.Cu")
		(net "M_D_DQ<22>")
	)
	(gr_poly
		(pts
			(xy 231.321102 -56.716676) (xy 231.352598 -56.685434) (xy 231.065324 -56.397652) (xy 231.034082 -56.429148)
			(xy 230.960168 -56.628538) (xy 231.121712 -56.790336)
		)
		(stroke
			(width 0)
			(type solid)
		)
		(fill yes)
		(layer "In2.Cu")
		(net "M_A_DQS_DP<11>")
	)
	(gr_poly
		(pts
			(xy 231.42067 -98.595942) (xy 231.34701 -98.396552) (xy 231.315514 -98.365056) (xy 231.02824 -98.65233)
			(xy 231.059482 -98.683826) (xy 231.258872 -98.757486)
		)
		(stroke
			(width 0)
			(type solid)
		)
		(fill yes)
		(layer "In2.Cu")
		(net "M_D_DQ<19>")
	)
	(gr_poly
		(pts
			(xy 231.512364 -94.999556) (xy 231.438704 -94.80042) (xy 231.407208 -94.768924) (xy 231.119934 -95.056198)
			(xy 231.15143 -95.087694) (xy 231.350566 -95.161354)
		)
		(stroke
			(width 0)
			(type solid)
		)
		(fill yes)
		(layer "In2.Cu")
		(net "M_D_DQS_DP<2>")
	)
	(gr_poly
		(pts
			(xy 231.518968 -56.519064) (xy 231.592882 -56.319928) (xy 231.431338 -56.15813) (xy 231.231948 -56.231536)
			(xy 231.200452 -56.263032) (xy 231.487472 -56.55056)
		)
		(stroke
			(width 0)
			(type solid)
		)
		(fill yes)
		(layer "In2.Cu")
		(net "M_A_DQS_DN<11>")
	)
	(gr_poly
		(pts
			(xy 231.549956 -96.076262) (xy 231.47655 -95.876872) (xy 231.445054 -95.845376) (xy 231.157526 -96.13265)
			(xy 231.189022 -96.164146) (xy 231.388412 -96.237806)
		)
		(stroke
			(width 0)
			(type solid)
		)
		(fill yes)
		(layer "In2.Cu")
		(net "M_D_DQ<23>")
	)
	(gr_poly
		(pts
			(xy 231.554528 -97.374964) (xy 231.554528 -96.968818) (xy 231.509824 -96.968818) (xy 231.316784 -97.057718)
			(xy 231.317038 -97.286318) (xy 231.510078 -97.375218)
		)
		(stroke
			(width 0)
			(type solid)
		)
		(fill yes)
		(layer "In2.Cu")
		(net "M_D_DQ<18>")
	)
	(gr_poly
		(pts
			(xy 231.775254 -93.844364) (xy 231.775254 -93.799914) (xy 231.368854 -93.799914) (xy 231.368854 -93.844364)
			(xy 231.457754 -94.037404) (xy 231.686354 -94.037404)
		)
		(stroke
			(width 0)
			(type solid)
		)
		(fill yes)
		(layer "In2.Cu")
		(net "M_D_DQS_DN<11>")
	)
	(gr_poly
		(pts
			(xy 231.775254 -93.564964) (xy 231.686354 -93.371924) (xy 231.457754 -93.371924) (xy 231.368854 -93.564964)
			(xy 231.368854 -93.609414) (xy 231.775254 -93.609414)
		)
		(stroke
			(width 0)
			(type solid)
		)
		(fill yes)
		(layer "In2.Cu")
		(net "M_D_DQS_DP<11>")
	)
	(gr_poly
		(pts
			(xy 231.795574 -102.818184) (xy 231.764332 -102.786688) (xy 231.564942 -102.713028) (xy 231.403144 -102.874572)
			(xy 231.476804 -103.073962) (xy 231.5083 -103.105458)
		)
		(stroke
			(width 0)
			(type solid)
		)
		(fill yes)
		(layer "In2.Cu")
		(net "M_D_DQ<24>")
	)
	(gr_poly
		(pts
			(xy 231.98201 -97.286318) (xy 231.98201 -97.057718) (xy 231.78897 -96.968818) (xy 231.74452 -96.968818)
			(xy 231.74452 -97.374964) (xy 231.78897 -97.375218)
		)
		(stroke
			(width 0)
			(type solid)
		)
		(fill yes)
		(layer "In2.Cu")
		(net "M_D_DQ<19>")
	)
	(gr_poly
		(pts
			(xy 232.035096 -103.183182) (xy 231.961436 -102.983792) (xy 231.92994 -102.95255) (xy 231.642666 -103.239824)
			(xy 231.674162 -103.27132) (xy 231.873552 -103.34498)
		)
		(stroke
			(width 0)
			(type solid)
		)
		(fill yes)
		(layer "In2.Cu")
		(net "M_D_DQ<25>")
	)
	(gr_poly
		(pts
			(xy 232.172256 -100.942648) (xy 232.14076 -100.911406) (xy 231.94137 -100.837746) (xy 231.779826 -100.99929)
			(xy 231.853486 -101.19868) (xy 231.884982 -101.230176)
		)
		(stroke
			(width 0)
			(type solid)
		)
		(fill yes)
		(layer "In2.Cu")
		(net "M_D_DQ<28>")
	)
	(gr_poly
		(pts
			(xy 232.264204 -59.109102) (xy 232.264204 -59.064652) (xy 231.857804 -59.064652) (xy 231.857804 -59.109102)
			(xy 231.946704 -59.302142) (xy 232.175304 -59.302142)
		)
		(stroke
			(width 0)
			(type solid)
		)
		(fill yes)
		(layer "In2.Cu")
		(net "M_A_DQ<20>")
	)
	(gr_poly
		(pts
			(xy 232.264204 -58.829702) (xy 232.175304 -58.636662) (xy 231.946704 -58.636662) (xy 231.857804 -58.829702)
			(xy 231.857804 -58.874152) (xy 232.264204 -58.874152)
		)
		(stroke
			(width 0)
			(type solid)
		)
		(fill yes)
		(layer "In2.Cu")
		(net "M_A_DQ<21>")
	)
	(gr_poly
		(pts
			(xy 232.287318 -95.469456) (xy 232.287318 -95.425006) (xy 231.880918 -95.425006) (xy 231.880918 -95.469456)
			(xy 231.969818 -95.662496) (xy 232.198418 -95.662496)
		)
		(stroke
			(width 0)
			(type solid)
		)
		(fill yes)
		(layer "In2.Cu")
		(net "M_D_DQ<23>")
	)
	(gr_poly
		(pts
			(xy 232.287318 -95.190564) (xy 232.198418 -94.997524) (xy 231.969818 -94.997524) (xy 231.880918 -95.190564)
			(xy 231.880918 -95.235014) (xy 232.287318 -95.235014)
		)
		(stroke
			(width 0)
			(type solid)
		)
		(fill yes)
		(layer "In2.Cu")
		(net "M_D_DQ<22>")
	)
	(gr_poly
		(pts
			(xy 232.411778 -101.3079) (xy 232.338118 -101.10851) (xy 232.306622 -101.077014) (xy 232.019348 -101.364542)
			(xy 232.050844 -101.395784) (xy 232.250234 -101.469444)
		)
		(stroke
			(width 0)
			(type solid)
		)
		(fill yes)
		(layer "In2.Cu")
		(net "M_D_DQ<29>")
	)
	(gr_poly
		(pts
			(xy 232.496106 -102.117652) (xy 232.46461 -102.086156) (xy 232.265474 -102.012496) (xy 232.103676 -102.174294)
			(xy 232.177336 -102.37343) (xy 232.208832 -102.404926)
		)
		(stroke
			(width 0)
			(type solid)
		)
		(fill yes)
		(layer "In2.Cu")
		(net "M_D_DQ<24>")
	)
	(gr_poly
		(pts
			(xy 232.500424 -94.682564) (xy 232.500424 -94.638114) (xy 232.094024 -94.638114) (xy 232.094024 -94.682564)
			(xy 232.182924 -94.875604) (xy 232.411524 -94.875604)
		)
		(stroke
			(width 0)
			(type solid)
		)
		(fill yes)
		(layer "In2.Cu")
		(net "M_D_DQS_DP<2>")
	)
	(gr_poly
		(pts
			(xy 232.500424 -94.403164) (xy 232.411524 -94.210124) (xy 232.182924 -94.210124) (xy 232.094024 -94.403164)
			(xy 232.094024 -94.447614) (xy 232.500424 -94.447614)
		)
		(stroke
			(width 0)
			(type solid)
		)
		(fill yes)
		(layer "In2.Cu")
		(net "M_D_DQS_DN<2>")
	)
	(gr_poly
		(pts
			(xy 232.666794 -91.341956) (xy 232.666794 -91.297506) (xy 232.260394 -91.297506) (xy 232.260394 -91.341956)
			(xy 232.349294 -91.534996) (xy 232.577894 -91.534996)
		)
		(stroke
			(width 0)
			(type solid)
		)
		(fill yes)
		(layer "In2.Cu")
		(net "M_D_DQ<21>")
	)
	(gr_poly
		(pts
			(xy 232.678224 -58.297064) (xy 232.678224 -58.252614) (xy 232.271824 -58.252614) (xy 232.271824 -58.297064)
			(xy 232.360724 -58.490104) (xy 232.589324 -58.490104)
		)
		(stroke
			(width 0)
			(type solid)
		)
		(fill yes)
		(layer "In2.Cu")
		(net "M_A_DQ<16>")
	)
	(gr_poly
		(pts
			(xy 232.71607 -92.102686) (xy 232.62717 -91.909646) (xy 232.39857 -91.909646) (xy 232.30967 -92.102686)
			(xy 232.30967 -92.147136) (xy 232.71607 -92.147136)
		)
		(stroke
			(width 0)
			(type solid)
		)
		(fill yes)
		(layer "In2.Cu")
		(net "M_D_DQ<16>")
	)
	(gr_poly
		(pts
			(xy 232.735628 -102.48265) (xy 232.661968 -102.283514) (xy 232.630472 -102.252018) (xy 232.343198 -102.539292)
			(xy 232.374694 -102.570788) (xy 232.57383 -102.644448)
		)
		(stroke
			(width 0)
			(type solid)
		)
		(fill yes)
		(layer "In2.Cu")
		(net "M_D_DQ<25>")
	)
	(gr_poly
		(pts
			(xy 232.792016 -96.231456) (xy 232.792016 -96.187006) (xy 232.385616 -96.187006) (xy 232.385616 -96.231456)
			(xy 232.474516 -96.424496) (xy 232.703116 -96.424496)
		)
		(stroke
			(width 0)
			(type solid)
		)
		(fill yes)
		(layer "In2.Cu")
		(net "M_D_DQ<19>")
	)
	(gr_poly
		(pts
			(xy 232.792016 -95.952564) (xy 232.703116 -95.759524) (xy 232.474516 -95.759524) (xy 232.385616 -95.952564)
			(xy 232.385616 -95.997014) (xy 232.792016 -95.997014)
		)
		(stroke
			(width 0)
			(type solid)
		)
		(fill yes)
		(layer "In2.Cu")
		(net "M_D_DQ<18>")
	)
	(gr_poly
		(pts
			(xy 232.805224 -58.017664) (xy 232.716324 -57.824624) (xy 232.487724 -57.824624) (xy 232.398824 -58.017664)
			(xy 232.398824 -58.062114) (xy 232.805224 -58.062114)
		)
		(stroke
			(width 0)
			(type solid)
		)
		(fill yes)
		(layer "In2.Cu")
		(net "M_A_DQ<17>")
	)
	(gr_poly
		(pts
			(xy 232.81767 -92.382086) (xy 232.81767 -92.337636) (xy 232.41127 -92.337636) (xy 232.41127 -92.382086)
			(xy 232.50017 -92.575126) (xy 232.72877 -92.575126)
		)
		(stroke
			(width 0)
			(type solid)
		)
		(fill yes)
		(layer "In2.Cu")
		(net "M_D_DQ<17>")
	)
	(gr_poly
		(pts
			(xy 232.842816 -57.21604) (xy 232.842816 -57.17159) (xy 232.436416 -57.17159) (xy 232.436416 -57.21604)
			(xy 232.525316 -57.40908) (xy 232.753916 -57.40908)
		)
		(stroke
			(width 0)
			(type solid)
		)
		(fill yes)
		(layer "In2.Cu")
		(net "M_A_DQS_DP<11>")
	)
	(gr_poly
		(pts
			(xy 232.842816 -56.93664) (xy 232.753916 -56.7436) (xy 232.525316 -56.7436) (xy 232.436416 -56.93664)
			(xy 232.436416 -56.98109) (xy 232.842816 -56.98109)
		)
		(stroke
			(width 0)
			(type solid)
		)
		(fill yes)
		(layer "In2.Cu")
		(net "M_A_DQS_DN<11>")
	)
	(gr_poly
		(pts
			(xy 232.872788 -100.242116) (xy 232.841292 -100.210874) (xy 232.641902 -100.137214) (xy 232.480358 -100.298758)
			(xy 232.554018 -100.498148) (xy 232.585514 -100.529644)
		)
		(stroke
			(width 0)
			(type solid)
		)
		(fill yes)
		(layer "In2.Cu")
		(net "M_D_DQ<28>")
	)
	(gr_poly
		(pts
			(xy 233.01579 -59.53125) (xy 233.047286 -59.500008) (xy 232.759758 -59.21248) (xy 232.728516 -59.243976)
			(xy 232.654856 -59.443366) (xy 232.8164 -59.60491)
		)
		(stroke
			(width 0)
			(type solid)
		)
		(fill yes)
		(layer "In2.Cu")
		(net "M_A_DQ<20>")
	)
	(gr_poly
		(pts
			(xy 233.11231 -100.607368) (xy 233.03865 -100.407978) (xy 233.007154 -100.376482) (xy 232.71988 -100.66401)
			(xy 232.751376 -100.695252) (xy 232.950766 -100.768912)
		)
		(stroke
			(width 0)
			(type solid)
		)
		(fill yes)
		(layer "In2.Cu")
		(net "M_D_DQ<29>")
	)
	(gr_poly
		(pts
			(xy 233.196638 -101.41712) (xy 233.165142 -101.385624) (xy 232.965752 -101.311964) (xy 232.804208 -101.473762)
			(xy 232.877868 -101.673152) (xy 232.909364 -101.704394)
		)
		(stroke
			(width 0)
			(type solid)
		)
		(fill yes)
		(layer "In2.Cu")
		(net "M_D_DQ<24>")
	)
	(gr_poly
		(pts
			(xy 233.212894 -59.334146) (xy 233.286554 -59.134756) (xy 233.12501 -58.973212) (xy 232.92562 -59.046872)
			(xy 232.894124 -59.078114) (xy 233.181652 -59.365642)
		)
		(stroke
			(width 0)
			(type solid)
		)
		(fill yes)
		(layer "In2.Cu")
		(net "M_A_DQ<21>")
	)
	(gr_poly
		(pts
			(xy 233.257344 -58.630058) (xy 233.28884 -58.598562) (xy 233.001566 -58.311288) (xy 232.97007 -58.342784)
			(xy 232.89641 -58.54192) (xy 233.058208 -58.703718)
		)
		(stroke
			(width 0)
			(type solid)
		)
		(fill yes)
		(layer "In2.Cu")
		(net "M_A_DQ<16>")
	)
	(gr_poly
		(pts
			(xy 233.277918 -95.469456) (xy 233.277918 -95.425006) (xy 232.871518 -95.425006) (xy 232.871518 -95.469456)
			(xy 232.960418 -95.662496) (xy 233.189018 -95.662496)
		)
		(stroke
			(width 0)
			(type solid)
		)
		(fill yes)
		(layer "In2.Cu")
		(net "M_D_DQ<23>")
	)
	(gr_poly
		(pts
			(xy 233.277918 -95.190564) (xy 233.189018 -94.997524) (xy 232.960418 -94.997524) (xy 232.871518 -95.190564)
			(xy 232.871518 -95.235014) (xy 233.277918 -95.235014)
		)
		(stroke
			(width 0)
			(type solid)
		)
		(fill yes)
		(layer "In2.Cu")
		(net "M_D_DQ<22>")
	)
	(gr_poly
		(pts
			(xy 233.326686 -54.570122) (xy 233.357928 -54.538626) (xy 233.070654 -54.251352) (xy 233.039158 -54.282848)
			(xy 232.965498 -54.482238) (xy 233.127296 -54.643782)
		)
		(stroke
			(width 0)
			(type solid)
		)
		(fill yes)
		(layer "In2.Cu")
		(net "M_A_DQ<22>")
	)
	(gr_poly
		(pts
			(xy 233.43616 -101.782372) (xy 233.3625 -101.582982) (xy 233.331004 -101.551486) (xy 233.04373 -101.83876)
			(xy 233.074972 -101.870256) (xy 233.274362 -101.943916)
		)
		(stroke
			(width 0)
			(type solid)
		)
		(fill yes)
		(layer "In2.Cu")
		(net "M_D_DQ<25>")
	)
	(gr_poly
		(pts
			(xy 233.454702 -58.4327) (xy 233.528362 -58.233564) (xy 233.366564 -58.071766) (xy 233.167428 -58.145426)
			(xy 233.135932 -58.176922) (xy 233.423206 -58.464196)
		)
		(stroke
			(width 0)
			(type solid)
		)
		(fill yes)
		(layer "In2.Cu")
		(net "M_A_DQ<17>")
	)
	(gr_poly
		(pts
			(xy 233.468926 -104.053894) (xy 233.43743 -104.022652) (xy 233.237786 -103.9495) (xy 233.076496 -104.111552)
			(xy 233.150664 -104.310688) (xy 233.18216 -104.34193)
		)
		(stroke
			(width 0)
			(type solid)
		)
		(fill yes)
		(layer "In2.Cu")
		(net "M_D_DQS_DN<3>")
	)
	(gr_poly
		(pts
			(xy 233.491024 -94.682564) (xy 233.491024 -94.638114) (xy 233.084624 -94.638114) (xy 233.084624 -94.682564)
			(xy 233.173524 -94.875604) (xy 233.402124 -94.875604)
		)
		(stroke
			(width 0)
			(type solid)
		)
		(fill yes)
		(layer "In2.Cu")
		(net "M_D_DQS_DP<2>")
	)
	(gr_poly
		(pts
			(xy 233.491024 -94.403164) (xy 233.402124 -94.210124) (xy 233.173524 -94.210124) (xy 233.084624 -94.403164)
			(xy 233.084624 -94.447614) (xy 233.491024 -94.447614)
		)
		(stroke
			(width 0)
			(type solid)
		)
		(fill yes)
		(layer "In2.Cu")
		(net "M_D_DQS_DN<2>")
	)
	(gr_poly
		(pts
			(xy 233.52379 -54.373018) (xy 233.59745 -54.173628) (xy 233.435906 -54.01183) (xy 233.236516 -54.08549)
			(xy 233.20502 -54.116986) (xy 233.492294 -54.40426)
		)
		(stroke
			(width 0)
			(type solid)
		)
		(fill yes)
		(layer "In2.Cu")
		(net "M_A_DQ<23>")
	)
	(gr_poly
		(pts
			(xy 233.544364 -57.571386) (xy 233.575606 -57.53989) (xy 233.288332 -57.252616) (xy 233.256836 -57.284112)
			(xy 233.183176 -57.483502) (xy 233.344974 -57.645046)
		)
		(stroke
			(width 0)
			(type solid)
		)
		(fill yes)
		(layer "In2.Cu")
		(net "M_A_DQS_DP<11>")
	)
	(gr_poly
		(pts
			(xy 233.657394 -91.341956) (xy 233.657394 -91.297506) (xy 233.250994 -91.297506) (xy 233.250994 -91.341956)
			(xy 233.339894 -91.534996) (xy 233.568494 -91.534996)
		)
		(stroke
			(width 0)
			(type solid)
		)
		(fill yes)
		(layer "In2.Cu")
		(net "M_D_DQ<21>")
	)
	(gr_poly
		(pts
			(xy 233.657394 -91.063064) (xy 233.568494 -90.870024) (xy 233.339894 -90.870024) (xy 233.250994 -91.063064)
			(xy 233.250994 -91.107514) (xy 233.657394 -91.107514)
		)
		(stroke
			(width 0)
			(type solid)
		)
		(fill yes)
		(layer "In2.Cu")
		(net "M_D_DQ<20>")
	)
	(gr_poly
		(pts
			(xy 233.670856 -56.173878) (xy 233.702352 -56.142636) (xy 233.414824 -55.855108) (xy 233.383582 -55.886604)
			(xy 233.309922 -56.085994) (xy 233.471466 -56.247538)
		)
		(stroke
			(width 0)
			(type solid)
		)
		(fill yes)
		(layer "In2.Cu")
		(net "M_A_DQS_DN<2>")
	)
	(gr_poly
		(pts
			(xy 233.70667 -92.102686) (xy 233.61777 -91.909646) (xy 233.38917 -91.909646) (xy 233.30027 -92.102686)
			(xy 233.30027 -92.147136) (xy 233.70667 -92.147136)
		)
		(stroke
			(width 0)
			(type solid)
		)
		(fill yes)
		(layer "In2.Cu")
		(net "M_D_DQ<16>")
	)
	(gr_poly
		(pts
			(xy 233.708956 -57.340754) (xy 233.782616 -57.141618) (xy 233.620818 -56.97982) (xy 233.421682 -57.05348)
			(xy 233.390186 -57.084976) (xy 233.67746 -57.37225)
		)
		(stroke
			(width 0)
			(type solid)
		)
		(fill yes)
		(layer "In2.Cu")
		(net "M_A_DQS_DN<11>")
	)
	(gr_poly
		(pts
			(xy 233.709718 -104.4194) (xy 233.63555 -104.22001) (xy 233.604054 -104.188768) (xy 233.317288 -104.476804)
			(xy 233.348784 -104.508046) (xy 233.548428 -104.581198)
		)
		(stroke
			(width 0)
			(type solid)
		)
		(fill yes)
		(layer "In2.Cu")
		(net "M_D_DQS_DP<3>")
	)
	(gr_poly
		(pts
			(xy 233.73334 -93.2688) (xy 233.73334 -93.22435) (xy 233.32694 -93.22435) (xy 233.32694 -93.2688)
			(xy 233.41584 -93.46184) (xy 233.64444 -93.46184)
		)
		(stroke
			(width 0)
			(type solid)
		)
		(fill yes)
		(layer "In2.Cu")
		(net "M_D_DQS_DN<11>")
	)
	(gr_poly
		(pts
			(xy 233.73334 -92.9894) (xy 233.64444 -92.79636) (xy 233.41584 -92.79636) (xy 233.32694 -92.9894)
			(xy 233.32694 -93.03385) (xy 233.73334 -93.03385)
		)
		(stroke
			(width 0)
			(type solid)
		)
		(fill yes)
		(layer "In2.Cu")
		(net "M_D_DQS_DP<11>")
	)
	(gr_poly
		(pts
			(xy 233.744516 -53.26507) (xy 233.766868 -53.226462) (xy 233.421428 -53.027072) (xy 233.39933 -53.06568)
			(xy 233.391202 -53.25745) (xy 233.582464 -53.36794)
		)
		(stroke
			(width 0)
			(type solid)
		)
		(fill yes)
		(layer "In2.Cu")
		(net "M_A_DQ<18>")
	)
	(gr_poly
		(pts
			(xy 233.764582 -99.56038) (xy 233.74223 -99.522026) (xy 233.580178 -99.419156) (xy 233.388916 -99.529646)
			(xy 233.397044 -99.721416) (xy 233.419142 -99.75977)
		)
		(stroke
			(width 0)
			(type solid)
		)
		(fill yes)
		(layer "In2.Cu")
		(net "M_D_DQ<28>")
	)
	(gr_poly
		(pts
			(xy 233.782616 -96.231456) (xy 233.782616 -96.187006) (xy 233.376216 -96.187006) (xy 233.376216 -96.231456)
			(xy 233.465116 -96.424496) (xy 233.693716 -96.424496)
		)
		(stroke
			(width 0)
			(type solid)
		)
		(fill yes)
		(layer "In2.Cu")
		(net "M_D_DQ<19>")
	)
	(gr_poly
		(pts
			(xy 233.782616 -95.952564) (xy 233.693716 -95.759524) (xy 233.465116 -95.759524) (xy 233.376216 -95.952564)
			(xy 233.376216 -95.997014) (xy 233.782616 -95.997014)
		)
		(stroke
			(width 0)
			(type solid)
		)
		(fill yes)
		(layer "In2.Cu")
		(net "M_D_DQ<18>")
	)
	(gr_poly
		(pts
			(xy 233.80827 -92.382086) (xy 233.80827 -92.337636) (xy 233.40187 -92.337636) (xy 233.40187 -92.382086)
			(xy 233.49077 -92.575126) (xy 233.71937 -92.575126)
		)
		(stroke
			(width 0)
			(type solid)
		)
		(fill yes)
		(layer "In2.Cu")
		(net "M_D_DQ<17>")
	)
	(gr_poly
		(pts
			(xy 233.868468 -55.976266) (xy 233.942128 -55.77713) (xy 233.78033 -55.615332) (xy 233.581194 -55.688992)
			(xy 233.549698 -55.720488) (xy 233.836972 -56.007762)
		)
		(stroke
			(width 0)
			(type solid)
		)
		(fill yes)
		(layer "In2.Cu")
		(net "M_A_DQS_DP<2>")
	)
	(gr_poly
		(pts
			(xy 234.026964 -55.270654) (xy 234.05846 -55.239158) (xy 233.771186 -54.951884) (xy 233.73969 -54.98338)
			(xy 233.66603 -55.182516) (xy 233.827828 -55.344314)
		)
		(stroke
			(width 0)
			(type solid)
		)
		(fill yes)
		(layer "In2.Cu")
		(net "M_A_DQ<22>")
	)
	(gr_poly
		(pts
			(xy 234.16768 -103.351838) (xy 234.136184 -103.320596) (xy 233.93654 -103.24719) (xy 233.77525 -103.409242)
			(xy 233.849418 -103.608632) (xy 233.880914 -103.639874)
		)
		(stroke
			(width 0)
			(type solid)
		)
		(fill yes)
		(layer "In2.Cu")
		(net "M_D_DQS_DN<3>")
	)
	(gr_poly
		(pts
			(xy 234.181396 -58.701686) (xy 234.181396 -58.657236) (xy 233.774996 -58.657236) (xy 233.774996 -58.701686)
			(xy 233.863896 -58.894726) (xy 234.092496 -58.894726)
		)
		(stroke
			(width 0)
			(type solid)
		)
		(fill yes)
		(layer "In2.Cu")
		(net "M_A_DQ<16>")
	)
	(gr_poly
		(pts
			(xy 234.181396 -58.422286) (xy 234.092496 -58.229246) (xy 233.863896 -58.229246) (xy 233.774996 -58.422286)
			(xy 233.774996 -58.466736) (xy 234.181396 -58.466736)
		)
		(stroke
			(width 0)
			(type solid)
		)
		(fill yes)
		(layer "In2.Cu")
		(net "M_A_DQ<17>")
	)
	(gr_poly
		(pts
			(xy 234.183174 -59.692286) (xy 234.183174 -59.647836) (xy 233.776774 -59.647836) (xy 233.776774 -59.692286)
			(xy 233.865674 -59.885326) (xy 234.094274 -59.885326)
		)
		(stroke
			(width 0)
			(type solid)
		)
		(fill yes)
		(layer "In2.Cu")
		(net "M_A_DQ<20>")
	)
	(gr_poly
		(pts
			(xy 234.183174 -59.412886) (xy 234.094274 -59.219846) (xy 233.865674 -59.219846) (xy 233.776774 -59.412886)
			(xy 233.776774 -59.457336) (xy 234.183174 -59.457336)
		)
		(stroke
			(width 0)
			(type solid)
		)
		(fill yes)
		(layer "In2.Cu")
		(net "M_A_DQ<21>")
	)
	(gr_poly
		(pts
			(xy 234.224322 -55.073296) (xy 234.297982 -54.87416) (xy 234.136184 -54.712362) (xy 233.937048 -54.786022)
			(xy 233.905552 -54.817518) (xy 234.192826 -55.104792)
		)
		(stroke
			(width 0)
			(type solid)
		)
		(fill yes)
		(layer "In2.Cu")
		(net "M_A_DQ<23>")
	)
	(gr_poly
		(pts
			(xy 234.268518 -95.469456) (xy 234.268518 -95.425006) (xy 233.862118 -95.425006) (xy 233.862118 -95.469456)
			(xy 233.951018 -95.662496) (xy 234.179618 -95.662496)
		)
		(stroke
			(width 0)
			(type solid)
		)
		(fill yes)
		(layer "In2.Cu")
		(net "M_D_DQ<23>")
	)
	(gr_poly
		(pts
			(xy 234.268518 -95.190564) (xy 234.179618 -94.997524) (xy 233.951018 -94.997524) (xy 233.862118 -95.190564)
			(xy 233.862118 -95.235014) (xy 234.268518 -95.235014)
		)
		(stroke
			(width 0)
			(type solid)
		)
		(fill yes)
		(layer "In2.Cu")
		(net "M_D_DQ<22>")
	)
	(gr_poly
		(pts
			(xy 234.287822 -101.925628) (xy 234.230418 -101.742494) (xy 234.198922 -101.710998) (xy 233.916982 -101.993192)
			(xy 233.948478 -102.024434) (xy 234.131612 -102.081838)
		)
		(stroke
			(width 0)
			(type solid)
		)
		(fill yes)
		(layer "In2.Cu")
		(net "M_D_DQS_DN<12>")
	)
	(gr_poly
		(pts
			(xy 234.390946 -53.161946) (xy 234.399074 -52.970176) (xy 234.207812 -52.859686) (xy 234.04576 -52.962556)
			(xy 234.023408 -53.00091) (xy 234.368848 -53.200554)
		)
		(stroke
			(width 0)
			(type solid)
		)
		(fill yes)
		(layer "In2.Cu")
		(net "M_A_DQ<19>")
	)
	(gr_poly
		(pts
			(xy 234.399074 -100.80625) (xy 234.390946 -100.61448) (xy 234.368848 -100.575872) (xy 234.023408 -100.775262)
			(xy 234.04576 -100.81387) (xy 234.207812 -100.91674)
		)
		(stroke
			(width 0)
			(type solid)
		)
		(fill yes)
		(layer "In2.Cu")
		(net "M_D_DQ<25>")
	)
	(gr_poly
		(pts
			(xy 234.402884 -99.813618) (xy 234.394756 -99.621848) (xy 234.372658 -99.583494) (xy 234.027218 -99.78263)
			(xy 234.04957 -99.821238) (xy 234.211622 -99.924108)
		)
		(stroke
			(width 0)
			(type solid)
		)
		(fill yes)
		(layer "In2.Cu")
		(net "M_D_DQ<29>")
	)
	(gr_poly
		(pts
			(xy 234.408472 -103.71709) (xy 234.334304 -103.517954) (xy 234.302808 -103.486712) (xy 234.016042 -103.774748)
			(xy 234.047538 -103.80599) (xy 234.247182 -103.879142)
		)
		(stroke
			(width 0)
			(type solid)
		)
		(fill yes)
		(layer "In2.Cu")
		(net "M_D_DQS_DP<3>")
	)
	(gr_poly
		(pts
			(xy 234.477052 -57.711086) (xy 234.477052 -57.666636) (xy 234.070652 -57.666636) (xy 234.070652 -57.711086)
			(xy 234.159552 -57.904126) (xy 234.388152 -57.904126)
		)
		(stroke
			(width 0)
			(type solid)
		)
		(fill yes)
		(layer "In2.Cu")
		(net "M_A_DQS_DP<11>")
	)
	(gr_poly
		(pts
			(xy 234.477052 -57.431686) (xy 234.388152 -57.238646) (xy 234.159552 -57.238646) (xy 234.070652 -57.431686)
			(xy 234.070652 -57.476136) (xy 234.477052 -57.476136)
		)
		(stroke
			(width 0)
			(type solid)
		)
		(fill yes)
		(layer "In2.Cu")
		(net "M_A_DQS_DN<11>")
	)
	(gr_poly
		(pts
			(xy 234.483148 -94.36354) (xy 234.483148 -94.31909) (xy 234.076748 -94.31909) (xy 234.076748 -94.36354)
			(xy 234.165648 -94.55658) (xy 234.394248 -94.55658)
		)
		(stroke
			(width 0)
			(type solid)
		)
		(fill yes)
		(layer "In2.Cu")
		(net "M_D_DQS_DP<2>")
	)
	(gr_poly
		(pts
			(xy 234.483148 -94.08414) (xy 234.394248 -93.8911) (xy 234.165648 -93.8911) (xy 234.076748 -94.08414)
			(xy 234.076748 -94.12859) (xy 234.483148 -94.12859)
		)
		(stroke
			(width 0)
			(type solid)
		)
		(fill yes)
		(layer "In2.Cu")
		(net "M_D_DQS_DN<2>")
	)
	(gr_poly
		(pts
			(xy 234.599226 -53.758084) (xy 234.621578 -53.71973) (xy 234.276138 -53.520086) (xy 234.25404 -53.558694)
			(xy 234.245912 -53.750464) (xy 234.437174 -53.860954)
		)
		(stroke
			(width 0)
			(type solid)
		)
		(fill yes)
		(layer "In2.Cu")
		(net "M_A_DQ<18>")
	)
	(gr_poly
		(pts
			(xy 234.603036 -51.77917) (xy 234.625388 -51.740562) (xy 234.279948 -51.541172) (xy 234.25785 -51.57978)
			(xy 234.249722 -51.77155) (xy 234.440984 -51.88204)
		)
		(stroke
			(width 0)
			(type solid)
		)
		(fill yes)
		(layer "In2.Cu")
		(net "M_A_DQ<28>")
	)
	(gr_poly
		(pts
			(xy 234.621578 -100.056442) (xy 234.599226 -100.018088) (xy 234.437174 -99.915218) (xy 234.245912 -100.025708)
			(xy 234.25404 -100.217478) (xy 234.276138 -100.256086)
		)
		(stroke
			(width 0)
			(type solid)
		)
		(fill yes)
		(layer "In2.Cu")
		(net "M_D_DQ<24>")
	)
	(gr_poly
		(pts
			(xy 234.621578 -99.06635) (xy 234.599226 -99.027742) (xy 234.437174 -98.924872) (xy 234.245912 -99.035362)
			(xy 234.25404 -99.227132) (xy 234.276138 -99.26574)
		)
		(stroke
			(width 0)
			(type solid)
		)
		(fill yes)
		(layer "In2.Cu")
		(net "M_D_DQ<28>")
	)
	(gr_poly
		(pts
			(xy 234.623102 -101.04628) (xy 234.60075 -101.007926) (xy 234.438698 -100.905056) (xy 234.247436 -101.015546)
			(xy 234.255564 -101.207316) (xy 234.277662 -101.24567)
		)
		(stroke
			(width 0)
			(type solid)
		)
		(fill yes)
		(layer "In2.Cu")
		(net "M_D_DQS_DP<12>")
	)
	(gr_poly
		(pts
			(xy 234.866434 -102.649782) (xy 234.834938 -102.618286) (xy 234.635294 -102.545134) (xy 234.474004 -102.707186)
			(xy 234.548172 -102.906322) (xy 234.579668 -102.937818)
		)
		(stroke
			(width 0)
			(type solid)
		)
		(fill yes)
		(layer "In2.Cu")
		(net "M_D_DQS_DN<3>")
	)
	(gr_poly
		(pts
			(xy 235.02112 -54.39156) (xy 234.976924 -54.391814) (xy 234.806744 -54.480714) (xy 234.806744 -54.70144)
			(xy 234.976924 -54.79034) (xy 235.021374 -54.790594)
		)
		(stroke
			(width 0)
			(type solid)
		)
		(fill yes)
		(layer "In2.Cu")
		(net "M_A_DQ<18>")
	)
	(gr_poly
		(pts
			(xy 235.107226 -103.015034) (xy 235.033058 -102.815898) (xy 235.001562 -102.784402) (xy 234.714796 -103.072438)
			(xy 234.746292 -103.103934) (xy 234.945936 -103.177086)
		)
		(stroke
			(width 0)
			(type solid)
		)
		(fill yes)
		(layer "In2.Cu")
		(net "M_D_DQS_DP<3>")
	)
	(gr_poly
		(pts
			(xy 235.249466 -93.281246) (xy 235.257594 -93.089476) (xy 235.066332 -92.978986) (xy 234.90428 -93.081856)
			(xy 234.881928 -93.12021) (xy 235.227368 -93.319854)
		)
		(stroke
			(width 0)
			(type solid)
		)
		(fill yes)
		(layer "In2.Cu")
		(net "M_D_DQS_DP<11>")
	)
	(gr_poly
		(pts
			(xy 235.249466 -51.676046) (xy 235.257594 -51.484276) (xy 235.066332 -51.373786) (xy 234.90428 -51.476656)
			(xy 234.881928 -51.51501) (xy 235.227368 -51.714654)
		)
		(stroke
			(width 0)
			(type solid)
		)
		(fill yes)
		(layer "In2.Cu")
		(net "M_A_DQ<29>")
	)
	(gr_poly
		(pts
			(xy 235.251498 -53.658008) (xy 235.259626 -53.466238) (xy 235.068364 -53.356002) (xy 234.906312 -53.458872)
			(xy 234.88396 -53.497226) (xy 235.229654 -53.696616)
		)
		(stroke
			(width 0)
			(type solid)
		)
		(fill yes)
		(layer "In2.Cu")
		(net "M_A_DQ<19>")
	)
	(gr_poly
		(pts
			(xy 235.251752 -91.301316) (xy 235.25988 -91.109546) (xy 235.068618 -90.999056) (xy 234.906566 -91.101926)
			(xy 234.884214 -91.14028) (xy 235.229654 -91.33967)
		)
		(stroke
			(width 0)
			(type solid)
		)
		(fill yes)
		(layer "In2.Cu")
		(net "M_D_DQ<20>")
	)
	(gr_poly
		(pts
			(xy 235.251752 -59.602116) (xy 235.25988 -59.410346) (xy 235.068618 -59.299856) (xy 234.906566 -59.402726)
			(xy 234.884214 -59.441334) (xy 235.229654 -59.640724)
		)
		(stroke
			(width 0)
			(type solid)
		)
		(fill yes)
		(layer "In2.Cu")
		(net "M_A_DQ<21>")
	)
	(gr_poly
		(pts
			(xy 235.251752 -56.630316) (xy 235.25988 -56.438546) (xy 235.068618 -56.328056) (xy 234.906566 -56.430926)
			(xy 234.884214 -56.469534) (xy 235.229654 -56.668924)
		)
		(stroke
			(width 0)
			(type solid)
		)
		(fill yes)
		(layer "In2.Cu")
		(net "M_A_DQS_DP<2>")
	)
	(gr_poly
		(pts
			(xy 235.251752 -55.639716) (xy 235.25988 -55.447946) (xy 235.068618 -55.337456) (xy 234.906566 -55.440326)
			(xy 234.884214 -55.478934) (xy 235.229654 -55.678324)
		)
		(stroke
			(width 0)
			(type solid)
		)
		(fill yes)
		(layer "In2.Cu")
		(net "M_A_DQ<23>")
	)
	(gr_poly
		(pts
			(xy 235.25988 -100.30968) (xy 235.251752 -100.11791) (xy 235.229654 -100.079302) (xy 234.884214 -100.278946)
			(xy 234.906566 -100.3173) (xy 235.068618 -100.42017)
		)
		(stroke
			(width 0)
			(type solid)
		)
		(fill yes)
		(layer "In2.Cu")
		(net "M_D_DQ<25>")
	)
	(gr_poly
		(pts
			(xy 235.261404 -101.299264) (xy 235.253276 -101.107494) (xy 235.231178 -101.068886) (xy 234.885738 -101.26853)
			(xy 234.90809 -101.306884) (xy 235.070142 -101.409754)
		)
		(stroke
			(width 0)
			(type solid)
		)
		(fill yes)
		(layer "In2.Cu")
		(net "M_D_DQS_DN<12>")
	)
	(gr_poly
		(pts
			(xy 235.261404 -99.318318) (xy 235.253276 -99.126548) (xy 235.231178 -99.088194) (xy 234.885738 -99.28733)
			(xy 234.90809 -99.325938) (xy 235.070142 -99.428808)
		)
		(stroke
			(width 0)
			(type solid)
		)
		(fill yes)
		(layer "In2.Cu")
		(net "M_D_DQ<29>")
	)
	(gr_poly
		(pts
			(xy 235.379514 -103.713534) (xy 235.348018 -103.682292) (xy 235.148628 -103.608632) (xy 234.987084 -103.770176)
			(xy 235.060744 -103.969566) (xy 235.091986 -104.001062)
		)
		(stroke
			(width 0)
			(type solid)
		)
		(fill yes)
		(layer "In2.Cu")
		(net "M_D_DQ<30>")
	)
	(gr_poly
		(pts
			(xy 235.388912 -54.312312) (xy 235.559092 -54.223412) (xy 235.559092 -54.002686) (xy 235.388912 -53.913786)
			(xy 235.344462 -53.913532) (xy 235.344716 -54.312566)
		)
		(stroke
			(width 0)
			(type solid)
		)
		(fill yes)
		(layer "In2.Cu")
		(net "M_A_DQ<19>")
	)
	(gr_poly
		(pts
			(xy 235.457746 -52.272438) (xy 235.480098 -52.23383) (xy 235.134658 -52.034694) (xy 235.11256 -52.073048)
			(xy 235.104432 -52.264818) (xy 235.295694 -52.375308)
		)
		(stroke
			(width 0)
			(type solid)
		)
		(fill yes)
		(layer "In2.Cu")
		(net "M_A_DQ<28>")
	)
	(gr_poly
		(pts
			(xy 235.45927 -92.8878) (xy 235.481622 -92.849446) (xy 235.136182 -92.649802) (xy 235.114084 -92.68841)
			(xy 235.105956 -92.88018) (xy 235.297218 -92.99067)
		)
		(stroke
			(width 0)
			(type solid)
		)
		(fill yes)
		(layer "In2.Cu")
		(net "M_D_DQ<17>")
	)
	(gr_poly
		(pts
			(xy 235.45927 -91.8972) (xy 235.481622 -91.858846) (xy 235.136182 -91.659202) (xy 235.114084 -91.69781)
			(xy 235.105956 -91.88958) (xy 235.297218 -92.00007)
		)
		(stroke
			(width 0)
			(type solid)
		)
		(fill yes)
		(layer "In2.Cu")
		(net "M_D_DQ<21>")
	)
	(gr_poly
		(pts
			(xy 235.45927 -60.198) (xy 235.481622 -60.159646) (xy 235.136182 -59.960002) (xy 235.114084 -59.99861)
			(xy 235.105956 -60.19038) (xy 235.297218 -60.30087)
		)
		(stroke
			(width 0)
			(type solid)
		)
		(fill yes)
		(layer "In2.Cu")
		(net "M_A_DQ<20>")
	)
	(gr_poly
		(pts
			(xy 235.45927 -57.2262) (xy 235.481622 -57.187846) (xy 235.136182 -56.988202) (xy 235.114084 -57.02681)
			(xy 235.105956 -57.21858) (xy 235.297218 -57.32907)
		)
		(stroke
			(width 0)
			(type solid)
		)
		(fill yes)
		(layer "In2.Cu")
		(net "M_A_DQS_DN<2>")
	)
	(gr_poly
		(pts
			(xy 235.45927 -56.2356) (xy 235.481622 -56.197246) (xy 235.136182 -55.997602) (xy 235.114084 -56.03621)
			(xy 235.105956 -56.22798) (xy 235.297218 -56.33847)
		)
		(stroke
			(width 0)
			(type solid)
		)
		(fill yes)
		(layer "In2.Cu")
		(net "M_A_DQ<22>")
	)
	(gr_poly
		(pts
			(xy 235.459524 -55.245254) (xy 235.481876 -55.2069) (xy 235.136182 -55.00751) (xy 235.114338 -55.046118)
			(xy 235.10621 -55.237888) (xy 235.297472 -55.348124)
		)
		(stroke
			(width 0)
			(type solid)
		)
		(fill yes)
		(layer "In2.Cu")
		(net "M_A_DQ<18>")
	)
	(gr_poly
		(pts
			(xy 235.467652 -93.884496) (xy 235.490004 -93.846142) (xy 235.144564 -93.646498) (xy 235.122466 -93.685106)
			(xy 235.114338 -93.876876) (xy 235.3056 -93.987366)
		)
		(stroke
			(width 0)
			(type solid)
		)
		(fill yes)
		(layer "In2.Cu")
		(net "M_D_DQS_DN<11>")
	)
	(gr_poly
		(pts
			(xy 235.480098 -98.57105) (xy 235.457746 -98.532442) (xy 235.295694 -98.429572) (xy 235.104432 -98.540062)
			(xy 235.11256 -98.731832) (xy 235.134658 -98.77044)
		)
		(stroke
			(width 0)
			(type solid)
		)
		(fill yes)
		(layer "In2.Cu")
		(net "M_D_DQ<28>")
	)
	(gr_poly
		(pts
			(xy 235.481622 -99.56038) (xy 235.45927 -99.522026) (xy 235.297218 -99.419156) (xy 235.105956 -99.529646)
			(xy 235.114084 -99.721416) (xy 235.136182 -99.75977)
		)
		(stroke
			(width 0)
			(type solid)
		)
		(fill yes)
		(layer "In2.Cu")
		(net "M_D_DQ<24>")
	)
	(gr_poly
		(pts
			(xy 235.483908 -100.54971) (xy 235.461556 -100.511356) (xy 235.299504 -100.408486) (xy 235.108242 -100.518976)
			(xy 235.11637 -100.710746) (xy 235.138468 -100.749354)
		)
		(stroke
			(width 0)
			(type solid)
		)
		(fill yes)
		(layer "In2.Cu")
		(net "M_D_DQS_DP<12>")
	)
	(gr_poly
		(pts
			(xy 235.496862 -51.219354) (xy 235.522262 -51.182778) (xy 235.195618 -50.954178) (xy 235.170218 -50.9905)
			(xy 235.145326 -51.181) (xy 235.326428 -51.307746)
		)
		(stroke
			(width 0)
			(type solid)
		)
		(fill yes)
		(layer "In2.Cu")
		(net "M_A_DQ<24>")
	)
	(gr_poly
		(pts
			(xy 235.566966 -101.94925) (xy 235.53547 -101.917754) (xy 235.335826 -101.844602) (xy 235.174536 -102.006654)
			(xy 235.248704 -102.20579) (xy 235.2802 -102.237286)
		)
		(stroke
			(width 0)
			(type solid)
		)
		(fill yes)
		(layer "In2.Cu")
		(net "M_D_DQS_DN<3>")
	)
	(gr_poly
		(pts
			(xy 235.618782 -104.078786) (xy 235.545122 -103.879396) (xy 235.51388 -103.8479) (xy 235.226352 -104.135428)
			(xy 235.257848 -104.16667) (xy 235.457238 -104.24033)
		)
		(stroke
			(width 0)
			(type solid)
		)
		(fill yes)
		(layer "In2.Cu")
		(net "M_D_DQ<31>")
	)
	(gr_poly
		(pts
			(xy 235.807758 -102.314502) (xy 235.73359 -102.115366) (xy 235.702094 -102.08387) (xy 235.415328 -102.371906)
			(xy 235.446824 -102.403402) (xy 235.646468 -102.476554)
		)
		(stroke
			(width 0)
			(type solid)
		)
		(fill yes)
		(layer "In2.Cu")
		(net "M_D_DQS_DP<3>")
	)
	(gr_poly
		(pts
			(xy 235.811568 -59.00674) (xy 235.811568 -58.96229) (xy 235.412788 -58.96229) (xy 235.412788 -59.00674)
			(xy 235.501688 -59.17692) (xy 235.722668 -59.17692)
		)
		(stroke
			(width 0)
			(type solid)
		)
		(fill yes)
		(layer "In2.Cu")
		(net "M_A_DQ<16>")
	)
	(gr_poly
		(pts
			(xy 236.080046 -103.013002) (xy 236.04855 -102.98176) (xy 235.84916 -102.9081) (xy 235.687616 -103.069644)
			(xy 235.761276 -103.269034) (xy 235.792518 -103.30053)
		)
		(stroke
			(width 0)
			(type solid)
		)
		(fill yes)
		(layer "In2.Cu")
		(net "M_D_DQ<30>")
	)
	(gr_poly
		(pts
			(xy 236.094778 -55.13832) (xy 236.102906 -54.94655) (xy 235.911644 -54.83606) (xy 235.749592 -54.93893)
			(xy 235.72724 -54.977538) (xy 236.07268 -55.176674)
		)
		(stroke
			(width 0)
			(type solid)
		)
		(fill yes)
		(layer "In2.Cu")
		(net "M_A_DQ<19>")
	)
	(gr_poly
		(pts
			(xy 236.110272 -93.777816) (xy 236.1184 -93.586046) (xy 235.927138 -93.475556) (xy 235.765086 -93.578426)
			(xy 235.742734 -93.61678) (xy 236.088174 -93.81617)
		)
		(stroke
			(width 0)
			(type solid)
		)
		(fill yes)
		(layer "In2.Cu")
		(net "M_D_DQS_DP<11>")
	)
	(gr_poly
		(pts
			(xy 236.110272 -52.172616) (xy 236.1184 -51.980846) (xy 235.927138 -51.870356) (xy 235.765086 -51.973226)
			(xy 235.742734 -52.011834) (xy 236.088174 -52.211224)
		)
		(stroke
			(width 0)
			(type solid)
		)
		(fill yes)
		(layer "In2.Cu")
		(net "M_A_DQ<29>")
	)
	(gr_poly
		(pts
			(xy 236.111796 -92.788232) (xy 236.119924 -92.596462) (xy 235.928662 -92.485972) (xy 235.76661 -92.588842)
			(xy 235.744258 -92.62745) (xy 236.089698 -92.82684)
		)
		(stroke
			(width 0)
			(type solid)
		)
		(fill yes)
		(layer "In2.Cu")
		(net "M_D_DQ<16>")
	)
	(gr_poly
		(pts
			(xy 236.111796 -91.797632) (xy 236.119924 -91.605862) (xy 235.928662 -91.495372) (xy 235.76661 -91.598242)
			(xy 235.744258 -91.63685) (xy 236.089698 -91.83624)
		)
		(stroke
			(width 0)
			(type solid)
		)
		(fill yes)
		(layer "In2.Cu")
		(net "M_D_DQ<20>")
	)
	(gr_poly
		(pts
			(xy 236.116114 -100.80625) (xy 236.107986 -100.61448) (xy 236.085888 -100.575872) (xy 235.740448 -100.775262)
			(xy 235.7628 -100.81387) (xy 235.924852 -100.91674)
		)
		(stroke
			(width 0)
			(type solid)
		)
		(fill yes)
		(layer "In2.Cu")
		(net "M_D_DQS_DN<12>")
	)
	(gr_poly
		(pts
			(xy 236.116622 -57.219596) (xy 236.108494 -57.027826) (xy 236.086396 -56.989218) (xy 235.740956 -57.188862)
			(xy 235.763308 -57.227216) (xy 235.92536 -57.330086)
		)
		(stroke
			(width 0)
			(type solid)
		)
		(fill yes)
		(layer "In2.Cu")
		(net "M_A_DQS_DN<2>")
	)
	(gr_poly
		(pts
			(xy 236.1184 -98.82378) (xy 236.110272 -98.63201) (xy 236.088174 -98.593402) (xy 235.742734 -98.793046)
			(xy 235.765086 -98.8314) (xy 235.927138 -98.93427)
		)
		(stroke
			(width 0)
			(type solid)
		)
		(fill yes)
		(layer "In2.Cu")
		(net "M_D_DQ<29>")
	)
	(gr_poly
		(pts
			(xy 236.119924 -99.813618) (xy 236.111796 -99.621848) (xy 236.089698 -99.583494) (xy 235.744258 -99.78263)
			(xy 235.76661 -99.821238) (xy 235.928662 -99.924108)
		)
		(stroke
			(width 0)
			(type solid)
		)
		(fill yes)
		(layer "In2.Cu")
		(net "M_D_DQ<25>")
	)
	(gr_poly
		(pts
			(xy 236.119924 -58.208418) (xy 236.111796 -58.016648) (xy 236.089698 -57.978294) (xy 235.744258 -58.17743)
			(xy 235.76661 -58.216038) (xy 235.928662 -58.318908)
		)
		(stroke
			(width 0)
			(type solid)
		)
		(fill yes)
		(layer "In2.Cu")
		(net "M_A_DQ<17>")
	)
	(gr_poly
		(pts
			(xy 236.316266 -95.363284) (xy 236.338618 -95.32493) (xy 235.993178 -95.125286) (xy 235.97108 -95.163894)
			(xy 235.962952 -95.355664) (xy 236.154214 -95.466154)
		)
		(stroke
			(width 0)
			(type solid)
		)
		(fill yes)
		(layer "In2.Cu")
		(net "M_D_DQ<22>")
	)
	(gr_poly
		(pts
			(xy 236.316266 -92.391484) (xy 236.338618 -92.35313) (xy 235.993178 -92.153486) (xy 235.97108 -92.192094)
			(xy 235.962952 -92.383864) (xy 236.154214 -92.494354)
		)
		(stroke
			(width 0)
			(type solid)
		)
		(fill yes)
		(layer "In2.Cu")
		(net "M_D_DQ<21>")
	)
	(gr_poly
		(pts
			(xy 236.31779 -94.3737) (xy 236.340142 -94.335346) (xy 235.994702 -94.135702) (xy 235.972604 -94.17431)
			(xy 235.964476 -94.36608) (xy 236.155738 -94.47657)
		)
		(stroke
			(width 0)
			(type solid)
		)
		(fill yes)
		(layer "In2.Cu")
		(net "M_D_DQS_DN<11>")
	)
	(gr_poly
		(pts
			(xy 236.31779 -52.7685) (xy 236.340142 -52.730146) (xy 235.994702 -52.530502) (xy 235.972604 -52.56911)
			(xy 235.964476 -52.76088) (xy 236.155738 -52.87137)
		)
		(stroke
			(width 0)
			(type solid)
		)
		(fill yes)
		(layer "In2.Cu")
		(net "M_A_DQ<28>")
	)
	(gr_poly
		(pts
			(xy 236.319314 -103.378254) (xy 236.245654 -103.178864) (xy 236.214412 -103.147368) (xy 235.926884 -103.434896)
			(xy 235.95838 -103.466138) (xy 236.15777 -103.539798)
		)
		(stroke
			(width 0)
			(type solid)
		)
		(fill yes)
		(layer "In2.Cu")
		(net "M_D_DQ<31>")
	)
	(gr_poly
		(pts
			(xy 236.320076 -51.77917) (xy 236.342428 -51.740562) (xy 235.996988 -51.541172) (xy 235.97489 -51.57978)
			(xy 235.966762 -51.77155) (xy 236.158024 -51.88204)
		)
		(stroke
			(width 0)
			(type solid)
		)
		(fill yes)
		(layer "In2.Cu")
		(net "M_A_DQ<24>")
	)
	(gr_poly
		(pts
			(xy 236.338618 -100.056442) (xy 236.316266 -100.018088) (xy 236.154214 -99.915218) (xy 235.962952 -100.025708)
			(xy 235.97108 -100.217478) (xy 235.993178 -100.256086)
		)
		(stroke
			(width 0)
			(type solid)
		)
		(fill yes)
		(layer "In2.Cu")
		(net "M_D_DQS_DP<12>")
	)
	(gr_poly
		(pts
			(xy 236.340142 -101.046026) (xy 236.31779 -101.007672) (xy 236.155738 -100.904802) (xy 235.964476 -101.015292)
			(xy 235.972604 -101.207062) (xy 235.994702 -101.24567)
		)
		(stroke
			(width 0)
			(type solid)
		)
		(fill yes)
		(layer "In2.Cu")
		(net "M_D_DQS_DN<3>")
	)
	(gr_poly
		(pts
			(xy 236.340142 -98.07448) (xy 236.31779 -98.036126) (xy 236.155738 -97.933256) (xy 235.964476 -98.043746)
			(xy 235.972604 -98.235516) (xy 235.994702 -98.27387)
		)
		(stroke
			(width 0)
			(type solid)
		)
		(fill yes)
		(layer "In2.Cu")
		(net "M_D_DQ<28>")
	)
	(gr_poly
		(pts
			(xy 236.340142 -59.441334) (xy 236.31779 -59.402726) (xy 236.155738 -59.299856) (xy 235.964476 -59.410346)
			(xy 235.972604 -59.602116) (xy 235.994702 -59.640724)
		)
		(stroke
			(width 0)
			(type solid)
		)
		(fill yes)
		(layer "In2.Cu")
		(net "M_A_DQ<21>")
	)
	(gr_poly
		(pts
			(xy 236.342428 -99.06381) (xy 236.320076 -99.025456) (xy 236.158024 -98.922586) (xy 235.966762 -99.033076)
			(xy 235.97489 -99.224846) (xy 235.996988 -99.263454)
		)
		(stroke
			(width 0)
			(type solid)
		)
		(fill yes)
		(layer "In2.Cu")
		(net "M_D_DQ<24>")
	)
	(gr_poly
		(pts
			(xy 236.342428 -57.45861) (xy 236.320076 -57.420256) (xy 236.158024 -57.317386) (xy 235.966762 -57.427876)
			(xy 235.97489 -57.619646) (xy 235.996988 -57.658254)
		)
		(stroke
			(width 0)
			(type solid)
		)
		(fill yes)
		(layer "In2.Cu")
		(net "M_A_DQS_DP<11>")
	)
	(gr_poly
		(pts
			(xy 236.583982 -49.929034) (xy 236.615478 -49.897792) (xy 236.32795 -49.610264) (xy 236.296708 -49.64176)
			(xy 236.223048 -49.84115) (xy 236.384592 -50.002694)
		)
		(stroke
			(width 0)
			(type solid)
		)
		(fill yes)
		(layer "In2.Cu")
		(net "M_A_DQS_DP<12>")
	)
	(gr_poly
		(pts
			(xy 236.676438 -104.2543) (xy 236.644942 -104.223058) (xy 236.445552 -104.149398) (xy 236.284008 -104.310942)
			(xy 236.357668 -104.510332) (xy 236.38891 -104.541828)
		)
		(stroke
			(width 0)
			(type solid)
		)
		(fill yes)
		(layer "In2.Cu")
		(net "M_D_DQ<26>")
	)
	(gr_poly
		(pts
			(xy 236.737144 -50.2031) (xy 236.692694 -50.2031) (xy 236.499654 -50.292) (xy 236.499654 -50.5206)
			(xy 236.692694 -50.6095) (xy 236.737144 -50.6095)
		)
		(stroke
			(width 0)
			(type solid)
		)
		(fill yes)
		(layer "In2.Cu")
		(net "M_A_DQS_DP<12>")
	)
	(gr_poly
		(pts
			(xy 236.780578 -102.31247) (xy 236.749082 -102.281228) (xy 236.549692 -102.207568) (xy 236.388148 -102.369112)
			(xy 236.461808 -102.568502) (xy 236.49305 -102.599998)
		)
		(stroke
			(width 0)
			(type solid)
		)
		(fill yes)
		(layer "In2.Cu")
		(net "M_D_DQ<30>")
	)
	(gr_poly
		(pts
			(xy 236.781594 -49.731422) (xy 236.855254 -49.532286) (xy 236.693456 -49.370488) (xy 236.49432 -49.444148)
			(xy 236.462824 -49.475644) (xy 236.750098 -49.762918)
		)
		(stroke
			(width 0)
			(type solid)
		)
		(fill yes)
		(layer "In2.Cu")
		(net "M_A_DQS_DN<12>")
	)
	(gr_poly
		(pts
			(xy 236.915706 -104.619552) (xy 236.842046 -104.420162) (xy 236.810804 -104.388666) (xy 236.523276 -104.676194)
			(xy 236.554772 -104.707436) (xy 236.754162 -104.781096)
		)
		(stroke
			(width 0)
			(type solid)
		)
		(fill yes)
		(layer "In2.Cu")
		(net "M_D_DQ<27>")
	)
	(gr_poly
		(pts
			(xy 236.961172 -56.625744) (xy 236.9693 -56.433974) (xy 236.778038 -56.323484) (xy 236.615986 -56.426354)
			(xy 236.593634 -56.464962) (xy 236.939074 -56.664098)
		)
		(stroke
			(width 0)
			(type solid)
		)
		(fill yes)
		(layer "In2.Cu")
		(net "M_A_DQS_DP<2>")
	)
	(gr_poly
		(pts
			(xy 236.966506 -93.281246) (xy 236.974634 -93.089476) (xy 236.783372 -92.978986) (xy 236.62132 -93.081856)
			(xy 236.598968 -93.12021) (xy 236.944408 -93.319854)
		)
		(stroke
			(width 0)
			(type solid)
		)
		(fill yes)
		(layer "In2.Cu")
		(net "M_D_DQ<16>")
	)
	(gr_poly
		(pts
			(xy 236.966506 -51.676046) (xy 236.974634 -51.484276) (xy 236.783372 -51.373786) (xy 236.62132 -51.476656)
			(xy 236.598968 -51.51501) (xy 236.944408 -51.714654)
		)
		(stroke
			(width 0)
			(type solid)
		)
		(fill yes)
		(layer "In2.Cu")
		(net "M_A_DQ<25>")
	)
	(gr_poly
		(pts
			(xy 236.968792 -92.291916) (xy 236.97692 -92.100146) (xy 236.785658 -91.989656) (xy 236.623606 -92.092526)
			(xy 236.601254 -92.13088) (xy 236.946694 -92.33027)
		)
		(stroke
			(width 0)
			(type solid)
		)
		(fill yes)
		(layer "In2.Cu")
		(net "M_D_DQ<20>")
	)
	(gr_poly
		(pts
			(xy 236.970316 -94.273878) (xy 236.978444 -94.082108) (xy 236.787182 -93.971618) (xy 236.62513 -94.074488)
			(xy 236.602778 -94.112842) (xy 236.948218 -94.312486)
		)
		(stroke
			(width 0)
			(type solid)
		)
		(fill yes)
		(layer "In2.Cu")
		(net "M_D_DQS_DP<11>")
	)
	(gr_poly
		(pts
			(xy 236.970316 -52.668678) (xy 236.978444 -52.476908) (xy 236.787182 -52.366418) (xy 236.62513 -52.469288)
			(xy 236.602778 -52.507642) (xy 236.948218 -52.707286)
		)
		(stroke
			(width 0)
			(type solid)
		)
		(fill yes)
		(layer "In2.Cu")
		(net "M_A_DQ<29>")
	)
	(gr_poly
		(pts
			(xy 236.974634 -99.32035) (xy 236.966506 -99.12858) (xy 236.944408 -99.089972) (xy 236.598968 -99.289362)
			(xy 236.62132 -99.32797) (xy 236.783372 -99.43084)
		)
		(stroke
			(width 0)
			(type solid)
		)
		(fill yes)
		(layer "In2.Cu")
		(net "M_D_DQ<25>")
	)
	(gr_poly
		(pts
			(xy 236.97692 -100.30968) (xy 236.968792 -100.11791) (xy 236.946694 -100.079302) (xy 236.601254 -100.278946)
			(xy 236.623606 -100.3173) (xy 236.785658 -100.42017)
		)
		(stroke
			(width 0)
			(type solid)
		)
		(fill yes)
		(layer "In2.Cu")
		(net "M_D_DQS_DN<12>")
	)
	(gr_poly
		(pts
			(xy 236.978444 -101.299264) (xy 236.970316 -101.107494) (xy 236.948218 -101.068886) (xy 236.602778 -101.26853)
			(xy 236.62513 -101.306884) (xy 236.787182 -101.409754)
		)
		(stroke
			(width 0)
			(type solid)
		)
		(fill yes)
		(layer "In2.Cu")
		(net "M_D_DQS_DP<3>")
	)
	(gr_poly
		(pts
			(xy 236.978444 -98.327464) (xy 236.970316 -98.135694) (xy 236.948218 -98.097086) (xy 236.602778 -98.29673)
			(xy 236.62513 -98.335084) (xy 236.787182 -98.437954)
		)
		(stroke
			(width 0)
			(type solid)
		)
		(fill yes)
		(layer "In2.Cu")
		(net "M_D_DQ<29>")
	)
	(gr_poly
		(pts
			(xy 236.978444 -59.694064) (xy 236.970316 -59.502294) (xy 236.948218 -59.463686) (xy 236.602778 -59.66333)
			(xy 236.62513 -59.701684) (xy 236.787182 -59.804554)
		)
		(stroke
			(width 0)
			(type solid)
		)
		(fill yes)
		(layer "In2.Cu")
		(net "M_A_DQ<20>")
	)
	(gr_poly
		(pts
			(xy 237.019846 -102.677722) (xy 236.946186 -102.478332) (xy 236.914944 -102.446836) (xy 236.627416 -102.734364)
			(xy 236.658912 -102.765606) (xy 236.858302 -102.839266)
		)
		(stroke
			(width 0)
			(type solid)
		)
		(fill yes)
		(layer "In2.Cu")
		(net "M_D_DQ<31>")
	)
	(gr_poly
		(pts
			(xy 237.165134 -50.2666) (xy 237.165134 -50.038) (xy 236.972094 -49.9491) (xy 236.927644 -49.9491)
			(xy 236.927644 -50.3555) (xy 236.972094 -50.3555)
		)
		(stroke
			(width 0)
			(type solid)
		)
		(fill yes)
		(layer "In2.Cu")
		(net "M_A_DQS_DN<12>")
	)
	(gr_poly
		(pts
			(xy 237.174786 -52.272438) (xy 237.197138 -52.23383) (xy 236.851698 -52.034694) (xy 236.8296 -52.073048)
			(xy 236.821472 -52.264818) (xy 237.012734 -52.375308)
		)
		(stroke
			(width 0)
			(type solid)
		)
		(fill yes)
		(layer "In2.Cu")
		(net "M_A_DQ<24>")
	)
	(gr_poly
		(pts
			(xy 237.178088 -51.283616) (xy 237.20044 -51.245262) (xy 236.855 -51.045618) (xy 236.832902 -51.084226)
			(xy 236.824774 -51.275996) (xy 237.016036 -51.386486)
		)
		(stroke
			(width 0)
			(type solid)
		)
		(fill yes)
		(layer "In2.Cu")
		(net "M_A_DQS_DP<12>")
	)
	(gr_poly
		(pts
			(xy 237.178596 -94.87027) (xy 237.200948 -94.831662) (xy 236.855508 -94.632272) (xy 236.83341 -94.67088)
			(xy 236.825282 -94.86265) (xy 237.016544 -94.97314)
		)
		(stroke
			(width 0)
			(type solid)
		)
		(fill yes)
		(layer "In2.Cu")
		(net "M_D_DQS_DN<11>")
	)
	(gr_poly
		(pts
			(xy 237.178596 -53.26507) (xy 237.200948 -53.226462) (xy 236.855508 -53.027072) (xy 236.83341 -53.06568)
			(xy 236.825282 -53.25745) (xy 237.016544 -53.36794)
		)
		(stroke
			(width 0)
			(type solid)
		)
		(fill yes)
		(layer "In2.Cu")
		(net "M_A_DQ<28>")
	)
	(gr_poly
		(pts
			(xy 237.197138 -98.57105) (xy 237.174786 -98.532442) (xy 237.012734 -98.429572) (xy 236.821472 -98.540062)
			(xy 236.8296 -98.731832) (xy 236.851698 -98.77044)
		)
		(stroke
			(width 0)
			(type solid)
		)
		(fill yes)
		(layer "In2.Cu")
		(net "M_D_DQ<24>")
	)
	(gr_poly
		(pts
			(xy 237.197138 -97.58045) (xy 237.174786 -97.541842) (xy 237.012734 -97.438972) (xy 236.821472 -97.549462)
			(xy 236.8296 -97.741232) (xy 236.851698 -97.77984)
		)
		(stroke
			(width 0)
			(type solid)
		)
		(fill yes)
		(layer "In2.Cu")
		(net "M_D_DQ<28>")
	)
	(gr_poly
		(pts
			(xy 237.198662 -99.56038) (xy 237.17631 -99.522026) (xy 237.014258 -99.419156) (xy 236.822996 -99.529646)
			(xy 236.831124 -99.721416) (xy 236.853222 -99.75977)
		)
		(stroke
			(width 0)
			(type solid)
		)
		(fill yes)
		(layer "In2.Cu")
		(net "M_D_DQS_DP<12>")
	)
	(gr_poly
		(pts
			(xy 237.200948 -100.54971) (xy 237.178596 -100.511356) (xy 237.016544 -100.408486) (xy 236.825282 -100.518976)
			(xy 236.83341 -100.710746) (xy 236.855508 -100.749354)
		)
		(stroke
			(width 0)
			(type solid)
		)
		(fill yes)
		(layer "In2.Cu")
		(net "M_D_DQS_DN<3>")
	)
	(gr_poly
		(pts
			(xy 237.37697 -103.553768) (xy 237.345474 -103.522526) (xy 237.146084 -103.448866) (xy 236.98454 -103.61041)
			(xy 237.0582 -103.8098) (xy 237.089442 -103.841296)
		)
		(stroke
			(width 0)
			(type solid)
		)
		(fill yes)
		(layer "In2.Cu")
		(net "M_D_DQ<26>")
	)
	(gr_poly
		(pts
			(xy 237.48111 -101.611938) (xy 237.449614 -101.580696) (xy 237.250224 -101.507036) (xy 237.08868 -101.66858)
			(xy 237.16234 -101.86797) (xy 237.193582 -101.899466)
		)
		(stroke
			(width 0)
			(type solid)
		)
		(fill yes)
		(layer "In2.Cu")
		(net "M_D_DQ<30>")
	)
	(gr_poly
		(pts
			(xy 237.616238 -103.91902) (xy 237.542578 -103.71963) (xy 237.511336 -103.688134) (xy 237.223808 -103.975662)
			(xy 237.255304 -104.006904) (xy 237.454694 -104.080564)
		)
		(stroke
			(width 0)
			(type solid)
		)
		(fill yes)
		(layer "In2.Cu")
		(net "M_D_DQ<27>")
	)
	(gr_poly
		(pts
			(xy 237.720378 -101.97719) (xy 237.646718 -101.7778) (xy 237.615476 -101.746304) (xy 237.327948 -102.033832)
			(xy 237.359444 -102.065074) (xy 237.558834 -102.138734)
		)
		(stroke
			(width 0)
			(type solid)
		)
		(fill yes)
		(layer "In2.Cu")
		(net "M_D_DQ<31>")
	)
	(gr_poly
		(pts
			(xy 237.825026 -53.161946) (xy 237.833154 -52.970176) (xy 237.641892 -52.859686) (xy 237.47984 -52.962556)
			(xy 237.457488 -53.00091) (xy 237.802928 -53.200554)
		)
		(stroke
			(width 0)
			(type solid)
		)
		(fill yes)
		(layer "In2.Cu")
		(net "M_A_DQ<29>")
	)
	(gr_poly
		(pts
			(xy 237.827312 -93.777816) (xy 237.83544 -93.586046) (xy 237.644178 -93.475556) (xy 237.482126 -93.578426)
			(xy 237.459774 -93.61678) (xy 237.805214 -93.81617)
		)
		(stroke
			(width 0)
			(type solid)
		)
		(fill yes)
		(layer "In2.Cu")
		(net "M_D_DQ<16>")
	)
	(gr_poly
		(pts
			(xy 237.827312 -52.172616) (xy 237.83544 -51.980846) (xy 237.644178 -51.870356) (xy 237.482126 -51.973226)
			(xy 237.459774 -52.011834) (xy 237.805214 -52.211224)
		)
		(stroke
			(width 0)
			(type solid)
		)
		(fill yes)
		(layer "In2.Cu")
		(net "M_A_DQ<25>")
	)
	(gr_poly
		(pts
			(xy 237.828836 -92.788232) (xy 237.836964 -92.596462) (xy 237.645702 -92.485972) (xy 237.48365 -92.588842)
			(xy 237.461298 -92.62745) (xy 237.806738 -92.82684)
		)
		(stroke
			(width 0)
			(type solid)
		)
		(fill yes)
		(layer "In2.Cu")
		(net "M_D_DQ<20>")
	)
	(gr_poly
		(pts
			(xy 237.828836 -51.183032) (xy 237.836964 -50.991262) (xy 237.645702 -50.880772) (xy 237.48365 -50.983642)
			(xy 237.461298 -51.02225) (xy 237.806738 -51.22164)
		)
		(stroke
			(width 0)
			(type solid)
		)
		(fill yes)
		(layer "In2.Cu")
		(net "M_A_DQS_DN<12>")
	)
	(gr_poly
		(pts
			(xy 237.833154 -100.80625) (xy 237.825026 -100.61448) (xy 237.802928 -100.575872) (xy 237.457488 -100.775262)
			(xy 237.47984 -100.81387) (xy 237.641892 -100.91674)
		)
		(stroke
			(width 0)
			(type solid)
		)
		(fill yes)
		(layer "In2.Cu")
		(net "M_D_DQS_DP<3>")
	)
	(gr_poly
		(pts
			(xy 237.83544 -98.82378) (xy 237.827312 -98.63201) (xy 237.805214 -98.593402) (xy 237.459774 -98.793046)
			(xy 237.482126 -98.8314) (xy 237.644178 -98.93427)
		)
		(stroke
			(width 0)
			(type solid)
		)
		(fill yes)
		(layer "In2.Cu")
		(net "M_D_DQ<25>")
	)
	(gr_poly
		(pts
			(xy 237.83544 -97.83318) (xy 237.827312 -97.64141) (xy 237.805214 -97.602802) (xy 237.459774 -97.802446)
			(xy 237.482126 -97.8408) (xy 237.644178 -97.94367)
		)
		(stroke
			(width 0)
			(type solid)
		)
		(fill yes)
		(layer "In2.Cu")
		(net "M_D_DQ<29>")
	)
	(gr_poly
		(pts
			(xy 237.836964 -99.813618) (xy 237.828836 -99.621848) (xy 237.806738 -99.583494) (xy 237.461298 -99.78263)
			(xy 237.48365 -99.821238) (xy 237.645702 -99.924108)
		)
		(stroke
			(width 0)
			(type solid)
		)
		(fill yes)
		(layer "In2.Cu")
		(net "M_D_DQS_DN<12>")
	)
	(gr_poly
		(pts
			(xy 237.897924 -102.35184) (xy 237.866682 -102.320344) (xy 237.667292 -102.246938) (xy 237.505494 -102.408482)
			(xy 237.579154 -102.607872) (xy 237.61065 -102.639368)
		)
		(stroke
			(width 0)
			(type solid)
		)
		(fill yes)
		(layer "In2.Cu")
		(net "M_D_DQ<26>")
	)
	(gr_poly
		(pts
			(xy 238.033306 -53.758084) (xy 238.055658 -53.71973) (xy 237.710218 -53.520086) (xy 237.68812 -53.558694)
			(xy 237.679992 -53.750464) (xy 237.871254 -53.860954)
		)
		(stroke
			(width 0)
			(type solid)
		)
		(fill yes)
		(layer "In2.Cu")
		(net "M_A_DQ<28>")
	)
	(gr_poly
		(pts
			(xy 238.033306 -50.786284) (xy 238.055658 -50.74793) (xy 237.710218 -50.548286) (xy 237.68812 -50.586894)
			(xy 237.679992 -50.778664) (xy 237.871254 -50.889154)
		)
		(stroke
			(width 0)
			(type solid)
		)
		(fill yes)
		(layer "In2.Cu")
		(net "M_A_DQS_DN<3>")
	)
	(gr_poly
		(pts
			(xy 238.03483 -52.7685) (xy 238.057182 -52.730146) (xy 237.711742 -52.530502) (xy 237.689644 -52.56911)
			(xy 237.681516 -52.76088) (xy 237.872778 -52.87137)
		)
		(stroke
			(width 0)
			(type solid)
		)
		(fill yes)
		(layer "In2.Cu")
		(net "M_A_DQ<24>")
	)
	(gr_poly
		(pts
			(xy 238.037116 -51.77917) (xy 238.059468 -51.740562) (xy 237.714028 -51.541172) (xy 237.69193 -51.57978)
			(xy 237.683802 -51.77155) (xy 237.875064 -51.88204)
		)
		(stroke
			(width 0)
			(type solid)
		)
		(fill yes)
		(layer "In2.Cu")
		(net "M_A_DQS_DP<12>")
	)
	(gr_poly
		(pts
			(xy 238.055658 -100.056442) (xy 238.033306 -100.018088) (xy 237.871254 -99.915218) (xy 237.679992 -100.025708)
			(xy 237.68812 -100.217478) (xy 237.710218 -100.256086)
		)
		(stroke
			(width 0)
			(type solid)
		)
		(fill yes)
		(layer "In2.Cu")
		(net "M_D_DQS_DN<3>")
	)
	(gr_poly
		(pts
			(xy 238.057182 -98.07448) (xy 238.03483 -98.036126) (xy 237.872778 -97.933256) (xy 237.681516 -98.043746)
			(xy 237.689644 -98.235516) (xy 237.711742 -98.27387)
		)
		(stroke
			(width 0)
			(type solid)
		)
		(fill yes)
		(layer "In2.Cu")
		(net "M_D_DQ<24>")
	)
	(gr_poly
		(pts
			(xy 238.057182 -97.08388) (xy 238.03483 -97.045526) (xy 237.872778 -96.942656) (xy 237.681516 -97.053146)
			(xy 237.689644 -97.244916) (xy 237.711742 -97.28327)
		)
		(stroke
			(width 0)
			(type solid)
		)
		(fill yes)
		(layer "In2.Cu")
		(net "M_D_DQ<28>")
	)
	(gr_poly
		(pts
			(xy 238.05769 -101.045772) (xy 238.035338 -101.007418) (xy 237.873286 -100.904548) (xy 237.682024 -101.015038)
			(xy 237.690152 -101.206808) (xy 237.71225 -101.245162)
		)
		(stroke
			(width 0)
			(type solid)
		)
		(fill yes)
		(layer "In2.Cu")
		(net "M_D_DQ<30>")
	)
	(gr_poly
		(pts
			(xy 238.059468 -99.06381) (xy 238.037116 -99.025456) (xy 237.875064 -98.922586) (xy 237.683802 -99.033076)
			(xy 237.69193 -99.224846) (xy 237.714028 -99.263454)
		)
		(stroke
			(width 0)
			(type solid)
		)
		(fill yes)
		(layer "In2.Cu")
		(net "M_D_DQS_DP<12>")
	)
	(gr_poly
		(pts
			(xy 238.137446 -102.717092) (xy 238.063786 -102.517702) (xy 238.032544 -102.486206) (xy 237.745016 -102.773734)
			(xy 237.776512 -102.804976) (xy 237.975902 -102.878636)
		)
		(stroke
			(width 0)
			(type solid)
		)
		(fill yes)
		(layer "In2.Cu")
		(net "M_D_DQ<27>")
	)
	(gr_poly
		(pts
			(xy 238.683546 -51.676046) (xy 238.691674 -51.484276) (xy 238.500412 -51.373786) (xy 238.33836 -51.476656)
			(xy 238.316008 -51.51501) (xy 238.661448 -51.714654)
		)
		(stroke
			(width 0)
			(type solid)
		)
		(fill yes)
		(layer "In2.Cu")
		(net "M_A_DQS_DN<12>")
	)
	(gr_poly
		(pts
			(xy 238.685832 -53.658516) (xy 238.69396 -53.466746) (xy 238.502698 -53.356256) (xy 238.340646 -53.459126)
			(xy 238.318294 -53.497734) (xy 238.663734 -53.697124)
		)
		(stroke
			(width 0)
			(type solid)
		)
		(fill yes)
		(layer "In2.Cu")
		(net "M_A_DQ<29>")
	)
	(gr_poly
		(pts
			(xy 238.685832 -50.686716) (xy 238.69396 -50.494946) (xy 238.502698 -50.384456) (xy 238.340646 -50.487326)
			(xy 238.318294 -50.525934) (xy 238.663734 -50.725324)
		)
		(stroke
			(width 0)
			(type solid)
		)
		(fill yes)
		(layer "In2.Cu")
		(net "M_A_DQS_DP<3>")
	)
	(gr_poly
		(pts
			(xy 238.687356 -52.668678) (xy 238.695484 -52.476908) (xy 238.504222 -52.366418) (xy 238.34217 -52.469288)
			(xy 238.319818 -52.507642) (xy 238.665258 -52.707286)
		)
		(stroke
			(width 0)
			(type solid)
		)
		(fill yes)
		(layer "In2.Cu")
		(net "M_A_DQ<25>")
	)
	(gr_poly
		(pts
			(xy 238.691674 -99.32035) (xy 238.683546 -99.12858) (xy 238.661448 -99.089972) (xy 238.316008 -99.289362)
			(xy 238.33836 -99.32797) (xy 238.500412 -99.43084)
		)
		(stroke
			(width 0)
			(type solid)
		)
		(fill yes)
		(layer "In2.Cu")
		(net "M_D_DQS_DN<12>")
	)
	(gr_poly
		(pts
			(xy 238.69396 -100.30968) (xy 238.685832 -100.11791) (xy 238.663734 -100.079302) (xy 238.318294 -100.278946)
			(xy 238.340646 -100.3173) (xy 238.502698 -100.42017)
		)
		(stroke
			(width 0)
			(type solid)
		)
		(fill yes)
		(layer "In2.Cu")
		(net "M_D_DQS_DP<3>")
	)
	(gr_poly
		(pts
			(xy 238.695484 -101.299264) (xy 238.687356 -101.107494) (xy 238.665258 -101.068886) (xy 238.319818 -101.26853)
			(xy 238.34217 -101.306884) (xy 238.504222 -101.409754)
		)
		(stroke
			(width 0)
			(type solid)
		)
		(fill yes)
		(layer "In2.Cu")
		(net "M_D_DQ<31>")
	)
	(gr_poly
		(pts
			(xy 238.695484 -98.327464) (xy 238.687356 -98.135694) (xy 238.665258 -98.097086) (xy 238.319818 -98.29673)
			(xy 238.34217 -98.335084) (xy 238.504222 -98.437954)
		)
		(stroke
			(width 0)
			(type solid)
		)
		(fill yes)
		(layer "In2.Cu")
		(net "M_D_DQ<25>")
	)
	(gr_poly
		(pts
			(xy 238.695484 -97.336864) (xy 238.687356 -97.145094) (xy 238.665258 -97.106486) (xy 238.319818 -97.30613)
			(xy 238.34217 -97.344484) (xy 238.504222 -97.447354)
		)
		(stroke
			(width 0)
			(type solid)
		)
		(fill yes)
		(layer "In2.Cu")
		(net "M_D_DQ<29>")
	)
	(gr_poly
		(pts
			(xy 238.891826 -52.272438) (xy 238.914178 -52.23383) (xy 238.568738 -52.034694) (xy 238.54664 -52.073048)
			(xy 238.538512 -52.264818) (xy 238.729774 -52.375308)
		)
		(stroke
			(width 0)
			(type solid)
		)
		(fill yes)
		(layer "In2.Cu")
		(net "M_A_DQS_DP<12>")
	)
	(gr_poly
		(pts
			(xy 238.89335 -54.2544) (xy 238.915702 -54.216046) (xy 238.570262 -54.016402) (xy 238.548164 -54.05501)
			(xy 238.540036 -54.24678) (xy 238.731298 -54.35727)
		)
		(stroke
			(width 0)
			(type solid)
		)
		(fill yes)
		(layer "In2.Cu")
		(net "M_A_DQ<28>")
	)
	(gr_poly
		(pts
			(xy 238.89335 -51.2826) (xy 238.915702 -51.244246) (xy 238.570262 -51.044602) (xy 238.548164 -51.08321)
			(xy 238.540036 -51.27498) (xy 238.731298 -51.38547)
		)
		(stroke
			(width 0)
			(type solid)
		)
		(fill yes)
		(layer "In2.Cu")
		(net "M_A_DQS_DN<3>")
	)
	(gr_poly
		(pts
			(xy 238.895636 -53.26507) (xy 238.917988 -53.226462) (xy 238.572548 -53.027072) (xy 238.55045 -53.06568)
			(xy 238.542322 -53.25745) (xy 238.733584 -53.36794)
		)
		(stroke
			(width 0)
			(type solid)
		)
		(fill yes)
		(layer "In2.Cu")
		(net "M_A_DQ<24>")
	)
	(gr_poly
		(pts
			(xy 238.914178 -98.57105) (xy 238.891826 -98.532442) (xy 238.729774 -98.429572) (xy 238.538512 -98.540062)
			(xy 238.54664 -98.731832) (xy 238.568738 -98.77044)
		)
		(stroke
			(width 0)
			(type solid)
		)
		(fill yes)
		(layer "In2.Cu")
		(net "M_D_DQS_DP<12>")
	)
	(gr_poly
		(pts
			(xy 238.914178 -97.58045) (xy 238.891826 -97.541842) (xy 238.729774 -97.438972) (xy 238.538512 -97.549462)
			(xy 238.54664 -97.741232) (xy 238.568738 -97.77984)
		)
		(stroke
			(width 0)
			(type solid)
		)
		(fill yes)
		(layer "In2.Cu")
		(net "M_D_DQ<24>")
	)
	(gr_poly
		(pts
			(xy 238.914178 -96.58985) (xy 238.891826 -96.551242) (xy 238.729774 -96.448372) (xy 238.538512 -96.558862)
			(xy 238.54664 -96.750632) (xy 238.568738 -96.78924)
		)
		(stroke
			(width 0)
			(type solid)
		)
		(fill yes)
		(layer "In2.Cu")
		(net "M_D_DQ<28>")
	)
	(gr_poly
		(pts
			(xy 238.915702 -99.56038) (xy 238.89335 -99.522026) (xy 238.731298 -99.419156) (xy 238.540036 -99.529646)
			(xy 238.548164 -99.721416) (xy 238.570262 -99.75977)
		)
		(stroke
			(width 0)
			(type solid)
		)
		(fill yes)
		(layer "In2.Cu")
		(net "M_D_DQS_DN<3>")
	)
	(gr_poly
		(pts
			(xy 238.917988 -100.54971) (xy 238.895636 -100.511356) (xy 238.733584 -100.408486) (xy 238.542322 -100.518976)
			(xy 238.55045 -100.710746) (xy 238.572548 -100.749354)
		)
		(stroke
			(width 0)
			(type solid)
		)
		(fill yes)
		(layer "In2.Cu")
		(net "M_D_DQ<30>")
	)
	(gr_poly
		(pts
			(xy 239.064546 -101.74351) (xy 239.03305 -101.712014) (xy 238.833914 -101.638354) (xy 238.672116 -101.800152)
			(xy 238.745776 -101.999288) (xy 238.777272 -102.030784)
		)
		(stroke
			(width 0)
			(type solid)
		)
		(fill yes)
		(layer "In2.Cu")
		(net "M_D_DQ<26>")
	)
	(gr_poly
		(pts
			(xy 239.180624 -49.512728) (xy 239.136174 -49.512728) (xy 238.943134 -49.601628) (xy 238.943134 -49.830228)
			(xy 239.136174 -49.919128) (xy 239.180624 -49.919128)
		)
		(stroke
			(width 0)
			(type solid)
		)
		(fill yes)
		(layer "In2.Cu")
		(net "M_A_DQ<30>")
	)
	(gr_poly
		(pts
			(xy 239.304576 -102.109016) (xy 239.230916 -101.90988) (xy 239.19942 -101.878384) (xy 238.912146 -102.165658)
			(xy 238.943642 -102.197154) (xy 239.142778 -102.270814)
		)
		(stroke
			(width 0)
			(type solid)
		)
		(fill yes)
		(layer "In2.Cu")
		(net "M_D_DQ<27>")
	)
	(gr_poly
		(pts
			(xy 239.542066 -53.161946) (xy 239.550194 -52.970176) (xy 239.358932 -52.859686) (xy 239.19688 -52.962556)
			(xy 239.174528 -53.00091) (xy 239.519968 -53.200554)
		)
		(stroke
			(width 0)
			(type solid)
		)
		(fill yes)
		(layer "In2.Cu")
		(net "M_A_DQ<25>")
	)
	(gr_poly
		(pts
			(xy 239.544352 -52.172616) (xy 239.55248 -51.980846) (xy 239.361218 -51.870356) (xy 239.199166 -51.973226)
			(xy 239.176814 -52.011834) (xy 239.522254 -52.211224)
		)
		(stroke
			(width 0)
			(type solid)
		)
		(fill yes)
		(layer "In2.Cu")
		(net "M_A_DQS_DN<12>")
	)
	(gr_poly
		(pts
			(xy 239.545876 -54.154832) (xy 239.554004 -53.963062) (xy 239.362742 -53.852572) (xy 239.20069 -53.955442)
			(xy 239.178338 -53.99405) (xy 239.523778 -54.19344)
		)
		(stroke
			(width 0)
			(type solid)
		)
		(fill yes)
		(layer "In2.Cu")
		(net "M_A_DQ<29>")
	)
	(gr_poly
		(pts
			(xy 239.545876 -51.183032) (xy 239.554004 -50.991262) (xy 239.362742 -50.880772) (xy 239.20069 -50.983642)
			(xy 239.178338 -51.02225) (xy 239.523778 -51.22164)
		)
		(stroke
			(width 0)
			(type solid)
		)
		(fill yes)
		(layer "In2.Cu")
		(net "M_A_DQS_DP<3>")
	)
	(gr_poly
		(pts
			(xy 239.550194 -100.80625) (xy 239.542066 -100.61448) (xy 239.519968 -100.575872) (xy 239.174528 -100.775262)
			(xy 239.19688 -100.81387) (xy 239.358932 -100.91674)
		)
		(stroke
			(width 0)
			(type solid)
		)
		(fill yes)
		(layer "In2.Cu")
		(net "M_D_DQ<31>")
	)
	(gr_poly
		(pts
			(xy 239.55248 -98.82378) (xy 239.544352 -98.63201) (xy 239.522254 -98.593402) (xy 239.176814 -98.793046)
			(xy 239.199166 -98.8314) (xy 239.361218 -98.93427)
		)
		(stroke
			(width 0)
			(type solid)
		)
		(fill yes)
		(layer "In2.Cu")
		(net "M_D_DQS_DN<12>")
	)
	(gr_poly
		(pts
			(xy 239.55248 -97.83318) (xy 239.544352 -97.64141) (xy 239.522254 -97.602802) (xy 239.176814 -97.802446)
			(xy 239.199166 -97.8408) (xy 239.361218 -97.94367)
		)
		(stroke
			(width 0)
			(type solid)
		)
		(fill yes)
		(layer "In2.Cu")
		(net "M_D_DQ<25>")
	)
	(gr_poly
		(pts
			(xy 239.55248 -96.84258) (xy 239.544352 -96.65081) (xy 239.522254 -96.612202) (xy 239.176814 -96.811846)
			(xy 239.199166 -96.8502) (xy 239.361218 -96.95307)
		)
		(stroke
			(width 0)
			(type solid)
		)
		(fill yes)
		(layer "In2.Cu")
		(net "M_D_DQ<29>")
	)
	(gr_poly
		(pts
			(xy 239.554004 -99.813618) (xy 239.545876 -99.621848) (xy 239.523778 -99.583494) (xy 239.178338 -99.78263)
			(xy 239.20069 -99.821238) (xy 239.362742 -99.924108)
		)
		(stroke
			(width 0)
			(type solid)
		)
		(fill yes)
		(layer "In2.Cu")
		(net "M_D_DQS_DP<3>")
	)
	(gr_poly
		(pts
			(xy 239.608614 -49.830228) (xy 239.608614 -49.601628) (xy 239.415574 -49.512728) (xy 239.371124 -49.512728)
			(xy 239.371124 -49.919128) (xy 239.415574 -49.919128)
		)
		(stroke
			(width 0)
			(type solid)
		)
		(fill yes)
		(layer "In2.Cu")
		(net "M_A_DQ<31>")
	)
	(gr_poly
		(pts
			(xy 239.750346 -53.758084) (xy 239.772698 -53.71973) (xy 239.427258 -53.520086) (xy 239.40516 -53.558694)
			(xy 239.397032 -53.750464) (xy 239.588294 -53.860954)
		)
		(stroke
			(width 0)
			(type solid)
		)
		(fill yes)
		(layer "In2.Cu")
		(net "M_A_DQ<24>")
	)
	(gr_poly
		(pts
			(xy 239.750346 -51.776884) (xy 239.772698 -51.73853) (xy 239.427258 -51.538886) (xy 239.40516 -51.577494)
			(xy 239.397032 -51.769264) (xy 239.588294 -51.879754)
		)
		(stroke
			(width 0)
			(type solid)
		)
		(fill yes)
		(layer "In2.Cu")
		(net "M_A_DQS_DN<3>")
	)
	(gr_poly
		(pts
			(xy 239.750346 -50.786284) (xy 239.772698 -50.74793) (xy 239.427258 -50.548286) (xy 239.40516 -50.586894)
			(xy 239.397032 -50.778664) (xy 239.588294 -50.889154)
		)
		(stroke
			(width 0)
			(type solid)
		)
		(fill yes)
		(layer "In2.Cu")
		(net "M_A_DQ<30>")
	)
	(gr_poly
		(pts
			(xy 239.75187 -52.7685) (xy 239.774222 -52.730146) (xy 239.428782 -52.530502) (xy 239.406684 -52.56911)
			(xy 239.398556 -52.76088) (xy 239.589818 -52.87137)
		)
		(stroke
			(width 0)
			(type solid)
		)
		(fill yes)
		(layer "In2.Cu")
		(net "M_A_DQS_DP<12>")
	)
	(gr_poly
		(pts
			(xy 239.772698 -101.046788) (xy 239.750346 -101.008434) (xy 239.588294 -100.905564) (xy 239.397032 -101.016054)
			(xy 239.40516 -101.207824) (xy 239.427258 -101.246178)
		)
		(stroke
			(width 0)
			(type solid)
		)
		(fill yes)
		(layer "In2.Cu")
		(net "M_D_DQ<26>")
	)
	(gr_poly
		(pts
			(xy 239.772698 -100.056442) (xy 239.750346 -100.018088) (xy 239.588294 -99.915218) (xy 239.397032 -100.025708)
			(xy 239.40516 -100.217478) (xy 239.427258 -100.256086)
		)
		(stroke
			(width 0)
			(type solid)
		)
		(fill yes)
		(layer "In2.Cu")
		(net "M_D_DQ<30>")
	)
	(gr_poly
		(pts
			(xy 239.774222 -98.07448) (xy 239.75187 -98.036126) (xy 239.589818 -97.933256) (xy 239.398556 -98.043746)
			(xy 239.406684 -98.235516) (xy 239.428782 -98.27387)
		)
		(stroke
			(width 0)
			(type solid)
		)
		(fill yes)
		(layer "In2.Cu")
		(net "M_D_DQS_DP<12>")
	)
	(gr_poly
		(pts
			(xy 239.774222 -97.08388) (xy 239.75187 -97.045526) (xy 239.589818 -96.942656) (xy 239.398556 -97.053146)
			(xy 239.406684 -97.244916) (xy 239.428782 -97.28327)
		)
		(stroke
			(width 0)
			(type solid)
		)
		(fill yes)
		(layer "In2.Cu")
		(net "M_D_DQ<24>")
	)
	(gr_poly
		(pts
			(xy 239.775238 -96.0882) (xy 239.749838 -96.051624) (xy 239.579404 -95.963232) (xy 239.398302 -96.089978)
			(xy 239.423194 -96.280478) (xy 239.448594 -96.3168)
		)
		(stroke
			(width 0)
			(type solid)
		)
		(fill yes)
		(layer "In2.Cu")
		(net "M_D_DQ<28>")
	)
	(gr_poly
		(pts
			(xy 239.776508 -99.06381) (xy 239.754156 -99.025456) (xy 239.592104 -98.922586) (xy 239.400842 -99.033076)
			(xy 239.40897 -99.224846) (xy 239.431068 -99.263454)
		)
		(stroke
			(width 0)
			(type solid)
		)
		(fill yes)
		(layer "In2.Cu")
		(net "M_D_DQS_DN<3>")
	)
	(gr_poly
		(pts
			(xy 240.158524 -48.523652) (xy 240.114074 -48.523652) (xy 239.921034 -48.612552) (xy 239.921034 -48.841152)
			(xy 240.114074 -48.930052) (xy 240.158524 -48.930052)
		)
		(stroke
			(width 0)
			(type solid)
		)
		(fill yes)
		(layer "In2.Cu")
		(net "M_A_DQ<26>")
	)
	(gr_poly
		(pts
			(xy 240.402872 -53.658516) (xy 240.411 -53.466746) (xy 240.219738 -53.356256) (xy 240.057686 -53.459126)
			(xy 240.035334 -53.497734) (xy 240.380774 -53.697124)
		)
		(stroke
			(width 0)
			(type solid)
		)
		(fill yes)
		(layer "In2.Cu")
		(net "M_A_DQ<25>")
	)
	(gr_poly
		(pts
			(xy 240.402872 -51.677316) (xy 240.411 -51.485546) (xy 240.219738 -51.375056) (xy 240.057686 -51.477926)
			(xy 240.035334 -51.516534) (xy 240.380774 -51.715924)
		)
		(stroke
			(width 0)
			(type solid)
		)
		(fill yes)
		(layer "In2.Cu")
		(net "M_A_DQS_DP<3>")
	)
	(gr_poly
		(pts
			(xy 240.402872 -50.686716) (xy 240.411 -50.494946) (xy 240.219738 -50.384456) (xy 240.057686 -50.487326)
			(xy 240.035334 -50.525934) (xy 240.380774 -50.725324)
		)
		(stroke
			(width 0)
			(type solid)
		)
		(fill yes)
		(layer "In2.Cu")
		(net "M_A_DQ<31>")
	)
	(gr_poly
		(pts
			(xy 240.404396 -52.668678) (xy 240.412524 -52.476908) (xy 240.221262 -52.366418) (xy 240.05921 -52.469288)
			(xy 240.036858 -52.507642) (xy 240.382298 -52.707286)
		)
		(stroke
			(width 0)
			(type solid)
		)
		(fill yes)
		(layer "In2.Cu")
		(net "M_A_DQS_DN<12>")
	)
	(gr_poly
		(pts
			(xy 240.408714 -99.32035) (xy 240.400586 -99.12858) (xy 240.378488 -99.089972) (xy 240.033048 -99.289362)
			(xy 240.0554 -99.32797) (xy 240.217452 -99.43084)
		)
		(stroke
			(width 0)
			(type solid)
		)
		(fill yes)
		(layer "In2.Cu")
		(net "M_D_DQS_DP<3>")
	)
	(gr_poly
		(pts
			(xy 240.411 -101.300026) (xy 240.402872 -101.108256) (xy 240.380774 -101.069648) (xy 240.035334 -101.269038)
			(xy 240.057686 -101.307646) (xy 240.219738 -101.410516)
		)
		(stroke
			(width 0)
			(type solid)
		)
		(fill yes)
		(layer "In2.Cu")
		(net "M_D_DQ<27>")
	)
	(gr_poly
		(pts
			(xy 240.411 -100.30968) (xy 240.402872 -100.11791) (xy 240.380774 -100.079302) (xy 240.035334 -100.278946)
			(xy 240.057686 -100.3173) (xy 240.219738 -100.42017)
		)
		(stroke
			(width 0)
			(type solid)
		)
		(fill yes)
		(layer "In2.Cu")
		(net "M_D_DQ<31>")
	)
	(gr_poly
		(pts
			(xy 240.412524 -98.327464) (xy 240.404396 -98.135694) (xy 240.382298 -98.097086) (xy 240.036858 -98.29673)
			(xy 240.05921 -98.335084) (xy 240.221262 -98.437954)
		)
		(stroke
			(width 0)
			(type solid)
		)
		(fill yes)
		(layer "In2.Cu")
		(net "M_D_DQS_DN<12>")
	)
	(gr_poly
		(pts
			(xy 240.519204 -96.809814) (xy 240.519966 -96.589088) (xy 240.35004 -96.49968) (xy 240.305336 -96.499426)
			(xy 240.30432 -96.898206) (xy 240.34877 -96.898206)
		)
		(stroke
			(width 0)
			(type solid)
		)
		(fill yes)
		(layer "In2.Cu")
		(net "M_D_DQ<24>")
	)
	(gr_poly
		(pts
			(xy 240.585498 -95.432372) (xy 240.54943 -95.406464) (xy 240.359438 -95.378778) (xy 240.230152 -95.557848)
			(xy 240.316004 -95.729552) (xy 240.352072 -95.755714)
		)
		(stroke
			(width 0)
			(type solid)
		)
		(fill yes)
		(layer "In2.Cu")
		(net "M_D_DQ<24>")
	)
	(gr_poly
		(pts
			(xy 240.586514 -48.841152) (xy 240.586514 -48.612552) (xy 240.393474 -48.523652) (xy 240.349024 -48.523652)
			(xy 240.349024 -48.930052) (xy 240.393474 -48.930052)
		)
		(stroke
			(width 0)
			(type solid)
		)
		(fill yes)
		(layer "In2.Cu")
		(net "M_A_DQ<27>")
	)
	(gr_poly
		(pts
			(xy 240.61039 -52.2732) (xy 240.632742 -52.234846) (xy 240.287302 -52.035202) (xy 240.265204 -52.07381)
			(xy 240.257076 -52.26558) (xy 240.448338 -52.37607)
		)
		(stroke
			(width 0)
			(type solid)
		)
		(fill yes)
		(layer "In2.Cu")
		(net "M_A_DQS_DN<3>")
	)
	(gr_poly
		(pts
			(xy 240.61039 -51.2826) (xy 240.632742 -51.244246) (xy 240.287302 -51.044602) (xy 240.265204 -51.08321)
			(xy 240.257076 -51.27498) (xy 240.448338 -51.38547)
		)
		(stroke
			(width 0)
			(type solid)
		)
		(fill yes)
		(layer "In2.Cu")
		(net "M_A_DQ<30>")
	)
	(gr_poly
		(pts
			(xy 240.612676 -53.26507) (xy 240.635028 -53.226462) (xy 240.289588 -53.027072) (xy 240.26749 -53.06568)
			(xy 240.259362 -53.25745) (xy 240.450624 -53.36794)
		)
		(stroke
			(width 0)
			(type solid)
		)
		(fill yes)
		(layer "In2.Cu")
		(net "M_A_DQS_DP<12>")
	)
	(gr_poly
		(pts
			(xy 240.631218 -98.57105) (xy 240.608866 -98.532442) (xy 240.446814 -98.429572) (xy 240.255552 -98.540062)
			(xy 240.26368 -98.731832) (xy 240.285778 -98.77044)
		)
		(stroke
			(width 0)
			(type solid)
		)
		(fill yes)
		(layer "In2.Cu")
		(net "M_D_DQS_DN<3>")
	)
	(gr_poly
		(pts
			(xy 240.631218 -97.58045) (xy 240.608866 -97.541842) (xy 240.446814 -97.438972) (xy 240.255552 -97.549462)
			(xy 240.26368 -97.741232) (xy 240.285778 -97.77984)
		)
		(stroke
			(width 0)
			(type solid)
		)
		(fill yes)
		(layer "In2.Cu")
		(net "M_D_DQS_DP<12>")
	)
	(gr_poly
		(pts
			(xy 240.632742 -100.550726) (xy 240.61039 -100.512372) (xy 240.448338 -100.409502) (xy 240.257076 -100.519992)
			(xy 240.265204 -100.711762) (xy 240.287302 -100.75037)
		)
		(stroke
			(width 0)
			(type solid)
		)
		(fill yes)
		(layer "In2.Cu")
		(net "M_D_DQ<26>")
	)
	(gr_poly
		(pts
			(xy 240.632742 -99.56038) (xy 240.61039 -99.522026) (xy 240.448338 -99.419156) (xy 240.257076 -99.529646)
			(xy 240.265204 -99.721416) (xy 240.287302 -99.75977)
		)
		(stroke
			(width 0)
			(type solid)
		)
		(fill yes)
		(layer "In2.Cu")
		(net "M_D_DQ<30>")
	)
	(gr_poly
		(pts
			(xy 240.770918 -49.88687) (xy 240.802414 -49.855374) (xy 240.51514 -49.5681) (xy 240.483644 -49.599596)
			(xy 240.409984 -49.798732) (xy 240.571782 -49.96053)
		)
		(stroke
			(width 0)
			(type solid)
		)
		(fill yes)
		(layer "In2.Cu")
		(net "M_A_DQ<26>")
	)
	(gr_poly
		(pts
			(xy 240.96853 -49.689258) (xy 241.04219 -49.489868) (xy 240.880646 -49.328324) (xy 240.681256 -49.401984)
			(xy 240.64976 -49.433226) (xy 240.937288 -49.720754)
		)
		(stroke
			(width 0)
			(type solid)
		)
		(fill yes)
		(layer "In2.Cu")
		(net "M_A_DQ<27>")
	)
	(gr_poly
		(pts
			(xy 241.03076 -96.507046) (xy 240.98631 -96.507046) (xy 240.81613 -96.595946) (xy 240.81613 -96.816926)
			(xy 240.98631 -96.905826) (xy 241.03076 -96.905826)
		)
		(stroke
			(width 0)
			(type solid)
		)
		(fill yes)
		(layer "In2.Cu")
		(net "M_D_DQS_DP<12>")
	)
	(gr_poly
		(pts
			(xy 241.03076 -95.516446) (xy 240.98631 -95.516446) (xy 240.81613 -95.605346) (xy 240.81613 -95.826326)
			(xy 240.98631 -95.915226) (xy 241.03076 -95.915226)
		)
		(stroke
			(width 0)
			(type solid)
		)
		(fill yes)
		(layer "In2.Cu")
		(net "M_D_DQS_DP<12>")
	)
	(gr_poly
		(pts
			(xy 241.153696 -55.084218) (xy 241.145568 -54.892194) (xy 241.123216 -54.85384) (xy 240.77803 -55.05323)
			(xy 240.800128 -55.091838) (xy 240.96218 -55.194708)
		)
		(stroke
			(width 0)
			(type solid)
		)
		(fill yes)
		(layer "In2.Cu")
		(net "M_A_DQ<25>")
	)
	(gr_poly
		(pts
			(xy 241.259106 -53.161946) (xy 241.267234 -52.970176) (xy 241.075972 -52.859686) (xy 240.91392 -52.962556)
			(xy 240.891568 -53.00091) (xy 241.237008 -53.200554)
		)
		(stroke
			(width 0)
			(type solid)
		)
		(fill yes)
		(layer "In2.Cu")
		(net "M_A_DQS_DN<12>")
	)
	(gr_poly
		(pts
			(xy 241.262916 -52.173632) (xy 241.271044 -51.981862) (xy 241.079782 -51.871372) (xy 240.91773 -51.974242)
			(xy 240.895378 -52.01285) (xy 241.240818 -52.21224)
		)
		(stroke
			(width 0)
			(type solid)
		)
		(fill yes)
		(layer "In2.Cu")
		(net "M_A_DQS_DP<3>")
	)
	(gr_poly
		(pts
			(xy 241.269266 -97.833688) (xy 241.261138 -97.641664) (xy 241.239294 -97.60331) (xy 240.8936 -97.8027)
			(xy 240.915952 -97.841054) (xy 241.078004 -97.943924)
		)
		(stroke
			(width 0)
			(type solid)
		)
		(fill yes)
		(layer "In2.Cu")
		(net "M_D_DQS_DN<12>")
	)
	(gr_poly
		(pts
			(xy 241.26952 -99.81438) (xy 241.261392 -99.62261) (xy 241.239294 -99.584002) (xy 240.893854 -99.783646)
			(xy 240.916206 -99.822) (xy 241.078258 -99.92487)
		)
		(stroke
			(width 0)
			(type solid)
		)
		(fill yes)
		(layer "In2.Cu")
		(net "M_D_DQ<31>")
	)
	(gr_poly
		(pts
			(xy 241.26952 -98.82378) (xy 241.261392 -98.63201) (xy 241.239294 -98.593402) (xy 240.893854 -98.793046)
			(xy 240.916206 -98.8314) (xy 241.078258 -98.93427)
		)
		(stroke
			(width 0)
			(type solid)
		)
		(fill yes)
		(layer "In2.Cu")
		(net "M_D_DQS_DP<3>")
	)
	(gr_poly
		(pts
			(xy 241.271044 -100.803964) (xy 241.262916 -100.612194) (xy 241.240818 -100.573586) (xy 240.895378 -100.77323)
			(xy 240.91773 -100.811584) (xy 241.079782 -100.914454)
		)
		(stroke
			(width 0)
			(type solid)
		)
		(fill yes)
		(layer "In2.Cu")
		(net "M_D_DQ<27>")
	)
	(gr_poly
		(pts
			(xy 241.467386 -52.767484) (xy 241.489738 -52.72913) (xy 241.144298 -52.529486) (xy 241.1222 -52.568094)
			(xy 241.114072 -52.759864) (xy 241.305334 -52.870354)
		)
		(stroke
			(width 0)
			(type solid)
		)
		(fill yes)
		(layer "In2.Cu")
		(net "M_A_DQS_DN<3>")
	)
	(gr_poly
		(pts
			(xy 241.486182 -95.0976) (xy 241.460528 -95.061024) (xy 241.290348 -94.972632) (xy 241.109246 -95.099378)
			(xy 241.134138 -95.289624) (xy 241.159538 -95.325946)
		)
		(stroke
			(width 0)
			(type solid)
		)
		(fill yes)
		(layer "In2.Cu")
		(net "M_D_DQS_DP<12>")
	)
	(gr_poly
		(pts
			(xy 241.493548 -100.054156) (xy 241.471196 -100.015802) (xy 241.309144 -99.912932) (xy 241.117882 -100.023422)
			(xy 241.12601 -100.215192) (xy 241.148108 -100.253546)
		)
		(stroke
			(width 0)
			(type solid)
		)
		(fill yes)
		(layer "In2.Cu")
		(net "M_D_DQ<26>")
	)
	(gr_poly
		(pts
			(xy 241.497866 -99.065588) (xy 241.475514 -99.02698) (xy 241.313462 -98.92411) (xy 241.1222 -99.0346)
			(xy 241.130328 -99.22637) (xy 241.152426 -99.264724)
		)
		(stroke
			(width 0)
			(type solid)
		)
		(fill yes)
		(layer "In2.Cu")
		(net "M_D_DQ<30>")
	)
	(gr_poly
		(pts
			(xy 241.506502 -55.47106) (xy 241.48415 -55.432706) (xy 241.322098 -55.329836) (xy 241.130836 -55.440326)
			(xy 241.138964 -55.632096) (xy 241.161062 -55.67045)
		)
		(stroke
			(width 0)
			(type solid)
		)
		(fill yes)
		(layer "In2.Cu")
		(net "M_A_DQS_DN<3>")
	)
	(gr_poly
		(pts
			(xy 241.568986 -96.30918) (xy 241.568986 -96.0882) (xy 241.398806 -95.9993) (xy 241.354356 -95.9993)
			(xy 241.354356 -96.39808) (xy 241.398806 -96.39808)
		)
		(stroke
			(width 0)
			(type solid)
		)
		(fill yes)
		(layer "In2.Cu")
		(net "M_D_DQS_DN<12>")
	)
	(gr_poly
		(pts
			(xy 241.88928 -54.3941) (xy 241.84483 -54.3941) (xy 241.67465 -54.483) (xy 241.67465 -54.70398) (xy 241.84483 -54.79288)
			(xy 241.88928 -54.79288)
		)
		(stroke
			(width 0)
			(type solid)
		)
		(fill yes)
		(layer "In2.Cu")
		(net "M_A_DQS_DN<3>")
	)
	(gr_poly
		(pts
			(xy 241.88928 -53.4035) (xy 241.84483 -53.4035) (xy 241.67465 -53.4924) (xy 241.67465 -53.71338)
			(xy 241.84483 -53.80228) (xy 241.88928 -53.80228)
		)
		(stroke
			(width 0)
			(type solid)
		)
		(fill yes)
		(layer "In2.Cu")
		(net "M_A_DQS_DN<3>")
	)
	(gr_poly
		(pts
			(xy 241.902234 -50.802032) (xy 241.933476 -50.770536) (xy 241.646202 -50.483262) (xy 241.614706 -50.514758)
			(xy 241.541046 -50.714148) (xy 241.702844 -50.875692)
		)
		(stroke
			(width 0)
			(type solid)
		)
		(fill yes)
		(layer "In2.Cu")
		(net "M_A_DQ<26>")
	)
	(gr_poly
		(pts
			(xy 241.951002 -51.937158) (xy 241.982498 -51.905916) (xy 241.69497 -51.618388) (xy 241.663728 -51.649884)
			(xy 241.590068 -51.849274) (xy 241.751612 -52.010818)
		)
		(stroke
			(width 0)
			(type solid)
		)
		(fill yes)
		(layer "In2.Cu")
		(net "M_A_DQ<30>")
	)
	(gr_poly
		(pts
			(xy 242.080034 -96.00057) (xy 242.035584 -96.00057) (xy 241.865404 -96.08947) (xy 241.865404 -96.31045)
			(xy 242.035584 -96.39935) (xy 242.080034 -96.39935)
		)
		(stroke
			(width 0)
			(type solid)
		)
		(fill yes)
		(layer "In2.Cu")
		(net "M_D_DQ<30>")
	)
	(gr_poly
		(pts
			(xy 242.099846 -50.60442) (xy 242.173506 -50.40503) (xy 242.011708 -50.243486) (xy 241.812318 -50.317146)
			(xy 241.781076 -50.348642) (xy 242.06835 -50.635916)
		)
		(stroke
			(width 0)
			(type solid)
		)
		(fill yes)
		(layer "In2.Cu")
		(net "M_A_DQ<27>")
	)
	(gr_poly
		(pts
			(xy 242.12423 -55.73522) (xy 242.116102 -55.54345) (xy 242.094004 -55.504842) (xy 241.74831 -55.704232)
			(xy 241.770916 -55.742586) (xy 241.932714 -55.845456)
		)
		(stroke
			(width 0)
			(type solid)
		)
		(fill yes)
		(layer "In2.Cu")
		(net "M_A_DQS_DP<3>")
	)
	(gr_poly
		(pts
			(xy 242.125754 -100.310696) (xy 242.117626 -100.118926) (xy 242.095528 -100.080318) (xy 241.750088 -100.279962)
			(xy 241.77244 -100.318316) (xy 241.934492 -100.421186)
		)
		(stroke
			(width 0)
			(type solid)
		)
		(fill yes)
		(layer "In2.Cu")
		(net "M_D_DQ<27>")
	)
	(gr_poly
		(pts
			(xy 242.148614 -51.739546) (xy 242.222274 -51.54041) (xy 242.060476 -51.378612) (xy 241.86134 -51.452272)
			(xy 241.829844 -51.483768) (xy 242.117118 -51.771042)
		)
		(stroke
			(width 0)
			(type solid)
		)
		(fill yes)
		(layer "In2.Cu")
		(net "M_A_DQ<31>")
	)
	(gr_poly
		(pts
			(xy 242.257326 -55.289704) (xy 242.427252 -55.200804) (xy 242.427506 -54.980078) (xy 242.257326 -54.891178)
			(xy 242.212876 -54.890924) (xy 242.212622 -55.289958)
		)
		(stroke
			(width 0)
			(type solid)
		)
		(fill yes)
		(layer "In2.Cu")
		(net "M_A_DQS_DP<3>")
	)
	(gr_poly
		(pts
			(xy 242.257326 -53.321712) (xy 242.427252 -53.232812) (xy 242.427252 -53.012086) (xy 242.257072 -52.923186)
			(xy 242.212622 -52.922932) (xy 242.212876 -53.321966)
		)
		(stroke
			(width 0)
			(type solid)
		)
		(fill yes)
		(layer "In2.Cu")
		(net "M_A_DQS_DP<3>")
	)
	(gr_poly
		(pts
			(xy 242.277138 -99.165156) (xy 242.219734 -98.982022) (xy 242.188238 -98.950526) (xy 241.906298 -99.232466)
			(xy 241.937794 -99.263962) (xy 242.120928 -99.321366)
		)
		(stroke
			(width 0)
			(type solid)
		)
		(fill yes)
		(layer "In2.Cu")
		(net "M_D_DQ<31>")
	)
	(gr_poly
		(pts
			(xy 242.348258 -99.561142) (xy 242.325906 -99.522788) (xy 242.163854 -99.419918) (xy 241.972592 -99.530408)
			(xy 241.98072 -99.722178) (xy 242.002818 -99.760786)
		)
		(stroke
			(width 0)
			(type solid)
		)
		(fill yes)
		(layer "In2.Cu")
		(net "M_D_DQ<26>")
	)
	(gr_poly
		(pts
			(xy 242.427506 -96.816926) (xy 242.427506 -96.595946) (xy 242.257326 -96.507046) (xy 242.212876 -96.507046)
			(xy 242.212876 -96.905826) (xy 242.257326 -96.905826)
		)
		(stroke
			(width 0)
			(type solid)
		)
		(fill yes)
		(layer "In2.Cu")
		(net "M_D_DQ<30>")
	)
	(gr_poly
		(pts
			(xy 242.427506 -54.221126) (xy 242.427506 -54.000146) (xy 242.257326 -53.911246) (xy 242.212876 -53.911246)
			(xy 242.212876 -54.310026) (xy 242.257326 -54.310026)
		)
		(stroke
			(width 0)
			(type solid)
		)
		(fill yes)
		(layer "In2.Cu")
		(net "M_A_DQS_DP<3>")
	)
	(gr_poly
		(pts
			(xy 242.51031 -98.300794) (xy 242.603782 -98.100642) (xy 242.486942 -97.948242) (xy 242.44681 -97.929446)
			(xy 242.278154 -98.290634) (xy 242.31854 -98.30943)
		)
		(stroke
			(width 0)
			(type solid)
		)
		(fill yes)
		(layer "In2.Cu")
		(net "M_D_DQ<31>")
	)
	(gr_poly
		(pts
			(xy 242.586002 -52.572158) (xy 242.617498 -52.540916) (xy 242.32997 -52.253388) (xy 242.298728 -52.284884)
			(xy 242.225068 -52.484274) (xy 242.386612 -52.645818)
		)
		(stroke
			(width 0)
			(type solid)
		)
		(fill yes)
		(layer "In2.Cu")
		(net "M_A_DQ<30>")
	)
	(gr_poly
		(pts
			(xy 242.602512 -51.502564) (xy 242.634008 -51.471068) (xy 242.346734 -51.183794) (xy 242.315238 -51.21529)
			(xy 242.241578 -51.414426) (xy 242.403376 -51.576224)
		)
		(stroke
			(width 0)
			(type solid)
		)
		(fill yes)
		(layer "In2.Cu")
		(net "M_A_DQ<26>")
	)
	(gr_poly
		(pts
			(xy 242.747546 -98.49104) (xy 242.703096 -98.49104) (xy 242.532916 -98.57994) (xy 242.532916 -98.80092)
			(xy 242.703096 -98.88982) (xy 242.747546 -98.88982)
		)
		(stroke
			(width 0)
			(type solid)
		)
		(fill yes)
		(layer "In2.Cu")
		(net "M_D_DQ<26>")
	)
	(gr_poly
		(pts
			(xy 242.754912 -96.500188) (xy 242.710462 -96.500442) (xy 242.540282 -96.589342) (xy 242.540282 -96.810068)
			(xy 242.710462 -96.898968) (xy 242.754658 -96.898968)
		)
		(stroke
			(width 0)
			(type solid)
		)
		(fill yes)
		(layer "In2.Cu")
		(net "M_D_DQ<26>")
	)
	(gr_poly
		(pts
			(xy 242.783614 -52.374546) (xy 242.857274 -52.17541) (xy 242.695476 -52.013612) (xy 242.49634 -52.087272)
			(xy 242.464844 -52.118768) (xy 242.752118 -52.406042)
		)
		(stroke
			(width 0)
			(type solid)
		)
		(fill yes)
		(layer "In2.Cu")
		(net "M_A_DQ<31>")
	)
	(gr_poly
		(pts
			(xy 242.800124 -51.304952) (xy 242.873784 -51.105562) (xy 242.71224 -50.944018) (xy 242.51285 -51.017678)
			(xy 242.481354 -51.04892) (xy 242.768882 -51.336448)
		)
		(stroke
			(width 0)
			(type solid)
		)
		(fill yes)
		(layer "In2.Cu")
		(net "M_A_DQ<27>")
	)
	(gr_poly
		(pts
			(xy 242.880642 -52.95646) (xy 242.836192 -52.95646) (xy 242.643152 -53.045106) (xy 242.642898 -53.273706)
			(xy 242.835938 -53.36286) (xy 242.880388 -53.36286)
		)
		(stroke
			(width 0)
			(type solid)
		)
		(fill yes)
		(layer "In2.Cu")
		(net "M_A_DQ<30>")
	)
	(gr_poly
		(pts
			(xy 243.057172 -50.340768) (xy 243.088668 -50.309272) (xy 242.801394 -50.021998) (xy 242.769898 -50.05324)
			(xy 242.696238 -50.25263) (xy 242.857782 -50.414428)
		)
		(stroke
			(width 0)
			(type solid)
		)
		(fill yes)
		(layer "In2.Cu")
		(net "M_A_ECC<4>")
	)
	(gr_poly
		(pts
			(xy 243.206016 -96.089216) (xy 243.180616 -96.052894) (xy 243.010182 -95.964502) (xy 242.82908 -96.090994)
			(xy 242.853972 -96.281494) (xy 242.879372 -96.317816)
		)
		(stroke
			(width 0)
			(type solid)
		)
		(fill yes)
		(layer "In2.Cu")
		(net "M_D_DQ<26>")
	)
	(gr_poly
		(pts
			(xy 243.237512 -99.476052) (xy 243.134642 -99.314) (xy 243.096288 -99.291648) (xy 242.896644 -99.637088)
			(xy 242.935252 -99.659186) (xy 243.127022 -99.667314)
		)
		(stroke
			(width 0)
			(type solid)
		)
		(fill yes)
		(layer "In2.Cu")
		(net "M_D_DQ<27>")
	)
	(gr_poly
		(pts
			(xy 243.256054 -50.141886) (xy 243.329714 -49.942496) (xy 243.167916 -49.780952) (xy 242.968526 -49.854612)
			(xy 242.937284 -49.886108) (xy 243.224558 -50.173382)
		)
		(stroke
			(width 0)
			(type solid)
		)
		(fill yes)
		(layer "In2.Cu")
		(net "M_A_ECC<5>")
	)
	(gr_poly
		(pts
			(xy 243.285772 -54.71033) (xy 243.285772 -54.48935) (xy 243.115592 -54.40045) (xy 243.071142 -54.40045)
			(xy 243.071142 -54.79923) (xy 243.115592 -54.79923)
		)
		(stroke
			(width 0)
			(type solid)
		)
		(fill yes)
		(layer "In2.Cu")
		(net "M_A_DQ<31>")
	)
	(gr_poly
		(pts
			(xy 243.286026 -98.287586) (xy 243.286026 -98.066606) (xy 243.115846 -97.977706) (xy 243.071396 -97.977706)
			(xy 243.071396 -98.376486) (xy 243.115846 -98.376486)
		)
		(stroke
			(width 0)
			(type solid)
		)
		(fill yes)
		(layer "In2.Cu")
		(net "M_D_DQ<27>")
	)
	(gr_poly
		(pts
			(xy 243.286026 -97.296986) (xy 243.286026 -97.076006) (xy 243.115846 -96.987106) (xy 243.071396 -96.987106)
			(xy 243.071396 -97.385886) (xy 243.115846 -97.385886)
		)
		(stroke
			(width 0)
			(type solid)
		)
		(fill yes)
		(layer "In2.Cu")
		(net "M_D_DQ<27>")
	)
	(gr_poly
		(pts
			(xy 243.303044 -52.203096) (xy 243.33454 -52.1716) (xy 243.047266 -51.884326) (xy 243.01577 -51.915568)
			(xy 242.94211 -52.114958) (xy 243.103654 -52.276756)
		)
		(stroke
			(width 0)
			(type solid)
		)
		(fill yes)
		(layer "In2.Cu")
		(net "M_A_DQ<26>")
	)
	(gr_poly
		(pts
			(xy 243.308632 -53.27396) (xy 243.308886 -53.04536) (xy 243.115846 -52.95646) (xy 243.071396 -52.95646)
			(xy 243.071142 -53.36286) (xy 243.115592 -53.36286)
		)
		(stroke
			(width 0)
			(type solid)
		)
		(fill yes)
		(layer "In2.Cu")
		(net "M_A_DQ<31>")
	)
	(gr_poly
		(pts
			(xy 243.500656 -52.005484) (xy 243.574316 -51.806094) (xy 243.412772 -51.644296) (xy 243.213382 -51.717956)
			(xy 243.181886 -51.749452) (xy 243.46916 -52.036726)
		)
		(stroke
			(width 0)
			(type solid)
		)
		(fill yes)
		(layer "In2.Cu")
		(net "M_A_DQ<27>")
	)
	(gr_poly
		(pts
			(xy 243.605812 -52.623466) (xy 243.561362 -52.623466) (xy 243.368322 -52.712366) (xy 243.368322 -52.940966)
			(xy 243.561362 -53.029866) (xy 243.605812 -53.029866)
		)
		(stroke
			(width 0)
			(type solid)
		)
		(fill yes)
		(layer "In2.Cu")
		(net "M_A_DQ<26>")
	)
	(gr_poly
		(pts
			(xy 243.619528 -100.375974) (xy 243.574824 -100.375974) (xy 243.382038 -100.46462) (xy 243.382038 -100.693474)
			(xy 243.574824 -100.78212) (xy 243.619528 -100.78212)
		)
		(stroke
			(width 0)
			(type solid)
		)
		(fill yes)
		(layer "In2.Cu")
		(net "M_D_ECC<4>")
	)
	(gr_poly
		(pts
			(xy 243.854732 -100.78212) (xy 244.047772 -100.69322) (xy 244.047772 -100.464874) (xy 243.854732 -100.375974)
			(xy 243.810282 -100.37572) (xy 243.810282 -100.782374)
		)
		(stroke
			(width 0)
			(type solid)
		)
		(fill yes)
		(layer "In2.Cu")
		(net "M_D_ECC<5>")
	)
	(gr_poly
		(pts
			(xy 243.956332 -50.842418) (xy 244.029992 -50.643028) (xy 243.868448 -50.481484) (xy 243.669058 -50.555144)
			(xy 243.637562 -50.586386) (xy 243.92509 -50.873914)
		)
		(stroke
			(width 0)
			(type solid)
		)
		(fill yes)
		(layer "In2.Cu")
		(net "M_A_ECC<5>")
	)
	(gr_poly
		(pts
			(xy 244.033802 -52.940966) (xy 244.033802 -52.712366) (xy 243.840762 -52.623466) (xy 243.796312 -52.623466)
			(xy 243.796312 -53.029866) (xy 243.840762 -53.029866)
		)
		(stroke
			(width 0)
			(type solid)
		)
		(fill yes)
		(layer "In2.Cu")
		(net "M_A_DQ<27>")
	)
	(gr_poly
		(pts
			(xy 244.062504 -51.345846) (xy 244.094 -51.314604) (xy 243.806472 -51.027076) (xy 243.77523 -51.058572)
			(xy 243.70157 -51.257962) (xy 243.863114 -51.419506)
		)
		(stroke
			(width 0)
			(type solid)
		)
		(fill yes)
		(layer "In2.Cu")
		(net "M_A_ECC<4>")
	)
	(gr_poly
		(pts
			(xy 244.072664 -51.821334) (xy 244.028214 -51.821334) (xy 243.835174 -51.910234) (xy 243.835174 -52.138834)
			(xy 244.028214 -52.227734) (xy 244.072664 -52.227734)
		)
		(stroke
			(width 0)
			(type solid)
		)
		(fill yes)
		(layer "In2.Cu")
		(net "M_A_ECC<4>")
	)
	(gr_poly
		(pts
			(xy 244.144292 -54.220872) (xy 244.144292 -53.999892) (xy 243.974112 -53.910992) (xy 243.929662 -53.910992)
			(xy 243.929662 -54.309772) (xy 243.974112 -54.309772)
		)
		(stroke
			(width 0)
			(type solid)
		)
		(fill yes)
		(layer "In2.Cu")
		(net "M_A_DQ<27>")
	)
	(gr_poly
		(pts
			(xy 244.277642 -99.459796) (xy 244.246146 -99.4283) (xy 244.04701 -99.35464) (xy 243.885212 -99.516438)
			(xy 243.958872 -99.715574) (xy 243.990368 -99.74707)
		)
		(stroke
			(width 0)
			(type solid)
		)
		(fill yes)
		(layer "In2.Cu")
		(net "M_D_ECC<4>")
	)
	(gr_poly
		(pts
			(xy 244.3607 -50.546762) (xy 244.392196 -50.515266) (xy 244.104922 -50.227992) (xy 244.073426 -50.259234)
			(xy 243.999766 -50.458624) (xy 244.16131 -50.620422)
		)
		(stroke
			(width 0)
			(type solid)
		)
		(fill yes)
		(layer "In2.Cu")
		(net "M_A_ECC<0>")
	)
	(gr_poly
		(pts
			(xy 244.395498 -52.680616) (xy 244.351048 -52.680616) (xy 244.158008 -52.769516) (xy 244.158008 -52.998116)
			(xy 244.351048 -53.087016) (xy 244.395498 -53.087016)
		)
		(stroke
			(width 0)
			(type solid)
		)
		(fill yes)
		(layer "In2.Cu")
		(net "M_A_ECC<4>")
	)
	(gr_poly
		(pts
			(xy 244.464586 -57.8612) (xy 244.420136 -57.8612) (xy 244.249956 -57.9501) (xy 244.249956 -58.17108)
			(xy 244.420136 -58.25998) (xy 244.464586 -58.25998)
		)
		(stroke
			(width 0)
			(type solid)
		)
		(fill yes)
		(layer "In2.Cu")
		(net "M_A_ECC<4>")
	)
	(gr_poly
		(pts
			(xy 244.464586 -56.883046) (xy 244.420136 -56.883046) (xy 244.249956 -56.971946) (xy 244.249956 -57.192926)
			(xy 244.420136 -57.281826) (xy 244.464586 -57.281826)
		)
		(stroke
			(width 0)
			(type solid)
		)
		(fill yes)
		(layer "In2.Cu")
		(net "M_A_ECC<4>")
	)
	(gr_poly
		(pts
			(xy 244.464586 -55.892446) (xy 244.420136 -55.892446) (xy 244.249956 -55.981346) (xy 244.249956 -56.202326)
			(xy 244.420136 -56.291226) (xy 244.464586 -56.291226)
		)
		(stroke
			(width 0)
			(type solid)
		)
		(fill yes)
		(layer "In2.Cu")
		(net "M_A_ECC<4>")
	)
	(gr_poly
		(pts
			(xy 244.464586 -54.901846) (xy 244.420136 -54.901846) (xy 244.249956 -54.990746) (xy 244.249956 -55.211726)
			(xy 244.420136 -55.300626) (xy 244.464586 -55.300626)
		)
		(stroke
			(width 0)
			(type solid)
		)
		(fill yes)
		(layer "In2.Cu")
		(net "M_A_ECC<4>")
	)
	(gr_poly
		(pts
			(xy 244.464586 -53.911246) (xy 244.420136 -53.911246) (xy 244.249956 -54.000146) (xy 244.249956 -54.221126)
			(xy 244.420136 -54.310026) (xy 244.464586 -54.310026)
		)
		(stroke
			(width 0)
			(type solid)
		)
		(fill yes)
		(layer "In2.Cu")
		(net "M_A_ECC<4>")
	)
	(gr_poly
		(pts
			(xy 244.46484 -58.846974) (xy 244.42039 -58.846974) (xy 244.25021 -58.935874) (xy 244.25021 -59.156854)
			(xy 244.42039 -59.245754) (xy 244.464586 -59.245754)
		)
		(stroke
			(width 0)
			(type solid)
		)
		(fill yes)
		(layer "In2.Cu")
		(net "M_A_ECC<4>")
	)
	(gr_poly
		(pts
			(xy 244.517672 -99.825556) (xy 244.444012 -99.626166) (xy 244.41277 -99.59467) (xy 244.125242 -99.882198)
			(xy 244.156738 -99.91344) (xy 244.356128 -99.9871)
		)
		(stroke
			(width 0)
			(type solid)
		)
		(fill yes)
		(layer "In2.Cu")
		(net "M_D_ECC<5>")
	)
	(gr_poly
		(pts
			(xy 244.558058 -50.349404) (xy 244.631718 -50.150014) (xy 244.46992 -49.98847) (xy 244.27053 -50.06213)
			(xy 244.239288 -50.093626) (xy 244.526562 -50.3809)
		)
		(stroke
			(width 0)
			(type solid)
		)
		(fill yes)
		(layer "In2.Cu")
		(net "M_A_ECC<1>")
	)
	(gr_poly
		(pts
			(xy 244.65661 -51.54295) (xy 244.73027 -51.34356) (xy 244.568726 -51.182016) (xy 244.369336 -51.255676)
			(xy 244.33784 -51.286918) (xy 244.625368 -51.574446)
		)
		(stroke
			(width 0)
			(type solid)
		)
		(fill yes)
		(layer "In2.Cu")
		(net "M_A_ECC<5>")
	)
	(gr_poly
		(pts
			(xy 244.780308 -100.759514) (xy 244.735858 -100.759514) (xy 244.542818 -100.848414) (xy 244.542818 -101.077014)
			(xy 244.735858 -101.165914) (xy 244.780308 -101.165914)
		)
		(stroke
			(width 0)
			(type solid)
		)
		(fill yes)
		(layer "In2.Cu")
		(net "M_D_ECC<0>")
	)
	(gr_poly
		(pts
			(xy 244.901212 -59.701684) (xy 244.92331 -59.66333) (xy 244.578124 -59.463686) (xy 244.556026 -59.502294)
			(xy 244.547898 -59.694064) (xy 244.73916 -59.804554)
		)
		(stroke
			(width 0)
			(type solid)
		)
		(fill yes)
		(layer "In2.Cu")
		(net "M_A_ECC<4>")
	)
	(gr_poly
		(pts
			(xy 245.002812 -58.678826) (xy 245.002812 -58.457846) (xy 244.832632 -58.368946) (xy 244.788182 -58.368946)
			(xy 244.788182 -58.767726) (xy 244.832632 -58.767726)
		)
		(stroke
			(width 0)
			(type solid)
		)
		(fill yes)
		(layer "In2.Cu")
		(net "M_A_ECC<5>")
	)
	(gr_poly
		(pts
			(xy 245.002812 -57.68213) (xy 245.002812 -57.46115) (xy 244.832632 -57.37225) (xy 244.788182 -57.37225)
			(xy 244.788182 -57.77103) (xy 244.832632 -57.77103)
		)
		(stroke
			(width 0)
			(type solid)
		)
		(fill yes)
		(layer "In2.Cu")
		(net "M_A_ECC<5>")
	)
	(gr_poly
		(pts
			(xy 245.002812 -56.68518) (xy 245.002812 -56.4642) (xy 244.832632 -56.3753) (xy 244.788182 -56.3753)
			(xy 244.788182 -56.77408) (xy 244.832632 -56.77408)
		)
		(stroke
			(width 0)
			(type solid)
		)
		(fill yes)
		(layer "In2.Cu")
		(net "M_A_ECC<5>")
	)
	(gr_poly
		(pts
			(xy 245.002812 -55.69458) (xy 245.002812 -55.4736) (xy 244.832632 -55.3847) (xy 244.788182 -55.3847)
			(xy 244.788182 -55.78348) (xy 244.832632 -55.78348)
		)
		(stroke
			(width 0)
			(type solid)
		)
		(fill yes)
		(layer "In2.Cu")
		(net "M_A_ECC<5>")
	)
	(gr_poly
		(pts
			(xy 245.002812 -54.70398) (xy 245.002812 -54.483) (xy 244.832632 -54.3941) (xy 244.788182 -54.3941)
			(xy 244.788182 -54.79288) (xy 244.832632 -54.79288)
		)
		(stroke
			(width 0)
			(type solid)
		)
		(fill yes)
		(layer "In2.Cu")
		(net "M_A_ECC<5>")
	)
	(gr_poly
		(pts
			(xy 245.002812 -53.71338) (xy 245.002812 -53.4924) (xy 244.832632 -53.4035) (xy 244.788182 -53.4035)
			(xy 244.788182 -53.80228) (xy 244.832632 -53.80228)
		)
		(stroke
			(width 0)
			(type solid)
		)
		(fill yes)
		(layer "In2.Cu")
		(net "M_A_ECC<5>")
	)
	(gr_poly
		(pts
			(xy 245.061232 -51.24704) (xy 245.092728 -51.215798) (xy 244.8052 -50.92827) (xy 244.773958 -50.959766)
			(xy 244.700298 -51.159156) (xy 244.861842 -51.3207)
		)
		(stroke
			(width 0)
			(type solid)
		)
		(fill yes)
		(layer "In2.Cu")
		(net "M_A_ECC<0>")
	)
	(gr_poly
		(pts
			(xy 245.120414 -52.215034) (xy 245.120414 -51.986434) (xy 244.927374 -51.897534) (xy 244.882924 -51.897534)
			(xy 244.882924 -52.303934) (xy 244.927374 -52.303934)
		)
		(stroke
			(width 0)
			(type solid)
		)
		(fill yes)
		(layer "In2.Cu")
		(net "M_A_ECC<5>")
	)
	(gr_poly
		(pts
			(xy 245.20779 -101.077014) (xy 245.20779 -100.848414) (xy 245.01475 -100.759514) (xy 244.9703 -100.759514)
			(xy 244.9703 -101.165914) (xy 245.01475 -101.165914)
		)
		(stroke
			(width 0)
			(type solid)
		)
		(fill yes)
		(layer "In2.Cu")
		(net "M_D_ECC<1>")
	)
	(gr_poly
		(pts
			(xy 245.258336 -51.049936) (xy 245.331996 -50.850546) (xy 245.170452 -50.689002) (xy 244.971062 -50.762662)
			(xy 244.939566 -50.793904) (xy 245.227094 -51.081432)
		)
		(stroke
			(width 0)
			(type solid)
		)
		(fill yes)
		(layer "In2.Cu")
		(net "M_A_ECC<1>")
	)
	(gr_poly
		(pts
			(xy 245.323106 -97.9805) (xy 245.278656 -97.9805) (xy 245.108476 -98.0694) (xy 245.108476 -98.29038)
			(xy 245.278656 -98.37928) (xy 245.323106 -98.37928)
		)
		(stroke
			(width 0)
			(type solid)
		)
		(fill yes)
		(layer "In2.Cu")
		(net "M_D_ECC<4>")
	)
	(gr_poly
		(pts
			(xy 245.323106 -96.9899) (xy 245.278656 -96.9899) (xy 245.108476 -97.0788) (xy 245.108476 -97.29978)
			(xy 245.278656 -97.38868) (xy 245.323106 -97.38868)
		)
		(stroke
			(width 0)
			(type solid)
		)
		(fill yes)
		(layer "In2.Cu")
		(net "M_D_ECC<4>")
	)
	(gr_poly
		(pts
			(xy 245.323106 -95.9993) (xy 245.278656 -95.9993) (xy 245.108476 -96.0882) (xy 245.108476 -96.30918)
			(xy 245.278656 -96.39808) (xy 245.323106 -96.39808)
		)
		(stroke
			(width 0)
			(type solid)
		)
		(fill yes)
		(layer "In2.Cu")
		(net "M_D_ECC<4>")
	)
	(gr_poly
		(pts
			(xy 245.323106 -95.0087) (xy 245.278656 -95.0087) (xy 245.108476 -95.0976) (xy 245.108476 -95.31858)
			(xy 245.278656 -95.40748) (xy 245.323106 -95.40748)
		)
		(stroke
			(width 0)
			(type solid)
		)
		(fill yes)
		(layer "In2.Cu")
		(net "M_D_ECC<4>")
	)
	(gr_poly
		(pts
			(xy 245.323106 -94.030546) (xy 245.278656 -94.030546) (xy 245.108476 -94.119446) (xy 245.108476 -94.340426)
			(xy 245.278656 -94.429326) (xy 245.323106 -94.429326)
		)
		(stroke
			(width 0)
			(type solid)
		)
		(fill yes)
		(layer "In2.Cu")
		(net "M_D_ECC<4>")
	)
	(gr_poly
		(pts
			(xy 245.323106 -93.03385) (xy 245.278656 -93.03385) (xy 245.108476 -93.12275) (xy 245.108476 -93.34373)
			(xy 245.278656 -93.43263) (xy 245.323106 -93.43263)
		)
		(stroke
			(width 0)
			(type solid)
		)
		(fill yes)
		(layer "In2.Cu")
		(net "M_D_ECC<4>")
	)
	(gr_poly
		(pts
			(xy 245.323106 -92.047568) (xy 245.278656 -92.047822) (xy 245.10873 -92.136722) (xy 245.108476 -92.357448)
			(xy 245.278656 -92.446348) (xy 245.32336 -92.446602)
		)
		(stroke
			(width 0)
			(type solid)
		)
		(fill yes)
		(layer "In2.Cu")
		(net "M_D_ECC<4>")
	)
	(gr_poly
		(pts
			(xy 245.323106 -58.362342) (xy 245.278656 -58.362596) (xy 245.10873 -58.451496) (xy 245.10873 -58.672476)
			(xy 245.27891 -58.761122) (xy 245.32336 -58.761376)
		)
		(stroke
			(width 0)
			(type solid)
		)
		(fill yes)
		(layer "In2.Cu")
		(net "M_A_ECC<0>")
	)
	(gr_poly
		(pts
			(xy 245.323106 -57.37225) (xy 245.278656 -57.37225) (xy 245.108476 -57.46115) (xy 245.108476 -57.68213)
			(xy 245.278656 -57.77103) (xy 245.323106 -57.77103)
		)
		(stroke
			(width 0)
			(type solid)
		)
		(fill yes)
		(layer "In2.Cu")
		(net "M_A_ECC<0>")
	)
	(gr_poly
		(pts
			(xy 245.323106 -56.3753) (xy 245.278656 -56.3753) (xy 245.108476 -56.4642) (xy 245.108476 -56.68518)
			(xy 245.278656 -56.77408) (xy 245.323106 -56.77408)
		)
		(stroke
			(width 0)
			(type solid)
		)
		(fill yes)
		(layer "In2.Cu")
		(net "M_A_ECC<0>")
	)
	(gr_poly
		(pts
			(xy 245.32336 -55.39105) (xy 245.27891 -55.39105) (xy 245.10873 -55.47995) (xy 245.10873 -55.70093)
			(xy 245.27891 -55.78983) (xy 245.32336 -55.78983)
		)
		(stroke
			(width 0)
			(type solid)
		)
		(fill yes)
		(layer "In2.Cu")
		(net "M_A_ECC<0>")
	)
	(gr_poly
		(pts
			(xy 245.486174 -54.381146) (xy 245.441724 -54.381146) (xy 245.248684 -54.470046) (xy 245.248684 -54.698646)
			(xy 245.441724 -54.787546) (xy 245.486174 -54.787546)
		)
		(stroke
			(width 0)
			(type solid)
		)
		(fill yes)
		(layer "In2.Cu")
		(net "M_A_ECC<0>")
	)
	(gr_poly
		(pts
			(xy 245.486174 -53.390546) (xy 245.441724 -53.390546) (xy 245.248684 -53.479446) (xy 245.248684 -53.708046)
			(xy 245.441724 -53.796946) (xy 245.486174 -53.796946)
		)
		(stroke
			(width 0)
			(type solid)
		)
		(fill yes)
		(layer "In2.Cu")
		(net "M_A_ECC<0>")
	)
	(gr_poly
		(pts
			(xy 245.496588 -50.097944) (xy 245.52783 -50.066448) (xy 245.240556 -49.779174) (xy 245.20906 -49.81067)
			(xy 245.1354 -50.01006) (xy 245.297198 -50.171604)
		)
		(stroke
			(width 0)
			(type solid)
		)
		(fill yes)
		(layer "In2.Cu")
		(net "M_A_DQS_DP<17>")
	)
	(gr_poly
		(pts
			(xy 245.552468 -100.381562) (xy 245.478808 -100.182172) (xy 245.447566 -100.150676) (xy 245.160038 -100.438204)
			(xy 245.191534 -100.469446) (xy 245.390924 -100.543106)
		)
		(stroke
			(width 0)
			(type solid)
		)
		(fill yes)
		(layer "In2.Cu")
		(net "M_D_ECC<1>")
	)
	(gr_poly
		(pts
			(xy 245.553738 -59.602116) (xy 245.561866 -59.410346) (xy 245.370604 -59.299856) (xy 245.208552 -59.402726)
			(xy 245.1862 -59.441334) (xy 245.53164 -59.640724)
		)
		(stroke
			(width 0)
			(type solid)
		)
		(fill yes)
		(layer "In2.Cu")
		(net "M_A_ECC<5>")
	)
	(gr_poly
		(pts
			(xy 245.556532 -99.322382) (xy 245.548404 -99.130612) (xy 245.52656 -99.092258) (xy 245.180866 -99.291394)
			(xy 245.203218 -99.330002) (xy 245.36527 -99.432872)
		)
		(stroke
			(width 0)
			(type solid)
		)
		(fill yes)
		(layer "In2.Cu")
		(net "M_D_ECC<5>")
	)
	(gr_poly
		(pts
			(xy 245.604284 -52.008024) (xy 245.559834 -52.008024) (xy 245.366794 -52.096924) (xy 245.366794 -52.325524)
			(xy 245.559834 -52.414424) (xy 245.604284 -52.414424)
		)
		(stroke
			(width 0)
			(type solid)
		)
		(fill yes)
		(layer "In2.Cu")
		(net "M_A_ECC<0>")
	)
	(gr_poly
		(pts
			(xy 245.761256 -60.198) (xy 245.783608 -60.159646) (xy 245.438168 -59.960002) (xy 245.41607 -59.99861)
			(xy 245.407942 -60.19038) (xy 245.599204 -60.30087)
		)
		(stroke
			(width 0)
			(type solid)
		)
		(fill yes)
		(layer "In2.Cu")
		(net "M_A_ECC<4>")
	)
	(gr_poly
		(pts
			(xy 245.76913 -59.211718) (xy 245.791482 -59.173364) (xy 245.445788 -58.973974) (xy 245.42369 -59.012582)
			(xy 245.415816 -59.204352) (xy 245.607078 -59.314842)
		)
		(stroke
			(width 0)
			(type solid)
		)
		(fill yes)
		(layer "In2.Cu")
		(net "M_A_ECC<0>")
	)
	(gr_poly
		(pts
			(xy 245.783608 -99.56038) (xy 245.761256 -99.522026) (xy 245.599204 -99.419156) (xy 245.407942 -99.529646)
			(xy 245.41607 -99.721416) (xy 245.438168 -99.75977)
		)
		(stroke
			(width 0)
			(type solid)
		)
		(fill yes)
		(layer "In2.Cu")
		(net "M_D_ECC<0>")
	)
	(gr_poly
		(pts
			(xy 245.787672 -91.633294) (xy 245.765066 -91.59494) (xy 245.603268 -91.49207) (xy 245.411752 -91.602306)
			(xy 245.41988 -91.794076) (xy 245.442232 -91.832938)
		)
		(stroke
			(width 0)
			(type solid)
		)
		(fill yes)
		(layer "In2.Cu")
		(net "M_D_ECC<4>")
	)
	(gr_poly
		(pts
			(xy 245.861332 -98.788982) (xy 245.861332 -98.568002) (xy 245.691152 -98.479102) (xy 245.646956 -98.478848)
			(xy 245.646702 -98.877882) (xy 245.691152 -98.877882)
		)
		(stroke
			(width 0)
			(type solid)
		)
		(fill yes)
		(layer "In2.Cu")
		(net "M_D_ECC<5>")
	)
	(gr_poly
		(pts
			(xy 245.861332 -97.807526) (xy 245.861332 -97.586546) (xy 245.691152 -97.497646) (xy 245.646702 -97.497646)
			(xy 245.646702 -97.896426) (xy 245.691152 -97.896426)
		)
		(stroke
			(width 0)
			(type solid)
		)
		(fill yes)
		(layer "In2.Cu")
		(net "M_D_ECC<5>")
	)
	(gr_poly
		(pts
			(xy 245.861332 -96.816926) (xy 245.861332 -96.595946) (xy 245.691152 -96.507046) (xy 245.646702 -96.507046)
			(xy 245.646702 -96.905826) (xy 245.691152 -96.905826)
		)
		(stroke
			(width 0)
			(type solid)
		)
		(fill yes)
		(layer "In2.Cu")
		(net "M_D_ECC<5>")
	)
	(gr_poly
		(pts
			(xy 245.861332 -95.826326) (xy 245.861332 -95.605346) (xy 245.691152 -95.516446) (xy 245.646702 -95.516446)
			(xy 245.646702 -95.915226) (xy 245.691152 -95.915226)
		)
		(stroke
			(width 0)
			(type solid)
		)
		(fill yes)
		(layer "In2.Cu")
		(net "M_D_ECC<5>")
	)
	(gr_poly
		(pts
			(xy 245.861332 -94.829376) (xy 245.861332 -94.608396) (xy 245.691152 -94.519496) (xy 245.646702 -94.519496)
			(xy 245.646702 -94.918276) (xy 245.691152 -94.918276)
		)
		(stroke
			(width 0)
			(type solid)
		)
		(fill yes)
		(layer "In2.Cu")
		(net "M_D_ECC<5>")
	)
	(gr_poly
		(pts
			(xy 245.861332 -93.83268) (xy 245.861332 -93.6117) (xy 245.691152 -93.5228) (xy 245.646702 -93.5228)
			(xy 245.646702 -93.92158) (xy 245.691152 -93.92158)
		)
		(stroke
			(width 0)
			(type solid)
		)
		(fill yes)
		(layer "In2.Cu")
		(net "M_D_ECC<5>")
	)
	(gr_poly
		(pts
			(xy 245.861332 -92.854526) (xy 245.861332 -92.633546) (xy 245.691152 -92.544646) (xy 245.646702 -92.544646)
			(xy 245.646702 -92.943426) (xy 245.691152 -92.943426)
		)
		(stroke
			(width 0)
			(type solid)
		)
		(fill yes)
		(layer "In2.Cu")
		(net "M_D_ECC<5>")
	)
	(gr_poly
		(pts
			(xy 245.861332 -58.17108) (xy 245.861332 -57.9501) (xy 245.691152 -57.8612) (xy 245.646702 -57.8612)
			(xy 245.646702 -58.25998) (xy 245.691152 -58.25998)
		)
		(stroke
			(width 0)
			(type solid)
		)
		(fill yes)
		(layer "In2.Cu")
		(net "M_A_ECC<1>")
	)
	(gr_poly
		(pts
			(xy 245.861332 -57.192926) (xy 245.861332 -56.971946) (xy 245.691152 -56.883046) (xy 245.646702 -56.883046)
			(xy 245.646702 -57.281826) (xy 245.691152 -57.281826)
		)
		(stroke
			(width 0)
			(type solid)
		)
		(fill yes)
		(layer "In2.Cu")
		(net "M_A_ECC<1>")
	)
	(gr_poly
		(pts
			(xy 245.861332 -56.202326) (xy 245.861332 -55.981346) (xy 245.691152 -55.892446) (xy 245.646702 -55.892446)
			(xy 245.646702 -56.291226) (xy 245.691152 -56.291226)
		)
		(stroke
			(width 0)
			(type solid)
		)
		(fill yes)
		(layer "In2.Cu")
		(net "M_A_ECC<1>")
	)
	(gr_poly
		(pts
			(xy 245.878604 -101.402642) (xy 245.834154 -101.402642) (xy 245.641114 -101.491542) (xy 245.641114 -101.720142)
			(xy 245.834154 -101.809042) (xy 245.878604 -101.809042)
		)
		(stroke
			(width 0)
			(type solid)
		)
		(fill yes)
		(layer "In2.Cu")
		(net "M_D_DQS_DP<17>")
	)
	(gr_poly
		(pts
			(xy 245.914164 -54.698646) (xy 245.914164 -54.470046) (xy 245.721124 -54.381146) (xy 245.676674 -54.381146)
			(xy 245.676674 -54.787546) (xy 245.721124 -54.787546)
		)
		(stroke
			(width 0)
			(type solid)
		)
		(fill yes)
		(layer "In2.Cu")
		(net "M_A_ECC<1>")
	)
	(gr_poly
		(pts
			(xy 245.914164 -53.708046) (xy 245.914164 -53.479446) (xy 245.721124 -53.390546) (xy 245.676674 -53.390546)
			(xy 245.676674 -53.796946) (xy 245.721124 -53.796946)
		)
		(stroke
			(width 0)
			(type solid)
		)
		(fill yes)
		(layer "In2.Cu")
		(net "M_A_ECC<1>")
	)
	(gr_poly
		(pts
			(xy 246.031766 -52.325524) (xy 246.031766 -52.096924) (xy 245.838726 -52.008024) (xy 245.794276 -52.008024)
			(xy 245.794276 -52.414424) (xy 245.838726 -52.414424)
		)
		(stroke
			(width 0)
			(type solid)
		)
		(fill yes)
		(layer "In2.Cu")
		(net "M_A_ECC<1>")
	)
	(gr_poly
		(pts
			(xy 246.140478 -50.346864) (xy 246.214138 -50.147474) (xy 246.052594 -49.98593) (xy 245.853204 -50.05959)
			(xy 245.821708 -50.090832) (xy 246.109236 -50.37836)
		)
		(stroke
			(width 0)
			(type solid)
		)
		(fill yes)
		(layer "In2.Cu")
		(net "M_A_DQS_DN<17>")
	)
	(gr_poly
		(pts
			(xy 246.181626 -98.488246) (xy 246.137176 -98.488246) (xy 245.966996 -98.577146) (xy 245.966996 -98.798126)
			(xy 246.137176 -98.887026) (xy 246.181626 -98.887026)
		)
		(stroke
			(width 0)
			(type solid)
		)
		(fill yes)
		(layer "In2.Cu")
		(net "M_D_ECC<0>")
	)
	(gr_poly
		(pts
			(xy 246.181626 -97.491296) (xy 246.137176 -97.491296) (xy 245.966996 -97.580196) (xy 245.966996 -97.801176)
			(xy 246.137176 -97.890076) (xy 246.181626 -97.890076)
		)
		(stroke
			(width 0)
			(type solid)
		)
		(fill yes)
		(layer "In2.Cu")
		(net "M_D_ECC<0>")
	)
	(gr_poly
		(pts
			(xy 246.181626 -96.507046) (xy 246.137176 -96.507046) (xy 245.966996 -96.595946) (xy 245.966996 -96.816926)
			(xy 246.137176 -96.905826) (xy 246.181626 -96.905826)
		)
		(stroke
			(width 0)
			(type solid)
		)
		(fill yes)
		(layer "In2.Cu")
		(net "M_D_ECC<0>")
	)
	(gr_poly
		(pts
			(xy 246.181626 -95.516446) (xy 246.137176 -95.516446) (xy 245.966996 -95.605346) (xy 245.966996 -95.826326)
			(xy 246.137176 -95.915226) (xy 246.181626 -95.915226)
		)
		(stroke
			(width 0)
			(type solid)
		)
		(fill yes)
		(layer "In2.Cu")
		(net "M_D_ECC<0>")
	)
	(gr_poly
		(pts
			(xy 246.181626 -94.519496) (xy 246.137176 -94.519496) (xy 245.966996 -94.608396) (xy 245.966996 -94.829376)
			(xy 246.137176 -94.918276) (xy 246.181626 -94.918276)
		)
		(stroke
			(width 0)
			(type solid)
		)
		(fill yes)
		(layer "In2.Cu")
		(net "M_D_ECC<0>")
	)
	(gr_poly
		(pts
			(xy 246.181626 -93.5228) (xy 246.137176 -93.5228) (xy 245.966996 -93.6117) (xy 245.966996 -93.83268)
			(xy 246.137176 -93.92158) (xy 246.181626 -93.92158)
		)
		(stroke
			(width 0)
			(type solid)
		)
		(fill yes)
		(layer "In2.Cu")
		(net "M_D_ECC<0>")
	)
	(gr_poly
		(pts
			(xy 246.181626 -92.547186) (xy 246.13743 -92.547186) (xy 245.96725 -92.636086) (xy 245.96725 -92.856812)
			(xy 246.137176 -92.945712) (xy 246.18188 -92.945966)
		)
		(stroke
			(width 0)
			(type solid)
		)
		(fill yes)
		(layer "In2.Cu")
		(net "M_D_ECC<0>")
	)
	(gr_poly
		(pts
			(xy 246.181626 -56.883046) (xy 246.137176 -56.883046) (xy 245.966996 -56.971946) (xy 245.966996 -57.192926)
			(xy 246.137176 -57.281826) (xy 246.181626 -57.281826)
		)
		(stroke
			(width 0)
			(type solid)
		)
		(fill yes)
		(layer "In2.Cu")
		(net "M_A_DQS_DP<17>")
	)
	(gr_poly
		(pts
			(xy 246.181626 -55.893462) (xy 246.137176 -55.893462) (xy 245.966996 -55.982362) (xy 245.966996 -56.203342)
			(xy 246.137176 -56.292242) (xy 246.181626 -56.292242)
		)
		(stroke
			(width 0)
			(type solid)
		)
		(fill yes)
		(layer "In2.Cu")
		(net "M_A_DQS_DP<17>")
	)
	(gr_poly
		(pts
			(xy 246.18188 -57.85866) (xy 246.13743 -57.858914) (xy 245.96725 -57.947814) (xy 245.96725 -58.16854)
			(xy 246.13743 -58.25744) (xy 246.181626 -58.25744)
		)
		(stroke
			(width 0)
			(type solid)
		)
		(fill yes)
		(layer "In2.Cu")
		(net "M_A_DQS_DP<17>")
	)
	(gr_poly
		(pts
			(xy 246.182896 -90.546428) (xy 246.138192 -90.546428) (xy 245.968012 -90.634312) (xy 245.966996 -90.855546)
			(xy 246.136922 -90.9447) (xy 246.181372 -90.944954)
		)
		(stroke
			(width 0)
			(type solid)
		)
		(fill yes)
		(layer "In2.Cu")
		(net "M_D_ECC<4>")
	)
	(gr_poly
		(pts
			(xy 246.196866 -50.798476) (xy 246.228362 -50.76698) (xy 245.941088 -50.479706) (xy 245.909592 -50.511202)
			(xy 245.835932 -50.710338) (xy 245.99773 -50.872136)
		)
		(stroke
			(width 0)
			(type solid)
		)
		(fill yes)
		(layer "In2.Cu")
		(net "M_A_DQS_DP<17>")
	)
	(gr_poly
		(pts
			(xy 246.267224 -54.827424) (xy 246.222774 -54.827424) (xy 246.029734 -54.916324) (xy 246.029734 -55.144924)
			(xy 246.222774 -55.233824) (xy 246.267224 -55.233824)
		)
		(stroke
			(width 0)
			(type solid)
		)
		(fill yes)
		(layer "In2.Cu")
		(net "M_A_DQS_DP<17>")
	)
	(gr_poly
		(pts
			(xy 246.267224 -53.836824) (xy 246.222774 -53.836824) (xy 246.029734 -53.925724) (xy 246.029734 -54.154324)
			(xy 246.222774 -54.243224) (xy 246.267224 -54.243224)
		)
		(stroke
			(width 0)
			(type solid)
		)
		(fill yes)
		(layer "In2.Cu")
		(net "M_A_DQS_DP<17>")
	)
	(gr_poly
		(pts
			(xy 246.267224 -52.846224) (xy 246.222774 -52.846224) (xy 246.029734 -52.935124) (xy 246.029734 -53.163724)
			(xy 246.222774 -53.252624) (xy 246.267224 -53.252624)
		)
		(stroke
			(width 0)
			(type solid)
		)
		(fill yes)
		(layer "In2.Cu")
		(net "M_A_DQS_DP<17>")
	)
	(gr_poly
		(pts
			(xy 246.306594 -101.720142) (xy 246.306594 -101.491542) (xy 246.113554 -101.402642) (xy 246.069104 -101.402642)
			(xy 246.069104 -101.809042) (xy 246.113554 -101.809042)
		)
		(stroke
			(width 0)
			(type solid)
		)
		(fill yes)
		(layer "In2.Cu")
		(net "M_D_DQS_DN<17>")
	)
	(gr_poly
		(pts
			(xy 246.409972 -59.105546) (xy 246.4181 -58.913776) (xy 246.226838 -58.803286) (xy 246.064786 -58.906156)
			(xy 246.042434 -58.94451) (xy 246.387874 -59.144154)
		)
		(stroke
			(width 0)
			(type solid)
		)
		(fill yes)
		(layer "In2.Cu")
		(net "M_A_ECC<1>")
	)
	(gr_poly
		(pts
			(xy 246.413782 -60.098432) (xy 246.42191 -59.906662) (xy 246.230648 -59.796172) (xy 246.068596 -59.899042)
			(xy 246.046244 -59.93765) (xy 246.391684 -60.13704)
		)
		(stroke
			(width 0)
			(type solid)
		)
		(fill yes)
		(layer "In2.Cu")
		(net "M_A_ECC<5>")
	)
	(gr_poly
		(pts
			(xy 246.420132 -91.890088) (xy 246.412004 -91.698064) (xy 246.389906 -91.659456) (xy 246.04472 -91.8591)
			(xy 246.066818 -91.897454) (xy 246.22887 -92.000324)
		)
		(stroke
			(width 0)
			(type solid)
		)
		(fill yes)
		(layer "In2.Cu")
		(net "M_D_ECC<5>")
	)
	(gr_poly
		(pts
			(xy 246.618252 -59.701684) (xy 246.640604 -59.66333) (xy 246.295164 -59.463686) (xy 246.273066 -59.502294)
			(xy 246.264938 -59.694064) (xy 246.4562 -59.804554)
		)
		(stroke
			(width 0)
			(type solid)
		)
		(fill yes)
		(layer "In2.Cu")
		(net "M_A_ECC<0>")
	)
	(gr_poly
		(pts
			(xy 246.62003 -58.712354) (xy 246.642128 -58.674) (xy 246.296942 -58.474356) (xy 246.274844 -58.513218)
			(xy 246.266716 -58.704988) (xy 246.457978 -58.815224)
		)
		(stroke
			(width 0)
			(type solid)
		)
		(fill yes)
		(layer "In2.Cu")
		(net "M_A_DQS_DP<17>")
	)
	(gr_poly
		(pts
			(xy 246.642128 -92.130626) (xy 246.62003 -92.092272) (xy 246.457978 -91.989402) (xy 246.266716 -92.099638)
			(xy 246.274844 -92.291408) (xy 246.296942 -92.33027)
		)
		(stroke
			(width 0)
			(type solid)
		)
		(fill yes)
		(layer "In2.Cu")
		(net "M_D_ECC<0>")
	)
	(gr_poly
		(pts
			(xy 246.643398 -90.136472) (xy 246.617744 -90.099896) (xy 246.447564 -90.011504) (xy 246.266462 -90.13825)
			(xy 246.291354 -90.328496) (xy 246.316754 -90.364818)
		)
		(stroke
			(width 0)
			(type solid)
		)
		(fill yes)
		(layer "In2.Cu")
		(net "M_D_ECC<4>")
	)
	(gr_poly
		(pts
			(xy 246.654574 -100.221542) (xy 246.623078 -100.1903) (xy 246.423688 -100.11664) (xy 246.262144 -100.278184)
			(xy 246.335804 -100.477574) (xy 246.367046 -100.50907)
		)
		(stroke
			(width 0)
			(type solid)
		)
		(fill yes)
		(layer "In2.Cu")
		(net "M_D_DQS_DP<17>")
	)
	(gr_poly
		(pts
			(xy 246.695214 -55.017924) (xy 246.695214 -54.789324) (xy 246.502174 -54.700424) (xy 246.457724 -54.700424)
			(xy 246.457724 -55.106824) (xy 246.502174 -55.106824)
		)
		(stroke
			(width 0)
			(type solid)
		)
		(fill yes)
		(layer "In2.Cu")
		(net "M_A_DQS_DN<17>")
	)
	(gr_poly
		(pts
			(xy 246.695214 -54.154324) (xy 246.695214 -53.925724) (xy 246.502174 -53.836824) (xy 246.457724 -53.836824)
			(xy 246.457724 -54.243224) (xy 246.502174 -54.243224)
		)
		(stroke
			(width 0)
			(type solid)
		)
		(fill yes)
		(layer "In2.Cu")
		(net "M_A_DQS_DN<17>")
	)
	(gr_poly
		(pts
			(xy 246.718582 -52.355496) (xy 246.687086 -52.324254) (xy 246.487696 -52.250594) (xy 246.326152 -52.412138)
			(xy 246.399812 -52.611528) (xy 246.431054 -52.643024)
		)
		(stroke
			(width 0)
			(type solid)
		)
		(fill yes)
		(layer "In2.Cu")
		(net "M_A_DQS_DP<17>")
	)
	(gr_poly
		(pts
			(xy 246.719598 -91.35364) (xy 246.719598 -91.132914) (xy 246.549418 -91.044014) (xy 246.504968 -91.04376)
			(xy 246.505222 -91.44254) (xy 246.549418 -91.44254)
		)
		(stroke
			(width 0)
			(type solid)
		)
		(fill yes)
		(layer "In2.Cu")
		(net "M_D_ECC<5>")
	)
	(gr_poly
		(pts
			(xy 246.719598 -57.675272) (xy 246.719598 -57.454292) (xy 246.549418 -57.365392) (xy 246.504968 -57.365392)
			(xy 246.504968 -57.764172) (xy 246.549418 -57.764172)
		)
		(stroke
			(width 0)
			(type solid)
		)
		(fill yes)
		(layer "In2.Cu")
		(net "M_A_DQS_DN<17>")
	)
	(gr_poly
		(pts
			(xy 246.719598 -56.684672) (xy 246.719598 -56.463692) (xy 246.549418 -56.374792) (xy 246.504968 -56.374792)
			(xy 246.504968 -56.773572) (xy 246.549418 -56.773572)
		)
		(stroke
			(width 0)
			(type solid)
		)
		(fill yes)
		(layer "In2.Cu")
		(net "M_A_DQS_DN<17>")
	)
	(gr_poly
		(pts
			(xy 246.719852 -99.28098) (xy 246.719852 -99.06) (xy 246.549672 -98.9711) (xy 246.505222 -98.9711)
			(xy 246.505222 -99.36988) (xy 246.549672 -99.36988)
		)
		(stroke
			(width 0)
			(type solid)
		)
		(fill yes)
		(layer "In2.Cu")
		(net "M_D_ECC<1>")
	)
	(gr_poly
		(pts
			(xy 246.719852 -98.29038) (xy 246.719852 -98.0694) (xy 246.549672 -97.9805) (xy 246.505222 -97.9805)
			(xy 246.505222 -98.37928) (xy 246.549672 -98.37928)
		)
		(stroke
			(width 0)
			(type solid)
		)
		(fill yes)
		(layer "In2.Cu")
		(net "M_D_ECC<1>")
	)
	(gr_poly
		(pts
			(xy 246.719852 -97.312226) (xy 246.719852 -97.091246) (xy 246.549672 -97.002346) (xy 246.505222 -97.002346)
			(xy 246.505222 -97.401126) (xy 246.549672 -97.401126)
		)
		(stroke
			(width 0)
			(type solid)
		)
		(fill yes)
		(layer "In2.Cu")
		(net "M_D_ECC<1>")
	)
	(gr_poly
		(pts
			(xy 246.719852 -96.30918) (xy 246.719852 -96.0882) (xy 246.549672 -95.9993) (xy 246.505222 -95.9993)
			(xy 246.505222 -96.39808) (xy 246.549672 -96.39808)
		)
		(stroke
			(width 0)
			(type solid)
		)
		(fill yes)
		(layer "In2.Cu")
		(net "M_D_ECC<1>")
	)
	(gr_poly
		(pts
			(xy 246.719852 -95.31858) (xy 246.719852 -95.0976) (xy 246.549672 -95.0087) (xy 246.505222 -95.0087)
			(xy 246.505222 -95.40748) (xy 246.549672 -95.40748)
		)
		(stroke
			(width 0)
			(type solid)
		)
		(fill yes)
		(layer "In2.Cu")
		(net "M_D_ECC<1>")
	)
	(gr_poly
		(pts
			(xy 246.719852 -94.340426) (xy 246.719852 -94.119446) (xy 246.549672 -94.030546) (xy 246.505222 -94.030546)
			(xy 246.505222 -94.429326) (xy 246.549672 -94.429326)
		)
		(stroke
			(width 0)
			(type solid)
		)
		(fill yes)
		(layer "In2.Cu")
		(net "M_D_ECC<1>")
	)
	(gr_poly
		(pts
			(xy 246.719852 -93.34373) (xy 246.719852 -93.12275) (xy 246.549672 -93.03385) (xy 246.505222 -93.03385)
			(xy 246.505222 -93.43263) (xy 246.549672 -93.43263)
		)
		(stroke
			(width 0)
			(type solid)
		)
		(fill yes)
		(layer "In2.Cu")
		(net "M_D_ECC<1>")
	)
	(gr_poly
		(pts
			(xy 246.79275 -100.688648) (xy 246.71909 -100.489512) (xy 246.687594 -100.458016) (xy 246.40032 -100.74529)
			(xy 246.431816 -100.776786) (xy 246.630952 -100.850446)
		)
		(stroke
			(width 0)
			(type solid)
		)
		(fill yes)
		(layer "In2.Cu")
		(net "M_D_DQS_DN<17>")
	)
	(gr_poly
		(pts
			(xy 246.84101 -51.047396) (xy 246.91467 -50.848006) (xy 246.753126 -50.686208) (xy 246.553736 -50.759868)
			(xy 246.52224 -50.791364) (xy 246.809514 -51.078638)
		)
		(stroke
			(width 0)
			(type solid)
		)
		(fill yes)
		(layer "In2.Cu")
		(net "M_A_DQS_DN<17>")
	)
	(gr_poly
		(pts
			(xy 246.885206 -102.419912) (xy 246.840756 -102.419912) (xy 246.647716 -102.508812) (xy 246.647716 -102.737412)
			(xy 246.840756 -102.826312) (xy 246.885206 -102.826312)
		)
		(stroke
			(width 0)
			(type solid)
		)
		(fill yes)
		(layer "In2.Cu")
		(net "M_D_DQS_DN<8>")
	)
	(gr_poly
		(pts
			(xy 246.939816 -98.465894) (xy 246.895366 -98.465894) (xy 246.702326 -98.554794) (xy 246.702326 -98.783394)
			(xy 246.895366 -98.872294) (xy 246.939816 -98.872294)
		)
		(stroke
			(width 0)
			(type solid)
		)
		(fill yes)
		(layer "In2.Cu")
		(net "M_D_DQS_DP<17>")
	)
	(gr_poly
		(pts
			(xy 246.939816 -97.475294) (xy 246.895366 -97.475294) (xy 246.702326 -97.564194) (xy 246.702326 -97.792794)
			(xy 246.895366 -97.881694) (xy 246.939816 -97.881694)
		)
		(stroke
			(width 0)
			(type solid)
		)
		(fill yes)
		(layer "In2.Cu")
		(net "M_D_DQS_DP<17>")
	)
	(gr_poly
		(pts
			(xy 246.958358 -52.721002) (xy 246.884698 -52.521866) (xy 246.853202 -52.49037) (xy 246.565928 -52.777644)
			(xy 246.597424 -52.80914) (xy 246.79656 -52.8828)
		)
		(stroke
			(width 0)
			(type solid)
		)
		(fill yes)
		(layer "In2.Cu")
		(net "M_A_DQS_DN<17>")
	)
	(gr_poly
		(pts
			(xy 247.039892 -55.23865) (xy 246.995442 -55.23865) (xy 246.802402 -55.32755) (xy 246.802402 -55.55615)
			(xy 246.995442 -55.64505) (xy 247.039892 -55.64505)
		)
		(stroke
			(width 0)
			(type solid)
		)
		(fill yes)
		(layer "In2.Cu")
		(net "M_A_DQS_DN<8>")
	)
	(gr_poly
		(pts
			(xy 247.039892 -54.24805) (xy 246.995442 -54.24805) (xy 246.802402 -54.33695) (xy 246.802402 -54.56555)
			(xy 246.995442 -54.65445) (xy 247.039892 -54.65445)
		)
		(stroke
			(width 0)
			(type solid)
		)
		(fill yes)
		(layer "In2.Cu")
		(net "M_A_DQS_DN<8>")
	)
	(gr_poly
		(pts
			(xy 247.039892 -53.25745) (xy 246.995442 -53.25745) (xy 246.802402 -53.34635) (xy 246.802402 -53.57495)
			(xy 246.995442 -53.66385) (xy 247.039892 -53.66385)
		)
		(stroke
			(width 0)
			(type solid)
		)
		(fill yes)
		(layer "In2.Cu")
		(net "M_A_DQS_DN<8>")
	)
	(gr_poly
		(pts
			(xy 247.040146 -95.9993) (xy 246.995696 -95.9993) (xy 246.825516 -96.0882) (xy 246.825516 -96.30918)
			(xy 246.995696 -96.39808) (xy 247.040146 -96.39808)
		)
		(stroke
			(width 0)
			(type solid)
		)
		(fill yes)
		(layer "In2.Cu")
		(net "M_D_DQS_DP<17>")
	)
	(gr_poly
		(pts
			(xy 247.040146 -95.0087) (xy 246.995696 -95.0087) (xy 246.825516 -95.0976) (xy 246.825516 -95.31858)
			(xy 246.995696 -95.40748) (xy 247.040146 -95.40748)
		)
		(stroke
			(width 0)
			(type solid)
		)
		(fill yes)
		(layer "In2.Cu")
		(net "M_D_DQS_DP<17>")
	)
	(gr_poly
		(pts
			(xy 247.040146 -94.030546) (xy 246.995696 -94.030546) (xy 246.825516 -94.119446) (xy 246.825516 -94.340426)
			(xy 246.995696 -94.429326) (xy 247.040146 -94.429326)
		)
		(stroke
			(width 0)
			(type solid)
		)
		(fill yes)
		(layer "In2.Cu")
		(net "M_D_DQS_DP<17>")
	)
	(gr_poly
		(pts
			(xy 247.040146 -91.0463) (xy 246.995696 -91.0463) (xy 246.825516 -91.1352) (xy 246.825516 -91.35618)
			(xy 246.995696 -91.44508) (xy 247.040146 -91.44508)
		)
		(stroke
			(width 0)
			(type solid)
		)
		(fill yes)
		(layer "In2.Cu")
		(net "M_D_ECC<0>")
	)
	(gr_poly
		(pts
			(xy 247.040146 -56.3753) (xy 246.995696 -56.3753) (xy 246.825516 -56.4642) (xy 246.825516 -56.68518)
			(xy 246.995696 -56.77408) (xy 247.040146 -56.77408)
		)
		(stroke
			(width 0)
			(type solid)
		)
		(fill yes)
		(layer "In2.Cu")
		(net "M_A_DQS_DN<8>")
	)
	(gr_poly
		(pts
			(xy 247.0404 -93.044518) (xy 246.99595 -93.044772) (xy 246.82577 -93.133672) (xy 246.82577 -93.354652)
			(xy 246.99595 -93.443298) (xy 247.0404 -93.443552)
		)
		(stroke
			(width 0)
			(type solid)
		)
		(fill yes)
		(layer "In2.Cu")
		(net "M_D_DQS_DP<17>")
	)
	(gr_poly
		(pts
			(xy 247.0404 -57.361328) (xy 246.99595 -57.361328) (xy 246.82577 -57.450228) (xy 246.82577 -57.671208)
			(xy 246.99595 -57.760108) (xy 247.0404 -57.760362)
		)
		(stroke
			(width 0)
			(type solid)
		)
		(fill yes)
		(layer "In2.Cu")
		(net "M_A_DQS_DN<8>")
	)
	(gr_poly
		(pts
			(xy 247.225312 -50.50282) (xy 247.256808 -50.471578) (xy 246.96928 -50.18405) (xy 246.938038 -50.215546)
			(xy 246.864378 -50.414936) (xy 247.025922 -50.57648)
		)
		(stroke
			(width 0)
			(type solid)
		)
		(fill yes)
		(layer "In2.Cu")
		(net "M_A_DQS_DN<8>")
	)
	(gr_poly
		(pts
			(xy 247.270778 -59.601862) (xy 247.278906 -59.410092) (xy 247.087644 -59.299602) (xy 246.925592 -59.402472)
			(xy 246.90324 -59.440826) (xy 247.24868 -59.64047)
		)
		(stroke
			(width 0)
			(type solid)
		)
		(fill yes)
		(layer "In2.Cu")
		(net "M_A_ECC<1>")
	)
	(gr_poly
		(pts
			(xy 247.272556 -58.612532) (xy 247.280684 -58.420762) (xy 247.089422 -58.310272) (xy 246.92737 -58.413142)
			(xy 246.905018 -58.45175) (xy 247.250458 -58.65114)
		)
		(stroke
			(width 0)
			(type solid)
		)
		(fill yes)
		(layer "In2.Cu")
		(net "M_A_DQS_DN<17>")
	)
	(gr_poly
		(pts
			(xy 247.28043 -92.383864) (xy 247.272302 -92.192094) (xy 247.250204 -92.153486) (xy 246.904764 -92.35313)
			(xy 246.927116 -92.391484) (xy 247.089168 -92.494354)
		)
		(stroke
			(width 0)
			(type solid)
		)
		(fill yes)
		(layer "In2.Cu")
		(net "M_D_ECC<1>")
	)
	(gr_poly
		(pts
			(xy 247.310402 -51.96713) (xy 247.310402 -51.73853) (xy 247.117362 -51.64963) (xy 247.072912 -51.64963)
			(xy 247.072912 -52.05603) (xy 247.117362 -52.05603)
		)
		(stroke
			(width 0)
			(type solid)
		)
		(fill yes)
		(layer "In2.Cu")
		(net "M_A_DQS_DN<17>")
	)
	(gr_poly
		(pts
			(xy 247.313196 -102.737412) (xy 247.313196 -102.508812) (xy 247.120156 -102.419912) (xy 247.075706 -102.419912)
			(xy 247.075706 -102.826312) (xy 247.120156 -102.826312)
		)
		(stroke
			(width 0)
			(type solid)
		)
		(fill yes)
		(layer "In2.Cu")
		(net "M_D_DQS_DP<8>")
	)
	(gr_poly
		(pts
			(xy 247.367806 -98.783394) (xy 247.367806 -98.554794) (xy 247.174766 -98.465894) (xy 247.130316 -98.465894)
			(xy 247.130316 -98.872294) (xy 247.174766 -98.872294)
		)
		(stroke
			(width 0)
			(type solid)
		)
		(fill yes)
		(layer "In2.Cu")
		(net "M_D_DQS_DN<17>")
	)
	(gr_poly
		(pts
			(xy 247.367806 -97.792794) (xy 247.367806 -97.564194) (xy 247.174766 -97.475294) (xy 247.130316 -97.475294)
			(xy 247.130316 -97.881694) (xy 247.174766 -97.881694)
		)
		(stroke
			(width 0)
			(type solid)
		)
		(fill yes)
		(layer "In2.Cu")
		(net "M_D_DQS_DN<17>")
	)
	(gr_poly
		(pts
			(xy 247.387618 -90.872056) (xy 247.387618 -90.651076) (xy 247.217438 -90.562176) (xy 247.172988 -90.562176)
			(xy 247.172988 -90.960956) (xy 247.217438 -90.960956)
		)
		(stroke
			(width 0)
			(type solid)
		)
		(fill yes)
		(layer "In2.Cu")
		(net "M_D_ECC<0>")
	)
	(gr_poly
		(pts
			(xy 247.422924 -50.305208) (xy 247.496584 -50.106072) (xy 247.334786 -49.944274) (xy 247.13565 -50.017934)
			(xy 247.104154 -50.04943) (xy 247.391428 -50.336704)
		)
		(stroke
			(width 0)
			(type solid)
		)
		(fill yes)
		(layer "In2.Cu")
		(net "M_A_DQS_DP<8>")
	)
	(gr_poly
		(pts
			(xy 247.467882 -55.30215) (xy 247.467882 -55.07355) (xy 247.274842 -54.98465) (xy 247.230392 -54.98465)
			(xy 247.230392 -55.39105) (xy 247.274842 -55.39105)
		)
		(stroke
			(width 0)
			(type solid)
		)
		(fill yes)
		(layer "In2.Cu")
		(net "M_A_DQS_DP<8>")
	)
	(gr_poly
		(pts
			(xy 247.467882 -54.31155) (xy 247.467882 -54.08295) (xy 247.274842 -53.99405) (xy 247.230392 -53.99405)
			(xy 247.230392 -54.40045) (xy 247.274842 -54.40045)
		)
		(stroke
			(width 0)
			(type solid)
		)
		(fill yes)
		(layer "In2.Cu")
		(net "M_A_DQS_DP<8>")
	)
	(gr_poly
		(pts
			(xy 247.476772 -58.216038) (xy 247.499124 -58.177684) (xy 247.153684 -57.97804) (xy 247.131586 -58.016648)
			(xy 247.123458 -58.208418) (xy 247.31472 -58.318908)
		)
		(stroke
			(width 0)
			(type solid)
		)
		(fill yes)
		(layer "In2.Cu")
		(net "M_A_DQS_DN<8>")
	)
	(gr_poly
		(pts
			(xy 247.480582 -59.20867) (xy 247.502934 -59.170062) (xy 247.157494 -58.970672) (xy 247.135396 -59.00928)
			(xy 247.127268 -59.20105) (xy 247.31853 -59.31154)
		)
		(stroke
			(width 0)
			(type solid)
		)
		(fill yes)
		(layer "In2.Cu")
		(net "M_A_DQS_DP<17>")
	)
	(gr_poly
		(pts
			(xy 247.499124 -92.627196) (xy 247.476772 -92.588842) (xy 247.31472 -92.485972) (xy 247.123458 -92.596462)
			(xy 247.131586 -92.788232) (xy 247.153684 -92.82684)
		)
		(stroke
			(width 0)
			(type solid)
		)
		(fill yes)
		(layer "In2.Cu")
		(net "M_D_DQS_DP<17>")
	)
	(gr_poly
		(pts
			(xy 247.578372 -96.816926) (xy 247.578372 -96.595946) (xy 247.408192 -96.507046) (xy 247.363742 -96.507046)
			(xy 247.363742 -96.905826) (xy 247.408192 -96.905826)
		)
		(stroke
			(width 0)
			(type solid)
		)
		(fill yes)
		(layer "In2.Cu")
		(net "M_D_DQS_DN<17>")
	)
	(gr_poly
		(pts
			(xy 247.578372 -95.826326) (xy 247.578372 -95.605346) (xy 247.408192 -95.516446) (xy 247.363742 -95.516446)
			(xy 247.363742 -95.915226) (xy 247.408192 -95.915226)
		)
		(stroke
			(width 0)
			(type solid)
		)
		(fill yes)
		(layer "In2.Cu")
		(net "M_D_DQS_DN<17>")
	)
	(gr_poly
		(pts
			(xy 247.578372 -94.829376) (xy 247.578372 -94.608396) (xy 247.408192 -94.519496) (xy 247.363742 -94.519496)
			(xy 247.363742 -94.918276) (xy 247.408192 -94.918276)
		)
		(stroke
			(width 0)
			(type solid)
		)
		(fill yes)
		(layer "In2.Cu")
		(net "M_D_DQS_DN<17>")
	)
	(gr_poly
		(pts
			(xy 247.578372 -93.83268) (xy 247.578372 -93.6117) (xy 247.408192 -93.5228) (xy 247.363742 -93.5228)
			(xy 247.363742 -93.92158) (xy 247.408192 -93.92158)
		)
		(stroke
			(width 0)
			(type solid)
		)
		(fill yes)
		(layer "In2.Cu")
		(net "M_D_DQS_DN<17>")
	)
	(gr_poly
		(pts
			(xy 247.578372 -57.192926) (xy 247.578372 -56.971946) (xy 247.408192 -56.883046) (xy 247.363742 -56.883046)
			(xy 247.363742 -57.281826) (xy 247.408192 -57.281826)
		)
		(stroke
			(width 0)
			(type solid)
		)
		(fill yes)
		(layer "In2.Cu")
		(net "M_A_DQS_DP<8>")
	)
	(gr_poly
		(pts
			(xy 247.578372 -56.202326) (xy 247.578372 -55.981346) (xy 247.408192 -55.892446) (xy 247.363742 -55.892446)
			(xy 247.363742 -56.291226) (xy 247.408192 -56.291226)
		)
		(stroke
			(width 0)
			(type solid)
		)
		(fill yes)
		(layer "In2.Cu")
		(net "M_A_DQS_DP<8>")
	)
	(gr_poly
		(pts
			(xy 247.706896 -100.342954) (xy 247.6754 -100.311458) (xy 247.47601 -100.237798) (xy 247.314212 -100.399596)
			(xy 247.387872 -100.598986) (xy 247.419368 -100.630228)
		)
		(stroke
			(width 0)
			(type solid)
		)
		(fill yes)
		(layer "In2.Cu")
		(net "M_D_DQS_DN<8>")
	)
	(gr_poly
		(pts
			(xy 247.750584 -51.863244) (xy 247.706134 -51.863244) (xy 247.513094 -51.952144) (xy 247.513094 -52.180744)
			(xy 247.706134 -52.269644) (xy 247.750584 -52.269644)
		)
		(stroke
			(width 0)
			(type solid)
		)
		(fill yes)
		(layer "In2.Cu")
		(net "M_A_DQS_DN<8>")
	)
	(gr_poly
		(pts
			(xy 247.778778 -52.982622) (xy 247.705118 -52.783486) (xy 247.673622 -52.75199) (xy 247.386348 -53.039264)
			(xy 247.417844 -53.07076) (xy 247.61698 -53.14442)
		)
		(stroke
			(width 0)
			(type solid)
		)
		(fill yes)
		(layer "In2.Cu")
		(net "M_A_DQS_DP<8>")
	)
	(gr_poly
		(pts
			(xy 247.898666 -95.516192) (xy 247.854216 -95.516192) (xy 247.684036 -95.605092) (xy 247.684036 -95.826072)
			(xy 247.854216 -95.914972) (xy 247.898666 -95.914972)
		)
		(stroke
			(width 0)
			(type solid)
		)
		(fill yes)
		(layer "In2.Cu")
		(net "M_D_DQS_DN<8>")
	)
	(gr_poly
		(pts
			(xy 247.898666 -94.519496) (xy 247.854216 -94.519496) (xy 247.684036 -94.608396) (xy 247.684036 -94.829376)
			(xy 247.854216 -94.918276) (xy 247.898666 -94.918276)
		)
		(stroke
			(width 0)
			(type solid)
		)
		(fill yes)
		(layer "In2.Cu")
		(net "M_D_DQS_DN<8>")
	)
	(gr_poly
		(pts
			(xy 247.898666 -93.52915) (xy 247.854216 -93.529404) (xy 247.684036 -93.618304) (xy 247.683782 -93.83903)
			(xy 247.853962 -93.928184) (xy 247.898666 -93.928184)
		)
		(stroke
			(width 0)
			(type solid)
		)
		(fill yes)
		(layer "In2.Cu")
		(net "M_D_DQS_DN<8>")
	)
	(gr_poly
		(pts
			(xy 247.898666 -91.554046) (xy 247.854216 -91.554046) (xy 247.684036 -91.642946) (xy 247.684036 -91.863926)
			(xy 247.854216 -91.952826) (xy 247.898666 -91.952826)
		)
		(stroke
			(width 0)
			(type solid)
		)
		(fill yes)
		(layer "In2.Cu")
		(net "M_D_DQS_DP<17>")
	)
	(gr_poly
		(pts
			(xy 247.898666 -90.563446) (xy 247.854216 -90.563446) (xy 247.684036 -90.652346) (xy 247.684036 -90.873326)
			(xy 247.854216 -90.962226) (xy 247.898666 -90.962226)
		)
		(stroke
			(width 0)
			(type solid)
		)
		(fill yes)
		(layer "In2.Cu")
		(net "M_D_DQS_DP<17>")
	)
	(gr_poly
		(pts
			(xy 247.898666 -89.572846) (xy 247.854216 -89.572846) (xy 247.684036 -89.661746) (xy 247.684036 -89.882726)
			(xy 247.854216 -89.971626) (xy 247.898666 -89.971626)
		)
		(stroke
			(width 0)
			(type solid)
		)
		(fill yes)
		(layer "In2.Cu")
		(net "M_D_DQS_DP<17>")
	)
	(gr_poly
		(pts
			(xy 247.898666 -56.876442) (xy 247.853962 -56.876696) (xy 247.684036 -56.965596) (xy 247.684036 -57.186322)
			(xy 247.854216 -57.275222) (xy 247.898666 -57.275476)
		)
		(stroke
			(width 0)
			(type solid)
		)
		(fill yes)
		(layer "In2.Cu")
		(net "M_A_ECC<6>")
	)
	(gr_poly
		(pts
			(xy 247.898666 -55.892446) (xy 247.854216 -55.892446) (xy 247.684036 -55.981346) (xy 247.684036 -56.202326)
			(xy 247.854216 -56.291226) (xy 247.898666 -56.291226)
		)
		(stroke
			(width 0)
			(type solid)
		)
		(fill yes)
		(layer "In2.Cu")
		(net "M_A_ECC<6>")
	)
	(gr_poly
		(pts
			(xy 247.946672 -100.708714) (xy 247.873012 -100.509324) (xy 247.841516 -100.477828) (xy 247.554242 -100.765102)
			(xy 247.585484 -100.796598) (xy 247.784874 -100.870258)
		)
		(stroke
			(width 0)
			(type solid)
		)
		(fill yes)
		(layer "In2.Cu")
		(net "M_D_DQS_DP<8>")
	)
	(gr_poly
		(pts
			(xy 248.0437 -99.42957) (xy 247.99925 -99.42957) (xy 247.80621 -99.51847) (xy 247.80621 -99.74707)
			(xy 247.99925 -99.83597) (xy 248.0437 -99.83597)
		)
		(stroke
			(width 0)
			(type solid)
		)
		(fill yes)
		(layer "In2.Cu")
		(net "M_D_DQS_DN<8>")
	)
	(gr_poly
		(pts
			(xy 248.0437 -98.43897) (xy 247.99925 -98.43897) (xy 247.80621 -98.52787) (xy 247.80621 -98.75647)
			(xy 247.99925 -98.84537) (xy 248.0437 -98.84537)
		)
		(stroke
			(width 0)
			(type solid)
		)
		(fill yes)
		(layer "In2.Cu")
		(net "M_D_DQS_DN<8>")
	)
	(gr_poly
		(pts
			(xy 248.0437 -97.44837) (xy 247.99925 -97.44837) (xy 247.80621 -97.53727) (xy 247.80621 -97.76587)
			(xy 247.99925 -97.85477) (xy 248.0437 -97.85477)
		)
		(stroke
			(width 0)
			(type solid)
		)
		(fill yes)
		(layer "In2.Cu")
		(net "M_D_DQS_DN<8>")
	)
	(gr_poly
		(pts
			(xy 248.0437 -96.45777) (xy 247.99925 -96.45777) (xy 247.80621 -96.54667) (xy 247.80621 -96.77527)
			(xy 247.99925 -96.86417) (xy 248.0437 -96.86417)
		)
		(stroke
			(width 0)
			(type solid)
		)
		(fill yes)
		(layer "In2.Cu")
		(net "M_D_DQS_DN<8>")
	)
	(gr_poly
		(pts
			(xy 248.061226 -50.058574) (xy 248.092722 -50.027332) (xy 247.805194 -49.739804) (xy 247.773952 -49.7713)
			(xy 247.700292 -49.97069) (xy 247.861836 -50.132234)
		)
		(stroke
			(width 0)
			(type solid)
		)
		(fill yes)
		(layer "In2.Cu")
		(net "M_A_ECC<6>")
	)
	(gr_poly
		(pts
			(xy 248.066052 -102.01402) (xy 248.021602 -102.01402) (xy 247.828562 -102.10292) (xy 247.828562 -102.33152)
			(xy 248.021602 -102.42042) (xy 248.066052 -102.42042)
		)
		(stroke
			(width 0)
			(type solid)
		)
		(fill yes)
		(layer "In2.Cu")
		(net "M_D_ECC<6>")
	)
	(gr_poly
		(pts
			(xy 248.129298 -59.10707) (xy 248.137426 -58.9153) (xy 247.946164 -58.80481) (xy 247.784112 -58.90768)
			(xy 247.76176 -58.946034) (xy 248.1072 -59.145678)
		)
		(stroke
			(width 0)
			(type solid)
		)
		(fill yes)
		(layer "In2.Cu")
		(net "M_A_DQS_DN<17>")
	)
	(gr_poly
		(pts
			(xy 248.129298 -58.116216) (xy 248.137426 -57.924446) (xy 247.946164 -57.813956) (xy 247.784112 -57.916826)
			(xy 247.76176 -57.955434) (xy 248.1072 -58.154824)
		)
		(stroke
			(width 0)
			(type solid)
		)
		(fill yes)
		(layer "In2.Cu")
		(net "M_A_DQS_DP<8>")
	)
	(gr_poly
		(pts
			(xy 248.137172 -92.880688) (xy 248.129044 -92.688664) (xy 248.106946 -92.650056) (xy 247.76176 -92.8497)
			(xy 247.783858 -92.888054) (xy 247.94591 -92.990924)
		)
		(stroke
			(width 0)
			(type solid)
		)
		(fill yes)
		(layer "In2.Cu")
		(net "M_D_DQS_DN<17>")
	)
	(gr_poly
		(pts
			(xy 248.172224 -54.703218) (xy 248.127774 -54.703218) (xy 247.934734 -54.792118) (xy 247.934734 -55.020718)
			(xy 248.127774 -55.109618) (xy 248.172224 -55.109618)
		)
		(stroke
			(width 0)
			(type solid)
		)
		(fill yes)
		(layer "In2.Cu")
		(net "M_A_ECC<6>")
	)
	(gr_poly
		(pts
			(xy 248.178574 -52.180744) (xy 248.178574 -51.952144) (xy 247.985534 -51.863244) (xy 247.941084 -51.863244)
			(xy 247.941084 -52.269644) (xy 247.985534 -52.269644)
		)
		(stroke
			(width 0)
			(type solid)
		)
		(fill yes)
		(layer "In2.Cu")
		(net "M_A_DQS_DP<8>")
	)
	(gr_poly
		(pts
			(xy 248.258838 -49.860962) (xy 248.332498 -49.661826) (xy 248.1707 -49.500028) (xy 247.971564 -49.573688)
			(xy 247.940068 -49.605184) (xy 248.227342 -49.892458)
		)
		(stroke
			(width 0)
			(type solid)
		)
		(fill yes)
		(layer "In2.Cu")
		(net "M_A_ECC<7>")
	)
	(gr_poly
		(pts
			(xy 248.336816 -58.7121) (xy 248.359168 -58.673746) (xy 248.013728 -58.474102) (xy 247.99163 -58.51271)
			(xy 247.983502 -58.70448) (xy 248.174764 -58.81497)
		)
		(stroke
			(width 0)
			(type solid)
		)
		(fill yes)
		(layer "In2.Cu")
		(net "M_A_DQS_DN<8>")
	)
	(gr_poly
		(pts
			(xy 248.344436 -57.726072) (xy 248.366788 -57.687718) (xy 248.021348 -57.488074) (xy 247.998996 -57.526936)
			(xy 247.991122 -57.718706) (xy 248.182384 -57.828942)
		)
		(stroke
			(width 0)
			(type solid)
		)
		(fill yes)
		(layer "In2.Cu")
		(net "M_A_ECC<6>")
	)
	(gr_poly
		(pts
			(xy 248.366788 -93.116908) (xy 248.344436 -93.078554) (xy 248.182384 -92.975684) (xy 247.991122 -93.08592)
			(xy 247.998996 -93.27769) (xy 248.021348 -93.316552)
		)
		(stroke
			(width 0)
			(type solid)
		)
		(fill yes)
		(layer "In2.Cu")
		(net "M_D_DQS_DN<8>")
	)
	(gr_poly
		(pts
			(xy 248.381012 -61.41593) (xy 248.35866 -61.377576) (xy 248.196608 -61.274706) (xy 248.005346 -61.385196)
			(xy 248.013474 -61.576966) (xy 248.035572 -61.61532)
		)
		(stroke
			(width 0)
			(type solid)
		)
		(fill yes)
		(layer "In2.Cu")
		(net "M_A_DQS_DN<8>")
	)
	(gr_poly
		(pts
			(xy 248.436638 -92.34424) (xy 248.436638 -92.123514) (xy 248.266458 -92.034614) (xy 248.222008 -92.03436)
			(xy 248.222262 -92.43314) (xy 248.266458 -92.43314)
		)
		(stroke
			(width 0)
			(type solid)
		)
		(fill yes)
		(layer "In2.Cu")
		(net "M_D_DQS_DN<17>")
	)
	(gr_poly
		(pts
			(xy 248.436892 -95.31858) (xy 248.436892 -95.0976) (xy 248.266712 -95.0087) (xy 248.222262 -95.0087)
			(xy 248.222262 -95.40748) (xy 248.266712 -95.40748)
		)
		(stroke
			(width 0)
			(type solid)
		)
		(fill yes)
		(layer "In2.Cu")
		(net "M_D_DQS_DP<8>")
	)
	(gr_poly
		(pts
			(xy 248.436892 -94.340426) (xy 248.436892 -94.119446) (xy 248.266712 -94.030546) (xy 248.222262 -94.030546)
			(xy 248.222262 -94.429326) (xy 248.266712 -94.429326)
		)
		(stroke
			(width 0)
			(type solid)
		)
		(fill yes)
		(layer "In2.Cu")
		(net "M_D_DQS_DP<8>")
	)
	(gr_poly
		(pts
			(xy 248.436892 -91.35618) (xy 248.436892 -91.1352) (xy 248.266712 -91.0463) (xy 248.222262 -91.0463)
			(xy 248.222262 -91.44508) (xy 248.266712 -91.44508)
		)
		(stroke
			(width 0)
			(type solid)
		)
		(fill yes)
		(layer "In2.Cu")
		(net "M_D_DQS_DN<17>")
	)
	(gr_poly
		(pts
			(xy 248.436892 -90.36558) (xy 248.436892 -90.1446) (xy 248.266712 -90.0557) (xy 248.222262 -90.0557)
			(xy 248.222262 -90.45448) (xy 248.266712 -90.45448)
		)
		(stroke
			(width 0)
			(type solid)
		)
		(fill yes)
		(layer "In2.Cu")
		(net "M_D_DQS_DN<17>")
	)
	(gr_poly
		(pts
			(xy 248.436892 -56.68518) (xy 248.436892 -56.4642) (xy 248.266712 -56.3753) (xy 248.222262 -56.3753)
			(xy 248.222262 -56.77408) (xy 248.266712 -56.77408)
		)
		(stroke
			(width 0)
			(type solid)
		)
		(fill yes)
		(layer "In2.Cu")
		(net "M_A_ECC<7>")
	)
	(gr_poly
		(pts
			(xy 248.466864 -53.307234) (xy 248.422414 -53.307234) (xy 248.229374 -53.396134) (xy 248.229374 -53.624734)
			(xy 248.422414 -53.713634) (xy 248.466864 -53.713634)
		)
		(stroke
			(width 0)
			(type solid)
		)
		(fill yes)
		(layer "In2.Cu")
		(net "M_A_ECC<6>")
	)
	(gr_poly
		(pts
			(xy 248.466864 -52.316634) (xy 248.422414 -52.316634) (xy 248.229374 -52.405534) (xy 248.229374 -52.634134)
			(xy 248.422414 -52.723034) (xy 248.466864 -52.723034)
		)
		(stroke
			(width 0)
			(type solid)
		)
		(fill yes)
		(layer "In2.Cu")
		(net "M_A_ECC<6>")
	)
	(gr_poly
		(pts
			(xy 248.466864 -51.326034) (xy 248.422414 -51.326034) (xy 248.229374 -51.414934) (xy 248.229374 -51.643534)
			(xy 248.422414 -51.732434) (xy 248.466864 -51.732434)
		)
		(stroke
			(width 0)
			(type solid)
		)
		(fill yes)
		(layer "In2.Cu")
		(net "M_A_ECC<6>")
	)
	(gr_poly
		(pts
			(xy 248.47169 -99.74707) (xy 248.47169 -99.51847) (xy 248.27865 -99.42957) (xy 248.2342 -99.42957)
			(xy 248.2342 -99.83597) (xy 248.27865 -99.83597)
		)
		(stroke
			(width 0)
			(type solid)
		)
		(fill yes)
		(layer "In2.Cu")
		(net "M_D_DQS_DP<8>")
	)
	(gr_poly
		(pts
			(xy 248.47169 -98.75647) (xy 248.47169 -98.52787) (xy 248.27865 -98.43897) (xy 248.2342 -98.43897)
			(xy 248.2342 -98.84537) (xy 248.27865 -98.84537)
		)
		(stroke
			(width 0)
			(type solid)
		)
		(fill yes)
		(layer "In2.Cu")
		(net "M_D_DQS_DP<8>")
	)
	(gr_poly
		(pts
			(xy 248.47169 -97.76587) (xy 248.47169 -97.53727) (xy 248.27865 -97.44837) (xy 248.2342 -97.44837)
			(xy 248.2342 -97.85477) (xy 248.27865 -97.85477)
		)
		(stroke
			(width 0)
			(type solid)
		)
		(fill yes)
		(layer "In2.Cu")
		(net "M_D_DQS_DP<8>")
	)
	(gr_poly
		(pts
			(xy 248.47169 -96.77527) (xy 248.47169 -96.54667) (xy 248.27865 -96.45777) (xy 248.2342 -96.45777)
			(xy 248.2342 -96.86417) (xy 248.27865 -96.86417)
		)
		(stroke
			(width 0)
			(type solid)
		)
		(fill yes)
		(layer "In2.Cu")
		(net "M_D_DQS_DP<8>")
	)
	(gr_poly
		(pts
			(xy 248.493534 -102.33152) (xy 248.493534 -102.10292) (xy 248.300494 -102.01402) (xy 248.256044 -102.01402)
			(xy 248.256044 -102.42042) (xy 248.300494 -102.42042)
		)
		(stroke
			(width 0)
			(type solid)
		)
		(fill yes)
		(layer "In2.Cu")
		(net "M_D_ECC<7>")
	)
	(gr_poly
		(pts
			(xy 248.600214 -55.198518) (xy 248.600214 -54.969918) (xy 248.407174 -54.881018) (xy 248.362724 -54.881018)
			(xy 248.362724 -55.287418) (xy 248.407174 -55.287418)
		)
		(stroke
			(width 0)
			(type solid)
		)
		(fill yes)
		(layer "In2.Cu")
		(net "M_A_ECC<7>")
	)
	(gr_poly
		(pts
			(xy 248.605802 -100.848922) (xy 248.574306 -100.817426) (xy 248.37517 -100.743766) (xy 248.213372 -100.90531)
			(xy 248.287032 -101.1047) (xy 248.318528 -101.136196)
		)
		(stroke
			(width 0)
			(type solid)
		)
		(fill yes)
		(layer "In2.Cu")
		(net "M_D_ECC<6>")
	)
	(gr_poly
		(pts
			(xy 248.757186 -95.0087) (xy 248.712736 -95.0087) (xy 248.542556 -95.0976) (xy 248.542556 -95.31858)
			(xy 248.712736 -95.40748) (xy 248.757186 -95.40748)
		)
		(stroke
			(width 0)
			(type solid)
		)
		(fill yes)
		(layer "In2.Cu")
		(net "M_D_ECC<6>")
	)
	(gr_poly
		(pts
			(xy 248.757186 -94.033086) (xy 248.71299 -94.033086) (xy 248.54281 -94.121986) (xy 248.54281 -94.342712)
			(xy 248.712736 -94.431612) (xy 248.75744 -94.431866)
		)
		(stroke
			(width 0)
			(type solid)
		)
		(fill yes)
		(layer "In2.Cu")
		(net "M_D_ECC<6>")
	)
	(gr_poly
		(pts
			(xy 248.757186 -60.3377) (xy 248.712736 -60.3377) (xy 248.542556 -60.4266) (xy 248.542556 -60.64758)
			(xy 248.712736 -60.73648) (xy 248.757186 -60.73648)
		)
		(stroke
			(width 0)
			(type solid)
		)
		(fill yes)
		(layer "In2.Cu")
		(net "M_A_DQS_DN<8>")
	)
	(gr_poly
		(pts
			(xy 248.757186 -59.3471) (xy 248.712736 -59.3471) (xy 248.542556 -59.436) (xy 248.542556 -59.65698)
			(xy 248.712736 -59.74588) (xy 248.757186 -59.74588)
		)
		(stroke
			(width 0)
			(type solid)
		)
		(fill yes)
		(layer "In2.Cu")
		(net "M_A_DQS_DN<8>")
	)
	(gr_poly
		(pts
			(xy 248.75744 -56.37276) (xy 248.71299 -56.373014) (xy 248.54281 -56.461914) (xy 248.54281 -56.68264)
			(xy 248.71299 -56.77154) (xy 248.757186 -56.77154)
		)
		(stroke
			(width 0)
			(type solid)
		)
		(fill yes)
		(layer "In2.Cu")
		(net "M_A_ECC<2>")
	)
	(gr_poly
		(pts
			(xy 248.75744 -55.39105) (xy 248.71299 -55.39105) (xy 248.54281 -55.47995) (xy 248.54281 -55.70093)
			(xy 248.71299 -55.78983) (xy 248.75744 -55.78983)
		)
		(stroke
			(width 0)
			(type solid)
		)
		(fill yes)
		(layer "In2.Cu")
		(net "M_A_ECC<2>")
	)
	(gr_poly
		(pts
			(xy 248.815352 -99.873816) (xy 248.770902 -99.873816) (xy 248.577862 -99.962716) (xy 248.577862 -100.191316)
			(xy 248.770902 -100.280216) (xy 248.815352 -100.280216)
		)
		(stroke
			(width 0)
			(type solid)
		)
		(fill yes)
		(layer "In2.Cu")
		(net "M_D_ECC<6>")
	)
	(gr_poly
		(pts
			(xy 248.815352 -98.883216) (xy 248.770902 -98.883216) (xy 248.577862 -98.972116) (xy 248.577862 -99.200716)
			(xy 248.770902 -99.289616) (xy 248.815352 -99.289616)
		)
		(stroke
			(width 0)
			(type solid)
		)
		(fill yes)
		(layer "In2.Cu")
		(net "M_D_ECC<6>")
	)
	(gr_poly
		(pts
			(xy 248.815352 -97.892616) (xy 248.770902 -97.892616) (xy 248.577862 -97.981516) (xy 248.577862 -98.210116)
			(xy 248.770902 -98.299016) (xy 248.815352 -98.299016)
		)
		(stroke
			(width 0)
			(type solid)
		)
		(fill yes)
		(layer "In2.Cu")
		(net "M_D_ECC<6>")
	)
	(gr_poly
		(pts
			(xy 248.815352 -96.902016) (xy 248.770902 -96.902016) (xy 248.577862 -96.990916) (xy 248.577862 -97.219516)
			(xy 248.770902 -97.308416) (xy 248.815352 -97.308416)
		)
		(stroke
			(width 0)
			(type solid)
		)
		(fill yes)
		(layer "In2.Cu")
		(net "M_D_ECC<6>")
	)
	(gr_poly
		(pts
			(xy 248.845324 -101.21392) (xy 248.771664 -101.01453) (xy 248.740168 -100.983288) (xy 248.452894 -101.270562)
			(xy 248.484136 -101.302058) (xy 248.683526 -101.375718)
		)
		(stroke
			(width 0)
			(type solid)
		)
		(fill yes)
		(layer "In2.Cu")
		(net "M_D_ECC<7>")
	)
	(gr_poly
		(pts
			(xy 248.894346 -53.624734) (xy 248.894346 -53.396134) (xy 248.701306 -53.307234) (xy 248.656856 -53.307234)
			(xy 248.656856 -53.713634) (xy 248.701306 -53.713634)
		)
		(stroke
			(width 0)
			(type solid)
		)
		(fill yes)
		(layer "In2.Cu")
		(net "M_A_ECC<7>")
	)
	(gr_poly
		(pts
			(xy 248.894346 -52.634134) (xy 248.894346 -52.405534) (xy 248.701306 -52.316634) (xy 248.656856 -52.316634)
			(xy 248.656856 -52.723034) (xy 248.701306 -52.723034)
		)
		(stroke
			(width 0)
			(type solid)
		)
		(fill yes)
		(layer "In2.Cu")
		(net "M_A_ECC<7>")
	)
	(gr_poly
		(pts
			(xy 248.894346 -51.745134) (xy 248.894346 -51.516534) (xy 248.701306 -51.427634) (xy 248.656856 -51.427634)
			(xy 248.656856 -51.834034) (xy 248.701306 -51.834034)
		)
		(stroke
			(width 0)
			(type solid)
		)
		(fill yes)
		(layer "In2.Cu")
		(net "M_A_ECC<7>")
	)
	(gr_poly
		(pts
			(xy 248.95175 -90.474546) (xy 248.952512 -90.07602) (xy 248.908062 -90.07602) (xy 248.737628 -90.164412)
			(xy 248.73712 -90.385392) (xy 248.907046 -90.4748)
		)
		(stroke
			(width 0)
			(type solid)
		)
		(fill yes)
		(layer "In2.Cu")
		(net "M_D_ECC<6>")
	)
	(gr_poly
		(pts
			(xy 248.956576 -49.71288) (xy 248.912126 -49.71288) (xy 248.719086 -49.80178) (xy 248.719086 -50.03038)
			(xy 248.912126 -50.11928) (xy 248.956576 -50.11928)
		)
		(stroke
			(width 0)
			(type solid)
		)
		(fill yes)
		(layer "In2.Cu")
		(net "M_A_ECC<2>")
	)
	(gr_poly
		(pts
			(xy 248.985532 -57.619646) (xy 248.99366 -57.427876) (xy 248.802398 -57.317386) (xy 248.640346 -57.420256)
			(xy 248.617994 -57.45861) (xy 248.963434 -57.658254)
		)
		(stroke
			(width 0)
			(type solid)
		)
		(fill yes)
		(layer "In2.Cu")
		(net "M_A_ECC<7>")
	)
	(gr_poly
		(pts
			(xy 248.988326 -93.380306) (xy 248.980198 -93.188536) (xy 248.9581 -93.149674) (xy 248.61266 -93.349318)
			(xy 248.635012 -93.387672) (xy 248.797064 -93.490542)
		)
		(stroke
			(width 0)
			(type solid)
		)
		(fill yes)
		(layer "In2.Cu")
		(net "M_D_DQS_DP<8>")
	)
	(gr_poly
		(pts
			(xy 248.989342 -58.612278) (xy 248.99747 -58.420508) (xy 248.806208 -58.310018) (xy 248.644156 -58.412888)
			(xy 248.622058 -58.451242) (xy 248.967498 -58.650632)
		)
		(stroke
			(width 0)
			(type solid)
		)
		(fill yes)
		(layer "In2.Cu")
		(net "M_A_DQS_DP<8>")
	)
	(gr_poly
		(pts
			(xy 249.125232 -92.936822) (xy 249.295412 -92.847922) (xy 249.295412 -92.627196) (xy 249.125486 -92.538296)
			(xy 249.080782 -92.538042) (xy 249.080782 -92.937076)
		)
		(stroke
			(width 0)
			(type solid)
		)
		(fill yes)
		(layer "In2.Cu")
		(net "M_D_DQS_DP<8>")
	)
	(gr_poly
		(pts
			(xy 249.125232 -61.233304) (xy 249.295158 -61.144404) (xy 249.295412 -60.923678) (xy 249.125232 -60.834778)
			(xy 249.080528 -60.834524) (xy 249.080528 -61.233558)
		)
		(stroke
			(width 0)
			(type solid)
		)
		(fill yes)
		(layer "In2.Cu")
		(net "M_A_DQS_DP<8>")
	)
	(gr_poly
		(pts
			(xy 249.193812 -58.216038) (xy 249.216164 -58.17743) (xy 248.870724 -57.978294) (xy 248.848626 -58.016648)
			(xy 248.840498 -58.208418) (xy 249.03176 -58.318908)
		)
		(stroke
			(width 0)
			(type solid)
		)
		(fill yes)
		(layer "In2.Cu")
		(net "M_A_ECC<6>")
	)
	(gr_poly
		(pts
			(xy 249.19559 -57.226454) (xy 249.217688 -57.1881) (xy 248.872502 -56.988456) (xy 248.850404 -57.027318)
			(xy 248.842276 -57.219088) (xy 249.033538 -57.329324)
		)
		(stroke
			(width 0)
			(type solid)
		)
		(fill yes)
		(layer "In2.Cu")
		(net "M_A_ECC<2>")
	)
	(gr_poly
		(pts
			(xy 249.217688 -93.616526) (xy 249.19559 -93.578172) (xy 249.033538 -93.475302) (xy 248.842276 -93.585538)
			(xy 248.850404 -93.777308) (xy 248.872502 -93.81617)
		)
		(stroke
			(width 0)
			(type solid)
		)
		(fill yes)
		(layer "In2.Cu")
		(net "M_D_ECC<6>")
	)
	(gr_poly
		(pts
			(xy 249.233436 -53.92928) (xy 249.188986 -53.92928) (xy 248.995946 -54.01818) (xy 248.995946 -54.24678)
			(xy 249.188986 -54.33568) (xy 249.233436 -54.33568)
		)
		(stroke
			(width 0)
			(type solid)
		)
		(fill yes)
		(layer "In2.Cu")
		(net "M_A_ECC<2>")
	)
	(gr_poly
		(pts
			(xy 249.233436 -52.93868) (xy 249.188986 -52.93868) (xy 248.995946 -53.02758) (xy 248.995946 -53.25618)
			(xy 249.188986 -53.34508) (xy 249.233436 -53.34508)
		)
		(stroke
			(width 0)
			(type solid)
		)
		(fill yes)
		(layer "In2.Cu")
		(net "M_A_ECC<2>")
	)
	(gr_poly
		(pts
			(xy 249.233436 -51.94808) (xy 249.188986 -51.94808) (xy 248.995946 -52.03698) (xy 248.995946 -52.26558)
			(xy 249.188986 -52.35448) (xy 249.233436 -52.35448)
		)
		(stroke
			(width 0)
			(type solid)
		)
		(fill yes)
		(layer "In2.Cu")
		(net "M_A_ECC<2>")
	)
	(gr_poly
		(pts
			(xy 249.242834 -100.191316) (xy 249.242834 -99.962716) (xy 249.049794 -99.873816) (xy 249.005344 -99.873816)
			(xy 249.005344 -100.280216) (xy 249.049794 -100.280216)
		)
		(stroke
			(width 0)
			(type solid)
		)
		(fill yes)
		(layer "In2.Cu")
		(net "M_D_ECC<7>")
	)
	(gr_poly
		(pts
			(xy 249.242834 -99.200716) (xy 249.242834 -98.972116) (xy 249.049794 -98.883216) (xy 249.005344 -98.883216)
			(xy 249.005344 -99.289616) (xy 249.049794 -99.289616)
		)
		(stroke
			(width 0)
			(type solid)
		)
		(fill yes)
		(layer "In2.Cu")
		(net "M_D_ECC<7>")
	)
	(gr_poly
		(pts
			(xy 249.242834 -98.210116) (xy 249.242834 -97.981516) (xy 249.049794 -97.892616) (xy 249.005344 -97.892616)
			(xy 249.005344 -98.299016) (xy 249.049794 -98.299016)
		)
		(stroke
			(width 0)
			(type solid)
		)
		(fill yes)
		(layer "In2.Cu")
		(net "M_D_ECC<7>")
	)
	(gr_poly
		(pts
			(xy 249.242834 -97.219516) (xy 249.242834 -96.990916) (xy 249.049794 -96.902016) (xy 249.005344 -96.902016)
			(xy 249.005344 -97.308416) (xy 249.049794 -97.308416)
		)
		(stroke
			(width 0)
			(type solid)
		)
		(fill yes)
		(layer "In2.Cu")
		(net "M_D_ECC<7>")
	)
	(gr_poly
		(pts
			(xy 249.295158 -59.178698) (xy 249.295158 -58.957718) (xy 249.124978 -58.868818) (xy 249.080782 -58.868818)
			(xy 249.080782 -59.267598) (xy 249.124978 -59.267598)
		)
		(stroke
			(width 0)
			(type solid)
		)
		(fill yes)
		(layer "In2.Cu")
		(net "M_A_DQS_DP<8>")
	)
	(gr_poly
		(pts
			(xy 249.295412 -95.826326) (xy 249.295412 -95.605346) (xy 249.125232 -95.516446) (xy 249.080782 -95.516446)
			(xy 249.080782 -95.915226) (xy 249.125232 -95.915226)
		)
		(stroke
			(width 0)
			(type solid)
		)
		(fill yes)
		(layer "In2.Cu")
		(net "M_D_ECC<7>")
	)
	(gr_poly
		(pts
			(xy 249.295412 -94.829376) (xy 249.295412 -94.608396) (xy 249.125232 -94.519496) (xy 249.080782 -94.519496)
			(xy 249.080782 -94.918276) (xy 249.125232 -94.918276)
		)
		(stroke
			(width 0)
			(type solid)
		)
		(fill yes)
		(layer "In2.Cu")
		(net "M_D_ECC<7>")
	)
	(gr_poly
		(pts
			(xy 249.295412 -60.164726) (xy 249.295412 -59.943746) (xy 249.125232 -59.854846) (xy 249.080782 -59.854846)
			(xy 249.080782 -60.253626) (xy 249.125232 -60.253626)
		)
		(stroke
			(width 0)
			(type solid)
		)
		(fill yes)
		(layer "In2.Cu")
		(net "M_A_DQS_DP<8>")
	)
	(gr_poly
		(pts
			(xy 249.295412 -56.202326) (xy 249.295412 -55.981346) (xy 249.125232 -55.892446) (xy 249.080782 -55.892446)
			(xy 249.080782 -56.291226) (xy 249.125232 -56.291226)
		)
		(stroke
			(width 0)
			(type solid)
		)
		(fill yes)
		(layer "In2.Cu")
		(net "M_A_ECC<3>")
	)
	(gr_poly
		(pts
			(xy 249.340624 -102.316026) (xy 249.296174 -102.316026) (xy 249.103134 -102.404926) (xy 249.103134 -102.633526)
			(xy 249.296174 -102.722426) (xy 249.340624 -102.722426)
		)
		(stroke
			(width 0)
			(type solid)
		)
		(fill yes)
		(layer "In2.Cu")
		(net "M_D_ECC<2>")
	)
	(gr_poly
		(pts
			(xy 249.384566 -50.03038) (xy 249.384566 -49.80178) (xy 249.191526 -49.71288) (xy 249.147076 -49.71288)
			(xy 249.147076 -50.11928) (xy 249.191526 -50.11928)
		)
		(stroke
			(width 0)
			(type solid)
		)
		(fill yes)
		(layer "In2.Cu")
		(net "M_A_ECC<3>")
	)
	(gr_poly
		(pts
			(xy 249.602752 -100.938076) (xy 249.558302 -100.938076) (xy 249.365262 -101.026976) (xy 249.365262 -101.255576)
			(xy 249.558302 -101.344476) (xy 249.602752 -101.344476)
		)
		(stroke
			(width 0)
			(type solid)
		)
		(fill yes)
		(layer "In2.Cu")
		(net "M_D_ECC<2>")
	)
	(gr_poly
		(pts
			(xy 249.602752 -99.947476) (xy 249.558302 -99.947476) (xy 249.365262 -100.036376) (xy 249.365262 -100.264976)
			(xy 249.558302 -100.353876) (xy 249.602752 -100.353876)
		)
		(stroke
			(width 0)
			(type solid)
		)
		(fill yes)
		(layer "In2.Cu")
		(net "M_D_ECC<2>")
	)
	(gr_poly
		(pts
			(xy 249.602752 -98.956876) (xy 249.558302 -98.956876) (xy 249.365262 -99.045776) (xy 249.365262 -99.274376)
			(xy 249.558302 -99.363276) (xy 249.602752 -99.363276)
		)
		(stroke
			(width 0)
			(type solid)
		)
		(fill yes)
		(layer "In2.Cu")
		(net "M_D_ECC<2>")
	)
	(gr_poly
		(pts
			(xy 249.602752 -97.966276) (xy 249.558302 -97.966276) (xy 249.365262 -98.055176) (xy 249.365262 -98.283776)
			(xy 249.558302 -98.372676) (xy 249.602752 -98.372676)
		)
		(stroke
			(width 0)
			(type solid)
		)
		(fill yes)
		(layer "In2.Cu")
		(net "M_D_ECC<2>")
	)
	(gr_poly
		(pts
			(xy 249.602752 -96.975676) (xy 249.558302 -96.975676) (xy 249.365262 -97.064576) (xy 249.365262 -97.293176)
			(xy 249.558302 -97.382076) (xy 249.602752 -97.382076)
		)
		(stroke
			(width 0)
			(type solid)
		)
		(fill yes)
		(layer "In2.Cu")
		(net "M_D_ECC<2>")
	)
	(gr_poly
		(pts
			(xy 249.615706 -95.516446) (xy 249.571256 -95.516446) (xy 249.401076 -95.605346) (xy 249.401076 -95.826326)
			(xy 249.571256 -95.915226) (xy 249.615706 -95.915226)
		)
		(stroke
			(width 0)
			(type solid)
		)
		(fill yes)
		(layer "In2.Cu")
		(net "M_D_ECC<2>")
	)
	(gr_poly
		(pts
			(xy 249.615706 -94.530418) (xy 249.57151 -94.530418) (xy 249.40133 -94.619318) (xy 249.40133 -94.840298)
			(xy 249.57151 -94.928944) (xy 249.615706 -94.929198)
		)
		(stroke
			(width 0)
			(type solid)
		)
		(fill yes)
		(layer "In2.Cu")
		(net "M_D_ECC<2>")
	)
	(gr_poly
		(pts
			(xy 249.615706 -92.544646) (xy 249.571256 -92.544646) (xy 249.401076 -92.633546) (xy 249.401076 -92.854526)
			(xy 249.571256 -92.943426) (xy 249.615706 -92.943426)
		)
		(stroke
			(width 0)
			(type solid)
		)
		(fill yes)
		(layer "In2.Cu")
		(net "M_D_ECC<6>")
	)
	(gr_poly
		(pts
			(xy 249.615706 -58.857896) (xy 249.571256 -58.857896) (xy 249.401076 -58.946796) (xy 249.401076 -59.167776)
			(xy 249.571256 -59.256676) (xy 249.615706 -59.256676)
		)
		(stroke
			(width 0)
			(type solid)
		)
		(fill yes)
		(layer "In2.Cu")
		(net "M_A_ECC<6>")
	)
	(gr_poly
		(pts
			(xy 249.661426 -54.24678) (xy 249.661426 -54.01818) (xy 249.468386 -53.92928) (xy 249.423936 -53.92928)
			(xy 249.423936 -54.33568) (xy 249.468386 -54.33568)
		)
		(stroke
			(width 0)
			(type solid)
		)
		(fill yes)
		(layer "In2.Cu")
		(net "M_A_ECC<3>")
	)
	(gr_poly
		(pts
			(xy 249.661426 -53.25618) (xy 249.661426 -53.02758) (xy 249.468386 -52.93868) (xy 249.423936 -52.93868)
			(xy 249.423936 -53.34508) (xy 249.468386 -53.34508)
		)
		(stroke
			(width 0)
			(type solid)
		)
		(fill yes)
		(layer "In2.Cu")
		(net "M_A_ECC<3>")
	)
	(gr_poly
		(pts
			(xy 249.661426 -52.26558) (xy 249.661426 -52.03698) (xy 249.468386 -51.94808) (xy 249.423936 -51.94808)
			(xy 249.423936 -52.35448) (xy 249.468386 -52.35448)
		)
		(stroke
			(width 0)
			(type solid)
		)
		(fill yes)
		(layer "In2.Cu")
		(net "M_A_ECC<3>")
	)
	(gr_poly
		(pts
			(xy 249.768106 -102.633526) (xy 249.768106 -102.404926) (xy 249.575066 -102.316026) (xy 249.530616 -102.316026)
			(xy 249.530616 -102.722426) (xy 249.575066 -102.722426)
		)
		(stroke
			(width 0)
			(type solid)
		)
		(fill yes)
		(layer "In2.Cu")
		(net "M_D_ECC<3>")
	)
	(gr_poly
		(pts
			(xy 249.846084 -58.115708) (xy 249.854212 -57.923938) (xy 249.66295 -57.813702) (xy 249.500898 -57.916572)
			(xy 249.4788 -57.954926) (xy 249.823986 -58.15457)
		)
		(stroke
			(width 0)
			(type solid)
		)
		(fill yes)
		(layer "In2.Cu")
		(net "M_A_ECC<7>")
	)
	(gr_poly
		(pts
			(xy 249.847862 -57.126632) (xy 249.85599 -56.934862) (xy 249.664728 -56.824372) (xy 249.502676 -56.927242)
			(xy 249.480324 -56.965596) (xy 249.825764 -57.16524)
		)
		(stroke
			(width 0)
			(type solid)
		)
		(fill yes)
		(layer "In2.Cu")
		(net "M_A_ECC<3>")
	)
	(gr_poly
		(pts
			(xy 249.85599 -93.870018) (xy 249.848116 -93.678248) (xy 249.825764 -93.63964) (xy 249.480324 -93.839284)
			(xy 249.502676 -93.877638) (xy 249.664728 -93.980508)
		)
		(stroke
			(width 0)
			(type solid)
		)
		(fill yes)
		(layer "In2.Cu")
		(net "M_D_ECC<7>")
	)
	(gr_poly
		(pts
			(xy 249.983498 -93.421708) (xy 250.153678 -93.332808) (xy 250.153678 -93.111828) (xy 249.983498 -93.022928)
			(xy 249.939048 -93.022928) (xy 249.939048 -93.421962)
		)
		(stroke
			(width 0)
			(type solid)
		)
		(fill yes)
		(layer "In2.Cu")
		(net "M_D_ECC<7>")
	)
	(gr_poly
		(pts
			(xy 249.983498 -58.770012) (xy 250.153678 -58.681112) (xy 250.153678 -58.460386) (xy 249.983498 -58.371486)
			(xy 249.939302 -58.371486) (xy 249.939048 -58.770266)
		)
		(stroke
			(width 0)
			(type solid)
		)
		(fill yes)
		(layer "In2.Cu")
		(net "M_A_ECC<7>")
	)
	(gr_poly
		(pts
			(xy 250.030234 -101.255576) (xy 250.030234 -101.026976) (xy 249.837194 -100.938076) (xy 249.792744 -100.938076)
			(xy 249.792744 -101.344476) (xy 249.837194 -101.344476)
		)
		(stroke
			(width 0)
			(type solid)
		)
		(fill yes)
		(layer "In2.Cu")
		(net "M_D_ECC<3>")
	)
	(gr_poly
		(pts
			(xy 250.030234 -100.264976) (xy 250.030234 -100.036376) (xy 249.837194 -99.947476) (xy 249.792744 -99.947476)
			(xy 249.792744 -100.353876) (xy 249.837194 -100.353876)
		)
		(stroke
			(width 0)
			(type solid)
		)
		(fill yes)
		(layer "In2.Cu")
		(net "M_D_ECC<3>")
	)
	(gr_poly
		(pts
			(xy 250.030234 -99.274376) (xy 250.030234 -99.045776) (xy 249.837194 -98.956876) (xy 249.792744 -98.956876)
			(xy 249.792744 -99.363276) (xy 249.837194 -99.363276)
		)
		(stroke
			(width 0)
			(type solid)
		)
		(fill yes)
		(layer "In2.Cu")
		(net "M_D_ECC<3>")
	)
	(gr_poly
		(pts
			(xy 250.030234 -98.283776) (xy 250.030234 -98.055176) (xy 249.837194 -97.966276) (xy 249.792744 -97.966276)
			(xy 249.792744 -98.372676) (xy 249.837194 -98.372676)
		)
		(stroke
			(width 0)
			(type solid)
		)
		(fill yes)
		(layer "In2.Cu")
		(net "M_D_ECC<3>")
	)
	(gr_poly
		(pts
			(xy 250.030234 -97.293176) (xy 250.030234 -97.064576) (xy 249.837194 -96.975676) (xy 249.792744 -96.975676)
			(xy 249.792744 -97.382076) (xy 249.837194 -97.382076)
		)
		(stroke
			(width 0)
			(type solid)
		)
		(fill yes)
		(layer "In2.Cu")
		(net "M_D_ECC<3>")
	)
	(gr_poly
		(pts
			(xy 250.056142 -57.72277) (xy 250.078494 -57.684162) (xy 249.733054 -57.484772) (xy 249.710956 -57.52338)
			(xy 249.702828 -57.71515) (xy 249.89409 -57.82564)
		)
		(stroke
			(width 0)
			(type solid)
		)
		(fill yes)
		(layer "In2.Cu")
		(net "M_A_ECC<2>")
	)
	(gr_poly
		(pts
			(xy 250.07443 -94.112842) (xy 250.052332 -94.074488) (xy 249.89028 -93.971618) (xy 249.699018 -94.082108)
			(xy 249.707146 -94.273878) (xy 249.72899 -94.312232)
		)
		(stroke
			(width 0)
			(type solid)
		)
		(fill yes)
		(layer "In2.Cu")
		(net "M_D_ECC<2>")
	)
	(gr_poly
		(pts
			(xy 250.150376 -91.237562) (xy 250.172728 -91.198954) (xy 249.827288 -90.999564) (xy 249.80519 -91.038172)
			(xy 249.797062 -91.229942) (xy 249.988324 -91.340432)
		)
		(stroke
			(width 0)
			(type solid)
		)
		(fill yes)
		(layer "In2.Cu")
		(net "M_D_ECC<2>")
	)
	(gr_poly
		(pts
			(xy 250.153932 -96.30918) (xy 250.153932 -96.0882) (xy 249.983752 -95.9993) (xy 249.939302 -95.9993)
			(xy 249.939302 -96.39808) (xy 249.983752 -96.39808)
		)
		(stroke
			(width 0)
			(type solid)
		)
		(fill yes)
		(layer "In2.Cu")
		(net "M_D_ECC<3>")
	)
	(gr_poly
		(pts
			(xy 250.153932 -95.31858) (xy 250.153932 -95.0976) (xy 249.983752 -95.0087) (xy 249.939302 -95.0087)
			(xy 249.939302 -95.40748) (xy 249.983752 -95.40748)
		)
		(stroke
			(width 0)
			(type solid)
		)
		(fill yes)
		(layer "In2.Cu")
		(net "M_D_ECC<3>")
	)
	(gr_poly
		(pts
			(xy 250.153932 -92.34678) (xy 250.153932 -92.1258) (xy 249.983752 -92.0369) (xy 249.939302 -92.0369)
			(xy 249.939302 -92.43568) (xy 249.983752 -92.43568)
		)
		(stroke
			(width 0)
			(type solid)
		)
		(fill yes)
		(layer "In2.Cu")
		(net "M_D_ECC<7>")
	)
	(gr_poly
		(pts
			(xy 250.153932 -60.64758) (xy 250.153932 -60.4266) (xy 249.983752 -60.3377) (xy 249.939302 -60.3377)
			(xy 249.939302 -60.73648) (xy 249.983752 -60.73648)
		)
		(stroke
			(width 0)
			(type solid)
		)
		(fill yes)
		(layer "In2.Cu")
		(net "M_A_ECC<7>")
	)
	(gr_poly
		(pts
			(xy 250.153932 -59.65698) (xy 250.153932 -59.436) (xy 249.983752 -59.3471) (xy 249.939302 -59.3471)
			(xy 249.939302 -59.74588) (xy 249.983752 -59.74588)
		)
		(stroke
			(width 0)
			(type solid)
		)
		(fill yes)
		(layer "In2.Cu")
		(net "M_A_ECC<7>")
	)
	(gr_poly
		(pts
			(xy 250.474226 -93.03385) (xy 250.429776 -93.03385) (xy 250.259596 -93.12275) (xy 250.259596 -93.34373)
			(xy 250.429776 -93.43263) (xy 250.474226 -93.43263)
		)
		(stroke
			(width 0)
			(type solid)
		)
		(fill yes)
		(layer "In2.Cu")
		(net "M_D_ECC<2>")
	)
	(gr_poly
		(pts
			(xy 250.474226 -92.0369) (xy 250.429776 -92.0369) (xy 250.259596 -92.1258) (xy 250.259596 -92.34678)
			(xy 250.429776 -92.43568) (xy 250.474226 -92.43568)
		)
		(stroke
			(width 0)
			(type solid)
		)
		(fill yes)
		(layer "In2.Cu")
		(net "M_D_ECC<2>")
	)
	(gr_poly
		(pts
			(xy 250.474226 -59.3471) (xy 250.429776 -59.3471) (xy 250.259596 -59.436) (xy 250.259596 -59.65698)
			(xy 250.429776 -59.74588) (xy 250.474226 -59.74588)
		)
		(stroke
			(width 0)
			(type solid)
		)
		(fill yes)
		(layer "In2.Cu")
		(net "M_A_ECC<2>")
	)
	(gr_poly
		(pts
			(xy 250.474226 -58.368946) (xy 250.429776 -58.368946) (xy 250.259596 -58.457846) (xy 250.259596 -58.678826)
			(xy 250.429776 -58.767726) (xy 250.474226 -58.767726)
		)
		(stroke
			(width 0)
			(type solid)
		)
		(fill yes)
		(layer "In2.Cu")
		(net "M_A_ECC<2>")
	)
	(gr_poly
		(pts
			(xy 250.712732 -94.366588) (xy 250.704604 -94.174564) (xy 250.682506 -94.135956) (xy 250.33732 -94.3356)
			(xy 250.359418 -94.373954) (xy 250.52147 -94.476824)
		)
		(stroke
			(width 0)
			(type solid)
		)
		(fill yes)
		(layer "In2.Cu")
		(net "M_D_ECC<3>")
	)
	(gr_poly
		(pts
			(xy 250.768612 -57.709308) (xy 250.810268 -57.521856) (xy 250.641104 -57.379616) (xy 250.463558 -57.452768)
			(xy 250.434856 -57.48655) (xy 250.73991 -57.743344)
		)
		(stroke
			(width 0)
			(type solid)
		)
		(fill yes)
		(layer "In2.Cu")
		(net "M_A_ECC<3>")
	)
	(gr_poly
		(pts
			(xy 251.011944 -61.156596) (xy 251.01296 -60.935616) (xy 250.843288 -60.8457) (xy 250.798584 -60.8457)
			(xy 250.796806 -61.244226) (xy 250.841002 -61.24448)
		)
		(stroke
			(width 0)
			(type solid)
		)
		(fill yes)
		(layer "In2.Cu")
		(net "M_A_ECC<3>")
	)
	(gr_poly
		(pts
			(xy 251.012198 -93.83014) (xy 251.012198 -93.609414) (xy 250.842018 -93.520514) (xy 250.797568 -93.52026)
			(xy 250.797822 -93.91904) (xy 250.842018 -93.91904)
		)
		(stroke
			(width 0)
			(type solid)
		)
		(fill yes)
		(layer "In2.Cu")
		(net "M_D_ECC<3>")
	)
	(gr_poly
		(pts
			(xy 251.012452 -92.854526) (xy 251.012452 -92.633546) (xy 250.842272 -92.544646) (xy 250.797822 -92.544646)
			(xy 250.797822 -92.943426) (xy 250.842272 -92.943426)
		)
		(stroke
			(width 0)
			(type solid)
		)
		(fill yes)
		(layer "In2.Cu")
		(net "M_D_ECC<3>")
	)
	(gr_poly
		(pts
			(xy 251.012452 -91.863926) (xy 251.012452 -91.642946) (xy 250.842272 -91.554046) (xy 250.797822 -91.554046)
			(xy 250.797822 -91.952826) (xy 250.842272 -91.952826)
		)
		(stroke
			(width 0)
			(type solid)
		)
		(fill yes)
		(layer "In2.Cu")
		(net "M_D_ECC<3>")
	)
	(gr_poly
		(pts
			(xy 251.012452 -60.164726) (xy 251.012452 -59.943746) (xy 250.842272 -59.854846) (xy 250.797822 -59.854846)
			(xy 250.797822 -60.253626) (xy 250.842272 -60.253626)
		)
		(stroke
			(width 0)
			(type solid)
		)
		(fill yes)
		(layer "In2.Cu")
		(net "M_A_ECC<3>")
	)
	(gr_poly
		(pts
			(xy 251.012452 -59.167776) (xy 251.012452 -58.946796) (xy 250.842272 -58.857896) (xy 250.797822 -58.857896)
			(xy 250.797822 -59.256676) (xy 250.842272 -59.256676)
		)
		(stroke
			(width 0)
			(type solid)
		)
		(fill yes)
		(layer "In2.Cu")
		(net "M_A_ECC<3>")
	)
	(gr_poly
		(pts
			(xy 251.012706 -58.175398) (xy 251.011944 -57.954418) (xy 250.84151 -57.866026) (xy 250.79706 -57.866026)
			(xy 250.798076 -58.264806) (xy 250.84278 -58.264806)
		)
		(stroke
			(width 0)
			(type solid)
		)
		(fill yes)
		(layer "In2.Cu")
		(net "M_A_ECC<3>")
	)
	(gr_poly
		(pts
			(xy 272.256504 -104.670606) (xy 272.212054 -104.670606) (xy 272.019014 -104.759506) (xy 272.019014 -104.988106)
			(xy 272.212054 -105.077006) (xy 272.256504 -105.077006)
		)
		(stroke
			(width 0)
			(type solid)
		)
		(fill yes)
		(layer "In2.Cu")
		(net "M_D_DQ<44>")
	)
	(gr_poly
		(pts
			(xy 272.576036 -50.12055) (xy 272.531586 -50.12055) (xy 272.338546 -50.20945) (xy 272.338546 -50.43805)
			(xy 272.531586 -50.52695) (xy 272.576036 -50.52695)
		)
		(stroke
			(width 0)
			(type solid)
		)
		(fill yes)
		(layer "In2.Cu")
		(net "M_A_DQ<44>")
	)
	(gr_poly
		(pts
			(xy 272.576036 -49.12995) (xy 272.531586 -49.12995) (xy 272.338546 -49.21885) (xy 272.338546 -49.44745)
			(xy 272.531586 -49.53635) (xy 272.576036 -49.53635)
		)
		(stroke
			(width 0)
			(type solid)
		)
		(fill yes)
		(layer "In2.Cu")
		(net "M_A_DQ<44>")
	)
	(gr_poly
		(pts
			(xy 272.576036 -48.13935) (xy 272.531586 -48.13935) (xy 272.338546 -48.22825) (xy 272.338546 -48.45685)
			(xy 272.531586 -48.54575) (xy 272.576036 -48.54575)
		)
		(stroke
			(width 0)
			(type solid)
		)
		(fill yes)
		(layer "In2.Cu")
		(net "M_A_DQ<44>")
	)
	(gr_poly
		(pts
			(xy 272.683986 -104.988106) (xy 272.683986 -104.759506) (xy 272.490946 -104.670606) (xy 272.446496 -104.670606)
			(xy 272.446496 -105.077006) (xy 272.490946 -105.077006)
		)
		(stroke
			(width 0)
			(type solid)
		)
		(fill yes)
		(layer "In2.Cu")
		(net "M_D_DQ<45>")
	)
	(gr_poly
		(pts
			(xy 272.959322 -103.388668) (xy 272.92808 -103.357172) (xy 272.72869 -103.283512) (xy 272.566892 -103.445056)
			(xy 272.640552 -103.644446) (xy 272.672048 -103.675942)
		)
		(stroke
			(width 0)
			(type solid)
		)
		(fill yes)
		(layer "In2.Cu")
		(net "M_D_DQ<44>")
	)
	(gr_poly
		(pts
			(xy 273.004026 -50.43805) (xy 273.004026 -50.20945) (xy 272.810986 -50.12055) (xy 272.766536 -50.12055)
			(xy 272.766536 -50.52695) (xy 272.810986 -50.52695)
		)
		(stroke
			(width 0)
			(type solid)
		)
		(fill yes)
		(layer "In2.Cu")
		(net "M_A_DQ<45>")
	)
	(gr_poly
		(pts
			(xy 273.004026 -49.44745) (xy 273.004026 -49.21885) (xy 272.810986 -49.12995) (xy 272.766536 -49.12995)
			(xy 272.766536 -49.53635) (xy 272.810986 -49.53635)
		)
		(stroke
			(width 0)
			(type solid)
		)
		(fill yes)
		(layer "In2.Cu")
		(net "M_A_DQ<45>")
	)
	(gr_poly
		(pts
			(xy 273.004026 -48.45685) (xy 273.004026 -48.22825) (xy 272.810986 -48.13935) (xy 272.766536 -48.13935)
			(xy 272.766536 -48.54575) (xy 272.810986 -48.54575)
		)
		(stroke
			(width 0)
			(type solid)
		)
		(fill yes)
		(layer "In2.Cu")
		(net "M_A_DQ<45>")
	)
	(gr_poly
		(pts
			(xy 273.198844 -103.753666) (xy 273.125184 -103.554276) (xy 273.093688 -103.523034) (xy 272.806414 -103.810308)
			(xy 272.83791 -103.841804) (xy 273.0373 -103.915464)
		)
		(stroke
			(width 0)
			(type solid)
		)
		(fill yes)
		(layer "In2.Cu")
		(net "M_D_DQ<45>")
	)
	(gr_poly
		(pts
			(xy 273.314668 -51.474116) (xy 273.346164 -51.442874) (xy 273.058636 -51.155346) (xy 273.027394 -51.186842)
			(xy 272.953734 -51.386232) (xy 273.115278 -51.547776)
		)
		(stroke
			(width 0)
			(type solid)
		)
		(fill yes)
		(layer "In2.Cu")
		(net "M_A_DQ<44>")
	)
	(gr_poly
		(pts
			(xy 273.325336 -49.51984) (xy 273.280886 -49.51984) (xy 273.087846 -49.60874) (xy 273.087846 -49.83734)
			(xy 273.280886 -49.92624) (xy 273.325336 -49.92624)
		)
		(stroke
			(width 0)
			(type solid)
		)
		(fill yes)
		(layer "In2.Cu")
		(net "M_A_DQ<40>")
	)
	(gr_poly
		(pts
			(xy 273.325336 -48.52924) (xy 273.280886 -48.52924) (xy 273.087846 -48.61814) (xy 273.087846 -48.84674)
			(xy 273.280886 -48.93564) (xy 273.325336 -48.93564)
		)
		(stroke
			(width 0)
			(type solid)
		)
		(fill yes)
		(layer "In2.Cu")
		(net "M_A_DQ<40>")
	)
	(gr_poly
		(pts
			(xy 273.43608 -51.200304) (xy 273.50974 -51.001168) (xy 273.347942 -50.83937) (xy 273.148806 -50.91303)
			(xy 273.11731 -50.944526) (xy 273.404584 -51.2318)
		)
		(stroke
			(width 0)
			(type solid)
		)
		(fill yes)
		(layer "In2.Cu")
		(net "M_A_DQ<45>")
	)
	(gr_poly
		(pts
			(xy 273.659854 -102.688136) (xy 273.628358 -102.65664) (xy 273.429222 -102.58298) (xy 273.267424 -102.744778)
			(xy 273.341084 -102.943914) (xy 273.37258 -102.97541)
		)
		(stroke
			(width 0)
			(type solid)
		)
		(fill yes)
		(layer "In2.Cu")
		(net "M_D_DQ<44>")
	)
	(gr_poly
		(pts
			(xy 273.753326 -49.83734) (xy 273.753326 -49.60874) (xy 273.560286 -49.51984) (xy 273.515836 -49.51984)
			(xy 273.515836 -49.92624) (xy 273.560286 -49.92624)
		)
		(stroke
			(width 0)
			(type solid)
		)
		(fill yes)
		(layer "In2.Cu")
		(net "M_A_DQ<41>")
	)
	(gr_poly
		(pts
			(xy 273.753326 -48.84674) (xy 273.753326 -48.61814) (xy 273.560286 -48.52924) (xy 273.515836 -48.52924)
			(xy 273.515836 -48.93564) (xy 273.560286 -48.93564)
		)
		(stroke
			(width 0)
			(type solid)
		)
		(fill yes)
		(layer "In2.Cu")
		(net "M_A_DQ<41>")
	)
	(gr_poly
		(pts
			(xy 273.899376 -103.053134) (xy 273.825716 -102.853998) (xy 273.79422 -102.822502) (xy 273.506946 -103.109776)
			(xy 273.538442 -103.141272) (xy 273.737578 -103.214932)
		)
		(stroke
			(width 0)
			(type solid)
		)
		(fill yes)
		(layer "In2.Cu")
		(net "M_D_DQ<45>")
	)
	(gr_poly
		(pts
			(xy 274.042886 -104.482392) (xy 274.01139 -104.450896) (xy 273.812254 -104.377236) (xy 273.650456 -104.539034)
			(xy 273.724116 -104.73817) (xy 273.755612 -104.769666)
		)
		(stroke
			(width 0)
			(type solid)
		)
		(fill yes)
		(layer "In2.Cu")
		(net "M_D_DQ<40>")
	)
	(gr_poly
		(pts
			(xy 274.051014 -51.186588) (xy 274.08251 -51.155346) (xy 273.794982 -50.867818) (xy 273.76374 -50.899314)
			(xy 273.69008 -51.098704) (xy 273.851624 -51.260248)
		)
		(stroke
			(width 0)
			(type solid)
		)
		(fill yes)
		(layer "In2.Cu")
		(net "M_A_DQ<40>")
	)
	(gr_poly
		(pts
			(xy 274.080224 -53.349652) (xy 274.11172 -53.31841) (xy 273.824192 -53.030882) (xy 273.792696 -53.062378)
			(xy 273.71929 -53.261768) (xy 273.880834 -53.423312)
		)
		(stroke
			(width 0)
			(type solid)
		)
		(fill yes)
		(layer "In2.Cu")
		(net "M_A_DQ<44>")
	)
	(gr_poly
		(pts
			(xy 274.107148 -49.417224) (xy 274.062698 -49.417224) (xy 273.869658 -49.506124) (xy 273.869658 -49.734724)
			(xy 274.062698 -49.823624) (xy 274.107148 -49.823624)
		)
		(stroke
			(width 0)
			(type solid)
		)
		(fill yes)
		(layer "In2.Cu")
		(net "M_A_DQS_DP<14>")
	)
	(gr_poly
		(pts
			(xy 274.107148 -48.426624) (xy 274.062698 -48.426624) (xy 273.869658 -48.515524) (xy 273.869658 -48.744124)
			(xy 274.062698 -48.833024) (xy 274.107148 -48.833024)
		)
		(stroke
			(width 0)
			(type solid)
		)
		(fill yes)
		(layer "In2.Cu")
		(net "M_A_DQS_DP<14>")
	)
	(gr_poly
		(pts
			(xy 274.145248 -52.483258) (xy 274.145248 -52.254658) (xy 273.952208 -52.165758) (xy 273.907758 -52.165758)
			(xy 273.907758 -52.572158) (xy 273.952208 -52.572158)
		)
		(stroke
			(width 0)
			(type solid)
		)
		(fill yes)
		(layer "In2.Cu")
		(net "M_A_DQ<45>")
	)
	(gr_poly
		(pts
			(xy 274.172426 -50.912776) (xy 274.246086 -50.71364) (xy 274.084288 -50.551842) (xy 273.885152 -50.625502)
			(xy 273.853656 -50.656998) (xy 274.14093 -50.944272)
		)
		(stroke
			(width 0)
			(type solid)
		)
		(fill yes)
		(layer "In2.Cu")
		(net "M_A_DQ<41>")
	)
	(gr_poly
		(pts
			(xy 274.277836 -53.15204) (xy 274.351496 -52.95265) (xy 274.189698 -52.791106) (xy 273.990308 -52.864766)
			(xy 273.959066 -52.896262) (xy 274.24634 -53.183536)
		)
		(stroke
			(width 0)
			(type solid)
		)
		(fill yes)
		(layer "In2.Cu")
		(net "M_A_DQ<45>")
	)
	(gr_poly
		(pts
			(xy 274.282408 -104.84739) (xy 274.208748 -104.648254) (xy 274.177252 -104.616758) (xy 273.889978 -104.904032)
			(xy 273.921474 -104.935528) (xy 274.12061 -105.009188)
		)
		(stroke
			(width 0)
			(type solid)
		)
		(fill yes)
		(layer "In2.Cu")
		(net "M_D_DQ<41>")
	)
	(gr_poly
		(pts
			(xy 274.323556 -55.199026) (xy 274.279106 -55.199026) (xy 274.108926 -55.287926) (xy 274.108926 -55.508906)
			(xy 274.279106 -55.597806) (xy 274.323556 -55.597806)
		)
		(stroke
			(width 0)
			(type solid)
		)
		(fill yes)
		(layer "In2.Cu")
		(net "M_A_DQ<44>")
	)
	(gr_poly
		(pts
			(xy 274.323556 -54.208426) (xy 274.279106 -54.208426) (xy 274.108926 -54.297326) (xy 274.108926 -54.518306)
			(xy 274.279106 -54.607206) (xy 274.323556 -54.607206)
		)
		(stroke
			(width 0)
			(type solid)
		)
		(fill yes)
		(layer "In2.Cu")
		(net "M_A_DQ<44>")
	)
	(gr_poly
		(pts
			(xy 274.360386 -101.987604) (xy 274.32889 -101.956108) (xy 274.1295 -101.882448) (xy 273.967956 -102.044246)
			(xy 274.041616 -102.243636) (xy 274.073112 -102.274878)
		)
		(stroke
			(width 0)
			(type solid)
		)
		(fill yes)
		(layer "In2.Cu")
		(net "M_D_DQ<44>")
	)
	(gr_poly
		(pts
			(xy 274.441158 -51.784758) (xy 274.396708 -51.784758) (xy 274.203668 -51.873658) (xy 274.203668 -52.102258)
			(xy 274.396708 -52.191158) (xy 274.441158 -52.191158)
		)
		(stroke
			(width 0)
			(type solid)
		)
		(fill yes)
		(layer "In2.Cu")
		(net "M_A_DQ<40>")
	)
	(gr_poly
		(pts
			(xy 274.53463 -49.734724) (xy 274.53463 -49.506124) (xy 274.34159 -49.417224) (xy 274.29714 -49.417224)
			(xy 274.29714 -49.823624) (xy 274.34159 -49.823624)
		)
		(stroke
			(width 0)
			(type solid)
		)
		(fill yes)
		(layer "In2.Cu")
		(net "M_A_DQS_DN<14>")
	)
	(gr_poly
		(pts
			(xy 274.53463 -48.744124) (xy 274.53463 -48.515524) (xy 274.34159 -48.426624) (xy 274.29714 -48.426624)
			(xy 274.29714 -48.833024) (xy 274.34159 -48.833024)
		)
		(stroke
			(width 0)
			(type solid)
		)
		(fill yes)
		(layer "In2.Cu")
		(net "M_A_DQS_DN<14>")
	)
	(gr_poly
		(pts
			(xy 274.599908 -102.352856) (xy 274.526248 -102.153466) (xy 274.494752 -102.12197) (xy 274.207478 -102.409244)
			(xy 274.23872 -102.44074) (xy 274.43811 -102.5144)
		)
		(stroke
			(width 0)
			(type solid)
		)
		(fill yes)
		(layer "In2.Cu")
		(net "M_D_DQ<45>")
	)
	(gr_poly
		(pts
			(xy 274.672552 -105.290366) (xy 274.628102 -105.290366) (xy 274.435062 -105.379012) (xy 274.435062 -105.607866)
			(xy 274.628102 -105.696766) (xy 274.672552 -105.696766)
		)
		(stroke
			(width 0)
			(type solid)
		)
		(fill yes)
		(layer "In2.Cu")
		(net "M_D_DQS_DP<14>")
	)
	(gr_poly
		(pts
			(xy 274.743418 -103.78186) (xy 274.711922 -103.750364) (xy 274.512786 -103.676704) (xy 274.350988 -103.838502)
			(xy 274.424648 -104.037638) (xy 274.456144 -104.069134)
		)
		(stroke
			(width 0)
			(type solid)
		)
		(fill yes)
		(layer "In2.Cu")
		(net "M_D_DQ<40>")
	)
	(gr_poly
		(pts
			(xy 274.748244 -50.860198) (xy 274.77974 -50.828702) (xy 274.492466 -50.541428) (xy 274.46097 -50.572924)
			(xy 274.38731 -50.77206) (xy 274.549108 -50.933858)
		)
		(stroke
			(width 0)
			(type solid)
		)
		(fill yes)
		(layer "In2.Cu")
		(net "M_A_DQS_DP<14>")
	)
	(gr_poly
		(pts
			(xy 274.862036 -55.033418) (xy 274.862036 -54.812438) (xy 274.691856 -54.723538) (xy 274.647406 -54.723538)
			(xy 274.647406 -55.122318) (xy 274.691856 -55.122318)
		)
		(stroke
			(width 0)
			(type solid)
		)
		(fill yes)
		(layer "In2.Cu")
		(net "M_A_DQ<45>")
	)
	(gr_poly
		(pts
			(xy 274.869148 -52.102258) (xy 274.869148 -51.873658) (xy 274.676108 -51.784758) (xy 274.631658 -51.784758)
			(xy 274.631658 -52.191158) (xy 274.676108 -52.191158)
		)
		(stroke
			(width 0)
			(type solid)
		)
		(fill yes)
		(layer "In2.Cu")
		(net "M_A_DQ<41>")
	)
	(gr_poly
		(pts
			(xy 274.90928 -53.155088) (xy 274.940776 -53.123846) (xy 274.653248 -52.836318) (xy 274.621752 -52.867814)
			(xy 274.548346 -53.067204) (xy 274.70989 -53.228748)
		)
		(stroke
			(width 0)
			(type solid)
		)
		(fill yes)
		(layer "In2.Cu")
		(net "M_A_DQ<40>")
	)
	(gr_poly
		(pts
			(xy 274.90928 -48.498506) (xy 274.86483 -48.498506) (xy 274.67179 -48.587406) (xy 274.67179 -48.816006)
			(xy 274.86483 -48.904906) (xy 274.90928 -48.904906)
		)
		(stroke
			(width 0)
			(type solid)
		)
		(fill yes)
		(layer "In2.Cu")
		(net "M_A_DQS_DN<5>")
	)
	(gr_poly
		(pts
			(xy 274.945856 -50.662586) (xy 275.019516 -50.463196) (xy 274.857972 -50.301652) (xy 274.658582 -50.375312)
			(xy 274.627086 -50.406554) (xy 274.914614 -50.694082)
		)
		(stroke
			(width 0)
			(type solid)
		)
		(fill yes)
		(layer "In2.Cu")
		(net "M_A_DQS_DN<14>")
	)
	(gr_poly
		(pts
			(xy 274.98294 -104.146858) (xy 274.90928 -103.947722) (xy 274.877784 -103.916226) (xy 274.59051 -104.2035)
			(xy 274.622006 -104.234996) (xy 274.821142 -104.308656)
		)
		(stroke
			(width 0)
			(type solid)
		)
		(fill yes)
		(layer "In2.Cu")
		(net "M_D_DQ<41>")
	)
	(gr_poly
		(pts
			(xy 275.100542 -105.607866) (xy 275.100542 -105.379266) (xy 274.907502 -105.290366) (xy 274.863052 -105.290112)
			(xy 274.863052 -105.696766) (xy 274.907502 -105.696766)
		)
		(stroke
			(width 0)
			(type solid)
		)
		(fill yes)
		(layer "In2.Cu")
		(net "M_D_DQS_DN<14>")
	)
	(gr_poly
		(pts
			(xy 275.106892 -52.957476) (xy 275.180552 -52.758086) (xy 275.018754 -52.596542) (xy 274.819364 -52.670202)
			(xy 274.788122 -52.701698) (xy 275.075396 -52.988972)
		)
		(stroke
			(width 0)
			(type solid)
		)
		(fill yes)
		(layer "In2.Cu")
		(net "M_A_DQ<41>")
	)
	(gr_poly
		(pts
			(xy 275.146516 -53.406802) (xy 275.102066 -53.406802) (xy 274.909026 -53.495702) (xy 274.909026 -53.724302)
			(xy 275.102066 -53.813202) (xy 275.146516 -53.813202)
		)
		(stroke
			(width 0)
			(type solid)
		)
		(fill yes)
		(layer "In2.Cu")
		(net "M_A_DQ<40>")
	)
	(gr_poly
		(pts
			(xy 275.165058 -51.403758) (xy 275.120608 -51.403758) (xy 274.927568 -51.492658) (xy 274.927568 -51.721258)
			(xy 275.120608 -51.810158) (xy 275.165058 -51.810158)
		)
		(stroke
			(width 0)
			(type solid)
		)
		(fill yes)
		(layer "In2.Cu")
		(net "M_A_DQS_DP<14>")
	)
	(gr_poly
		(pts
			(xy 275.182076 -54.714648) (xy 275.137626 -54.714648) (xy 274.967446 -54.803548) (xy 274.967446 -55.024528)
			(xy 275.137626 -55.113428) (xy 275.182076 -55.113428)
		)
		(stroke
			(width 0)
			(type solid)
		)
		(fill yes)
		(layer "In2.Cu")
		(net "M_A_DQ<40>")
	)
	(gr_poly
		(pts
			(xy 275.220684 -100.252784) (xy 275.18233 -100.230432) (xy 274.970494 -100.210874) (xy 274.856194 -100.40874)
			(xy 274.978876 -100.582222) (xy 275.01723 -100.604574)
		)
		(stroke
			(width 0)
			(type solid)
		)
		(fill yes)
		(layer "In2.Cu")
		(net "M_D_DQ<44>")
	)
	(gr_poly
		(pts
			(xy 275.274532 -104.403652) (xy 275.243036 -104.372156) (xy 275.0439 -104.298496) (xy 274.882102 -104.460294)
			(xy 274.955762 -104.65943) (xy 274.987258 -104.690926)
		)
		(stroke
			(width 0)
			(type solid)
		)
		(fill yes)
		(layer "In2.Cu")
		(net "M_D_DQS_DP<14>")
	)
	(gr_poly
		(pts
			(xy 275.336762 -48.816006) (xy 275.336762 -48.587406) (xy 275.143722 -48.498506) (xy 275.099272 -48.498506)
			(xy 275.099272 -48.904906) (xy 275.143722 -48.904906)
		)
		(stroke
			(width 0)
			(type solid)
		)
		(fill yes)
		(layer "In2.Cu")
		(net "M_A_DQS_DP<5>")
	)
	(gr_poly
		(pts
			(xy 275.44395 -103.081328) (xy 275.412454 -103.049832) (xy 275.213318 -102.976172) (xy 275.05152 -103.13797)
			(xy 275.12518 -103.337106) (xy 275.156676 -103.368602)
		)
		(stroke
			(width 0)
			(type solid)
		)
		(fill yes)
		(layer "In2.Cu")
		(net "M_D_DQ<40>")
	)
	(gr_poly
		(pts
			(xy 275.514308 -104.769158) (xy 275.440648 -104.569768) (xy 275.409406 -104.538272) (xy 275.121878 -104.8258)
			(xy 275.153374 -104.857042) (xy 275.352764 -104.930702)
		)
		(stroke
			(width 0)
			(type solid)
		)
		(fill yes)
		(layer "In2.Cu")
		(net "M_D_DQS_DN<14>")
	)
	(gr_poly
		(pts
			(xy 275.53285 -101.791008) (xy 275.4884 -101.791008) (xy 275.29536 -101.879908) (xy 275.29536 -102.108508)
			(xy 275.4884 -102.197408) (xy 275.53285 -102.197408)
		)
		(stroke
			(width 0)
			(type solid)
		)
		(fill yes)
		(layer "In2.Cu")
		(net "M_D_DQ<40>")
	)
	(gr_poly
		(pts
			(xy 275.547328 -100.544122) (xy 275.424646 -100.37064) (xy 275.386292 -100.348288) (xy 275.182838 -100.700332)
			(xy 275.221446 -100.72243) (xy 275.433028 -100.742242)
		)
		(stroke
			(width 0)
			(type solid)
		)
		(fill yes)
		(layer "In2.Cu")
		(net "M_D_DQ<45>")
	)
	(gr_poly
		(pts
			(xy 275.566886 -50.040032) (xy 275.598382 -50.00879) (xy 275.310854 -49.721262) (xy 275.279612 -49.752758)
			(xy 275.205952 -49.952148) (xy 275.367496 -50.113692)
		)
		(stroke
			(width 0)
			(type solid)
		)
		(fill yes)
		(layer "In2.Cu")
		(net "M_A_DQS_DN<5>")
	)
	(gr_poly
		(pts
			(xy 275.574506 -53.622702) (xy 275.574506 -53.394102) (xy 275.381466 -53.305202) (xy 275.337016 -53.305202)
			(xy 275.337016 -53.711602) (xy 275.381466 -53.711602)
		)
		(stroke
			(width 0)
			(type solid)
		)
		(fill yes)
		(layer "In2.Cu")
		(net "M_A_DQ<41>")
	)
	(gr_poly
		(pts
			(xy 275.593048 -51.721258) (xy 275.593048 -51.492658) (xy 275.400008 -51.403758) (xy 275.355558 -51.403758)
			(xy 275.355558 -51.810158) (xy 275.400008 -51.810158)
		)
		(stroke
			(width 0)
			(type solid)
		)
		(fill yes)
		(layer "In2.Cu")
		(net "M_A_DQS_DN<14>")
	)
	(gr_poly
		(pts
			(xy 275.683472 -103.446326) (xy 275.609812 -103.24719) (xy 275.578316 -103.215694) (xy 275.291042 -103.502968)
			(xy 275.322538 -103.534464) (xy 275.521674 -103.608124)
		)
		(stroke
			(width 0)
			(type solid)
		)
		(fill yes)
		(layer "In2.Cu")
		(net "M_D_DQ<41>")
	)
	(gr_poly
		(pts
			(xy 275.683472 -48.349916) (xy 275.639022 -48.349916) (xy 275.445982 -48.438816) (xy 275.445982 -48.667416)
			(xy 275.639022 -48.756316) (xy 275.683472 -48.756316)
		)
		(stroke
			(width 0)
			(type solid)
		)
		(fill yes)
		(layer "In2.Cu")
		(net "M_A_DQ<46>")
	)
	(gr_poly
		(pts
			(xy 275.702776 -52.917598) (xy 275.734272 -52.886102) (xy 275.446998 -52.598828) (xy 275.415502 -52.630324)
			(xy 275.341842 -52.82946) (xy 275.50364 -52.991258)
		)
		(stroke
			(width 0)
			(type solid)
		)
		(fill yes)
		(layer "In2.Cu")
		(net "M_A_DQS_DP<14>")
	)
	(gr_poly
		(pts
			(xy 275.720048 -54.529228) (xy 275.720048 -54.308248) (xy 275.549868 -54.219348) (xy 275.505418 -54.219348)
			(xy 275.505418 -54.618128) (xy 275.549868 -54.618128)
		)
		(stroke
			(width 0)
			(type solid)
		)
		(fill yes)
		(layer "In2.Cu")
		(net "M_A_DQ<41>")
	)
	(gr_poly
		(pts
			(xy 275.764498 -49.84242) (xy 275.838158 -49.643284) (xy 275.67636 -49.481486) (xy 275.477224 -49.555146)
			(xy 275.445728 -49.586642) (xy 275.733002 -49.873916)
		)
		(stroke
			(width 0)
			(type solid)
		)
		(fill yes)
		(layer "In2.Cu")
		(net "M_A_DQS_DP<5>")
	)
	(gr_poly
		(pts
			(xy 275.888958 -50.95113) (xy 275.844508 -50.95113) (xy 275.651468 -51.04003) (xy 275.651468 -51.26863)
			(xy 275.844508 -51.35753) (xy 275.888958 -51.35753)
		)
		(stroke
			(width 0)
			(type solid)
		)
		(fill yes)
		(layer "In2.Cu")
		(net "M_A_DQS_DN<5>")
	)
	(gr_poly
		(pts
			(xy 275.900388 -52.719986) (xy 275.974048 -52.520596) (xy 275.812504 -52.359052) (xy 275.613114 -52.432712)
			(xy 275.581618 -52.463954) (xy 275.869146 -52.751482)
		)
		(stroke
			(width 0)
			(type solid)
		)
		(fill yes)
		(layer "In2.Cu")
		(net "M_A_DQS_DN<14>")
	)
	(gr_poly
		(pts
			(xy 275.931884 -99.386136) (xy 275.909532 -99.347782) (xy 275.74748 -99.244912) (xy 275.556218 -99.355402)
			(xy 275.564346 -99.547172) (xy 275.586444 -99.585526)
		)
		(stroke
			(width 0)
			(type solid)
		)
		(fill yes)
		(layer "In2.Cu")
		(net "M_D_DQ<44>")
	)
	(gr_poly
		(pts
			(xy 275.960332 -102.108508) (xy 275.960332 -101.879908) (xy 275.767292 -101.791008) (xy 275.722842 -101.791008)
			(xy 275.722842 -102.197408) (xy 275.767292 -102.197408)
		)
		(stroke
			(width 0)
			(type solid)
		)
		(fill yes)
		(layer "In2.Cu")
		(net "M_D_DQ<41>")
	)
	(gr_poly
		(pts
			(xy 275.975064 -103.70312) (xy 275.943568 -103.671624) (xy 275.744432 -103.597964) (xy 275.582634 -103.759762)
			(xy 275.656294 -103.958898) (xy 275.68779 -103.990394)
		)
		(stroke
			(width 0)
			(type solid)
		)
		(fill yes)
		(layer "In2.Cu")
		(net "M_D_DQS_DP<14>")
	)
	(gr_poly
		(pts
			(xy 276.040596 -54.212998) (xy 275.996146 -54.212998) (xy 275.825966 -54.301898) (xy 275.825966 -54.522878)
			(xy 275.996146 -54.611778) (xy 276.040596 -54.611778)
		)
		(stroke
			(width 0)
			(type solid)
		)
		(fill yes)
		(layer "In2.Cu")
		(net "M_A_DQS_DP<14>")
	)
	(gr_poly
		(pts
			(xy 276.111462 -48.667416) (xy 276.111462 -48.438816) (xy 275.918422 -48.349916) (xy 275.873972 -48.349916)
			(xy 275.873972 -48.756316) (xy 275.918422 -48.756316)
		)
		(stroke
			(width 0)
			(type solid)
		)
		(fill yes)
		(layer "In2.Cu")
		(net "M_A_DQ<47>")
	)
	(gr_poly
		(pts
			(xy 276.116542 -56.4388) (xy 276.075394 -56.251094) (xy 276.046692 -56.217058) (xy 275.741384 -56.473598)
			(xy 275.769832 -56.507634) (xy 275.947378 -56.580786)
		)
		(stroke
			(width 0)
			(type solid)
		)
		(fill yes)
		(layer "In2.Cu")
		(net "M_A_DQ<41>")
	)
	(gr_poly
		(pts
			(xy 276.142958 -100.53447) (xy 276.10435 -100.512372) (xy 275.892768 -100.49256) (xy 275.778468 -100.69068)
			(xy 275.90115 -100.864162) (xy 275.939504 -100.886514)
		)
		(stroke
			(width 0)
			(type solid)
		)
		(fill yes)
		(layer "In2.Cu")
		(net "M_D_DQ<40>")
	)
	(gr_poly
		(pts
			(xy 276.21484 -104.068626) (xy 276.14118 -103.869236) (xy 276.109938 -103.83774) (xy 275.82241 -104.125268)
			(xy 275.853906 -104.15651) (xy 276.053296 -104.23017)
		)
		(stroke
			(width 0)
			(type solid)
		)
		(fill yes)
		(layer "In2.Cu")
		(net "M_D_DQS_DN<14>")
	)
	(gr_poly
		(pts
			(xy 276.315678 -49.765458) (xy 276.347174 -49.733962) (xy 276.0599 -49.446688) (xy 276.028404 -49.478184)
			(xy 275.954744 -49.67732) (xy 276.116542 -49.839118)
		)
		(stroke
			(width 0)
			(type solid)
		)
		(fill yes)
		(layer "In2.Cu")
		(net "M_A_DQ<46>")
	)
	(gr_poly
		(pts
			(xy 276.316948 -51.26863) (xy 276.316948 -51.04003) (xy 276.123908 -50.95113) (xy 276.079458 -50.95113)
			(xy 276.079458 -51.35753) (xy 276.123908 -51.35753)
		)
		(stroke
			(width 0)
			(type solid)
		)
		(fill yes)
		(layer "In2.Cu")
		(net "M_A_DQS_DP<5>")
	)
	(gr_poly
		(pts
			(xy 276.32406 -102.70998) (xy 276.27961 -102.70998) (xy 276.086824 -102.79888) (xy 276.086824 -103.027734)
			(xy 276.27961 -103.11638) (xy 276.32406 -103.11638)
		)
		(stroke
			(width 0)
			(type solid)
		)
		(fill yes)
		(layer "In2.Cu")
		(net "M_D_DQS_DP<14>")
	)
	(gr_poly
		(pts
			(xy 276.332442 -98.299524) (xy 276.287992 -98.299778) (xy 276.118066 -98.388424) (xy 276.117812 -98.609404)
			(xy 276.287992 -98.69805) (xy 276.332442 -98.69805)
		)
		(stroke
			(width 0)
			(type solid)
		)
		(fill yes)
		(layer "In2.Cu")
		(net "M_D_DQ<44>")
	)
	(gr_poly
		(pts
			(xy 276.469602 -100.826062) (xy 276.34692 -100.65258) (xy 276.308312 -100.630228) (xy 276.105112 -100.982018)
			(xy 276.143466 -101.00437) (xy 276.355048 -101.023928)
		)
		(stroke
			(width 0)
			(type solid)
		)
		(fill yes)
		(layer "In2.Cu")
		(net "M_D_DQ<41>")
	)
	(gr_poly
		(pts
			(xy 276.505924 -105.303574) (xy 276.461474 -105.303574) (xy 276.268434 -105.392474) (xy 276.268434 -105.621074)
			(xy 276.461474 -105.709974) (xy 276.505924 -105.709974)
		)
		(stroke
			(width 0)
			(type solid)
		)
		(fill yes)
		(layer "In2.Cu")
		(net "M_D_DQS_DN<5>")
	)
	(gr_poly
		(pts
			(xy 276.50948 -56.785764) (xy 276.487128 -56.74741) (xy 276.325076 -56.644286) (xy 276.133814 -56.754776)
			(xy 276.141688 -56.9468) (xy 276.16404 -56.985154)
		)
		(stroke
			(width 0)
			(type solid)
		)
		(fill yes)
		(layer "In2.Cu")
		(net "M_A_DQS_DN<5>")
	)
	(gr_poly
		(pts
			(xy 276.511004 -48.238156) (xy 276.466554 -48.238156) (xy 276.273514 -48.327056) (xy 276.273514 -48.555656)
			(xy 276.466554 -48.644556) (xy 276.511004 -48.644556)
		)
		(stroke
			(width 0)
			(type solid)
		)
		(fill yes)
		(layer "In2.Cu")
		(net "M_A_DQ<42>")
	)
	(gr_poly
		(pts
			(xy 276.51329 -49.567846) (xy 276.58695 -49.368456) (xy 276.425406 -49.206912) (xy 276.226016 -49.280572)
			(xy 276.19452 -49.311814) (xy 276.482048 -49.599342)
		)
		(stroke
			(width 0)
			(type solid)
		)
		(fill yes)
		(layer "In2.Cu")
		(net "M_A_DQ<47>")
	)
	(gr_poly
		(pts
			(xy 276.55901 -103.11638) (xy 276.75205 -103.02748) (xy 276.75205 -102.79888) (xy 276.55901 -102.70998)
			(xy 276.514814 -102.70998) (xy 276.514814 -103.116634)
		)
		(stroke
			(width 0)
			(type solid)
		)
		(fill yes)
		(layer "In2.Cu")
		(net "M_D_DQS_DN<14>")
	)
	(gr_poly
		(pts
			(xy 276.563582 -99.633786) (xy 276.555454 -99.441762) (xy 276.53361 -99.403408) (xy 276.187916 -99.602798)
			(xy 276.210268 -99.641152) (xy 276.37232 -99.744022)
		)
		(stroke
			(width 0)
			(type solid)
		)
		(fill yes)
		(layer "In2.Cu")
		(net "M_D_DQ<45>")
	)
	(gr_poly
		(pts
			(xy 276.578568 -54.033928) (xy 276.578568 -53.812948) (xy 276.408388 -53.724048) (xy 276.363938 -53.724048)
			(xy 276.363938 -54.122828) (xy 276.408388 -54.122828)
		)
		(stroke
			(width 0)
			(type solid)
		)
		(fill yes)
		(layer "In2.Cu")
		(net "M_A_DQS_DN<14>")
	)
	(gr_poly
		(pts
			(xy 276.612604 -50.572924) (xy 276.568154 -50.572924) (xy 276.375114 -50.661824) (xy 276.375114 -50.890424)
			(xy 276.568154 -50.979324) (xy 276.612604 -50.979324)
		)
		(stroke
			(width 0)
			(type solid)
		)
		(fill yes)
		(layer "In2.Cu")
		(net "M_A_DQ<46>")
	)
	(gr_poly
		(pts
			(xy 276.692868 -99.186238) (xy 276.863048 -99.097338) (xy 276.863048 -98.876612) (xy 276.692868 -98.787712)
			(xy 276.648672 -98.787458) (xy 276.648418 -99.186492)
		)
		(stroke
			(width 0)
			(type solid)
		)
		(fill yes)
		(layer "In2.Cu")
		(net "M_D_DQ<45>")
	)
	(gr_poly
		(pts
			(xy 276.754082 -52.937664) (xy 276.785578 -52.906168) (xy 276.498304 -52.618894) (xy 276.466808 -52.65039)
			(xy 276.393148 -52.849526) (xy 276.554946 -53.011324)
		)
		(stroke
			(width 0)
			(type solid)
		)
		(fill yes)
		(layer "In2.Cu")
		(net "M_A_DQS_DN<5>")
	)
	(gr_poly
		(pts
			(xy 276.807676 -97.880932) (xy 276.782022 -97.844356) (xy 276.611842 -97.755964) (xy 276.43074 -97.88271)
			(xy 276.455632 -98.072956) (xy 276.481032 -98.109278)
		)
		(stroke
			(width 0)
			(type solid)
		)
		(fill yes)
		(layer "In2.Cu")
		(net "M_D_DQ<44>")
	)
	(gr_poly
		(pts
			(xy 276.89556 -101.317552) (xy 276.857206 -101.2952) (xy 276.645624 -101.275642) (xy 276.531324 -101.473762)
			(xy 276.654006 -101.647244) (xy 276.692614 -101.669342)
		)
		(stroke
			(width 0)
			(type solid)
		)
		(fill yes)
		(layer "In2.Cu")
		(net "M_D_DQS_DP<14>")
	)
	(gr_poly
		(pts
			(xy 276.899116 -55.705248) (xy 276.854666 -55.705248) (xy 276.684486 -55.794148) (xy 276.684486 -56.015128)
			(xy 276.854666 -56.104028) (xy 276.899116 -56.104028)
		)
		(stroke
			(width 0)
			(type solid)
		)
		(fill yes)
		(layer "In2.Cu")
		(net "M_A_DQS_DN<5>")
	)
	(gr_poly
		(pts
			(xy 276.933914 -105.621074) (xy 276.933914 -105.392474) (xy 276.740874 -105.303574) (xy 276.696424 -105.303574)
			(xy 276.696424 -105.709974) (xy 276.740874 -105.709974)
		)
		(stroke
			(width 0)
			(type solid)
		)
		(fill yes)
		(layer "In2.Cu")
		(net "M_D_DQS_DP<5>")
	)
	(gr_poly
		(pts
			(xy 276.938994 -48.555656) (xy 276.938994 -48.327056) (xy 276.745954 -48.238156) (xy 276.701504 -48.238156)
			(xy 276.701504 -48.644556) (xy 276.745954 -48.644556)
		)
		(stroke
			(width 0)
			(type solid)
		)
		(fill yes)
		(layer "In2.Cu")
		(net "M_A_DQ<43>")
	)
	(gr_poly
		(pts
			(xy 276.951694 -52.740052) (xy 277.025354 -52.540662) (xy 276.86381 -52.379118) (xy 276.66442 -52.452778)
			(xy 276.632924 -52.48402) (xy 276.920452 -52.771548)
		)
		(stroke
			(width 0)
			(type solid)
		)
		(fill yes)
		(layer "In2.Cu")
		(net "M_A_DQS_DP<5>")
	)
	(gr_poly
		(pts
			(xy 276.973284 -52.133754) (xy 277.00478 -52.102258) (xy 276.717506 -51.814984) (xy 276.68601 -51.84648)
			(xy 276.61235 -52.045616) (xy 276.774148 -52.207414)
		)
		(stroke
			(width 0)
			(type solid)
		)
		(fill yes)
		(layer "In2.Cu")
		(net "M_A_DQ<46>")
	)
	(gr_poly
		(pts
			(xy 277.016718 -104.100376) (xy 276.985222 -104.06888) (xy 276.785832 -103.99522) (xy 276.624288 -104.157018)
			(xy 276.697948 -104.356408) (xy 276.72919 -104.38765)
		)
		(stroke
			(width 0)
			(type solid)
		)
		(fill yes)
		(layer "In2.Cu")
		(net "M_D_DQS_DN<5>")
	)
	(gr_poly
		(pts
			(xy 277.039324 -53.709824) (xy 276.994874 -53.709824) (xy 276.801834 -53.798724) (xy 276.801834 -54.027324)
			(xy 276.994874 -54.116224) (xy 277.039324 -54.116224)
		)
		(stroke
			(width 0)
			(type solid)
		)
		(fill yes)
		(layer "In2.Cu")
		(net "M_A_DQS_DN<5>")
	)
	(gr_poly
		(pts
			(xy 277.040594 -51.373024) (xy 277.040594 -51.144424) (xy 276.847554 -51.055524) (xy 276.803104 -51.055524)
			(xy 276.803104 -51.461924) (xy 276.847554 -51.461924)
		)
		(stroke
			(width 0)
			(type solid)
		)
		(fill yes)
		(layer "In2.Cu")
		(net "M_A_DQ<47>")
	)
	(gr_poly
		(pts
			(xy 277.1394 -57.036716) (xy 277.131272 -56.844946) (xy 277.109428 -56.806592) (xy 276.763734 -57.005982)
			(xy 276.786086 -57.044336) (xy 276.948138 -57.147206)
		)
		(stroke
			(width 0)
			(type solid)
		)
		(fill yes)
		(layer "In2.Cu")
		(net "M_A_DQS_DP<5>")
	)
	(gr_poly
		(pts
			(xy 277.163022 -103.27259) (xy 277.118572 -103.27259) (xy 276.925532 -103.36149) (xy 276.925532 -103.59009)
			(xy 277.118572 -103.67899) (xy 277.163022 -103.67899)
		)
		(stroke
			(width 0)
			(type solid)
		)
		(fill yes)
		(layer "In2.Cu")
		(net "M_D_DQS_DN<5>")
	)
	(gr_poly
		(pts
			(xy 277.183596 -98.789998) (xy 277.139146 -98.789998) (xy 276.968966 -98.878898) (xy 276.968966 -99.099878)
			(xy 277.139146 -99.188778) (xy 277.183596 -99.188778)
		)
		(stroke
			(width 0)
			(type solid)
		)
		(fill yes)
		(layer "In2.Cu")
		(net "M_D_DQ<40>")
	)
	(gr_poly
		(pts
			(xy 277.22195 -101.608382) (xy 277.099268 -101.4349) (xy 277.06066 -101.412802) (xy 276.857714 -101.764592)
			(xy 276.896068 -101.786944) (xy 277.10765 -101.806502)
		)
		(stroke
			(width 0)
			(type solid)
		)
		(fill yes)
		(layer "In2.Cu")
		(net "M_D_DQS_DN<14>")
	)
	(gr_poly
		(pts
			(xy 277.256494 -104.465882) (xy 277.182834 -104.266492) (xy 277.151338 -104.234996) (xy 276.864064 -104.522524)
			(xy 276.895306 -104.553766) (xy 277.094696 -104.627426)
		)
		(stroke
			(width 0)
			(type solid)
		)
		(fill yes)
		(layer "In2.Cu")
		(net "M_D_DQS_DP<5>")
	)
	(gr_poly
		(pts
			(xy 277.266908 -56.588406) (xy 277.437088 -56.499506) (xy 277.437088 -56.278526) (xy 277.266908 -56.189626)
			(xy 277.222712 -56.189626) (xy 277.222458 -56.58866)
		)
		(stroke
			(width 0)
			(type solid)
		)
		(fill yes)
		(layer "In2.Cu")
		(net "M_A_DQS_DP<5>")
	)
	(gr_poly
		(pts
			(xy 277.274274 -49.699926) (xy 277.30577 -49.668684) (xy 277.018242 -49.381156) (xy 276.987 -49.412652)
			(xy 276.91334 -49.612042) (xy 277.074884 -49.773586)
		)
		(stroke
			(width 0)
			(type solid)
		)
		(fill yes)
		(layer "In2.Cu")
		(net "M_A_DQ<42>")
	)
	(gr_poly
		(pts
			(xy 277.422356 -100.128324) (xy 277.414228 -99.936554) (xy 277.39213 -99.897946) (xy 277.04669 -100.09759)
			(xy 277.069042 -100.135944) (xy 277.231094 -100.238814)
		)
		(stroke
			(width 0)
			(type solid)
		)
		(fill yes)
		(layer "In2.Cu")
		(net "M_D_DQ<41>")
	)
	(gr_poly
		(pts
			(xy 277.437342 -55.519828) (xy 277.437342 -55.298848) (xy 277.267162 -55.209948) (xy 277.222712 -55.209948)
			(xy 277.222712 -55.608728) (xy 277.267162 -55.608728)
		)
		(stroke
			(width 0)
			(type solid)
		)
		(fill yes)
		(layer "In2.Cu")
		(net "M_A_DQS_DP<5>")
	)
	(gr_poly
		(pts
			(xy 277.467314 -54.027324) (xy 277.467314 -53.798724) (xy 277.274274 -53.709824) (xy 277.229824 -53.709824)
			(xy 277.229824 -54.116224) (xy 277.274274 -54.116224)
		)
		(stroke
			(width 0)
			(type solid)
		)
		(fill yes)
		(layer "In2.Cu")
		(net "M_A_DQS_DP<5>")
	)
	(gr_poly
		(pts
			(xy 277.471886 -49.502314) (xy 277.545546 -49.303178) (xy 277.383748 -49.14138) (xy 277.184612 -49.21504)
			(xy 277.153116 -49.246536) (xy 277.44039 -49.53381)
		)
		(stroke
			(width 0)
			(type solid)
		)
		(fill yes)
		(layer "In2.Cu")
		(net "M_A_DQ<43>")
	)
	(gr_poly
		(pts
			(xy 277.487888 -102.407466) (xy 277.456392 -102.37597) (xy 277.257002 -102.30231) (xy 277.095458 -102.463854)
			(xy 277.169118 -102.663244) (xy 277.20036 -102.69474)
		)
		(stroke
			(width 0)
			(type solid)
		)
		(fill yes)
		(layer "In2.Cu")
		(net "M_D_DQS_DN<5>")
	)
	(gr_poly
		(pts
			(xy 277.531068 -98.615754) (xy 277.531068 -98.394774) (xy 277.360888 -98.305874) (xy 277.316438 -98.305874)
			(xy 277.316438 -98.704654) (xy 277.360888 -98.704654)
		)
		(stroke
			(width 0)
			(type solid)
		)
		(fill yes)
		(layer "In2.Cu")
		(net "M_D_DQ<40>")
	)
	(gr_poly
		(pts
			(xy 277.591012 -103.59009) (xy 277.591012 -103.36149) (xy 277.397972 -103.27259) (xy 277.353522 -103.27259)
			(xy 277.353522 -103.67899) (xy 277.397972 -103.67899)
		)
		(stroke
			(width 0)
			(type solid)
		)
		(fill yes)
		(layer "In2.Cu")
		(net "M_D_DQS_DP<5>")
	)
	(gr_poly
		(pts
			(xy 277.6093 -97.243138) (xy 277.57374 -97.216468) (xy 277.384002 -97.185988) (xy 277.251922 -97.36328)
			(xy 277.335234 -97.536254) (xy 277.370794 -97.56267)
		)
		(stroke
			(width 0)
			(type solid)
		)
		(fill yes)
		(layer "In2.Cu")
		(net "M_D_DQ<40>")
	)
	(gr_poly
		(pts
			(xy 277.61692 -52.380642) (xy 277.69058 -52.181252) (xy 277.529036 -52.019708) (xy 277.329646 -52.093368)
			(xy 277.29815 -52.12461) (xy 277.585678 -52.412138)
		)
		(stroke
			(width 0)
			(type solid)
		)
		(fill yes)
		(layer "In2.Cu")
		(net "M_A_DQ<47>")
	)
	(gr_poly
		(pts
			(xy 277.64232 -100.370386) (xy 277.619968 -100.332032) (xy 277.457916 -100.229162) (xy 277.266654 -100.339652)
			(xy 277.274782 -100.531422) (xy 277.29688 -100.57003)
		)
		(stroke
			(width 0)
			(type solid)
		)
		(fill yes)
		(layer "In2.Cu")
		(net "M_D_DQS_DP<14>")
	)
	(gr_poly
		(pts
			(xy 277.673816 -52.834286) (xy 277.705312 -52.80279) (xy 277.418038 -52.515516) (xy 277.386542 -52.547012)
			(xy 277.312882 -52.746148) (xy 277.47468 -52.907946)
		)
		(stroke
			(width 0)
			(type solid)
		)
		(fill yes)
		(layer "In2.Cu")
		(net "M_A_DQ<46>")
	)
	(gr_poly
		(pts
			(xy 277.699216 -105.292652) (xy 277.654766 -105.292906) (xy 277.461726 -105.381806) (xy 277.461726 -105.610152)
			(xy 277.654766 -105.699052) (xy 277.699216 -105.699306)
		)
		(stroke
			(width 0)
			(type solid)
		)
		(fill yes)
		(layer "In2.Cu")
		(net "M_D_DQ<46>")
	)
	(gr_poly
		(pts
			(xy 277.76551 -50.185828) (xy 277.72106 -50.185828) (xy 277.52802 -50.274728) (xy 277.52802 -50.503328)
			(xy 277.72106 -50.592228) (xy 277.76551 -50.592228)
		)
		(stroke
			(width 0)
			(type solid)
		)
		(fill yes)
		(layer "In2.Cu")
		(net "M_A_DQ<42>")
	)
	(gr_poly
		(pts
			(xy 277.890478 -54.222142) (xy 277.846028 -54.222142) (xy 277.652988 -54.311042) (xy 277.652988 -54.539642)
			(xy 277.846028 -54.628542) (xy 277.890478 -54.628542)
		)
		(stroke
			(width 0)
			(type solid)
		)
		(fill yes)
		(layer "In2.Cu")
		(net "M_A_DQ<46>")
	)
	(gr_poly
		(pts
			(xy 277.890478 -53.231542) (xy 277.846028 -53.231542) (xy 277.652988 -53.320442) (xy 277.652988 -53.549042)
			(xy 277.846028 -53.637942) (xy 277.890478 -53.637942)
		)
		(stroke
			(width 0)
			(type solid)
		)
		(fill yes)
		(layer "In2.Cu")
		(net "M_A_DQ<46>")
	)
	(gr_poly
		(pts
			(xy 277.933404 -105.699052) (xy 278.126444 -105.610152) (xy 278.126444 -105.381806) (xy 277.933404 -105.292906)
			(xy 277.889208 -105.292652) (xy 277.889208 -105.699306)
		)
		(stroke
			(width 0)
			(type solid)
		)
		(fill yes)
		(layer "In2.Cu")
		(net "M_D_DQ<47>")
	)
	(gr_poly
		(pts
			(xy 278.042116 -99.297744) (xy 277.997666 -99.297744) (xy 277.827486 -99.386644) (xy 277.827486 -99.607624)
			(xy 277.997666 -99.696524) (xy 278.042116 -99.696524)
		)
		(stroke
			(width 0)
			(type solid)
		)
		(fill yes)
		(layer "In2.Cu")
		(net "M_D_DQS_DP<14>")
	)
	(gr_poly
		(pts
			(xy 278.042116 -98.307144) (xy 277.997666 -98.307144) (xy 277.827486 -98.396044) (xy 277.827486 -98.617024)
			(xy 277.997666 -98.705924) (xy 278.042116 -98.705924)
		)
		(stroke
			(width 0)
			(type solid)
		)
		(fill yes)
		(layer "In2.Cu")
		(net "M_D_DQS_DP<14>")
	)
	(gr_poly
		(pts
			(xy 278.076406 -57.111138) (xy 278.11476 -56.89346) (xy 277.962614 -56.776366) (xy 277.918672 -56.768746)
			(xy 277.849584 -57.16143) (xy 277.893272 -57.16905)
		)
		(stroke
			(width 0)
			(type solid)
		)
		(fill yes)
		(layer "In2.Cu")
		(net "M_A_DQ<47>")
	)
	(gr_poly
		(pts
			(xy 278.1935 -50.630328) (xy 278.1935 -50.401728) (xy 278.00046 -50.312828) (xy 277.95601 -50.312828)
			(xy 277.95601 -50.719228) (xy 278.00046 -50.719228)
		)
		(stroke
			(width 0)
			(type solid)
		)
		(fill yes)
		(layer "In2.Cu")
		(net "M_A_DQ<43>")
	)
	(gr_poly
		(pts
			(xy 278.295862 -56.015128) (xy 278.295862 -55.794148) (xy 278.125682 -55.705248) (xy 278.081232 -55.705248)
			(xy 278.081232 -56.104028) (xy 278.125682 -56.104028)
		)
		(stroke
			(width 0)
			(type solid)
		)
		(fill yes)
		(layer "In2.Cu")
		(net "M_A_DQ<47>")
	)
	(gr_poly
		(pts
			(xy 278.318468 -54.895242) (xy 278.318468 -54.666642) (xy 278.125428 -54.577742) (xy 278.080978 -54.577742)
			(xy 278.080978 -54.984142) (xy 278.125428 -54.984142)
		)
		(stroke
			(width 0)
			(type solid)
		)
		(fill yes)
		(layer "In2.Cu")
		(net "M_A_DQ<47>")
	)
	(gr_poly
		(pts
			(xy 278.318468 -53.904642) (xy 278.318468 -53.676042) (xy 278.125428 -53.587142) (xy 278.080978 -53.587142)
			(xy 278.080978 -53.993542) (xy 278.125428 -53.993542)
		)
		(stroke
			(width 0)
			(type solid)
		)
		(fill yes)
		(layer "In2.Cu")
		(net "M_A_DQ<47>")
	)
	(gr_poly
		(pts
			(xy 278.390604 -51.965606) (xy 278.4221 -51.93411) (xy 278.134826 -51.646836) (xy 278.10333 -51.678332)
			(xy 278.02967 -51.877468) (xy 278.191468 -52.039266)
		)
		(stroke
			(width 0)
			(type solid)
		)
		(fill yes)
		(layer "In2.Cu")
		(net "M_A_DQ<42>")
	)
	(gr_poly
		(pts
			(xy 278.409654 -104.305608) (xy 278.378158 -104.274366) (xy 278.178768 -104.200706) (xy 278.017224 -104.36225)
			(xy 278.090884 -104.56164) (xy 278.122126 -104.593136)
		)
		(stroke
			(width 0)
			(type solid)
		)
		(fill yes)
		(layer "In2.Cu")
		(net "M_D_DQ<46>")
	)
	(gr_poly
		(pts
			(xy 278.487124 -101.391974) (xy 278.442674 -101.391974) (xy 278.249634 -101.480874) (xy 278.249634 -101.709474)
			(xy 278.442674 -101.798374) (xy 278.487124 -101.798374)
		)
		(stroke
			(width 0)
			(type solid)
		)
		(fill yes)
		(layer "In2.Cu")
		(net "M_D_DQS_DN<5>")
	)
	(gr_poly
		(pts
			(xy 278.529796 -100.289106) (xy 278.426926 -100.127054) (xy 278.388572 -100.104702) (xy 278.188928 -100.450142)
			(xy 278.227536 -100.47224) (xy 278.419306 -100.480368)
		)
		(stroke
			(width 0)
			(type solid)
		)
		(fill yes)
		(layer "In2.Cu")
		(net "M_D_DQS_DN<14>")
	)
	(gr_poly
		(pts
			(xy 278.580342 -99.099878) (xy 278.580342 -98.878898) (xy 278.410162 -98.789998) (xy 278.365712 -98.789998)
			(xy 278.365712 -99.188778) (xy 278.410162 -99.188778)
		)
		(stroke
			(width 0)
			(type solid)
		)
		(fill yes)
		(layer "In2.Cu")
		(net "M_D_DQS_DN<14>")
	)
	(gr_poly
		(pts
			(xy 278.580342 -98.109278) (xy 278.580342 -97.888298) (xy 278.410162 -97.799398) (xy 278.365712 -97.799398)
			(xy 278.365712 -98.198178) (xy 278.410162 -98.198178)
		)
		(stroke
			(width 0)
			(type solid)
		)
		(fill yes)
		(layer "In2.Cu")
		(net "M_D_DQS_DN<14>")
	)
	(gr_poly
		(pts
			(xy 278.590502 -51.769518) (xy 278.664162 -51.570382) (xy 278.502364 -51.408584) (xy 278.303228 -51.482244)
			(xy 278.271732 -51.51374) (xy 278.559006 -51.801014)
		)
		(stroke
			(width 0)
			(type solid)
		)
		(fill yes)
		(layer "In2.Cu")
		(net "M_A_DQ<43>")
	)
	(gr_poly
		(pts
			(xy 278.59609 -102.350316) (xy 278.52243 -102.150926) (xy 278.490934 -102.11943) (xy 278.20366 -102.406704)
			(xy 278.235156 -102.4382) (xy 278.434546 -102.51186)
		)
		(stroke
			(width 0)
			(type solid)
		)
		(fill yes)
		(layer "In2.Cu")
		(net "M_D_DQS_DP<5>")
	)
	(gr_poly
		(pts
			(xy 278.616156 -55.711344) (xy 278.571706 -55.711344) (xy 278.401526 -55.800244) (xy 278.401526 -56.021224)
			(xy 278.571706 -56.110124) (xy 278.616156 -56.110124)
		)
		(stroke
			(width 0)
			(type solid)
		)
		(fill yes)
		(layer "In2.Cu")
		(net "M_A_DQ<42>")
	)
	(gr_poly
		(pts
			(xy 278.616664 -54.213506) (xy 278.572214 -54.213506) (xy 278.379174 -54.302406) (xy 278.379174 -54.531006)
			(xy 278.572214 -54.619906) (xy 278.616664 -54.619906)
		)
		(stroke
			(width 0)
			(type solid)
		)
		(fill yes)
		(layer "In2.Cu")
		(net "M_A_DQ<42>")
	)
	(gr_poly
		(pts
			(xy 278.616664 -53.222906) (xy 278.572214 -53.222906) (xy 278.379174 -53.311806) (xy 278.379174 -53.540406)
			(xy 278.572214 -53.629306) (xy 278.616664 -53.629306)
		)
		(stroke
			(width 0)
			(type solid)
		)
		(fill yes)
		(layer "In2.Cu")
		(net "M_A_DQ<42>")
	)
	(gr_poly
		(pts
			(xy 278.648922 -104.67086) (xy 278.575262 -104.47147) (xy 278.54402 -104.439974) (xy 278.256492 -104.727502)
			(xy 278.287988 -104.758744) (xy 278.487378 -104.832404)
		)
		(stroke
			(width 0)
			(type solid)
		)
		(fill yes)
		(layer "In2.Cu")
		(net "M_D_DQ<47>")
	)
	(gr_poly
		(pts
			(xy 278.896318 -100.722176) (xy 278.864822 -100.69068) (xy 278.665432 -100.61702) (xy 278.503888 -100.778818)
			(xy 278.577548 -100.978208) (xy 278.60879 -101.00945)
		)
		(stroke
			(width 0)
			(type solid)
		)
		(fill yes)
		(layer "In2.Cu")
		(net "M_D_DQS_DN<5>")
	)
	(gr_poly
		(pts
			(xy 278.927306 -100.295202) (xy 278.966676 -100.275136) (xy 278.781002 -99.91344) (xy 278.741378 -99.93376)
			(xy 278.610314 -100.101146) (xy 278.714962 -100.304346)
		)
		(stroke
			(width 0)
			(type solid)
		)
		(fill yes)
		(layer "In2.Cu")
		(net "M_D_DQS_DN<5>")
	)
	(gr_poly
		(pts
			(xy 279.036526 -105.141776) (xy 278.992076 -105.141776) (xy 278.799036 -105.230676) (xy 278.799036 -105.459276)
			(xy 278.992076 -105.548176) (xy 279.036526 -105.548176)
		)
		(stroke
			(width 0)
			(type solid)
		)
		(fill yes)
		(layer "In2.Cu")
		(net "M_D_DQ<42>")
	)
	(gr_poly
		(pts
			(xy 279.044654 -54.531006) (xy 279.044654 -54.302406) (xy 278.851614 -54.213506) (xy 278.807164 -54.213506)
			(xy 278.807164 -54.619906) (xy 278.851614 -54.619906)
		)
		(stroke
			(width 0)
			(type solid)
		)
		(fill yes)
		(layer "In2.Cu")
		(net "M_A_DQ<43>")
	)
	(gr_poly
		(pts
			(xy 279.044654 -53.540406) (xy 279.044654 -53.311806) (xy 278.851614 -53.222906) (xy 278.807164 -53.222906)
			(xy 278.807164 -53.629306) (xy 278.851614 -53.629306)
		)
		(stroke
			(width 0)
			(type solid)
		)
		(fill yes)
		(layer "In2.Cu")
		(net "M_A_DQ<43>")
	)
	(gr_poly
		(pts
			(xy 279.046432 -102.76713) (xy 279.001982 -102.76713) (xy 278.808942 -102.85603) (xy 278.808942 -103.08463)
			(xy 279.001982 -103.17353) (xy 279.046432 -103.17353)
		)
		(stroke
			(width 0)
			(type solid)
		)
		(fill yes)
		(layer "In2.Cu")
		(net "M_D_DQ<46>")
	)
	(gr_poly
		(pts
			(xy 279.09139 -97.800668) (xy 279.04694 -97.800668) (xy 278.87676 -97.889568) (xy 278.87676 -98.110548)
			(xy 279.04694 -98.199448) (xy 279.09139 -98.199448)
		)
		(stroke
			(width 0)
			(type solid)
		)
		(fill yes)
		(layer "In2.Cu")
		(net "M_D_DQ<46>")
	)
	(gr_poly
		(pts
			(xy 279.136094 -101.087682) (xy 279.062434 -100.888292) (xy 279.030938 -100.856796) (xy 278.743664 -101.144324)
			(xy 278.774906 -101.175566) (xy 278.974296 -101.249226)
		)
		(stroke
			(width 0)
			(type solid)
		)
		(fill yes)
		(layer "In2.Cu")
		(net "M_D_DQS_DP<5>")
	)
	(gr_poly
		(pts
			(xy 279.144476 -50.056034) (xy 279.175972 -50.024792) (xy 278.888444 -49.737264) (xy 278.857202 -49.76876)
			(xy 278.783542 -49.96815) (xy 278.945086 -50.129694)
		)
		(stroke
			(width 0)
			(type solid)
		)
		(fill yes)
		(layer "In2.Cu")
		(net "M_A_DQ<52>")
	)
	(gr_poly
		(pts
			(xy 279.154382 -56.504078) (xy 279.154382 -56.283098) (xy 278.984202 -56.194198) (xy 278.939752 -56.194198)
			(xy 278.939752 -56.592978) (xy 278.984202 -56.592978)
		)
		(stroke
			(width 0)
			(type solid)
		)
		(fill yes)
		(layer "In2.Cu")
		(net "M_A_DQ<43>")
	)
	(gr_poly
		(pts
			(xy 279.154382 -55.513478) (xy 279.154382 -55.292498) (xy 278.984202 -55.203598) (xy 278.939752 -55.203598)
			(xy 278.939752 -55.602378) (xy 278.984202 -55.602378)
		)
		(stroke
			(width 0)
			(type solid)
		)
		(fill yes)
		(layer "In2.Cu")
		(net "M_A_DQ<43>")
	)
	(gr_poly
		(pts
			(xy 279.243536 -50.531014) (xy 279.199086 -50.531014) (xy 279.006046 -50.619914) (xy 279.006046 -50.848514)
			(xy 279.199086 -50.937414) (xy 279.243536 -50.937414)
		)
		(stroke
			(width 0)
			(type solid)
		)
		(fill yes)
		(layer "In2.Cu")
		(net "M_A_DQ<52>")
	)
	(gr_poly
		(pts
			(xy 279.403302 -49.919382) (xy 279.476962 -49.719992) (xy 279.315418 -49.558448) (xy 279.116028 -49.632108)
			(xy 279.084532 -49.66335) (xy 279.37206 -49.950878)
		)
		(stroke
			(width 0)
			(type solid)
		)
		(fill yes)
		(layer "In2.Cu")
		(net "M_A_DQ<53>")
	)
	(gr_poly
		(pts
			(xy 279.429464 -100.599748) (xy 279.430226 -100.378768) (xy 279.260046 -100.28936) (xy 279.215596 -100.28936)
			(xy 279.21458 -100.687886) (xy 279.25903 -100.68814)
		)
		(stroke
			(width 0)
			(type solid)
		)
		(fill yes)
		(layer "In2.Cu")
		(net "M_D_DQS_DP<5>")
	)
	(gr_poly
		(pts
			(xy 279.438862 -98.617024) (xy 279.438862 -98.396044) (xy 279.268682 -98.307144) (xy 279.224232 -98.307144)
			(xy 279.224232 -98.705924) (xy 279.268682 -98.705924)
		)
		(stroke
			(width 0)
			(type solid)
		)
		(fill yes)
		(layer "In2.Cu")
		(net "M_D_DQ<46>")
	)
	(gr_poly
		(pts
			(xy 279.439116 -51.353974) (xy 279.394666 -51.353974) (xy 279.201626 -51.442874) (xy 279.201626 -51.671474)
			(xy 279.394666 -51.760374) (xy 279.439116 -51.760374)
		)
		(stroke
			(width 0)
			(type solid)
		)
		(fill yes)
		(layer "In2.Cu")
		(net "M_A_DQ<52>")
	)
	(gr_poly
		(pts
			(xy 279.464008 -105.459276) (xy 279.464008 -105.230676) (xy 279.270968 -105.141776) (xy 279.226518 -105.141776)
			(xy 279.226518 -105.548176) (xy 279.270968 -105.548176)
		)
		(stroke
			(width 0)
			(type solid)
		)
		(fill yes)
		(layer "In2.Cu")
		(net "M_D_DQ<43>")
	)
	(gr_poly
		(pts
			(xy 279.473914 -103.08463) (xy 279.473914 -102.85603) (xy 279.280874 -102.76713) (xy 279.236424 -102.76713)
			(xy 279.236424 -103.17353) (xy 279.280874 -103.17353)
		)
		(stroke
			(width 0)
			(type solid)
		)
		(fill yes)
		(layer "In2.Cu")
		(net "M_D_DQ<47>")
	)
	(gr_poly
		(pts
			(xy 279.474676 -55.203598) (xy 279.430226 -55.203598) (xy 279.260046 -55.292498) (xy 279.260046 -55.513478)
			(xy 279.430226 -55.602378) (xy 279.474676 -55.602378)
		)
		(stroke
			(width 0)
			(type solid)
		)
		(fill yes)
		(layer "In2.Cu")
		(net "M_A_DQ<52>")
	)
	(gr_poly
		(pts
			(xy 279.474676 -54.212998) (xy 279.430226 -54.212998) (xy 279.260046 -54.301898) (xy 279.260046 -54.522878)
			(xy 279.430226 -54.611778) (xy 279.474676 -54.611778)
		)
		(stroke
			(width 0)
			(type solid)
		)
		(fill yes)
		(layer "In2.Cu")
		(net "M_A_DQ<52>")
	)
	(gr_poly
		(pts
			(xy 279.611836 -104.158796) (xy 279.58034 -104.127554) (xy 279.38095 -104.053894) (xy 279.219406 -104.215438)
			(xy 279.293066 -104.414828) (xy 279.324308 -104.446324)
		)
		(stroke
			(width 0)
			(type solid)
		)
		(fill yes)
		(layer "In2.Cu")
		(net "M_D_DQ<42>")
	)
	(gr_poly
		(pts
			(xy 279.61844 -53.212492) (xy 279.57399 -53.212492) (xy 279.38095 -53.301392) (xy 279.38095 -53.529992)
			(xy 279.57399 -53.618892) (xy 279.61844 -53.618892)
		)
		(stroke
			(width 0)
			(type solid)
		)
		(fill yes)
		(layer "In2.Cu")
		(net "M_A_DQ<52>")
	)
	(gr_poly
		(pts
			(xy 279.61844 -52.221892) (xy 279.57399 -52.221892) (xy 279.38095 -52.310792) (xy 279.38095 -52.539392)
			(xy 279.57399 -52.628292) (xy 279.61844 -52.628292)
		)
		(stroke
			(width 0)
			(type solid)
		)
		(fill yes)
		(layer "In2.Cu")
		(net "M_A_DQ<52>")
	)
	(gr_poly
		(pts
			(xy 279.671526 -50.594514) (xy 279.671526 -50.365914) (xy 279.478486 -50.277014) (xy 279.434036 -50.277014)
			(xy 279.434036 -50.683414) (xy 279.478486 -50.683414)
		)
		(stroke
			(width 0)
			(type solid)
		)
		(fill yes)
		(layer "In2.Cu")
		(net "M_A_DQ<53>")
	)
	(gr_poly
		(pts
			(xy 279.680924 -101.723698) (xy 279.649428 -101.692202) (xy 279.450292 -101.618542) (xy 279.288494 -101.78034)
			(xy 279.362154 -101.979476) (xy 279.39365 -102.010972)
		)
		(stroke
			(width 0)
			(type solid)
		)
		(fill yes)
		(layer "In2.Cu")
		(net "M_D_DQ<46>")
	)
	(gr_poly
		(pts
			(xy 279.823926 -103.363776) (xy 279.779476 -103.363776) (xy 279.586436 -103.452676) (xy 279.586436 -103.681276)
			(xy 279.779476 -103.770176) (xy 279.823926 -103.770176)
		)
		(stroke
			(width 0)
			(type solid)
		)
		(fill yes)
		(layer "In2.Cu")
		(net "M_D_DQ<42>")
	)
	(gr_poly
		(pts
			(xy 279.851104 -104.524048) (xy 279.777444 -104.324658) (xy 279.746202 -104.293162) (xy 279.458674 -104.58069)
			(xy 279.49017 -104.612186) (xy 279.68956 -104.685592)
		)
		(stroke
			(width 0)
			(type solid)
		)
		(fill yes)
		(layer "In2.Cu")
		(net "M_D_DQ<43>")
	)
	(gr_poly
		(pts
			(xy 279.867106 -51.671474) (xy 279.867106 -51.442874) (xy 279.674066 -51.353974) (xy 279.629616 -51.353974)
			(xy 279.629616 -51.760374) (xy 279.674066 -51.760374)
		)
		(stroke
			(width 0)
			(type solid)
		)
		(fill yes)
		(layer "In2.Cu")
		(net "M_A_DQ<53>")
	)
	(gr_poly
		(pts
			(xy 279.891744 -100.26142) (xy 279.847294 -100.26142) (xy 279.654254 -100.35032) (xy 279.654254 -100.57892)
			(xy 279.847294 -100.66782) (xy 279.891744 -100.66782)
		)
		(stroke
			(width 0)
			(type solid)
		)
		(fill yes)
		(layer "In2.Cu")
		(net "M_D_DQ<46>")
	)
	(gr_poly
		(pts
			(xy 279.920446 -102.088696) (xy 279.846786 -101.88956) (xy 279.81529 -101.858064) (xy 279.528016 -102.145338)
			(xy 279.559512 -102.176834) (xy 279.758648 -102.250494)
		)
		(stroke
			(width 0)
			(type solid)
		)
		(fill yes)
		(layer "In2.Cu")
		(net "M_D_DQ<47>")
	)
	(gr_poly
		(pts
			(xy 279.94991 -98.305874) (xy 279.90546 -98.305874) (xy 279.73528 -98.394774) (xy 279.73528 -98.615754)
			(xy 279.90546 -98.704654) (xy 279.94991 -98.704654)
		)
		(stroke
			(width 0)
			(type solid)
		)
		(fill yes)
		(layer "In2.Cu")
		(net "M_D_DQ<42>")
	)
	(gr_poly
		(pts
			(xy 280.012902 -55.030624) (xy 280.012902 -54.809644) (xy 279.842722 -54.720744) (xy 279.798272 -54.720744)
			(xy 279.798272 -55.119524) (xy 279.842722 -55.119524)
		)
		(stroke
			(width 0)
			(type solid)
		)
		(fill yes)
		(layer "In2.Cu")
		(net "M_A_DQ<53>")
	)
	(gr_poly
		(pts
			(xy 280.04643 -53.529992) (xy 280.04643 -53.301392) (xy 279.85339 -53.212492) (xy 279.80894 -53.212492)
			(xy 279.80894 -53.618892) (xy 279.85339 -53.618892)
		)
		(stroke
			(width 0)
			(type solid)
		)
		(fill yes)
		(layer "In2.Cu")
		(net "M_A_DQ<53>")
	)
	(gr_poly
		(pts
			(xy 280.04643 -52.539392) (xy 280.04643 -52.310792) (xy 279.85339 -52.221892) (xy 279.80894 -52.221892)
			(xy 279.80894 -52.628292) (xy 279.85339 -52.628292)
		)
		(stroke
			(width 0)
			(type solid)
		)
		(fill yes)
		(layer "In2.Cu")
		(net "M_A_DQ<53>")
	)
	(gr_poly
		(pts
			(xy 280.087324 -49.354486) (xy 280.042874 -49.354486) (xy 279.849834 -49.443386) (xy 279.849834 -49.671986)
			(xy 280.042874 -49.760886) (xy 280.087324 -49.760886)
		)
		(stroke
			(width 0)
			(type solid)
		)
		(fill yes)
		(layer "In2.Cu")
		(net "M_A_DQ<48>")
	)
	(gr_poly
		(pts
			(xy 280.087324 -48.363886) (xy 280.042874 -48.363886) (xy 279.849834 -48.452786) (xy 279.849834 -48.681386)
			(xy 280.042874 -48.770286) (xy 280.087324 -48.770286)
		)
		(stroke
			(width 0)
			(type solid)
		)
		(fill yes)
		(layer "In2.Cu")
		(net "M_A_DQ<48>")
	)
	(gr_poly
		(pts
			(xy 280.162508 -50.974752) (xy 280.118058 -50.974752) (xy 279.925018 -51.063652) (xy 279.925018 -51.292252)
			(xy 280.118058 -51.381152) (xy 280.162508 -51.381152)
		)
		(stroke
			(width 0)
			(type solid)
		)
		(fill yes)
		(layer "In2.Cu")
		(net "M_A_DQ<48>")
	)
	(gr_poly
		(pts
			(xy 280.251408 -103.681276) (xy 280.251408 -103.452676) (xy 280.058368 -103.363776) (xy 280.013918 -103.363776)
			(xy 280.013918 -103.770176) (xy 280.058368 -103.770176)
		)
		(stroke
			(width 0)
			(type solid)
		)
		(fill yes)
		(layer "In2.Cu")
		(net "M_D_DQ<43>")
	)
	(gr_poly
		(pts
			(xy 280.319226 -101.18852) (xy 280.319226 -100.95992) (xy 280.126186 -100.87102) (xy 280.081736 -100.87102)
			(xy 280.081736 -101.27742) (xy 280.126186 -101.27742)
		)
		(stroke
			(width 0)
			(type solid)
		)
		(fill yes)
		(layer "In2.Cu")
		(net "M_D_DQ<47>")
	)
	(gr_poly
		(pts
			(xy 280.319226 -100.19792) (xy 280.319226 -99.96932) (xy 280.126186 -99.88042) (xy 280.081736 -99.88042)
			(xy 280.081736 -100.28682) (xy 280.126186 -100.28682)
		)
		(stroke
			(width 0)
			(type solid)
		)
		(fill yes)
		(layer "In2.Cu")
		(net "M_D_DQ<47>")
	)
	(gr_poly
		(pts
			(xy 280.323036 -102.329996) (xy 280.29154 -102.298754) (xy 280.09215 -102.225094) (xy 279.930606 -102.386638)
			(xy 280.004266 -102.586028) (xy 280.035508 -102.617524)
		)
		(stroke
			(width 0)
			(type solid)
		)
		(fill yes)
		(layer "In2.Cu")
		(net "M_D_DQ<42>")
	)
	(gr_poly
		(pts
			(xy 280.333196 -54.720744) (xy 280.288746 -54.720744) (xy 280.118566 -54.809644) (xy 280.118566 -55.030624)
			(xy 280.288746 -55.119524) (xy 280.333196 -55.119524)
		)
		(stroke
			(width 0)
			(type solid)
		)
		(fill yes)
		(layer "In2.Cu")
		(net "M_A_DQ<48>")
	)
	(gr_poly
		(pts
			(xy 280.38552 -53.079904) (xy 280.34107 -53.079904) (xy 280.14803 -53.168804) (xy 280.14803 -53.397404)
			(xy 280.34107 -53.486304) (xy 280.38552 -53.486304)
		)
		(stroke
			(width 0)
			(type solid)
		)
		(fill yes)
		(layer "In2.Cu")
		(net "M_A_DQ<48>")
	)
	(gr_poly
		(pts
			(xy 280.38552 -52.089304) (xy 280.34107 -52.089304) (xy 280.14803 -52.178204) (xy 280.14803 -52.406804)
			(xy 280.34107 -52.495704) (xy 280.38552 -52.495704)
		)
		(stroke
			(width 0)
			(type solid)
		)
		(fill yes)
		(layer "In2.Cu")
		(net "M_A_DQ<48>")
	)
	(gr_poly
		(pts
			(xy 280.515314 -49.671986) (xy 280.515314 -49.443386) (xy 280.322274 -49.354486) (xy 280.277824 -49.354486)
			(xy 280.277824 -49.760886) (xy 280.322274 -49.760886)
		)
		(stroke
			(width 0)
			(type solid)
		)
		(fill yes)
		(layer "In2.Cu")
		(net "M_A_DQ<49>")
	)
	(gr_poly
		(pts
			(xy 280.515314 -48.681386) (xy 280.515314 -48.452786) (xy 280.322274 -48.363886) (xy 280.277824 -48.363886)
			(xy 280.277824 -48.770286) (xy 280.322274 -48.770286)
		)
		(stroke
			(width 0)
			(type solid)
		)
		(fill yes)
		(layer "In2.Cu")
		(net "M_A_DQ<49>")
	)
	(gr_poly
		(pts
			(xy 280.561796 -104.536494) (xy 280.517346 -104.536494) (xy 280.324306 -104.625394) (xy 280.324306 -104.853994)
			(xy 280.517346 -104.942894) (xy 280.561796 -104.942894)
		)
		(stroke
			(width 0)
			(type solid)
		)
		(fill yes)
		(layer "In2.Cu")
		(net "M_D_DQ<52>")
	)
	(gr_poly
		(pts
			(xy 280.562304 -102.695248) (xy 280.488644 -102.495858) (xy 280.457402 -102.464362) (xy 280.169874 -102.75189)
			(xy 280.20137 -102.783386) (xy 280.40076 -102.856792)
		)
		(stroke
			(width 0)
			(type solid)
		)
		(fill yes)
		(layer "In2.Cu")
		(net "M_D_DQ<43>")
	)
	(gr_poly
		(pts
			(xy 280.590498 -51.292252) (xy 280.590498 -51.063652) (xy 280.397458 -50.974752) (xy 280.353008 -50.974752)
			(xy 280.353008 -51.381152) (xy 280.397458 -51.381152)
		)
		(stroke
			(width 0)
			(type solid)
		)
		(fill yes)
		(layer "In2.Cu")
		(net "M_A_DQ<49>")
	)
	(gr_poly
		(pts
			(xy 280.667206 -101.495606) (xy 280.622756 -101.495606) (xy 280.429716 -101.584506) (xy 280.429716 -101.813106)
			(xy 280.622756 -101.902006) (xy 280.667206 -101.902006)
		)
		(stroke
			(width 0)
			(type solid)
		)
		(fill yes)
		(layer "In2.Cu")
		(net "M_D_DQ<42>")
	)
	(gr_poly
		(pts
			(xy 280.667206 -100.505006) (xy 280.622756 -100.505006) (xy 280.429716 -100.593906) (xy 280.429716 -100.822506)
			(xy 280.622756 -100.911406) (xy 280.667206 -100.911406)
		)
		(stroke
			(width 0)
			(type solid)
		)
		(fill yes)
		(layer "In2.Cu")
		(net "M_D_DQ<42>")
	)
	(gr_poly
		(pts
			(xy 280.81351 -53.397404) (xy 280.81351 -53.168804) (xy 280.62047 -53.079904) (xy 280.57602 -53.079904)
			(xy 280.57602 -53.486304) (xy 280.62047 -53.486304)
		)
		(stroke
			(width 0)
			(type solid)
		)
		(fill yes)
		(layer "In2.Cu")
		(net "M_A_DQ<49>")
	)
	(gr_poly
		(pts
			(xy 280.81351 -52.406804) (xy 280.81351 -52.178204) (xy 280.62047 -52.089304) (xy 280.57602 -52.089304)
			(xy 280.57602 -52.495704) (xy 280.62047 -52.495704)
		)
		(stroke
			(width 0)
			(type solid)
		)
		(fill yes)
		(layer "In2.Cu")
		(net "M_A_DQ<49>")
	)
	(gr_poly
		(pts
			(xy 280.871422 -54.522878) (xy 280.871422 -54.301898) (xy 280.701242 -54.212998) (xy 280.656792 -54.212998)
			(xy 280.656792 -54.611778) (xy 280.701242 -54.611778)
		)
		(stroke
			(width 0)
			(type solid)
		)
		(fill yes)
		(layer "In2.Cu")
		(net "M_A_DQ<49>")
	)
	(gr_poly
		(pts
			(xy 280.989786 -104.853994) (xy 280.989786 -104.625394) (xy 280.796746 -104.536494) (xy 280.752296 -104.536494)
			(xy 280.752296 -104.942894) (xy 280.796746 -104.942894)
		)
		(stroke
			(width 0)
			(type solid)
		)
		(fill yes)
		(layer "In2.Cu")
		(net "M_D_DQ<53>")
	)
	(gr_poly
		(pts
			(xy 281.094688 -101.813106) (xy 281.094688 -101.584506) (xy 280.901648 -101.495606) (xy 280.857198 -101.495606)
			(xy 280.857198 -101.902006) (xy 280.901648 -101.902006)
		)
		(stroke
			(width 0)
			(type solid)
		)
		(fill yes)
		(layer "In2.Cu")
		(net "M_D_DQ<43>")
	)
	(gr_poly
		(pts
			(xy 281.094688 -100.822506) (xy 281.094688 -100.593906) (xy 280.901648 -100.505006) (xy 280.857198 -100.505006)
			(xy 280.857198 -100.911406) (xy 280.901648 -100.911406)
		)
		(stroke
			(width 0)
			(type solid)
		)
		(fill yes)
		(layer "In2.Cu")
		(net "M_D_DQ<43>")
	)
	(gr_poly
		(pts
			(xy 281.154378 -99.973638) (xy 281.154886 -99.752658) (xy 280.984706 -99.663504) (xy 280.940256 -99.663504)
			(xy 280.939494 -100.06203) (xy 280.983944 -100.062284)
		)
		(stroke
			(width 0)
			(type solid)
		)
		(fill yes)
		(layer "In2.Cu")
		(net "M_D_DQ<43>")
	)
	(gr_poly
		(pts
			(xy 281.162506 -103.694484) (xy 281.13101 -103.662988) (xy 280.931874 -103.589328) (xy 280.770076 -103.751126)
			(xy 280.843736 -103.950262) (xy 280.875232 -103.981758)
		)
		(stroke
			(width 0)
			(type solid)
		)
		(fill yes)
		(layer "In2.Cu")
		(net "M_D_DQ<52>")
	)
	(gr_poly
		(pts
			(xy 281.191716 -54.212998) (xy 281.147266 -54.212998) (xy 280.977086 -54.301898) (xy 280.977086 -54.522878)
			(xy 281.147266 -54.611778) (xy 281.191716 -54.611778)
		)
		(stroke
			(width 0)
			(type solid)
		)
		(fill yes)
		(layer "In2.Cu")
		(net "M_A_DQS_DP<15>")
	)
	(gr_poly
		(pts
			(xy 281.220164 -51.776884) (xy 281.25166 -51.745642) (xy 280.964132 -51.458114) (xy 280.93289 -51.48961)
			(xy 280.85923 -51.689) (xy 281.020774 -51.850544)
		)
		(stroke
			(width 0)
			(type solid)
		)
		(fill yes)
		(layer "In2.Cu")
		(net "M_A_DQS_DP<15>")
	)
	(gr_poly
		(pts
			(xy 281.23007 -49.558194) (xy 281.18562 -49.558194) (xy 280.99258 -49.647094) (xy 280.99258 -49.875694)
			(xy 281.18562 -49.964594) (xy 281.23007 -49.964594)
		)
		(stroke
			(width 0)
			(type solid)
		)
		(fill yes)
		(layer "In2.Cu")
		(net "M_A_DQS_DP<15>")
	)
	(gr_poly
		(pts
			(xy 281.23007 -48.567594) (xy 281.18562 -48.567594) (xy 280.99258 -48.656494) (xy 280.99258 -48.885094)
			(xy 281.18562 -48.973994) (xy 281.23007 -48.973994)
		)
		(stroke
			(width 0)
			(type solid)
		)
		(fill yes)
		(layer "In2.Cu")
		(net "M_A_DQS_DP<15>")
	)
	(gr_poly
		(pts
			(xy 281.327098 -56.374538) (xy 281.285696 -56.187086) (xy 281.257248 -56.15305) (xy 280.951686 -56.409336)
			(xy 280.980388 -56.443372) (xy 281.157934 -56.516524)
		)
		(stroke
			(width 0)
			(type solid)
		)
		(fill yes)
		(layer "In2.Cu")
		(net "M_A_DQ<49>")
	)
	(gr_poly
		(pts
			(xy 281.329384 -53.056028) (xy 281.284934 -53.056028) (xy 281.091894 -53.144928) (xy 281.091894 -53.373528)
			(xy 281.284934 -53.462428) (xy 281.329384 -53.462428)
		)
		(stroke
			(width 0)
			(type solid)
		)
		(fill yes)
		(layer "In2.Cu")
		(net "M_A_DQS_DP<15>")
	)
	(gr_poly
		(pts
			(xy 281.329384 -52.192428) (xy 281.284934 -52.192428) (xy 281.091894 -52.281328) (xy 281.091894 -52.509928)
			(xy 281.284934 -52.598828) (xy 281.329384 -52.598828)
		)
		(stroke
			(width 0)
			(type solid)
		)
		(fill yes)
		(layer "In2.Cu")
		(net "M_A_DQS_DP<15>")
	)
	(gr_poly
		(pts
			(xy 281.402028 -104.059482) (xy 281.328368 -103.860346) (xy 281.296872 -103.82885) (xy 281.009598 -104.116124)
			(xy 281.041094 -104.14762) (xy 281.24023 -104.22128)
		)
		(stroke
			(width 0)
			(type solid)
		)
		(fill yes)
		(layer "In2.Cu")
		(net "M_D_DQ<53>")
	)
	(gr_poly
		(pts
			(xy 281.475942 -102.757478) (xy 281.431492 -102.757478) (xy 281.238452 -102.846378) (xy 281.238452 -103.074978)
			(xy 281.431492 -103.163878) (xy 281.475942 -103.163878)
		)
		(stroke
			(width 0)
			(type solid)
		)
		(fill yes)
		(layer "In2.Cu")
		(net "M_D_DQ<52>")
	)
	(gr_poly
		(pts
			(xy 281.476196 -101.281484) (xy 281.431746 -101.281484) (xy 281.261566 -101.370384) (xy 281.261566 -101.591364)
			(xy 281.431746 -101.680264) (xy 281.476196 -101.680264)
		)
		(stroke
			(width 0)
			(type solid)
		)
		(fill yes)
		(layer "In2.Cu")
		(net "M_D_DQ<52>")
	)
	(gr_poly
		(pts
			(xy 281.476196 -100.290884) (xy 281.431746 -100.290884) (xy 281.261566 -100.379784) (xy 281.261566 -100.600764)
			(xy 281.431746 -100.689664) (xy 281.476196 -100.689664)
		)
		(stroke
			(width 0)
			(type solid)
		)
		(fill yes)
		(layer "In2.Cu")
		(net "M_D_DQ<52>")
	)
	(gr_poly
		(pts
			(xy 281.476196 -99.300284) (xy 281.431746 -99.300284) (xy 281.261566 -99.389184) (xy 281.261566 -99.610164)
			(xy 281.431746 -99.699064) (xy 281.476196 -99.699064)
		)
		(stroke
			(width 0)
			(type solid)
		)
		(fill yes)
		(layer "In2.Cu")
		(net "M_D_DQ<52>")
	)
	(gr_poly
		(pts
			(xy 281.476196 -98.309684) (xy 281.431746 -98.309684) (xy 281.261566 -98.398584) (xy 281.261566 -98.619564)
			(xy 281.431746 -98.708464) (xy 281.476196 -98.708464)
		)
		(stroke
			(width 0)
			(type solid)
		)
		(fill yes)
		(layer "In2.Cu")
		(net "M_D_DQ<52>")
	)
	(gr_poly
		(pts
			(xy 281.507438 -51.669188) (xy 281.581098 -51.469798) (xy 281.419554 -51.308254) (xy 281.220164 -51.381914)
			(xy 281.188668 -51.413156) (xy 281.476196 -51.700684)
		)
		(stroke
			(width 0)
			(type solid)
		)
		(fill yes)
		(layer "In2.Cu")
		(net "M_A_DQS_DN<15>")
	)
	(gr_poly
		(pts
			(xy 281.65806 -49.875694) (xy 281.65806 -49.647094) (xy 281.46502 -49.558194) (xy 281.42057 -49.558194)
			(xy 281.42057 -49.964594) (xy 281.46502 -49.964594)
		)
		(stroke
			(width 0)
			(type solid)
		)
		(fill yes)
		(layer "In2.Cu")
		(net "M_A_DQS_DN<15>")
	)
	(gr_poly
		(pts
			(xy 281.65806 -48.885094) (xy 281.65806 -48.656494) (xy 281.46502 -48.567594) (xy 281.42057 -48.567594)
			(xy 281.42057 -48.973994) (xy 281.46502 -48.973994)
		)
		(stroke
			(width 0)
			(type solid)
		)
		(fill yes)
		(layer "In2.Cu")
		(net "M_A_DQS_DN<15>")
	)
	(gr_poly
		(pts
			(xy 281.757374 -53.881528) (xy 281.757374 -53.652928) (xy 281.564334 -53.564028) (xy 281.519884 -53.564028)
			(xy 281.519884 -53.970428) (xy 281.564334 -53.970428)
		)
		(stroke
			(width 0)
			(type solid)
		)
		(fill yes)
		(layer "In2.Cu")
		(net "M_A_DQS_DN<15>")
	)
	(gr_poly
		(pts
			(xy 281.757374 -52.890928) (xy 281.757374 -52.662328) (xy 281.564334 -52.573428) (xy 281.519884 -52.573428)
			(xy 281.519884 -52.979828) (xy 281.564334 -52.979828)
		)
		(stroke
			(width 0)
			(type solid)
		)
		(fill yes)
		(layer "In2.Cu")
		(net "M_A_DQS_DN<15>")
	)
	(gr_poly
		(pts
			(xy 281.904186 -103.074978) (xy 281.904186 -102.846378) (xy 281.711146 -102.757478) (xy 281.666696 -102.757478)
			(xy 281.666696 -103.163878) (xy 281.711146 -103.163878)
		)
		(stroke
			(width 0)
			(type solid)
		)
		(fill yes)
		(layer "In2.Cu")
		(net "M_D_DQ<53>")
	)
	(gr_poly
		(pts
			(xy 282.014422 -102.068884) (xy 282.014422 -101.847904) (xy 281.844242 -101.759004) (xy 281.799792 -101.759004)
			(xy 281.799792 -102.157784) (xy 281.844242 -102.157784)
		)
		(stroke
			(width 0)
			(type solid)
		)
		(fill yes)
		(layer "In2.Cu")
		(net "M_D_DQ<53>")
	)
	(gr_poly
		(pts
			(xy 282.014422 -101.078284) (xy 282.014422 -100.857304) (xy 281.844242 -100.768404) (xy 281.799792 -100.768404)
			(xy 281.799792 -101.167184) (xy 281.844242 -101.167184)
		)
		(stroke
			(width 0)
			(type solid)
		)
		(fill yes)
		(layer "In2.Cu")
		(net "M_D_DQ<53>")
	)
	(gr_poly
		(pts
			(xy 282.014422 -100.090478) (xy 282.014422 -99.869498) (xy 281.844242 -99.780598) (xy 281.799792 -99.780598)
			(xy 281.799792 -100.179378) (xy 281.844242 -100.179378)
		)
		(stroke
			(width 0)
			(type solid)
		)
		(fill yes)
		(layer "In2.Cu")
		(net "M_D_DQ<53>")
	)
	(gr_poly
		(pts
			(xy 282.050236 -55.705248) (xy 282.005786 -55.705248) (xy 281.835606 -55.794148) (xy 281.835606 -56.015128)
			(xy 282.005786 -56.104028) (xy 282.050236 -56.104028)
		)
		(stroke
			(width 0)
			(type solid)
		)
		(fill yes)
		(layer "In2.Cu")
		(net "M_A_DQS_DN<6>")
	)
	(gr_poly
		(pts
			(xy 282.050236 -54.714648) (xy 282.005786 -54.714648) (xy 281.835606 -54.803548) (xy 281.835606 -55.024528)
			(xy 282.005786 -55.113428) (xy 282.050236 -55.113428)
		)
		(stroke
			(width 0)
			(type solid)
		)
		(fill yes)
		(layer "In2.Cu")
		(net "M_A_DQS_DN<6>")
	)
	(gr_poly
		(pts
			(xy 282.14193 -53.47589) (xy 282.09748 -53.47589) (xy 281.90444 -53.56479) (xy 281.90444 -53.79339)
			(xy 282.09748 -53.88229) (xy 282.14193 -53.88229)
		)
		(stroke
			(width 0)
			(type solid)
		)
		(fill yes)
		(layer "In2.Cu")
		(net "M_A_DQS_DN<6>")
	)
	(gr_poly
		(pts
			(xy 282.14193 -52.48529) (xy 282.09748 -52.48529) (xy 281.90444 -52.57419) (xy 281.90444 -52.80279)
			(xy 282.09748 -52.89169) (xy 282.14193 -52.89169)
		)
		(stroke
			(width 0)
			(type solid)
		)
		(fill yes)
		(layer "In2.Cu")
		(net "M_A_DQS_DN<6>")
	)
	(gr_poly
		(pts
			(xy 282.14193 -51.49469) (xy 282.09748 -51.49469) (xy 281.90444 -51.58359) (xy 281.90444 -51.81219)
			(xy 282.09748 -51.90109) (xy 282.14193 -51.90109)
		)
		(stroke
			(width 0)
			(type solid)
		)
		(fill yes)
		(layer "In2.Cu")
		(net "M_A_DQS_DN<6>")
	)
	(gr_poly
		(pts
			(xy 282.189174 -104.686354) (xy 282.157678 -104.655112) (xy 281.958288 -104.581452) (xy 281.796744 -104.742996)
			(xy 281.870404 -104.942386) (xy 281.901646 -104.973882)
		)
		(stroke
			(width 0)
			(type solid)
		)
		(fill yes)
		(layer "In2.Cu")
		(net "M_D_DQ<48>")
	)
	(gr_poly
		(pts
			(xy 282.334716 -103.33101) (xy 282.290266 -103.33101) (xy 282.097226 -103.41991) (xy 282.097226 -103.64851)
			(xy 282.290266 -103.73741) (xy 282.334716 -103.73741)
		)
		(stroke
			(width 0)
			(type solid)
		)
		(fill yes)
		(layer "In2.Cu")
		(net "M_D_DQ<48>")
	)
	(gr_poly
		(pts
			(xy 282.334716 -101.76764) (xy 282.290266 -101.76764) (xy 282.120086 -101.85654) (xy 282.120086 -102.07752)
			(xy 282.290266 -102.16642) (xy 282.334716 -102.16642)
		)
		(stroke
			(width 0)
			(type solid)
		)
		(fill yes)
		(layer "In2.Cu")
		(net "M_D_DQ<48>")
	)
	(gr_poly
		(pts
			(xy 282.334716 -100.783136) (xy 282.290266 -100.783136) (xy 282.120086 -100.872036) (xy 282.120086 -101.093016)
			(xy 282.290266 -101.181916) (xy 282.334716 -101.181916)
		)
		(stroke
			(width 0)
			(type solid)
		)
		(fill yes)
		(layer "In2.Cu")
		(net "M_D_DQ<48>")
	)
	(gr_poly
		(pts
			(xy 282.334716 -99.792536) (xy 282.290266 -99.792536) (xy 282.120086 -99.881436) (xy 282.120086 -100.102416)
			(xy 282.290266 -100.191316) (xy 282.334716 -100.191316)
		)
		(stroke
			(width 0)
			(type solid)
		)
		(fill yes)
		(layer "In2.Cu")
		(net "M_D_DQ<48>")
	)
	(gr_poly
		(pts
			(xy 282.334716 -98.801936) (xy 282.290266 -98.801936) (xy 282.120086 -98.890836) (xy 282.120086 -99.111816)
			(xy 282.290266 -99.200716) (xy 282.334716 -99.200716)
		)
		(stroke
			(width 0)
			(type solid)
		)
		(fill yes)
		(layer "In2.Cu")
		(net "M_D_DQ<48>")
	)
	(gr_poly
		(pts
			(xy 282.418028 -56.588406) (xy 282.588208 -56.499506) (xy 282.588208 -56.278526) (xy 282.418028 -56.189626)
			(xy 282.373832 -56.189626) (xy 282.373578 -56.58866)
		)
		(stroke
			(width 0)
			(type solid)
		)
		(fill yes)
		(layer "In2.Cu")
		(net "M_A_DQS_DP<6>")
	)
	(gr_poly
		(pts
			(xy 282.482544 -48.857662) (xy 282.438094 -48.857662) (xy 282.245054 -48.946562) (xy 282.245054 -49.175162)
			(xy 282.438094 -49.264062) (xy 282.482544 -49.264062)
		)
		(stroke
			(width 0)
			(type solid)
		)
		(fill yes)
		(layer "In2.Cu")
		(net "M_A_DQS_DN<6>")
	)
	(gr_poly
		(pts
			(xy 282.518866 -104.962452) (xy 282.445206 -104.763062) (xy 282.413964 -104.731566) (xy 282.126436 -105.019094)
			(xy 282.157932 -105.050336) (xy 282.357322 -105.123996)
		)
		(stroke
			(width 0)
			(type solid)
		)
		(fill yes)
		(layer "In2.Cu")
		(net "M_D_DQ<49>")
	)
	(gr_poly
		(pts
			(xy 282.531566 -97.766886) (xy 282.487116 -97.766886) (xy 282.316936 -97.855786) (xy 282.316936 -98.076766)
			(xy 282.487116 -98.165666) (xy 282.531566 -98.165666)
		)
		(stroke
			(width 0)
			(type solid)
		)
		(fill yes)
		(layer "In2.Cu")
		(net "M_D_DQ<48>")
	)
	(gr_poly
		(pts
			(xy 282.56992 -53.79339) (xy 282.56992 -53.56479) (xy 282.37688 -53.47589) (xy 282.33243 -53.47589)
			(xy 282.33243 -53.88229) (xy 282.37688 -53.88229)
		)
		(stroke
			(width 0)
			(type solid)
		)
		(fill yes)
		(layer "In2.Cu")
		(net "M_A_DQS_DP<6>")
	)
	(gr_poly
		(pts
			(xy 282.56992 -52.80279) (xy 282.56992 -52.57419) (xy 282.37688 -52.48529) (xy 282.33243 -52.48529)
			(xy 282.33243 -52.89169) (xy 282.37688 -52.89169)
		)
		(stroke
			(width 0)
			(type solid)
		)
		(fill yes)
		(layer "In2.Cu")
		(net "M_A_DQS_DP<6>")
	)
	(gr_poly
		(pts
			(xy 282.56992 -51.81219) (xy 282.56992 -51.58359) (xy 282.37688 -51.49469) (xy 282.33243 -51.49469)
			(xy 282.33243 -51.90109) (xy 282.37688 -51.90109)
		)
		(stroke
			(width 0)
			(type solid)
		)
		(fill yes)
		(layer "In2.Cu")
		(net "M_A_DQS_DP<6>")
	)
	(gr_poly
		(pts
			(xy 282.588462 -55.519828) (xy 282.588462 -55.298848) (xy 282.418282 -55.209948) (xy 282.373832 -55.209948)
			(xy 282.373832 -55.608728) (xy 282.418282 -55.608728)
		)
		(stroke
			(width 0)
			(type solid)
		)
		(fill yes)
		(layer "In2.Cu")
		(net "M_A_DQS_DP<6>")
	)
	(gr_poly
		(pts
			(xy 282.76296 -103.64851) (xy 282.76296 -103.41991) (xy 282.56992 -103.33101) (xy 282.52547 -103.33101)
			(xy 282.52547 -103.73741) (xy 282.56992 -103.73741)
		)
		(stroke
			(width 0)
			(type solid)
		)
		(fill yes)
		(layer "In2.Cu")
		(net "M_D_DQ<49>")
	)
	(gr_poly
		(pts
			(xy 282.872942 -102.57917) (xy 282.872942 -102.35819) (xy 282.702762 -102.26929) (xy 282.658312 -102.26929)
			(xy 282.658312 -102.66807) (xy 282.702762 -102.66807)
		)
		(stroke
			(width 0)
			(type solid)
		)
		(fill yes)
		(layer "In2.Cu")
		(net "M_D_DQ<49>")
	)
	(gr_poly
		(pts
			(xy 282.872942 -101.58222) (xy 282.872942 -101.36124) (xy 282.702762 -101.27234) (xy 282.658312 -101.27234)
			(xy 282.658312 -101.67112) (xy 282.702762 -101.67112)
		)
		(stroke
			(width 0)
			(type solid)
		)
		(fill yes)
		(layer "In2.Cu")
		(net "M_D_DQ<49>")
	)
	(gr_poly
		(pts
			(xy 282.872942 -100.58527) (xy 282.872942 -100.36429) (xy 282.702762 -100.27539) (xy 282.658312 -100.27539)
			(xy 282.658312 -100.67417) (xy 282.702762 -100.67417)
		)
		(stroke
			(width 0)
			(type solid)
		)
		(fill yes)
		(layer "In2.Cu")
		(net "M_D_DQ<49>")
	)
	(gr_poly
		(pts
			(xy 282.90901 -52.69357) (xy 282.86456 -52.69357) (xy 282.67152 -52.78247) (xy 282.67152 -53.01107)
			(xy 282.86456 -53.09997) (xy 282.90901 -53.09997)
		)
		(stroke
			(width 0)
			(type solid)
		)
		(fill yes)
		(layer "In2.Cu")
		(net "M_A_DQ<54>")
	)
	(gr_poly
		(pts
			(xy 282.90901 -51.80457) (xy 282.86456 -51.80457) (xy 282.67152 -51.89347) (xy 282.67152 -52.12207)
			(xy 282.86456 -52.21097) (xy 282.90901 -52.21097)
		)
		(stroke
			(width 0)
			(type solid)
		)
		(fill yes)
		(layer "In2.Cu")
		(net "M_A_DQ<54>")
	)
	(gr_poly
		(pts
			(xy 282.910534 -49.175162) (xy 282.910534 -48.946562) (xy 282.717494 -48.857662) (xy 282.673044 -48.857662)
			(xy 282.673044 -49.264062) (xy 282.717494 -49.264062)
		)
		(stroke
			(width 0)
			(type solid)
		)
		(fill yes)
		(layer "In2.Cu")
		(net "M_A_DQS_DP<6>")
	)
	(gr_poly
		(pts
			(xy 283.041598 -54.00421) (xy 282.997148 -54.00421) (xy 282.804108 -54.09311) (xy 282.804108 -54.32171)
			(xy 282.997148 -54.41061) (xy 283.041598 -54.41061)
		)
		(stroke
			(width 0)
			(type solid)
		)
		(fill yes)
		(layer "In2.Cu")
		(net "M_A_DQ<54>")
	)
	(gr_poly
		(pts
			(xy 283.121862 -103.880666) (xy 283.077412 -103.880666) (xy 282.884372 -103.969566) (xy 282.884372 -104.198166)
			(xy 283.077412 -104.287066) (xy 283.121862 -104.287066)
		)
		(stroke
			(width 0)
			(type solid)
		)
		(fill yes)
		(layer "In2.Cu")
		(net "M_D_DQS_DP<15>")
	)
	(gr_poly
		(pts
			(xy 283.193236 -102.263194) (xy 283.148786 -102.263194) (xy 282.978606 -102.352094) (xy 282.978606 -102.573074)
			(xy 283.148786 -102.661974) (xy 283.193236 -102.661974)
		)
		(stroke
			(width 0)
			(type solid)
		)
		(fill yes)
		(layer "In2.Cu")
		(net "M_D_DQS_DP<15>")
	)
	(gr_poly
		(pts
			(xy 283.193236 -101.26345) (xy 283.148786 -101.26345) (xy 282.978606 -101.35235) (xy 282.978606 -101.57333)
			(xy 283.148786 -101.66223) (xy 283.193236 -101.66223)
		)
		(stroke
			(width 0)
			(type solid)
		)
		(fill yes)
		(layer "In2.Cu")
		(net "M_D_DQS_DP<15>")
	)
	(gr_poly
		(pts
			(xy 283.193236 -100.275644) (xy 283.148786 -100.275644) (xy 282.978606 -100.364544) (xy 282.978606 -100.585524)
			(xy 283.148786 -100.674424) (xy 283.193236 -100.674424)
		)
		(stroke
			(width 0)
			(type solid)
		)
		(fill yes)
		(layer "In2.Cu")
		(net "M_D_DQS_DP<15>")
	)
	(gr_poly
		(pts
			(xy 283.193236 -98.307144) (xy 283.148786 -98.307144) (xy 282.978606 -98.396044) (xy 282.978606 -98.617024)
			(xy 283.148786 -98.705924) (xy 283.193236 -98.705924)
		)
		(stroke
			(width 0)
			(type solid)
		)
		(fill yes)
		(layer "In2.Cu")
		(net "M_D_DQS_DP<15>")
	)
	(gr_poly
		(pts
			(xy 283.19349 -99.291394) (xy 283.14904 -99.291394) (xy 282.97886 -99.380294) (xy 282.97886 -99.601274)
			(xy 283.14904 -99.690174) (xy 283.19349 -99.690174)
		)
		(stroke
			(width 0)
			(type solid)
		)
		(fill yes)
		(layer "In2.Cu")
		(net "M_D_DQS_DP<15>")
	)
	(gr_poly
		(pts
			(xy 283.227526 -57.111138) (xy 283.26588 -56.89346) (xy 283.113734 -56.776366) (xy 283.069792 -56.768746)
			(xy 283.000704 -57.16143) (xy 283.044392 -57.16905)
		)
		(stroke
			(width 0)
			(type solid)
		)
		(fill yes)
		(layer "In2.Cu")
		(net "M_A_DQ<55>")
	)
	(gr_poly
		(pts
			(xy 283.337254 -53.01107) (xy 283.337254 -52.78247) (xy 283.144214 -52.69357) (xy 283.099764 -52.69357)
			(xy 283.099764 -53.09997) (xy 283.144214 -53.09997)
		)
		(stroke
			(width 0)
			(type solid)
		)
		(fill yes)
		(layer "In2.Cu")
		(net "M_A_DQ<55>")
	)
	(gr_poly
		(pts
			(xy 283.3497 -51.13528) (xy 283.318458 -51.103784) (xy 283.119068 -51.030124) (xy 282.95727 -51.191668)
			(xy 283.03093 -51.391058) (xy 283.062426 -51.422554)
		)
		(stroke
			(width 0)
			(type solid)
		)
		(fill yes)
		(layer "In2.Cu")
		(net "M_A_DQ<54>")
	)
	(gr_poly
		(pts
			(xy 283.446982 -56.015128) (xy 283.446982 -55.794148) (xy 283.276802 -55.705248) (xy 283.232352 -55.705248)
			(xy 283.232352 -56.104028) (xy 283.276802 -56.104028)
		)
		(stroke
			(width 0)
			(type solid)
		)
		(fill yes)
		(layer "In2.Cu")
		(net "M_A_DQ<55>")
	)
	(gr_poly
		(pts
			(xy 283.469842 -54.11851) (xy 283.469842 -53.88991) (xy 283.276802 -53.80101) (xy 283.232352 -53.80101)
			(xy 283.232352 -54.20741) (xy 283.276802 -54.20741)
		)
		(stroke
			(width 0)
			(type solid)
		)
		(fill yes)
		(layer "In2.Cu")
		(net "M_A_DQ<55>")
	)
	(gr_poly
		(pts
			(xy 283.549852 -104.198166) (xy 283.549852 -103.969566) (xy 283.356812 -103.880666) (xy 283.312362 -103.880666)
			(xy 283.312362 -104.287066) (xy 283.356812 -104.287066)
		)
		(stroke
			(width 0)
			(type solid)
		)
		(fill yes)
		(layer "In2.Cu")
		(net "M_D_DQS_DN<15>")
	)
	(gr_poly
		(pts
			(xy 283.576522 -50.048668) (xy 283.532072 -50.048668) (xy 283.339032 -50.137568) (xy 283.339032 -50.366168)
			(xy 283.532072 -50.455068) (xy 283.576522 -50.455068)
		)
		(stroke
			(width 0)
			(type solid)
		)
		(fill yes)
		(layer "In2.Cu")
		(net "M_A_DQ<54>")
	)
	(gr_poly
		(pts
			(xy 283.576522 -49.058068) (xy 283.532072 -49.058068) (xy 283.339032 -49.146968) (xy 283.339032 -49.375568)
			(xy 283.532072 -49.464468) (xy 283.576522 -49.464468)
		)
		(stroke
			(width 0)
			(type solid)
		)
		(fill yes)
		(layer "In2.Cu")
		(net "M_A_DQ<54>")
	)
	(gr_poly
		(pts
			(xy 283.590492 -51.507898) (xy 283.516832 -51.308762) (xy 283.485336 -51.277266) (xy 283.198062 -51.56454)
			(xy 283.229558 -51.596036) (xy 283.428694 -51.669696)
		)
		(stroke
			(width 0)
			(type solid)
		)
		(fill yes)
		(layer "In2.Cu")
		(net "M_A_DQ<55>")
	)
	(gr_poly
		(pts
			(xy 283.656024 -97.891854) (xy 283.633672 -97.853246) (xy 283.47162 -97.750376) (xy 283.280358 -97.860866)
			(xy 283.288486 -98.052636) (xy 283.310584 -98.091244)
		)
		(stroke
			(width 0)
			(type solid)
		)
		(fill yes)
		(layer "In2.Cu")
		(net "M_D_DQS_DP<15>")
	)
	(gr_poly
		(pts
			(xy 283.731208 -103.06177) (xy 283.731208 -102.84079) (xy 283.561028 -102.75189) (xy 283.516578 -102.75189)
			(xy 283.516578 -103.15067) (xy 283.561028 -103.15067)
		)
		(stroke
			(width 0)
			(type solid)
		)
		(fill yes)
		(layer "In2.Cu")
		(net "M_D_DQS_DN<15>")
	)
	(gr_poly
		(pts
			(xy 283.731462 -102.08387) (xy 283.731462 -101.86289) (xy 283.561282 -101.77399) (xy 283.516832 -101.77399)
			(xy 283.516832 -102.17277) (xy 283.561282 -102.17277)
		)
		(stroke
			(width 0)
			(type solid)
		)
		(fill yes)
		(layer "In2.Cu")
		(net "M_D_DQS_DN<15>")
	)
	(gr_poly
		(pts
			(xy 283.731462 -101.09581) (xy 283.731462 -100.87483) (xy 283.561282 -100.78593) (xy 283.516832 -100.78593)
			(xy 283.516832 -101.18471) (xy 283.561282 -101.18471)
		)
		(stroke
			(width 0)
			(type solid)
		)
		(fill yes)
		(layer "In2.Cu")
		(net "M_D_DQS_DN<15>")
	)
	(gr_poly
		(pts
			(xy 283.731462 -100.10267) (xy 283.731462 -99.88169) (xy 283.561282 -99.79279) (xy 283.516832 -99.79279)
			(xy 283.516832 -100.19157) (xy 283.561282 -100.19157)
		)
		(stroke
			(width 0)
			(type solid)
		)
		(fill yes)
		(layer "In2.Cu")
		(net "M_D_DQS_DN<15>")
	)
	(gr_poly
		(pts
			(xy 283.731462 -99.099878) (xy 283.731462 -98.878898) (xy 283.561282 -98.789998) (xy 283.516832 -98.789998)
			(xy 283.516832 -99.188778) (xy 283.561282 -99.188778)
		)
		(stroke
			(width 0)
			(type solid)
		)
		(fill yes)
		(layer "In2.Cu")
		(net "M_D_DQS_DN<15>")
	)
	(gr_poly
		(pts
			(xy 283.756608 -54.23281) (xy 283.712158 -54.23281) (xy 283.519118 -54.32171) (xy 283.519118 -54.55031)
			(xy 283.712158 -54.63921) (xy 283.756608 -54.63921)
		)
		(stroke
			(width 0)
			(type solid)
		)
		(fill yes)
		(layer "In2.Cu")
		(net "M_A_DQ<50>")
	)
	(gr_poly
		(pts
			(xy 283.922724 -52.893976) (xy 283.878274 -52.893976) (xy 283.685234 -52.982876) (xy 283.685234 -53.211476)
			(xy 283.878274 -53.300376) (xy 283.922724 -53.300376)
		)
		(stroke
			(width 0)
			(type solid)
		)
		(fill yes)
		(layer "In2.Cu")
		(net "M_A_DQ<50>")
	)
	(gr_poly
		(pts
			(xy 283.922724 -51.776376) (xy 283.878274 -51.776376) (xy 283.685234 -51.865276) (xy 283.685234 -52.093876)
			(xy 283.878274 -52.182776) (xy 283.922724 -52.182776)
		)
		(stroke
			(width 0)
			(type solid)
		)
		(fill yes)
		(layer "In2.Cu")
		(net "M_A_DQ<50>")
	)
	(gr_poly
		(pts
			(xy 284.004512 -50.366168) (xy 284.004512 -50.137568) (xy 283.811472 -50.048668) (xy 283.767022 -50.048668)
			(xy 283.767022 -50.455068) (xy 283.811472 -50.455068)
		)
		(stroke
			(width 0)
			(type solid)
		)
		(fill yes)
		(layer "In2.Cu")
		(net "M_A_DQ<55>")
	)
	(gr_poly
		(pts
			(xy 284.004512 -49.375568) (xy 284.004512 -49.146968) (xy 283.811472 -49.058068) (xy 283.767022 -49.058068)
			(xy 283.767022 -49.464468) (xy 283.811472 -49.464468)
		)
		(stroke
			(width 0)
			(type solid)
		)
		(fill yes)
		(layer "In2.Cu")
		(net "M_A_DQ<55>")
	)
	(gr_poly
		(pts
			(xy 284.051756 -105.135172) (xy 284.007306 -105.135172) (xy 283.814266 -105.224072) (xy 283.814266 -105.452672)
			(xy 284.007306 -105.541572) (xy 284.051756 -105.541572)
		)
		(stroke
			(width 0)
			(type solid)
		)
		(fill yes)
		(layer "In2.Cu")
		(net "M_D_DQS_DN<6>")
	)
	(gr_poly
		(pts
			(xy 284.051756 -104.144572) (xy 284.007306 -104.144572) (xy 283.814266 -104.233472) (xy 283.814266 -104.462072)
			(xy 284.007306 -104.550972) (xy 284.051756 -104.550972)
		)
		(stroke
			(width 0)
			(type solid)
		)
		(fill yes)
		(layer "In2.Cu")
		(net "M_D_DQS_DN<6>")
	)
	(gr_poly
		(pts
			(xy 284.051756 -102.752398) (xy 284.007306 -102.752398) (xy 283.837126 -102.841298) (xy 283.837126 -103.062278)
			(xy 284.007306 -103.151178) (xy 284.051756 -103.151178)
		)
		(stroke
			(width 0)
			(type solid)
		)
		(fill yes)
		(layer "In2.Cu")
		(net "M_D_DQS_DN<6>")
	)
	(gr_poly
		(pts
			(xy 284.051756 -101.761798) (xy 284.007306 -101.761798) (xy 283.837126 -101.850698) (xy 283.837126 -102.071678)
			(xy 284.007306 -102.160578) (xy 284.051756 -102.160578)
		)
		(stroke
			(width 0)
			(type solid)
		)
		(fill yes)
		(layer "In2.Cu")
		(net "M_D_DQS_DN<6>")
	)
	(gr_poly
		(pts
			(xy 284.051756 -100.771198) (xy 284.007306 -100.771198) (xy 283.837126 -100.860098) (xy 283.837126 -101.081078)
			(xy 284.007306 -101.169978) (xy 284.051756 -101.169978)
		)
		(stroke
			(width 0)
			(type solid)
		)
		(fill yes)
		(layer "In2.Cu")
		(net "M_D_DQS_DN<6>")
	)
	(gr_poly
		(pts
			(xy 284.150054 -100.364544) (xy 283.96692 -100.010214) (xy 283.92755 -100.030534) (xy 283.81706 -100.18776)
			(xy 283.91866 -100.384102) (xy 284.110684 -100.384864)
		)
		(stroke
			(width 0)
			(type solid)
		)
		(fill yes)
		(layer "In2.Cu")
		(net "M_D_DQS_DN<6>")
	)
	(gr_poly
		(pts
			(xy 284.184598 -54.55031) (xy 284.184598 -54.32171) (xy 283.991558 -54.23281) (xy 283.947108 -54.23281)
			(xy 283.947108 -54.63921) (xy 283.991558 -54.63921)
		)
		(stroke
			(width 0)
			(type solid)
		)
		(fill yes)
		(layer "In2.Cu")
		(net "M_A_DQ<51>")
	)
	(gr_poly
		(pts
			(xy 284.2768 -51.301142) (xy 284.245304 -51.269646) (xy 284.046168 -51.195986) (xy 283.88437 -51.357784)
			(xy 283.95803 -51.55692) (xy 283.989526 -51.588416)
		)
		(stroke
			(width 0)
			(type solid)
		)
		(fill yes)
		(layer "In2.Cu")
		(net "M_A_DQ<50>")
	)
	(gr_poly
		(pts
			(xy 284.305502 -56.504078) (xy 284.305502 -56.283098) (xy 284.135322 -56.194198) (xy 284.090872 -56.194198)
			(xy 284.090872 -56.592978) (xy 284.135322 -56.592978)
		)
		(stroke
			(width 0)
			(type solid)
		)
		(fill yes)
		(layer "In2.Cu")
		(net "M_A_DQ<51>")
	)
	(gr_poly
		(pts
			(xy 284.305502 -55.513478) (xy 284.305502 -55.292498) (xy 284.135322 -55.203598) (xy 284.090872 -55.203598)
			(xy 284.090872 -55.602378) (xy 284.135322 -55.602378)
		)
		(stroke
			(width 0)
			(type solid)
		)
		(fill yes)
		(layer "In2.Cu")
		(net "M_A_DQ<51>")
	)
	(gr_poly
		(pts
			(xy 284.343602 -50.494438) (xy 284.299152 -50.494438) (xy 284.106112 -50.583338) (xy 284.106112 -50.811938)
			(xy 284.299152 -50.900838) (xy 284.343602 -50.900838)
		)
		(stroke
			(width 0)
			(type solid)
		)
		(fill yes)
		(layer "In2.Cu")
		(net "M_A_DQ<50>")
	)
	(gr_poly
		(pts
			(xy 284.350714 -53.211476) (xy 284.350714 -52.982876) (xy 284.157674 -52.893976) (xy 284.113224 -52.893976)
			(xy 284.113224 -53.300376) (xy 284.157674 -53.300376)
		)
		(stroke
			(width 0)
			(type solid)
		)
		(fill yes)
		(layer "In2.Cu")
		(net "M_A_DQ<51>")
	)
	(gr_poly
		(pts
			(xy 284.350714 -52.220876) (xy 284.350714 -51.992276) (xy 284.157674 -51.903376) (xy 284.113224 -51.903376)
			(xy 284.113224 -52.309776) (xy 284.157674 -52.309776)
		)
		(stroke
			(width 0)
			(type solid)
		)
		(fill yes)
		(layer "In2.Cu")
		(net "M_A_DQ<51>")
	)
	(gr_poly
		(pts
			(xy 284.479746 -105.452672) (xy 284.479746 -105.224072) (xy 284.286706 -105.135172) (xy 284.242256 -105.135172)
			(xy 284.242256 -105.541572) (xy 284.286706 -105.541572)
		)
		(stroke
			(width 0)
			(type solid)
		)
		(fill yes)
		(layer "In2.Cu")
		(net "M_D_DQS_DP<6>")
	)
	(gr_poly
		(pts
			(xy 284.479746 -104.462072) (xy 284.479746 -104.233472) (xy 284.286706 -104.144572) (xy 284.242256 -104.144572)
			(xy 284.242256 -104.550972) (xy 284.286706 -104.550972)
		)
		(stroke
			(width 0)
			(type solid)
		)
		(fill yes)
		(layer "In2.Cu")
		(net "M_D_DQS_DP<6>")
	)
	(gr_poly
		(pts
			(xy 284.589982 -103.570024) (xy 284.589982 -103.349044) (xy 284.419802 -103.260144) (xy 284.375352 -103.260144)
			(xy 284.375352 -103.658924) (xy 284.419802 -103.658924)
		)
		(stroke
			(width 0)
			(type solid)
		)
		(fill yes)
		(layer "In2.Cu")
		(net "M_D_DQS_DP<6>")
	)
	(gr_poly
		(pts
			(xy 284.589982 -102.579424) (xy 284.589982 -102.358444) (xy 284.419802 -102.269544) (xy 284.375352 -102.269544)
			(xy 284.375352 -102.668324) (xy 284.419802 -102.668324)
		)
		(stroke
			(width 0)
			(type solid)
		)
		(fill yes)
		(layer "In2.Cu")
		(net "M_D_DQS_DP<6>")
	)
	(gr_poly
		(pts
			(xy 284.589982 -101.588824) (xy 284.589982 -101.367844) (xy 284.419802 -101.278944) (xy 284.375352 -101.278944)
			(xy 284.375352 -101.677724) (xy 284.419802 -101.677724)
		)
		(stroke
			(width 0)
			(type solid)
		)
		(fill yes)
		(layer "In2.Cu")
		(net "M_D_DQS_DP<6>")
	)
	(gr_poly
		(pts
			(xy 284.589982 -100.598224) (xy 284.589982 -100.377244) (xy 284.419802 -100.288344) (xy 284.375352 -100.288344)
			(xy 284.375352 -100.687124) (xy 284.419802 -100.687124)
		)
		(stroke
			(width 0)
			(type solid)
		)
		(fill yes)
		(layer "In2.Cu")
		(net "M_D_DQS_DP<6>")
	)
	(gr_poly
		(pts
			(xy 284.589982 -97.613724) (xy 284.589982 -97.392744) (xy 284.419802 -97.303844) (xy 284.375352 -97.303844)
			(xy 284.375352 -97.702624) (xy 284.419802 -97.702624)
		)
		(stroke
			(width 0)
			(type solid)
		)
		(fill yes)
		(layer "In2.Cu")
		(net "M_D_DQS_DN<15>")
	)
	(gr_poly
		(pts
			(xy 284.599888 -98.445828) (xy 284.568392 -98.414586) (xy 284.385258 -98.356928) (xy 284.229048 -98.513138)
			(xy 284.286452 -98.696526) (xy 284.317948 -98.727768)
		)
		(stroke
			(width 0)
			(type solid)
		)
		(fill yes)
		(layer "In2.Cu")
		(net "M_D_DQ<54>")
	)
	(gr_poly
		(pts
			(xy 284.625542 -55.203598) (xy 284.581092 -55.203598) (xy 284.410912 -55.292498) (xy 284.410912 -55.513478)
			(xy 284.581092 -55.602378) (xy 284.625542 -55.602378)
		)
		(stroke
			(width 0)
			(type solid)
		)
		(fill yes)
		(layer "In2.Cu")
		(net "M_A_DQ<60>")
	)
	(gr_poly
		(pts
			(xy 284.625542 -54.212998) (xy 284.581092 -54.212998) (xy 284.410912 -54.301898) (xy 284.410912 -54.522878)
			(xy 284.581092 -54.611778) (xy 284.625542 -54.611778)
		)
		(stroke
			(width 0)
			(type solid)
		)
		(fill yes)
		(layer "In2.Cu")
		(net "M_A_DQ<60>")
	)
	(gr_poly
		(pts
			(xy 284.74162 -49.762918) (xy 284.710124 -49.731422) (xy 284.510988 -49.657762) (xy 284.34919 -49.81956)
			(xy 284.42285 -50.018696) (xy 284.454346 -50.050192)
		)
		(stroke
			(width 0)
			(type solid)
		)
		(fill yes)
		(layer "In2.Cu")
		(net "M_A_DQ<50>")
	)
	(gr_poly
		(pts
			(xy 284.771592 -51.065938) (xy 284.771592 -50.837338) (xy 284.578552 -50.748438) (xy 284.534102 -50.748438)
			(xy 284.534102 -51.154838) (xy 284.578552 -51.154838)
		)
		(stroke
			(width 0)
			(type solid)
		)
		(fill yes)
		(layer "In2.Cu")
		(net "M_A_DQ<51>")
	)
	(gr_poly
		(pts
			(xy 284.910276 -103.260144) (xy 284.865826 -103.260144) (xy 284.695646 -103.349044) (xy 284.695646 -103.570024)
			(xy 284.865826 -103.658924) (xy 284.910276 -103.658924)
		)
		(stroke
			(width 0)
			(type solid)
		)
		(fill yes)
		(layer "In2.Cu")
		(net "M_D_DQ<54>")
	)
	(gr_poly
		(pts
			(xy 284.910276 -102.269544) (xy 284.865826 -102.269544) (xy 284.695646 -102.358444) (xy 284.695646 -102.579424)
			(xy 284.865826 -102.668324) (xy 284.910276 -102.668324)
		)
		(stroke
			(width 0)
			(type solid)
		)
		(fill yes)
		(layer "In2.Cu")
		(net "M_D_DQ<54>")
	)
	(gr_poly
		(pts
			(xy 284.910276 -101.278944) (xy 284.865826 -101.278944) (xy 284.695646 -101.367844) (xy 284.695646 -101.588824)
			(xy 284.865826 -101.677724) (xy 284.910276 -101.677724)
		)
		(stroke
			(width 0)
			(type solid)
		)
		(fill yes)
		(layer "In2.Cu")
		(net "M_D_DQ<54>")
	)
	(gr_poly
		(pts
			(xy 284.910276 -100.288344) (xy 284.865826 -100.288344) (xy 284.695646 -100.377244) (xy 284.695646 -100.598224)
			(xy 284.865826 -100.687124) (xy 284.910276 -100.687124)
		)
		(stroke
			(width 0)
			(type solid)
		)
		(fill yes)
		(layer "In2.Cu")
		(net "M_D_DQ<54>")
	)
	(gr_poly
		(pts
			(xy 284.970474 -105.492042) (xy 284.926024 -105.492042) (xy 284.732984 -105.580942) (xy 284.732984 -105.809542)
			(xy 284.926024 -105.898442) (xy 284.970474 -105.898442)
		)
		(stroke
			(width 0)
			(type solid)
		)
		(fill yes)
		(layer "In2.Cu")
		(net "M_D_DQ<54>")
	)
	(gr_poly
		(pts
			(xy 284.970474 -104.501442) (xy 284.926024 -104.501442) (xy 284.732984 -104.590342) (xy 284.732984 -104.818942)
			(xy 284.926024 -104.907842) (xy 284.970474 -104.907842)
		)
		(stroke
			(width 0)
			(type solid)
		)
		(fill yes)
		(layer "In2.Cu")
		(net "M_D_DQ<54>")
	)
	(gr_poly
		(pts
			(xy 285.013146 -50.096928) (xy 284.939486 -49.897792) (xy 284.90799 -49.866296) (xy 284.620716 -50.15357)
			(xy 284.652212 -50.185066) (xy 284.851348 -50.258726)
		)
		(stroke
			(width 0)
			(type solid)
		)
		(fill yes)
		(layer "In2.Cu")
		(net "M_A_DQ<51>")
	)
	(gr_poly
		(pts
			(xy 285.163768 -55.030624) (xy 285.163768 -54.809644) (xy 284.993588 -54.720744) (xy 284.949138 -54.720744)
			(xy 284.949138 -55.119524) (xy 284.993588 -55.119524)
		)
		(stroke
			(width 0)
			(type solid)
		)
		(fill yes)
		(layer "In2.Cu")
		(net "M_A_DQ<61>")
	)
	(gr_poly
		(pts
			(xy 285.37408 -52.764944) (xy 285.342584 -52.733702) (xy 285.143194 -52.660042) (xy 284.98165 -52.821586)
			(xy 285.05531 -53.020976) (xy 285.086552 -53.052472)
		)
		(stroke
			(width 0)
			(type solid)
		)
		(fill yes)
		(layer "In2.Cu")
		(net "M_A_DQ<60>")
	)
	(gr_poly
		(pts
			(xy 285.398464 -105.809542) (xy 285.398464 -105.580942) (xy 285.205424 -105.492042) (xy 285.160974 -105.492042)
			(xy 285.160974 -105.898442) (xy 285.205424 -105.898442)
		)
		(stroke
			(width 0)
			(type solid)
		)
		(fill yes)
		(layer "In2.Cu")
		(net "M_D_DQ<55>")
	)
	(gr_poly
		(pts
			(xy 285.398464 -104.818942) (xy 285.398464 -104.590342) (xy 285.205424 -104.501442) (xy 285.160974 -104.501442)
			(xy 285.160974 -104.907842) (xy 285.205424 -104.907842)
		)
		(stroke
			(width 0)
			(type solid)
		)
		(fill yes)
		(layer "In2.Cu")
		(net "M_D_DQ<55>")
	)
	(gr_poly
		(pts
			(xy 285.448502 -104.052878) (xy 285.448502 -103.831898) (xy 285.278322 -103.742998) (xy 285.233872 -103.742998)
			(xy 285.233872 -104.141778) (xy 285.278322 -104.141778)
		)
		(stroke
			(width 0)
			(type solid)
		)
		(fill yes)
		(layer "In2.Cu")
		(net "M_D_DQ<55>")
	)
	(gr_poly
		(pts
			(xy 285.448502 -103.062278) (xy 285.448502 -102.841298) (xy 285.278322 -102.752398) (xy 285.233872 -102.752398)
			(xy 285.233872 -103.151178) (xy 285.278322 -103.151178)
		)
		(stroke
			(width 0)
			(type solid)
		)
		(fill yes)
		(layer "In2.Cu")
		(net "M_D_DQ<55>")
	)
	(gr_poly
		(pts
			(xy 285.448502 -102.071678) (xy 285.448502 -101.850698) (xy 285.278322 -101.761798) (xy 285.233872 -101.761798)
			(xy 285.233872 -102.160578) (xy 285.278322 -102.160578)
		)
		(stroke
			(width 0)
			(type solid)
		)
		(fill yes)
		(layer "In2.Cu")
		(net "M_D_DQ<55>")
	)
	(gr_poly
		(pts
			(xy 285.448502 -101.081078) (xy 285.448502 -100.860098) (xy 285.278322 -100.771198) (xy 285.233872 -100.771198)
			(xy 285.233872 -101.169978) (xy 285.278322 -101.169978)
		)
		(stroke
			(width 0)
			(type solid)
		)
		(fill yes)
		(layer "In2.Cu")
		(net "M_D_DQ<55>")
	)
	(gr_poly
		(pts
			(xy 285.448502 -100.090478) (xy 285.448502 -99.869498) (xy 285.278322 -99.780598) (xy 285.233872 -99.780598)
			(xy 285.233872 -100.179378) (xy 285.278322 -100.179378)
		)
		(stroke
			(width 0)
			(type solid)
		)
		(fill yes)
		(layer "In2.Cu")
		(net "M_D_DQ<55>")
	)
	(gr_poly
		(pts
			(xy 285.484062 -54.720744) (xy 285.439612 -54.720744) (xy 285.269432 -54.809644) (xy 285.269432 -55.030624)
			(xy 285.439612 -55.119524) (xy 285.484062 -55.119524)
		)
		(stroke
			(width 0)
			(type solid)
		)
		(fill yes)
		(layer "In2.Cu")
		(net "M_A_DQ<56>")
	)
	(gr_poly
		(pts
			(xy 285.485078 -99.003358) (xy 285.507176 -98.96475) (xy 285.161736 -98.76536) (xy 285.139638 -98.803968)
			(xy 285.13151 -98.995738) (xy 285.322772 -99.106228)
		)
		(stroke
			(width 0)
			(type solid)
		)
		(fill yes)
		(layer "In2.Cu")
		(net "M_D_DQ<50>")
	)
	(gr_poly
		(pts
			(xy 285.613856 -53.13045) (xy 285.540196 -52.931314) (xy 285.5087 -52.899818) (xy 285.221426 -53.187092)
			(xy 285.252922 -53.218588) (xy 285.452058 -53.292248)
		)
		(stroke
			(width 0)
			(type solid)
		)
		(fill yes)
		(layer "In2.Cu")
		(net "M_A_DQ<61>")
	)
	(gr_poly
		(pts
			(xy 285.615126 -51.943) (xy 285.570676 -51.943) (xy 285.377636 -52.0319) (xy 285.377636 -52.2605)
			(xy 285.570676 -52.3494) (xy 285.615126 -52.3494)
		)
		(stroke
			(width 0)
			(type solid)
		)
		(fill yes)
		(layer "In2.Cu")
		(net "M_A_DQ<60>")
	)
	(gr_poly
		(pts
			(xy 285.705804 -56.44388) (xy 285.835344 -56.302148) (xy 285.759652 -56.094376) (xy 285.569406 -56.068976)
			(xy 285.52775 -56.084216) (xy 285.663894 -56.45912)
		)
		(stroke
			(width 0)
			(type solid)
		)
		(fill yes)
		(layer "In2.Cu")
		(net "M_A_DQ<61>")
	)
	(gr_poly
		(pts
			(xy 285.768542 -103.740204) (xy 285.724092 -103.740204) (xy 285.553912 -103.829104) (xy 285.553912 -104.050084)
			(xy 285.724092 -104.138984) (xy 285.768542 -104.138984)
		)
		(stroke
			(width 0)
			(type solid)
		)
		(fill yes)
		(layer "In2.Cu")
		(net "M_D_DQ<50>")
	)
	(gr_poly
		(pts
			(xy 285.768542 -102.749604) (xy 285.724092 -102.749604) (xy 285.553912 -102.838504) (xy 285.553912 -103.059484)
			(xy 285.724092 -103.148384) (xy 285.768542 -103.148384)
		)
		(stroke
			(width 0)
			(type solid)
		)
		(fill yes)
		(layer "In2.Cu")
		(net "M_D_DQ<50>")
	)
	(gr_poly
		(pts
			(xy 285.768542 -101.759004) (xy 285.724092 -101.759004) (xy 285.553912 -101.847904) (xy 285.553912 -102.068884)
			(xy 285.724092 -102.157784) (xy 285.768542 -102.157784)
		)
		(stroke
			(width 0)
			(type solid)
		)
		(fill yes)
		(layer "In2.Cu")
		(net "M_D_DQ<50>")
	)
	(gr_poly
		(pts
			(xy 285.768542 -100.768404) (xy 285.724092 -100.768404) (xy 285.553912 -100.857304) (xy 285.553912 -101.078284)
			(xy 285.724092 -101.167184) (xy 285.768542 -101.167184)
		)
		(stroke
			(width 0)
			(type solid)
		)
		(fill yes)
		(layer "In2.Cu")
		(net "M_D_DQ<50>")
	)
	(gr_poly
		(pts
			(xy 285.768542 -99.777804) (xy 285.724092 -99.777804) (xy 285.553912 -99.866704) (xy 285.553912 -100.087684)
			(xy 285.724092 -100.176584) (xy 285.768542 -100.176584)
		)
		(stroke
			(width 0)
			(type solid)
		)
		(fill yes)
		(layer "In2.Cu")
		(net "M_D_DQ<50>")
	)
	(gr_poly
		(pts
			(xy 285.940246 -104.83977) (xy 285.895796 -104.83977) (xy 285.702756 -104.92867) (xy 285.702756 -105.15727)
			(xy 285.895796 -105.24617) (xy 285.940246 -105.24617)
		)
		(stroke
			(width 0)
			(type solid)
		)
		(fill yes)
		(layer "In2.Cu")
		(net "M_D_DQ<50>")
	)
	(gr_poly
		(pts
			(xy 286.022288 -54.522878) (xy 286.022288 -54.301898) (xy 285.852108 -54.212998) (xy 285.807658 -54.212998)
			(xy 285.807658 -54.611778) (xy 285.852108 -54.611778)
		)
		(stroke
			(width 0)
			(type solid)
		)
		(fill yes)
		(layer "In2.Cu")
		(net "M_A_DQ<57>")
	)
	(gr_poly
		(pts
			(xy 286.022288 -51.32451) (xy 285.990792 -51.293268) (xy 285.791402 -51.219608) (xy 285.629858 -51.381152)
			(xy 285.703518 -51.580542) (xy 285.73476 -51.612038)
		)
		(stroke
			(width 0)
			(type solid)
		)
		(fill yes)
		(layer "In2.Cu")
		(net "M_A_DQ<60>")
	)
	(gr_poly
		(pts
			(xy 286.043116 -52.2605) (xy 286.043116 -52.0319) (xy 285.850076 -51.943) (xy 285.805626 -51.943)
			(xy 285.805626 -52.3494) (xy 285.850076 -52.3494)
		)
		(stroke
			(width 0)
			(type solid)
		)
		(fill yes)
		(layer "In2.Cu")
		(net "M_A_DQ<61>")
	)
	(gr_poly
		(pts
			(xy 286.1056 -53.038756) (xy 286.074104 -53.00726) (xy 285.874968 -52.9336) (xy 285.71317 -53.095398)
			(xy 285.78683 -53.294534) (xy 285.818326 -53.32603)
		)
		(stroke
			(width 0)
			(type solid)
		)
		(fill yes)
		(layer "In2.Cu")
		(net "M_A_DQ<56>")
	)
	(gr_poly
		(pts
			(xy 286.307022 -103.572818) (xy 286.307022 -103.351838) (xy 286.136842 -103.262938) (xy 286.092392 -103.262938)
			(xy 286.092392 -103.661718) (xy 286.136842 -103.661718)
		)
		(stroke
			(width 0)
			(type solid)
		)
		(fill yes)
		(layer "In2.Cu")
		(net "M_D_DQ<51>")
	)
	(gr_poly
		(pts
			(xy 286.307022 -102.582218) (xy 286.307022 -102.361238) (xy 286.136842 -102.272338) (xy 286.092392 -102.272338)
			(xy 286.092392 -102.671118) (xy 286.136842 -102.671118)
		)
		(stroke
			(width 0)
			(type solid)
		)
		(fill yes)
		(layer "In2.Cu")
		(net "M_D_DQ<51>")
	)
	(gr_poly
		(pts
			(xy 286.307022 -101.591618) (xy 286.307022 -101.370638) (xy 286.136842 -101.281738) (xy 286.092392 -101.281738)
			(xy 286.092392 -101.680518) (xy 286.136842 -101.680518)
		)
		(stroke
			(width 0)
			(type solid)
		)
		(fill yes)
		(layer "In2.Cu")
		(net "M_D_DQ<51>")
	)
	(gr_poly
		(pts
			(xy 286.307022 -100.601018) (xy 286.307022 -100.380038) (xy 286.136842 -100.291138) (xy 286.092392 -100.291138)
			(xy 286.092392 -100.689918) (xy 286.136842 -100.689918)
		)
		(stroke
			(width 0)
			(type solid)
		)
		(fill yes)
		(layer "In2.Cu")
		(net "M_D_DQ<51>")
	)
	(gr_poly
		(pts
			(xy 286.307022 -99.610418) (xy 286.307022 -99.389438) (xy 286.136842 -99.300538) (xy 286.092392 -99.300538)
			(xy 286.092392 -99.699318) (xy 286.136842 -99.699318)
		)
		(stroke
			(width 0)
			(type solid)
		)
		(fill yes)
		(layer "In2.Cu")
		(net "M_D_DQ<51>")
	)
	(gr_poly
		(pts
			(xy 286.340042 -52.33543) (xy 286.295592 -52.33543) (xy 286.102552 -52.42433) (xy 286.102552 -52.65293)
			(xy 286.295592 -52.74183) (xy 286.340042 -52.74183)
		)
		(stroke
			(width 0)
			(type solid)
		)
		(fill yes)
		(layer "In2.Cu")
		(net "M_A_DQ<56>")
	)
	(gr_poly
		(pts
			(xy 286.342582 -56.194198) (xy 286.298132 -56.194198) (xy 286.127952 -56.283098) (xy 286.127952 -56.504078)
			(xy 286.298132 -56.592978) (xy 286.342582 -56.592978)
		)
		(stroke
			(width 0)
			(type solid)
		)
		(fill yes)
		(layer "In2.Cu")
		(net "M_A_DQ<57>")
	)
	(gr_poly
		(pts
			(xy 286.342582 -54.212998) (xy 286.298132 -54.212998) (xy 286.127952 -54.301898) (xy 286.127952 -54.522878)
			(xy 286.298132 -54.611778) (xy 286.342582 -54.611778)
		)
		(stroke
			(width 0)
			(type solid)
		)
		(fill yes)
		(layer "In2.Cu")
		(net "M_A_DQS_DP<16>")
	)
	(gr_poly
		(pts
			(xy 286.368236 -105.15727) (xy 286.368236 -104.92867) (xy 286.175196 -104.83977) (xy 286.130746 -104.83977)
			(xy 286.130746 -105.24617) (xy 286.175196 -105.24617)
		)
		(stroke
			(width 0)
			(type solid)
		)
		(fill yes)
		(layer "In2.Cu")
		(net "M_D_DQ<51>")
	)
	(gr_poly
		(pts
			(xy 286.420814 -53.328824) (xy 286.347154 -53.129688) (xy 286.315658 -53.098192) (xy 286.028384 -53.385466)
			(xy 286.05988 -53.416962) (xy 286.259016 -53.490622)
		)
		(stroke
			(width 0)
			(type solid)
		)
		(fill yes)
		(layer "In2.Cu")
		(net "M_A_DQ<57>")
	)
	(gr_poly
		(pts
			(xy 286.516064 -51.436016) (xy 286.442404 -51.23688) (xy 286.410908 -51.205384) (xy 286.123634 -51.492658)
			(xy 286.15513 -51.524154) (xy 286.354266 -51.597814)
		)
		(stroke
			(width 0)
			(type solid)
		)
		(fill yes)
		(layer "In2.Cu")
		(net "M_A_DQ<61>")
	)
	(gr_poly
		(pts
			(xy 286.627062 -100.288344) (xy 286.582612 -100.288344) (xy 286.412432 -100.377244) (xy 286.412432 -100.598224)
			(xy 286.582612 -100.687124) (xy 286.627062 -100.687124)
		)
		(stroke
			(width 0)
			(type solid)
		)
		(fill yes)
		(layer "In2.Cu")
		(net "M_D_DQ<60>")
	)
	(gr_poly
		(pts
			(xy 286.627062 -99.297744) (xy 286.582612 -99.297744) (xy 286.412432 -99.386644) (xy 286.412432 -99.607624)
			(xy 286.582612 -99.696524) (xy 286.627062 -99.696524)
		)
		(stroke
			(width 0)
			(type solid)
		)
		(fill yes)
		(layer "In2.Cu")
		(net "M_D_DQ<60>")
	)
	(gr_poly
		(pts
			(xy 286.627062 -98.307144) (xy 286.582612 -98.307144) (xy 286.412432 -98.396044) (xy 286.412432 -98.617024)
			(xy 286.582612 -98.705924) (xy 286.627062 -98.705924)
		)
		(stroke
			(width 0)
			(type solid)
		)
		(fill yes)
		(layer "In2.Cu")
		(net "M_D_DQ<60>")
	)
	(gr_poly
		(pts
			(xy 286.762698 -103.162862) (xy 286.718248 -103.162862) (xy 286.525208 -103.251762) (xy 286.525208 -103.480362)
			(xy 286.718502 -103.569262) (xy 286.762698 -103.569262)
		)
		(stroke
			(width 0)
			(type solid)
		)
		(fill yes)
		(layer "In2.Cu")
		(net "M_D_DQ<60>")
	)
	(gr_poly
		(pts
			(xy 286.80537 -53.810662) (xy 286.783018 -53.772054) (xy 286.620966 -53.669184) (xy 286.429704 -53.779674)
			(xy 286.437832 -53.971444) (xy 286.45993 -54.009798)
		)
		(stroke
			(width 0)
			(type solid)
		)
		(fill yes)
		(layer "In2.Cu")
		(net "M_A_DQS_DP<16>")
	)
	(gr_poly
		(pts
			(xy 286.880554 -55.01894) (xy 286.880554 -54.79796) (xy 286.710374 -54.70906) (xy 286.665924 -54.70906)
			(xy 286.66567 -55.10784) (xy 286.710374 -55.10784)
		)
		(stroke
			(width 0)
			(type solid)
		)
		(fill yes)
		(layer "In2.Cu")
		(net "M_A_DQS_DN<16>")
	)
	(gr_poly
		(pts
			(xy 286.894016 -101.501448) (xy 286.849566 -101.501448) (xy 286.656526 -101.590348) (xy 286.656526 -101.818948)
			(xy 286.84982 -101.907848) (xy 286.894016 -101.907848)
		)
		(stroke
			(width 0)
			(type solid)
		)
		(fill yes)
		(layer "In2.Cu")
		(net "M_D_DQ<60>")
	)
	(gr_poly
		(pts
			(xy 286.898334 -51.555904) (xy 286.866838 -51.524408) (xy 286.667702 -51.450748) (xy 286.505904 -51.612546)
			(xy 286.579564 -51.811682) (xy 286.61106 -51.843178)
		)
		(stroke
			(width 0)
			(type solid)
		)
		(fill yes)
		(layer "In2.Cu")
		(net "M_A_DQ<56>")
	)
	(gr_poly
		(pts
			(xy 287.138618 -51.921918) (xy 287.064958 -51.722528) (xy 287.033716 -51.691032) (xy 286.746188 -51.97856)
			(xy 286.777684 -52.009802) (xy 286.977074 -52.083462)
		)
		(stroke
			(width 0)
			(type solid)
		)
		(fill yes)
		(layer "In2.Cu")
		(net "M_A_DQ<57>")
	)
	(gr_poly
		(pts
			(xy 287.165288 -100.090478) (xy 287.165288 -99.869498) (xy 286.995108 -99.780598) (xy 286.950658 -99.780598)
			(xy 286.950658 -100.179378) (xy 286.995108 -100.179378)
		)
		(stroke
			(width 0)
			(type solid)
		)
		(fill yes)
		(layer "In2.Cu")
		(net "M_D_DQ<61>")
	)
	(gr_poly
		(pts
			(xy 287.165288 -99.099878) (xy 287.165288 -98.878898) (xy 286.995108 -98.789998) (xy 286.950658 -98.789998)
			(xy 286.950658 -99.188778) (xy 286.995108 -99.188778)
		)
		(stroke
			(width 0)
			(type solid)
		)
		(fill yes)
		(layer "In2.Cu")
		(net "M_D_DQ<61>")
	)
	(gr_poly
		(pts
			(xy 287.190942 -103.495094) (xy 287.190688 -103.266494) (xy 286.997648 -103.177594) (xy 286.953198 -103.177848)
			(xy 286.953198 -103.583994) (xy 286.997648 -103.583994)
		)
		(stroke
			(width 0)
			(type solid)
		)
		(fill yes)
		(layer "In2.Cu")
		(net "M_D_DQ<61>")
	)
	(gr_poly
		(pts
			(xy 287.201102 -56.701944) (xy 287.156652 -56.701944) (xy 286.986472 -56.790844) (xy 286.986472 -57.011824)
			(xy 287.156652 -57.100724) (xy 287.201102 -57.100724)
		)
		(stroke
			(width 0)
			(type solid)
		)
		(fill yes)
		(layer "In2.Cu")
		(net "M_A_DQS_DN<7>")
	)
	(gr_poly
		(pts
			(xy 287.201102 -55.711344) (xy 287.156652 -55.711344) (xy 286.986472 -55.800244) (xy 286.986472 -56.021224)
			(xy 287.156652 -56.110124) (xy 287.201102 -56.110124)
		)
		(stroke
			(width 0)
			(type solid)
		)
		(fill yes)
		(layer "In2.Cu")
		(net "M_A_DQS_DN<7>")
	)
	(gr_poly
		(pts
			(xy 287.201102 -52.733194) (xy 287.156652 -52.733194) (xy 286.986472 -52.822094) (xy 286.986472 -53.043074)
			(xy 287.156652 -53.131974) (xy 287.201102 -53.131974)
		)
		(stroke
			(width 0)
			(type solid)
		)
		(fill yes)
		(layer "In2.Cu")
		(net "M_A_DQS_DP<16>")
	)
	(gr_poly
		(pts
			(xy 287.322514 -101.832918) (xy 287.32226 -101.604318) (xy 287.12922 -101.515418) (xy 287.08477 -101.515672)
			(xy 287.08477 -101.921818) (xy 287.12922 -101.921818)
		)
		(stroke
			(width 0)
			(type solid)
		)
		(fill yes)
		(layer "In2.Cu")
		(net "M_D_DQ<61>")
	)
	(gr_poly
		(pts
			(xy 287.437576 -54.066948) (xy 287.429448 -53.875178) (xy 287.40735 -53.83657) (xy 287.06191 -54.036214)
			(xy 287.084262 -54.074568) (xy 287.246314 -54.177438)
		)
		(stroke
			(width 0)
			(type solid)
		)
		(fill yes)
		(layer "In2.Cu")
		(net "M_A_DQS_DN<16>")
	)
	(gr_poly
		(pts
			(xy 287.485582 -99.780598) (xy 287.441132 -99.780598) (xy 287.270952 -99.869498) (xy 287.270952 -100.090478)
			(xy 287.441132 -100.179378) (xy 287.485582 -100.179378)
		)
		(stroke
			(width 0)
			(type solid)
		)
		(fill yes)
		(layer "In2.Cu")
		(net "M_D_DQ<56>")
	)
	(gr_poly
		(pts
			(xy 287.485582 -98.789998) (xy 287.441132 -98.789998) (xy 287.270952 -98.878898) (xy 287.270952 -99.099878)
			(xy 287.441132 -99.188778) (xy 287.485582 -99.188778)
		)
		(stroke
			(width 0)
			(type solid)
		)
		(fill yes)
		(layer "In2.Cu")
		(net "M_D_DQ<56>")
	)
	(gr_poly
		(pts
			(xy 287.609534 -50.844704) (xy 287.578038 -50.813208) (xy 287.378902 -50.739548) (xy 287.217104 -50.901346)
			(xy 287.290764 -51.100482) (xy 287.32226 -51.131978)
		)
		(stroke
			(width 0)
			(type solid)
		)
		(fill yes)
		(layer "In2.Cu")
		(net "M_A_DQ<56>")
	)
	(gr_poly
		(pts
			(xy 287.618424 -102.051358) (xy 287.57372 -102.051358) (xy 287.38068 -102.140258) (xy 287.380934 -102.368858)
			(xy 287.573974 -102.457758) (xy 287.618424 -102.457758)
		)
		(stroke
			(width 0)
			(type solid)
		)
		(fill yes)
		(layer "In2.Cu")
		(net "M_D_DQ<56>")
	)
	(gr_poly
		(pts
			(xy 287.618424 -101.060758) (xy 287.57372 -101.060758) (xy 287.38068 -101.149658) (xy 287.380934 -101.378258)
			(xy 287.573974 -101.467158) (xy 287.618424 -101.467158)
		)
		(stroke
			(width 0)
			(type solid)
		)
		(fill yes)
		(layer "In2.Cu")
		(net "M_D_DQ<56>")
	)
	(gr_poly
		(pts
			(xy 287.661604 -54.306978) (xy 287.639252 -54.268624) (xy 287.4772 -54.165754) (xy 287.285938 -54.276244)
			(xy 287.294066 -54.468014) (xy 287.316164 -54.506622)
		)
		(stroke
			(width 0)
			(type solid)
		)
		(fill yes)
		(layer "In2.Cu")
		(net "M_A_DQS_DN<7>")
	)
	(gr_poly
		(pts
			(xy 287.707324 -105.146856) (xy 287.738566 -105.11536) (xy 287.451292 -104.828086) (xy 287.419796 -104.859582)
			(xy 287.346136 -105.058972) (xy 287.507934 -105.220516)
		)
		(stroke
			(width 0)
			(type solid)
		)
		(fill yes)
		(layer "In2.Cu")
		(net "M_D_DQ<60>")
	)
	(gr_poly
		(pts
			(xy 287.739328 -57.494678) (xy 287.739328 -57.273698) (xy 287.569148 -57.184798) (xy 287.524698 -57.184798)
			(xy 287.524698 -57.583578) (xy 287.569148 -57.583578)
		)
		(stroke
			(width 0)
			(type solid)
		)
		(fill yes)
		(layer "In2.Cu")
		(net "M_A_DQS_DP<7>")
	)
	(gr_poly
		(pts
			(xy 287.739328 -56.504078) (xy 287.739328 -56.283098) (xy 287.569148 -56.194198) (xy 287.524698 -56.194198)
			(xy 287.524698 -56.592978) (xy 287.569148 -56.592978)
		)
		(stroke
			(width 0)
			(type solid)
		)
		(fill yes)
		(layer "In2.Cu")
		(net "M_A_DQS_DP<7>")
	)
	(gr_poly
		(pts
			(xy 287.739328 -53.538374) (xy 287.739328 -53.317394) (xy 287.569148 -53.228494) (xy 287.524698 -53.228494)
			(xy 287.524698 -53.627274) (xy 287.569148 -53.627274)
		)
		(stroke
			(width 0)
			(type solid)
		)
		(fill yes)
		(layer "In2.Cu")
		(net "M_A_DQS_DN<16>")
	)
	(gr_poly
		(pts
			(xy 287.849818 -51.210718) (xy 287.776158 -51.011328) (xy 287.744916 -50.979832) (xy 287.457388 -51.26736)
			(xy 287.488884 -51.298602) (xy 287.688274 -51.372262)
		)
		(stroke
			(width 0)
			(type solid)
		)
		(fill yes)
		(layer "In2.Cu")
		(net "M_A_DQ<57>")
	)
	(gr_poly
		(pts
			(xy 287.877758 -51.929284) (xy 287.846262 -51.898042) (xy 287.646872 -51.824382) (xy 287.485328 -51.985926)
			(xy 287.558988 -52.185316) (xy 287.59023 -52.216812)
		)
		(stroke
			(width 0)
			(type solid)
		)
		(fill yes)
		(layer "In2.Cu")
		(net "M_A_DQS_DP<16>")
	)
	(gr_poly
		(pts
			(xy 287.904936 -104.949244) (xy 287.978596 -104.749854) (xy 287.816798 -104.58831) (xy 287.617408 -104.66197)
			(xy 287.586166 -104.693466) (xy 287.87344 -104.98074)
		)
		(stroke
			(width 0)
			(type solid)
		)
		(fill yes)
		(layer "In2.Cu")
		(net "M_D_DQ<61>")
	)
	(gr_poly
		(pts
			(xy 288.046414 -102.001828) (xy 288.04616 -101.773228) (xy 287.85312 -101.684328) (xy 287.80867 -101.684582)
			(xy 287.80867 -102.090728) (xy 287.85312 -102.090728)
		)
		(stroke
			(width 0)
			(type solid)
		)
		(fill yes)
		(layer "In2.Cu")
		(net "M_D_DQ<57>")
	)
	(gr_poly
		(pts
			(xy 288.046414 -101.011228) (xy 288.04616 -100.782628) (xy 287.85312 -100.693728) (xy 287.80867 -100.693982)
			(xy 287.80867 -101.100128) (xy 287.85312 -101.100128)
		)
		(stroke
			(width 0)
			(type solid)
		)
		(fill yes)
		(layer "In2.Cu")
		(net "M_D_DQ<57>")
	)
	(gr_poly
		(pts
			(xy 288.059622 -53.233574) (xy 288.015172 -53.233574) (xy 287.844992 -53.322474) (xy 287.844992 -53.543454)
			(xy 288.015172 -53.632354) (xy 288.059622 -53.632354)
		)
		(stroke
			(width 0)
			(type solid)
		)
		(fill yes)
		(layer "In2.Cu")
		(net "M_A_DQS_DN<7>")
	)
	(gr_poly
		(pts
			(xy 288.117534 -52.29479) (xy 288.043874 -52.095654) (xy 288.012378 -52.064158) (xy 287.725104 -52.351432)
			(xy 287.7566 -52.382928) (xy 287.955736 -52.456588)
		)
		(stroke
			(width 0)
			(type solid)
		)
		(fill yes)
		(layer "In2.Cu")
		(net "M_A_DQS_DN<16>")
	)
	(gr_poly
		(pts
			(xy 288.281618 -55.461662) (xy 288.296604 -55.270146) (xy 288.109152 -55.153052) (xy 287.943544 -55.25008)
			(xy 287.920176 -55.287926) (xy 288.25825 -55.499254)
		)
		(stroke
			(width 0)
			(type solid)
		)
		(fill yes)
		(layer "In2.Cu")
		(net "M_A_DQ<62>")
	)
	(gr_poly
		(pts
			(xy 288.299906 -54.559962) (xy 288.291778 -54.368192) (xy 288.26968 -54.329584) (xy 287.92424 -54.528974)
			(xy 287.946592 -54.567582) (xy 288.108644 -54.670452)
		)
		(stroke
			(width 0)
			(type solid)
		)
		(fill yes)
		(layer "In2.Cu")
		(net "M_A_DQS_DP<7>")
	)
	(gr_poly
		(pts
			(xy 288.344102 -102.269544) (xy 288.299652 -102.269544) (xy 288.129472 -102.358444) (xy 288.129472 -102.579424)
			(xy 288.299652 -102.668324) (xy 288.344102 -102.668324)
		)
		(stroke
			(width 0)
			(type solid)
		)
		(fill yes)
		(layer "In2.Cu")
		(net "M_D_DQS_DP<16>")
	)
	(gr_poly
		(pts
			(xy 288.344102 -101.272594) (xy 288.299652 -101.272594) (xy 288.129472 -101.361494) (xy 288.129472 -101.582474)
			(xy 288.299652 -101.671374) (xy 288.344102 -101.671374)
		)
		(stroke
			(width 0)
			(type solid)
		)
		(fill yes)
		(layer "In2.Cu")
		(net "M_D_DQS_DP<16>")
	)
	(gr_poly
		(pts
			(xy 288.344102 -100.275898) (xy 288.299652 -100.275898) (xy 288.129472 -100.364798) (xy 288.129472 -100.585778)
			(xy 288.299652 -100.674678) (xy 288.344102 -100.674678)
		)
		(stroke
			(width 0)
			(type solid)
		)
		(fill yes)
		(layer "In2.Cu")
		(net "M_D_DQS_DP<16>")
	)
	(gr_poly
		(pts
			(xy 288.344102 -99.285298) (xy 288.299652 -99.285298) (xy 288.129472 -99.374198) (xy 288.129472 -99.595178)
			(xy 288.299652 -99.684078) (xy 288.344102 -99.684078)
		)
		(stroke
			(width 0)
			(type solid)
		)
		(fill yes)
		(layer "In2.Cu")
		(net "M_D_DQS_DP<16>")
	)
	(gr_poly
		(pts
			(xy 288.407602 -105.847388) (xy 288.439098 -105.815892) (xy 288.151824 -105.528618) (xy 288.120328 -105.560114)
			(xy 288.046668 -105.75925) (xy 288.208466 -105.921048)
		)
		(stroke
			(width 0)
			(type solid)
		)
		(fill yes)
		(layer "In2.Cu")
		(net "M_D_DQ<60>")
	)
	(gr_poly
		(pts
			(xy 288.497772 -56.054498) (xy 288.520124 -56.016144) (xy 288.174684 -55.816754) (xy 288.152586 -55.855108)
			(xy 288.144458 -56.046878) (xy 288.33572 -56.157368)
		)
		(stroke
			(width 0)
			(type solid)
		)
		(fill yes)
		(layer "In2.Cu")
		(net "M_A_DQ<63>")
	)
	(gr_poly
		(pts
			(xy 288.502598 -104.351582) (xy 288.53384 -104.320086) (xy 288.246566 -104.032812) (xy 288.21507 -104.064308)
			(xy 288.14141 -104.263698) (xy 288.303208 -104.425242)
		)
		(stroke
			(width 0)
			(type solid)
		)
		(fill yes)
		(layer "In2.Cu")
		(net "M_D_DQ<56>")
	)
	(gr_poly
		(pts
			(xy 288.526728 -56.77154) (xy 288.503106 -56.733948) (xy 288.337498 -56.636666) (xy 288.150046 -56.754014)
			(xy 288.165032 -56.945022) (xy 288.1884 -56.983122)
		)
		(stroke
			(width 0)
			(type solid)
		)
		(fill yes)
		(layer "In2.Cu")
		(net "M_A_DQ<58>")
	)
	(gr_poly
		(pts
			(xy 288.588958 -51.218084) (xy 288.557462 -51.186842) (xy 288.358072 -51.113182) (xy 288.196528 -51.274726)
			(xy 288.270188 -51.474116) (xy 288.30143 -51.505612)
		)
		(stroke
			(width 0)
			(type solid)
		)
		(fill yes)
		(layer "In2.Cu")
		(net "M_A_DQS_DP<16>")
	)
	(gr_poly
		(pts
			(xy 288.597848 -58.002424) (xy 288.597848 -57.781444) (xy 288.427668 -57.692544) (xy 288.383218 -57.692544)
			(xy 288.383218 -58.091324) (xy 288.427668 -58.091324)
		)
		(stroke
			(width 0)
			(type solid)
		)
		(fill yes)
		(layer "In2.Cu")
		(net "M_A_DQ<59>")
	)
	(gr_poly
		(pts
			(xy 288.597848 -54.033674) (xy 288.597848 -53.812694) (xy 288.427668 -53.723794) (xy 288.383218 -53.723794)
			(xy 288.383218 -54.122574) (xy 288.427668 -54.122574)
		)
		(stroke
			(width 0)
			(type solid)
		)
		(fill yes)
		(layer "In2.Cu")
		(net "M_A_DQS_DP<7>")
	)
	(gr_poly
		(pts
			(xy 288.605214 -105.649776) (xy 288.678874 -105.450386) (xy 288.51733 -105.288842) (xy 288.31794 -105.362502)
			(xy 288.286444 -105.393744) (xy 288.573972 -105.681272)
		)
		(stroke
			(width 0)
			(type solid)
		)
		(fill yes)
		(layer "In2.Cu")
		(net "M_D_DQ<61>")
	)
	(gr_poly
		(pts
			(xy 288.70021 -104.15397) (xy 288.77387 -103.95458) (xy 288.612072 -103.793036) (xy 288.412682 -103.866696)
			(xy 288.38144 -103.898192) (xy 288.668714 -104.185466)
		)
		(stroke
			(width 0)
			(type solid)
		)
		(fill yes)
		(layer "In2.Cu")
		(net "M_D_DQ<57>")
	)
	(gr_poly
		(pts
			(xy 288.813748 -52.46243) (xy 288.782252 -52.431188) (xy 288.582862 -52.357528) (xy 288.421318 -52.519072)
			(xy 288.494978 -52.718462) (xy 288.52622 -52.749958)
		)
		(stroke
			(width 0)
			(type solid)
		)
		(fill yes)
		(layer "In2.Cu")
		(net "M_A_DQS_DN<7>")
	)
	(gr_poly
		(pts
			(xy 288.828734 -51.58359) (xy 288.755074 -51.384454) (xy 288.723578 -51.352958) (xy 288.436304 -51.640232)
			(xy 288.4678 -51.671728) (xy 288.666936 -51.745388)
		)
		(stroke
			(width 0)
			(type solid)
		)
		(fill yes)
		(layer "In2.Cu")
		(net "M_A_DQS_DN<16>")
	)
	(gr_poly
		(pts
			(xy 288.882328 -102.071678) (xy 288.882328 -101.850698) (xy 288.712148 -101.761798) (xy 288.667698 -101.761798)
			(xy 288.667698 -102.160578) (xy 288.712148 -102.160578)
		)
		(stroke
			(width 0)
			(type solid)
		)
		(fill yes)
		(layer "In2.Cu")
		(net "M_D_DQS_DN<16>")
	)
	(gr_poly
		(pts
			(xy 288.882328 -101.093524) (xy 288.882328 -100.872544) (xy 288.712148 -100.783644) (xy 288.667698 -100.783644)
			(xy 288.667698 -101.182424) (xy 288.712148 -101.182424)
		)
		(stroke
			(width 0)
			(type solid)
		)
		(fill yes)
		(layer "In2.Cu")
		(net "M_D_DQS_DN<16>")
	)
	(gr_poly
		(pts
			(xy 288.882328 -100.096828) (xy 288.882328 -99.875848) (xy 288.712148 -99.786948) (xy 288.667698 -99.786948)
			(xy 288.667698 -100.185728) (xy 288.712148 -100.185728)
		)
		(stroke
			(width 0)
			(type solid)
		)
		(fill yes)
		(layer "In2.Cu")
		(net "M_D_DQS_DN<16>")
	)
	(gr_poly
		(pts
			(xy 289.053524 -52.827936) (xy 288.979864 -52.6288) (xy 288.948368 -52.597304) (xy 288.661094 -52.884578)
			(xy 288.69259 -52.916074) (xy 288.891726 -52.989734)
		)
		(stroke
			(width 0)
			(type solid)
		)
		(fill yes)
		(layer "In2.Cu")
		(net "M_A_DQS_DP<7>")
	)
	(gr_poly
		(pts
			(xy 289.063684 -54.769004) (xy 289.019234 -54.769004) (xy 288.826194 -54.857904) (xy 288.826194 -55.086504)
			(xy 289.019234 -55.175404) (xy 289.063684 -55.175404)
		)
		(stroke
			(width 0)
			(type solid)
		)
		(fill yes)
		(layer "In2.Cu")
		(net "M_A_DQ<62>")
	)
	(gr_poly
		(pts
			(xy 289.063684 -53.778404) (xy 289.019234 -53.778404) (xy 288.826194 -53.867304) (xy 288.826194 -54.095904)
			(xy 289.019234 -54.184804) (xy 289.063684 -54.184804)
		)
		(stroke
			(width 0)
			(type solid)
		)
		(fill yes)
		(layer "In2.Cu")
		(net "M_A_DQ<62>")
	)
	(gr_poly
		(pts
			(xy 289.108134 -106.54792) (xy 289.13963 -106.516424) (xy 288.852356 -106.22915) (xy 288.82086 -106.260392)
			(xy 288.7472 -106.459782) (xy 288.908744 -106.62158)
		)
		(stroke
			(width 0)
			(type solid)
		)
		(fill yes)
		(layer "In2.Cu")
		(net "M_D_DQ<60>")
	)
	(gr_poly
		(pts
			(xy 289.123374 -103.728266) (xy 289.15487 -103.69677) (xy 288.867596 -103.409496) (xy 288.8361 -103.440992)
			(xy 288.76244 -103.640128) (xy 288.924238 -103.801926)
		)
		(stroke
			(width 0)
			(type solid)
		)
		(fill yes)
		(layer "In2.Cu")
		(net "M_D_DQS_DP<16>")
	)
	(gr_poly
		(pts
			(xy 289.202622 -100.783644) (xy 289.158172 -100.783644) (xy 288.987992 -100.872544) (xy 288.987992 -101.093524)
			(xy 289.158172 -101.182424) (xy 289.202622 -101.182424)
		)
		(stroke
			(width 0)
			(type solid)
		)
		(fill yes)
		(layer "In2.Cu")
		(net "M_D_DQS_DN<7>")
	)
	(gr_poly
		(pts
			(xy 289.202622 -99.786948) (xy 289.158172 -99.786948) (xy 288.987992 -99.875848) (xy 288.987992 -100.096828)
			(xy 289.158172 -100.185728) (xy 289.202622 -100.185728)
		)
		(stroke
			(width 0)
			(type solid)
		)
		(fill yes)
		(layer "In2.Cu")
		(net "M_D_DQS_DN<7>")
	)
	(gr_poly
		(pts
			(xy 289.202876 -105.052114) (xy 289.234372 -105.020618) (xy 288.947098 -104.733344) (xy 288.915602 -104.76484)
			(xy 288.841942 -104.963976) (xy 289.00374 -105.125774)
		)
		(stroke
			(width 0)
			(type solid)
		)
		(fill yes)
		(layer "In2.Cu")
		(net "M_D_DQ<56>")
	)
	(gr_poly
		(pts
			(xy 289.305746 -106.350308) (xy 289.379406 -106.150918) (xy 289.217862 -105.98912) (xy 289.018472 -106.06278)
			(xy 288.986976 -106.094276) (xy 289.27425 -106.38155)
		)
		(stroke
			(width 0)
			(type solid)
		)
		(fill yes)
		(layer "In2.Cu")
		(net "M_D_DQ<61>")
	)
	(gr_poly
		(pts
			(xy 289.32124 -103.5304) (xy 289.3949 -103.331264) (xy 289.233102 -103.169466) (xy 289.033966 -103.243126)
			(xy 289.00247 -103.274622) (xy 289.289744 -103.561896)
		)
		(stroke
			(width 0)
			(type solid)
		)
		(fill yes)
		(layer "In2.Cu")
		(net "M_D_DQS_DN<16>")
	)
	(gr_poly
		(pts
			(xy 289.400488 -104.854502) (xy 289.474148 -104.655112) (xy 289.312604 -104.493568) (xy 289.113214 -104.567228)
			(xy 289.081718 -104.59847) (xy 289.369246 -104.885998)
		)
		(stroke
			(width 0)
			(type solid)
		)
		(fill yes)
		(layer "In2.Cu")
		(net "M_D_DQ<57>")
	)
	(gr_poly
		(pts
			(xy 289.491674 -55.086504) (xy 289.491674 -54.857904) (xy 289.298634 -54.769004) (xy 289.254184 -54.769004)
			(xy 289.254184 -55.175404) (xy 289.298634 -55.175404)
		)
		(stroke
			(width 0)
			(type solid)
		)
		(fill yes)
		(layer "In2.Cu")
		(net "M_A_DQ<63>")
	)
	(gr_poly
		(pts
			(xy 289.491674 -54.095904) (xy 289.491674 -53.867304) (xy 289.298634 -53.778404) (xy 289.254184 -53.778404)
			(xy 289.254184 -54.184804) (xy 289.298634 -54.184804)
		)
		(stroke
			(width 0)
			(type solid)
		)
		(fill yes)
		(layer "In2.Cu")
		(net "M_A_DQ<63>")
	)
	(gr_poly
		(pts
			(xy 289.601148 -53.026056) (xy 289.569652 -52.99456) (xy 289.370262 -52.921154) (xy 289.208718 -53.082698)
			(xy 289.282378 -53.282088) (xy 289.31362 -53.313584)
		)
		(stroke
			(width 0)
			(type solid)
		)
		(fill yes)
		(layer "In2.Cu")
		(net "M_A_DQ<62>")
	)
	(gr_poly
		(pts
			(xy 289.666934 -56.348884) (xy 289.635438 -56.317388) (xy 289.436302 -56.243728) (xy 289.274504 -56.405526)
			(xy 289.348164 -56.604662) (xy 289.37966 -56.636158)
		)
		(stroke
			(width 0)
			(type solid)
		)
		(fill yes)
		(layer "In2.Cu")
		(net "M_A_DQ<58>")
	)
	(gr_poly
		(pts
			(xy 289.74034 -99.593908) (xy 289.74034 -99.372928) (xy 289.57016 -99.284028) (xy 289.52571 -99.284028)
			(xy 289.52571 -99.682808) (xy 289.57016 -99.682808)
		)
		(stroke
			(width 0)
			(type solid)
		)
		(fill yes)
		(layer "In2.Cu")
		(net "M_D_DQS_DP<7>")
	)
	(gr_poly
		(pts
			(xy 289.740848 -101.582474) (xy 289.740848 -101.361494) (xy 289.570668 -101.272594) (xy 289.526218 -101.272594)
			(xy 289.526218 -101.671374) (xy 289.570668 -101.671374)
		)
		(stroke
			(width 0)
			(type solid)
		)
		(fill yes)
		(layer "In2.Cu")
		(net "M_D_DQS_DP<7>")
	)
	(gr_poly
		(pts
			(xy 289.740848 -100.585778) (xy 289.740848 -100.364798) (xy 289.570668 -100.275898) (xy 289.526218 -100.275898)
			(xy 289.526218 -100.674678) (xy 289.570668 -100.674678)
		)
		(stroke
			(width 0)
			(type solid)
		)
		(fill yes)
		(layer "In2.Cu")
		(net "M_D_DQS_DP<7>")
	)
	(gr_poly
		(pts
			(xy 289.830764 -55.213504) (xy 289.786314 -55.213504) (xy 289.593274 -55.302404) (xy 289.593274 -55.531004)
			(xy 289.786314 -55.619904) (xy 289.830764 -55.619904)
		)
		(stroke
			(width 0)
			(type solid)
		)
		(fill yes)
		(layer "In2.Cu")
		(net "M_A_DQ<58>")
	)
	(gr_poly
		(pts
			(xy 289.830764 -54.222904) (xy 289.786314 -54.222904) (xy 289.593274 -54.311804) (xy 289.593274 -54.540404)
			(xy 289.786314 -54.629304) (xy 289.830764 -54.629304)
		)
		(stroke
			(width 0)
			(type solid)
		)
		(fill yes)
		(layer "In2.Cu")
		(net "M_A_DQ<58>")
	)
	(gr_poly
		(pts
			(xy 289.834574 -104.439466) (xy 289.86607 -104.40797) (xy 289.578796 -104.120696) (xy 289.5473 -104.152192)
			(xy 289.47364 -104.351328) (xy 289.635438 -104.513126)
		)
		(stroke
			(width 0)
			(type solid)
		)
		(fill yes)
		(layer "In2.Cu")
		(net "M_D_DQS_DP<16>")
	)
	(gr_poly
		(pts
			(xy 289.839654 -53.393086) (xy 289.765994 -53.193696) (xy 289.734498 -53.1622) (xy 289.447224 -53.449728)
			(xy 289.478466 -53.481224) (xy 289.677856 -53.554884)
		)
		(stroke
			(width 0)
			(type solid)
		)
		(fill yes)
		(layer "In2.Cu")
		(net "M_A_DQ<63>")
	)
	(gr_poly
		(pts
			(xy 289.903408 -105.752646) (xy 289.934904 -105.72115) (xy 289.64763 -105.433876) (xy 289.616134 -105.465118)
			(xy 289.542474 -105.664508) (xy 289.704018 -105.826306)
		)
		(stroke
			(width 0)
			(type solid)
		)
		(fill yes)
		(layer "In2.Cu")
		(net "M_D_DQ<56>")
	)
	(gr_poly
		(pts
			(xy 289.90671 -56.71439) (xy 289.83305 -56.515) (xy 289.801808 -56.483504) (xy 289.51428 -56.771032)
			(xy 289.545776 -56.802274) (xy 289.745166 -56.875934)
		)
		(stroke
			(width 0)
			(type solid)
		)
		(fill yes)
		(layer "In2.Cu")
		(net "M_A_DQ<59>")
	)
	(gr_poly
		(pts
			(xy 290.03244 -104.2416) (xy 290.1061 -104.042464) (xy 289.944302 -103.880666) (xy 289.745166 -103.954326)
			(xy 289.71367 -103.985822) (xy 290.000944 -104.273096)
		)
		(stroke
			(width 0)
			(type solid)
		)
		(fill yes)
		(layer "In2.Cu")
		(net "M_D_DQS_DN<16>")
	)
	(gr_poly
		(pts
			(xy 290.043362 -103.55961) (xy 290.074858 -103.528114) (xy 289.787584 -103.24084) (xy 289.756088 -103.272336)
			(xy 289.682428 -103.471472) (xy 289.844226 -103.63327)
		)
		(stroke
			(width 0)
			(type solid)
		)
		(fill yes)
		(layer "In2.Cu")
		(net "M_D_DQS_DN<7>")
	)
	(gr_poly
		(pts
			(xy 290.061142 -101.272594) (xy 290.016692 -101.272594) (xy 289.846512 -101.361494) (xy 289.846512 -101.582474)
			(xy 290.016692 -101.671374) (xy 290.061142 -101.671374)
		)
		(stroke
			(width 0)
			(type solid)
		)
		(fill yes)
		(layer "In2.Cu")
		(net "M_D_DQ<63>")
	)
	(gr_poly
		(pts
			(xy 290.10102 -105.555034) (xy 290.17468 -105.355644) (xy 290.013136 -105.193846) (xy 289.813746 -105.267506)
			(xy 289.78225 -105.299002) (xy 290.069524 -105.586276)
		)
		(stroke
			(width 0)
			(type solid)
		)
		(fill yes)
		(layer "In2.Cu")
		(net "M_D_DQ<57>")
	)
	(gr_poly
		(pts
			(xy 290.240974 -103.361998) (xy 290.314634 -103.162608) (xy 290.15309 -103.001064) (xy 289.9537 -103.074724)
			(xy 289.922204 -103.105966) (xy 290.209732 -103.393494)
		)
		(stroke
			(width 0)
			(type solid)
		)
		(fill yes)
		(layer "In2.Cu")
		(net "M_D_DQS_DP<7>")
	)
	(gr_poly
		(pts
			(xy 290.258754 -55.531004) (xy 290.258754 -55.302404) (xy 290.065714 -55.213504) (xy 290.021264 -55.213504)
			(xy 290.021264 -55.619904) (xy 290.065714 -55.619904)
		)
		(stroke
			(width 0)
			(type solid)
		)
		(fill yes)
		(layer "In2.Cu")
		(net "M_A_DQ<59>")
	)
	(gr_poly
		(pts
			(xy 290.258754 -54.540404) (xy 290.258754 -54.311804) (xy 290.065714 -54.222904) (xy 290.021264 -54.222904)
			(xy 290.021264 -54.629304) (xy 290.065714 -54.629304)
		)
		(stroke
			(width 0)
			(type solid)
		)
		(fill yes)
		(layer "In2.Cu")
		(net "M_A_DQ<59>")
	)
	(gr_poly
		(pts
			(xy 290.312348 -52.314856) (xy 290.280852 -52.28336) (xy 290.081462 -52.209954) (xy 289.919918 -52.371498)
			(xy 289.993578 -52.570888) (xy 290.02482 -52.602384)
		)
		(stroke
			(width 0)
			(type solid)
		)
		(fill yes)
		(layer "In2.Cu")
		(net "M_A_DQ<62>")
	)
	(gr_poly
		(pts
			(xy 290.479734 -53.231542) (xy 290.448238 -53.2003) (xy 290.248848 -53.12664) (xy 290.087304 -53.288184)
			(xy 290.160964 -53.487574) (xy 290.192206 -53.51907)
		)
		(stroke
			(width 0)
			(type solid)
		)
		(fill yes)
		(layer "In2.Cu")
		(net "M_A_DQ<58>")
	)
	(gr_poly
		(pts
			(xy 290.550854 -52.681886) (xy 290.477194 -52.482496) (xy 290.445698 -52.451) (xy 290.158424 -52.738528)
			(xy 290.189666 -52.770024) (xy 290.389056 -52.843684)
		)
		(stroke
			(width 0)
			(type solid)
		)
		(fill yes)
		(layer "In2.Cu")
		(net "M_A_DQ<63>")
	)
	(gr_poly
		(pts
			(xy 290.614608 -106.463846) (xy 290.646104 -106.43235) (xy 290.35883 -106.145076) (xy 290.327334 -106.176318)
			(xy 290.253674 -106.375708) (xy 290.415218 -106.537506)
		)
		(stroke
			(width 0)
			(type solid)
		)
		(fill yes)
		(layer "In2.Cu")
		(net "M_D_DQ<56>")
	)
	(gr_poly
		(pts
			(xy 290.754562 -104.27081) (xy 290.786058 -104.239314) (xy 290.498784 -103.95204) (xy 290.467288 -103.983536)
			(xy 290.393628 -104.182672) (xy 290.555426 -104.34447)
		)
		(stroke
			(width 0)
			(type solid)
		)
		(fill yes)
		(layer "In2.Cu")
		(net "M_D_DQS_DN<7>")
	)
	(gr_poly
		(pts
			(xy 290.81222 -106.266234) (xy 290.88588 -106.066844) (xy 290.724336 -105.905046) (xy 290.524946 -105.978706)
			(xy 290.49345 -106.010202) (xy 290.780724 -106.297476)
		)
		(stroke
			(width 0)
			(type solid)
		)
		(fill yes)
		(layer "In2.Cu")
		(net "M_D_DQ<57>")
	)
	(gr_poly
		(pts
			(xy 290.818062 -103.29291) (xy 290.849558 -103.261414) (xy 290.562284 -102.97414) (xy 290.530788 -103.005636)
			(xy 290.457128 -103.204772) (xy 290.618926 -103.36657)
		)
		(stroke
			(width 0)
			(type solid)
		)
		(fill yes)
		(layer "In2.Cu")
		(net "M_D_DQ<62>")
	)
	(gr_poly
		(pts
			(xy 290.952174 -104.073198) (xy 291.025834 -103.873808) (xy 290.86429 -103.712264) (xy 290.6649 -103.785924)
			(xy 290.633404 -103.817166) (xy 290.920932 -104.104694)
		)
		(stroke
			(width 0)
			(type solid)
		)
		(fill yes)
		(layer "In2.Cu")
		(net "M_D_DQS_DP<7>")
	)
	(gr_poly
		(pts
			(xy 290.97351 -53.343302) (xy 290.89985 -53.143912) (xy 290.868608 -53.112416) (xy 290.58108 -53.399944)
			(xy 290.612576 -53.431186) (xy 290.811966 -53.504846)
		)
		(stroke
			(width 0)
			(type solid)
		)
		(fill yes)
		(layer "In2.Cu")
		(net "M_A_DQ<59>")
	)
	(gr_poly
		(pts
			(xy 291.015928 -103.095044) (xy 291.089588 -102.895908) (xy 290.92779 -102.73411) (xy 290.728654 -102.80777)
			(xy 290.697158 -102.839266) (xy 290.984432 -103.12654)
		)
		(stroke
			(width 0)
			(type solid)
		)
		(fill yes)
		(layer "In2.Cu")
		(net "M_D_DQ<63>")
	)
	(gr_poly
		(pts
			(xy 291.68598 -105.20045) (xy 291.68598 -105.156) (xy 291.27958 -105.156) (xy 291.27958 -105.20045)
			(xy 291.36848 -105.39349) (xy 291.59708 -105.39349)
		)
		(stroke
			(width 0)
			(type solid)
		)
		(fill yes)
		(layer "In2.Cu")
		(net "M_D_DQS_DP<16>")
	)
	(gr_poly
		(pts
			(xy 291.68598 -104.92105) (xy 291.59708 -104.72801) (xy 291.36848 -104.72801) (xy 291.27958 -104.92105)
			(xy 291.27958 -104.9655) (xy 291.68598 -104.9655)
		)
		(stroke
			(width 0)
			(type solid)
		)
		(fill yes)
		(layer "In2.Cu")
		(net "M_D_DQS_DN<16>")
	)
	(gr_poly
		(pts
			(xy 292.06698 -104.457754) (xy 292.06698 -104.413304) (xy 291.66058 -104.413304) (xy 291.66058 -104.457754)
			(xy 291.74948 -104.650794) (xy 291.97808 -104.650794)
		)
		(stroke
			(width 0)
			(type solid)
		)
		(fill yes)
		(layer "In2.Cu")
		(net "M_D_DQS_DN<7>")
	)
	(gr_poly
		(pts
			(xy 292.06698 -104.178354) (xy 291.97808 -103.985314) (xy 291.74948 -103.985314) (xy 291.66058 -104.178354)
			(xy 291.66058 -104.222804) (xy 292.06698 -104.222804)
		)
		(stroke
			(width 0)
			(type solid)
		)
		(fill yes)
		(layer "In2.Cu")
		(net "M_D_DQS_DP<7>")
	)
	(gr_poly
		(pts
			(xy 292.479476 -103.002842) (xy 292.479476 -102.958392) (xy 292.073076 -102.958392) (xy 292.073076 -103.002842)
			(xy 292.161976 -103.195882) (xy 292.390576 -103.195882)
		)
		(stroke
			(width 0)
			(type solid)
		)
		(fill yes)
		(layer "In2.Cu")
		(net "M_D_DQ<58>")
	)
	(gr_poly
		(pts
			(xy 292.479476 -102.723442) (xy 292.390576 -102.530402) (xy 292.161976 -102.530402) (xy 292.073076 -102.723442)
			(xy 292.073076 -102.767892) (xy 292.479476 -102.767892)
		)
		(stroke
			(width 0)
			(type solid)
		)
		(fill yes)
		(layer "In2.Cu")
		(net "M_D_DQ<59>")
	)
	(gr_poly
		(pts
			(xy 292.93058 -103.72725) (xy 292.93058 -103.6828) (xy 292.52418 -103.6828) (xy 292.52418 -103.72725)
			(xy 292.61308 -103.92029) (xy 292.84168 -103.92029)
		)
		(stroke
			(width 0)
			(type solid)
		)
		(fill yes)
		(layer "In2.Cu")
		(net "M_D_DQ<62>")
	)
	(gr_poly
		(pts
			(xy 292.93058 -103.44785) (xy 292.84168 -103.25481) (xy 292.61308 -103.25481) (xy 292.52418 -103.44785)
			(xy 292.52418 -103.4923) (xy 292.93058 -103.4923)
		)
		(stroke
			(width 0)
			(type solid)
		)
		(fill yes)
		(layer "In2.Cu")
		(net "M_D_DQ<63>")
	)
	(gr_poly
		(pts
			(xy 292.948614 -105.8164) (xy 292.98011 -105.784904) (xy 292.692836 -105.49763) (xy 292.66134 -105.529126)
			(xy 292.58768 -105.728262) (xy 292.749478 -105.89006)
		)
		(stroke
			(width 0)
			(type solid)
		)
		(fill yes)
		(layer "In2.Cu")
		(net "M_D_DQS_DP<16>")
	)
	(gr_poly
		(pts
			(xy 293.146226 -105.618788) (xy 293.219886 -105.419398) (xy 293.058342 -105.257854) (xy 292.858952 -105.331514)
			(xy 292.827456 -105.362756) (xy 293.114984 -105.650284)
		)
		(stroke
			(width 0)
			(type solid)
		)
		(fill yes)
		(layer "In2.Cu")
		(net "M_D_DQS_DN<16>")
	)
	(gr_poly
		(pts
			(xy 293.247064 -105.00995) (xy 293.27856 -104.978454) (xy 292.991286 -104.69118) (xy 292.95979 -104.722676)
			(xy 292.88613 -104.921812) (xy 293.047928 -105.08361)
		)
		(stroke
			(width 0)
			(type solid)
		)
		(fill yes)
		(layer "In2.Cu")
		(net "M_D_DQS_DN<7>")
	)
	(gr_poly
		(pts
			(xy 293.444676 -104.812338) (xy 293.518336 -104.612948) (xy 293.356792 -104.451404) (xy 293.157402 -104.525064)
			(xy 293.125906 -104.556306) (xy 293.413434 -104.843834)
		)
		(stroke
			(width 0)
			(type solid)
		)
		(fill yes)
		(layer "In2.Cu")
		(net "M_D_DQS_DP<7>")
	)
	(gr_poly
		(pts
			(xy 293.470076 -103.002842) (xy 293.470076 -102.958392) (xy 293.063676 -102.958392) (xy 293.063676 -103.002842)
			(xy 293.152576 -103.195882) (xy 293.381176 -103.195882)
		)
		(stroke
			(width 0)
			(type solid)
		)
		(fill yes)
		(layer "In2.Cu")
		(net "M_D_DQ<58>")
	)
	(gr_poly
		(pts
			(xy 293.470076 -102.723442) (xy 293.381176 -102.530402) (xy 293.152576 -102.530402) (xy 293.063676 -102.723442)
			(xy 293.063676 -102.767892) (xy 293.470076 -102.767892)
		)
		(stroke
			(width 0)
			(type solid)
		)
		(fill yes)
		(layer "In2.Cu")
		(net "M_D_DQ<59>")
	)
	(gr_poly
		(pts
			(xy 293.92118 -103.72725) (xy 293.92118 -103.6828) (xy 293.51478 -103.6828) (xy 293.51478 -103.72725)
			(xy 293.60368 -103.92029) (xy 293.83228 -103.92029)
		)
		(stroke
			(width 0)
			(type solid)
		)
		(fill yes)
		(layer "In2.Cu")
		(net "M_D_DQ<62>")
	)
	(gr_poly
		(pts
			(xy 293.92118 -103.44785) (xy 293.83228 -103.25481) (xy 293.60368 -103.25481) (xy 293.51478 -103.44785)
			(xy 293.51478 -103.4923) (xy 293.92118 -103.4923)
		)
		(stroke
			(width 0)
			(type solid)
		)
		(fill yes)
		(layer "In2.Cu")
		(net "M_D_DQ<63>")
	)
	(gr_poly
		(pts
			(xy 294.460676 -103.002842) (xy 294.460676 -102.958392) (xy 294.054276 -102.958392) (xy 294.054276 -103.002842)
			(xy 294.143176 -103.195882) (xy 294.371776 -103.195882)
		)
		(stroke
			(width 0)
			(type solid)
		)
		(fill yes)
		(layer "In2.Cu")
		(net "M_D_DQ<58>")
	)
	(gr_poly
		(pts
			(xy 294.460676 -102.723442) (xy 294.371776 -102.530402) (xy 294.143176 -102.530402) (xy 294.054276 -102.723442)
			(xy 294.054276 -102.767892) (xy 294.460676 -102.767892)
		)
		(stroke
			(width 0)
			(type solid)
		)
		(fill yes)
		(layer "In2.Cu")
		(net "M_D_DQ<59>")
	)
	(gr_poly
		(pts
			(xy 294.941498 -104.227884) (xy 294.972994 -104.196642) (xy 294.685466 -103.909114) (xy 294.654224 -103.94061)
			(xy 294.580564 -104.14) (xy 294.742108 -104.301544)
		)
		(stroke
			(width 0)
			(type solid)
		)
		(fill yes)
		(layer "In2.Cu")
		(net "M_D_DQ<62>")
	)
	(gr_poly
		(pts
			(xy 295.13911 -104.030272) (xy 295.21277 -103.830882) (xy 295.051226 -103.669338) (xy 294.851836 -103.742998)
			(xy 294.82034 -103.77424) (xy 295.107868 -104.061768)
		)
		(stroke
			(width 0)
			(type solid)
		)
		(fill yes)
		(layer "In2.Cu")
		(net "M_D_DQ<63>")
	)
	(gr_poly
		(pts
			(xy 295.278556 -103.497126) (xy 295.310052 -103.465884) (xy 295.022524 -103.178356) (xy 294.991282 -103.209852)
			(xy 294.917622 -103.409242) (xy 295.079166 -103.570786)
		)
		(stroke
			(width 0)
			(type solid)
		)
		(fill yes)
		(layer "In2.Cu")
		(net "M_D_DQ<58>")
	)
	(gr_poly
		(pts
			(xy 295.476168 -103.299514) (xy 295.549828 -103.100124) (xy 295.388284 -102.93858) (xy 295.188894 -103.01224)
			(xy 295.157398 -103.043482) (xy 295.444926 -103.33101)
		)
		(stroke
			(width 0)
			(type solid)
		)
		(fill yes)
		(layer "In2.Cu")
		(net "M_D_DQ<59>")
	)
	(gr_poly
		(pts
			(xy 295.64203 -104.928416) (xy 295.673272 -104.89692) (xy 295.385998 -104.609646) (xy 295.354502 -104.641142)
			(xy 295.280842 -104.840532) (xy 295.44264 -105.002076)
		)
		(stroke
			(width 0)
			(type solid)
		)
		(fill yes)
		(layer "In2.Cu")
		(net "M_D_DQ<62>")
	)
	(gr_poly
		(pts
			(xy 295.85031 -104.741472) (xy 295.92397 -104.542082) (xy 295.762426 -104.380538) (xy 295.563036 -104.454198)
			(xy 295.53154 -104.48544) (xy 295.819068 -104.772968)
		)
		(stroke
			(width 0)
			(type solid)
		)
		(fill yes)
		(layer "In2.Cu")
		(net "M_D_DQ<63>")
	)
	(gr_poly
		(pts
			(xy 295.989756 -104.208326) (xy 296.021252 -104.177084) (xy 295.733724 -103.889556) (xy 295.702482 -103.921052)
			(xy 295.628822 -104.120442) (xy 295.790366 -104.281986)
		)
		(stroke
			(width 0)
			(type solid)
		)
		(fill yes)
		(layer "In2.Cu")
		(net "M_D_DQ<58>")
	)
	(gr_poly
		(pts
			(xy 296.187368 -104.010714) (xy 296.261028 -103.811324) (xy 296.099484 -103.64978) (xy 295.900094 -103.72344)
			(xy 295.868598 -103.754682) (xy 296.156126 -104.04221)
		)
		(stroke
			(width 0)
			(type solid)
		)
		(fill yes)
		(layer "In2.Cu")
		(net "M_D_DQ<59>")
	)
	(gr_poly
		(pts
			(xy 297.077384 -104.46385) (xy 297.077384 -104.4194) (xy 296.670984 -104.4194) (xy 296.670984 -104.46385)
			(xy 296.759884 -104.65689) (xy 296.988484 -104.65689)
		)
		(stroke
			(width 0)
			(type solid)
		)
		(fill yes)
		(layer "In2.Cu")
		(net "M_D_DQ<58>")
	)
	(gr_poly
		(pts
			(xy 297.123358 -104.18445) (xy 297.034458 -103.99141) (xy 296.805858 -103.99141) (xy 296.716958 -104.18445)
			(xy 296.716958 -104.2289) (xy 297.123358 -104.2289)
		)
		(stroke
			(width 0)
			(type solid)
		)
		(fill yes)
		(layer "In2.Cu")
		(net "M_D_DQ<59>")
	)
	(gr_poly
		(pts
			(xy 297.165776 -105.55605) (xy 297.165776 -105.5116) (xy 296.759376 -105.5116) (xy 296.759376 -105.55605)
			(xy 296.848276 -105.74909) (xy 297.076876 -105.74909)
		)
		(stroke
			(width 0)
			(type solid)
		)
		(fill yes)
		(layer "In2.Cu")
		(net "M_D_DQ<62>")
	)
	(gr_poly
		(pts
			(xy 297.165776 -105.27665) (xy 297.076876 -105.08361) (xy 296.848276 -105.08361) (xy 296.759376 -105.27665)
			(xy 296.759376 -105.3211) (xy 297.165776 -105.3211)
		)
		(stroke
			(width 0)
			(type solid)
		)
		(fill yes)
		(layer "In2.Cu")
		(net "M_D_DQ<63>")
	)
	(gr_poly
		(pts
			(xy 368.1476 -100.78974) (xy 368.1476 -96.266) (xy 366.6744 -96.266) (xy 366.6744 -100.827078) (xy 366.676686 -100.838)
			(xy 368.13744 -100.838)
		)
		(stroke
			(width 0)
			(type solid)
		)
		(fill yes)
		(layer "In2.Cu")
		(net "GND")
	)
	(gr_poly
		(pts
			(xy 475.5134 -40.0558) (xy 472.8718 -40.0558) (xy 472.8718 -43.307) (xy 474.69552 -43.307) (xy 474.73108 -43.307)
			(xy 475.5134 -43.307)
		)
		(stroke
			(width 0)
			(type solid)
		)
		(fill yes)
		(layer "In2.Cu")
		(net "GND")
	)
	(gr_poly
		(pts
			(arc
				(start 408.799792 -100.71354)
				(mid 408.81851 -100.710117)
				(end 408.837384 -100.707698)
			)
			(xy 408.837384 -98.206814) (xy 405.636984 -98.206814) (xy 405.636984 -100.71354)
		)
		(stroke
			(width 0)
			(type solid)
		)
		(fill yes)
		(layer "In2.Cu")
		(net "GND")
	)
	(gr_poly
		(pts
			(arc
				(start 375.229628 -128.852676)
				(mid 374.975628 -128.852676)
				(end 375.229628 -128.852676)
			)
		)
		(stroke
			(width 0)
			(type solid)
		)
		(fill yes)
		(layer "In2.Cu")
		(net "GND")
	)
	(gr_poly
		(pts
			(arc
				(start 377.013724 -129.521712)
				(mid 376.759724 -129.521712)
				(end 377.013724 -129.521712)
			)
		)
		(stroke
			(width 0)
			(type solid)
		)
		(fill yes)
		(layer "In2.Cu")
		(net "GND")
	)
	(gr_poly
		(pts
			(arc
				(start 378.189236 -131.520184)
				(mid 377.935236 -131.520184)
				(end 378.189236 -131.520184)
			)
		)
		(stroke
			(width 0)
			(type solid)
		)
		(fill yes)
		(layer "In2.Cu")
		(net "GND")
	)
	(gr_poly
		(pts
			(arc
				(start 378.823474 -128.804416)
				(mid 378.569474 -128.804416)
				(end 378.823474 -128.804416)
			)
		)
		(stroke
			(width 0)
			(type solid)
		)
		(fill yes)
		(layer "In2.Cu")
		(net "GND")
	)
	(gr_poly
		(pts
			(arc
				(start 379.613922 -132.790438)
				(mid 379.359922 -132.790438)
				(end 379.613922 -132.790438)
			)
		)
		(stroke
			(width 0)
			(type solid)
		)
		(fill yes)
		(layer "In2.Cu")
		(net "GND")
	)
	(gr_poly
		(pts
			(arc
				(start 380.428246 -128.350518)
				(mid 380.174246 -128.350518)
				(end 380.428246 -128.350518)
			)
		)
		(stroke
			(width 0)
			(type solid)
		)
		(fill yes)
		(layer "In2.Cu")
		(net "GND")
	)
	(gr_poly
		(pts
			(arc
				(start 381.531622 -128.35763)
				(mid 381.277622 -128.35763)
				(end 381.531622 -128.35763)
			)
		)
		(stroke
			(width 0)
			(type solid)
		)
		(fill yes)
		(layer "In2.Cu")
		(net "GND")
	)
	(gr_poly
		(pts
			(arc
				(start 382.581912 -131.097274)
				(mid 382.327912 -131.097274)
				(end 382.581912 -131.097274)
			)
		)
		(stroke
			(width 0)
			(type solid)
		)
		(fill yes)
		(layer "In2.Cu")
		(net "GND")
	)
	(gr_poly
		(pts
			(arc
				(start 382.66624 -129.07772)
				(mid 382.41224 -129.07772)
				(end 382.66624 -129.07772)
			)
		)
		(stroke
			(width 0)
			(type solid)
		)
		(fill yes)
		(layer "In2.Cu")
		(net "GND")
	)
	(gr_poly
		(pts
			(arc
				(start 383.97561 -128.976374)
				(mid 383.72161 -128.976374)
				(end 383.97561 -128.976374)
			)
		)
		(stroke
			(width 0)
			(type solid)
		)
		(fill yes)
		(layer "In2.Cu")
		(net "GND")
	)
	(gr_poly
		(pts
			(arc
				(start 384.27533 -131.833366)
				(mid 384.02133 -131.833366)
				(end 384.27533 -131.833366)
			)
		)
		(stroke
			(width 0)
			(type solid)
		)
		(fill yes)
		(layer "In2.Cu")
		(net "GND")
	)
	(gr_poly
		(pts
			(arc
				(start 389.12927 -129.744216)
				(mid 388.87527 -129.744216)
				(end 389.12927 -129.744216)
			)
		)
		(stroke
			(width 0)
			(type solid)
		)
		(fill yes)
		(layer "In2.Cu")
		(net "GND")
	)
	(gr_poly
		(pts
			(arc
				(start 389.774938 -127.73533)
				(mid 389.520938 -127.73533)
				(end 389.774938 -127.73533)
			)
		)
		(stroke
			(width 0)
			(type solid)
		)
		(fill yes)
		(layer "In2.Cu")
		(net "GND")
	)
	(gr_poly
		(pts
			(arc
				(start 391.892028 -130.095752)
				(mid 391.638028 -130.095752)
				(end 391.892028 -130.095752)
			)
		)
		(stroke
			(width 0)
			(type solid)
		)
		(fill yes)
		(layer "In2.Cu")
		(net "GND")
	)
	(gr_poly
		(pts
			(arc
				(start 391.916666 -128.122172)
				(mid 391.662666 -128.122172)
				(end 391.916666 -128.122172)
			)
		)
		(stroke
			(width 0)
			(type solid)
		)
		(fill yes)
		(layer "In2.Cu")
		(net "GND")
	)
	(gr_poly
		(pts
			(arc
				(start 393.403074 -128.683766)
				(mid 393.149074 -128.683766)
				(end 393.403074 -128.683766)
			)
		)
		(stroke
			(width 0)
			(type solid)
		)
		(fill yes)
		(layer "In2.Cu")
		(net "GND")
	)
	(gr_poly
		(pts
			(arc
				(start 395.222222 -128.184148)
				(mid 394.968222 -128.184148)
				(end 395.222222 -128.184148)
			)
		)
		(stroke
			(width 0)
			(type solid)
		)
		(fill yes)
		(layer "In2.Cu")
		(net "GND")
	)
	(gr_poly
		(pts
			(arc
				(start 395.305788 -130.12547)
				(mid 395.051788 -130.12547)
				(end 395.305788 -130.12547)
			)
		)
		(stroke
			(width 0)
			(type solid)
		)
		(fill yes)
		(layer "In2.Cu")
		(net "GND")
	)
	(gr_poly
		(pts
			(arc
				(start 406.307544 -145.49501)
				(mid 406.053544 -145.49501)
				(end 406.307544 -145.49501)
			)
		)
		(stroke
			(width 0)
			(type solid)
		)
		(fill yes)
		(layer "In2.Cu")
		(net "GND")
	)
	(gr_poly
		(pts
			(arc
				(start 406.846786 -151.661876)
				(mid 406.592786 -151.661876)
				(end 406.846786 -151.661876)
			)
		)
		(stroke
			(width 0)
			(type solid)
		)
		(fill yes)
		(layer "In2.Cu")
		(net "GND")
	)
	(gr_poly
		(pts
			(arc
				(start 406.889966 -153.0985)
				(mid 406.635966 -153.0985)
				(end 406.889966 -153.0985)
			)
		)
		(stroke
			(width 0)
			(type solid)
		)
		(fill yes)
		(layer "In2.Cu")
		(net "GND")
	)
	(gr_poly
		(pts
			(arc
				(start 407.048716 -143.701008)
				(mid 406.794716 -143.701008)
				(end 407.048716 -143.701008)
			)
		)
		(stroke
			(width 0)
			(type solid)
		)
		(fill yes)
		(layer "In2.Cu")
		(net "GND")
	)
	(gr_poly
		(pts
			(arc
				(start 407.075132 -155.158186)
				(mid 406.821132 -155.158186)
				(end 407.075132 -155.158186)
			)
		)
		(stroke
			(width 0)
			(type solid)
		)
		(fill yes)
		(layer "In2.Cu")
		(net "GND")
	)
	(gr_poly
		(pts
			(arc
				(start 407.321512 -148.092414)
				(mid 407.067512 -148.092414)
				(end 407.321512 -148.092414)
			)
		)
		(stroke
			(width 0)
			(type solid)
		)
		(fill yes)
		(layer "In2.Cu")
		(net "GND")
	)
	(gr_poly
		(pts
			(arc
				(start 407.32837 -146.831558)
				(mid 407.07437 -146.831558)
				(end 407.32837 -146.831558)
			)
		)
		(stroke
			(width 0)
			(type solid)
		)
		(fill yes)
		(layer "In2.Cu")
		(net "GND")
	)
	(gr_poly
		(pts
			(arc
				(start 409.017216 -141.386306)
				(mid 408.763216 -141.386306)
				(end 409.017216 -141.386306)
			)
		)
		(stroke
			(width 0)
			(type solid)
		)
		(fill yes)
		(layer "In2.Cu")
		(net "GND")
	)
	(gr_poly
		(pts
			(arc
				(start 410.014928 -150.445724)
				(mid 409.760928 -150.445724)
				(end 410.014928 -150.445724)
			)
		)
		(stroke
			(width 0)
			(type solid)
		)
		(fill yes)
		(layer "In2.Cu")
		(net "GND")
	)
	(gr_poly
		(pts
			(arc
				(start 410.275532 -151.667972)
				(mid 410.021532 -151.667972)
				(end 410.275532 -151.667972)
			)
		)
		(stroke
			(width 0)
			(type solid)
		)
		(fill yes)
		(layer "In2.Cu")
		(net "GND")
	)
	(gr_poly
		(pts
			(arc
				(start 410.34335 -148.393404)
				(mid 410.08935 -148.393404)
				(end 410.34335 -148.393404)
			)
		)
		(stroke
			(width 0)
			(type solid)
		)
		(fill yes)
		(layer "In2.Cu")
		(net "GND")
	)
	(gr_poly
		(pts
			(arc
				(start 410.57068 -153.82875)
				(mid 410.31668 -153.82875)
				(end 410.57068 -153.82875)
			)
		)
		(stroke
			(width 0)
			(type solid)
		)
		(fill yes)
		(layer "In2.Cu")
		(net "GND")
	)
	(gr_poly
		(pts
			(arc
				(start 412.122366 -140.922756)
				(mid 411.868366 -140.922756)
				(end 412.122366 -140.922756)
			)
		)
		(stroke
			(width 0)
			(type solid)
		)
		(fill yes)
		(layer "In2.Cu")
		(net "GND")
	)
	(gr_poly
		(pts
			(arc
				(start 412.697422 -142.683738)
				(mid 412.443422 -142.683738)
				(end 412.697422 -142.683738)
			)
		)
		(stroke
			(width 0)
			(type solid)
		)
		(fill yes)
		(layer "In2.Cu")
		(net "GND")
	)
	(gr_poly
		(pts
			(arc
				(start 421.375332 -139.294616)
				(mid 421.121332 -139.294616)
				(end 421.375332 -139.294616)
			)
		)
		(stroke
			(width 0)
			(type solid)
		)
		(fill yes)
		(layer "In2.Cu")
		(net "GND")
	)
	(gr_poly
		(pts
			(arc
				(start 422.808146 -139.28852)
				(mid 422.554146 -139.28852)
				(end 422.808146 -139.28852)
			)
		)
		(stroke
			(width 0)
			(type solid)
		)
		(fill yes)
		(layer "In2.Cu")
		(net "GND")
	)
	(gr_poly
		(pts
			(arc
				(start 424.08094 -139.16914)
				(mid 423.82694 -139.16914)
				(end 424.08094 -139.16914)
			)
		)
		(stroke
			(width 0)
			(type solid)
		)
		(fill yes)
		(layer "In2.Cu")
		(net "GND")
	)
	(gr_poly
		(pts
			(arc
				(start 426.15104 -139.758674)
				(mid 425.89704 -139.758674)
				(end 426.15104 -139.758674)
			)
		)
		(stroke
			(width 0)
			(type solid)
		)
		(fill yes)
		(layer "In2.Cu")
		(net "GND")
	)
	(gr_poly
		(pts
			(arc
				(start 426.845984 -139.167616)
				(mid 426.591984 -139.167616)
				(end 426.845984 -139.167616)
			)
		)
		(stroke
			(width 0)
			(type solid)
		)
		(fill yes)
		(layer "In2.Cu")
		(net "GND")
	)
	(gr_poly
		(pts
			(arc
				(start 428.37735 -139.252452)
				(mid 428.12335 -139.252452)
				(end 428.37735 -139.252452)
			)
		)
		(stroke
			(width 0)
			(type solid)
		)
		(fill yes)
		(layer "In2.Cu")
		(net "GND")
	)
	(gr_poly
		(pts
			(arc
				(start 430.824132 -123.68403)
				(mid 430.570132 -123.68403)
				(end 430.824132 -123.68403)
			)
		)
		(stroke
			(width 0)
			(type solid)
		)
		(fill yes)
		(layer "In2.Cu")
		(net "GND")
	)
	(gr_poly
		(pts
			(arc
				(start 431.375312 -138.619484)
				(mid 431.121312 -138.619484)
				(end 431.375312 -138.619484)
			)
		)
		(stroke
			(width 0)
			(type solid)
		)
		(fill yes)
		(layer "In2.Cu")
		(net "GND")
	)
	(gr_poly
		(pts
			(arc
				(start 433.991766 -139.07135)
				(mid 433.737766 -139.07135)
				(end 433.991766 -139.07135)
			)
		)
		(stroke
			(width 0)
			(type solid)
		)
		(fill yes)
		(layer "In2.Cu")
		(net "GND")
	)
	(gr_poly
		(pts
			(arc
				(start 439.2168 -127.6604)
				(mid 438.9628 -127.6604)
				(end 439.2168 -127.6604)
			)
		)
		(stroke
			(width 0)
			(type solid)
		)
		(fill yes)
		(layer "In2.Cu")
		(net "GND")
	)
	(gr_poly
		(pts
			(arc
				(start 440.51982 -127.6731)
				(mid 440.26582 -127.6731)
				(end 440.51982 -127.6731)
			)
		)
		(stroke
			(width 0)
			(type solid)
		)
		(fill yes)
		(layer "In2.Cu")
		(net "GND")
	)
	(gr_poly
		(pts
			(arc
				(start 440.567826 -123.986544)
				(mid 440.313826 -123.986544)
				(end 440.567826 -123.986544)
			)
		)
		(stroke
			(width 0)
			(type solid)
		)
		(fill yes)
		(layer "In2.Cu")
		(net "GND")
	)
	(gr_poly
		(pts
			(arc
				(start 442.185806 -126.056898)
				(mid 441.931806 -126.056898)
				(end 442.185806 -126.056898)
			)
		)
		(stroke
			(width 0)
			(type solid)
		)
		(fill yes)
		(layer "In2.Cu")
		(net "GND")
	)
	(gr_poly
		(pts
			(arc
				(start 442.843666 -123.181364)
				(mid 442.589666 -123.181364)
				(end 442.843666 -123.181364)
			)
		)
		(stroke
			(width 0)
			(type solid)
		)
		(fill yes)
		(layer "In2.Cu")
		(net "GND")
	)
	(gr_poly
		(pts
			(arc
				(start 444.278766 -123.196604)
				(mid 444.024766 -123.196604)
				(end 444.278766 -123.196604)
			)
		)
		(stroke
			(width 0)
			(type solid)
		)
		(fill yes)
		(layer "In2.Cu")
		(net "GND")
	)
	(gr_poly
		(pts
			(arc
				(start 444.456312 -125.464062)
				(mid 444.202312 -125.464062)
				(end 444.456312 -125.464062)
			)
		)
		(stroke
			(width 0)
			(type solid)
		)
		(fill yes)
		(layer "In2.Cu")
		(net "GND")
	)
	(gr_poly
		(pts
			(arc
				(start 445.0842 -125.483366)
				(mid 444.8302 -125.483366)
				(end 445.0842 -125.483366)
			)
		)
		(stroke
			(width 0)
			(type solid)
		)
		(fill yes)
		(layer "In2.Cu")
		(net "GND")
	)
	(gr_poly
		(pts
			(arc
				(start 445.906906 -123.188984)
				(mid 445.652906 -123.188984)
				(end 445.906906 -123.188984)
			)
		)
		(stroke
			(width 0)
			(type solid)
		)
		(fill yes)
		(layer "In2.Cu")
		(net "GND")
	)
	(gr_poly
		(pts
			(arc
				(start 446.786254 -125.421644)
				(mid 446.532254 -125.421644)
				(end 446.786254 -125.421644)
			)
		)
		(stroke
			(width 0)
			(type solid)
		)
		(fill yes)
		(layer "In2.Cu")
		(net "GND")
	)
	(gr_poly
		(pts
			(arc
				(start 447.413126 -120.097804)
				(mid 447.159126 -120.097804)
				(end 447.413126 -120.097804)
			)
		)
		(stroke
			(width 0)
			(type solid)
		)
		(fill yes)
		(layer "In2.Cu")
		(net "GND")
	)
	(gr_poly
		(pts
			(arc
				(start 448.528186 -124.552964)
				(mid 448.274186 -124.552964)
				(end 448.528186 -124.552964)
			)
		)
		(stroke
			(width 0)
			(type solid)
		)
		(fill yes)
		(layer "In2.Cu")
		(net "GND")
	)
	(gr_poly
		(pts
			(arc
				(start 449.018406 -120.077484)
				(mid 448.764406 -120.077484)
				(end 449.018406 -120.077484)
			)
		)
		(stroke
			(width 0)
			(type solid)
		)
		(fill yes)
		(layer "In2.Cu")
		(net "GND")
	)
	(gr_poly
		(pts
			(arc
				(start 449.775326 -124.519944)
				(mid 449.521326 -124.519944)
				(end 449.775326 -124.519944)
			)
		)
		(stroke
			(width 0)
			(type solid)
		)
		(fill yes)
		(layer "In2.Cu")
		(net "GND")
	)
	(gr_poly
		(pts
			(arc
				(start 450.603366 -119.912384)
				(mid 450.349366 -119.912384)
				(end 450.603366 -119.912384)
			)
		)
		(stroke
			(width 0)
			(type solid)
		)
		(fill yes)
		(layer "In2.Cu")
		(net "GND")
	)
	(gr_poly
		(pts
			(arc
				(start 452.160386 -119.920004)
				(mid 451.906386 -119.920004)
				(end 452.160386 -119.920004)
			)
		)
		(stroke
			(width 0)
			(type solid)
		)
		(fill yes)
		(layer "In2.Cu")
		(net "GND")
	)
	(gr_poly
		(pts
			(arc
				(start 453.397112 -124.942854)
				(mid 453.143112 -124.942854)
				(end 453.397112 -124.942854)
			)
		)
		(stroke
			(width 0)
			(type solid)
		)
		(fill yes)
		(layer "In2.Cu")
		(net "GND")
	)
	(gr_poly
		(pts
			(arc
				(start 453.984106 -140.341604)
				(mid 453.730106 -140.341604)
				(end 453.984106 -140.341604)
			)
		)
		(stroke
			(width 0)
			(type solid)
		)
		(fill yes)
		(layer "In2.Cu")
		(net "GND")
	)
	(gr_poly
		(pts
			(arc
				(start 454.679812 -124.942854)
				(mid 454.425812 -124.942854)
				(end 454.679812 -124.942854)
			)
		)
		(stroke
			(width 0)
			(type solid)
		)
		(fill yes)
		(layer "In2.Cu")
		(net "GND")
	)
	(gr_poly
		(pts
			(arc
				(start 454.720706 -120.999504)
				(mid 454.466706 -120.999504)
				(end 454.720706 -120.999504)
			)
		)
		(stroke
			(width 0)
			(type solid)
		)
		(fill yes)
		(layer "In2.Cu")
		(net "GND")
	)
	(gr_poly
		(pts
			(arc
				(start 456.097386 -121.014744)
				(mid 455.843386 -121.014744)
				(end 456.097386 -121.014744)
			)
		)
		(stroke
			(width 0)
			(type solid)
		)
		(fill yes)
		(layer "In2.Cu")
		(net "GND")
	)
	(gr_poly
		(pts
			(arc
				(start 456.357228 -124.930408)
				(mid 456.103228 -124.930408)
				(end 456.357228 -124.930408)
			)
		)
		(stroke
			(width 0)
			(type solid)
		)
		(fill yes)
		(layer "In2.Cu")
		(net "GND")
	)
	(gr_poly
		(pts
			(arc
				(start 457.639928 -124.9553)
				(mid 457.385928 -124.9553)
				(end 457.639928 -124.9553)
			)
		)
		(stroke
			(width 0)
			(type solid)
		)
		(fill yes)
		(layer "In2.Cu")
		(net "GND")
	)
	(gr_poly
		(pts
			(arc
				(start 457.707746 -119.643144)
				(mid 457.453746 -119.643144)
				(end 457.707746 -119.643144)
			)
		)
		(stroke
			(width 0)
			(type solid)
		)
		(fill yes)
		(layer "In2.Cu")
		(net "GND")
	)
	(gr_poly
		(pts
			(arc
				(start 459.033626 -119.686324)
				(mid 458.779626 -119.686324)
				(end 459.033626 -119.686324)
			)
		)
		(stroke
			(width 0)
			(type solid)
		)
		(fill yes)
		(layer "In2.Cu")
		(net "GND")
	)
	(gr_poly
		(pts
			(arc
				(start 459.119986 -124.86894)
				(mid 458.865986 -124.86894)
				(end 459.119986 -124.86894)
			)
		)
		(stroke
			(width 0)
			(type solid)
		)
		(fill yes)
		(layer "In2.Cu")
		(net "GND")
	)
	(gr_poly
		(pts
			(arc
				(start 459.97368 -144.49171)
				(mid 459.71968 -144.49171)
				(end 459.97368 -144.49171)
			)
		)
		(stroke
			(width 0)
			(type solid)
		)
		(fill yes)
		(layer "In2.Cu")
		(net "GND")
	)
	(gr_poly
		(pts
			(arc
				(start 459.974188 -145.155666)
				(mid 459.720188 -145.155666)
				(end 459.974188 -145.155666)
			)
		)
		(stroke
			(width 0)
			(type solid)
		)
		(fill yes)
		(layer "In2.Cu")
		(net "GND")
	)
	(gr_poly
		(pts
			(arc
				(start 460.402686 -124.881132)
				(mid 460.148686 -124.881132)
				(end 460.402686 -124.881132)
			)
		)
		(stroke
			(width 0)
			(type solid)
		)
		(fill yes)
		(layer "In2.Cu")
		(net "GND")
	)
	(gr_poly
		(pts
			(arc
				(start 460.43977 -122.271282)
				(mid 460.18577 -122.271282)
				(end 460.43977 -122.271282)
			)
		)
		(stroke
			(width 0)
			(type solid)
		)
		(fill yes)
		(layer "In2.Cu")
		(net "GND")
	)
	(gr_poly
		(pts
			(arc
				(start 461.734662 -122.258836)
				(mid 461.480662 -122.258836)
				(end 461.734662 -122.258836)
			)
		)
		(stroke
			(width 0)
			(type solid)
		)
		(fill yes)
		(layer "In2.Cu")
		(net "GND")
	)
	(gr_poly
		(pts
			(arc
				(start 462.178908 -124.918216)
				(mid 461.924908 -124.918216)
				(end 462.178908 -124.918216)
			)
		)
		(stroke
			(width 0)
			(type solid)
		)
		(fill yes)
		(layer "In2.Cu")
		(net "GND")
	)
	(gr_poly
		(pts
			(arc
				(start 463.449162 -124.930408)
				(mid 463.195162 -124.930408)
				(end 463.449162 -124.930408)
			)
		)
		(stroke
			(width 0)
			(type solid)
		)
		(fill yes)
		(layer "In2.Cu")
		(net "GND")
	)
	(gr_poly
		(pts
			(arc
				(start 11.338306 -24.8412)
				(mid 11.064494 -24.8412)
				(end 11.338306 -24.8412)
			)
		)
		(stroke
			(width 0)
			(type solid)
		)
		(fill yes)
		(layer "In2.Cu")
		(net "GND")
	)
	(gr_poly
		(pts
			(arc
				(start 11.363706 -35.4076)
				(mid 11.089894 -35.4076)
				(end 11.363706 -35.4076)
			)
		)
		(stroke
			(width 0)
			(type solid)
		)
		(fill yes)
		(layer "In2.Cu")
		(net "GND")
	)
	(gr_poly
		(pts
			(arc
				(start 11.363706 -33.1978)
				(mid 11.089894 -33.1978)
				(end 11.363706 -33.1978)
			)
		)
		(stroke
			(width 0)
			(type solid)
		)
		(fill yes)
		(layer "In2.Cu")
		(net "GND")
	)
	(gr_poly
		(pts
			(arc
				(start 11.363706 -29.6672)
				(mid 11.089894 -29.6672)
				(end 11.363706 -29.6672)
			)
		)
		(stroke
			(width 0)
			(type solid)
		)
		(fill yes)
		(layer "In2.Cu")
		(net "GND")
	)
	(gr_poly
		(pts
			(arc
				(start 11.363706 -28.321)
				(mid 11.089894 -28.321)
				(end 11.363706 -28.321)
			)
		)
		(stroke
			(width 0)
			(type solid)
		)
		(fill yes)
		(layer "In2.Cu")
		(net "GND")
	)
	(gr_poly
		(pts
			(arc
				(start 11.389106 -36.7792)
				(mid 11.115294 -36.7792)
				(end 11.389106 -36.7792)
			)
		)
		(stroke
			(width 0)
			(type solid)
		)
		(fill yes)
		(layer "In2.Cu")
		(net "GND")
	)
	(gr_poly
		(pts
			(arc
				(start 11.389106 -31.9024)
				(mid 11.115294 -31.9024)
				(end 11.389106 -31.9024)
			)
		)
		(stroke
			(width 0)
			(type solid)
		)
		(fill yes)
		(layer "In2.Cu")
		(net "GND")
	)
	(gr_poly
		(pts
			(arc
				(start 11.389106 -26.0858)
				(mid 11.115294 -26.0858)
				(end 11.389106 -26.0858)
			)
		)
		(stroke
			(width 0)
			(type solid)
		)
		(fill yes)
		(layer "In2.Cu")
		(net "GND")
	)
	(gr_poly
		(pts
			(arc
				(start 11.465306 -39.1414)
				(mid 11.191494 -39.1414)
				(end 11.465306 -39.1414)
			)
		)
		(stroke
			(width 0)
			(type solid)
		)
		(fill yes)
		(layer "In2.Cu")
		(net "GND")
	)
	(gr_poly
		(pts
			(arc
				(start 12.481306 -26.6446)
				(mid 12.207494 -26.6446)
				(end 12.481306 -26.6446)
			)
		)
		(stroke
			(width 0)
			(type solid)
		)
		(fill yes)
		(layer "In2.Cu")
		(net "GND")
	)
	(gr_poly
		(pts
			(arc
				(start 12.506706 -27.8384)
				(mid 12.232894 -27.8384)
				(end 12.506706 -27.8384)
			)
		)
		(stroke
			(width 0)
			(type solid)
		)
		(fill yes)
		(layer "In2.Cu")
		(net "GND")
	)
	(gr_poly
		(pts
			(arc
				(start 12.506706 -24.257)
				(mid 12.232894 -24.257)
				(end 12.506706 -24.257)
			)
		)
		(stroke
			(width 0)
			(type solid)
		)
		(fill yes)
		(layer "In2.Cu")
		(net "GND")
	)
	(gr_poly
		(pts
			(arc
				(start 12.506706 -23.0378)
				(mid 12.232894 -23.0378)
				(end 12.506706 -23.0378)
			)
		)
		(stroke
			(width 0)
			(type solid)
		)
		(fill yes)
		(layer "In2.Cu")
		(net "GND")
	)
	(gr_poly
		(pts
			(arc
				(start 12.532106 -34.9504)
				(mid 12.258294 -34.9504)
				(end 12.532106 -34.9504)
			)
		)
		(stroke
			(width 0)
			(type solid)
		)
		(fill yes)
		(layer "In2.Cu")
		(net "GND")
	)
	(gr_poly
		(pts
			(arc
				(start 12.532106 -30.2006)
				(mid 12.258294 -30.2006)
				(end 12.532106 -30.2006)
			)
		)
		(stroke
			(width 0)
			(type solid)
		)
		(fill yes)
		(layer "In2.Cu")
		(net "GND")
	)
	(gr_poly
		(pts
			(arc
				(start 12.557506 -33.6804)
				(mid 12.283694 -33.6804)
				(end 12.557506 -33.6804)
			)
		)
		(stroke
			(width 0)
			(type solid)
		)
		(fill yes)
		(layer "In2.Cu")
		(net "GND")
	)
	(gr_poly
		(pts
			(arc
				(start 12.557506 -31.369)
				(mid 12.283694 -31.369)
				(end 12.557506 -31.369)
			)
		)
		(stroke
			(width 0)
			(type solid)
		)
		(fill yes)
		(layer "In2.Cu")
		(net "GND")
	)
	(gr_poly
		(pts
			(arc
				(start 15.453106 -38.481)
				(mid 15.179294 -38.481)
				(end 15.453106 -38.481)
			)
		)
		(stroke
			(width 0)
			(type solid)
		)
		(fill yes)
		(layer "In2.Cu")
		(net "GND")
	)
	(gr_poly
		(pts
			(arc
				(start 15.707106 -22.8092)
				(mid 15.433294 -22.8092)
				(end 15.707106 -22.8092)
			)
		)
		(stroke
			(width 0)
			(type solid)
		)
		(fill yes)
		(layer "In2.Cu")
		(net "GND")
	)
	(gr_poly
		(pts
			(arc
				(start 15.992094 -27.790902)
				(mid 15.718282 -27.790902)
				(end 15.992094 -27.790902)
			)
		)
		(stroke
			(width 0)
			(type solid)
		)
		(fill yes)
		(layer "In2.Cu")
		(net "GND")
	)
	(gr_poly
		(pts
			(arc
				(start 16.012414 -26.6954)
				(mid 15.738602 -26.6954)
				(end 16.012414 -26.6954)
			)
		)
		(stroke
			(width 0)
			(type solid)
		)
		(fill yes)
		(layer "In2.Cu")
		(net "GND")
	)
	(gr_poly
		(pts
			(arc
				(start 16.018002 -31.34233)
				(mid 15.74419 -31.34233)
				(end 16.018002 -31.34233)
			)
		)
		(stroke
			(width 0)
			(type solid)
		)
		(fill yes)
		(layer "In2.Cu")
		(net "GND")
	)
	(gr_poly
		(pts
			(arc
				(start 16.286734 -29.567886)
				(mid 16.012922 -29.567886)
				(end 16.286734 -29.567886)
			)
		)
		(stroke
			(width 0)
			(type solid)
		)
		(fill yes)
		(layer "In2.Cu")
		(net "GND")
	)
	(gr_poly
		(pts
			(arc
				(start 16.326104 -33.172908)
				(mid 16.052292 -33.172908)
				(end 16.326104 -33.172908)
			)
		)
		(stroke
			(width 0)
			(type solid)
		)
		(fill yes)
		(layer "In2.Cu")
		(net "GND")
	)
	(gr_poly
		(pts
			(arc
				(start 16.356838 -24.79548)
				(mid 16.083026 -24.79548)
				(end 16.356838 -24.79548)
			)
		)
		(stroke
			(width 0)
			(type solid)
		)
		(fill yes)
		(layer "In2.Cu")
		(net "GND")
	)
	(gr_poly
		(pts
			(arc
				(start 16.361918 -36.7792)
				(mid 16.088106 -36.7792)
				(end 16.361918 -36.7792)
			)
		)
		(stroke
			(width 0)
			(type solid)
		)
		(fill yes)
		(layer "In2.Cu")
		(net "GND")
	)
	(gr_poly
		(pts
			(arc
				(start 16.364458 -35.576256)
				(mid 16.090646 -35.576256)
				(end 16.364458 -35.576256)
			)
		)
		(stroke
			(width 0)
			(type solid)
		)
		(fill yes)
		(layer "In2.Cu")
		(net "GND")
	)
	(gr_poly
		(pts
			(arc
				(start 17.557242 -31.4706)
				(mid 17.28343 -31.4706)
				(end 17.557242 -31.4706)
			)
		)
		(stroke
			(width 0)
			(type solid)
		)
		(fill yes)
		(layer "In2.Cu")
		(net "GND")
	)
	(gr_poly
		(pts
			(arc
				(start 17.559274 -33.6804)
				(mid 17.285462 -33.6804)
				(end 17.559274 -33.6804)
			)
		)
		(stroke
			(width 0)
			(type solid)
		)
		(fill yes)
		(layer "In2.Cu")
		(net "GND")
	)
	(gr_poly
		(pts
			(arc
				(start 17.569434 -35.0012)
				(mid 17.295622 -35.0012)
				(end 17.569434 -35.0012)
			)
		)
		(stroke
			(width 0)
			(type solid)
		)
		(fill yes)
		(layer "In2.Cu")
		(net "GND")
	)
	(gr_poly
		(pts
			(arc
				(start 17.575022 -30.14472)
				(mid 17.30121 -30.14472)
				(end 17.575022 -30.14472)
			)
		)
		(stroke
			(width 0)
			(type solid)
		)
		(fill yes)
		(layer "In2.Cu")
		(net "GND")
	)
	(gr_poly
		(pts
			(arc
				(start 18.120106 -38.4556)
				(mid 17.846294 -38.4556)
				(end 18.120106 -38.4556)
			)
		)
		(stroke
			(width 0)
			(type solid)
		)
		(fill yes)
		(layer "In2.Cu")
		(net "GND")
	)
	(gr_poly
		(pts
			(arc
				(start 18.183606 -22.7584)
				(mid 17.909794 -22.7584)
				(end 18.183606 -22.7584)
			)
		)
		(stroke
			(width 0)
			(type solid)
		)
		(fill yes)
		(layer "In2.Cu")
		(net "GND")
	)
	(gr_poly
		(pts
			(arc
				(start 145.67662 -59.1185)
				(mid 145.37182 -59.1185)
				(end 145.67662 -59.1185)
			)
		)
		(stroke
			(width 0)
			(type solid)
		)
		(fill yes)
		(layer "In2.Cu")
		(net "GND")
	)
	(gr_poly
		(pts
			(arc
				(start 145.67662 -57.94502)
				(mid 145.37182 -57.94502)
				(end 145.67662 -57.94502)
			)
		)
		(stroke
			(width 0)
			(type solid)
		)
		(fill yes)
		(layer "In2.Cu")
		(net "GND")
	)
	(gr_poly
		(pts
			(arc
				(start 147.56384 -59.58586)
				(mid 147.25904 -59.58586)
				(end 147.56384 -59.58586)
			)
		)
		(stroke
			(width 0)
			(type solid)
		)
		(fill yes)
		(layer "In2.Cu")
		(net "GND")
	)
	(gr_poly
		(pts
			(arc
				(start 147.56384 -58.43524)
				(mid 147.25904 -58.43524)
				(end 147.56384 -58.43524)
			)
		)
		(stroke
			(width 0)
			(type solid)
		)
		(fill yes)
		(layer "In2.Cu")
		(net "GND")
	)
	(gr_poly
		(pts
			(arc
				(start 154.326844 -118.363238)
				(mid 154.035252 -118.363238)
				(end 154.326844 -118.363238)
			)
		)
		(stroke
			(width 0)
			(type solid)
		)
		(fill yes)
		(layer "In2.Cu")
		(net "GND")
	)
	(gr_poly
		(pts
			(arc
				(start 158.555436 -118.553484)
				(mid 158.263844 -118.553484)
				(end 158.555436 -118.553484)
			)
		)
		(stroke
			(width 0)
			(type solid)
		)
		(fill yes)
		(layer "In2.Cu")
		(net "GND")
	)
	(gr_poly
		(pts
			(arc
				(start 14.28369 -93.725492)
				(mid 13.969238 -93.725492)
				(end 14.28369 -93.725492)
			)
		)
		(stroke
			(width 0)
			(type solid)
		)
		(fill yes)
		(layer "In2.Cu")
		(net "GND")
	)
	(gr_poly
		(pts
			(arc
				(start 156.656278 -27.518106)
				(mid 156.330142 -27.518106)
				(end 156.656278 -27.518106)
			)
		)
		(stroke
			(width 0)
			(type solid)
		)
		(fill yes)
		(layer "In2.Cu")
		(net "GND")
	)
	(gr_poly
		(pts
			(arc
				(start 156.669486 -30.131258)
				(mid 156.34335 -30.131258)
				(end 156.669486 -30.131258)
			)
		)
		(stroke
			(width 0)
			(type solid)
		)
		(fill yes)
		(layer "In2.Cu")
		(net "GND")
	)
	(gr_poly
		(pts
			(arc
				(start 158.201868 -28.4988)
				(mid 157.875732 -28.4988)
				(end 158.201868 -28.4988)
			)
		)
		(stroke
			(width 0)
			(type solid)
		)
		(fill yes)
		(layer "In2.Cu")
		(net "GND")
	)
	(gr_poly
		(pts
			(arc
				(start 319.644268 -28.1686)
				(mid 319.318132 -28.1686)
				(end 319.644268 -28.1686)
			)
		)
		(stroke
			(width 0)
			(type solid)
		)
		(fill yes)
		(layer "In2.Cu")
		(net "GND")
	)
	(gr_poly
		(pts
			(arc
				(start 365.882936 -137.286238)
				(mid 365.566452 -137.286238)
				(end 365.882936 -137.286238)
			)
		)
		(stroke
			(width 0)
			(type solid)
		)
		(fill yes)
		(layer "In2.Cu")
		(net "GND")
	)
	(gr_poly
		(pts
			(arc
				(start 315.598048 -47.67834)
				(mid 315.191648 -47.67834)
				(end 315.598048 -47.67834)
			)
		)
		(stroke
			(width 0)
			(type solid)
		)
		(fill yes)
		(layer "In2.Cu")
		(net "GND")
	)
	(gr_line
		(start 5.830316 -4.479544)
		(end 6.026912 -4.67614)
		(stroke
			(width 0.0635)
			(type default)
		)
		(layer "In2.Cu")
	)
	(gr_line
		(start 5.83184 -4.118356)
		(end 6.36524 -4.118356)
		(stroke
			(width 0.0635)
			(type default)
		)
		(layer "In2.Cu")
	)
	(gr_line
		(start 6.026912 -4.67614)
		(end 6.026912 -4.757674)
		(stroke
			(width 0.0635)
			(type default)
		)
		(layer "In2.Cu")
	)
	(gr_line
		(start 15.977616 4.231132)
		(end 16.02105 4.231132)
		(stroke
			(width 0.0635)
			(type default)
		)
		(layer "In2.Cu")
	)
	(gr_line
		(start 16.229076 4.079748)
		(end 16.27251 4.079748)
		(stroke
			(width 0.0635)
			(type default)
		)
		(layer "In2.Cu")
	)
	(gr_line
		(start 17.718532 4.336288)
		(end 18.077688 4.695444)
		(stroke
			(width 0.0635)
			(type default)
		)
		(layer "In2.Cu")
	)
	(gr_line
		(start 17.972532 4.079748)
		(end 18.290286 4.079748)
		(stroke
			(width 0.0635)
			(type default)
		)
		(layer "In2.Cu")
	)
	(gr_line
		(start 18.290286 4.079748)
		(end 18.894044 4.683506)
		(stroke
			(width 0.0635)
			(type default)
		)
		(layer "In2.Cu")
	)
	(gr_line
		(start 21.8821 -87.545418)
		(end 22.3266 -87.989918)
		(stroke
			(width 0.0635)
			(type default)
		)
		(layer "In2.Cu")
	)
	(gr_line
		(start 21.8821 -87.155782)
		(end 21.8821 -87.545418)
		(stroke
			(width 0.0635)
			(type default)
		)
		(layer "In2.Cu")
	)
	(gr_line
		(start 21.8821 -87.155782)
		(end 21.90242 -87.135462)
		(stroke
			(width 0.0635)
			(type default)
		)
		(layer "In2.Cu")
	)
	(gr_line
		(start 22.13102 -87.12962)
		(end 22.181312 -87.179912)
		(stroke
			(width 0.0635)
			(type default)
		)
		(layer "In2.Cu")
	)
	(gr_line
		(start 22.18309 -87.18169)
		(end 22.352 -87.3506)
		(stroke
			(width 0.0635)
			(type default)
		)
		(layer "In2.Cu")
	)
	(gr_line
		(start 22.3266 -87.989918)
		(end 22.3266 -88.265)
		(stroke
			(width 0.0635)
			(type default)
		)
		(layer "In2.Cu")
	)
	(gr_line
		(start 23.802848 -96.648778)
		(end 24.526748 -97.372678)
		(stroke
			(width 0.0635)
			(type default)
		)
		(layer "In2.Cu")
	)
	(gr_line
		(start 24.757888 -96.757236)
		(end 24.757888 -97.144078)
		(stroke
			(width 0.0635)
			(type default)
		)
		(layer "In2.Cu")
	)
	(gr_line
		(start 37.949632 -50.01006)
		(end 38.1 -49.8602)
		(stroke
			(width 0.0635)
			(type default)
		)
		(layer "In2.Cu")
	)
	(gr_line
		(start 37.962332 -50.243232)
		(end 38.1 -50.3809)
		(stroke
			(width 0.0635)
			(type default)
		)
		(layer "In2.Cu")
	)
	(gr_line
		(start 38.1 -50.3809)
		(end 38.1 -50.7619)
		(stroke
			(width 0.0635)
			(type default)
		)
		(layer "In2.Cu")
	)
	(gr_line
		(start 38.1 -49.4919)
		(end 38.1 -49.8602)
		(stroke
			(width 0.0635)
			(type default)
		)
		(layer "In2.Cu")
	)
	(gr_line
		(start 38.633654 -102.94366)
		(end 38.961568 -102.616)
		(stroke
			(width 0.0635)
			(type default)
		)
		(layer "In2.Cu")
	)
	(gr_line
		(start 38.633908 -103.17734)
		(end 38.961568 -103.505)
		(stroke
			(width 0.0635)
			(type default)
		)
		(layer "In2.Cu")
	)
	(gr_line
		(start 41.348152 -50.9143)
		(end 41.348152 -50.9651)
		(stroke
			(width 0.0635)
			(type default)
		)
		(layer "In2.Cu")
	)
	(gr_line
		(start 41.348152 -50.9143)
		(end 41.802304 -50.460148)
		(stroke
			(width 0.0635)
			(type default)
		)
		(layer "In2.Cu")
	)
	(gr_line
		(start 41.3512 -49.6824)
		(end 41.802304 -50.133504)
		(stroke
			(width 0.0635)
			(type default)
		)
		(layer "In2.Cu")
	)
	(gr_line
		(start 41.804082 -50.45837)
		(end 41.894252 -50.3682)
		(stroke
			(width 0.0635)
			(type default)
		)
		(layer "In2.Cu")
	)
	(gr_line
		(start 41.804082 -50.135282)
		(end 41.8084 -50.1396)
		(stroke
			(width 0.0635)
			(type default)
		)
		(layer "In2.Cu")
	)
	(gr_line
		(start 67.101466 -69.45884)
		(end 67.344798 -69.329808)
		(stroke
			(width 0.0635)
			(type default)
		)
		(layer "In2.Cu")
	)
	(gr_line
		(start 67.344798 -69.329808)
		(end 67.40652 -69.126862)
		(stroke
			(width 0.0635)
			(type default)
		)
		(layer "In2.Cu")
	)
	(gr_line
		(start 67.622674 -69.039486)
		(end 67.793362 -69.092064)
		(stroke
			(width 0.0635)
			(type default)
		)
		(layer "In2.Cu")
	)
	(gr_line
		(start 67.793362 -69.092064)
		(end 68.036186 -68.963286)
		(stroke
			(width 0.0635)
			(type default)
		)
		(layer "In2.Cu")
	)
	(gr_line
		(start 129.944368 -76.864464)
		(end 129.944368 -77.202538)
		(stroke
			(width 0.04445)
			(type default)
		)
		(layer "In2.Cu")
	)
	(gr_line
		(start 129.944368 -76.864464)
		(end 129.947162 -76.86167)
		(stroke
			(width 0.04445)
			(type default)
		)
		(layer "In2.Cu")
	)
	(gr_line
		(start 129.944368 -76.550012)
		(end 129.947162 -76.552806)
		(stroke
			(width 0.04445)
			(type default)
		)
		(layer "In2.Cu")
	)
	(gr_line
		(start 129.944368 -76.211938)
		(end 129.944368 -76.550012)
		(stroke
			(width 0.04445)
			(type default)
		)
		(layer "In2.Cu")
	)
	(gr_line
		(start 129.950718 -76.858114)
		(end 130.009646 -76.799186)
		(stroke
			(width 0.04445)
			(type default)
		)
		(layer "In2.Cu")
	)
	(gr_line
		(start 129.950718 -76.556362)
		(end 130.00228 -76.607924)
		(stroke
			(width 0.04445)
			(type default)
		)
		(layer "In2.Cu")
	)
	(gr_line
		(start 130.785108 -76.116434)
		(end 130.820668 -76.116434)
		(stroke
			(width 0.04445)
			(type default)
		)
		(layer "In2.Cu")
	)
	(gr_line
		(start 130.791712 -76.306934)
		(end 130.814064 -76.306934)
		(stroke
			(width 0.04445)
			(type default)
		)
		(layer "In2.Cu")
	)
	(gr_line
		(start 131.643628 -76.802488)
		(end 131.679188 -76.802488)
		(stroke
			(width 0.04445)
			(type default)
		)
		(layer "In2.Cu")
	)
	(gr_line
		(start 131.650232 -76.611988)
		(end 131.661408 -76.611988)
		(stroke
			(width 0.04445)
			(type default)
		)
		(layer "In2.Cu")
	)
	(gr_line
		(start 132.004562 -76.417678)
		(end 132.007864 -76.411836)
		(stroke
			(width 0.04445)
			(type default)
		)
		(layer "In2.Cu")
	)
	(gr_line
		(start 132.173218 -76.507086)
		(end 132.17652 -76.501244)
		(stroke
			(width 0.04445)
			(type default)
		)
		(layer "In2.Cu")
	)
	(gr_line
		(start 132.501894 -76.116434)
		(end 132.53466 -76.116434)
		(stroke
			(width 0.04445)
			(type default)
		)
		(layer "In2.Cu")
	)
	(gr_line
		(start 132.519674 -76.306934)
		(end 132.541264 -76.306934)
		(stroke
			(width 0.04445)
			(type default)
		)
		(layer "In2.Cu")
	)
	(gr_line
		(start 133.356604 -75.621388)
		(end 133.38937 -75.621388)
		(stroke
			(width 0.04445)
			(type default)
		)
		(layer "In2.Cu")
	)
	(gr_line
		(start 133.363208 -75.811888)
		(end 133.395974 -75.811888)
		(stroke
			(width 0.04445)
			(type default)
		)
		(layer "In2.Cu")
	)
	(gr_line
		(start 134.218934 -75.125834)
		(end 134.2517 -75.125834)
		(stroke
			(width 0.04445)
			(type default)
		)
		(layer "In2.Cu")
	)
	(gr_line
		(start 134.225538 -75.316334)
		(end 134.258304 -75.316334)
		(stroke
			(width 0.04445)
			(type default)
		)
		(layer "In2.Cu")
	)
	(gr_line
		(start 135.08228 -74.630534)
		(end 135.108188 -74.630534)
		(stroke
			(width 0.04445)
			(type default)
		)
		(layer "In2.Cu")
	)
	(gr_line
		(start 135.090408 -74.821034)
		(end 135.10006 -74.821034)
		(stroke
			(width 0.04445)
			(type default)
		)
		(layer "In2.Cu")
	)
	(gr_line
		(start 135.932164 -75.316334)
		(end 135.975344 -75.316334)
		(stroke
			(width 0.04445)
			(type default)
		)
		(layer "In2.Cu")
	)
	(gr_line
		(start 135.938768 -75.125834)
		(end 135.96874 -75.125834)
		(stroke
			(width 0.04445)
			(type default)
		)
		(layer "In2.Cu")
	)
	(gr_line
		(start 136.79932 -74.630534)
		(end 136.8171 -74.630534)
		(stroke
			(width 0.04445)
			(type default)
		)
		(layer "In2.Cu")
	)
	(gr_line
		(start 136.807448 -74.821034)
		(end 136.825228 -74.821034)
		(stroke
			(width 0.04445)
			(type default)
		)
		(layer "In2.Cu")
	)
	(gr_line
		(start 137.649204 -74.135234)
		(end 137.68197 -74.135234)
		(stroke
			(width 0.04445)
			(type default)
		)
		(layer "In2.Cu")
	)
	(gr_line
		(start 137.655808 -74.325734)
		(end 137.688574 -74.325734)
		(stroke
			(width 0.04445)
			(type default)
		)
		(layer "In2.Cu")
	)
	(gr_line
		(start 138.504422 -73.639934)
		(end 138.547348 -73.639934)
		(stroke
			(width 0.04445)
			(type default)
		)
		(layer "In2.Cu")
	)
	(gr_line
		(start 138.51128 -73.830434)
		(end 138.554206 -73.830434)
		(stroke
			(width 0.04445)
			(type default)
		)
		(layer "In2.Cu")
	)
	(gr_line
		(start 139.370054 -73.144634)
		(end 139.405614 -73.144634)
		(stroke
			(width 0.04445)
			(type default)
		)
		(layer "In2.Cu")
	)
	(gr_line
		(start 139.376658 -73.335134)
		(end 139.39901 -73.335134)
		(stroke
			(width 0.04445)
			(type default)
		)
		(layer "In2.Cu")
	)
	(gr_line
		(start 139.387834 -74.38771)
		(end 139.387834 -74.725784)
		(stroke
			(width 0.04445)
			(type default)
		)
		(layer "In2.Cu")
	)
	(gr_line
		(start 139.387834 -74.38771)
		(end 139.408662 -74.366882)
		(stroke
			(width 0.04445)
			(type default)
		)
		(layer "In2.Cu")
	)
	(gr_line
		(start 139.387834 -74.073258)
		(end 139.408662 -74.094086)
		(stroke
			(width 0.04445)
			(type default)
		)
		(layer "In2.Cu")
	)
	(gr_line
		(start 139.387834 -73.735184)
		(end 139.387834 -74.073258)
		(stroke
			(width 0.04445)
			(type default)
		)
		(layer "In2.Cu")
	)
	(gr_line
		(start 139.41044 -74.365104)
		(end 139.445746 -74.329798)
		(stroke
			(width 0.04445)
			(type default)
		)
		(layer "In2.Cu")
	)
	(gr_line
		(start 139.41044 -74.095864)
		(end 139.452858 -74.138282)
		(stroke
			(width 0.04445)
			(type default)
		)
		(layer "In2.Cu")
	)
	(gr_line
		(start 140.224256 -73.830434)
		(end 141.37513 -73.830434)
		(stroke
			(width 0.04445)
			(type default)
		)
		(layer "In2.Cu")
	)
	(gr_line
		(start 140.22832 -73.639934)
		(end 141.454124 -73.639934)
		(stroke
			(width 0.04445)
			(type default)
		)
		(layer "In2.Cu")
	)
	(gr_line
		(start 141.37513 -73.830434)
		(end 141.898116 -74.35342)
		(stroke
			(width 0.04445)
			(type default)
		)
		(layer "In2.Cu")
	)
	(gr_line
		(start 141.454124 -73.639934)
		(end 141.95171 -74.13752)
		(stroke
			(width 0.04445)
			(type default)
		)
		(layer "In2.Cu")
	)
	(gr_line
		(start 141.95171 -74.13752)
		(end 141.983968 -74.13752)
		(stroke
			(width 0.04445)
			(type default)
		)
		(layer "In2.Cu")
	)
	(gr_line
		(start 143.00835 -75.316334)
		(end 143.0274 -75.335384)
		(stroke
			(width 0.04445)
			(type default)
		)
		(layer "In2.Cu")
	)
	(gr_line
		(start 143.00835 -75.125834)
		(end 143.0274 -75.106784)
		(stroke
			(width 0.04445)
			(type default)
		)
		(layer "In2.Cu")
	)
	(gr_line
		(start 143.0274 -75.335384)
		(end 143.049498 -75.335384)
		(stroke
			(width 0.04445)
			(type default)
		)
		(layer "In2.Cu")
	)
	(gr_line
		(start 143.0274 -75.106784)
		(end 143.049498 -75.106784)
		(stroke
			(width 0.04445)
			(type default)
		)
		(layer "In2.Cu")
	)
	(gr_line
		(start 143.392906 -73.744074)
		(end 143.392906 -73.771506)
		(stroke
			(width 0.04445)
			(type default)
		)
		(layer "In2.Cu")
	)
	(gr_line
		(start 143.392906 -73.744074)
		(end 143.4084 -73.72858)
		(stroke
			(width 0.04445)
			(type default)
		)
		(layer "In2.Cu")
	)
	(gr_line
		(start 143.546322 -73.923906)
		(end 143.572484 -73.923906)
		(stroke
			(width 0.04445)
			(type default)
		)
		(layer "In2.Cu")
	)
	(gr_line
		(start 143.572484 -73.923906)
		(end 143.587978 -73.908412)
		(stroke
			(width 0.04445)
			(type default)
		)
		(layer "In2.Cu")
	)
	(gr_line
		(start 160.3502 -69.215)
		(end 160.412684 -69.277484)
		(stroke
			(width 0.0635)
			(type default)
		)
		(layer "In2.Cu")
	)
	(gr_line
		(start 160.38068 -68.9864)
		(end 160.412684 -68.954396)
		(stroke
			(width 0.0635)
			(type default)
		)
		(layer "In2.Cu")
	)
	(gr_line
		(start 160.414462 -69.279262)
		(end 160.88614 -69.75094)
		(stroke
			(width 0.0635)
			(type default)
		)
		(layer "In2.Cu")
	)
	(gr_line
		(start 160.414462 -68.952618)
		(end 160.88614 -68.48094)
		(stroke
			(width 0.0635)
			(type default)
		)
		(layer "In2.Cu")
	)
	(gr_line
		(start 167.707056 -44.009056)
		(end 167.7924 -44.0944)
		(stroke
			(width 0.0635)
			(type default)
		)
		(layer "In2.Cu")
	)
	(gr_line
		(start 167.707056 -43.646344)
		(end 167.7924 -43.561)
		(stroke
			(width 0.0635)
			(type default)
		)
		(layer "In2.Cu")
	)
	(gr_line
		(start 167.7924 -44.0944)
		(end 167.7924 -44.45)
		(stroke
			(width 0.0635)
			(type default)
		)
		(layer "In2.Cu")
	)
	(gr_line
		(start 167.7924 -43.18)
		(end 167.7924 -43.561)
		(stroke
			(width 0.0635)
			(type default)
		)
		(layer "In2.Cu")
	)
	(gr_line
		(start 187.739528 -63.838582)
		(end 187.8076 -63.906654)
		(stroke
			(width 0.0635)
			(type default)
		)
		(layer "In2.Cu")
	)
	(gr_line
		(start 187.739528 -63.47587)
		(end 187.833 -63.382398)
		(stroke
			(width 0.0635)
			(type default)
		)
		(layer "In2.Cu")
	)
	(gr_line
		(start 187.8076 -63.906654)
		(end 187.8076 -64.3636)
		(stroke
			(width 0.0635)
			(type default)
		)
		(layer "In2.Cu")
	)
	(gr_line
		(start 187.833 -62.865)
		(end 187.833 -63.382398)
		(stroke
			(width 0.0635)
			(type default)
		)
		(layer "In2.Cu")
	)
	(gr_line
		(start 202.759056 -50.308256)
		(end 203.0222 -50.5714)
		(stroke
			(width 0.0635)
			(type default)
		)
		(layer "In2.Cu")
	)
	(gr_line
		(start 202.759056 -49.945544)
		(end 203.0222 -49.6824)
		(stroke
			(width 0.0635)
			(type default)
		)
		(layer "In2.Cu")
	)
	(gr_line
		(start 206.6798 -50.5206)
		(end 206.917544 -50.282856)
		(stroke
			(width 0.0635)
			(type default)
		)
		(layer "In2.Cu")
	)
	(gr_line
		(start 206.6798 -49.6824)
		(end 206.917544 -49.920144)
		(stroke
			(width 0.0635)
			(type default)
		)
		(layer "In2.Cu")
	)
	(gr_line
		(start 232.101898 -69.45884)
		(end 232.34523 -69.329808)
		(stroke
			(width 0.0635)
			(type default)
		)
		(layer "In2.Cu")
	)
	(gr_line
		(start 232.195116 -68.5038)
		(end 232.244646 -68.55333)
		(stroke
			(width 0.0635)
			(type default)
		)
		(layer "In2.Cu")
	)
	(gr_line
		(start 232.34523 -69.329808)
		(end 232.399586 -69.1515)
		(stroke
			(width 0.0635)
			(type default)
		)
		(layer "In2.Cu")
	)
	(gr_line
		(start 232.514648 -68.823332)
		(end 232.51795 -68.826634)
		(stroke
			(width 0.0635)
			(type default)
		)
		(layer "In2.Cu")
	)
	(gr_line
		(start 232.51795 -68.826634)
		(end 232.520236 -68.830952)
		(stroke
			(width 0.0635)
			(type default)
		)
		(layer "In2.Cu")
	)
	(gr_line
		(start 232.634282 -69.042788)
		(end 232.793794 -69.092064)
		(stroke
			(width 0.0635)
			(type default)
		)
		(layer "In2.Cu")
	)
	(gr_line
		(start 232.793794 -69.092064)
		(end 233.036618 -68.963286)
		(stroke
			(width 0.0635)
			(type default)
		)
		(layer "In2.Cu")
	)
	(gr_line
		(start 290.6522 -65.810384)
		(end 290.945316 -65.979548)
		(stroke
			(width 0.04445)
			(type default)
		)
		(layer "In2.Cu")
	)
	(gr_line
		(start 290.945316 -65.979548)
		(end 290.99891 -65.96507)
		(stroke
			(width 0.04445)
			(type default)
		)
		(layer "In2.Cu")
	)
	(gr_line
		(start 291.00526 -65.963292)
		(end 291.034724 -65.955418)
		(stroke
			(width 0.04445)
			(type default)
		)
		(layer "In2.Cu")
	)
	(gr_line
		(start 291.196522 -66.058034)
		(end 291.203888 -66.085466)
		(stroke
			(width 0.04445)
			(type default)
		)
		(layer "In2.Cu")
	)
	(gr_line
		(start 291.205412 -66.091562)
		(end 291.217604 -66.136774)
		(stroke
			(width 0.04445)
			(type default)
		)
		(layer "In2.Cu")
	)
	(gr_line
		(start 291.217604 -66.136774)
		(end 291.51072 -66.305938)
		(stroke
			(width 0.04445)
			(type default)
		)
		(layer "In2.Cu")
	)
	(gr_line
		(start 291.48913 -65.715388)
		(end 291.521896 -65.715388)
		(stroke
			(width 0.04445)
			(type default)
		)
		(layer "In2.Cu")
	)
	(gr_line
		(start 291.495734 -65.905888)
		(end 291.5285 -65.905888)
		(stroke
			(width 0.04445)
			(type default)
		)
		(layer "In2.Cu")
	)
	(gr_line
		(start 292.35146 -65.219834)
		(end 292.384226 -65.219834)
		(stroke
			(width 0.04445)
			(type default)
		)
		(layer "In2.Cu")
	)
	(gr_line
		(start 292.358064 -65.410334)
		(end 292.39083 -65.410334)
		(stroke
			(width 0.04445)
			(type default)
		)
		(layer "In2.Cu")
	)
	(gr_line
		(start 293.20617 -64.724788)
		(end 293.22776 -64.724788)
		(stroke
			(width 0.04445)
			(type default)
		)
		(layer "In2.Cu")
	)
	(gr_line
		(start 293.212774 -64.915288)
		(end 293.22776 -64.915288)
		(stroke
			(width 0.04445)
			(type default)
		)
		(layer "In2.Cu")
	)
	(gr_line
		(start 294.073326 -64.229488)
		(end 294.091106 -64.229488)
		(stroke
			(width 0.04445)
			(type default)
		)
		(layer "In2.Cu")
	)
	(gr_line
		(start 294.081454 -64.419988)
		(end 294.099234 -64.419988)
		(stroke
			(width 0.04445)
			(type default)
		)
		(layer "In2.Cu")
	)
	(gr_line
		(start 294.92321 -63.734188)
		(end 294.955976 -63.734188)
		(stroke
			(width 0.04445)
			(type default)
		)
		(layer "In2.Cu")
	)
	(gr_line
		(start 294.929814 -63.924688)
		(end 294.96258 -63.924688)
		(stroke
			(width 0.04445)
			(type default)
		)
		(layer "In2.Cu")
	)
	(gr_line
		(start 294.9448 -98.995738)
		(end 295.237916 -98.826574)
		(stroke
			(width 0.04445)
			(type default)
		)
		(layer "In2.Cu")
	)
	(gr_line
		(start 294.9448 -76.864464)
		(end 294.9448 -77.202538)
		(stroke
			(width 0.04445)
			(type default)
		)
		(layer "In2.Cu")
	)
	(gr_line
		(start 294.9448 -76.864464)
		(end 294.947594 -76.86167)
		(stroke
			(width 0.04445)
			(type default)
		)
		(layer "In2.Cu")
	)
	(gr_line
		(start 294.9448 -76.550012)
		(end 294.947594 -76.552806)
		(stroke
			(width 0.04445)
			(type default)
		)
		(layer "In2.Cu")
	)
	(gr_line
		(start 294.9448 -76.211938)
		(end 294.9448 -76.550012)
		(stroke
			(width 0.04445)
			(type default)
		)
		(layer "In2.Cu")
	)
	(gr_line
		(start 294.95115 -76.858114)
		(end 295.010078 -76.799186)
		(stroke
			(width 0.04445)
			(type default)
		)
		(layer "In2.Cu")
	)
	(gr_line
		(start 294.95115 -76.556362)
		(end 295.002712 -76.607924)
		(stroke
			(width 0.04445)
			(type default)
		)
		(layer "In2.Cu")
	)
	(gr_line
		(start 295.237916 -98.826574)
		(end 295.261284 -98.739198)
		(stroke
			(width 0.04445)
			(type default)
		)
		(layer "In2.Cu")
	)
	(gr_line
		(start 295.433242 -98.64852)
		(end 295.510204 -98.669348)
		(stroke
			(width 0.04445)
			(type default)
		)
		(layer "In2.Cu")
	)
	(gr_line
		(start 295.510204 -98.669348)
		(end 295.80332 -98.500184)
		(stroke
			(width 0.04445)
			(type default)
		)
		(layer "In2.Cu")
	)
	(gr_line
		(start 295.745408 -100.085652)
		(end 295.80332 -100.143564)
		(stroke
			(width 0.04445)
			(type default)
		)
		(layer "In2.Cu")
	)
	(gr_line
		(start 295.78554 -76.116434)
		(end 295.8211 -76.116434)
		(stroke
			(width 0.04445)
			(type default)
		)
		(layer "In2.Cu")
	)
	(gr_line
		(start 295.78554 -63.238634)
		(end 295.8211 -63.238634)
		(stroke
			(width 0.04445)
			(type default)
		)
		(layer "In2.Cu")
	)
	(gr_line
		(start 295.80332 -100.143564)
		(end 295.80332 -100.481638)
		(stroke
			(width 0.04445)
			(type default)
		)
		(layer "In2.Cu")
	)
	(gr_arc
		(start 295.80332 -99.490784)
		(mid 295.528156 -99.824338)
		(end 295.29151 -100.186236)
		(stroke
			(width 0.04445)
			(type default)
		)
		(layer "In2.Cu")
	)
	(gr_line
		(start 296.64406 -76.802488)
		(end 296.67962 -76.802488)
		(stroke
			(width 0.04445)
			(type default)
		)
		(layer "In2.Cu")
	)
	(gr_line
		(start 296.64406 -63.924688)
		(end 296.66184 -63.924688)
		(stroke
			(width 0.04445)
			(type default)
		)
		(layer "In2.Cu")
	)
	(gr_line
		(start 296.650664 -63.734188)
		(end 296.686732 -63.734188)
		(stroke
			(width 0.04445)
			(type default)
		)
		(layer "In2.Cu")
	)
	(gr_line
		(start 296.66184 -99.986338)
		(end 296.954702 -100.155248)
		(stroke
			(width 0.04445)
			(type default)
		)
		(layer "In2.Cu")
	)
	(gr_line
		(start 296.954702 -100.155248)
		(end 297.042332 -100.131626)
		(stroke
			(width 0.04445)
			(type default)
		)
		(layer "In2.Cu")
	)
	(gr_line
		(start 297.000168 -64.110616)
		(end 297.007788 -64.123824)
		(stroke
			(width 0.04445)
			(type default)
		)
		(layer "In2.Cu")
	)
	(gr_line
		(start 297.004994 -76.417678)
		(end 297.008296 -76.411836)
		(stroke
			(width 0.04445)
			(type default)
		)
		(layer "In2.Cu")
	)
	(gr_line
		(start 297.007788 -64.123824)
		(end 297.008296 -64.12484)
		(stroke
			(width 0.04445)
			(type default)
		)
		(layer "In2.Cu")
	)
	(gr_line
		(start 297.17365 -76.507086)
		(end 297.176952 -76.501244)
		(stroke
			(width 0.04445)
			(type default)
		)
		(layer "In2.Cu")
	)
	(gr_line
		(start 297.17365 -64.029082)
		(end 297.176952 -64.034924)
		(stroke
			(width 0.04445)
			(type default)
		)
		(layer "In2.Cu")
	)
	(gr_line
		(start 297.20667 -100.235258)
		(end 297.227244 -100.312474)
		(stroke
			(width 0.04445)
			(type default)
		)
		(layer "In2.Cu")
	)
	(gr_line
		(start 297.227244 -100.312474)
		(end 297.520106 -100.481384)
		(stroke
			(width 0.04445)
			(type default)
		)
		(layer "In2.Cu")
	)
	(gr_line
		(start 297.495214 -64.419734)
		(end 297.531282 -64.419734)
		(stroke
			(width 0.04445)
			(type default)
		)
		(layer "In2.Cu")
	)
	(gr_line
		(start 297.502326 -99.890834)
		(end 297.537886 -99.890834)
		(stroke
			(width 0.04445)
			(type default)
		)
		(layer "In2.Cu")
	)
	(gr_line
		(start 297.502326 -76.116434)
		(end 297.535092 -76.116434)
		(stroke
			(width 0.04445)
			(type default)
		)
		(layer "In2.Cu")
	)
	(gr_line
		(start 297.520106 -99.490784)
		(end 297.813222 -99.321874)
		(stroke
			(width 0.04445)
			(type default)
		)
		(layer "In2.Cu")
	)
	(gr_line
		(start 297.520106 -98.16211)
		(end 297.520106 -98.500184)
		(stroke
			(width 0.04445)
			(type default)
		)
		(layer "In2.Cu")
	)
	(gr_line
		(start 297.520106 -98.16211)
		(end 297.540934 -98.141282)
		(stroke
			(width 0.04445)
			(type default)
		)
		(layer "In2.Cu")
	)
	(gr_line
		(start 297.520106 -97.847658)
		(end 297.540934 -97.868486)
		(stroke
			(width 0.04445)
			(type default)
		)
		(layer "In2.Cu")
	)
	(gr_line
		(start 297.520106 -97.509584)
		(end 297.520106 -97.847658)
		(stroke
			(width 0.04445)
			(type default)
		)
		(layer "In2.Cu")
	)
	(gr_line
		(start 297.520106 -76.306934)
		(end 297.541696 -76.306934)
		(stroke
			(width 0.04445)
			(type default)
		)
		(layer "In2.Cu")
	)
	(gr_line
		(start 297.520106 -64.229234)
		(end 297.537886 -64.229234)
		(stroke
			(width 0.04445)
			(type default)
		)
		(layer "In2.Cu")
	)
	(gr_line
		(start 297.542712 -98.139504)
		(end 297.58513 -98.097086)
		(stroke
			(width 0.04445)
			(type default)
		)
		(layer "In2.Cu")
	)
	(gr_line
		(start 297.542712 -97.870264)
		(end 297.578018 -97.90557)
		(stroke
			(width 0.04445)
			(type default)
		)
		(layer "In2.Cu")
	)
	(gr_line
		(start 297.813222 -99.321874)
		(end 297.900598 -99.345496)
		(stroke
			(width 0.04445)
			(type default)
		)
		(layer "In2.Cu")
	)
	(gr_line
		(start 297.860466 -65.599818)
		(end 297.866816 -65.610486)
		(stroke
			(width 0.04445)
			(type default)
		)
		(layer "In2.Cu")
	)
	(gr_line
		(start 297.866816 -65.610486)
		(end 297.871642 -65.619122)
		(stroke
			(width 0.04445)
			(type default)
		)
		(layer "In2.Cu")
	)
	(gr_line
		(start 298.02709 -65.5066)
		(end 298.031916 -65.515236)
		(stroke
			(width 0.04445)
			(type default)
		)
		(layer "In2.Cu")
	)
	(gr_line
		(start 298.031916 -65.515236)
		(end 298.038266 -65.525904)
		(stroke
			(width 0.04445)
			(type default)
		)
		(layer "In2.Cu")
	)
	(gr_line
		(start 298.064936 -99.24161)
		(end 298.08551 -99.164648)
		(stroke
			(width 0.04445)
			(type default)
		)
		(layer "In2.Cu")
	)
	(gr_line
		(start 298.08551 -99.164648)
		(end 298.378626 -98.995738)
		(stroke
			(width 0.04445)
			(type default)
		)
		(layer "In2.Cu")
	)
	(gr_line
		(start 298.357036 -75.621388)
		(end 298.400216 -75.621388)
		(stroke
			(width 0.04445)
			(type default)
		)
		(layer "In2.Cu")
	)
	(gr_line
		(start 298.360846 -66.896488)
		(end 298.393612 -66.896488)
		(stroke
			(width 0.04445)
			(type default)
		)
		(layer "In2.Cu")
	)
	(gr_line
		(start 298.36364 -75.811888)
		(end 298.393612 -75.811888)
		(stroke
			(width 0.04445)
			(type default)
		)
		(layer "In2.Cu")
	)
	(gr_line
		(start 298.36745 -66.705988)
		(end 298.400216 -66.705988)
		(stroke
			(width 0.04445)
			(type default)
		)
		(layer "In2.Cu")
	)
	(gr_line
		(start 298.378626 -98.005138)
		(end 298.671742 -98.174048)
		(stroke
			(width 0.04445)
			(type default)
		)
		(layer "In2.Cu")
	)
	(gr_line
		(start 298.671742 -98.174048)
		(end 298.69511 -98.261424)
		(stroke
			(width 0.04445)
			(type default)
		)
		(layer "In2.Cu")
	)
	(gr_line
		(start 298.866814 -98.352102)
		(end 298.94403 -98.331274)
		(stroke
			(width 0.04445)
			(type default)
		)
		(layer "In2.Cu")
	)
	(gr_line
		(start 298.94403 -98.331274)
		(end 298.9834 -98.35388)
		(stroke
			(width 0.04445)
			(type default)
		)
		(layer "In2.Cu")
	)
	(gr_line
		(start 298.9834 -98.35388)
		(end 299.0215 -98.375978)
		(stroke
			(width 0.04445)
			(type default)
		)
		(layer "In2.Cu")
	)
	(gr_line
		(start 299.0215 -98.375978)
		(end 299.237146 -98.500184)
		(stroke
			(width 0.04445)
			(type default)
		)
		(layer "In2.Cu")
	)
	(gr_line
		(start 299.215556 -76.306934)
		(end 299.258736 -76.306934)
		(stroke
			(width 0.04445)
			(type default)
		)
		(layer "In2.Cu")
	)
	(gr_line
		(start 299.215556 -67.391534)
		(end 299.248322 -67.391534)
		(stroke
			(width 0.04445)
			(type default)
		)
		(layer "In2.Cu")
	)
	(gr_line
		(start 299.22216 -76.116434)
		(end 299.252132 -76.116434)
		(stroke
			(width 0.04445)
			(type default)
		)
		(layer "In2.Cu")
	)
	(gr_line
		(start 299.22216 -67.201034)
		(end 299.254926 -67.201034)
		(stroke
			(width 0.04445)
			(type default)
		)
		(layer "In2.Cu")
	)
	(gr_line
		(start 299.237146 -97.509584)
		(end 299.530262 -97.340674)
		(stroke
			(width 0.04445)
			(type default)
		)
		(layer "In2.Cu")
	)
	(gr_line
		(start 299.237146 -96.18091)
		(end 299.237146 -96.518984)
		(stroke
			(width 0.04445)
			(type default)
		)
		(layer "In2.Cu")
	)
	(gr_line
		(start 299.237146 -96.18091)
		(end 299.257974 -96.160082)
		(stroke
			(width 0.04445)
			(type default)
		)
		(layer "In2.Cu")
	)
	(gr_line
		(start 299.237146 -95.866458)
		(end 299.257974 -95.887286)
		(stroke
			(width 0.04445)
			(type default)
		)
		(layer "In2.Cu")
	)
	(gr_line
		(start 299.237146 -95.528384)
		(end 299.237146 -95.866458)
		(stroke
			(width 0.04445)
			(type default)
		)
		(layer "In2.Cu")
	)
	(gr_line
		(start 299.259752 -96.158304)
		(end 299.295058 -96.122998)
		(stroke
			(width 0.04445)
			(type default)
		)
		(layer "In2.Cu")
	)
	(gr_line
		(start 299.259752 -95.889064)
		(end 299.302424 -95.931736)
		(stroke
			(width 0.04445)
			(type default)
		)
		(layer "In2.Cu")
	)
	(gr_line
		(start 299.530262 -97.340674)
		(end 299.617638 -97.364296)
		(stroke
			(width 0.04445)
			(type default)
		)
		(layer "In2.Cu")
	)
	(gr_line
		(start 299.781976 -97.26041)
		(end 299.80255 -97.183448)
		(stroke
			(width 0.04445)
			(type default)
		)
		(layer "In2.Cu")
	)
	(gr_line
		(start 299.80255 -97.183448)
		(end 300.095666 -97.014538)
		(stroke
			(width 0.04445)
			(type default)
		)
		(layer "In2.Cu")
	)
	(gr_line
		(start 300.074076 -75.621388)
		(end 300.106842 -75.621388)
		(stroke
			(width 0.04445)
			(type default)
		)
		(layer "In2.Cu")
	)
	(gr_line
		(start 300.08068 -75.811888)
		(end 300.113446 -75.811888)
		(stroke
			(width 0.04445)
			(type default)
		)
		(layer "In2.Cu")
	)
	(gr_line
		(start 300.095666 -96.023938)
		(end 300.388782 -96.192848)
		(stroke
			(width 0.04445)
			(type default)
		)
		(layer "In2.Cu")
	)
	(gr_line
		(start 300.095666 -93.052138)
		(end 300.388782 -92.882974)
		(stroke
			(width 0.04445)
			(type default)
		)
		(layer "In2.Cu")
	)
	(gr_line
		(start 300.095666 -91.723464)
		(end 300.095666 -92.061538)
		(stroke
			(width 0.04445)
			(type default)
		)
		(layer "In2.Cu")
	)
	(gr_line
		(start 300.095666 -91.723464)
		(end 300.116494 -91.702636)
		(stroke
			(width 0.04445)
			(type default)
		)
		(layer "In2.Cu")
	)
	(gr_line
		(start 300.095666 -91.409012)
		(end 300.116494 -91.42984)
		(stroke
			(width 0.04445)
			(type default)
		)
		(layer "In2.Cu")
	)
	(gr_line
		(start 300.095666 -91.070938)
		(end 300.095666 -91.409012)
		(stroke
			(width 0.04445)
			(type default)
		)
		(layer "In2.Cu")
	)
	(gr_line
		(start 300.095666 -67.887088)
		(end 300.113446 -67.887088)
		(stroke
			(width 0.04445)
			(type default)
		)
		(layer "In2.Cu")
	)
	(gr_line
		(start 300.095666 -67.696588)
		(end 300.106842 -67.696588)
		(stroke
			(width 0.04445)
			(type default)
		)
		(layer "In2.Cu")
	)
	(gr_line
		(start 300.118272 -91.700858)
		(end 300.153578 -91.665552)
		(stroke
			(width 0.04445)
			(type default)
		)
		(layer "In2.Cu")
	)
	(gr_line
		(start 300.118272 -91.431618)
		(end 300.16069 -91.474036)
		(stroke
			(width 0.04445)
			(type default)
		)
		(layer "In2.Cu")
	)
	(gr_line
		(start 300.36389 -102.560628)
		(end 300.45025 -102.646988)
		(stroke
			(width 0.04445)
			(type default)
		)
		(layer "In2.Cu")
	)
	(gr_line
		(start 300.388782 -96.192848)
		(end 300.476158 -96.169226)
		(stroke
			(width 0.04445)
			(type default)
		)
		(layer "In2.Cu")
	)
	(gr_line
		(start 300.388782 -92.882974)
		(end 300.476158 -92.906596)
		(stroke
			(width 0.04445)
			(type default)
		)
		(layer "In2.Cu")
	)
	(gr_line
		(start 300.45025 -102.646988)
		(end 300.72965 -102.646988)
		(stroke
			(width 0.04445)
			(type default)
		)
		(layer "In2.Cu")
	)
	(gr_line
		(start 300.55439 -102.367588)
		(end 300.62551 -102.367588)
		(stroke
			(width 0.04445)
			(type default)
		)
		(layer "In2.Cu")
	)
	(gr_line
		(start 300.640496 -96.273112)
		(end 300.66107 -96.350074)
		(stroke
			(width 0.04445)
			(type default)
		)
		(layer "In2.Cu")
	)
	(gr_line
		(start 300.640496 -92.80271)
		(end 300.66107 -92.725748)
		(stroke
			(width 0.04445)
			(type default)
		)
		(layer "In2.Cu")
	)
	(gr_line
		(start 300.66107 -96.350074)
		(end 300.954186 -96.518984)
		(stroke
			(width 0.04445)
			(type default)
		)
		(layer "In2.Cu")
	)
	(gr_line
		(start 300.66107 -92.725748)
		(end 300.954186 -92.556584)
		(stroke
			(width 0.04445)
			(type default)
		)
		(layer "In2.Cu")
	)
	(gr_line
		(start 300.72965 -102.646988)
		(end 300.81601 -102.560628)
		(stroke
			(width 0.04445)
			(type default)
		)
		(layer "In2.Cu")
	)
	(gr_line
		(start 300.936406 -75.125834)
		(end 300.969172 -75.125834)
		(stroke
			(width 0.04445)
			(type default)
		)
		(layer "In2.Cu")
	)
	(gr_line
		(start 300.936406 -67.201034)
		(end 300.971966 -67.201034)
		(stroke
			(width 0.04445)
			(type default)
		)
		(layer "In2.Cu")
	)
	(gr_line
		(start 300.94301 -75.316334)
		(end 300.975776 -75.316334)
		(stroke
			(width 0.04445)
			(type default)
		)
		(layer "In2.Cu")
	)
	(gr_line
		(start 300.954186 -95.528384)
		(end 301.247302 -95.359474)
		(stroke
			(width 0.04445)
			(type default)
		)
		(layer "In2.Cu")
	)
	(gr_line
		(start 300.954186 -94.199964)
		(end 300.954186 -94.538038)
		(stroke
			(width 0.04445)
			(type default)
		)
		(layer "In2.Cu")
	)
	(gr_line
		(start 300.954186 -94.199964)
		(end 300.975014 -94.179136)
		(stroke
			(width 0.04445)
			(type default)
		)
		(layer "In2.Cu")
	)
	(gr_line
		(start 300.954186 -93.885258)
		(end 300.975014 -93.906086)
		(stroke
			(width 0.04445)
			(type default)
		)
		(layer "In2.Cu")
	)
	(gr_line
		(start 300.954186 -93.547184)
		(end 300.954186 -93.885258)
		(stroke
			(width 0.04445)
			(type default)
		)
		(layer "In2.Cu")
	)
	(gr_line
		(start 300.976792 -94.177358)
		(end 301.012098 -94.142052)
		(stroke
			(width 0.04445)
			(type default)
		)
		(layer "In2.Cu")
	)
	(gr_line
		(start 300.976792 -93.907864)
		(end 301.019464 -93.950536)
		(stroke
			(width 0.04445)
			(type default)
		)
		(layer "In2.Cu")
	)
	(gr_line
		(start 301.10049 -102.560628)
		(end 301.18685 -102.646988)
		(stroke
			(width 0.04445)
			(type default)
		)
		(layer "In2.Cu")
	)
	(gr_arc
		(start 301.183548 -91.470988)
		(mid 301.059414 -91.495665)
		(end 300.954186 -91.565984)
		(stroke
			(width 0.04445)
			(type default)
		)
		(layer "In2.Cu")
	)
	(gr_line
		(start 301.183548 -91.470988)
		(end 301.601886 -91.470988)
		(stroke
			(width 0.04445)
			(type default)
		)
		(layer "In2.Cu")
	)
	(gr_line
		(start 301.18685 -102.646988)
		(end 301.46625 -102.646988)
		(stroke
			(width 0.04445)
			(type default)
		)
		(layer "In2.Cu")
	)
	(gr_line
		(start 301.205392 -100.878894)
		(end 301.291752 -100.792534)
		(stroke
			(width 0.04445)
			(type default)
		)
		(layer "In2.Cu")
	)
	(gr_line
		(start 301.247302 -95.359474)
		(end 301.33671 -95.383604)
		(stroke
			(width 0.04445)
			(type default)
		)
		(layer "In2.Cu")
	)
	(gr_line
		(start 301.29099 -102.367588)
		(end 301.36211 -102.367588)
		(stroke
			(width 0.04445)
			(type default)
		)
		(layer "In2.Cu")
	)
	(gr_line
		(start 301.291752 -100.792534)
		(end 301.558452 -100.792534)
		(stroke
			(width 0.04445)
			(type default)
		)
		(layer "In2.Cu")
	)
	(gr_line
		(start 301.395892 -101.071934)
		(end 301.454312 -101.071934)
		(stroke
			(width 0.04445)
			(type default)
		)
		(layer "In2.Cu")
	)
	(gr_line
		(start 301.46625 -102.646988)
		(end 301.55261 -102.560628)
		(stroke
			(width 0.04445)
			(type default)
		)
		(layer "In2.Cu")
	)
	(gr_line
		(start 301.498254 -91.81338)
		(end 301.498508 -91.813634)
		(stroke
			(width 0.04445)
			(type default)
		)
		(layer "In2.Cu")
	)
	(gr_line
		(start 301.498254 -91.81338)
		(end 301.51959 -91.892374)
		(stroke
			(width 0.04445)
			(type default)
		)
		(layer "In2.Cu")
	)
	(gr_line
		(start 301.51959 -91.892374)
		(end 301.812706 -92.061538)
		(stroke
			(width 0.04445)
			(type default)
		)
		(layer "In2.Cu")
	)
	(gr_line
		(start 301.558452 -100.792534)
		(end 301.644812 -100.878894)
		(stroke
			(width 0.04445)
			(type default)
		)
		(layer "In2.Cu")
	)
	(gr_line
		(start 301.791116 -74.630788)
		(end 301.823882 -74.630788)
		(stroke
			(width 0.04445)
			(type default)
		)
		(layer "In2.Cu")
	)
	(gr_line
		(start 301.794926 -67.887088)
		(end 301.830486 -67.887088)
		(stroke
			(width 0.04445)
			(type default)
		)
		(layer "In2.Cu")
	)
	(gr_line
		(start 301.79772 -74.821288)
		(end 301.830486 -74.821288)
		(stroke
			(width 0.04445)
			(type default)
		)
		(layer "In2.Cu")
	)
	(gr_line
		(start 301.812706 -91.070938)
		(end 302.105822 -90.901774)
		(stroke
			(width 0.04445)
			(type default)
		)
		(layer "In2.Cu")
	)
	(gr_line
		(start 301.812706 -89.742264)
		(end 301.812706 -90.080338)
		(stroke
			(width 0.04445)
			(type default)
		)
		(layer "In2.Cu")
	)
	(gr_line
		(start 301.812706 -89.742264)
		(end 301.833534 -89.721436)
		(stroke
			(width 0.04445)
			(type default)
		)
		(layer "In2.Cu")
	)
	(gr_line
		(start 301.812706 -89.427812)
		(end 301.833534 -89.44864)
		(stroke
			(width 0.04445)
			(type default)
		)
		(layer "In2.Cu")
	)
	(gr_line
		(start 301.812706 -89.089738)
		(end 301.812706 -89.427812)
		(stroke
			(width 0.04445)
			(type default)
		)
		(layer "In2.Cu")
	)
	(gr_line
		(start 301.835312 -89.719658)
		(end 301.870618 -89.684352)
		(stroke
			(width 0.04445)
			(type default)
		)
		(layer "In2.Cu")
	)
	(gr_line
		(start 301.835312 -89.450418)
		(end 301.87773 -89.492836)
		(stroke
			(width 0.04445)
			(type default)
		)
		(layer "In2.Cu")
	)
	(gr_line
		(start 301.83709 -102.560628)
		(end 301.92345 -102.646988)
		(stroke
			(width 0.04445)
			(type default)
		)
		(layer "In2.Cu")
	)
	(gr_line
		(start 301.92345 -102.646988)
		(end 302.20285 -102.646988)
		(stroke
			(width 0.04445)
			(type default)
		)
		(layer "In2.Cu")
	)
	(gr_line
		(start 301.933356 -102.984046)
		(end 301.938944 -102.986586)
		(stroke
			(width 0.04445)
			(type default)
		)
		(layer "In2.Cu")
	)
	(gr_line
		(start 302.01489 -101.7524)
		(end 302.10125 -101.83876)
		(stroke
			(width 0.04445)
			(type default)
		)
		(layer "In2.Cu")
	)
	(gr_line
		(start 302.02759 -102.367588)
		(end 302.09871 -102.367588)
		(stroke
			(width 0.04445)
			(type default)
		)
		(layer "In2.Cu")
	)
	(gr_line
		(start 302.10125 -101.83876)
		(end 302.38065 -101.83876)
		(stroke
			(width 0.04445)
			(type default)
		)
		(layer "In2.Cu")
	)
	(gr_line
		(start 302.105822 -90.901774)
		(end 302.193198 -90.925396)
		(stroke
			(width 0.04445)
			(type default)
		)
		(layer "In2.Cu")
	)
	(gr_line
		(start 302.146716 -103.278686)
		(end 302.51273 -103.430578)
		(stroke
			(width 0.04445)
			(type default)
		)
		(layer "In2.Cu")
	)
	(gr_line
		(start 302.194722 -103.08971)
		(end 302.307752 -103.042974)
		(stroke
			(width 0.04445)
			(type default)
		)
		(layer "In2.Cu")
	)
	(gr_line
		(start 302.20285 -102.646988)
		(end 302.28921 -102.560628)
		(stroke
			(width 0.04445)
			(type default)
		)
		(layer "In2.Cu")
	)
	(gr_line
		(start 302.20539 -101.55936)
		(end 302.27651 -101.55936)
		(stroke
			(width 0.04445)
			(type default)
		)
		(layer "In2.Cu")
	)
	(gr_line
		(start 302.307752 -103.042974)
		(end 302.565816 -103.149908)
		(stroke
			(width 0.04445)
			(type default)
		)
		(layer "In2.Cu")
	)
	(gr_line
		(start 302.357536 -90.82151)
		(end 302.37811 -90.744548)
		(stroke
			(width 0.04445)
			(type default)
		)
		(layer "In2.Cu")
	)
	(gr_line
		(start 302.37811 -90.744548)
		(end 302.671226 -90.575384)
		(stroke
			(width 0.04445)
			(type default)
		)
		(layer "In2.Cu")
	)
	(gr_line
		(start 302.38065 -101.83876)
		(end 302.46701 -101.7524)
		(stroke
			(width 0.04445)
			(type default)
		)
		(layer "In2.Cu")
	)
	(gr_line
		(start 302.424846 -100.878894)
		(end 302.511206 -100.792534)
		(stroke
			(width 0.04445)
			(type default)
		)
		(layer "In2.Cu")
	)
	(gr_line
		(start 302.511206 -100.792534)
		(end 302.790606 -100.792534)
		(stroke
			(width 0.04445)
			(type default)
		)
		(layer "In2.Cu")
	)
	(gr_line
		(start 302.565816 -103.149908)
		(end 302.612552 -103.262938)
		(stroke
			(width 0.04445)
			(type default)
		)
		(layer "In2.Cu")
	)
	(gr_line
		(start 302.57369 -102.560628)
		(end 302.66005 -102.646988)
		(stroke
			(width 0.04445)
			(type default)
		)
		(layer "In2.Cu")
	)
	(gr_line
		(start 302.615346 -101.071934)
		(end 302.686466 -101.071934)
		(stroke
			(width 0.04445)
			(type default)
		)
		(layer "In2.Cu")
	)
	(gr_line
		(start 302.653446 -74.135234)
		(end 302.686212 -74.135234)
		(stroke
			(width 0.04445)
			(type default)
		)
		(layer "In2.Cu")
	)
	(gr_line
		(start 302.653446 -67.201034)
		(end 302.689006 -67.201034)
		(stroke
			(width 0.04445)
			(type default)
		)
		(layer "In2.Cu")
	)
	(gr_line
		(start 302.65624 -93.947234)
		(end 302.686212 -93.947234)
		(stroke
			(width 0.04445)
			(type default)
		)
		(layer "In2.Cu")
	)
	(gr_line
		(start 302.66005 -102.646988)
		(end 302.93945 -102.646988)
		(stroke
			(width 0.04445)
			(type default)
		)
		(layer "In2.Cu")
	)
	(gr_line
		(start 302.66005 -74.325734)
		(end 302.692816 -74.325734)
		(stroke
			(width 0.04445)
			(type default)
		)
		(layer "In2.Cu")
	)
	(gr_line
		(start 302.75149 -101.7524)
		(end 302.83785 -101.83876)
		(stroke
			(width 0.04445)
			(type default)
		)
		(layer "In2.Cu")
	)
	(gr_line
		(start 302.76419 -102.367588)
		(end 302.83531 -102.367588)
		(stroke
			(width 0.04445)
			(type default)
		)
		(layer "In2.Cu")
	)
	(gr_line
		(start 302.790606 -100.792534)
		(end 302.876966 -100.878894)
		(stroke
			(width 0.04445)
			(type default)
		)
		(layer "In2.Cu")
	)
	(gr_line
		(start 302.83785 -101.83876)
		(end 303.11725 -101.83876)
		(stroke
			(width 0.04445)
			(type default)
		)
		(layer "In2.Cu")
	)
	(gr_line
		(start 302.93945 -102.646988)
		(end 303.02581 -102.560628)
		(stroke
			(width 0.04445)
			(type default)
		)
		(layer "In2.Cu")
	)
	(gr_line
		(start 302.94199 -101.55936)
		(end 303.01311 -101.55936)
		(stroke
			(width 0.04445)
			(type default)
		)
		(layer "In2.Cu")
	)
	(gr_line
		(start 302.966628 -98.61804)
		(end 303.052988 -98.53168)
		(stroke
			(width 0.04445)
			(type default)
		)
		(layer "In2.Cu")
	)
	(gr_line
		(start 303.052988 -98.53168)
		(end 303.332388 -98.53168)
		(stroke
			(width 0.04445)
			(type default)
		)
		(layer "In2.Cu")
	)
	(gr_line
		(start 303.11725 -101.83876)
		(end 303.20361 -101.7524)
		(stroke
			(width 0.04445)
			(type default)
		)
		(layer "In2.Cu")
	)
	(gr_line
		(start 303.157128 -98.81108)
		(end 303.228248 -98.81108)
		(stroke
			(width 0.04445)
			(type default)
		)
		(layer "In2.Cu")
	)
	(gr_line
		(start 303.227232 -103.52024)
		(end 303.233836 -103.523034)
		(stroke
			(width 0.04445)
			(type default)
		)
		(layer "In2.Cu")
	)
	(gr_line
		(start 303.275492 -99.835208)
		(end 303.361852 -99.748848)
		(stroke
			(width 0.04445)
			(type default)
		)
		(layer "In2.Cu")
	)
	(gr_line
		(start 303.29759 -102.560628)
		(end 303.38395 -102.646988)
		(stroke
			(width 0.04445)
			(type default)
		)
		(layer "In2.Cu")
	)
	(gr_line
		(start 303.332388 -98.53168)
		(end 303.418748 -98.61804)
		(stroke
			(width 0.04445)
			(type default)
		)
		(layer "In2.Cu")
	)
	(gr_line
		(start 303.361852 -99.748848)
		(end 303.641252 -99.748848)
		(stroke
			(width 0.04445)
			(type default)
		)
		(layer "In2.Cu")
	)
	(gr_line
		(start 303.38395 -102.646988)
		(end 303.65065 -102.646988)
		(stroke
			(width 0.04445)
			(type default)
		)
		(layer "In2.Cu")
	)
	(gr_line
		(start 303.465992 -100.028248)
		(end 303.537112 -100.028248)
		(stroke
			(width 0.04445)
			(type default)
		)
		(layer "In2.Cu")
	)
	(gr_line
		(start 303.48809 -102.367588)
		(end 303.54651 -102.367588)
		(stroke
			(width 0.04445)
			(type default)
		)
		(layer "In2.Cu")
	)
	(gr_line
		(start 303.508156 -73.640188)
		(end 303.540922 -73.640188)
		(stroke
			(width 0.04445)
			(type default)
		)
		(layer "In2.Cu")
	)
	(gr_line
		(start 303.511966 -67.887088)
		(end 303.547526 -67.887088)
		(stroke
			(width 0.04445)
			(type default)
		)
		(layer "In2.Cu")
	)
	(gr_line
		(start 303.51476 -95.623888)
		(end 303.544732 -95.623888)
		(stroke
			(width 0.04445)
			(type default)
		)
		(layer "In2.Cu")
	)
	(gr_line
		(start 303.51476 -73.830688)
		(end 303.547526 -73.830688)
		(stroke
			(width 0.04445)
			(type default)
		)
		(layer "In2.Cu")
	)
	(gr_line
		(start 303.641252 -99.748848)
		(end 303.727612 -99.835208)
		(stroke
			(width 0.04445)
			(type default)
		)
		(layer "In2.Cu")
	)
	(gr_line
		(start 303.65065 -102.646988)
		(end 303.73701 -102.560628)
		(stroke
			(width 0.04445)
			(type default)
		)
		(layer "In2.Cu")
	)
	(gr_line
		(start 303.703228 -98.61804)
		(end 303.789588 -98.53168)
		(stroke
			(width 0.04445)
			(type default)
		)
		(layer "In2.Cu")
	)
	(gr_line
		(start 303.789588 -98.53168)
		(end 304.068988 -98.53168)
		(stroke
			(width 0.04445)
			(type default)
		)
		(layer "In2.Cu")
	)
	(gr_line
		(start 303.893728 -98.81108)
		(end 303.964848 -98.81108)
		(stroke
			(width 0.04445)
			(type default)
		)
		(layer "In2.Cu")
	)
	(gr_line
		(start 304.012092 -99.835208)
		(end 304.098452 -99.748848)
		(stroke
			(width 0.04445)
			(type default)
		)
		(layer "In2.Cu")
	)
	(gr_line
		(start 304.068988 -98.53168)
		(end 304.155348 -98.61804)
		(stroke
			(width 0.04445)
			(type default)
		)
		(layer "In2.Cu")
	)
	(gr_line
		(start 304.098452 -99.748848)
		(end 304.377852 -99.748848)
		(stroke
			(width 0.04445)
			(type default)
		)
		(layer "In2.Cu")
	)
	(gr_line
		(start 304.128424 -98.124264)
		(end 304.16246 -98.1583)
		(stroke
			(width 0.04445)
			(type default)
		)
		(layer "In2.Cu")
	)
	(gr_line
		(start 304.134774 -93.581728)
		(end 304.141632 -93.583506)
		(stroke
			(width 0.04445)
			(type default)
		)
		(layer "In2.Cu")
	)
	(gr_line
		(start 304.141632 -93.583506)
		(end 304.147474 -93.587824)
		(stroke
			(width 0.04445)
			(type default)
		)
		(layer "In2.Cu")
	)
	(gr_line
		(start 304.202592 -100.028248)
		(end 304.273712 -100.028248)
		(stroke
			(width 0.04445)
			(type default)
		)
		(layer "In2.Cu")
	)
	(gr_line
		(start 304.207672 -93.86951)
		(end 304.23358 -93.88856)
		(stroke
			(width 0.04445)
			(type default)
		)
		(layer "In2.Cu")
	)
	(gr_line
		(start 304.339498 -104.08666)
		(end 304.425858 -104.0003)
		(stroke
			(width 0.04445)
			(type default)
		)
		(layer "In2.Cu")
	)
	(gr_line
		(start 304.366676 -97.109534)
		(end 304.399442 -97.109534)
		(stroke
			(width 0.04445)
			(type default)
		)
		(layer "In2.Cu")
	)
	(gr_line
		(start 304.370486 -73.144634)
		(end 304.406046 -73.144634)
		(stroke
			(width 0.04445)
			(type default)
		)
		(layer "In2.Cu")
	)
	(gr_line
		(start 304.370486 -67.201034)
		(end 304.406046 -67.201034)
		(stroke
			(width 0.04445)
			(type default)
		)
		(layer "In2.Cu")
	)
	(gr_line
		(start 304.377852 -99.748848)
		(end 304.464212 -99.835208)
		(stroke
			(width 0.04445)
			(type default)
		)
		(layer "In2.Cu")
	)
	(gr_line
		(start 304.388266 -74.38771)
		(end 304.388266 -74.725784)
		(stroke
			(width 0.04445)
			(type default)
		)
		(layer "In2.Cu")
	)
	(gr_line
		(start 304.388266 -74.38771)
		(end 304.409094 -74.366882)
		(stroke
			(width 0.04445)
			(type default)
		)
		(layer "In2.Cu")
	)
	(gr_line
		(start 304.388266 -74.073258)
		(end 304.409094 -74.094086)
		(stroke
			(width 0.04445)
			(type default)
		)
		(layer "In2.Cu")
	)
	(gr_line
		(start 304.388266 -73.735184)
		(end 304.388266 -74.073258)
		(stroke
			(width 0.04445)
			(type default)
		)
		(layer "In2.Cu")
	)
	(gr_line
		(start 304.410872 -74.365104)
		(end 304.446178 -74.329798)
		(stroke
			(width 0.04445)
			(type default)
		)
		(layer "In2.Cu")
	)
	(gr_line
		(start 304.410872 -74.095864)
		(end 304.453544 -74.138536)
		(stroke
			(width 0.04445)
			(type default)
		)
		(layer "In2.Cu")
	)
	(gr_line
		(start 304.425858 -104.0003)
		(end 304.692558 -104.0003)
		(stroke
			(width 0.04445)
			(type default)
		)
		(layer "In2.Cu")
	)
	(gr_line
		(start 304.495962 -96.928686)
		(end 304.589942 -96.928686)
		(stroke
			(width 0.04445)
			(type default)
		)
		(layer "In2.Cu")
	)
	(gr_line
		(start 304.521362 -102.367588)
		(end 304.52695 -102.370128)
		(stroke
			(width 0.04445)
			(type default)
		)
		(layer "In2.Cu")
	)
	(gr_line
		(start 304.529998 -104.2797)
		(end 304.588418 -104.2797)
		(stroke
			(width 0.04445)
			(type default)
		)
		(layer "In2.Cu")
	)
	(gr_line
		(start 304.639726 -93.69552)
		(end 304.726086 -93.60916)
		(stroke
			(width 0.04445)
			(type default)
		)
		(layer "In2.Cu")
	)
	(gr_line
		(start 304.692558 -104.0003)
		(end 304.778918 -104.08666)
		(stroke
			(width 0.04445)
			(type default)
		)
		(layer "In2.Cu")
	)
	(gr_line
		(start 304.726086 -93.60916)
		(end 305.005486 -93.60916)
		(stroke
			(width 0.04445)
			(type default)
		)
		(layer "In2.Cu")
	)
	(gr_arc
		(start 304.748438 -90.75293)
		(mid 304.741982 -90.763407)
		(end 304.735738 -90.774012)
		(stroke
			(width 0.04445)
			(type default)
		)
		(layer "In2.Cu")
	)
	(gr_line
		(start 304.7746 -93.147134)
		(end 304.81397 -93.186504)
		(stroke
			(width 0.04445)
			(type default)
		)
		(layer "In2.Cu")
	)
	(gr_line
		(start 304.7746 -92.956634)
		(end 304.81397 -92.917264)
		(stroke
			(width 0.04445)
			(type default)
		)
		(layer "In2.Cu")
	)
	(gr_line
		(start 304.815748 -102.489508)
		(end 304.822352 -102.492302)
		(stroke
			(width 0.04445)
			(type default)
		)
		(layer "In2.Cu")
	)
	(gr_line
		(start 304.815748 -93.188282)
		(end 304.8254 -93.197934)
		(stroke
			(width 0.04445)
			(type default)
		)
		(layer "In2.Cu")
	)
	(gr_line
		(start 304.815748 -92.915486)
		(end 304.8254 -92.905834)
		(stroke
			(width 0.04445)
			(type default)
		)
		(layer "In2.Cu")
	)
	(gr_line
		(start 304.8254 -93.197934)
		(end 304.847498 -93.197934)
		(stroke
			(width 0.04445)
			(type default)
		)
		(layer "In2.Cu")
	)
	(gr_line
		(start 304.8254 -92.905834)
		(end 304.847498 -92.905834)
		(stroke
			(width 0.04445)
			(type default)
		)
		(layer "In2.Cu")
	)
	(gr_line
		(start 304.830226 -93.88856)
		(end 304.901346 -93.88856)
		(stroke
			(width 0.04445)
			(type default)
		)
		(layer "In2.Cu")
	)
	(gr_line
		(start 305.005486 -93.60916)
		(end 305.091846 -93.69552)
		(stroke
			(width 0.04445)
			(type default)
		)
		(layer "In2.Cu")
	)
	(gr_line
		(start 305.050698 -104.08666)
		(end 305.137058 -104.0003)
		(stroke
			(width 0.04445)
			(type default)
		)
		(layer "In2.Cu")
	)
	(gr_line
		(start 305.07051 -93.197934)
		(end 305.129438 -93.139006)
		(stroke
			(width 0.05715)
			(type default)
		)
		(layer "In2.Cu")
	)
	(gr_line
		(start 305.137058 -104.0003)
		(end 305.403758 -104.0003)
		(stroke
			(width 0.04445)
			(type default)
		)
		(layer "In2.Cu")
	)
	(gr_line
		(start 305.229006 -73.830688)
		(end 305.413664 -73.830688)
		(stroke
			(width 0.04445)
			(type default)
		)
		(layer "In2.Cu")
	)
	(gr_line
		(start 305.229006 -67.887088)
		(end 305.246786 -67.887088)
		(stroke
			(width 0.04445)
			(type default)
		)
		(layer "In2.Cu")
	)
	(gr_line
		(start 305.23561 -73.640188)
		(end 305.449986 -73.640188)
		(stroke
			(width 0.04445)
			(type default)
		)
		(layer "In2.Cu")
	)
	(gr_line
		(start 305.241198 -104.2797)
		(end 305.299618 -104.2797)
		(stroke
			(width 0.04445)
			(type default)
		)
		(layer "In2.Cu")
	)
	(gr_line
		(start 305.261264 -100.06838)
		(end 305.347624 -99.98202)
		(stroke
			(width 0.04445)
			(type default)
		)
		(layer "In2.Cu")
	)
	(gr_line
		(start 305.347624 -99.98202)
		(end 305.627024 -99.98202)
		(stroke
			(width 0.04445)
			(type default)
		)
		(layer "In2.Cu")
	)
	(gr_line
		(start 305.361594 -96.54286)
		(end 305.402996 -96.501458)
		(stroke
			(width 0.04445)
			(type default)
		)
		(layer "In2.Cu")
	)
	(gr_line
		(start 305.363372 -96.814132)
		(end 305.485546 -96.814132)
		(stroke
			(width 0.04445)
			(type default)
		)
		(layer "In2.Cu")
	)
	(gr_line
		(start 305.3969 -89.789)
		(end 305.43627 -89.82837)
		(stroke
			(width 0.04445)
			(type default)
		)
		(layer "In2.Cu")
	)
	(gr_line
		(start 305.3969 -89.5985)
		(end 305.43627 -89.55913)
		(stroke
			(width 0.04445)
			(type default)
		)
		(layer "In2.Cu")
	)
	(gr_line
		(start 305.403758 -104.0003)
		(end 305.490118 -104.08666)
		(stroke
			(width 0.04445)
			(type default)
		)
		(layer "In2.Cu")
	)
	(gr_line
		(start 305.438048 -89.830148)
		(end 305.4477 -89.8398)
		(stroke
			(width 0.04445)
			(type default)
		)
		(layer "In2.Cu")
	)
	(gr_line
		(start 305.438048 -89.557352)
		(end 305.4477 -89.5477)
		(stroke
			(width 0.04445)
			(type default)
		)
		(layer "In2.Cu")
	)
	(gr_line
		(start 305.4477 -89.8398)
		(end 305.469798 -89.8398)
		(stroke
			(width 0.04445)
			(type default)
		)
		(layer "In2.Cu")
	)
	(gr_line
		(start 305.4477 -89.5477)
		(end 305.469798 -89.5477)
		(stroke
			(width 0.04445)
			(type default)
		)
		(layer "In2.Cu")
	)
	(gr_line
		(start 305.451764 -100.26142)
		(end 305.522884 -100.26142)
		(stroke
			(width 0.04445)
			(type default)
		)
		(layer "In2.Cu")
	)
	(gr_line
		(start 305.462686 -75.282044)
		(end 305.496722 -75.31608)
		(stroke
			(width 0.04445)
			(type default)
		)
		(layer "In2.Cu")
	)
	(gr_line
		(start 305.485546 -96.814132)
		(end 305.674268 -96.62541)
		(stroke
			(width 0.04445)
			(type default)
		)
		(layer "In2.Cu")
	)
	(gr_line
		(start 305.528726 -90.21826)
		(end 305.615086 -90.1319)
		(stroke
			(width 0.04445)
			(type default)
		)
		(layer "In2.Cu")
	)
	(gr_line
		(start 305.597052 -93.349064)
		(end 305.597052 -93.471238)
		(stroke
			(width 0.04445)
			(type default)
		)
		(layer "In2.Cu")
	)
	(gr_line
		(start 305.597052 -93.349064)
		(end 305.794664 -93.151452)
		(stroke
			(width 0.04445)
			(type default)
		)
		(layer "In2.Cu")
	)
	(gr_line
		(start 305.615086 -90.1319)
		(end 305.881786 -90.1319)
		(stroke
			(width 0.04445)
			(type default)
		)
		(layer "In2.Cu")
	)
	(gr_line
		(start 305.627024 -99.98202)
		(end 305.713384 -100.06838)
		(stroke
			(width 0.04445)
			(type default)
		)
		(layer "In2.Cu")
	)
	(gr_line
		(start 305.674268 -96.503236)
		(end 305.674268 -96.62541)
		(stroke
			(width 0.04445)
			(type default)
		)
		(layer "In2.Cu")
	)
	(gr_line
		(start 305.719226 -90.4113)
		(end 305.777646 -90.4113)
		(stroke
			(width 0.04445)
			(type default)
		)
		(layer "In2.Cu")
	)
	(gr_line
		(start 305.761898 -104.08666)
		(end 305.848258 -104.0003)
		(stroke
			(width 0.04445)
			(type default)
		)
		(layer "In2.Cu")
	)
	(gr_line
		(start 305.794664 -93.151452)
		(end 305.916838 -93.151452)
		(stroke
			(width 0.04445)
			(type default)
		)
		(layer "In2.Cu")
	)
	(gr_line
		(start 305.848258 -104.0003)
		(end 306.114958 -104.0003)
		(stroke
			(width 0.04445)
			(type default)
		)
		(layer "In2.Cu")
	)
	(gr_line
		(start 305.850036 -90.97645)
		(end 305.884072 -90.942414)
		(stroke
			(width 0.04445)
			(type default)
		)
		(layer "In2.Cu")
	)
	(gr_line
		(start 305.863498 -91.991434)
		(end 305.947318 -91.99118)
		(stroke
			(width 0.05715)
			(type default)
		)
		(layer "In2.Cu")
	)
	(gr_line
		(start 305.864514 -96.03994)
		(end 305.905916 -95.998538)
		(stroke
			(width 0.04445)
			(type default)
		)
		(layer "In2.Cu")
	)
	(gr_line
		(start 305.866292 -96.311212)
		(end 305.988466 -96.311212)
		(stroke
			(width 0.04445)
			(type default)
		)
		(layer "In2.Cu")
	)
	(gr_line
		(start 305.868324 -93.473016)
		(end 305.918616 -93.422724)
		(stroke
			(width 0.04445)
			(type default)
		)
		(layer "In2.Cu")
	)
	(gr_line
		(start 305.881786 -90.1319)
		(end 305.968146 -90.21826)
		(stroke
			(width 0.04445)
			(type default)
		)
		(layer "In2.Cu")
	)
	(gr_line
		(start 305.92903 -102.035864)
		(end 305.9684 -102.075234)
		(stroke
			(width 0.04445)
			(type default)
		)
		(layer "In2.Cu")
	)
	(gr_line
		(start 305.92903 -101.845364)
		(end 305.9684 -101.805994)
		(stroke
			(width 0.04445)
			(type default)
		)
		(layer "In2.Cu")
	)
	(gr_line
		(start 305.952398 -104.2797)
		(end 306.010818 -104.2797)
		(stroke
			(width 0.04445)
			(type default)
		)
		(layer "In2.Cu")
	)
	(gr_line
		(start 305.970178 -102.077012)
		(end 305.97983 -102.086664)
		(stroke
			(width 0.04445)
			(type default)
		)
		(layer "In2.Cu")
	)
	(gr_line
		(start 305.970178 -101.804216)
		(end 305.97983 -101.794564)
		(stroke
			(width 0.04445)
			(type default)
		)
		(layer "In2.Cu")
	)
	(gr_line
		(start 305.978306 -74.325734)
		(end 307.234336 -74.325734)
		(stroke
			(width 0.04445)
			(type default)
		)
		(layer "In2.Cu")
	)
	(gr_line
		(start 305.97983 -102.086664)
		(end 306.001928 -102.086664)
		(stroke
			(width 0.04445)
			(type default)
		)
		(layer "In2.Cu")
	)
	(gr_line
		(start 305.97983 -101.794564)
		(end 306.001928 -101.794564)
		(stroke
			(width 0.04445)
			(type default)
		)
		(layer "In2.Cu")
	)
	(gr_line
		(start 305.988466 -96.311212)
		(end 306.177188 -96.12249)
		(stroke
			(width 0.04445)
			(type default)
		)
		(layer "In2.Cu")
	)
	(gr_line
		(start 306.014628 -74.135234)
		(end 307.257196 -74.135234)
		(stroke
			(width 0.04445)
			(type default)
		)
		(layer "In2.Cu")
	)
	(gr_line
		(start 306.072286 -101.071934)
		(end 306.111656 -101.111304)
		(stroke
			(width 0.04445)
			(type default)
		)
		(layer "In2.Cu")
	)
	(gr_line
		(start 306.072286 -100.881434)
		(end 306.111656 -100.842064)
		(stroke
			(width 0.04445)
			(type default)
		)
		(layer "In2.Cu")
	)
	(gr_line
		(start 306.087526 -67.201034)
		(end 306.120292 -67.201034)
		(stroke
			(width 0.04445)
			(type default)
		)
		(layer "In2.Cu")
	)
	(gr_line
		(start 306.09413 -67.391534)
		(end 306.126896 -67.391534)
		(stroke
			(width 0.04445)
			(type default)
		)
		(layer "In2.Cu")
	)
	(gr_line
		(start 306.113434 -101.113082)
		(end 306.123086 -101.122734)
		(stroke
			(width 0.04445)
			(type default)
		)
		(layer "In2.Cu")
	)
	(gr_line
		(start 306.113434 -100.840286)
		(end 306.123086 -100.830634)
		(stroke
			(width 0.04445)
			(type default)
		)
		(layer "In2.Cu")
	)
	(gr_line
		(start 306.114958 -104.0003)
		(end 306.201318 -104.08666)
		(stroke
			(width 0.04445)
			(type default)
		)
		(layer "In2.Cu")
	)
	(gr_line
		(start 306.123086 -101.122734)
		(end 306.145184 -101.122734)
		(stroke
			(width 0.04445)
			(type default)
		)
		(layer "In2.Cu")
	)
	(gr_line
		(start 306.123086 -100.830634)
		(end 306.145184 -100.830634)
		(stroke
			(width 0.04445)
			(type default)
		)
		(layer "In2.Cu")
	)
	(gr_line
		(start 306.145438 -89.8398)
		(end 306.179982 -89.819988)
		(stroke
			(width 0.05715)
			(type default)
		)
		(layer "In2.Cu")
	)
	(gr_line
		(start 306.177188 -96.000316)
		(end 306.177188 -96.12249)
		(stroke
			(width 0.04445)
			(type default)
		)
		(layer "In2.Cu")
	)
	(gr_line
		(start 306.199794 -103.24465)
		(end 306.239164 -103.28402)
		(stroke
			(width 0.04445)
			(type default)
		)
		(layer "In2.Cu")
	)
	(gr_line
		(start 306.199794 -103.05415)
		(end 306.239164 -103.01478)
		(stroke
			(width 0.04445)
			(type default)
		)
		(layer "In2.Cu")
	)
	(gr_line
		(start 306.239926 -90.21826)
		(end 306.326286 -90.1319)
		(stroke
			(width 0.04445)
			(type default)
		)
		(layer "In2.Cu")
	)
	(gr_line
		(start 306.240942 -103.285798)
		(end 306.250594 -103.29545)
		(stroke
			(width 0.04445)
			(type default)
		)
		(layer "In2.Cu")
	)
	(gr_line
		(start 306.240942 -103.013002)
		(end 306.250594 -103.00335)
		(stroke
			(width 0.04445)
			(type default)
		)
		(layer "In2.Cu")
	)
	(gr_line
		(start 306.250594 -103.29545)
		(end 306.272692 -103.29545)
		(stroke
			(width 0.04445)
			(type default)
		)
		(layer "In2.Cu")
	)
	(gr_line
		(start 306.250594 -103.00335)
		(end 306.272692 -103.00335)
		(stroke
			(width 0.04445)
			(type default)
		)
		(layer "In2.Cu")
	)
	(gr_line
		(start 306.262786 -99.734624)
		(end 306.262786 -99.856798)
		(stroke
			(width 0.04445)
			(type default)
		)
		(layer "In2.Cu")
	)
	(gr_line
		(start 306.262786 -99.734624)
		(end 306.460398 -99.537012)
		(stroke
			(width 0.04445)
			(type default)
		)
		(layer "In2.Cu")
	)
	(gr_line
		(start 306.326286 -90.1319)
		(end 306.592986 -90.1319)
		(stroke
			(width 0.04445)
			(type default)
		)
		(layer "In2.Cu")
	)
	(gr_line
		(start 306.430426 -90.4113)
		(end 306.488846 -90.4113)
		(stroke
			(width 0.04445)
			(type default)
		)
		(layer "In2.Cu")
	)
	(gr_line
		(start 306.460398 -99.537012)
		(end 306.582572 -99.537012)
		(stroke
			(width 0.04445)
			(type default)
		)
		(layer "In2.Cu")
	)
	(gr_line
		(start 306.534058 -99.858576)
		(end 306.58435 -99.808284)
		(stroke
			(width 0.04445)
			(type default)
		)
		(layer "In2.Cu")
	)
	(gr_line
		(start 306.545996 -66.878708)
		(end 306.610258 -66.792856)
		(stroke
			(width 0.04445)
			(type default)
		)
		(layer "In2.Cu")
	)
	(gr_line
		(start 306.592986 -90.1319)
		(end 306.679346 -90.21826)
		(stroke
			(width 0.04445)
			(type default)
		)
		(layer "In2.Cu")
	)
	(gr_line
		(start 306.626768 -92.895166)
		(end 306.666138 -92.934536)
		(stroke
			(width 0.04445)
			(type default)
		)
		(layer "In2.Cu")
	)
	(gr_line
		(start 306.626768 -92.704666)
		(end 306.666138 -92.665296)
		(stroke
			(width 0.04445)
			(type default)
		)
		(layer "In2.Cu")
	)
	(gr_line
		(start 306.667916 -92.936314)
		(end 306.677568 -92.945966)
		(stroke
			(width 0.04445)
			(type default)
		)
		(layer "In2.Cu")
	)
	(gr_line
		(start 306.667916 -92.663518)
		(end 306.677568 -92.653866)
		(stroke
			(width 0.04445)
			(type default)
		)
		(layer "In2.Cu")
	)
	(gr_line
		(start 306.677568 -92.945966)
		(end 306.699666 -92.945966)
		(stroke
			(width 0.04445)
			(type default)
		)
		(layer "In2.Cu")
	)
	(gr_line
		(start 306.677568 -92.653866)
		(end 306.699666 -92.653866)
		(stroke
			(width 0.04445)
			(type default)
		)
		(layer "In2.Cu")
	)
	(gr_line
		(start 306.68087 -67.013582)
		(end 306.76723 -66.93916)
		(stroke
			(width 0.04445)
			(type default)
		)
		(layer "In2.Cu")
	)
	(gr_line
		(start 306.823872 -66.474848)
		(end 306.827428 -66.49847)
		(stroke
			(width 0.04445)
			(type default)
		)
		(layer "In2.Cu")
	)
	(gr_line
		(start 306.823872 -66.474848)
		(end 306.83708 -66.457068)
		(stroke
			(width 0.04445)
			(type default)
		)
		(layer "In2.Cu")
	)
	(gr_line
		(start 306.847748 -91.45524)
		(end 306.934108 -91.5416)
		(stroke
			(width 0.04445)
			(type default)
		)
		(layer "In2.Cu")
	)
	(gr_line
		(start 306.909724 -104.0892)
		(end 306.93233 -104.104186)
		(stroke
			(width 0.04445)
			(type default)
		)
		(layer "In2.Cu")
	)
	(gr_line
		(start 306.934108 -91.5416)
		(end 307.200808 -91.5416)
		(stroke
			(width 0.04445)
			(type default)
		)
		(layer "In2.Cu")
	)
	(gr_line
		(start 307.00472 -66.630042)
		(end 307.027326 -66.626994)
		(stroke
			(width 0.04445)
			(type default)
		)
		(layer "In2.Cu")
	)
	(gr_line
		(start 307.027326 -66.626994)
		(end 307.040534 -66.609214)
		(stroke
			(width 0.04445)
			(type default)
		)
		(layer "In2.Cu")
	)
	(gr_line
		(start 307.038248 -91.2622)
		(end 307.096668 -91.2622)
		(stroke
			(width 0.04445)
			(type default)
		)
		(layer "In2.Cu")
	)
	(gr_line
		(start 307.051202 -104.412796)
		(end 307.368956 -104.624632)
		(stroke
			(width 0.04445)
			(type default)
		)
		(layer "In2.Cu")
	)
	(gr_line
		(start 307.06568 -99.33686)
		(end 307.15204 -99.2505)
		(stroke
			(width 0.04445)
			(type default)
		)
		(layer "In2.Cu")
	)
	(gr_line
		(start 307.134768 -104.236266)
		(end 307.254402 -104.21239)
		(stroke
			(width 0.04445)
			(type default)
		)
		(layer "In2.Cu")
	)
	(gr_line
		(start 307.15204 -99.2505)
		(end 307.43144 -99.2505)
		(stroke
			(width 0.04445)
			(type default)
		)
		(layer "In2.Cu")
	)
	(gr_line
		(start 307.170836 -98.76282)
		(end 307.210206 -98.80219)
		(stroke
			(width 0.04445)
			(type default)
		)
		(layer "In2.Cu")
	)
	(gr_line
		(start 307.170836 -98.57232)
		(end 307.210206 -98.53295)
		(stroke
			(width 0.04445)
			(type default)
		)
		(layer "In2.Cu")
	)
	(gr_line
		(start 307.182012 -90.4113)
		(end 307.185822 -90.409776)
		(stroke
			(width 0.04445)
			(type default)
		)
		(layer "In2.Cu")
	)
	(gr_line
		(start 307.200808 -91.5416)
		(end 307.287168 -91.45524)
		(stroke
			(width 0.04445)
			(type default)
		)
		(layer "In2.Cu")
	)
	(gr_line
		(start 307.211984 -98.803968)
		(end 307.221636 -98.81362)
		(stroke
			(width 0.04445)
			(type default)
		)
		(layer "In2.Cu")
	)
	(gr_line
		(start 307.211984 -98.531172)
		(end 307.221636 -98.52152)
		(stroke
			(width 0.04445)
			(type default)
		)
		(layer "In2.Cu")
	)
	(gr_line
		(start 307.221636 -98.52152)
		(end 307.243734 -98.52152)
		(stroke
			(width 0.04445)
			(type default)
		)
		(layer "In2.Cu")
	)
	(gr_line
		(start 307.234336 -74.325734)
		(end 307.277516 -74.368914)
		(stroke
			(width 0.04445)
			(type default)
		)
		(layer "In2.Cu")
	)
	(gr_line
		(start 307.254402 -104.21239)
		(end 307.476398 -104.360472)
		(stroke
			(width 0.04445)
			(type default)
		)
		(layer "In2.Cu")
	)
	(gr_line
		(start 307.25618 -99.5299)
		(end 307.3273 -99.5299)
		(stroke
			(width 0.04445)
			(type default)
		)
		(layer "In2.Cu")
	)
	(gr_line
		(start 307.257196 -74.135234)
		(end 307.277516 -74.114914)
		(stroke
			(width 0.04445)
			(type default)
		)
		(layer "In2.Cu")
	)
	(gr_line
		(start 307.277516 -74.114914)
		(end 307.466746 -74.114914)
		(stroke
			(width 0.0635)
			(type default)
		)
		(layer "In2.Cu")
	)
	(gr_line
		(start 307.299614 -96.59366)
		(end 307.338984 -96.63303)
		(stroke
			(width 0.04445)
			(type default)
		)
		(layer "In2.Cu")
	)
	(gr_line
		(start 307.299614 -96.40316)
		(end 307.338984 -96.36379)
		(stroke
			(width 0.04445)
			(type default)
		)
		(layer "In2.Cu")
	)
	(gr_line
		(start 307.305964 -75.31608)
		(end 307.493416 -75.31608)
		(stroke
			(width 0.04445)
			(type default)
		)
		(layer "In2.Cu")
	)
	(gr_line
		(start 307.30698 -100.830634)
		(end 307.352446 -100.863146)
		(stroke
			(width 0.05715)
			(type default)
		)
		(layer "In2.Cu")
	)
	(gr_line
		(start 307.326538 -101.794564)
		(end 307.372004 -101.827076)
		(stroke
			(width 0.05715)
			(type default)
		)
		(layer "In2.Cu")
	)
	(gr_line
		(start 307.340762 -96.634808)
		(end 307.350414 -96.64446)
		(stroke
			(width 0.04445)
			(type default)
		)
		(layer "In2.Cu")
	)
	(gr_line
		(start 307.340762 -96.362012)
		(end 307.350414 -96.35236)
		(stroke
			(width 0.04445)
			(type default)
		)
		(layer "In2.Cu")
	)
	(gr_line
		(start 307.350414 -96.64446)
		(end 307.372512 -96.64446)
		(stroke
			(width 0.04445)
			(type default)
		)
		(layer "In2.Cu")
	)
	(gr_line
		(start 307.350414 -96.35236)
		(end 307.372512 -96.35236)
		(stroke
			(width 0.04445)
			(type default)
		)
		(layer "In2.Cu")
	)
	(gr_line
		(start 307.352446 -103.00335)
		(end 307.397912 -103.035862)
		(stroke
			(width 0.05715)
			(type default)
		)
		(layer "In2.Cu")
	)
	(gr_line
		(start 307.43144 -99.2505)
		(end 307.5178 -99.33686)
		(stroke
			(width 0.04445)
			(type default)
		)
		(layer "In2.Cu")
	)
	(gr_line
		(start 307.476398 -104.360472)
		(end 307.500274 -104.48036)
		(stroke
			(width 0.04445)
			(type default)
		)
		(layer "In2.Cu")
	)
	(gr_line
		(start 307.493416 -75.31608)
		(end 307.515514 -75.338178)
		(stroke
			(width 0.04445)
			(type default)
		)
		(layer "In2.Cu")
	)
	(gr_line
		(start 307.499512 -75.12558)
		(end 307.515514 -75.109578)
		(stroke
			(width 0.04445)
			(type default)
		)
		(layer "In2.Cu")
	)
	(gr_line
		(start 307.504084 -88.724232)
		(end 307.510434 -88.720676)
		(stroke
			(width 0.05715)
			(type default)
		)
		(layer "In2.Cu")
	)
	(gr_line
		(start 307.510434 -88.720676)
		(end 307.517292 -88.719152)
		(stroke
			(width 0.05715)
			(type default)
		)
		(layer "In2.Cu")
	)
	(gr_line
		(start 307.515514 -75.109578)
		(end 307.702966 -75.109578)
		(stroke
			(width 0.0635)
			(type default)
		)
		(layer "In2.Cu")
	)
	(gr_line
		(start 307.565298 -95.685356)
		(end 307.604668 -95.724726)
		(stroke
			(width 0.04445)
			(type default)
		)
		(layer "In2.Cu")
	)
	(gr_line
		(start 307.565298 -95.494856)
		(end 307.604668 -95.455486)
		(stroke
			(width 0.04445)
			(type default)
		)
		(layer "In2.Cu")
	)
	(gr_line
		(start 307.606446 -95.726504)
		(end 307.616098 -95.736156)
		(stroke
			(width 0.04445)
			(type default)
		)
		(layer "In2.Cu")
	)
	(gr_line
		(start 307.606446 -95.453708)
		(end 307.616098 -95.444056)
		(stroke
			(width 0.04445)
			(type default)
		)
		(layer "In2.Cu")
	)
	(gr_line
		(start 307.616098 -95.736156)
		(end 307.638196 -95.736156)
		(stroke
			(width 0.04445)
			(type default)
		)
		(layer "In2.Cu")
	)
	(gr_line
		(start 307.616098 -95.444056)
		(end 307.638196 -95.444056)
		(stroke
			(width 0.04445)
			(type default)
		)
		(layer "In2.Cu")
	)
	(gr_line
		(start 307.64353 -104.807766)
		(end 307.961792 -105.019856)
		(stroke
			(width 0.04445)
			(type default)
		)
		(layer "In2.Cu")
	)
	(gr_line
		(start 307.64734 -91.4527)
		(end 307.68671 -91.49207)
		(stroke
			(width 0.04445)
			(type default)
		)
		(layer "In2.Cu")
	)
	(gr_line
		(start 307.64734 -91.2622)
		(end 307.68671 -91.22283)
		(stroke
			(width 0.04445)
			(type default)
		)
		(layer "In2.Cu")
	)
	(gr_line
		(start 307.688488 -91.493848)
		(end 307.69814 -91.5035)
		(stroke
			(width 0.04445)
			(type default)
		)
		(layer "In2.Cu")
	)
	(gr_line
		(start 307.688488 -91.221052)
		(end 307.69814 -91.2114)
		(stroke
			(width 0.04445)
			(type default)
		)
		(layer "In2.Cu")
	)
	(gr_line
		(start 307.69814 -91.5035)
		(end 307.720238 -91.5035)
		(stroke
			(width 0.04445)
			(type default)
		)
		(layer "In2.Cu")
	)
	(gr_line
		(start 307.69814 -91.2114)
		(end 307.720238 -91.2114)
		(stroke
			(width 0.04445)
			(type default)
		)
		(layer "In2.Cu")
	)
	(gr_line
		(start 307.726334 -104.630982)
		(end 307.846222 -104.607106)
		(stroke
			(width 0.04445)
			(type default)
		)
		(layer "In2.Cu")
	)
	(gr_line
		(start 307.752242 -89.986104)
		(end 307.756052 -89.98458)
		(stroke
			(width 0.04445)
			(type default)
		)
		(layer "In2.Cu")
	)
	(gr_line
		(start 307.77688 -94.633288)
		(end 307.81625 -94.672658)
		(stroke
			(width 0.04445)
			(type default)
		)
		(layer "In2.Cu")
	)
	(gr_line
		(start 307.77688 -94.442788)
		(end 307.81625 -94.403418)
		(stroke
			(width 0.04445)
			(type default)
		)
		(layer "In2.Cu")
	)
	(gr_line
		(start 307.818028 -94.674436)
		(end 307.82768 -94.684088)
		(stroke
			(width 0.04445)
			(type default)
		)
		(layer "In2.Cu")
	)
	(gr_line
		(start 307.818028 -94.40164)
		(end 307.82768 -94.391988)
		(stroke
			(width 0.04445)
			(type default)
		)
		(layer "In2.Cu")
	)
	(gr_line
		(start 307.82768 -94.684088)
		(end 307.849778 -94.684088)
		(stroke
			(width 0.04445)
			(type default)
		)
		(layer "In2.Cu")
	)
	(gr_line
		(start 307.82768 -94.391988)
		(end 307.849778 -94.391988)
		(stroke
			(width 0.04445)
			(type default)
		)
		(layer "In2.Cu")
	)
	(gr_line
		(start 307.846222 -104.607106)
		(end 308.068218 -104.754934)
		(stroke
			(width 0.04445)
			(type default)
		)
		(layer "In2.Cu")
	)
	(gr_line
		(start 307.886862 -93.538802)
		(end 307.926232 -93.578172)
		(stroke
			(width 0.04445)
			(type default)
		)
		(layer "In2.Cu")
	)
	(gr_line
		(start 307.886862 -93.348302)
		(end 307.926232 -93.308932)
		(stroke
			(width 0.04445)
			(type default)
		)
		(layer "In2.Cu")
	)
	(gr_line
		(start 307.899562 -97.590864)
		(end 307.938932 -97.630234)
		(stroke
			(width 0.04445)
			(type default)
		)
		(layer "In2.Cu")
	)
	(gr_line
		(start 307.899562 -97.400364)
		(end 307.938932 -97.360994)
		(stroke
			(width 0.04445)
			(type default)
		)
		(layer "In2.Cu")
	)
	(gr_line
		(start 307.92801 -93.57995)
		(end 307.937662 -93.589602)
		(stroke
			(width 0.04445)
			(type default)
		)
		(layer "In2.Cu")
	)
	(gr_line
		(start 307.92801 -93.307154)
		(end 307.937662 -93.297502)
		(stroke
			(width 0.04445)
			(type default)
		)
		(layer "In2.Cu")
	)
	(gr_line
		(start 307.937662 -93.589602)
		(end 307.95976 -93.589602)
		(stroke
			(width 0.04445)
			(type default)
		)
		(layer "In2.Cu")
	)
	(gr_line
		(start 307.937662 -93.297502)
		(end 307.95976 -93.297502)
		(stroke
			(width 0.04445)
			(type default)
		)
		(layer "In2.Cu")
	)
	(gr_line
		(start 307.94071 -97.632012)
		(end 307.950362 -97.641664)
		(stroke
			(width 0.04445)
			(type default)
		)
		(layer "In2.Cu")
	)
	(gr_line
		(start 307.94071 -97.359216)
		(end 307.950362 -97.349564)
		(stroke
			(width 0.04445)
			(type default)
		)
		(layer "In2.Cu")
	)
	(gr_line
		(start 307.950362 -97.641664)
		(end 307.97246 -97.641664)
		(stroke
			(width 0.04445)
			(type default)
		)
		(layer "In2.Cu")
	)
	(gr_line
		(start 307.950362 -97.349564)
		(end 307.97246 -97.349564)
		(stroke
			(width 0.04445)
			(type default)
		)
		(layer "In2.Cu")
	)
	(gr_line
		(start 308.068218 -104.754934)
		(end 308.092348 -104.875076)
		(stroke
			(width 0.04445)
			(type default)
		)
		(layer "In2.Cu")
	)
	(gr_line
		(start 308.226206 -95.736156)
		(end 308.23154 -95.734378)
		(stroke
			(width 0.05715)
			(type default)
		)
		(layer "In2.Cu")
	)
	(gr_line
		(start 308.22646 -99.5299)
		(end 308.26583 -99.56927)
		(stroke
			(width 0.04445)
			(type default)
		)
		(layer "In2.Cu")
	)
	(gr_line
		(start 308.22646 -99.3394)
		(end 308.26583 -99.30003)
		(stroke
			(width 0.04445)
			(type default)
		)
		(layer "In2.Cu")
	)
	(gr_line
		(start 308.267608 -99.571048)
		(end 308.27726 -99.5807)
		(stroke
			(width 0.04445)
			(type default)
		)
		(layer "In2.Cu")
	)
	(gr_line
		(start 308.267608 -99.298252)
		(end 308.27726 -99.2886)
		(stroke
			(width 0.04445)
			(type default)
		)
		(layer "In2.Cu")
	)
	(gr_line
		(start 308.27726 -99.5807)
		(end 308.299358 -99.5807)
		(stroke
			(width 0.04445)
			(type default)
		)
		(layer "In2.Cu")
	)
	(gr_line
		(start 308.27726 -99.2886)
		(end 308.299358 -99.2886)
		(stroke
			(width 0.04445)
			(type default)
		)
		(layer "In2.Cu")
	)
	(gr_line
		(start 308.3179 -91.5035)
		(end 308.323742 -91.501722)
		(stroke
			(width 0.05715)
			(type default)
		)
		(layer "In2.Cu")
	)
	(gr_line
		(start 308.351682 -92.27947)
		(end 308.357778 -92.27947)
		(stroke
			(width 0.05715)
			(type default)
		)
		(layer "In2.Cu")
	)
	(gr_line
		(start 308.357778 -92.27947)
		(end 308.360064 -92.278708)
		(stroke
			(width 0.05715)
			(type default)
		)
		(layer "In2.Cu")
	)
	(gr_line
		(start 308.360064 -92.278708)
		(end 308.363366 -92.277692)
		(stroke
			(width 0.05715)
			(type default)
		)
		(layer "In2.Cu")
	)
	(gr_line
		(start 308.4068 -90.17508)
		(end 308.44617 -90.21445)
		(stroke
			(width 0.04445)
			(type default)
		)
		(layer "In2.Cu")
	)
	(gr_line
		(start 308.4068 -89.98458)
		(end 308.44617 -89.94521)
		(stroke
			(width 0.04445)
			(type default)
		)
		(layer "In2.Cu")
	)
	(gr_line
		(start 308.447948 -90.216228)
		(end 308.4576 -90.22588)
		(stroke
			(width 0.04445)
			(type default)
		)
		(layer "In2.Cu")
	)
	(gr_line
		(start 308.447948 -89.943432)
		(end 308.4576 -89.93378)
		(stroke
			(width 0.04445)
			(type default)
		)
		(layer "In2.Cu")
	)
	(gr_line
		(start 308.4576 -90.22588)
		(end 308.479698 -90.22588)
		(stroke
			(width 0.04445)
			(type default)
		)
		(layer "In2.Cu")
	)
	(gr_line
		(start 308.4576 -89.93378)
		(end 308.479698 -89.93378)
		(stroke
			(width 0.04445)
			(type default)
		)
		(layer "In2.Cu")
	)
	(gr_line
		(start 308.463188 -94.684088)
		(end 308.468522 -94.68231)
		(stroke
			(width 0.05715)
			(type default)
		)
		(layer "In2.Cu")
	)
	(gr_line
		(start 308.74335 -99.2886)
		(end 308.778656 -99.309174)
		(stroke
			(width 0.05715)
			(type default)
		)
		(layer "In2.Cu")
	)
	(gr_line
		(start 308.832758 -92.945966)
		(end 308.838092 -92.944188)
		(stroke
			(width 0.05715)
			(type default)
		)
		(layer "In2.Cu")
	)
	(gr_line
		(start 308.961282 -90.22588)
		(end 308.965092 -90.22461)
		(stroke
			(width 0.05715)
			(type default)
		)
		(layer "In2.Cu")
	)
	(gr_line
		(start 309.075836 -98.52152)
		(end 309.111142 -98.542094)
		(stroke
			(width 0.05715)
			(type default)
		)
		(layer "In2.Cu")
	)
	(gr_line
		(start 309.130954 -93.589602)
		(end 309.136288 -93.587824)
		(stroke
			(width 0.05715)
			(type default)
		)
		(layer "In2.Cu")
	)
	(gr_line
		(start 309.137558 -105.807002)
		(end 309.150766 -105.874566)
		(stroke
			(width 0.04445)
			(type default)
		)
		(layer "In2.Cu")
	)
	(gr_line
		(start 309.150766 -105.874566)
		(end 309.169054 -105.886758)
		(stroke
			(width 0.04445)
			(type default)
		)
		(layer "In2.Cu")
	)
	(gr_line
		(start 309.204868 -97.349564)
		(end 309.241444 -97.371408)
		(stroke
			(width 0.05715)
			(type default)
		)
		(layer "In2.Cu")
	)
	(gr_line
		(start 309.247794 -105.645712)
		(end 309.331614 -105.643934)
		(stroke
			(width 0.04445)
			(type default)
		)
		(layer "In2.Cu")
	)
	(gr_line
		(start 309.364888 -96.35236)
		(end 309.40121 -96.374204)
		(stroke
			(width 0.05715)
			(type default)
		)
		(layer "In2.Cu")
	)
	(gr_line
		(start 310.722264 -62.340744)
		(end 310.754776 -62.299342)
		(stroke
			(width 0.0635)
			(type default)
		)
		(layer "In2.Cu")
	)
	(gr_line
		(start 311.239408 -89.535762)
		(end 311.257696 -89.530174)
		(stroke
			(width 0.05715)
			(type default)
		)
		(layer "In2.Cu")
	)
	(gr_line
		(start 311.257696 -89.530174)
		(end 311.272682 -89.518236)
		(stroke
			(width 0.05715)
			(type default)
		)
		(layer "In2.Cu")
	)
	(gr_line
		(start 311.285128 -88.192356)
		(end 311.31383 -88.18626)
		(stroke
			(width 0.05715)
			(type default)
		)
		(layer "In2.Cu")
	)
	(gr_line
		(start 311.31383 -88.18626)
		(end 311.337452 -88.167464)
		(stroke
			(width 0.05715)
			(type default)
		)
		(layer "In2.Cu")
	)
	(gr_line
		(start 311.382664 -100.831142)
		(end 311.402476 -100.842826)
		(stroke
			(width 0.05715)
			(type default)
		)
		(layer "In2.Cu")
	)
	(gr_line
		(start 311.402476 -100.842826)
		(end 311.415938 -100.861368)
		(stroke
			(width 0.05715)
			(type default)
		)
		(layer "In2.Cu")
	)
	(gr_line
		(start 311.512966 -90.512646)
		(end 311.529222 -90.507566)
		(stroke
			(width 0.05715)
			(type default)
		)
		(layer "In2.Cu")
	)
	(gr_line
		(start 311.529222 -90.507566)
		(end 311.542684 -90.496898)
		(stroke
			(width 0.05715)
			(type default)
		)
		(layer "In2.Cu")
	)
	(gr_line
		(start 311.911238 -100.178616)
		(end 311.930796 -100.190046)
		(stroke
			(width 0.05715)
			(type default)
		)
		(layer "In2.Cu")
	)
	(gr_line
		(start 311.930796 -100.190046)
		(end 311.944766 -100.209096)
		(stroke
			(width 0.05715)
			(type default)
		)
		(layer "In2.Cu")
	)
	(gr_line
		(start 312.258964 -91.070176)
		(end 312.27522 -91.065096)
		(stroke
			(width 0.05715)
			(type default)
		)
		(layer "In2.Cu")
	)
	(gr_line
		(start 312.27522 -91.065096)
		(end 312.288682 -91.054428)
		(stroke
			(width 0.05715)
			(type default)
		)
		(layer "In2.Cu")
	)
	(gr_line
		(start 312.526426 -99.343464)
		(end 312.550556 -99.357942)
		(stroke
			(width 0.05715)
			(type default)
		)
		(layer "In2.Cu")
	)
	(gr_line
		(start 312.550556 -99.357942)
		(end 312.565542 -99.37877)
		(stroke
			(width 0.05715)
			(type default)
		)
		(layer "In2.Cu")
	)
	(gr_line
		(start 312.619136 -103.016558)
		(end 312.630058 -103.031544)
		(stroke
			(width 0.05715)
			(type default)
		)
		(layer "In2.Cu")
	)
	(gr_line
		(start 312.630058 -103.031544)
		(end 312.645298 -103.041196)
		(stroke
			(width 0.05715)
			(type default)
		)
		(layer "In2.Cu")
	)
	(gr_line
		(start 312.677302 -91.754706)
		(end 312.693558 -91.749626)
		(stroke
			(width 0.05715)
			(type default)
		)
		(layer "In2.Cu")
	)
	(gr_line
		(start 312.693558 -91.749626)
		(end 312.70702 -91.738958)
		(stroke
			(width 0.05715)
			(type default)
		)
		(layer "In2.Cu")
	)
	(gr_line
		(start 313.038998 -98.559112)
		(end 313.058556 -98.570796)
		(stroke
			(width 0.05715)
			(type default)
		)
		(layer "In2.Cu")
	)
	(gr_line
		(start 313.058556 -98.570796)
		(end 313.071764 -98.589338)
		(stroke
			(width 0.05715)
			(type default)
		)
		(layer "In2.Cu")
	)
	(gr_line
		(start 313.278266 -102.54361)
		(end 313.289188 -102.558596)
		(stroke
			(width 0.05715)
			(type default)
		)
		(layer "In2.Cu")
	)
	(gr_line
		(start 313.289188 -102.558596)
		(end 313.304936 -102.568502)
		(stroke
			(width 0.05715)
			(type default)
		)
		(layer "In2.Cu")
	)
	(gr_line
		(start 313.450986 -92.250768)
		(end 313.467242 -92.245688)
		(stroke
			(width 0.05715)
			(type default)
		)
		(layer "In2.Cu")
	)
	(gr_line
		(start 313.467242 -92.245688)
		(end 313.480704 -92.23502)
		(stroke
			(width 0.05715)
			(type default)
		)
		(layer "In2.Cu")
	)
	(gr_line
		(start 313.870594 -93.00591)
		(end 313.88685 -93.00083)
		(stroke
			(width 0.05715)
			(type default)
		)
		(layer "In2.Cu")
	)
	(gr_line
		(start 313.88685 -93.00083)
		(end 313.900312 -92.990162)
		(stroke
			(width 0.05715)
			(type default)
		)
		(layer "In2.Cu")
	)
	(gr_line
		(start 313.915298 -93.96476)
		(end 313.932316 -93.959426)
		(stroke
			(width 0.05715)
			(type default)
		)
		(layer "In2.Cu")
	)
	(gr_line
		(start 313.932316 -93.959426)
		(end 313.946286 -93.94825)
		(stroke
			(width 0.05715)
			(type default)
		)
		(layer "In2.Cu")
	)
	(gr_line
		(start 314.230512 -102.169976)
		(end 314.241434 -102.184962)
		(stroke
			(width 0.05715)
			(type default)
		)
		(layer "In2.Cu")
	)
	(gr_line
		(start 314.241434 -102.184962)
		(end 314.257182 -102.194868)
		(stroke
			(width 0.05715)
			(type default)
		)
		(layer "In2.Cu")
	)
	(gr_line
		(start 314.875164 -101.570536)
		(end 314.886086 -101.585522)
		(stroke
			(width 0.05715)
			(type default)
		)
		(layer "In2.Cu")
	)
	(gr_line
		(start 314.886086 -101.585522)
		(end 314.901834 -101.595428)
		(stroke
			(width 0.05715)
			(type default)
		)
		(layer "In2.Cu")
	)
	(gr_line
		(start 316.947804 -83.674712)
		(end 316.99454 -83.637374)
		(stroke
			(width 0.05715)
			(type default)
		)
		(layer "In2.Cu")
	)
	(gr_line
		(start 316.99454 -83.637374)
		(end 317.009526 -83.579208)
		(stroke
			(width 0.05715)
			(type default)
		)
		(layer "In2.Cu")
	)
	(gr_line
		(start 317.19393 -110.90021)
		(end 317.252858 -110.939326)
		(stroke
			(width 0.05715)
			(type default)
		)
		(layer "In2.Cu")
	)
	(gr_line
		(start 317.252858 -110.939326)
		(end 317.271908 -111.00816)
		(stroke
			(width 0.05715)
			(type default)
		)
		(layer "In2.Cu")
	)
	(gr_line
		(start 317.797942 -84.292948)
		(end 317.84544 -84.254848)
		(stroke
			(width 0.05715)
			(type default)
		)
		(layer "In2.Cu")
	)
	(gr_line
		(start 317.84544 -84.254848)
		(end 317.86068 -84.195666)
		(stroke
			(width 0.05715)
			(type default)
		)
		(layer "In2.Cu")
	)
	(gr_line
		(start 318.666876 -117.150896)
		(end 318.670432 -117.163596)
		(stroke
			(width 0.05715)
			(type default)
		)
		(layer "In2.Cu")
	)
	(gr_line
		(start 318.670432 -117.163596)
		(end 318.677798 -117.174264)
		(stroke
			(width 0.05715)
			(type default)
		)
		(layer "In2.Cu")
	)
	(gr_line
		(start 318.80937 -84.67852)
		(end 318.857376 -84.640166)
		(stroke
			(width 0.05715)
			(type default)
		)
		(layer "In2.Cu")
	)
	(gr_line
		(start 318.857376 -84.640166)
		(end 318.872616 -84.581492)
		(stroke
			(width 0.05715)
			(type default)
		)
		(layer "In2.Cu")
	)
	(gr_line
		(start 319.39611 -72.466454)
		(end 319.484756 -72.12203)
		(stroke
			(width 0.05715)
			(type default)
		)
		(layer "In2.Cu")
	)
	(gr_line
		(start 319.39611 -72.466454)
		(end 319.513204 -72.664828)
		(stroke
			(width 0.05715)
			(type default)
		)
		(layer "In2.Cu")
	)
	(gr_line
		(start 319.484756 -72.12203)
		(end 319.68313 -72.004936)
		(stroke
			(width 0.05715)
			(type default)
		)
		(layer "In2.Cu")
	)
	(gr_line
		(start 319.642744 -85.165946)
		(end 319.690242 -85.127846)
		(stroke
			(width 0.05715)
			(type default)
		)
		(layer "In2.Cu")
	)
	(gr_line
		(start 319.655698 -71.45782)
		(end 319.744344 -71.113396)
		(stroke
			(width 0.05715)
			(type default)
		)
		(layer "In2.Cu")
	)
	(gr_line
		(start 319.655698 -71.45782)
		(end 319.772792 -71.656448)
		(stroke
			(width 0.05715)
			(type default)
		)
		(layer "In2.Cu")
	)
	(gr_line
		(start 319.690242 -85.127846)
		(end 319.705482 -85.068664)
		(stroke
			(width 0.05715)
			(type default)
		)
		(layer "In2.Cu")
	)
	(gr_line
		(start 319.744344 -71.113396)
		(end 319.942718 -70.996302)
		(stroke
			(width 0.05715)
			(type default)
		)
		(layer "In2.Cu")
	)
	(gr_line
		(start 319.807336 -72.70496)
		(end 319.960244 -72.110346)
		(stroke
			(width 0.05715)
			(type default)
		)
		(layer "In2.Cu")
	)
	(gr_line
		(start 319.915286 -70.449186)
		(end 320.003932 -70.104762)
		(stroke
			(width 0.05715)
			(type default)
		)
		(layer "In2.Cu")
	)
	(gr_line
		(start 319.915286 -70.449186)
		(end 320.03238 -70.64756)
		(stroke
			(width 0.05715)
			(type default)
		)
		(layer "In2.Cu")
	)
	(gr_line
		(start 320.003932 -70.104762)
		(end 320.202052 -69.987668)
		(stroke
			(width 0.05715)
			(type default)
		)
		(layer "In2.Cu")
	)
	(gr_line
		(start 320.020696 -119.107712)
		(end 320.061844 -119.167148)
		(stroke
			(width 0.05715)
			(type default)
		)
		(layer "In2.Cu")
	)
	(gr_line
		(start 320.04 -112.08131)
		(end 320.049906 -112.088422)
		(stroke
			(width 0.05715)
			(type default)
		)
		(layer "In2.Cu")
	)
	(gr_line
		(start 320.049906 -112.088422)
		(end 320.057272 -112.098836)
		(stroke
			(width 0.05715)
			(type default)
		)
		(layer "In2.Cu")
	)
	(gr_line
		(start 320.0527 -110.899448)
		(end 320.062098 -110.906306)
		(stroke
			(width 0.05715)
			(type default)
		)
		(layer "In2.Cu")
	)
	(gr_line
		(start 320.061844 -119.167148)
		(end 320.131186 -119.18442)
		(stroke
			(width 0.05715)
			(type default)
		)
		(layer "In2.Cu")
	)
	(gr_line
		(start 320.062098 -110.906306)
		(end 320.068702 -110.91545)
		(stroke
			(width 0.05715)
			(type default)
		)
		(layer "In2.Cu")
	)
	(gr_line
		(start 320.06667 -71.69658)
		(end 320.219324 -71.102982)
		(stroke
			(width 0.05715)
			(type default)
		)
		(layer "In2.Cu")
	)
	(gr_line
		(start 320.183764 -73.338436)
		(end 320.27241 -72.994012)
		(stroke
			(width 0.05715)
			(type default)
		)
		(layer "In2.Cu")
	)
	(gr_line
		(start 320.183764 -73.338436)
		(end 320.300858 -73.536302)
		(stroke
			(width 0.05715)
			(type default)
		)
		(layer "In2.Cu")
	)
	(gr_line
		(start 320.27241 -72.994012)
		(end 320.47053 -72.877172)
		(stroke
			(width 0.05715)
			(type default)
		)
		(layer "In2.Cu")
	)
	(gr_line
		(start 320.286126 -69.669914)
		(end 320.293492 -69.64172)
		(stroke
			(width 0.05715)
			(type default)
		)
		(layer "In2.Cu")
	)
	(gr_line
		(start 320.293492 -69.64172)
		(end 320.31178 -69.62013)
		(stroke
			(width 0.05715)
			(type default)
		)
		(layer "In2.Cu")
	)
	(gr_line
		(start 320.326258 -70.68693)
		(end 320.478658 -70.094602)
		(stroke
			(width 0.05715)
			(type default)
		)
		(layer "In2.Cu")
	)
	(gr_line
		(start 320.443352 -72.330056)
		(end 320.531998 -71.985632)
		(stroke
			(width 0.05715)
			(type default)
		)
		(layer "In2.Cu")
	)
	(gr_line
		(start 320.443352 -72.330056)
		(end 320.560446 -72.527922)
		(stroke
			(width 0.05715)
			(type default)
		)
		(layer "In2.Cu")
	)
	(gr_line
		(start 320.495168 -85.502242)
		(end 320.542666 -85.464142)
		(stroke
			(width 0.05715)
			(type default)
		)
		(layer "In2.Cu")
	)
	(gr_line
		(start 320.531998 -71.985632)
		(end 320.730118 -71.868792)
		(stroke
			(width 0.05715)
			(type default)
		)
		(layer "In2.Cu")
	)
	(gr_line
		(start 320.542666 -85.464142)
		(end 320.557906 -85.40496)
		(stroke
			(width 0.05715)
			(type default)
		)
		(layer "In2.Cu")
	)
	(gr_line
		(start 320.594736 -73.577958)
		(end 320.747898 -72.98309)
		(stroke
			(width 0.05715)
			(type default)
		)
		(layer "In2.Cu")
	)
	(gr_line
		(start 320.70294 -71.321422)
		(end 320.791586 -70.976998)
		(stroke
			(width 0.05715)
			(type default)
		)
		(layer "In2.Cu")
	)
	(gr_line
		(start 320.70294 -71.321422)
		(end 320.820034 -71.519542)
		(stroke
			(width 0.05715)
			(type default)
		)
		(layer "In2.Cu")
	)
	(gr_line
		(start 320.791586 -70.976998)
		(end 320.989706 -70.860158)
		(stroke
			(width 0.05715)
			(type default)
		)
		(layer "In2.Cu")
	)
	(gr_line
		(start 320.854578 -72.568562)
		(end 321.007232 -71.975472)
		(stroke
			(width 0.05715)
			(type default)
		)
		(layer "In2.Cu")
	)
	(gr_line
		(start 320.962528 -70.312788)
		(end 321.051174 -69.968364)
		(stroke
			(width 0.05715)
			(type default)
		)
		(layer "In2.Cu")
	)
	(gr_line
		(start 320.962528 -70.312788)
		(end 321.079622 -70.511162)
		(stroke
			(width 0.05715)
			(type default)
		)
		(layer "In2.Cu")
	)
	(gr_line
		(start 321.051174 -69.968364)
		(end 321.249548 -69.851524)
		(stroke
			(width 0.05715)
			(type default)
		)
		(layer "In2.Cu")
	)
	(gr_line
		(start 321.114166 -71.560182)
		(end 321.26682 -70.966838)
		(stroke
			(width 0.05715)
			(type default)
		)
		(layer "In2.Cu")
	)
	(gr_line
		(start 321.314064 -85.962744)
		(end 321.361562 -85.924644)
		(stroke
			(width 0.05715)
			(type default)
		)
		(layer "In2.Cu")
	)
	(gr_line
		(start 321.333622 -69.533516)
		(end 321.340988 -69.505322)
		(stroke
			(width 0.05715)
			(type default)
		)
		(layer "In2.Cu")
	)
	(gr_line
		(start 321.340988 -69.505322)
		(end 321.359276 -69.483732)
		(stroke
			(width 0.05715)
			(type default)
		)
		(layer "In2.Cu")
	)
	(gr_line
		(start 321.361562 -85.924644)
		(end 321.376802 -85.865462)
		(stroke
			(width 0.05715)
			(type default)
		)
		(layer "In2.Cu")
	)
	(gr_line
		(start 321.373754 -70.550532)
		(end 321.526408 -69.958204)
		(stroke
			(width 0.05715)
			(type default)
		)
		(layer "In2.Cu")
	)
	(gr_line
		(start 321.596258 -72.1614)
		(end 321.684904 -71.816976)
		(stroke
			(width 0.05715)
			(type default)
		)
		(layer "In2.Cu")
	)
	(gr_line
		(start 321.596258 -72.1614)
		(end 321.713098 -72.359774)
		(stroke
			(width 0.05715)
			(type default)
		)
		(layer "In2.Cu")
	)
	(gr_line
		(start 321.684904 -71.816976)
		(end 321.883024 -71.700136)
		(stroke
			(width 0.05715)
			(type default)
		)
		(layer "In2.Cu")
	)
	(gr_line
		(start 321.743832 -119.588788)
		(end 321.81292 -119.606314)
		(stroke
			(width 0.05715)
			(type default)
		)
		(layer "In2.Cu")
	)
	(gr_line
		(start 321.81292 -119.606314)
		(end 321.876928 -119.573548)
		(stroke
			(width 0.05715)
			(type default)
		)
		(layer "In2.Cu")
	)
	(gr_line
		(start 321.855846 -71.152766)
		(end 321.944492 -70.808342)
		(stroke
			(width 0.05715)
			(type default)
		)
		(layer "In2.Cu")
	)
	(gr_line
		(start 321.855846 -71.152766)
		(end 321.972686 -71.35114)
		(stroke
			(width 0.05715)
			(type default)
		)
		(layer "In2.Cu")
	)
	(gr_line
		(start 321.899534 -74.714354)
		(end 321.985132 -74.382376)
		(stroke
			(width 0.05715)
			(type default)
		)
		(layer "In2.Cu")
	)
	(gr_line
		(start 321.899534 -74.714354)
		(end 322.016628 -74.912982)
		(stroke
			(width 0.05715)
			(type default)
		)
		(layer "In2.Cu")
	)
	(gr_line
		(start 321.944492 -70.808342)
		(end 322.142612 -70.691502)
		(stroke
			(width 0.05715)
			(type default)
		)
		(layer "In2.Cu")
	)
	(gr_line
		(start 321.985132 -74.382376)
		(end 322.183506 -74.265028)
		(stroke
			(width 0.05715)
			(type default)
		)
		(layer "In2.Cu")
	)
	(gr_line
		(start 322.006976 -72.401176)
		(end 322.160392 -71.805546)
		(stroke
			(width 0.05715)
			(type default)
		)
		(layer "In2.Cu")
	)
	(gr_line
		(start 322.112132 -70.156578)
		(end 322.197476 -69.8246)
		(stroke
			(width 0.05715)
			(type default)
		)
		(layer "In2.Cu")
	)
	(gr_line
		(start 322.112132 -70.156578)
		(end 322.229226 -70.354952)
		(stroke
			(width 0.05715)
			(type default)
		)
		(layer "In2.Cu")
	)
	(gr_line
		(start 322.123562 -86.40572)
		(end 322.17106 -86.36762)
		(stroke
			(width 0.05715)
			(type default)
		)
		(layer "In2.Cu")
	)
	(gr_line
		(start 322.152772 -73.730612)
		(end 322.241418 -73.386188)
		(stroke
			(width 0.05715)
			(type default)
		)
		(layer "In2.Cu")
	)
	(gr_line
		(start 322.152772 -73.730612)
		(end 322.27012 -73.928986)
		(stroke
			(width 0.05715)
			(type default)
		)
		(layer "In2.Cu")
	)
	(gr_line
		(start 322.17106 -86.36762)
		(end 322.1863 -86.308438)
		(stroke
			(width 0.05715)
			(type default)
		)
		(layer "In2.Cu")
	)
	(gr_line
		(start 322.197476 -69.8246)
		(end 322.395596 -69.707506)
		(stroke
			(width 0.05715)
			(type default)
		)
		(layer "In2.Cu")
	)
	(gr_line
		(start 322.241418 -73.386188)
		(end 322.440046 -73.269094)
		(stroke
			(width 0.05715)
			(type default)
		)
		(layer "In2.Cu")
	)
	(gr_line
		(start 322.266564 -71.39305)
		(end 322.419726 -70.797674)
		(stroke
			(width 0.05715)
			(type default)
		)
		(layer "In2.Cu")
	)
	(gr_line
		(start 322.310506 -74.952098)
		(end 322.460112 -74.371708)
		(stroke
			(width 0.05715)
			(type default)
		)
		(layer "In2.Cu")
	)
	(gr_line
		(start 322.412614 -72.722232)
		(end 322.50126 -72.377808)
		(stroke
			(width 0.05715)
			(type default)
		)
		(layer "In2.Cu")
	)
	(gr_line
		(start 322.412614 -72.722232)
		(end 322.529708 -72.920606)
		(stroke
			(width 0.05715)
			(type default)
		)
		(layer "In2.Cu")
	)
	(gr_line
		(start 322.50126 -72.377808)
		(end 322.699634 -72.260714)
		(stroke
			(width 0.05715)
			(type default)
		)
		(layer "In2.Cu")
	)
	(gr_line
		(start 322.523104 -70.395338)
		(end 322.672456 -69.814694)
		(stroke
			(width 0.05715)
			(type default)
		)
		(layer "In2.Cu")
	)
	(gr_line
		(start 322.563998 -73.96861)
		(end 322.716398 -73.376536)
		(stroke
			(width 0.05715)
			(type default)
		)
		(layer "In2.Cu")
	)
	(gr_line
		(start 322.568824 -69.04355)
		(end 322.57619 -69.015356)
		(stroke
			(width 0.05715)
			(type default)
		)
		(layer "In2.Cu")
	)
	(gr_line
		(start 322.57619 -69.015356)
		(end 322.594478 -68.993766)
		(stroke
			(width 0.05715)
			(type default)
		)
		(layer "In2.Cu")
	)
	(gr_line
		(start 322.640452 -118.853204)
		(end 322.709794 -118.817644)
		(stroke
			(width 0.05715)
			(type default)
		)
		(layer "In2.Cu")
	)
	(gr_line
		(start 322.709794 -118.817644)
		(end 322.784216 -118.838472)
		(stroke
			(width 0.05715)
			(type default)
		)
		(layer "In2.Cu")
	)
	(gr_line
		(start 322.823586 -72.96023)
		(end 322.97624 -72.367648)
		(stroke
			(width 0.05715)
			(type default)
		)
		(layer "In2.Cu")
	)
	(gr_line
		(start 323.101462 -86.617302)
		(end 323.14896 -86.579202)
		(stroke
			(width 0.05715)
			(type default)
		)
		(layer "In2.Cu")
	)
	(gr_line
		(start 323.14896 -86.579202)
		(end 323.1642 -86.52002)
		(stroke
			(width 0.05715)
			(type default)
		)
		(layer "In2.Cu")
	)
	(gr_line
		(start 323.39153 -72.557894)
		(end 323.480176 -72.21347)
		(stroke
			(width 0.05715)
			(type default)
		)
		(layer "In2.Cu")
	)
	(gr_line
		(start 323.39153 -72.557894)
		(end 323.508624 -72.756268)
		(stroke
			(width 0.05715)
			(type default)
		)
		(layer "In2.Cu")
	)
	(gr_line
		(start 323.480176 -72.21347)
		(end 323.67855 -72.096122)
		(stroke
			(width 0.05715)
			(type default)
		)
		(layer "In2.Cu")
	)
	(gr_line
		(start 323.575172 -68.870068)
		(end 323.582538 -68.841874)
		(stroke
			(width 0.05715)
			(type default)
		)
		(layer "In2.Cu")
	)
	(gr_line
		(start 323.582538 -68.841874)
		(end 323.601334 -68.819268)
		(stroke
			(width 0.05715)
			(type default)
		)
		(layer "In2.Cu")
	)
	(gr_line
		(start 323.651118 -71.54926)
		(end 323.739764 -71.204836)
		(stroke
			(width 0.05715)
			(type default)
		)
		(layer "In2.Cu")
	)
	(gr_line
		(start 323.651118 -71.54926)
		(end 323.768212 -71.747888)
		(stroke
			(width 0.05715)
			(type default)
		)
		(layer "In2.Cu")
	)
	(gr_line
		(start 323.708268 -74.973942)
		(end 323.793866 -74.641964)
		(stroke
			(width 0.05715)
			(type default)
		)
		(layer "In2.Cu")
	)
	(gr_line
		(start 323.708268 -74.973942)
		(end 323.825616 -75.172316)
		(stroke
			(width 0.05715)
			(type default)
		)
		(layer "In2.Cu")
	)
	(gr_line
		(start 323.739764 -71.204836)
		(end 323.938138 -71.087742)
		(stroke
			(width 0.05715)
			(type default)
		)
		(layer "In2.Cu")
	)
	(gr_line
		(start 323.793866 -74.641964)
		(end 323.99224 -74.525124)
		(stroke
			(width 0.05715)
			(type default)
		)
		(layer "In2.Cu")
	)
	(gr_line
		(start 323.802248 -72.796908)
		(end 323.955156 -72.203056)
		(stroke
			(width 0.05715)
			(type default)
		)
		(layer "In2.Cu")
	)
	(gr_line
		(start 323.818758 -118.119398)
		(end 323.822822 -118.135654)
		(stroke
			(width 0.05715)
			(type default)
		)
		(layer "In2.Cu")
	)
	(gr_line
		(start 323.822822 -118.135654)
		(end 323.832982 -118.149624)
		(stroke
			(width 0.05715)
			(type default)
		)
		(layer "In2.Cu")
	)
	(gr_line
		(start 323.84365 -119.135652)
		(end 323.903086 -119.152162)
		(stroke
			(width 0.05715)
			(type default)
		)
		(layer "In2.Cu")
	)
	(gr_line
		(start 323.903086 -119.152162)
		(end 323.940932 -119.201946)
		(stroke
			(width 0.05715)
			(type default)
		)
		(layer "In2.Cu")
	)
	(gr_line
		(start 323.910706 -70.54088)
		(end 323.999352 -70.196456)
		(stroke
			(width 0.05715)
			(type default)
		)
		(layer "In2.Cu")
	)
	(gr_line
		(start 323.910706 -70.54088)
		(end 324.0278 -70.739254)
		(stroke
			(width 0.05715)
			(type default)
		)
		(layer "In2.Cu")
	)
	(gr_line
		(start 323.96176 -73.9902)
		(end 324.047104 -73.657968)
		(stroke
			(width 0.05715)
			(type default)
		)
		(layer "In2.Cu")
	)
	(gr_line
		(start 323.96176 -73.9902)
		(end 324.078854 -74.188574)
		(stroke
			(width 0.05715)
			(type default)
		)
		(layer "In2.Cu")
	)
	(gr_line
		(start 323.999352 -70.196456)
		(end 324.197472 -70.079108)
		(stroke
			(width 0.05715)
			(type default)
		)
		(layer "In2.Cu")
	)
	(gr_line
		(start 324.022466 -117.765068)
		(end 324.030848 -117.776752)
		(stroke
			(width 0.05715)
			(type default)
		)
		(layer "In2.Cu")
	)
	(gr_line
		(start 324.02907 -112.60074)
		(end 324.046342 -112.61217)
		(stroke
			(width 0.05715)
			(type default)
		)
		(layer "In2.Cu")
	)
	(gr_line
		(start 324.030848 -117.776752)
		(end 324.034658 -117.79123)
		(stroke
			(width 0.05715)
			(type default)
		)
		(layer "In2.Cu")
	)
	(gr_line
		(start 324.046342 -112.61217)
		(end 324.057772 -112.629442)
		(stroke
			(width 0.05715)
			(type default)
		)
		(layer "In2.Cu")
	)
	(gr_line
		(start 324.047104 -73.657968)
		(end 324.245478 -73.540874)
		(stroke
			(width 0.05715)
			(type default)
		)
		(layer "In2.Cu")
	)
	(gr_line
		(start 324.06209 -71.787258)
		(end 324.214236 -71.195946)
		(stroke
			(width 0.05715)
			(type default)
		)
		(layer "In2.Cu")
	)
	(gr_line
		(start 324.119494 -75.211686)
		(end 324.268338 -74.633582)
		(stroke
			(width 0.05715)
			(type default)
		)
		(layer "In2.Cu")
	)
	(gr_line
		(start 324.170294 -69.532246)
		(end 324.25894 -69.187822)
		(stroke
			(width 0.05715)
			(type default)
		)
		(layer "In2.Cu")
	)
	(gr_line
		(start 324.170294 -69.532246)
		(end 324.287388 -69.73062)
		(stroke
			(width 0.05715)
			(type default)
		)
		(layer "In2.Cu")
	)
	(gr_line
		(start 324.214998 -73.006204)
		(end 324.300596 -72.674226)
		(stroke
			(width 0.05715)
			(type default)
		)
		(layer "In2.Cu")
	)
	(gr_line
		(start 324.214998 -73.006204)
		(end 324.332092 -73.204578)
		(stroke
			(width 0.05715)
			(type default)
		)
		(layer "In2.Cu")
	)
	(gr_line
		(start 324.25894 -69.187822)
		(end 324.45706 -69.070728)
		(stroke
			(width 0.05715)
			(type default)
		)
		(layer "In2.Cu")
	)
	(gr_line
		(start 324.300596 -72.674226)
		(end 324.49897 -72.556878)
		(stroke
			(width 0.05715)
			(type default)
		)
		(layer "In2.Cu")
	)
	(gr_line
		(start 324.321678 -70.777862)
		(end 324.474078 -70.186042)
		(stroke
			(width 0.05715)
			(type default)
		)
		(layer "In2.Cu")
	)
	(gr_line
		(start 324.372732 -74.228198)
		(end 324.522084 -73.647808)
		(stroke
			(width 0.05715)
			(type default)
		)
		(layer "In2.Cu")
	)
	(gr_line
		(start 324.444614 -119.867934)
		(end 324.44944 -119.87403)
		(stroke
			(width 0.05715)
			(type default)
		)
		(layer "In2.Cu")
	)
	(gr_line
		(start 324.44944 -119.87403)
		(end 324.452234 -119.881904)
		(stroke
			(width 0.05715)
			(type default)
		)
		(layer "In2.Cu")
	)
	(gr_line
		(start 324.541134 -68.752974)
		(end 324.5485 -68.72478)
		(stroke
			(width 0.05715)
			(type default)
		)
		(layer "In2.Cu")
	)
	(gr_line
		(start 324.5485 -68.72478)
		(end 324.566788 -68.70319)
		(stroke
			(width 0.05715)
			(type default)
		)
		(layer "In2.Cu")
	)
	(gr_line
		(start 324.581266 -69.770498)
		(end 324.73392 -69.177408)
		(stroke
			(width 0.05715)
			(type default)
		)
		(layer "In2.Cu")
	)
	(gr_line
		(start 324.626478 -73.242932)
		(end 324.775576 -72.663558)
		(stroke
			(width 0.05715)
			(type default)
		)
		(layer "In2.Cu")
	)
	(gr_line
		(start 324.635622 -118.044214)
		(end 324.640194 -118.061486)
		(stroke
			(width 0.05715)
			(type default)
		)
		(layer "In2.Cu")
	)
	(gr_line
		(start 324.640194 -118.061486)
		(end 324.650862 -118.076218)
		(stroke
			(width 0.05715)
			(type default)
		)
		(layer "In2.Cu")
	)
	(gr_line
		(start 324.643242 -110.295944)
		(end 324.710044 -110.338362)
		(stroke
			(width 0.05715)
			(type default)
		)
		(layer "In2.Cu")
	)
	(gr_line
		(start 324.710044 -110.338362)
		(end 324.729602 -110.4138)
		(stroke
			(width 0.05715)
			(type default)
		)
		(layer "In2.Cu")
	)
	(gr_line
		(start 324.823836 -117.633496)
		(end 324.833488 -117.647212)
		(stroke
			(width 0.05715)
			(type default)
		)
		(layer "In2.Cu")
	)
	(gr_line
		(start 324.833488 -117.647212)
		(end 324.837806 -117.663214)
		(stroke
			(width 0.05715)
			(type default)
		)
		(layer "In2.Cu")
	)
	(gr_line
		(start 324.877684 -113.8682)
		(end 324.888606 -113.88471)
		(stroke
			(width 0.05715)
			(type default)
		)
		(layer "In2.Cu")
	)
	(gr_line
		(start 324.888606 -113.88471)
		(end 324.89267 -113.904268)
		(stroke
			(width 0.05715)
			(type default)
		)
		(layer "In2.Cu")
	)
	(gr_line
		(start 325.151242 -119.465598)
		(end 325.154544 -119.47017)
		(stroke
			(width 0.05715)
			(type default)
		)
		(layer "In2.Cu")
	)
	(gr_line
		(start 325.154544 -119.47017)
		(end 325.156068 -119.474996)
		(stroke
			(width 0.05715)
			(type default)
		)
		(layer "In2.Cu")
	)
	(gr_line
		(start 325.17715 -116.767864)
		(end 325.296276 -117.35435)
		(stroke
			(width 0.05715)
			(type default)
		)
		(layer "In2.Cu")
	)
	(gr_line
		(start 325.233792 -72.630792)
		(end 325.322438 -72.286368)
		(stroke
			(width 0.05715)
			(type default)
		)
		(layer "In2.Cu")
	)
	(gr_line
		(start 325.233792 -72.630792)
		(end 325.350886 -72.828912)
		(stroke
			(width 0.05715)
			(type default)
		)
		(layer "In2.Cu")
	)
	(gr_line
		(start 325.322438 -72.286368)
		(end 325.520558 -72.16902)
		(stroke
			(width 0.05715)
			(type default)
		)
		(layer "In2.Cu")
	)
	(gr_line
		(start 325.379588 -117.763036)
		(end 325.386192 -117.795548)
		(stroke
			(width 0.05715)
			(type default)
		)
		(layer "In2.Cu")
	)
	(gr_line
		(start 325.386192 -117.795548)
		(end 325.407528 -117.822726)
		(stroke
			(width 0.05715)
			(type default)
		)
		(layer "In2.Cu")
	)
	(gr_line
		(start 325.458582 -116.674392)
		(end 325.650606 -116.801392)
		(stroke
			(width 0.05715)
			(type default)
		)
		(layer "In2.Cu")
	)
	(gr_line
		(start 325.492872 -68.705984)
		(end 325.499984 -68.677536)
		(stroke
			(width 0.05715)
			(type default)
		)
		(layer "In2.Cu")
	)
	(gr_line
		(start 325.49338 -71.622158)
		(end 325.582026 -71.277734)
		(stroke
			(width 0.05715)
			(type default)
		)
		(layer "In2.Cu")
	)
	(gr_line
		(start 325.49338 -71.622158)
		(end 325.61022 -71.820532)
		(stroke
			(width 0.05715)
			(type default)
		)
		(layer "In2.Cu")
	)
	(gr_line
		(start 325.499984 -68.677536)
		(end 325.519288 -68.654168)
		(stroke
			(width 0.05715)
			(type default)
		)
		(layer "In2.Cu")
	)
	(gr_line
		(start 325.536052 -123.853702)
		(end 325.537576 -123.85802)
		(stroke
			(width 0.05715)
			(type default)
		)
		(layer "In2.Cu")
	)
	(gr_line
		(start 325.537576 -123.85802)
		(end 325.54037 -123.86183)
		(stroke
			(width 0.05715)
			(type default)
		)
		(layer "In2.Cu")
	)
	(gr_line
		(start 325.582026 -71.277734)
		(end 325.780146 -71.160894)
		(stroke
			(width 0.05715)
			(type default)
		)
		(layer "In2.Cu")
	)
	(gr_line
		(start 325.591932 -117.329204)
		(end 325.718932 -117.137434)
		(stroke
			(width 0.05715)
			(type default)
		)
		(layer "In2.Cu")
	)
	(gr_line
		(start 325.644764 -72.868536)
		(end 325.79691 -72.277224)
		(stroke
			(width 0.05715)
			(type default)
		)
		(layer "In2.Cu")
	)
	(gr_line
		(start 325.650606 -116.801392)
		(end 325.718932 -117.137434)
		(stroke
			(width 0.05715)
			(type default)
		)
		(layer "In2.Cu")
	)
	(gr_line
		(start 325.904606 -71.858886)
		(end 326.056244 -71.269098)
		(stroke
			(width 0.05715)
			(type default)
		)
		(layer "In2.Cu")
	)
	(gr_line
		(start 325.94677 -119.361458)
		(end 325.950072 -119.36603)
		(stroke
			(width 0.05715)
			(type default)
		)
		(layer "In2.Cu")
	)
	(gr_line
		(start 325.950072 -119.36603)
		(end 325.951596 -119.370856)
		(stroke
			(width 0.05715)
			(type default)
		)
		(layer "In2.Cu")
	)
	(gr_line
		(start 326.130412 -123.134882)
		(end 326.131936 -123.1392)
		(stroke
			(width 0.05715)
			(type default)
		)
		(layer "In2.Cu")
	)
	(gr_line
		(start 326.131936 -123.1392)
		(end 326.13473 -123.14301)
		(stroke
			(width 0.05715)
			(type default)
		)
		(layer "In2.Cu")
	)
	(gr_line
		(start 326.203056 -117.207792)
		(end 326.20712 -117.223286)
		(stroke
			(width 0.05715)
			(type default)
		)
		(layer "In2.Cu")
	)
	(gr_line
		(start 326.20712 -117.223286)
		(end 326.216264 -117.23624)
		(stroke
			(width 0.05715)
			(type default)
		)
		(layer "In2.Cu")
	)
	(gr_line
		(start 326.383396 -68.825872)
		(end 326.390762 -68.797678)
		(stroke
			(width 0.05715)
			(type default)
		)
		(layer "In2.Cu")
	)
	(gr_line
		(start 326.390762 -68.797678)
		(end 326.409558 -68.77558)
		(stroke
			(width 0.05715)
			(type default)
		)
		(layer "In2.Cu")
	)
	(gr_line
		(start 326.439276 -62.265306)
		(end 326.457564 -62.243462)
		(stroke
			(width 0.05715)
			(type default)
		)
		(layer "In2.Cu")
	)
	(gr_line
		(start 326.447404 -71.92645)
		(end 326.53605 -71.582026)
		(stroke
			(width 0.05715)
			(type default)
		)
		(layer "In2.Cu")
	)
	(gr_line
		(start 326.447404 -71.92645)
		(end 326.564498 -72.124824)
		(stroke
			(width 0.05715)
			(type default)
		)
		(layer "In2.Cu")
	)
	(gr_line
		(start 326.457564 -62.243462)
		(end 326.483218 -62.23127)
		(stroke
			(width 0.05715)
			(type default)
		)
		(layer "In2.Cu")
	)
	(gr_line
		(start 326.463406 -75.980036)
		(end 326.46874 -76.007468)
		(stroke
			(width 0.05715)
			(type default)
		)
		(layer "In2.Cu")
	)
	(gr_line
		(start 326.463406 -75.980036)
		(end 326.468994 -76.00823)
		(stroke
			(width 0.05715)
			(type default)
		)
		(layer "In2.Cu")
	)
	(gr_line
		(start 326.463406 -75.980036)
		(end 326.470264 -75.95362)
		(stroke
			(width 0.05715)
			(type default)
		)
		(layer "In2.Cu")
	)
	(gr_line
		(start 326.463406 -75.980036)
		(end 326.470518 -75.952858)
		(stroke
			(width 0.05715)
			(type default)
		)
		(layer "In2.Cu")
	)
	(gr_line
		(start 326.53605 -71.582026)
		(end 326.73417 -71.465186)
		(stroke
			(width 0.05715)
			(type default)
		)
		(layer "In2.Cu")
	)
	(gr_line
		(start 326.575166 -63.222886)
		(end 326.593454 -63.201042)
		(stroke
			(width 0.05715)
			(type default)
		)
		(layer "In2.Cu")
	)
	(gr_line
		(start 326.593454 -63.201042)
		(end 326.619108 -63.18885)
		(stroke
			(width 0.05715)
			(type default)
		)
		(layer "In2.Cu")
	)
	(gr_line
		(start 326.706992 -70.917816)
		(end 326.795638 -70.573392)
		(stroke
			(width 0.05715)
			(type default)
		)
		(layer "In2.Cu")
	)
	(gr_line
		(start 326.706992 -70.917816)
		(end 326.823832 -71.11619)
		(stroke
			(width 0.05715)
			(type default)
		)
		(layer "In2.Cu")
	)
	(gr_line
		(start 326.7202 -123.945396)
		(end 326.758554 -123.997974)
		(stroke
			(width 0.05715)
			(type default)
		)
		(layer "In2.Cu")
	)
	(gr_line
		(start 326.726804 -125.487684)
		(end 326.765158 -125.540262)
		(stroke
			(width 0.05715)
			(type default)
		)
		(layer "In2.Cu")
	)
	(gr_line
		(start 326.758554 -123.997974)
		(end 326.821038 -124.014738)
		(stroke
			(width 0.05715)
			(type default)
		)
		(layer "In2.Cu")
	)
	(gr_line
		(start 326.765158 -125.540262)
		(end 326.827642 -125.557026)
		(stroke
			(width 0.05715)
			(type default)
		)
		(layer "In2.Cu")
	)
	(gr_line
		(start 326.795638 -70.573392)
		(end 326.993758 -70.456552)
		(stroke
			(width 0.05715)
			(type default)
		)
		(layer "In2.Cu")
	)
	(gr_line
		(start 326.804782 -122.685302)
		(end 326.806306 -122.68962)
		(stroke
			(width 0.05715)
			(type default)
		)
		(layer "In2.Cu")
	)
	(gr_line
		(start 326.806306 -122.68962)
		(end 326.8091 -122.69343)
		(stroke
			(width 0.05715)
			(type default)
		)
		(layer "In2.Cu")
	)
	(gr_line
		(start 326.823324 -63.917576)
		(end 326.841612 -63.895732)
		(stroke
			(width 0.05715)
			(type default)
		)
		(layer "In2.Cu")
	)
	(gr_line
		(start 326.841612 -63.895732)
		(end 326.867266 -63.88354)
		(stroke
			(width 0.05715)
			(type default)
		)
		(layer "In2.Cu")
	)
	(gr_line
		(start 326.858122 -72.166226)
		(end 327.011284 -71.571104)
		(stroke
			(width 0.05715)
			(type default)
		)
		(layer "In2.Cu")
	)
	(gr_line
		(start 326.966326 -69.909182)
		(end 327.054972 -69.565012)
		(stroke
			(width 0.05715)
			(type default)
		)
		(layer "In2.Cu")
	)
	(gr_line
		(start 326.966326 -69.909182)
		(end 327.08342 -70.107556)
		(stroke
			(width 0.05715)
			(type default)
		)
		(layer "In2.Cu")
	)
	(gr_line
		(start 327.054972 -69.565012)
		(end 327.253346 -69.447918)
		(stroke
			(width 0.05715)
			(type default)
		)
		(layer "In2.Cu")
	)
	(gr_line
		(start 327.117964 -71.156576)
		(end 327.270618 -70.563232)
		(stroke
			(width 0.05715)
			(type default)
		)
		(layer "In2.Cu")
	)
	(gr_line
		(start 327.173082 -64.532002)
		(end 327.19137 -64.510158)
		(stroke
			(width 0.05715)
			(type default)
		)
		(layer "In2.Cu")
	)
	(gr_line
		(start 327.19137 -64.510158)
		(end 327.217024 -64.497966)
		(stroke
			(width 0.05715)
			(type default)
		)
		(layer "In2.Cu")
	)
	(gr_line
		(start 327.259442 -110.325154)
		(end 327.28916 -110.33887)
		(stroke
			(width 0.05715)
			(type default)
		)
		(layer "In2.Cu")
	)
	(gr_line
		(start 327.275698 -123.332494)
		(end 327.31329 -123.38431)
		(stroke
			(width 0.05715)
			(type default)
		)
		(layer "In2.Cu")
	)
	(gr_line
		(start 327.281794 -76.84389)
		(end 327.287128 -76.871576)
		(stroke
			(width 0.05715)
			(type default)
		)
		(layer "In2.Cu")
	)
	(gr_line
		(start 327.281794 -76.84389)
		(end 327.287128 -76.871322)
		(stroke
			(width 0.05715)
			(type default)
		)
		(layer "In2.Cu")
	)
	(gr_line
		(start 327.281794 -76.84389)
		(end 327.288652 -76.817474)
		(stroke
			(width 0.05715)
			(type default)
		)
		(layer "In2.Cu")
	)
	(gr_line
		(start 327.281794 -76.84389)
		(end 327.288906 -76.816966)
		(stroke
			(width 0.05715)
			(type default)
		)
		(layer "In2.Cu")
	)
	(gr_line
		(start 327.287128 -76.871322)
		(end 327.287382 -76.872084)
		(stroke
			(width 0.05715)
			(type default)
		)
		(layer "In2.Cu")
	)
	(gr_line
		(start 327.28916 -110.33887)
		(end 327.309226 -110.36427)
		(stroke
			(width 0.05715)
			(type default)
		)
		(layer "In2.Cu")
	)
	(gr_line
		(start 327.31329 -123.38431)
		(end 327.375774 -123.401074)
		(stroke
			(width 0.05715)
			(type default)
		)
		(layer "In2.Cu")
	)
	(gr_line
		(start 327.377552 -70.147434)
		(end 327.530206 -69.554344)
		(stroke
			(width 0.05715)
			(type default)
		)
		(layer "In2.Cu")
	)
	(gr_line
		(start 327.435464 -68.748656)
		(end 327.44283 -68.720462)
		(stroke
			(width 0.05715)
			(type default)
		)
		(layer "In2.Cu")
	)
	(gr_line
		(start 327.44283 -68.720462)
		(end 327.461372 -68.69811)
		(stroke
			(width 0.05715)
			(type default)
		)
		(layer "In2.Cu")
	)
	(gr_line
		(start 327.524618 -65.152524)
		(end 327.542906 -65.13068)
		(stroke
			(width 0.05715)
			(type default)
		)
		(layer "In2.Cu")
	)
	(gr_line
		(start 327.542906 -65.13068)
		(end 327.56856 -65.118488)
		(stroke
			(width 0.05715)
			(type default)
		)
		(layer "In2.Cu")
	)
	(gr_line
		(start 327.58126 -71.642732)
		(end 327.730866 -71.062342)
		(stroke
			(width 0.05715)
			(type default)
		)
		(layer "In2.Cu")
	)
	(gr_line
		(start 327.581514 -71.64197)
		(end 327.730866 -71.062596)
		(stroke
			(width 0.05715)
			(type default)
		)
		(layer "In2.Cu")
	)
	(gr_line
		(start 327.660762 -82.04327)
		(end 327.663556 -82.05851)
		(stroke
			(width 0.05715)
			(type default)
		)
		(layer "In2.Cu")
	)
	(gr_line
		(start 327.663556 -82.05851)
		(end 327.672192 -82.07248)
		(stroke
			(width 0.05715)
			(type default)
		)
		(layer "In2.Cu")
	)
	(gr_line
		(start 327.763124 -79.280512)
		(end 327.879202 -79.866998)
		(stroke
			(width 0.05715)
			(type default)
		)
		(layer "In2.Cu")
	)
	(gr_line
		(start 327.763632 -79.281528)
		(end 327.878948 -79.866236)
		(stroke
			(width 0.05715)
			(type default)
		)
		(layer "In2.Cu")
	)
	(gr_line
		(start 327.817988 -111.010446)
		(end 327.83018 -111.02594)
		(stroke
			(width 0.05715)
			(type default)
		)
		(layer "In2.Cu")
	)
	(gr_line
		(start 327.83018 -111.02594)
		(end 327.835768 -111.045244)
		(stroke
			(width 0.05715)
			(type default)
		)
		(layer "In2.Cu")
	)
	(gr_line
		(start 327.834752 -70.65899)
		(end 327.984866 -70.076568)
		(stroke
			(width 0.05715)
			(type default)
		)
		(layer "In2.Cu")
	)
	(gr_line
		(start 327.83526 -70.65772)
		(end 327.984612 -70.078346)
		(stroke
			(width 0.05715)
			(type default)
		)
		(layer "In2.Cu")
	)
	(gr_line
		(start 327.85812 -71.749158)
		(end 328.05624 -71.632318)
		(stroke
			(width 0.05715)
			(type default)
		)
		(layer "In2.Cu")
	)
	(gr_line
		(start 327.899776 -82.437478)
		(end 328.223626 -82.956908)
		(stroke
			(width 0.05715)
			(type default)
		)
		(layer "In2.Cu")
	)
	(gr_line
		(start 327.901046 -82.438748)
		(end 328.222356 -82.95386)
		(stroke
			(width 0.05715)
			(type default)
		)
		(layer "In2.Cu")
	)
	(gr_line
		(start 327.942448 -109.71149)
		(end 327.9775 -109.727746)
		(stroke
			(width 0.05715)
			(type default)
		)
		(layer "In2.Cu")
	)
	(gr_line
		(start 327.95972 -80.275684)
		(end 328.075798 -80.862932)
		(stroke
			(width 0.05715)
			(type default)
		)
		(layer "In2.Cu")
	)
	(gr_line
		(start 327.960228 -80.2767)
		(end 328.075798 -80.862678)
		(stroke
			(width 0.05715)
			(type default)
		)
		(layer "In2.Cu")
	)
	(gr_line
		(start 327.9775 -109.727746)
		(end 327.999598 -109.758226)
		(stroke
			(width 0.05715)
			(type default)
		)
		(layer "In2.Cu")
	)
	(gr_line
		(start 328.017378 -65.656968)
		(end 328.035666 -65.635124)
		(stroke
			(width 0.05715)
			(type default)
		)
		(layer "In2.Cu")
	)
	(gr_line
		(start 328.024998 -71.10222)
		(end 328.141838 -71.30034)
		(stroke
			(width 0.05715)
			(type default)
		)
		(layer "In2.Cu")
	)
	(gr_line
		(start 328.035666 -65.635124)
		(end 328.06132 -65.622932)
		(stroke
			(width 0.05715)
			(type default)
		)
		(layer "In2.Cu")
	)
	(gr_line
		(start 328.045318 -79.188818)
		(end 328.23658 -79.316834)
		(stroke
			(width 0.05715)
			(type default)
		)
		(layer "In2.Cu")
	)
	(gr_line
		(start 328.05624 -71.632318)
		(end 328.141838 -71.30034)
		(stroke
			(width 0.05715)
			(type default)
		)
		(layer "In2.Cu")
	)
	(gr_line
		(start 328.088498 -69.674994)
		(end 328.238104 -69.094096)
		(stroke
			(width 0.05715)
			(type default)
		)
		(layer "In2.Cu")
	)
	(gr_line
		(start 328.088498 -69.67474)
		(end 328.238104 -69.09435)
		(stroke
			(width 0.05715)
			(type default)
		)
		(layer "In2.Cu")
	)
	(gr_line
		(start 328.111612 -70.765416)
		(end 328.309986 -70.648576)
		(stroke
			(width 0.05715)
			(type default)
		)
		(layer "In2.Cu")
	)
	(gr_line
		(start 328.131424 -82.251804)
		(end 328.355452 -82.30362)
		(stroke
			(width 0.05715)
			(type default)
		)
		(layer "In2.Cu")
	)
	(gr_line
		(start 328.149458 -76.262992)
		(end 328.1553 -76.292202)
		(stroke
			(width 0.05715)
			(type default)
		)
		(layer "In2.Cu")
	)
	(gr_line
		(start 328.149458 -76.262992)
		(end 328.156824 -76.234036)
		(stroke
			(width 0.05715)
			(type default)
		)
		(layer "In2.Cu")
	)
	(gr_line
		(start 328.149458 -76.262992)
		(end 328.157078 -76.233782)
		(stroke
			(width 0.05715)
			(type default)
		)
		(layer "In2.Cu")
	)
	(gr_line
		(start 328.156824 -81.273396)
		(end 328.160126 -81.289398)
		(stroke
			(width 0.05715)
			(type default)
		)
		(layer "In2.Cu")
	)
	(gr_line
		(start 328.156824 -76.234036)
		(end 328.157078 -76.23302)
		(stroke
			(width 0.05715)
			(type default)
		)
		(layer "In2.Cu")
	)
	(gr_line
		(start 328.157332 -81.274158)
		(end 328.160126 -81.289398)
		(stroke
			(width 0.05715)
			(type default)
		)
		(layer "In2.Cu")
	)
	(gr_line
		(start 328.160126 -81.289398)
		(end 328.168762 -81.303368)
		(stroke
			(width 0.05715)
			(type default)
		)
		(layer "In2.Cu")
	)
	(gr_line
		(start 328.174858 -79.844392)
		(end 328.303128 -79.65313)
		(stroke
			(width 0.05715)
			(type default)
		)
		(layer "In2.Cu")
	)
	(gr_line
		(start 328.225912 -117.097048)
		(end 328.235056 -117.135402)
		(stroke
			(width 0.05715)
			(type default)
		)
		(layer "In2.Cu")
	)
	(gr_line
		(start 328.225912 -117.097048)
		(end 328.237342 -117.057932)
		(stroke
			(width 0.05715)
			(type default)
		)
		(layer "In2.Cu")
	)
	(gr_line
		(start 328.23658 -79.316834)
		(end 328.303128 -79.65313)
		(stroke
			(width 0.05715)
			(type default)
		)
		(layer "In2.Cu")
	)
	(gr_line
		(start 328.242422 -80.18526)
		(end 328.43343 -80.31353)
		(stroke
			(width 0.05715)
			(type default)
		)
		(layer "In2.Cu")
	)
	(gr_line
		(start 328.27849 -70.118224)
		(end 328.395584 -70.316344)
		(stroke
			(width 0.05715)
			(type default)
		)
		(layer "In2.Cu")
	)
	(gr_line
		(start 328.309986 -70.648576)
		(end 328.395584 -70.316344)
		(stroke
			(width 0.05715)
			(type default)
		)
		(layer "In2.Cu")
	)
	(gr_line
		(start 328.342244 -68.69049)
		(end 328.34961 -68.662042)
		(stroke
			(width 0.05715)
			(type default)
		)
		(layer "In2.Cu")
	)
	(gr_line
		(start 328.34961 -68.662042)
		(end 328.36866 -68.639436)
		(stroke
			(width 0.05715)
			(type default)
		)
		(layer "In2.Cu")
	)
	(gr_line
		(start 328.355452 -82.30362)
		(end 328.543666 -82.605372)
		(stroke
			(width 0.05715)
			(type default)
		)
		(layer "In2.Cu")
	)
	(gr_line
		(start 328.365358 -69.781674)
		(end 328.563478 -69.66458)
		(stroke
			(width 0.05715)
			(type default)
		)
		(layer "In2.Cu")
	)
	(gr_line
		(start 328.371962 -80.841088)
		(end 328.499978 -80.649826)
		(stroke
			(width 0.05715)
			(type default)
		)
		(layer "In2.Cu")
	)
	(gr_line
		(start 328.376534 -108.913676)
		(end 328.392028 -108.920788)
		(stroke
			(width 0.05715)
			(type default)
		)
		(layer "In2.Cu")
	)
	(gr_line
		(start 328.392028 -108.920788)
		(end 328.40422 -108.93298)
		(stroke
			(width 0.05715)
			(type default)
		)
		(layer "In2.Cu")
	)
	(gr_line
		(start 328.43343 -80.31353)
		(end 328.499978 -80.649826)
		(stroke
			(width 0.05715)
			(type default)
		)
		(layer "In2.Cu")
	)
	(gr_line
		(start 328.450956 -83.32089)
		(end 328.774806 -83.839812)
		(stroke
			(width 0.05715)
			(type default)
		)
		(layer "In2.Cu")
	)
	(gr_line
		(start 328.452226 -83.322414)
		(end 328.774044 -83.838542)
		(stroke
			(width 0.05715)
			(type default)
		)
		(layer "In2.Cu")
	)
	(gr_line
		(start 328.49185 -82.829654)
		(end 328.543666 -82.605372)
		(stroke
			(width 0.05715)
			(type default)
		)
		(layer "In2.Cu")
	)
	(gr_line
		(start 328.532236 -69.134228)
		(end 328.649076 -69.332602)
		(stroke
			(width 0.05715)
			(type default)
		)
		(layer "In2.Cu")
	)
	(gr_line
		(start 328.53249 -78.202028)
		(end 328.64933 -78.792578)
		(stroke
			(width 0.05715)
			(type default)
		)
		(layer "In2.Cu")
	)
	(gr_line
		(start 328.532998 -78.203298)
		(end 328.64933 -78.791816)
		(stroke
			(width 0.05715)
			(type default)
		)
		(layer "In2.Cu")
	)
	(gr_line
		(start 328.53503 -110.49)
		(end 328.544428 -110.5027)
		(stroke
			(width 0.05715)
			(type default)
		)
		(layer "In2.Cu")
	)
	(gr_line
		(start 328.544428 -110.5027)
		(end 328.549 -110.51921)
		(stroke
			(width 0.05715)
			(type default)
		)
		(layer "In2.Cu")
	)
	(gr_line
		(start 328.563478 -69.66458)
		(end 328.649076 -69.332602)
		(stroke
			(width 0.05715)
			(type default)
		)
		(layer "In2.Cu")
	)
	(gr_line
		(start 328.59726 -120.623076)
		(end 328.60107 -120.62841)
		(stroke
			(width 0.05715)
			(type default)
		)
		(layer "In2.Cu")
	)
	(gr_line
		(start 328.60107 -120.62841)
		(end 328.60615 -120.632474)
		(stroke
			(width 0.05715)
			(type default)
		)
		(layer "In2.Cu")
	)
	(gr_line
		(start 328.65949 -66.13144)
		(end 328.686922 -66.099182)
		(stroke
			(width 0.05715)
			(type default)
		)
		(layer "In2.Cu")
	)
	(gr_line
		(start 328.682604 -83.13547)
		(end 328.906632 -83.187286)
		(stroke
			(width 0.05715)
			(type default)
		)
		(layer "In2.Cu")
	)
	(gr_line
		(start 328.68616 -119.036846)
		(end 328.7014 -119.1006)
		(stroke
			(width 0.05715)
			(type default)
		)
		(layer "In2.Cu")
	)
	(gr_line
		(start 328.686922 -66.099182)
		(end 328.727054 -66.084958)
		(stroke
			(width 0.05715)
			(type default)
		)
		(layer "In2.Cu")
	)
	(gr_line
		(start 328.7014 -119.1006)
		(end 328.753216 -119.140986)
		(stroke
			(width 0.05715)
			(type default)
		)
		(layer "In2.Cu")
	)
	(gr_line
		(start 328.729594 -79.19847)
		(end 328.845926 -79.786734)
		(stroke
			(width 0.05715)
			(type default)
		)
		(layer "In2.Cu")
	)
	(gr_line
		(start 328.730356 -79.200248)
		(end 328.845926 -79.785718)
		(stroke
			(width 0.05715)
			(type default)
		)
		(layer "In2.Cu")
	)
	(gr_line
		(start 328.752454 -115.303554)
		(end 328.752708 -115.303554)
		(stroke
			(width 0.05715)
			(type default)
		)
		(layer "In2.Cu")
	)
	(gr_line
		(start 328.79665 -82.309716)
		(end 329.113896 -82.818478)
		(stroke
			(width 0.05715)
			(type default)
		)
		(layer "In2.Cu")
	)
	(gr_line
		(start 328.796904 -82.310224)
		(end 329.113896 -82.818478)
		(stroke
			(width 0.05715)
			(type default)
		)
		(layer "In2.Cu")
	)
	(gr_line
		(start 328.810366 -73.711562)
		(end 328.960988 -73.12914)
		(stroke
			(width 0.05715)
			(type default)
		)
		(layer "In2.Cu")
	)
	(gr_line
		(start 328.81062 -73.710546)
		(end 328.960734 -73.130664)
		(stroke
			(width 0.05715)
			(type default)
		)
		(layer "In2.Cu")
	)
	(gr_line
		(start 328.815446 -78.112112)
		(end 329.006708 -78.240382)
		(stroke
			(width 0.05715)
			(type default)
		)
		(layer "In2.Cu")
	)
	(gr_line
		(start 328.906632 -83.187286)
		(end 329.094846 -83.489038)
		(stroke
			(width 0.05715)
			(type default)
		)
		(layer "In2.Cu")
	)
	(gr_line
		(start 328.944986 -78.76794)
		(end 329.073002 -78.576678)
		(stroke
			(width 0.05715)
			(type default)
		)
		(layer "In2.Cu")
	)
	(gr_line
		(start 329.001374 -84.20354)
		(end 329.325986 -84.723732)
		(stroke
			(width 0.05715)
			(type default)
		)
		(layer "In2.Cu")
	)
	(gr_line
		(start 329.003152 -84.205572)
		(end 329.325478 -84.722208)
		(stroke
			(width 0.05715)
			(type default)
		)
		(layer "In2.Cu")
	)
	(gr_line
		(start 329.006708 -78.240382)
		(end 329.073002 -78.576678)
		(stroke
			(width 0.05715)
			(type default)
		)
		(layer "In2.Cu")
	)
	(gr_line
		(start 329.012296 -79.108808)
		(end 329.203558 -79.237078)
		(stroke
			(width 0.05715)
			(type default)
		)
		(layer "In2.Cu")
	)
	(gr_line
		(start 329.02779 -80.706976)
		(end 329.031092 -80.722978)
		(stroke
			(width 0.05715)
			(type default)
		)
		(layer "In2.Cu")
	)
	(gr_line
		(start 329.028044 -82.124296)
		(end 329.25258 -82.176366)
		(stroke
			(width 0.05715)
			(type default)
		)
		(layer "In2.Cu")
	)
	(gr_line
		(start 329.028298 -80.707738)
		(end 329.031092 -80.722978)
		(stroke
			(width 0.05715)
			(type default)
		)
		(layer "In2.Cu")
	)
	(gr_line
		(start 329.031092 -80.722978)
		(end 329.039728 -80.736948)
		(stroke
			(width 0.05715)
			(type default)
		)
		(layer "In2.Cu")
	)
	(gr_line
		(start 329.03287 -115.38585)
		(end 329.033124 -115.38585)
		(stroke
			(width 0.05715)
			(type default)
		)
		(layer "In2.Cu")
	)
	(gr_line
		(start 329.042776 -117.190774)
		(end 329.050396 -117.223032)
		(stroke
			(width 0.05715)
			(type default)
		)
		(layer "In2.Cu")
	)
	(gr_line
		(start 329.042776 -117.190774)
		(end 329.050904 -117.15877)
		(stroke
			(width 0.05715)
			(type default)
		)
		(layer "In2.Cu")
	)
	(gr_line
		(start 329.04303 -83.71332)
		(end 329.094846 -83.489038)
		(stroke
			(width 0.05715)
			(type default)
		)
		(layer "In2.Cu")
	)
	(gr_line
		(start 329.043792 -115.349274)
		(end 329.057 -115.30457)
		(stroke
			(width 0.05715)
			(type default)
		)
		(layer "In2.Cu")
	)
	(gr_line
		(start 329.044046 -115.259358)
		(end 329.057 -115.30457)
		(stroke
			(width 0.05715)
			(type default)
		)
		(layer "In2.Cu")
	)
	(gr_line
		(start 329.057 -40.63238)
		(end 329.414632 -40.990012)
		(stroke
			(width 0.0635)
			(type default)
		)
		(layer "In2.Cu")
	)
	(gr_line
		(start 329.065382 -72.72655)
		(end 329.21575 -72.146668)
		(stroke
			(width 0.05715)
			(type default)
		)
		(layer "In2.Cu")
	)
	(gr_line
		(start 329.065636 -72.726296)
		(end 329.215496 -72.147176)
		(stroke
			(width 0.05715)
			(type default)
		)
		(layer "In2.Cu")
	)
	(gr_line
		(start 329.087226 -73.818242)
		(end 329.2856 -73.701402)
		(stroke
			(width 0.05715)
			(type default)
		)
		(layer "In2.Cu")
	)
	(gr_line
		(start 329.1205 -69.702172)
		(end 329.145392 -69.605906)
		(stroke
			(width 0.05715)
			(type default)
		)
		(layer "In2.Cu")
	)
	(gr_line
		(start 329.14209 -79.764636)
		(end 329.270106 -79.573374)
		(stroke
			(width 0.05715)
			(type default)
		)
		(layer "In2.Cu")
	)
	(gr_line
		(start 329.145392 -69.605906)
		(end 329.235562 -69.563488)
		(stroke
			(width 0.05715)
			(type default)
		)
		(layer "In2.Cu")
	)
	(gr_line
		(start 329.170538 -66.650362)
		(end 329.197208 -66.618358)
		(stroke
			(width 0.05715)
			(type default)
		)
		(layer "In2.Cu")
	)
	(gr_line
		(start 329.185524 -76.113132)
		(end 329.191366 -76.142342)
		(stroke
			(width 0.05715)
			(type default)
		)
		(layer "In2.Cu")
	)
	(gr_line
		(start 329.185524 -76.113132)
		(end 329.19289 -76.084176)
		(stroke
			(width 0.05715)
			(type default)
		)
		(layer "In2.Cu")
	)
	(gr_line
		(start 329.185524 -76.113132)
		(end 329.193144 -76.083922)
		(stroke
			(width 0.05715)
			(type default)
		)
		(layer "In2.Cu")
	)
	(gr_line
		(start 329.19289 -76.084176)
		(end 329.193144 -76.08316)
		(stroke
			(width 0.05715)
			(type default)
		)
		(layer "In2.Cu")
	)
	(gr_line
		(start 329.197208 -66.618358)
		(end 329.23607 -66.604642)
		(stroke
			(width 0.05715)
			(type default)
		)
		(layer "In2.Cu")
	)
	(gr_line
		(start 329.203558 -79.237078)
		(end 329.270106 -79.573374)
		(stroke
			(width 0.05715)
			(type default)
		)
		(layer "In2.Cu")
	)
	(gr_line
		(start 329.233784 -84.018882)
		(end 329.457812 -84.070952)
		(stroke
			(width 0.05715)
			(type default)
		)
		(layer "In2.Cu")
	)
	(gr_line
		(start 329.25258 -82.176366)
		(end 329.433936 -82.46745)
		(stroke
			(width 0.05715)
			(type default)
		)
		(layer "In2.Cu")
	)
	(gr_line
		(start 329.254866 -73.17105)
		(end 329.371452 -73.369678)
		(stroke
			(width 0.05715)
			(type default)
		)
		(layer "In2.Cu")
	)
	(gr_line
		(start 329.2856 -73.701402)
		(end 329.371452 -73.369678)
		(stroke
			(width 0.05715)
			(type default)
		)
		(layer "In2.Cu")
	)
	(gr_line
		(start 329.31989 -71.743824)
		(end 329.470512 -71.16318)
		(stroke
			(width 0.05715)
			(type default)
		)
		(layer "In2.Cu")
	)
	(gr_line
		(start 329.320652 -71.741792)
		(end 329.470004 -71.16572)
		(stroke
			(width 0.05715)
			(type default)
		)
		(layer "In2.Cu")
	)
	(gr_line
		(start 329.334368 -83.171792)
		(end 329.651868 -83.681062)
		(stroke
			(width 0.05715)
			(type default)
		)
		(layer "In2.Cu")
	)
	(gr_line
		(start 329.334622 -83.1723)
		(end 329.651868 -83.681062)
		(stroke
			(width 0.05715)
			(type default)
		)
		(layer "In2.Cu")
	)
	(gr_line
		(start 329.341988 -72.8345)
		(end 329.540362 -72.717914)
		(stroke
			(width 0.05715)
			(type default)
		)
		(layer "In2.Cu")
	)
	(gr_line
		(start 329.38212 -82.691732)
		(end 329.433936 -82.46745)
		(stroke
			(width 0.05715)
			(type default)
		)
		(layer "In2.Cu")
	)
	(gr_line
		(start 329.382374 -118.623334)
		(end 329.392788 -118.667022)
		(stroke
			(width 0.05715)
			(type default)
		)
		(layer "In2.Cu")
	)
	(gr_line
		(start 329.392788 -118.667022)
		(end 329.424538 -118.698772)
		(stroke
			(width 0.05715)
			(type default)
		)
		(layer "In2.Cu")
	)
	(gr_line
		(start 329.393042 -41.183052)
		(end 329.438 -41.138094)
		(stroke
			(width 0.0635)
			(type default)
		)
		(layer "In2.Cu")
	)
	(gr_line
		(start 329.418188 -40.993568)
		(end 329.438 -41.01338)
		(stroke
			(width 0.0635)
			(type default)
		)
		(layer "In2.Cu")
	)
	(gr_line
		(start 329.438 -41.01338)
		(end 329.438 -41.138094)
		(stroke
			(width 0.0635)
			(type default)
		)
		(layer "In2.Cu")
	)
	(gr_line
		(start 329.457812 -84.070952)
		(end 329.646026 -84.372704)
		(stroke
			(width 0.05715)
			(type default)
		)
		(layer "In2.Cu")
	)
	(gr_line
		(start 329.509628 -72.187816)
		(end 329.626214 -72.385936)
		(stroke
			(width 0.05715)
			(type default)
		)
		(layer "In2.Cu")
	)
	(gr_line
		(start 329.540362 -72.717914)
		(end 329.626214 -72.385936)
		(stroke
			(width 0.05715)
			(type default)
		)
		(layer "In2.Cu")
	)
	(gr_line
		(start 329.542648 -122.364246)
		(end 329.555094 -122.374152)
		(stroke
			(width 0.05715)
			(type default)
		)
		(layer "In2.Cu")
	)
	(gr_line
		(start 329.552554 -85.087206)
		(end 329.877928 -85.608922)
		(stroke
			(width 0.05715)
			(type default)
		)
		(layer "In2.Cu")
	)
	(gr_line
		(start 329.553824 -85.08873)
		(end 329.877166 -85.60689)
		(stroke
			(width 0.05715)
			(type default)
		)
		(layer "In2.Cu")
	)
	(gr_line
		(start 329.555094 -122.374152)
		(end 329.571096 -122.378978)
		(stroke
			(width 0.05715)
			(type default)
		)
		(layer "In2.Cu")
	)
	(gr_line
		(start 329.565762 -82.986372)
		(end 329.790298 -83.038442)
		(stroke
			(width 0.05715)
			(type default)
		)
		(layer "In2.Cu")
	)
	(gr_line
		(start 329.59421 -84.596732)
		(end 329.646026 -84.372704)
		(stroke
			(width 0.05715)
			(type default)
		)
		(layer "In2.Cu")
	)
	(gr_line
		(start 329.59675 -71.851012)
		(end 329.795124 -71.734426)
		(stroke
			(width 0.05715)
			(type default)
		)
		(layer "In2.Cu")
	)
	(gr_line
		(start 329.605894 -67.170046)
		(end 329.632818 -67.138042)
		(stroke
			(width 0.05715)
			(type default)
		)
		(layer "In2.Cu")
	)
	(gr_line
		(start 329.632818 -67.138042)
		(end 329.672188 -67.124072)
		(stroke
			(width 0.05715)
			(type default)
		)
		(layer "In2.Cu")
	)
	(gr_line
		(start 329.6666 -41.10101)
		(end 329.6666 -41.268904)
		(stroke
			(width 0.0635)
			(type default)
		)
		(layer "In2.Cu")
	)
	(gr_line
		(start 329.6666 -41.10101)
		(end 329.774042 -40.993568)
		(stroke
			(width 0.0635)
			(type default)
		)
		(layer "In2.Cu")
	)
	(gr_line
		(start 329.737974 -70.130924)
		(end 329.762866 -70.035166)
		(stroke
			(width 0.05715)
			(type default)
		)
		(layer "In2.Cu")
	)
	(gr_line
		(start 329.737974 -70.13067)
		(end 329.762866 -70.035166)
		(stroke
			(width 0.05715)
			(type default)
		)
		(layer "In2.Cu")
	)
	(gr_line
		(start 329.762866 -70.035166)
		(end 329.851512 -69.993764)
		(stroke
			(width 0.05715)
			(type default)
		)
		(layer "In2.Cu")
	)
	(gr_line
		(start 329.76439 -71.204328)
		(end 329.880976 -71.402448)
		(stroke
			(width 0.05715)
			(type default)
		)
		(layer "In2.Cu")
	)
	(gr_line
		(start 329.777598 -40.990012)
		(end 330.176378 -40.591232)
		(stroke
			(width 0.0635)
			(type default)
		)
		(layer "In2.Cu")
	)
	(gr_line
		(start 329.784964 -84.902548)
		(end 330.008992 -84.954364)
		(stroke
			(width 0.05715)
			(type default)
		)
		(layer "In2.Cu")
	)
	(gr_line
		(start 329.788774 -121.550938)
		(end 329.803506 -121.562622)
		(stroke
			(width 0.05715)
			(type default)
		)
		(layer "In2.Cu")
	)
	(gr_line
		(start 329.790298 -83.038442)
		(end 329.971654 -83.329526)
		(stroke
			(width 0.05715)
			(type default)
		)
		(layer "In2.Cu")
	)
	(gr_line
		(start 329.795124 -71.734426)
		(end 329.880976 -71.402448)
		(stroke
			(width 0.05715)
			(type default)
		)
		(layer "In2.Cu")
	)
	(gr_line
		(start 329.803506 -121.562622)
		(end 329.822048 -121.567956)
		(stroke
			(width 0.05715)
			(type default)
		)
		(layer "In2.Cu")
	)
	(gr_line
		(start 329.818492 -115.230148)
		(end 329.828652 -115.26774)
		(stroke
			(width 0.05715)
			(type default)
		)
		(layer "In2.Cu")
	)
	(gr_line
		(start 329.819254 -115.305332)
		(end 329.828652 -115.26774)
		(stroke
			(width 0.05715)
			(type default)
		)
		(layer "In2.Cu")
	)
	(gr_line
		(start 329.87107 -84.032852)
		(end 330.188824 -84.542122)
		(stroke
			(width 0.05715)
			(type default)
		)
		(layer "In2.Cu")
	)
	(gr_line
		(start 329.87107 -84.032852)
		(end 330.189332 -84.543138)
		(stroke
			(width 0.05715)
			(type default)
		)
		(layer "In2.Cu")
	)
	(gr_line
		(start 329.879452 -119.153432)
		(end 329.912218 -119.186198)
		(stroke
			(width 0.05715)
			(type default)
		)
		(layer "In2.Cu")
	)
	(gr_line
		(start 329.912218 -119.186198)
		(end 329.957176 -119.196612)
		(stroke
			(width 0.05715)
			(type default)
		)
		(layer "In2.Cu")
	)
	(gr_line
		(start 329.917552 -61.63818)
		(end 329.941174 -61.627004)
		(stroke
			(width 0.05715)
			(type default)
		)
		(layer "In2.Cu")
	)
	(gr_line
		(start 329.919838 -83.553808)
		(end 329.971654 -83.329526)
		(stroke
			(width 0.05715)
			(type default)
		)
		(layer "In2.Cu")
	)
	(gr_line
		(start 329.9206 -97.7646)
		(end 329.924156 -97.783396)
		(stroke
			(width 0.05715)
			(type default)
		)
		(layer "In2.Cu")
	)
	(gr_line
		(start 329.9206 -97.7646)
		(end 329.924156 -97.745804)
		(stroke
			(width 0.05715)
			(type default)
		)
		(layer "In2.Cu")
	)
	(gr_line
		(start 329.9206 -97.7646)
		(end 329.92441 -97.784158)
		(stroke
			(width 0.05715)
			(type default)
		)
		(layer "In2.Cu")
	)
	(gr_line
		(start 329.9206 -97.7646)
		(end 329.92441 -97.745042)
		(stroke
			(width 0.05715)
			(type default)
		)
		(layer "In2.Cu")
	)
	(gr_line
		(start 329.969876 -80.081882)
		(end 329.97267 -80.097122)
		(stroke
			(width 0.05715)
			(type default)
		)
		(layer "In2.Cu")
	)
	(gr_line
		(start 329.97267 -80.097122)
		(end 329.981306 -80.111092)
		(stroke
			(width 0.05715)
			(type default)
		)
		(layer "In2.Cu")
	)
	(gr_line
		(start 330.008992 -84.954364)
		(end 330.197206 -85.256116)
		(stroke
			(width 0.05715)
			(type default)
		)
		(layer "In2.Cu")
	)
	(gr_line
		(start 330.010008 -91.48064)
		(end 330.013564 -91.499436)
		(stroke
			(width 0.05715)
			(type default)
		)
		(layer "In2.Cu")
	)
	(gr_line
		(start 330.010008 -91.48064)
		(end 330.013564 -91.461844)
		(stroke
			(width 0.05715)
			(type default)
		)
		(layer "In2.Cu")
	)
	(gr_line
		(start 330.010008 -91.48064)
		(end 330.013818 -91.500198)
		(stroke
			(width 0.05715)
			(type default)
		)
		(layer "In2.Cu")
	)
	(gr_line
		(start 330.010008 -91.48064)
		(end 330.013818 -91.461082)
		(stroke
			(width 0.05715)
			(type default)
		)
		(layer "In2.Cu")
	)
	(gr_line
		(start 330.016866 -104.171242)
		(end 330.02093 -104.149906)
		(stroke
			(width 0.05715)
			(type default)
		)
		(layer "In2.Cu")
	)
	(gr_line
		(start 330.016866 -104.171242)
		(end 330.021184 -104.149144)
		(stroke
			(width 0.05715)
			(type default)
		)
		(layer "In2.Cu")
	)
	(gr_line
		(start 330.016866 -104.171242)
		(end 330.021438 -104.192324)
		(stroke
			(width 0.05715)
			(type default)
		)
		(layer "In2.Cu")
	)
	(gr_line
		(start 330.016866 -104.171242)
		(end 330.021438 -104.191816)
		(stroke
			(width 0.05715)
			(type default)
		)
		(layer "In2.Cu")
	)
	(gr_line
		(start 330.101194 -66.97218)
		(end 330.163932 -66.949828)
		(stroke
			(width 0.05715)
			(type default)
		)
		(layer "In2.Cu")
	)
	(gr_line
		(start 330.102972 -85.969602)
		(end 330.428854 -86.491826)
		(stroke
			(width 0.05715)
			(type default)
		)
		(layer "In2.Cu")
	)
	(gr_line
		(start 330.10348 -83.848448)
		(end 330.327762 -83.900518)
		(stroke
			(width 0.05715)
			(type default)
		)
		(layer "In2.Cu")
	)
	(gr_line
		(start 330.103988 -85.970872)
		(end 330.428092 -86.490302)
		(stroke
			(width 0.05715)
			(type default)
		)
		(layer "In2.Cu")
	)
	(gr_line
		(start 330.14539 -85.480398)
		(end 330.197206 -85.256116)
		(stroke
			(width 0.05715)
			(type default)
		)
		(layer "In2.Cu")
	)
	(gr_line
		(start 330.15682 -66.277744)
		(end 330.220574 -66.255138)
		(stroke
			(width 0.05715)
			(type default)
		)
		(layer "In2.Cu")
	)
	(gr_line
		(start 330.163932 -66.949828)
		(end 330.227686 -66.972688)
		(stroke
			(width 0.05715)
			(type default)
		)
		(layer "In2.Cu")
	)
	(gr_line
		(start 330.178664 -65.570608)
		(end 330.242672 -65.548002)
		(stroke
			(width 0.05715)
			(type default)
		)
		(layer "In2.Cu")
	)
	(gr_line
		(start 330.208636 -80.475582)
		(end 330.532232 -80.99425)
		(stroke
			(width 0.05715)
			(type default)
		)
		(layer "In2.Cu")
	)
	(gr_line
		(start 330.208636 -80.475582)
		(end 330.53274 -80.995266)
		(stroke
			(width 0.05715)
			(type default)
		)
		(layer "In2.Cu")
	)
	(gr_line
		(start 330.220574 -66.255138)
		(end 330.283566 -66.277744)
		(stroke
			(width 0.05715)
			(type default)
		)
		(layer "In2.Cu")
	)
	(gr_line
		(start 330.242672 -65.548002)
		(end 330.304902 -65.570608)
		(stroke
			(width 0.05715)
			(type default)
		)
		(layer "In2.Cu")
	)
	(gr_line
		(start 330.292964 -62.27318)
		(end 330.316586 -62.262004)
		(stroke
			(width 0.05715)
			(type default)
		)
		(layer "In2.Cu")
	)
	(gr_line
		(start 330.327762 -83.900518)
		(end 330.509372 -84.191602)
		(stroke
			(width 0.05715)
			(type default)
		)
		(layer "In2.Cu")
	)
	(gr_line
		(start 330.33589 -85.78596)
		(end 330.560172 -85.837776)
		(stroke
			(width 0.05715)
			(type default)
		)
		(layer "In2.Cu")
	)
	(gr_line
		(start 330.361798 -120.39092)
		(end 330.368656 -120.396254)
		(stroke
			(width 0.05715)
			(type default)
		)
		(layer "In2.Cu")
	)
	(gr_line
		(start 330.36637 -122.61469)
		(end 330.939648 -122.78487)
		(stroke
			(width 0.05715)
			(type default)
		)
		(layer "In2.Cu")
	)
	(gr_line
		(start 330.366878 -126.503938)
		(end 330.398374 -126.51232)
		(stroke
			(width 0.05715)
			(type default)
		)
		(layer "In2.Cu")
	)
	(gr_line
		(start 330.368656 -120.396254)
		(end 330.376784 -120.399048)
		(stroke
			(width 0.05715)
			(type default)
		)
		(layer "In2.Cu")
	)
	(gr_line
		(start 330.398374 -126.51232)
		(end 330.430632 -126.505462)
		(stroke
			(width 0.05715)
			(type default)
		)
		(layer "In2.Cu")
	)
	(gr_line
		(start 330.407264 -84.892896)
		(end 330.727558 -85.406484)
		(stroke
			(width 0.05715)
			(type default)
		)
		(layer "In2.Cu")
	)
	(gr_line
		(start 330.408534 -84.89442)
		(end 330.726796 -85.404706)
		(stroke
			(width 0.05715)
			(type default)
		)
		(layer "In2.Cu")
	)
	(gr_line
		(start 330.416154 -122.322082)
		(end 330.618338 -122.212354)
		(stroke
			(width 0.05715)
			(type default)
		)
		(layer "In2.Cu")
	)
	(gr_line
		(start 330.440538 -80.290416)
		(end 330.664566 -80.342232)
		(stroke
			(width 0.05715)
			(type default)
		)
		(layer "In2.Cu")
	)
	(gr_line
		(start 330.457302 -84.415884)
		(end 330.509372 -84.191602)
		(stroke
			(width 0.05715)
			(type default)
		)
		(layer "In2.Cu")
	)
	(gr_line
		(start 330.560172 -85.837776)
		(end 330.748386 -86.139528)
		(stroke
			(width 0.05715)
			(type default)
		)
		(layer "In2.Cu")
	)
	(gr_line
		(start 330.599542 -62.90818)
		(end 330.623164 -62.897004)
		(stroke
			(width 0.05715)
			(type default)
		)
		(layer "In2.Cu")
	)
	(gr_line
		(start 330.618338 -122.212354)
		(end 330.947014 -122.30989)
		(stroke
			(width 0.05715)
			(type default)
		)
		(layer "In2.Cu")
	)
	(gr_line
		(start 330.640944 -84.710524)
		(end 330.86548 -84.762594)
		(stroke
			(width 0.05715)
			(type default)
		)
		(layer "In2.Cu")
	)
	(gr_line
		(start 330.664566 -80.342232)
		(end 330.85278 -80.643984)
		(stroke
			(width 0.05715)
			(type default)
		)
		(layer "In2.Cu")
	)
	(gr_line
		(start 330.665836 -70.398132)
		(end 330.690728 -70.302628)
		(stroke
			(width 0.05715)
			(type default)
		)
		(layer "In2.Cu")
	)
	(gr_line
		(start 330.666344 -70.397624)
		(end 330.690728 -70.302628)
		(stroke
			(width 0.05715)
			(type default)
		)
		(layer "In2.Cu")
	)
	(gr_line
		(start 330.684124 -107.286298)
		(end 330.698602 -107.353354)
		(stroke
			(width 0.05715)
			(type default)
		)
		(layer "In2.Cu")
	)
	(gr_line
		(start 330.690728 -70.302628)
		(end 330.779374 -70.261226)
		(stroke
			(width 0.05715)
			(type default)
		)
		(layer "In2.Cu")
	)
	(gr_line
		(start 330.69657 -86.364064)
		(end 330.748386 -86.139528)
		(stroke
			(width 0.05715)
			(type default)
		)
		(layer "In2.Cu")
	)
	(gr_line
		(start 330.698602 -107.353354)
		(end 330.752196 -107.394756)
		(stroke
			(width 0.05715)
			(type default)
		)
		(layer "In2.Cu")
	)
	(gr_line
		(start 330.73213 -112.741202)
		(end 330.791058 -112.80013)
		(stroke
			(width 0.05715)
			(type default)
		)
		(layer "In2.Cu")
	)
	(gr_line
		(start 330.746862 -97.862136)
		(end 330.750418 -97.880932)
		(stroke
			(width 0.05715)
			(type default)
		)
		(layer "In2.Cu")
	)
	(gr_line
		(start 330.746862 -97.862136)
		(end 330.750418 -97.84334)
		(stroke
			(width 0.05715)
			(type default)
		)
		(layer "In2.Cu")
	)
	(gr_line
		(start 330.746862 -97.862136)
		(end 330.750672 -97.881694)
		(stroke
			(width 0.05715)
			(type default)
		)
		(layer "In2.Cu")
	)
	(gr_line
		(start 330.746862 -97.862136)
		(end 330.750672 -97.842578)
		(stroke
			(width 0.05715)
			(type default)
		)
		(layer "In2.Cu")
	)
	(gr_line
		(start 330.759816 -81.359248)
		(end 331.08392 -81.878932)
		(stroke
			(width 0.05715)
			(type default)
		)
		(layer "In2.Cu")
	)
	(gr_line
		(start 330.760578 -81.36001)
		(end 331.083666 -81.87817)
		(stroke
			(width 0.05715)
			(type default)
		)
		(layer "In2.Cu")
	)
	(gr_line
		(start 330.800964 -80.868266)
		(end 330.85278 -80.643984)
		(stroke
			(width 0.05715)
			(type default)
		)
		(layer "In2.Cu")
	)
	(gr_line
		(start 330.807314 -66.061082)
		(end 331.367638 -66.26225)
		(stroke
			(width 0.05715)
			(type default)
		)
		(layer "In2.Cu")
	)
	(gr_line
		(start 330.827126 -91.417394)
		(end 330.830682 -91.43619)
		(stroke
			(width 0.05715)
			(type default)
		)
		(layer "In2.Cu")
	)
	(gr_line
		(start 330.827126 -91.417394)
		(end 330.830682 -91.398598)
		(stroke
			(width 0.05715)
			(type default)
		)
		(layer "In2.Cu")
	)
	(gr_line
		(start 330.827126 -91.417394)
		(end 330.830936 -91.436952)
		(stroke
			(width 0.05715)
			(type default)
		)
		(layer "In2.Cu")
	)
	(gr_line
		(start 330.827126 -91.417394)
		(end 330.830936 -91.397836)
		(stroke
			(width 0.05715)
			(type default)
		)
		(layer "In2.Cu")
	)
	(gr_line
		(start 330.837286 -72.280018)
		(end 330.843128 -72.311006)
		(stroke
			(width 0.05715)
			(type default)
		)
		(layer "In2.Cu")
	)
	(gr_line
		(start 330.837286 -72.280018)
		(end 330.843128 -72.310498)
		(stroke
			(width 0.05715)
			(type default)
		)
		(layer "In2.Cu")
	)
	(gr_line
		(start 330.837286 -72.280018)
		(end 330.845922 -72.249792)
		(stroke
			(width 0.05715)
			(type default)
		)
		(layer "In2.Cu")
	)
	(gr_line
		(start 330.837286 -72.280018)
		(end 330.845922 -72.249538)
		(stroke
			(width 0.05715)
			(type default)
		)
		(layer "In2.Cu")
	)
	(gr_line
		(start 330.845922 -72.249792)
		(end 330.846176 -72.249284)
		(stroke
			(width 0.05715)
			(type default)
		)
		(layer "In2.Cu")
	)
	(gr_line
		(start 330.86548 -84.762594)
		(end 331.04709 -85.053678)
		(stroke
			(width 0.05715)
			(type default)
		)
		(layer "In2.Cu")
	)
	(gr_line
		(start 330.869798 -94.3737)
		(end 330.873608 -94.393258)
		(stroke
			(width 0.05715)
			(type default)
		)
		(layer "In2.Cu")
	)
	(gr_line
		(start 330.870052 -94.412054)
		(end 330.873608 -94.393258)
		(stroke
			(width 0.05715)
			(type default)
		)
		(layer "In2.Cu")
	)
	(gr_line
		(start 330.872338 -65.771522)
		(end 331.080618 -65.673224)
		(stroke
			(width 0.05715)
			(type default)
		)
		(layer "In2.Cu")
	)
	(gr_line
		(start 330.885292 -101.19614)
		(end 330.889102 -101.215698)
		(stroke
			(width 0.05715)
			(type default)
		)
		(layer "In2.Cu")
	)
	(gr_line
		(start 330.885546 -101.234494)
		(end 330.889102 -101.215698)
		(stroke
			(width 0.05715)
			(type default)
		)
		(layer "In2.Cu")
	)
	(gr_line
		(start 330.919836 -63.54318)
		(end 330.943458 -63.532004)
		(stroke
			(width 0.05715)
			(type default)
		)
		(layer "In2.Cu")
	)
	(gr_line
		(start 330.920598 -119.418862)
		(end 330.94549 -119.424704)
		(stroke
			(width 0.05715)
			(type default)
		)
		(layer "In2.Cu")
	)
	(gr_line
		(start 330.94549 -119.424704)
		(end 330.97089 -119.419624)
		(stroke
			(width 0.05715)
			(type default)
		)
		(layer "In2.Cu")
	)
	(gr_line
		(start 330.947014 -122.30989)
		(end 331.056742 -122.512074)
		(stroke
			(width 0.05715)
			(type default)
		)
		(layer "In2.Cu")
	)
	(gr_line
		(start 330.965302 -111.494062)
		(end 331.02423 -111.55299)
		(stroke
			(width 0.05715)
			(type default)
		)
		(layer "In2.Cu")
	)
	(gr_line
		(start 330.987654 -73.080118)
		(end 330.993242 -73.109074)
		(stroke
			(width 0.05715)
			(type default)
		)
		(layer "In2.Cu")
	)
	(gr_line
		(start 330.988162 -73.08088)
		(end 330.993242 -73.109074)
		(stroke
			(width 0.05715)
			(type default)
		)
		(layer "In2.Cu")
	)
	(gr_line
		(start 330.991718 -81.174082)
		(end 331.215746 -81.225898)
		(stroke
			(width 0.05715)
			(type default)
		)
		(layer "In2.Cu")
	)
	(gr_line
		(start 330.993242 -73.109074)
		(end 331.010514 -73.132188)
		(stroke
			(width 0.05715)
			(type default)
		)
		(layer "In2.Cu")
	)
	(gr_line
		(start 330.99502 -85.27796)
		(end 331.04709 -85.053678)
		(stroke
			(width 0.05715)
			(type default)
		)
		(layer "In2.Cu")
	)
	(gr_line
		(start 331.080618 -65.673224)
		(end 331.403198 -65.789302)
		(stroke
			(width 0.05715)
			(type default)
		)
		(layer "In2.Cu")
	)
	(gr_line
		(start 331.116178 -87.041228)
		(end 331.15758 -87.107522)
		(stroke
			(width 0.05715)
			(type default)
		)
		(layer "In2.Cu")
	)
	(gr_line
		(start 331.130402 -104.04983)
		(end 331.133958 -104.068626)
		(stroke
			(width 0.05715)
			(type default)
		)
		(layer "In2.Cu")
	)
	(gr_line
		(start 331.130402 -104.04983)
		(end 331.133958 -104.068372)
		(stroke
			(width 0.05715)
			(type default)
		)
		(layer "In2.Cu")
	)
	(gr_line
		(start 331.130402 -104.04983)
		(end 331.133958 -104.031034)
		(stroke
			(width 0.05715)
			(type default)
		)
		(layer "In2.Cu")
	)
	(gr_line
		(start 331.130402 -104.04983)
		(end 331.134212 -104.030272)
		(stroke
			(width 0.05715)
			(type default)
		)
		(layer "In2.Cu")
	)
	(gr_line
		(start 331.133958 -104.068626)
		(end 331.134212 -104.069388)
		(stroke
			(width 0.05715)
			(type default)
		)
		(layer "In2.Cu")
	)
	(gr_line
		(start 331.135736 -64.17818)
		(end 331.159358 -64.167004)
		(stroke
			(width 0.05715)
			(type default)
		)
		(layer "In2.Cu")
	)
	(gr_line
		(start 331.142848 -87.183976)
		(end 331.15758 -87.107522)
		(stroke
			(width 0.05715)
			(type default)
		)
		(layer "In2.Cu")
	)
	(gr_line
		(start 331.215746 -81.225898)
		(end 331.40396 -81.52765)
		(stroke
			(width 0.05715)
			(type default)
		)
		(layer "In2.Cu")
	)
	(gr_line
		(start 331.250544 -113.25987)
		(end 331.29601 -113.270538)
		(stroke
			(width 0.05715)
			(type default)
		)
		(layer "In2.Cu")
	)
	(gr_line
		(start 331.254354 -70.829678)
		(end 331.28077 -70.737984)
		(stroke
			(width 0.05715)
			(type default)
		)
		(layer "In2.Cu")
	)
	(gr_line
		(start 331.28077 -70.737984)
		(end 331.366114 -70.697852)
		(stroke
			(width 0.05715)
			(type default)
		)
		(layer "In2.Cu")
	)
	(gr_line
		(start 331.310234 -82.241898)
		(end 331.634846 -82.762344)
		(stroke
			(width 0.05715)
			(type default)
		)
		(layer "In2.Cu")
	)
	(gr_line
		(start 331.310742 -82.242406)
		(end 331.634592 -82.761582)
		(stroke
			(width 0.05715)
			(type default)
		)
		(layer "In2.Cu")
	)
	(gr_line
		(start 331.340968 -122.903742)
		(end 331.912722 -123.07316)
		(stroke
			(width 0.05715)
			(type default)
		)
		(layer "In2.Cu")
	)
	(gr_line
		(start 331.352144 -81.751932)
		(end 331.40396 -81.52765)
		(stroke
			(width 0.05715)
			(type default)
		)
		(layer "In2.Cu")
	)
	(gr_line
		(start 331.390498 -122.61088)
		(end 331.592428 -122.501152)
		(stroke
			(width 0.05715)
			(type default)
		)
		(layer "In2.Cu")
	)
	(gr_line
		(start 331.403198 -65.789302)
		(end 331.501242 -65.997328)
		(stroke
			(width 0.05715)
			(type default)
		)
		(layer "In2.Cu")
	)
	(gr_line
		(start 331.523848 -72.314562)
		(end 331.52969 -72.34555)
		(stroke
			(width 0.05715)
			(type default)
		)
		(layer "In2.Cu")
	)
	(gr_line
		(start 331.523848 -72.314562)
		(end 331.52969 -72.345042)
		(stroke
			(width 0.05715)
			(type default)
		)
		(layer "In2.Cu")
	)
	(gr_line
		(start 331.523848 -72.314562)
		(end 331.532484 -72.28459)
		(stroke
			(width 0.05715)
			(type default)
		)
		(layer "In2.Cu")
	)
	(gr_line
		(start 331.523848 -72.314562)
		(end 331.532484 -72.284336)
		(stroke
			(width 0.05715)
			(type default)
		)
		(layer "In2.Cu")
	)
	(gr_line
		(start 331.532484 -72.284336)
		(end 331.532738 -72.283828)
		(stroke
			(width 0.05715)
			(type default)
		)
		(layer "In2.Cu")
	)
	(gr_line
		(start 331.542644 -82.057494)
		(end 331.766926 -82.109564)
		(stroke
			(width 0.05715)
			(type default)
		)
		(layer "In2.Cu")
	)
	(gr_line
		(start 331.592428 -122.501152)
		(end 331.921104 -122.598688)
		(stroke
			(width 0.05715)
			(type default)
		)
		(layer "In2.Cu")
	)
	(gr_line
		(start 331.622908 -72.841104)
		(end 331.628496 -72.87006)
		(stroke
			(width 0.05715)
			(type default)
		)
		(layer "In2.Cu")
	)
	(gr_line
		(start 331.622908 -72.84085)
		(end 331.628496 -72.87006)
		(stroke
			(width 0.05715)
			(type default)
		)
		(layer "In2.Cu")
	)
	(gr_line
		(start 331.628496 -72.87006)
		(end 331.645768 -72.893174)
		(stroke
			(width 0.05715)
			(type default)
		)
		(layer "In2.Cu")
	)
	(gr_line
		(start 331.640688 -106.680508)
		(end 331.65669 -106.762804)
		(stroke
			(width 0.05715)
			(type default)
		)
		(layer "In2.Cu")
	)
	(gr_line
		(start 331.65669 -106.762804)
		(end 331.725778 -106.80954)
		(stroke
			(width 0.05715)
			(type default)
		)
		(layer "In2.Cu")
	)
	(gr_line
		(start 331.70749 -94.452694)
		(end 331.7113 -94.433136)
		(stroke
			(width 0.05715)
			(type default)
		)
		(layer "In2.Cu")
	)
	(gr_line
		(start 331.70749 -94.413578)
		(end 331.7113 -94.433136)
		(stroke
			(width 0.05715)
			(type default)
		)
		(layer "In2.Cu")
	)
	(gr_line
		(start 331.707744 -94.451932)
		(end 331.7113 -94.433136)
		(stroke
			(width 0.05715)
			(type default)
		)
		(layer "In2.Cu")
	)
	(gr_line
		(start 331.707744 -94.41434)
		(end 331.7113 -94.433136)
		(stroke
			(width 0.05715)
			(type default)
		)
		(layer "In2.Cu")
	)
	(gr_line
		(start 331.723238 -67.820032)
		(end 331.77734 -67.83959)
		(stroke
			(width 0.05715)
			(type default)
		)
		(layer "In2.Cu")
	)
	(gr_line
		(start 331.743304 -67.112134)
		(end 331.797406 -67.131692)
		(stroke
			(width 0.05715)
			(type default)
		)
		(layer "In2.Cu")
	)
	(gr_line
		(start 331.762862 -66.403982)
		(end 331.816964 -66.42354)
		(stroke
			(width 0.05715)
			(type default)
		)
		(layer "In2.Cu")
	)
	(gr_line
		(start 331.766926 -82.109564)
		(end 331.95514 -82.411316)
		(stroke
			(width 0.05715)
			(type default)
		)
		(layer "In2.Cu")
	)
	(gr_line
		(start 331.77734 -67.83959)
		(end 331.832204 -67.823334)
		(stroke
			(width 0.05715)
			(type default)
		)
		(layer "In2.Cu")
	)
	(gr_line
		(start 331.797406 -67.131692)
		(end 331.85227 -67.115436)
		(stroke
			(width 0.05715)
			(type default)
		)
		(layer "In2.Cu")
	)
	(gr_line
		(start 331.816964 -66.42354)
		(end 331.871828 -66.407284)
		(stroke
			(width 0.05715)
			(type default)
		)
		(layer "In2.Cu")
	)
	(gr_line
		(start 331.823822 -71.272654)
		(end 331.84973 -71.182738)
		(stroke
			(width 0.05715)
			(type default)
		)
		(layer "In2.Cu")
	)
	(gr_line
		(start 331.824076 -71.272146)
		(end 331.84973 -71.182738)
		(stroke
			(width 0.05715)
			(type default)
		)
		(layer "In2.Cu")
	)
	(gr_line
		(start 331.833728 -101.961442)
		(end 331.837538 -101.941884)
		(stroke
			(width 0.05715)
			(type default)
		)
		(layer "In2.Cu")
	)
	(gr_line
		(start 331.833728 -101.922326)
		(end 331.837538 -101.941884)
		(stroke
			(width 0.05715)
			(type default)
		)
		(layer "In2.Cu")
	)
	(gr_line
		(start 331.833982 -101.96068)
		(end 331.837538 -101.941884)
		(stroke
			(width 0.05715)
			(type default)
		)
		(layer "In2.Cu")
	)
	(gr_line
		(start 331.833982 -101.923088)
		(end 331.837538 -101.941884)
		(stroke
			(width 0.05715)
			(type default)
		)
		(layer "In2.Cu")
	)
	(gr_line
		(start 331.838808 -85.224874)
		(end 332.161642 -85.742526)
		(stroke
			(width 0.05715)
			(type default)
		)
		(layer "In2.Cu")
	)
	(gr_line
		(start 331.83957 -85.22589)
		(end 332.161134 -85.741256)
		(stroke
			(width 0.05715)
			(type default)
		)
		(layer "In2.Cu")
	)
	(gr_line
		(start 331.84973 -71.182738)
		(end 331.93482 -71.142606)
		(stroke
			(width 0.05715)
			(type default)
		)
		(layer "In2.Cu")
	)
	(gr_line
		(start 331.862176 -83.12658)
		(end 332.185518 -83.644994)
		(stroke
			(width 0.05715)
			(type default)
		)
		(layer "In2.Cu")
	)
	(gr_line
		(start 331.86243 -83.127088)
		(end 332.185772 -83.645502)
		(stroke
			(width 0.05715)
			(type default)
		)
		(layer "In2.Cu")
	)
	(gr_line
		(start 331.90307 -82.635344)
		(end 331.95514 -82.411316)
		(stroke
			(width 0.05715)
			(type default)
		)
		(layer "In2.Cu")
	)
	(gr_line
		(start 331.921104 -122.598688)
		(end 332.030832 -122.800872)
		(stroke
			(width 0.05715)
			(type default)
		)
		(layer "In2.Cu")
	)
	(gr_line
		(start 331.962252 -86.833202)
		(end 332.002892 -86.89848)
		(stroke
			(width 0.05715)
			(type default)
		)
		(layer "In2.Cu")
	)
	(gr_line
		(start 331.962506 -86.834218)
		(end 332.002892 -86.89848)
		(stroke
			(width 0.05715)
			(type default)
		)
		(layer "In2.Cu")
	)
	(gr_line
		(start 331.988414 -86.973156)
		(end 332.002892 -86.89848)
		(stroke
			(width 0.05715)
			(type default)
		)
		(layer "In2.Cu")
	)
	(gr_line
		(start 331.988414 -86.972394)
		(end 332.002892 -86.89848)
		(stroke
			(width 0.05715)
			(type default)
		)
		(layer "In2.Cu")
	)
	(gr_line
		(start 332.068932 -59.95416)
		(end 332.080108 -59.95035)
		(stroke
			(width 0.05715)
			(type default)
		)
		(layer "In2.Cu")
	)
	(gr_line
		(start 332.069948 -85.038692)
		(end 332.29423 -85.090762)
		(stroke
			(width 0.05715)
			(type default)
		)
		(layer "In2.Cu")
	)
	(gr_line
		(start 332.078076 -77.175106)
		(end 332.082394 -77.196442)
		(stroke
			(width 0.05715)
			(type default)
		)
		(layer "In2.Cu")
	)
	(gr_line
		(start 332.078076 -77.175106)
		(end 332.082394 -77.15377)
		(stroke
			(width 0.05715)
			(type default)
		)
		(layer "In2.Cu")
	)
	(gr_line
		(start 332.093824 -82.94116)
		(end 332.318106 -82.99323)
		(stroke
			(width 0.05715)
			(type default)
		)
		(layer "In2.Cu")
	)
	(gr_line
		(start 332.200758 -108.150152)
		(end 332.2828 -108.213906)
		(stroke
			(width 0.05715)
			(type default)
		)
		(layer "In2.Cu")
	)
	(gr_line
		(start 332.209648 -125.45695)
		(end 332.241144 -125.465332)
		(stroke
			(width 0.05715)
			(type default)
		)
		(layer "In2.Cu")
	)
	(gr_line
		(start 332.23327 -77.938376)
		(end 332.35265 -78.52537)
		(stroke
			(width 0.05715)
			(type default)
		)
		(layer "In2.Cu")
	)
	(gr_line
		(start 332.23327 -77.937868)
		(end 332.35265 -78.524862)
		(stroke
			(width 0.05715)
			(type default)
		)
		(layer "In2.Cu")
	)
	(gr_line
		(start 332.241144 -125.465332)
		(end 332.273402 -125.458474)
		(stroke
			(width 0.05715)
			(type default)
		)
		(layer "In2.Cu")
	)
	(gr_line
		(start 332.29423 -85.090762)
		(end 332.482444 -85.392514)
		(stroke
			(width 0.05715)
			(type default)
		)
		(layer "In2.Cu")
	)
	(gr_line
		(start 332.318106 -82.99323)
		(end 332.50632 -83.294982)
		(stroke
			(width 0.05715)
			(type default)
		)
		(layer "In2.Cu")
	)
	(gr_line
		(start 332.38948 -86.107778)
		(end 332.713076 -86.6267)
		(stroke
			(width 0.05715)
			(type default)
		)
		(layer "In2.Cu")
	)
	(gr_line
		(start 332.39075 -86.109556)
		(end 332.712314 -86.624922)
		(stroke
			(width 0.05715)
			(type default)
		)
		(layer "In2.Cu")
	)
	(gr_line
		(start 332.406752 -83.999832)
		(end 332.72349 -84.507324)
		(stroke
			(width 0.05715)
			(type default)
		)
		(layer "In2.Cu")
	)
	(gr_line
		(start 332.40726 -84.00034)
		(end 332.722982 -84.506562)
		(stroke
			(width 0.05715)
			(type default)
		)
		(layer "In2.Cu")
	)
	(gr_line
		(start 332.430374 -85.616542)
		(end 332.482444 -85.392514)
		(stroke
			(width 0.05715)
			(type default)
		)
		(layer "In2.Cu")
	)
	(gr_line
		(start 332.44028 -124.756926)
		(end 332.471776 -124.765308)
		(stroke
			(width 0.05715)
			(type default)
		)
		(layer "In2.Cu")
	)
	(gr_line
		(start 332.45425 -83.51901)
		(end 332.50632 -83.294982)
		(stroke
			(width 0.05715)
			(type default)
		)
		(layer "In2.Cu")
	)
	(gr_line
		(start 332.471776 -124.765308)
		(end 332.504034 -124.75845)
		(stroke
			(width 0.05715)
			(type default)
		)
		(layer "In2.Cu")
	)
	(gr_line
		(start 332.514956 -77.844904)
		(end 332.70698 -77.97165)
		(stroke
			(width 0.05715)
			(type default)
		)
		(layer "In2.Cu")
	)
	(gr_line
		(start 332.621128 -85.922358)
		(end 332.84541 -85.974428)
		(stroke
			(width 0.05715)
			(type default)
		)
		(layer "In2.Cu")
	)
	(gr_line
		(start 332.6384 -83.813904)
		(end 332.862428 -83.865974)
		(stroke
			(width 0.05715)
			(type default)
		)
		(layer "In2.Cu")
	)
	(gr_line
		(start 332.641956 -74.826114)
		(end 332.658466 -74.848212)
		(stroke
			(width 0.05715)
			(type default)
		)
		(layer "In2.Cu")
	)
	(gr_line
		(start 332.648306 -78.499716)
		(end 332.775306 -78.307692)
		(stroke
			(width 0.05715)
			(type default)
		)
		(layer "In2.Cu")
	)
	(gr_line
		(start 332.658466 -74.848212)
		(end 332.664054 -74.87539)
		(stroke
			(width 0.05715)
			(type default)
		)
		(layer "In2.Cu")
	)
	(gr_line
		(start 332.70698 -77.97165)
		(end 332.775306 -78.307692)
		(stroke
			(width 0.05715)
			(type default)
		)
		(layer "In2.Cu")
	)
	(gr_line
		(start 332.743048 -80.44307)
		(end 332.862682 -81.030572)
		(stroke
			(width 0.05715)
			(type default)
		)
		(layer "In2.Cu")
	)
	(gr_line
		(start 332.743302 -80.443578)
		(end 332.862682 -81.030318)
		(stroke
			(width 0.05715)
			(type default)
		)
		(layer "In2.Cu")
	)
	(gr_line
		(start 332.749906 -75.34021)
		(end 332.754224 -75.318874)
		(stroke
			(width 0.05715)
			(type default)
		)
		(layer "In2.Cu")
	)
	(gr_line
		(start 332.749906 -75.297538)
		(end 332.754224 -75.318874)
		(stroke
			(width 0.05715)
			(type default)
		)
		(layer "In2.Cu")
	)
	(gr_line
		(start 332.84541 -85.974428)
		(end 333.03337 -86.27618)
		(stroke
			(width 0.05715)
			(type default)
		)
		(layer "In2.Cu")
	)
	(gr_line
		(start 332.849982 -76.9493)
		(end 332.8543 -76.970636)
		(stroke
			(width 0.05715)
			(type default)
		)
		(layer "In2.Cu")
	)
	(gr_line
		(start 332.849982 -76.9493)
		(end 332.8543 -76.927964)
		(stroke
			(width 0.05715)
			(type default)
		)
		(layer "In2.Cu")
	)
	(gr_line
		(start 332.862428 -83.865974)
		(end 333.043784 -84.156804)
		(stroke
			(width 0.05715)
			(type default)
		)
		(layer "In2.Cu")
	)
	(gr_line
		(start 332.88859 -107.241086)
		(end 332.9051 -107.252262)
		(stroke
			(width 0.05715)
			(type default)
		)
		(layer "In2.Cu")
	)
	(gr_line
		(start 332.9051 -107.252262)
		(end 332.916276 -107.268772)
		(stroke
			(width 0.05715)
			(type default)
		)
		(layer "In2.Cu")
	)
	(gr_line
		(start 332.92796 -72.351646)
		(end 332.933802 -72.382634)
		(stroke
			(width 0.05715)
			(type default)
		)
		(layer "In2.Cu")
	)
	(gr_line
		(start 332.92796 -72.351646)
		(end 332.933802 -72.382126)
		(stroke
			(width 0.05715)
			(type default)
		)
		(layer "In2.Cu")
	)
	(gr_line
		(start 332.92796 -72.351646)
		(end 332.936596 -72.32142)
		(stroke
			(width 0.05715)
			(type default)
		)
		(layer "In2.Cu")
	)
	(gr_line
		(start 332.92796 -72.351646)
		(end 332.93685 -72.320912)
		(stroke
			(width 0.05715)
			(type default)
		)
		(layer "In2.Cu")
	)
	(gr_line
		(start 332.94066 -86.991444)
		(end 333.264256 -87.510366)
		(stroke
			(width 0.05715)
			(type default)
		)
		(layer "In2.Cu")
	)
	(gr_line
		(start 332.94193 -86.993222)
		(end 333.264002 -87.50935)
		(stroke
			(width 0.05715)
			(type default)
		)
		(layer "In2.Cu")
	)
	(gr_line
		(start 332.981554 -86.500208)
		(end 333.03337 -86.27618)
		(stroke
			(width 0.05715)
			(type default)
		)
		(layer "In2.Cu")
	)
	(gr_line
		(start 332.986634 -81.639156)
		(end 332.990698 -81.658714)
		(stroke
			(width 0.05715)
			(type default)
		)
		(layer "In2.Cu")
	)
	(gr_line
		(start 332.990698 -81.658714)
		(end 333.00162 -81.675478)
		(stroke
			(width 0.05715)
			(type default)
		)
		(layer "In2.Cu")
	)
	(gr_line
		(start 332.991968 -84.381086)
		(end 333.043784 -84.156804)
		(stroke
			(width 0.05715)
			(type default)
		)
		(layer "In2.Cu")
	)
	(gr_line
		(start 333.024988 -80.350614)
		(end 333.217012 -80.47736)
		(stroke
			(width 0.05715)
			(type default)
		)
		(layer "In2.Cu")
	)
	(gr_line
		(start 333.0321 -118.709186)
		(end 333.045562 -118.706392)
		(stroke
			(width 0.05715)
			(type default)
		)
		(layer "In2.Cu")
	)
	(gr_line
		(start 333.045562 -118.706392)
		(end 333.059532 -118.708424)
		(stroke
			(width 0.05715)
			(type default)
		)
		(layer "In2.Cu")
	)
	(gr_line
		(start 333.157322 -73.571608)
		(end 333.16291 -73.600564)
		(stroke
			(width 0.05715)
			(type default)
		)
		(layer "In2.Cu")
	)
	(gr_line
		(start 333.15783 -73.57237)
		(end 333.16291 -73.600564)
		(stroke
			(width 0.05715)
			(type default)
		)
		(layer "In2.Cu")
	)
	(gr_line
		(start 333.158338 -81.005426)
		(end 333.285338 -80.813402)
		(stroke
			(width 0.05715)
			(type default)
		)
		(layer "In2.Cu")
	)
	(gr_line
		(start 333.16291 -73.600564)
		(end 333.180182 -73.623678)
		(stroke
			(width 0.05715)
			(type default)
		)
		(layer "In2.Cu")
	)
	(gr_line
		(start 333.172308 -86.806024)
		(end 333.396336 -86.858094)
		(stroke
			(width 0.05715)
			(type default)
		)
		(layer "In2.Cu")
	)
	(gr_line
		(start 333.206344 -71.385176)
		(end 333.232506 -71.294498)
		(stroke
			(width 0.05715)
			(type default)
		)
		(layer "In2.Cu")
	)
	(gr_line
		(start 333.217012 -80.47736)
		(end 333.285338 -80.813402)
		(stroke
			(width 0.05715)
			(type default)
		)
		(layer "In2.Cu")
	)
	(gr_line
		(start 333.231236 -82.022442)
		(end 333.561944 -82.522314)
		(stroke
			(width 0.05715)
			(type default)
		)
		(layer "In2.Cu")
	)
	(gr_line
		(start 333.23149 -82.022696)
		(end 333.561944 -82.52206)
		(stroke
			(width 0.05715)
			(type default)
		)
		(layer "In2.Cu")
	)
	(gr_line
		(start 333.232252 -71.294498)
		(end 333.232506 -71.294498)
		(stroke
			(width 0.05715)
			(type default)
		)
		(layer "In2.Cu")
	)
	(gr_line
		(start 333.232252 -71.294498)
		(end 333.232506 -71.293736)
		(stroke
			(width 0.05715)
			(type default)
		)
		(layer "In2.Cu")
	)
	(gr_line
		(start 333.232506 -71.293736)
		(end 333.319628 -71.252842)
		(stroke
			(width 0.05715)
			(type default)
		)
		(layer "In2.Cu")
	)
	(gr_line
		(start 333.232506 -71.293736)
		(end 333.319882 -71.252588)
		(stroke
			(width 0.05715)
			(type default)
		)
		(layer "In2.Cu")
	)
	(gr_line
		(start 333.334868 -74.664316)
		(end 333.351378 -74.686668)
		(stroke
			(width 0.05715)
			(type default)
		)
		(layer "In2.Cu")
	)
	(gr_line
		(start 333.351378 -74.686668)
		(end 333.356966 -74.713846)
		(stroke
			(width 0.05715)
			(type default)
		)
		(layer "In2.Cu")
	)
	(gr_line
		(start 333.396336 -86.858094)
		(end 333.58455 -87.159846)
		(stroke
			(width 0.05715)
			(type default)
		)
		(layer "In2.Cu")
	)
	(gr_line
		(start 333.458312 -81.831434)
		(end 333.683864 -81.877154)
		(stroke
			(width 0.05715)
			(type default)
		)
		(layer "In2.Cu")
	)
	(gr_line
		(start 333.475584 -75.339702)
		(end 333.479902 -75.318366)
		(stroke
			(width 0.05715)
			(type default)
		)
		(layer "In2.Cu")
	)
	(gr_line
		(start 333.475584 -75.29703)
		(end 333.479902 -75.318366)
		(stroke
			(width 0.05715)
			(type default)
		)
		(layer "In2.Cu")
	)
	(gr_line
		(start 333.48422 -42.43578)
		(end 333.48422 -43.22826)
		(stroke
			(width 0.0635)
			(type default)
		)
		(layer "In2.Cu")
	)
	(gr_line
		(start 333.48422 -42.43578)
		(end 334.04302 -41.87698)
		(stroke
			(width 0.0635)
			(type default)
		)
		(layer "In2.Cu")
	)
	(gr_line
		(start 333.492602 -108.123228)
		(end 333.52105 -108.165646)
		(stroke
			(width 0.05715)
			(type default)
		)
		(layer "In2.Cu")
	)
	(gr_line
		(start 333.492602 -87.87638)
		(end 333.814674 -88.392762)
		(stroke
			(width 0.05715)
			(type default)
		)
		(layer "In2.Cu")
	)
	(gr_line
		(start 333.492856 -108.123736)
		(end 333.52105 -108.165646)
		(stroke
			(width 0.05715)
			(type default)
		)
		(layer "In2.Cu")
	)
	(gr_line
		(start 333.532734 -87.383874)
		(end 333.58455 -87.159846)
		(stroke
			(width 0.05715)
			(type default)
		)
		(layer "In2.Cu")
	)
	(gr_line
		(start 333.537052 -77.139038)
		(end 333.542132 -77.113892)
		(stroke
			(width 0.05715)
			(type default)
		)
		(layer "In2.Cu")
	)
	(gr_line
		(start 333.537052 -77.139038)
		(end 333.54264 -77.164184)
		(stroke
			(width 0.05715)
			(type default)
		)
		(layer "In2.Cu")
	)
	(gr_line
		(start 333.537052 -77.139038)
		(end 333.542894 -77.164946)
		(stroke
			(width 0.05715)
			(type default)
		)
		(layer "In2.Cu")
	)
	(gr_line
		(start 333.542132 -77.113384)
		(end 333.542132 -77.113892)
		(stroke
			(width 0.05715)
			(type default)
		)
		(layer "In2.Cu")
	)
	(gr_line
		(start 333.545434 -80.367124)
		(end 333.549498 -80.386682)
		(stroke
			(width 0.05715)
			(type default)
		)
		(layer "In2.Cu")
	)
	(gr_line
		(start 333.549498 -80.386682)
		(end 333.56042 -80.403446)
		(stroke
			(width 0.05715)
			(type default)
		)
		(layer "In2.Cu")
	)
	(gr_line
		(start 333.549498 -80.386682)
		(end 333.56042 -80.403192)
		(stroke
			(width 0.05715)
			(type default)
		)
		(layer "In2.Cu")
	)
	(gr_line
		(start 333.62011 -76.73086)
		(end 333.739744 -76.143358)
		(stroke
			(width 0.05715)
			(type default)
		)
		(layer "In2.Cu")
	)
	(gr_line
		(start 333.683864 -81.877154)
		(end 333.87284 -82.163158)
		(stroke
			(width 0.05715)
			(type default)
		)
		(layer "In2.Cu")
	)
	(gr_line
		(start 333.685896 -80.593184)
		(end 333.732886 -80.66405)
		(stroke
			(width 0.05715)
			(type default)
		)
		(layer "In2.Cu")
	)
	(gr_line
		(start 333.686658 -80.593946)
		(end 333.732886 -80.66405)
		(stroke
			(width 0.05715)
			(type default)
		)
		(layer "In2.Cu")
	)
	(gr_line
		(start 333.723488 -87.68969)
		(end 333.947516 -87.74176)
		(stroke
			(width 0.05715)
			(type default)
		)
		(layer "In2.Cu")
	)
	(gr_line
		(start 333.732886 -80.66405)
		(end 333.73314 -80.66405)
		(stroke
			(width 0.05715)
			(type default)
		)
		(layer "In2.Cu")
	)
	(gr_line
		(start 333.73314 -80.66405)
		(end 334.02397 -81.103724)
		(stroke
			(width 0.05715)
			(type default)
		)
		(layer "In2.Cu")
	)
	(gr_line
		(start 333.73314 -80.66405)
		(end 334.024732 -81.105248)
		(stroke
			(width 0.05715)
			(type default)
		)
		(layer "In2.Cu")
	)
	(gr_line
		(start 333.74076 -43.48226)
		(end 334.05572 -43.1673)
		(stroke
			(width 0.0635)
			(type default)
		)
		(layer "In2.Cu")
	)
	(gr_line
		(start 333.807308 -78.34122)
		(end 333.81061 -78.355444)
		(stroke
			(width 0.05715)
			(type default)
		)
		(layer "In2.Cu")
	)
	(gr_line
		(start 333.81061 -78.355444)
		(end 333.818484 -78.367636)
		(stroke
			(width 0.05715)
			(type default)
		)
		(layer "In2.Cu")
	)
	(gr_line
		(start 333.82712 -82.38871)
		(end 333.87284 -82.163158)
		(stroke
			(width 0.05715)
			(type default)
		)
		(layer "In2.Cu")
	)
	(gr_line
		(start 333.902304 -76.82357)
		(end 334.094074 -76.69657)
		(stroke
			(width 0.05715)
			(type default)
		)
		(layer "In2.Cu")
	)
	(gr_line
		(start 333.902304 -76.823316)
		(end 334.094074 -76.69657)
		(stroke
			(width 0.05715)
			(type default)
		)
		(layer "In2.Cu")
	)
	(gr_line
		(start 333.912972 -80.402176)
		(end 334.138778 -80.44815)
		(stroke
			(width 0.05715)
			(type default)
		)
		(layer "In2.Cu")
	)
	(gr_line
		(start 333.947516 -87.74176)
		(end 334.13573 -88.043512)
		(stroke
			(width 0.05715)
			(type default)
		)
		(layer "In2.Cu")
	)
	(gr_line
		(start 333.96174 -74.180954)
		(end 333.979012 -74.204068)
		(stroke
			(width 0.05715)
			(type default)
		)
		(layer "In2.Cu")
	)
	(gr_line
		(start 333.962248 -74.18197)
		(end 333.979012 -74.204068)
		(stroke
			(width 0.05715)
			(type default)
		)
		(layer "In2.Cu")
	)
	(gr_line
		(start 333.979012 -74.204068)
		(end 333.984346 -74.231246)
		(stroke
			(width 0.05715)
			(type default)
		)
		(layer "In2.Cu")
	)
	(gr_line
		(start 333.9846 -58.957972)
		(end 334.42275 -58.957972)
		(stroke
			(width 0.05715)
			(type default)
		)
		(layer "In2.Cu")
	)
	(gr_line
		(start 334.032098 -78.696312)
		(end 334.039464 -78.707488)
		(stroke
			(width 0.05715)
			(type default)
		)
		(layer "In2.Cu")
	)
	(gr_line
		(start 334.0354 -76.16825)
		(end 334.1624 -76.360528)
		(stroke
			(width 0.05715)
			(type default)
		)
		(layer "In2.Cu")
	)
	(gr_line
		(start 334.0354 -60.36183)
		(end 334.35798 -60.36183)
		(stroke
			(width 0.05715)
			(type default)
		)
		(layer "In2.Cu")
	)
	(gr_line
		(start 334.039464 -78.707488)
		(end 334.049878 -78.715362)
		(stroke
			(width 0.05715)
			(type default)
		)
		(layer "In2.Cu")
	)
	(gr_line
		(start 334.039464 -78.707488)
		(end 334.050132 -78.715616)
		(stroke
			(width 0.05715)
			(type default)
		)
		(layer "In2.Cu")
	)
	(gr_line
		(start 334.043528 -88.759792)
		(end 334.060546 -88.78697)
		(stroke
			(width 0.05715)
			(type default)
		)
		(layer "In2.Cu")
	)
	(gr_line
		(start 334.043782 -88.760046)
		(end 334.060546 -88.78697)
		(stroke
			(width 0.05715)
			(type default)
		)
		(layer "In2.Cu")
	)
	(gr_line
		(start 334.060546 -88.78697)
		(end 334.087978 -88.80348)
		(stroke
			(width 0.05715)
			(type default)
		)
		(layer "In2.Cu")
	)
	(gr_line
		(start 334.08366 -88.267286)
		(end 334.13573 -88.043512)
		(stroke
			(width 0.05715)
			(type default)
		)
		(layer "In2.Cu")
	)
	(gr_line
		(start 334.094074 -76.69657)
		(end 334.1624 -76.360528)
		(stroke
			(width 0.05715)
			(type default)
		)
		(layer "In2.Cu")
	)
	(gr_line
		(start 334.138778 -80.44815)
		(end 334.33512 -80.744822)
		(stroke
			(width 0.05715)
			(type default)
		)
		(layer "In2.Cu")
	)
	(gr_line
		(start 334.141064 -123.73356)
		(end 334.175862 -123.743974)
		(stroke
			(width 0.05715)
			(type default)
		)
		(layer "In2.Cu")
	)
	(gr_line
		(start 334.175862 -123.743974)
		(end 334.210914 -123.736354)
		(stroke
			(width 0.05715)
			(type default)
		)
		(layer "In2.Cu")
	)
	(gr_line
		(start 334.201516 -75.34021)
		(end 334.205834 -75.318874)
		(stroke
			(width 0.05715)
			(type default)
		)
		(layer "In2.Cu")
	)
	(gr_line
		(start 334.201516 -75.297538)
		(end 334.205834 -75.318874)
		(stroke
			(width 0.05715)
			(type default)
		)
		(layer "In2.Cu")
	)
	(gr_line
		(start 334.260698 -81.461356)
		(end 334.598264 -81.971896)
		(stroke
			(width 0.05715)
			(type default)
		)
		(layer "In2.Cu")
	)
	(gr_line
		(start 334.26146 -81.462372)
		(end 334.59801 -81.971388)
		(stroke
			(width 0.05715)
			(type default)
		)
		(layer "In2.Cu")
	)
	(gr_line
		(start 334.289146 -80.970374)
		(end 334.33512 -80.744822)
		(stroke
			(width 0.05715)
			(type default)
		)
		(layer "In2.Cu")
	)
	(gr_line
		(start 334.313276 -83.657694)
		(end 334.324198 -83.674204)
		(stroke
			(width 0.05715)
			(type default)
		)
		(layer "In2.Cu")
	)
	(gr_line
		(start 334.324198 -83.674204)
		(end 334.341216 -83.685634)
		(stroke
			(width 0.05715)
			(type default)
		)
		(layer "In2.Cu")
	)
	(gr_line
		(start 334.35798 -60.36183)
		(end 334.47482 -60.47867)
		(stroke
			(width 0.05715)
			(type default)
		)
		(layer "In2.Cu")
	)
	(gr_line
		(start 334.39608 -78.97495)
		(end 334.46212 -79.02448)
		(stroke
			(width 0.05715)
			(type default)
		)
		(layer "In2.Cu")
	)
	(gr_line
		(start 334.396334 -78.97495)
		(end 334.46212 -79.02448)
		(stroke
			(width 0.05715)
			(type default)
		)
		(layer "In2.Cu")
	)
	(gr_line
		(start 334.42275 -58.957972)
		(end 334.47482 -58.905902)
		(stroke
			(width 0.05715)
			(type default)
		)
		(layer "In2.Cu")
	)
	(gr_line
		(start 334.461866 -79.02448)
		(end 334.46212 -79.02448)
		(stroke
			(width 0.05715)
			(type default)
		)
		(layer "In2.Cu")
	)
	(gr_line
		(start 334.461866 -79.02448)
		(end 334.88503 -79.341472)
		(stroke
			(width 0.05715)
			(type default)
		)
		(layer "In2.Cu")
	)
	(gr_line
		(start 334.461866 -79.02448)
		(end 334.885792 -79.342234)
		(stroke
			(width 0.05715)
			(type default)
		)
		(layer "In2.Cu")
	)
	(gr_line
		(start 334.487774 -81.270602)
		(end 334.713326 -81.31683)
		(stroke
			(width 0.05715)
			(type default)
		)
		(layer "In2.Cu")
	)
	(gr_line
		(start 334.53705 -58.540142)
		(end 334.555592 -58.507122)
		(stroke
			(width 0.05715)
			(type default)
		)
		(layer "In2.Cu")
	)
	(gr_line
		(start 334.544162 -78.717648)
		(end 334.771746 -78.685136)
		(stroke
			(width 0.05715)
			(type default)
		)
		(layer "In2.Cu")
	)
	(gr_line
		(start 334.713326 -81.31683)
		(end 334.909668 -81.613248)
		(stroke
			(width 0.05715)
			(type default)
		)
		(layer "In2.Cu")
	)
	(gr_line
		(start 334.72628 -122.954542)
		(end 334.76057 -122.964194)
		(stroke
			(width 0.05715)
			(type default)
		)
		(layer "In2.Cu")
	)
	(gr_line
		(start 334.76057 -122.964194)
		(end 334.795368 -122.956828)
		(stroke
			(width 0.05715)
			(type default)
		)
		(layer "In2.Cu")
	)
	(gr_line
		(start 334.771746 -78.685136)
		(end 335.056226 -78.898242)
		(stroke
			(width 0.05715)
			(type default)
		)
		(layer "In2.Cu")
	)
	(gr_line
		(start 334.774032 -58.119518)
		(end 334.78978 -58.091324)
		(stroke
			(width 0.05715)
			(type default)
		)
		(layer "In2.Cu")
	)
	(gr_line
		(start 334.78978 -58.091324)
		(end 334.81645 -58.073544)
		(stroke
			(width 0.05715)
			(type default)
		)
		(layer "In2.Cu")
	)
	(gr_line
		(start 334.819498 -64.81318)
		(end 334.84312 -64.802004)
		(stroke
			(width 0.05715)
			(type default)
		)
		(layer "In2.Cu")
	)
	(gr_line
		(start 334.824578 -70.545706)
		(end 335.365598 -70.291452)
		(stroke
			(width 0.05715)
			(type default)
		)
		(layer "In2.Cu")
	)
	(gr_line
		(start 334.826102 -70.545198)
		(end 335.36509 -70.29196)
		(stroke
			(width 0.05715)
			(type default)
		)
		(layer "In2.Cu")
	)
	(gr_line
		(start 334.846676 -84.024978)
		(end 335.342484 -84.357718)
		(stroke
			(width 0.05715)
			(type default)
		)
		(layer "In2.Cu")
	)
	(gr_line
		(start 334.846676 -84.024978)
		(end 335.342992 -84.357972)
		(stroke
			(width 0.05715)
			(type default)
		)
		(layer "In2.Cu")
	)
	(gr_line
		(start 334.863694 -81.8388)
		(end 334.909668 -81.613248)
		(stroke
			(width 0.05715)
			(type default)
		)
		(layer "In2.Cu")
	)
	(gr_line
		(start 334.89138 -60.47867)
		(end 335.001616 -60.368434)
		(stroke
			(width 0.05715)
			(type default)
		)
		(layer "In2.Cu")
	)
	(gr_line
		(start 334.89138 -58.905902)
		(end 334.94345 -58.957972)
		(stroke
			(width 0.05715)
			(type default)
		)
		(layer "In2.Cu")
	)
	(gr_line
		(start 334.91805 -70.827138)
		(end 335.134712 -70.90537)
		(stroke
			(width 0.05715)
			(type default)
		)
		(layer "In2.Cu")
	)
	(gr_line
		(start 334.94345 -58.957972)
		(end 335.3816 -58.957972)
		(stroke
			(width 0.05715)
			(type default)
		)
		(layer "In2.Cu")
	)
	(gr_line
		(start 334.962754 -71.81342)
		(end 335.19999 -72.050656)
		(stroke
			(width 0.05715)
			(type default)
		)
		(layer "In2.Cu")
	)
	(gr_line
		(start 334.980534 -83.759802)
		(end 335.206086 -83.715352)
		(stroke
			(width 0.05715)
			(type default)
		)
		(layer "In2.Cu")
	)
	(gr_line
		(start 334.98155 -65.44818)
		(end 335.005172 -65.437004)
		(stroke
			(width 0.05715)
			(type default)
		)
		(layer "In2.Cu")
	)
	(gr_line
		(start 335.001616 -60.368434)
		(end 335.353406 -60.368434)
		(stroke
			(width 0.05715)
			(type default)
		)
		(layer "In2.Cu")
	)
	(gr_line
		(start 335.056226 -78.898242)
		(end 335.088992 -79.126334)
		(stroke
			(width 0.05715)
			(type default)
		)
		(layer "In2.Cu")
	)
	(gr_line
		(start 335.061306 -82.671412)
		(end 335.101438 -82.732118)
		(stroke
			(width 0.05715)
			(type default)
		)
		(layer "In2.Cu")
	)
	(gr_line
		(start 335.101438 -82.732118)
		(end 335.171542 -82.751168)
		(stroke
			(width 0.05715)
			(type default)
		)
		(layer "In2.Cu")
	)
	(gr_line
		(start 335.1276 -66.089022)
		(end 335.151222 -66.077846)
		(stroke
			(width 0.05715)
			(type default)
		)
		(layer "In2.Cu")
	)
	(gr_line
		(start 335.134712 -70.90537)
		(end 335.4451 -70.759574)
		(stroke
			(width 0.05715)
			(type default)
		)
		(layer "In2.Cu")
	)
	(gr_line
		(start 335.206086 -83.715352)
		(end 335.49082 -83.906614)
		(stroke
			(width 0.05715)
			(type default)
		)
		(layer "In2.Cu")
	)
	(gr_line
		(start 335.22666 -79.598012)
		(end 335.71815 -79.966312)
		(stroke
			(width 0.05715)
			(type default)
		)
		(layer "In2.Cu")
	)
	(gr_line
		(start 335.227422 -66.74739)
		(end 335.251044 -66.736214)
		(stroke
			(width 0.05715)
			(type default)
		)
		(layer "In2.Cu")
	)
	(gr_line
		(start 335.228184 -79.598774)
		(end 335.71688 -79.965042)
		(stroke
			(width 0.05715)
			(type default)
		)
		(layer "In2.Cu")
	)
	(gr_line
		(start 335.242662 -88.545924)
		(end 335.25968 -88.573102)
		(stroke
			(width 0.05715)
			(type default)
		)
		(layer "In2.Cu")
	)
	(gr_line
		(start 335.247234 -122.16511)
		(end 335.290922 -122.180858)
		(stroke
			(width 0.05715)
			(type default)
		)
		(layer "In2.Cu")
	)
	(gr_line
		(start 335.25968 -88.573102)
		(end 335.287112 -88.589612)
		(stroke
			(width 0.05715)
			(type default)
		)
		(layer "In2.Cu")
	)
	(gr_line
		(start 335.290922 -122.180858)
		(end 335.336388 -122.171206)
		(stroke
			(width 0.05715)
			(type default)
		)
		(layer "In2.Cu")
	)
	(gr_line
		(start 335.377028 -79.342234)
		(end 335.60512 -79.309722)
		(stroke
			(width 0.05715)
			(type default)
		)
		(layer "In2.Cu")
	)
	(gr_line
		(start 335.404714 -67.38239)
		(end 335.428336 -67.371214)
		(stroke
			(width 0.05715)
			(type default)
		)
		(layer "In2.Cu")
	)
	(gr_line
		(start 335.4451 -70.759574)
		(end 335.522824 -70.543166)
		(stroke
			(width 0.05715)
			(type default)
		)
		(layer "In2.Cu")
	)
	(gr_line
		(start 335.49082 -83.906614)
		(end 335.535524 -84.13242)
		(stroke
			(width 0.05715)
			(type default)
		)
		(layer "In2.Cu")
	)
	(gr_line
		(start 335.549748 -68.01739)
		(end 335.57337 -68.006214)
		(stroke
			(width 0.05715)
			(type default)
		)
		(layer "In2.Cu")
	)
	(gr_line
		(start 335.586578 -82.86369)
		(end 336.17789 -83.023964)
		(stroke
			(width 0.05715)
			(type default)
		)
		(layer "In2.Cu")
	)
	(gr_line
		(start 335.587086 -82.86369)
		(end 336.176366 -83.023202)
		(stroke
			(width 0.05715)
			(type default)
		)
		(layer "In2.Cu")
	)
	(gr_line
		(start 335.60512 -79.309722)
		(end 335.8896 -79.523082)
		(stroke
			(width 0.05715)
			(type default)
		)
		(layer "In2.Cu")
	)
	(gr_line
		(start 335.616804 -72.050656)
		(end 335.85404 -71.81342)
		(stroke
			(width 0.05715)
			(type default)
		)
		(layer "In2.Cu")
	)
	(gr_line
		(start 335.630266 -82.570066)
		(end 335.830164 -82.455766)
		(stroke
			(width 0.05715)
			(type default)
		)
		(layer "In2.Cu")
	)
	(gr_line
		(start 335.698592 -114.301016)
		(end 335.726024 -114.30762)
		(stroke
			(width 0.05715)
			(type default)
		)
		(layer "In2.Cu")
	)
	(gr_line
		(start 335.708498 -68.65493)
		(end 335.732628 -68.6435)
		(stroke
			(width 0.05715)
			(type default)
		)
		(layer "In2.Cu")
	)
	(gr_line
		(start 335.726024 -114.30762)
		(end 335.753456 -114.30127)
		(stroke
			(width 0.05715)
			(type default)
		)
		(layer "In2.Cu")
	)
	(gr_line
		(start 335.830164 -82.455766)
		(end 336.173318 -82.54873)
		(stroke
			(width 0.05715)
			(type default)
		)
		(layer "In2.Cu")
	)
	(gr_line
		(start 335.83372 -69.308726)
		(end 335.857342 -69.29755)
		(stroke
			(width 0.05715)
			(type default)
		)
		(layer "In2.Cu")
	)
	(gr_line
		(start 335.8896 -79.523082)
		(end 335.922112 -79.75092)
		(stroke
			(width 0.05715)
			(type default)
		)
		(layer "In2.Cu")
	)
	(gr_line
		(start 335.906618 -70.037452)
		(end 335.955894 -70.014084)
		(stroke
			(width 0.05715)
			(type default)
		)
		(layer "In2.Cu")
	)
	(gr_line
		(start 335.955894 -70.014084)
		(end 336.01025 -70.023482)
		(stroke
			(width 0.05715)
			(type default)
		)
		(layer "In2.Cu")
	)
	(gr_line
		(start 335.955894 -70.014084)
		(end 336.010504 -70.023482)
		(stroke
			(width 0.05715)
			(type default)
		)
		(layer "In2.Cu")
	)
	(gr_line
		(start 336.028284 -57.26303)
		(end 336.07375 -57.037224)
		(stroke
			(width 0.05715)
			(type default)
		)
		(layer "In2.Cu")
	)
	(gr_line
		(start 336.060288 -80.222852)
		(end 336.551778 -80.591406)
		(stroke
			(width 0.05715)
			(type default)
		)
		(layer "In2.Cu")
	)
	(gr_line
		(start 336.061304 -80.22336)
		(end 336.55127 -80.590644)
		(stroke
			(width 0.05715)
			(type default)
		)
		(layer "In2.Cu")
	)
	(gr_line
		(start 336.06486 -119.164608)
		(end 336.107786 -119.171212)
		(stroke
			(width 0.05715)
			(type default)
		)
		(layer "In2.Cu")
	)
	(gr_line
		(start 336.07375 -57.037224)
		(end 336.358992 -56.846978)
		(stroke
			(width 0.05715)
			(type default)
		)
		(layer "In2.Cu")
	)
	(gr_line
		(start 336.107786 -119.171212)
		(end 336.140298 -119.19839)
		(stroke
			(width 0.05715)
			(type default)
		)
		(layer "In2.Cu")
	)
	(gr_line
		(start 336.173318 -82.54873)
		(end 336.287872 -82.748374)
		(stroke
			(width 0.05715)
			(type default)
		)
		(layer "In2.Cu")
	)
	(gr_line
		(start 336.210148 -79.96682)
		(end 336.43824 -79.934308)
		(stroke
			(width 0.05715)
			(type default)
		)
		(layer "In2.Cu")
	)
	(gr_line
		(start 336.21726 -72.82942)
		(end 336.240628 -72.840088)
		(stroke
			(width 0.05715)
			(type default)
		)
		(layer "In2.Cu")
	)
	(gr_line
		(start 336.2198 -57.489598)
		(end 336.720434 -57.155842)
		(stroke
			(width 0.05715)
			(type default)
		)
		(layer "In2.Cu")
	)
	(gr_line
		(start 336.228436 -71.034402)
		(end 336.414872 -70.847966)
		(stroke
			(width 0.05715)
			(type default)
		)
		(layer "In2.Cu")
	)
	(gr_line
		(start 336.358992 -56.846978)
		(end 336.584798 -56.89219)
		(stroke
			(width 0.05715)
			(type default)
		)
		(layer "In2.Cu")
	)
	(gr_line
		(start 336.378804 -70.08749)
		(end 336.44713 -70.099428)
		(stroke
			(width 0.05715)
			(type default)
		)
		(layer "In2.Cu")
	)
	(gr_line
		(start 336.43824 -79.934308)
		(end 336.72272 -80.147668)
		(stroke
			(width 0.05715)
			(type default)
		)
		(layer "In2.Cu")
	)
	(gr_line
		(start 336.44713 -70.099428)
		(end 336.491326 -70.152006)
		(stroke
			(width 0.05715)
			(type default)
		)
		(layer "In2.Cu")
	)
	(gr_line
		(start 336.528918 -119.903748)
		(end 336.555334 -119.925846)
		(stroke
			(width 0.05715)
			(type default)
		)
		(layer "In2.Cu")
	)
	(gr_line
		(start 336.555334 -119.925846)
		(end 336.5881 -119.932958)
		(stroke
			(width 0.05715)
			(type default)
		)
		(layer "In2.Cu")
	)
	(gr_line
		(start 336.592926 -83.136232)
		(end 337.181952 -83.295998)
		(stroke
			(width 0.05715)
			(type default)
		)
		(layer "In2.Cu")
	)
	(gr_line
		(start 336.593942 -83.136486)
		(end 337.181444 -83.295744)
		(stroke
			(width 0.05715)
			(type default)
		)
		(layer "In2.Cu")
	)
	(gr_line
		(start 336.635852 -82.842608)
		(end 336.835242 -82.728054)
		(stroke
			(width 0.05715)
			(type default)
		)
		(layer "In2.Cu")
	)
	(gr_line
		(start 336.662776 -70.356222)
		(end 336.706972 -70.408546)
		(stroke
			(width 0.05715)
			(type default)
		)
		(layer "In2.Cu")
	)
	(gr_line
		(start 336.662776 -70.355968)
		(end 336.706972 -70.408546)
		(stroke
			(width 0.05715)
			(type default)
		)
		(layer "In2.Cu")
	)
	(gr_line
		(start 336.666078 -111.540798)
		(end 336.687922 -111.545116)
		(stroke
			(width 0.05715)
			(type default)
		)
		(layer "In2.Cu")
	)
	(gr_line
		(start 336.687922 -111.545116)
		(end 336.705702 -111.557054)
		(stroke
			(width 0.05715)
			(type default)
		)
		(layer "In2.Cu")
	)
	(gr_line
		(start 336.709512 -70.624192)
		(end 337.119722 -71.034402)
		(stroke
			(width 0.05715)
			(type default)
		)
		(layer "In2.Cu")
	)
	(gr_line
		(start 336.72272 -80.147668)
		(end 336.755486 -80.375506)
		(stroke
			(width 0.05715)
			(type default)
		)
		(layer "In2.Cu")
	)
	(gr_line
		(start 336.7786 -60.4266)
		(end 337.135216 -60.4266)
		(stroke
			(width 0.05715)
			(type default)
		)
		(layer "In2.Cu")
	)
	(gr_line
		(start 336.7786 -58.957972)
		(end 337.21675 -58.957972)
		(stroke
			(width 0.05715)
			(type default)
		)
		(layer "In2.Cu")
	)
	(gr_line
		(start 336.805016 -73.098914)
		(end 336.887312 -73.13676)
		(stroke
			(width 0.05715)
			(type default)
		)
		(layer "In2.Cu")
	)
	(gr_line
		(start 336.820256 -90.442034)
		(end 336.830924 -90.448384)
		(stroke
			(width 0.05715)
			(type default)
		)
		(layer "In2.Cu")
	)
	(gr_line
		(start 336.830924 -90.448384)
		(end 336.84337 -90.450924)
		(stroke
			(width 0.05715)
			(type default)
		)
		(layer "In2.Cu")
	)
	(gr_line
		(start 336.835242 -82.728054)
		(end 337.178396 -82.821018)
		(stroke
			(width 0.05715)
			(type default)
		)
		(layer "In2.Cu")
	)
	(gr_line
		(start 336.887312 -73.13676)
		(end 336.915252 -73.222866)
		(stroke
			(width 0.05715)
			(type default)
		)
		(layer "In2.Cu")
	)
	(gr_line
		(start 336.89417 -80.847946)
		(end 337.384644 -81.215484)
		(stroke
			(width 0.05715)
			(type default)
		)
		(layer "In2.Cu")
	)
	(gr_line
		(start 336.896202 -80.848962)
		(end 337.383882 -81.214722)
		(stroke
			(width 0.05715)
			(type default)
		)
		(layer "In2.Cu")
	)
	(gr_line
		(start 337.023202 -110.82528)
		(end 337.045046 -110.829598)
		(stroke
			(width 0.05715)
			(type default)
		)
		(layer "In2.Cu")
	)
	(gr_line
		(start 337.043776 -80.59166)
		(end 337.271614 -80.559148)
		(stroke
			(width 0.05715)
			(type default)
		)
		(layer "In2.Cu")
	)
	(gr_line
		(start 337.045046 -110.829598)
		(end 337.062826 -110.841536)
		(stroke
			(width 0.05715)
			(type default)
		)
		(layer "In2.Cu")
	)
	(gr_line
		(start 337.051142 -113.70945)
		(end 337.085432 -113.70183)
		(stroke
			(width 0.05715)
			(type default)
		)
		(layer "In2.Cu")
	)
	(gr_line
		(start 337.085432 -113.70183)
		(end 337.11896 -113.71072)
		(stroke
			(width 0.05715)
			(type default)
		)
		(layer "In2.Cu")
	)
	(gr_line
		(start 337.135216 -60.4266)
		(end 337.227926 -60.51931)
		(stroke
			(width 0.05715)
			(type default)
		)
		(layer "In2.Cu")
	)
	(gr_line
		(start 337.178396 -82.821018)
		(end 337.29295 -83.020662)
		(stroke
			(width 0.05715)
			(type default)
		)
		(layer "In2.Cu")
	)
	(gr_line
		(start 337.21675 -58.957972)
		(end 337.26882 -58.905902)
		(stroke
			(width 0.05715)
			(type default)
		)
		(layer "In2.Cu")
	)
	(gr_line
		(start 337.234276 -89.757504)
		(end 337.244944 -89.763854)
		(stroke
			(width 0.05715)
			(type default)
		)
		(layer "In2.Cu")
	)
	(gr_line
		(start 337.244944 -89.763854)
		(end 337.25739 -89.766394)
		(stroke
			(width 0.05715)
			(type default)
		)
		(layer "In2.Cu")
	)
	(gr_line
		(start 337.271614 -80.559148)
		(end 337.556094 -80.772254)
		(stroke
			(width 0.05715)
			(type default)
		)
		(layer "In2.Cu")
	)
	(gr_line
		(start 337.33105 -58.477404)
		(end 337.355688 -58.438542)
		(stroke
			(width 0.05715)
			(type default)
		)
		(layer "In2.Cu")
	)
	(gr_line
		(start 337.351624 -75.522582)
		(end 337.536028 -76.093066)
		(stroke
			(width 0.05715)
			(type default)
		)
		(layer "In2.Cu")
	)
	(gr_line
		(start 337.351878 -75.52309)
		(end 337.536028 -76.092812)
		(stroke
			(width 0.05715)
			(type default)
		)
		(layer "In2.Cu")
	)
	(gr_line
		(start 337.556094 -80.772254)
		(end 337.588606 -81.000092)
		(stroke
			(width 0.05715)
			(type default)
		)
		(layer "In2.Cu")
	)
	(gr_line
		(start 337.592416 -58.066178)
		(end 337.602322 -58.050684)
		(stroke
			(width 0.05715)
			(type default)
		)
		(layer "In2.Cu")
	)
	(gr_line
		(start 337.597496 -83.40852)
		(end 338.186776 -83.568032)
		(stroke
			(width 0.05715)
			(type default)
		)
		(layer "In2.Cu")
	)
	(gr_line
		(start 337.598004 -83.40852)
		(end 338.186268 -83.568032)
		(stroke
			(width 0.05715)
			(type default)
		)
		(layer "In2.Cu")
	)
	(gr_line
		(start 337.598766 -120.158002)
		(end 337.622642 -120.163336)
		(stroke
			(width 0.05715)
			(type default)
		)
		(layer "In2.Cu")
	)
	(gr_line
		(start 337.602322 -58.050684)
		(end 337.616546 -58.040524)
		(stroke
			(width 0.05715)
			(type default)
		)
		(layer "In2.Cu")
	)
	(gr_line
		(start 337.621118 -75.398122)
		(end 337.826096 -75.50277)
		(stroke
			(width 0.05715)
			(type default)
		)
		(layer "In2.Cu")
	)
	(gr_line
		(start 337.622642 -120.163336)
		(end 337.646518 -120.15851)
		(stroke
			(width 0.05715)
			(type default)
		)
		(layer "In2.Cu")
	)
	(gr_line
		(start 337.64093 -83.114896)
		(end 337.84032 -83.000596)
		(stroke
			(width 0.05715)
			(type default)
		)
		(layer "In2.Cu")
	)
	(gr_line
		(start 337.64474 -60.51931)
		(end 337.73745 -60.4266)
		(stroke
			(width 0.05715)
			(type default)
		)
		(layer "In2.Cu")
	)
	(gr_line
		(start 337.664044 -76.488798)
		(end 337.848194 -77.05852)
		(stroke
			(width 0.05715)
			(type default)
		)
		(layer "In2.Cu")
	)
	(gr_line
		(start 337.664044 -76.488544)
		(end 337.84794 -77.05725)
		(stroke
			(width 0.05715)
			(type default)
		)
		(layer "In2.Cu")
	)
	(gr_line
		(start 337.68538 -58.905902)
		(end 337.73745 -58.957972)
		(stroke
			(width 0.05715)
			(type default)
		)
		(layer "In2.Cu")
	)
	(gr_line
		(start 337.691984 -85.934804)
		(end 337.706462 -85.944456)
		(stroke
			(width 0.05715)
			(type default)
		)
		(layer "In2.Cu")
	)
	(gr_line
		(start 337.701128 -56.15051)
		(end 337.718908 -56.138826)
		(stroke
			(width 0.05715)
			(type default)
		)
		(layer "In2.Cu")
	)
	(gr_line
		(start 337.706462 -85.944456)
		(end 337.723226 -85.948012)
		(stroke
			(width 0.05715)
			(type default)
		)
		(layer "In2.Cu")
	)
	(gr_line
		(start 337.718908 -56.138826)
		(end 337.719924 -56.138318)
		(stroke
			(width 0.05715)
			(type default)
		)
		(layer "In2.Cu")
	)
	(gr_line
		(start 337.719924 -56.138318)
		(end 337.73999 -56.134508)
		(stroke
			(width 0.05715)
			(type default)
		)
		(layer "In2.Cu")
	)
	(gr_line
		(start 337.73745 -60.4266)
		(end 338.1756 -60.4266)
		(stroke
			(width 0.05715)
			(type default)
		)
		(layer "In2.Cu")
	)
	(gr_line
		(start 337.73745 -58.957972)
		(end 338.1756 -58.957972)
		(stroke
			(width 0.05715)
			(type default)
		)
		(layer "In2.Cu")
	)
	(gr_line
		(start 337.826096 -75.50277)
		(end 337.931506 -75.82916)
		(stroke
			(width 0.05715)
			(type default)
		)
		(layer "In2.Cu")
	)
	(gr_line
		(start 337.826858 -76.034138)
		(end 337.931506 -75.82916)
		(stroke
			(width 0.05715)
			(type default)
		)
		(layer "In2.Cu")
	)
	(gr_line
		(start 337.84032 -83.000596)
		(end 338.183474 -83.09356)
		(stroke
			(width 0.05715)
			(type default)
		)
		(layer "In2.Cu")
	)
	(gr_line
		(start 337.840828 -111.718598)
		(end 337.858608 -111.730536)
		(stroke
			(width 0.05715)
			(type default)
		)
		(layer "In2.Cu")
	)
	(gr_line
		(start 337.858608 -111.730536)
		(end 337.880452 -111.734854)
		(stroke
			(width 0.05715)
			(type default)
		)
		(layer "In2.Cu")
	)
	(gr_line
		(start 337.863434 -70.11289)
		(end 338.09305 -69.883274)
		(stroke
			(width 0.05715)
			(type default)
		)
		(layer "In2.Cu")
	)
	(gr_line
		(start 337.933792 -76.364846)
		(end 338.13877 -76.469494)
		(stroke
			(width 0.05715)
			(type default)
		)
		(layer "In2.Cu")
	)
	(gr_line
		(start 338.09305 -69.883274)
		(end 338.0994 -69.883274)
		(stroke
			(width 0.05715)
			(type default)
		)
		(layer "In2.Cu")
	)
	(gr_line
		(start 338.0994 -69.70776)
		(end 338.0994 -69.883274)
		(stroke
			(width 0.05715)
			(type default)
		)
		(layer "In2.Cu")
	)
	(gr_line
		(start 338.13877 -76.469494)
		(end 338.24418 -76.795884)
		(stroke
			(width 0.05715)
			(type default)
		)
		(layer "In2.Cu")
	)
	(gr_line
		(start 338.139278 -77.000608)
		(end 338.24418 -76.795884)
		(stroke
			(width 0.05715)
			(type default)
		)
		(layer "In2.Cu")
	)
	(gr_line
		(start 338.183474 -83.09356)
		(end 338.298028 -83.29295)
		(stroke
			(width 0.05715)
			(type default)
		)
		(layer "In2.Cu")
	)
	(gr_line
		(start 338.219542 -81.84134)
		(end 338.698332 -82.200242)
		(stroke
			(width 0.05715)
			(type default)
		)
		(layer "In2.Cu")
	)
	(gr_line
		(start 338.219542 -81.84134)
		(end 338.69884 -82.20075)
		(stroke
			(width 0.05715)
			(type default)
		)
		(layer "In2.Cu")
	)
	(gr_line
		(start 338.36864 -81.5848)
		(end 338.596224 -81.552034)
		(stroke
			(width 0.05715)
			(type default)
		)
		(layer "In2.Cu")
	)
	(gr_line
		(start 338.418424 -57.459626)
		(end 338.455508 -57.23255)
		(stroke
			(width 0.05715)
			(type default)
		)
		(layer "In2.Cu")
	)
	(gr_line
		(start 338.455508 -57.23255)
		(end 338.733638 -57.03189)
		(stroke
			(width 0.05715)
			(type default)
		)
		(layer "In2.Cu")
	)
	(gr_line
		(start 338.511642 -69.894958)
		(end 338.729574 -70.11289)
		(stroke
			(width 0.05715)
			(type default)
		)
		(layer "In2.Cu")
	)
	(gr_line
		(start 338.511642 -69.703442)
		(end 338.511642 -69.894958)
		(stroke
			(width 0.05715)
			(type default)
		)
		(layer "In2.Cu")
	)
	(gr_line
		(start 338.57438 -124.476764)
		(end 338.594954 -124.472446)
		(stroke
			(width 0.05715)
			(type default)
		)
		(layer "In2.Cu")
	)
	(gr_line
		(start 338.594954 -124.472446)
		(end 338.61629 -124.47651)
		(stroke
			(width 0.05715)
			(type default)
		)
		(layer "In2.Cu")
	)
	(gr_line
		(start 338.596224 -81.552034)
		(end 338.870798 -81.757774)
		(stroke
			(width 0.05715)
			(type default)
		)
		(layer "In2.Cu")
	)
	(gr_line
		(start 338.602066 -83.680808)
		(end 339.193378 -83.841082)
		(stroke
			(width 0.05715)
			(type default)
		)
		(layer "In2.Cu")
	)
	(gr_line
		(start 338.603336 -83.681062)
		(end 339.192616 -83.840574)
		(stroke
			(width 0.05715)
			(type default)
		)
		(layer "In2.Cu")
	)
	(gr_line
		(start 338.61883 -57.678574)
		(end 339.10397 -57.32907)
		(stroke
			(width 0.05715)
			(type default)
		)
		(layer "In2.Cu")
	)
	(gr_line
		(start 338.645754 -83.387184)
		(end 338.845398 -83.272884)
		(stroke
			(width 0.05715)
			(type default)
		)
		(layer "In2.Cu")
	)
	(gr_line
		(start 338.729574 -70.11289)
		(end 338.75472 -70.11289)
		(stroke
			(width 0.05715)
			(type default)
		)
		(layer "In2.Cu")
	)
	(gr_line
		(start 338.733638 -57.03189)
		(end 338.960714 -57.068974)
		(stroke
			(width 0.05715)
			(type default)
		)
		(layer "In2.Cu")
	)
	(gr_line
		(start 338.819744 -119.62384)
		(end 338.947506 -119.432324)
		(stroke
			(width 0.05715)
			(type default)
		)
		(layer "In2.Cu")
	)
	(gr_line
		(start 338.845398 -83.272884)
		(end 339.188806 -83.365848)
		(stroke
			(width 0.05715)
			(type default)
		)
		(layer "In2.Cu")
	)
	(gr_line
		(start 338.84997 -111.923322)
		(end 338.868766 -111.926878)
		(stroke
			(width 0.05715)
			(type default)
		)
		(layer "In2.Cu")
	)
	(gr_line
		(start 338.868766 -111.926878)
		(end 338.887562 -111.923322)
		(stroke
			(width 0.05715)
			(type default)
		)
		(layer "In2.Cu")
	)
	(gr_line
		(start 338.870798 -81.757774)
		(end 338.90331 -81.985612)
		(stroke
			(width 0.05715)
			(type default)
		)
		(layer "In2.Cu")
	)
	(gr_line
		(start 338.912454 -119.90578)
		(end 339.498432 -119.788686)
		(stroke
			(width 0.05715)
			(type default)
		)
		(layer "In2.Cu")
	)
	(gr_line
		(start 338.947506 -119.432324)
		(end 339.283802 -119.365268)
		(stroke
			(width 0.05715)
			(type default)
		)
		(layer "In2.Cu")
	)
	(gr_line
		(start 339.133688 -123.702318)
		(end 339.154262 -123.698)
		(stroke
			(width 0.05715)
			(type default)
		)
		(layer "In2.Cu")
	)
	(gr_line
		(start 339.14842 -121.362978)
		(end 339.1662 -121.359168)
		(stroke
			(width 0.05715)
			(type default)
		)
		(layer "In2.Cu")
	)
	(gr_line
		(start 339.154262 -123.698)
		(end 339.175344 -123.702064)
		(stroke
			(width 0.05715)
			(type default)
		)
		(layer "In2.Cu")
	)
	(gr_line
		(start 339.1662 -121.359168)
		(end 339.180678 -121.349516)
		(stroke
			(width 0.05715)
			(type default)
		)
		(layer "In2.Cu")
	)
	(gr_line
		(start 339.188806 -83.365848)
		(end 339.30336 -83.565492)
		(stroke
			(width 0.05715)
			(type default)
		)
		(layer "In2.Cu")
	)
	(gr_line
		(start 339.283802 -119.365268)
		(end 339.475318 -119.49303)
		(stroke
			(width 0.05715)
			(type default)
		)
		(layer "In2.Cu")
	)
	(gr_line
		(start 339.36178 -56.108346)
		(end 339.381846 -56.104536)
		(stroke
			(width 0.05715)
			(type default)
		)
		(layer "In2.Cu")
	)
	(gr_line
		(start 339.37829 -81.790032)
		(end 339.408262 -81.882488)
		(stroke
			(width 0.05715)
			(type default)
		)
		(layer "In2.Cu")
	)
	(gr_line
		(start 339.381846 -56.104536)
		(end 339.399372 -56.092852)
		(stroke
			(width 0.05715)
			(type default)
		)
		(layer "In2.Cu")
	)
	(gr_line
		(start 339.40496 -76.515722)
		(end 339.878924 -76.515722)
		(stroke
			(width 0.05715)
			(type default)
		)
		(layer "In2.Cu")
	)
	(gr_line
		(start 339.408262 -81.882488)
		(end 339.49767 -81.919064)
		(stroke
			(width 0.05715)
			(type default)
		)
		(layer "In2.Cu")
	)
	(gr_line
		(start 339.414104 -122.991626)
		(end 339.436964 -122.9868)
		(stroke
			(width 0.05715)
			(type default)
		)
		(layer "In2.Cu")
	)
	(gr_line
		(start 339.436964 -122.9868)
		(end 339.459824 -122.991372)
		(stroke
			(width 0.05715)
			(type default)
		)
		(layer "In2.Cu")
	)
	(gr_line
		(start 339.457792 -69.02577)
		(end 339.732112 -68.75145)
		(stroke
			(width 0.05715)
			(type default)
		)
		(layer "In2.Cu")
	)
	(gr_line
		(start 339.507322 -86.347046)
		(end 340.0933 -86.477856)
		(stroke
			(width 0.05715)
			(type default)
		)
		(layer "In2.Cu")
	)
	(gr_line
		(start 339.50783 -86.347046)
		(end 340.094062 -86.47811)
		(stroke
			(width 0.05715)
			(type default)
		)
		(layer "In2.Cu")
	)
	(gr_line
		(start 339.538564 -86.051898)
		(end 339.733128 -85.928708)
		(stroke
			(width 0.05715)
			(type default)
		)
		(layer "In2.Cu")
	)
	(gr_line
		(start 339.5726 -60.4266)
		(end 340.01075 -60.4266)
		(stroke
			(width 0.05715)
			(type default)
		)
		(layer "In2.Cu")
	)
	(gr_line
		(start 339.5726 -58.957972)
		(end 339.989668 -58.957972)
		(stroke
			(width 0.05715)
			(type default)
		)
		(layer "In2.Cu")
	)
	(gr_line
		(start 339.60689 -83.953096)
		(end 340.198964 -84.113624)
		(stroke
			(width 0.05715)
			(type default)
		)
		(layer "In2.Cu")
	)
	(gr_line
		(start 339.607144 -83.953096)
		(end 340.198456 -84.11337)
		(stroke
			(width 0.05715)
			(type default)
		)
		(layer "In2.Cu")
	)
	(gr_line
		(start 339.650832 -83.659726)
		(end 339.85073 -83.545172)
		(stroke
			(width 0.05715)
			(type default)
		)
		(layer "In2.Cu")
	)
	(gr_line
		(start 339.653372 -91.013026)
		(end 339.680804 -91.018614)
		(stroke
			(width 0.05715)
			(type default)
		)
		(layer "In2.Cu")
	)
	(gr_line
		(start 339.670136 -90.24874)
		(end 339.697568 -90.254328)
		(stroke
			(width 0.05715)
			(type default)
		)
		(layer "In2.Cu")
	)
	(gr_line
		(start 339.6742 -55.558182)
		(end 339.691218 -55.547006)
		(stroke
			(width 0.05715)
			(type default)
		)
		(layer "In2.Cu")
	)
	(gr_line
		(start 339.680804 -91.018614)
		(end 339.707728 -91.011756)
		(stroke
			(width 0.05715)
			(type default)
		)
		(layer "In2.Cu")
	)
	(gr_line
		(start 339.691218 -55.547006)
		(end 339.710522 -55.54345)
		(stroke
			(width 0.05715)
			(type default)
		)
		(layer "In2.Cu")
	)
	(gr_line
		(start 339.697568 -90.254328)
		(end 339.724492 -90.24747)
		(stroke
			(width 0.05715)
			(type default)
		)
		(layer "In2.Cu")
	)
	(gr_line
		(start 339.733128 -85.928708)
		(end 340.067646 -86.003384)
		(stroke
			(width 0.05715)
			(type default)
		)
		(layer "In2.Cu")
	)
	(gr_line
		(start 339.85073 -83.545172)
		(end 340.193884 -83.638136)
		(stroke
			(width 0.05715)
			(type default)
		)
		(layer "In2.Cu")
	)
	(gr_line
		(start 339.878924 -76.515722)
		(end 339.89264 -76.502006)
		(stroke
			(width 0.05715)
			(type default)
		)
		(layer "In2.Cu")
	)
	(gr_arc
		(start 339.89264 -76.502006)
		(mid 339.973462 -76.468528)
		(end 340.00694 -76.387706)
		(stroke
			(width 0.05715)
			(type default)
		)
		(layer "In2.Cu")
	)
	(gr_line
		(start 339.989668 -58.957972)
		(end 340.041738 -58.905902)
		(stroke
			(width 0.05715)
			(type default)
		)
		(layer "In2.Cu")
	)
	(gr_line
		(start 340.006432 -111.407956)
		(end 340.025228 -111.4044)
		(stroke
			(width 0.05715)
			(type default)
		)
		(layer "In2.Cu")
	)
	(gr_line
		(start 340.00694 -75.732132)
		(end 340.017354 -75.709272)
		(stroke
			(width 0.05715)
			(type default)
		)
		(layer "In2.Cu")
	)
	(gr_line
		(start 340.01075 -60.4266)
		(end 340.06282 -60.47867)
		(stroke
			(width 0.05715)
			(type default)
		)
		(layer "In2.Cu")
	)
	(gr_line
		(start 340.025228 -111.4044)
		(end 340.044024 -111.407956)
		(stroke
			(width 0.05715)
			(type default)
		)
		(layer "In2.Cu")
	)
	(gr_line
		(start 340.055962 -121.540524)
		(end 340.079076 -121.535444)
		(stroke
			(width 0.05715)
			(type default)
		)
		(layer "In2.Cu")
	)
	(gr_line
		(start 340.065614 -122.19432)
		(end 340.088728 -122.18924)
		(stroke
			(width 0.05715)
			(type default)
		)
		(layer "In2.Cu")
	)
	(gr_line
		(start 340.067646 -86.003384)
		(end 340.19109 -86.197948)
		(stroke
			(width 0.05715)
			(type default)
		)
		(layer "In2.Cu")
	)
	(gr_line
		(start 340.071202 -68.67398)
		(end 340.422992 -69.02577)
		(stroke
			(width 0.05715)
			(type default)
		)
		(layer "In2.Cu")
	)
	(gr_line
		(start 340.079076 -121.535444)
		(end 340.10219 -121.540524)
		(stroke
			(width 0.05715)
			(type default)
		)
		(layer "In2.Cu")
	)
	(gr_line
		(start 340.088728 -122.18924)
		(end 340.111842 -122.19432)
		(stroke
			(width 0.05715)
			(type default)
		)
		(layer "In2.Cu")
	)
	(gr_line
		(start 340.09457 -119.66956)
		(end 340.113366 -119.666004)
		(stroke
			(width 0.05715)
			(type default)
		)
		(layer "In2.Cu")
	)
	(gr_line
		(start 340.104222 -58.13044)
		(end 340.117684 -58.103262)
		(stroke
			(width 0.05715)
			(type default)
		)
		(layer "In2.Cu")
	)
	(gr_line
		(start 340.113366 -119.666004)
		(end 340.129368 -119.655336)
		(stroke
			(width 0.05715)
			(type default)
		)
		(layer "In2.Cu")
	)
	(gr_line
		(start 340.148672 -68.75145)
		(end 340.422992 -69.02577)
		(stroke
			(width 0.05715)
			(type default)
		)
		(layer "In2.Cu")
	)
	(gr_line
		(start 340.193884 -83.638136)
		(end 340.308438 -83.83778)
		(stroke
			(width 0.05715)
			(type default)
		)
		(layer "In2.Cu")
	)
	(gr_line
		(start 340.267798 -75.158346)
		(end 340.299802 -75.087734)
		(stroke
			(width 0.05715)
			(type default)
		)
		(layer "In2.Cu")
	)
	(gr_line
		(start 340.272878 -56.12638)
		(end 340.294468 -56.110886)
		(stroke
			(width 0.05715)
			(type default)
		)
		(layer "In2.Cu")
	)
	(gr_line
		(start 340.294468 -56.110886)
		(end 340.320376 -56.105806)
		(stroke
			(width 0.05715)
			(type default)
		)
		(layer "In2.Cu")
	)
	(gr_arc
		(start 340.29904 -76.387706)
		(mid 340.311829 -76.44018)
		(end 340.3473 -76.480924)
		(stroke
			(width 0.05715)
			(type default)
		)
		(layer "In2.Cu")
	)
	(gr_line
		(start 340.299802 -75.087734)
		(end 340.371938 -75.057762)
		(stroke
			(width 0.05715)
			(type default)
		)
		(layer "In2.Cu")
	)
	(gr_arc
		(start 340.3473 -76.480924)
		(mid 340.385873 -76.506698)
		(end 340.431374 -76.515722)
		(stroke
			(width 0.05715)
			(type default)
		)
		(layer "In2.Cu")
	)
	(gr_line
		(start 340.431374 -76.515722)
		(end 340.80196 -76.515722)
		(stroke
			(width 0.05715)
			(type default)
		)
		(layer "In2.Cu")
	)
	(gr_line
		(start 340.458552 -58.905902)
		(end 340.510622 -58.957972)
		(stroke
			(width 0.05715)
			(type default)
		)
		(layer "In2.Cu")
	)
	(gr_line
		(start 340.47938 -60.47867)
		(end 340.53145 -60.4266)
		(stroke
			(width 0.05715)
			(type default)
		)
		(layer "In2.Cu")
	)
	(gr_line
		(start 340.510622 -58.957972)
		(end 340.9696 -58.957972)
		(stroke
			(width 0.05715)
			(type default)
		)
		(layer "In2.Cu")
	)
	(gr_line
		(start 340.53145 -60.4266)
		(end 340.9696 -60.4266)
		(stroke
			(width 0.05715)
			(type default)
		)
		(layer "In2.Cu")
	)
	(gr_line
		(start 340.568534 -57.199022)
		(end 340.585298 -57.165494)
		(stroke
			(width 0.05715)
			(type default)
		)
		(layer "In2.Cu")
	)
	(gr_line
		(start 340.585298 -57.165494)
		(end 340.61527 -57.144412)
		(stroke
			(width 0.05715)
			(type default)
		)
		(layer "In2.Cu")
	)
	(gr_line
		(start 340.598506 -84.221828)
		(end 341.179658 -84.379308)
		(stroke
			(width 0.05715)
			(type default)
		)
		(layer "In2.Cu")
	)
	(gr_line
		(start 340.59876 -84.221828)
		(end 341.179912 -84.379308)
		(stroke
			(width 0.05715)
			(type default)
		)
		(layer "In2.Cu")
	)
	(gr_line
		(start 340.643718 -83.928712)
		(end 340.843362 -83.814158)
		(stroke
			(width 0.05715)
			(type default)
		)
		(layer "In2.Cu")
	)
	(gr_line
		(start 340.651084 -114.1603)
		(end 340.687914 -114.182398)
		(stroke
			(width 0.05715)
			(type default)
		)
		(layer "In2.Cu")
	)
	(gr_line
		(start 340.655402 -121.95683)
		(end 341.255096 -122.084338)
		(stroke
			(width 0.05715)
			(type default)
		)
		(layer "In2.Cu")
	)
	(gr_line
		(start 340.683596 -121.661174)
		(end 340.876382 -121.535952)
		(stroke
			(width 0.05715)
			(type default)
		)
		(layer "In2.Cu")
	)
	(gr_line
		(start 340.68639 -86.610444)
		(end 341.270336 -86.740746)
		(stroke
			(width 0.05715)
			(type default)
		)
		(layer "In2.Cu")
	)
	(gr_line
		(start 340.686644 -86.610444)
		(end 341.270844 -86.741)
		(stroke
			(width 0.05715)
			(type default)
		)
		(layer "In2.Cu")
	)
	(gr_line
		(start 340.71687 -86.315296)
		(end 340.91118 -86.191852)
		(stroke
			(width 0.05715)
			(type default)
		)
		(layer "In2.Cu")
	)
	(gr_line
		(start 340.843362 -83.814158)
		(end 341.174324 -83.90382)
		(stroke
			(width 0.05715)
			(type default)
		)
		(layer "In2.Cu")
	)
	(gr_line
		(start 340.876382 -121.535952)
		(end 341.224108 -121.609866)
		(stroke
			(width 0.05715)
			(type default)
		)
		(layer "In2.Cu")
	)
	(gr_line
		(start 340.91118 -86.191852)
		(end 341.245952 -86.266782)
		(stroke
			(width 0.05715)
			(type default)
		)
		(layer "In2.Cu")
	)
	(gr_line
		(start 340.978998 -118.73484)
		(end 340.995 -118.724172)
		(stroke
			(width 0.05715)
			(type default)
		)
		(layer "In2.Cu")
	)
	(gr_line
		(start 340.995 -118.724172)
		(end 341.013796 -118.720616)
		(stroke
			(width 0.05715)
			(type default)
		)
		(layer "In2.Cu")
	)
	(gr_line
		(start 341.154512 -114.463068)
		(end 341.207344 -114.494818)
		(stroke
			(width 0.05715)
			(type default)
		)
		(layer "In2.Cu")
	)
	(gr_line
		(start 341.174324 -83.90382)
		(end 341.289132 -84.103464)
		(stroke
			(width 0.05715)
			(type default)
		)
		(layer "In2.Cu")
	)
	(gr_line
		(start 341.189564 -112.954054)
		(end 341.210138 -112.957864)
		(stroke
			(width 0.05715)
			(type default)
		)
		(layer "In2.Cu")
	)
	(gr_line
		(start 341.207344 -114.494818)
		(end 341.229696 -114.55146)
		(stroke
			(width 0.05715)
			(type default)
		)
		(layer "In2.Cu")
	)
	(gr_line
		(start 341.210138 -112.957864)
		(end 341.227156 -112.969294)
		(stroke
			(width 0.05715)
			(type default)
		)
		(layer "In2.Cu")
	)
	(gr_line
		(start 341.224108 -121.609866)
		(end 341.349584 -121.80316)
		(stroke
			(width 0.05715)
			(type default)
		)
		(layer "In2.Cu")
	)
	(gr_line
		(start 341.245952 -86.266782)
		(end 341.369142 -86.461092)
		(stroke
			(width 0.05715)
			(type default)
		)
		(layer "In2.Cu")
	)
	(gr_line
		(start 341.291672 -68.09613)
		(end 341.565992 -67.82181)
		(stroke
			(width 0.05715)
			(type default)
		)
		(layer "In2.Cu")
	)
	(gr_line
		(start 341.340948 -56.631586)
		(end 341.36076 -56.617362)
		(stroke
			(width 0.05715)
			(type default)
		)
		(layer "In2.Cu")
	)
	(gr_line
		(start 341.36076 -56.617362)
		(end 341.385144 -56.612536)
		(stroke
			(width 0.05715)
			(type default)
		)
		(layer "In2.Cu")
	)
	(gr_line
		(start 341.509858 -119.437912)
		(end 341.52586 -119.427244)
		(stroke
			(width 0.05715)
			(type default)
		)
		(layer "In2.Cu")
	)
	(gr_line
		(start 341.52586 -119.427244)
		(end 341.544656 -119.423688)
		(stroke
			(width 0.05715)
			(type default)
		)
		(layer "In2.Cu")
	)
	(gr_line
		(start 341.579454 -84.487512)
		(end 342.160606 -84.644992)
		(stroke
			(width 0.05715)
			(type default)
		)
		(layer "In2.Cu")
	)
	(gr_line
		(start 341.579454 -84.487512)
		(end 342.161876 -84.6455)
		(stroke
			(width 0.05715)
			(type default)
		)
		(layer "In2.Cu")
	)
	(gr_line
		(start 341.624412 -84.194396)
		(end 341.824056 -84.079842)
		(stroke
			(width 0.05715)
			(type default)
		)
		(layer "In2.Cu")
	)
	(gr_line
		(start 341.776304 -113.339626)
		(end 341.792814 -113.350802)
		(stroke
			(width 0.05715)
			(type default)
		)
		(layer "In2.Cu")
	)
	(gr_line
		(start 341.792814 -113.350802)
		(end 341.80399 -113.367312)
		(stroke
			(width 0.05715)
			(type default)
		)
		(layer "In2.Cu")
	)
	(gr_line
		(start 341.807038 -113.894616)
		(end 341.818214 -113.911634)
		(stroke
			(width 0.05715)
			(type default)
		)
		(layer "In2.Cu")
	)
	(gr_line
		(start 341.818214 -113.911634)
		(end 341.835232 -113.923064)
		(stroke
			(width 0.05715)
			(type default)
		)
		(layer "In2.Cu")
	)
	(gr_line
		(start 341.818214 -113.911634)
		(end 341.83574 -113.923572)
		(stroke
			(width 0.05715)
			(type default)
		)
		(layer "In2.Cu")
	)
	(gr_line
		(start 341.824056 -84.079842)
		(end 342.155018 -84.169504)
		(stroke
			(width 0.05715)
			(type default)
		)
		(layer "In2.Cu")
	)
	(gr_line
		(start 341.961978 -116.69522)
		(end 341.972646 -116.711476)
		(stroke
			(width 0.05715)
			(type default)
		)
		(layer "In2.Cu")
	)
	(gr_line
		(start 341.972646 -116.711476)
		(end 341.989664 -116.722906)
		(stroke
			(width 0.05715)
			(type default)
		)
		(layer "In2.Cu")
	)
	(gr_line
		(start 341.982552 -67.82181)
		(end 342.256872 -68.09613)
		(stroke
			(width 0.05715)
			(type default)
		)
		(layer "In2.Cu")
	)
	(gr_line
		(start 342.155018 -84.169504)
		(end 342.269826 -84.369402)
		(stroke
			(width 0.05715)
			(type default)
		)
		(layer "In2.Cu")
	)
	(gr_line
		(start 342.364568 -76.134214)
		(end 342.36533 -76.133452)
		(stroke
			(width 0.05715)
			(type default)
		)
		(layer "In2.Cu")
	)
	(gr_line
		(start 342.36533 -76.133452)
		(end 342.729566 -76.133452)
		(stroke
			(width 0.05715)
			(type default)
		)
		(layer "In2.Cu")
	)
	(gr_line
		(start 342.3666 -60.4266)
		(end 342.80475 -60.4266)
		(stroke
			(width 0.05715)
			(type default)
		)
		(layer "In2.Cu")
	)
	(gr_line
		(start 342.3666 -58.957972)
		(end 342.80475 -58.957972)
		(stroke
			(width 0.05715)
			(type default)
		)
		(layer "In2.Cu")
	)
	(gr_line
		(start 342.386158 -122.324622)
		(end 342.409018 -122.329448)
		(stroke
			(width 0.05715)
			(type default)
		)
		(layer "In2.Cu")
	)
	(gr_line
		(start 342.401652 -123.878848)
		(end 342.427052 -123.883928)
		(stroke
			(width 0.05715)
			(type default)
		)
		(layer "In2.Cu")
	)
	(gr_line
		(start 342.409018 -122.329448)
		(end 342.431878 -122.324876)
		(stroke
			(width 0.05715)
			(type default)
		)
		(layer "In2.Cu")
	)
	(gr_line
		(start 342.427052 -123.883928)
		(end 342.451944 -123.878086)
		(stroke
			(width 0.05715)
			(type default)
		)
		(layer "In2.Cu")
	)
	(gr_line
		(start 342.44661 -114.334036)
		(end 342.465152 -114.346482)
		(stroke
			(width 0.05715)
			(type default)
		)
		(layer "In2.Cu")
	)
	(gr_line
		(start 342.450166 -122.989086)
		(end 342.473026 -122.993912)
		(stroke
			(width 0.05715)
			(type default)
		)
		(layer "In2.Cu")
	)
	(gr_line
		(start 342.465152 -114.346482)
		(end 342.486996 -114.3508)
		(stroke
			(width 0.05715)
			(type default)
		)
		(layer "In2.Cu")
	)
	(gr_line
		(start 342.473026 -122.993912)
		(end 342.495886 -122.98934)
		(stroke
			(width 0.05715)
			(type default)
		)
		(layer "In2.Cu")
	)
	(gr_line
		(start 342.489536 -125.53188)
		(end 342.509856 -125.535944)
		(stroke
			(width 0.05715)
			(type default)
		)
		(layer "In2.Cu")
	)
	(gr_line
		(start 342.509856 -125.535944)
		(end 342.530938 -125.531372)
		(stroke
			(width 0.05715)
			(type default)
		)
		(layer "In2.Cu")
	)
	(gr_line
		(start 342.536526 -53.07584)
		(end 342.70823 -53.07584)
		(stroke
			(width 0.0635)
			(type default)
		)
		(layer "In2.Cu")
	)
	(gr_line
		(start 342.605106 -124.67463)
		(end 342.62568 -124.678694)
		(stroke
			(width 0.05715)
			(type default)
		)
		(layer "In2.Cu")
	)
	(gr_line
		(start 342.62568 -124.678694)
		(end 342.646254 -124.674376)
		(stroke
			(width 0.05715)
			(type default)
		)
		(layer "In2.Cu")
	)
	(gr_line
		(start 342.70823 -53.07584)
		(end 342.83523 -52.94884)
		(stroke
			(width 0.0635)
			(type default)
		)
		(layer "In2.Cu")
	)
	(gr_arc
		(start 342.729566 -76.133452)
		(mid 342.917792 -76.055486)
		(end 342.995758 -75.86726)
		(stroke
			(width 0.05715)
			(type default)
		)
		(layer "In2.Cu")
	)
	(gr_line
		(start 342.76411 -89.18448)
		(end 342.791034 -89.177622)
		(stroke
			(width 0.05715)
			(type default)
		)
		(layer "In2.Cu")
	)
	(gr_line
		(start 342.791034 -89.177622)
		(end 342.818466 -89.18321)
		(stroke
			(width 0.05715)
			(type default)
		)
		(layer "In2.Cu")
	)
	(gr_line
		(start 342.79713 -89.93632)
		(end 342.824054 -89.929462)
		(stroke
			(width 0.05715)
			(type default)
		)
		(layer "In2.Cu")
	)
	(gr_line
		(start 342.80475 -60.4266)
		(end 342.85682 -60.47867)
		(stroke
			(width 0.05715)
			(type default)
		)
		(layer "In2.Cu")
	)
	(gr_line
		(start 342.80475 -58.957972)
		(end 342.85682 -58.905902)
		(stroke
			(width 0.05715)
			(type default)
		)
		(layer "In2.Cu")
	)
	(gr_line
		(start 342.812624 -52.616608)
		(end 342.83523 -52.639214)
		(stroke
			(width 0.0635)
			(type default)
		)
		(layer "In2.Cu")
	)
	(gr_line
		(start 342.824054 -89.929462)
		(end 342.851486 -89.93505)
		(stroke
			(width 0.05715)
			(type default)
		)
		(layer "In2.Cu")
	)
	(gr_line
		(start 342.83523 -52.919884)
		(end 342.83523 -52.94884)
		(stroke
			(width 0.0635)
			(type default)
		)
		(layer "In2.Cu")
	)
	(gr_line
		(start 342.91905 -58.570622)
		(end 342.93048 -58.546238)
		(stroke
			(width 0.05715)
			(type default)
		)
		(layer "In2.Cu")
	)
	(gr_line
		(start 342.995758 -75.562206)
		(end 343.042748 -75.508866)
		(stroke
			(width 0.05715)
			(type default)
		)
		(layer "In2.Cu")
	)
	(gr_line
		(start 343.06383 -52.688744)
		(end 343.086436 -52.71135)
		(stroke
			(width 0.0635)
			(type default)
		)
		(layer "In2.Cu")
	)
	(gr_line
		(start 343.069926 -118.309136)
		(end 343.088976 -118.305326)
		(stroke
			(width 0.05715)
			(type default)
		)
		(layer "In2.Cu")
	)
	(gr_line
		(start 343.088214 -52.713128)
		(end 343.450926 -53.07584)
		(stroke
			(width 0.0635)
			(type default)
		)
		(layer "In2.Cu")
	)
	(gr_line
		(start 343.088976 -118.305326)
		(end 343.108026 -118.309136)
		(stroke
			(width 0.05715)
			(type default)
		)
		(layer "In2.Cu")
	)
	(gr_line
		(start 343.099898 -58.184542)
		(end 343.119202 -58.143394)
		(stroke
			(width 0.05715)
			(type default)
		)
		(layer "In2.Cu")
	)
	(gr_line
		(start 343.119202 -58.143394)
		(end 343.156032 -58.118756)
		(stroke
			(width 0.05715)
			(type default)
		)
		(layer "In2.Cu")
	)
	(gr_line
		(start 343.166192 -84.917534)
		(end 343.749122 -85.075522)
		(stroke
			(width 0.05715)
			(type default)
		)
		(layer "In2.Cu")
	)
	(gr_line
		(start 343.166446 -84.917534)
		(end 343.74836 -85.075268)
		(stroke
			(width 0.05715)
			(type default)
		)
		(layer "In2.Cu")
	)
	(gr_line
		(start 343.174828 -84.146644)
		(end 343.234264 -84.171028)
		(stroke
			(width 0.05715)
			(type default)
		)
		(layer "In2.Cu")
	)
	(gr_line
		(start 343.205816 -112.903)
		(end 343.248234 -112.931448)
		(stroke
			(width 0.05715)
			(type default)
		)
		(layer "In2.Cu")
	)
	(gr_line
		(start 343.211404 -84.624418)
		(end 343.411556 -84.509864)
		(stroke
			(width 0.05715)
			(type default)
		)
		(layer "In2.Cu")
	)
	(gr_line
		(start 343.234264 -84.171028)
		(end 343.297256 -84.152486)
		(stroke
			(width 0.05715)
			(type default)
		)
		(layer "In2.Cu")
	)
	(gr_line
		(start 343.254584 -83.457796)
		(end 343.315036 -83.482434)
		(stroke
			(width 0.05715)
			(type default)
		)
		(layer "In2.Cu")
	)
	(gr_line
		(start 343.27338 -60.47867)
		(end 343.32545 -60.4266)
		(stroke
			(width 0.05715)
			(type default)
		)
		(layer "In2.Cu")
	)
	(gr_line
		(start 343.27338 -58.905902)
		(end 343.32545 -58.957972)
		(stroke
			(width 0.05715)
			(type default)
		)
		(layer "In2.Cu")
	)
	(gr_line
		(start 343.285318 -114.208306)
		(end 343.307416 -114.212624)
		(stroke
			(width 0.05715)
			(type default)
		)
		(layer "In2.Cu")
	)
	(gr_arc
		(start 343.287858 -75.86726)
		(mid 343.355929 -76.031599)
		(end 343.520268 -76.09967)
		(stroke
			(width 0.05715)
			(type default)
		)
		(layer "In2.Cu")
	)
	(gr_line
		(start 343.307416 -114.212624)
		(end 343.325958 -114.22507)
		(stroke
			(width 0.05715)
			(type default)
		)
		(layer "In2.Cu")
	)
	(gr_line
		(start 343.315036 -83.482434)
		(end 343.378028 -83.463892)
		(stroke
			(width 0.05715)
			(type default)
		)
		(layer "In2.Cu")
	)
	(gr_line
		(start 343.32545 -60.4266)
		(end 343.7636 -60.4266)
		(stroke
			(width 0.05715)
			(type default)
		)
		(layer "In2.Cu")
	)
	(gr_line
		(start 343.32545 -58.957972)
		(end 343.7636 -58.957972)
		(stroke
			(width 0.05715)
			(type default)
		)
		(layer "In2.Cu")
	)
	(gr_line
		(start 343.358216 -87.207598)
		(end 343.38133 -87.212678)
		(stroke
			(width 0.05715)
			(type default)
		)
		(layer "In2.Cu")
	)
	(gr_line
		(start 343.38133 -87.212678)
		(end 343.404444 -87.20836)
		(stroke
			(width 0.05715)
			(type default)
		)
		(layer "In2.Cu")
	)
	(gr_line
		(start 343.411556 -84.509864)
		(end 343.742518 -84.599526)
		(stroke
			(width 0.05715)
			(type default)
		)
		(layer "In2.Cu")
	)
	(gr_line
		(start 343.450926 -53.07584)
		(end 343.806526 -53.07584)
		(stroke
			(width 0.0635)
			(type default)
		)
		(layer "In2.Cu")
	)
	(gr_line
		(start 343.452704 -119.04218)
		(end 343.473024 -119.038116)
		(stroke
			(width 0.05715)
			(type default)
		)
		(layer "In2.Cu")
	)
	(gr_line
		(start 343.473024 -119.038116)
		(end 343.494106 -119.042434)
		(stroke
			(width 0.05715)
			(type default)
		)
		(layer "In2.Cu")
	)
	(gr_line
		(start 343.520268 -76.09967)
		(end 343.832688 -76.09967)
		(stroke
			(width 0.05715)
			(type default)
		)
		(layer "In2.Cu")
	)
	(gr_line
		(start 343.526872 -67.48653)
		(end 343.739216 -67.48653)
		(stroke
			(width 0.05715)
			(type default)
		)
		(layer "In2.Cu")
	)
	(gr_line
		(start 343.535 -74.948796)
		(end 343.545668 -74.936858)
		(stroke
			(width 0.05715)
			(type default)
		)
		(layer "In2.Cu")
	)
	(gr_line
		(start 343.545668 -74.936858)
		(end 343.560146 -74.929238)
		(stroke
			(width 0.05715)
			(type default)
		)
		(layer "In2.Cu")
	)
	(gr_line
		(start 343.662254 -122.078496)
		(end 343.681304 -122.074686)
		(stroke
			(width 0.05715)
			(type default)
		)
		(layer "In2.Cu")
	)
	(gr_line
		(start 343.681304 -122.074686)
		(end 343.69756 -122.064018)
		(stroke
			(width 0.05715)
			(type default)
		)
		(layer "In2.Cu")
	)
	(gr_line
		(start 343.737692 -86.845394)
		(end 343.867486 -86.655402)
		(stroke
			(width 0.05715)
			(type default)
		)
		(layer "In2.Cu")
	)
	(gr_line
		(start 343.739216 -67.48653)
		(end 343.907364 -67.318382)
		(stroke
			(width 0.05715)
			(type default)
		)
		(layer "In2.Cu")
	)
	(gr_line
		(start 343.742518 -84.599526)
		(end 343.857072 -84.799424)
		(stroke
			(width 0.05715)
			(type default)
		)
		(layer "In2.Cu")
	)
	(gr_line
		(start 343.826846 -87.128604)
		(end 344.42781 -87.015066)
		(stroke
			(width 0.05715)
			(type default)
		)
		(layer "In2.Cu")
	)
	(gr_line
		(start 343.826846 -87.128604)
		(end 344.428064 -87.015066)
		(stroke
			(width 0.05715)
			(type default)
		)
		(layer "In2.Cu")
	)
	(gr_line
		(start 343.847928 -122.71883)
		(end 343.866978 -122.71502)
		(stroke
			(width 0.05715)
			(type default)
		)
		(layer "In2.Cu")
	)
	(gr_line
		(start 343.866978 -122.71502)
		(end 343.883234 -122.704352)
		(stroke
			(width 0.05715)
			(type default)
		)
		(layer "In2.Cu")
	)
	(gr_line
		(start 343.867486 -86.655402)
		(end 344.216736 -86.589362)
		(stroke
			(width 0.05715)
			(type default)
		)
		(layer "In2.Cu")
	)
	(gr_line
		(start 344.008456 -118.067836)
		(end 344.025474 -118.079012)
		(stroke
			(width 0.05715)
			(type default)
		)
		(layer "In2.Cu")
	)
	(gr_line
		(start 344.025474 -118.079012)
		(end 344.045286 -118.083076)
		(stroke
			(width 0.05715)
			(type default)
		)
		(layer "In2.Cu")
	)
	(gr_line
		(start 344.045794 -124.91593)
		(end 344.079068 -124.909072)
		(stroke
			(width 0.05715)
			(type default)
		)
		(layer "In2.Cu")
	)
	(gr_line
		(start 344.079068 -124.909072)
		(end 344.11158 -124.91847)
		(stroke
			(width 0.05715)
			(type default)
		)
		(layer "In2.Cu")
	)
	(gr_line
		(start 344.116152 -124.068332)
		(end 344.129614 -124.065538)
		(stroke
			(width 0.05715)
			(type default)
		)
		(layer "In2.Cu")
	)
	(gr_line
		(start 344.129614 -124.065538)
		(end 344.143838 -124.06757)
		(stroke
			(width 0.05715)
			(type default)
		)
		(layer "In2.Cu")
	)
	(gr_line
		(start 344.146124 -85.182964)
		(end 344.729054 -85.340952)
		(stroke
			(width 0.05715)
			(type default)
		)
		(layer "In2.Cu")
	)
	(gr_line
		(start 344.146886 -85.183218)
		(end 344.728292 -85.340698)
		(stroke
			(width 0.05715)
			(type default)
		)
		(layer "In2.Cu")
	)
	(gr_line
		(start 344.192098 -84.890102)
		(end 344.39225 -84.775548)
		(stroke
			(width 0.05715)
			(type default)
		)
		(layer "In2.Cu")
	)
	(gr_line
		(start 344.216736 -86.589362)
		(end 344.406982 -86.719156)
		(stroke
			(width 0.05715)
			(type default)
		)
		(layer "In2.Cu")
	)
	(gr_line
		(start 344.323924 -67.318382)
		(end 344.492072 -67.48653)
		(stroke
			(width 0.05715)
			(type default)
		)
		(layer "In2.Cu")
	)
	(gr_line
		(start 344.39225 -84.775548)
		(end 344.723212 -84.86521)
		(stroke
			(width 0.05715)
			(type default)
		)
		(layer "In2.Cu")
	)
	(gr_line
		(start 344.723212 -84.86521)
		(end 344.837766 -85.065108)
		(stroke
			(width 0.05715)
			(type default)
		)
		(layer "In2.Cu")
	)
	(gr_line
		(start 344.770456 -114.310922)
		(end 344.788236 -114.32286)
		(stroke
			(width 0.05715)
			(type default)
		)
		(layer "In2.Cu")
	)
	(gr_line
		(start 344.788236 -114.32286)
		(end 344.81008 -114.327178)
		(stroke
			(width 0.05715)
			(type default)
		)
		(layer "In2.Cu")
	)
	(gr_line
		(start 344.839798 -115.598956)
		(end 344.85834 -115.611402)
		(stroke
			(width 0.05715)
			(type default)
		)
		(layer "In2.Cu")
	)
	(gr_line
		(start 344.85834 -115.611402)
		(end 344.880438 -115.61572)
		(stroke
			(width 0.05715)
			(type default)
		)
		(layer "In2.Cu")
	)
	(gr_line
		(start 344.98407 -120.854978)
		(end 345.000326 -120.84431)
		(stroke
			(width 0.05715)
			(type default)
		)
		(layer "In2.Cu")
	)
	(gr_line
		(start 345.000326 -120.84431)
		(end 345.019376 -120.8405)
		(stroke
			(width 0.05715)
			(type default)
		)
		(layer "In2.Cu")
	)
	(gr_line
		(start 345.062556 -76.40701)
		(end 345.390216 -76.40701)
		(stroke
			(width 0.05715)
			(type default)
		)
		(layer "In2.Cu")
	)
	(gr_line
		(start 345.12758 -85.448902)
		(end 345.175332 -85.461856)
		(stroke
			(width 0.05715)
			(type default)
		)
		(layer "In2.Cu")
	)
	(gr_line
		(start 345.128088 -85.448902)
		(end 345.175332 -85.461856)
		(stroke
			(width 0.05715)
			(type default)
		)
		(layer "In2.Cu")
	)
	(gr_line
		(start 345.1606 -60.4266)
		(end 345.59875 -60.4266)
		(stroke
			(width 0.05715)
			(type default)
		)
		(layer "In2.Cu")
	)
	(gr_line
		(start 345.1606 -58.957972)
		(end 345.567254 -58.957972)
		(stroke
			(width 0.05715)
			(type default)
		)
		(layer "In2.Cu")
	)
	(gr_line
		(start 345.175332 -85.461856)
		(end 345.221306 -85.447632)
		(stroke
			(width 0.05715)
			(type default)
		)
		(layer "In2.Cu")
	)
	(gr_line
		(start 345.208606 -121.469404)
		(end 345.224862 -121.458736)
		(stroke
			(width 0.05715)
			(type default)
		)
		(layer "In2.Cu")
	)
	(gr_line
		(start 345.224862 -122.826526)
		(end 345.249246 -122.814842)
		(stroke
			(width 0.05715)
			(type default)
		)
		(layer "In2.Cu")
	)
	(gr_line
		(start 345.224862 -121.458736)
		(end 345.243658 -121.454926)
		(stroke
			(width 0.05715)
			(type default)
		)
		(layer "In2.Cu")
	)
	(gr_line
		(start 345.382596 -56.63438)
		(end 345.399614 -56.623204)
		(stroke
			(width 0.05715)
			(type default)
		)
		(layer "In2.Cu")
	)
	(gr_arc
		(start 345.390216 -76.40701)
		(mid 345.554555 -76.338939)
		(end 345.622626 -76.1746)
		(stroke
			(width 0.05715)
			(type default)
		)
		(layer "In2.Cu")
	)
	(gr_line
		(start 345.399614 -56.623204)
		(end 345.419426 -56.61914)
		(stroke
			(width 0.05715)
			(type default)
		)
		(layer "In2.Cu")
	)
	(gr_line
		(start 345.500198 -124.56033)
		(end 345.5162 -124.562616)
		(stroke
			(width 0.05715)
			(type default)
		)
		(layer "In2.Cu")
	)
	(gr_line
		(start 345.5162 -124.562616)
		(end 345.531694 -124.55906)
		(stroke
			(width 0.05715)
			(type default)
		)
		(layer "In2.Cu")
	)
	(gr_line
		(start 345.559634 -125.33122)
		(end 345.596718 -125.341888)
		(stroke
			(width 0.05715)
			(type default)
		)
		(layer "In2.Cu")
	)
	(gr_line
		(start 345.567254 -58.957972)
		(end 345.607894 -58.917332)
		(stroke
			(width 0.05715)
			(type default)
		)
		(layer "In2.Cu")
	)
	(gr_line
		(start 345.571572 -114.475006)
		(end 345.590368 -114.478562)
		(stroke
			(width 0.05715)
			(type default)
		)
		(layer "In2.Cu")
	)
	(gr_line
		(start 345.576144 -123.169172)
		(end 345.628214 -123.221242)
		(stroke
			(width 0.05715)
			(type default)
		)
		(layer "In2.Cu")
	)
	(gr_line
		(start 345.576144 -122.752612)
		(end 345.659202 -122.669554)
		(stroke
			(width 0.05715)
			(type default)
		)
		(layer "In2.Cu")
	)
	(gr_line
		(start 345.590368 -114.478562)
		(end 345.609164 -114.475006)
		(stroke
			(width 0.05715)
			(type default)
		)
		(layer "In2.Cu")
	)
	(gr_line
		(start 345.59875 -60.4266)
		(end 345.65082 -60.47867)
		(stroke
			(width 0.05715)
			(type default)
		)
		(layer "In2.Cu")
	)
	(gr_line
		(start 345.616784 -86.493096)
		(end 345.63558 -86.48954)
		(stroke
			(width 0.05715)
			(type default)
		)
		(layer "In2.Cu")
	)
	(gr_line
		(start 345.622626 -75.827636)
		(end 345.728544 -75.761596)
		(stroke
			(width 0.05715)
			(type default)
		)
		(layer "In2.Cu")
	)
	(gr_line
		(start 345.622626 -75.827636)
		(end 345.728798 -75.761342)
		(stroke
			(width 0.05715)
			(type default)
		)
		(layer "In2.Cu")
	)
	(gr_line
		(start 345.628214 -123.221242)
		(end 345.628214 -123.576842)
		(stroke
			(width 0.05715)
			(type default)
		)
		(layer "In2.Cu")
	)
	(gr_line
		(start 345.63558 -86.48954)
		(end 345.653614 -86.49335)
		(stroke
			(width 0.05715)
			(type default)
		)
		(layer "In2.Cu")
	)
	(gr_line
		(start 345.659202 -122.344942)
		(end 345.659202 -122.669554)
		(stroke
			(width 0.05715)
			(type default)
		)
		(layer "In2.Cu")
	)
	(gr_line
		(start 345.681554 -58.60161)
		(end 345.71178 -58.558176)
		(stroke
			(width 0.05715)
			(type default)
		)
		(layer "In2.Cu")
	)
	(gr_line
		(start 345.730322 -72.279256)
		(end 345.747086 -72.20712)
		(stroke
			(width 0.05715)
			(type default)
		)
		(layer "In2.Cu")
	)
	(gr_line
		(start 345.73464 -73.148444)
		(end 345.838526 -73.105264)
		(stroke
			(width 0.05715)
			(type default)
		)
		(layer "In2.Cu")
	)
	(gr_line
		(start 345.747086 -72.20712)
		(end 345.807538 -72.164448)
		(stroke
			(width 0.05715)
			(type default)
		)
		(layer "In2.Cu")
	)
	(gr_line
		(start 345.838526 -73.105264)
		(end 345.863672 -72.996298)
		(stroke
			(width 0.05715)
			(type default)
		)
		(layer "In2.Cu")
	)
	(gr_line
		(start 345.879674 -126.038102)
		(end 346.17152 -126.329948)
		(stroke
			(width 0.05715)
			(type default)
		)
		(layer "In2.Cu")
	)
	(gr_line
		(start 345.881198 -125.623066)
		(end 346.03944 -125.623066)
		(stroke
			(width 0.05715)
			(type default)
		)
		(layer "In2.Cu")
	)
	(gr_line
		(start 345.888818 -82.420206)
		(end 345.933268 -82.406998)
		(stroke
			(width 0.05715)
			(type default)
		)
		(layer "In2.Cu")
	)
	(gr_line
		(start 345.893644 -83.083654)
		(end 345.938094 -83.070446)
		(stroke
			(width 0.05715)
			(type default)
		)
		(layer "In2.Cu")
	)
	(gr_arc
		(start 345.914726 -76.1746)
		(mid 345.982797 -76.338939)
		(end 346.147136 -76.40701)
		(stroke
			(width 0.05715)
			(type default)
		)
		(layer "In2.Cu")
	)
	(gr_line
		(start 345.933268 -82.406998)
		(end 345.977972 -82.419444)
		(stroke
			(width 0.05715)
			(type default)
		)
		(layer "In2.Cu")
	)
	(gr_line
		(start 345.938094 -83.070446)
		(end 345.982798 -83.082892)
		(stroke
			(width 0.05715)
			(type default)
		)
		(layer "In2.Cu")
	)
	(gr_line
		(start 346.024708 -58.917332)
		(end 346.065348 -58.957972)
		(stroke
			(width 0.05715)
			(type default)
		)
		(layer "In2.Cu")
	)
	(gr_line
		(start 346.036138 -84.886546)
		(end 346.090748 -84.869528)
		(stroke
			(width 0.05715)
			(type default)
		)
		(layer "In2.Cu")
	)
	(gr_line
		(start 346.03944 -125.623066)
		(end 346.161614 -125.500892)
		(stroke
			(width 0.05715)
			(type default)
		)
		(layer "In2.Cu")
	)
	(gr_line
		(start 346.04579 -115.5446)
		(end 346.067888 -115.548918)
		(stroke
			(width 0.05715)
			(type default)
		)
		(layer "In2.Cu")
	)
	(gr_line
		(start 346.065348 -58.957972)
		(end 346.5576 -58.957972)
		(stroke
			(width 0.05715)
			(type default)
		)
		(layer "In2.Cu")
	)
	(gr_line
		(start 346.06738 -60.47867)
		(end 346.11945 -60.4266)
		(stroke
			(width 0.05715)
			(type default)
		)
		(layer "In2.Cu")
	)
	(gr_line
		(start 346.067888 -115.548918)
		(end 346.08643 -115.561364)
		(stroke
			(width 0.05715)
			(type default)
		)
		(layer "In2.Cu")
	)
	(gr_line
		(start 346.090748 -84.869528)
		(end 346.145104 -84.88807)
		(stroke
			(width 0.05715)
			(type default)
		)
		(layer "In2.Cu")
	)
	(gr_line
		(start 346.097606 -75.531218)
		(end 346.606876 -75.213464)
		(stroke
			(width 0.05715)
			(type default)
		)
		(layer "In2.Cu")
	)
	(gr_line
		(start 346.098114 -75.530964)
		(end 346.606876 -75.213464)
		(stroke
			(width 0.05715)
			(type default)
		)
		(layer "In2.Cu")
	)
	(gr_line
		(start 346.11945 -60.4266)
		(end 346.5576 -60.4266)
		(stroke
			(width 0.05715)
			(type default)
		)
		(layer "In2.Cu")
	)
	(gr_line
		(start 346.125038 -124.12726)
		(end 346.157042 -124.120148)
		(stroke
			(width 0.05715)
			(type default)
		)
		(layer "In2.Cu")
	)
	(gr_line
		(start 346.147136 -76.40701)
		(end 346.459556 -76.40701)
		(stroke
			(width 0.05715)
			(type default)
		)
		(layer "In2.Cu")
	)
	(gr_line
		(start 346.148152 -54.584092)
		(end 346.22994 -54.56809)
		(stroke
			(width 0.05715)
			(type default)
		)
		(layer "In2.Cu")
	)
	(gr_line
		(start 346.151962 -67.44335)
		(end 346.389198 -67.206114)
		(stroke
			(width 0.05715)
			(type default)
		)
		(layer "In2.Cu")
	)
	(gr_line
		(start 346.157042 -124.120148)
		(end 346.188284 -124.128022)
		(stroke
			(width 0.05715)
			(type default)
		)
		(layer "In2.Cu")
	)
	(gr_line
		(start 346.161614 -125.177042)
		(end 346.161614 -125.500892)
		(stroke
			(width 0.05715)
			(type default)
		)
		(layer "In2.Cu")
	)
	(gr_line
		(start 346.17152 -126.329948)
		(end 346.17152 -126.379224)
		(stroke
			(width 0.05715)
			(type default)
		)
		(layer "In2.Cu")
	)
	(gr_line
		(start 346.216986 -114.058954)
		(end 346.235782 -114.055398)
		(stroke
			(width 0.05715)
			(type default)
		)
		(layer "In2.Cu")
	)
	(gr_line
		(start 346.224352 -75.799442)
		(end 346.448888 -75.851258)
		(stroke
			(width 0.05715)
			(type default)
		)
		(layer "In2.Cu")
	)
	(gr_line
		(start 346.22994 -54.56809)
		(end 346.276422 -54.498494)
		(stroke
			(width 0.05715)
			(type default)
		)
		(layer "In2.Cu")
	)
	(gr_line
		(start 346.235782 -114.055398)
		(end 346.254578 -114.058954)
		(stroke
			(width 0.05715)
			(type default)
		)
		(layer "In2.Cu")
	)
	(gr_line
		(start 346.448888 -75.851258)
		(end 346.739718 -75.669648)
		(stroke
			(width 0.05715)
			(type default)
		)
		(layer "In2.Cu")
	)
	(gr_line
		(start 346.54363 -54.097936)
		(end 346.555822 -54.079648)
		(stroke
			(width 0.05715)
			(type default)
		)
		(layer "In2.Cu")
	)
	(gr_line
		(start 346.555822 -54.079648)
		(end 346.56014 -54.058312)
		(stroke
			(width 0.05715)
			(type default)
		)
		(layer "In2.Cu")
	)
	(gr_line
		(start 346.55633 -121.192544)
		(end 346.604082 -121.182892)
		(stroke
			(width 0.05715)
			(type default)
		)
		(layer "In2.Cu")
	)
	(gr_line
		(start 346.604082 -121.182892)
		(end 346.64904 -121.200672)
		(stroke
			(width 0.05715)
			(type default)
		)
		(layer "In2.Cu")
	)
	(gr_line
		(start 346.614242 -52.298854)
		(end 346.618052 -52.279804)
		(stroke
			(width 0.05715)
			(type default)
		)
		(layer "In2.Cu")
	)
	(gr_line
		(start 346.618052 -52.279804)
		(end 346.628974 -52.26304)
		(stroke
			(width 0.05715)
			(type default)
		)
		(layer "In2.Cu")
	)
	(gr_line
		(start 346.637864 -86.989666)
		(end 346.659708 -86.994238)
		(stroke
			(width 0.05715)
			(type default)
		)
		(layer "In2.Cu")
	)
	(gr_line
		(start 346.659708 -86.994238)
		(end 346.681552 -86.989412)
		(stroke
			(width 0.05715)
			(type default)
		)
		(layer "In2.Cu")
	)
	(gr_line
		(start 346.739718 -75.669648)
		(end 346.791788 -75.445366)
		(stroke
			(width 0.05715)
			(type default)
		)
		(layer "In2.Cu")
	)
	(gr_line
		(start 346.769182 -116.021866)
		(end 346.785692 -116.033042)
		(stroke
			(width 0.05715)
			(type default)
		)
		(layer "In2.Cu")
	)
	(gr_line
		(start 346.776802 -120.48871)
		(end 346.799662 -120.484138)
		(stroke
			(width 0.05715)
			(type default)
		)
		(layer "In2.Cu")
	)
	(gr_line
		(start 346.785692 -116.033042)
		(end 346.796868 -116.049552)
		(stroke
			(width 0.05715)
			(type default)
		)
		(layer "In2.Cu")
	)
	(gr_line
		(start 346.798392 -124.584714)
		(end 346.822776 -124.591064)
		(stroke
			(width 0.05715)
			(type default)
		)
		(layer "In2.Cu")
	)
	(gr_line
		(start 346.799662 -120.484138)
		(end 346.822522 -120.488964)
		(stroke
			(width 0.05715)
			(type default)
		)
		(layer "In2.Cu")
	)
	(gr_line
		(start 346.799662 -65.388236)
		(end 346.962222 -65.550796)
		(stroke
			(width 0.05715)
			(type default)
		)
		(layer "In2.Cu")
	)
	(gr_line
		(start 346.806012 -67.206114)
		(end 347.043248 -67.44335)
		(stroke
			(width 0.05715)
			(type default)
		)
		(layer "In2.Cu")
	)
	(gr_line
		(start 346.822776 -124.591064)
		(end 346.847668 -124.586492)
		(stroke
			(width 0.05715)
			(type default)
		)
		(layer "In2.Cu")
	)
	(gr_line
		(start 346.832428 -83.622896)
		(end 346.866972 -83.632548)
		(stroke
			(width 0.05715)
			(type default)
		)
		(layer "In2.Cu")
	)
	(gr_line
		(start 346.846398 -82.964782)
		(end 346.880942 -82.974434)
		(stroke
			(width 0.05715)
			(type default)
		)
		(layer "In2.Cu")
	)
	(gr_line
		(start 346.846652 -82.964782)
		(end 346.880942 -82.974434)
		(stroke
			(width 0.05715)
			(type default)
		)
		(layer "In2.Cu")
	)
	(gr_line
		(start 346.866972 -83.632548)
		(end 346.902024 -83.624166)
		(stroke
			(width 0.05715)
			(type default)
		)
		(layer "In2.Cu")
	)
	(gr_line
		(start 346.880942 -82.974434)
		(end 346.915994 -82.966052)
		(stroke
			(width 0.05715)
			(type default)
		)
		(layer "In2.Cu")
	)
	(gr_line
		(start 346.962222 -65.550796)
		(end 347.317822 -65.550796)
		(stroke
			(width 0.05715)
			(type default)
		)
		(layer "In2.Cu")
	)
	(gr_line
		(start 346.99575 -85.487256)
		(end 347.042994 -85.503258)
		(stroke
			(width 0.05715)
			(type default)
		)
		(layer "In2.Cu")
	)
	(gr_line
		(start 347.02242 -114.208306)
		(end 347.044264 -114.212624)
		(stroke
			(width 0.05715)
			(type default)
		)
		(layer "In2.Cu")
	)
	(gr_line
		(start 347.042994 -85.503258)
		(end 347.091508 -85.490812)
		(stroke
			(width 0.05715)
			(type default)
		)
		(layer "In2.Cu")
	)
	(gr_line
		(start 347.044264 -114.212624)
		(end 347.062806 -114.22507)
		(stroke
			(width 0.05715)
			(type default)
		)
		(layer "In2.Cu")
	)
	(gr_line
		(start 347.067886 -116.974366)
		(end 347.079062 -116.990876)
		(stroke
			(width 0.05715)
			(type default)
		)
		(layer "In2.Cu")
	)
	(gr_line
		(start 347.079062 -116.990876)
		(end 347.095572 -117.002052)
		(stroke
			(width 0.05715)
			(type default)
		)
		(layer "In2.Cu")
	)
	(gr_line
		(start 347.091762 -65.093596)
		(end 347.188282 -65.093596)
		(stroke
			(width 0.05715)
			(type default)
		)
		(layer "In2.Cu")
	)
	(gr_line
		(start 347.217238 -56.999124)
		(end 347.266514 -56.989472)
		(stroke
			(width 0.05715)
			(type default)
		)
		(layer "In2.Cu")
	)
	(gr_line
		(start 347.220286 -55.056024)
		(end 347.302074 -55.040022)
		(stroke
			(width 0.05715)
			(type default)
		)
		(layer "In2.Cu")
	)
	(gr_line
		(start 347.26372 -115.212622)
		(end 347.268038 -115.234466)
		(stroke
			(width 0.05715)
			(type default)
		)
		(layer "In2.Cu")
	)
	(gr_line
		(start 347.268038 -115.234466)
		(end 347.280484 -115.253008)
		(stroke
			(width 0.05715)
			(type default)
		)
		(layer "In2.Cu")
	)
	(gr_line
		(start 347.302074 -55.040022)
		(end 347.348048 -54.970934)
		(stroke
			(width 0.05715)
			(type default)
		)
		(layer "In2.Cu")
	)
	(gr_line
		(start 347.306138 -114.389154)
		(end 347.323918 -114.400838)
		(stroke
			(width 0.05715)
			(type default)
		)
		(layer "In2.Cu")
	)
	(gr_line
		(start 347.317822 -65.550796)
		(end 347.480382 -65.388236)
		(stroke
			(width 0.05715)
			(type default)
		)
		(layer "In2.Cu")
	)
	(gr_line
		(start 347.323918 -114.400838)
		(end 347.335602 -114.418618)
		(stroke
			(width 0.05715)
			(type default)
		)
		(layer "In2.Cu")
	)
	(gr_line
		(start 347.323918 -114.400838)
		(end 347.33611 -114.419126)
		(stroke
			(width 0.05715)
			(type default)
		)
		(layer "In2.Cu")
	)
	(gr_line
		(start 347.423994 -114.55146)
		(end 347.43644 -114.570256)
		(stroke
			(width 0.05715)
			(type default)
		)
		(layer "In2.Cu")
	)
	(gr_line
		(start 347.43644 -114.570256)
		(end 347.440758 -114.5921)
		(stroke
			(width 0.05715)
			(type default)
		)
		(layer "In2.Cu")
	)
	(gr_line
		(start 347.446854 -115.50015)
		(end 347.457776 -115.516406)
		(stroke
			(width 0.05715)
			(type default)
		)
		(layer "In2.Cu")
	)
	(gr_line
		(start 347.457776 -115.516406)
		(end 347.474032 -115.527328)
		(stroke
			(width 0.05715)
			(type default)
		)
		(layer "In2.Cu")
	)
	(gr_line
		(start 347.559376 -83.17103)
		(end 347.606366 -83.159854)
		(stroke
			(width 0.05715)
			(type default)
		)
		(layer "In2.Cu")
	)
	(gr_line
		(start 347.598746 -82.507074)
		(end 347.646244 -82.495898)
		(stroke
			(width 0.05715)
			(type default)
		)
		(layer "In2.Cu")
	)
	(gr_line
		(start 347.606366 -83.159854)
		(end 347.652086 -83.176618)
		(stroke
			(width 0.05715)
			(type default)
		)
		(layer "In2.Cu")
	)
	(gr_line
		(start 347.646244 -82.495898)
		(end 347.691964 -82.512662)
		(stroke
			(width 0.05715)
			(type default)
		)
		(layer "In2.Cu")
	)
	(gr_line
		(start 347.646244 -82.495898)
		(end 347.692472 -82.512662)
		(stroke
			(width 0.05715)
			(type default)
		)
		(layer "In2.Cu")
	)
	(gr_line
		(start 347.656404 -55.687468)
		(end 347.738192 -55.671466)
		(stroke
			(width 0.05715)
			(type default)
		)
		(layer "In2.Cu")
	)
	(gr_line
		(start 347.679264 -115.665504)
		(end 347.697806 -115.67795)
		(stroke
			(width 0.05715)
			(type default)
		)
		(layer "In2.Cu")
	)
	(gr_line
		(start 347.697806 -115.67795)
		(end 347.71965 -115.682268)
		(stroke
			(width 0.05715)
			(type default)
		)
		(layer "In2.Cu")
	)
	(gr_line
		(start 347.738192 -55.671466)
		(end 347.78442 -55.602124)
		(stroke
			(width 0.05715)
			(type default)
		)
		(layer "In2.Cu")
	)
	(gr_line
		(start 347.764608 -117.45341)
		(end 347.78315 -117.465856)
		(stroke
			(width 0.05715)
			(type default)
		)
		(layer "In2.Cu")
	)
	(gr_line
		(start 347.78315 -117.465856)
		(end 347.805248 -117.470174)
		(stroke
			(width 0.05715)
			(type default)
		)
		(layer "In2.Cu")
	)
	(gr_line
		(start 347.798898 -124.114052)
		(end 347.872812 -124.100336)
		(stroke
			(width 0.05715)
			(type default)
		)
		(layer "In2.Cu")
	)
	(gr_line
		(start 347.80728 -76.509626)
		(end 348.25051 -76.509626)
		(stroke
			(width 0.05715)
			(type default)
		)
		(layer "In2.Cu")
	)
	(gr_line
		(start 347.82252 -85.0011)
		(end 347.89872 -84.981542)
		(stroke
			(width 0.05715)
			(type default)
		)
		(layer "In2.Cu")
	)
	(gr_line
		(start 347.841062 -65.388236)
		(end 348.003622 -65.550796)
		(stroke
			(width 0.05715)
			(type default)
		)
		(layer "In2.Cu")
	)
	(gr_line
		(start 347.872812 -124.100336)
		(end 347.936058 -124.139452)
		(stroke
			(width 0.05715)
			(type default)
		)
		(layer "In2.Cu")
	)
	(gr_line
		(start 347.890338 -86.42858)
		(end 347.940884 -86.417658)
		(stroke
			(width 0.05715)
			(type default)
		)
		(layer "In2.Cu")
	)
	(gr_line
		(start 347.89872 -84.981542)
		(end 347.967046 -85.019134)
		(stroke
			(width 0.05715)
			(type default)
		)
		(layer "In2.Cu")
	)
	(gr_line
		(start 347.89872 -84.981542)
		(end 347.967808 -85.019388)
		(stroke
			(width 0.05715)
			(type default)
		)
		(layer "In2.Cu")
	)
	(gr_line
		(start 347.940884 -86.417658)
		(end 347.988636 -86.436962)
		(stroke
			(width 0.05715)
			(type default)
		)
		(layer "In2.Cu")
	)
	(gr_line
		(start 347.9546 -60.4266)
		(end 348.39275 -60.4266)
		(stroke
			(width 0.05715)
			(type default)
		)
		(layer "In2.Cu")
	)
	(gr_line
		(start 347.9546 -58.957972)
		(end 348.39275 -58.957972)
		(stroke
			(width 0.05715)
			(type default)
		)
		(layer "In2.Cu")
	)
	(gr_line
		(start 348.003622 -65.550796)
		(end 348.359222 -65.550796)
		(stroke
			(width 0.05715)
			(type default)
		)
		(layer "In2.Cu")
	)
	(gr_line
		(start 348.133162 -65.093596)
		(end 348.229682 -65.093596)
		(stroke
			(width 0.05715)
			(type default)
		)
		(layer "In2.Cu")
	)
	(gr_line
		(start 348.160594 -82.993992)
		(end 348.207076 -83.01101)
		(stroke
			(width 0.05715)
			(type default)
		)
		(layer "In2.Cu")
	)
	(gr_line
		(start 348.207076 -83.01101)
		(end 348.25559 -82.99958)
		(stroke
			(width 0.05715)
			(type default)
		)
		(layer "In2.Cu")
	)
	(gr_line
		(start 348.246192 -83.703668)
		(end 348.286324 -83.7184)
		(stroke
			(width 0.05715)
			(type default)
		)
		(layer "In2.Cu")
	)
	(gr_arc
		(start 348.25051 -76.509626)
		(mid 348.331332 -76.476148)
		(end 348.36481 -76.395326)
		(stroke
			(width 0.05715)
			(type default)
		)
		(layer "In2.Cu")
	)
	(gr_line
		(start 348.28607 -56.338724)
		(end 348.367604 -56.322468)
		(stroke
			(width 0.05715)
			(type default)
		)
		(layer "In2.Cu")
	)
	(gr_line
		(start 348.286324 -83.7184)
		(end 348.328488 -83.710272)
		(stroke
			(width 0.05715)
			(type default)
		)
		(layer "In2.Cu")
	)
	(gr_line
		(start 348.331028 -91.329256)
		(end 348.352618 -91.333574)
		(stroke
			(width 0.05715)
			(type default)
		)
		(layer "In2.Cu")
	)
	(gr_line
		(start 348.341442 -74.475594)
		(end 348.358968 -74.464672)
		(stroke
			(width 0.05715)
			(type default)
		)
		(layer "In2.Cu")
	)
	(gr_line
		(start 348.342204 -74.475086)
		(end 348.358968 -74.464672)
		(stroke
			(width 0.05715)
			(type default)
		)
		(layer "In2.Cu")
	)
	(gr_line
		(start 348.347284 -53.474112)
		(end 348.358968 -53.456586)
		(stroke
			(width 0.05715)
			(type default)
		)
		(layer "In2.Cu")
	)
	(gr_line
		(start 348.352618 -91.333574)
		(end 348.374208 -91.329256)
		(stroke
			(width 0.05715)
			(type default)
		)
		(layer "In2.Cu")
	)
	(gr_line
		(start 348.352618 -90.588084)
		(end 348.371668 -90.591894)
		(stroke
			(width 0.05715)
			(type default)
		)
		(layer "In2.Cu")
	)
	(gr_line
		(start 348.352872 -90.588084)
		(end 348.371668 -90.591894)
		(stroke
			(width 0.05715)
			(type default)
		)
		(layer "In2.Cu")
	)
	(gr_line
		(start 348.358968 -74.464672)
		(end 348.370906 -74.447654)
		(stroke
			(width 0.05715)
			(type default)
		)
		(layer "In2.Cu")
	)
	(gr_line
		(start 348.358968 -74.464672)
		(end 348.371414 -74.447146)
		(stroke
			(width 0.05715)
			(type default)
		)
		(layer "In2.Cu")
	)
	(gr_line
		(start 348.358968 -53.456586)
		(end 348.362778 -53.43652)
		(stroke
			(width 0.05715)
			(type default)
		)
		(layer "In2.Cu")
	)
	(gr_line
		(start 348.359222 -65.550796)
		(end 348.521782 -65.388236)
		(stroke
			(width 0.05715)
			(type default)
		)
		(layer "In2.Cu")
	)
	(gr_line
		(start 348.36481 -75.900534)
		(end 348.472506 -75.834748)
		(stroke
			(width 0.05715)
			(type default)
		)
		(layer "In2.Cu")
	)
	(gr_line
		(start 348.367604 -56.322468)
		(end 348.41434 -56.252364)
		(stroke
			(width 0.05715)
			(type default)
		)
		(layer "In2.Cu")
	)
	(gr_line
		(start 348.371668 -90.591894)
		(end 348.390464 -90.588084)
		(stroke
			(width 0.05715)
			(type default)
		)
		(layer "In2.Cu")
	)
	(gr_line
		(start 348.371668 -90.591894)
		(end 348.390718 -90.588084)
		(stroke
			(width 0.05715)
			(type default)
		)
		(layer "In2.Cu")
	)
	(gr_line
		(start 348.39275 -60.4266)
		(end 348.44482 -60.47867)
		(stroke
			(width 0.05715)
			(type default)
		)
		(layer "In2.Cu")
	)
	(gr_line
		(start 348.39275 -58.957972)
		(end 348.44482 -58.905902)
		(stroke
			(width 0.05715)
			(type default)
		)
		(layer "In2.Cu")
	)
	(gr_line
		(start 348.422722 -72.694038)
		(end 348.465902 -72.671178)
		(stroke
			(width 0.05715)
			(type default)
		)
		(layer "In2.Cu")
	)
	(gr_line
		(start 348.465902 -72.671178)
		(end 348.490286 -72.628252)
		(stroke
			(width 0.05715)
			(type default)
		)
		(layer "In2.Cu")
	)
	(gr_line
		(start 348.50705 -58.230516)
		(end 348.537784 -58.186574)
		(stroke
			(width 0.05715)
			(type default)
		)
		(layer "In2.Cu")
	)
	(gr_line
		(start 348.57182 -86.985856)
		(end 348.618302 -87.004652)
		(stroke
			(width 0.05715)
			(type default)
		)
		(layer "In2.Cu")
	)
	(gr_line
		(start 348.572582 -86.98611)
		(end 348.618302 -87.004652)
		(stroke
			(width 0.05715)
			(type default)
		)
		(layer "In2.Cu")
	)
	(gr_line
		(start 348.576646 -50.871882)
		(end 348.580456 -50.851816)
		(stroke
			(width 0.05715)
			(type default)
		)
		(layer "In2.Cu")
	)
	(gr_line
		(start 348.580456 -50.851816)
		(end 348.59214 -50.83429)
		(stroke
			(width 0.05715)
			(type default)
		)
		(layer "In2.Cu")
	)
	(gr_line
		(start 348.609158 -82.915252)
		(end 348.62389 -82.91195)
		(stroke
			(width 0.05715)
			(type default)
		)
		(layer "In2.Cu")
	)
	(gr_line
		(start 348.618302 -87.004652)
		(end 348.667832 -86.994746)
		(stroke
			(width 0.05715)
			(type default)
		)
		(layer "In2.Cu")
	)
	(gr_line
		(start 348.62389 -82.91195)
		(end 348.637098 -82.90306)
		(stroke
			(width 0.05715)
			(type default)
		)
		(layer "In2.Cu")
	)
	(gr_line
		(start 348.627954 -85.715348)
		(end 348.628462 -85.715602)
		(stroke
			(width 0.05715)
			(type default)
		)
		(layer "In2.Cu")
	)
	(gr_line
		(start 348.628462 -85.715602)
		(end 348.629224 -85.715856)
		(stroke
			(width 0.05715)
			(type default)
		)
		(layer "In2.Cu")
	)
	(gr_line
		(start 348.65437 -57.010046)
		(end 348.736666 -56.993536)
		(stroke
			(width 0.05715)
			(type default)
		)
		(layer "In2.Cu")
	)
	(gr_arc
		(start 348.65691 -76.395326)
		(mid 348.690388 -76.476148)
		(end 348.77121 -76.509626)
		(stroke
			(width 0.05715)
			(type default)
		)
		(layer "In2.Cu")
	)
	(gr_line
		(start 348.736666 -56.993536)
		(end 348.782894 -56.924194)
		(stroke
			(width 0.05715)
			(type default)
		)
		(layer "In2.Cu")
	)
	(gr_line
		(start 348.77121 -76.509626)
		(end 349.20428 -76.509626)
		(stroke
			(width 0.05715)
			(type default)
		)
		(layer "In2.Cu")
	)
	(gr_line
		(start 348.788482 -115.89004)
		(end 348.807278 -115.893596)
		(stroke
			(width 0.05715)
			(type default)
		)
		(layer "In2.Cu")
	)
	(gr_line
		(start 348.807278 -115.893596)
		(end 348.826074 -115.89004)
		(stroke
			(width 0.05715)
			(type default)
		)
		(layer "In2.Cu")
	)
	(gr_line
		(start 348.86138 -60.47867)
		(end 348.91345 -60.4266)
		(stroke
			(width 0.05715)
			(type default)
		)
		(layer "In2.Cu")
	)
	(gr_line
		(start 348.86138 -58.905902)
		(end 348.91345 -58.957972)
		(stroke
			(width 0.05715)
			(type default)
		)
		(layer "In2.Cu")
	)
	(gr_line
		(start 348.882462 -65.388236)
		(end 349.045022 -65.550796)
		(stroke
			(width 0.05715)
			(type default)
		)
		(layer "In2.Cu")
	)
	(gr_line
		(start 348.91345 -60.4266)
		(end 349.3516 -60.4266)
		(stroke
			(width 0.05715)
			(type default)
		)
		(layer "In2.Cu")
	)
	(gr_line
		(start 348.91345 -58.957972)
		(end 349.3516 -58.957972)
		(stroke
			(width 0.05715)
			(type default)
		)
		(layer "In2.Cu")
	)
	(gr_line
		(start 349.045022 -65.550796)
		(end 349.400622 -65.550796)
		(stroke
			(width 0.05715)
			(type default)
		)
		(layer "In2.Cu")
	)
	(gr_line
		(start 349.050356 -53.702966)
		(end 349.06204 -53.685186)
		(stroke
			(width 0.05715)
			(type default)
		)
		(layer "In2.Cu")
	)
	(gr_line
		(start 349.06204 -53.685186)
		(end 349.06585 -53.66512)
		(stroke
			(width 0.05715)
			(type default)
		)
		(layer "In2.Cu")
	)
	(gr_line
		(start 349.163132 -70.851776)
		(end 349.18904 -70.80631)
		(stroke
			(width 0.05715)
			(type default)
		)
		(layer "In2.Cu")
	)
	(gr_line
		(start 349.174562 -65.093596)
		(end 349.271082 -65.093596)
		(stroke
			(width 0.05715)
			(type default)
		)
		(layer "In2.Cu")
	)
	(gr_line
		(start 349.18904 -70.80631)
		(end 349.235014 -70.78345)
		(stroke
			(width 0.05715)
			(type default)
		)
		(layer "In2.Cu")
	)
	(gr_line
		(start 349.287338 -51.068732)
		(end 349.291148 -51.049682)
		(stroke
			(width 0.05715)
			(type default)
		)
		(layer "In2.Cu")
	)
	(gr_line
		(start 349.291148 -51.049682)
		(end 349.30207 -51.032918)
		(stroke
			(width 0.05715)
			(type default)
		)
		(layer "In2.Cu")
	)
	(gr_line
		(start 349.394272 -85.905086)
		(end 349.421196 -85.91169)
		(stroke
			(width 0.05715)
			(type default)
		)
		(layer "In2.Cu")
	)
	(gr_line
		(start 349.400622 -65.550796)
		(end 349.563182 -65.388236)
		(stroke
			(width 0.05715)
			(type default)
		)
		(layer "In2.Cu")
	)
	(gr_line
		(start 349.413068 -123.09856)
		(end 349.453708 -123.124976)
		(stroke
			(width 0.05715)
			(type default)
		)
		(layer "In2.Cu")
	)
	(gr_line
		(start 349.421196 -85.91169)
		(end 349.447612 -85.90661)
		(stroke
			(width 0.05715)
			(type default)
		)
		(layer "In2.Cu")
	)
	(gr_line
		(start 349.614236 -81.891378)
		(end 349.632016 -81.87944)
		(stroke
			(width 0.05715)
			(type default)
		)
		(layer "In2.Cu")
	)
	(gr_line
		(start 349.632016 -81.87944)
		(end 349.653606 -81.875122)
		(stroke
			(width 0.05715)
			(type default)
		)
		(layer "In2.Cu")
	)
	(gr_line
		(start 349.667068 -54.37378)
		(end 349.677736 -54.357524)
		(stroke
			(width 0.05715)
			(type default)
		)
		(layer "In2.Cu")
	)
	(gr_line
		(start 349.677736 -54.357524)
		(end 349.681546 -54.338474)
		(stroke
			(width 0.05715)
			(type default)
		)
		(layer "In2.Cu")
	)
	(gr_line
		(start 349.69704 -115.422934)
		(end 349.715836 -115.419378)
		(stroke
			(width 0.05715)
			(type default)
		)
		(layer "In2.Cu")
	)
	(gr_line
		(start 349.715836 -115.419378)
		(end 349.734632 -115.422934)
		(stroke
			(width 0.05715)
			(type default)
		)
		(layer "In2.Cu")
	)
	(gr_line
		(start 349.79864 -69.346572)
		(end 349.800418 -69.345302)
		(stroke
			(width 0.05715)
			(type default)
		)
		(layer "In2.Cu")
	)
	(gr_line
		(start 349.800418 -69.345302)
		(end 349.803212 -69.344286)
		(stroke
			(width 0.05715)
			(type default)
		)
		(layer "In2.Cu")
	)
	(gr_line
		(start 349.878142 -62.10554)
		(end 349.878142 -62.335664)
		(stroke
			(width 0.05715)
			(type default)
		)
		(layer "In2.Cu")
	)
	(gr_line
		(start 349.878142 -62.10554)
		(end 350.120712 -61.86297)
		(stroke
			(width 0.05715)
			(type default)
		)
		(layer "In2.Cu")
	)
	(gr_line
		(start 349.890588 -67.4624)
		(end 350.127824 -67.225164)
		(stroke
			(width 0.05715)
			(type default)
		)
		(layer "In2.Cu")
	)
	(gr_line
		(start 350.014286 -51.18608)
		(end 350.018096 -51.16703)
		(stroke
			(width 0.05715)
			(type default)
		)
		(layer "In2.Cu")
	)
	(gr_line
		(start 350.018096 -51.16703)
		(end 350.028764 -51.150774)
		(stroke
			(width 0.05715)
			(type default)
		)
		(layer "In2.Cu")
	)
	(gr_line
		(start 350.099376 -85.780118)
		(end 350.12122 -85.7758)
		(stroke
			(width 0.05715)
			(type default)
		)
		(layer "In2.Cu")
	)
	(gr_line
		(start 350.120712 -61.86297)
		(end 350.350836 -61.86297)
		(stroke
			(width 0.05715)
			(type default)
		)
		(layer "In2.Cu")
	)
	(gr_line
		(start 350.12122 -85.7758)
		(end 350.139 -85.763862)
		(stroke
			(width 0.05715)
			(type default)
		)
		(layer "In2.Cu")
	)
	(gr_line
		(start 350.122744 -71.447914)
		(end 350.139 -71.4248)
		(stroke
			(width 0.05715)
			(type default)
		)
		(layer "In2.Cu")
	)
	(gr_line
		(start 350.139 -71.4248)
		(end 350.16313 -71.410322)
		(stroke
			(width 0.05715)
			(type default)
		)
		(layer "In2.Cu")
	)
	(gr_line
		(start 350.274382 -54.686962)
		(end 350.28505 -54.670706)
		(stroke
			(width 0.05715)
			(type default)
		)
		(layer "In2.Cu")
	)
	(gr_line
		(start 350.28505 -54.670706)
		(end 350.28886 -54.651656)
		(stroke
			(width 0.05715)
			(type default)
		)
		(layer "In2.Cu")
	)
	(gr_line
		(start 350.293178 -62.337188)
		(end 350.35236 -62.278006)
		(stroke
			(width 0.05715)
			(type default)
		)
		(layer "In2.Cu")
	)
	(gr_line
		(start 350.318578 -83.025742)
		(end 350.337374 -83.022186)
		(stroke
			(width 0.05715)
			(type default)
		)
		(layer "In2.Cu")
	)
	(gr_line
		(start 350.337374 -83.022186)
		(end 350.35617 -83.025742)
		(stroke
			(width 0.05715)
			(type default)
		)
		(layer "In2.Cu")
	)
	(gr_line
		(start 350.36506 -86.654386)
		(end 350.385888 -86.650068)
		(stroke
			(width 0.05715)
			(type default)
		)
		(layer "In2.Cu")
	)
	(gr_line
		(start 350.385888 -86.650068)
		(end 350.402906 -86.638638)
		(stroke
			(width 0.05715)
			(type default)
		)
		(layer "In2.Cu")
	)
	(gr_line
		(start 350.544638 -67.225164)
		(end 350.781874 -67.4624)
		(stroke
			(width 0.05715)
			(type default)
		)
		(layer "In2.Cu")
	)
	(gr_line
		(start 350.548702 -123.226322)
		(end 350.710246 -123.387866)
		(stroke
			(width 0.05715)
			(type default)
		)
		(layer "In2.Cu")
	)
	(gr_line
		(start 350.548702 -122.809762)
		(end 350.784414 -122.57405)
		(stroke
			(width 0.05715)
			(type default)
		)
		(layer "In2.Cu")
	)
	(gr_line
		(start 350.621092 -51.501548)
		(end 350.624902 -51.482498)
		(stroke
			(width 0.05715)
			(type default)
		)
		(layer "In2.Cu")
	)
	(gr_line
		(start 350.6216 -126.139448)
		(end 350.659192 -126.162816)
		(stroke
			(width 0.05715)
			(type default)
		)
		(layer "In2.Cu")
	)
	(gr_line
		(start 350.624902 -51.482498)
		(end 350.63557 -51.466242)
		(stroke
			(width 0.05715)
			(type default)
		)
		(layer "In2.Cu")
	)
	(gr_line
		(start 350.672654 -76.57211)
		(end 351.094802 -76.57211)
		(stroke
			(width 0.05715)
			(type default)
		)
		(layer "In2.Cu")
	)
	(gr_line
		(start 350.708214 -123.822206)
		(end 350.710246 -123.387866)
		(stroke
			(width 0.05715)
			(type default)
		)
		(layer "In2.Cu")
	)
	(gr_line
		(start 350.7486 -60.4266)
		(end 351.18675 -60.4266)
		(stroke
			(width 0.05715)
			(type default)
		)
		(layer "In2.Cu")
	)
	(gr_line
		(start 350.7486 -58.957972)
		(end 351.18675 -58.957972)
		(stroke
			(width 0.05715)
			(type default)
		)
		(layer "In2.Cu")
	)
	(gr_line
		(start 350.800416 -55.462424)
		(end 350.813878 -55.44312)
		(stroke
			(width 0.05715)
			(type default)
		)
		(layer "In2.Cu")
	)
	(gr_line
		(start 350.813878 -55.44312)
		(end 350.818196 -55.420514)
		(stroke
			(width 0.05715)
			(type default)
		)
		(layer "In2.Cu")
	)
	(gr_line
		(start 350.845374 -115.638834)
		(end 350.867218 -115.643152)
		(stroke
			(width 0.05715)
			(type default)
		)
		(layer "In2.Cu")
	)
	(gr_line
		(start 350.86163 -83.421728)
		(end 350.880426 -83.425284)
		(stroke
			(width 0.05715)
			(type default)
		)
		(layer "In2.Cu")
	)
	(gr_line
		(start 350.867218 -115.643152)
		(end 350.884998 -115.65509)
		(stroke
			(width 0.05715)
			(type default)
		)
		(layer "In2.Cu")
	)
	(gr_line
		(start 350.880426 -83.425284)
		(end 350.899222 -83.421728)
		(stroke
			(width 0.05715)
			(type default)
		)
		(layer "In2.Cu")
	)
	(gr_line
		(start 351.019872 -116.098574)
		(end 351.51568 -116.432838)
		(stroke
			(width 0.05715)
			(type default)
		)
		(layer "In2.Cu")
	)
	(gr_line
		(start 351.02038 -116.098828)
		(end 351.514664 -116.43233)
		(stroke
			(width 0.05715)
			(type default)
		)
		(layer "In2.Cu")
	)
	(gr_line
		(start 351.0407 -36.617656)
		(end 351.061782 -36.581842)
		(stroke
			(width 0.05715)
			(type default)
		)
		(layer "In2.Cu")
	)
	(gr_arc
		(start 351.094802 -76.57211)
		(mid 351.170811 -76.543174)
		(end 351.20834 -76.471018)
		(stroke
			(width 0.05715)
			(type default)
		)
		(layer "In2.Cu")
	)
	(gr_line
		(start 351.152206 -84.727796)
		(end 351.169986 -84.715858)
		(stroke
			(width 0.05715)
			(type default)
		)
		(layer "In2.Cu")
	)
	(gr_line
		(start 351.155 -115.83416)
		(end 351.380806 -115.790218)
		(stroke
			(width 0.05715)
			(type default)
		)
		(layer "In2.Cu")
	)
	(gr_line
		(start 351.169986 -84.715858)
		(end 351.19183 -84.71154)
		(stroke
			(width 0.05715)
			(type default)
		)
		(layer "In2.Cu")
	)
	(gr_line
		(start 351.18675 -60.4266)
		(end 351.23882 -60.47867)
		(stroke
			(width 0.05715)
			(type default)
		)
		(layer "In2.Cu")
	)
	(gr_line
		(start 351.18675 -58.957972)
		(end 351.23882 -58.905902)
		(stroke
			(width 0.05715)
			(type default)
		)
		(layer "In2.Cu")
	)
	(gr_line
		(start 351.209102 -75.856338)
		(end 351.222056 -75.83043)
		(stroke
			(width 0.05715)
			(type default)
		)
		(layer "In2.Cu")
	)
	(gr_line
		(start 351.245678 -51.793648)
		(end 351.249488 -51.773582)
		(stroke
			(width 0.05715)
			(type default)
		)
		(layer "In2.Cu")
	)
	(gr_line
		(start 351.249488 -51.773582)
		(end 351.261172 -51.755802)
		(stroke
			(width 0.05715)
			(type default)
		)
		(layer "In2.Cu")
	)
	(gr_line
		(start 351.294192 -126.227332)
		(end 351.344992 -126.278132)
		(stroke
			(width 0.05715)
			(type default)
		)
		(layer "In2.Cu")
	)
	(gr_line
		(start 351.294192 -125.810772)
		(end 351.347024 -125.75794)
		(stroke
			(width 0.05715)
			(type default)
		)
		(layer "In2.Cu")
	)
	(gr_line
		(start 351.30105 -58.589418)
		(end 351.332038 -58.545222)
		(stroke
			(width 0.05715)
			(type default)
		)
		(layer "In2.Cu")
	)
	(gr_line
		(start 351.30486 -45.774102)
		(end 351.3328 -45.731938)
		(stroke
			(width 0.05715)
			(type default)
		)
		(layer "In2.Cu")
	)
	(gr_line
		(start 351.343214 -126.64313)
		(end 351.344992 -126.278132)
		(stroke
			(width 0.05715)
			(type default)
		)
		(layer "In2.Cu")
	)
	(gr_line
		(start 351.347024 -125.75794)
		(end 351.348802 -125.392942)
		(stroke
			(width 0.05715)
			(type default)
		)
		(layer "In2.Cu")
	)
	(gr_line
		(start 351.380806 -115.790218)
		(end 351.665032 -115.981988)
		(stroke
			(width 0.05715)
			(type default)
		)
		(layer "In2.Cu")
	)
	(gr_line
		(start 351.382838 -36.038282)
		(end 351.415096 -35.983672)
		(stroke
			(width 0.05715)
			(type default)
		)
		(layer "In2.Cu")
	)
	(gr_line
		(start 351.406968 -85.608668)
		(end 351.42551 -85.596222)
		(stroke
			(width 0.05715)
			(type default)
		)
		(layer "In2.Cu")
	)
	(gr_line
		(start 351.415096 -35.983672)
		(end 351.474024 -35.960812)
		(stroke
			(width 0.05715)
			(type default)
		)
		(layer "In2.Cu")
	)
	(gr_line
		(start 351.42551 -85.596222)
		(end 351.447608 -85.591904)
		(stroke
			(width 0.05715)
			(type default)
		)
		(layer "In2.Cu")
	)
	(gr_line
		(start 351.474024 -69.064886)
		(end 351.549208 -69.03847)
		(stroke
			(width 0.05715)
			(type default)
		)
		(layer "In2.Cu")
	)
	(gr_arc
		(start 351.502472 -76.47432)
		(mid 351.540749 -76.544292)
		(end 351.615502 -76.57211)
		(stroke
			(width 0.05715)
			(type default)
		)
		(layer "In2.Cu")
	)
	(gr_line
		(start 351.508568 -74.324972)
		(end 351.549208 -74.30008)
		(stroke
			(width 0.05715)
			(type default)
		)
		(layer "In2.Cu")
	)
	(gr_line
		(start 351.508822 -74.324718)
		(end 351.549208 -74.30008)
		(stroke
			(width 0.05715)
			(type default)
		)
		(layer "In2.Cu")
	)
	(gr_line
		(start 351.5233 -75.216766)
		(end 351.559368 -75.14336)
		(stroke
			(width 0.05715)
			(type default)
		)
		(layer "In2.Cu")
	)
	(gr_line
		(start 351.549208 -74.30008)
		(end 351.57029 -74.257408)
		(stroke
			(width 0.05715)
			(type default)
		)
		(layer "In2.Cu")
	)
	(gr_line
		(start 351.549208 -74.30008)
		(end 351.570798 -74.256646)
		(stroke
			(width 0.05715)
			(type default)
		)
		(layer "In2.Cu")
	)
	(gr_line
		(start 351.549208 -69.03847)
		(end 351.585276 -68.967858)
		(stroke
			(width 0.05715)
			(type default)
		)
		(layer "In2.Cu")
	)
	(gr_line
		(start 351.549208 -69.03847)
		(end 351.585784 -68.967096)
		(stroke
			(width 0.05715)
			(type default)
		)
		(layer "In2.Cu")
	)
	(gr_line
		(start 351.559368 -75.14336)
		(end 351.637092 -75.116944)
		(stroke
			(width 0.05715)
			(type default)
		)
		(layer "In2.Cu")
	)
	(gr_line
		(start 351.615502 -76.57211)
		(end 352.069654 -76.57211)
		(stroke
			(width 0.05715)
			(type default)
		)
		(layer "In2.Cu")
	)
	(gr_line
		(start 351.636838 -82.97799)
		(end 351.765616 -82.787236)
		(stroke
			(width 0.05715)
			(type default)
		)
		(layer "In2.Cu")
	)
	(gr_line
		(start 351.65538 -60.47867)
		(end 351.70745 -60.4266)
		(stroke
			(width 0.05715)
			(type default)
		)
		(layer "In2.Cu")
	)
	(gr_line
		(start 351.65538 -58.905902)
		(end 351.70745 -58.957972)
		(stroke
			(width 0.05715)
			(type default)
		)
		(layer "In2.Cu")
	)
	(gr_line
		(start 351.665032 -115.981988)
		(end 351.70872 -116.207794)
		(stroke
			(width 0.05715)
			(type default)
		)
		(layer "In2.Cu")
	)
	(gr_line
		(start 351.70745 -60.4266)
		(end 352.1456 -60.4266)
		(stroke
			(width 0.05715)
			(type default)
		)
		(layer "In2.Cu")
	)
	(gr_line
		(start 351.70745 -58.957972)
		(end 352.1456 -58.957972)
		(stroke
			(width 0.05715)
			(type default)
		)
		(layer "In2.Cu")
	)
	(gr_line
		(start 351.728278 -83.260184)
		(end 352.314002 -83.146392)
		(stroke
			(width 0.05715)
			(type default)
		)
		(layer "In2.Cu")
	)
	(gr_line
		(start 351.728278 -83.260184)
		(end 352.31451 -83.146392)
		(stroke
			(width 0.05715)
			(type default)
		)
		(layer "In2.Cu")
	)
	(gr_line
		(start 351.765616 -82.787236)
		(end 352.102166 -82.721704)
		(stroke
			(width 0.05715)
			(type default)
		)
		(layer "In2.Cu")
	)
	(gr_line
		(start 351.83953 -69.81571)
		(end 351.893124 -69.78904)
		(stroke
			(width 0.05715)
			(type default)
		)
		(layer "In2.Cu")
	)
	(gr_line
		(start 351.860612 -116.665756)
		(end 352.357436 -117.000782)
		(stroke
			(width 0.05715)
			(type default)
		)
		(layer "In2.Cu")
	)
	(gr_line
		(start 351.861374 -116.66601)
		(end 352.357182 -117.000528)
		(stroke
			(width 0.05715)
			(type default)
		)
		(layer "In2.Cu")
	)
	(gr_line
		(start 351.861628 -75.040236)
		(end 351.940876 -75.013312)
		(stroke
			(width 0.05715)
			(type default)
		)
		(layer "In2.Cu")
	)
	(gr_line
		(start 351.883726 -58.268108)
		(end 351.897696 -58.248042)
		(stroke
			(width 0.05715)
			(type default)
		)
		(layer "In2.Cu")
	)
	(gr_line
		(start 351.887282 -84.576412)
		(end 351.906078 -84.572856)
		(stroke
			(width 0.05715)
			(type default)
		)
		(layer "In2.Cu")
	)
	(gr_line
		(start 351.893124 -69.78904)
		(end 351.920302 -69.735954)
		(stroke
			(width 0.05715)
			(type default)
		)
		(layer "In2.Cu")
	)
	(gr_line
		(start 351.897696 -58.248042)
		(end 351.902522 -58.224166)
		(stroke
			(width 0.05715)
			(type default)
		)
		(layer "In2.Cu")
	)
	(gr_line
		(start 351.906078 -84.572856)
		(end 351.924874 -84.576412)
		(stroke
			(width 0.05715)
			(type default)
		)
		(layer "In2.Cu")
	)
	(gr_line
		(start 351.940876 -75.013312)
		(end 352.016568 -75.050396)
		(stroke
			(width 0.05715)
			(type default)
		)
		(layer "In2.Cu")
	)
	(gr_line
		(start 351.962974 -85.491574)
		(end 351.98177 -85.488018)
		(stroke
			(width 0.05715)
			(type default)
		)
		(layer "In2.Cu")
	)
	(gr_line
		(start 351.98177 -85.488018)
		(end 352.000566 -85.491574)
		(stroke
			(width 0.05715)
			(type default)
		)
		(layer "In2.Cu")
	)
	(gr_line
		(start 351.997264 -116.402358)
		(end 352.22307 -116.358416)
		(stroke
			(width 0.05715)
			(type default)
		)
		(layer "In2.Cu")
	)
	(gr_line
		(start 352.012504 -74.22134)
		(end 352.039428 -74.300588)
		(stroke
			(width 0.05715)
			(type default)
		)
		(layer "In2.Cu")
	)
	(gr_line
		(start 352.012504 -74.22134)
		(end 352.049588 -74.145648)
		(stroke
			(width 0.05715)
			(type default)
		)
		(layer "In2.Cu")
	)
	(gr_line
		(start 352.102166 -82.721704)
		(end 352.29292 -82.850482)
		(stroke
			(width 0.05715)
			(type default)
		)
		(layer "In2.Cu")
	)
	(gr_line
		(start 352.105722 -89.547192)
		(end 352.126042 -89.543128)
		(stroke
			(width 0.05715)
			(type default)
		)
		(layer "In2.Cu")
	)
	(gr_line
		(start 352.116136 -74.525124)
		(end 352.142552 -74.602848)
		(stroke
			(width 0.05715)
			(type default)
		)
		(layer "In2.Cu")
	)
	(gr_line
		(start 352.126042 -89.543128)
		(end 352.145092 -89.546938)
		(stroke
			(width 0.05715)
			(type default)
		)
		(layer "In2.Cu")
	)
	(gr_line
		(start 352.142552 -74.602848)
		(end 352.215958 -74.638916)
		(stroke
			(width 0.05715)
			(type default)
		)
		(layer "In2.Cu")
	)
	(gr_line
		(start 352.16846 -90.2589)
		(end 352.189796 -90.254582)
		(stroke
			(width 0.05715)
			(type default)
		)
		(layer "In2.Cu")
	)
	(gr_line
		(start 352.184716 -73.87082)
		(end 352.220784 -73.797414)
		(stroke
			(width 0.05715)
			(type default)
		)
		(layer "In2.Cu")
	)
	(gr_line
		(start 352.189796 -90.254582)
		(end 352.211132 -90.2589)
		(stroke
			(width 0.05715)
			(type default)
		)
		(layer "In2.Cu")
	)
	(gr_line
		(start 352.206814 -75.46975)
		(end 352.282506 -75.506834)
		(stroke
			(width 0.05715)
			(type default)
		)
		(layer "In2.Cu")
	)
	(gr_line
		(start 352.21037 -70.534784)
		(end 352.252026 -70.509892)
		(stroke
			(width 0.05715)
			(type default)
		)
		(layer "In2.Cu")
	)
	(gr_line
		(start 352.220784 -73.797414)
		(end 352.298508 -73.770998)
		(stroke
			(width 0.05715)
			(type default)
		)
		(layer "In2.Cu")
	)
	(gr_line
		(start 352.22307 -116.358416)
		(end 352.507296 -116.549932)
		(stroke
			(width 0.05715)
			(type default)
		)
		(layer "In2.Cu")
	)
	(gr_line
		(start 352.252026 -70.509892)
		(end 352.27387 -70.46722)
		(stroke
			(width 0.05715)
			(type default)
		)
		(layer "In2.Cu")
	)
	(gr_line
		(start 352.277934 -157.655006)
		(end 352.300794 -157.655006)
		(stroke
			(width 0.0635)
			(type default)
		)
		(layer "In2.Cu")
	)
	(gr_line
		(start 352.282506 -75.506834)
		(end 352.361754 -75.47991)
		(stroke
			(width 0.05715)
			(type default)
		)
		(layer "In2.Cu")
	)
	(gr_line
		(start 352.2853 -38.979602)
		(end 352.31324 -38.937438)
		(stroke
			(width 0.05715)
			(type default)
		)
		(layer "In2.Cu")
	)
	(gr_line
		(start 352.300794 -157.655006)
		(end 352.573844 -157.381956)
		(stroke
			(width 0.0635)
			(type default)
		)
		(layer "In2.Cu")
	)
	(gr_line
		(start 352.356166 -82.27949)
		(end 352.374962 -82.283046)
		(stroke
			(width 0.05715)
			(type default)
		)
		(layer "In2.Cu")
	)
	(gr_line
		(start 352.374962 -82.283046)
		(end 352.393758 -82.27949)
		(stroke
			(width 0.05715)
			(type default)
		)
		(layer "In2.Cu")
	)
	(gr_line
		(start 352.507296 -116.549932)
		(end 352.551238 -116.775992)
		(stroke
			(width 0.05715)
			(type default)
		)
		(layer "In2.Cu")
	)
	(gr_line
		(start 352.523044 -73.69429)
		(end 352.602292 -73.667366)
		(stroke
			(width 0.05715)
			(type default)
		)
		(layer "In2.Cu")
	)
	(gr_line
		(start 352.54946 -45.425106)
		(end 352.5774 -45.382942)
		(stroke
			(width 0.05715)
			(type default)
		)
		(layer "In2.Cu")
	)
	(gr_line
		(start 352.585528 -75.403456)
		(end 352.664268 -75.376532)
		(stroke
			(width 0.05715)
			(type default)
		)
		(layer "In2.Cu")
	)
	(gr_line
		(start 352.585782 -75.403456)
		(end 352.664268 -75.376532)
		(stroke
			(width 0.05715)
			(type default)
		)
		(layer "In2.Cu")
	)
	(gr_line
		(start 352.602292 -73.667366)
		(end 352.677984 -73.70445)
		(stroke
			(width 0.05715)
			(type default)
		)
		(layer "In2.Cu")
	)
	(gr_line
		(start 352.611182 -85.908134)
		(end 352.629978 -85.91169)
		(stroke
			(width 0.05715)
			(type default)
		)
		(layer "In2.Cu")
	)
	(gr_line
		(start 352.629978 -85.91169)
		(end 352.648774 -85.908134)
		(stroke
			(width 0.05715)
			(type default)
		)
		(layer "In2.Cu")
	)
	(gr_line
		(start 352.634042 -82.784188)
		(end 352.76282 -82.59318)
		(stroke
			(width 0.05715)
			(type default)
		)
		(layer "In2.Cu")
	)
	(gr_line
		(start 352.664268 -75.376532)
		(end 352.700844 -75.302364)
		(stroke
			(width 0.05715)
			(type default)
		)
		(layer "In2.Cu")
	)
	(gr_line
		(start 352.668586 -74.535792)
		(end 352.741992 -74.57186)
		(stroke
			(width 0.05715)
			(type default)
		)
		(layer "In2.Cu")
	)
	(gr_line
		(start 352.67392 -72.87514)
		(end 352.700844 -72.954134)
		(stroke
			(width 0.05715)
			(type default)
		)
		(layer "In2.Cu")
	)
	(gr_line
		(start 352.67392 -72.87514)
		(end 352.711004 -72.80021)
		(stroke
			(width 0.05715)
			(type default)
		)
		(layer "In2.Cu")
	)
	(gr_line
		(start 352.676714 -85.020404)
		(end 352.69551 -85.02396)
		(stroke
			(width 0.05715)
			(type default)
		)
		(layer "In2.Cu")
	)
	(gr_line
		(start 352.69551 -85.02396)
		(end 352.714306 -85.020404)
		(stroke
			(width 0.05715)
			(type default)
		)
		(layer "In2.Cu")
	)
	(gr_line
		(start 352.723958 -83.066636)
		(end 353.31146 -82.95259)
		(stroke
			(width 0.05715)
			(type default)
		)
		(layer "In2.Cu")
	)
	(gr_line
		(start 352.725228 -83.066382)
		(end 353.310698 -82.95259)
		(stroke
			(width 0.05715)
			(type default)
		)
		(layer "In2.Cu")
	)
	(gr_line
		(start 352.741992 -74.57186)
		(end 352.768916 -74.6506)
		(stroke
			(width 0.05715)
			(type default)
		)
		(layer "In2.Cu")
	)
	(gr_line
		(start 352.741992 -74.57186)
		(end 352.768916 -74.650346)
		(stroke
			(width 0.05715)
			(type default)
		)
		(layer "In2.Cu")
	)
	(gr_line
		(start 352.748088 -121.747026)
		(end 352.772726 -121.75236)
		(stroke
			(width 0.05715)
			(type default)
		)
		(layer "In2.Cu")
	)
	(gr_line
		(start 352.76282 -82.59318)
		(end 353.09937 -82.527902)
		(stroke
			(width 0.05715)
			(type default)
		)
		(layer "In2.Cu")
	)
	(gr_line
		(start 352.772726 -121.75236)
		(end 352.793046 -121.7676)
		(stroke
			(width 0.05715)
			(type default)
		)
		(layer "In2.Cu")
	)
	(gr_line
		(start 352.777298 -73.178416)
		(end 352.804222 -73.256902)
		(stroke
			(width 0.05715)
			(type default)
		)
		(layer "In2.Cu")
	)
	(gr_line
		(start 352.804222 -73.256902)
		(end 352.87839 -73.293478)
		(stroke
			(width 0.05715)
			(type default)
		)
		(layer "In2.Cu")
	)
	(gr_line
		(start 352.83521 -75.029314)
		(end 352.872294 -74.953622)
		(stroke
			(width 0.05715)
			(type default)
		)
		(layer "In2.Cu")
	)
	(gr_line
		(start 352.835464 -75.028552)
		(end 352.872294 -74.953622)
		(stroke
			(width 0.05715)
			(type default)
		)
		(layer "In2.Cu")
	)
	(gr_line
		(start 352.845116 -74.873612)
		(end 352.872294 -74.953622)
		(stroke
			(width 0.05715)
			(type default)
		)
		(layer "In2.Cu")
	)
	(gr_line
		(start 352.84537 -74.874374)
		(end 352.872294 -74.953622)
		(stroke
			(width 0.05715)
			(type default)
		)
		(layer "In2.Cu")
	)
	(gr_line
		(start 352.86823 -74.123804)
		(end 352.943922 -74.160888)
		(stroke
			(width 0.05715)
			(type default)
		)
		(layer "In2.Cu")
	)
	(gr_line
		(start 352.895662 -55.315104)
		(end 352.903536 -55.35422)
		(stroke
			(width 0.05715)
			(type default)
		)
		(layer "In2.Cu")
	)
	(gr_line
		(start 352.895662 -55.315104)
		(end 352.903536 -55.353712)
		(stroke
			(width 0.05715)
			(type default)
		)
		(layer "In2.Cu")
	)
	(gr_line
		(start 352.895662 -55.315104)
		(end 352.9076 -55.278274)
		(stroke
			(width 0.05715)
			(type default)
		)
		(layer "In2.Cu")
	)
	(gr_line
		(start 352.895662 -55.315104)
		(end 352.907854 -55.27802)
		(stroke
			(width 0.05715)
			(type default)
		)
		(layer "In2.Cu")
	)
	(gr_line
		(start 352.903536 -55.353712)
		(end 352.903536 -55.353966)
		(stroke
			(width 0.05715)
			(type default)
		)
		(layer "In2.Cu")
	)
	(gr_line
		(start 352.936556 -157.381956)
		(end 353.209606 -157.655006)
		(stroke
			(width 0.0635)
			(type default)
		)
		(layer "In2.Cu")
	)
	(gr_line
		(start 352.943922 -74.160888)
		(end 353.02317 -74.133964)
		(stroke
			(width 0.05715)
			(type default)
		)
		(layer "In2.Cu")
	)
	(gr_line
		(start 353.09937 -82.527902)
		(end 353.290124 -82.656426)
		(stroke
			(width 0.05715)
			(type default)
		)
		(layer "In2.Cu")
	)
	(gr_line
		(start 353.209606 -157.655006)
		(end 353.276154 -157.655006)
		(stroke
			(width 0.0635)
			(type default)
		)
		(layer "In2.Cu")
	)
	(gr_line
		(start 353.239324 -50.052224)
		(end 353.243388 -50.032158)
		(stroke
			(width 0.05715)
			(type default)
		)
		(layer "In2.Cu")
	)
	(gr_line
		(start 353.243388 -50.032158)
		(end 353.254818 -50.01514)
		(stroke
			(width 0.05715)
			(type default)
		)
		(layer "In2.Cu")
	)
	(gr_line
		(start 353.246944 -74.05751)
		(end 353.325684 -74.030586)
		(stroke
			(width 0.05715)
			(type default)
		)
		(layer "In2.Cu")
	)
	(gr_line
		(start 353.247198 -74.05751)
		(end 353.325684 -74.030586)
		(stroke
			(width 0.05715)
			(type default)
		)
		(layer "In2.Cu")
	)
	(gr_line
		(start 353.325684 -74.030586)
		(end 353.36226 -73.956418)
		(stroke
			(width 0.05715)
			(type default)
		)
		(layer "In2.Cu")
	)
	(gr_line
		(start 353.32924 -73.189338)
		(end 353.403408 -73.225914)
		(stroke
			(width 0.05715)
			(type default)
		)
		(layer "In2.Cu")
	)
	(gr_line
		(start 353.370896 -57.634124)
		(end 353.375468 -57.656476)
		(stroke
			(width 0.05715)
			(type default)
		)
		(layer "In2.Cu")
	)
	(gr_line
		(start 353.375468 -57.656476)
		(end 353.387914 -57.674002)
		(stroke
			(width 0.05715)
			(type default)
		)
		(layer "In2.Cu")
	)
	(gr_line
		(start 353.393502 -117.699282)
		(end 353.411282 -117.71122)
		(stroke
			(width 0.05715)
			(type default)
		)
		(layer "In2.Cu")
	)
	(gr_line
		(start 353.403408 -73.225914)
		(end 353.430332 -73.304654)
		(stroke
			(width 0.05715)
			(type default)
		)
		(layer "In2.Cu")
	)
	(gr_line
		(start 353.403408 -73.225914)
		(end 353.430332 -73.3044)
		(stroke
			(width 0.05715)
			(type default)
		)
		(layer "In2.Cu")
	)
	(gr_line
		(start 353.411282 -117.71122)
		(end 353.433126 -117.715538)
		(stroke
			(width 0.05715)
			(type default)
		)
		(layer "In2.Cu")
	)
	(gr_line
		(start 353.485958 -81.769204)
		(end 353.504754 -81.765648)
		(stroke
			(width 0.05715)
			(type default)
		)
		(layer "In2.Cu")
	)
	(gr_line
		(start 353.496626 -73.683368)
		(end 353.53371 -73.607676)
		(stroke
			(width 0.05715)
			(type default)
		)
		(layer "In2.Cu")
	)
	(gr_line
		(start 353.49688 -73.682606)
		(end 353.53371 -73.607676)
		(stroke
			(width 0.05715)
			(type default)
		)
		(layer "In2.Cu")
	)
	(gr_line
		(start 353.504754 -81.765648)
		(end 353.52355 -81.769204)
		(stroke
			(width 0.05715)
			(type default)
		)
		(layer "In2.Cu")
	)
	(gr_line
		(start 353.506532 -73.527666)
		(end 353.53371 -73.607676)
		(stroke
			(width 0.05715)
			(type default)
		)
		(layer "In2.Cu")
	)
	(gr_line
		(start 353.506786 -73.528428)
		(end 353.53371 -73.607676)
		(stroke
			(width 0.05715)
			(type default)
		)
		(layer "In2.Cu")
	)
	(gr_line
		(start 353.5426 -60.4266)
		(end 353.964494 -60.4266)
		(stroke
			(width 0.05715)
			(type default)
		)
		(layer "In2.Cu")
	)
	(gr_line
		(start 353.5426 -58.957972)
		(end 353.98075 -58.957972)
		(stroke
			(width 0.05715)
			(type default)
		)
		(layer "In2.Cu")
	)
	(gr_line
		(start 353.60229 -76.720954)
		(end 354.04044 -76.720954)
		(stroke
			(width 0.05715)
			(type default)
		)
		(layer "In2.Cu")
	)
	(gr_line
		(start 353.7585 -38.074854)
		(end 353.786186 -38.033198)
		(stroke
			(width 0.05715)
			(type default)
		)
		(layer "In2.Cu")
	)
	(gr_line
		(start 353.853496 -71.943468)
		(end 353.866704 -72.01789)
		(stroke
			(width 0.05715)
			(type default)
		)
		(layer "In2.Cu")
	)
	(gr_line
		(start 353.853496 -71.943468)
		(end 353.866704 -72.017636)
		(stroke
			(width 0.05715)
			(type default)
		)
		(layer "In2.Cu")
	)
	(gr_line
		(start 353.853496 -71.943468)
		(end 353.893882 -71.87946)
		(stroke
			(width 0.05715)
			(type default)
		)
		(layer "In2.Cu")
	)
	(gr_line
		(start 353.866704 -72.017636)
		(end 353.866704 -72.018144)
		(stroke
			(width 0.05715)
			(type default)
		)
		(layer "In2.Cu")
	)
	(gr_line
		(start 353.893882 -71.879206)
		(end 353.893882 -71.87946)
		(stroke
			(width 0.05715)
			(type default)
		)
		(layer "In2.Cu")
	)
	(gr_line
		(start 353.915218 -82.5373)
		(end 353.934014 -82.533744)
		(stroke
			(width 0.05715)
			(type default)
		)
		(layer "In2.Cu")
	)
	(gr_line
		(start 353.934014 -82.533744)
		(end 353.95281 -82.5373)
		(stroke
			(width 0.05715)
			(type default)
		)
		(layer "In2.Cu")
	)
	(gr_line
		(start 353.962716 -120.12676)
		(end 353.984814 -120.131332)
		(stroke
			(width 0.05715)
			(type default)
		)
		(layer "In2.Cu")
	)
	(gr_line
		(start 353.964494 -60.4266)
		(end 354.024692 -60.486798)
		(stroke
			(width 0.05715)
			(type default)
		)
		(layer "In2.Cu")
	)
	(gr_line
		(start 353.98075 -58.957972)
		(end 354.03282 -58.905902)
		(stroke
			(width 0.05715)
			(type default)
		)
		(layer "In2.Cu")
	)
	(gr_line
		(start 353.984814 -120.131332)
		(end 354.006404 -120.12676)
		(stroke
			(width 0.05715)
			(type default)
		)
		(layer "In2.Cu")
	)
	(gr_line
		(start 354.02266 -44.47921)
		(end 354.0506 -44.437046)
		(stroke
			(width 0.05715)
			(type default)
		)
		(layer "In2.Cu")
	)
	(gr_arc
		(start 354.04044 -76.720954)
		(mid 354.121262 -76.687476)
		(end 354.15474 -76.606654)
		(stroke
			(width 0.05715)
			(type default)
		)
		(layer "In2.Cu")
	)
	(gr_line
		(start 354.067872 -62.098936)
		(end 354.085906 -62.052962)
		(stroke
			(width 0.05715)
			(type default)
		)
		(layer "In2.Cu")
	)
	(gr_line
		(start 354.085906 -62.052962)
		(end 354.125784 -62.023752)
		(stroke
			(width 0.05715)
			(type default)
		)
		(layer "In2.Cu")
	)
	(gr_line
		(start 354.121212 -123.116594)
		(end 354.155248 -123.343924)
		(stroke
			(width 0.05715)
			(type default)
		)
		(layer "In2.Cu")
	)
	(gr_line
		(start 354.155248 -123.343924)
		(end 354.430838 -123.547886)
		(stroke
			(width 0.05715)
			(type default)
		)
		(layer "In2.Cu")
	)
	(gr_line
		(start 354.28428 -85.292438)
		(end 354.303076 -85.288882)
		(stroke
			(width 0.05715)
			(type default)
		)
		(layer "In2.Cu")
	)
	(gr_line
		(start 354.303076 -85.288882)
		(end 354.321872 -85.292438)
		(stroke
			(width 0.05715)
			(type default)
		)
		(layer "In2.Cu")
	)
	(gr_line
		(start 354.311204 -35.939984)
		(end 354.32746 -35.9156)
		(stroke
			(width 0.05715)
			(type default)
		)
		(layer "In2.Cu")
	)
	(gr_line
		(start 354.325936 -122.90171)
		(end 354.80498 -123.25604)
		(stroke
			(width 0.05715)
			(type default)
		)
		(layer "In2.Cu")
	)
	(gr_line
		(start 354.32746 -35.9156)
		(end 354.352606 -35.90036)
		(stroke
			(width 0.05715)
			(type default)
		)
		(layer "In2.Cu")
	)
	(gr_line
		(start 354.356162 -58.545222)
		(end 354.38715 -58.589418)
		(stroke
			(width 0.05715)
			(type default)
		)
		(layer "In2.Cu")
	)
	(gr_line
		(start 354.3935 -38.291008)
		(end 354.421186 -38.249352)
		(stroke
			(width 0.05715)
			(type default)
		)
		(layer "In2.Cu")
	)
	(gr_line
		(start 354.430838 -123.547886)
		(end 354.658422 -123.51385)
		(stroke
			(width 0.05715)
			(type default)
		)
		(layer "In2.Cu")
	)
	(gr_line
		(start 354.441252 -60.486798)
		(end 354.50145 -60.4266)
		(stroke
			(width 0.05715)
			(type default)
		)
		(layer "In2.Cu")
	)
	(gr_arc
		(start 354.44684 -76.606654)
		(mid 354.480318 -76.687476)
		(end 354.56114 -76.720954)
		(stroke
			(width 0.05715)
			(type default)
		)
		(layer "In2.Cu")
	)
	(gr_line
		(start 354.44938 -58.905902)
		(end 354.50145 -58.957972)
		(stroke
			(width 0.05715)
			(type default)
		)
		(layer "In2.Cu")
	)
	(gr_line
		(start 354.50145 -60.4266)
		(end 354.9396 -60.4266)
		(stroke
			(width 0.05715)
			(type default)
		)
		(layer "In2.Cu")
	)
	(gr_line
		(start 354.50145 -58.957972)
		(end 354.9396 -58.957972)
		(stroke
			(width 0.05715)
			(type default)
		)
		(layer "In2.Cu")
	)
	(gr_line
		(start 354.56114 -76.720954)
		(end 354.99929 -76.720954)
		(stroke
			(width 0.05715)
			(type default)
		)
		(layer "In2.Cu")
	)
	(gr_line
		(start 354.576888 -120.900952)
		(end 354.595938 -120.904762)
		(stroke
			(width 0.05715)
			(type default)
		)
		(layer "In2.Cu")
	)
	(gr_line
		(start 354.595938 -120.904762)
		(end 354.614988 -120.900952)
		(stroke
			(width 0.05715)
			(type default)
		)
		(layer "In2.Cu")
	)
	(gr_line
		(start 354.599748 -118.790974)
		(end 354.618544 -118.79453)
		(stroke
			(width 0.05715)
			(type default)
		)
		(layer "In2.Cu")
	)
	(gr_line
		(start 354.600002 -62.593982)
		(end 354.618036 -62.548008)
		(stroke
			(width 0.05715)
			(type default)
		)
		(layer "In2.Cu")
	)
	(gr_line
		(start 354.604828 -117.943376)
		(end 354.62337 -117.946932)
		(stroke
			(width 0.05715)
			(type default)
		)
		(layer "In2.Cu")
	)
	(gr_line
		(start 354.618036 -62.548008)
		(end 354.657152 -62.51956)
		(stroke
			(width 0.05715)
			(type default)
		)
		(layer "In2.Cu")
	)
	(gr_line
		(start 354.618544 -118.79453)
		(end 354.63734 -118.790974)
		(stroke
			(width 0.05715)
			(type default)
		)
		(layer "In2.Cu")
	)
	(gr_line
		(start 354.62337 -117.946932)
		(end 354.642166 -117.943376)
		(stroke
			(width 0.05715)
			(type default)
		)
		(layer "In2.Cu")
	)
	(gr_line
		(start 354.65766 -44.73321)
		(end 354.6856 -44.691046)
		(stroke
			(width 0.05715)
			(type default)
		)
		(layer "In2.Cu")
	)
	(gr_line
		(start 354.818696 -36.483798)
		(end 354.834952 -36.459414)
		(stroke
			(width 0.05715)
			(type default)
		)
		(layer "In2.Cu")
	)
	(gr_line
		(start 354.829618 -52.6034)
		(end 354.833428 -52.62245)
		(stroke
			(width 0.05715)
			(type default)
		)
		(layer "In2.Cu")
	)
	(gr_line
		(start 354.829618 -52.6034)
		(end 354.833682 -52.583588)
		(stroke
			(width 0.05715)
			(type default)
		)
		(layer "In2.Cu")
	)
	(gr_line
		(start 354.834952 -36.459414)
		(end 354.860098 -36.444174)
		(stroke
			(width 0.05715)
			(type default)
		)
		(layer "In2.Cu")
	)
	(gr_line
		(start 354.961444 -117.581172)
		(end 355.090222 -117.390164)
		(stroke
			(width 0.05715)
			(type default)
		)
		(layer "In2.Cu")
	)
	(gr_line
		(start 355.05136 -117.86362)
		(end 355.639624 -117.749574)
		(stroke
			(width 0.05715)
			(type default)
		)
		(layer "In2.Cu")
	)
	(gr_line
		(start 355.052122 -117.86362)
		(end 355.639116 -117.749574)
		(stroke
			(width 0.05715)
			(type default)
		)
		(layer "In2.Cu")
	)
	(gr_line
		(start 355.08184 -48.57496)
		(end 355.082094 -48.57369)
		(stroke
			(width 0.05715)
			(type default)
		)
		(layer "In2.Cu")
	)
	(gr_line
		(start 355.082094 -48.57369)
		(end 355.08311 -48.571912)
		(stroke
			(width 0.05715)
			(type default)
		)
		(layer "In2.Cu")
	)
	(gr_line
		(start 355.090222 -117.390164)
		(end 355.426772 -117.324886)
		(stroke
			(width 0.05715)
			(type default)
		)
		(layer "In2.Cu")
	)
	(gr_line
		(start 355.091492 -53.914548)
		(end 355.108002 -53.997098)
		(stroke
			(width 0.05715)
			(type default)
		)
		(layer "In2.Cu")
	)
	(gr_line
		(start 355.094286 -85.442806)
		(end 355.116384 -85.447124)
		(stroke
			(width 0.05715)
			(type default)
		)
		(layer "In2.Cu")
	)
	(gr_line
		(start 355.108002 -53.997098)
		(end 355.178868 -54.044342)
		(stroke
			(width 0.05715)
			(type default)
		)
		(layer "In2.Cu")
	)
	(gr_line
		(start 355.116384 -85.447124)
		(end 355.134926 -85.45957)
		(stroke
			(width 0.05715)
			(type default)
		)
		(layer "In2.Cu")
	)
	(gr_line
		(start 355.145848 -63.084964)
		(end 355.16312 -63.040768)
		(stroke
			(width 0.05715)
			(type default)
		)
		(layer "In2.Cu")
	)
	(gr_line
		(start 355.162104 -50.941732)
		(end 355.16566 -50.922936)
		(stroke
			(width 0.05715)
			(type default)
		)
		(layer "In2.Cu")
	)
	(gr_line
		(start 355.16312 -63.040768)
		(end 355.200712 -63.01359)
		(stroke
			(width 0.05715)
			(type default)
		)
		(layer "In2.Cu")
	)
	(gr_line
		(start 355.16566 -50.922936)
		(end 355.176328 -50.906934)
		(stroke
			(width 0.05715)
			(type default)
		)
		(layer "In2.Cu")
	)
	(gr_line
		(start 355.2317 -90.873834)
		(end 355.312472 -90.89009)
		(stroke
			(width 0.05715)
			(type default)
		)
		(layer "In2.Cu")
	)
	(gr_line
		(start 355.249988 -37.01161)
		(end 355.32187 -36.943284)
		(stroke
			(width 0.05715)
			(type default)
		)
		(layer "In2.Cu")
	)
	(gr_line
		(start 355.312472 -90.89009)
		(end 355.358446 -90.958924)
		(stroke
			(width 0.05715)
			(type default)
		)
		(layer "In2.Cu")
	)
	(gr_line
		(start 355.41204 -84.197952)
		(end 355.430836 -84.194396)
		(stroke
			(width 0.05715)
			(type default)
		)
		(layer "In2.Cu")
	)
	(gr_line
		(start 355.426772 -117.324886)
		(end 355.617526 -117.45341)
		(stroke
			(width 0.05715)
			(type default)
		)
		(layer "In2.Cu")
	)
	(gr_line
		(start 355.430836 -84.194396)
		(end 355.449632 -84.197952)
		(stroke
			(width 0.05715)
			(type default)
		)
		(layer "In2.Cu")
	)
	(gr_line
		(start 355.47173 -37.200332)
		(end 355.482398 -37.18433)
		(stroke
			(width 0.05715)
			(type default)
		)
		(layer "In2.Cu")
	)
	(gr_line
		(start 355.482398 -37.18433)
		(end 355.499416 -37.17417)
		(stroke
			(width 0.05715)
			(type default)
		)
		(layer "In2.Cu")
	)
	(gr_line
		(start 355.510084 -52.631086)
		(end 355.513894 -52.650136)
		(stroke
			(width 0.05715)
			(type default)
		)
		(layer "In2.Cu")
	)
	(gr_line
		(start 355.510084 -52.631086)
		(end 355.514148 -52.61102)
		(stroke
			(width 0.05715)
			(type default)
		)
		(layer "In2.Cu")
	)
	(gr_line
		(start 355.558344 -90.213688)
		(end 355.640132 -90.22969)
		(stroke
			(width 0.05715)
			(type default)
		)
		(layer "In2.Cu")
	)
	(gr_line
		(start 355.56444 -85.749384)
		(end 355.58095 -85.76056)
		(stroke
			(width 0.05715)
			(type default)
		)
		(layer "In2.Cu")
	)
	(gr_line
		(start 355.58095 -85.76056)
		(end 355.592126 -85.77707)
		(stroke
			(width 0.05715)
			(type default)
		)
		(layer "In2.Cu")
	)
	(gr_line
		(start 355.640132 -90.22969)
		(end 355.686614 -90.299286)
		(stroke
			(width 0.05715)
			(type default)
		)
		(layer "In2.Cu")
	)
	(gr_line
		(start 355.665278 -124.256038)
		(end 355.672898 -124.261626)
		(stroke
			(width 0.05715)
			(type default)
		)
		(layer "In2.Cu")
	)
	(gr_line
		(start 355.667056 -53.41747)
		(end 355.683566 -53.50002)
		(stroke
			(width 0.05715)
			(type default)
		)
		(layer "In2.Cu")
	)
	(gr_line
		(start 355.672898 -124.261626)
		(end 355.681788 -124.264674)
		(stroke
			(width 0.05715)
			(type default)
		)
		(layer "In2.Cu")
	)
	(gr_line
		(start 355.683566 -53.50002)
		(end 355.753416 -53.546248)
		(stroke
			(width 0.05715)
			(type default)
		)
		(layer "In2.Cu")
	)
	(gr_line
		(start 355.699822 -85.936582)
		(end 355.712014 -85.95487)
		(stroke
			(width 0.05715)
			(type default)
		)
		(layer "In2.Cu")
	)
	(gr_line
		(start 355.700076 -85.93709)
		(end 355.712014 -85.95487)
		(stroke
			(width 0.05715)
			(type default)
		)
		(layer "In2.Cu")
	)
	(gr_line
		(start 355.712014 -85.95487)
		(end 355.716332 -85.976714)
		(stroke
			(width 0.05715)
			(type default)
		)
		(layer "In2.Cu")
	)
	(gr_line
		(start 355.784404 -84.262976)
		(end 355.806248 -84.267294)
		(stroke
			(width 0.05715)
			(type default)
		)
		(layer "In2.Cu")
	)
	(gr_line
		(start 355.796596 -51.197256)
		(end 355.800406 -51.17719)
		(stroke
			(width 0.05715)
			(type default)
		)
		(layer "In2.Cu")
	)
	(gr_line
		(start 355.800406 -51.17719)
		(end 355.81209 -51.15941)
		(stroke
			(width 0.05715)
			(type default)
		)
		(layer "In2.Cu")
	)
	(gr_line
		(start 355.806248 -84.267294)
		(end 355.824028 -84.279232)
		(stroke
			(width 0.05715)
			(type default)
		)
		(layer "In2.Cu")
	)
	(gr_line
		(start 355.806248 -84.267294)
		(end 355.82479 -84.27974)
		(stroke
			(width 0.05715)
			(type default)
		)
		(layer "In2.Cu")
	)
	(gr_line
		(start 355.854 -34.253932)
		(end 355.879146 -34.238692)
		(stroke
			(width 0.05715)
			(type default)
		)
		(layer "In2.Cu")
	)
	(gr_line
		(start 355.879146 -34.238692)
		(end 355.895402 -34.214308)
		(stroke
			(width 0.05715)
			(type default)
		)
		(layer "In2.Cu")
	)
	(gr_line
		(start 355.958902 -117.387116)
		(end 356.08768 -117.196362)
		(stroke
			(width 0.05715)
			(type default)
		)
		(layer "In2.Cu")
	)
	(gr_line
		(start 356.045516 -60.984384)
		(end 356.058724 -60.974732)
		(stroke
			(width 0.05715)
			(type default)
		)
		(layer "In2.Cu")
	)
	(gr_line
		(start 356.04958 -117.669818)
		(end 356.636828 -117.555518)
		(stroke
			(width 0.05715)
			(type default)
		)
		(layer "In2.Cu")
	)
	(gr_line
		(start 356.050342 -117.66931)
		(end 356.63632 -117.555518)
		(stroke
			(width 0.05715)
			(type default)
		)
		(layer "In2.Cu")
	)
	(gr_line
		(start 356.058724 -60.974732)
		(end 356.067614 -60.961016)
		(stroke
			(width 0.05715)
			(type default)
		)
		(layer "In2.Cu")
	)
	(gr_line
		(start 356.08768 -117.196362)
		(end 356.42423 -117.13083)
		(stroke
			(width 0.05715)
			(type default)
		)
		(layer "In2.Cu")
	)
	(gr_line
		(start 356.098094 -85.790786)
		(end 356.10165 -85.809582)
		(stroke
			(width 0.05715)
			(type default)
		)
		(layer "In2.Cu")
	)
	(gr_line
		(start 356.098094 -85.790786)
		(end 356.10165 -85.77199)
		(stroke
			(width 0.05715)
			(type default)
		)
		(layer "In2.Cu")
	)
	(gr_line
		(start 356.098094 -85.790786)
		(end 356.101904 -85.810344)
		(stroke
			(width 0.05715)
			(type default)
		)
		(layer "In2.Cu")
	)
	(gr_line
		(start 356.098094 -85.790786)
		(end 356.101904 -85.771228)
		(stroke
			(width 0.05715)
			(type default)
		)
		(layer "In2.Cu")
	)
	(gr_line
		(start 356.162356 -82.966814)
		(end 356.245668 -82.98307)
		(stroke
			(width 0.05715)
			(type default)
		)
		(layer "In2.Cu")
	)
	(gr_line
		(start 356.20833 -84.538058)
		(end 356.22484 -84.549234)
		(stroke
			(width 0.05715)
			(type default)
		)
		(layer "In2.Cu")
	)
	(gr_line
		(start 356.209346 -84.539074)
		(end 356.22484 -84.549234)
		(stroke
			(width 0.05715)
			(type default)
		)
		(layer "In2.Cu")
	)
	(gr_line
		(start 356.21849 -35.117278)
		(end 356.243636 -35.102038)
		(stroke
			(width 0.05715)
			(type default)
		)
		(layer "In2.Cu")
	)
	(gr_line
		(start 356.22484 -84.549234)
		(end 356.235 -84.564728)
		(stroke
			(width 0.05715)
			(type default)
		)
		(layer "In2.Cu")
	)
	(gr_line
		(start 356.22484 -84.549234)
		(end 356.236016 -84.565744)
		(stroke
			(width 0.05715)
			(type default)
		)
		(layer "In2.Cu")
	)
	(gr_line
		(start 356.243636 -35.102038)
		(end 356.259892 -35.077654)
		(stroke
			(width 0.05715)
			(type default)
		)
		(layer "In2.Cu")
	)
	(gr_line
		(start 356.245668 -82.98307)
		(end 356.293166 -83.053428)
		(stroke
			(width 0.05715)
			(type default)
		)
		(layer "In2.Cu")
	)
	(gr_line
		(start 356.318058 -90.605102)
		(end 356.322376 -90.626946)
		(stroke
			(width 0.05715)
			(type default)
		)
		(layer "In2.Cu")
	)
	(gr_line
		(start 356.322376 -90.626946)
		(end 356.335076 -90.645996)
		(stroke
			(width 0.05715)
			(type default)
		)
		(layer "In2.Cu")
	)
	(gr_line
		(start 356.371398 -76.719684)
		(end 356.809548 -76.719684)
		(stroke
			(width 0.05715)
			(type default)
		)
		(layer "In2.Cu")
	)
	(gr_line
		(start 356.402132 -84.812378)
		(end 356.414578 -84.83092)
		(stroke
			(width 0.05715)
			(type default)
		)
		(layer "In2.Cu")
	)
	(gr_line
		(start 356.40264 -84.81314)
		(end 356.414578 -84.83092)
		(stroke
			(width 0.05715)
			(type default)
		)
		(layer "In2.Cu")
	)
	(gr_line
		(start 356.414578 -84.83092)
		(end 356.418896 -84.852764)
		(stroke
			(width 0.05715)
			(type default)
		)
		(layer "In2.Cu")
	)
	(gr_line
		(start 356.422452 -63.975234)
		(end 356.439724 -63.926466)
		(stroke
			(width 0.05715)
			(type default)
		)
		(layer "In2.Cu")
	)
	(gr_line
		(start 356.42423 -117.13083)
		(end 356.614984 -117.259608)
		(stroke
			(width 0.05715)
			(type default)
		)
		(layer "In2.Cu")
	)
	(gr_line
		(start 356.439724 -63.926466)
		(end 356.481888 -63.895732)
		(stroke
			(width 0.05715)
			(type default)
		)
		(layer "In2.Cu")
	)
	(gr_line
		(start 356.494588 -85.242908)
		(end 356.494842 -85.24367)
		(stroke
			(width 0.05715)
			(type default)
		)
		(layer "In2.Cu")
	)
	(gr_line
		(start 356.494842 -85.281262)
		(end 356.498398 -85.262466)
		(stroke
			(width 0.05715)
			(type default)
		)
		(layer "In2.Cu")
	)
	(gr_line
		(start 356.494842 -85.281008)
		(end 356.494842 -85.281516)
		(stroke
			(width 0.05715)
			(type default)
		)
		(layer "In2.Cu")
	)
	(gr_line
		(start 356.494842 -85.281008)
		(end 356.498398 -85.262466)
		(stroke
			(width 0.05715)
			(type default)
		)
		(layer "In2.Cu")
	)
	(gr_line
		(start 356.494842 -85.243416)
		(end 356.498398 -85.262466)
		(stroke
			(width 0.05715)
			(type default)
		)
		(layer "In2.Cu")
	)
	(gr_line
		(start 356.566978 -61.487558)
		(end 356.582218 -61.476382)
		(stroke
			(width 0.05715)
			(type default)
		)
		(layer "In2.Cu")
	)
	(gr_line
		(start 356.582218 -61.476382)
		(end 356.592378 -61.46038)
		(stroke
			(width 0.05715)
			(type default)
		)
		(layer "In2.Cu")
	)
	(gr_line
		(start 356.598728 -35.738308)
		(end 356.623874 -35.723068)
		(stroke
			(width 0.05715)
			(type default)
		)
		(layer "In2.Cu")
	)
	(gr_line
		(start 356.623874 -35.723068)
		(end 356.64013 -35.698684)
		(stroke
			(width 0.05715)
			(type default)
		)
		(layer "In2.Cu")
	)
	(gr_line
		(start 356.66934 -69.061584)
		(end 356.68585 -69.11721)
		(stroke
			(width 0.05715)
			(type default)
		)
		(layer "In2.Cu")
	)
	(gr_line
		(start 356.66934 -69.061584)
		(end 356.68585 -69.116702)
		(stroke
			(width 0.05715)
			(type default)
		)
		(layer "In2.Cu")
	)
	(gr_line
		(start 356.66934 -69.061584)
		(end 356.688644 -69.007228)
		(stroke
			(width 0.05715)
			(type default)
		)
		(layer "In2.Cu")
	)
	(gr_line
		(start 356.66934 -69.061584)
		(end 356.688898 -69.006466)
		(stroke
			(width 0.05715)
			(type default)
		)
		(layer "In2.Cu")
	)
	(gr_line
		(start 356.68585 -69.11721)
		(end 356.68585 -69.117464)
		(stroke
			(width 0.05715)
			(type default)
		)
		(layer "In2.Cu")
	)
	(gr_arc
		(start 356.809548 -76.719684)
		(mid 356.89037 -76.686206)
		(end 356.923848 -76.605384)
		(stroke
			(width 0.05715)
			(type default)
		)
		(layer "In2.Cu")
	)
	(gr_line
		(start 356.836726 -85.925406)
		(end 356.84079 -85.945726)
		(stroke
			(width 0.05715)
			(type default)
		)
		(layer "In2.Cu")
	)
	(gr_line
		(start 356.836726 -85.924898)
		(end 356.836726 -85.925406)
		(stroke
			(width 0.05715)
			(type default)
		)
		(layer "In2.Cu")
	)
	(gr_line
		(start 356.836726 -85.924898)
		(end 356.83698 -85.924644)
		(stroke
			(width 0.05715)
			(type default)
		)
		(layer "In2.Cu")
	)
	(gr_line
		(start 356.83698 -85.924644)
		(end 356.840536 -85.905848)
		(stroke
			(width 0.05715)
			(type default)
		)
		(layer "In2.Cu")
	)
	(gr_line
		(start 356.83698 -85.924644)
		(end 356.84079 -85.905086)
		(stroke
			(width 0.05715)
			(type default)
		)
		(layer "In2.Cu")
	)
	(gr_line
		(start 356.923848 -75.058016)
		(end 356.925118 -75.053698)
		(stroke
			(width 0.05715)
			(type default)
		)
		(layer "In2.Cu")
	)
	(gr_line
		(start 356.938072 -93.855032)
		(end 356.94366 -93.863414)
		(stroke
			(width 0.05715)
			(type default)
		)
		(layer "In2.Cu")
	)
	(gr_line
		(start 356.94366 -93.863414)
		(end 356.952042 -93.870018)
		(stroke
			(width 0.05715)
			(type default)
		)
		(layer "In2.Cu")
	)
	(gr_line
		(start 356.964996 -64.38138)
		(end 356.982522 -64.332358)
		(stroke
			(width 0.05715)
			(type default)
		)
		(layer "In2.Cu")
	)
	(gr_line
		(start 356.979982 -90.327226)
		(end 356.983538 -90.34653)
		(stroke
			(width 0.05715)
			(type default)
		)
		(layer "In2.Cu")
	)
	(gr_line
		(start 356.982522 -64.332358)
		(end 357.023924 -64.302386)
		(stroke
			(width 0.05715)
			(type default)
		)
		(layer "In2.Cu")
	)
	(gr_line
		(start 356.983538 -90.34653)
		(end 356.994714 -90.363548)
		(stroke
			(width 0.05715)
			(type default)
		)
		(layer "In2.Cu")
	)
	(gr_line
		(start 357.002588 -86.755478)
		(end 357.119936 -87.342218)
		(stroke
			(width 0.05715)
			(type default)
		)
		(layer "In2.Cu")
	)
	(gr_line
		(start 357.002842 -86.755732)
		(end 357.119682 -87.340694)
		(stroke
			(width 0.05715)
			(type default)
		)
		(layer "In2.Cu")
	)
	(gr_line
		(start 357.04145 -36.244784)
		(end 357.066342 -36.229798)
		(stroke
			(width 0.05715)
			(type default)
		)
		(layer "In2.Cu")
	)
	(gr_line
		(start 357.066342 -36.229798)
		(end 357.082852 -36.20516)
		(stroke
			(width 0.05715)
			(type default)
		)
		(layer "In2.Cu")
	)
	(gr_line
		(start 357.14305 -61.959744)
		(end 357.154734 -61.951362)
		(stroke
			(width 0.05715)
			(type default)
		)
		(layer "In2.Cu")
	)
	(gr_line
		(start 357.153464 -84.329778)
		(end 357.165402 -84.347558)
		(stroke
			(width 0.05715)
			(type default)
		)
		(layer "In2.Cu")
	)
	(gr_line
		(start 357.154734 -61.951362)
		(end 357.163116 -61.938662)
		(stroke
			(width 0.05715)
			(type default)
		)
		(layer "In2.Cu")
	)
	(gr_line
		(start 357.165402 -84.347558)
		(end 357.16972 -84.369402)
		(stroke
			(width 0.05715)
			(type default)
		)
		(layer "In2.Cu")
	)
	(gr_line
		(start 357.16845 -32.304228)
		(end 357.179118 -32.287972)
		(stroke
			(width 0.05715)
			(type default)
		)
		(layer "In2.Cu")
	)
	(gr_line
		(start 357.179118 -32.287972)
		(end 357.183182 -32.268922)
		(stroke
			(width 0.05715)
			(type default)
		)
		(layer "In2.Cu")
	)
	(gr_arc
		(start 357.215948 -76.605384)
		(mid 357.249426 -76.686206)
		(end 357.330248 -76.719684)
		(stroke
			(width 0.05715)
			(type default)
		)
		(layer "In2.Cu")
	)
	(gr_line
		(start 357.284782 -86.66353)
		(end 357.476298 -86.791292)
		(stroke
			(width 0.05715)
			(type default)
		)
		(layer "In2.Cu")
	)
	(gr_line
		(start 357.299514 -85.076538)
		(end 357.303324 -85.05698)
		(stroke
			(width 0.05715)
			(type default)
		)
		(layer "In2.Cu")
	)
	(gr_line
		(start 357.299768 -85.075776)
		(end 357.303324 -85.05698)
		(stroke
			(width 0.05715)
			(type default)
		)
		(layer "In2.Cu")
	)
	(gr_line
		(start 357.299768 -85.038438)
		(end 357.303324 -85.05698)
		(stroke
			(width 0.05715)
			(type default)
		)
		(layer "In2.Cu")
	)
	(gr_line
		(start 357.299768 -85.038184)
		(end 357.303324 -85.05698)
		(stroke
			(width 0.05715)
			(type default)
		)
		(layer "In2.Cu")
	)
	(gr_line
		(start 357.299768 -85.03793)
		(end 357.299768 -85.038438)
		(stroke
			(width 0.05715)
			(type default)
		)
		(layer "In2.Cu")
	)
	(gr_line
		(start 357.315516 -41.977564)
		(end 357.326184 -41.961308)
		(stroke
			(width 0.05715)
			(type default)
		)
		(layer "In2.Cu")
	)
	(gr_line
		(start 357.326184 -41.961308)
		(end 357.329994 -41.942258)
		(stroke
			(width 0.05715)
			(type default)
		)
		(layer "In2.Cu")
	)
	(gr_line
		(start 357.330248 -76.719684)
		(end 357.768398 -76.719684)
		(stroke
			(width 0.05715)
			(type default)
		)
		(layer "In2.Cu")
	)
	(gr_line
		(start 357.388922 -93.378782)
		(end 357.39451 -93.387164)
		(stroke
			(width 0.05715)
			(type default)
		)
		(layer "In2.Cu")
	)
	(gr_line
		(start 357.39451 -93.387164)
		(end 357.402892 -93.393768)
		(stroke
			(width 0.05715)
			(type default)
		)
		(layer "In2.Cu")
	)
	(gr_line
		(start 357.415592 -87.319104)
		(end 357.543354 -87.127588)
		(stroke
			(width 0.05715)
			(type default)
		)
		(layer "In2.Cu")
	)
	(gr_line
		(start 357.476298 -86.791292)
		(end 357.543354 -87.127588)
		(stroke
			(width 0.05715)
			(type default)
		)
		(layer "In2.Cu")
	)
	(gr_line
		(start 357.507286 -64.788288)
		(end 357.525066 -64.73825)
		(stroke
			(width 0.05715)
			(type default)
		)
		(layer "In2.Cu")
	)
	(gr_line
		(start 357.525066 -64.73825)
		(end 357.5685 -64.7065)
		(stroke
			(width 0.05715)
			(type default)
		)
		(layer "In2.Cu")
	)
	(gr_line
		(start 357.53802 -68.5546)
		(end 357.557324 -68.613782)
		(stroke
			(width 0.05715)
			(type default)
		)
		(layer "In2.Cu")
	)
	(gr_line
		(start 357.53802 -68.5546)
		(end 357.557578 -68.61429)
		(stroke
			(width 0.05715)
			(type default)
		)
		(layer "In2.Cu")
	)
	(gr_line
		(start 357.53802 -68.5546)
		(end 357.559102 -68.495418)
		(stroke
			(width 0.05715)
			(type default)
		)
		(layer "In2.Cu")
	)
	(gr_line
		(start 357.53802 -68.5546)
		(end 357.559102 -68.495164)
		(stroke
			(width 0.05715)
			(type default)
		)
		(layer "In2.Cu")
	)
	(gr_line
		(start 357.541322 -89.450672)
		(end 357.544878 -89.469468)
		(stroke
			(width 0.05715)
			(type default)
		)
		(layer "In2.Cu")
	)
	(gr_line
		(start 357.544878 -89.469468)
		(end 357.5558 -89.486232)
		(stroke
			(width 0.05715)
			(type default)
		)
		(layer "In2.Cu")
	)
	(gr_line
		(start 357.559102 -68.495418)
		(end 357.559356 -68.49491)
		(stroke
			(width 0.05715)
			(type default)
		)
		(layer "In2.Cu")
	)
	(gr_line
		(start 357.587042 -98.811588)
		(end 357.599488 -98.762058)
		(stroke
			(width 0.05715)
			(type default)
		)
		(layer "In2.Cu")
	)
	(gr_line
		(start 357.587042 -98.811588)
		(end 357.599488 -98.761804)
		(stroke
			(width 0.05715)
			(type default)
		)
		(layer "In2.Cu")
	)
	(gr_line
		(start 357.587042 -98.811588)
		(end 357.604314 -98.859848)
		(stroke
			(width 0.05715)
			(type default)
		)
		(layer "In2.Cu")
	)
	(gr_line
		(start 357.587042 -98.811588)
		(end 357.604314 -98.859594)
		(stroke
			(width 0.05715)
			(type default)
		)
		(layer "In2.Cu")
	)
	(gr_line
		(start 357.604314 -98.859848)
		(end 357.604568 -98.860356)
		(stroke
			(width 0.05715)
			(type default)
		)
		(layer "In2.Cu")
	)
	(gr_line
		(start 357.614728 -55.315104)
		(end 357.683816 -55.360824)
		(stroke
			(width 0.05715)
			(type default)
		)
		(layer "In2.Cu")
	)
	(gr_line
		(start 357.683816 -55.360824)
		(end 357.700326 -55.442866)
		(stroke
			(width 0.05715)
			(type default)
		)
		(layer "In2.Cu")
	)
	(gr_line
		(start 357.684832 -32.938974)
		(end 357.6955 -32.922718)
		(stroke
			(width 0.05715)
			(type default)
		)
		(layer "In2.Cu")
	)
	(gr_line
		(start 357.6955 -32.922718)
		(end 357.699564 -32.903668)
		(stroke
			(width 0.05715)
			(type default)
		)
		(layer "In2.Cu")
	)
	(gr_line
		(start 357.80599 -119.021098)
		(end 357.829104 -119.016018)
		(stroke
			(width 0.05715)
			(type default)
		)
		(layer "In2.Cu")
	)
	(gr_line
		(start 357.829104 -119.016018)
		(end 357.852218 -119.021098)
		(stroke
			(width 0.05715)
			(type default)
		)
		(layer "In2.Cu")
	)
	(gr_line
		(start 357.851456 -92.91955)
		(end 357.857044 -92.927932)
		(stroke
			(width 0.05715)
			(type default)
		)
		(layer "In2.Cu")
	)
	(gr_line
		(start 357.857044 -92.927932)
		(end 357.865426 -92.934536)
		(stroke
			(width 0.05715)
			(type default)
		)
		(layer "In2.Cu")
	)
	(gr_line
		(start 357.91394 -42.294302)
		(end 357.925624 -42.276522)
		(stroke
			(width 0.05715)
			(type default)
		)
		(layer "In2.Cu")
	)
	(gr_line
		(start 357.925624 -42.276522)
		(end 357.929434 -42.256456)
		(stroke
			(width 0.05715)
			(type default)
		)
		(layer "In2.Cu")
	)
	(gr_line
		(start 357.976932 -56.944514)
		(end 357.991664 -56.903366)
		(stroke
			(width 0.05715)
			(type default)
		)
		(layer "In2.Cu")
	)
	(gr_line
		(start 357.976932 -56.943498)
		(end 357.991664 -56.903366)
		(stroke
			(width 0.05715)
			(type default)
		)
		(layer "In2.Cu")
	)
	(gr_line
		(start 357.983028 -56.860948)
		(end 357.991664 -56.903366)
		(stroke
			(width 0.05715)
			(type default)
		)
		(layer "In2.Cu")
	)
	(gr_line
		(start 357.983028 -56.860694)
		(end 357.991664 -56.903366)
		(stroke
			(width 0.05715)
			(type default)
		)
		(layer "In2.Cu")
	)
	(gr_line
		(start 357.983536 -72.450198)
		(end 357.998014 -72.498966)
		(stroke
			(width 0.05715)
			(type default)
		)
		(layer "In2.Cu")
	)
	(gr_line
		(start 357.98379 -72.546718)
		(end 357.998014 -72.498966)
		(stroke
			(width 0.05715)
			(type default)
		)
		(layer "In2.Cu")
	)
	(gr_line
		(start 357.98379 -72.545702)
		(end 357.998014 -72.498966)
		(stroke
			(width 0.05715)
			(type default)
		)
		(layer "In2.Cu")
	)
	(gr_line
		(start 357.98379 -72.45096)
		(end 357.998014 -72.498966)
		(stroke
			(width 0.05715)
			(type default)
		)
		(layer "In2.Cu")
	)
	(gr_line
		(start 358.01046 -82.64144)
		(end 358.032304 -82.645758)
		(stroke
			(width 0.05715)
			(type default)
		)
		(layer "In2.Cu")
	)
	(gr_line
		(start 358.032304 -82.645758)
		(end 358.050084 -82.657696)
		(stroke
			(width 0.05715)
			(type default)
		)
		(layer "In2.Cu")
	)
	(gr_line
		(start 358.050846 -65.193418)
		(end 358.068372 -65.144396)
		(stroke
			(width 0.05715)
			(type default)
		)
		(layer "In2.Cu")
	)
	(gr_line
		(start 358.066594 -125.066552)
		(end 358.07523 -125.0696)
		(stroke
			(width 0.05715)
			(type default)
		)
		(layer "In2.Cu")
	)
	(gr_line
		(start 358.068372 -65.144396)
		(end 358.109774 -65.114424)
		(stroke
			(width 0.05715)
			(type default)
		)
		(layer "In2.Cu")
	)
	(gr_line
		(start 358.068372 -65.144396)
		(end 358.110536 -65.113662)
		(stroke
			(width 0.05715)
			(type default)
		)
		(layer "In2.Cu")
	)
	(gr_line
		(start 358.115108 -94.399608)
		(end 358.17048 -94.442534)
		(stroke
			(width 0.05715)
			(type default)
		)
		(layer "In2.Cu")
	)
	(gr_line
		(start 358.17048 -94.442534)
		(end 358.185466 -94.51086)
		(stroke
			(width 0.05715)
			(type default)
		)
		(layer "In2.Cu")
	)
	(gr_line
		(start 358.175306 -54.807612)
		(end 358.245156 -54.85384)
		(stroke
			(width 0.05715)
			(type default)
		)
		(layer "In2.Cu")
	)
	(gr_line
		(start 358.180132 -52.818284)
		(end 358.184704 -52.84089)
		(stroke
			(width 0.05715)
			(type default)
		)
		(layer "In2.Cu")
	)
	(gr_line
		(start 358.180132 -52.818284)
		(end 358.184704 -52.840636)
		(stroke
			(width 0.05715)
			(type default)
		)
		(layer "In2.Cu")
	)
	(gr_line
		(start 358.180132 -52.818284)
		(end 358.184958 -52.7939)
		(stroke
			(width 0.05715)
			(type default)
		)
		(layer "In2.Cu")
	)
	(gr_line
		(start 358.184704 -52.84089)
		(end 358.184704 -52.841144)
		(stroke
			(width 0.05715)
			(type default)
		)
		(layer "In2.Cu")
	)
	(gr_line
		(start 358.184958 -52.793392)
		(end 358.184958 -52.7939)
		(stroke
			(width 0.05715)
			(type default)
		)
		(layer "In2.Cu")
	)
	(gr_line
		(start 358.24033 -90.52052)
		(end 358.252776 -90.539316)
		(stroke
			(width 0.05715)
			(type default)
		)
		(layer "In2.Cu")
	)
	(gr_line
		(start 358.245156 -54.85384)
		(end 358.261412 -54.936136)
		(stroke
			(width 0.05715)
			(type default)
		)
		(layer "In2.Cu")
	)
	(gr_line
		(start 358.245664 -88.573864)
		(end 358.24922 -88.59266)
		(stroke
			(width 0.05715)
			(type default)
		)
		(layer "In2.Cu")
	)
	(gr_line
		(start 358.245664 -88.573864)
		(end 358.24922 -88.555068)
		(stroke
			(width 0.05715)
			(type default)
		)
		(layer "In2.Cu")
	)
	(gr_line
		(start 358.245664 -88.573864)
		(end 358.249474 -88.593422)
		(stroke
			(width 0.05715)
			(type default)
		)
		(layer "In2.Cu")
	)
	(gr_line
		(start 358.245664 -88.573864)
		(end 358.249474 -88.554306)
		(stroke
			(width 0.05715)
			(type default)
		)
		(layer "In2.Cu")
	)
	(gr_line
		(start 358.252776 -90.539316)
		(end 358.271826 -90.552016)
		(stroke
			(width 0.05715)
			(type default)
		)
		(layer "In2.Cu")
	)
	(gr_line
		(start 358.271064 -33.25241)
		(end 358.280716 -33.237678)
		(stroke
			(width 0.05715)
			(type default)
		)
		(layer "In2.Cu")
	)
	(gr_line
		(start 358.280716 -33.237678)
		(end 358.284272 -33.220914)
		(stroke
			(width 0.05715)
			(type default)
		)
		(layer "In2.Cu")
	)
	(gr_line
		(start 358.31907 -119.861838)
		(end 358.34193 -119.857266)
		(stroke
			(width 0.05715)
			(type default)
		)
		(layer "In2.Cu")
	)
	(gr_line
		(start 358.328722 -88.146128)
		(end 358.44353 -87.555578)
		(stroke
			(width 0.05715)
			(type default)
		)
		(layer "In2.Cu")
	)
	(gr_line
		(start 358.32923 -88.14435)
		(end 358.44353 -87.557102)
		(stroke
			(width 0.05715)
			(type default)
		)
		(layer "In2.Cu")
	)
	(gr_line
		(start 358.34193 -119.857266)
		(end 358.36479 -119.862092)
		(stroke
			(width 0.05715)
			(type default)
		)
		(layer "In2.Cu")
	)
	(gr_line
		(start 358.350312 -92.396056)
		(end 358.396286 -92.46489)
		(stroke
			(width 0.05715)
			(type default)
		)
		(layer "In2.Cu")
	)
	(gr_line
		(start 358.37495 -116.919756)
		(end 358.393746 -116.9162)
		(stroke
			(width 0.05715)
			(type default)
		)
		(layer "In2.Cu")
	)
	(gr_line
		(start 358.389682 -117.763544)
		(end 358.408478 -117.759988)
		(stroke
			(width 0.05715)
			(type default)
		)
		(layer "In2.Cu")
	)
	(gr_line
		(start 358.393746 -116.9162)
		(end 358.412288 -116.919756)
		(stroke
			(width 0.05715)
			(type default)
		)
		(layer "In2.Cu")
	)
	(gr_line
		(start 358.396286 -92.46489)
		(end 358.477058 -92.481146)
		(stroke
			(width 0.05715)
			(type default)
		)
		(layer "In2.Cu")
	)
	(gr_line
		(start 358.408478 -117.759988)
		(end 358.427274 -117.763544)
		(stroke
			(width 0.05715)
			(type default)
		)
		(layer "In2.Cu")
	)
	(gr_line
		(start 358.430576 -60.023756)
		(end 358.441498 -60.007246)
		(stroke
			(width 0.05715)
			(type default)
		)
		(layer "In2.Cu")
	)
	(gr_line
		(start 358.43083 -60.023502)
		(end 358.441498 -60.007246)
		(stroke
			(width 0.05715)
			(type default)
		)
		(layer "In2.Cu")
	)
	(gr_line
		(start 358.432608 -82.915506)
		(end 358.447848 -82.92592)
		(stroke
			(width 0.05715)
			(type default)
		)
		(layer "In2.Cu")
	)
	(gr_line
		(start 358.437434 -34.923222)
		(end 358.441244 -34.904172)
		(stroke
			(width 0.05715)
			(type default)
		)
		(layer "In2.Cu")
	)
	(gr_line
		(start 358.440736 -89.57564)
		(end 358.444292 -89.594944)
		(stroke
			(width 0.05715)
			(type default)
		)
		(layer "In2.Cu")
	)
	(gr_line
		(start 358.441244 -34.904172)
		(end 358.451912 -34.887916)
		(stroke
			(width 0.05715)
			(type default)
		)
		(layer "In2.Cu")
	)
	(gr_line
		(start 358.441498 -60.007246)
		(end 358.4448 -59.98972)
		(stroke
			(width 0.05715)
			(type default)
		)
		(layer "In2.Cu")
	)
	(gr_line
		(start 358.441498 -60.007246)
		(end 358.445054 -59.989212)
		(stroke
			(width 0.05715)
			(type default)
		)
		(layer "In2.Cu")
	)
	(gr_line
		(start 358.444292 -89.594944)
		(end 358.455468 -89.611962)
		(stroke
			(width 0.05715)
			(type default)
		)
		(layer "In2.Cu")
	)
	(gr_line
		(start 358.447848 -82.92592)
		(end 358.458262 -82.94116)
		(stroke
			(width 0.05715)
			(type default)
		)
		(layer "In2.Cu")
	)
	(gr_line
		(start 358.447848 -62.824868)
		(end 358.507792 -62.78118)
		(stroke
			(width 0.05715)
			(type default)
		)
		(layer "In2.Cu")
	)
	(gr_line
		(start 358.46385 -42.796206)
		(end 358.47528 -42.779188)
		(stroke
			(width 0.05715)
			(type default)
		)
		(layer "In2.Cu")
	)
	(gr_line
		(start 358.47528 -42.779188)
		(end 358.479344 -42.759122)
		(stroke
			(width 0.05715)
			(type default)
		)
		(layer "In2.Cu")
	)
	(gr_line
		(start 358.507792 -62.78118)
		(end 358.523032 -62.709298)
		(stroke
			(width 0.05715)
			(type default)
		)
		(layer "In2.Cu")
	)
	(gr_line
		(start 358.522778 -87.147654)
		(end 358.621076 -86.642194)
		(stroke
			(width 0.05715)
			(type default)
		)
		(layer "In2.Cu")
	)
	(gr_line
		(start 358.541066 -96.204024)
		(end 358.54132 -96.203008)
		(stroke
			(width 0.05715)
			(type default)
		)
		(layer "In2.Cu")
	)
	(gr_line
		(start 358.541066 -96.203008)
		(end 358.54894 -96.17202)
		(stroke
			(width 0.05715)
			(type default)
		)
		(layer "In2.Cu")
	)
	(gr_line
		(start 358.54132 -96.203008)
		(end 358.54894 -96.17202)
		(stroke
			(width 0.05715)
			(type default)
		)
		(layer "In2.Cu")
	)
	(gr_line
		(start 358.542082 -96.141286)
		(end 358.54894 -96.17202)
		(stroke
			(width 0.05715)
			(type default)
		)
		(layer "In2.Cu")
	)
	(gr_line
		(start 358.542336 -96.14154)
		(end 358.54894 -96.17202)
		(stroke
			(width 0.05715)
			(type default)
		)
		(layer "In2.Cu")
	)
	(gr_line
		(start 358.593644 -65.599056)
		(end 358.61117 -65.550034)
		(stroke
			(width 0.05715)
			(type default)
		)
		(layer "In2.Cu")
	)
	(gr_line
		(start 358.61117 -65.550034)
		(end 358.652572 -65.520062)
		(stroke
			(width 0.05715)
			(type default)
		)
		(layer "In2.Cu")
	)
	(gr_line
		(start 358.611678 -88.235536)
		(end 358.802432 -88.106758)
		(stroke
			(width 0.05715)
			(type default)
		)
		(layer "In2.Cu")
	)
	(gr_line
		(start 358.621076 -86.642194)
		(end 358.62133 -86.642194)
		(stroke
			(width 0.05715)
			(type default)
		)
		(layer "In2.Cu")
	)
	(gr_line
		(start 358.62133 -86.642194)
		(end 358.633014 -86.582758)
		(stroke
			(width 0.05715)
			(type default)
		)
		(layer "In2.Cu")
	)
	(gr_line
		(start 358.633014 -86.582758)
		(end 358.637078 -86.561422)
		(stroke
			(width 0.05715)
			(type default)
		)
		(layer "In2.Cu")
	)
	(gr_line
		(start 358.644952 -56.968898)
		(end 358.659684 -56.92775)
		(stroke
			(width 0.05715)
			(type default)
		)
		(layer "In2.Cu")
	)
	(gr_line
		(start 358.644952 -56.967882)
		(end 358.659684 -56.92775)
		(stroke
			(width 0.05715)
			(type default)
		)
		(layer "In2.Cu")
	)
	(gr_line
		(start 358.645206 -101.759512)
		(end 358.665018 -101.81463)
		(stroke
			(width 0.05715)
			(type default)
		)
		(layer "In2.Cu")
	)
	(gr_line
		(start 358.651048 -56.885332)
		(end 358.659684 -56.92775)
		(stroke
			(width 0.05715)
			(type default)
		)
		(layer "In2.Cu")
	)
	(gr_line
		(start 358.651048 -56.884824)
		(end 358.659684 -56.92775)
		(stroke
			(width 0.05715)
			(type default)
		)
		(layer "In2.Cu")
	)
	(gr_line
		(start 358.665018 -101.81463)
		(end 358.71277 -101.847396)
		(stroke
			(width 0.05715)
			(type default)
		)
		(layer "In2.Cu")
	)
	(gr_line
		(start 358.66959 -83.254342)
		(end 358.682036 -83.272884)
		(stroke
			(width 0.05715)
			(type default)
		)
		(layer "In2.Cu")
	)
	(gr_line
		(start 358.672638 -94.605856)
		(end 358.771698 -95.189548)
		(stroke
			(width 0.05715)
			(type default)
		)
		(layer "In2.Cu")
	)
	(gr_line
		(start 358.672638 -94.605602)
		(end 358.771952 -95.19158)
		(stroke
			(width 0.05715)
			(type default)
		)
		(layer "In2.Cu")
	)
	(gr_line
		(start 358.682036 -83.272884)
		(end 358.686354 -83.294982)
		(stroke
			(width 0.05715)
			(type default)
		)
		(layer "In2.Cu")
	)
	(gr_line
		(start 358.739186 -87.5792)
		(end 358.867964 -87.770208)
		(stroke
			(width 0.05715)
			(type default)
		)
		(layer "In2.Cu")
	)
	(gr_line
		(start 358.802432 -88.106758)
		(end 358.867964 -87.770208)
		(stroke
			(width 0.05715)
			(type default)
		)
		(layer "In2.Cu")
	)
	(gr_line
		(start 358.804972 -125.14961)
		(end 358.836214 -125.180852)
		(stroke
			(width 0.05715)
			(type default)
		)
		(layer "In2.Cu")
	)
	(gr_line
		(start 358.804972 -124.732796)
		(end 358.887014 -124.650754)
		(stroke
			(width 0.05715)
			(type default)
		)
		(layer "In2.Cu")
	)
	(gr_line
		(start 358.80548 -87.238078)
		(end 358.996234 -87.1093)
		(stroke
			(width 0.05715)
			(type default)
		)
		(layer "In2.Cu")
	)
	(gr_line
		(start 358.836214 -125.180852)
		(end 358.836214 -125.532642)
		(stroke
			(width 0.05715)
			(type default)
		)
		(layer "In2.Cu")
	)
	(gr_line
		(start 358.83723 -94.134178)
		(end 358.89692 -94.180152)
		(stroke
			(width 0.05715)
			(type default)
		)
		(layer "In2.Cu")
	)
	(gr_line
		(start 358.842056 -95.607632)
		(end 358.941116 -96.19234)
		(stroke
			(width 0.05715)
			(type default)
		)
		(layer "In2.Cu")
	)
	(gr_line
		(start 358.84231 -95.60814)
		(end 358.941116 -96.19234)
		(stroke
			(width 0.05715)
			(type default)
		)
		(layer "In2.Cu")
	)
	(gr_line
		(start 358.862122 -33.535366)
		(end 358.87279 -33.51911)
		(stroke
			(width 0.05715)
			(type default)
		)
		(layer "In2.Cu")
	)
	(gr_line
		(start 358.872282 -122.110754)
		(end 358.951022 -122.189494)
		(stroke
			(width 0.05715)
			(type default)
		)
		(layer "In2.Cu")
	)
	(gr_line
		(start 358.872282 -121.69394)
		(end 358.912414 -121.653808)
		(stroke
			(width 0.05715)
			(type default)
		)
		(layer "In2.Cu")
	)
	(gr_line
		(start 358.87279 -33.51911)
		(end 358.8766 -33.50133)
		(stroke
			(width 0.05715)
			(type default)
		)
		(layer "In2.Cu")
	)
	(gr_line
		(start 358.887014 -124.338842)
		(end 358.887014 -124.650754)
		(stroke
			(width 0.05715)
			(type default)
		)
		(layer "In2.Cu")
	)
	(gr_line
		(start 358.896158 -53.098192)
		(end 358.900476 -53.119782)
		(stroke
			(width 0.05715)
			(type default)
		)
		(layer "In2.Cu")
	)
	(gr_line
		(start 358.896158 -53.098192)
		(end 358.900476 -53.119528)
		(stroke
			(width 0.05715)
			(type default)
		)
		(layer "In2.Cu")
	)
	(gr_line
		(start 358.896158 -53.098192)
		(end 358.900476 -53.07711)
		(stroke
			(width 0.05715)
			(type default)
		)
		(layer "In2.Cu")
	)
	(gr_line
		(start 358.896158 -53.098192)
		(end 358.900476 -53.076856)
		(stroke
			(width 0.05715)
			(type default)
		)
		(layer "In2.Cu")
	)
	(gr_line
		(start 358.89692 -94.180152)
		(end 358.90962 -94.255082)
		(stroke
			(width 0.05715)
			(type default)
		)
		(layer "In2.Cu")
	)
	(gr_line
		(start 358.900476 -53.119528)
		(end 358.900476 -53.120036)
		(stroke
			(width 0.05715)
			(type default)
		)
		(layer "In2.Cu")
	)
	(gr_line
		(start 358.912414 -121.265442)
		(end 358.912414 -121.653808)
		(stroke
			(width 0.05715)
			(type default)
		)
		(layer "In2.Cu")
	)
	(gr_line
		(start 358.933242 -86.581996)
		(end 359.061766 -86.77275)
		(stroke
			(width 0.05715)
			(type default)
		)
		(layer "In2.Cu")
	)
	(gr_line
		(start 358.951022 -122.189494)
		(end 358.951022 -122.563128)
		(stroke
			(width 0.05715)
			(type default)
		)
		(layer "In2.Cu")
	)
	(gr_line
		(start 358.957118 -94.520258)
		(end 359.14457 -94.653608)
		(stroke
			(width 0.05715)
			(type default)
		)
		(layer "In2.Cu")
	)
	(gr_line
		(start 358.996234 -87.1093)
		(end 359.061766 -86.77275)
		(stroke
			(width 0.05715)
			(type default)
		)
		(layer "In2.Cu")
	)
	(gr_line
		(start 359.011982 -96.610932)
		(end 359.111042 -97.19564)
		(stroke
			(width 0.05715)
			(type default)
		)
		(layer "In2.Cu")
	)
	(gr_line
		(start 359.011982 -96.610678)
		(end 359.111042 -97.195894)
		(stroke
			(width 0.05715)
			(type default)
		)
		(layer "In2.Cu")
	)
	(gr_line
		(start 359.018332 -63.209932)
		(end 359.07853 -63.16599)
		(stroke
			(width 0.05715)
			(type default)
		)
		(layer "In2.Cu")
	)
	(gr_line
		(start 359.020872 -35.31235)
		(end 359.024682 -35.292284)
		(stroke
			(width 0.05715)
			(type default)
		)
		(layer "In2.Cu")
	)
	(gr_line
		(start 359.024682 -35.292284)
		(end 359.036366 -35.274504)
		(stroke
			(width 0.05715)
			(type default)
		)
		(layer "In2.Cu")
	)
	(gr_line
		(start 359.061512 -43.129454)
		(end 359.073196 -43.111674)
		(stroke
			(width 0.05715)
			(type default)
		)
		(layer "In2.Cu")
	)
	(gr_line
		(start 359.06837 -95.17888)
		(end 359.20172 -94.991682)
		(stroke
			(width 0.05715)
			(type default)
		)
		(layer "In2.Cu")
	)
	(gr_line
		(start 359.073196 -43.111674)
		(end 359.077006 -43.091608)
		(stroke
			(width 0.05715)
			(type default)
		)
		(layer "In2.Cu")
	)
	(gr_line
		(start 359.07853 -63.16599)
		(end 359.094024 -63.093346)
		(stroke
			(width 0.05715)
			(type default)
		)
		(layer "In2.Cu")
	)
	(gr_line
		(start 359.08488 -76.703682)
		(end 359.52303 -76.703682)
		(stroke
			(width 0.05715)
			(type default)
		)
		(layer "In2.Cu")
	)
	(gr_line
		(start 359.12425 -85.586824)
		(end 359.12806 -85.567266)
		(stroke
			(width 0.05715)
			(type default)
		)
		(layer "In2.Cu")
	)
	(gr_line
		(start 359.12425 -85.547708)
		(end 359.12806 -85.567266)
		(stroke
			(width 0.05715)
			(type default)
		)
		(layer "In2.Cu")
	)
	(gr_line
		(start 359.124504 -85.586062)
		(end 359.12806 -85.567266)
		(stroke
			(width 0.05715)
			(type default)
		)
		(layer "In2.Cu")
	)
	(gr_line
		(start 359.124504 -85.54847)
		(end 359.12806 -85.567266)
		(stroke
			(width 0.05715)
			(type default)
		)
		(layer "In2.Cu")
	)
	(gr_line
		(start 359.126536 -95.522288)
		(end 359.313988 -95.65513)
		(stroke
			(width 0.05715)
			(type default)
		)
		(layer "In2.Cu")
	)
	(gr_line
		(start 359.14457 -94.653608)
		(end 359.20172 -94.991682)
		(stroke
			(width 0.05715)
			(type default)
		)
		(layer "In2.Cu")
	)
	(gr_line
		(start 359.226866 -68.513706)
		(end 359.232454 -68.539614)
		(stroke
			(width 0.05715)
			(type default)
		)
		(layer "In2.Cu")
	)
	(gr_line
		(start 359.226866 -68.513706)
		(end 359.233216 -68.487036)
		(stroke
			(width 0.05715)
			(type default)
		)
		(layer "In2.Cu")
	)
	(gr_line
		(start 359.233216 -68.486782)
		(end 359.23347 -68.48602)
		(stroke
			(width 0.05715)
			(type default)
		)
		(layer "In2.Cu")
	)
	(gr_line
		(start 359.238042 -96.180656)
		(end 359.371138 -95.993458)
		(stroke
			(width 0.05715)
			(type default)
		)
		(layer "In2.Cu")
	)
	(gr_line
		(start 359.295954 -96.524064)
		(end 359.483406 -96.656906)
		(stroke
			(width 0.05715)
			(type default)
		)
		(layer "In2.Cu")
	)
	(gr_line
		(start 359.313988 -95.65513)
		(end 359.371138 -95.993458)
		(stroke
			(width 0.05715)
			(type default)
		)
		(layer "In2.Cu")
	)
	(gr_line
		(start 359.316274 -57.026048)
		(end 359.316528 -57.025032)
		(stroke
			(width 0.05715)
			(type default)
		)
		(layer "In2.Cu")
	)
	(gr_line
		(start 359.316528 -57.025032)
		(end 359.331514 -56.983122)
		(stroke
			(width 0.05715)
			(type default)
		)
		(layer "In2.Cu")
	)
	(gr_line
		(start 359.316528 -57.024778)
		(end 359.331514 -56.983122)
		(stroke
			(width 0.05715)
			(type default)
		)
		(layer "In2.Cu")
	)
	(gr_line
		(start 359.322624 -56.939688)
		(end 359.331514 -56.983122)
		(stroke
			(width 0.05715)
			(type default)
		)
		(layer "In2.Cu")
	)
	(gr_line
		(start 359.322624 -56.939434)
		(end 359.331514 -56.983122)
		(stroke
			(width 0.05715)
			(type default)
		)
		(layer "In2.Cu")
	)
	(gr_line
		(start 359.322624 -56.93918)
		(end 359.322624 -56.939434)
		(stroke
			(width 0.05715)
			(type default)
		)
		(layer "In2.Cu")
	)
	(gr_line
		(start 359.325926 -47.088044)
		(end 359.329736 -47.067978)
		(stroke
			(width 0.05715)
			(type default)
		)
		(layer "In2.Cu")
	)
	(gr_line
		(start 359.329736 -47.067978)
		(end 359.341166 -47.05096)
		(stroke
			(width 0.05715)
			(type default)
		)
		(layer "In2.Cu")
	)
	(gr_line
		(start 359.333546 -98.512376)
		(end 359.336086 -98.526854)
		(stroke
			(width 0.05715)
			(type default)
		)
		(layer "In2.Cu")
	)
	(gr_line
		(start 359.336086 -98.526854)
		(end 359.343198 -98.539046)
		(stroke
			(width 0.05715)
			(type default)
		)
		(layer "In2.Cu")
	)
	(gr_line
		(start 359.376218 -94.103444)
		(end 359.400856 -94.122494)
		(stroke
			(width 0.05715)
			(type default)
		)
		(layer "In2.Cu")
	)
	(gr_line
		(start 359.400856 -94.122494)
		(end 359.431082 -94.12859)
		(stroke
			(width 0.05715)
			(type default)
		)
		(layer "In2.Cu")
	)
	(gr_line
		(start 359.40746 -97.182686)
		(end 359.540556 -96.99498)
		(stroke
			(width 0.05715)
			(type default)
		)
		(layer "In2.Cu")
	)
	(gr_line
		(start 359.451148 -33.916112)
		(end 359.461816 -33.899856)
		(stroke
			(width 0.05715)
			(type default)
		)
		(layer "In2.Cu")
	)
	(gr_line
		(start 359.461816 -33.899856)
		(end 359.46588 -33.880806)
		(stroke
			(width 0.05715)
			(type default)
		)
		(layer "In2.Cu")
	)
	(gr_line
		(start 359.483406 -96.656906)
		(end 359.540556 -96.99498)
		(stroke
			(width 0.05715)
			(type default)
		)
		(layer "In2.Cu")
	)
	(gr_line
		(start 359.52303 -76.703682)
		(end 359.63479 -76.591922)
		(stroke
			(width 0.05715)
			(type default)
		)
		(layer "In2.Cu")
	)
	(gr_line
		(start 359.549954 -44.905676)
		(end 359.560622 -44.889674)
		(stroke
			(width 0.05715)
			(type default)
		)
		(layer "In2.Cu")
	)
	(gr_line
		(start 359.560622 -44.889674)
		(end 359.564178 -44.870878)
		(stroke
			(width 0.05715)
			(type default)
		)
		(layer "In2.Cu")
	)
	(gr_line
		(start 359.600754 -100.464366)
		(end 359.62209 -100.376228)
		(stroke
			(width 0.05715)
			(type default)
		)
		(layer "In2.Cu")
	)
	(gr_line
		(start 359.600754 -100.464366)
		(end 359.62209 -100.375974)
		(stroke
			(width 0.05715)
			(type default)
		)
		(layer "In2.Cu")
	)
	(gr_line
		(start 359.600754 -100.464366)
		(end 359.651554 -100.539804)
		(stroke
			(width 0.05715)
			(type default)
		)
		(layer "In2.Cu")
	)
	(gr_line
		(start 359.600754 -100.464366)
		(end 359.652062 -100.540312)
		(stroke
			(width 0.05715)
			(type default)
		)
		(layer "In2.Cu")
	)
	(gr_line
		(start 359.610152 -35.61969)
		(end 359.613962 -35.60064)
		(stroke
			(width 0.05715)
			(type default)
		)
		(layer "In2.Cu")
	)
	(gr_line
		(start 359.613962 -35.60064)
		(end 359.62463 -35.584892)
		(stroke
			(width 0.05715)
			(type default)
		)
		(layer "In2.Cu")
	)
	(gr_line
		(start 359.620312 -63.572644)
		(end 359.68051 -63.528702)
		(stroke
			(width 0.05715)
			(type default)
		)
		(layer "In2.Cu")
	)
	(gr_line
		(start 359.651808 -100.540312)
		(end 359.652316 -100.541328)
		(stroke
			(width 0.05715)
			(type default)
		)
		(layer "In2.Cu")
	)
	(gr_line
		(start 359.68051 -63.528702)
		(end 359.696004 -63.456058)
		(stroke
			(width 0.05715)
			(type default)
		)
		(layer "In2.Cu")
	)
	(gr_line
		(start 359.891584 -65.745868)
		(end 359.908094 -65.677288)
		(stroke
			(width 0.05715)
			(type default)
		)
		(layer "In2.Cu")
	)
	(gr_line
		(start 359.908094 -65.677288)
		(end 359.964736 -65.63614)
		(stroke
			(width 0.05715)
			(type default)
		)
		(layer "In2.Cu")
	)
	(gr_arc
		(start 359.929684 -76.591668)
		(mid 359.963796 -76.671007)
		(end 360.04373 -76.703682)
		(stroke
			(width 0.05715)
			(type default)
		)
		(layer "In2.Cu")
	)
	(gr_line
		(start 359.989628 -57.093866)
		(end 359.989882 -57.09285)
		(stroke
			(width 0.05715)
			(type default)
		)
		(layer "In2.Cu")
	)
	(gr_line
		(start 359.989628 -57.09285)
		(end 360.004868 -57.05094)
		(stroke
			(width 0.05715)
			(type default)
		)
		(layer "In2.Cu")
	)
	(gr_line
		(start 359.989882 -57.09285)
		(end 360.004868 -57.05094)
		(stroke
			(width 0.05715)
			(type default)
		)
		(layer "In2.Cu")
	)
	(gr_line
		(start 359.995978 -57.007506)
		(end 360.004868 -57.05094)
		(stroke
			(width 0.05715)
			(type default)
		)
		(layer "In2.Cu")
	)
	(gr_line
		(start 359.995978 -57.007252)
		(end 360.004868 -57.05094)
		(stroke
			(width 0.05715)
			(type default)
		)
		(layer "In2.Cu")
	)
	(gr_line
		(start 360.014012 -34.334958)
		(end 360.02468 -34.318702)
		(stroke
			(width 0.05715)
			(type default)
		)
		(layer "In2.Cu")
	)
	(gr_line
		(start 360.02468 -34.318702)
		(end 360.028744 -34.299652)
		(stroke
			(width 0.05715)
			(type default)
		)
		(layer "In2.Cu")
	)
	(gr_line
		(start 360.04373 -76.703682)
		(end 360.48188 -76.703682)
		(stroke
			(width 0.05715)
			(type default)
		)
		(layer "In2.Cu")
	)
	(gr_line
		(start 360.093768 -47.110904)
		(end 360.097832 -47.090838)
		(stroke
			(width 0.05715)
			(type default)
		)
		(layer "In2.Cu")
	)
	(gr_line
		(start 360.097832 -47.090838)
		(end 360.109262 -47.07382)
		(stroke
			(width 0.05715)
			(type default)
		)
		(layer "In2.Cu")
	)
	(gr_line
		(start 360.122216 -99.30765)
		(end 360.122724 -99.308412)
		(stroke
			(width 0.05715)
			(type default)
		)
		(layer "In2.Cu")
	)
	(gr_line
		(start 360.12247 -99.308158)
		(end 360.162348 -99.3775)
		(stroke
			(width 0.05715)
			(type default)
		)
		(layer "In2.Cu")
	)
	(gr_line
		(start 360.122724 -99.308412)
		(end 360.162348 -99.3775)
		(stroke
			(width 0.05715)
			(type default)
		)
		(layer "In2.Cu")
	)
	(gr_line
		(start 360.130852 -101.250496)
		(end 360.142028 -101.267006)
		(stroke
			(width 0.05715)
			(type default)
		)
		(layer "In2.Cu")
	)
	(gr_line
		(start 360.142028 -101.267006)
		(end 360.158538 -101.278182)
		(stroke
			(width 0.05715)
			(type default)
		)
		(layer "In2.Cu")
	)
	(gr_line
		(start 360.143806 -99.45497)
		(end 360.162348 -99.3775)
		(stroke
			(width 0.05715)
			(type default)
		)
		(layer "In2.Cu")
	)
	(gr_line
		(start 360.143806 -99.454716)
		(end 360.162348 -99.3775)
		(stroke
			(width 0.05715)
			(type default)
		)
		(layer "In2.Cu")
	)
	(gr_line
		(start 360.14533 -45.184568)
		(end 360.157014 -45.166788)
		(stroke
			(width 0.05715)
			(type default)
		)
		(layer "In2.Cu")
	)
	(gr_line
		(start 360.157014 -45.166788)
		(end 360.160824 -45.146722)
		(stroke
			(width 0.05715)
			(type default)
		)
		(layer "In2.Cu")
	)
	(gr_line
		(start 360.1593 -87.594186)
		(end 360.16311 -87.613236)
		(stroke
			(width 0.05715)
			(type default)
		)
		(layer "In2.Cu")
	)
	(gr_line
		(start 360.1593 -87.594186)
		(end 360.163364 -87.574374)
		(stroke
			(width 0.05715)
			(type default)
		)
		(layer "In2.Cu")
	)
	(gr_line
		(start 360.19105 -63.958724)
		(end 360.25074 -63.91529)
		(stroke
			(width 0.05715)
			(type default)
		)
		(layer "In2.Cu")
	)
	(gr_line
		(start 360.215688 -102.523798)
		(end 360.23296 -102.535736)
		(stroke
			(width 0.05715)
			(type default)
		)
		(layer "In2.Cu")
	)
	(gr_line
		(start 360.222038 -35.87242)
		(end 360.225848 -35.852354)
		(stroke
			(width 0.05715)
			(type default)
		)
		(layer "In2.Cu")
	)
	(gr_line
		(start 360.225848 -35.852354)
		(end 360.237532 -35.834574)
		(stroke
			(width 0.05715)
			(type default)
		)
		(layer "In2.Cu")
	)
	(gr_line
		(start 360.23296 -102.535736)
		(end 360.244136 -102.553008)
		(stroke
			(width 0.05715)
			(type default)
		)
		(layer "In2.Cu")
	)
	(gr_line
		(start 360.241342 -56.220614)
		(end 360.24566 -56.24195)
		(stroke
			(width 0.05715)
			(type default)
		)
		(layer "In2.Cu")
	)
	(gr_line
		(start 360.241342 -56.220614)
		(end 360.24566 -56.199278)
		(stroke
			(width 0.05715)
			(type default)
		)
		(layer "In2.Cu")
	)
	(gr_line
		(start 360.24566 -88.025732)
		(end 360.362754 -88.609932)
		(stroke
			(width 0.05715)
			(type default)
		)
		(layer "In2.Cu")
	)
	(gr_line
		(start 360.24566 -87.162894)
		(end 360.362246 -86.579456)
		(stroke
			(width 0.05715)
			(type default)
		)
		(layer "In2.Cu")
	)
	(gr_line
		(start 360.25074 -63.91529)
		(end 360.266234 -63.842646)
		(stroke
			(width 0.05715)
			(type default)
		)
		(layer "In2.Cu")
	)
	(gr_line
		(start 360.307636 -113.913412)
		(end 360.32313 -113.856262)
		(stroke
			(width 0.05715)
			(type default)
		)
		(layer "In2.Cu")
	)
	(gr_line
		(start 360.307636 -113.913412)
		(end 360.323384 -113.856008)
		(stroke
			(width 0.05715)
			(type default)
		)
		(layer "In2.Cu")
	)
	(gr_line
		(start 360.307636 -113.913412)
		(end 360.328972 -113.968784)
		(stroke
			(width 0.05715)
			(type default)
		)
		(layer "In2.Cu")
	)
	(gr_line
		(start 360.307636 -113.913412)
		(end 360.329226 -113.969292)
		(stroke
			(width 0.05715)
			(type default)
		)
		(layer "In2.Cu")
	)
	(gr_line
		(start 360.319828 -59.10453)
		(end 360.32313 -59.089036)
		(stroke
			(width 0.05715)
			(type default)
		)
		(layer "In2.Cu")
	)
	(gr_line
		(start 360.32313 -113.856262)
		(end 360.323384 -113.8555)
		(stroke
			(width 0.05715)
			(type default)
		)
		(layer "In2.Cu")
	)
	(gr_line
		(start 360.32313 -59.089036)
		(end 360.331258 -59.07659)
		(stroke
			(width 0.05715)
			(type default)
		)
		(layer "In2.Cu")
	)
	(gr_line
		(start 360.444796 -86.166706)
		(end 360.56189 -85.581998)
		(stroke
			(width 0.05715)
			(type default)
		)
		(layer "In2.Cu")
	)
	(gr_line
		(start 360.527346 -87.932514)
		(end 360.718862 -88.060022)
		(stroke
			(width 0.05715)
			(type default)
		)
		(layer "In2.Cu")
	)
	(gr_line
		(start 360.527346 -87.255858)
		(end 360.718862 -87.12835)
		(stroke
			(width 0.05715)
			(type default)
		)
		(layer "In2.Cu")
	)
	(gr_line
		(start 360.55046 -89.549478)
		(end 360.55427 -89.568528)
		(stroke
			(width 0.05715)
			(type default)
		)
		(layer "In2.Cu")
	)
	(gr_line
		(start 360.55427 -89.568528)
		(end 360.564938 -89.584784)
		(stroke
			(width 0.05715)
			(type default)
		)
		(layer "In2.Cu")
	)
	(gr_line
		(start 360.569002 -111.216694)
		(end 360.581956 -111.168942)
		(stroke
			(width 0.05715)
			(type default)
		)
		(layer "In2.Cu")
	)
	(gr_line
		(start 360.569002 -111.216694)
		(end 360.58221 -111.168688)
		(stroke
			(width 0.05715)
			(type default)
		)
		(layer "In2.Cu")
	)
	(gr_line
		(start 360.569002 -111.216694)
		(end 360.583988 -111.263684)
		(stroke
			(width 0.05715)
			(type default)
		)
		(layer "In2.Cu")
	)
	(gr_line
		(start 360.569002 -111.216694)
		(end 360.584242 -111.264446)
		(stroke
			(width 0.05715)
			(type default)
		)
		(layer "In2.Cu")
	)
	(gr_line
		(start 360.581956 -111.168942)
		(end 360.58221 -111.16818)
		(stroke
			(width 0.05715)
			(type default)
		)
		(layer "In2.Cu")
	)
	(gr_line
		(start 360.597704 -34.65195)
		(end 360.608372 -34.635694)
		(stroke
			(width 0.05715)
			(type default)
		)
		(layer "In2.Cu")
	)
	(gr_line
		(start 360.608372 -34.635694)
		(end 360.612436 -34.616644)
		(stroke
			(width 0.05715)
			(type default)
		)
		(layer "In2.Cu")
	)
	(gr_line
		(start 360.643678 -85.171788)
		(end 360.761026 -84.586064)
		(stroke
			(width 0.05715)
			(type default)
		)
		(layer "In2.Cu")
	)
	(gr_line
		(start 360.65841 -88.58758)
		(end 360.785918 -88.396064)
		(stroke
			(width 0.05715)
			(type default)
		)
		(layer "In2.Cu")
	)
	(gr_line
		(start 360.65841 -86.601046)
		(end 360.785918 -86.792308)
		(stroke
			(width 0.05715)
			(type default)
		)
		(layer "In2.Cu")
	)
	(gr_line
		(start 360.684064 -57.039764)
		(end 360.69905 -56.998108)
		(stroke
			(width 0.05715)
			(type default)
		)
		(layer "In2.Cu")
	)
	(gr_line
		(start 360.684064 -57.039002)
		(end 360.69905 -56.998108)
		(stroke
			(width 0.05715)
			(type default)
		)
		(layer "In2.Cu")
	)
	(gr_line
		(start 360.69016 -56.954674)
		(end 360.69905 -56.998108)
		(stroke
			(width 0.05715)
			(type default)
		)
		(layer "In2.Cu")
	)
	(gr_line
		(start 360.69016 -56.95442)
		(end 360.69905 -56.998108)
		(stroke
			(width 0.05715)
			(type default)
		)
		(layer "In2.Cu")
	)
	(gr_line
		(start 360.69016 -56.954166)
		(end 360.69016 -56.95442)
		(stroke
			(width 0.05715)
			(type default)
		)
		(layer "In2.Cu")
	)
	(gr_line
		(start 360.70413 -92.629482)
		(end 360.72318 -92.633292)
		(stroke
			(width 0.05715)
			(type default)
		)
		(layer "In2.Cu")
	)
	(gr_line
		(start 360.718862 -88.060022)
		(end 360.785918 -88.396064)
		(stroke
			(width 0.05715)
			(type default)
		)
		(layer "In2.Cu")
	)
	(gr_line
		(start 360.718862 -87.12835)
		(end 360.785918 -86.792308)
		(stroke
			(width 0.05715)
			(type default)
		)
		(layer "In2.Cu")
	)
	(gr_line
		(start 360.72318 -92.633292)
		(end 360.739436 -92.64396)
		(stroke
			(width 0.05715)
			(type default)
		)
		(layer "In2.Cu")
	)
	(gr_line
		(start 360.725974 -50.614072)
		(end 360.729784 -50.633122)
		(stroke
			(width 0.05715)
			(type default)
		)
		(layer "In2.Cu")
	)
	(gr_line
		(start 360.725974 -50.614072)
		(end 360.730038 -50.59426)
		(stroke
			(width 0.05715)
			(type default)
		)
		(layer "In2.Cu")
	)
	(gr_line
		(start 360.726736 -86.25967)
		(end 360.917998 -86.132162)
		(stroke
			(width 0.05715)
			(type default)
		)
		(layer "In2.Cu")
	)
	(gr_line
		(start 360.731816 -45.512228)
		(end 360.743246 -45.49521)
		(stroke
			(width 0.05715)
			(type default)
		)
		(layer "In2.Cu")
	)
	(gr_line
		(start 360.743246 -45.49521)
		(end 360.747056 -45.475144)
		(stroke
			(width 0.05715)
			(type default)
		)
		(layer "In2.Cu")
	)
	(gr_line
		(start 360.762296 -64.343534)
		(end 360.822494 -64.299592)
		(stroke
			(width 0.05715)
			(type default)
		)
		(layer "In2.Cu")
	)
	(gr_line
		(start 360.767376 -103.350568)
		(end 360.7943 -103.391716)
		(stroke
			(width 0.05715)
			(type default)
		)
		(layer "In2.Cu")
	)
	(gr_line
		(start 360.772202 -13.966952)
		(end 360.788204 -13.892022)
		(stroke
			(width 0.05715)
			(type default)
		)
		(layer "In2.Cu")
	)
	(gr_line
		(start 360.78541 -80.038448)
		(end 360.789982 -80.060546)
		(stroke
			(width 0.05715)
			(type default)
		)
		(layer "In2.Cu")
	)
	(gr_line
		(start 360.78541 -80.038448)
		(end 360.790236 -80.016096)
		(stroke
			(width 0.05715)
			(type default)
		)
		(layer "In2.Cu")
	)
	(gr_line
		(start 360.788204 -13.892022)
		(end 360.850434 -13.847572)
		(stroke
			(width 0.05715)
			(type default)
		)
		(layer "In2.Cu")
	)
	(gr_line
		(start 360.822494 -64.299592)
		(end 360.837988 -64.226948)
		(stroke
			(width 0.05715)
			(type default)
		)
		(layer "In2.Cu")
	)
	(gr_line
		(start 360.833416 -101.380798)
		(end 360.848656 -101.390958)
		(stroke
			(width 0.05715)
			(type default)
		)
		(layer "In2.Cu")
	)
	(gr_line
		(start 360.833416 -101.380544)
		(end 360.848656 -101.390958)
		(stroke
			(width 0.05715)
			(type default)
		)
		(layer "In2.Cu")
	)
	(gr_line
		(start 360.842814 -84.1756)
		(end 360.960416 -83.58759)
		(stroke
			(width 0.05715)
			(type default)
		)
		(layer "In2.Cu")
	)
	(gr_line
		(start 360.847894 -120.38965)
		(end 360.937556 -120.4087)
		(stroke
			(width 0.05715)
			(type default)
		)
		(layer "In2.Cu")
	)
	(gr_line
		(start 360.848656 -101.390958)
		(end 360.85907 -101.406198)
		(stroke
			(width 0.05715)
			(type default)
		)
		(layer "In2.Cu")
	)
	(gr_line
		(start 360.8578 -85.604604)
		(end 360.985054 -85.79612)
		(stroke
			(width 0.05715)
			(type default)
		)
		(layer "In2.Cu")
	)
	(gr_line
		(start 360.898948 -59.447938)
		(end 360.90225 -59.432444)
		(stroke
			(width 0.05715)
			(type default)
		)
		(layer "In2.Cu")
	)
	(gr_line
		(start 360.90225 -59.432444)
		(end 360.910378 -59.419998)
		(stroke
			(width 0.05715)
			(type default)
		)
		(layer "In2.Cu")
	)
	(gr_line
		(start 360.917998 -86.132162)
		(end 360.985054 -85.79612)
		(stroke
			(width 0.05715)
			(type default)
		)
		(layer "In2.Cu")
	)
	(gr_line
		(start 360.925872 -85.263736)
		(end 361.117388 -85.135974)
		(stroke
			(width 0.05715)
			(type default)
		)
		(layer "In2.Cu")
	)
	(gr_line
		(start 360.937556 -120.4087)
		(end 360.983784 -120.48744)
		(stroke
			(width 0.05715)
			(type default)
		)
		(layer "In2.Cu")
	)
	(gr_line
		(start 360.979212 -113.87201)
		(end 360.994706 -113.815368)
		(stroke
			(width 0.05715)
			(type default)
		)
		(layer "In2.Cu")
	)
	(gr_line
		(start 360.979212 -113.87201)
		(end 360.994706 -113.815114)
		(stroke
			(width 0.05715)
			(type default)
		)
		(layer "In2.Cu")
	)
	(gr_line
		(start 360.979212 -113.87201)
		(end 361.000802 -113.92789)
		(stroke
			(width 0.05715)
			(type default)
		)
		(layer "In2.Cu")
	)
	(gr_line
		(start 360.979212 -113.87201)
		(end 361.000802 -113.927636)
		(stroke
			(width 0.05715)
			(type default)
		)
		(layer "In2.Cu")
	)
	(gr_line
		(start 360.994706 -113.81486)
		(end 360.994706 -113.815114)
		(stroke
			(width 0.05715)
			(type default)
		)
		(layer "In2.Cu")
	)
	(gr_line
		(start 361.000802 -113.92789)
		(end 361.001056 -113.928398)
		(stroke
			(width 0.05715)
			(type default)
		)
		(layer "In2.Cu")
	)
	(gr_line
		(start 361.015534 -36.119308)
		(end 361.019344 -36.099242)
		(stroke
			(width 0.05715)
			(type default)
		)
		(layer "In2.Cu")
	)
	(gr_line
		(start 361.019344 -36.099242)
		(end 361.031028 -36.081716)
		(stroke
			(width 0.05715)
			(type default)
		)
		(layer "In2.Cu")
	)
	(gr_line
		(start 361.056936 -84.60867)
		(end 361.184444 -84.799932)
		(stroke
			(width 0.05715)
			(type default)
		)
		(layer "In2.Cu")
	)
	(gr_line
		(start 361.11434 -111.963454)
		(end 361.12958 -112.011206)
		(stroke
			(width 0.05715)
			(type default)
		)
		(layer "In2.Cu")
	)
	(gr_line
		(start 361.114594 -111.964216)
		(end 361.12958 -112.011206)
		(stroke
			(width 0.05715)
			(type default)
		)
		(layer "In2.Cu")
	)
	(gr_line
		(start 361.116372 -112.060228)
		(end 361.116626 -112.059212)
		(stroke
			(width 0.05715)
			(type default)
		)
		(layer "In2.Cu")
	)
	(gr_line
		(start 361.116626 -112.059212)
		(end 361.12958 -112.011206)
		(stroke
			(width 0.05715)
			(type default)
		)
		(layer "In2.Cu")
	)
	(gr_line
		(start 361.116626 -112.058958)
		(end 361.12958 -112.011206)
		(stroke
			(width 0.05715)
			(type default)
		)
		(layer "In2.Cu")
	)
	(gr_line
		(start 361.117388 -85.135974)
		(end 361.184444 -84.799932)
		(stroke
			(width 0.05715)
			(type default)
		)
		(layer "In2.Cu")
	)
	(gr_line
		(start 361.125262 -84.267294)
		(end 361.316524 -84.139786)
		(stroke
			(width 0.05715)
			(type default)
		)
		(layer "In2.Cu")
	)
	(gr_line
		(start 361.131358 -94.171262)
		(end 361.150408 -94.175072)
		(stroke
			(width 0.05715)
			(type default)
		)
		(layer "In2.Cu")
	)
	(gr_line
		(start 361.150408 -94.175072)
		(end 361.166156 -94.18574)
		(stroke
			(width 0.05715)
			(type default)
		)
		(layer "In2.Cu")
	)
	(gr_line
		(start 361.150408 -94.175072)
		(end 361.166664 -94.18574)
		(stroke
			(width 0.05715)
			(type default)
		)
		(layer "In2.Cu")
	)
	(gr_line
		(start 361.191048 -34.931604)
		(end 361.201716 -34.915348)
		(stroke
			(width 0.05715)
			(type default)
		)
		(layer "In2.Cu")
	)
	(gr_line
		(start 361.201716 -34.915348)
		(end 361.20578 -34.896552)
		(stroke
			(width 0.05715)
			(type default)
		)
		(layer "In2.Cu")
	)
	(gr_line
		(start 361.202732 -110.00486)
		(end 361.211368 -109.973364)
		(stroke
			(width 0.05715)
			(type default)
		)
		(layer "In2.Cu")
	)
	(gr_line
		(start 361.202732 -110.004606)
		(end 361.211368 -109.973364)
		(stroke
			(width 0.05715)
			(type default)
		)
		(layer "In2.Cu")
	)
	(gr_line
		(start 361.20451 -109.941614)
		(end 361.211368 -109.973364)
		(stroke
			(width 0.05715)
			(type default)
		)
		(layer "In2.Cu")
	)
	(gr_line
		(start 361.204764 -109.942122)
		(end 361.211368 -109.973364)
		(stroke
			(width 0.05715)
			(type default)
		)
		(layer "In2.Cu")
	)
	(gr_line
		(start 361.22356 -99.16795)
		(end 361.22864 -99.191572)
		(stroke
			(width 0.05715)
			(type default)
		)
		(layer "In2.Cu")
	)
	(gr_line
		(start 361.22356 -99.16795)
		(end 361.22864 -99.191064)
		(stroke
			(width 0.05715)
			(type default)
		)
		(layer "In2.Cu")
	)
	(gr_line
		(start 361.22356 -99.16795)
		(end 361.22864 -99.144836)
		(stroke
			(width 0.05715)
			(type default)
		)
		(layer "In2.Cu")
	)
	(gr_line
		(start 361.22356 -99.16795)
		(end 361.22864 -99.144582)
		(stroke
			(width 0.05715)
			(type default)
		)
		(layer "In2.Cu")
	)
	(gr_line
		(start 361.252008 -111.259874)
		(end 361.264962 -111.21263)
		(stroke
			(width 0.05715)
			(type default)
		)
		(layer "In2.Cu")
	)
	(gr_line
		(start 361.252008 -111.259874)
		(end 361.264962 -111.212122)
		(stroke
			(width 0.05715)
			(type default)
		)
		(layer "In2.Cu")
	)
	(gr_line
		(start 361.252008 -111.259874)
		(end 361.266994 -111.307118)
		(stroke
			(width 0.05715)
			(type default)
		)
		(layer "In2.Cu")
	)
	(gr_line
		(start 361.252008 -111.259874)
		(end 361.266994 -111.306864)
		(stroke
			(width 0.05715)
			(type default)
		)
		(layer "In2.Cu")
	)
	(gr_line
		(start 361.256072 -83.612228)
		(end 361.38358 -83.803744)
		(stroke
			(width 0.05715)
			(type default)
		)
		(layer "In2.Cu")
	)
	(gr_line
		(start 361.26039 -116.374418)
		(end 361.263692 -116.3828)
		(stroke
			(width 0.05715)
			(type default)
		)
		(layer "In2.Cu")
	)
	(gr_line
		(start 361.263692 -116.3828)
		(end 361.26928 -116.389912)
		(stroke
			(width 0.05715)
			(type default)
		)
		(layer "In2.Cu")
	)
	(gr_line
		(start 361.266994 -111.307118)
		(end 361.267248 -111.30788)
		(stroke
			(width 0.05715)
			(type default)
		)
		(layer "In2.Cu")
	)
	(gr_line
		(start 361.287822 -119.750332)
		(end 361.336844 -119.760746)
		(stroke
			(width 0.05715)
			(type default)
		)
		(layer "In2.Cu")
	)
	(gr_line
		(start 361.295188 -96.321626)
		(end 361.300268 -96.345248)
		(stroke
			(width 0.05715)
			(type default)
		)
		(layer "In2.Cu")
	)
	(gr_line
		(start 361.295188 -96.321626)
		(end 361.300268 -96.34474)
		(stroke
			(width 0.05715)
			(type default)
		)
		(layer "In2.Cu")
	)
	(gr_line
		(start 361.295188 -96.321626)
		(end 361.300268 -96.298512)
		(stroke
			(width 0.05715)
			(type default)
		)
		(layer "In2.Cu")
	)
	(gr_line
		(start 361.295188 -96.321626)
		(end 361.300268 -96.29775)
		(stroke
			(width 0.05715)
			(type default)
		)
		(layer "In2.Cu")
	)
	(gr_line
		(start 361.316524 -84.139786)
		(end 361.38358 -83.803744)
		(stroke
			(width 0.05715)
			(type default)
		)
		(layer "In2.Cu")
	)
	(gr_line
		(start 361.336844 -119.760746)
		(end 361.372404 -119.796306)
		(stroke
			(width 0.05715)
			(type default)
		)
		(layer "In2.Cu")
	)
	(gr_line
		(start 361.338114 -45.771054)
		(end 361.349544 -45.754036)
		(stroke
			(width 0.05715)
			(type default)
		)
		(layer "In2.Cu")
	)
	(gr_line
		(start 361.338876 -52.229258)
		(end 361.34294 -52.209446)
		(stroke
			(width 0.05715)
			(type default)
		)
		(layer "In2.Cu")
	)
	(gr_line
		(start 361.338876 -52.189634)
		(end 361.34294 -52.209446)
		(stroke
			(width 0.05715)
			(type default)
		)
		(layer "In2.Cu")
	)
	(gr_line
		(start 361.33913 -52.228496)
		(end 361.34294 -52.209446)
		(stroke
			(width 0.05715)
			(type default)
		)
		(layer "In2.Cu")
	)
	(gr_line
		(start 361.33913 -52.190396)
		(end 361.34294 -52.209446)
		(stroke
			(width 0.05715)
			(type default)
		)
		(layer "In2.Cu")
	)
	(gr_line
		(start 361.34548 -14.340586)
		(end 361.361482 -14.265656)
		(stroke
			(width 0.05715)
			(type default)
		)
		(layer "In2.Cu")
	)
	(gr_line
		(start 361.349544 -45.754036)
		(end 361.353608 -45.73397)
		(stroke
			(width 0.05715)
			(type default)
		)
		(layer "In2.Cu")
	)
	(gr_line
		(start 361.361482 -14.265656)
		(end 361.423712 -14.221206)
		(stroke
			(width 0.05715)
			(type default)
		)
		(layer "In2.Cu")
	)
	(gr_line
		(start 361.396788 -50.653188)
		(end 361.406186 -50.606198)
		(stroke
			(width 0.05715)
			(type default)
		)
		(layer "In2.Cu")
	)
	(gr_line
		(start 361.396788 -50.653188)
		(end 361.41406 -50.698146)
		(stroke
			(width 0.05715)
			(type default)
		)
		(layer "In2.Cu")
	)
	(gr_line
		(start 361.400852 -102.209092)
		(end 361.4293 -102.251256)
		(stroke
			(width 0.05715)
			(type default)
		)
		(layer "In2.Cu")
	)
	(gr_line
		(start 361.449874 -64.915796)
		(end 361.509818 -64.872108)
		(stroke
			(width 0.05715)
			(type default)
		)
		(layer "In2.Cu")
	)
	(gr_line
		(start 361.488228 -90.969084)
		(end 361.50042 -90.987372)
		(stroke
			(width 0.05715)
			(type default)
		)
		(layer "In2.Cu")
	)
	(gr_line
		(start 361.497372 -59.708796)
		(end 361.500674 -59.693302)
		(stroke
			(width 0.05715)
			(type default)
		)
		(layer "In2.Cu")
	)
	(gr_line
		(start 361.50042 -90.987372)
		(end 361.518708 -90.999564)
		(stroke
			(width 0.05715)
			(type default)
		)
		(layer "In2.Cu")
	)
	(gr_line
		(start 361.500674 -59.693302)
		(end 361.508802 -59.680856)
		(stroke
			(width 0.05715)
			(type default)
		)
		(layer "In2.Cu")
	)
	(gr_line
		(start 361.509818 -64.872108)
		(end 361.525312 -64.799464)
		(stroke
			(width 0.05715)
			(type default)
		)
		(layer "In2.Cu")
	)
	(gr_line
		(start 361.52074 -94.42196)
		(end 361.58932 -94.46768)
		(stroke
			(width 0.05715)
			(type default)
		)
		(layer "In2.Cu")
	)
	(gr_line
		(start 361.521502 -94.422468)
		(end 361.58932 -94.46768)
		(stroke
			(width 0.05715)
			(type default)
		)
		(layer "In2.Cu")
	)
	(gr_line
		(start 361.528868 -82.191352)
		(end 361.53344 -82.21345)
		(stroke
			(width 0.05715)
			(type default)
		)
		(layer "In2.Cu")
	)
	(gr_line
		(start 361.529122 -82.234278)
		(end 361.53344 -82.21345)
		(stroke
			(width 0.05715)
			(type default)
		)
		(layer "In2.Cu")
	)
	(gr_line
		(start 361.58932 -94.46768)
		(end 361.605576 -94.548706)
		(stroke
			(width 0.05715)
			(type default)
		)
		(layer "In2.Cu")
	)
	(gr_line
		(start 361.615736 -36.375594)
		(end 361.6198 -36.355528)
		(stroke
			(width 0.05715)
			(type default)
		)
		(layer "In2.Cu")
	)
	(gr_line
		(start 361.6198 -36.355528)
		(end 361.630976 -36.338764)
		(stroke
			(width 0.05715)
			(type default)
		)
		(layer "In2.Cu")
	)
	(gr_line
		(start 361.671108 -113.894616)
		(end 361.686602 -113.837974)
		(stroke
			(width 0.05715)
			(type default)
		)
		(layer "In2.Cu")
	)
	(gr_line
		(start 361.671108 -113.894616)
		(end 361.686856 -113.837466)
		(stroke
			(width 0.05715)
			(type default)
		)
		(layer "In2.Cu")
	)
	(gr_line
		(start 361.671108 -113.894616)
		(end 361.692444 -113.949988)
		(stroke
			(width 0.05715)
			(type default)
		)
		(layer "In2.Cu")
	)
	(gr_line
		(start 361.671108 -113.894616)
		(end 361.692444 -113.94948)
		(stroke
			(width 0.05715)
			(type default)
		)
		(layer "In2.Cu")
	)
	(gr_line
		(start 361.778042 -95.453454)
		(end 361.782868 -95.430848)
		(stroke
			(width 0.05715)
			(type default)
		)
		(layer "In2.Cu")
	)
	(gr_line
		(start 361.778042 -95.4532)
		(end 361.782868 -95.430848)
		(stroke
			(width 0.05715)
			(type default)
		)
		(layer "In2.Cu")
	)
	(gr_line
		(start 361.778296 -95.408242)
		(end 361.782868 -95.430848)
		(stroke
			(width 0.05715)
			(type default)
		)
		(layer "In2.Cu")
	)
	(gr_line
		(start 361.778296 -95.407988)
		(end 361.782868 -95.430848)
		(stroke
			(width 0.05715)
			(type default)
		)
		(layer "In2.Cu")
	)
	(gr_line
		(start 361.778804 -111.94923)
		(end 361.779058 -111.949992)
		(stroke
			(width 0.05715)
			(type default)
		)
		(layer "In2.Cu")
	)
	(gr_line
		(start 361.779058 -111.950246)
		(end 361.794044 -111.997236)
		(stroke
			(width 0.05715)
			(type default)
		)
		(layer "In2.Cu")
	)
	(gr_line
		(start 361.779058 -111.949992)
		(end 361.794044 -111.997236)
		(stroke
			(width 0.05715)
			(type default)
		)
		(layer "In2.Cu")
	)
	(gr_line
		(start 361.78109 -112.044988)
		(end 361.794044 -111.997236)
		(stroke
			(width 0.05715)
			(type default)
		)
		(layer "In2.Cu")
	)
	(gr_line
		(start 361.78109 -112.04448)
		(end 361.794044 -111.997236)
		(stroke
			(width 0.05715)
			(type default)
		)
		(layer "In2.Cu")
	)
	(gr_line
		(start 361.786678 -115.954556)
		(end 361.78998 -115.962938)
		(stroke
			(width 0.05715)
			(type default)
		)
		(layer "In2.Cu")
	)
	(gr_line
		(start 361.78998 -115.962938)
		(end 361.795568 -115.97005)
		(stroke
			(width 0.05715)
			(type default)
		)
		(layer "In2.Cu")
	)
	(gr_line
		(start 361.808776 -113.390172)
		(end 361.966764 -112.811814)
		(stroke
			(width 0.05715)
			(type default)
		)
		(layer "In2.Cu")
	)
	(gr_line
		(start 361.809538 -113.388648)
		(end 361.96651 -112.81283)
		(stroke
			(width 0.05715)
			(type default)
		)
		(layer "In2.Cu")
	)
	(gr_line
		(start 361.84332 -114.339624)
		(end 362.05922 -114.897154)
		(stroke
			(width 0.05715)
			(type default)
		)
		(layer "In2.Cu")
	)
	(gr_line
		(start 361.855512 -97.597976)
		(end 361.860592 -97.574608)
		(stroke
			(width 0.05715)
			(type default)
		)
		(layer "In2.Cu")
	)
	(gr_line
		(start 361.855512 -97.597722)
		(end 361.860592 -97.574608)
		(stroke
			(width 0.05715)
			(type default)
		)
		(layer "In2.Cu")
	)
	(gr_line
		(start 361.855512 -97.551494)
		(end 361.860592 -97.574608)
		(stroke
			(width 0.05715)
			(type default)
		)
		(layer "In2.Cu")
	)
	(gr_line
		(start 361.855512 -97.550986)
		(end 361.860592 -97.574608)
		(stroke
			(width 0.05715)
			(type default)
		)
		(layer "In2.Cu")
	)
	(gr_line
		(start 361.875832 -99.169728)
		(end 361.880912 -99.193096)
		(stroke
			(width 0.05715)
			(type default)
		)
		(layer "In2.Cu")
	)
	(gr_line
		(start 361.875832 -99.169728)
		(end 361.880912 -99.192842)
		(stroke
			(width 0.05715)
			(type default)
		)
		(layer "In2.Cu")
	)
	(gr_line
		(start 361.875832 -99.169728)
		(end 361.880912 -99.146614)
		(stroke
			(width 0.05715)
			(type default)
		)
		(layer "In2.Cu")
	)
	(gr_line
		(start 361.875832 -99.169728)
		(end 361.880912 -99.14636)
		(stroke
			(width 0.05715)
			(type default)
		)
		(layer "In2.Cu")
	)
	(gr_line
		(start 361.879896 -110.06963)
		(end 361.888532 -110.038134)
		(stroke
			(width 0.05715)
			(type default)
		)
		(layer "In2.Cu")
	)
	(gr_line
		(start 361.879896 -110.069376)
		(end 361.888532 -110.038134)
		(stroke
			(width 0.05715)
			(type default)
		)
		(layer "In2.Cu")
	)
	(gr_line
		(start 361.881674 -110.006384)
		(end 361.888532 -110.038134)
		(stroke
			(width 0.05715)
			(type default)
		)
		(layer "In2.Cu")
	)
	(gr_line
		(start 361.881928 -110.006892)
		(end 361.888532 -110.038134)
		(stroke
			(width 0.05715)
			(type default)
		)
		(layer "In2.Cu")
	)
	(gr_line
		(start 361.882436 -93.406214)
		(end 361.935776 -93.441774)
		(stroke
			(width 0.05715)
			(type default)
		)
		(layer "In2.Cu")
	)
	(gr_line
		(start 361.917234 -14.71549)
		(end 361.933236 -14.64056)
		(stroke
			(width 0.05715)
			(type default)
		)
		(layer "In2.Cu")
	)
	(gr_line
		(start 361.933236 -14.64056)
		(end 361.995466 -14.59611)
		(stroke
			(width 0.05715)
			(type default)
		)
		(layer "In2.Cu")
	)
	(gr_line
		(start 361.935776 -93.441774)
		(end 361.955334 -93.502734)
		(stroke
			(width 0.05715)
			(type default)
		)
		(layer "In2.Cu")
	)
	(gr_line
		(start 361.960414 -35.215068)
		(end 361.970066 -35.200336)
		(stroke
			(width 0.05715)
			(type default)
		)
		(layer "In2.Cu")
	)
	(gr_line
		(start 361.965748 -96.375982)
		(end 361.970828 -96.399604)
		(stroke
			(width 0.05715)
			(type default)
		)
		(layer "In2.Cu")
	)
	(gr_line
		(start 361.965748 -96.375982)
		(end 361.970828 -96.399096)
		(stroke
			(width 0.05715)
			(type default)
		)
		(layer "In2.Cu")
	)
	(gr_line
		(start 361.965748 -96.375982)
		(end 361.970828 -96.352868)
		(stroke
			(width 0.05715)
			(type default)
		)
		(layer "In2.Cu")
	)
	(gr_line
		(start 361.965748 -96.375982)
		(end 361.970828 -96.352614)
		(stroke
			(width 0.05715)
			(type default)
		)
		(layer "In2.Cu")
	)
	(gr_line
		(start 361.969304 -111.292386)
		(end 361.98175 -111.24692)
		(stroke
			(width 0.05715)
			(type default)
		)
		(layer "In2.Cu")
	)
	(gr_line
		(start 361.969304 -111.292386)
		(end 361.982004 -111.246158)
		(stroke
			(width 0.05715)
			(type default)
		)
		(layer "In2.Cu")
	)
	(gr_line
		(start 361.969304 -111.292386)
		(end 361.983782 -111.337598)
		(stroke
			(width 0.05715)
			(type default)
		)
		(layer "In2.Cu")
	)
	(gr_line
		(start 361.969304 -111.292386)
		(end 361.984036 -111.33836)
		(stroke
			(width 0.05715)
			(type default)
		)
		(layer "In2.Cu")
	)
	(gr_line
		(start 361.970066 -35.200336)
		(end 361.973622 -35.183572)
		(stroke
			(width 0.05715)
			(type default)
		)
		(layer "In2.Cu")
	)
	(gr_line
		(start 362.084366 -113.500154)
		(end 362.284264 -113.385854)
		(stroke
			(width 0.05715)
			(type default)
		)
		(layer "In2.Cu")
	)
	(gr_line
		(start 362.09351 -117.408198)
		(end 362.12145 -117.442742)
		(stroke
			(width 0.05715)
			(type default)
		)
		(layer "In2.Cu")
	)
	(gr_line
		(start 362.105194 -114.200178)
		(end 362.31576 -114.292888)
		(stroke
			(width 0.05715)
			(type default)
		)
		(layer "In2.Cu")
	)
	(gr_line
		(start 362.108242 -50.705258)
		(end 362.117132 -50.660554)
		(stroke
			(width 0.05715)
			(type default)
		)
		(layer "In2.Cu")
	)
	(gr_line
		(start 362.108242 -50.705258)
		(end 362.117386 -50.659792)
		(stroke
			(width 0.05715)
			(type default)
		)
		(layer "In2.Cu")
	)
	(gr_line
		(start 362.108242 -50.705258)
		(end 362.124752 -50.748438)
		(stroke
			(width 0.05715)
			(type default)
		)
		(layer "In2.Cu")
	)
	(gr_line
		(start 362.108242 -50.705258)
		(end 362.124752 -50.748184)
		(stroke
			(width 0.05715)
			(type default)
		)
		(layer "In2.Cu")
	)
	(gr_line
		(start 362.12145 -117.442742)
		(end 362.162598 -117.45722)
		(stroke
			(width 0.05715)
			(type default)
		)
		(layer "In2.Cu")
	)
	(gr_line
		(start 362.124752 -50.748184)
		(end 362.124752 -50.748438)
		(stroke
			(width 0.05715)
			(type default)
		)
		(layer "In2.Cu")
	)
	(gr_line
		(start 362.21162 -36.65601)
		(end 362.21543 -36.635944)
		(stroke
			(width 0.05715)
			(type default)
		)
		(layer "In2.Cu")
	)
	(gr_line
		(start 362.21543 -36.635944)
		(end 362.227114 -36.618164)
		(stroke
			(width 0.05715)
			(type default)
		)
		(layer "In2.Cu")
	)
	(gr_line
		(start 362.229654 -60.064396)
		(end 362.233718 -60.0456)
		(stroke
			(width 0.05715)
			(type default)
		)
		(layer "In2.Cu")
	)
	(gr_line
		(start 362.233718 -60.0456)
		(end 362.244386 -60.029344)
		(stroke
			(width 0.05715)
			(type default)
		)
		(layer "In2.Cu")
	)
	(gr_line
		(start 362.260388 -112.855248)
		(end 362.374434 -113.054892)
		(stroke
			(width 0.05715)
			(type default)
		)
		(layer "In2.Cu")
	)
	(gr_line
		(start 362.284264 -113.385854)
		(end 362.374434 -113.054892)
		(stroke
			(width 0.05715)
			(type default)
		)
		(layer "In2.Cu")
	)
	(gr_line
		(start 362.299758 -115.518438)
		(end 362.30306 -115.52682)
		(stroke
			(width 0.05715)
			(type default)
		)
		(layer "In2.Cu")
	)
	(gr_line
		(start 362.30306 -115.52682)
		(end 362.308648 -115.533932)
		(stroke
			(width 0.05715)
			(type default)
		)
		(layer "In2.Cu")
	)
	(gr_line
		(start 362.31576 -114.292888)
		(end 362.439712 -114.612674)
		(stroke
			(width 0.05715)
			(type default)
		)
		(layer "In2.Cu")
	)
	(gr_line
		(start 362.346494 -114.82324)
		(end 362.439712 -114.612674)
		(stroke
			(width 0.05715)
			(type default)
		)
		(layer "In2.Cu")
	)
	(gr_line
		(start 362.382816 -116.695728)
		(end 362.410756 -116.730272)
		(stroke
			(width 0.05715)
			(type default)
		)
		(layer "In2.Cu")
	)
	(gr_line
		(start 362.410756 -116.730272)
		(end 362.452412 -116.745004)
		(stroke
			(width 0.05715)
			(type default)
		)
		(layer "In2.Cu")
	)
	(gr_line
		(start 362.455714 -92.990416)
		(end 362.508546 -93.025722)
		(stroke
			(width 0.05715)
			(type default)
		)
		(layer "In2.Cu")
	)
	(gr_line
		(start 362.480606 -111.934244)
		(end 362.48086 -111.934752)
		(stroke
			(width 0.05715)
			(type default)
		)
		(layer "In2.Cu")
	)
	(gr_line
		(start 362.48086 -111.935006)
		(end 362.4961 -111.982758)
		(stroke
			(width 0.05715)
			(type default)
		)
		(layer "In2.Cu")
	)
	(gr_line
		(start 362.48086 -111.934752)
		(end 362.4961 -111.982758)
		(stroke
			(width 0.05715)
			(type default)
		)
		(layer "In2.Cu")
	)
	(gr_line
		(start 362.483146 -112.030256)
		(end 362.4961 -111.982758)
		(stroke
			(width 0.05715)
			(type default)
		)
		(layer "In2.Cu")
	)
	(gr_line
		(start 362.488226 -15.090394)
		(end 362.504228 -15.015464)
		(stroke
			(width 0.05715)
			(type default)
		)
		(layer "In2.Cu")
	)
	(gr_line
		(start 362.497624 -95.181928)
		(end 362.497624 -95.182182)
		(stroke
			(width 0.05715)
			(type default)
		)
		(layer "In2.Cu")
	)
	(gr_line
		(start 362.497624 -95.181928)
		(end 362.509816 -95.220028)
		(stroke
			(width 0.05715)
			(type default)
		)
		(layer "In2.Cu")
	)
	(gr_line
		(start 362.497624 -95.181674)
		(end 362.509816 -95.220028)
		(stroke
			(width 0.05715)
			(type default)
		)
		(layer "In2.Cu")
	)
	(gr_line
		(start 362.501434 -95.25889)
		(end 362.509816 -95.220028)
		(stroke
			(width 0.05715)
			(type default)
		)
		(layer "In2.Cu")
	)
	(gr_line
		(start 362.501434 -95.258636)
		(end 362.509816 -95.220028)
		(stroke
			(width 0.05715)
			(type default)
		)
		(layer "In2.Cu")
	)
	(gr_line
		(start 362.504228 -15.015464)
		(end 362.566458 -14.97076)
		(stroke
			(width 0.05715)
			(type default)
		)
		(layer "In2.Cu")
	)
	(gr_line
		(start 362.508546 -93.025722)
		(end 362.528104 -93.08592)
		(stroke
			(width 0.05715)
			(type default)
		)
		(layer "In2.Cu")
	)
	(gr_line
		(start 362.51134 -97.582736)
		(end 362.51642 -97.559368)
		(stroke
			(width 0.05715)
			(type default)
		)
		(layer "In2.Cu")
	)
	(gr_line
		(start 362.51134 -97.582482)
		(end 362.51642 -97.559368)
		(stroke
			(width 0.05715)
			(type default)
		)
		(layer "In2.Cu")
	)
	(gr_line
		(start 362.51134 -97.536254)
		(end 362.51642 -97.559368)
		(stroke
			(width 0.05715)
			(type default)
		)
		(layer "In2.Cu")
	)
	(gr_line
		(start 362.51134 -97.535746)
		(end 362.51642 -97.559368)
		(stroke
			(width 0.05715)
			(type default)
		)
		(layer "In2.Cu")
	)
	(gr_line
		(start 362.54817 -99.127564)
		(end 362.552742 -99.149916)
		(stroke
			(width 0.05715)
			(type default)
		)
		(layer "In2.Cu")
	)
	(gr_line
		(start 362.54817 -99.127564)
		(end 362.552996 -99.105212)
		(stroke
			(width 0.05715)
			(type default)
		)
		(layer "In2.Cu")
	)
	(gr_line
		(start 362.54817 -99.127564)
		(end 362.552996 -99.104958)
		(stroke
			(width 0.05715)
			(type default)
		)
		(layer "In2.Cu")
	)
	(gr_line
		(start 362.556806 -35.47745)
		(end 362.566458 -35.462972)
		(stroke
			(width 0.05715)
			(type default)
		)
		(layer "In2.Cu")
	)
	(gr_line
		(start 362.562394 -110.225586)
		(end 362.57103 -110.193836)
		(stroke
			(width 0.05715)
			(type default)
		)
		(layer "In2.Cu")
	)
	(gr_line
		(start 362.564172 -110.162086)
		(end 362.57103 -110.193836)
		(stroke
			(width 0.05715)
			(type default)
		)
		(layer "In2.Cu")
	)
	(gr_line
		(start 362.564426 -110.162594)
		(end 362.57103 -110.193836)
		(stroke
			(width 0.05715)
			(type default)
		)
		(layer "In2.Cu")
	)
	(gr_line
		(start 362.566458 -35.462972)
		(end 362.570014 -35.446208)
		(stroke
			(width 0.05715)
			(type default)
		)
		(layer "In2.Cu")
	)
	(gr_line
		(start 362.636054 -96.466152)
		(end 362.641134 -96.490028)
		(stroke
			(width 0.05715)
			(type default)
		)
		(layer "In2.Cu")
	)
	(gr_line
		(start 362.636054 -96.466152)
		(end 362.641134 -96.489266)
		(stroke
			(width 0.05715)
			(type default)
		)
		(layer "In2.Cu")
	)
	(gr_line
		(start 362.636054 -96.466152)
		(end 362.641134 -96.443038)
		(stroke
			(width 0.05715)
			(type default)
		)
		(layer "In2.Cu")
	)
	(gr_line
		(start 362.636054 -96.466152)
		(end 362.641134 -96.44253)
		(stroke
			(width 0.05715)
			(type default)
		)
		(layer "In2.Cu")
	)
	(gr_line
		(start 362.71962 -116.041424)
		(end 362.74756 -116.075968)
		(stroke
			(width 0.05715)
			(type default)
		)
		(layer "In2.Cu")
	)
	(gr_line
		(start 362.74756 -116.075968)
		(end 362.788708 -116.090446)
		(stroke
			(width 0.05715)
			(type default)
		)
		(layer "In2.Cu")
	)
	(gr_line
		(start 362.74756 -116.075968)
		(end 362.789216 -116.0907)
		(stroke
			(width 0.05715)
			(type default)
		)
		(layer "In2.Cu")
	)
	(gr_line
		(start 362.823506 -36.901628)
		(end 362.827316 -36.882578)
		(stroke
			(width 0.05715)
			(type default)
		)
		(layer "In2.Cu")
	)
	(gr_line
		(start 362.827316 -36.882578)
		(end 362.837984 -36.866322)
		(stroke
			(width 0.05715)
			(type default)
		)
		(layer "In2.Cu")
	)
	(gr_line
		(start 362.879386 -109.785658)
		(end 362.89488 -109.85881)
		(stroke
			(width 0.05715)
			(type default)
		)
		(layer "In2.Cu")
	)
	(gr_line
		(start 362.89488 -109.85881)
		(end 362.955332 -109.902752)
		(stroke
			(width 0.05715)
			(type default)
		)
		(layer "In2.Cu")
	)
	(gr_line
		(start 362.914692 -16.24203)
		(end 362.930694 -16.1671)
		(stroke
			(width 0.05715)
			(type default)
		)
		(layer "In2.Cu")
	)
	(gr_line
		(start 362.930694 -16.1671)
		(end 362.992924 -16.12265)
		(stroke
			(width 0.05715)
			(type default)
		)
		(layer "In2.Cu")
	)
	(gr_line
		(start 363.000036 -54.156356)
		(end 363.029246 -54.08422)
		(stroke
			(width 0.05715)
			(type default)
		)
		(layer "In2.Cu")
	)
	(gr_line
		(start 363.001052 -54.010814)
		(end 363.001306 -54.011322)
		(stroke
			(width 0.05715)
			(type default)
		)
		(layer "In2.Cu")
	)
	(gr_line
		(start 363.001306 -54.011576)
		(end 363.029246 -54.08422)
		(stroke
			(width 0.05715)
			(type default)
		)
		(layer "In2.Cu")
	)
	(gr_line
		(start 363.001306 -54.011322)
		(end 363.029246 -54.08422)
		(stroke
			(width 0.05715)
			(type default)
		)
		(layer "In2.Cu")
	)
	(gr_line
		(start 363.030262 -92.606114)
		(end 363.083602 -92.641674)
		(stroke
			(width 0.05715)
			(type default)
		)
		(layer "In2.Cu")
	)
	(gr_line
		(start 363.083602 -92.641674)
		(end 363.103668 -92.703396)
		(stroke
			(width 0.05715)
			(type default)
		)
		(layer "In2.Cu")
	)
	(gr_line
		(start 363.16793 -97.61347)
		(end 363.17301 -97.590102)
		(stroke
			(width 0.05715)
			(type default)
		)
		(layer "In2.Cu")
	)
	(gr_line
		(start 363.16793 -97.613216)
		(end 363.17301 -97.590102)
		(stroke
			(width 0.05715)
			(type default)
		)
		(layer "In2.Cu")
	)
	(gr_line
		(start 363.16793 -97.566988)
		(end 363.17301 -97.590102)
		(stroke
			(width 0.05715)
			(type default)
		)
		(layer "In2.Cu")
	)
	(gr_line
		(start 363.16793 -97.566226)
		(end 363.17301 -97.590102)
		(stroke
			(width 0.05715)
			(type default)
		)
		(layer "In2.Cu")
	)
	(gr_line
		(start 363.194854 -95.147892)
		(end 363.207046 -95.185738)
		(stroke
			(width 0.05715)
			(type default)
		)
		(layer "In2.Cu")
	)
	(gr_line
		(start 363.194854 -95.147638)
		(end 363.194854 -95.147892)
		(stroke
			(width 0.05715)
			(type default)
		)
		(layer "In2.Cu")
	)
	(gr_line
		(start 363.194854 -95.147638)
		(end 363.207046 -95.185738)
		(stroke
			(width 0.05715)
			(type default)
		)
		(layer "In2.Cu")
	)
	(gr_line
		(start 363.198664 -95.224854)
		(end 363.207046 -95.185738)
		(stroke
			(width 0.05715)
			(type default)
		)
		(layer "In2.Cu")
	)
	(gr_line
		(start 363.198664 -95.224346)
		(end 363.207046 -95.185738)
		(stroke
			(width 0.05715)
			(type default)
		)
		(layer "In2.Cu")
	)
	(gr_line
		(start 363.21111 -99.122484)
		(end 363.215936 -99.145598)
		(stroke
			(width 0.05715)
			(type default)
		)
		(layer "In2.Cu")
	)
	(gr_line
		(start 363.21111 -99.122484)
		(end 363.21619 -99.146106)
		(stroke
			(width 0.05715)
			(type default)
		)
		(layer "In2.Cu")
	)
	(gr_line
		(start 363.21111 -99.122484)
		(end 363.21619 -99.098608)
		(stroke
			(width 0.05715)
			(type default)
		)
		(layer "In2.Cu")
	)
	(gr_line
		(start 363.21111 -99.122484)
		(end 363.21619 -99.098354)
		(stroke
			(width 0.05715)
			(type default)
		)
		(layer "In2.Cu")
	)
	(gr_line
		(start 363.211872 -35.667696)
		(end 363.22254 -35.65144)
		(stroke
			(width 0.05715)
			(type default)
		)
		(layer "In2.Cu")
	)
	(gr_line
		(start 363.22254 -35.65144)
		(end 363.226604 -35.63239)
		(stroke
			(width 0.05715)
			(type default)
		)
		(layer "In2.Cu")
	)
	(gr_line
		(start 363.263688 -122.101102)
		(end 363.322616 -122.16003)
		(stroke
			(width 0.05715)
			(type default)
		)
		(layer "In2.Cu")
	)
	(gr_line
		(start 363.290358 -96.469962)
		(end 363.295438 -96.493838)
		(stroke
			(width 0.05715)
			(type default)
		)
		(layer "In2.Cu")
	)
	(gr_line
		(start 363.290358 -96.469962)
		(end 363.295438 -96.493076)
		(stroke
			(width 0.05715)
			(type default)
		)
		(layer "In2.Cu")
	)
	(gr_line
		(start 363.290358 -96.469962)
		(end 363.295438 -96.446848)
		(stroke
			(width 0.05715)
			(type default)
		)
		(layer "In2.Cu")
	)
	(gr_line
		(start 363.290358 -96.469962)
		(end 363.295438 -96.446594)
		(stroke
			(width 0.05715)
			(type default)
		)
		(layer "In2.Cu")
	)
	(gr_line
		(start 363.411008 -37.216588)
		(end 363.414818 -37.197538)
		(stroke
			(width 0.05715)
			(type default)
		)
		(layer "In2.Cu")
	)
	(gr_line
		(start 363.414818 -37.197538)
		(end 363.425486 -37.181282)
		(stroke
			(width 0.05715)
			(type default)
		)
		(layer "In2.Cu")
	)
	(gr_line
		(start 363.420152 -52.253896)
		(end 363.42955 -52.20716)
		(stroke
			(width 0.05715)
			(type default)
		)
		(layer "In2.Cu")
	)
	(gr_line
		(start 363.420152 -52.253896)
		(end 363.42955 -52.206906)
		(stroke
			(width 0.05715)
			(type default)
		)
		(layer "In2.Cu")
	)
	(gr_line
		(start 363.420152 -52.253896)
		(end 363.43717 -52.2986)
		(stroke
			(width 0.05715)
			(type default)
		)
		(layer "In2.Cu")
	)
	(gr_line
		(start 363.420152 -52.253896)
		(end 363.437424 -52.2986)
		(stroke
			(width 0.05715)
			(type default)
		)
		(layer "In2.Cu")
	)
	(gr_line
		(start 363.43717 -52.2986)
		(end 363.437678 -52.299616)
		(stroke
			(width 0.05715)
			(type default)
		)
		(layer "In2.Cu")
	)
	(gr_line
		(start 363.450632 -109.411008)
		(end 363.46638 -109.485176)
		(stroke
			(width 0.05715)
			(type default)
		)
		(layer "In2.Cu")
	)
	(gr_line
		(start 363.46638 -109.485176)
		(end 363.527594 -109.529372)
		(stroke
			(width 0.05715)
			(type default)
		)
		(layer "In2.Cu")
	)
	(gr_line
		(start 363.486446 -16.61668)
		(end 363.502448 -16.54175)
		(stroke
			(width 0.05715)
			(type default)
		)
		(layer "In2.Cu")
	)
	(gr_line
		(start 363.502448 -16.54175)
		(end 363.564678 -16.4973)
		(stroke
			(width 0.05715)
			(type default)
		)
		(layer "In2.Cu")
	)
	(gr_line
		(start 363.744002 -54.290468)
		(end 363.773212 -54.218332)
		(stroke
			(width 0.05715)
			(type default)
		)
		(layer "In2.Cu")
	)
	(gr_line
		(start 363.744002 -54.28996)
		(end 363.773212 -54.218332)
		(stroke
			(width 0.05715)
			(type default)
		)
		(layer "In2.Cu")
	)
	(gr_line
		(start 363.745272 -54.145688)
		(end 363.773212 -54.218332)
		(stroke
			(width 0.05715)
			(type default)
		)
		(layer "In2.Cu")
	)
	(gr_line
		(start 363.745272 -54.145434)
		(end 363.773212 -54.218332)
		(stroke
			(width 0.05715)
			(type default)
		)
		(layer "In2.Cu")
	)
	(gr_line
		(start 363.76102 -92.143834)
		(end 363.814868 -92.179902)
		(stroke
			(width 0.05715)
			(type default)
		)
		(layer "In2.Cu")
	)
	(gr_line
		(start 363.802676 -46.055534)
		(end 363.809788 -46.020228)
		(stroke
			(width 0.05715)
			(type default)
		)
		(layer "In2.Cu")
	)
	(gr_line
		(start 363.802676 -46.055534)
		(end 363.809788 -46.019974)
		(stroke
			(width 0.05715)
			(type default)
		)
		(layer "In2.Cu")
	)
	(gr_line
		(start 363.802676 -46.055534)
		(end 363.81309 -46.090078)
		(stroke
			(width 0.05715)
			(type default)
		)
		(layer "In2.Cu")
	)
	(gr_line
		(start 363.802676 -46.055534)
		(end 363.813344 -46.091094)
		(stroke
			(width 0.05715)
			(type default)
		)
		(layer "In2.Cu")
	)
	(gr_line
		(start 363.806232 -35.941)
		(end 363.815884 -35.926268)
		(stroke
			(width 0.05715)
			(type default)
		)
		(layer "In2.Cu")
	)
	(gr_line
		(start 363.814868 -92.179902)
		(end 363.834426 -92.240862)
		(stroke
			(width 0.05715)
			(type default)
		)
		(layer "In2.Cu")
	)
	(gr_line
		(start 363.815884 -35.926268)
		(end 363.81944 -35.909504)
		(stroke
			(width 0.05715)
			(type default)
		)
		(layer "In2.Cu")
	)
	(gr_line
		(start 363.825282 -97.633536)
		(end 363.830362 -97.60966)
		(stroke
			(width 0.05715)
			(type default)
		)
		(layer "In2.Cu")
	)
	(gr_line
		(start 363.825282 -97.632774)
		(end 363.830362 -97.60966)
		(stroke
			(width 0.05715)
			(type default)
		)
		(layer "In2.Cu")
	)
	(gr_line
		(start 363.825282 -97.586546)
		(end 363.830362 -97.60966)
		(stroke
			(width 0.05715)
			(type default)
		)
		(layer "In2.Cu")
	)
	(gr_line
		(start 363.825282 -97.585784)
		(end 363.830362 -97.60966)
		(stroke
			(width 0.05715)
			(type default)
		)
		(layer "In2.Cu")
	)
	(gr_line
		(start 363.866684 -95.064834)
		(end 363.87913 -95.102934)
		(stroke
			(width 0.05715)
			(type default)
		)
		(layer "In2.Cu")
	)
	(gr_line
		(start 363.866938 -95.065596)
		(end 363.87913 -95.102934)
		(stroke
			(width 0.05715)
			(type default)
		)
		(layer "In2.Cu")
	)
	(gr_line
		(start 363.87024 -142.53464)
		(end 364.151164 -142.815564)
		(stroke
			(width 0.0635)
			(type default)
		)
		(layer "In2.Cu")
	)
	(gr_line
		(start 363.870748 -95.14205)
		(end 363.87913 -95.102934)
		(stroke
			(width 0.05715)
			(type default)
		)
		(layer "In2.Cu")
	)
	(gr_line
		(start 363.871002 -95.141288)
		(end 363.87913 -95.102934)
		(stroke
			(width 0.05715)
			(type default)
		)
		(layer "In2.Cu")
	)
	(gr_line
		(start 364.002828 -108.953554)
		(end 364.018322 -109.025944)
		(stroke
			(width 0.05715)
			(type default)
		)
		(layer "In2.Cu")
	)
	(gr_line
		(start 364.018322 -109.025944)
		(end 364.078266 -109.069378)
		(stroke
			(width 0.05715)
			(type default)
		)
		(layer "In2.Cu")
	)
	(gr_line
		(start 364.037626 -37.450014)
		(end 364.041436 -37.430964)
		(stroke
			(width 0.05715)
			(type default)
		)
		(layer "In2.Cu")
	)
	(gr_line
		(start 364.041436 -37.430964)
		(end 364.052104 -37.414708)
		(stroke
			(width 0.05715)
			(type default)
		)
		(layer "In2.Cu")
	)
	(gr_line
		(start 364.057946 -16.99133)
		(end 364.073948 -16.9164)
		(stroke
			(width 0.05715)
			(type default)
		)
		(layer "In2.Cu")
	)
	(gr_line
		(start 364.073948 -16.9164)
		(end 364.136178 -16.87195)
		(stroke
			(width 0.05715)
			(type default)
		)
		(layer "In2.Cu")
	)
	(gr_line
		(start 364.108238 -99.336352)
		(end 364.113064 -99.359212)
		(stroke
			(width 0.05715)
			(type default)
		)
		(layer "In2.Cu")
	)
	(gr_line
		(start 364.108238 -99.336352)
		(end 364.113318 -99.312984)
		(stroke
			(width 0.05715)
			(type default)
		)
		(layer "In2.Cu")
	)
	(gr_line
		(start 364.151164 -96.393508)
		(end 364.156244 -96.416622)
		(stroke
			(width 0.05715)
			(type default)
		)
		(layer "In2.Cu")
	)
	(gr_line
		(start 364.151164 -96.393508)
		(end 364.156244 -96.37014)
		(stroke
			(width 0.05715)
			(type default)
		)
		(layer "In2.Cu")
	)
	(gr_line
		(start 364.358682 -51.69027)
		(end 364.362492 -51.70932)
		(stroke
			(width 0.05715)
			(type default)
		)
		(layer "In2.Cu")
	)
	(gr_line
		(start 364.358682 -51.69027)
		(end 364.362746 -51.670458)
		(stroke
			(width 0.05715)
			(type default)
		)
		(layer "In2.Cu")
	)
	(gr_line
		(start 364.404656 -36.239958)
		(end 364.414308 -36.225226)
		(stroke
			(width 0.05715)
			(type default)
		)
		(layer "In2.Cu")
	)
	(gr_line
		(start 364.414308 -36.225226)
		(end 364.417864 -36.208462)
		(stroke
			(width 0.05715)
			(type default)
		)
		(layer "In2.Cu")
	)
	(gr_line
		(start 364.445042 -51.258724)
		(end 364.562136 -50.673762)
		(stroke
			(width 0.05715)
			(type default)
		)
		(layer "In2.Cu")
	)
	(gr_line
		(start 364.461044 -113.73612)
		(end 364.473998 -113.688876)
		(stroke
			(width 0.05715)
			(type default)
		)
		(layer "In2.Cu")
	)
	(gr_line
		(start 364.461044 -113.73612)
		(end 364.474252 -113.687606)
		(stroke
			(width 0.05715)
			(type default)
		)
		(layer "In2.Cu")
	)
	(gr_line
		(start 364.461044 -113.73612)
		(end 364.47603 -113.783618)
		(stroke
			(width 0.05715)
			(type default)
		)
		(layer "In2.Cu")
	)
	(gr_line
		(start 364.461044 -113.73612)
		(end 364.476284 -113.783618)
		(stroke
			(width 0.05715)
			(type default)
		)
		(layer "In2.Cu")
	)
	(gr_line
		(start 364.47603 -113.783618)
		(end 364.476284 -113.784634)
		(stroke
			(width 0.05715)
			(type default)
		)
		(layer "In2.Cu")
	)
	(gr_line
		(start 364.503462 -54.408324)
		(end 364.532926 -54.33568)
		(stroke
			(width 0.05715)
			(type default)
		)
		(layer "In2.Cu")
	)
	(gr_line
		(start 364.503716 -54.407816)
		(end 364.503716 -54.40807)
		(stroke
			(width 0.05715)
			(type default)
		)
		(layer "In2.Cu")
	)
	(gr_line
		(start 364.503716 -54.407816)
		(end 364.532926 -54.33568)
		(stroke
			(width 0.05715)
			(type default)
		)
		(layer "In2.Cu")
	)
	(gr_line
		(start 364.504478 -54.261512)
		(end 364.504986 -54.262528)
		(stroke
			(width 0.05715)
			(type default)
		)
		(layer "In2.Cu")
	)
	(gr_line
		(start 364.504732 -54.262528)
		(end 364.532926 -54.33568)
		(stroke
			(width 0.05715)
			(type default)
		)
		(layer "In2.Cu")
	)
	(gr_line
		(start 364.504986 -54.262782)
		(end 364.532926 -54.33568)
		(stroke
			(width 0.05715)
			(type default)
		)
		(layer "In2.Cu")
	)
	(gr_line
		(start 364.50778 -110.668308)
		(end 364.555278 -110.702852)
		(stroke
			(width 0.05715)
			(type default)
		)
		(layer "In2.Cu")
	)
	(gr_line
		(start 364.513876 -142.815564)
		(end 364.78464 -142.5448)
		(stroke
			(width 0.0635)
			(type default)
		)
		(layer "In2.Cu")
	)
	(gr_line
		(start 364.555278 -110.702852)
		(end 364.572804 -110.758478)
		(stroke
			(width 0.05715)
			(type default)
		)
		(layer "In2.Cu")
	)
	(gr_line
		(start 364.609888 -42.002202)
		(end 364.613952 -41.982136)
		(stroke
			(width 0.05715)
			(type default)
		)
		(layer "In2.Cu")
	)
	(gr_line
		(start 364.611412 -47.700946)
		(end 364.62208 -47.736506)
		(stroke
			(width 0.05715)
			(type default)
		)
		(layer "In2.Cu")
	)
	(gr_line
		(start 364.611666 -47.701962)
		(end 364.62208 -47.736506)
		(stroke
			(width 0.05715)
			(type default)
		)
		(layer "In2.Cu")
	)
	(gr_line
		(start 364.613952 -41.982136)
		(end 364.625128 -41.965118)
		(stroke
			(width 0.05715)
			(type default)
		)
		(layer "In2.Cu")
	)
	(gr_line
		(start 364.614968 -47.771812)
		(end 364.62208 -47.736506)
		(stroke
			(width 0.05715)
			(type default)
		)
		(layer "In2.Cu")
	)
	(gr_line
		(start 364.614968 -47.771304)
		(end 364.62208 -47.736506)
		(stroke
			(width 0.05715)
			(type default)
		)
		(layer "In2.Cu")
	)
	(gr_line
		(start 364.62843 -17.366996)
		(end 364.644432 -17.292066)
		(stroke
			(width 0.05715)
			(type default)
		)
		(layer "In2.Cu")
	)
	(gr_line
		(start 364.644432 -17.292066)
		(end 364.706662 -17.247616)
		(stroke
			(width 0.05715)
			(type default)
		)
		(layer "In2.Cu")
	)
	(gr_line
		(start 364.644432 -17.292066)
		(end 364.706662 -17.247362)
		(stroke
			(width 0.05715)
			(type default)
		)
		(layer "In2.Cu")
	)
	(gr_line
		(start 364.66018 -46.031912)
		(end 364.667546 -45.995336)
		(stroke
			(width 0.05715)
			(type default)
		)
		(layer "In2.Cu")
	)
	(gr_line
		(start 364.66018 -46.031912)
		(end 364.671356 -46.067472)
		(stroke
			(width 0.05715)
			(type default)
		)
		(layer "In2.Cu")
	)
	(gr_line
		(start 364.689136 -53.344826)
		(end 364.692946 -53.364384)
		(stroke
			(width 0.05715)
			(type default)
		)
		(layer "In2.Cu")
	)
	(gr_line
		(start 364.692946 -53.364384)
		(end 364.705138 -53.382926)
		(stroke
			(width 0.05715)
			(type default)
		)
		(layer "In2.Cu")
	)
	(gr_line
		(start 364.714282 -37.602922)
		(end 364.718092 -37.583872)
		(stroke
			(width 0.05715)
			(type default)
		)
		(layer "In2.Cu")
	)
	(gr_line
		(start 364.718092 -37.583618)
		(end 364.718092 -37.583872)
		(stroke
			(width 0.05715)
			(type default)
		)
		(layer "In2.Cu")
	)
	(gr_line
		(start 364.718092 -37.583618)
		(end 364.729268 -37.5666)
		(stroke
			(width 0.05715)
			(type default)
		)
		(layer "In2.Cu")
	)
	(gr_line
		(start 364.725712 -94.999556)
		(end 364.737904 -95.037656)
		(stroke
			(width 0.05715)
			(type default)
		)
		(layer "In2.Cu")
	)
	(gr_line
		(start 364.726728 -51.351942)
		(end 364.918244 -51.224434)
		(stroke
			(width 0.05715)
			(type default)
		)
		(layer "In2.Cu")
	)
	(gr_line
		(start 364.729522 -95.076264)
		(end 364.737904 -95.037656)
		(stroke
			(width 0.05715)
			(type default)
		)
		(layer "In2.Cu")
	)
	(gr_line
		(start 364.735618 -97.786444)
		(end 364.740698 -97.76333)
		(stroke
			(width 0.05715)
			(type default)
		)
		(layer "In2.Cu")
	)
	(gr_line
		(start 364.735618 -97.739962)
		(end 364.740698 -97.76333)
		(stroke
			(width 0.05715)
			(type default)
		)
		(layer "In2.Cu")
	)
	(gr_line
		(start 364.79988 -122.22988)
		(end 364.8964 -122.3264)
		(stroke
			(width 0.05715)
			(type default)
		)
		(layer "In2.Cu")
	)
	(gr_line
		(start 364.79988 -121.813066)
		(end 364.844584 -121.768362)
		(stroke
			(width 0.05715)
			(type default)
		)
		(layer "In2.Cu")
	)
	(gr_line
		(start 364.816644 -125.131322)
		(end 364.881414 -125.196092)
		(stroke
			(width 0.05715)
			(type default)
		)
		(layer "In2.Cu")
	)
	(gr_line
		(start 364.816644 -124.714762)
		(end 364.856014 -124.675392)
		(stroke
			(width 0.05715)
			(type default)
		)
		(layer "In2.Cu")
	)
	(gr_line
		(start 364.844584 -121.333514)
		(end 364.844584 -121.768362)
		(stroke
			(width 0.05715)
			(type default)
		)
		(layer "In2.Cu")
	)
	(gr_line
		(start 364.856014 -124.288042)
		(end 364.856014 -124.675392)
		(stroke
			(width 0.05715)
			(type default)
		)
		(layer "In2.Cu")
	)
	(gr_line
		(start 364.857792 -50.696876)
		(end 364.985554 -50.888392)
		(stroke
			(width 0.05715)
			(type default)
		)
		(layer "In2.Cu")
	)
	(gr_line
		(start 364.877096 -115.040918)
		(end 364.896908 -115.103656)
		(stroke
			(width 0.05715)
			(type default)
		)
		(layer "In2.Cu")
	)
	(gr_line
		(start 364.881414 -125.196092)
		(end 364.881414 -125.583442)
		(stroke
			(width 0.05715)
			(type default)
		)
		(layer "In2.Cu")
	)
	(gr_line
		(start 364.8964 -122.3264)
		(end 364.8964 -122.6566)
		(stroke
			(width 0.05715)
			(type default)
		)
		(layer "In2.Cu")
	)
	(gr_line
		(start 364.896908 -115.103656)
		(end 364.952026 -115.139978)
		(stroke
			(width 0.05715)
			(type default)
		)
		(layer "In2.Cu")
	)
	(gr_line
		(start 364.918244 -51.224434)
		(end 364.985554 -50.888392)
		(stroke
			(width 0.05715)
			(type default)
		)
		(layer "In2.Cu")
	)
	(gr_line
		(start 364.994952 -44.360084)
		(end 364.998762 -44.341034)
		(stroke
			(width 0.05715)
			(type default)
		)
		(layer "In2.Cu")
	)
	(gr_line
		(start 364.998762 -44.341034)
		(end 365.00943 -44.324778)
		(stroke
			(width 0.05715)
			(type default)
		)
		(layer "In2.Cu")
	)
	(gr_line
		(start 365.010192 -36.504626)
		(end 365.020352 -36.489132)
		(stroke
			(width 0.05715)
			(type default)
		)
		(layer "In2.Cu")
	)
	(gr_line
		(start 365.020352 -36.489132)
		(end 365.024162 -36.471352)
		(stroke
			(width 0.05715)
			(type default)
		)
		(layer "In2.Cu")
	)
	(gr_line
		(start 365.08817 -110.301278)
		(end 365.135668 -110.335822)
		(stroke
			(width 0.05715)
			(type default)
		)
		(layer "In2.Cu")
	)
	(gr_line
		(start 365.098584 -112.409732)
		(end 365.113316 -112.45596)
		(stroke
			(width 0.05715)
			(type default)
		)
		(layer "In2.Cu")
	)
	(gr_line
		(start 365.098838 -112.41024)
		(end 365.113316 -112.45596)
		(stroke
			(width 0.05715)
			(type default)
		)
		(layer "In2.Cu")
	)
	(gr_line
		(start 365.100616 -112.502188)
		(end 365.113316 -112.45596)
		(stroke
			(width 0.05715)
			(type default)
		)
		(layer "In2.Cu")
	)
	(gr_line
		(start 365.10087 -112.50168)
		(end 365.113316 -112.45596)
		(stroke
			(width 0.05715)
			(type default)
		)
		(layer "In2.Cu")
	)
	(gr_line
		(start 365.134398 -113.6904)
		(end 365.146844 -113.64468)
		(stroke
			(width 0.05715)
			(type default)
		)
		(layer "In2.Cu")
	)
	(gr_line
		(start 365.134398 -113.6904)
		(end 365.147098 -113.643918)
		(stroke
			(width 0.05715)
			(type default)
		)
		(layer "In2.Cu")
	)
	(gr_line
		(start 365.134398 -113.6904)
		(end 365.148876 -113.735866)
		(stroke
			(width 0.05715)
			(type default)
		)
		(layer "In2.Cu")
	)
	(gr_line
		(start 365.134398 -113.6904)
		(end 365.148876 -113.735612)
		(stroke
			(width 0.05715)
			(type default)
		)
		(layer "In2.Cu")
	)
	(gr_line
		(start 365.135668 -110.335822)
		(end 365.153448 -110.391702)
		(stroke
			(width 0.05715)
			(type default)
		)
		(layer "In2.Cu")
	)
	(gr_line
		(start 365.148876 -113.735866)
		(end 365.148876 -113.73612)
		(stroke
			(width 0.05715)
			(type default)
		)
		(layer "In2.Cu")
	)
	(gr_line
		(start 365.179864 -53.567838)
		(end 365.190786 -53.584348)
		(stroke
			(width 0.05715)
			(type default)
		)
		(layer "In2.Cu")
	)
	(gr_line
		(start 365.190786 -53.584348)
		(end 365.19485 -53.604414)
		(stroke
			(width 0.05715)
			(type default)
		)
		(layer "In2.Cu")
	)
	(gr_line
		(start 365.21517 -111.551212)
		(end 365.39678 -112.122712)
		(stroke
			(width 0.05715)
			(type default)
		)
		(layer "In2.Cu")
	)
	(gr_line
		(start 365.215932 -111.552482)
		(end 365.396526 -112.121188)
		(stroke
			(width 0.05715)
			(type default)
		)
		(layer "In2.Cu")
	)
	(gr_line
		(start 365.318548 -116.984272)
		(end 365.88319 -117.183916)
		(stroke
			(width 0.05715)
			(type default)
		)
		(layer "In2.Cu")
	)
	(gr_line
		(start 365.319056 -116.984526)
		(end 365.883444 -117.183916)
		(stroke
			(width 0.05715)
			(type default)
		)
		(layer "In2.Cu")
	)
	(gr_line
		(start 365.341662 -17.934432)
		(end 365.357664 -17.859502)
		(stroke
			(width 0.05715)
			(type default)
		)
		(layer "In2.Cu")
	)
	(gr_line
		(start 365.357664 -17.859502)
		(end 365.419894 -17.815052)
		(stroke
			(width 0.05715)
			(type default)
		)
		(layer "In2.Cu")
	)
	(gr_line
		(start 365.384334 -116.694966)
		(end 365.591852 -116.595652)
		(stroke
			(width 0.05715)
			(type default)
		)
		(layer "In2.Cu")
	)
	(gr_line
		(start 365.407448 -114.546634)
		(end 365.427514 -114.610134)
		(stroke
			(width 0.05715)
			(type default)
		)
		(layer "In2.Cu")
	)
	(gr_line
		(start 365.427514 -114.610134)
		(end 365.483648 -114.647218)
		(stroke
			(width 0.05715)
			(type default)
		)
		(layer "In2.Cu")
	)
	(gr_line
		(start 365.427514 -114.610134)
		(end 365.483902 -114.647218)
		(stroke
			(width 0.05715)
			(type default)
		)
		(layer "In2.Cu")
	)
	(gr_line
		(start 365.458248 -47.59198)
		(end 365.469424 -47.627286)
		(stroke
			(width 0.05715)
			(type default)
		)
		(layer "In2.Cu")
	)
	(gr_line
		(start 365.458248 -47.591472)
		(end 365.458248 -47.591726)
		(stroke
			(width 0.05715)
			(type default)
		)
		(layer "In2.Cu")
	)
	(gr_line
		(start 365.462058 -47.663354)
		(end 365.469424 -47.627286)
		(stroke
			(width 0.05715)
			(type default)
		)
		(layer "In2.Cu")
	)
	(gr_line
		(start 365.48568 -111.429546)
		(end 365.69015 -111.53521)
		(stroke
			(width 0.05715)
			(type default)
		)
		(layer "In2.Cu")
	)
	(gr_line
		(start 365.51362 -104.60863)
		(end 365.671354 -104.766364)
		(stroke
			(width 0.05715)
			(type default)
		)
		(layer "In2.Cu")
	)
	(gr_line
		(start 365.51362 -104.19207)
		(end 365.712502 -103.993188)
		(stroke
			(width 0.05715)
			(type default)
		)
		(layer "In2.Cu")
	)
	(gr_line
		(start 365.536226 -55.618126)
		(end 365.581692 -55.5498)
		(stroke
			(width 0.05715)
			(type default)
		)
		(layer "In2.Cu")
	)
	(gr_line
		(start 365.565436 -55.46852)
		(end 365.581692 -55.5498)
		(stroke
			(width 0.05715)
			(type default)
		)
		(layer "In2.Cu")
	)
	(gr_line
		(start 365.591852 -116.595652)
		(end 365.915194 -116.709952)
		(stroke
			(width 0.05715)
			(type default)
		)
		(layer "In2.Cu")
	)
	(gr_line
		(start 365.618268 -36.760404)
		(end 365.62792 -36.745672)
		(stroke
			(width 0.05715)
			(type default)
		)
		(layer "In2.Cu")
	)
	(gr_line
		(start 365.62792 -36.745672)
		(end 365.631476 -36.728908)
		(stroke
			(width 0.05715)
			(type default)
		)
		(layer "In2.Cu")
	)
	(gr_line
		(start 365.688118 -112.066324)
		(end 365.794036 -111.862108)
		(stroke
			(width 0.05715)
			(type default)
		)
		(layer "In2.Cu")
	)
	(gr_line
		(start 365.69015 -111.53521)
		(end 365.794036 -111.862108)
		(stroke
			(width 0.05715)
			(type default)
		)
		(layer "In2.Cu")
	)
	(gr_line
		(start 365.775748 -112.350042)
		(end 365.776002 -112.35055)
		(stroke
			(width 0.05715)
			(type default)
		)
		(layer "In2.Cu")
	)
	(gr_line
		(start 365.776002 -112.35055)
		(end 365.79048 -112.39627)
		(stroke
			(width 0.05715)
			(type default)
		)
		(layer "In2.Cu")
	)
	(gr_line
		(start 365.776002 -112.350296)
		(end 365.79048 -112.39627)
		(stroke
			(width 0.05715)
			(type default)
		)
		(layer "In2.Cu")
	)
	(gr_line
		(start 365.77778 -112.442752)
		(end 365.79048 -112.39627)
		(stroke
			(width 0.05715)
			(type default)
		)
		(layer "In2.Cu")
	)
	(gr_line
		(start 365.778034 -112.44199)
		(end 365.79048 -112.39627)
		(stroke
			(width 0.05715)
			(type default)
		)
		(layer "In2.Cu")
	)
	(gr_line
		(start 365.815118 -113.618264)
		(end 365.827564 -113.572544)
		(stroke
			(width 0.05715)
			(type default)
		)
		(layer "In2.Cu")
	)
	(gr_line
		(start 365.815118 -113.618264)
		(end 365.827818 -113.572036)
		(stroke
			(width 0.05715)
			(type default)
		)
		(layer "In2.Cu")
	)
	(gr_line
		(start 365.815118 -113.618264)
		(end 365.829596 -113.664238)
		(stroke
			(width 0.05715)
			(type default)
		)
		(layer "In2.Cu")
	)
	(gr_line
		(start 365.815118 -113.618264)
		(end 365.829596 -113.663984)
		(stroke
			(width 0.05715)
			(type default)
		)
		(layer "In2.Cu")
	)
	(gr_line
		(start 365.829596 -113.663984)
		(end 365.82985 -113.664492)
		(stroke
			(width 0.05715)
			(type default)
		)
		(layer "In2.Cu")
	)
	(gr_line
		(start 365.849408 -109.990636)
		(end 365.896906 -110.024926)
		(stroke
			(width 0.05715)
			(type default)
		)
		(layer "In2.Cu")
	)
	(gr_line
		(start 365.896906 -110.024926)
		(end 365.914686 -110.081314)
		(stroke
			(width 0.05715)
			(type default)
		)
		(layer "In2.Cu")
	)
	(gr_line
		(start 365.913924 -18.308828)
		(end 365.929926 -18.233898)
		(stroke
			(width 0.05715)
			(type default)
		)
		(layer "In2.Cu")
	)
	(gr_line
		(start 365.915194 -116.709952)
		(end 366.014508 -116.917724)
		(stroke
			(width 0.05715)
			(type default)
		)
		(layer "In2.Cu")
	)
	(gr_line
		(start 365.929926 -18.233898)
		(end 365.992156 -18.189448)
		(stroke
			(width 0.05715)
			(type default)
		)
		(layer "In2.Cu")
	)
	(gr_line
		(start 365.971582 -36.837874)
		(end 365.978186 -36.80714)
		(stroke
			(width 0.05715)
			(type default)
		)
		(layer "In2.Cu")
	)
	(gr_line
		(start 365.971582 -36.837874)
		(end 365.978186 -36.806632)
		(stroke
			(width 0.05715)
			(type default)
		)
		(layer "In2.Cu")
	)
	(gr_line
		(start 365.971582 -36.837874)
		(end 365.979456 -36.868608)
		(stroke
			(width 0.05715)
			(type default)
		)
		(layer "In2.Cu")
	)
	(gr_line
		(start 365.971582 -36.837874)
		(end 365.979456 -36.868354)
		(stroke
			(width 0.05715)
			(type default)
		)
		(layer "In2.Cu")
	)
	(gr_line
		(start 365.97209 -114.112294)
		(end 365.992156 -114.175286)
		(stroke
			(width 0.05715)
			(type default)
		)
		(layer "In2.Cu")
	)
	(gr_line
		(start 365.972598 -114.11331)
		(end 365.992156 -114.175286)
		(stroke
			(width 0.05715)
			(type default)
		)
		(layer "In2.Cu")
	)
	(gr_line
		(start 365.979456 -36.868608)
		(end 365.97971 -36.869624)
		(stroke
			(width 0.05715)
			(type default)
		)
		(layer "In2.Cu")
	)
	(gr_line
		(start 365.992156 -114.175286)
		(end 366.047274 -114.211608)
		(stroke
			(width 0.05715)
			(type default)
		)
		(layer "In2.Cu")
	)
	(gr_line
		(start 366.058704 -40.340026)
		(end 366.070896 -40.321992)
		(stroke
			(width 0.05715)
			(type default)
		)
		(layer "In2.Cu")
	)
	(gr_line
		(start 366.070896 -40.321992)
		(end 366.07496 -40.300148)
		(stroke
			(width 0.05715)
			(type default)
		)
		(layer "In2.Cu")
	)
	(gr_line
		(start 366.276128 -117.3226)
		(end 366.841278 -117.522244)
		(stroke
			(width 0.05715)
			(type default)
		)
		(layer "In2.Cu")
	)
	(gr_line
		(start 366.30356 -118.220744)
		(end 366.819434 -118.524782)
		(stroke
			(width 0.05715)
			(type default)
		)
		(layer "In2.Cu")
	)
	(gr_line
		(start 366.304322 -118.220998)
		(end 366.81918 -118.524528)
		(stroke
			(width 0.05715)
			(type default)
		)
		(layer "In2.Cu")
	)
	(gr_line
		(start 366.342168 -117.033548)
		(end 366.54994 -116.934234)
		(stroke
			(width 0.05715)
			(type default)
		)
		(layer "In2.Cu")
	)
	(gr_line
		(start 366.423702 -117.949472)
		(end 366.64646 -117.891814)
		(stroke
			(width 0.05715)
			(type default)
		)
		(layer "In2.Cu")
	)
	(gr_line
		(start 366.503458 -42.61104)
		(end 366.51565 -42.592498)
		(stroke
			(width 0.05715)
			(type default)
		)
		(layer "In2.Cu")
	)
	(gr_line
		(start 366.51565 -42.592498)
		(end 366.519714 -42.570654)
		(stroke
			(width 0.05715)
			(type default)
		)
		(layer "In2.Cu")
	)
	(gr_line
		(start 366.520222 -37.78504)
		(end 366.526826 -37.809932)
		(stroke
			(width 0.05715)
			(type default)
		)
		(layer "In2.Cu")
	)
	(gr_line
		(start 366.520222 -37.784532)
		(end 366.526826 -37.809932)
		(stroke
			(width 0.05715)
			(type default)
		)
		(layer "In2.Cu")
	)
	(gr_line
		(start 366.522 -37.836602)
		(end 366.526826 -37.809932)
		(stroke
			(width 0.05715)
			(type default)
		)
		(layer "In2.Cu")
	)
	(gr_line
		(start 366.522254 -37.83584)
		(end 366.526826 -37.809932)
		(stroke
			(width 0.05715)
			(type default)
		)
		(layer "In2.Cu")
	)
	(gr_line
		(start 366.528604 -112.011714)
		(end 366.528858 -112.012222)
		(stroke
			(width 0.05715)
			(type default)
		)
		(layer "In2.Cu")
	)
	(gr_line
		(start 366.528604 -112.011714)
		(end 366.543336 -112.057942)
		(stroke
			(width 0.05715)
			(type default)
		)
		(layer "In2.Cu")
	)
	(gr_line
		(start 366.528858 -112.012222)
		(end 366.543336 -112.057942)
		(stroke
			(width 0.05715)
			(type default)
		)
		(layer "In2.Cu")
	)
	(gr_line
		(start 366.530636 -112.10417)
		(end 366.543336 -112.057942)
		(stroke
			(width 0.05715)
			(type default)
		)
		(layer "In2.Cu")
	)
	(gr_line
		(start 366.53089 -112.103662)
		(end 366.543336 -112.057942)
		(stroke
			(width 0.05715)
			(type default)
		)
		(layer "In2.Cu")
	)
	(gr_line
		(start 366.53724 -18.646394)
		(end 366.553242 -18.571464)
		(stroke
			(width 0.05715)
			(type default)
		)
		(layer "In2.Cu")
	)
	(gr_line
		(start 366.54994 -116.934234)
		(end 366.873282 -117.048534)
		(stroke
			(width 0.05715)
			(type default)
		)
		(layer "In2.Cu")
	)
	(gr_line
		(start 366.553242 -18.571464)
		(end 366.615472 -18.52676)
		(stroke
			(width 0.05715)
			(type default)
		)
		(layer "In2.Cu")
	)
	(gr_line
		(start 366.556036 -115.352322)
		(end 366.597438 -115.3795)
		(stroke
			(width 0.05715)
			(type default)
		)
		(layer "In2.Cu")
	)
	(gr_line
		(start 366.58677 -116.215668)
		(end 366.62741 -116.242592)
		(stroke
			(width 0.05715)
			(type default)
		)
		(layer "In2.Cu")
	)
	(gr_line
		(start 366.64646 -117.891814)
		(end 366.941862 -118.066058)
		(stroke
			(width 0.05715)
			(type default)
		)
		(layer "In2.Cu")
	)
	(gr_line
		(start 366.738662 -114.666522)
		(end 366.780064 -114.6937)
		(stroke
			(width 0.05715)
			(type default)
		)
		(layer "In2.Cu")
	)
	(gr_line
		(start 366.739424 -114.666776)
		(end 366.780064 -114.6937)
		(stroke
			(width 0.05715)
			(type default)
		)
		(layer "In2.Cu")
	)
	(gr_line
		(start 366.793526 -36.819332)
		(end 366.80013 -36.78809)
		(stroke
			(width 0.05715)
			(type default)
		)
		(layer "In2.Cu")
	)
	(gr_line
		(start 366.793526 -36.819332)
		(end 366.8014 -36.849812)
		(stroke
			(width 0.05715)
			(type default)
		)
		(layer "In2.Cu")
	)
	(gr_line
		(start 366.873282 -117.048534)
		(end 366.972342 -117.256052)
		(stroke
			(width 0.05715)
			(type default)
		)
		(layer "In2.Cu")
	)
	(gr_line
		(start 366.941862 -118.066058)
		(end 366.99952 -118.288816)
		(stroke
			(width 0.05715)
			(type default)
		)
		(layer "In2.Cu")
	)
	(gr_line
		(start 366.94237 -22.933406)
		(end 366.945926 -22.916642)
		(stroke
			(width 0.05715)
			(type default)
		)
		(layer "In2.Cu")
	)
	(gr_line
		(start 366.945926 -22.916642)
		(end 366.955578 -22.90191)
		(stroke
			(width 0.05715)
			(type default)
		)
		(layer "In2.Cu")
	)
	(gr_line
		(start 366.955578 -11.829542)
		(end 366.959134 -11.827002)
		(stroke
			(width 0.05715)
			(type default)
		)
		(layer "In2.Cu")
	)
	(gr_line
		(start 366.959134 -11.827002)
		(end 366.963198 -11.825732)
		(stroke
			(width 0.05715)
			(type default)
		)
		(layer "In2.Cu")
	)
	(gr_line
		(start 366.980724 -9.81837)
		(end 366.993678 -9.808972)
		(stroke
			(width 0.05715)
			(type default)
		)
		(layer "In2.Cu")
	)
	(gr_line
		(start 366.993678 -9.808972)
		(end 367.002314 -9.796018)
		(stroke
			(width 0.05715)
			(type default)
		)
		(layer "In2.Cu")
	)
	(gr_line
		(start 367.113312 -19.016472)
		(end 367.128806 -18.943574)
		(stroke
			(width 0.05715)
			(type default)
		)
		(layer "In2.Cu")
	)
	(gr_line
		(start 367.128806 -18.943574)
		(end 367.19002 -18.899632)
		(stroke
			(width 0.05715)
			(type default)
		)
		(layer "In2.Cu")
	)
	(gr_line
		(start 367.178844 -118.736618)
		(end 367.705894 -119.04726)
		(stroke
			(width 0.05715)
			(type default)
		)
		(layer "In2.Cu")
	)
	(gr_line
		(start 367.179606 -118.736872)
		(end 367.70564 -119.047006)
		(stroke
			(width 0.05715)
			(type default)
		)
		(layer "In2.Cu")
	)
	(gr_line
		(start 367.23574 -117.66169)
		(end 367.246916 -117.6655)
		(stroke
			(width 0.05715)
			(type default)
		)
		(layer "In2.Cu")
	)
	(gr_line
		(start 367.253012 -10.04824)
		(end 367.2586 -10.04443)
		(stroke
			(width 0.05715)
			(type default)
		)
		(layer "In2.Cu")
	)
	(gr_line
		(start 367.2586 -10.04443)
		(end 367.264442 -10.042652)
		(stroke
			(width 0.05715)
			(type default)
		)
		(layer "In2.Cu")
	)
	(gr_line
		(start 367.26368 -24.535638)
		(end 367.26749 -24.517858)
		(stroke
			(width 0.05715)
			(type default)
		)
		(layer "In2.Cu")
	)
	(gr_line
		(start 367.26749 -24.517858)
		(end 367.278158 -24.501602)
		(stroke
			(width 0.05715)
			(type default)
		)
		(layer "In2.Cu")
	)
	(gr_line
		(start 367.298986 -118.465346)
		(end 367.521744 -118.407688)
		(stroke
			(width 0.05715)
			(type default)
		)
		(layer "In2.Cu")
	)
	(gr_line
		(start 367.300764 -10.798048)
		(end 367.306352 -10.794238)
		(stroke
			(width 0.05715)
			(type default)
		)
		(layer "In2.Cu")
	)
	(gr_line
		(start 367.306352 -10.794238)
		(end 367.312194 -10.79246)
		(stroke
			(width 0.05715)
			(type default)
		)
		(layer "In2.Cu")
	)
	(gr_line
		(start 367.316004 -8.797544)
		(end 367.328196 -8.77951)
		(stroke
			(width 0.05715)
			(type default)
		)
		(layer "In2.Cu")
	)
	(gr_line
		(start 367.328196 -8.77951)
		(end 367.34623 -8.767318)
		(stroke
			(width 0.05715)
			(type default)
		)
		(layer "In2.Cu")
	)
	(gr_line
		(start 367.363502 -114.6937)
		(end 367.3856 -114.6937)
		(stroke
			(width 0.04445)
			(type default)
		)
		(layer "In2.Cu")
	)
	(gr_line
		(start 367.363502 -114.4016)
		(end 367.3856 -114.4016)
		(stroke
			(width 0.04445)
			(type default)
		)
		(layer "In2.Cu")
	)
	(gr_line
		(start 367.364772 -37.850318)
		(end 367.371884 -37.878004)
		(stroke
			(width 0.05715)
			(type default)
		)
		(layer "In2.Cu")
	)
	(gr_line
		(start 367.366804 -37.905182)
		(end 367.371884 -37.878004)
		(stroke
			(width 0.05715)
			(type default)
		)
		(layer "In2.Cu")
	)
	(gr_line
		(start 367.3856 -114.6937)
		(end 367.395252 -114.684048)
		(stroke
			(width 0.04445)
			(type default)
		)
		(layer "In2.Cu")
	)
	(gr_line
		(start 367.3856 -114.4016)
		(end 367.395252 -114.411252)
		(stroke
			(width 0.04445)
			(type default)
		)
		(layer "In2.Cu")
	)
	(gr_line
		(start 367.39703 -114.68227)
		(end 367.4364 -114.6429)
		(stroke
			(width 0.04445)
			(type default)
		)
		(layer "In2.Cu")
	)
	(gr_line
		(start 367.39703 -114.41303)
		(end 367.4364 -114.4524)
		(stroke
			(width 0.04445)
			(type default)
		)
		(layer "In2.Cu")
	)
	(gr_line
		(start 367.490502 -115.3795)
		(end 367.5126 -115.3795)
		(stroke
			(width 0.04445)
			(type default)
		)
		(layer "In2.Cu")
	)
	(gr_line
		(start 367.5126 -115.3795)
		(end 367.522252 -115.369848)
		(stroke
			(width 0.04445)
			(type default)
		)
		(layer "In2.Cu")
	)
	(gr_line
		(start 367.5126 -115.0874)
		(end 367.522252 -115.097052)
		(stroke
			(width 0.04445)
			(type default)
		)
		(layer "In2.Cu")
	)
	(gr_line
		(start 367.521744 -118.407688)
		(end 367.828322 -118.588282)
		(stroke
			(width 0.05715)
			(type default)
		)
		(layer "In2.Cu")
	)
	(gr_line
		(start 367.52403 -115.36807)
		(end 367.5634 -115.3287)
		(stroke
			(width 0.04445)
			(type default)
		)
		(layer "In2.Cu")
	)
	(gr_line
		(start 367.52403 -115.09883)
		(end 367.5634 -115.1382)
		(stroke
			(width 0.04445)
			(type default)
		)
		(layer "In2.Cu")
	)
	(gr_line
		(start 367.687352 -25.655524)
		(end 367.691416 -25.636474)
		(stroke
			(width 0.05715)
			(type default)
		)
		(layer "In2.Cu")
	)
	(gr_line
		(start 367.691416 -25.636474)
		(end 367.702338 -25.620472)
		(stroke
			(width 0.05715)
			(type default)
		)
		(layer "In2.Cu")
	)
	(gr_line
		(start 367.752122 -32.31134)
		(end 367.767616 -32.238696)
		(stroke
			(width 0.05715)
			(type default)
		)
		(layer "In2.Cu")
	)
	(gr_line
		(start 367.767616 -32.238696)
		(end 367.827814 -32.194754)
		(stroke
			(width 0.05715)
			(type default)
		)
		(layer "In2.Cu")
	)
	(gr_line
		(start 367.828322 -118.588282)
		(end 367.885726 -118.81104)
		(stroke
			(width 0.05715)
			(type default)
		)
		(layer "In2.Cu")
	)
	(gr_line
		(start 368.076226 -119.265446)
		(end 368.602514 -119.575326)
		(stroke
			(width 0.05715)
			(type default)
		)
		(layer "In2.Cu")
	)
	(gr_line
		(start 368.076734 -119.2657)
		(end 368.60226 -119.575326)
		(stroke
			(width 0.05715)
			(type default)
		)
		(layer "In2.Cu")
	)
	(gr_line
		(start 368.14125 -24.97836)
		(end 368.17427 -24.9301)
		(stroke
			(width 0.05715)
			(type default)
		)
		(layer "In2.Cu")
	)
	(gr_line
		(start 368.17427 -24.9301)
		(end 368.229642 -24.910796)
		(stroke
			(width 0.05715)
			(type default)
		)
		(layer "In2.Cu")
	)
	(gr_line
		(start 368.17554 -134.59206)
		(end 368.689382 -134.078218)
		(stroke
			(width 0.0635)
			(type default)
		)
		(layer "In2.Cu")
	)
	(gr_line
		(start 368.196368 -118.994174)
		(end 368.419126 -118.936516)
		(stroke
			(width 0.05715)
			(type default)
		)
		(layer "In2.Cu")
	)
	(gr_line
		(start 368.263424 -23.022306)
		(end 368.275616 -23.004272)
		(stroke
			(width 0.05715)
			(type default)
		)
		(layer "In2.Cu")
	)
	(gr_line
		(start 368.275616 -23.004272)
		(end 368.29365 -22.99208)
		(stroke
			(width 0.05715)
			(type default)
		)
		(layer "In2.Cu")
	)
	(gr_line
		(start 368.294412 -25.91562)
		(end 368.29873 -25.895808)
		(stroke
			(width 0.05715)
			(type default)
		)
		(layer "In2.Cu")
	)
	(gr_line
		(start 368.29873 -25.895808)
		(end 368.31016 -25.879044)
		(stroke
			(width 0.05715)
			(type default)
		)
		(layer "In2.Cu")
	)
	(gr_line
		(start 368.35715 -20.799552)
		(end 368.369342 -20.781264)
		(stroke
			(width 0.05715)
			(type default)
		)
		(layer "In2.Cu")
	)
	(gr_line
		(start 368.369342 -20.781264)
		(end 368.38763 -20.769072)
		(stroke
			(width 0.05715)
			(type default)
		)
		(layer "In2.Cu")
	)
	(gr_line
		(start 368.419126 -118.936516)
		(end 368.72545 -119.11711)
		(stroke
			(width 0.05715)
			(type default)
		)
		(layer "In2.Cu")
	)
	(gr_line
		(start 368.42954 -134.8486)
		(end 368.748564 -134.8486)
		(stroke
			(width 0.0635)
			(type default)
		)
		(layer "In2.Cu")
	)
	(gr_line
		(start 368.555016 -25.520904)
		(end 368.588544 -25.471882)
		(stroke
			(width 0.05715)
			(type default)
		)
		(layer "In2.Cu")
	)
	(gr_line
		(start 368.588544 -25.471882)
		(end 368.644932 -25.452324)
		(stroke
			(width 0.05715)
			(type default)
		)
		(layer "In2.Cu")
	)
	(gr_line
		(start 368.601244 -114.415062)
		(end 368.651536 -114.36477)
		(stroke
			(width 0.04445)
			(type default)
		)
		(layer "In2.Cu")
	)
	(gr_line
		(start 368.603022 -114.686334)
		(end 368.725196 -114.686334)
		(stroke
			(width 0.04445)
			(type default)
		)
		(layer "In2.Cu")
	)
	(gr_line
		(start 368.725196 -114.686334)
		(end 368.922808 -114.488722)
		(stroke
			(width 0.04445)
			(type default)
		)
		(layer "In2.Cu")
	)
	(gr_line
		(start 368.72545 -119.11711)
		(end 368.783108 -119.339868)
		(stroke
			(width 0.05715)
			(type default)
		)
		(layer "In2.Cu")
	)
	(gr_line
		(start 368.748564 -134.8486)
		(end 369.197382 -135.297418)
		(stroke
			(width 0.0635)
			(type default)
		)
		(layer "In2.Cu")
	)
	(gr_line
		(start 368.76355 -31.874206)
		(end 368.823748 -31.830264)
		(stroke
			(width 0.05715)
			(type default)
		)
		(layer "In2.Cu")
	)
	(gr_line
		(start 368.823748 -31.830264)
		(end 368.839242 -31.75762)
		(stroke
			(width 0.05715)
			(type default)
		)
		(layer "In2.Cu")
	)
	(gr_line
		(start 368.922808 -114.366548)
		(end 368.922808 -114.488722)
		(stroke
			(width 0.04445)
			(type default)
		)
		(layer "In2.Cu")
	)
	(gr_line
		(start 369.00485 -11.81862)
		(end 369.008406 -11.81608)
		(stroke
			(width 0.05715)
			(type default)
		)
		(layer "In2.Cu")
	)
	(gr_line
		(start 369.008406 -11.81608)
		(end 369.01247 -11.81481)
		(stroke
			(width 0.05715)
			(type default)
		)
		(layer "In2.Cu")
	)
	(gr_line
		(start 369.121944 -113.894362)
		(end 369.172236 -113.84407)
		(stroke
			(width 0.04445)
			(type default)
		)
		(layer "In2.Cu")
	)
	(gr_line
		(start 369.123722 -114.165634)
		(end 369.245896 -114.165634)
		(stroke
			(width 0.04445)
			(type default)
		)
		(layer "In2.Cu")
	)
	(gr_line
		(start 369.245896 -114.165634)
		(end 369.443508 -113.968022)
		(stroke
			(width 0.04445)
			(type default)
		)
		(layer "In2.Cu")
	)
	(gr_line
		(start 369.249452 -22.355302)
		(end 369.265708 -22.344634)
		(stroke
			(width 0.05715)
			(type default)
		)
		(layer "In2.Cu")
	)
	(gr_line
		(start 369.292124 -119.981726)
		(end 369.326922 -120.0023)
		(stroke
			(width 0.05715)
			(type default)
		)
		(layer "In2.Cu")
	)
	(gr_line
		(start 369.301268 -12.390374)
		(end 369.304824 -12.387834)
		(stroke
			(width 0.05715)
			(type default)
		)
		(layer "In2.Cu")
	)
	(gr_line
		(start 369.304824 -12.387834)
		(end 369.308888 -12.386564)
		(stroke
			(width 0.05715)
			(type default)
		)
		(layer "In2.Cu")
	)
	(gr_line
		(start 369.374166 -27.836114)
		(end 369.379754 -27.809952)
		(stroke
			(width 0.05715)
			(type default)
		)
		(layer "In2.Cu")
	)
	(gr_line
		(start 369.379754 -27.809952)
		(end 369.396264 -27.787854)
		(stroke
			(width 0.05715)
			(type default)
		)
		(layer "In2.Cu")
	)
	(gr_line
		(start 369.443508 -113.845848)
		(end 369.443508 -113.968022)
		(stroke
			(width 0.04445)
			(type default)
		)
		(layer "In2.Cu")
	)
	(gr_line
		(start 369.479576 -9.615678)
		(end 369.53063 -9.59866)
		(stroke
			(width 0.05715)
			(type default)
		)
		(layer "In2.Cu")
	)
	(gr_line
		(start 369.506246 -120.975882)
		(end 369.541044 -120.996456)
		(stroke
			(width 0.05715)
			(type default)
		)
		(layer "In2.Cu")
	)
	(gr_line
		(start 369.53063 -9.59866)
		(end 369.563142 -9.556242)
		(stroke
			(width 0.05715)
			(type default)
		)
		(layer "In2.Cu")
	)
	(gr_line
		(start 369.598956 -12.96162)
		(end 369.602512 -12.95908)
		(stroke
			(width 0.05715)
			(type default)
		)
		(layer "In2.Cu")
	)
	(gr_line
		(start 369.602512 -12.95908)
		(end 369.606576 -12.95781)
		(stroke
			(width 0.05715)
			(type default)
		)
		(layer "In2.Cu")
	)
	(gr_line
		(start 369.632484 -121.790206)
		(end 369.667282 -121.81078)
		(stroke
			(width 0.05715)
			(type default)
		)
		(layer "In2.Cu")
	)
	(gr_line
		(start 369.693952 -122.564652)
		(end 369.73002 -122.585734)
		(stroke
			(width 0.05715)
			(type default)
		)
		(layer "In2.Cu")
	)
	(gr_line
		(start 369.73002 -122.585734)
		(end 369.730274 -122.58548)
		(stroke
			(width 0.05715)
			(type default)
		)
		(layer "In2.Cu")
	)
	(gr_line
		(start 369.896644 -13.532612)
		(end 369.9002 -13.530072)
		(stroke
			(width 0.05715)
			(type default)
		)
		(layer "In2.Cu")
	)
	(gr_line
		(start 369.9002 -13.530072)
		(end 369.904264 -13.528802)
		(stroke
			(width 0.05715)
			(type default)
		)
		(layer "In2.Cu")
	)
	(gr_line
		(start 370.151914 -6.897624)
		(end 370.159026 -6.893052)
		(stroke
			(width 0.05715)
			(type default)
		)
		(layer "In2.Cu")
	)
	(gr_line
		(start 370.159026 -6.893052)
		(end 370.1669 -6.890766)
		(stroke
			(width 0.05715)
			(type default)
		)
		(layer "In2.Cu")
	)
	(gr_line
		(start 370.270278 -24.50973)
		(end 370.319808 -24.492458)
		(stroke
			(width 0.05715)
			(type default)
		)
		(layer "In2.Cu")
	)
	(gr_line
		(start 370.303806 -113.67262)
		(end 370.390166 -113.75898)
		(stroke
			(width 0.04445)
			(type default)
		)
		(layer "In2.Cu")
	)
	(gr_line
		(start 370.30533 -14.317472)
		(end 370.308886 -14.314932)
		(stroke
			(width 0.05715)
			(type default)
		)
		(layer "In2.Cu")
	)
	(gr_line
		(start 370.308886 -14.314932)
		(end 370.31295 -14.313662)
		(stroke
			(width 0.05715)
			(type default)
		)
		(layer "In2.Cu")
	)
	(gr_line
		(start 370.319808 -24.492458)
		(end 370.351304 -24.450548)
		(stroke
			(width 0.05715)
			(type default)
		)
		(layer "In2.Cu")
	)
	(gr_line
		(start 370.33454 -117.6655)
		(end 370.356638 -117.6655)
		(stroke
			(width 0.04445)
			(type default)
		)
		(layer "In2.Cu")
	)
	(gr_line
		(start 370.33454 -117.3734)
		(end 370.356638 -117.3734)
		(stroke
			(width 0.04445)
			(type default)
		)
		(layer "In2.Cu")
	)
	(gr_line
		(start 370.356638 -117.6655)
		(end 370.36629 -117.655848)
		(stroke
			(width 0.04445)
			(type default)
		)
		(layer "In2.Cu")
	)
	(gr_line
		(start 370.356638 -117.3734)
		(end 370.36629 -117.383052)
		(stroke
			(width 0.04445)
			(type default)
		)
		(layer "In2.Cu")
	)
	(gr_line
		(start 370.368068 -117.65407)
		(end 370.407438 -117.6147)
		(stroke
			(width 0.04445)
			(type default)
		)
		(layer "In2.Cu")
	)
	(gr_line
		(start 370.368068 -117.38483)
		(end 370.407438 -117.4242)
		(stroke
			(width 0.04445)
			(type default)
		)
		(layer "In2.Cu")
	)
	(gr_line
		(start 370.390166 -113.75898)
		(end 370.669566 -113.75898)
		(stroke
			(width 0.04445)
			(type default)
		)
		(layer "In2.Cu")
	)
	(gr_line
		(start 370.474494 -22.400768)
		(end 370.49075 -22.3901)
		(stroke
			(width 0.05715)
			(type default)
		)
		(layer "In2.Cu")
	)
	(gr_line
		(start 370.494306 -113.47958)
		(end 370.565426 -113.47958)
		(stroke
			(width 0.04445)
			(type default)
		)
		(layer "In2.Cu")
	)
	(gr_line
		(start 370.5352 -126.377954)
		(end 370.538756 -126.377954)
		(stroke
			(width 0.0635)
			(type default)
		)
		(layer "In2.Cu")
	)
	(gr_line
		(start 370.603018 -14.888718)
		(end 370.606574 -14.886178)
		(stroke
			(width 0.05715)
			(type default)
		)
		(layer "In2.Cu")
	)
	(gr_line
		(start 370.606574 -14.886178)
		(end 370.610638 -14.884908)
		(stroke
			(width 0.05715)
			(type default)
		)
		(layer "In2.Cu")
	)
	(gr_line
		(start 370.634006 -19.623024)
		(end 370.652294 -19.610832)
		(stroke
			(width 0.05715)
			(type default)
		)
		(layer "In2.Cu")
	)
	(gr_line
		(start 370.652294 -19.610832)
		(end 370.664486 -19.592544)
		(stroke
			(width 0.05715)
			(type default)
		)
		(layer "In2.Cu")
	)
	(gr_line
		(start 370.669566 -113.75898)
		(end 370.755926 -113.67262)
		(stroke
			(width 0.04445)
			(type default)
		)
		(layer "In2.Cu")
	)
	(gr_line
		(start 370.78666 -126.48946)
		(end 370.790216 -126.48946)
		(stroke
			(width 0.0635)
			(type default)
		)
		(layer "In2.Cu")
	)
	(gr_line
		(start 370.822728 -25.002998)
		(end 370.872258 -24.985726)
		(stroke
			(width 0.05715)
			(type default)
		)
		(layer "In2.Cu")
	)
	(gr_line
		(start 370.825268 -7.426452)
		(end 370.860828 -7.379716)
		(stroke
			(width 0.05715)
			(type default)
		)
		(layer "In2.Cu")
	)
	(gr_line
		(start 370.860828 -7.379716)
		(end 370.919248 -7.362952)
		(stroke
			(width 0.05715)
			(type default)
		)
		(layer "In2.Cu")
	)
	(gr_line
		(start 370.872258 -24.985726)
		(end 370.9035 -24.943816)
		(stroke
			(width 0.05715)
			(type default)
		)
		(layer "In2.Cu")
	)
	(gr_line
		(start 370.872258 -24.985726)
		(end 370.903754 -24.943816)
		(stroke
			(width 0.05715)
			(type default)
		)
		(layer "In2.Cu")
	)
	(gr_line
		(start 370.889276 -122.58548)
		(end 370.911374 -122.58548)
		(stroke
			(width 0.04445)
			(type default)
		)
		(layer "In2.Cu")
	)
	(gr_line
		(start 370.889276 -122.29338)
		(end 370.911374 -122.29338)
		(stroke
			(width 0.04445)
			(type default)
		)
		(layer "In2.Cu")
	)
	(gr_line
		(start 370.899944 -22.11705)
		(end 370.9162 -22.106382)
		(stroke
			(width 0.05715)
			(type default)
		)
		(layer "In2.Cu")
	)
	(gr_line
		(start 370.900452 -15.459964)
		(end 370.904008 -15.457424)
		(stroke
			(width 0.05715)
			(type default)
		)
		(layer "In2.Cu")
	)
	(gr_line
		(start 370.904008 -15.457424)
		(end 370.908072 -15.456154)
		(stroke
			(width 0.05715)
			(type default)
		)
		(layer "In2.Cu")
	)
	(gr_line
		(start 370.911374 -122.58548)
		(end 370.921026 -122.575828)
		(stroke
			(width 0.04445)
			(type default)
		)
		(layer "In2.Cu")
	)
	(gr_line
		(start 370.911374 -122.29338)
		(end 370.921026 -122.303032)
		(stroke
			(width 0.04445)
			(type default)
		)
		(layer "In2.Cu")
	)
	(gr_line
		(start 370.9162 -22.106382)
		(end 370.92763 -22.089364)
		(stroke
			(width 0.05715)
			(type default)
		)
		(layer "In2.Cu")
	)
	(gr_line
		(start 370.922804 -122.57405)
		(end 370.962174 -122.53468)
		(stroke
			(width 0.04445)
			(type default)
		)
		(layer "In2.Cu")
	)
	(gr_line
		(start 370.922804 -122.30481)
		(end 370.962174 -122.34418)
		(stroke
			(width 0.04445)
			(type default)
		)
		(layer "In2.Cu")
	)
	(gr_line
		(start 370.93906 -19.181318)
		(end 370.9416 -19.177254)
		(stroke
			(width 0.05715)
			(type default)
		)
		(layer "In2.Cu")
	)
	(gr_line
		(start 370.9416 -19.177254)
		(end 370.943124 -19.172682)
		(stroke
			(width 0.05715)
			(type default)
		)
		(layer "In2.Cu")
	)
	(gr_line
		(start 371.036088 -116.242592)
		(end 371.058186 -116.242592)
		(stroke
			(width 0.04445)
			(type default)
		)
		(layer "In2.Cu")
	)
	(gr_line
		(start 371.036088 -115.950492)
		(end 371.058186 -115.950492)
		(stroke
			(width 0.04445)
			(type default)
		)
		(layer "In2.Cu")
	)
	(gr_line
		(start 371.040406 -113.67262)
		(end 371.126766 -113.75898)
		(stroke
			(width 0.04445)
			(type default)
		)
		(layer "In2.Cu")
	)
	(gr_line
		(start 371.058186 -116.242592)
		(end 371.067838 -116.23294)
		(stroke
			(width 0.04445)
			(type default)
		)
		(layer "In2.Cu")
	)
	(gr_line
		(start 371.058186 -115.950492)
		(end 371.067838 -115.960144)
		(stroke
			(width 0.04445)
			(type default)
		)
		(layer "In2.Cu")
	)
	(gr_line
		(start 371.064282 -120.0023)
		(end 371.08638 -120.0023)
		(stroke
			(width 0.04445)
			(type default)
		)
		(layer "In2.Cu")
	)
	(gr_line
		(start 371.064282 -119.7102)
		(end 371.08638 -119.7102)
		(stroke
			(width 0.04445)
			(type default)
		)
		(layer "In2.Cu")
	)
	(gr_line
		(start 371.06606 -17.859502)
		(end 371.084348 -17.803368)
		(stroke
			(width 0.05715)
			(type default)
		)
		(layer "In2.Cu")
	)
	(gr_line
		(start 371.069616 -116.231162)
		(end 371.108986 -116.191792)
		(stroke
			(width 0.04445)
			(type default)
		)
		(layer "In2.Cu")
	)
	(gr_line
		(start 371.069616 -115.961922)
		(end 371.108986 -116.001292)
		(stroke
			(width 0.04445)
			(type default)
		)
		(layer "In2.Cu")
	)
	(gr_line
		(start 371.084348 -17.803368)
		(end 371.1321 -17.769332)
		(stroke
			(width 0.05715)
			(type default)
		)
		(layer "In2.Cu")
	)
	(gr_line
		(start 371.08638 -120.0023)
		(end 371.096032 -119.992648)
		(stroke
			(width 0.04445)
			(type default)
		)
		(layer "In2.Cu")
	)
	(gr_line
		(start 371.08638 -119.7102)
		(end 371.096032 -119.719852)
		(stroke
			(width 0.04445)
			(type default)
		)
		(layer "In2.Cu")
	)
	(gr_line
		(start 371.09781 -119.99087)
		(end 371.13718 -119.9515)
		(stroke
			(width 0.04445)
			(type default)
		)
		(layer "In2.Cu")
	)
	(gr_line
		(start 371.09781 -119.72163)
		(end 371.13718 -119.761)
		(stroke
			(width 0.04445)
			(type default)
		)
		(layer "In2.Cu")
	)
	(gr_line
		(start 371.126766 -113.75898)
		(end 371.406166 -113.75898)
		(stroke
			(width 0.04445)
			(type default)
		)
		(layer "In2.Cu")
	)
	(gr_line
		(start 371.180614 -122.34164)
		(end 371.266974 -122.25528)
		(stroke
			(width 0.04445)
			(type default)
		)
		(layer "In2.Cu")
	)
	(gr_line
		(start 371.18798 -21.698458)
		(end 371.198648 -21.682202)
		(stroke
			(width 0.05715)
			(type default)
		)
		(layer "In2.Cu")
	)
	(gr_line
		(start 371.197632 -16.030702)
		(end 371.201188 -16.028162)
		(stroke
			(width 0.05715)
			(type default)
		)
		(layer "In2.Cu")
	)
	(gr_line
		(start 371.198648 -21.682202)
		(end 371.202712 -21.663152)
		(stroke
			(width 0.05715)
			(type default)
		)
		(layer "In2.Cu")
	)
	(gr_line
		(start 371.201188 -16.028162)
		(end 371.205252 -16.026892)
		(stroke
			(width 0.05715)
			(type default)
		)
		(layer "In2.Cu")
	)
	(gr_line
		(start 371.230906 -113.47958)
		(end 371.302026 -113.47958)
		(stroke
			(width 0.04445)
			(type default)
		)
		(layer "In2.Cu")
	)
	(gr_line
		(start 371.266974 -122.25528)
		(end 371.533674 -122.25528)
		(stroke
			(width 0.04445)
			(type default)
		)
		(layer "In2.Cu")
	)
	(gr_line
		(start 371.367304 -9.754616)
		(end 371.428264 -9.734296)
		(stroke
			(width 0.05715)
			(type default)
		)
		(layer "In2.Cu")
	)
	(gr_line
		(start 371.371114 -122.53468)
		(end 371.429534 -122.53468)
		(stroke
			(width 0.04445)
			(type default)
		)
		(layer "In2.Cu")
	)
	(gr_line
		(start 371.406166 -113.75898)
		(end 371.492526 -113.67262)
		(stroke
			(width 0.04445)
			(type default)
		)
		(layer "In2.Cu")
	)
	(gr_line
		(start 371.40896 -117.61724)
		(end 371.49532 -117.7036)
		(stroke
			(width 0.04445)
			(type default)
		)
		(layer "In2.Cu")
	)
	(gr_line
		(start 371.428264 -9.734296)
		(end 371.463824 -9.680956)
		(stroke
			(width 0.05715)
			(type default)
		)
		(layer "In2.Cu")
	)
	(gr_line
		(start 371.49532 -117.7036)
		(end 371.77472 -117.7036)
		(stroke
			(width 0.04445)
			(type default)
		)
		(layer "In2.Cu")
	)
	(gr_line
		(start 371.533674 -122.25528)
		(end 371.620034 -122.34164)
		(stroke
			(width 0.04445)
			(type default)
		)
		(layer "In2.Cu")
	)
	(gr_line
		(start 371.59946 -117.4242)
		(end 371.67058 -117.4242)
		(stroke
			(width 0.04445)
			(type default)
		)
		(layer "In2.Cu")
	)
	(gr_line
		(start 371.607842 -22.769322)
		(end 371.624352 -22.747224)
		(stroke
			(width 0.05715)
			(type default)
		)
		(layer "In2.Cu")
	)
	(gr_line
		(start 371.621812 -18.284952)
		(end 371.637814 -18.210022)
		(stroke
			(width 0.05715)
			(type default)
		)
		(layer "In2.Cu")
	)
	(gr_line
		(start 371.624352 -22.747224)
		(end 371.62994 -22.721062)
		(stroke
			(width 0.05715)
			(type default)
		)
		(layer "In2.Cu")
	)
	(gr_line
		(start 371.637814 -18.210022)
		(end 371.700044 -18.165572)
		(stroke
			(width 0.05715)
			(type default)
		)
		(layer "In2.Cu")
	)
	(gr_line
		(start 371.739414 -10.450322)
		(end 371.790468 -10.432288)
		(stroke
			(width 0.05715)
			(type default)
		)
		(layer "In2.Cu")
	)
	(gr_line
		(start 371.77472 -117.7036)
		(end 371.86108 -117.61724)
		(stroke
			(width 0.04445)
			(type default)
		)
		(layer "In2.Cu")
	)
	(gr_line
		(start 371.777006 -113.67262)
		(end 371.863366 -113.75898)
		(stroke
			(width 0.04445)
			(type default)
		)
		(layer "In2.Cu")
	)
	(gr_line
		(start 371.790468 -10.432288)
		(end 371.821964 -10.388092)
		(stroke
			(width 0.05715)
			(type default)
		)
		(layer "In2.Cu")
	)
	(gr_line
		(start 371.804438 -119.75846)
		(end 371.890798 -119.6721)
		(stroke
			(width 0.04445)
			(type default)
		)
		(layer "In2.Cu")
	)
	(gr_line
		(start 371.863366 -113.75898)
		(end 372.142766 -113.75898)
		(stroke
			(width 0.04445)
			(type default)
		)
		(layer "In2.Cu")
	)
	(gr_line
		(start 371.890798 -119.6721)
		(end 372.170198 -119.6721)
		(stroke
			(width 0.04445)
			(type default)
		)
		(layer "In2.Cu")
	)
	(gr_line
		(start 371.891814 -122.34164)
		(end 371.978174 -122.25528)
		(stroke
			(width 0.04445)
			(type default)
		)
		(layer "In2.Cu")
	)
	(gr_line
		(start 371.967506 -113.47958)
		(end 372.038626 -113.47958)
		(stroke
			(width 0.04445)
			(type default)
		)
		(layer "In2.Cu")
	)
	(gr_line
		(start 371.978174 -122.25528)
		(end 372.257574 -122.25528)
		(stroke
			(width 0.04445)
			(type default)
		)
		(layer "In2.Cu")
	)
	(gr_line
		(start 371.994938 -119.9515)
		(end 372.066058 -119.9515)
		(stroke
			(width 0.04445)
			(type default)
		)
		(layer "In2.Cu")
	)
	(gr_line
		(start 372.082314 -122.53468)
		(end 372.153434 -122.53468)
		(stroke
			(width 0.04445)
			(type default)
		)
		(layer "In2.Cu")
	)
	(gr_line
		(start 372.142766 -113.75898)
		(end 372.229126 -113.67262)
		(stroke
			(width 0.04445)
			(type default)
		)
		(layer "In2.Cu")
	)
	(gr_line
		(start 372.14556 -117.61724)
		(end 372.23192 -117.7036)
		(stroke
			(width 0.04445)
			(type default)
		)
		(layer "In2.Cu")
	)
	(gr_line
		(start 372.170198 -119.6721)
		(end 372.256558 -119.75846)
		(stroke
			(width 0.04445)
			(type default)
		)
		(layer "In2.Cu")
	)
	(gr_line
		(start 372.17096 -23.248366)
		(end 372.18747 -23.226268)
		(stroke
			(width 0.05715)
			(type default)
		)
		(layer "In2.Cu")
	)
	(gr_line
		(start 372.18747 -23.226268)
		(end 372.193058 -23.200106)
		(stroke
			(width 0.05715)
			(type default)
		)
		(layer "In2.Cu")
	)
	(gr_line
		(start 372.188486 -18.685256)
		(end 372.204488 -18.610326)
		(stroke
			(width 0.05715)
			(type default)
		)
		(layer "In2.Cu")
	)
	(gr_line
		(start 372.204488 -18.610326)
		(end 372.266718 -18.565876)
		(stroke
			(width 0.05715)
			(type default)
		)
		(layer "In2.Cu")
	)
	(gr_line
		(start 372.228618 -115.998752)
		(end 372.314978 -115.912392)
		(stroke
			(width 0.04445)
			(type default)
		)
		(layer "In2.Cu")
	)
	(gr_line
		(start 372.23192 -117.7036)
		(end 372.51132 -117.7036)
		(stroke
			(width 0.04445)
			(type default)
		)
		(layer "In2.Cu")
	)
	(gr_line
		(start 372.257574 -122.25528)
		(end 372.343934 -122.34164)
		(stroke
			(width 0.04445)
			(type default)
		)
		(layer "In2.Cu")
	)
	(gr_line
		(start 372.314978 -115.912392)
		(end 372.581678 -115.912392)
		(stroke
			(width 0.04445)
			(type default)
		)
		(layer "In2.Cu")
	)
	(gr_line
		(start 372.33606 -117.4242)
		(end 372.40718 -117.4242)
		(stroke
			(width 0.04445)
			(type default)
		)
		(layer "In2.Cu")
	)
	(gr_line
		(start 372.419118 -116.191792)
		(end 372.477538 -116.191792)
		(stroke
			(width 0.04445)
			(type default)
		)
		(layer "In2.Cu")
	)
	(gr_line
		(start 372.458996 -7.662672)
		(end 372.49735 -7.605268)
		(stroke
			(width 0.05715)
			(type default)
		)
		(layer "In2.Cu")
	)
	(gr_line
		(start 372.49735 -7.605268)
		(end 372.563898 -7.586218)
		(stroke
			(width 0.05715)
			(type default)
		)
		(layer "In2.Cu")
	)
	(gr_line
		(start 372.51132 -117.7036)
		(end 372.59768 -117.61724)
		(stroke
			(width 0.04445)
			(type default)
		)
		(layer "In2.Cu")
	)
	(gr_line
		(start 372.513606 -113.67262)
		(end 372.599966 -113.75898)
		(stroke
			(width 0.04445)
			(type default)
		)
		(layer "In2.Cu")
	)
	(gr_line
		(start 372.541038 -119.75846)
		(end 372.627398 -119.6721)
		(stroke
			(width 0.04445)
			(type default)
		)
		(layer "In2.Cu")
	)
	(gr_line
		(start 372.581678 -115.912392)
		(end 372.668038 -115.998752)
		(stroke
			(width 0.04445)
			(type default)
		)
		(layer "In2.Cu")
	)
	(gr_line
		(start 372.599966 -113.75898)
		(end 372.879366 -113.75898)
		(stroke
			(width 0.04445)
			(type default)
		)
		(layer "In2.Cu")
	)
	(gr_line
		(start 372.627398 -119.6721)
		(end 372.906798 -119.6721)
		(stroke
			(width 0.04445)
			(type default)
		)
		(layer "In2.Cu")
	)
	(gr_line
		(start 372.628414 -122.34164)
		(end 372.714774 -122.25528)
		(stroke
			(width 0.04445)
			(type default)
		)
		(layer "In2.Cu")
	)
	(gr_line
		(start 372.704106 -113.47958)
		(end 372.775226 -113.47958)
		(stroke
			(width 0.04445)
			(type default)
		)
		(layer "In2.Cu")
	)
	(gr_line
		(start 372.714774 -122.25528)
		(end 372.994174 -122.25528)
		(stroke
			(width 0.04445)
			(type default)
		)
		(layer "In2.Cu")
	)
	(gr_line
		(start 372.731538 -119.9515)
		(end 372.802658 -119.9515)
		(stroke
			(width 0.04445)
			(type default)
		)
		(layer "In2.Cu")
	)
	(gr_line
		(start 372.767098 -19.09191)
		(end 372.7831 -19.01698)
		(stroke
			(width 0.05715)
			(type default)
		)
		(layer "In2.Cu")
	)
	(gr_line
		(start 372.7831 -19.01698)
		(end 372.84533 -18.97253)
		(stroke
			(width 0.05715)
			(type default)
		)
		(layer "In2.Cu")
	)
	(gr_line
		(start 372.818914 -122.53468)
		(end 372.890034 -122.53468)
		(stroke
			(width 0.04445)
			(type default)
		)
		(layer "In2.Cu")
	)
	(gr_line
		(start 372.879366 -113.75898)
		(end 372.965726 -113.67262)
		(stroke
			(width 0.04445)
			(type default)
		)
		(layer "In2.Cu")
	)
	(gr_line
		(start 372.905782 -23.581106)
		(end 372.92153 -23.560024)
		(stroke
			(width 0.05715)
			(type default)
		)
		(layer "In2.Cu")
	)
	(gr_line
		(start 372.906798 -119.6721)
		(end 372.993158 -119.75846)
		(stroke
			(width 0.04445)
			(type default)
		)
		(layer "In2.Cu")
	)
	(gr_line
		(start 372.92153 -23.560024)
		(end 372.92661 -23.535386)
		(stroke
			(width 0.05715)
			(type default)
		)
		(layer "In2.Cu")
	)
	(gr_line
		(start 372.9228 -120.996456)
		(end 372.944898 -120.996456)
		(stroke
			(width 0.04445)
			(type default)
		)
		(layer "In2.Cu")
	)
	(gr_line
		(start 372.9228 -120.704356)
		(end 372.944898 -120.704356)
		(stroke
			(width 0.04445)
			(type default)
		)
		(layer "In2.Cu")
	)
	(gr_line
		(start 372.939818 -115.998752)
		(end 373.026178 -115.912392)
		(stroke
			(width 0.04445)
			(type default)
		)
		(layer "In2.Cu")
	)
	(gr_line
		(start 372.944898 -120.996456)
		(end 372.95455 -120.986804)
		(stroke
			(width 0.04445)
			(type default)
		)
		(layer "In2.Cu")
	)
	(gr_line
		(start 372.944898 -120.704356)
		(end 372.95455 -120.714008)
		(stroke
			(width 0.04445)
			(type default)
		)
		(layer "In2.Cu")
	)
	(gr_line
		(start 372.956328 -120.985026)
		(end 372.995698 -120.945656)
		(stroke
			(width 0.04445)
			(type default)
		)
		(layer "In2.Cu")
	)
	(gr_line
		(start 372.956328 -120.715786)
		(end 372.995698 -120.755156)
		(stroke
			(width 0.04445)
			(type default)
		)
		(layer "In2.Cu")
	)
	(gr_line
		(start 372.994174 -122.25528)
		(end 373.080534 -122.34164)
		(stroke
			(width 0.04445)
			(type default)
		)
		(layer "In2.Cu")
	)
	(gr_line
		(start 373.015764 -8.199374)
		(end 373.054372 -8.145018)
		(stroke
			(width 0.05715)
			(type default)
		)
		(layer "In2.Cu")
	)
	(gr_line
		(start 373.026178 -115.912392)
		(end 373.292878 -115.912392)
		(stroke
			(width 0.04445)
			(type default)
		)
		(layer "In2.Cu")
	)
	(gr_line
		(start 373.054372 -8.145018)
		(end 373.118126 -8.126984)
		(stroke
			(width 0.05715)
			(type default)
		)
		(layer "In2.Cu")
	)
	(gr_line
		(start 373.130318 -116.191792)
		(end 373.188738 -116.191792)
		(stroke
			(width 0.04445)
			(type default)
		)
		(layer "In2.Cu")
	)
	(gr_line
		(start 373.190008 -20.892008)
		(end 373.205756 -20.818094)
		(stroke
			(width 0.05715)
			(type default)
		)
		(layer "In2.Cu")
	)
	(gr_line
		(start 373.205756 -20.818094)
		(end 373.267986 -20.77339)
		(stroke
			(width 0.05715)
			(type default)
		)
		(layer "In2.Cu")
	)
	(gr_line
		(start 373.208804 -126.48946)
		(end 373.21236 -126.48946)
		(stroke
			(width 0.0635)
			(type default)
		)
		(layer "In2.Cu")
	)
	(gr_line
		(start 373.250206 -113.67262)
		(end 373.336566 -113.75898)
		(stroke
			(width 0.04445)
			(type default)
		)
		(layer "In2.Cu")
	)
	(gr_line
		(start 373.277638 -120.752616)
		(end 373.363998 -120.666256)
		(stroke
			(width 0.04445)
			(type default)
		)
		(layer "In2.Cu")
	)
	(gr_line
		(start 373.277638 -119.75846)
		(end 373.363998 -119.6721)
		(stroke
			(width 0.04445)
			(type default)
		)
		(layer "In2.Cu")
	)
	(gr_line
		(start 373.292878 -115.912392)
		(end 373.379238 -115.998752)
		(stroke
			(width 0.04445)
			(type default)
		)
		(layer "In2.Cu")
	)
	(gr_line
		(start 373.336566 -113.75898)
		(end 373.615966 -113.75898)
		(stroke
			(width 0.04445)
			(type default)
		)
		(layer "In2.Cu")
	)
	(gr_line
		(start 373.363998 -120.666256)
		(end 373.643398 -120.666256)
		(stroke
			(width 0.04445)
			(type default)
		)
		(layer "In2.Cu")
	)
	(gr_line
		(start 373.363998 -119.6721)
		(end 373.643398 -119.6721)
		(stroke
			(width 0.04445)
			(type default)
		)
		(layer "In2.Cu")
	)
	(gr_line
		(start 373.365014 -122.34164)
		(end 373.451374 -122.25528)
		(stroke
			(width 0.04445)
			(type default)
		)
		(layer "In2.Cu")
	)
	(gr_line
		(start 373.440706 -113.47958)
		(end 373.511826 -113.47958)
		(stroke
			(width 0.04445)
			(type default)
		)
		(layer "In2.Cu")
	)
	(gr_line
		(start 373.451374 -122.25528)
		(end 373.730774 -122.25528)
		(stroke
			(width 0.04445)
			(type default)
		)
		(layer "In2.Cu")
	)
	(gr_line
		(start 373.460264 -126.377954)
		(end 373.46382 -126.377954)
		(stroke
			(width 0.0635)
			(type default)
		)
		(layer "In2.Cu")
	)
	(gr_line
		(start 373.468138 -120.945656)
		(end 373.539258 -120.945656)
		(stroke
			(width 0.04445)
			(type default)
		)
		(layer "In2.Cu")
	)
	(gr_line
		(start 373.468138 -119.9515)
		(end 373.539258 -119.9515)
		(stroke
			(width 0.04445)
			(type default)
		)
		(layer "In2.Cu")
	)
	(gr_line
		(start 373.555514 -122.53468)
		(end 373.626634 -122.53468)
		(stroke
			(width 0.04445)
			(type default)
		)
		(layer "In2.Cu")
	)
	(gr_line
		(start 373.615966 -113.75898)
		(end 373.702326 -113.67262)
		(stroke
			(width 0.04445)
			(type default)
		)
		(layer "In2.Cu")
	)
	(gr_line
		(start 373.643398 -120.666256)
		(end 373.729758 -120.752616)
		(stroke
			(width 0.04445)
			(type default)
		)
		(layer "In2.Cu")
	)
	(gr_line
		(start 373.643398 -119.6721)
		(end 373.729758 -119.75846)
		(stroke
			(width 0.04445)
			(type default)
		)
		(layer "In2.Cu")
	)
	(gr_line
		(start 373.64924 -117.22608)
		(end 373.7356 -117.31244)
		(stroke
			(width 0.04445)
			(type default)
		)
		(layer "In2.Cu")
	)
	(gr_line
		(start 373.651018 -115.998752)
		(end 373.737378 -115.912392)
		(stroke
			(width 0.04445)
			(type default)
		)
		(layer "In2.Cu")
	)
	(gr_line
		(start 373.730774 -122.25528)
		(end 373.817134 -122.34164)
		(stroke
			(width 0.04445)
			(type default)
		)
		(layer "In2.Cu")
	)
	(gr_line
		(start 373.7356 -117.31244)
		(end 374.015 -117.31244)
		(stroke
			(width 0.04445)
			(type default)
		)
		(layer "In2.Cu")
	)
	(gr_line
		(start 373.737378 -115.912392)
		(end 374.004078 -115.912392)
		(stroke
			(width 0.04445)
			(type default)
		)
		(layer "In2.Cu")
	)
	(gr_line
		(start 373.83974 -117.03304)
		(end 373.91086 -117.03304)
		(stroke
			(width 0.04445)
			(type default)
		)
		(layer "In2.Cu")
	)
	(gr_line
		(start 373.841518 -116.191792)
		(end 373.899938 -116.191792)
		(stroke
			(width 0.04445)
			(type default)
		)
		(layer "In2.Cu")
	)
	(gr_line
		(start 373.993156 -15.721076)
		(end 373.996712 -15.718536)
		(stroke
			(width 0.05715)
			(type default)
		)
		(layer "In2.Cu")
	)
	(gr_line
		(start 373.996712 -15.718536)
		(end 374.000776 -15.717266)
		(stroke
			(width 0.05715)
			(type default)
		)
		(layer "In2.Cu")
	)
	(gr_line
		(start 374.004078 -115.912392)
		(end 374.090438 -115.998752)
		(stroke
			(width 0.04445)
			(type default)
		)
		(layer "In2.Cu")
	)
	(gr_line
		(start 374.014238 -120.752616)
		(end 374.100598 -120.666256)
		(stroke
			(width 0.04445)
			(type default)
		)
		(layer "In2.Cu")
	)
	(gr_line
		(start 374.014238 -119.75846)
		(end 374.100598 -119.6721)
		(stroke
			(width 0.04445)
			(type default)
		)
		(layer "In2.Cu")
	)
	(gr_line
		(start 374.015 -117.31244)
		(end 374.10136 -117.22608)
		(stroke
			(width 0.04445)
			(type default)
		)
		(layer "In2.Cu")
	)
	(gr_line
		(start 374.100598 -120.666256)
		(end 374.379998 -120.666256)
		(stroke
			(width 0.04445)
			(type default)
		)
		(layer "In2.Cu")
	)
	(gr_line
		(start 374.100598 -119.6721)
		(end 374.379998 -119.6721)
		(stroke
			(width 0.04445)
			(type default)
		)
		(layer "In2.Cu")
	)
	(gr_line
		(start 374.101614 -122.34164)
		(end 374.187974 -122.25528)
		(stroke
			(width 0.04445)
			(type default)
		)
		(layer "In2.Cu")
	)
	(gr_line
		(start 374.187974 -122.25528)
		(end 374.467374 -122.25528)
		(stroke
			(width 0.04445)
			(type default)
		)
		(layer "In2.Cu")
	)
	(gr_line
		(start 374.204738 -120.945656)
		(end 374.275858 -120.945656)
		(stroke
			(width 0.04445)
			(type default)
		)
		(layer "In2.Cu")
	)
	(gr_line
		(start 374.204738 -119.9515)
		(end 374.275858 -119.9515)
		(stroke
			(width 0.04445)
			(type default)
		)
		(layer "In2.Cu")
	)
	(gr_line
		(start 374.245378 -114.056922)
		(end 374.442736 -114.25428)
		(stroke
			(width 0.04445)
			(type default)
		)
		(layer "In2.Cu")
	)
	(gr_line
		(start 374.245378 -113.934748)
		(end 374.245378 -114.056922)
		(stroke
			(width 0.04445)
			(type default)
		)
		(layer "In2.Cu")
	)
	(gr_line
		(start 374.257824 -20.065238)
		(end 374.75541 -19.70913)
		(stroke
			(width 0.05715)
			(type default)
		)
		(layer "In2.Cu")
	)
	(gr_line
		(start 374.292114 -122.53468)
		(end 374.363234 -122.53468)
		(stroke
			(width 0.04445)
			(type default)
		)
		(layer "In2.Cu")
	)
	(gr_line
		(start 374.34266 -16.273526)
		(end 374.346216 -16.270986)
		(stroke
			(width 0.05715)
			(type default)
		)
		(layer "In2.Cu")
	)
	(gr_line
		(start 374.346216 -16.270986)
		(end 374.350534 -16.269462)
		(stroke
			(width 0.05715)
			(type default)
		)
		(layer "In2.Cu")
	)
	(gr_line
		(start 374.379998 -120.666256)
		(end 374.466358 -120.752616)
		(stroke
			(width 0.04445)
			(type default)
		)
		(layer "In2.Cu")
	)
	(gr_line
		(start 374.379998 -119.6721)
		(end 374.466358 -119.75846)
		(stroke
			(width 0.04445)
			(type default)
		)
		(layer "In2.Cu")
	)
	(gr_line
		(start 374.402096 -20.324318)
		(end 374.629426 -20.36191)
		(stroke
			(width 0.05715)
			(type default)
		)
		(layer "In2.Cu")
	)
	(gr_line
		(start 374.442736 -114.25428)
		(end 374.56491 -114.25428)
		(stroke
			(width 0.04445)
			(type default)
		)
		(layer "In2.Cu")
	)
	(gr_line
		(start 374.467374 -122.25528)
		(end 374.553734 -122.34164)
		(stroke
			(width 0.04445)
			(type default)
		)
		(layer "In2.Cu")
	)
	(gr_line
		(start 374.51665 -113.93297)
		(end 374.566688 -113.983008)
		(stroke
			(width 0.04445)
			(type default)
		)
		(layer "In2.Cu")
	)
	(gr_line
		(start 374.542812 -117.508782)
		(end 374.740424 -117.706394)
		(stroke
			(width 0.04445)
			(type default)
		)
		(layer "In2.Cu")
	)
	(gr_line
		(start 374.542812 -117.386608)
		(end 374.542812 -117.508782)
		(stroke
			(width 0.04445)
			(type default)
		)
		(layer "In2.Cu")
	)
	(gr_line
		(start 374.549924 -116.461032)
		(end 374.591326 -116.502434)
		(stroke
			(width 0.04445)
			(type default)
		)
		(layer "In2.Cu")
	)
	(gr_line
		(start 374.551702 -116.18976)
		(end 374.673876 -116.18976)
		(stroke
			(width 0.04445)
			(type default)
		)
		(layer "In2.Cu")
	)
	(gr_line
		(start 374.629426 -20.36191)
		(end 374.918478 -20.1549)
		(stroke
			(width 0.05715)
			(type default)
		)
		(layer "In2.Cu")
	)
	(gr_line
		(start 374.673876 -116.18976)
		(end 374.862598 -116.378482)
		(stroke
			(width 0.04445)
			(type default)
		)
		(layer "In2.Cu")
	)
	(gr_line
		(start 374.700292 -16.82369)
		(end 374.703848 -16.82115)
		(stroke
			(width 0.05715)
			(type default)
		)
		(layer "In2.Cu")
	)
	(gr_line
		(start 374.703848 -16.82115)
		(end 374.708166 -16.819626)
		(stroke
			(width 0.05715)
			(type default)
		)
		(layer "In2.Cu")
	)
	(gr_line
		(start 374.717564 -113.485422)
		(end 374.915176 -113.683034)
		(stroke
			(width 0.04445)
			(type default)
		)
		(layer "In2.Cu")
	)
	(gr_line
		(start 374.717564 -113.363248)
		(end 374.717564 -113.485422)
		(stroke
			(width 0.04445)
			(type default)
		)
		(layer "In2.Cu")
	)
	(gr_line
		(start 374.740424 -117.706394)
		(end 374.862598 -117.706394)
		(stroke
			(width 0.04445)
			(type default)
		)
		(layer "In2.Cu")
	)
	(gr_line
		(start 374.750838 -120.752616)
		(end 374.837198 -120.666256)
		(stroke
			(width 0.04445)
			(type default)
		)
		(layer "In2.Cu")
	)
	(gr_line
		(start 374.750838 -119.75846)
		(end 374.837198 -119.6721)
		(stroke
			(width 0.04445)
			(type default)
		)
		(layer "In2.Cu")
	)
	(gr_line
		(start 374.766078 -114.577622)
		(end 374.96369 -114.775234)
		(stroke
			(width 0.04445)
			(type default)
		)
		(layer "In2.Cu")
	)
	(gr_line
		(start 374.766078 -114.455448)
		(end 374.766078 -114.577622)
		(stroke
			(width 0.04445)
			(type default)
		)
		(layer "In2.Cu")
	)
	(gr_line
		(start 374.795542 -121.81078)
		(end 374.81764 -121.81078)
		(stroke
			(width 0.04445)
			(type default)
		)
		(layer "In2.Cu")
	)
	(gr_line
		(start 374.795542 -121.51868)
		(end 374.81764 -121.51868)
		(stroke
			(width 0.04445)
			(type default)
		)
		(layer "In2.Cu")
	)
	(gr_line
		(start 374.814084 -117.38483)
		(end 374.864376 -117.435122)
		(stroke
			(width 0.04445)
			(type default)
		)
		(layer "In2.Cu")
	)
	(gr_line
		(start 374.81764 -121.81078)
		(end 374.827292 -121.801128)
		(stroke
			(width 0.04445)
			(type default)
		)
		(layer "In2.Cu")
	)
	(gr_line
		(start 374.81764 -121.51868)
		(end 374.827292 -121.528332)
		(stroke
			(width 0.04445)
			(type default)
		)
		(layer "In2.Cu")
	)
	(gr_line
		(start 374.82907 -121.79935)
		(end 374.86844 -121.75998)
		(stroke
			(width 0.04445)
			(type default)
		)
		(layer "In2.Cu")
	)
	(gr_line
		(start 374.82907 -121.53011)
		(end 374.86844 -121.56948)
		(stroke
			(width 0.04445)
			(type default)
		)
		(layer "In2.Cu")
	)
	(gr_line
		(start 374.837198 -120.666256)
		(end 375.116598 -120.666256)
		(stroke
			(width 0.04445)
			(type default)
		)
		(layer "In2.Cu")
	)
	(gr_line
		(start 374.837198 -119.6721)
		(end 375.116598 -119.6721)
		(stroke
			(width 0.04445)
			(type default)
		)
		(layer "In2.Cu")
	)
	(gr_line
		(start 374.838214 -122.34164)
		(end 374.924574 -122.25528)
		(stroke
			(width 0.04445)
			(type default)
		)
		(layer "In2.Cu")
	)
	(gr_line
		(start 374.862598 -116.378482)
		(end 374.862598 -116.500656)
		(stroke
			(width 0.04445)
			(type default)
		)
		(layer "In2.Cu")
	)
	(gr_line
		(start 374.915176 -113.683034)
		(end 375.03735 -113.683034)
		(stroke
			(width 0.04445)
			(type default)
		)
		(layer "In2.Cu")
	)
	(gr_line
		(start 374.918478 -20.1549)
		(end 374.95607 -19.927824)
		(stroke
			(width 0.05715)
			(type default)
		)
		(layer "In2.Cu")
	)
	(gr_line
		(start 374.924574 -122.25528)
		(end 375.203974 -122.25528)
		(stroke
			(width 0.04445)
			(type default)
		)
		(layer "In2.Cu")
	)
	(gr_line
		(start 374.941338 -120.945656)
		(end 375.012458 -120.945656)
		(stroke
			(width 0.04445)
			(type default)
		)
		(layer "In2.Cu")
	)
	(gr_line
		(start 374.941338 -119.9515)
		(end 375.012458 -119.9515)
		(stroke
			(width 0.04445)
			(type default)
		)
		(layer "In2.Cu")
	)
	(gr_line
		(start 374.96369 -114.775234)
		(end 375.085864 -114.775234)
		(stroke
			(width 0.04445)
			(type default)
		)
		(layer "In2.Cu")
	)
	(gr_line
		(start 374.988836 -113.36147)
		(end 375.039128 -113.411762)
		(stroke
			(width 0.04445)
			(type default)
		)
		(layer "In2.Cu")
	)
	(gr_line
		(start 375.028714 -122.53468)
		(end 375.099834 -122.53468)
		(stroke
			(width 0.04445)
			(type default)
		)
		(layer "In2.Cu")
	)
	(gr_line
		(start 375.03735 -114.45367)
		(end 375.087642 -114.503962)
		(stroke
			(width 0.04445)
			(type default)
		)
		(layer "In2.Cu")
	)
	(gr_line
		(start 375.052844 -116.963952)
		(end 375.094246 -117.005354)
		(stroke
			(width 0.04445)
			(type default)
		)
		(layer "In2.Cu")
	)
	(gr_line
		(start 375.054622 -116.69268)
		(end 375.176796 -116.69268)
		(stroke
			(width 0.04445)
			(type default)
		)
		(layer "In2.Cu")
	)
	(gr_line
		(start 375.063766 -118.029736)
		(end 375.261378 -118.227348)
		(stroke
			(width 0.04445)
			(type default)
		)
		(layer "In2.Cu")
	)
	(gr_line
		(start 375.063766 -117.907562)
		(end 375.063766 -118.029736)
		(stroke
			(width 0.04445)
			(type default)
		)
		(layer "In2.Cu")
	)
	(gr_line
		(start 375.097294 -17.359376)
		(end 375.10085 -17.356836)
		(stroke
			(width 0.05715)
			(type default)
		)
		(layer "In2.Cu")
	)
	(gr_line
		(start 375.10085 -17.356836)
		(end 375.102882 -17.356074)
		(stroke
			(width 0.05715)
			(type default)
		)
		(layer "In2.Cu")
	)
	(gr_line
		(start 375.102882 -17.356328)
		(end 375.10339 -17.356074)
		(stroke
			(width 0.05715)
			(type default)
		)
		(layer "In2.Cu")
	)
	(gr_line
		(start 375.102882 -17.356074)
		(end 375.102882 -17.356328)
		(stroke
			(width 0.05715)
			(type default)
		)
		(layer "In2.Cu")
	)
	(gr_line
		(start 375.106692 -19.457924)
		(end 375.601738 -19.103848)
		(stroke
			(width 0.05715)
			(type default)
		)
		(layer "In2.Cu")
	)
	(gr_line
		(start 375.116598 -120.666256)
		(end 375.202958 -120.752616)
		(stroke
			(width 0.04445)
			(type default)
		)
		(layer "In2.Cu")
	)
	(gr_line
		(start 375.116598 -119.6721)
		(end 375.202958 -119.75846)
		(stroke
			(width 0.04445)
			(type default)
		)
		(layer "In2.Cu")
	)
	(gr_line
		(start 375.176796 -116.69268)
		(end 375.365518 -116.881402)
		(stroke
			(width 0.04445)
			(type default)
		)
		(layer "In2.Cu")
	)
	(gr_line
		(start 375.203974 -122.25528)
		(end 375.290334 -122.34164)
		(stroke
			(width 0.04445)
			(type default)
		)
		(layer "In2.Cu")
	)
	(gr_line
		(start 375.238264 -114.006122)
		(end 375.435876 -114.203734)
		(stroke
			(width 0.04445)
			(type default)
		)
		(layer "In2.Cu")
	)
	(gr_line
		(start 375.238264 -113.883948)
		(end 375.238264 -114.006122)
		(stroke
			(width 0.04445)
			(type default)
		)
		(layer "In2.Cu")
	)
	(gr_line
		(start 375.247662 -121.56694)
		(end 375.334022 -121.48058)
		(stroke
			(width 0.04445)
			(type default)
		)
		(layer "In2.Cu")
	)
	(gr_line
		(start 375.249186 -19.71802)
		(end 375.476262 -19.755866)
		(stroke
			(width 0.05715)
			(type default)
		)
		(layer "In2.Cu")
	)
	(gr_line
		(start 375.261378 -118.227348)
		(end 375.383552 -118.227348)
		(stroke
			(width 0.04445)
			(type default)
		)
		(layer "In2.Cu")
	)
	(gr_line
		(start 375.287032 -115.098576)
		(end 375.484644 -115.296188)
		(stroke
			(width 0.04445)
			(type default)
		)
		(layer "In2.Cu")
	)
	(gr_line
		(start 375.287032 -114.976402)
		(end 375.287032 -115.098576)
		(stroke
			(width 0.04445)
			(type default)
		)
		(layer "In2.Cu")
	)
	(gr_line
		(start 375.334022 -121.48058)
		(end 375.613422 -121.48058)
		(stroke
			(width 0.04445)
			(type default)
		)
		(layer "In2.Cu")
	)
	(gr_line
		(start 375.335038 -117.905784)
		(end 375.38533 -117.956076)
		(stroke
			(width 0.04445)
			(type default)
		)
		(layer "In2.Cu")
	)
	(gr_line
		(start 375.365518 -116.881402)
		(end 375.365518 -117.003576)
		(stroke
			(width 0.04445)
			(type default)
		)
		(layer "In2.Cu")
	)
	(gr_line
		(start 375.435876 -114.203734)
		(end 375.55805 -114.203734)
		(stroke
			(width 0.04445)
			(type default)
		)
		(layer "In2.Cu")
	)
	(gr_line
		(start 375.438162 -121.75998)
		(end 375.509282 -121.75998)
		(stroke
			(width 0.04445)
			(type default)
		)
		(layer "In2.Cu")
	)
	(gr_line
		(start 375.476262 -19.755866)
		(end 375.765314 -19.548856)
		(stroke
			(width 0.05715)
			(type default)
		)
		(layer "In2.Cu")
	)
	(gr_line
		(start 375.484644 -115.296188)
		(end 375.606818 -115.296188)
		(stroke
			(width 0.04445)
			(type default)
		)
		(layer "In2.Cu")
	)
	(gr_line
		(start 375.487438 -120.752616)
		(end 375.573798 -120.666256)
		(stroke
			(width 0.04445)
			(type default)
		)
		(layer "In2.Cu")
	)
	(gr_line
		(start 375.487438 -119.75846)
		(end 375.573798 -119.6721)
		(stroke
			(width 0.04445)
			(type default)
		)
		(layer "In2.Cu")
	)
	(gr_line
		(start 375.509536 -113.88217)
		(end 375.559828 -113.932462)
		(stroke
			(width 0.04445)
			(type default)
		)
		(layer "In2.Cu")
	)
	(gr_line
		(start 375.555764 -117.466872)
		(end 375.597166 -117.508274)
		(stroke
			(width 0.04445)
			(type default)
		)
		(layer "In2.Cu")
	)
	(gr_line
		(start 375.557542 -117.1956)
		(end 375.679716 -117.1956)
		(stroke
			(width 0.04445)
			(type default)
		)
		(layer "In2.Cu")
	)
	(gr_line
		(start 375.558304 -114.974624)
		(end 375.608596 -115.024916)
		(stroke
			(width 0.04445)
			(type default)
		)
		(layer "In2.Cu")
	)
	(gr_line
		(start 375.573798 -120.666256)
		(end 375.853198 -120.666256)
		(stroke
			(width 0.04445)
			(type default)
		)
		(layer "In2.Cu")
	)
	(gr_line
		(start 375.573798 -119.6721)
		(end 375.853198 -119.6721)
		(stroke
			(width 0.04445)
			(type default)
		)
		(layer "In2.Cu")
	)
	(gr_line
		(start 375.584466 -118.550436)
		(end 375.782078 -118.748048)
		(stroke
			(width 0.04445)
			(type default)
		)
		(layer "In2.Cu")
	)
	(gr_line
		(start 375.584466 -118.428262)
		(end 375.584466 -118.550436)
		(stroke
			(width 0.04445)
			(type default)
		)
		(layer "In2.Cu")
	)
	(gr_line
		(start 375.613422 -121.48058)
		(end 375.699782 -121.56694)
		(stroke
			(width 0.04445)
			(type default)
		)
		(layer "In2.Cu")
	)
	(gr_line
		(start 375.677938 -120.945656)
		(end 375.749058 -120.945656)
		(stroke
			(width 0.04445)
			(type default)
		)
		(layer "In2.Cu")
	)
	(gr_line
		(start 375.677938 -119.9515)
		(end 375.749058 -119.9515)
		(stroke
			(width 0.04445)
			(type default)
		)
		(layer "In2.Cu")
	)
	(gr_line
		(start 375.679716 -117.1956)
		(end 375.868438 -117.384322)
		(stroke
			(width 0.04445)
			(type default)
		)
		(layer "In2.Cu")
	)
	(gr_line
		(start 375.759218 -114.527076)
		(end 375.95683 -114.724688)
		(stroke
			(width 0.04445)
			(type default)
		)
		(layer "In2.Cu")
	)
	(gr_line
		(start 375.759218 -114.404902)
		(end 375.759218 -114.527076)
		(stroke
			(width 0.04445)
			(type default)
		)
		(layer "In2.Cu")
	)
	(gr_line
		(start 375.76125 -129.02565)
		(end 375.861072 -129.125472)
		(stroke
			(width 0.05715)
			(type default)
		)
		(layer "In2.Cu")
	)
	(gr_line
		(start 375.765314 -19.548856)
		(end 375.802906 -19.32178)
		(stroke
			(width 0.05715)
			(type default)
		)
		(layer "In2.Cu")
	)
	(gr_line
		(start 375.782078 -118.748048)
		(end 375.904252 -118.748048)
		(stroke
			(width 0.04445)
			(type default)
		)
		(layer "In2.Cu")
	)
	(gr_line
		(start 375.807732 -115.619276)
		(end 376.005344 -115.816888)
		(stroke
			(width 0.04445)
			(type default)
		)
		(layer "In2.Cu")
	)
	(gr_line
		(start 375.807732 -115.497102)
		(end 375.807732 -115.619276)
		(stroke
			(width 0.04445)
			(type default)
		)
		(layer "In2.Cu")
	)
	(gr_line
		(start 375.853198 -120.666256)
		(end 375.939558 -120.752616)
		(stroke
			(width 0.04445)
			(type default)
		)
		(layer "In2.Cu")
	)
	(gr_line
		(start 375.853198 -119.6721)
		(end 375.939558 -119.75846)
		(stroke
			(width 0.04445)
			(type default)
		)
		(layer "In2.Cu")
	)
	(gr_line
		(start 375.855738 -118.426484)
		(end 375.90603 -118.476776)
		(stroke
			(width 0.04445)
			(type default)
		)
		(layer "In2.Cu")
	)
	(gr_line
		(start 375.868438 -117.384322)
		(end 375.868438 -117.506496)
		(stroke
			(width 0.04445)
			(type default)
		)
		(layer "In2.Cu")
	)
	(gr_arc
		(start 375.8946 -129.206244)
		(mid 375.88584 -129.162535)
		(end 375.861072 -129.125472)
		(stroke
			(width 0.05715)
			(type default)
		)
		(layer "In2.Cu")
	)
	(gr_line
		(start 375.954036 -18.851372)
		(end 376.450352 -18.49628)
		(stroke
			(width 0.05715)
			(type default)
		)
		(layer "In2.Cu")
	)
	(gr_line
		(start 375.95683 -114.724688)
		(end 376.079004 -114.724688)
		(stroke
			(width 0.04445)
			(type default)
		)
		(layer "In2.Cu")
	)
	(gr_line
		(start 376.005344 -115.816888)
		(end 376.127518 -115.816888)
		(stroke
			(width 0.04445)
			(type default)
		)
		(layer "In2.Cu")
	)
	(gr_line
		(start 376.03049 -114.403124)
		(end 376.080782 -114.453416)
		(stroke
			(width 0.04445)
			(type default)
		)
		(layer "In2.Cu")
	)
	(gr_line
		(start 376.079004 -115.495324)
		(end 376.129296 -115.545616)
		(stroke
			(width 0.04445)
			(type default)
		)
		(layer "In2.Cu")
	)
	(gr_line
		(start 376.096022 -19.111976)
		(end 376.323098 -19.149568)
		(stroke
			(width 0.05715)
			(type default)
		)
		(layer "In2.Cu")
	)
	(gr_arc
		(start 376.220228 -129.227072)
		(mid 376.195466 -129.264131)
		(end 376.1867 -129.307844)
		(stroke
			(width 0.05715)
			(type default)
		)
		(layer "In2.Cu")
	)
	(gr_line
		(start 376.220228 -129.227072)
		(end 376.42165 -129.02565)
		(stroke
			(width 0.05715)
			(type default)
		)
		(layer "In2.Cu")
	)
	(gr_line
		(start 376.323098 -19.149568)
		(end 376.61215 -18.942812)
		(stroke
			(width 0.05715)
			(type default)
		)
		(layer "In2.Cu")
	)
	(gr_line
		(start 376.61215 -18.942812)
		(end 376.649996 -18.715482)
		(stroke
			(width 0.05715)
			(type default)
		)
		(layer "In2.Cu")
	)
	(gr_line
		(start 376.63755 -122.76836)
		(end 376.72391 -122.682)
		(stroke
			(width 0.04445)
			(type default)
		)
		(layer "In2.Cu")
	)
	(gr_line
		(start 376.72391 -122.682)
		(end 377.00331 -122.682)
		(stroke
			(width 0.04445)
			(type default)
		)
		(layer "In2.Cu")
	)
	(gr_line
		(start 376.72645 -9.093962)
		(end 376.768614 -9.078976)
		(stroke
			(width 0.05715)
			(type default)
		)
		(layer "In2.Cu")
	)
	(gr_line
		(start 376.762772 -10.433558)
		(end 376.804936 -10.418572)
		(stroke
			(width 0.05715)
			(type default)
		)
		(layer "In2.Cu")
	)
	(gr_line
		(start 376.76709 -9.75614)
		(end 376.809254 -9.741154)
		(stroke
			(width 0.05715)
			(type default)
		)
		(layer "In2.Cu")
	)
	(gr_line
		(start 376.768614 -9.078976)
		(end 376.813064 -9.088374)
		(stroke
			(width 0.05715)
			(type default)
		)
		(layer "In2.Cu")
	)
	(gr_line
		(start 376.77217 -11.106658)
		(end 376.814334 -11.091672)
		(stroke
			(width 0.05715)
			(type default)
		)
		(layer "In2.Cu")
	)
	(gr_line
		(start 376.800364 -18.245836)
		(end 376.818906 -18.232374)
		(stroke
			(width 0.05715)
			(type default)
		)
		(layer "In2.Cu")
	)
	(gr_line
		(start 376.804936 -10.418572)
		(end 376.849386 -10.42797)
		(stroke
			(width 0.05715)
			(type default)
		)
		(layer "In2.Cu")
	)
	(gr_line
		(start 376.809254 -9.741154)
		(end 376.853704 -9.750552)
		(stroke
			(width 0.05715)
			(type default)
		)
		(layer "In2.Cu")
	)
	(gr_line
		(start 376.814334 -11.091672)
		(end 376.858784 -11.10107)
		(stroke
			(width 0.05715)
			(type default)
		)
		(layer "In2.Cu")
	)
	(gr_line
		(start 376.818906 -18.232374)
		(end 376.841512 -18.227548)
		(stroke
			(width 0.05715)
			(type default)
		)
		(layer "In2.Cu")
	)
	(gr_line
		(start 376.82805 -122.9614)
		(end 376.89917 -122.9614)
		(stroke
			(width 0.04445)
			(type default)
		)
		(layer "In2.Cu")
	)
	(gr_line
		(start 376.870214 -12.000738)
		(end 376.912378 -11.985752)
		(stroke
			(width 0.05715)
			(type default)
		)
		(layer "In2.Cu")
	)
	(gr_line
		(start 376.89155 -12.669774)
		(end 376.933714 -12.654788)
		(stroke
			(width 0.05715)
			(type default)
		)
		(layer "In2.Cu")
	)
	(gr_line
		(start 376.912378 -11.985752)
		(end 376.956574 -11.99515)
		(stroke
			(width 0.05715)
			(type default)
		)
		(layer "In2.Cu")
	)
	(gr_line
		(start 376.931936 -13.33119)
		(end 376.9741 -13.316204)
		(stroke
			(width 0.05715)
			(type default)
		)
		(layer "In2.Cu")
	)
	(gr_line
		(start 376.933714 -12.654788)
		(end 376.97791 -12.664186)
		(stroke
			(width 0.05715)
			(type default)
		)
		(layer "In2.Cu")
	)
	(gr_line
		(start 376.935238 -16.034766)
		(end 376.977402 -16.01978)
		(stroke
			(width 0.05715)
			(type default)
		)
		(layer "In2.Cu")
	)
	(gr_line
		(start 376.939556 -15.357094)
		(end 376.982228 -15.342108)
		(stroke
			(width 0.05715)
			(type default)
		)
		(layer "In2.Cu")
	)
	(gr_line
		(start 376.94616 -14.00175)
		(end 376.988324 -13.986764)
		(stroke
			(width 0.05715)
			(type default)
		)
		(layer "In2.Cu")
	)
	(gr_line
		(start 376.952002 -16.703802)
		(end 376.994166 -16.688816)
		(stroke
			(width 0.05715)
			(type default)
		)
		(layer "In2.Cu")
	)
	(gr_line
		(start 376.955558 -14.675104)
		(end 376.997722 -14.660118)
		(stroke
			(width 0.05715)
			(type default)
		)
		(layer "In2.Cu")
	)
	(gr_line
		(start 376.9741 -13.316204)
		(end 377.018296 -13.325602)
		(stroke
			(width 0.05715)
			(type default)
		)
		(layer "In2.Cu")
	)
	(gr_line
		(start 376.977402 -16.01978)
		(end 377.021852 -16.029178)
		(stroke
			(width 0.05715)
			(type default)
		)
		(layer "In2.Cu")
	)
	(gr_line
		(start 376.982228 -15.342108)
		(end 377.026678 -15.351506)
		(stroke
			(width 0.05715)
			(type default)
		)
		(layer "In2.Cu")
	)
	(gr_line
		(start 376.988324 -13.986764)
		(end 377.03252 -13.996162)
		(stroke
			(width 0.05715)
			(type default)
		)
		(layer "In2.Cu")
	)
	(gr_line
		(start 376.994166 -16.688816)
		(end 377.038362 -16.698214)
		(stroke
			(width 0.05715)
			(type default)
		)
		(layer "In2.Cu")
	)
	(gr_line
		(start 376.997722 -14.660118)
		(end 377.042172 -14.669516)
		(stroke
			(width 0.05715)
			(type default)
		)
		(layer "In2.Cu")
	)
	(gr_line
		(start 377.00331 -122.682)
		(end 377.08967 -122.76836)
		(stroke
			(width 0.04445)
			(type default)
		)
		(layer "In2.Cu")
	)
	(gr_line
		(start 377.19762 -117.77726)
		(end 377.496324 -117.77726)
		(stroke
			(width 0.044704)
			(type default)
		)
		(layer "In2.Cu")
	)
	(gr_line
		(start 377.366022 -129.032)
		(end 377.415552 -129.08153)
		(stroke
			(width 0.05715)
			(type default)
		)
		(layer "In2.Cu")
	)
	(gr_line
		(start 377.387612 -120.945656)
		(end 377.451874 -120.945656)
		(stroke
			(width 0.04445)
			(type default)
		)
		(layer "In2.Cu")
	)
	(gr_arc
		(start 377.44908 -129.162302)
		(mid 377.440305 -129.118603)
		(end 377.415552 -129.08153)
		(stroke
			(width 0.05715)
			(type default)
		)
		(layer "In2.Cu")
	)
	(gr_line
		(start 377.496324 -117.77726)
		(end 377.574556 -117.855492)
		(stroke
			(width 0.044704)
			(type default)
		)
		(layer "In2.Cu")
	)
	(gr_line
		(start 377.576334 -117.85727)
		(end 377.60021 -117.881146)
		(stroke
			(width 0.044704)
			(type default)
		)
		(layer "In2.Cu")
	)
	(gr_line
		(start 377.578112 -120.8024)
		(end 377.642374 -120.8024)
		(stroke
			(width 0.04445)
			(type default)
		)
		(layer "In2.Cu")
	)
	(gr_line
		(start 377.736354 -118.94566)
		(end 377.762516 -118.926102)
		(stroke
			(width 0.04445)
			(type default)
		)
		(layer "In2.Cu")
	)
	(gr_line
		(start 377.791218 -117.912642)
		(end 377.84659 -117.85727)
		(stroke
			(width 0.044704)
			(type default)
		)
		(layer "In2.Cu")
	)
	(gr_arc
		(start 377.811284 -129.246122)
		(mid 377.75945 -129.323748)
		(end 377.74118 -129.415286)
		(stroke
			(width 0.05715)
			(type default)
		)
		(layer "In2.Cu")
	)
	(gr_line
		(start 377.811284 -129.246122)
		(end 378.025406 -129.032)
		(stroke
			(width 0.05715)
			(type default)
		)
		(layer "In2.Cu")
	)
	(gr_line
		(start 377.83135 -116.953284)
		(end 378.169424 -116.953284)
		(stroke
			(width 0.04445)
			(type default)
		)
		(layer "In2.Cu")
	)
	(gr_line
		(start 377.848368 -117.855492)
		(end 377.892056 -117.811804)
		(stroke
			(width 0.044704)
			(type default)
		)
		(layer "In2.Cu")
	)
	(gr_line
		(start 377.852178 -117.624098)
		(end 377.869704 -117.613938)
		(stroke
			(width 0.04445)
			(type default)
		)
		(layer "In2.Cu")
	)
	(gr_line
		(start 377.892056 -117.811804)
		(end 378.32665 -117.811804)
		(stroke
			(width 0.044704)
			(type default)
		)
		(layer "In2.Cu")
	)
	(gr_line
		(start 377.942602 -119.761)
		(end 377.957334 -119.775732)
		(stroke
			(width 0.04445)
			(type default)
		)
		(layer "In2.Cu")
	)
	(gr_line
		(start 377.9647 -120.9929)
		(end 377.982226 -120.98274)
		(stroke
			(width 0.04445)
			(type default)
		)
		(layer "In2.Cu")
	)
	(gr_line
		(start 378.025406 -129.032)
		(end 378.026422 -129.032)
		(stroke
			(width 0.05715)
			(type default)
		)
		(layer "In2.Cu")
	)
	(gr_arc
		(start 378.031248 -123.474734)
		(mid 377.882662 -123.413002)
		(end 377.723146 -123.39193)
		(stroke
			(width 0.04445)
			(type default)
		)
		(layer "In2.Cu")
	)
	(gr_arc
		(start 378.031248 -123.474734)
		(mid 378.32654 -123.553865)
		(end 378.621798 -123.474734)
		(stroke
			(width 0.04445)
			(type default)
		)
		(layer "In2.Cu")
	)
	(gr_arc
		(start 378.126752 -123.309634)
		(mid 377.972099 -123.240751)
		(end 377.806458 -123.205748)
		(stroke
			(width 0.04445)
			(type default)
		)
		(layer "In2.Cu")
	)
	(gr_arc
		(start 378.126752 -123.309634)
		(mid 378.32665 -123.363133)
		(end 378.526548 -123.309634)
		(stroke
			(width 0.04445)
			(type default)
		)
		(layer "In2.Cu")
	)
	(gr_line
		(start 378.169424 -116.953284)
		(end 378.190252 -116.932456)
		(stroke
			(width 0.04445)
			(type default)
		)
		(layer "In2.Cu")
	)
	(gr_line
		(start 378.19203 -116.930678)
		(end 378.234448 -116.88826)
		(stroke
			(width 0.04445)
			(type default)
		)
		(layer "In2.Cu")
	)
	(gr_line
		(start 378.32665 -121.245884)
		(end 378.49556 -121.539)
		(stroke
			(width 0.04445)
			(type default)
		)
		(layer "In2.Cu")
	)
	(gr_line
		(start 378.425964 -116.895372)
		(end 378.46127 -116.930678)
		(stroke
			(width 0.04445)
			(type default)
		)
		(layer "In2.Cu")
	)
	(gr_line
		(start 378.463048 -116.932456)
		(end 378.483876 -116.953284)
		(stroke
			(width 0.04445)
			(type default)
		)
		(layer "In2.Cu")
	)
	(gr_line
		(start 378.474732 -121.616216)
		(end 378.49556 -121.539)
		(stroke
			(width 0.04445)
			(type default)
		)
		(layer "In2.Cu")
	)
	(gr_line
		(start 378.483876 -116.953284)
		(end 378.82195 -116.953284)
		(stroke
			(width 0.04445)
			(type default)
		)
		(layer "In2.Cu")
	)
	(gr_line
		(start 378.4854 -132.08)
		(end 378.629672 -132.224272)
		(stroke
			(width 0.05715)
			(type default)
		)
		(layer "In2.Cu")
	)
	(gr_line
		(start 378.52096 -4.807712)
		(end 378.58827 -4.788408)
		(stroke
			(width 0.05715)
			(type default)
		)
		(layer "In2.Cu")
	)
	(gr_line
		(start 378.56541 -121.78792)
		(end 378.65304 -121.811288)
		(stroke
			(width 0.04445)
			(type default)
		)
		(layer "In2.Cu")
	)
	(gr_line
		(start 378.58827 -4.788408)
		(end 378.626878 -4.730496)
		(stroke
			(width 0.05715)
			(type default)
		)
		(layer "In2.Cu")
	)
	(gr_line
		(start 378.620274 -17.332706)
		(end 378.643388 -17.337786)
		(stroke
			(width 0.05715)
			(type default)
		)
		(layer "In2.Cu")
	)
	(gr_line
		(start 378.621798 -123.474734)
		(end 378.622052 -123.474734)
		(stroke
			(width 0.04445)
			(type default)
		)
		(layer "In2.Cu")
	)
	(gr_line
		(start 378.643388 -17.337786)
		(end 378.666502 -17.332706)
		(stroke
			(width 0.05715)
			(type default)
		)
		(layer "In2.Cu")
	)
	(gr_line
		(start 378.65304 -121.811288)
		(end 378.82195 -122.104404)
		(stroke
			(width 0.04445)
			(type default)
		)
		(layer "In2.Cu")
	)
	(gr_line
		(start 378.656596 -16.674338)
		(end 378.67971 -16.679418)
		(stroke
			(width 0.05715)
			(type default)
		)
		(layer "In2.Cu")
	)
	(gr_line
		(start 378.6632 -133.552438)
		(end 378.6632 -133.966458)
		(stroke
			(width 0.05715)
			(type default)
		)
		(layer "In2.Cu")
	)
	(gr_arc
		(start 378.6632 -132.305044)
		(mid 378.65444 -132.261335)
		(end 378.629672 -132.224272)
		(stroke
			(width 0.05715)
			(type default)
		)
		(layer "In2.Cu")
	)
	(gr_line
		(start 378.67971 -16.679418)
		(end 378.702824 -16.674338)
		(stroke
			(width 0.05715)
			(type default)
		)
		(layer "In2.Cu")
	)
	(gr_line
		(start 378.714 -16.00835)
		(end 378.737114 -16.01343)
		(stroke
			(width 0.05715)
			(type default)
		)
		(layer "In2.Cu")
	)
	(gr_line
		(start 378.737114 -16.01343)
		(end 378.760228 -16.00835)
		(stroke
			(width 0.05715)
			(type default)
		)
		(layer "In2.Cu")
	)
	(gr_line
		(start 378.783342 -15.337282)
		(end 378.806456 -15.342362)
		(stroke
			(width 0.05715)
			(type default)
		)
		(layer "In2.Cu")
	)
	(gr_line
		(start 378.806456 -15.342362)
		(end 378.82957 -15.337282)
		(stroke
			(width 0.05715)
			(type default)
		)
		(layer "In2.Cu")
	)
	(gr_line
		(start 378.82195 -118.670324)
		(end 378.99086 -118.96344)
		(stroke
			(width 0.04445)
			(type default)
		)
		(layer "In2.Cu")
	)
	(gr_line
		(start 378.831094 -14.676628)
		(end 378.854208 -14.681708)
		(stroke
			(width 0.05715)
			(type default)
		)
		(layer "In2.Cu")
	)
	(gr_line
		(start 378.839984 -12.69365)
		(end 378.863098 -12.69873)
		(stroke
			(width 0.05715)
			(type default)
		)
		(layer "In2.Cu")
	)
	(gr_line
		(start 378.849128 -14.012672)
		(end 378.872242 -14.017752)
		(stroke
			(width 0.05715)
			(type default)
		)
		(layer "In2.Cu")
	)
	(gr_line
		(start 378.854208 -14.681708)
		(end 378.877322 -14.676628)
		(stroke
			(width 0.05715)
			(type default)
		)
		(layer "In2.Cu")
	)
	(gr_line
		(start 378.856748 -13.361416)
		(end 378.879862 -13.366496)
		(stroke
			(width 0.05715)
			(type default)
		)
		(layer "In2.Cu")
	)
	(gr_line
		(start 378.863098 -12.69873)
		(end 378.886212 -12.69365)
		(stroke
			(width 0.05715)
			(type default)
		)
		(layer "In2.Cu")
	)
	(gr_line
		(start 378.872242 -14.017752)
		(end 378.895356 -14.012672)
		(stroke
			(width 0.05715)
			(type default)
		)
		(layer "In2.Cu")
	)
	(gr_line
		(start 378.879862 -13.366496)
		(end 378.902976 -13.361416)
		(stroke
			(width 0.05715)
			(type default)
		)
		(layer "In2.Cu")
	)
	(gr_arc
		(start 378.9553 -133.257798)
		(mid 378.978068 -133.349595)
		(end 379.03785 -133.422898)
		(stroke
			(width 0.05715)
			(type default)
		)
		(layer "In2.Cu")
	)
	(gr_line
		(start 378.963428 -11.846052)
		(end 378.986542 -11.851132)
		(stroke
			(width 0.05715)
			(type default)
		)
		(layer "In2.Cu")
	)
	(gr_line
		(start 378.979176 -11.178286)
		(end 379.00229 -11.183366)
		(stroke
			(width 0.05715)
			(type default)
		)
		(layer "In2.Cu")
	)
	(gr_line
		(start 378.981208 -9.847072)
		(end 379.004576 -9.851898)
		(stroke
			(width 0.05715)
			(type default)
		)
		(layer "In2.Cu")
	)
	(gr_line
		(start 378.986542 -11.851132)
		(end 379.009656 -11.846052)
		(stroke
			(width 0.05715)
			(type default)
		)
		(layer "In2.Cu")
	)
	(gr_arc
		(start 378.988828 -132.236972)
		(mid 378.964066 -132.274031)
		(end 378.9553 -132.317744)
		(stroke
			(width 0.05715)
			(type default)
		)
		(layer "In2.Cu")
	)
	(gr_line
		(start 378.988828 -132.236972)
		(end 379.1458 -132.08)
		(stroke
			(width 0.05715)
			(type default)
		)
		(layer "In2.Cu")
	)
	(gr_line
		(start 378.99086 -118.96344)
		(end 379.067822 -118.984014)
		(stroke
			(width 0.04445)
			(type default)
		)
		(layer "In2.Cu")
	)
	(gr_line
		(start 379.00229 -11.183366)
		(end 379.025404 -11.178286)
		(stroke
			(width 0.05715)
			(type default)
		)
		(layer "In2.Cu")
	)
	(gr_line
		(start 379.004576 -9.851898)
		(end 379.028452 -9.846818)
		(stroke
			(width 0.05715)
			(type default)
		)
		(layer "In2.Cu")
	)
	(gr_line
		(start 379.016514 -10.50798)
		(end 379.039628 -10.51306)
		(stroke
			(width 0.05715)
			(type default)
		)
		(layer "In2.Cu")
	)
	(gr_arc
		(start 379.021848 -123.474734)
		(mid 379.31725 -123.553865)
		(end 379.612652 -123.474734)
		(stroke
			(width 0.04445)
			(type default)
		)
		(layer "In2.Cu")
	)
	(gr_arc
		(start 379.03785 -134.095998)
		(mid 378.978024 -134.169279)
		(end 378.9553 -134.261098)
		(stroke
			(width 0.05715)
			(type default)
		)
		(layer "In2.Cu")
	)
	(gr_arc
		(start 379.03785 -134.095998)
		(mid 379.09762 -134.022697)
		(end 379.1204 -133.930898)
		(stroke
			(width 0.05715)
			(type default)
		)
		(layer "In2.Cu")
	)
	(gr_line
		(start 379.039628 -10.51306)
		(end 379.062742 -10.50798)
		(stroke
			(width 0.05715)
			(type default)
		)
		(layer "In2.Cu")
	)
	(gr_line
		(start 379.065282 -3.145028)
		(end 379.069092 -3.124962)
		(stroke
			(width 0.05715)
			(type default)
		)
		(layer "In2.Cu")
	)
	(gr_line
		(start 379.069092 -3.124962)
		(end 379.08103 -3.106928)
		(stroke
			(width 0.05715)
			(type default)
		)
		(layer "In2.Cu")
	)
	(gr_arc
		(start 379.117352 -123.309634)
		(mid 379.317394 -123.36326)
		(end 379.517402 -123.309634)
		(stroke
			(width 0.04445)
			(type default)
		)
		(layer "In2.Cu")
	)
	(gr_arc
		(start 379.1204 -133.587998)
		(mid 379.097659 -133.496185)
		(end 379.03785 -133.422898)
		(stroke
			(width 0.05715)
			(type default)
		)
		(layer "In2.Cu")
	)
	(gr_line
		(start 379.1204 -133.587998)
		(end 379.1204 -133.930898)
		(stroke
			(width 0.05715)
			(type default)
		)
		(layer "In2.Cu")
	)
	(gr_line
		(start 379.14834 -119.235728)
		(end 379.171962 -119.148098)
		(stroke
			(width 0.04445)
			(type default)
		)
		(layer "In2.Cu")
	)
	(gr_line
		(start 379.14834 -119.235728)
		(end 379.31725 -119.528844)
		(stroke
			(width 0.04445)
			(type default)
		)
		(layer "In2.Cu")
	)
	(gr_line
		(start 379.21438 -3.84937)
		(end 379.226064 -3.83159)
		(stroke
			(width 0.05715)
			(type default)
		)
		(layer "In2.Cu")
	)
	(gr_line
		(start 379.226064 -3.83159)
		(end 379.229874 -3.811524)
		(stroke
			(width 0.05715)
			(type default)
		)
		(layer "In2.Cu")
	)
	(gr_line
		(start 379.31725 -121.245884)
		(end 379.655324 -121.245884)
		(stroke
			(width 0.04445)
			(type default)
		)
		(layer "In2.Cu")
	)
	(gr_line
		(start 379.345952 -2.709672)
		(end 379.357382 -2.692654)
		(stroke
			(width 0.05715)
			(type default)
		)
		(layer "In2.Cu")
	)
	(gr_line
		(start 379.357382 -2.692654)
		(end 379.373638 -2.681986)
		(stroke
			(width 0.05715)
			(type default)
		)
		(layer "In2.Cu")
	)
	(gr_line
		(start 379.509528 -5.211826)
		(end 379.576076 -5.192776)
		(stroke
			(width 0.05715)
			(type default)
		)
		(layer "In2.Cu")
	)
	(gr_arc
		(start 379.517402 -123.309634)
		(mid 379.661026 -123.167899)
		(end 379.7173 -122.9741)
		(stroke
			(width 0.04445)
			(type default)
		)
		(layer "In2.Cu")
	)
	(gr_line
		(start 379.576076 -5.192776)
		(end 379.614176 -5.135626)
		(stroke
			(width 0.05715)
			(type default)
		)
		(layer "In2.Cu")
	)
	(gr_arc
		(start 379.612652 -123.474734)
		(mid 379.823516 -123.26773)
		(end 379.9078 -122.984514)
		(stroke
			(width 0.04445)
			(type default)
		)
		(layer "In2.Cu")
	)
	(gr_line
		(start 379.655324 -121.245884)
		(end 379.676152 -121.266712)
		(stroke
			(width 0.04445)
			(type default)
		)
		(layer "In2.Cu")
	)
	(gr_line
		(start 379.67793 -121.26849)
		(end 379.713236 -121.303796)
		(stroke
			(width 0.04445)
			(type default)
		)
		(layer "In2.Cu")
	)
	(gr_line
		(start 379.81255 -120.387364)
		(end 379.98146 -120.094248)
		(stroke
			(width 0.04445)
			(type default)
		)
		(layer "In2.Cu")
	)
	(gr_line
		(start 379.81255 -118.670324)
		(end 380.150624 -118.670324)
		(stroke
			(width 0.04445)
			(type default)
		)
		(layer "In2.Cu")
	)
	(gr_line
		(start 379.842268 -4.266946)
		(end 379.85446 -4.248658)
		(stroke
			(width 0.05715)
			(type default)
		)
		(layer "In2.Cu")
	)
	(gr_line
		(start 379.85446 -4.248658)
		(end 379.872748 -4.236466)
		(stroke
			(width 0.05715)
			(type default)
		)
		(layer "In2.Cu")
	)
	(gr_line
		(start 379.904752 -121.310908)
		(end 379.94717 -121.26849)
		(stroke
			(width 0.04445)
			(type default)
		)
		(layer "In2.Cu")
	)
	(gr_line
		(start 379.948948 -121.266712)
		(end 379.969776 -121.245884)
		(stroke
			(width 0.04445)
			(type default)
		)
		(layer "In2.Cu")
	)
	(gr_line
		(start 379.969776 -121.245884)
		(end 380.30785 -121.245884)
		(stroke
			(width 0.04445)
			(type default)
		)
		(layer "In2.Cu")
	)
	(gr_line
		(start 379.98146 -120.094248)
		(end 380.058422 -120.073674)
		(stroke
			(width 0.04445)
			(type default)
		)
		(layer "In2.Cu")
	)
	(gr_arc
		(start 380.012448 -122.451114)
		(mid 379.801576 -122.658114)
		(end 379.7173 -122.941334)
		(stroke
			(width 0.04445)
			(type default)
		)
		(layer "In2.Cu")
	)
	(gr_arc
		(start 380.012448 -122.451114)
		(mid 380.156252 -122.309431)
		(end 380.2126 -122.11558)
		(stroke
			(width 0.04445)
			(type default)
		)
		(layer "In2.Cu")
	)
	(gr_line
		(start 380.067312 -5.746496)
		(end 380.134622 -5.727192)
		(stroke
			(width 0.05715)
			(type default)
		)
		(layer "In2.Cu")
	)
	(gr_arc
		(start 380.091696 -136.015984)
		(mid 380.172763 -136.064883)
		(end 380.266956 -136.074404)
		(stroke
			(width 0.05715)
			(type default)
		)
		(layer "In2.Cu")
	)
	(gr_line
		(start 380.09322 -136.43102)
		(end 380.386082 -136.723882)
		(stroke
			(width 0.05715)
			(type default)
		)
		(layer "In2.Cu")
	)
	(gr_arc
		(start 380.107952 -122.616214)
		(mid 379.964174 -122.757905)
		(end 379.9078 -122.951748)
		(stroke
			(width 0.04445)
			(type default)
		)
		(layer "In2.Cu")
	)
	(gr_arc
		(start 380.107952 -122.616214)
		(mid 380.318816 -122.40921)
		(end 380.4031 -122.125994)
		(stroke
			(width 0.04445)
			(type default)
		)
		(layer "In2.Cu")
	)
	(gr_line
		(start 380.134622 -5.727192)
		(end 380.17323 -5.66928)
		(stroke
			(width 0.05715)
			(type default)
		)
		(layer "In2.Cu")
	)
	(gr_line
		(start 380.13894 -119.82196)
		(end 380.162562 -119.90959)
		(stroke
			(width 0.04445)
			(type default)
		)
		(layer "In2.Cu")
	)
	(gr_line
		(start 380.13894 -119.82196)
		(end 380.30785 -119.528844)
		(stroke
			(width 0.04445)
			(type default)
		)
		(layer "In2.Cu")
	)
	(gr_line
		(start 380.150624 -118.670324)
		(end 380.171452 -118.691152)
		(stroke
			(width 0.04445)
			(type default)
		)
		(layer "In2.Cu")
	)
	(gr_line
		(start 380.17323 -118.69293)
		(end 380.215648 -118.735348)
		(stroke
			(width 0.04445)
			(type default)
		)
		(layer "In2.Cu")
	)
	(gr_line
		(start 380.407164 -118.728236)
		(end 380.44247 -118.69293)
		(stroke
			(width 0.04445)
			(type default)
		)
		(layer "In2.Cu")
	)
	(gr_line
		(start 380.436882 -4.746752)
		(end 380.45517 -4.73456)
		(stroke
			(width 0.05715)
			(type default)
		)
		(layer "In2.Cu")
	)
	(gr_arc
		(start 380.441962 -136.132824)
		(mid 380.36101 -136.083988)
		(end 380.266956 -136.074404)
		(stroke
			(width 0.05715)
			(type default)
		)
		(layer "In2.Cu")
	)
	(gr_line
		(start 380.441962 -136.132824)
		(end 380.684532 -136.375394)
		(stroke
			(width 0.05715)
			(type default)
		)
		(layer "In2.Cu")
	)
	(gr_line
		(start 380.444248 -118.691152)
		(end 380.465076 -118.670324)
		(stroke
			(width 0.04445)
			(type default)
		)
		(layer "In2.Cu")
	)
	(gr_line
		(start 380.465076 -118.670324)
		(end 380.80315 -118.670324)
		(stroke
			(width 0.04445)
			(type default)
		)
		(layer "In2.Cu")
	)
	(gr_line
		(start 380.50597 -131.094988)
		(end 380.702312 -131.29133)
		(stroke
			(width 0.05715)
			(type default)
		)
		(layer "In2.Cu")
	)
	(gr_arc
		(start 380.508002 -121.59234)
		(mid 380.296978 -121.799438)
		(end 380.2126 -122.082814)
		(stroke
			(width 0.04445)
			(type default)
		)
		(layer "In2.Cu")
	)
	(gr_line
		(start 380.562358 -129.092706)
		(end 380.698502 -129.22885)
		(stroke
			(width 0.05715)
			(type default)
		)
		(layer "In2.Cu")
	)
	(gr_arc
		(start 380.603252 -121.757694)
		(mid 380.459467 -121.899384)
		(end 380.4031 -122.093228)
		(stroke
			(width 0.04445)
			(type default)
		)
		(layer "In2.Cu")
	)
	(gr_line
		(start 380.665736 -1.81991)
		(end 380.681992 -1.809242)
		(stroke
			(width 0.05715)
			(type default)
		)
		(layer "In2.Cu")
	)
	(gr_line
		(start 380.681992 -1.809242)
		(end 380.701042 -1.805432)
		(stroke
			(width 0.05715)
			(type default)
		)
		(layer "In2.Cu")
	)
	(gr_arc
		(start 380.73203 -129.309622)
		(mid 380.723264 -129.265916)
		(end 380.698502 -129.22885)
		(stroke
			(width 0.05715)
			(type default)
		)
		(layer "In2.Cu")
	)
	(gr_arc
		(start 380.73584 -131.372102)
		(mid 380.727139 -131.328361)
		(end 380.702312 -131.29133)
		(stroke
			(width 0.05715)
			(type default)
		)
		(layer "In2.Cu")
	)
	(gr_arc
		(start 380.742952 -136.5504)
		(mid 380.733376 -136.456346)
		(end 380.684532 -136.375394)
		(stroke
			(width 0.05715)
			(type default)
		)
		(layer "In2.Cu")
	)
	(gr_arc
		(start 380.742952 -136.5504)
		(mid 380.752417 -136.644423)
		(end 380.801118 -136.725406)
		(stroke
			(width 0.05715)
			(type default)
		)
		(layer "In2.Cu")
	)
	(gr_line
		(start 380.80315 -120.387364)
		(end 380.97206 -120.68048)
		(stroke
			(width 0.04445)
			(type default)
		)
		(layer "In2.Cu")
	)
	(gr_arc
		(start 380.80315 -116.111274)
		(mid 380.873481 -116.349754)
		(end 381.0508 -116.524024)
		(stroke
			(width 0.04445)
			(type default)
		)
		(layer "In2.Cu")
	)
	(gr_line
		(start 380.80315 -116.078254)
		(end 380.80315 -116.111274)
		(stroke
			(width 0.04445)
			(type default)
		)
		(layer "In2.Cu")
	)
	(gr_arc
		(start 380.80315 -112.677194)
		(mid 380.873488 -112.915667)
		(end 381.0508 -113.089944)
		(stroke
			(width 0.04445)
			(type default)
		)
		(layer "In2.Cu")
	)
	(gr_line
		(start 380.80315 -112.644174)
		(end 380.80315 -112.677194)
		(stroke
			(width 0.04445)
			(type default)
		)
		(layer "In2.Cu")
	)
	(gr_line
		(start 380.806452 -114.415062)
		(end 380.81966 -114.239548)
		(stroke
			(width 0.04445)
			(type default)
		)
		(layer "In2.Cu")
	)
	(gr_arc
		(start 380.806452 -114.415062)
		(mid 380.851049 -114.641683)
		(end 381.005588 -114.813334)
		(stroke
			(width 0.04445)
			(type default)
		)
		(layer "In2.Cu")
	)
	(gr_line
		(start 380.97206 -120.68048)
		(end 381.05969 -120.703848)
		(stroke
			(width 0.04445)
			(type default)
		)
		(layer "In2.Cu")
	)
	(gr_arc
		(start 381.003048 -121.757694)
		(mid 380.80315 -121.704195)
		(end 380.603252 -121.757694)
		(stroke
			(width 0.04445)
			(type default)
		)
		(layer "In2.Cu")
	)
	(gr_arc
		(start 381.003048 -121.757694)
		(mid 381.29845 -121.836825)
		(end 381.593852 -121.757694)
		(stroke
			(width 0.04445)
			(type default)
		)
		(layer "In2.Cu")
	)
	(gr_line
		(start 381.005588 -114.813334)
		(end 381.197612 -114.93627)
		(stroke
			(width 0.04445)
			(type default)
		)
		(layer "In2.Cu")
	)
	(gr_arc
		(start 381.0508 -115.665504)
		(mid 380.873502 -115.839796)
		(end 380.80315 -116.078254)
		(stroke
			(width 0.04445)
			(type default)
		)
		(layer "In2.Cu")
	)
	(gr_arc
		(start 381.0508 -115.665504)
		(mid 381.226149 -115.494101)
		(end 381.297942 -115.259612)
		(stroke
			(width 0.04445)
			(type default)
		)
		(layer "In2.Cu")
	)
	(gr_arc
		(start 381.0508 -112.231424)
		(mid 380.873509 -112.405718)
		(end 380.80315 -112.644174)
		(stroke
			(width 0.04445)
			(type default)
		)
		(layer "In2.Cu")
	)
	(gr_arc
		(start 381.0508 -112.231424)
		(mid 381.228102 -112.057135)
		(end 381.29845 -111.818674)
		(stroke
			(width 0.04445)
			(type default)
		)
		(layer "In2.Cu")
	)
	(gr_arc
		(start 381.053848 -113.985802)
		(mid 380.915517 -114.093073)
		(end 380.81966 -114.239548)
		(stroke
			(width 0.04445)
			(type default)
		)
		(layer "In2.Cu")
	)
	(gr_arc
		(start 381.053848 -113.985802)
		(mid 381.201287 -113.868561)
		(end 381.29845 -113.707164)
		(stroke
			(width 0.04445)
			(type default)
		)
		(layer "In2.Cu")
	)
	(gr_arc
		(start 381.057658 -129.257806)
		(mid 381.032896 -129.294865)
		(end 381.02413 -129.338578)
		(stroke
			(width 0.05715)
			(type default)
		)
		(layer "In2.Cu")
	)
	(gr_line
		(start 381.057658 -129.257806)
		(end 381.222758 -129.092706)
		(stroke
			(width 0.05715)
			(type default)
		)
		(layer "In2.Cu")
	)
	(gr_arc
		(start 381.061468 -131.19989)
		(mid 381.036706 -131.236949)
		(end 381.02794 -131.280662)
		(stroke
			(width 0.05715)
			(type default)
		)
		(layer "In2.Cu")
	)
	(gr_line
		(start 381.061468 -131.19989)
		(end 381.16637 -131.094988)
		(stroke
			(width 0.05715)
			(type default)
		)
		(layer "In2.Cu")
	)
	(gr_line
		(start 381.068834 -120.98782)
		(end 381.149352 -120.876314)
		(stroke
			(width 0.04445)
			(type default)
		)
		(layer "In2.Cu")
	)
	(gr_line
		(start 381.068834 -120.98782)
		(end 381.25273 -121.238772)
		(stroke
			(width 0.04445)
			(type default)
		)
		(layer "In2.Cu")
	)
	(gr_arc
		(start 381.098552 -121.592594)
		(mid 380.803317 -121.513397)
		(end 380.508002 -121.59234)
		(stroke
			(width 0.04445)
			(type default)
		)
		(layer "In2.Cu")
	)
	(gr_arc
		(start 381.098552 -121.592594)
		(mid 381.298594 -121.64622)
		(end 381.498602 -121.592594)
		(stroke
			(width 0.04445)
			(type default)
		)
		(layer "In2.Cu")
	)
	(gr_line
		(start 381.184658 -139.784836)
		(end 381.214122 -139.8143)
		(stroke
			(width 0.05715)
			(type default)
		)
		(layer "In2.Cu")
	)
	(gr_line
		(start 381.25273 -121.238772)
		(end 381.29845 -121.245884)
		(stroke
			(width 0.04445)
			(type default)
		)
		(layer "In2.Cu")
	)
	(gr_line
		(start 381.297942 -115.259612)
		(end 381.29845 -115.248944)
		(stroke
			(width 0.04445)
			(type default)
		)
		(layer "In2.Cu")
	)
	(gr_arc
		(start 381.29845 -116.936774)
		(mid 381.228102 -116.698313)
		(end 381.0508 -116.524024)
		(stroke
			(width 0.04445)
			(type default)
		)
		(layer "In2.Cu")
	)
	(gr_arc
		(start 381.29845 -116.936774)
		(mid 381.396062 -117.215924)
		(end 381.566674 -117.457474)
		(stroke
			(width 0.04445)
			(type default)
		)
		(layer "In2.Cu")
	)
	(gr_arc
		(start 381.29845 -115.248944)
		(mid 381.274729 -115.083992)
		(end 381.197612 -114.93627)
		(stroke
			(width 0.04445)
			(type default)
		)
		(layer "In2.Cu")
	)
	(gr_arc
		(start 381.29845 -113.502694)
		(mid 381.228102 -113.264233)
		(end 381.0508 -113.089944)
		(stroke
			(width 0.04445)
			(type default)
		)
		(layer "In2.Cu")
	)
	(gr_line
		(start 381.29845 -113.502694)
		(end 381.29845 -113.707164)
		(stroke
			(width 0.04445)
			(type default)
		)
		(layer "In2.Cu")
	)
	(gr_line
		(start 381.29845 -111.785654)
		(end 381.29845 -111.818674)
		(stroke
			(width 0.04445)
			(type default)
		)
		(layer "In2.Cu")
	)
	(gr_line
		(start 381.352806 -1.674876)
		(end 381.371856 -1.671066)
		(stroke
			(width 0.05715)
			(type default)
		)
		(layer "In2.Cu")
	)
	(gr_line
		(start 381.364744 -3.241548)
		(end 381.381 -3.23088)
		(stroke
			(width 0.05715)
			(type default)
		)
		(layer "In2.Cu")
	)
	(gr_line
		(start 381.371856 -1.671066)
		(end 381.390906 -1.674876)
		(stroke
			(width 0.05715)
			(type default)
		)
		(layer "In2.Cu")
	)
	(gr_line
		(start 381.381 -3.23088)
		(end 381.40005 -3.22707)
		(stroke
			(width 0.05715)
			(type default)
		)
		(layer "In2.Cu")
	)
	(gr_arc
		(start 381.498602 -121.592594)
		(mid 381.64149 -121.452439)
		(end 381.6985 -121.260616)
		(stroke
			(width 0.04445)
			(type default)
		)
		(layer "In2.Cu")
	)
	(gr_arc
		(start 381.498602 -120.899428)
		(mid 381.327648 -120.846835)
		(end 381.150876 -120.874028)
		(stroke
			(width 0.04445)
			(type default)
		)
		(layer "In2.Cu")
	)
	(gr_line
		(start 381.541782 -4.009898)
		(end 381.558038 -3.99923)
		(stroke
			(width 0.05715)
			(type default)
		)
		(layer "In2.Cu")
	)
	(gr_arc
		(start 381.5461 -111.372904)
		(mid 381.368802 -111.547196)
		(end 381.29845 -111.785654)
		(stroke
			(width 0.04445)
			(type default)
		)
		(layer "In2.Cu")
	)
	(gr_line
		(start 381.5461 -111.372904)
		(end 381.84963 -111.024162)
		(stroke
			(width 0.04445)
			(type default)
		)
		(layer "In2.Cu")
	)
	(gr_line
		(start 381.558038 -3.99923)
		(end 381.577088 -3.99542)
		(stroke
			(width 0.05715)
			(type default)
		)
		(layer "In2.Cu")
	)
	(gr_arc
		(start 381.593852 -121.757694)
		(mid 381.804716 -121.55069)
		(end 381.889 -121.267474)
		(stroke
			(width 0.04445)
			(type default)
		)
		(layer "In2.Cu")
	)
	(gr_arc
		(start 381.593852 -120.734074)
		(mid 381.331196 -120.655737)
		(end 381.061468 -120.704356)
		(stroke
			(width 0.04445)
			(type default)
		)
		(layer "In2.Cu")
	)
	(gr_line
		(start 381.66675 -123.761246)
		(end 381.66675 -123.939808)
		(stroke
			(width 0.0635)
			(type default)
		)
		(layer "In2.Cu")
	)
	(gr_line
		(start 381.66675 -123.739148)
		(end 381.66675 -123.761246)
		(stroke
			(width 0.04445)
			(type default)
		)
		(layer "In2.Cu")
	)
	(gr_line
		(start 381.66675 -123.739148)
		(end 381.6985 -123.707398)
		(stroke
			(width 0.04445)
			(type default)
		)
		(layer "In2.Cu")
	)
	(gr_line
		(start 381.6985 -122.941334)
		(end 381.6985 -123.707398)
		(stroke
			(width 0.04445)
			(type default)
		)
		(layer "In2.Cu")
	)
	(gr_arc
		(start 381.6985 -121.260616)
		(mid 381.698762 -121.246011)
		(end 381.6985 -121.231406)
		(stroke
			(width 0.04445)
			(type default)
		)
		(layer "In2.Cu")
	)
	(gr_arc
		(start 381.6985 -121.231406)
		(mid 381.641369 -121.039656)
		(end 381.498602 -120.899428)
		(stroke
			(width 0.04445)
			(type default)
		)
		(layer "In2.Cu")
	)
	(gr_line
		(start 381.6985 -119.507254)
		(end 381.6985 -119.550434)
		(stroke
			(width 0.04445)
			(type default)
		)
		(layer "In2.Cu")
	)
	(gr_arc
		(start 381.6985 -117.790214)
		(mid 381.664346 -117.61126)
		(end 381.566674 -117.457474)
		(stroke
			(width 0.04445)
			(type default)
		)
		(layer "In2.Cu")
	)
	(gr_line
		(start 381.6985 -117.790214)
		(end 381.6985 -117.833394)
		(stroke
			(width 0.04445)
			(type default)
		)
		(layer "In2.Cu")
	)
	(gr_line
		(start 381.84963 -110.81639)
		(end 381.84963 -111.024162)
		(stroke
			(width 0.04445)
			(type default)
		)
		(layer "In2.Cu")
	)
	(gr_line
		(start 381.84963 -110.81639)
		(end 382.27 -110.39602)
		(stroke
			(width 0.04445)
			(type default)
		)
		(layer "In2.Cu")
	)
	(gr_line
		(start 381.889 -123.707398)
		(end 381.92075 -123.739148)
		(stroke
			(width 0.04445)
			(type default)
		)
		(layer "In2.Cu")
	)
	(gr_line
		(start 381.889 -122.951748)
		(end 381.889 -123.707398)
		(stroke
			(width 0.04445)
			(type default)
		)
		(layer "In2.Cu")
	)
	(gr_arc
		(start 381.889 -121.224294)
		(mid 381.804719 -120.941077)
		(end 381.593852 -120.734074)
		(stroke
			(width 0.04445)
			(type default)
		)
		(layer "In2.Cu")
	)
	(gr_line
		(start 381.889 -121.224294)
		(end 381.889 -121.267474)
		(stroke
			(width 0.04445)
			(type default)
		)
		(layer "In2.Cu")
	)
	(gr_line
		(start 381.889 -117.800628)
		(end 381.889 -117.82298)
		(stroke
			(width 0.04445)
			(type default)
		)
		(layer "In2.Cu")
	)
	(gr_line
		(start 381.92075 -123.761246)
		(end 381.92075 -123.939808)
		(stroke
			(width 0.0635)
			(type default)
		)
		(layer "In2.Cu")
	)
	(gr_line
		(start 381.92075 -123.739148)
		(end 381.92075 -123.761246)
		(stroke
			(width 0.04445)
			(type default)
		)
		(layer "In2.Cu")
	)
	(gr_arc
		(start 382.094994 -117.441472)
		(mid 381.944166 -117.593612)
		(end 381.889 -117.800628)
		(stroke
			(width 0.04445)
			(type default)
		)
		(layer "In2.Cu")
	)
	(gr_arc
		(start 382.094994 -117.441472)
		(mid 382.300063 -117.239619)
		(end 382.3843 -116.96446)
		(stroke
			(width 0.04445)
			(type default)
		)
		(layer "In2.Cu")
	)
	(gr_line
		(start 382.1938 -122.082814)
		(end 382.1938 -122.11558)
		(stroke
			(width 0.04445)
			(type default)
		)
		(layer "In2.Cu")
	)
	(gr_line
		(start 382.1938 -120.376188)
		(end 382.1938 -120.408954)
		(stroke
			(width 0.04445)
			(type default)
		)
		(layer "In2.Cu")
	)
	(gr_arc
		(start 382.20904 -133.965696)
		(mid 382.300837 -133.942928)
		(end 382.37414 -133.883146)
		(stroke
			(width 0.05715)
			(type default)
		)
		(layer "In2.Cu")
	)
	(gr_line
		(start 382.27 -110.39602)
		(end 382.387348 -110.39602)
		(stroke
			(width 0.04445)
			(type default)
		)
		(layer "In2.Cu")
	)
	(gr_line
		(start 382.3843 -122.093228)
		(end 382.3843 -122.125994)
		(stroke
			(width 0.04445)
			(type default)
		)
		(layer "In2.Cu")
	)
	(gr_line
		(start 382.3843 -120.365774)
		(end 382.3843 -120.39854)
		(stroke
			(width 0.04445)
			(type default)
		)
		(layer "In2.Cu")
	)
	(gr_line
		(start 382.3843 -118.648734)
		(end 382.3843 -118.691914)
		(stroke
			(width 0.04445)
			(type default)
		)
		(layer "In2.Cu")
	)
	(gr_line
		(start 382.3843 -116.942108)
		(end 382.3843 -116.96446)
		(stroke
			(width 0.04445)
			(type default)
		)
		(layer "In2.Cu")
	)
	(gr_arc
		(start 382.393444 -137.04062)
		(mid 382.485241 -137.017852)
		(end 382.558544 -136.95807)
		(stroke
			(width 0.05715)
			(type default)
		)
		(layer "In2.Cu")
	)
	(gr_line
		(start 382.50368 -134.257796)
		(end 382.9177 -134.257796)
		(stroke
			(width 0.05715)
			(type default)
		)
		(layer "In2.Cu")
	)
	(gr_arc
		(start 382.53924 -133.800596)
		(mid 382.447415 -133.823322)
		(end 382.37414 -133.883146)
		(stroke
			(width 0.05715)
			(type default)
		)
		(layer "In2.Cu")
	)
	(gr_line
		(start 382.53924 -133.800596)
		(end 382.88214 -133.800596)
		(stroke
			(width 0.05715)
			(type default)
		)
		(layer "In2.Cu")
	)
	(gr_line
		(start 382.57734 -3.795268)
		(end 382.59639 -3.791458)
		(stroke
			(width 0.05715)
			(type default)
		)
		(layer "In2.Cu")
	)
	(gr_arc
		(start 382.584452 -116.606574)
		(mid 382.44066 -116.748262)
		(end 382.3843 -116.942108)
		(stroke
			(width 0.04445)
			(type default)
		)
		(layer "In2.Cu")
	)
	(gr_arc
		(start 382.584452 -116.606574)
		(mid 382.76329 -116.42772)
		(end 382.8288 -116.18341)
		(stroke
			(width 0.04445)
			(type default)
		)
		(layer "In2.Cu")
	)
	(gr_line
		(start 382.59639 -3.791458)
		(end 382.61544 -3.795268)
		(stroke
			(width 0.05715)
			(type default)
		)
		(layer "In2.Cu")
	)
	(gr_line
		(start 382.600454 -6.062218)
		(end 382.600708 -6.062218)
		(stroke
			(width 0.05715)
			(type default)
		)
		(layer "In2.Cu")
	)
	(gr_line
		(start 382.688084 -137.33272)
		(end 383.102104 -137.33272)
		(stroke
			(width 0.05715)
			(type default)
		)
		(layer "In2.Cu")
	)
	(gr_line
		(start 382.708658 -2.965196)
		(end 382.727708 -2.961386)
		(stroke
			(width 0.05715)
			(type default)
		)
		(layer "In2.Cu")
	)
	(gr_arc
		(start 382.723644 -136.87552)
		(mid 382.63182 -136.898246)
		(end 382.558544 -136.95807)
		(stroke
			(width 0.05715)
			(type default)
		)
		(layer "In2.Cu")
	)
	(gr_line
		(start 382.723644 -136.87552)
		(end 383.066544 -136.87552)
		(stroke
			(width 0.05715)
			(type default)
		)
		(layer "In2.Cu")
	)
	(gr_line
		(start 382.727708 -2.961386)
		(end 382.746758 -2.965196)
		(stroke
			(width 0.05715)
			(type default)
		)
		(layer "In2.Cu")
	)
	(gr_line
		(start 382.8288 -115.154456)
		(end 382.8288 -116.18341)
		(stroke
			(width 0.04445)
			(type default)
		)
		(layer "In2.Cu")
	)
	(gr_line
		(start 382.8288 -115.154456)
		(end 383.097278 -114.885978)
		(stroke
			(width 0.04445)
			(type default)
		)
		(layer "In2.Cu")
	)
	(gr_line
		(start 382.8796 -121.224294)
		(end 382.8796 -121.267474)
		(stroke
			(width 0.04445)
			(type default)
		)
		(layer "In2.Cu")
	)
	(gr_line
		(start 382.88087 -131.59105)
		(end 382.88087 -131.61137)
		(stroke
			(width 0.05715)
			(type default)
		)
		(layer "In2.Cu")
	)
	(gr_line
		(start 382.88087 -131.59105)
		(end 383.12725 -131.34467)
		(stroke
			(width 0.05715)
			(type default)
		)
		(layer "In2.Cu")
	)
	(gr_arc
		(start 382.914652 -130.04292)
		(mid 382.878155 -129.859399)
		(end 382.77419 -129.70383)
		(stroke
			(width 0.05715)
			(type default)
		)
		(layer "In2.Cu")
	)
	(gr_arc
		(start 383.04724 -133.883146)
		(mid 382.973934 -133.823397)
		(end 382.88214 -133.800596)
		(stroke
			(width 0.05715)
			(type default)
		)
		(layer "In2.Cu")
	)
	(gr_arc
		(start 383.04724 -133.883146)
		(mid 383.120521 -133.942972)
		(end 383.21234 -133.965696)
		(stroke
			(width 0.05715)
			(type default)
		)
		(layer "In2.Cu")
	)
	(gr_line
		(start 383.097278 -113.953544)
		(end 383.097278 -114.885978)
		(stroke
			(width 0.04445)
			(type default)
		)
		(layer "In2.Cu")
	)
	(gr_line
		(start 383.097278 -113.953544)
		(end 383.735326 -113.315496)
		(stroke
			(width 0.04445)
			(type default)
		)
		(layer "In2.Cu")
	)
	(gr_line
		(start 383.191004 -127.771652)
		(end 383.30886 -127.889508)
		(stroke
			(width 0.05715)
			(type default)
		)
		(layer "In2.Cu")
	)
	(gr_arc
		(start 383.231644 -136.95807)
		(mid 383.158341 -136.898313)
		(end 383.066544 -136.87552)
		(stroke
			(width 0.05715)
			(type default)
		)
		(layer "In2.Cu")
	)
	(gr_arc
		(start 383.231644 -136.95807)
		(mid 383.304925 -137.017896)
		(end 383.396744 -137.04062)
		(stroke
			(width 0.05715)
			(type default)
		)
		(layer "In2.Cu")
	)
	(gr_arc
		(start 383.27203 -129.866136)
		(mid 383.22368 -129.938637)
		(end 383.206752 -130.024124)
		(stroke
			(width 0.05715)
			(type default)
		)
		(layer "In2.Cu")
	)
	(gr_line
		(start 383.27203 -129.866136)
		(end 383.43459 -129.70383)
		(stroke
			(width 0.05715)
			(type default)
		)
		(layer "In2.Cu")
	)
	(gr_arc
		(start 383.350008 -127.989076)
		(mid 383.339312 -127.935212)
		(end 383.30886 -127.889508)
		(stroke
			(width 0.05715)
			(type default)
		)
		(layer "In2.Cu")
	)
	(gr_line
		(start 383.54127 -131.59105)
		(end 383.54127 -131.61137)
		(stroke
			(width 0.05715)
			(type default)
		)
		(layer "In2.Cu")
	)
	(gr_line
		(start 383.54127 -131.59105)
		(end 383.755392 -131.376928)
		(stroke
			(width 0.05715)
			(type default)
		)
		(layer "In2.Cu")
	)
	(gr_arc
		(start 383.67462 -127.923036)
		(mid 383.650623 -127.958935)
		(end 383.642108 -128.001268)
		(stroke
			(width 0.05715)
			(type default)
		)
		(layer "In2.Cu")
	)
	(gr_line
		(start 383.67462 -127.923036)
		(end 383.826004 -127.771652)
		(stroke
			(width 0.05715)
			(type default)
		)
		(layer "In2.Cu")
	)
	(gr_line
		(start 383.735326 -110.395258)
		(end 383.735326 -113.315496)
		(stroke
			(width 0.04445)
			(type default)
		)
		(layer "In2.Cu")
	)
	(gr_line
		(start 383.735326 -110.395258)
		(end 384.24993 -109.880654)
		(stroke
			(width 0.04445)
			(type default)
		)
		(layer "In2.Cu")
	)
	(gr_arc
		(start 383.766822 -133.965696)
		(mid 383.858619 -133.942928)
		(end 383.931922 -133.883146)
		(stroke
			(width 0.05715)
			(type default)
		)
		(layer "In2.Cu")
	)
	(gr_arc
		(start 383.836418 -131.3434)
		(mid 383.79258 -131.35212)
		(end 383.755392 -131.376928)
		(stroke
			(width 0.05715)
			(type default)
		)
		(layer "In2.Cu")
	)
	(gr_arc
		(start 383.836418 -131.0513)
		(mid 383.452645 -131.12741)
		(end 383.12725 -131.34467)
		(stroke
			(width 0.05715)
			(type default)
		)
		(layer "In2.Cu")
	)
	(gr_arc
		(start 383.986532 -130.247136)
		(mid 384.033272 -130.237821)
		(end 384.072892 -130.211322)
		(stroke
			(width 0.05715)
			(type default)
		)
		(layer "In2.Cu")
	)
	(gr_line
		(start 384.061462 -134.257796)
		(end 384.475482 -134.257796)
		(stroke
			(width 0.05715)
			(type default)
		)
		(layer "In2.Cu")
	)
	(gr_line
		(start 384.072892 -130.211322)
		(end 384.08864 -130.195574)
		(stroke
			(width 0.05715)
			(type default)
		)
		(layer "In2.Cu")
	)
	(gr_arc
		(start 384.097022 -133.800596)
		(mid 384.005202 -133.823328)
		(end 383.931922 -133.883146)
		(stroke
			(width 0.05715)
			(type default)
		)
		(layer "In2.Cu")
	)
	(gr_line
		(start 384.097022 -133.800596)
		(end 384.439922 -133.800596)
		(stroke
			(width 0.05715)
			(type default)
		)
		(layer "In2.Cu")
	)
	(gr_arc
		(start 384.175 -130.15976)
		(mid 384.128249 -130.169053)
		(end 384.08864 -130.195574)
		(stroke
			(width 0.05715)
			(type default)
		)
		(layer "In2.Cu")
	)
	(gr_line
		(start 384.175 -130.15976)
		(end 384.416808 -130.15976)
		(stroke
			(width 0.05715)
			(type default)
		)
		(layer "In2.Cu")
	)
	(gr_line
		(start 384.24993 -109.880654)
		(end 386.849874 -109.880654)
		(stroke
			(width 0.04445)
			(type default)
		)
		(layer "In2.Cu")
	)
	(gr_line
		(start 384.279394 -4.906772)
		(end 384.335782 -4.878832)
		(stroke
			(width 0.05715)
			(type default)
		)
		(layer "In2.Cu")
	)
	(gr_line
		(start 384.281172 -130.539236)
		(end 384.310636 -130.539236)
		(stroke
			(width 0.05715)
			(type default)
		)
		(layer "In2.Cu")
	)
	(gr_line
		(start 384.335782 -4.878832)
		(end 384.39852 -4.891278)
		(stroke
			(width 0.05715)
			(type default)
		)
		(layer "In2.Cu")
	)
	(gr_arc
		(start 384.503168 -130.195574)
		(mid 384.463548 -130.169089)
		(end 384.416808 -130.15976)
		(stroke
			(width 0.05715)
			(type default)
		)
		(layer "In2.Cu")
	)
	(gr_line
		(start 384.503168 -130.195574)
		(end 384.518916 -130.211322)
		(stroke
			(width 0.05715)
			(type default)
		)
		(layer "In2.Cu")
	)
	(gr_arc
		(start 384.518916 -130.211322)
		(mid 384.558524 -130.237851)
		(end 384.605276 -130.247136)
		(stroke
			(width 0.05715)
			(type default)
		)
		(layer "In2.Cu")
	)
	(gr_arc
		(start 384.605022 -133.883146)
		(mid 384.531722 -133.823369)
		(end 384.439922 -133.800596)
		(stroke
			(width 0.05715)
			(type default)
		)
		(layer "In2.Cu")
	)
	(gr_arc
		(start 384.605022 -133.883146)
		(mid 384.678303 -133.942972)
		(end 384.770122 -133.965696)
		(stroke
			(width 0.05715)
			(type default)
		)
		(layer "In2.Cu")
	)
	(gr_line
		(start 384.946144 -5.298948)
		(end 384.978656 -5.305552)
		(stroke
			(width 0.05715)
			(type default)
		)
		(layer "In2.Cu")
	)
	(gr_line
		(start 384.978656 -5.305552)
		(end 385.010914 -5.296408)
		(stroke
			(width 0.05715)
			(type default)
		)
		(layer "In2.Cu")
	)
	(gr_line
		(start 385.103624 -4.590796)
		(end 385.136136 -4.5974)
		(stroke
			(width 0.05715)
			(type default)
		)
		(layer "In2.Cu")
	)
	(gr_line
		(start 385.136136 -4.5974)
		(end 385.168394 -4.588256)
		(stroke
			(width 0.05715)
			(type default)
		)
		(layer "In2.Cu")
	)
	(gr_line
		(start 385.49834 -3.813556)
		(end 385.530852 -3.82016)
		(stroke
			(width 0.05715)
			(type default)
		)
		(layer "In2.Cu")
	)
	(gr_line
		(start 385.530852 -3.82016)
		(end 385.56311 -3.811016)
		(stroke
			(width 0.05715)
			(type default)
		)
		(layer "In2.Cu")
	)
	(gr_arc
		(start 385.632706 -139.720066)
		(mid 385.724503 -139.697298)
		(end 385.797806 -139.637516)
		(stroke
			(width 0.05715)
			(type default)
		)
		(layer "In2.Cu")
	)
	(gr_arc
		(start 385.877816 -136.190228)
		(mid 385.958881 -136.239145)
		(end 386.053076 -136.248648)
		(stroke
			(width 0.05715)
			(type default)
		)
		(layer "In2.Cu")
	)
	(gr_line
		(start 385.87934 -136.605264)
		(end 386.172202 -136.898126)
		(stroke
			(width 0.05715)
			(type default)
		)
		(layer "In2.Cu")
	)
	(gr_line
		(start 385.927346 -140.012166)
		(end 386.341366 -140.012166)
		(stroke
			(width 0.05715)
			(type default)
		)
		(layer "In2.Cu")
	)
	(gr_arc
		(start 385.962906 -139.554966)
		(mid 385.871088 -139.577701)
		(end 385.797806 -139.637516)
		(stroke
			(width 0.05715)
			(type default)
		)
		(layer "In2.Cu")
	)
	(gr_line
		(start 385.962906 -139.554966)
		(end 386.305806 -139.554966)
		(stroke
			(width 0.05715)
			(type default)
		)
		(layer "In2.Cu")
	)
	(gr_arc
		(start 386.188204 -133.618478)
		(mid 386.269185 -133.667187)
		(end 386.36321 -133.676644)
		(stroke
			(width 0.05715)
			(type default)
		)
		(layer "In2.Cu")
	)
	(gr_line
		(start 386.189728 -134.033514)
		(end 386.48259 -134.326376)
		(stroke
			(width 0.05715)
			(type default)
		)
		(layer "In2.Cu")
	)
	(gr_arc
		(start 386.228082 -136.307068)
		(mid 386.147135 -136.258209)
		(end 386.053076 -136.248648)
		(stroke
			(width 0.05715)
			(type default)
		)
		(layer "In2.Cu")
	)
	(gr_line
		(start 386.228082 -136.307068)
		(end 386.470652 -136.549638)
		(stroke
			(width 0.05715)
			(type default)
		)
		(layer "In2.Cu")
	)
	(gr_arc
		(start 386.470906 -139.637516)
		(mid 386.397611 -139.577726)
		(end 386.305806 -139.554966)
		(stroke
			(width 0.05715)
			(type default)
		)
		(layer "In2.Cu")
	)
	(gr_arc
		(start 386.470906 -139.637516)
		(mid 386.544187 -139.697342)
		(end 386.636006 -139.720066)
		(stroke
			(width 0.05715)
			(type default)
		)
		(layer "In2.Cu")
	)
	(gr_arc
		(start 386.529072 -136.724644)
		(mid 386.519482 -136.630595)
		(end 386.470652 -136.549638)
		(stroke
			(width 0.05715)
			(type default)
		)
		(layer "In2.Cu")
	)
	(gr_arc
		(start 386.529072 -136.724644)
		(mid 386.53852 -136.818675)
		(end 386.587238 -136.89965)
		(stroke
			(width 0.05715)
			(type default)
		)
		(layer "In2.Cu")
	)
	(gr_arc
		(start 386.538216 -133.735064)
		(mid 386.457263 -133.686221)
		(end 386.36321 -133.676644)
		(stroke
			(width 0.05715)
			(type default)
		)
		(layer "In2.Cu")
	)
	(gr_line
		(start 386.538216 -133.735064)
		(end 386.780786 -133.977634)
		(stroke
			(width 0.05715)
			(type default)
		)
		(layer "In2.Cu")
	)
	(gr_arc
		(start 386.829808 -137.14222)
		(mid 386.910872 -137.191142)
		(end 387.005068 -137.20064)
		(stroke
			(width 0.05715)
			(type default)
		)
		(layer "In2.Cu")
	)
	(gr_line
		(start 386.831332 -137.557256)
		(end 387.124194 -137.850118)
		(stroke
			(width 0.05715)
			(type default)
		)
		(layer "In2.Cu")
	)
	(gr_line
		(start 386.833872 -2.427478)
		(end 386.852922 -2.431288)
		(stroke
			(width 0.05715)
			(type default)
		)
		(layer "In2.Cu")
	)
	(gr_arc
		(start 386.839206 -134.15264)
		(mid 386.829644 -134.058579)
		(end 386.780786 -133.977634)
		(stroke
			(width 0.05715)
			(type default)
		)
		(layer "In2.Cu")
	)
	(gr_arc
		(start 386.839206 -134.15264)
		(mid 386.848727 -134.246833)
		(end 386.897626 -134.3279)
		(stroke
			(width 0.05715)
			(type default)
		)
		(layer "In2.Cu")
	)
	(gr_line
		(start 386.849874 -109.880654)
		(end 387.3373 -109.393228)
		(stroke
			(width 0.04445)
			(type default)
		)
		(layer "In2.Cu")
	)
	(gr_line
		(start 386.852922 -2.431288)
		(end 386.871972 -2.427478)
		(stroke
			(width 0.05715)
			(type default)
		)
		(layer "In2.Cu")
	)
	(gr_arc
		(start 387.140196 -134.57047)
		(mid 387.221177 -134.619179)
		(end 387.315202 -134.628636)
		(stroke
			(width 0.05715)
			(type default)
		)
		(layer "In2.Cu")
	)
	(gr_line
		(start 387.14172 -134.985506)
		(end 387.434582 -135.278368)
		(stroke
			(width 0.05715)
			(type default)
		)
		(layer "In2.Cu")
	)
	(gr_arc
		(start 387.180074 -137.25906)
		(mid 387.099127 -137.210201)
		(end 387.005068 -137.20064)
		(stroke
			(width 0.05715)
			(type default)
		)
		(layer "In2.Cu")
	)
	(gr_line
		(start 387.180074 -137.25906)
		(end 387.422644 -137.50163)
		(stroke
			(width 0.05715)
			(type default)
		)
		(layer "In2.Cu")
	)
	(gr_line
		(start 387.3373 -109.0549)
		(end 387.3373 -109.393228)
		(stroke
			(width 0.04445)
			(type default)
		)
		(layer "In2.Cu")
	)
	(gr_line
		(start 387.46303 -2.143506)
		(end 387.48208 -2.139696)
		(stroke
			(width 0.05715)
			(type default)
		)
		(layer "In2.Cu")
	)
	(gr_arc
		(start 387.481064 -137.676636)
		(mid 387.471474 -137.582587)
		(end 387.422644 -137.50163)
		(stroke
			(width 0.05715)
			(type default)
		)
		(layer "In2.Cu")
	)
	(gr_arc
		(start 387.481064 -137.676636)
		(mid 387.490508 -137.770669)
		(end 387.53923 -137.851642)
		(stroke
			(width 0.05715)
			(type default)
		)
		(layer "In2.Cu")
	)
	(gr_line
		(start 387.48208 -2.139696)
		(end 387.50113 -2.143506)
		(stroke
			(width 0.05715)
			(type default)
		)
		(layer "In2.Cu")
	)
	(gr_arc
		(start 387.490208 -134.687056)
		(mid 387.409254 -134.638218)
		(end 387.315202 -134.628636)
		(stroke
			(width 0.05715)
			(type default)
		)
		(layer "In2.Cu")
	)
	(gr_line
		(start 387.490208 -134.687056)
		(end 387.732778 -134.929626)
		(stroke
			(width 0.05715)
			(type default)
		)
		(layer "In2.Cu")
	)
	(gr_line
		(start 387.696456 -4.225036)
		(end 387.730492 -4.215384)
		(stroke
			(width 0.05715)
			(type default)
		)
		(layer "In2.Cu")
	)
	(gr_line
		(start 387.730492 -4.215384)
		(end 387.764782 -4.22275)
		(stroke
			(width 0.05715)
			(type default)
		)
		(layer "In2.Cu")
	)
	(gr_line
		(start 387.77037 -2.876296)
		(end 387.804406 -2.866644)
		(stroke
			(width 0.05715)
			(type default)
		)
		(layer "In2.Cu")
	)
	(gr_line
		(start 387.780276 -3.537712)
		(end 387.814312 -3.52806)
		(stroke
			(width 0.05715)
			(type default)
		)
		(layer "In2.Cu")
	)
	(gr_arc
		(start 387.791198 -135.104632)
		(mid 387.781632 -135.010573)
		(end 387.732778 -134.929626)
		(stroke
			(width 0.05715)
			(type default)
		)
		(layer "In2.Cu")
	)
	(gr_arc
		(start 387.791198 -135.104632)
		(mid 387.800719 -135.198825)
		(end 387.849618 -135.279892)
		(stroke
			(width 0.05715)
			(type default)
		)
		(layer "In2.Cu")
	)
	(gr_line
		(start 387.804406 -2.866644)
		(end 387.838696 -2.87401)
		(stroke
			(width 0.05715)
			(type default)
		)
		(layer "In2.Cu")
	)
	(gr_line
		(start 387.814312 -3.52806)
		(end 387.848602 -3.535426)
		(stroke
			(width 0.05715)
			(type default)
		)
		(layer "In2.Cu")
	)
	(gr_line
		(start 388.239762 -2.319528)
		(end 388.262622 -2.3241)
		(stroke
			(width 0.05715)
			(type default)
		)
		(layer "In2.Cu")
	)
	(gr_line
		(start 388.262622 -2.3241)
		(end 388.285482 -2.319274)
		(stroke
			(width 0.05715)
			(type default)
		)
		(layer "In2.Cu")
	)
	(gr_line
		(start 388.809484 -10.286492)
		(end 388.832598 -10.281412)
		(stroke
			(width 0.05715)
			(type default)
		)
		(layer "In2.Cu")
	)
	(gr_line
		(start 388.831836 -15.680436)
		(end 388.85495 -15.675356)
		(stroke
			(width 0.05715)
			(type default)
		)
		(layer "In2.Cu")
	)
	(gr_line
		(start 388.832598 -10.281412)
		(end 388.855712 -10.286492)
		(stroke
			(width 0.05715)
			(type default)
		)
		(layer "In2.Cu")
	)
	(gr_line
		(start 388.850124 -11.598656)
		(end 388.873238 -11.593576)
		(stroke
			(width 0.05715)
			(type default)
		)
		(layer "In2.Cu")
	)
	(gr_line
		(start 388.85495 -15.675356)
		(end 388.878064 -15.680436)
		(stroke
			(width 0.05715)
			(type default)
		)
		(layer "In2.Cu")
	)
	(gr_line
		(start 388.855712 -10.948162)
		(end 388.878826 -10.943082)
		(stroke
			(width 0.05715)
			(type default)
		)
		(layer "In2.Cu")
	)
	(gr_line
		(start 388.870698 -12.254738)
		(end 388.893812 -12.249658)
		(stroke
			(width 0.05715)
			(type default)
		)
		(layer "In2.Cu")
	)
	(gr_line
		(start 388.870952 -12.906502)
		(end 388.894066 -12.901422)
		(stroke
			(width 0.05715)
			(type default)
		)
		(layer "In2.Cu")
	)
	(gr_line
		(start 388.873238 -11.593576)
		(end 388.896352 -11.598656)
		(stroke
			(width 0.05715)
			(type default)
		)
		(layer "In2.Cu")
	)
	(gr_line
		(start 388.877048 -13.559536)
		(end 388.900162 -13.554456)
		(stroke
			(width 0.05715)
			(type default)
		)
		(layer "In2.Cu")
	)
	(gr_line
		(start 388.878826 -10.943082)
		(end 388.90194 -10.948162)
		(stroke
			(width 0.05715)
			(type default)
		)
		(layer "In2.Cu")
	)
	(gr_line
		(start 388.880858 -14.86408)
		(end 388.903972 -14.859)
		(stroke
			(width 0.05715)
			(type default)
		)
		(layer "In2.Cu")
	)
	(gr_line
		(start 388.887208 -14.213332)
		(end 388.910322 -14.208252)
		(stroke
			(width 0.05715)
			(type default)
		)
		(layer "In2.Cu")
	)
	(gr_line
		(start 388.893812 -12.249658)
		(end 388.916926 -12.254738)
		(stroke
			(width 0.05715)
			(type default)
		)
		(layer "In2.Cu")
	)
	(gr_line
		(start 388.894066 -12.901422)
		(end 388.91718 -12.906502)
		(stroke
			(width 0.05715)
			(type default)
		)
		(layer "In2.Cu")
	)
	(gr_line
		(start 388.900162 -13.554456)
		(end 388.923276 -13.559536)
		(stroke
			(width 0.05715)
			(type default)
		)
		(layer "In2.Cu")
	)
	(gr_line
		(start 388.903972 -14.859)
		(end 388.927086 -14.86408)
		(stroke
			(width 0.05715)
			(type default)
		)
		(layer "In2.Cu")
	)
	(gr_line
		(start 388.910322 -14.208252)
		(end 388.933182 -14.213078)
		(stroke
			(width 0.05715)
			(type default)
		)
		(layer "In2.Cu")
	)
	(gr_arc
		(start 391.197084 -138.12774)
		(mid 391.288906 -138.105009)
		(end 391.362184 -138.04519)
		(stroke
			(width 0.05715)
			(type default)
		)
		(layer "In2.Cu")
	)
	(gr_line
		(start 391.345166 -1.575816)
		(end 391.36828 -1.570736)
		(stroke
			(width 0.05715)
			(type default)
		)
		(layer "In2.Cu")
	)
	(gr_line
		(start 391.36828 -1.570736)
		(end 391.391394 -1.575816)
		(stroke
			(width 0.05715)
			(type default)
		)
		(layer "In2.Cu")
	)
	(gr_line
		(start 391.43178 -16.521176)
		(end 391.454894 -16.526256)
		(stroke
			(width 0.05715)
			(type default)
		)
		(layer "In2.Cu")
	)
	(gr_line
		(start 391.454894 -16.526256)
		(end 391.478008 -16.521176)
		(stroke
			(width 0.05715)
			(type default)
		)
		(layer "In2.Cu")
	)
	(gr_line
		(start 391.465308 -15.051024)
		(end 391.488168 -15.05585)
		(stroke
			(width 0.05715)
			(type default)
		)
		(layer "In2.Cu")
	)
	(gr_line
		(start 391.466578 -14.398752)
		(end 391.489692 -14.403832)
		(stroke
			(width 0.05715)
			(type default)
		)
		(layer "In2.Cu")
	)
	(gr_line
		(start 391.466578 -13.746988)
		(end 391.489692 -13.752068)
		(stroke
			(width 0.05715)
			(type default)
		)
		(layer "In2.Cu")
	)
	(gr_line
		(start 391.466578 -11.791696)
		(end 391.489692 -11.796776)
		(stroke
			(width 0.05715)
			(type default)
		)
		(layer "In2.Cu")
	)
	(gr_line
		(start 391.466578 -11.139932)
		(end 391.489692 -11.145012)
		(stroke
			(width 0.05715)
			(type default)
		)
		(layer "In2.Cu")
	)
	(gr_line
		(start 391.467086 -15.702026)
		(end 391.4902 -15.707106)
		(stroke
			(width 0.05715)
			(type default)
		)
		(layer "In2.Cu")
	)
	(gr_line
		(start 391.46734 -13.095224)
		(end 391.490454 -13.100304)
		(stroke
			(width 0.05715)
			(type default)
		)
		(layer "In2.Cu")
	)
	(gr_line
		(start 391.46734 -12.44346)
		(end 391.490454 -12.44854)
		(stroke
			(width 0.05715)
			(type default)
		)
		(layer "In2.Cu")
	)
	(gr_line
		(start 391.488168 -15.05585)
		(end 391.511282 -15.05077)
		(stroke
			(width 0.05715)
			(type default)
		)
		(layer "In2.Cu")
	)
	(gr_line
		(start 391.489692 -14.403832)
		(end 391.512806 -14.398752)
		(stroke
			(width 0.05715)
			(type default)
		)
		(layer "In2.Cu")
	)
	(gr_line
		(start 391.489692 -13.752068)
		(end 391.512806 -13.746988)
		(stroke
			(width 0.05715)
			(type default)
		)
		(layer "In2.Cu")
	)
	(gr_line
		(start 391.489692 -11.796776)
		(end 391.512806 -11.791696)
		(stroke
			(width 0.05715)
			(type default)
		)
		(layer "In2.Cu")
	)
	(gr_line
		(start 391.489692 -11.145012)
		(end 391.512806 -11.139932)
		(stroke
			(width 0.05715)
			(type default)
		)
		(layer "In2.Cu")
	)
	(gr_line
		(start 391.4902 -15.707106)
		(end 391.513314 -15.702026)
		(stroke
			(width 0.05715)
			(type default)
		)
		(layer "In2.Cu")
	)
	(gr_line
		(start 391.490454 -13.100304)
		(end 391.513568 -13.095224)
		(stroke
			(width 0.05715)
			(type default)
		)
		(layer "In2.Cu")
	)
	(gr_line
		(start 391.490454 -12.44854)
		(end 391.513568 -12.44346)
		(stroke
			(width 0.05715)
			(type default)
		)
		(layer "In2.Cu")
	)
	(gr_line
		(start 391.491724 -138.41984)
		(end 391.905744 -138.41984)
		(stroke
			(width 0.05715)
			(type default)
		)
		(layer "In2.Cu")
	)
	(gr_arc
		(start 391.527284 -137.96264)
		(mid 391.435487 -137.985408)
		(end 391.362184 -138.04519)
		(stroke
			(width 0.05715)
			(type default)
		)
		(layer "In2.Cu")
	)
	(gr_line
		(start 391.527284 -137.96264)
		(end 391.870184 -137.96264)
		(stroke
			(width 0.05715)
			(type default)
		)
		(layer "In2.Cu")
	)
	(gr_line
		(start 392.008614 -16.10995)
		(end 392.59129 -15.986252)
		(stroke
			(width 0.05715)
			(type default)
		)
		(layer "In2.Cu")
	)
	(gr_line
		(start 392.03503 -16.405352)
		(end 392.22807 -16.530574)
		(stroke
			(width 0.05715)
			(type default)
		)
		(layer "In2.Cu")
	)
	(gr_arc
		(start 392.035284 -138.04519)
		(mid 391.962003 -137.985364)
		(end 391.870184 -137.96264)
		(stroke
			(width 0.05715)
			(type default)
		)
		(layer "In2.Cu")
	)
	(gr_arc
		(start 392.035284 -138.04519)
		(mid 392.108579 -138.104982)
		(end 392.200384 -138.12774)
		(stroke
			(width 0.05715)
			(type default)
		)
		(layer "In2.Cu")
	)
	(gr_line
		(start 392.089132 -6.772148)
		(end 392.112246 -6.767068)
		(stroke
			(width 0.05715)
			(type default)
		)
		(layer "In2.Cu")
	)
	(gr_line
		(start 392.112246 -6.767068)
		(end 392.13536 -6.772148)
		(stroke
			(width 0.05715)
			(type default)
		)
		(layer "In2.Cu")
	)
	(gr_line
		(start 392.115294 -7.436866)
		(end 392.138408 -7.431786)
		(stroke
			(width 0.05715)
			(type default)
		)
		(layer "In2.Cu")
	)
	(gr_line
		(start 392.135106 -8.09371)
		(end 392.15822 -8.08863)
		(stroke
			(width 0.05715)
			(type default)
		)
		(layer "In2.Cu")
	)
	(gr_line
		(start 392.138408 -7.431786)
		(end 392.161522 -7.436866)
		(stroke
			(width 0.05715)
			(type default)
		)
		(layer "In2.Cu")
	)
	(gr_line
		(start 392.15822 -8.08863)
		(end 392.181334 -8.09371)
		(stroke
			(width 0.05715)
			(type default)
		)
		(layer "In2.Cu")
	)
	(gr_line
		(start 392.162792 -8.751824)
		(end 392.185906 -8.746744)
		(stroke
			(width 0.05715)
			(type default)
		)
		(layer "In2.Cu")
	)
	(gr_line
		(start 392.185906 -8.746744)
		(end 392.20902 -8.751824)
		(stroke
			(width 0.05715)
			(type default)
		)
		(layer "In2.Cu")
	)
	(gr_line
		(start 392.22807 -16.530574)
		(end 392.563604 -16.459454)
		(stroke
			(width 0.05715)
			(type default)
		)
		(layer "In2.Cu")
	)
	(gr_line
		(start 392.404346 -5.505704)
		(end 392.426952 -5.51053)
		(stroke
			(width 0.05715)
			(type default)
		)
		(layer "In2.Cu")
	)
	(gr_line
		(start 392.4173 -4.145534)
		(end 392.45286 -4.153154)
		(stroke
			(width 0.05715)
			(type default)
		)
		(layer "In2.Cu")
	)
	(gr_line
		(start 392.426952 -5.51053)
		(end 392.45032 -5.50545)
		(stroke
			(width 0.05715)
			(type default)
		)
		(layer "In2.Cu")
	)
	(gr_line
		(start 392.439652 -4.808474)
		(end 392.475466 -4.816094)
		(stroke
			(width 0.05715)
			(type default)
		)
		(layer "In2.Cu")
	)
	(gr_line
		(start 392.45286 -4.153154)
		(end 392.487912 -4.14274)
		(stroke
			(width 0.05715)
			(type default)
		)
		(layer "In2.Cu")
	)
	(gr_line
		(start 392.475466 -4.816094)
		(end 392.510264 -4.805934)
		(stroke
			(width 0.05715)
			(type default)
		)
		(layer "In2.Cu")
	)
	(gr_line
		(start 392.50874 -2.111756)
		(end 392.531854 -2.116836)
		(stroke
			(width 0.05715)
			(type default)
		)
		(layer "In2.Cu")
	)
	(gr_line
		(start 392.531854 -2.116836)
		(end 392.554968 -2.111756)
		(stroke
			(width 0.05715)
			(type default)
		)
		(layer "In2.Cu")
	)
	(gr_line
		(start 392.563604 -16.459454)
		(end 392.688826 -16.266414)
		(stroke
			(width 0.05715)
			(type default)
		)
		(layer "In2.Cu")
	)
	(gr_line
		(start 392.815572 -3.741674)
		(end 392.850116 -3.731514)
		(stroke
			(width 0.05715)
			(type default)
		)
		(layer "In2.Cu")
	)
	(gr_arc
		(start 392.834622 -138.12774)
		(mid 392.92646 -138.10503)
		(end 392.999722 -138.04519)
		(stroke
			(width 0.05715)
			(type default)
		)
		(layer "In2.Cu")
	)
	(gr_line
		(start 392.844274 -4.403598)
		(end 392.879072 -4.393438)
		(stroke
			(width 0.05715)
			(type default)
		)
		(layer "In2.Cu")
	)
	(gr_line
		(start 392.850116 -3.731514)
		(end 392.885676 -3.739134)
		(stroke
			(width 0.05715)
			(type default)
		)
		(layer "In2.Cu")
	)
	(gr_line
		(start 392.879072 -4.393438)
		(end 392.914886 -4.401058)
		(stroke
			(width 0.05715)
			(type default)
		)
		(layer "In2.Cu")
	)
	(gr_line
		(start 392.99261 -5.091176)
		(end 393.01547 -5.08635)
		(stroke
			(width 0.05715)
			(type default)
		)
		(layer "In2.Cu")
	)
	(gr_line
		(start 392.999976 -7.912862)
		(end 393.02309 -7.917942)
		(stroke
			(width 0.05715)
			(type default)
		)
		(layer "In2.Cu")
	)
	(gr_line
		(start 393.00404 -15.898368)
		(end 393.5857 -15.77467)
		(stroke
			(width 0.05715)
			(type default)
		)
		(layer "In2.Cu")
	)
	(gr_line
		(start 393.005818 -7.255002)
		(end 393.028932 -7.260082)
		(stroke
			(width 0.05715)
			(type default)
		)
		(layer "In2.Cu")
	)
	(gr_line
		(start 393.01547 -5.08635)
		(end 393.038584 -5.09143)
		(stroke
			(width 0.05715)
			(type default)
		)
		(layer "In2.Cu")
	)
	(gr_line
		(start 393.02309 -7.917942)
		(end 393.046204 -7.912862)
		(stroke
			(width 0.05715)
			(type default)
		)
		(layer "In2.Cu")
	)
	(gr_line
		(start 393.028932 -7.260082)
		(end 393.052046 -7.255002)
		(stroke
			(width 0.05715)
			(type default)
		)
		(layer "In2.Cu")
	)
	(gr_line
		(start 393.029186 -16.194278)
		(end 393.221972 -16.3195)
		(stroke
			(width 0.05715)
			(type default)
		)
		(layer "In2.Cu")
	)
	(gr_line
		(start 393.062968 -8.579358)
		(end 393.086082 -8.584438)
		(stroke
			(width 0.05715)
			(type default)
		)
		(layer "In2.Cu")
	)
	(gr_line
		(start 393.086082 -8.584438)
		(end 393.109196 -8.579358)
		(stroke
			(width 0.05715)
			(type default)
		)
		(layer "In2.Cu")
	)
	(gr_arc
		(start 393.111482 -140.961618)
		(mid 393.203279 -140.93885)
		(end 393.276582 -140.879068)
		(stroke
			(width 0.05715)
			(type default)
		)
		(layer "In2.Cu")
	)
	(gr_line
		(start 393.112498 -9.241536)
		(end 393.135612 -9.246616)
		(stroke
			(width 0.05715)
			(type default)
		)
		(layer "In2.Cu")
	)
	(gr_line
		(start 393.129262 -138.41984)
		(end 393.543282 -138.41984)
		(stroke
			(width 0.05715)
			(type default)
		)
		(layer "In2.Cu")
	)
	(gr_line
		(start 393.135612 -9.246616)
		(end 393.158726 -9.241536)
		(stroke
			(width 0.05715)
			(type default)
		)
		(layer "In2.Cu")
	)
	(gr_arc
		(start 393.164822 -137.96264)
		(mid 393.073025 -137.985408)
		(end 392.999722 -138.04519)
		(stroke
			(width 0.05715)
			(type default)
		)
		(layer "In2.Cu")
	)
	(gr_line
		(start 393.164822 -137.96264)
		(end 393.507722 -137.96264)
		(stroke
			(width 0.05715)
			(type default)
		)
		(layer "In2.Cu")
	)
	(gr_line
		(start 393.221972 -16.3195)
		(end 393.557252 -16.248126)
		(stroke
			(width 0.05715)
			(type default)
		)
		(layer "In2.Cu")
	)
	(gr_line
		(start 393.406122 -141.253718)
		(end 393.820142 -141.253718)
		(stroke
			(width 0.05715)
			(type default)
		)
		(layer "In2.Cu")
	)
	(gr_arc
		(start 393.441682 -140.796518)
		(mid 393.349848 -140.819231)
		(end 393.276582 -140.879068)
		(stroke
			(width 0.05715)
			(type default)
		)
		(layer "In2.Cu")
	)
	(gr_line
		(start 393.441682 -140.796518)
		(end 393.784582 -140.796518)
		(stroke
			(width 0.05715)
			(type default)
		)
		(layer "In2.Cu")
	)
	(gr_line
		(start 393.557252 -16.248126)
		(end 393.682474 -16.05534)
		(stroke
			(width 0.05715)
			(type default)
		)
		(layer "In2.Cu")
	)
	(gr_arc
		(start 393.672822 -138.04519)
		(mid 393.599541 -137.985364)
		(end 393.507722 -137.96264)
		(stroke
			(width 0.05715)
			(type default)
		)
		(layer "In2.Cu")
	)
	(gr_arc
		(start 393.672822 -138.04519)
		(mid 393.746119 -138.104969)
		(end 393.837922 -138.12774)
		(stroke
			(width 0.05715)
			(type default)
		)
		(layer "In2.Cu")
	)
	(gr_arc
		(start 393.949682 -140.879068)
		(mid 393.876381 -140.819299)
		(end 393.784582 -140.796518)
		(stroke
			(width 0.05715)
			(type default)
		)
		(layer "In2.Cu")
	)
	(gr_arc
		(start 393.949682 -140.879068)
		(mid 394.022963 -140.938894)
		(end 394.114782 -140.961618)
		(stroke
			(width 0.05715)
			(type default)
		)
		(layer "In2.Cu")
	)
	(gr_line
		(start 393.986258 -4.271772)
		(end 394.008864 -4.276598)
		(stroke
			(width 0.05715)
			(type default)
		)
		(layer "In2.Cu")
	)
	(gr_line
		(start 393.989306 -4.928108)
		(end 394.012166 -4.932934)
		(stroke
			(width 0.05715)
			(type default)
		)
		(layer "In2.Cu")
	)
	(gr_line
		(start 393.992354 -5.592826)
		(end 394.01496 -5.597652)
		(stroke
			(width 0.05715)
			(type default)
		)
		(layer "In2.Cu")
	)
	(gr_line
		(start 394.008864 -4.276598)
		(end 394.031724 -4.272026)
		(stroke
			(width 0.05715)
			(type default)
		)
		(layer "In2.Cu")
	)
	(gr_line
		(start 394.012166 -4.932934)
		(end 394.035026 -4.928362)
		(stroke
			(width 0.05715)
			(type default)
		)
		(layer "In2.Cu")
	)
	(gr_line
		(start 394.01496 -5.597652)
		(end 394.03782 -5.59308)
		(stroke
			(width 0.05715)
			(type default)
		)
		(layer "In2.Cu")
	)
	(gr_line
		(start 394.233908 -1.45669)
		(end 394.257022 -1.45161)
		(stroke
			(width 0.05715)
			(type default)
		)
		(layer "In2.Cu")
	)
	(gr_line
		(start 394.257022 -1.45161)
		(end 394.280136 -1.45669)
		(stroke
			(width 0.05715)
			(type default)
		)
		(layer "In2.Cu")
	)
	(gr_line
		(start 394.656818 -6.615684)
		(end 394.679932 -6.610604)
		(stroke
			(width 0.05715)
			(type default)
		)
		(layer "In2.Cu")
	)
	(gr_line
		(start 394.66266 -5.17017)
		(end 394.68171 -5.16636)
		(stroke
			(width 0.05715)
			(type default)
		)
		(layer "In2.Cu")
	)
	(gr_line
		(start 394.668248 -7.269734)
		(end 394.691362 -7.264654)
		(stroke
			(width 0.05715)
			(type default)
		)
		(layer "In2.Cu")
	)
	(gr_line
		(start 394.679932 -6.610604)
		(end 394.703046 -6.615684)
		(stroke
			(width 0.05715)
			(type default)
		)
		(layer "In2.Cu")
	)
	(gr_line
		(start 394.691362 -7.264654)
		(end 394.714476 -7.269734)
		(stroke
			(width 0.05715)
			(type default)
		)
		(layer "In2.Cu")
	)
	(gr_arc
		(start 394.716508 -140.961618)
		(mid 394.808305 -140.93885)
		(end 394.881608 -140.879068)
		(stroke
			(width 0.05715)
			(type default)
		)
		(layer "In2.Cu")
	)
	(gr_line
		(start 394.734288 -4.490466)
		(end 394.753338 -4.486656)
		(stroke
			(width 0.05715)
			(type default)
		)
		(layer "In2.Cu")
	)
	(gr_line
		(start 394.734542 -7.935722)
		(end 394.757656 -7.930642)
		(stroke
			(width 0.05715)
			(type default)
		)
		(layer "In2.Cu")
	)
	(gr_line
		(start 394.753338 -4.486656)
		(end 394.772388 -4.490466)
		(stroke
			(width 0.05715)
			(type default)
		)
		(layer "In2.Cu")
	)
	(gr_line
		(start 394.757656 -7.930642)
		(end 394.78077 -7.935722)
		(stroke
			(width 0.05715)
			(type default)
		)
		(layer "In2.Cu")
	)
	(gr_line
		(start 394.78331 -8.597646)
		(end 394.806424 -8.592566)
		(stroke
			(width 0.05715)
			(type default)
		)
		(layer "In2.Cu")
	)
	(gr_line
		(start 394.806424 -8.592566)
		(end 394.829538 -8.597646)
		(stroke
			(width 0.05715)
			(type default)
		)
		(layer "In2.Cu")
	)
	(gr_line
		(start 394.84808 -3.810508)
		(end 394.86713 -3.806698)
		(stroke
			(width 0.05715)
			(type default)
		)
		(layer "In2.Cu")
	)
	(gr_line
		(start 394.86713 -3.806698)
		(end 394.88618 -3.810508)
		(stroke
			(width 0.05715)
			(type default)
		)
		(layer "In2.Cu")
	)
	(gr_line
		(start 394.990574 -15.47622)
		(end 395.013688 -15.47114)
		(stroke
			(width 0.05715)
			(type default)
		)
		(layer "In2.Cu")
	)
	(gr_line
		(start 395.011148 -141.253718)
		(end 395.425168 -141.253718)
		(stroke
			(width 0.05715)
			(type default)
		)
		(layer "In2.Cu")
	)
	(gr_line
		(start 395.013688 -15.47114)
		(end 395.036802 -15.47622)
		(stroke
			(width 0.05715)
			(type default)
		)
		(layer "In2.Cu")
	)
	(gr_arc
		(start 395.046708 -140.796518)
		(mid 394.954893 -140.819256)
		(end 394.881608 -140.879068)
		(stroke
			(width 0.05715)
			(type default)
		)
		(layer "In2.Cu")
	)
	(gr_line
		(start 395.046708 -140.796518)
		(end 395.389608 -140.796518)
		(stroke
			(width 0.05715)
			(type default)
		)
		(layer "In2.Cu")
	)
	(gr_line
		(start 395.18971 -14.622526)
		(end 395.212824 -14.617446)
		(stroke
			(width 0.05715)
			(type default)
		)
		(layer "In2.Cu")
	)
	(gr_line
		(start 395.212824 -14.617446)
		(end 395.235938 -14.622526)
		(stroke
			(width 0.05715)
			(type default)
		)
		(layer "In2.Cu")
	)
	(gr_line
		(start 395.214602 -13.965682)
		(end 395.237716 -13.960602)
		(stroke
			(width 0.05715)
			(type default)
		)
		(layer "In2.Cu")
	)
	(gr_line
		(start 395.237716 -13.960602)
		(end 395.26083 -13.965682)
		(stroke
			(width 0.05715)
			(type default)
		)
		(layer "In2.Cu")
	)
	(gr_line
		(start 395.238986 -13.308584)
		(end 395.2621 -13.303504)
		(stroke
			(width 0.05715)
			(type default)
		)
		(layer "In2.Cu")
	)
	(gr_line
		(start 395.2621 -13.303504)
		(end 395.285214 -13.308584)
		(stroke
			(width 0.05715)
			(type default)
		)
		(layer "In2.Cu")
	)
	(gr_line
		(start 395.263116 -12.65174)
		(end 395.28623 -12.64666)
		(stroke
			(width 0.05715)
			(type default)
		)
		(layer "In2.Cu")
	)
	(gr_line
		(start 395.28623 -12.64666)
		(end 395.309344 -12.65174)
		(stroke
			(width 0.05715)
			(type default)
		)
		(layer "In2.Cu")
	)
	(gr_line
		(start 395.287246 -11.994642)
		(end 395.31036 -11.989562)
		(stroke
			(width 0.05715)
			(type default)
		)
		(layer "In2.Cu")
	)
	(gr_line
		(start 395.31036 -11.989562)
		(end 395.333474 -11.994642)
		(stroke
			(width 0.05715)
			(type default)
		)
		(layer "In2.Cu")
	)
	(gr_line
		(start 395.312138 -11.337798)
		(end 395.335252 -11.332718)
		(stroke
			(width 0.05715)
			(type default)
		)
		(layer "In2.Cu")
	)
	(gr_line
		(start 395.335252 -11.332718)
		(end 395.358366 -11.337798)
		(stroke
			(width 0.05715)
			(type default)
		)
		(layer "In2.Cu")
	)
	(gr_line
		(start 395.33576 -10.6807)
		(end 395.359128 -10.67562)
		(stroke
			(width 0.05715)
			(type default)
		)
		(layer "In2.Cu")
	)
	(gr_line
		(start 395.359128 -10.675874)
		(end 395.359382 -10.67562)
		(stroke
			(width 0.05715)
			(type default)
		)
		(layer "In2.Cu")
	)
	(gr_line
		(start 395.359128 -10.67562)
		(end 395.359128 -10.675874)
		(stroke
			(width 0.05715)
			(type default)
		)
		(layer "In2.Cu")
	)
	(gr_line
		(start 395.359382 -10.67562)
		(end 395.382496 -10.6807)
		(stroke
			(width 0.05715)
			(type default)
		)
		(layer "In2.Cu")
	)
	(gr_line
		(start 395.360906 -10.023856)
		(end 395.38402 -10.018776)
		(stroke
			(width 0.05715)
			(type default)
		)
		(layer "In2.Cu")
	)
	(gr_line
		(start 395.38402 -10.018776)
		(end 395.407134 -10.023856)
		(stroke
			(width 0.05715)
			(type default)
		)
		(layer "In2.Cu")
	)
	(gr_arc
		(start 395.554708 -140.879068)
		(mid 395.481409 -140.81929)
		(end 395.389608 -140.796518)
		(stroke
			(width 0.05715)
			(type default)
		)
		(layer "In2.Cu")
	)
	(gr_arc
		(start 395.554708 -140.879068)
		(mid 395.627989 -140.938894)
		(end 395.719808 -140.961618)
		(stroke
			(width 0.05715)
			(type default)
		)
		(layer "In2.Cu")
	)
	(gr_line
		(start 395.780006 -9.098026)
		(end 395.80312 -9.103106)
		(stroke
			(width 0.05715)
			(type default)
		)
		(layer "In2.Cu")
	)
	(gr_line
		(start 395.780006 -8.446262)
		(end 395.80312 -8.451342)
		(stroke
			(width 0.05715)
			(type default)
		)
		(layer "In2.Cu")
	)
	(gr_line
		(start 395.780006 -7.794498)
		(end 395.80312 -7.799578)
		(stroke
			(width 0.05715)
			(type default)
		)
		(layer "In2.Cu")
	)
	(gr_line
		(start 395.780006 -7.142734)
		(end 395.80312 -7.147814)
		(stroke
			(width 0.05715)
			(type default)
		)
		(layer "In2.Cu")
	)
	(gr_line
		(start 395.80312 -9.103106)
		(end 395.826234 -9.098026)
		(stroke
			(width 0.05715)
			(type default)
		)
		(layer "In2.Cu")
	)
	(gr_line
		(start 395.80312 -8.451342)
		(end 395.826234 -8.446262)
		(stroke
			(width 0.05715)
			(type default)
		)
		(layer "In2.Cu")
	)
	(gr_line
		(start 395.80312 -7.799578)
		(end 395.826234 -7.794498)
		(stroke
			(width 0.05715)
			(type default)
		)
		(layer "In2.Cu")
	)
	(gr_line
		(start 395.80312 -7.147814)
		(end 395.826234 -7.142734)
		(stroke
			(width 0.05715)
			(type default)
		)
		(layer "In2.Cu")
	)
	(gr_arc
		(start 396.312898 -140.961618)
		(mid 396.404695 -140.93885)
		(end 396.477998 -140.879068)
		(stroke
			(width 0.05715)
			(type default)
		)
		(layer "In2.Cu")
	)
	(gr_line
		(start 396.41907 -5.811774)
		(end 396.43812 -5.815584)
		(stroke
			(width 0.05715)
			(type default)
		)
		(layer "In2.Cu")
	)
	(gr_line
		(start 396.43812 -5.815584)
		(end 396.45717 -5.811774)
		(stroke
			(width 0.05715)
			(type default)
		)
		(layer "In2.Cu")
	)
	(gr_line
		(start 396.460726 -5.125974)
		(end 396.479776 -5.129784)
		(stroke
			(width 0.05715)
			(type default)
		)
		(layer "In2.Cu")
	)
	(gr_line
		(start 396.485872 -4.428236)
		(end 396.504922 -4.432046)
		(stroke
			(width 0.05715)
			(type default)
		)
		(layer "In2.Cu")
	)
	(gr_line
		(start 396.607538 -141.253718)
		(end 397.021558 -141.253718)
		(stroke
			(width 0.05715)
			(type default)
		)
		(layer "In2.Cu")
	)
	(gr_arc
		(start 396.643098 -140.796518)
		(mid 396.551286 -140.81926)
		(end 396.477998 -140.879068)
		(stroke
			(width 0.05715)
			(type default)
		)
		(layer "In2.Cu")
	)
	(gr_line
		(start 396.643098 -140.796518)
		(end 396.985998 -140.796518)
		(stroke
			(width 0.05715)
			(type default)
		)
		(layer "In2.Cu")
	)
	(gr_line
		(start 396.9258 -2.316988)
		(end 396.948914 -2.322068)
		(stroke
			(width 0.05715)
			(type default)
		)
		(layer "In2.Cu")
	)
	(gr_line
		(start 396.930372 -8.565134)
		(end 396.953486 -8.560054)
		(stroke
			(width 0.05715)
			(type default)
		)
		(layer "In2.Cu")
	)
	(gr_line
		(start 396.930372 -7.91337)
		(end 396.953486 -7.90829)
		(stroke
			(width 0.05715)
			(type default)
		)
		(layer "In2.Cu")
	)
	(gr_line
		(start 396.930372 -7.261606)
		(end 396.953486 -7.256526)
		(stroke
			(width 0.05715)
			(type default)
		)
		(layer "In2.Cu")
	)
	(gr_line
		(start 396.930372 -6.609842)
		(end 396.953486 -6.604762)
		(stroke
			(width 0.05715)
			(type default)
		)
		(layer "In2.Cu")
	)
	(gr_line
		(start 396.948914 -2.322068)
		(end 396.972028 -2.316988)
		(stroke
			(width 0.05715)
			(type default)
		)
		(layer "In2.Cu")
	)
	(gr_line
		(start 396.953486 -8.560054)
		(end 396.9766 -8.565134)
		(stroke
			(width 0.05715)
			(type default)
		)
		(layer "In2.Cu")
	)
	(gr_line
		(start 396.953486 -7.90829)
		(end 396.9766 -7.91337)
		(stroke
			(width 0.05715)
			(type default)
		)
		(layer "In2.Cu")
	)
	(gr_line
		(start 396.953486 -7.256526)
		(end 396.9766 -7.261606)
		(stroke
			(width 0.05715)
			(type default)
		)
		(layer "In2.Cu")
	)
	(gr_line
		(start 396.953486 -6.604762)
		(end 396.9766 -6.609842)
		(stroke
			(width 0.05715)
			(type default)
		)
		(layer "In2.Cu")
	)
	(gr_arc
		(start 397.151098 -140.879068)
		(mid 397.077798 -140.819293)
		(end 396.985998 -140.796518)
		(stroke
			(width 0.05715)
			(type default)
		)
		(layer "In2.Cu")
	)
	(gr_arc
		(start 397.151098 -140.879068)
		(mid 397.224379 -140.938894)
		(end 397.316198 -140.961618)
		(stroke
			(width 0.05715)
			(type default)
		)
		(layer "In2.Cu")
	)
	(gr_line
		(start 397.619982 -3.912108)
		(end 397.63954 -3.908044)
		(stroke
			(width 0.05715)
			(type default)
		)
		(layer "In2.Cu")
	)
	(gr_line
		(start 397.63954 -3.908044)
		(end 397.65859 -3.911854)
		(stroke
			(width 0.05715)
			(type default)
		)
		(layer "In2.Cu")
	)
	(gr_line
		(start 397.689832 -4.58978)
		(end 397.708882 -4.58597)
		(stroke
			(width 0.05715)
			(type default)
		)
		(layer "In2.Cu")
	)
	(gr_line
		(start 397.708882 -4.58597)
		(end 397.70939 -4.58597)
		(stroke
			(width 0.05715)
			(type default)
		)
		(layer "In2.Cu")
	)
	(gr_line
		(start 397.70939 -4.58597)
		(end 397.729202 -4.590034)
		(stroke
			(width 0.05715)
			(type default)
		)
		(layer "In2.Cu")
	)
	(gr_line
		(start 397.722598 -5.260848)
		(end 397.741648 -5.257038)
		(stroke
			(width 0.05715)
			(type default)
		)
		(layer "In2.Cu")
	)
	(gr_line
		(start 397.741648 -5.257038)
		(end 397.760698 -5.260848)
		(stroke
			(width 0.05715)
			(type default)
		)
		(layer "In2.Cu")
	)
	(gr_line
		(start 398.121378 -1.774444)
		(end 398.144492 -1.769364)
		(stroke
			(width 0.05715)
			(type default)
		)
		(layer "In2.Cu")
	)
	(gr_line
		(start 398.144492 -1.769364)
		(end 398.167606 -1.774444)
		(stroke
			(width 0.05715)
			(type default)
		)
		(layer "In2.Cu")
	)
	(gr_line
		(start 398.172686 -9.117584)
		(end 398.1958 -9.122664)
		(stroke
			(width 0.05715)
			(type default)
		)
		(layer "In2.Cu")
	)
	(gr_line
		(start 398.172686 -8.46582)
		(end 398.1958 -8.4709)
		(stroke
			(width 0.05715)
			(type default)
		)
		(layer "In2.Cu")
	)
	(gr_line
		(start 398.172686 -7.814056)
		(end 398.1958 -7.819136)
		(stroke
			(width 0.05715)
			(type default)
		)
		(layer "In2.Cu")
	)
	(gr_line
		(start 398.172686 -7.162292)
		(end 398.1958 -7.167372)
		(stroke
			(width 0.05715)
			(type default)
		)
		(layer "In2.Cu")
	)
	(gr_line
		(start 398.1958 -9.122664)
		(end 398.218914 -9.117584)
		(stroke
			(width 0.05715)
			(type default)
		)
		(layer "In2.Cu")
	)
	(gr_line
		(start 398.1958 -8.4709)
		(end 398.218914 -8.46582)
		(stroke
			(width 0.05715)
			(type default)
		)
		(layer "In2.Cu")
	)
	(gr_line
		(start 398.1958 -7.819136)
		(end 398.218914 -7.814056)
		(stroke
			(width 0.05715)
			(type default)
		)
		(layer "In2.Cu")
	)
	(gr_line
		(start 398.1958 -7.167372)
		(end 398.218914 -7.162292)
		(stroke
			(width 0.05715)
			(type default)
		)
		(layer "In2.Cu")
	)
	(gr_line
		(start 398.650206 -15.6464)
		(end 398.67586 -15.651734)
		(stroke
			(width 0.05715)
			(type default)
		)
		(layer "In2.Cu")
	)
	(gr_line
		(start 398.650968 -12.335764)
		(end 398.676114 -12.341098)
		(stroke
			(width 0.05715)
			(type default)
		)
		(layer "In2.Cu")
	)
	(gr_line
		(start 398.652238 -14.984222)
		(end 398.675352 -14.989302)
		(stroke
			(width 0.05715)
			(type default)
		)
		(layer "In2.Cu")
	)
	(gr_line
		(start 398.652746 -14.322298)
		(end 398.67586 -14.327378)
		(stroke
			(width 0.05715)
			(type default)
		)
		(layer "In2.Cu")
	)
	(gr_line
		(start 398.653 -13.659866)
		(end 398.676114 -13.664946)
		(stroke
			(width 0.05715)
			(type default)
		)
		(layer "In2.Cu")
	)
	(gr_line
		(start 398.653 -12.997942)
		(end 398.676622 -13.003022)
		(stroke
			(width 0.05715)
			(type default)
		)
		(layer "In2.Cu")
	)
	(gr_line
		(start 398.653254 -16.542512)
		(end 398.676368 -16.547592)
		(stroke
			(width 0.05715)
			(type default)
		)
		(layer "In2.Cu")
	)
	(gr_line
		(start 398.653762 -11.011408)
		(end 398.676876 -11.016488)
		(stroke
			(width 0.05715)
			(type default)
		)
		(layer "In2.Cu")
	)
	(gr_line
		(start 398.654016 -11.67384)
		(end 398.676622 -11.678666)
		(stroke
			(width 0.05715)
			(type default)
		)
		(layer "In2.Cu")
	)
	(gr_line
		(start 398.65427 -11.67384)
		(end 398.676622 -11.678666)
		(stroke
			(width 0.05715)
			(type default)
		)
		(layer "In2.Cu")
	)
	(gr_line
		(start 398.675352 -14.989302)
		(end 398.698466 -14.984222)
		(stroke
			(width 0.05715)
			(type default)
		)
		(layer "In2.Cu")
	)
	(gr_line
		(start 398.67586 -15.651734)
		(end 398.701514 -15.6464)
		(stroke
			(width 0.05715)
			(type default)
		)
		(layer "In2.Cu")
	)
	(gr_line
		(start 398.67586 -14.327378)
		(end 398.698974 -14.322298)
		(stroke
			(width 0.05715)
			(type default)
		)
		(layer "In2.Cu")
	)
	(gr_line
		(start 398.676114 -13.664946)
		(end 398.699228 -13.659866)
		(stroke
			(width 0.05715)
			(type default)
		)
		(layer "In2.Cu")
	)
	(gr_line
		(start 398.676114 -12.341098)
		(end 398.70126 -12.335764)
		(stroke
			(width 0.05715)
			(type default)
		)
		(layer "In2.Cu")
	)
	(gr_line
		(start 398.676368 -16.547592)
		(end 398.699482 -16.542512)
		(stroke
			(width 0.05715)
			(type default)
		)
		(layer "In2.Cu")
	)
	(gr_line
		(start 398.676622 -13.003022)
		(end 398.699228 -12.998196)
		(stroke
			(width 0.05715)
			(type default)
		)
		(layer "In2.Cu")
	)
	(gr_line
		(start 398.676622 -11.678666)
		(end 398.69872 -11.67384)
		(stroke
			(width 0.05715)
			(type default)
		)
		(layer "In2.Cu")
	)
	(gr_line
		(start 398.676622 -11.678666)
		(end 398.699228 -11.67384)
		(stroke
			(width 0.05715)
			(type default)
		)
		(layer "In2.Cu")
	)
	(gr_line
		(start 398.676876 -11.016488)
		(end 398.69999 -11.011408)
		(stroke
			(width 0.05715)
			(type default)
		)
		(layer "In2.Cu")
	)
	(gr_line
		(start 399.412968 -7.913624)
		(end 399.436336 -7.908544)
		(stroke
			(width 0.05715)
			(type default)
		)
		(layer "In2.Cu")
	)
	(gr_line
		(start 399.412968 -7.26186)
		(end 399.436336 -7.25678)
		(stroke
			(width 0.05715)
			(type default)
		)
		(layer "In2.Cu")
	)
	(gr_line
		(start 399.413476 -8.565388)
		(end 399.43659 -8.560308)
		(stroke
			(width 0.05715)
			(type default)
		)
		(layer "In2.Cu")
	)
	(gr_line
		(start 399.413476 -6.610096)
		(end 399.43659 -6.605016)
		(stroke
			(width 0.05715)
			(type default)
		)
		(layer "In2.Cu")
	)
	(gr_line
		(start 399.436336 -7.908544)
		(end 399.458942 -7.91337)
		(stroke
			(width 0.05715)
			(type default)
		)
		(layer "In2.Cu")
	)
	(gr_line
		(start 399.436336 -7.25678)
		(end 399.458942 -7.261606)
		(stroke
			(width 0.05715)
			(type default)
		)
		(layer "In2.Cu")
	)
	(gr_line
		(start 399.43659 -8.560308)
		(end 399.459704 -8.565388)
		(stroke
			(width 0.05715)
			(type default)
		)
		(layer "In2.Cu")
	)
	(gr_line
		(start 399.43659 -6.605016)
		(end 399.459704 -6.610096)
		(stroke
			(width 0.05715)
			(type default)
		)
		(layer "In2.Cu")
	)
	(gr_line
		(start 399.84934 -144.339818)
		(end 399.84934 -144.753838)
		(stroke
			(width 0.05715)
			(type default)
		)
		(layer "In2.Cu")
	)
	(gr_line
		(start 399.84934 -142.993618)
		(end 399.84934 -143.407638)
		(stroke
			(width 0.05715)
			(type default)
		)
		(layer "In2.Cu")
	)
	(gr_line
		(start 400.071844 -2.477262)
		(end 400.094958 -2.482342)
		(stroke
			(width 0.05715)
			(type default)
		)
		(layer "In2.Cu")
	)
	(gr_line
		(start 400.094958 -2.482342)
		(end 400.118072 -2.477262)
		(stroke
			(width 0.05715)
			(type default)
		)
		(layer "In2.Cu")
	)
	(gr_arc
		(start 400.14144 -144.045178)
		(mid 400.164208 -144.136975)
		(end 400.22399 -144.210278)
		(stroke
			(width 0.05715)
			(type default)
		)
		(layer "In2.Cu")
	)
	(gr_arc
		(start 400.14144 -142.698978)
		(mid 400.164208 -142.790775)
		(end 400.22399 -142.864078)
		(stroke
			(width 0.05715)
			(type default)
		)
		(layer "In2.Cu")
	)
	(gr_arc
		(start 400.22399 -144.883378)
		(mid 400.164164 -144.956659)
		(end 400.14144 -145.048478)
		(stroke
			(width 0.05715)
			(type default)
		)
		(layer "In2.Cu")
	)
	(gr_arc
		(start 400.22399 -144.883378)
		(mid 400.283769 -144.810081)
		(end 400.30654 -144.718278)
		(stroke
			(width 0.05715)
			(type default)
		)
		(layer "In2.Cu")
	)
	(gr_arc
		(start 400.22399 -143.537178)
		(mid 400.164164 -143.610459)
		(end 400.14144 -143.702278)
		(stroke
			(width 0.05715)
			(type default)
		)
		(layer "In2.Cu")
	)
	(gr_arc
		(start 400.22399 -143.537178)
		(mid 400.283769 -143.463881)
		(end 400.30654 -143.372078)
		(stroke
			(width 0.05715)
			(type default)
		)
		(layer "In2.Cu")
	)
	(gr_arc
		(start 400.30654 -144.375378)
		(mid 400.28383 -144.28354)
		(end 400.22399 -144.210278)
		(stroke
			(width 0.05715)
			(type default)
		)
		(layer "In2.Cu")
	)
	(gr_line
		(start 400.30654 -144.375378)
		(end 400.30654 -144.718278)
		(stroke
			(width 0.05715)
			(type default)
		)
		(layer "In2.Cu")
	)
	(gr_arc
		(start 400.30654 -143.029178)
		(mid 400.28383 -142.93734)
		(end 400.22399 -142.864078)
		(stroke
			(width 0.05715)
			(type default)
		)
		(layer "In2.Cu")
	)
	(gr_line
		(start 400.30654 -143.029178)
		(end 400.30654 -143.372078)
		(stroke
			(width 0.05715)
			(type default)
		)
		(layer "In2.Cu")
	)
	(gr_arc
		(start 400.567652 -137.81913)
		(mid 400.648599 -137.867989)
		(end 400.742658 -137.87755)
		(stroke
			(width 0.05715)
			(type default)
		)
		(layer "In2.Cu")
	)
	(gr_line
		(start 400.569176 -138.234166)
		(end 400.862038 -138.527028)
		(stroke
			(width 0.05715)
			(type default)
		)
		(layer "In2.Cu")
	)
	(gr_line
		(start 400.655536 -7.162546)
		(end 400.678904 -7.167626)
		(stroke
			(width 0.05715)
			(type default)
		)
		(layer "In2.Cu")
	)
	(gr_line
		(start 400.65579 -9.117838)
		(end 400.678904 -9.122918)
		(stroke
			(width 0.05715)
			(type default)
		)
		(layer "In2.Cu")
	)
	(gr_line
		(start 400.65579 -8.466074)
		(end 400.678904 -8.471154)
		(stroke
			(width 0.05715)
			(type default)
		)
		(layer "In2.Cu")
	)
	(gr_line
		(start 400.65579 -7.81431)
		(end 400.678904 -7.81939)
		(stroke
			(width 0.05715)
			(type default)
		)
		(layer "In2.Cu")
	)
	(gr_line
		(start 400.678904 -9.122918)
		(end 400.702018 -9.117838)
		(stroke
			(width 0.05715)
			(type default)
		)
		(layer "In2.Cu")
	)
	(gr_line
		(start 400.678904 -8.471154)
		(end 400.702018 -8.466074)
		(stroke
			(width 0.05715)
			(type default)
		)
		(layer "In2.Cu")
	)
	(gr_line
		(start 400.678904 -7.81939)
		(end 400.702018 -7.81431)
		(stroke
			(width 0.05715)
			(type default)
		)
		(layer "In2.Cu")
	)
	(gr_line
		(start 400.678904 -7.167626)
		(end 400.70151 -7.1628)
		(stroke
			(width 0.05715)
			(type default)
		)
		(layer "In2.Cu")
	)
	(gr_line
		(start 400.71675 -4.821682)
		(end 400.74088 -4.826508)
		(stroke
			(width 0.05715)
			(type default)
		)
		(layer "In2.Cu")
	)
	(gr_line
		(start 400.729958 -6.152642)
		(end 400.750278 -6.156706)
		(stroke
			(width 0.05715)
			(type default)
		)
		(layer "In2.Cu")
	)
	(gr_line
		(start 400.736562 -5.489702)
		(end 400.759422 -5.494274)
		(stroke
			(width 0.05715)
			(type default)
		)
		(layer "In2.Cu")
	)
	(gr_line
		(start 400.74088 -4.82219)
		(end 400.74088 -4.826508)
		(stroke
			(width 0.05715)
			(type default)
		)
		(layer "In2.Cu")
	)
	(gr_line
		(start 400.750278 -6.156706)
		(end 400.755358 -6.156706)
		(stroke
			(width 0.05715)
			(type default)
		)
		(layer "In2.Cu")
	)
	(gr_line
		(start 400.755358 -6.156706)
		(end 400.775932 -6.152388)
		(stroke
			(width 0.05715)
			(type default)
		)
		(layer "In2.Cu")
	)
	(gr_line
		(start 400.759422 -5.494274)
		(end 400.782282 -5.489448)
		(stroke
			(width 0.05715)
			(type default)
		)
		(layer "In2.Cu")
	)
	(gr_arc
		(start 400.917918 -137.935716)
		(mid 400.836823 -137.886931)
		(end 400.742658 -137.87755)
		(stroke
			(width 0.05715)
			(type default)
		)
		(layer "In2.Cu")
	)
	(gr_line
		(start 400.917918 -137.935716)
		(end 401.160234 -138.178286)
		(stroke
			(width 0.05715)
			(type default)
		)
		(layer "In2.Cu")
	)
	(gr_line
		(start 400.93646 -15.768828)
		(end 400.959066 -15.764002)
		(stroke
			(width 0.05715)
			(type default)
		)
		(layer "In2.Cu")
	)
	(gr_line
		(start 400.959066 -15.764002)
		(end 400.982434 -15.769082)
		(stroke
			(width 0.05715)
			(type default)
		)
		(layer "In2.Cu")
	)
	(gr_arc
		(start 401.218654 -138.353292)
		(mid 401.209075 -138.25924)
		(end 401.160234 -138.178286)
		(stroke
			(width 0.05715)
			(type default)
		)
		(layer "In2.Cu")
	)
	(gr_arc
		(start 401.218654 -138.353292)
		(mid 401.228175 -138.447485)
		(end 401.277074 -138.528552)
		(stroke
			(width 0.05715)
			(type default)
		)
		(layer "In2.Cu")
	)
	(gr_line
		(start 401.36445 -12.795758)
		(end 401.387564 -12.790678)
		(stroke
			(width 0.05715)
			(type default)
		)
		(layer "In2.Cu")
	)
	(gr_line
		(start 401.378674 -14.117066)
		(end 401.401788 -14.111986)
		(stroke
			(width 0.05715)
			(type default)
		)
		(layer "In2.Cu")
	)
	(gr_line
		(start 401.384262 -13.453618)
		(end 401.407376 -13.448538)
		(stroke
			(width 0.05715)
			(type default)
		)
		(layer "In2.Cu")
	)
	(gr_line
		(start 401.387564 -12.790678)
		(end 401.410678 -12.795758)
		(stroke
			(width 0.05715)
			(type default)
		)
		(layer "In2.Cu")
	)
	(gr_line
		(start 401.395946 -14.775434)
		(end 401.41906 -14.770354)
		(stroke
			(width 0.05715)
			(type default)
		)
		(layer "In2.Cu")
	)
	(gr_line
		(start 401.401788 -14.111986)
		(end 401.424902 -14.117066)
		(stroke
			(width 0.05715)
			(type default)
		)
		(layer "In2.Cu")
	)
	(gr_line
		(start 401.407376 -13.448538)
		(end 401.43049 -13.453618)
		(stroke
			(width 0.05715)
			(type default)
		)
		(layer "In2.Cu")
	)
	(gr_line
		(start 401.41906 -14.770354)
		(end 401.442174 -14.775434)
		(stroke
			(width 0.05715)
			(type default)
		)
		(layer "In2.Cu")
	)
	(gr_line
		(start 401.428458 -12.120118)
		(end 401.451572 -12.115038)
		(stroke
			(width 0.05715)
			(type default)
		)
		(layer "In2.Cu")
	)
	(gr_line
		(start 401.451572 -12.115038)
		(end 401.474686 -12.120118)
		(stroke
			(width 0.05715)
			(type default)
		)
		(layer "In2.Cu")
	)
	(gr_line
		(start 401.474178 -10.78611)
		(end 401.497292 -10.78103)
		(stroke
			(width 0.05715)
			(type default)
		)
		(layer "In2.Cu")
	)
	(gr_line
		(start 401.484084 -10.1219)
		(end 401.507198 -10.11682)
		(stroke
			(width 0.05715)
			(type default)
		)
		(layer "In2.Cu")
	)
	(gr_line
		(start 401.488402 -11.44524)
		(end 401.511516 -11.44016)
		(stroke
			(width 0.05715)
			(type default)
		)
		(layer "In2.Cu")
	)
	(gr_line
		(start 401.497292 -10.78103)
		(end 401.520406 -10.78611)
		(stroke
			(width 0.05715)
			(type default)
		)
		(layer "In2.Cu")
	)
	(gr_line
		(start 401.507198 -10.11682)
		(end 401.530312 -10.1219)
		(stroke
			(width 0.05715)
			(type default)
		)
		(layer "In2.Cu")
	)
	(gr_line
		(start 401.511516 -11.44016)
		(end 401.53463 -11.44524)
		(stroke
			(width 0.05715)
			(type default)
		)
		(layer "In2.Cu")
	)
	(gr_line
		(start 401.571206 -16.193262)
		(end 401.593304 -16.198088)
		(stroke
			(width 0.05715)
			(type default)
		)
		(layer "In2.Cu")
	)
	(gr_arc
		(start 401.580604 -138.832082)
		(mid 401.661671 -138.880981)
		(end 401.755864 -138.890502)
		(stroke
			(width 0.05715)
			(type default)
		)
		(layer "In2.Cu")
	)
	(gr_line
		(start 401.582128 -139.247118)
		(end 401.87499 -139.53998)
		(stroke
			(width 0.05715)
			(type default)
		)
		(layer "In2.Cu")
	)
	(gr_line
		(start 401.593304 -16.198088)
		(end 401.615402 -16.193516)
		(stroke
			(width 0.05715)
			(type default)
		)
		(layer "In2.Cu")
	)
	(gr_line
		(start 401.775676 -8.59155)
		(end 401.79879 -8.58647)
		(stroke
			(width 0.05715)
			(type default)
		)
		(layer "In2.Cu")
	)
	(gr_line
		(start 401.775676 -7.939786)
		(end 401.79879 -7.934706)
		(stroke
			(width 0.05715)
			(type default)
		)
		(layer "In2.Cu")
	)
	(gr_line
		(start 401.775676 -7.288022)
		(end 401.79879 -7.282942)
		(stroke
			(width 0.05715)
			(type default)
		)
		(layer "In2.Cu")
	)
	(gr_line
		(start 401.798282 -6.631432)
		(end 401.821396 -6.626352)
		(stroke
			(width 0.05715)
			(type default)
		)
		(layer "In2.Cu")
	)
	(gr_line
		(start 401.79879 -8.58647)
		(end 401.821904 -8.59155)
		(stroke
			(width 0.05715)
			(type default)
		)
		(layer "In2.Cu")
	)
	(gr_line
		(start 401.79879 -7.934706)
		(end 401.821904 -7.939786)
		(stroke
			(width 0.05715)
			(type default)
		)
		(layer "In2.Cu")
	)
	(gr_line
		(start 401.79879 -7.282942)
		(end 401.821904 -7.288022)
		(stroke
			(width 0.05715)
			(type default)
		)
		(layer "In2.Cu")
	)
	(gr_line
		(start 401.821396 -6.626352)
		(end 401.84451 -6.631432)
		(stroke
			(width 0.05715)
			(type default)
		)
		(layer "In2.Cu")
	)
	(gr_arc
		(start 401.93087 -138.948922)
		(mid 401.849918 -138.900084)
		(end 401.755864 -138.890502)
		(stroke
			(width 0.05715)
			(type default)
		)
		(layer "In2.Cu")
	)
	(gr_line
		(start 401.93087 -138.948922)
		(end 402.17344 -139.191492)
		(stroke
			(width 0.05715)
			(type default)
		)
		(layer "In2.Cu")
	)
	(gr_line
		(start 402.142198 -14.567916)
		(end 402.164804 -14.572742)
		(stroke
			(width 0.05715)
			(type default)
		)
		(layer "In2.Cu")
	)
	(gr_line
		(start 402.142706 -14.567916)
		(end 402.164804 -14.572742)
		(stroke
			(width 0.05715)
			(type default)
		)
		(layer "In2.Cu")
	)
	(gr_line
		(start 402.14931 -13.25118)
		(end 402.172424 -13.25626)
		(stroke
			(width 0.05715)
			(type default)
		)
		(layer "In2.Cu")
	)
	(gr_line
		(start 402.154136 -15.225268)
		(end 402.177504 -15.230348)
		(stroke
			(width 0.05715)
			(type default)
		)
		(layer "In2.Cu")
	)
	(gr_line
		(start 402.155406 -15.225522)
		(end 402.177504 -15.230348)
		(stroke
			(width 0.05715)
			(type default)
		)
		(layer "In2.Cu")
	)
	(gr_line
		(start 402.164804 -14.572742)
		(end 402.18741 -14.567916)
		(stroke
			(width 0.05715)
			(type default)
		)
		(layer "In2.Cu")
	)
	(gr_line
		(start 402.164804 -14.572742)
		(end 402.187664 -14.567916)
		(stroke
			(width 0.05715)
			(type default)
		)
		(layer "In2.Cu")
	)
	(gr_line
		(start 402.172424 -13.25626)
		(end 402.195284 -13.251434)
		(stroke
			(width 0.05715)
			(type default)
		)
		(layer "In2.Cu")
	)
	(gr_line
		(start 402.173186 -10.556748)
		(end 402.1963 -10.561828)
		(stroke
			(width 0.05715)
			(type default)
		)
		(layer "In2.Cu")
	)
	(gr_line
		(start 402.175726 -13.91031)
		(end 402.19884 -13.91539)
		(stroke
			(width 0.05715)
			(type default)
		)
		(layer "In2.Cu")
	)
	(gr_line
		(start 402.176742 -11.223752)
		(end 402.199856 -11.228832)
		(stroke
			(width 0.05715)
			(type default)
		)
		(layer "In2.Cu")
	)
	(gr_line
		(start 402.177504 -15.230348)
		(end 402.20011 -15.225522)
		(stroke
			(width 0.05715)
			(type default)
		)
		(layer "In2.Cu")
	)
	(gr_line
		(start 402.196046 -12.57173)
		(end 402.219922 -12.57681)
		(stroke
			(width 0.05715)
			(type default)
		)
		(layer "In2.Cu")
	)
	(gr_line
		(start 402.1963 -10.561828)
		(end 402.219414 -10.556748)
		(stroke
			(width 0.05715)
			(type default)
		)
		(layer "In2.Cu")
	)
	(gr_line
		(start 402.196808 -12.57173)
		(end 402.219922 -12.57681)
		(stroke
			(width 0.05715)
			(type default)
		)
		(layer "In2.Cu")
	)
	(gr_line
		(start 402.19884 -13.91539)
		(end 402.221954 -13.91031)
		(stroke
			(width 0.05715)
			(type default)
		)
		(layer "In2.Cu")
	)
	(gr_line
		(start 402.199856 -11.228832)
		(end 402.22297 -11.223752)
		(stroke
			(width 0.05715)
			(type default)
		)
		(layer "In2.Cu")
	)
	(gr_line
		(start 402.219922 -12.57681)
		(end 402.24329 -12.571984)
		(stroke
			(width 0.05715)
			(type default)
		)
		(layer "In2.Cu")
	)
	(gr_arc
		(start 402.23186 -139.366498)
		(mid 402.222283 -139.272444)
		(end 402.17344 -139.191492)
		(stroke
			(width 0.05715)
			(type default)
		)
		(layer "In2.Cu")
	)
	(gr_arc
		(start 402.23186 -139.366498)
		(mid 402.241325 -139.460521)
		(end 402.290026 -139.541504)
		(stroke
			(width 0.05715)
			(type default)
		)
		(layer "In2.Cu")
	)
	(gr_line
		(start 402.26234 -11.898376)
		(end 402.28647 -11.903456)
		(stroke
			(width 0.05715)
			(type default)
		)
		(layer "In2.Cu")
	)
	(gr_line
		(start 402.262594 -11.898376)
		(end 402.28647 -11.903456)
		(stroke
			(width 0.05715)
			(type default)
		)
		(layer "In2.Cu")
	)
	(gr_line
		(start 402.28647 -11.903456)
		(end 402.309584 -11.89863)
		(stroke
			(width 0.05715)
			(type default)
		)
		(layer "In2.Cu")
	)
	(gr_line
		(start 403.29739 -7.899908)
		(end 403.320504 -7.904988)
		(stroke
			(width 0.05715)
			(type default)
		)
		(layer "In2.Cu")
	)
	(gr_line
		(start 403.320504 -7.904988)
		(end 403.343618 -7.899908)
		(stroke
			(width 0.05715)
			(type default)
		)
		(layer "In2.Cu")
	)
	(gr_line
		(start 403.325838 -7.244588)
		(end 403.348952 -7.249668)
		(stroke
			(width 0.05715)
			(type default)
		)
		(layer "In2.Cu")
	)
	(gr_line
		(start 403.32914 -8.558276)
		(end 403.352254 -8.563356)
		(stroke
			(width 0.05715)
			(type default)
		)
		(layer "In2.Cu")
	)
	(gr_line
		(start 403.3393 -10.0203)
		(end 403.362414 -10.01522)
		(stroke
			(width 0.05715)
			(type default)
		)
		(layer "In2.Cu")
	)
	(gr_line
		(start 403.34057 -12.040108)
		(end 403.363684 -12.035028)
		(stroke
			(width 0.05715)
			(type default)
		)
		(layer "In2.Cu")
	)
	(gr_line
		(start 403.347174 -15.543022)
		(end 403.36851 -15.538704)
		(stroke
			(width 0.05715)
			(type default)
		)
		(layer "In2.Cu")
	)
	(gr_line
		(start 403.347936 -14.68247)
		(end 403.37105 -14.67739)
		(stroke
			(width 0.05715)
			(type default)
		)
		(layer "In2.Cu")
	)
	(gr_line
		(start 403.34819 -14.682216)
		(end 403.37105 -14.67739)
		(stroke
			(width 0.05715)
			(type default)
		)
		(layer "In2.Cu")
	)
	(gr_line
		(start 403.348952 -7.249668)
		(end 403.372066 -7.244588)
		(stroke
			(width 0.05715)
			(type default)
		)
		(layer "In2.Cu")
	)
	(gr_line
		(start 403.352254 -8.563356)
		(end 403.375368 -8.558276)
		(stroke
			(width 0.05715)
			(type default)
		)
		(layer "In2.Cu")
	)
	(gr_line
		(start 403.352508 -10.685272)
		(end 403.375622 -10.680192)
		(stroke
			(width 0.05715)
			(type default)
		)
		(layer "In2.Cu")
	)
	(gr_line
		(start 403.353016 -14.021562)
		(end 403.37613 -14.016482)
		(stroke
			(width 0.05715)
			(type default)
		)
		(layer "In2.Cu")
	)
	(gr_line
		(start 403.356572 -12.705334)
		(end 403.379432 -12.700508)
		(stroke
			(width 0.05715)
			(type default)
		)
		(layer "In2.Cu")
	)
	(gr_line
		(start 403.362414 -10.01522)
		(end 403.385528 -10.0203)
		(stroke
			(width 0.05715)
			(type default)
		)
		(layer "In2.Cu")
	)
	(gr_line
		(start 403.36343 -13.36929)
		(end 403.386544 -13.36421)
		(stroke
			(width 0.05715)
			(type default)
		)
		(layer "In2.Cu")
	)
	(gr_line
		(start 403.363684 -12.035028)
		(end 403.386798 -12.040108)
		(stroke
			(width 0.05715)
			(type default)
		)
		(layer "In2.Cu")
	)
	(gr_line
		(start 403.36851 -15.538704)
		(end 403.389846 -15.543022)
		(stroke
			(width 0.05715)
			(type default)
		)
		(layer "In2.Cu")
	)
	(gr_line
		(start 403.37105 -14.67739)
		(end 403.394164 -14.68247)
		(stroke
			(width 0.05715)
			(type default)
		)
		(layer "In2.Cu")
	)
	(gr_line
		(start 403.375622 -10.680192)
		(end 403.398736 -10.685272)
		(stroke
			(width 0.05715)
			(type default)
		)
		(layer "In2.Cu")
	)
	(gr_line
		(start 403.37613 -14.016482)
		(end 403.399244 -14.021562)
		(stroke
			(width 0.05715)
			(type default)
		)
		(layer "In2.Cu")
	)
	(gr_line
		(start 403.379432 -12.700508)
		(end 403.402546 -12.705588)
		(stroke
			(width 0.05715)
			(type default)
		)
		(layer "In2.Cu")
	)
	(gr_line
		(start 403.386036 -9.222232)
		(end 403.40915 -9.227312)
		(stroke
			(width 0.05715)
			(type default)
		)
		(layer "In2.Cu")
	)
	(gr_line
		(start 403.386544 -13.36421)
		(end 403.409658 -13.36929)
		(stroke
			(width 0.05715)
			(type default)
		)
		(layer "In2.Cu")
	)
	(gr_line
		(start 403.40915 -9.227312)
		(end 403.432264 -9.222232)
		(stroke
			(width 0.05715)
			(type default)
		)
		(layer "In2.Cu")
	)
	(gr_line
		(start 403.424898 -11.362944)
		(end 403.448012 -11.357864)
		(stroke
			(width 0.05715)
			(type default)
		)
		(layer "In2.Cu")
	)
	(gr_line
		(start 403.448012 -11.357864)
		(end 403.471126 -11.362944)
		(stroke
			(width 0.05715)
			(type default)
		)
		(layer "In2.Cu")
	)
	(gr_line
		(start 404.00732 -119.98198)
		(end 404.26894 -120.2436)
		(stroke
			(width 0.05715)
			(type default)
		)
		(layer "In2.Cu")
	)
	(gr_line
		(start 404.492714 -7.357364)
		(end 404.515828 -7.352284)
		(stroke
			(width 0.05715)
			(type default)
		)
		(layer "In2.Cu")
	)
	(gr_line
		(start 404.515828 -7.352284)
		(end 404.538942 -7.357364)
		(stroke
			(width 0.05715)
			(type default)
		)
		(layer "In2.Cu")
	)
	(gr_line
		(start 404.524718 -8.015732)
		(end 404.547832 -8.010652)
		(stroke
			(width 0.05715)
			(type default)
		)
		(layer "In2.Cu")
	)
	(gr_line
		(start 404.547832 -8.010652)
		(end 404.570946 -8.015732)
		(stroke
			(width 0.05715)
			(type default)
		)
		(layer "In2.Cu")
	)
	(gr_line
		(start 404.581614 -8.679688)
		(end 404.604728 -8.674608)
		(stroke
			(width 0.05715)
			(type default)
		)
		(layer "In2.Cu")
	)
	(gr_line
		(start 404.604728 -8.674608)
		(end 404.627842 -8.679688)
		(stroke
			(width 0.05715)
			(type default)
		)
		(layer "In2.Cu")
	)
	(gr_line
		(start 404.667466 -1.213612)
		(end 404.69058 -1.208532)
		(stroke
			(width 0.05715)
			(type default)
		)
		(layer "In2.Cu")
	)
	(gr_line
		(start 404.6855 -120.2436)
		(end 404.94712 -119.98198)
		(stroke
			(width 0.05715)
			(type default)
		)
		(layer "In2.Cu")
	)
	(gr_line
		(start 404.69058 -1.208532)
		(end 404.713694 -1.213612)
		(stroke
			(width 0.05715)
			(type default)
		)
		(layer "In2.Cu")
	)
	(gr_line
		(start 404.737316 -138.095228)
		(end 404.73757 -138.095228)
		(stroke
			(width 0.05715)
			(type default)
		)
		(layer "In2.Cu")
	)
	(gr_line
		(start 404.833328 -6.635496)
		(end 404.856442 -6.630416)
		(stroke
			(width 0.05715)
			(type default)
		)
		(layer "In2.Cu")
	)
	(gr_line
		(start 404.856442 -6.630416)
		(end 404.879556 -6.635496)
		(stroke
			(width 0.05715)
			(type default)
		)
		(layer "In2.Cu")
	)
	(gr_line
		(start 404.944072 -137.888472)
		(end 404.944326 -137.888472)
		(stroke
			(width 0.05715)
			(type default)
		)
		(layer "In2.Cu")
	)
	(gr_line
		(start 405.025352 -137.922)
		(end 405.02713 -137.922)
		(stroke
			(width 0.05715)
			(type default)
		)
		(layer "In2.Cu")
	)
	(gr_line
		(start 405.055832 -14.017752)
		(end 405.078946 -14.022832)
		(stroke
			(width 0.05715)
			(type default)
		)
		(layer "In2.Cu")
	)
	(gr_line
		(start 405.055832 -13.355574)
		(end 405.078946 -13.360654)
		(stroke
			(width 0.05715)
			(type default)
		)
		(layer "In2.Cu")
	)
	(gr_line
		(start 405.056086 -12.693396)
		(end 405.0792 -12.698476)
		(stroke
			(width 0.05715)
			(type default)
		)
		(layer "In2.Cu")
	)
	(gr_line
		(start 405.073612 -15.338298)
		(end 405.096726 -15.343378)
		(stroke
			(width 0.05715)
			(type default)
		)
		(layer "In2.Cu")
	)
	(gr_line
		(start 405.073866 -14.67612)
		(end 405.09698 -14.6812)
		(stroke
			(width 0.05715)
			(type default)
		)
		(layer "In2.Cu")
	)
	(gr_line
		(start 405.078946 -14.022832)
		(end 405.10206 -14.017752)
		(stroke
			(width 0.05715)
			(type default)
		)
		(layer "In2.Cu")
	)
	(gr_line
		(start 405.078946 -13.360654)
		(end 405.102822 -13.355574)
		(stroke
			(width 0.05715)
			(type default)
		)
		(layer "In2.Cu")
	)
	(gr_line
		(start 405.0792 -12.698476)
		(end 405.102314 -12.693396)
		(stroke
			(width 0.05715)
			(type default)
		)
		(layer "In2.Cu")
	)
	(gr_line
		(start 405.096726 -15.343378)
		(end 405.11984 -15.338298)
		(stroke
			(width 0.05715)
			(type default)
		)
		(layer "In2.Cu")
	)
	(gr_line
		(start 405.09698 -14.6812)
		(end 405.120094 -14.67612)
		(stroke
			(width 0.05715)
			(type default)
		)
		(layer "In2.Cu")
	)
	(gr_line
		(start 405.133556 -12.014708)
		(end 405.15667 -12.019788)
		(stroke
			(width 0.05715)
			(type default)
		)
		(layer "In2.Cu")
	)
	(gr_line
		(start 405.133556 -11.35253)
		(end 405.15667 -11.35761)
		(stroke
			(width 0.05715)
			(type default)
		)
		(layer "In2.Cu")
	)
	(gr_line
		(start 405.133556 -10.690352)
		(end 405.15667 -10.695432)
		(stroke
			(width 0.05715)
			(type default)
		)
		(layer "In2.Cu")
	)
	(gr_line
		(start 405.15667 -12.019788)
		(end 405.179784 -12.014708)
		(stroke
			(width 0.05715)
			(type default)
		)
		(layer "In2.Cu")
	)
	(gr_line
		(start 405.15667 -11.35761)
		(end 405.179784 -11.35253)
		(stroke
			(width 0.05715)
			(type default)
		)
		(layer "In2.Cu")
	)
	(gr_line
		(start 405.15667 -10.695432)
		(end 405.179784 -10.690352)
		(stroke
			(width 0.05715)
			(type default)
		)
		(layer "In2.Cu")
	)
	(gr_line
		(start 405.498046 -7.859522)
		(end 405.52116 -7.864602)
		(stroke
			(width 0.05715)
			(type default)
		)
		(layer "In2.Cu")
	)
	(gr_line
		(start 405.515826 -8.514842)
		(end 405.53894 -8.519922)
		(stroke
			(width 0.05715)
			(type default)
		)
		(layer "In2.Cu")
	)
	(gr_line
		(start 405.52116 -7.864602)
		(end 405.544274 -7.859522)
		(stroke
			(width 0.05715)
			(type default)
		)
		(layer "In2.Cu")
	)
	(gr_line
		(start 405.52751 -9.169146)
		(end 405.550624 -9.174226)
		(stroke
			(width 0.05715)
			(type default)
		)
		(layer "In2.Cu")
	)
	(gr_line
		(start 405.53894 -8.519922)
		(end 405.562054 -8.514842)
		(stroke
			(width 0.05715)
			(type default)
		)
		(layer "In2.Cu")
	)
	(gr_line
		(start 405.550624 -9.174226)
		(end 405.573738 -9.169146)
		(stroke
			(width 0.05715)
			(type default)
		)
		(layer "In2.Cu")
	)
	(gr_line
		(start 405.821134 -7.134098)
		(end 405.844248 -7.139178)
		(stroke
			(width 0.05715)
			(type default)
		)
		(layer "In2.Cu")
	)
	(gr_line
		(start 405.844248 -7.139178)
		(end 405.867362 -7.134098)
		(stroke
			(width 0.05715)
			(type default)
		)
		(layer "In2.Cu")
	)
	(gr_line
		(start 405.872188 -3.451606)
		(end 405.895302 -3.44678)
		(stroke
			(width 0.05715)
			(type default)
		)
		(layer "In2.Cu")
	)
	(gr_line
		(start 405.873966 -4.771644)
		(end 405.89708 -4.766564)
		(stroke
			(width 0.05715)
			(type default)
		)
		(layer "In2.Cu")
	)
	(gr_line
		(start 405.882094 -4.107942)
		(end 405.905208 -4.102862)
		(stroke
			(width 0.05715)
			(type default)
		)
		(layer "In2.Cu")
	)
	(gr_line
		(start 405.895302 -3.44678)
		(end 405.917146 -3.451606)
		(stroke
			(width 0.05715)
			(type default)
		)
		(layer "In2.Cu")
	)
	(gr_line
		(start 405.89708 -4.766564)
		(end 405.920194 -4.771644)
		(stroke
			(width 0.05715)
			(type default)
		)
		(layer "In2.Cu")
	)
	(gr_line
		(start 405.905208 -4.102862)
		(end 405.928322 -4.107942)
		(stroke
			(width 0.05715)
			(type default)
		)
		(layer "In2.Cu")
	)
	(gr_arc
		(start 406.454356 -144.7165)
		(mid 406.498097 -144.707799)
		(end 406.535128 -144.682972)
		(stroke
			(width 0.05715)
			(type default)
		)
		(layer "In2.Cu")
	)
	(gr_arc
		(start 406.535128 -145.042128)
		(mid 406.498095 -145.017275)
		(end 406.454356 -145.0086)
		(stroke
			(width 0.05715)
			(type default)
		)
		(layer "In2.Cu")
	)
	(gr_line
		(start 406.535128 -145.042128)
		(end 406.86355 -145.37055)
		(stroke
			(width 0.05715)
			(type default)
		)
		(layer "In2.Cu")
	)
	(gr_line
		(start 406.535128 -144.682972)
		(end 406.86355 -144.35455)
		(stroke
			(width 0.05715)
			(type default)
		)
		(layer "In2.Cu")
	)
	(gr_line
		(start 406.728422 -7.309612)
		(end 406.751536 -7.304532)
		(stroke
			(width 0.05715)
			(type default)
		)
		(layer "In2.Cu")
	)
	(gr_line
		(start 406.73401 -6.651752)
		(end 406.757124 -6.646672)
		(stroke
			(width 0.05715)
			(type default)
		)
		(layer "In2.Cu")
	)
	(gr_line
		(start 406.746456 -7.964932)
		(end 406.76957 -7.959852)
		(stroke
			(width 0.05715)
			(type default)
		)
		(layer "In2.Cu")
	)
	(gr_line
		(start 406.751536 -7.304532)
		(end 406.77465 -7.309612)
		(stroke
			(width 0.05715)
			(type default)
		)
		(layer "In2.Cu")
	)
	(gr_line
		(start 406.757124 -6.646672)
		(end 406.780238 -6.651752)
		(stroke
			(width 0.05715)
			(type default)
		)
		(layer "In2.Cu")
	)
	(gr_line
		(start 406.757886 -8.619236)
		(end 406.781 -8.614156)
		(stroke
			(width 0.05715)
			(type default)
		)
		(layer "In2.Cu")
	)
	(gr_line
		(start 406.76957 -7.959852)
		(end 406.792684 -7.964932)
		(stroke
			(width 0.05715)
			(type default)
		)
		(layer "In2.Cu")
	)
	(gr_line
		(start 406.781 -8.614156)
		(end 406.804114 -8.619236)
		(stroke
			(width 0.05715)
			(type default)
		)
		(layer "In2.Cu")
	)
	(gr_arc
		(start 407.513282 -147.30095)
		(mid 407.557023 -147.292249)
		(end 407.594054 -147.267422)
		(stroke
			(width 0.05715)
			(type default)
		)
		(layer "In2.Cu")
	)
	(gr_arc
		(start 407.594054 -147.626578)
		(mid 407.557014 -147.601759)
		(end 407.513282 -147.59305)
		(stroke
			(width 0.05715)
			(type default)
		)
		(layer "In2.Cu")
	)
	(gr_line
		(start 407.594054 -147.626578)
		(end 407.922476 -147.955)
		(stroke
			(width 0.05715)
			(type default)
		)
		(layer "In2.Cu")
	)
	(gr_line
		(start 407.594054 -147.267422)
		(end 407.922476 -146.939)
		(stroke
			(width 0.05715)
			(type default)
		)
		(layer "In2.Cu")
	)
	(gr_line
		(start 407.61793 -13.84681)
		(end 407.641044 -13.84173)
		(stroke
			(width 0.05715)
			(type default)
		)
		(layer "In2.Cu")
	)
	(gr_line
		(start 407.620724 -14.508226)
		(end 407.643838 -14.503146)
		(stroke
			(width 0.05715)
			(type default)
		)
		(layer "In2.Cu")
	)
	(gr_line
		(start 407.629868 -12.51966)
		(end 407.652982 -12.51458)
		(stroke
			(width 0.05715)
			(type default)
		)
		(layer "In2.Cu")
	)
	(gr_line
		(start 407.636218 -13.180568)
		(end 407.659332 -13.175488)
		(stroke
			(width 0.05715)
			(type default)
		)
		(layer "In2.Cu")
	)
	(gr_line
		(start 407.641044 -13.84173)
		(end 407.664158 -13.84681)
		(stroke
			(width 0.05715)
			(type default)
		)
		(layer "In2.Cu")
	)
	(gr_line
		(start 407.643838 -14.503146)
		(end 407.666952 -14.508226)
		(stroke
			(width 0.05715)
			(type default)
		)
		(layer "In2.Cu")
	)
	(gr_line
		(start 407.652982 -12.51458)
		(end 407.676096 -12.51966)
		(stroke
			(width 0.05715)
			(type default)
		)
		(layer "In2.Cu")
	)
	(gr_line
		(start 407.659332 -13.175488)
		(end 407.682446 -13.180568)
		(stroke
			(width 0.05715)
			(type default)
		)
		(layer "In2.Cu")
	)
	(gr_line
		(start 407.729944 -11.8364)
		(end 407.753058 -11.83132)
		(stroke
			(width 0.05715)
			(type default)
		)
		(layer "In2.Cu")
	)
	(gr_line
		(start 407.751026 -11.16965)
		(end 407.77414 -11.16457)
		(stroke
			(width 0.05715)
			(type default)
		)
		(layer "In2.Cu")
	)
	(gr_line
		(start 407.753058 -11.83132)
		(end 407.776172 -11.8364)
		(stroke
			(width 0.05715)
			(type default)
		)
		(layer "In2.Cu")
	)
	(gr_line
		(start 407.762456 -9.843008)
		(end 407.78557 -9.837928)
		(stroke
			(width 0.05715)
			(type default)
		)
		(layer "In2.Cu")
	)
	(gr_line
		(start 407.77414 -11.16457)
		(end 407.797254 -11.16965)
		(stroke
			(width 0.05715)
			(type default)
		)
		(layer "In2.Cu")
	)
	(gr_line
		(start 407.78557 -9.837928)
		(end 407.808684 -9.843008)
		(stroke
			(width 0.05715)
			(type default)
		)
		(layer "In2.Cu")
	)
	(gr_line
		(start 407.787602 -10.500106)
		(end 407.810716 -10.495026)
		(stroke
			(width 0.05715)
			(type default)
		)
		(layer "In2.Cu")
	)
	(gr_line
		(start 407.810716 -10.495026)
		(end 407.83383 -10.500106)
		(stroke
			(width 0.05715)
			(type default)
		)
		(layer "In2.Cu")
	)
	(gr_line
		(start 407.898092 -16.2687)
		(end 408.126438 -16.497046)
		(stroke
			(width 0.05715)
			(type default)
		)
		(layer "In2.Cu")
	)
	(gr_line
		(start 407.928064 -9.156446)
		(end 407.951178 -9.161526)
		(stroke
			(width 0.05715)
			(type default)
		)
		(layer "In2.Cu")
	)
	(gr_line
		(start 407.928064 -8.504682)
		(end 407.951178 -8.509762)
		(stroke
			(width 0.05715)
			(type default)
		)
		(layer "In2.Cu")
	)
	(gr_line
		(start 407.928064 -7.852918)
		(end 407.951178 -7.857998)
		(stroke
			(width 0.05715)
			(type default)
		)
		(layer "In2.Cu")
	)
	(gr_arc
		(start 407.93289 -142.277084)
		(mid 407.895852 -142.252252)
		(end 407.852118 -142.243556)
		(stroke
			(width 0.05715)
			(type default)
		)
		(layer "In2.Cu")
	)
	(gr_line
		(start 407.93289 -142.277084)
		(end 408.313382 -142.657576)
		(stroke
			(width 0.05715)
			(type default)
		)
		(layer "In2.Cu")
	)
	(gr_line
		(start 407.945336 -7.197344)
		(end 407.96845 -7.202424)
		(stroke
			(width 0.05715)
			(type default)
		)
		(layer "In2.Cu")
	)
	(gr_line
		(start 407.951178 -9.161526)
		(end 407.974292 -9.156446)
		(stroke
			(width 0.05715)
			(type default)
		)
		(layer "In2.Cu")
	)
	(gr_line
		(start 407.951178 -8.509762)
		(end 407.974292 -8.504682)
		(stroke
			(width 0.05715)
			(type default)
		)
		(layer "In2.Cu")
	)
	(gr_line
		(start 407.951178 -7.857998)
		(end 407.974292 -7.852918)
		(stroke
			(width 0.05715)
			(type default)
		)
		(layer "In2.Cu")
	)
	(gr_arc
		(start 407.956258 -141.951456)
		(mid 407.999964 -141.942692)
		(end 408.03703 -141.917928)
		(stroke
			(width 0.05715)
			(type default)
		)
		(layer "In2.Cu")
	)
	(gr_line
		(start 407.96845 -7.202424)
		(end 407.991564 -7.197344)
		(stroke
			(width 0.05715)
			(type default)
		)
		(layer "In2.Cu")
	)
	(gr_line
		(start 408.03703 -141.917928)
		(end 408.313382 -141.641576)
		(stroke
			(width 0.05715)
			(type default)
		)
		(layer "In2.Cu")
	)
	(gr_line
		(start 408.190192 -15.97406)
		(end 408.546808 -15.97406)
		(stroke
			(width 0.05715)
			(type default)
		)
		(layer "In2.Cu")
	)
	(gr_line
		(start 408.323796 -1.980438)
		(end 408.372818 -1.990852)
		(stroke
			(width 0.05715)
			(type default)
		)
		(layer "In2.Cu")
	)
	(gr_line
		(start 408.372818 -1.990852)
		(end 408.408378 -2.026412)
		(stroke
			(width 0.05715)
			(type default)
		)
		(layer "In2.Cu")
	)
	(gr_line
		(start 409.833826 -3.865372)
		(end 409.892754 -3.9243)
		(stroke
			(width 0.05715)
			(type default)
		)
		(layer "In2.Cu")
	)
	(gr_line
		(start 410.36875 -5.349494)
		(end 410.391864 -5.354574)
		(stroke
			(width 0.05715)
			(type default)
		)
		(layer "In2.Cu")
	)
	(gr_line
		(start 410.376878 -4.698238)
		(end 410.399992 -4.703318)
		(stroke
			(width 0.05715)
			(type default)
		)
		(layer "In2.Cu")
	)
	(gr_line
		(start 410.391864 -5.354574)
		(end 410.414978 -5.349494)
		(stroke
			(width 0.05715)
			(type default)
		)
		(layer "In2.Cu")
	)
	(gr_line
		(start 410.399992 -4.703318)
		(end 410.423106 -4.698238)
		(stroke
			(width 0.05715)
			(type default)
		)
		(layer "In2.Cu")
	)
	(gr_line
		(start 410.405834 -6.023102)
		(end 410.428948 -6.028182)
		(stroke
			(width 0.05715)
			(type default)
		)
		(layer "In2.Cu")
	)
	(gr_line
		(start 410.428948 -6.028182)
		(end 410.452062 -6.023102)
		(stroke
			(width 0.05715)
			(type default)
		)
		(layer "In2.Cu")
	)
	(gr_line
		(start 410.81706 -3.9243)
		(end 410.825442 -3.921506)
		(stroke
			(width 0.05715)
			(type default)
		)
		(layer "In2.Cu")
	)
	(gr_line
		(start 411.428692 -2.73177)
		(end 411.752542 -2.73177)
		(stroke
			(width 0.05715)
			(type default)
		)
		(layer "In2.Cu")
	)
	(gr_line
		(start 411.480254 -5.506212)
		(end 411.503368 -5.501132)
		(stroke
			(width 0.05715)
			(type default)
		)
		(layer "In2.Cu")
	)
	(gr_line
		(start 411.480508 -6.157976)
		(end 411.503622 -6.152896)
		(stroke
			(width 0.05715)
			(type default)
		)
		(layer "In2.Cu")
	)
	(gr_line
		(start 411.480762 -7.461504)
		(end 411.503876 -7.456424)
		(stroke
			(width 0.05715)
			(type default)
		)
		(layer "In2.Cu")
	)
	(gr_line
		(start 411.481016 -6.80974)
		(end 411.50413 -6.80466)
		(stroke
			(width 0.05715)
			(type default)
		)
		(layer "In2.Cu")
	)
	(gr_line
		(start 411.48127 -8.113014)
		(end 411.504384 -8.107934)
		(stroke
			(width 0.05715)
			(type default)
		)
		(layer "In2.Cu")
	)
	(gr_line
		(start 411.503368 -5.501132)
		(end 411.526482 -5.506212)
		(stroke
			(width 0.05715)
			(type default)
		)
		(layer "In2.Cu")
	)
	(gr_line
		(start 411.503622 -6.152896)
		(end 411.526736 -6.157976)
		(stroke
			(width 0.05715)
			(type default)
		)
		(layer "In2.Cu")
	)
	(gr_line
		(start 411.503876 -7.456424)
		(end 411.52699 -7.461504)
		(stroke
			(width 0.05715)
			(type default)
		)
		(layer "In2.Cu")
	)
	(gr_line
		(start 411.50413 -6.80466)
		(end 411.527244 -6.80974)
		(stroke
			(width 0.05715)
			(type default)
		)
		(layer "In2.Cu")
	)
	(gr_line
		(start 411.504384 -8.107934)
		(end 411.527498 -8.113014)
		(stroke
			(width 0.05715)
			(type default)
		)
		(layer "In2.Cu")
	)
	(gr_line
		(start 411.657292 -3.644392)
		(end 411.68828 -3.633978)
		(stroke
			(width 0.05715)
			(type default)
		)
		(layer "In2.Cu")
	)
	(gr_line
		(start 411.752542 -2.73177)
		(end 411.804612 -2.78384)
		(stroke
			(width 0.05715)
			(type default)
		)
		(layer "In2.Cu")
	)
	(gr_line
		(start 412.14929 -10.1346)
		(end 412.534354 -10.137394)
		(stroke
			(width 0.05715)
			(type default)
		)
		(layer "In2.Cu")
	)
	(gr_line
		(start 412.221172 -2.78384)
		(end 412.273242 -2.73177)
		(stroke
			(width 0.05715)
			(type default)
		)
		(layer "In2.Cu")
	)
	(gr_line
		(start 412.273242 -2.73177)
		(end 412.698692 -2.73177)
		(stroke
			(width 0.05715)
			(type default)
		)
		(layer "In2.Cu")
	)
	(gr_line
		(start 412.413958 -15.15364)
		(end 412.437072 -15.15872)
		(stroke
			(width 0.05715)
			(type default)
		)
		(layer "In2.Cu")
	)
	(gr_line
		(start 412.430722 -15.818358)
		(end 412.453836 -15.823438)
		(stroke
			(width 0.05715)
			(type default)
		)
		(layer "In2.Cu")
	)
	(gr_line
		(start 412.435802 -13.828776)
		(end 412.458916 -13.833856)
		(stroke
			(width 0.05715)
			(type default)
		)
		(layer "In2.Cu")
	)
	(gr_line
		(start 412.43631 -14.488922)
		(end 412.459424 -14.494002)
		(stroke
			(width 0.05715)
			(type default)
		)
		(layer "In2.Cu")
	)
	(gr_line
		(start 412.437072 -15.15872)
		(end 412.460186 -15.15364)
		(stroke
			(width 0.05715)
			(type default)
		)
		(layer "In2.Cu")
	)
	(gr_line
		(start 412.453836 -15.823438)
		(end 412.47695 -15.818358)
		(stroke
			(width 0.05715)
			(type default)
		)
		(layer "In2.Cu")
	)
	(gr_line
		(start 412.458916 -13.833856)
		(end 412.48203 -13.828776)
		(stroke
			(width 0.05715)
			(type default)
		)
		(layer "In2.Cu")
	)
	(gr_line
		(start 412.459424 -14.494002)
		(end 412.482538 -14.488922)
		(stroke
			(width 0.05715)
			(type default)
		)
		(layer "In2.Cu")
	)
	(gr_line
		(start 412.496762 -13.137642)
		(end 412.519876 -13.142722)
		(stroke
			(width 0.05715)
			(type default)
		)
		(layer "In2.Cu")
	)
	(gr_line
		(start 412.507938 -12.468606)
		(end 412.531052 -12.473686)
		(stroke
			(width 0.05715)
			(type default)
		)
		(layer "In2.Cu")
	)
	(gr_line
		(start 412.519876 -13.142722)
		(end 412.54299 -13.137642)
		(stroke
			(width 0.05715)
			(type default)
		)
		(layer "In2.Cu")
	)
	(gr_line
		(start 412.531052 -12.473686)
		(end 412.554166 -12.468606)
		(stroke
			(width 0.05715)
			(type default)
		)
		(layer "In2.Cu")
	)
	(gr_line
		(start 412.534354 -10.137394)
		(end 412.644844 -10.249916)
		(stroke
			(width 0.05715)
			(type default)
		)
		(layer "In2.Cu")
	)
	(gr_line
		(start 412.568898 -11.805158)
		(end 412.592012 -11.810238)
		(stroke
			(width 0.05715)
			(type default)
		)
		(layer "In2.Cu")
	)
	(gr_line
		(start 412.591758 -11.0617)
		(end 412.65094 -11.002772)
		(stroke
			(width 0.05715)
			(type default)
		)
		(layer "In2.Cu")
	)
	(gr_line
		(start 412.592012 -11.810238)
		(end 412.615126 -11.805158)
		(stroke
			(width 0.05715)
			(type default)
		)
		(layer "In2.Cu")
	)
	(gr_arc
		(start 412.659576 -141.397228)
		(mid 412.740398 -141.36375)
		(end 412.773876 -141.282928)
		(stroke
			(width 0.05715)
			(type default)
		)
		(layer "In2.Cu")
	)
	(gr_arc
		(start 412.773876 -141.803628)
		(mid 412.740398 -141.722806)
		(end 412.659576 -141.689328)
		(stroke
			(width 0.05715)
			(type default)
		)
		(layer "In2.Cu")
	)
	(gr_line
		(start 412.773876 -141.803628)
		(end 412.773876 -142.0368)
		(stroke
			(width 0.05715)
			(type default)
		)
		(layer "In2.Cu")
	)
	(gr_line
		(start 412.773876 -141.0208)
		(end 412.773876 -141.282928)
		(stroke
			(width 0.05715)
			(type default)
		)
		(layer "In2.Cu")
	)
	(gr_line
		(start 412.878524 -10.775188)
		(end 412.937706 -10.716006)
		(stroke
			(width 0.05715)
			(type default)
		)
		(layer "In2.Cu")
	)
	(gr_line
		(start 412.937706 -10.716006)
		(end 412.93796 -10.632948)
		(stroke
			(width 0.05715)
			(type default)
		)
		(layer "In2.Cu")
	)
	(gr_line
		(start 412.942024 -10.25144)
		(end 413.054546 -10.140442)
		(stroke
			(width 0.05715)
			(type default)
		)
		(layer "In2.Cu")
	)
	(gr_line
		(start 413.054546 -10.140442)
		(end 413.43961 -10.143236)
		(stroke
			(width 0.05715)
			(type default)
		)
		(layer "In2.Cu")
	)
	(gr_line
		(start 413.803592 -1.73355)
		(end 414.127442 -1.73355)
		(stroke
			(width 0.05715)
			(type default)
		)
		(layer "In2.Cu")
	)
	(gr_line
		(start 414.063688 -3.926078)
		(end 414.128204 -3.912362)
		(stroke
			(width 0.05715)
			(type default)
		)
		(layer "In2.Cu")
	)
	(gr_line
		(start 414.127442 -1.73355)
		(end 414.179512 -1.78562)
		(stroke
			(width 0.05715)
			(type default)
		)
		(layer "In2.Cu")
	)
	(gr_line
		(start 414.128204 -3.912362)
		(end 414.170114 -3.8608)
		(stroke
			(width 0.05715)
			(type default)
		)
		(layer "In2.Cu")
	)
	(gr_line
		(start 414.492694 -3.462274)
		(end 414.533842 -3.411474)
		(stroke
			(width 0.05715)
			(type default)
		)
		(layer "In2.Cu")
	)
	(gr_line
		(start 414.596072 -1.78562)
		(end 414.648142 -1.73355)
		(stroke
			(width 0.05715)
			(type default)
		)
		(layer "In2.Cu")
	)
	(gr_line
		(start 414.629092 -10.124948)
		(end 414.984946 -10.124948)
		(stroke
			(width 0.05715)
			(type default)
		)
		(layer "In2.Cu")
	)
	(gr_line
		(start 414.648142 -1.73355)
		(end 415.073592 -1.73355)
		(stroke
			(width 0.05715)
			(type default)
		)
		(layer "In2.Cu")
	)
	(gr_line
		(start 414.67405 -4.53136)
		(end 414.83661 -4.3688)
		(stroke
			(width 0.05715)
			(type default)
		)
		(layer "In2.Cu")
	)
	(gr_line
		(start 414.83661 -4.3688)
		(end 415.17951 -4.3688)
		(stroke
			(width 0.05715)
			(type default)
		)
		(layer "In2.Cu")
	)
	(gr_line
		(start 414.921954 -11.315446)
		(end 414.970976 -11.305032)
		(stroke
			(width 0.05715)
			(type default)
		)
		(layer "In2.Cu")
	)
	(gr_line
		(start 414.96615 -4.826)
		(end 415.04997 -4.826)
		(stroke
			(width 0.05715)
			(type default)
		)
		(layer "In2.Cu")
	)
	(gr_line
		(start 414.970976 -11.305032)
		(end 415.006536 -11.269472)
		(stroke
			(width 0.05715)
			(type default)
		)
		(layer "In2.Cu")
	)
	(gr_line
		(start 414.984946 -10.124948)
		(end 415.037016 -10.177018)
		(stroke
			(width 0.05715)
			(type default)
		)
		(layer "In2.Cu")
	)
	(gr_line
		(start 415.17951 -4.3688)
		(end 415.34207 -4.53136)
		(stroke
			(width 0.05715)
			(type default)
		)
		(layer "In2.Cu")
	)
	(gr_line
		(start 415.332418 -10.94359)
		(end 415.391346 -10.884662)
		(stroke
			(width 0.05715)
			(type default)
		)
		(layer "In2.Cu")
	)
	(gr_line
		(start 415.453576 -10.177018)
		(end 415.505646 -10.124948)
		(stroke
			(width 0.05715)
			(type default)
		)
		(layer "In2.Cu")
	)
	(gr_line
		(start 415.468054 -6.641846)
		(end 415.491168 -6.646926)
		(stroke
			(width 0.05715)
			(type default)
		)
		(layer "In2.Cu")
	)
	(gr_line
		(start 415.491168 -6.646926)
		(end 415.514282 -6.641846)
		(stroke
			(width 0.05715)
			(type default)
		)
		(layer "In2.Cu")
	)
	(gr_line
		(start 415.505646 -10.124948)
		(end 415.899092 -10.124948)
		(stroke
			(width 0.05715)
			(type default)
		)
		(layer "In2.Cu")
	)
	(gr_line
		(start 415.511742 -7.303008)
		(end 415.534856 -7.308088)
		(stroke
			(width 0.05715)
			(type default)
		)
		(layer "In2.Cu")
	)
	(gr_line
		(start 415.52368 -7.957312)
		(end 415.546794 -7.962392)
		(stroke
			(width 0.05715)
			(type default)
		)
		(layer "In2.Cu")
	)
	(gr_line
		(start 415.534856 -7.308088)
		(end 415.55797 -7.303008)
		(stroke
			(width 0.05715)
			(type default)
		)
		(layer "In2.Cu")
	)
	(gr_line
		(start 415.546794 -7.962392)
		(end 415.569908 -7.957312)
		(stroke
			(width 0.05715)
			(type default)
		)
		(layer "In2.Cu")
	)
	(gr_line
		(start 415.5694 -8.618728)
		(end 415.592514 -8.623808)
		(stroke
			(width 0.05715)
			(type default)
		)
		(layer "In2.Cu")
	)
	(gr_line
		(start 415.592514 -8.623808)
		(end 415.615628 -8.618728)
		(stroke
			(width 0.05715)
			(type default)
		)
		(layer "In2.Cu")
	)
	(gr_line
		(start 415.751264 -4.826)
		(end 415.773616 -4.815586)
		(stroke
			(width 0.05715)
			(type default)
		)
		(layer "In2.Cu")
	)
	(gr_line
		(start 415.817812 -9.323578)
		(end 415.840926 -9.328658)
		(stroke
			(width 0.05715)
			(type default)
		)
		(layer "In2.Cu")
	)
	(gr_line
		(start 415.840926 -9.328658)
		(end 415.86404 -9.323578)
		(stroke
			(width 0.05715)
			(type default)
		)
		(layer "In2.Cu")
	)
	(gr_line
		(start 416.27171 -2.82067)
		(end 416.615372 -2.82067)
		(stroke
			(width 0.05715)
			(type default)
		)
		(layer "In2.Cu")
	)
	(gr_line
		(start 416.615372 -2.82067)
		(end 416.685476 -2.890774)
		(stroke
			(width 0.05715)
			(type default)
		)
		(layer "In2.Cu")
	)
	(gr_line
		(start 416.704018 -4.390644)
		(end 416.717226 -4.384548)
		(stroke
			(width 0.05715)
			(type default)
		)
		(layer "In2.Cu")
	)
	(gr_line
		(start 417.014152 -6.323584)
		(end 417.021264 -6.32206)
		(stroke
			(width 0.05715)
			(type default)
		)
		(layer "In2.Cu")
	)
	(gr_line
		(start 417.021264 -6.32206)
		(end 417.027614 -6.318504)
		(stroke
			(width 0.05715)
			(type default)
		)
		(layer "In2.Cu")
	)
	(gr_line
		(start 417.029392 -10.023348)
		(end 417.415472 -10.023348)
		(stroke
			(width 0.05715)
			(type default)
		)
		(layer "In2.Cu")
	)
	(gr_line
		(start 417.102036 -2.890774)
		(end 417.17214 -2.82067)
		(stroke
			(width 0.05715)
			(type default)
		)
		(layer "In2.Cu")
	)
	(gr_line
		(start 417.17214 -2.82067)
		(end 417.54171 -2.82067)
		(stroke
			(width 0.05715)
			(type default)
		)
		(layer "In2.Cu")
	)
	(gr_line
		(start 417.375594 -11.445748)
		(end 417.426902 -11.434826)
		(stroke
			(width 0.05715)
			(type default)
		)
		(layer "In2.Cu")
	)
	(gr_line
		(start 417.415472 -10.023348)
		(end 417.467542 -10.075418)
		(stroke
			(width 0.05715)
			(type default)
		)
		(layer "In2.Cu")
	)
	(gr_line
		(start 417.762944 -11.09853)
		(end 417.821872 -11.039602)
		(stroke
			(width 0.05715)
			(type default)
		)
		(layer "In2.Cu")
	)
	(gr_line
		(start 417.884102 -10.075418)
		(end 417.936172 -10.023348)
		(stroke
			(width 0.05715)
			(type default)
		)
		(layer "In2.Cu")
	)
	(gr_line
		(start 417.936172 -10.023348)
		(end 418.299392 -10.023348)
		(stroke
			(width 0.05715)
			(type default)
		)
		(layer "In2.Cu")
	)
	(gr_line
		(start 418.04463 -6.775196)
		(end 418.050472 -6.773926)
		(stroke
			(width 0.05715)
			(type default)
		)
		(layer "In2.Cu")
	)
	(gr_line
		(start 418.050472 -6.773926)
		(end 418.05606 -6.770878)
		(stroke
			(width 0.05715)
			(type default)
		)
		(layer "In2.Cu")
	)
	(gr_line
		(start 418.781992 -1.60655)
		(end 419.207442 -1.60655)
		(stroke
			(width 0.05715)
			(type default)
		)
		(layer "In2.Cu")
	)
	(gr_line
		(start 418.925756 -5.251196)
		(end 418.979858 -5.220716)
		(stroke
			(width 0.05715)
			(type default)
		)
		(layer "In2.Cu")
	)
	(gr_line
		(start 418.972238 -11.773154)
		(end 419.02126 -11.76274)
		(stroke
			(width 0.05715)
			(type default)
		)
		(layer "In2.Cu")
	)
	(gr_line
		(start 418.979858 -5.220716)
		(end 419.004496 -5.162804)
		(stroke
			(width 0.05715)
			(type default)
		)
		(layer "In2.Cu")
	)
	(gr_line
		(start 419.02126 -11.76274)
		(end 419.05682 -11.72718)
		(stroke
			(width 0.05715)
			(type default)
		)
		(layer "In2.Cu")
	)
	(gr_line
		(start 419.207442 -1.60655)
		(end 419.259512 -1.65862)
		(stroke
			(width 0.05715)
			(type default)
		)
		(layer "In2.Cu")
	)
	(gr_line
		(start 419.280848 -12.386056)
		(end 419.32987 -12.375642)
		(stroke
			(width 0.05715)
			(type default)
		)
		(layer "In2.Cu")
	)
	(gr_line
		(start 419.32987 -12.375642)
		(end 419.36543 -12.340082)
		(stroke
			(width 0.05715)
			(type default)
		)
		(layer "In2.Cu")
	)
	(gr_line
		(start 419.402514 -4.226306)
		(end 419.410642 -4.207256)
		(stroke
			(width 0.05715)
			(type default)
		)
		(layer "In2.Cu")
	)
	(gr_line
		(start 419.429692 -10.023348)
		(end 419.826948 -10.023348)
		(stroke
			(width 0.05715)
			(type default)
		)
		(layer "In2.Cu")
	)
	(gr_line
		(start 419.474904 -147.32762)
		(end 419.663626 -147.32762)
		(stroke
			(width 0.05715)
			(type default)
		)
		(layer "In2.Cu")
	)
	(gr_arc
		(start 419.514528 -147.653502)
		(mid 419.482589 -147.631044)
		(end 419.444932 -147.620736)
		(stroke
			(width 0.05715)
			(type default)
		)
		(layer "In2.Cu")
	)
	(gr_line
		(start 419.514528 -147.653502)
		(end 419.777926 -147.9169)
		(stroke
			(width 0.05715)
			(type default)
		)
		(layer "In2.Cu")
	)
	(gr_arc
		(start 419.663626 -147.32762)
		(mid 419.744448 -147.294142)
		(end 419.777926 -147.21332)
		(stroke
			(width 0.05715)
			(type default)
		)
		(layer "In2.Cu")
	)
	(gr_line
		(start 419.676072 -1.65862)
		(end 419.728142 -1.60655)
		(stroke
			(width 0.05715)
			(type default)
		)
		(layer "In2.Cu")
	)
	(gr_line
		(start 419.696392 -126.50978)
		(end 419.858952 -126.34722)
		(stroke
			(width 0.05715)
			(type default)
		)
		(layer "In2.Cu")
	)
	(gr_line
		(start 419.728142 -1.60655)
		(end 420.051992 -1.60655)
		(stroke
			(width 0.05715)
			(type default)
		)
		(layer "In2.Cu")
	)
	(gr_line
		(start 419.777926 -146.9009)
		(end 419.777926 -147.21332)
		(stroke
			(width 0.05715)
			(type default)
		)
		(layer "In2.Cu")
	)
	(gr_line
		(start 419.826948 -10.023348)
		(end 419.88232 -10.07872)
		(stroke
			(width 0.05715)
			(type default)
		)
		(layer "In2.Cu")
	)
	(gr_line
		(start 419.858952 -126.34722)
		(end 420.201852 -126.34722)
		(stroke
			(width 0.05715)
			(type default)
		)
		(layer "In2.Cu")
	)
	(gr_line
		(start 419.988492 -126.80442)
		(end 420.072312 -126.80442)
		(stroke
			(width 0.05715)
			(type default)
		)
		(layer "In2.Cu")
	)
	(gr_line
		(start 420.171372 -10.612628)
		(end 420.2303 -10.5537)
		(stroke
			(width 0.05715)
			(type default)
		)
		(layer "In2.Cu")
	)
	(gr_line
		(start 420.201852 -126.34722)
		(end 420.364412 -126.50978)
		(stroke
			(width 0.05715)
			(type default)
		)
		(layer "In2.Cu")
	)
	(gr_line
		(start 420.299134 -10.07872)
		(end 420.354506 -10.023348)
		(stroke
			(width 0.05715)
			(type default)
		)
		(layer "In2.Cu")
	)
	(gr_line
		(start 420.354506 -10.023348)
		(end 420.699692 -10.023348)
		(stroke
			(width 0.05715)
			(type default)
		)
		(layer "In2.Cu")
	)
	(gr_line
		(start 420.692072 -10.599928)
		(end 420.751 -10.541)
		(stroke
			(width 0.05715)
			(type default)
		)
		(layer "In2.Cu")
	)
	(gr_line
		(start 420.971726 -2.605532)
		(end 421.375078 -2.605532)
		(stroke
			(width 0.05715)
			(type default)
		)
		(layer "In2.Cu")
	)
	(gr_line
		(start 421.323516 -139.954)
		(end 421.7289 -139.954)
		(stroke
			(width 0.05715)
			(type default)
		)
		(layer "In2.Cu")
	)
	(gr_line
		(start 421.368982 -12.60221)
		(end 421.418004 -12.591796)
		(stroke
			(width 0.05715)
			(type default)
		)
		(layer "In2.Cu")
	)
	(gr_line
		(start 421.375078 -2.605532)
		(end 421.444166 -2.67462)
		(stroke
			(width 0.05715)
			(type default)
		)
		(layer "In2.Cu")
	)
	(gr_line
		(start 421.418004 -12.591796)
		(end 421.453564 -12.556236)
		(stroke
			(width 0.05715)
			(type default)
		)
		(layer "In2.Cu")
	)
	(gr_line
		(start 421.527732 -4.846066)
		(end 421.57777 -4.81838)
		(stroke
			(width 0.05715)
			(type default)
		)
		(layer "In2.Cu")
	)
	(gr_line
		(start 421.57777 -4.81838)
		(end 421.602154 -4.767072)
		(stroke
			(width 0.05715)
			(type default)
		)
		(layer "In2.Cu")
	)
	(gr_line
		(start 421.6908 -13.194792)
		(end 421.739822 -13.184378)
		(stroke
			(width 0.05715)
			(type default)
		)
		(layer "In2.Cu")
	)
	(gr_arc
		(start 421.7289 -139.954)
		(mid 421.818703 -139.916803)
		(end 421.8559 -139.827)
		(stroke
			(width 0.05715)
			(type default)
		)
		(layer "In2.Cu")
	)
	(gr_line
		(start 421.739822 -13.184378)
		(end 421.775382 -13.148818)
		(stroke
			(width 0.05715)
			(type default)
		)
		(layer "In2.Cu")
	)
	(gr_line
		(start 421.799258 -4.352036)
		(end 421.810942 -4.327652)
		(stroke
			(width 0.05715)
			(type default)
		)
		(layer "In2.Cu")
	)
	(gr_line
		(start 421.829992 -10.023348)
		(end 422.233344 -10.023348)
		(stroke
			(width 0.05715)
			(type default)
		)
		(layer "In2.Cu")
	)
	(gr_line
		(start 421.860726 -2.67462)
		(end 421.95623 -2.579116)
		(stroke
			(width 0.05715)
			(type default)
		)
		(layer "In2.Cu")
	)
	(gr_line
		(start 421.95623 -2.579116)
		(end 422.242742 -2.579116)
		(stroke
			(width 0.05715)
			(type default)
		)
		(layer "In2.Cu")
	)
	(gr_line
		(start 422.002966 -13.796772)
		(end 422.051988 -13.786358)
		(stroke
			(width 0.05715)
			(type default)
		)
		(layer "In2.Cu")
	)
	(gr_line
		(start 422.051988 -13.786358)
		(end 422.087548 -13.750798)
		(stroke
			(width 0.05715)
			(type default)
		)
		(layer "In2.Cu")
	)
	(gr_arc
		(start 422.148 -139.827)
		(mid 422.185197 -139.916803)
		(end 422.275 -139.954)
		(stroke
			(width 0.05715)
			(type default)
		)
		(layer "In2.Cu")
	)
	(gr_line
		(start 422.233344 -10.023348)
		(end 422.304464 -10.094468)
		(stroke
			(width 0.05715)
			(type default)
		)
		(layer "In2.Cu")
	)
	(gr_line
		(start 422.275 -139.954)
		(end 422.593516 -139.954)
		(stroke
			(width 0.05715)
			(type default)
		)
		(layer "In2.Cu")
	)
	(gr_line
		(start 422.721278 -10.094468)
		(end 422.792398 -10.023348)
		(stroke
			(width 0.05715)
			(type default)
		)
		(layer "In2.Cu")
	)
	(gr_line
		(start 422.792398 -10.023348)
		(end 423.099992 -10.023348)
		(stroke
			(width 0.05715)
			(type default)
		)
		(layer "In2.Cu")
	)
	(gr_line
		(start 422.946068 -10.650474)
		(end 423.004996 -10.591546)
		(stroke
			(width 0.05715)
			(type default)
		)
		(layer "In2.Cu")
	)
	(gr_line
		(start 423.118026 -6.354572)
		(end 423.137076 -6.350508)
		(stroke
			(width 0.05715)
			(type default)
		)
		(layer "In2.Cu")
	)
	(gr_line
		(start 423.137076 -6.350508)
		(end 423.153078 -6.33984)
		(stroke
			(width 0.05715)
			(type default)
		)
		(layer "In2.Cu")
	)
	(gr_line
		(start 423.22496 -11.285728)
		(end 423.283888 -11.2268)
		(stroke
			(width 0.05715)
			(type default)
		)
		(layer "In2.Cu")
	)
	(gr_line
		(start 423.412666 -1.583944)
		(end 423.808144 -1.583944)
		(stroke
			(width 0.05715)
			(type default)
		)
		(layer "In2.Cu")
	)
	(gr_line
		(start 423.50436 -11.920728)
		(end 423.563288 -11.8618)
		(stroke
			(width 0.05715)
			(type default)
		)
		(layer "In2.Cu")
	)
	(gr_line
		(start 423.808144 -1.583944)
		(end 423.89552 -1.67132)
		(stroke
			(width 0.05715)
			(type default)
		)
		(layer "In2.Cu")
	)
	(gr_line
		(start 423.8625 -5.86613)
		(end 423.904156 -5.838444)
		(stroke
			(width 0.05715)
			(type default)
		)
		(layer "In2.Cu")
	)
	(gr_line
		(start 423.904156 -5.838444)
		(end 423.923968 -5.792216)
		(stroke
			(width 0.05715)
			(type default)
		)
		(layer "In2.Cu")
	)
	(gr_line
		(start 424.0784 -139.838176)
		(end 424.235626 -139.838176)
		(stroke
			(width 0.05715)
			(type default)
		)
		(layer "In2.Cu")
	)
	(gr_line
		(start 424.230292 -10.023348)
		(end 424.653964 -10.023348)
		(stroke
			(width 0.05715)
			(type default)
		)
		(layer "In2.Cu")
	)
	(gr_line
		(start 424.235118 -5.062728)
		(end 424.2435 -5.042916)
		(stroke
			(width 0.05715)
			(type default)
		)
		(layer "In2.Cu")
	)
	(gr_line
		(start 424.31208 -1.67132)
		(end 424.399456 -1.583944)
		(stroke
			(width 0.05715)
			(type default)
		)
		(layer "In2.Cu")
	)
	(gr_line
		(start 424.399456 -1.583944)
		(end 424.682666 -1.583944)
		(stroke
			(width 0.05715)
			(type default)
		)
		(layer "In2.Cu")
	)
	(gr_arc
		(start 424.410378 -140.012928)
		(mid 424.359206 -139.889332)
		(end 424.235626 -139.838176)
		(stroke
			(width 0.05715)
			(type default)
		)
		(layer "In2.Cu")
	)
	(gr_line
		(start 424.50385 -6.731)
		(end 424.5229 -6.726936)
		(stroke
			(width 0.05715)
			(type default)
		)
		(layer "In2.Cu")
	)
	(gr_line
		(start 424.5229 -6.726936)
		(end 424.538902 -6.716268)
		(stroke
			(width 0.05715)
			(type default)
		)
		(layer "In2.Cu")
	)
	(gr_line
		(start 424.653964 -10.023348)
		(end 424.683428 -10.052812)
		(stroke
			(width 0.05715)
			(type default)
		)
		(layer "In2.Cu")
	)
	(gr_arc
		(start 424.816778 -139.838176)
		(mid 424.735956 -139.871654)
		(end 424.702478 -139.952476)
		(stroke
			(width 0.05715)
			(type default)
		)
		(layer "In2.Cu")
	)
	(gr_line
		(start 424.816778 -139.838176)
		(end 425.3484 -139.838176)
		(stroke
			(width 0.05715)
			(type default)
		)
		(layer "In2.Cu")
	)
	(gr_line
		(start 425.000166 -6.40842)
		(end 425.018962 -6.39572)
		(stroke
			(width 0.05715)
			(type default)
		)
		(layer "In2.Cu")
	)
	(gr_line
		(start 425.018962 -6.39572)
		(end 425.031154 -6.376924)
		(stroke
			(width 0.05715)
			(type default)
		)
		(layer "In2.Cu")
	)
	(gr_line
		(start 425.100242 -10.052812)
		(end 425.129706 -10.023348)
		(stroke
			(width 0.05715)
			(type default)
		)
		(layer "In2.Cu")
	)
	(gr_line
		(start 425.129706 -10.023348)
		(end 425.500292 -10.023348)
		(stroke
			(width 0.05715)
			(type default)
		)
		(layer "In2.Cu")
	)
	(gr_line
		(start 425.812712 -2.890774)
		(end 426.175424 -2.890774)
		(stroke
			(width 0.05715)
			(type default)
		)
		(layer "In2.Cu")
	)
	(gr_line
		(start 426.175424 -2.890774)
		(end 426.24883 -2.96418)
		(stroke
			(width 0.05715)
			(type default)
		)
		(layer "In2.Cu")
	)
	(gr_line
		(start 426.597826 -3.988054)
		(end 426.62475 -3.946906)
		(stroke
			(width 0.05715)
			(type default)
		)
		(layer "In2.Cu")
	)
	(gr_line
		(start 426.630592 -10.023348)
		(end 427.015148 -10.023348)
		(stroke
			(width 0.05715)
			(type default)
		)
		(layer "In2.Cu")
	)
	(gr_line
		(start 426.665644 -2.96418)
		(end 426.73905 -2.890774)
		(stroke
			(width 0.05715)
			(type default)
		)
		(layer "In2.Cu")
	)
	(gr_line
		(start 426.72 -139.838176)
		(end 427.171866 -139.38631)
		(stroke
			(width 0.05715)
			(type default)
		)
		(layer "In2.Cu")
	)
	(gr_line
		(start 426.73905 -2.890774)
		(end 427.082712 -2.890774)
		(stroke
			(width 0.05715)
			(type default)
		)
		(layer "In2.Cu")
	)
	(gr_line
		(start 426.816012 -6.997954)
		(end 426.835062 -6.99389)
		(stroke
			(width 0.05715)
			(type default)
		)
		(layer "In2.Cu")
	)
	(gr_line
		(start 426.835062 -6.99389)
		(end 426.851064 -6.983222)
		(stroke
			(width 0.05715)
			(type default)
		)
		(layer "In2.Cu")
	)
	(gr_line
		(start 427.015148 -10.023348)
		(end 427.05782 -10.06602)
		(stroke
			(width 0.05715)
			(type default)
		)
		(layer "In2.Cu")
	)
	(gr_arc
		(start 427.171866 -139.38631)
		(mid 427.199299 -139.345159)
		(end 427.20895 -139.296648)
		(stroke
			(width 0.05715)
			(type default)
		)
		(layer "In2.Cu")
	)
	(gr_line
		(start 427.47438 -10.06602)
		(end 427.517052 -10.023348)
		(stroke
			(width 0.05715)
			(type default)
		)
		(layer "In2.Cu")
	)
	(gr_arc
		(start 427.50105 -139.296648)
		(mid 427.51069 -139.345164)
		(end 427.538134 -139.38631)
		(stroke
			(width 0.05715)
			(type default)
		)
		(layer "In2.Cu")
	)
	(gr_line
		(start 427.517052 -10.023348)
		(end 427.900592 -10.023348)
		(stroke
			(width 0.05715)
			(type default)
		)
		(layer "In2.Cu")
	)
	(gr_line
		(start 427.538134 -139.38631)
		(end 427.99 -139.838176)
		(stroke
			(width 0.05715)
			(type default)
		)
		(layer "In2.Cu")
	)
	(gr_line
		(start 427.560994 -11.782806)
		(end 427.585378 -11.770868)
		(stroke
			(width 0.05715)
			(type default)
		)
		(layer "In2.Cu")
	)
	(gr_line
		(start 428.039784 -6.189472)
		(end 428.065692 -6.172454)
		(stroke
			(width 0.05715)
			(type default)
		)
		(layer "In2.Cu")
	)
	(gr_line
		(start 428.065692 -6.172454)
		(end 428.081186 -6.145022)
		(stroke
			(width 0.05715)
			(type default)
		)
		(layer "In2.Cu")
	)
	(gr_line
		(start 428.230792 -2.72415)
		(end 428.575724 -2.72415)
		(stroke
			(width 0.05715)
			(type default)
		)
		(layer "In2.Cu")
	)
	(gr_line
		(start 428.575724 -2.72415)
		(end 428.652178 -2.800604)
		(stroke
			(width 0.05715)
			(type default)
		)
		(layer "In2.Cu")
	)
	(gr_line
		(start 428.992538 -4.54914)
		(end 429.012096 -4.51485)
		(stroke
			(width 0.05715)
			(type default)
		)
		(layer "In2.Cu")
	)
	(gr_line
		(start 429.030892 -10.023348)
		(end 429.428148 -10.023348)
		(stroke
			(width 0.05715)
			(type default)
		)
		(layer "In2.Cu")
	)
	(gr_line
		(start 429.068738 -2.800604)
		(end 429.145192 -2.72415)
		(stroke
			(width 0.05715)
			(type default)
		)
		(layer "In2.Cu")
	)
	(gr_line
		(start 429.145192 -2.72415)
		(end 429.500792 -2.72415)
		(stroke
			(width 0.05715)
			(type default)
		)
		(layer "In2.Cu")
	)
	(gr_line
		(start 429.428148 -10.023348)
		(end 429.45812 -10.05332)
		(stroke
			(width 0.05715)
			(type default)
		)
		(layer "In2.Cu")
	)
	(gr_line
		(start 429.60798 -10.799826)
		(end 429.617886 -10.795254)
		(stroke
			(width 0.05715)
			(type default)
		)
		(layer "In2.Cu")
	)
	(gr_line
		(start 429.874934 -10.05332)
		(end 429.904906 -10.023348)
		(stroke
			(width 0.05715)
			(type default)
		)
		(layer "In2.Cu")
	)
	(gr_line
		(start 429.904906 -10.023348)
		(end 430.300892 -10.023348)
		(stroke
			(width 0.05715)
			(type default)
		)
		(layer "In2.Cu")
	)
	(gr_line
		(start 463.699098 -127.84201)
		(end 463.861658 -127.67945)
		(stroke
			(width 0.05715)
			(type default)
		)
		(layer "In2.Cu")
	)
	(gr_line
		(start 463.861658 -127.67945)
		(end 464.204558 -127.67945)
		(stroke
			(width 0.05715)
			(type default)
		)
		(layer "In2.Cu")
	)
	(gr_line
		(start 463.991198 -128.13665)
		(end 464.075018 -128.13665)
		(stroke
			(width 0.05715)
			(type default)
		)
		(layer "In2.Cu")
	)
	(gr_line
		(start 464.204558 -127.67945)
		(end 464.367118 -127.84201)
		(stroke
			(width 0.05715)
			(type default)
		)
		(layer "In2.Cu")
	)
	(gr_line
		(start 464.715098 -127.84201)
		(end 464.877658 -127.67945)
		(stroke
			(width 0.05715)
			(type default)
		)
		(layer "In2.Cu")
	)
	(gr_line
		(start 464.877658 -127.67945)
		(end 465.220558 -127.67945)
		(stroke
			(width 0.05715)
			(type default)
		)
		(layer "In2.Cu")
	)
	(gr_line
		(start 465.007198 -128.13665)
		(end 465.091018 -128.13665)
		(stroke
			(width 0.05715)
			(type default)
		)
		(layer "In2.Cu")
	)
	(gr_line
		(start 465.220558 -127.67945)
		(end 465.383118 -127.84201)
		(stroke
			(width 0.05715)
			(type default)
		)
		(layer "In2.Cu")
	)
	(gr_line
		(start 468.50935 -127.62865)
		(end 468.568024 -127.569976)
		(stroke
			(width 0.05715)
			(type default)
		)
		(layer "In2.Cu")
	)
	(gr_line
		(start 469.269572 -126.868174)
		(end 469.3285 -126.809246)
		(stroke
			(width 0.05715)
			(type default)
		)
		(layer "In2.Cu")
	)
	(gr_line
		(start 470.41816 -124.73686)
		(end 470.590626 -124.909326)
		(stroke
			(width 0.05715)
			(type default)
		)
		(layer "In2.Cu")
	)
	(gr_line
		(start 470.41816 -124.3203)
		(end 470.590626 -124.147834)
		(stroke
			(width 0.05715)
			(type default)
		)
		(layer "In2.Cu")
	)
	(gr_line
		(start 470.590626 -124.909326)
		(end 470.590626 -125.11405)
		(stroke
			(width 0.05715)
			(type default)
		)
		(layer "In2.Cu")
	)
	(gr_line
		(start 470.590626 -123.84405)
		(end 470.590626 -124.147834)
		(stroke
			(width 0.05715)
			(type default)
		)
		(layer "In2.Cu")
	)
	(gr_line
		(start 1.1684 -67.0052)
		(end 2.8702 -68.707)
		(stroke
			(width 1.27)
			(type default)
		)
		(layer "In3.Cu")
	)
	(gr_line
		(start 1.1684 -60.1218)
		(end 1.1684 -67.0052)
		(stroke
			(width 1.27)
			(type default)
		)
		(layer "In3.Cu")
	)
	(gr_line
		(start 2.4384 -58.8518)
		(end 1.1684 -60.1218)
		(stroke
			(width 1.27)
			(type default)
		)
		(layer "In3.Cu")
	)
	(gr_line
		(start 2.4384 -50.0634)
		(end 2.4384 -58.8518)
		(stroke
			(width 1.27)
			(type default)
		)
		(layer "In3.Cu")
	)
	(gr_line
		(start 2.8702 -85.8266)
		(end 3.8608 -86.8172)
		(stroke
			(width 1.27)
			(type default)
		)
		(layer "In3.Cu")
	)
	(gr_line
		(start 2.8702 -68.707)
		(end 2.8702 -85.8266)
		(stroke
			(width 1.27)
			(type default)
		)
		(layer "In3.Cu")
	)
	(gr_line
		(start 3.0988 -49.403)
		(end 2.4384 -50.0634)
		(stroke
			(width 1.27)
			(type default)
		)
		(layer "In3.Cu")
	)
	(gr_line
		(start 3.8608 -86.8172)
		(end 10.107422 -86.8172)
		(stroke
			(width 1.27)
			(type default)
		)
		(layer "In3.Cu")
	)
	(gr_line
		(start 9.72185 -49.403)
		(end 3.0988 -49.403)
		(stroke
			(width 1.27)
			(type default)
		)
		(layer "In3.Cu")
	)
	(gr_line
		(start 10.107422 -86.8172)
		(end 10.727436 -86.197186)
		(stroke
			(width 1.27)
			(type default)
		)
		(layer "In3.Cu")
	)
	(gr_line
		(start 10.727436 -86.197186)
		(end 10.727436 -50.408586)
		(stroke
			(width 1.27)
			(type default)
		)
		(layer "In3.Cu")
	)
	(gr_line
		(start 10.727436 -50.408586)
		(end 9.72185 -49.403)
		(stroke
			(width 1.27)
			(type default)
		)
		(layer "In3.Cu")
	)
	(gr_line
		(start 429.82007 -137.109454)
		(end 431.09007 -137.109454)
		(stroke
			(width 0.2)
			(type default)
		)
		(layer "In3.Cu")
	)
	(gr_arc
		(start 429.82007 -135.580374)
		(mid 429.05553 -136.344914)
		(end 429.82007 -137.109454)
		(stroke
			(width 0.2)
			(type default)
		)
		(layer "In3.Cu")
	)
	(gr_arc
		(start 431.09007 -137.109454)
		(mid 431.629783 -136.886423)
		(end 431.85461 -136.347454)
		(stroke
			(width 0.2)
			(type default)
		)
		(layer "In3.Cu")
	)
	(gr_line
		(start 431.09007 -135.580374)
		(end 429.82007 -135.580374)
		(stroke
			(width 0.2)
			(type default)
		)
		(layer "In3.Cu")
	)
	(gr_line
		(start 431.666142 -136.347454)
		(end 431.666142 -136.344914)
		(stroke
			(width 0.2)
			(type default)
		)
		(layer "In3.Cu")
	)
	(gr_line
		(start 431.666142 -136.344914)
		(end 431.85461 -136.344914)
		(stroke
			(width 0.2)
			(type default)
		)
		(layer "In3.Cu")
	)
	(gr_line
		(start 431.85461 -136.347454)
		(end 431.666142 -136.347454)
		(stroke
			(width 0.2)
			(type default)
		)
		(layer "In3.Cu")
	)
	(gr_arc
		(start 431.85461 -136.344914)
		(mid 431.630681 -135.804303)
		(end 431.09007 -135.580374)
		(stroke
			(width 0.2)
			(type default)
		)
		(layer "In3.Cu")
	)
	(gr_line
		(start 433.63007 -137.109454)
		(end 434.90007 -137.109454)
		(stroke
			(width 0.2)
			(type default)
		)
		(layer "In3.Cu")
	)
	(gr_arc
		(start 433.63007 -135.580374)
		(mid 432.86553 -136.344914)
		(end 433.63007 -137.109454)
		(stroke
			(width 0.2)
			(type default)
		)
		(layer "In3.Cu")
	)
	(gr_arc
		(start 434.90007 -137.109454)
		(mid 435.439783 -136.886423)
		(end 435.66461 -136.347454)
		(stroke
			(width 0.2)
			(type default)
		)
		(layer "In3.Cu")
	)
	(gr_line
		(start 434.90007 -135.580374)
		(end 433.63007 -135.580374)
		(stroke
			(width 0.2)
			(type default)
		)
		(layer "In3.Cu")
	)
	(gr_line
		(start 435.473856 -136.347454)
		(end 435.473856 -136.344914)
		(stroke
			(width 0.2)
			(type default)
		)
		(layer "In3.Cu")
	)
	(gr_line
		(start 435.473856 -136.344914)
		(end 435.66461 -136.344914)
		(stroke
			(width 0.2)
			(type default)
		)
		(layer "In3.Cu")
	)
	(gr_line
		(start 435.66461 -136.347454)
		(end 435.473856 -136.347454)
		(stroke
			(width 0.2)
			(type default)
		)
		(layer "In3.Cu")
	)
	(gr_arc
		(start 435.66461 -136.344914)
		(mid 435.440681 -135.804303)
		(end 434.90007 -135.580374)
		(stroke
			(width 0.2)
			(type default)
		)
		(layer "In3.Cu")
	)
	(gr_line
		(start -5.1816 -96.078294)
		(end -5.1816 -96.162114)
		(stroke
			(width 0.05715)
			(type default)
		)
		(layer "In4.Cu")
	)
	(gr_line
		(start -5.1816 -95.062294)
		(end -5.1816 -95.146114)
		(stroke
			(width 0.05715)
			(type default)
		)
		(layer "In4.Cu")
	)
	(gr_line
		(start -4.88696 -96.454214)
		(end -4.7244 -96.291654)
		(stroke
			(width 0.05715)
			(type default)
		)
		(layer "In4.Cu")
	)
	(gr_line
		(start -4.88696 -95.786194)
		(end -4.7244 -95.948754)
		(stroke
			(width 0.05715)
			(type default)
		)
		(layer "In4.Cu")
	)
	(gr_line
		(start -4.88696 -95.438214)
		(end -4.7244 -95.275654)
		(stroke
			(width 0.05715)
			(type default)
		)
		(layer "In4.Cu")
	)
	(gr_line
		(start -4.88696 -94.770194)
		(end -4.7244 -94.932754)
		(stroke
			(width 0.05715)
			(type default)
		)
		(layer "In4.Cu")
	)
	(gr_line
		(start -4.7244 -95.948754)
		(end -4.7244 -96.291654)
		(stroke
			(width 0.05715)
			(type default)
		)
		(layer "In4.Cu")
	)
	(gr_line
		(start -4.7244 -94.932754)
		(end -4.7244 -95.275654)
		(stroke
			(width 0.05715)
			(type default)
		)
		(layer "In4.Cu")
	)
	(gr_line
		(start -3.899916 -100.769928)
		(end -3.551682 -100.769928)
		(stroke
			(width 0.05715)
			(type default)
		)
		(layer "In4.Cu")
	)
	(gr_line
		(start -3.899916 -92.769944)
		(end -3.529076 -92.769944)
		(stroke
			(width 0.05715)
			(type default)
		)
		(layer "In4.Cu")
	)
	(gr_line
		(start -3.76555 -97.75444)
		(end -3.60299 -97.59188)
		(stroke
			(width 0.05715)
			(type default)
		)
		(layer "In4.Cu")
	)
	(gr_line
		(start -3.60299 -97.59188)
		(end -3.26009 -97.59188)
		(stroke
			(width 0.05715)
			(type default)
		)
		(layer "In4.Cu")
	)
	(gr_line
		(start -3.551682 -100.769928)
		(end -3.499612 -100.717858)
		(stroke
			(width 0.05715)
			(type default)
		)
		(layer "In4.Cu")
	)
	(gr_line
		(start -3.529076 -92.769944)
		(end -3.397504 -92.901516)
		(stroke
			(width 0.05715)
			(type default)
		)
		(layer "In4.Cu")
	)
	(gr_line
		(start -3.47345 -98.04908)
		(end -3.38963 -98.04908)
		(stroke
			(width 0.05715)
			(type default)
		)
		(layer "In4.Cu")
	)
	(gr_line
		(start -3.429 -123.5456)
		(end -3.153156 -123.821444)
		(stroke
			(width 0.0635)
			(type default)
		)
		(layer "In4.Cu")
	)
	(gr_line
		(start -3.26009 -97.59188)
		(end -3.09753 -97.75444)
		(stroke
			(width 0.05715)
			(type default)
		)
		(layer "In4.Cu")
	)
	(gr_line
		(start -3.083052 -100.717858)
		(end -3.030982 -100.769928)
		(stroke
			(width 0.05715)
			(type default)
		)
		(layer "In4.Cu")
	)
	(gr_line
		(start -3.030982 -100.769928)
		(end -2.500122 -100.769928)
		(stroke
			(width 0.05715)
			(type default)
		)
		(layer "In4.Cu")
	)
	(gr_line
		(start -2.980944 -92.901516)
		(end -2.849372 -92.769944)
		(stroke
			(width 0.05715)
			(type default)
		)
		(layer "In4.Cu")
	)
	(gr_line
		(start -2.849372 -92.769944)
		(end -2.500122 -92.769944)
		(stroke
			(width 0.05715)
			(type default)
		)
		(layer "In4.Cu")
	)
	(gr_line
		(start -2.790444 -123.821444)
		(end -2.5146 -123.5456)
		(stroke
			(width 0.0635)
			(type default)
		)
		(layer "In4.Cu")
	)
	(gr_line
		(start -2.599944 -102.769924)
		(end -2.16027 -102.769924)
		(stroke
			(width 0.05715)
			(type default)
		)
		(layer "In4.Cu")
	)
	(gr_line
		(start -2.16027 -102.769924)
		(end -2.1082 -102.821994)
		(stroke
			(width 0.05715)
			(type default)
		)
		(layer "In4.Cu")
	)
	(gr_line
		(start -1.69164 -102.821994)
		(end -1.63957 -102.769924)
		(stroke
			(width 0.05715)
			(type default)
		)
		(layer "In4.Cu")
	)
	(gr_line
		(start -1.63957 -102.769924)
		(end -1.20015 -102.769924)
		(stroke
			(width 0.05715)
			(type default)
		)
		(layer "In4.Cu")
	)
	(gr_poly
		(pts
			(xy 368.2238 -96.2406) (xy 366.5982 -96.2406) (xy 366.5982 -100.9142) (xy 368.2238 -100.9142)
		)
		(stroke
			(width 0)
			(type solid)
		)
		(fill yes)
		(layer "In4.Cu")
		(net "GND")
	)
	(gr_poly
		(pts
			(xy 65.124076 -88.092534) (xy 65.035176 -87.922354) (xy 64.814196 -87.922354) (xy 64.725296 -88.092534)
			(xy 64.725296 -88.136984) (xy 65.124076 -88.136984)
		)
		(stroke
			(width 0)
			(type solid)
		)
		(fill yes)
		(layer "In4.Cu")
		(net "M_L_DQ<2>")
	)
	(gr_poly
		(pts
			(xy 65.243202 -88.383364) (xy 65.243202 -88.338914) (xy 64.844422 -88.339168) (xy 64.844676 -88.383618)
			(xy 64.933576 -88.553544) (xy 65.154302 -88.553544)
		)
		(stroke
			(width 0)
			(type solid)
		)
		(fill yes)
		(layer "In4.Cu")
		(net "M_L_DQ<3>")
	)
	(gr_poly
		(pts
			(xy 65.365376 -64.13373) (xy 65.396872 -64.102488) (xy 65.109344 -63.81496) (xy 65.078102 -63.846456)
			(xy 65.004442 -64.045846) (xy 65.165986 -64.20739)
		)
		(stroke
			(width 0)
			(type solid)
		)
		(fill yes)
		(layer "In4.Cu")
		(net "M_H_DQ<6>")
	)
	(gr_poly
		(pts
			(xy 65.620392 -62.612524) (xy 65.575942 -62.612524) (xy 65.382902 -62.701424) (xy 65.382902 -62.930024)
			(xy 65.575942 -63.018924) (xy 65.620392 -63.018924)
		)
		(stroke
			(width 0)
			(type solid)
		)
		(fill yes)
		(layer "In4.Cu")
		(net "M_H_DQ<2>")
	)
	(gr_poly
		(pts
			(xy 65.709292 -87.036656) (xy 65.709292 -86.992206) (xy 65.302892 -86.992206) (xy 65.302892 -87.036656)
			(xy 65.391792 -87.229696) (xy 65.620392 -87.229696)
		)
		(stroke
			(width 0)
			(type solid)
		)
		(fill yes)
		(layer "In4.Cu")
		(net "M_L_DQ<7>")
	)
	(gr_poly
		(pts
			(xy 65.709292 -86.757764) (xy 65.620392 -86.564724) (xy 65.391792 -86.564724) (xy 65.302892 -86.757764)
			(xy 65.302892 -86.802214) (xy 65.709292 -86.802214)
		)
		(stroke
			(width 0)
			(type solid)
		)
		(fill yes)
		(layer "In4.Cu")
		(net "M_L_DQ<6>")
	)
	(gr_poly
		(pts
			(xy 65.843912 -85.854286) (xy 65.843912 -85.809836) (xy 65.437512 -85.809836) (xy 65.437512 -85.854286)
			(xy 65.526412 -86.047326) (xy 65.755012 -86.047326)
		)
		(stroke
			(width 0)
			(type solid)
		)
		(fill yes)
		(layer "In4.Cu")
		(net "M_L_DQS_DP<0>")
	)
	(gr_poly
		(pts
			(xy 65.843912 -85.574886) (xy 65.755012 -85.381846) (xy 65.526412 -85.381846) (xy 65.437512 -85.574886)
			(xy 65.437512 -85.619336) (xy 65.843912 -85.619336)
		)
		(stroke
			(width 0)
			(type solid)
		)
		(fill yes)
		(layer "In4.Cu")
		(net "M_L_DQS_DN<0>")
	)
	(gr_poly
		(pts
			(xy 65.91808 -64.292226) (xy 65.99174 -64.092836) (xy 65.830196 -63.931292) (xy 65.630806 -64.004952)
			(xy 65.59931 -64.036194) (xy 65.886838 -64.323722)
		)
		(stroke
			(width 0)
			(type solid)
		)
		(fill yes)
		(layer "In4.Cu")
		(net "M_H_DQ<7>")
	)
	(gr_poly
		(pts
			(xy 65.936876 -49.228756) (xy 65.968372 -49.197514) (xy 65.680844 -48.909986) (xy 65.649602 -48.941482)
			(xy 65.575942 -49.140872) (xy 65.737486 -49.302416)
		)
		(stroke
			(width 0)
			(type solid)
		)
		(fill yes)
		(layer "In4.Cu")
		(net "M_H_DQ<20>")
	)
	(gr_poly
		(pts
			(xy 66.048382 -62.879224) (xy 66.048382 -62.650624) (xy 65.855342 -62.561724) (xy 65.810892 -62.561724)
			(xy 65.810892 -62.968124) (xy 65.855342 -62.968124)
		)
		(stroke
			(width 0)
			(type solid)
		)
		(fill yes)
		(layer "In4.Cu")
		(net "M_H_DQ<3>")
	)
	(gr_poly
		(pts
			(xy 66.065908 -64.834262) (xy 66.09715 -64.802766) (xy 65.809876 -64.515492) (xy 65.77838 -64.546988)
			(xy 65.70472 -64.746378) (xy 65.866518 -64.907922)
		)
		(stroke
			(width 0)
			(type solid)
		)
		(fill yes)
		(layer "In4.Cu")
		(net "M_H_DQ<6>")
	)
	(gr_poly
		(pts
			(xy 66.072258 -96.053402) (xy 66.040762 -96.021906) (xy 65.841372 -95.948246) (xy 65.679828 -96.110044)
			(xy 65.753488 -96.30918) (xy 65.78473 -96.340676)
		)
		(stroke
			(width 0)
			(type solid)
		)
		(fill yes)
		(layer "In4.Cu")
		(net "M_L_DQ<14>")
	)
	(gr_poly
		(pts
			(xy 66.114676 -88.092534) (xy 66.025776 -87.922354) (xy 65.804796 -87.922354) (xy 65.715896 -88.092534)
			(xy 65.715896 -88.136984) (xy 66.114676 -88.136984)
		)
		(stroke
			(width 0)
			(type solid)
		)
		(fill yes)
		(layer "In4.Cu")
		(net "M_L_DQ<2>")
	)
	(gr_poly
		(pts
			(xy 66.134234 -49.031398) (xy 66.207894 -48.832008) (xy 66.04635 -48.670464) (xy 65.84696 -48.744124)
			(xy 65.815464 -48.775366) (xy 66.102992 -49.062894)
		)
		(stroke
			(width 0)
			(type solid)
		)
		(fill yes)
		(layer "In4.Cu")
		(net "M_H_DQ<21>")
	)
	(gr_poly
		(pts
			(xy 66.166238 -63.847726) (xy 66.197734 -63.81623) (xy 65.91046 -63.528956) (xy 65.878964 -63.560452)
			(xy 65.805304 -63.759588) (xy 65.967102 -63.921386)
		)
		(stroke
			(width 0)
			(type solid)
		)
		(fill yes)
		(layer "In4.Cu")
		(net "M_H_DQ<2>")
	)
	(gr_poly
		(pts
			(xy 66.233802 -88.383364) (xy 66.233802 -88.338914) (xy 65.835022 -88.339168) (xy 65.835276 -88.383618)
			(xy 65.924176 -88.553544) (xy 66.144902 -88.553544)
		)
		(stroke
			(width 0)
			(type solid)
		)
		(fill yes)
		(layer "In4.Cu")
		(net "M_L_DQ<3>")
	)
	(gr_poly
		(pts
			(xy 66.301366 -89.49944) (xy 66.26987 -89.468198) (xy 66.07048 -89.394538) (xy 65.908936 -89.556082)
			(xy 65.982596 -89.755472) (xy 66.013838 -89.786968)
		)
		(stroke
			(width 0)
			(type solid)
		)
		(fill yes)
		(layer "In4.Cu")
		(net "M_L_DQ<12>")
	)
	(gr_poly
		(pts
			(xy 66.31178 -96.418654) (xy 66.23812 -96.219264) (xy 66.206624 -96.187768) (xy 65.91935 -96.475042)
			(xy 65.950592 -96.506538) (xy 66.149982 -96.580198)
		)
		(stroke
			(width 0)
			(type solid)
		)
		(fill yes)
		(layer "In4.Cu")
		(net "M_L_DQ<15>")
	)
	(gr_poly
		(pts
			(xy 66.36385 -63.650114) (xy 66.43751 -63.450724) (xy 66.275966 -63.28918) (xy 66.076576 -63.36284)
			(xy 66.04508 -63.394082) (xy 66.332608 -63.68161)
		)
		(stroke
			(width 0)
			(type solid)
		)
		(fill yes)
		(layer "In4.Cu")
		(net "M_H_DQ<3>")
	)
	(gr_poly
		(pts
			(xy 66.489072 -62.330838) (xy 66.444622 -62.330838) (xy 66.251582 -62.419738) (xy 66.251582 -62.648338)
			(xy 66.444622 -62.737238) (xy 66.489072 -62.737238)
		)
		(stroke
			(width 0)
			(type solid)
		)
		(fill yes)
		(layer "In4.Cu")
		(net "M_H_DQ<12>")
	)
	(gr_poly
		(pts
			(xy 66.489072 -61.340238) (xy 66.444622 -61.340238) (xy 66.251582 -61.429138) (xy 66.251582 -61.657738)
			(xy 66.444622 -61.746638) (xy 66.489072 -61.746638)
		)
		(stroke
			(width 0)
			(type solid)
		)
		(fill yes)
		(layer "In4.Cu")
		(net "M_H_DQ<12>")
	)
	(gr_poly
		(pts
			(xy 66.540634 -89.864692) (xy 66.466974 -89.665302) (xy 66.435732 -89.633806) (xy 66.148204 -89.921334)
			(xy 66.1797 -89.952576) (xy 66.37909 -90.026236)
		)
		(stroke
			(width 0)
			(type solid)
		)
		(fill yes)
		(layer "In4.Cu")
		(net "M_L_DQ<13>")
	)
	(gr_poly
		(pts
			(xy 66.591688 -91.642438) (xy 66.518028 -91.443302) (xy 66.486532 -91.411806) (xy 66.199258 -91.69908)
			(xy 66.230754 -91.730576) (xy 66.42989 -91.804236)
		)
		(stroke
			(width 0)
			(type solid)
		)
		(fill yes)
		(layer "In4.Cu")
		(net "M_L_DQ<9>")
	)
	(gr_poly
		(pts
			(xy 66.637408 -49.929288) (xy 66.668904 -49.898046) (xy 66.381376 -49.610518) (xy 66.350134 -49.642014)
			(xy 66.276474 -49.841404) (xy 66.438018 -50.002948)
		)
		(stroke
			(width 0)
			(type solid)
		)
		(fill yes)
		(layer "In4.Cu")
		(net "M_H_DQ<20>")
	)
	(gr_poly
		(pts
			(xy 66.688716 -93.823282) (xy 66.65722 -93.791786) (xy 66.458084 -93.718126) (xy 66.296286 -93.879924)
			(xy 66.369946 -94.07906) (xy 66.401442 -94.110556)
		)
		(stroke
			(width 0)
			(type solid)
		)
		(fill yes)
		(layer "In4.Cu")
		(net "M_L_DQS_DN<1>")
	)
	(gr_poly
		(pts
			(xy 66.699892 -87.036656) (xy 66.699892 -86.992206) (xy 66.293492 -86.992206) (xy 66.293492 -87.036656)
			(xy 66.382392 -87.229696) (xy 66.610992 -87.229696)
		)
		(stroke
			(width 0)
			(type solid)
		)
		(fill yes)
		(layer "In4.Cu")
		(net "M_L_DQ<7>")
	)
	(gr_poly
		(pts
			(xy 66.699892 -86.757764) (xy 66.610992 -86.564724) (xy 66.382392 -86.564724) (xy 66.293492 -86.757764)
			(xy 66.293492 -86.802214) (xy 66.699892 -86.802214)
		)
		(stroke
			(width 0)
			(type solid)
		)
		(fill yes)
		(layer "In4.Cu")
		(net "M_L_DQ<6>")
	)
	(gr_poly
		(pts
			(xy 66.730118 -67.12204) (xy 66.730118 -67.07759) (xy 66.323718 -67.07759) (xy 66.323718 -67.12204)
			(xy 66.412618 -67.31508) (xy 66.641218 -67.31508)
		)
		(stroke
			(width 0)
			(type solid)
		)
		(fill yes)
		(layer "In4.Cu")
		(net "M_H_DQS_DP<9>")
	)
	(gr_poly
		(pts
			(xy 66.730118 -66.84264) (xy 66.641218 -66.6496) (xy 66.412618 -66.6496) (xy 66.323718 -66.84264)
			(xy 66.323718 -66.88709) (xy 66.730118 -66.88709)
		)
		(stroke
			(width 0)
			(type solid)
		)
		(fill yes)
		(layer "In4.Cu")
		(net "M_H_DQS_DN<9>")
	)
	(gr_poly
		(pts
			(xy 66.750438 -83.406488) (xy 66.676778 -83.207098) (xy 66.645536 -83.175602) (xy 66.358008 -83.46313)
			(xy 66.389504 -83.494372) (xy 66.588894 -83.568032)
		)
		(stroke
			(width 0)
			(type solid)
		)
		(fill yes)
		(layer "In4.Cu")
		(net "M_L_DQ<1>")
	)
	(gr_poly
		(pts
			(xy 66.77279 -95.35287) (xy 66.741294 -95.321374) (xy 66.541904 -95.247714) (xy 66.38036 -95.409512)
			(xy 66.45402 -95.608648) (xy 66.485262 -95.640144)
		)
		(stroke
			(width 0)
			(type solid)
		)
		(fill yes)
		(layer "In4.Cu")
		(net "M_L_DQ<14>")
	)
	(gr_poly
		(pts
			(xy 66.834766 -49.73193) (xy 66.908426 -49.53254) (xy 66.746882 -49.370996) (xy 66.547492 -49.444656)
			(xy 66.515996 -49.475898) (xy 66.803524 -49.763426)
		)
		(stroke
			(width 0)
			(type solid)
		)
		(fill yes)
		(layer "In4.Cu")
		(net "M_H_DQ<21>")
	)
	(gr_poly
		(pts
			(xy 66.85788 -85.94344) (xy 66.85788 -85.89899) (xy 66.45148 -85.89899) (xy 66.45148 -85.94344) (xy 66.54038 -86.13648)
			(xy 66.76898 -86.13648)
		)
		(stroke
			(width 0)
			(type solid)
		)
		(fill yes)
		(layer "In4.Cu")
		(net "M_L_DQS_DP<0>")
	)
	(gr_poly
		(pts
			(xy 66.85788 -85.66404) (xy 66.76898 -85.471) (xy 66.54038 -85.471) (xy 66.45148 -85.66404) (xy 66.45148 -85.70849)
			(xy 66.85788 -85.70849)
		)
		(stroke
			(width 0)
			(type solid)
		)
		(fill yes)
		(layer "In4.Cu")
		(net "M_L_DQS_DN<0>")
	)
	(gr_poly
		(pts
			(xy 66.917062 -62.140338) (xy 66.917062 -61.911738) (xy 66.724022 -61.822838) (xy 66.679572 -61.822838)
			(xy 66.679572 -62.229238) (xy 66.724022 -62.229238)
		)
		(stroke
			(width 0)
			(type solid)
		)
		(fill yes)
		(layer "In4.Cu")
		(net "M_H_DQ<13>")
	)
	(gr_poly
		(pts
			(xy 66.928492 -94.188788) (xy 66.854832 -93.989398) (xy 66.82359 -93.957902) (xy 66.536062 -94.24543)
			(xy 66.567558 -94.276672) (xy 66.766948 -94.350332)
		)
		(stroke
			(width 0)
			(type solid)
		)
		(fill yes)
		(layer "In4.Cu")
		(net "M_L_DQS_DP<1>")
	)
	(gr_poly
		(pts
			(xy 66.945002 -82.195416) (xy 66.945002 -82.150966) (xy 66.538602 -82.150966) (xy 66.538602 -82.195416)
			(xy 66.627502 -82.388456) (xy 66.856102 -82.388456)
		)
		(stroke
			(width 0)
			(type solid)
		)
		(fill yes)
		(layer "In4.Cu")
		(net "M_L_DQ<5>")
	)
	(gr_poly
		(pts
			(xy 66.945002 -81.916524) (xy 66.856102 -81.723484) (xy 66.627502 -81.723484) (xy 66.538602 -81.916524)
			(xy 66.538602 -81.960974) (xy 66.945002 -81.960974)
		)
		(stroke
			(width 0)
			(type solid)
		)
		(fill yes)
		(layer "In4.Cu")
		(net "M_L_DQ<4>")
	)
	(gr_poly
		(pts
			(xy 67.012312 -95.718122) (xy 66.938652 -95.518732) (xy 66.907156 -95.487236) (xy 66.619882 -95.77451)
			(xy 66.651124 -95.806006) (xy 66.850514 -95.879666)
		)
		(stroke
			(width 0)
			(type solid)
		)
		(fill yes)
		(layer "In4.Cu")
		(net "M_L_DQ<15>")
	)
	(gr_poly
		(pts
			(xy 67.12077 -48.31969) (xy 67.152266 -48.288448) (xy 66.864738 -48.00092) (xy 66.833496 -48.032416)
			(xy 66.759836 -48.231806) (xy 66.92138 -48.39335)
		)
		(stroke
			(width 0)
			(type solid)
		)
		(fill yes)
		(layer "In4.Cu")
		(net "M_H_DQ<16>")
	)
	(gr_poly
		(pts
			(xy 67.179698 -90.942414) (xy 67.091052 -90.749628) (xy 66.862198 -90.749628) (xy 66.773298 -90.942414)
			(xy 66.773298 -90.987118) (xy 67.179698 -90.987118)
		)
		(stroke
			(width 0)
			(type solid)
		)
		(fill yes)
		(layer "In4.Cu")
		(net "M_L_DQ<8>")
	)
	(gr_poly
		(pts
			(xy 67.248278 -58.571638) (xy 67.279774 -58.540396) (xy 66.992246 -58.252868) (xy 66.961004 -58.284364)
			(xy 66.887344 -58.483754) (xy 67.048888 -58.645298)
		)
		(stroke
			(width 0)
			(type solid)
		)
		(fill yes)
		(layer "In4.Cu")
		(net "M_H_DQS_DP<10>")
	)
	(gr_poly
		(pts
			(xy 67.306698 -91.22156) (xy 67.306698 -91.17711) (xy 66.900298 -91.17711) (xy 66.900298 -91.22156)
			(xy 66.989198 -91.4146) (xy 67.218052 -91.4146)
		)
		(stroke
			(width 0)
			(type solid)
		)
		(fill yes)
		(layer "In4.Cu")
		(net "M_L_DQ<9>")
	)
	(gr_poly
		(pts
			(xy 67.318128 -48.122332) (xy 67.391788 -47.922942) (xy 67.230244 -47.761398) (xy 67.030854 -47.835058)
			(xy 66.999358 -47.8663) (xy 67.286886 -48.153828)
		)
		(stroke
			(width 0)
			(type solid)
		)
		(fill yes)
		(layer "In4.Cu")
		(net "M_H_DQ<17>")
	)
	(gr_poly
		(pts
			(xy 67.333114 -82.683096) (xy 67.244214 -82.490056) (xy 67.015614 -82.490056) (xy 66.926714 -82.683096)
			(xy 66.926714 -82.727546) (xy 67.333114 -82.727546)
		)
		(stroke
			(width 0)
			(type solid)
		)
		(fill yes)
		(layer "In4.Cu")
		(net "M_L_DQ<0>")
	)
	(gr_poly
		(pts
			(xy 67.36588 -100.840032) (xy 67.334384 -100.808536) (xy 67.134994 -100.734876) (xy 66.97345 -100.896674)
			(xy 67.046856 -101.096064) (xy 67.078352 -101.127306)
		)
		(stroke
			(width 0)
			(type solid)
		)
		(fill yes)
		(layer "In4.Cu")
		(net "M_L_DQ<20>")
	)
	(gr_poly
		(pts
			(xy 67.389248 -93.12275) (xy 67.357752 -93.091254) (xy 67.158616 -93.017594) (xy 66.996818 -93.179392)
			(xy 67.070478 -93.378528) (xy 67.101974 -93.410024)
		)
		(stroke
			(width 0)
			(type solid)
		)
		(fill yes)
		(layer "In4.Cu")
		(net "M_L_DQS_DN<1>")
	)
	(gr_poly
		(pts
			(xy 67.445128 -61.825124) (xy 67.400678 -61.825378) (xy 67.230498 -61.914278) (xy 67.230752 -62.135004)
			(xy 67.400678 -62.223904) (xy 67.445382 -62.224158)
		)
		(stroke
			(width 0)
			(type solid)
		)
		(fill yes)
		(layer "In4.Cu")
		(net "M_H_DQ<8>")
	)
	(gr_poly
		(pts
			(xy 67.445128 -60.845446) (xy 67.400678 -60.845446) (xy 67.230498 -60.934346) (xy 67.230498 -61.155326)
			(xy 67.400678 -61.244226) (xy 67.445128 -61.244226)
		)
		(stroke
			(width 0)
			(type solid)
		)
		(fill yes)
		(layer "In4.Cu")
		(net "M_H_DQ<8>")
	)
	(gr_poly
		(pts
			(xy 67.44589 -58.374026) (xy 67.51955 -58.17489) (xy 67.357752 -58.013092) (xy 67.158616 -58.086752)
			(xy 67.12712 -58.118248) (xy 67.414394 -58.405522)
		)
		(stroke
			(width 0)
			(type solid)
		)
		(fill yes)
		(layer "In4.Cu")
		(net "M_H_DQS_DN<10>")
	)
	(gr_poly
		(pts
			(xy 67.473322 -94.652338) (xy 67.441826 -94.620842) (xy 67.242436 -94.547182) (xy 67.080892 -94.70898)
			(xy 67.154552 -94.908116) (xy 67.185794 -94.939612)
		)
		(stroke
			(width 0)
			(type solid)
		)
		(fill yes)
		(layer "In4.Cu")
		(net "M_L_DQ<14>")
	)
	(gr_poly
		(pts
			(xy 67.605656 -101.205792) (xy 67.531996 -101.006402) (xy 67.500754 -100.974906) (xy 67.213226 -101.26218)
			(xy 67.244722 -101.293676) (xy 67.444112 -101.367336)
		)
		(stroke
			(width 0)
			(type solid)
		)
		(fill yes)
		(layer "In4.Cu")
		(net "M_L_DQ<21>")
	)
	(gr_poly
		(pts
			(xy 67.629024 -93.488256) (xy 67.555364 -93.288866) (xy 67.524122 -93.25737) (xy 67.236594 -93.544898)
			(xy 67.26809 -93.57614) (xy 67.46748 -93.6498)
		)
		(stroke
			(width 0)
			(type solid)
		)
		(fill yes)
		(layer "In4.Cu")
		(net "M_L_DQS_DP<1>")
	)
	(gr_poly
		(pts
			(xy 67.650106 -68.017136) (xy 67.658234 -67.825366) (xy 67.466972 -67.714876) (xy 67.30492 -67.817746)
			(xy 67.282568 -67.856354) (xy 67.628008 -68.055744)
		)
		(stroke
			(width 0)
			(type solid)
		)
		(fill yes)
		(layer "In4.Cu")
		(net "M_H_DQ<1>")
	)
	(gr_poly
		(pts
			(xy 67.650106 -67.026536) (xy 67.658234 -66.834766) (xy 67.466972 -66.724276) (xy 67.30492 -66.827146)
			(xy 67.282568 -66.865754) (xy 67.628008 -67.065144)
		)
		(stroke
			(width 0)
			(type solid)
		)
		(fill yes)
		(layer "In4.Cu")
		(net "M_H_DQS_DN<9>")
	)
	(gr_poly
		(pts
			(xy 67.650106 -66.035936) (xy 67.658234 -65.844166) (xy 67.466972 -65.733676) (xy 67.30492 -65.836546)
			(xy 67.282568 -65.875154) (xy 67.628008 -66.074544)
		)
		(stroke
			(width 0)
			(type solid)
		)
		(fill yes)
		(layer "In4.Cu")
		(net "M_H_DQS_DN<0>")
	)
	(gr_poly
		(pts
			(xy 67.650106 -65.045336) (xy 67.658234 -64.853566) (xy 67.466972 -64.743076) (xy 67.30492 -64.845946)
			(xy 67.282568 -64.884554) (xy 67.628008 -65.083944)
		)
		(stroke
			(width 0)
			(type solid)
		)
		(fill yes)
		(layer "In4.Cu")
		(net "M_H_DQ<7>")
	)
	(gr_poly
		(pts
			(xy 67.650106 -64.054736) (xy 67.658234 -63.862966) (xy 67.466972 -63.752476) (xy 67.30492 -63.855346)
			(xy 67.282568 -63.893954) (xy 67.628008 -64.093344)
		)
		(stroke
			(width 0)
			(type solid)
		)
		(fill yes)
		(layer "In4.Cu")
		(net "M_H_DQ<3>")
	)
	(gr_poly
		(pts
			(xy 67.677284 -63.070232) (xy 67.685412 -62.878462) (xy 67.49415 -62.767972) (xy 67.332098 -62.870842)
			(xy 67.309746 -62.90945) (xy 67.655186 -63.10884)
		)
		(stroke
			(width 0)
			(type solid)
		)
		(fill yes)
		(layer "In4.Cu")
		(net "M_H_DQ<13>")
	)
	(gr_poly
		(pts
			(xy 67.679062 -84.929726) (xy 67.653408 -84.739226) (xy 67.627754 -84.703158) (xy 67.302126 -84.933536)
			(xy 67.32778 -84.969858) (xy 67.498722 -85.057488)
		)
		(stroke
			(width 0)
			(type solid)
		)
		(fill yes)
		(layer "In4.Cu")
		(net "M_L_DQS_DN<9>")
	)
	(gr_poly
		(pts
			(xy 67.681856 -88.897206) (xy 67.673728 -88.705436) (xy 67.65163 -88.666828) (xy 67.30619 -88.866472)
			(xy 67.328542 -88.904826) (xy 67.490594 -89.007696)
		)
		(stroke
			(width 0)
			(type solid)
		)
		(fill yes)
		(layer "In4.Cu")
		(net "M_L_DQ<13>")
	)
	(gr_poly
		(pts
			(xy 67.683888 -87.92718) (xy 67.67576 -87.73541) (xy 67.653662 -87.696802) (xy 67.308222 -87.896446)
			(xy 67.330574 -87.9348) (xy 67.492626 -88.03767)
		)
		(stroke
			(width 0)
			(type solid)
		)
		(fill yes)
		(layer "In4.Cu")
		(net "M_L_DQ<3>")
	)
	(gr_poly
		(pts
			(xy 67.683888 -86.93658) (xy 67.67576 -86.74481) (xy 67.653662 -86.706202) (xy 67.308222 -86.905846)
			(xy 67.330574 -86.9442) (xy 67.492626 -87.04707)
		)
		(stroke
			(width 0)
			(type solid)
		)
		(fill yes)
		(layer "In4.Cu")
		(net "M_L_DQ<7>")
	)
	(gr_poly
		(pts
			(xy 67.683888 -85.94598) (xy 67.67576 -85.75421) (xy 67.653662 -85.715602) (xy 67.308222 -85.915246)
			(xy 67.330574 -85.9536) (xy 67.492626 -86.05647)
		)
		(stroke
			(width 0)
			(type solid)
		)
		(fill yes)
		(layer "In4.Cu")
		(net "M_L_DQS_DP<0>")
	)
	(gr_poly
		(pts
			(xy 67.710812 -50.11039) (xy 67.710812 -50.06594) (xy 67.304412 -50.06594) (xy 67.304412 -50.11039)
			(xy 67.393312 -50.30343) (xy 67.621912 -50.30343)
		)
		(stroke
			(width 0)
			(type solid)
		)
		(fill yes)
		(layer "In4.Cu")
		(net "M_H_DQ<20>")
	)
	(gr_poly
		(pts
			(xy 67.710812 -49.831244) (xy 67.621912 -49.638204) (xy 67.393312 -49.638204) (xy 67.304412 -49.831244)
			(xy 67.304412 -49.875694) (xy 67.710812 -49.875694)
		)
		(stroke
			(width 0)
			(type solid)
		)
		(fill yes)
		(layer "In4.Cu")
		(net "M_H_DQ<21>")
	)
	(gr_poly
		(pts
			(xy 67.712844 -95.01759) (xy 67.639184 -94.8182) (xy 67.607688 -94.786704) (xy 67.320414 -95.073978)
			(xy 67.351656 -95.105474) (xy 67.551046 -95.179134)
		)
		(stroke
			(width 0)
			(type solid)
		)
		(fill yes)
		(layer "In4.Cu")
		(net "M_L_DQ<15>")
	)
	(gr_poly
		(pts
			(xy 67.781932 -92.460064) (xy 67.781932 -92.415614) (xy 67.375532 -92.415614) (xy 67.375532 -92.460064)
			(xy 67.464432 -92.653104) (xy 67.693032 -92.653104)
		)
		(stroke
			(width 0)
			(type solid)
		)
		(fill yes)
		(layer "In4.Cu")
		(net "M_L_DQS_DN<10>")
	)
	(gr_poly
		(pts
			(xy 67.781932 -92.180664) (xy 67.693032 -91.987624) (xy 67.464432 -91.987624) (xy 67.375532 -92.180664)
			(xy 67.375532 -92.225114) (xy 67.781932 -92.225114)
		)
		(stroke
			(width 0)
			(type solid)
		)
		(fill yes)
		(layer "In4.Cu")
		(net "M_L_DQS_DP<10>")
	)
	(gr_poly
		(pts
			(xy 67.797934 -83.491832) (xy 67.826382 -83.457796) (xy 67.521074 -83.201256) (xy 67.492372 -83.235292)
			(xy 67.451224 -83.422998) (xy 67.620388 -83.564984)
		)
		(stroke
			(width 0)
			(type solid)
		)
		(fill yes)
		(layer "In4.Cu")
		(net "M_L_DQ<1>")
	)
	(gr_poly
		(pts
			(xy 67.805808 -68.628514) (xy 67.834256 -68.594478) (xy 67.528948 -68.337938) (xy 67.500246 -68.371974)
			(xy 67.459098 -68.55968) (xy 67.628262 -68.701666)
		)
		(stroke
			(width 0)
			(type solid)
		)
		(fill yes)
		(layer "In4.Cu")
		(net "M_H_DQ<0>")
	)
	(gr_poly
		(pts
			(xy 67.821302 -49.020222) (xy 67.852798 -48.98898) (xy 67.56527 -48.701452) (xy 67.534028 -48.732948)
			(xy 67.460368 -48.932338) (xy 67.621912 -49.093882)
		)
		(stroke
			(width 0)
			(type solid)
		)
		(fill yes)
		(layer "In4.Cu")
		(net "M_H_DQ<16>")
	)
	(gr_poly
		(pts
			(xy 67.831716 -84.186776) (xy 67.803268 -84.15274) (xy 67.625722 -84.079588) (xy 67.456558 -84.221574)
			(xy 67.497706 -84.40928) (xy 67.526408 -84.443316)
		)
		(stroke
			(width 0)
			(type solid)
		)
		(fill yes)
		(layer "In4.Cu")
		(net "M_L_DQS_DP<9>")
	)
	(gr_poly
		(pts
			(xy 67.84848 -89.161112) (xy 67.824096 -89.124282) (xy 67.655694 -89.03208) (xy 67.471544 -89.154508)
			(xy 67.492118 -89.34577) (xy 67.51701 -89.3826)
		)
		(stroke
			(width 0)
			(type solid)
		)
		(fill yes)
		(layer "In4.Cu")
		(net "M_L_DQ<8>")
	)
	(gr_poly
		(pts
			(xy 67.884802 -67.62877) (xy 67.907154 -67.590416) (xy 67.561714 -67.390772) (xy 67.539616 -67.42938)
			(xy 67.531488 -67.62115) (xy 67.72275 -67.73164)
		)
		(stroke
			(width 0)
			(type solid)
		)
		(fill yes)
		(layer "In4.Cu")
		(net "M_H_DQS_DP<9>")
	)
	(gr_poly
		(pts
			(xy 67.887088 -63.667386) (xy 67.909694 -63.629032) (xy 67.564 -63.429642) (xy 67.541902 -63.46825)
			(xy 67.533774 -63.66002) (xy 67.72529 -63.770256)
		)
		(stroke
			(width 0)
			(type solid)
		)
		(fill yes)
		(layer "In4.Cu")
		(net "M_H_DQ<12>")
	)
	(gr_poly
		(pts
			(xy 67.887088 -62.676786) (xy 67.909694 -62.638432) (xy 67.564 -62.439042) (xy 67.541902 -62.47765)
			(xy 67.533774 -62.66942) (xy 67.72529 -62.779656)
		)
		(stroke
			(width 0)
			(type solid)
		)
		(fill yes)
		(layer "In4.Cu")
		(net "M_H_DQ<8>")
	)
	(gr_poly
		(pts
			(xy 67.90563 -88.16848) (xy 67.883278 -88.130126) (xy 67.721226 -88.027256) (xy 67.529964 -88.137746)
			(xy 67.538092 -88.329516) (xy 67.56019 -88.36787)
		)
		(stroke
			(width 0)
			(type solid)
		)
		(fill yes)
		(layer "In4.Cu")
		(net "M_L_DQ<12>")
	)
	(gr_poly
		(pts
			(xy 67.90563 -87.17788) (xy 67.883278 -87.139526) (xy 67.721226 -87.036656) (xy 67.529964 -87.147146)
			(xy 67.538092 -87.338916) (xy 67.56019 -87.37727)
		)
		(stroke
			(width 0)
			(type solid)
		)
		(fill yes)
		(layer "In4.Cu")
		(net "M_L_DQ<2>")
	)
	(gr_poly
		(pts
			(xy 67.90563 -86.18728) (xy 67.883278 -86.148926) (xy 67.721226 -86.046056) (xy 67.529964 -86.156546)
			(xy 67.538092 -86.348316) (xy 67.56019 -86.38667)
		)
		(stroke
			(width 0)
			(type solid)
		)
		(fill yes)
		(layer "In4.Cu")
		(net "M_L_DQ<6>")
	)
	(gr_poly
		(pts
			(xy 67.90563 -85.19668) (xy 67.883278 -85.158326) (xy 67.721226 -85.055456) (xy 67.529964 -85.165946)
			(xy 67.538092 -85.357716) (xy 67.56019 -85.39607)
		)
		(stroke
			(width 0)
			(type solid)
		)
		(fill yes)
		(layer "In4.Cu")
		(net "M_L_DQS_DN<0>")
	)
	(gr_poly
		(pts
			(xy 67.94881 -59.27217) (xy 67.980052 -59.240674) (xy 67.692778 -58.9534) (xy 67.661282 -58.984896)
			(xy 67.587622 -59.184286) (xy 67.74942 -59.34583)
		)
		(stroke
			(width 0)
			(type solid)
		)
		(fill yes)
		(layer "In4.Cu")
		(net "M_H_DQS_DP<10>")
	)
	(gr_poly
		(pts
			(xy 67.983354 -61.63818) (xy 67.983354 -61.4172) (xy 67.813174 -61.3283) (xy 67.768724 -61.3283)
			(xy 67.768724 -61.72708) (xy 67.813174 -61.72708)
		)
		(stroke
			(width 0)
			(type solid)
		)
		(fill yes)
		(layer "In4.Cu")
		(net "M_H_DQ<9>")
	)
	(gr_poly
		(pts
			(xy 67.983354 -60.64758) (xy 67.983354 -60.4266) (xy 67.813174 -60.3377) (xy 67.768724 -60.3377)
			(xy 67.768724 -60.73648) (xy 67.813174 -60.73648)
		)
		(stroke
			(width 0)
			(type solid)
		)
		(fill yes)
		(layer "In4.Cu")
		(net "M_H_DQ<9>")
	)
	(gr_poly
		(pts
			(xy 68.015104 -95.786702) (xy 67.983608 -95.755206) (xy 67.784472 -95.681546) (xy 67.622674 -95.843344)
			(xy 67.696334 -96.04248) (xy 67.72783 -96.073976)
		)
		(stroke
			(width 0)
			(type solid)
		)
		(fill yes)
		(layer "In4.Cu")
		(net "M_L_DQ<10>")
	)
	(gr_poly
		(pts
			(xy 68.01866 -48.822864) (xy 68.09232 -48.623474) (xy 67.930776 -48.46193) (xy 67.731386 -48.53559)
			(xy 67.69989 -48.566832) (xy 67.987418 -48.85436)
		)
		(stroke
			(width 0)
			(type solid)
		)
		(fill yes)
		(layer "In4.Cu")
		(net "M_H_DQ<17>")
	)
	(gr_poly
		(pts
			(xy 68.022978 -90.589608) (xy 68.022978 -90.360754) (xy 67.829938 -90.272108) (xy 67.785488 -90.272108)
			(xy 67.785488 -90.678508) (xy 67.829938 -90.678508)
		)
		(stroke
			(width 0)
			(type solid)
		)
		(fill yes)
		(layer "In4.Cu")
		(net "M_L_DQ<9>")
	)
	(gr_poly
		(pts
			(xy 68.146422 -59.074558) (xy 68.220082 -58.875168) (xy 68.058284 -58.713624) (xy 67.858894 -58.787284)
			(xy 67.827652 -58.81878) (xy 68.114926 -59.106054)
		)
		(stroke
			(width 0)
			(type solid)
		)
		(fill yes)
		(layer "In4.Cu")
		(net "M_H_DQS_DN<10>")
	)
	(gr_poly
		(pts
			(xy 68.254626 -96.1517) (xy 68.180966 -95.952564) (xy 68.14947 -95.921068) (xy 67.862196 -96.208342)
			(xy 67.893692 -96.239838) (xy 68.092828 -96.313498)
		)
		(stroke
			(width 0)
			(type solid)
		)
		(fill yes)
		(layer "In4.Cu")
		(net "M_L_DQ<11>")
	)
	(gr_poly
		(pts
			(xy 68.29298 -93.135704) (xy 68.293234 -93.091254) (xy 67.88658 -93.091254) (xy 67.886834 -93.135704)
			(xy 67.975734 -93.328744) (xy 68.20408 -93.328744)
		)
		(stroke
			(width 0)
			(type solid)
		)
		(fill yes)
		(layer "In4.Cu")
		(net "M_L_DQS_DP<1>")
	)
	(gr_poly
		(pts
			(xy 68.29298 -92.85605) (xy 68.204334 -92.663264) (xy 67.97548 -92.663264) (xy 67.886834 -92.85605)
			(xy 67.886834 -92.900754) (xy 68.29298 -92.900754)
		)
		(stroke
			(width 0)
			(type solid)
		)
		(fill yes)
		(layer "In4.Cu")
		(net "M_L_DQS_DN<1>")
	)
	(gr_poly
		(pts
			(xy 68.303648 -60.343796) (xy 68.259198 -60.343796) (xy 68.089018 -60.432696) (xy 68.089018 -60.653676)
			(xy 68.259198 -60.742576) (xy 68.303648 -60.742576)
		)
		(stroke
			(width 0)
			(type solid)
		)
		(fill yes)
		(layer "In4.Cu")
		(net "M_H_DQS_DP<10>")
	)
	(gr_poly
		(pts
			(xy 68.303902 -61.323474) (xy 68.259452 -61.323728) (xy 68.089272 -61.412628) (xy 68.089526 -61.633354)
			(xy 68.259452 -61.722254) (xy 68.304156 -61.722508)
		)
		(stroke
			(width 0)
			(type solid)
		)
		(fill yes)
		(layer "In4.Cu")
		(net "M_H_DQS_DP<10>")
	)
	(gr_poly
		(pts
			(xy 68.436236 -90.967814) (xy 68.391786 -90.967814) (xy 68.198746 -91.056714) (xy 68.198746 -91.285314)
			(xy 68.391786 -91.374214) (xy 68.436236 -91.374214)
		)
		(stroke
			(width 0)
			(type solid)
		)
		(fill yes)
		(layer "In4.Cu")
		(net "M_L_DQS_DP<10>")
	)
	(gr_poly
		(pts
			(xy 68.47459 -94.15907) (xy 68.443094 -94.127574) (xy 68.243704 -94.053914) (xy 68.08216 -94.215712)
			(xy 68.15582 -94.414848) (xy 68.187062 -94.446344)
		)
		(stroke
			(width 0)
			(type solid)
		)
		(fill yes)
		(layer "In4.Cu")
		(net "M_L_DQ<14>")
	)
	(gr_poly
		(pts
			(xy 68.480178 -69.527166) (xy 68.49491 -69.335396) (xy 68.307458 -69.218302) (xy 68.14185 -69.315584)
			(xy 68.118482 -69.353176) (xy 68.456556 -69.564758)
		)
		(stroke
			(width 0)
			(type solid)
		)
		(fill yes)
		(layer "In4.Cu")
		(net "M_H_DQ<5>")
	)
	(gr_poly
		(pts
			(xy 68.511166 -100.80244) (xy 68.511166 -100.75799) (xy 68.104766 -100.75799) (xy 68.104766 -100.80244)
			(xy 68.193666 -100.99548) (xy 68.422266 -100.99548)
		)
		(stroke
			(width 0)
			(type solid)
		)
		(fill yes)
		(layer "In4.Cu")
		(net "M_L_DQ<21>")
	)
	(gr_poly
		(pts
			(xy 68.511166 -100.522786) (xy 68.422266 -100.329746) (xy 68.193666 -100.329746) (xy 68.104766 -100.522786)
			(xy 68.104766 -100.567236) (xy 68.511166 -100.567236)
		)
		(stroke
			(width 0)
			(type solid)
		)
		(fill yes)
		(layer "In4.Cu")
		(net "M_L_DQ<20>")
	)
	(gr_poly
		(pts
			(xy 68.52666 -67.522598) (xy 68.534788 -67.330828) (xy 68.343526 -67.220338) (xy 68.181474 -67.323208)
			(xy 68.159122 -67.361562) (xy 68.504562 -67.561206)
		)
		(stroke
			(width 0)
			(type solid)
		)
		(fill yes)
		(layer "In4.Cu")
		(net "M_H_DQS_DN<9>")
	)
	(gr_poly
		(pts
			(xy 68.52666 -66.531998) (xy 68.534788 -66.340228) (xy 68.343526 -66.229738) (xy 68.181474 -66.332608)
			(xy 68.159122 -66.370962) (xy 68.504562 -66.570606)
		)
		(stroke
			(width 0)
			(type solid)
		)
		(fill yes)
		(layer "In4.Cu")
		(net "M_H_DQS_DN<0>")
	)
	(gr_poly
		(pts
			(xy 68.53428 -68.517516) (xy 68.542408 -68.325746) (xy 68.351146 -68.215256) (xy 68.189094 -68.318126)
			(xy 68.166742 -68.35648) (xy 68.512182 -68.55587)
		)
		(stroke
			(width 0)
			(type solid)
		)
		(fill yes)
		(layer "In4.Cu")
		(net "M_H_DQ<1>")
	)
	(gr_poly
		(pts
			(xy 68.53428 -65.545716) (xy 68.542408 -65.353946) (xy 68.351146 -65.243456) (xy 68.189094 -65.346326)
			(xy 68.166742 -65.38468) (xy 68.512182 -65.58407)
		)
		(stroke
			(width 0)
			(type solid)
		)
		(fill yes)
		(layer "In4.Cu")
		(net "M_H_DQ<7>")
	)
	(gr_poly
		(pts
			(xy 68.53428 -64.555116) (xy 68.542408 -64.363346) (xy 68.351146 -64.252856) (xy 68.189094 -64.355726)
			(xy 68.166742 -64.394334) (xy 68.512182 -64.593724)
		)
		(stroke
			(width 0)
			(type solid)
		)
		(fill yes)
		(layer "In4.Cu")
		(net "M_H_DQ<3>")
	)
	(gr_poly
		(pts
			(xy 68.53428 -63.564516) (xy 68.542408 -63.372746) (xy 68.351146 -63.262256) (xy 68.189094 -63.365126)
			(xy 68.166742 -63.403734) (xy 68.512182 -63.603124)
		)
		(stroke
			(width 0)
			(type solid)
		)
		(fill yes)
		(layer "In4.Cu")
		(net "M_H_DQ<13>")
	)
	(gr_poly
		(pts
			(xy 68.53428 -62.573916) (xy 68.542408 -62.382146) (xy 68.351146 -62.271656) (xy 68.189094 -62.374526)
			(xy 68.166742 -62.413134) (xy 68.512182 -62.612524)
		)
		(stroke
			(width 0)
			(type solid)
		)
		(fill yes)
		(layer "In4.Cu")
		(net "M_H_DQ<9>")
	)
	(gr_poly
		(pts
			(xy 68.542408 -82.478626) (xy 68.53428 -82.286856) (xy 68.512182 -82.248248) (xy 68.166742 -82.447638)
			(xy 68.189094 -82.486246) (xy 68.351146 -82.589116)
		)
		(stroke
			(width 0)
			(type solid)
		)
		(fill yes)
		(layer "In4.Cu")
		(net "M_L_DQ<5>")
	)
	(gr_poly
		(pts
			(xy 68.543932 -89.412064) (xy 68.535804 -89.220294) (xy 68.513706 -89.181686) (xy 68.168266 -89.38133)
			(xy 68.190618 -89.419684) (xy 68.35267 -89.522554)
		)
		(stroke
			(width 0)
			(type solid)
		)
		(fill yes)
		(layer "In4.Cu")
		(net "M_L_DQ<9>")
	)
	(gr_poly
		(pts
			(xy 68.543932 -88.421464) (xy 68.535804 -88.229694) (xy 68.513706 -88.191086) (xy 68.168266 -88.39073)
			(xy 68.190618 -88.429084) (xy 68.35267 -88.531954)
		)
		(stroke
			(width 0)
			(type solid)
		)
		(fill yes)
		(layer "In4.Cu")
		(net "M_L_DQ<13>")
	)
	(gr_poly
		(pts
			(xy 68.543932 -87.430864) (xy 68.535804 -87.239094) (xy 68.513706 -87.200486) (xy 68.168266 -87.40013)
			(xy 68.190618 -87.438484) (xy 68.35267 -87.541354)
		)
		(stroke
			(width 0)
			(type solid)
		)
		(fill yes)
		(layer "In4.Cu")
		(net "M_L_DQ<3>")
	)
	(gr_poly
		(pts
			(xy 68.543932 -86.440264) (xy 68.535804 -86.248494) (xy 68.513706 -86.209886) (xy 68.168266 -86.40953)
			(xy 68.190618 -86.447884) (xy 68.35267 -86.550754)
		)
		(stroke
			(width 0)
			(type solid)
		)
		(fill yes)
		(layer "In4.Cu")
		(net "M_L_DQ<7>")
	)
	(gr_poly
		(pts
			(xy 68.543932 -85.449664) (xy 68.535804 -85.257894) (xy 68.513706 -85.219286) (xy 68.168266 -85.41893)
			(xy 68.190618 -85.457284) (xy 68.35267 -85.560154)
		)
		(stroke
			(width 0)
			(type solid)
		)
		(fill yes)
		(layer "In4.Cu")
		(net "M_L_DQS_DP<0>")
	)
	(gr_poly
		(pts
			(xy 68.543932 -84.459064) (xy 68.535804 -84.267294) (xy 68.513706 -84.228686) (xy 68.168266 -84.42833)
			(xy 68.190618 -84.466684) (xy 68.35267 -84.569554)
		)
		(stroke
			(width 0)
			(type solid)
		)
		(fill yes)
		(layer "In4.Cu")
		(net "M_L_DQS_DN<9>")
	)
	(gr_poly
		(pts
			(xy 68.543932 -83.468718) (xy 68.535804 -83.276948) (xy 68.513706 -83.238594) (xy 68.168266 -83.43773)
			(xy 68.190618 -83.476338) (xy 68.35267 -83.579208)
		)
		(stroke
			(width 0)
			(type solid)
		)
		(fill yes)
		(layer "In4.Cu")
		(net "M_L_DQ<1>")
	)
	(gr_poly
		(pts
			(xy 68.61683 -92.354654) (xy 68.54317 -92.155264) (xy 68.511674 -92.123768) (xy 68.224146 -92.411296)
			(xy 68.255642 -92.442792) (xy 68.455032 -92.516452)
		)
		(stroke
			(width 0)
			(type solid)
		)
		(fill yes)
		(layer "In4.Cu")
		(net "M_L_DQS_DN<10>")
	)
	(gr_poly
		(pts
			(xy 68.628768 -50.736754) (xy 68.660264 -50.705512) (xy 68.372736 -50.417984) (xy 68.341494 -50.44948)
			(xy 68.267834 -50.64887) (xy 68.429378 -50.810414)
		)
		(stroke
			(width 0)
			(type solid)
		)
		(fill yes)
		(layer "In4.Cu")
		(net "M_H_DQ<20>")
	)
	(gr_poly
		(pts
			(xy 68.695316 -70.137274) (xy 68.718684 -70.099682) (xy 68.380864 -69.8881) (xy 68.356988 -69.925692)
			(xy 68.34251 -70.117462) (xy 68.529708 -70.234556)
		)
		(stroke
			(width 0)
			(type solid)
		)
		(fill yes)
		(layer "In4.Cu")
		(net "M_H_DQ<4>")
	)
	(gr_poly
		(pts
			(xy 68.697094 -102.539292) (xy 68.623434 -102.340156) (xy 68.591938 -102.30866) (xy 68.304664 -102.595934)
			(xy 68.33616 -102.62743) (xy 68.535296 -102.70109)
		)
		(stroke
			(width 0)
			(type solid)
		)
		(fill yes)
		(layer "In4.Cu")
		(net "M_L_DQ<17>")
	)
	(gr_poly
		(pts
			(xy 68.714112 -94.524322) (xy 68.640452 -94.324932) (xy 68.608956 -94.293436) (xy 68.321682 -94.58071)
			(xy 68.352924 -94.612206) (xy 68.552314 -94.685866)
		)
		(stroke
			(width 0)
			(type solid)
		)
		(fill yes)
		(layer "In4.Cu")
		(net "M_L_DQ<15>")
	)
	(gr_poly
		(pts
			(xy 68.74002 -62.178184) (xy 68.762626 -62.13983) (xy 68.416932 -61.94044) (xy 68.394834 -61.979048)
			(xy 68.386706 -62.170818) (xy 68.578222 -62.281054)
		)
		(stroke
			(width 0)
			(type solid)
		)
		(fill yes)
		(layer "In4.Cu")
		(net "M_H_DQS_DP<10>")
	)
	(gr_poly
		(pts
			(xy 68.741798 -69.1134) (xy 68.76415 -69.075046) (xy 68.41871 -68.875402) (xy 68.396612 -68.91401)
			(xy 68.388484 -69.10578) (xy 68.579746 -69.21627)
		)
		(stroke
			(width 0)
			(type solid)
		)
		(fill yes)
		(layer "In4.Cu")
		(net "M_H_DQ<0>")
	)
	(gr_poly
		(pts
			(xy 68.741798 -66.1416) (xy 68.76415 -66.103246) (xy 68.41871 -65.903602) (xy 68.396612 -65.94221)
			(xy 68.388484 -66.13398) (xy 68.579746 -66.24447)
		)
		(stroke
			(width 0)
			(type solid)
		)
		(fill yes)
		(layer "In4.Cu")
		(net "M_H_DQ<6>")
	)
	(gr_poly
		(pts
			(xy 68.741798 -65.151) (xy 68.76415 -65.112646) (xy 68.41871 -64.913002) (xy 68.396612 -64.95161)
			(xy 68.388484 -65.14338) (xy 68.579746 -65.25387)
		)
		(stroke
			(width 0)
			(type solid)
		)
		(fill yes)
		(layer "In4.Cu")
		(net "M_H_DQ<2>")
	)
	(gr_poly
		(pts
			(xy 68.741798 -64.1604) (xy 68.76415 -64.122046) (xy 68.41871 -63.922402) (xy 68.396612 -63.96101)
			(xy 68.388484 -64.15278) (xy 68.579746 -64.26327)
		)
		(stroke
			(width 0)
			(type solid)
		)
		(fill yes)
		(layer "In4.Cu")
		(net "M_H_DQ<12>")
	)
	(gr_poly
		(pts
			(xy 68.741798 -63.1698) (xy 68.76415 -63.131446) (xy 68.41871 -62.931802) (xy 68.396612 -62.97041)
			(xy 68.388484 -63.16218) (xy 68.579746 -63.27267)
		)
		(stroke
			(width 0)
			(type solid)
		)
		(fill yes)
		(layer "In4.Cu")
		(net "M_H_DQ<8>")
	)
	(gr_poly
		(pts
			(xy 68.74256 -68.123308) (xy 68.764912 -68.084954) (xy 68.419472 -67.88531) (xy 68.397374 -67.923918)
			(xy 68.389246 -68.115688) (xy 68.580508 -68.226178)
		)
		(stroke
			(width 0)
			(type solid)
		)
		(fill yes)
		(layer "In4.Cu")
		(net "M_H_DQS_DP<9>")
	)
	(gr_poly
		(pts
			(xy 68.743576 -67.133216) (xy 68.765928 -67.094862) (xy 68.420488 -66.895218) (xy 68.39839 -66.933826)
			(xy 68.390262 -67.125596) (xy 68.581524 -67.236086)
		)
		(stroke
			(width 0)
			(type solid)
		)
		(fill yes)
		(layer "In4.Cu")
		(net "M_H_DQS_DP<0>")
	)
	(gr_poly
		(pts
			(xy 68.762626 -89.65565) (xy 68.740274 -89.617042) (xy 68.578222 -89.514172) (xy 68.38696 -89.624662)
			(xy 68.395088 -89.816432) (xy 68.417186 -89.85504)
		)
		(stroke
			(width 0)
			(type solid)
		)
		(fill yes)
		(layer "In4.Cu")
		(net "M_L_DQS_DP<10>")
	)
	(gr_poly
		(pts
			(xy 68.762626 -88.66505) (xy 68.740274 -88.626442) (xy 68.578222 -88.523572) (xy 68.38696 -88.634062)
			(xy 68.395088 -88.825832) (xy 68.417186 -88.86444)
		)
		(stroke
			(width 0)
			(type solid)
		)
		(fill yes)
		(layer "In4.Cu")
		(net "M_L_DQ<8>")
	)
	(gr_poly
		(pts
			(xy 68.762626 -87.67445) (xy 68.740274 -87.635842) (xy 68.578222 -87.532972) (xy 68.38696 -87.643462)
			(xy 68.395088 -87.835232) (xy 68.417186 -87.87384)
		)
		(stroke
			(width 0)
			(type solid)
		)
		(fill yes)
		(layer "In4.Cu")
		(net "M_L_DQ<12>")
	)
	(gr_poly
		(pts
			(xy 68.762626 -86.68385) (xy 68.740274 -86.645242) (xy 68.578222 -86.542372) (xy 68.38696 -86.652862)
			(xy 68.395088 -86.844632) (xy 68.417186 -86.88324)
		)
		(stroke
			(width 0)
			(type solid)
		)
		(fill yes)
		(layer "In4.Cu")
		(net "M_L_DQ<2>")
	)
	(gr_poly
		(pts
			(xy 68.762626 -85.69325) (xy 68.740274 -85.654642) (xy 68.578222 -85.551772) (xy 68.38696 -85.662262)
			(xy 68.395088 -85.854032) (xy 68.417186 -85.89264)
		)
		(stroke
			(width 0)
			(type solid)
		)
		(fill yes)
		(layer "In4.Cu")
		(net "M_L_DQ<6>")
	)
	(gr_poly
		(pts
			(xy 68.762626 -84.70265) (xy 68.740274 -84.664042) (xy 68.578222 -84.561172) (xy 68.38696 -84.671662)
			(xy 68.395088 -84.863432) (xy 68.417186 -84.90204)
		)
		(stroke
			(width 0)
			(type solid)
		)
		(fill yes)
		(layer "In4.Cu")
		(net "M_L_DQS_DN<0>")
	)
	(gr_poly
		(pts
			(xy 68.762626 -83.71205) (xy 68.740274 -83.673442) (xy 68.578222 -83.570572) (xy 68.38696 -83.681062)
			(xy 68.395088 -83.872832) (xy 68.417186 -83.91144)
		)
		(stroke
			(width 0)
			(type solid)
		)
		(fill yes)
		(layer "In4.Cu")
		(net "M_L_DQS_DP<9>")
	)
	(gr_poly
		(pts
			(xy 68.762626 -82.72145) (xy 68.740274 -82.682842) (xy 68.578222 -82.579972) (xy 68.38696 -82.690462)
			(xy 68.395088 -82.882232) (xy 68.417186 -82.92084)
		)
		(stroke
			(width 0)
			(type solid)
		)
		(fill yes)
		(layer "In4.Cu")
		(net "M_L_DQ<0>")
	)
	(gr_poly
		(pts
			(xy 68.762626 -81.73085) (xy 68.740274 -81.692242) (xy 68.578222 -81.589372) (xy 68.38696 -81.699862)
			(xy 68.395088 -81.891632) (xy 68.417186 -81.93024)
		)
		(stroke
			(width 0)
			(type solid)
		)
		(fill yes)
		(layer "In4.Cu")
		(net "M_L_DQ<4>")
	)
	(gr_poly
		(pts
			(xy 68.825872 -50.53965) (xy 68.899532 -50.34026) (xy 68.737988 -50.178716) (xy 68.538598 -50.252376)
			(xy 68.507102 -50.283618) (xy 68.79463 -50.571146)
		)
		(stroke
			(width 0)
			(type solid)
		)
		(fill yes)
		(layer "In4.Cu")
		(net "M_H_DQ<21>")
	)
	(gr_poly
		(pts
			(xy 68.841874 -61.14923) (xy 68.841874 -60.92825) (xy 68.671694 -60.83935) (xy 68.627244 -60.83935)
			(xy 68.627244 -61.23813) (xy 68.671694 -61.23813)
		)
		(stroke
			(width 0)
			(type solid)
		)
		(fill yes)
		(layer "In4.Cu")
		(net "M_H_DQS_DN<10>")
	)
	(gr_poly
		(pts
			(xy 68.841874 -60.15863) (xy 68.841874 -59.93765) (xy 68.671694 -59.84875) (xy 68.627244 -59.84875)
			(xy 68.627244 -60.24753) (xy 68.671694 -60.24753)
		)
		(stroke
			(width 0)
			(type solid)
		)
		(fill yes)
		(layer "In4.Cu")
		(net "M_H_DQS_DN<10>")
	)
	(gr_poly
		(pts
			(xy 68.864226 -91.285314) (xy 68.864226 -91.056714) (xy 68.671186 -90.967814) (xy 68.626736 -90.967814)
			(xy 68.626736 -91.374214) (xy 68.671186 -91.374214)
		)
		(stroke
			(width 0)
			(type solid)
		)
		(fill yes)
		(layer "In4.Cu")
		(net "M_L_DQS_DN<10>")
	)
	(gr_poly
		(pts
			(xy 68.878704 -101.753162) (xy 68.847208 -101.721666) (xy 68.648072 -101.648006) (xy 68.486274 -101.809804)
			(xy 68.559934 -102.00894) (xy 68.59143 -102.040436)
		)
		(stroke
			(width 0)
			(type solid)
		)
		(fill yes)
		(layer "In4.Cu")
		(net "M_L_DQ<16>")
	)
	(gr_poly
		(pts
			(xy 68.994274 -92.470732) (xy 68.962778 -92.43949) (xy 68.763388 -92.36583) (xy 68.601844 -92.527374)
			(xy 68.675504 -92.726764) (xy 68.706746 -92.75826)
		)
		(stroke
			(width 0)
			(type solid)
		)
		(fill yes)
		(layer "In4.Cu")
		(net "M_L_DQS_DN<1>")
	)
	(gr_poly
		(pts
			(xy 69.013832 -49.807368) (xy 69.045074 -49.775872) (xy 68.7578 -49.488598) (xy 68.726304 -49.520094)
			(xy 68.652644 -49.719484) (xy 68.814442 -49.881028)
		)
		(stroke
			(width 0)
			(type solid)
		)
		(fill yes)
		(layer "In4.Cu")
		(net "M_H_DQ<16>")
	)
	(gr_poly
		(pts
			(xy 69.162168 -60.828174) (xy 69.117972 -60.828174) (xy 68.947792 -60.917074) (xy 68.947792 -61.138054)
			(xy 69.117972 -61.226954) (xy 69.162422 -61.227208)
		)
		(stroke
			(width 0)
			(type solid)
		)
		(fill yes)
		(layer "In4.Cu")
		(net "M_H_DQS_DP<1>")
	)
	(gr_poly
		(pts
			(xy 69.162676 -91.304618) (xy 69.118226 -91.304618) (xy 68.925186 -91.393518) (xy 68.925186 -91.622118)
			(xy 69.118226 -91.711018) (xy 69.162676 -91.711018)
		)
		(stroke
			(width 0)
			(type solid)
		)
		(fill yes)
		(layer "In4.Cu")
		(net "M_L_DQS_DN<1>")
	)
	(gr_poly
		(pts
			(xy 69.162676 -59.35726) (xy 69.118226 -59.35726) (xy 68.925186 -59.44616) (xy 68.925186 -59.67476)
			(xy 69.118226 -59.76366) (xy 69.162676 -59.76366)
		)
		(stroke
			(width 0)
			(type solid)
		)
		(fill yes)
		(layer "In4.Cu")
		(net "M_H_DQS_DP<1>")
	)
	(gr_poly
		(pts
			(xy 69.175122 -93.458538) (xy 69.143626 -93.427042) (xy 68.944236 -93.353382) (xy 68.782692 -93.51518)
			(xy 68.856352 -93.714316) (xy 68.887594 -93.745812)
		)
		(stroke
			(width 0)
			(type solid)
		)
		(fill yes)
		(layer "In4.Cu")
		(net "M_L_DQ<14>")
	)
	(gr_poly
		(pts
			(xy 69.177154 -48.826928) (xy 69.20865 -48.795432) (xy 68.921376 -48.508158) (xy 68.88988 -48.539654)
			(xy 68.81622 -48.73879) (xy 68.978018 -48.900588)
		)
		(stroke
			(width 0)
			(type solid)
		)
		(fill yes)
		(layer "In4.Cu")
		(net "M_H_DQS_DP<11>")
	)
	(gr_poly
		(pts
			(xy 69.210936 -49.61001) (xy 69.284596 -49.41062) (xy 69.123052 -49.249076) (xy 68.923662 -49.322736)
			(xy 68.892166 -49.354232) (xy 69.17944 -49.641506)
		)
		(stroke
			(width 0)
			(type solid)
		)
		(fill yes)
		(layer "In4.Cu")
		(net "M_H_DQ<17>")
	)
	(gr_poly
		(pts
			(xy 69.23405 -92.836238) (xy 69.16039 -92.637102) (xy 69.128894 -92.605606) (xy 68.84162 -92.89288)
			(xy 68.873116 -92.924376) (xy 69.072252 -92.998036)
		)
		(stroke
			(width 0)
			(type solid)
		)
		(fill yes)
		(layer "In4.Cu")
		(net "M_L_DQS_DP<1>")
	)
	(gr_poly
		(pts
			(xy 69.338444 -93.89999) (xy 69.264784 -93.7006) (xy 69.233288 -93.669104) (xy 68.946014 -93.956378)
			(xy 68.977256 -93.987874) (xy 69.176646 -94.061534)
		)
		(stroke
			(width 0)
			(type solid)
		)
		(fill yes)
		(layer "In4.Cu")
		(net "M_L_DQ<15>")
	)
	(gr_poly
		(pts
			(xy 69.374766 -48.629316) (xy 69.448426 -48.429926) (xy 69.286882 -48.268382) (xy 69.087492 -48.342042)
			(xy 69.055996 -48.373284) (xy 69.343524 -48.660812)
		)
		(stroke
			(width 0)
			(type solid)
		)
		(fill yes)
		(layer "In4.Cu")
		(net "M_H_DQS_DN<11>")
	)
	(gr_poly
		(pts
			(xy 69.382386 -62.074552) (xy 69.390514 -61.882782) (xy 69.199252 -61.772292) (xy 69.0372 -61.875162)
			(xy 69.014848 -61.91377) (xy 69.360288 -62.11316)
		)
		(stroke
			(width 0)
			(type solid)
		)
		(fill yes)
		(layer "In4.Cu")
		(net "M_H_DQS_DN<10>")
	)
	(gr_poly
		(pts
			(xy 69.394324 -70.004432) (xy 69.402452 -69.812662) (xy 69.21119 -69.702172) (xy 69.049138 -69.805042)
			(xy 69.026786 -69.84365) (xy 69.372226 -70.04304)
		)
		(stroke
			(width 0)
			(type solid)
		)
		(fill yes)
		(layer "In4.Cu")
		(net "M_H_DQ<5>")
	)
	(gr_poly
		(pts
			(xy 69.394324 -69.013832) (xy 69.402452 -68.822062) (xy 69.21119 -68.711572) (xy 69.049138 -68.814442)
			(xy 69.026786 -68.85305) (xy 69.372226 -69.05244)
		)
		(stroke
			(width 0)
			(type solid)
		)
		(fill yes)
		(layer "In4.Cu")
		(net "M_H_DQ<1>")
	)
	(gr_poly
		(pts
			(xy 69.394324 -68.023232) (xy 69.402452 -67.831462) (xy 69.21119 -67.720972) (xy 69.049138 -67.823842)
			(xy 69.026786 -67.86245) (xy 69.372226 -68.06184)
		)
		(stroke
			(width 0)
			(type solid)
		)
		(fill yes)
		(layer "In4.Cu")
		(net "M_H_DQS_DN<9>")
	)
	(gr_poly
		(pts
			(xy 69.394324 -67.032632) (xy 69.402452 -66.840862) (xy 69.21119 -66.730372) (xy 69.049138 -66.833242)
			(xy 69.026786 -66.87185) (xy 69.372226 -67.07124)
		)
		(stroke
			(width 0)
			(type solid)
		)
		(fill yes)
		(layer "In4.Cu")
		(net "M_H_DQS_DN<0>")
	)
	(gr_poly
		(pts
			(xy 69.394324 -66.042032) (xy 69.402452 -65.850262) (xy 69.21119 -65.739772) (xy 69.049138 -65.842642)
			(xy 69.026786 -65.88125) (xy 69.372226 -66.08064)
		)
		(stroke
			(width 0)
			(type solid)
		)
		(fill yes)
		(layer "In4.Cu")
		(net "M_H_DQ<7>")
	)
	(gr_poly
		(pts
			(xy 69.394324 -65.051432) (xy 69.402452 -64.859662) (xy 69.21119 -64.749172) (xy 69.049138 -64.852042)
			(xy 69.026786 -64.89065) (xy 69.372226 -65.09004)
		)
		(stroke
			(width 0)
			(type solid)
		)
		(fill yes)
		(layer "In4.Cu")
		(net "M_H_DQ<3>")
	)
	(gr_poly
		(pts
			(xy 69.394324 -64.060832) (xy 69.402452 -63.869062) (xy 69.21119 -63.758572) (xy 69.049138 -63.861442)
			(xy 69.026786 -63.90005) (xy 69.372226 -64.09944)
		)
		(stroke
			(width 0)
			(type solid)
		)
		(fill yes)
		(layer "In4.Cu")
		(net "M_H_DQ<13>")
	)
	(gr_poly
		(pts
			(xy 69.394324 -63.070232) (xy 69.402452 -62.878462) (xy 69.21119 -62.767972) (xy 69.049138 -62.870842)
			(xy 69.026786 -62.90945) (xy 69.372226 -63.10884)
		)
		(stroke
			(width 0)
			(type solid)
		)
		(fill yes)
		(layer "In4.Cu")
		(net "M_H_DQ<9>")
	)
	(gr_poly
		(pts
			(xy 69.397626 -101.83876) (xy 69.323966 -101.639624) (xy 69.29247 -101.608128) (xy 69.005196 -101.895402)
			(xy 69.036692 -101.926898) (xy 69.235828 -102.000558)
		)
		(stroke
			(width 0)
			(type solid)
		)
		(fill yes)
		(layer "In4.Cu")
		(net "M_L_DQ<17>")
	)
	(gr_poly
		(pts
			(xy 69.398642 -100.80625) (xy 69.390514 -100.61448) (xy 69.368416 -100.575872) (xy 69.022976 -100.775262)
			(xy 69.045328 -100.81387) (xy 69.20738 -100.91674)
		)
		(stroke
			(width 0)
			(type solid)
		)
		(fill yes)
		(layer "In4.Cu")
		(net "M_L_DQ<21>")
	)
	(gr_poly
		(pts
			(xy 69.400928 -89.90838) (xy 69.3928 -89.71661) (xy 69.370702 -89.678002) (xy 69.025262 -89.877646)
			(xy 69.047614 -89.916) (xy 69.209666 -90.01887)
		)
		(stroke
			(width 0)
			(type solid)
		)
		(fill yes)
		(layer "In4.Cu")
		(net "M_L_DQS_DN<10>")
	)
	(gr_poly
		(pts
			(xy 69.400928 -88.91778) (xy 69.3928 -88.72601) (xy 69.370702 -88.687402) (xy 69.025262 -88.887046)
			(xy 69.047614 -88.9254) (xy 69.209666 -89.02827)
		)
		(stroke
			(width 0)
			(type solid)
		)
		(fill yes)
		(layer "In4.Cu")
		(net "M_L_DQ<9>")
	)
	(gr_poly
		(pts
			(xy 69.400928 -87.92718) (xy 69.3928 -87.73541) (xy 69.370702 -87.696802) (xy 69.025262 -87.896446)
			(xy 69.047614 -87.9348) (xy 69.209666 -88.03767)
		)
		(stroke
			(width 0)
			(type solid)
		)
		(fill yes)
		(layer "In4.Cu")
		(net "M_L_DQ<13>")
	)
	(gr_poly
		(pts
			(xy 69.400928 -86.93658) (xy 69.3928 -86.74481) (xy 69.370702 -86.706202) (xy 69.025262 -86.905846)
			(xy 69.047614 -86.9442) (xy 69.209666 -87.04707)
		)
		(stroke
			(width 0)
			(type solid)
		)
		(fill yes)
		(layer "In4.Cu")
		(net "M_L_DQ<3>")
	)
	(gr_poly
		(pts
			(xy 69.400928 -85.94598) (xy 69.3928 -85.75421) (xy 69.370702 -85.715602) (xy 69.025262 -85.915246)
			(xy 69.047614 -85.9536) (xy 69.209666 -86.05647)
		)
		(stroke
			(width 0)
			(type solid)
		)
		(fill yes)
		(layer "In4.Cu")
		(net "M_L_DQ<7>")
	)
	(gr_poly
		(pts
			(xy 69.400928 -84.95538) (xy 69.3928 -84.76361) (xy 69.370702 -84.725002) (xy 69.025262 -84.924646)
			(xy 69.047614 -84.963) (xy 69.209666 -85.06587)
		)
		(stroke
			(width 0)
			(type solid)
		)
		(fill yes)
		(layer "In4.Cu")
		(net "M_L_DQS_DP<0>")
	)
	(gr_poly
		(pts
			(xy 69.400928 -83.96478) (xy 69.3928 -83.77301) (xy 69.370702 -83.734402) (xy 69.025262 -83.934046)
			(xy 69.047614 -83.9724) (xy 69.209666 -84.07527)
		)
		(stroke
			(width 0)
			(type solid)
		)
		(fill yes)
		(layer "In4.Cu")
		(net "M_L_DQS_DN<9>")
	)
	(gr_poly
		(pts
			(xy 69.400928 -81.98358) (xy 69.3928 -81.79181) (xy 69.370702 -81.753202) (xy 69.025262 -81.952846)
			(xy 69.047614 -81.9912) (xy 69.209666 -82.09407)
		)
		(stroke
			(width 0)
			(type solid)
		)
		(fill yes)
		(layer "In4.Cu")
		(net "M_L_DQ<5>")
	)
	(gr_poly
		(pts
			(xy 69.402452 -82.973418) (xy 69.394324 -82.781648) (xy 69.372226 -82.743294) (xy 69.026786 -82.94243)
			(xy 69.049138 -82.981038) (xy 69.21119 -83.083908)
		)
		(stroke
			(width 0)
			(type solid)
		)
		(fill yes)
		(layer "In4.Cu")
		(net "M_L_DQ<1>")
	)
	(gr_poly
		(pts
			(xy 69.428868 -95.353886) (xy 69.428868 -95.309436) (xy 69.022468 -95.309436) (xy 69.022468 -95.353886)
			(xy 69.111368 -95.546926) (xy 69.339968 -95.546926)
		)
		(stroke
			(width 0)
			(type solid)
		)
		(fill yes)
		(layer "In4.Cu")
		(net "M_L_DQ<11>")
	)
	(gr_poly
		(pts
			(xy 69.428868 -95.074486) (xy 69.339968 -94.881446) (xy 69.111368 -94.881446) (xy 69.022468 -95.074486)
			(xy 69.022468 -95.118936) (xy 69.428868 -95.118936)
		)
		(stroke
			(width 0)
			(type solid)
		)
		(fill yes)
		(layer "In4.Cu")
		(net "M_L_DQ<10>")
	)
	(gr_poly
		(pts
			(xy 69.590666 -91.368118) (xy 69.590666 -91.139518) (xy 69.397626 -91.050618) (xy 69.353176 -91.050618)
			(xy 69.353176 -91.457018) (xy 69.397626 -91.457018)
		)
		(stroke
			(width 0)
			(type solid)
		)
		(fill yes)
		(layer "In4.Cu")
		(net "M_L_DQS_DP<1>")
	)
	(gr_poly
		(pts
			(xy 69.590666 -59.67476) (xy 69.590666 -59.44616) (xy 69.397626 -59.35726) (xy 69.353176 -59.35726)
			(xy 69.353176 -59.76366) (xy 69.397626 -59.76366)
		)
		(stroke
			(width 0)
			(type solid)
		)
		(fill yes)
		(layer "In4.Cu")
		(net "M_H_DQS_DN<1>")
	)
	(gr_poly
		(pts
			(xy 69.598794 -69.607684) (xy 69.621146 -69.56933) (xy 69.275706 -69.369686) (xy 69.253608 -69.408294)
			(xy 69.24548 -69.600064) (xy 69.436742 -69.710554)
		)
		(stroke
			(width 0)
			(type solid)
		)
		(fill yes)
		(layer "In4.Cu")
		(net "M_H_DQ<0>")
	)
	(gr_poly
		(pts
			(xy 69.598794 -67.626484) (xy 69.621146 -67.58813) (xy 69.275706 -67.388486) (xy 69.253608 -67.427094)
			(xy 69.24548 -67.618864) (xy 69.436742 -67.729354)
		)
		(stroke
			(width 0)
			(type solid)
		)
		(fill yes)
		(layer "In4.Cu")
		(net "M_H_DQS_DP<0>")
	)
	(gr_poly
		(pts
			(xy 69.598794 -66.635884) (xy 69.621146 -66.59753) (xy 69.275706 -66.397886) (xy 69.253608 -66.436494)
			(xy 69.24548 -66.628264) (xy 69.436742 -66.738754)
		)
		(stroke
			(width 0)
			(type solid)
		)
		(fill yes)
		(layer "In4.Cu")
		(net "M_H_DQ<6>")
	)
	(gr_poly
		(pts
			(xy 69.598794 -65.645284) (xy 69.621146 -65.60693) (xy 69.275706 -65.407286) (xy 69.253608 -65.445894)
			(xy 69.24548 -65.637664) (xy 69.436742 -65.748154)
		)
		(stroke
			(width 0)
			(type solid)
		)
		(fill yes)
		(layer "In4.Cu")
		(net "M_H_DQ<2>")
	)
	(gr_poly
		(pts
			(xy 69.598794 -64.654684) (xy 69.621146 -64.61633) (xy 69.275706 -64.416686) (xy 69.253608 -64.455294)
			(xy 69.24548 -64.647064) (xy 69.436742 -64.757554)
		)
		(stroke
			(width 0)
			(type solid)
		)
		(fill yes)
		(layer "In4.Cu")
		(net "M_H_DQ<12>")
	)
	(gr_poly
		(pts
			(xy 69.598794 -63.664084) (xy 69.621146 -63.62573) (xy 69.275706 -63.426086) (xy 69.253608 -63.464694)
			(xy 69.24548 -63.656464) (xy 69.436742 -63.766954)
		)
		(stroke
			(width 0)
			(type solid)
		)
		(fill yes)
		(layer "In4.Cu")
		(net "M_H_DQ<8>")
	)
	(gr_poly
		(pts
			(xy 69.598794 -62.673484) (xy 69.621146 -62.63513) (xy 69.275706 -62.435486) (xy 69.253608 -62.474094)
			(xy 69.24548 -62.665864) (xy 69.436742 -62.776354)
		)
		(stroke
			(width 0)
			(type solid)
		)
		(fill yes)
		(layer "In4.Cu")
		(net "M_H_DQS_DP<10>")
	)
	(gr_poly
		(pts
			(xy 69.598794 -61.682884) (xy 69.621146 -61.64453) (xy 69.275452 -61.44514) (xy 69.253608 -61.483494)
			(xy 69.24548 -61.675264) (xy 69.436742 -61.785754)
		)
		(stroke
			(width 0)
			(type solid)
		)
		(fill yes)
		(layer "In4.Cu")
		(net "M_H_DQS_DP<1>")
	)
	(gr_poly
		(pts
			(xy 69.600318 -68.617846) (xy 69.62267 -68.579238) (xy 69.27723 -68.379848) (xy 69.255132 -68.418456)
			(xy 69.247004 -68.610226) (xy 69.438266 -68.720716)
		)
		(stroke
			(width 0)
			(type solid)
		)
		(fill yes)
		(layer "In4.Cu")
		(net "M_H_DQS_DP<9>")
	)
	(gr_poly
		(pts
			(xy 69.602604 -51.77917) (xy 69.624956 -51.740562) (xy 69.279516 -51.541172) (xy 69.257418 -51.57978)
			(xy 69.24929 -51.77155) (xy 69.440552 -51.88204)
		)
		(stroke
			(width 0)
			(type solid)
		)
		(fill yes)
		(layer "In4.Cu")
		(net "M_H_DQ<20>")
	)
	(gr_poly
		(pts
			(xy 69.608192 -70.603872) (xy 69.63029 -70.565518) (xy 69.285104 -70.366128) (xy 69.262752 -70.404482)
			(xy 69.254624 -70.596506) (xy 69.44614 -70.706996)
		)
		(stroke
			(width 0)
			(type solid)
		)
		(fill yes)
		(layer "In4.Cu")
		(net "M_H_DQ<4>")
	)
	(gr_poly
		(pts
			(xy 69.621146 -100.056442) (xy 69.598794 -100.018088) (xy 69.436742 -99.915218) (xy 69.24548 -100.025708)
			(xy 69.253608 -100.217478) (xy 69.275706 -100.256086)
		)
		(stroke
			(width 0)
			(type solid)
		)
		(fill yes)
		(layer "In4.Cu")
		(net "M_L_DQ<20>")
	)
	(gr_poly
		(pts
			(xy 69.62267 -101.04628) (xy 69.600318 -101.007926) (xy 69.438266 -100.905056) (xy 69.247004 -101.015546)
			(xy 69.255132 -101.207316) (xy 69.27723 -101.24567)
		)
		(stroke
			(width 0)
			(type solid)
		)
		(fill yes)
		(layer "In4.Cu")
		(net "M_L_DQ<16>")
	)
	(gr_poly
		(pts
			(xy 69.62267 -90.14968) (xy 69.600318 -90.111326) (xy 69.438266 -90.008456) (xy 69.247004 -90.118946)
			(xy 69.255132 -90.310716) (xy 69.27723 -90.34907)
		)
		(stroke
			(width 0)
			(type solid)
		)
		(fill yes)
		(layer "In4.Cu")
		(net "M_L_DQS_DN<1>")
	)
	(gr_poly
		(pts
			(xy 69.62267 -89.15908) (xy 69.600318 -89.120726) (xy 69.438266 -89.017856) (xy 69.247004 -89.128346)
			(xy 69.255132 -89.320116) (xy 69.27723 -89.35847)
		)
		(stroke
			(width 0)
			(type solid)
		)
		(fill yes)
		(layer "In4.Cu")
		(net "M_L_DQS_DP<10>")
	)
	(gr_poly
		(pts
			(xy 69.62267 -88.16848) (xy 69.600318 -88.130126) (xy 69.438266 -88.027256) (xy 69.247004 -88.137746)
			(xy 69.255132 -88.329516) (xy 69.27723 -88.36787)
		)
		(stroke
			(width 0)
			(type solid)
		)
		(fill yes)
		(layer "In4.Cu")
		(net "M_L_DQ<8>")
	)
	(gr_poly
		(pts
			(xy 69.62267 -87.17788) (xy 69.600318 -87.139526) (xy 69.438266 -87.036656) (xy 69.247004 -87.147146)
			(xy 69.255132 -87.338916) (xy 69.27723 -87.37727)
		)
		(stroke
			(width 0)
			(type solid)
		)
		(fill yes)
		(layer "In4.Cu")
		(net "M_L_DQ<12>")
	)
	(gr_poly
		(pts
			(xy 69.62267 -86.18728) (xy 69.600318 -86.148926) (xy 69.438266 -86.046056) (xy 69.247004 -86.156546)
			(xy 69.255132 -86.348316) (xy 69.27723 -86.38667)
		)
		(stroke
			(width 0)
			(type solid)
		)
		(fill yes)
		(layer "In4.Cu")
		(net "M_L_DQ<2>")
	)
	(gr_poly
		(pts
			(xy 69.62267 -85.19668) (xy 69.600318 -85.158326) (xy 69.438266 -85.055456) (xy 69.247004 -85.165946)
			(xy 69.255132 -85.357716) (xy 69.27723 -85.39607)
		)
		(stroke
			(width 0)
			(type solid)
		)
		(fill yes)
		(layer "In4.Cu")
		(net "M_L_DQ<6>")
	)
	(gr_poly
		(pts
			(xy 69.62267 -84.20608) (xy 69.600318 -84.167726) (xy 69.438266 -84.064856) (xy 69.247004 -84.175346)
			(xy 69.255132 -84.367116) (xy 69.27723 -84.40547)
		)
		(stroke
			(width 0)
			(type solid)
		)
		(fill yes)
		(layer "In4.Cu")
		(net "M_L_DQS_DN<0>")
	)
	(gr_poly
		(pts
			(xy 69.62267 -83.21548) (xy 69.600318 -83.177126) (xy 69.438266 -83.074256) (xy 69.247004 -83.184746)
			(xy 69.255132 -83.376516) (xy 69.27723 -83.41487)
		)
		(stroke
			(width 0)
			(type solid)
		)
		(fill yes)
		(layer "In4.Cu")
		(net "M_L_DQS_DP<9>")
	)
	(gr_poly
		(pts
			(xy 69.62267 -81.23428) (xy 69.600318 -81.195926) (xy 69.438266 -81.093056) (xy 69.247004 -81.203546)
			(xy 69.255132 -81.395316) (xy 69.27723 -81.43367)
		)
		(stroke
			(width 0)
			(type solid)
		)
		(fill yes)
		(layer "In4.Cu")
		(net "M_L_DQ<4>")
	)
	(gr_poly
		(pts
			(xy 69.63029 -82.220308) (xy 69.608192 -82.181954) (xy 69.44614 -82.07883) (xy 69.254624 -82.18932)
			(xy 69.262752 -82.381344) (xy 69.285104 -82.419698)
		)
		(stroke
			(width 0)
			(type solid)
		)
		(fill yes)
		(layer "In4.Cu")
		(net "M_L_DQ<0>")
	)
	(gr_poly
		(pts
			(xy 69.70014 -60.653676) (xy 69.70014 -60.432696) (xy 69.52996 -60.343796) (xy 69.48551 -60.343796)
			(xy 69.48551 -60.742576) (xy 69.52996 -60.742576)
		)
		(stroke
			(width 0)
			(type solid)
		)
		(fill yes)
		(layer "In4.Cu")
		(net "M_H_DQS_DN<1>")
	)
	(gr_poly
		(pts
			(xy 69.714364 -50.5079) (xy 69.745606 -50.476404) (xy 69.458332 -50.18913) (xy 69.426836 -50.220626)
			(xy 69.353176 -50.420016) (xy 69.514974 -50.58156)
		)
		(stroke
			(width 0)
			(type solid)
		)
		(fill yes)
		(layer "In4.Cu")
		(net "M_H_DQ<16>")
	)
	(gr_poly
		(pts
			(xy 69.877686 -49.52746) (xy 69.909182 -49.495964) (xy 69.621908 -49.20869) (xy 69.590412 -49.240186)
			(xy 69.516752 -49.439322) (xy 69.67855 -49.60112)
		)
		(stroke
			(width 0)
			(type solid)
		)
		(fill yes)
		(layer "In4.Cu")
		(net "M_H_DQS_DP<11>")
	)
	(gr_poly
		(pts
			(xy 69.911468 -50.310542) (xy 69.985128 -50.111152) (xy 69.823584 -49.949608) (xy 69.624194 -50.023268)
			(xy 69.592698 -50.054764) (xy 69.879972 -50.342038)
		)
		(stroke
			(width 0)
			(type solid)
		)
		(fill yes)
		(layer "In4.Cu")
		(net "M_H_DQ<17>")
	)
	(gr_poly
		(pts
			(xy 70.020688 -92.0369) (xy 69.976238 -92.0369) (xy 69.806058 -92.1258) (xy 69.806058 -92.34678)
			(xy 69.976238 -92.43568) (xy 70.020688 -92.43568)
		)
		(stroke
			(width 0)
			(type solid)
		)
		(fill yes)
		(layer "In4.Cu")
		(net "M_L_DQ<14>")
	)
	(gr_poly
		(pts
			(xy 70.020688 -60.343796) (xy 69.976238 -60.343796) (xy 69.806058 -60.432696) (xy 69.806058 -60.653676)
			(xy 69.976238 -60.742576) (xy 70.020688 -60.742576)
		)
		(stroke
			(width 0)
			(type solid)
		)
		(fill yes)
		(layer "In4.Cu")
		(net "M_H_DQ<14>")
	)
	(gr_poly
		(pts
			(xy 70.020688 -59.353196) (xy 69.976238 -59.353196) (xy 69.806058 -59.442096) (xy 69.806058 -59.663076)
			(xy 69.976238 -59.751976) (xy 70.020688 -59.751976)
		)
		(stroke
			(width 0)
			(type solid)
		)
		(fill yes)
		(layer "In4.Cu")
		(net "M_H_DQ<14>")
	)
	(gr_poly
		(pts
			(xy 70.020688 -58.362596) (xy 69.976238 -58.362596) (xy 69.806058 -58.451496) (xy 69.806058 -58.672476)
			(xy 69.976238 -58.761376) (xy 70.020688 -58.761376)
		)
		(stroke
			(width 0)
			(type solid)
		)
		(fill yes)
		(layer "In4.Cu")
		(net "M_H_DQ<14>")
	)
	(gr_poly
		(pts
			(xy 70.020688 -57.371996) (xy 69.976238 -57.371996) (xy 69.806058 -57.460896) (xy 69.806058 -57.681876)
			(xy 69.976238 -57.770776) (xy 70.020688 -57.770776)
		)
		(stroke
			(width 0)
			(type solid)
		)
		(fill yes)
		(layer "In4.Cu")
		(net "M_H_DQ<14>")
	)
	(gr_poly
		(pts
			(xy 70.020688 -56.381396) (xy 69.976238 -56.381396) (xy 69.806058 -56.470296) (xy 69.806058 -56.691276)
			(xy 69.976238 -56.780176) (xy 70.020688 -56.780176)
		)
		(stroke
			(width 0)
			(type solid)
		)
		(fill yes)
		(layer "In4.Cu")
		(net "M_H_DQ<14>")
	)
	(gr_poly
		(pts
			(xy 70.075298 -49.329848) (xy 70.148958 -49.130458) (xy 69.987414 -48.968914) (xy 69.788024 -49.042574)
			(xy 69.756528 -49.073816) (xy 70.044056 -49.361344)
		)
		(stroke
			(width 0)
			(type solid)
		)
		(fill yes)
		(layer "In4.Cu")
		(net "M_H_DQS_DN<11>")
	)
	(gr_poly
		(pts
			(xy 70.211442 -91.04757) (xy 70.166992 -91.04757) (xy 69.996812 -91.13647) (xy 69.996812 -91.35745)
			(xy 70.166992 -91.44635) (xy 70.211442 -91.44635)
		)
		(stroke
			(width 0)
			(type solid)
		)
		(fill yes)
		(layer "In4.Cu")
		(net "M_L_DQ<14>")
	)
	(gr_poly
		(pts
			(xy 70.2437 -82.381344) (xy 70.251828 -82.18932) (xy 70.060312 -82.07883) (xy 69.89826 -82.181954)
			(xy 69.876162 -82.220308) (xy 70.221348 -82.419698)
		)
		(stroke
			(width 0)
			(type solid)
		)
		(fill yes)
		(layer "In4.Cu")
		(net "M_L_DQ<0>")
	)
	(gr_poly
		(pts
			(xy 70.249034 -51.676046) (xy 70.257162 -51.484276) (xy 70.0659 -51.373786) (xy 69.903848 -51.476656)
			(xy 69.881496 -51.51501) (xy 70.226936 -51.714654)
		)
		(stroke
			(width 0)
			(type solid)
		)
		(fill yes)
		(layer "In4.Cu")
		(net "M_H_DQ<21>")
	)
	(gr_poly
		(pts
			(xy 70.250558 -61.582808) (xy 70.258686 -61.391038) (xy 70.067424 -61.280548) (xy 69.905372 -61.383418)
			(xy 69.88302 -61.421772) (xy 70.22846 -61.621162)
		)
		(stroke
			(width 0)
			(type solid)
		)
		(fill yes)
		(layer "In4.Cu")
		(net "M_H_DQS_DN<1>")
	)
	(gr_poly
		(pts
			(xy 70.25132 -83.376516) (xy 70.259448 -83.184746) (xy 70.068186 -83.074256) (xy 69.906134 -83.177126)
			(xy 69.883782 -83.21548) (xy 70.229222 -83.41487)
		)
		(stroke
			(width 0)
			(type solid)
		)
		(fill yes)
		(layer "In4.Cu")
		(net "M_L_DQS_DP<9>")
	)
	(gr_poly
		(pts
			(xy 70.25132 -81.395316) (xy 70.259448 -81.203546) (xy 70.068186 -81.093056) (xy 69.906134 -81.195926)
			(xy 69.883782 -81.23428) (xy 70.229222 -81.43367)
		)
		(stroke
			(width 0)
			(type solid)
		)
		(fill yes)
		(layer "In4.Cu")
		(net "M_L_DQ<4>")
	)
	(gr_poly
		(pts
			(xy 70.251574 -93.380052) (xy 70.2437 -93.188282) (xy 70.221602 -93.149674) (xy 69.876162 -93.349318)
			(xy 69.898514 -93.387418) (xy 70.060312 -93.490542)
		)
		(stroke
			(width 0)
			(type solid)
		)
		(fill yes)
		(layer "In4.Cu")
		(net "M_L_DQ<15>")
	)
	(gr_poly
		(pts
			(xy 70.251828 -70.596506) (xy 70.2437 -70.404482) (xy 70.221348 -70.366128) (xy 69.876162 -70.565518)
			(xy 69.89826 -70.603872) (xy 70.060312 -70.706996)
		)
		(stroke
			(width 0)
			(type solid)
		)
		(fill yes)
		(layer "In4.Cu")
		(net "M_H_DQ<4>")
	)
	(gr_poly
		(pts
			(xy 70.259448 -100.30968) (xy 70.25132 -100.11791) (xy 70.229222 -100.079302) (xy 69.883782 -100.278946)
			(xy 69.906134 -100.3173) (xy 70.068186 -100.42017)
		)
		(stroke
			(width 0)
			(type solid)
		)
		(fill yes)
		(layer "In4.Cu")
		(net "M_L_DQ<21>")
	)
	(gr_poly
		(pts
			(xy 70.259448 -68.610226) (xy 70.25132 -68.418456) (xy 70.229222 -68.379848) (xy 69.883782 -68.579238)
			(xy 69.906134 -68.617846) (xy 70.068186 -68.720716)
		)
		(stroke
			(width 0)
			(type solid)
		)
		(fill yes)
		(layer "In4.Cu")
		(net "M_H_DQS_DP<9>")
	)
	(gr_poly
		(pts
			(xy 70.260972 -101.299264) (xy 70.252844 -101.107494) (xy 70.230746 -101.068886) (xy 69.885306 -101.26853)
			(xy 69.907658 -101.306884) (xy 70.06971 -101.409754)
		)
		(stroke
			(width 0)
			(type solid)
		)
		(fill yes)
		(layer "In4.Cu")
		(net "M_L_DQ<17>")
	)
	(gr_poly
		(pts
			(xy 70.260972 -95.355664) (xy 70.252844 -95.163894) (xy 70.230746 -95.125286) (xy 69.885306 -95.32493)
			(xy 69.907658 -95.363284) (xy 70.06971 -95.466154)
		)
		(stroke
			(width 0)
			(type solid)
		)
		(fill yes)
		(layer "In4.Cu")
		(net "M_L_DQ<11>")
	)
	(gr_poly
		(pts
			(xy 70.260972 -90.402664) (xy 70.252844 -90.210894) (xy 70.230746 -90.172286) (xy 69.885306 -90.37193)
			(xy 69.907658 -90.410284) (xy 70.06971 -90.513154)
		)
		(stroke
			(width 0)
			(type solid)
		)
		(fill yes)
		(layer "In4.Cu")
		(net "M_L_DQS_DP<1>")
	)
	(gr_poly
		(pts
			(xy 70.260972 -89.412064) (xy 70.252844 -89.220294) (xy 70.230746 -89.181686) (xy 69.885306 -89.38133)
			(xy 69.907658 -89.419684) (xy 70.06971 -89.522554)
		)
		(stroke
			(width 0)
			(type solid)
		)
		(fill yes)
		(layer "In4.Cu")
		(net "M_L_DQS_DN<10>")
	)
	(gr_poly
		(pts
			(xy 70.260972 -88.421464) (xy 70.252844 -88.229694) (xy 70.230746 -88.191086) (xy 69.885306 -88.39073)
			(xy 69.907658 -88.429084) (xy 70.06971 -88.531954)
		)
		(stroke
			(width 0)
			(type solid)
		)
		(fill yes)
		(layer "In4.Cu")
		(net "M_L_DQ<9>")
	)
	(gr_poly
		(pts
			(xy 70.260972 -87.430864) (xy 70.252844 -87.239094) (xy 70.230746 -87.200486) (xy 69.885306 -87.40013)
			(xy 69.907658 -87.438484) (xy 70.06971 -87.541354)
		)
		(stroke
			(width 0)
			(type solid)
		)
		(fill yes)
		(layer "In4.Cu")
		(net "M_L_DQ<13>")
	)
	(gr_poly
		(pts
			(xy 70.260972 -69.600064) (xy 70.252844 -69.408294) (xy 70.230746 -69.369686) (xy 69.885306 -69.56933)
			(xy 69.907658 -69.607684) (xy 70.06971 -69.710554)
		)
		(stroke
			(width 0)
			(type solid)
		)
		(fill yes)
		(layer "In4.Cu")
		(net "M_H_DQ<0>")
	)
	(gr_poly
		(pts
			(xy 70.260972 -67.618864) (xy 70.252844 -67.427094) (xy 70.230746 -67.388486) (xy 69.885306 -67.58813)
			(xy 69.907658 -67.626484) (xy 70.06971 -67.729354)
		)
		(stroke
			(width 0)
			(type solid)
		)
		(fill yes)
		(layer "In4.Cu")
		(net "M_H_DQS_DP<0>")
	)
	(gr_poly
		(pts
			(xy 70.314312 -48.271938) (xy 70.345808 -48.240442) (xy 70.058534 -47.953168) (xy 70.027038 -47.984664)
			(xy 69.953378 -48.1838) (xy 70.115176 -48.345598)
		)
		(stroke
			(width 0)
			(type solid)
		)
		(fill yes)
		(layer "In4.Cu")
		(net "M_H_DQS_DP<2>")
	)
	(gr_poly
		(pts
			(xy 70.377304 -103.1113) (xy 70.345808 -103.080058) (xy 70.146418 -103.006398) (xy 69.984874 -103.167942)
			(xy 70.058534 -103.367332) (xy 70.089776 -103.398828)
		)
		(stroke
			(width 0)
			(type solid)
		)
		(fill yes)
		(layer "In4.Cu")
		(net "M_L_DQS_DN<2>")
	)
	(gr_poly
		(pts
			(xy 70.38848 -92.936822) (xy 70.55866 -92.848176) (xy 70.55866 -92.627196) (xy 70.388734 -92.538296)
			(xy 70.344284 -92.538042) (xy 70.344284 -92.937076)
		)
		(stroke
			(width 0)
			(type solid)
		)
		(fill yes)
		(layer "In4.Cu")
		(net "M_L_DQ<15>")
	)
	(gr_poly
		(pts
			(xy 70.457314 -82.981038) (xy 70.479666 -82.94243) (xy 70.134226 -82.743294) (xy 70.112128 -82.781648)
			(xy 70.104 -82.973418) (xy 70.295262 -83.083908)
		)
		(stroke
			(width 0)
			(type solid)
		)
		(fill yes)
		(layer "In4.Cu")
		(net "M_L_DQ<1>")
	)
	(gr_poly
		(pts
			(xy 70.457314 -52.272438) (xy 70.479666 -52.23383) (xy 70.134226 -52.034694) (xy 70.112128 -52.073048)
			(xy 70.104 -52.264818) (xy 70.295262 -52.375308)
		)
		(stroke
			(width 0)
			(type solid)
		)
		(fill yes)
		(layer "In4.Cu")
		(net "M_H_DQ<20>")
	)
	(gr_poly
		(pts
			(xy 70.458838 -83.9724) (xy 70.48119 -83.934046) (xy 70.13575 -83.734402) (xy 70.113652 -83.77301)
			(xy 70.105524 -83.96478) (xy 70.296786 -84.07527)
		)
		(stroke
			(width 0)
			(type solid)
		)
		(fill yes)
		(layer "In4.Cu")
		(net "M_L_DQS_DN<9>")
	)
	(gr_poly
		(pts
			(xy 70.458838 -81.9912) (xy 70.48119 -81.952846) (xy 70.13575 -81.753202) (xy 70.113652 -81.79181)
			(xy 70.105524 -81.98358) (xy 70.296786 -82.09407)
		)
		(stroke
			(width 0)
			(type solid)
		)
		(fill yes)
		(layer "In4.Cu")
		(net "M_L_DQ<5>")
	)
	(gr_poly
		(pts
			(xy 70.458838 -51.282854) (xy 70.48119 -51.244246) (xy 70.13575 -51.044856) (xy 70.113652 -51.083464)
			(xy 70.105524 -51.275234) (xy 70.296786 -51.385724)
		)
		(stroke
			(width 0)
			(type solid)
		)
		(fill yes)
		(layer "In4.Cu")
		(net "M_H_DQ<16>")
	)
	(gr_poly
		(pts
			(xy 70.46214 -63.950342) (xy 70.486016 -63.91275) (xy 70.147688 -63.701168) (xy 70.12432 -63.739014)
			(xy 70.109334 -63.930276) (xy 70.296786 -64.04737)
		)
		(stroke
			(width 0)
			(type solid)
		)
		(fill yes)
		(layer "In4.Cu")
		(net "M_H_DQ<8>")
	)
	(gr_poly
		(pts
			(xy 70.466204 -62.183518) (xy 70.488556 -62.145164) (xy 70.143116 -61.94552) (xy 70.121018 -61.984128)
			(xy 70.11289 -62.175898) (xy 70.304152 -62.286388)
		)
		(stroke
			(width 0)
			(type solid)
		)
		(fill yes)
		(layer "In4.Cu")
		(net "M_H_DQS_DP<1>")
	)
	(gr_poly
		(pts
			(xy 70.472046 -55.25516) (xy 70.494398 -55.21706) (xy 70.15099 -55.014622) (xy 70.128384 -55.05323)
			(xy 70.118732 -55.244746) (xy 70.308978 -55.357014)
		)
		(stroke
			(width 0)
			(type solid)
		)
		(fill yes)
		(layer "In4.Cu")
		(net "M_H_DQ<10>")
	)
	(gr_poly
		(pts
			(xy 70.479158 -63.106046) (xy 70.451472 -63.070994) (xy 70.27672 -62.991492) (xy 70.10273 -63.127636)
			(xy 70.137274 -63.316358) (xy 70.164706 -63.35141)
		)
		(stroke
			(width 0)
			(type solid)
		)
		(fill yes)
		(layer "In4.Cu")
		(net "M_H_DQ<9>")
	)
	(gr_poly
		(pts
			(xy 70.479666 -89.65565) (xy 70.457314 -89.617042) (xy 70.295262 -89.514172) (xy 70.104 -89.624662)
			(xy 70.112128 -89.816432) (xy 70.134226 -89.85504)
		)
		(stroke
			(width 0)
			(type solid)
		)
		(fill yes)
		(layer "In4.Cu")
		(net "M_L_DQS_DN<1>")
	)
	(gr_poly
		(pts
			(xy 70.479666 -88.66505) (xy 70.457314 -88.626442) (xy 70.295262 -88.523572) (xy 70.104 -88.634062)
			(xy 70.112128 -88.825832) (xy 70.134226 -88.86444)
		)
		(stroke
			(width 0)
			(type solid)
		)
		(fill yes)
		(layer "In4.Cu")
		(net "M_L_DQS_DP<10>")
	)
	(gr_poly
		(pts
			(xy 70.479666 -87.67445) (xy 70.457314 -87.635842) (xy 70.295262 -87.532972) (xy 70.104 -87.643462)
			(xy 70.112128 -87.835232) (xy 70.134226 -87.87384)
		)
		(stroke
			(width 0)
			(type solid)
		)
		(fill yes)
		(layer "In4.Cu")
		(net "M_L_DQ<8>")
	)
	(gr_poly
		(pts
			(xy 70.479666 -86.68385) (xy 70.457314 -86.645242) (xy 70.295262 -86.542372) (xy 70.104 -86.652862)
			(xy 70.112128 -86.844632) (xy 70.134226 -86.88324)
		)
		(stroke
			(width 0)
			(type solid)
		)
		(fill yes)
		(layer "In4.Cu")
		(net "M_L_DQ<12>")
	)
	(gr_poly
		(pts
			(xy 70.479666 -85.69325) (xy 70.457314 -85.654642) (xy 70.295262 -85.551772) (xy 70.104 -85.662262)
			(xy 70.112128 -85.854032) (xy 70.134226 -85.89264)
		)
		(stroke
			(width 0)
			(type solid)
		)
		(fill yes)
		(layer "In4.Cu")
		(net "M_L_DQ<2>")
	)
	(gr_poly
		(pts
			(xy 70.479666 -69.84365) (xy 70.457314 -69.805042) (xy 70.295262 -69.702172) (xy 70.104 -69.812662)
			(xy 70.112128 -70.004432) (xy 70.134226 -70.04304)
		)
		(stroke
			(width 0)
			(type solid)
		)
		(fill yes)
		(layer "In4.Cu")
		(net "M_H_DQ<5>")
	)
	(gr_poly
		(pts
			(xy 70.479666 -68.85305) (xy 70.457314 -68.814442) (xy 70.295262 -68.711572) (xy 70.104 -68.822062)
			(xy 70.112128 -69.013832) (xy 70.134226 -69.05244)
		)
		(stroke
			(width 0)
			(type solid)
		)
		(fill yes)
		(layer "In4.Cu")
		(net "M_H_DQ<1>")
	)
	(gr_poly
		(pts
			(xy 70.479666 -66.87185) (xy 70.457314 -66.833242) (xy 70.295262 -66.730372) (xy 70.104 -66.840862)
			(xy 70.112128 -67.032632) (xy 70.134226 -67.07124)
		)
		(stroke
			(width 0)
			(type solid)
		)
		(fill yes)
		(layer "In4.Cu")
		(net "M_H_DQS_DN<0>")
	)
	(gr_poly
		(pts
			(xy 70.48119 -99.56038) (xy 70.458838 -99.522026) (xy 70.296786 -99.419156) (xy 70.105524 -99.529646)
			(xy 70.113652 -99.721416) (xy 70.13575 -99.75977)
		)
		(stroke
			(width 0)
			(type solid)
		)
		(fill yes)
		(layer "In4.Cu")
		(net "M_L_DQ<20>")
	)
	(gr_poly
		(pts
			(xy 70.483476 -100.54971) (xy 70.461124 -100.511356) (xy 70.299072 -100.408486) (xy 70.10781 -100.518976)
			(xy 70.115938 -100.710746) (xy 70.138036 -100.749354)
		)
		(stroke
			(width 0)
			(type solid)
		)
		(fill yes)
		(layer "In4.Cu")
		(net "M_L_DQ<16>")
	)
	(gr_poly
		(pts
			(xy 70.483476 -94.60611) (xy 70.461124 -94.567756) (xy 70.299072 -94.464886) (xy 70.10781 -94.575376)
			(xy 70.115938 -94.767146) (xy 70.138036 -94.805754)
		)
		(stroke
			(width 0)
			(type solid)
		)
		(fill yes)
		(layer "In4.Cu")
		(net "M_L_DQ<10>")
	)
	(gr_poly
		(pts
			(xy 70.511924 -48.074326) (xy 70.585584 -47.874936) (xy 70.42404 -47.713392) (xy 70.22465 -47.787052)
			(xy 70.193154 -47.818294) (xy 70.480682 -48.105822)
		)
		(stroke
			(width 0)
			(type solid)
		)
		(fill yes)
		(layer "In4.Cu")
		(net "M_H_DQS_DN<2>")
	)
	(gr_poly
		(pts
			(xy 70.558914 -60.158376) (xy 70.558914 -59.937396) (xy 70.388734 -59.848496) (xy 70.344284 -59.848496)
			(xy 70.344284 -60.247276) (xy 70.388734 -60.247276)
		)
		(stroke
			(width 0)
			(type solid)
		)
		(fill yes)
		(layer "In4.Cu")
		(net "M_H_DQ<15>")
	)
	(gr_poly
		(pts
			(xy 70.558914 -59.167776) (xy 70.558914 -58.946796) (xy 70.388734 -58.857896) (xy 70.344284 -58.857896)
			(xy 70.344284 -59.256676) (xy 70.388734 -59.256676)
		)
		(stroke
			(width 0)
			(type solid)
		)
		(fill yes)
		(layer "In4.Cu")
		(net "M_H_DQ<15>")
	)
	(gr_poly
		(pts
			(xy 70.558914 -58.177176) (xy 70.558914 -57.956196) (xy 70.388734 -57.867296) (xy 70.344284 -57.867296)
			(xy 70.344284 -58.266076) (xy 70.388734 -58.266076)
		)
		(stroke
			(width 0)
			(type solid)
		)
		(fill yes)
		(layer "In4.Cu")
		(net "M_H_DQ<15>")
	)
	(gr_poly
		(pts
			(xy 70.558914 -57.186576) (xy 70.558914 -56.965596) (xy 70.388734 -56.876696) (xy 70.344284 -56.876696)
			(xy 70.344284 -57.275476) (xy 70.388734 -57.275476)
		)
		(stroke
			(width 0)
			(type solid)
		)
		(fill yes)
		(layer "In4.Cu")
		(net "M_H_DQ<15>")
	)
	(gr_poly
		(pts
			(xy 70.558914 -56.202326) (xy 70.558914 -55.981346) (xy 70.388734 -55.892446) (xy 70.344284 -55.892446)
			(xy 70.344284 -56.291226) (xy 70.388734 -56.291226)
		)
		(stroke
			(width 0)
			(type solid)
		)
		(fill yes)
		(layer "In4.Cu")
		(net "M_H_DQ<15>")
	)
	(gr_poly
		(pts
			(xy 70.61708 -103.476806) (xy 70.54342 -103.27767) (xy 70.511924 -103.246174) (xy 70.22465 -103.533448)
			(xy 70.256146 -103.564944) (xy 70.455282 -103.638604)
		)
		(stroke
			(width 0)
			(type solid)
		)
		(fill yes)
		(layer "In4.Cu")
		(net "M_L_DQS_DP<2>")
	)
	(gr_poly
		(pts
			(xy 70.636892 -101.744272) (xy 70.605396 -101.712776) (xy 70.40626 -101.639116) (xy 70.244462 -101.800914)
			(xy 70.318122 -102.00005) (xy 70.349618 -102.031546)
		)
		(stroke
			(width 0)
			(type solid)
		)
		(fill yes)
		(layer "In4.Cu")
		(net "M_L_DQS_DP<11>")
	)
	(gr_poly
		(pts
			(xy 70.876668 -102.109778) (xy 70.803008 -101.910388) (xy 70.771766 -101.878892) (xy 70.484238 -102.16642)
			(xy 70.515734 -102.197662) (xy 70.715124 -102.271322)
		)
		(stroke
			(width 0)
			(type solid)
		)
		(fill yes)
		(layer "In4.Cu")
		(net "M_L_DQS_DN<11>")
	)
	(gr_poly
		(pts
			(xy 70.879208 -93.5228) (xy 70.834758 -93.5228) (xy 70.664578 -93.6117) (xy 70.664578 -93.83268)
			(xy 70.834758 -93.92158) (xy 70.879208 -93.92158)
		)
		(stroke
			(width 0)
			(type solid)
		)
		(fill yes)
		(layer "In4.Cu")
		(net "M_L_DQ<10>")
	)
	(gr_poly
		(pts
			(xy 70.879208 -92.544646) (xy 70.834758 -92.544646) (xy 70.664578 -92.633546) (xy 70.664578 -92.854526)
			(xy 70.834758 -92.943426) (xy 70.879208 -92.943426)
		)
		(stroke
			(width 0)
			(type solid)
		)
		(fill yes)
		(layer "In4.Cu")
		(net "M_L_DQ<10>")
	)
	(gr_poly
		(pts
			(xy 70.879208 -59.848496) (xy 70.834758 -59.848496) (xy 70.664578 -59.937396) (xy 70.664578 -60.158376)
			(xy 70.834758 -60.247276) (xy 70.879208 -60.247276)
		)
		(stroke
			(width 0)
			(type solid)
		)
		(fill yes)
		(layer "In4.Cu")
		(net "M_H_DQ<10>")
	)
	(gr_poly
		(pts
			(xy 70.879208 -58.857896) (xy 70.834758 -58.857896) (xy 70.664578 -58.946796) (xy 70.664578 -59.167776)
			(xy 70.834758 -59.256676) (xy 70.879208 -59.256676)
		)
		(stroke
			(width 0)
			(type solid)
		)
		(fill yes)
		(layer "In4.Cu")
		(net "M_H_DQ<10>")
	)
	(gr_poly
		(pts
			(xy 70.879208 -57.8612) (xy 70.834758 -57.8612) (xy 70.664578 -57.9501) (xy 70.664578 -58.17108)
			(xy 70.834758 -58.25998) (xy 70.879208 -58.25998)
		)
		(stroke
			(width 0)
			(type solid)
		)
		(fill yes)
		(layer "In4.Cu")
		(net "M_H_DQ<10>")
	)
	(gr_poly
		(pts
			(xy 70.879208 -56.883046) (xy 70.834758 -56.883046) (xy 70.664578 -56.971946) (xy 70.664578 -57.192926)
			(xy 70.834758 -57.281826) (xy 70.879208 -57.281826)
		)
		(stroke
			(width 0)
			(type solid)
		)
		(fill yes)
		(layer "In4.Cu")
		(net "M_H_DQ<10>")
	)
	(gr_poly
		(pts
			(xy 70.879208 -55.892446) (xy 70.834758 -55.892446) (xy 70.664578 -55.981346) (xy 70.664578 -56.202326)
			(xy 70.834758 -56.291226) (xy 70.879208 -56.291226)
		)
		(stroke
			(width 0)
			(type solid)
		)
		(fill yes)
		(layer "In4.Cu")
		(net "M_H_DQ<10>")
	)
	(gr_poly
		(pts
			(xy 70.993 -49.879504) (xy 70.993 -49.835054) (xy 70.5866 -49.835054) (xy 70.5866 -49.879504) (xy 70.6755 -50.072544)
			(xy 70.9041 -50.072544)
		)
		(stroke
			(width 0)
			(type solid)
		)
		(fill yes)
		(layer "In4.Cu")
		(net "M_H_DQS_DP<11>")
	)
	(gr_poly
		(pts
			(xy 70.993 -49.600104) (xy 70.9041 -49.407064) (xy 70.6755 -49.407064) (xy 70.5866 -49.600104) (xy 70.5866 -49.644554)
			(xy 70.993 -49.644554)
		)
		(stroke
			(width 0)
			(type solid)
		)
		(fill yes)
		(layer "In4.Cu")
		(net "M_H_DQS_DN<11>")
	)
	(gr_poly
		(pts
			(xy 71.103236 -89.915746) (xy 71.095108 -89.723976) (xy 71.07301 -89.685368) (xy 70.72757 -89.885012)
			(xy 70.749922 -89.923366) (xy 70.911974 -90.026236)
		)
		(stroke
			(width 0)
			(type solid)
		)
		(fill yes)
		(layer "In4.Cu")
		(net "M_L_DQS_DP<1>")
	)
	(gr_poly
		(pts
			(xy 71.108824 -91.552268) (xy 71.068946 -91.532202) (xy 70.877176 -91.534742) (xy 70.777354 -91.731846)
			(xy 70.889114 -91.888056) (xy 70.928738 -91.908122)
		)
		(stroke
			(width 0)
			(type solid)
		)
		(fill yes)
		(layer "In4.Cu")
		(net "M_L_DQ<10>")
	)
	(gr_poly
		(pts
			(xy 71.110094 -94.865952) (xy 71.10222 -94.674182) (xy 71.079868 -94.635574) (xy 70.734428 -94.834964)
			(xy 70.757034 -94.873318) (xy 70.918832 -94.976442)
		)
		(stroke
			(width 0)
			(type solid)
		)
		(fill yes)
		(layer "In4.Cu")
		(net "M_L_DQ<11>")
	)
	(gr_poly
		(pts
			(xy 71.110348 -62.175898) (xy 71.10222 -61.984128) (xy 71.080122 -61.94552) (xy 70.734682 -62.14491)
			(xy 70.757034 -62.183518) (xy 70.919086 -62.286388)
		)
		(stroke
			(width 0)
			(type solid)
		)
		(fill yes)
		(layer "In4.Cu")
		(net "M_H_DQS_DP<1>")
	)
	(gr_poly
		(pts
			(xy 71.111364 -88.825832) (xy 71.119492 -88.634062) (xy 70.92823 -88.523572) (xy 70.766178 -88.626442)
			(xy 70.743826 -88.66505) (xy 71.089266 -88.86444)
		)
		(stroke
			(width 0)
			(type solid)
		)
		(fill yes)
		(layer "In4.Cu")
		(net "M_L_DQS_DP<10>")
	)
	(gr_poly
		(pts
			(xy 71.111364 -87.835232) (xy 71.119492 -87.643462) (xy 70.92823 -87.532972) (xy 70.766178 -87.635842)
			(xy 70.743826 -87.67445) (xy 71.089266 -87.87384)
		)
		(stroke
			(width 0)
			(type solid)
		)
		(fill yes)
		(layer "In4.Cu")
		(net "M_L_DQ<8>")
	)
	(gr_poly
		(pts
			(xy 71.111364 -86.844632) (xy 71.119492 -86.652862) (xy 70.92823 -86.542372) (xy 70.766178 -86.645242)
			(xy 70.743826 -86.68385) (xy 71.089266 -86.88324)
		)
		(stroke
			(width 0)
			(type solid)
		)
		(fill yes)
		(layer "In4.Cu")
		(net "M_L_DQ<12>")
	)
	(gr_poly
		(pts
			(xy 71.111364 -85.854032) (xy 71.119492 -85.662262) (xy 70.92823 -85.551772) (xy 70.766178 -85.654642)
			(xy 70.743826 -85.69325) (xy 71.089266 -85.89264)
		)
		(stroke
			(width 0)
			(type solid)
		)
		(fill yes)
		(layer "In4.Cu")
		(net "M_L_DQ<2>")
	)
	(gr_poly
		(pts
			(xy 71.111364 -83.872832) (xy 71.119492 -83.681062) (xy 70.92823 -83.570572) (xy 70.766178 -83.673442)
			(xy 70.743826 -83.71205) (xy 71.089266 -83.91144)
		)
		(stroke
			(width 0)
			(type solid)
		)
		(fill yes)
		(layer "In4.Cu")
		(net "M_L_DQS_DP<9>")
	)
	(gr_poly
		(pts
			(xy 71.111364 -82.882232) (xy 71.119492 -82.690462) (xy 70.92823 -82.579972) (xy 70.766178 -82.682842)
			(xy 70.743826 -82.72145) (xy 71.089266 -82.92084)
		)
		(stroke
			(width 0)
			(type solid)
		)
		(fill yes)
		(layer "In4.Cu")
		(net "M_L_DQ<0>")
	)
	(gr_poly
		(pts
			(xy 71.111364 -81.891632) (xy 71.119492 -81.699862) (xy 70.92823 -81.589372) (xy 70.766178 -81.692242)
			(xy 70.743826 -81.73085) (xy 71.089266 -81.93024)
		)
		(stroke
			(width 0)
			(type solid)
		)
		(fill yes)
		(layer "In4.Cu")
		(net "M_L_DQ<4>")
	)
	(gr_poly
		(pts
			(xy 71.115682 -100.80625) (xy 71.107554 -100.61448) (xy 71.085456 -100.575872) (xy 70.740016 -100.775262)
			(xy 70.762368 -100.81387) (xy 70.92442 -100.91674)
		)
		(stroke
			(width 0)
			(type solid)
		)
		(fill yes)
		(layer "In4.Cu")
		(net "M_L_DQ<17>")
	)
	(gr_poly
		(pts
			(xy 71.11619 -67.125596) (xy 71.108062 -66.933826) (xy 71.085964 -66.895218) (xy 70.740524 -67.094862)
			(xy 70.762876 -67.133216) (xy 70.924928 -67.236086)
		)
		(stroke
			(width 0)
			(type solid)
		)
		(fill yes)
		(layer "In4.Cu")
		(net "M_H_DQS_DP<0>")
	)
	(gr_poly
		(pts
			(xy 71.117968 -70.09638) (xy 71.10984 -69.90461) (xy 71.087742 -69.866002) (xy 70.742302 -70.065646)
			(xy 70.764654 -70.104) (xy 70.926706 -70.20687)
		)
		(stroke
			(width 0)
			(type solid)
		)
		(fill yes)
		(layer "In4.Cu")
		(net "M_H_DQ<4>")
	)
	(gr_poly
		(pts
			(xy 71.117968 -69.10578) (xy 71.10984 -68.91401) (xy 71.087742 -68.875402) (xy 70.742302 -69.075046)
			(xy 70.764654 -69.1134) (xy 70.926706 -69.21627)
		)
		(stroke
			(width 0)
			(type solid)
		)
		(fill yes)
		(layer "In4.Cu")
		(net "M_H_DQ<0>")
	)
	(gr_poly
		(pts
			(xy 71.117968 -66.13398) (xy 71.10984 -65.94221) (xy 71.087742 -65.903602) (xy 70.742302 -66.103246)
			(xy 70.764654 -66.1416) (xy 70.926706 -66.24447)
		)
		(stroke
			(width 0)
			(type solid)
		)
		(fill yes)
		(layer "In4.Cu")
		(net "M_H_DQ<7>")
	)
	(gr_poly
		(pts
			(xy 71.117968 -64.15278) (xy 71.10984 -63.96101) (xy 71.087742 -63.922402) (xy 70.742302 -64.122046)
			(xy 70.764654 -64.1604) (xy 70.926706 -64.26327)
		)
		(stroke
			(width 0)
			(type solid)
		)
		(fill yes)
		(layer "In4.Cu")
		(net "M_H_DQ<13>")
	)
	(gr_poly
		(pts
			(xy 71.247 -94.422722) (xy 71.41718 -94.334076) (xy 71.41718 -94.113096) (xy 71.247254 -94.024196)
			(xy 71.20255 -94.024196) (xy 71.20255 -94.422976)
		)
		(stroke
			(width 0)
			(type solid)
		)
		(fill yes)
		(layer "In4.Cu")
		(net "M_L_DQ<11>")
	)
	(gr_poly
		(pts
			(xy 71.314818 -51.562762) (xy 71.33717 -51.524408) (xy 70.99173 -51.325018) (xy 70.969632 -51.363372)
			(xy 70.961504 -51.555142) (xy 71.152766 -51.665632)
		)
		(stroke
			(width 0)
			(type solid)
		)
		(fill yes)
		(layer "In4.Cu")
		(net "M_H_DQ<16>")
	)
	(gr_poly
		(pts
			(xy 71.315834 -87.438484) (xy 71.338186 -87.40013) (xy 70.992746 -87.200486) (xy 70.970648 -87.239094)
			(xy 70.96252 -87.430864) (xy 71.153782 -87.541354)
		)
		(stroke
			(width 0)
			(type solid)
		)
		(fill yes)
		(layer "In4.Cu")
		(net "M_L_DQ<13>")
	)
	(gr_poly
		(pts
			(xy 71.315834 -85.457284) (xy 71.338186 -85.41893) (xy 70.992746 -85.219286) (xy 70.970648 -85.257894)
			(xy 70.96252 -85.449664) (xy 71.153782 -85.560154)
		)
		(stroke
			(width 0)
			(type solid)
		)
		(fill yes)
		(layer "In4.Cu")
		(net "M_L_DQ<6>")
	)
	(gr_poly
		(pts
			(xy 71.315834 -84.466684) (xy 71.338186 -84.42833) (xy 70.992746 -84.228686) (xy 70.970648 -84.267294)
			(xy 70.96252 -84.459064) (xy 71.153782 -84.569554)
		)
		(stroke
			(width 0)
			(type solid)
		)
		(fill yes)
		(layer "In4.Cu")
		(net "M_L_DQS_DN<9>")
	)
	(gr_poly
		(pts
			(xy 71.319644 -82.48777) (xy 71.341996 -82.449162) (xy 70.996556 -82.249772) (xy 70.974458 -82.28838)
			(xy 70.96633 -82.48015) (xy 71.157592 -82.59064)
		)
		(stroke
			(width 0)
			(type solid)
		)
		(fill yes)
		(layer "In4.Cu")
		(net "M_L_DQ<5>")
	)
	(gr_poly
		(pts
			(xy 71.338186 -100.056442) (xy 71.315834 -100.018088) (xy 71.153782 -99.915218) (xy 70.96252 -100.025708)
			(xy 70.970648 -100.217478) (xy 70.992746 -100.256086)
		)
		(stroke
			(width 0)
			(type solid)
		)
		(fill yes)
		(layer "In4.Cu")
		(net "M_L_DQ<16>")
	)
	(gr_poly
		(pts
			(xy 71.33971 -101.04628) (xy 71.317358 -101.007926) (xy 71.155306 -100.905056) (xy 70.964044 -101.015546)
			(xy 70.972172 -101.207316) (xy 70.99427 -101.24567)
		)
		(stroke
			(width 0)
			(type solid)
		)
		(fill yes)
		(layer "In4.Cu")
		(net "M_L_DQS_DP<11>")
	)
	(gr_poly
		(pts
			(xy 71.33971 -69.34708) (xy 71.317358 -69.308726) (xy 71.155306 -69.205856) (xy 70.964044 -69.316346)
			(xy 70.972172 -69.508116) (xy 70.99427 -69.54647)
		)
		(stroke
			(width 0)
			(type solid)
		)
		(fill yes)
		(layer "In4.Cu")
		(net "M_H_DQ<5>")
	)
	(gr_poly
		(pts
			(xy 71.341488 -61.421264) (xy 71.319136 -61.38291) (xy 71.157084 -61.28004) (xy 70.965822 -61.39053)
			(xy 70.97395 -61.5823) (xy 70.996048 -61.620908)
		)
		(stroke
			(width 0)
			(type solid)
		)
		(fill yes)
		(layer "In4.Cu")
		(net "M_H_DQS_DN<1>")
	)
	(gr_poly
		(pts
			(xy 71.347076 -66.370962) (xy 71.324724 -66.332608) (xy 71.162672 -66.229738) (xy 70.97141 -66.340228)
			(xy 70.979538 -66.531998) (xy 71.001636 -66.570606)
		)
		(stroke
			(width 0)
			(type solid)
		)
		(fill yes)
		(layer "In4.Cu")
		(net "M_H_DQS_DN<0>")
	)
	(gr_poly
		(pts
			(xy 71.417434 -93.34373) (xy 71.417434 -93.12275) (xy 71.247254 -93.03385) (xy 71.202804 -93.03385)
			(xy 71.202804 -93.43263) (xy 71.247254 -93.43263)
		)
		(stroke
			(width 0)
			(type solid)
		)
		(fill yes)
		(layer "In4.Cu")
		(net "M_L_DQ<11>")
	)
	(gr_poly
		(pts
			(xy 71.417434 -59.65698) (xy 71.417434 -59.436) (xy 71.247254 -59.3471) (xy 71.202804 -59.3471) (xy 71.202804 -59.74588)
			(xy 71.247254 -59.74588)
		)
		(stroke
			(width 0)
			(type solid)
		)
		(fill yes)
		(layer "In4.Cu")
		(net "M_H_DQ<11>")
	)
	(gr_poly
		(pts
			(xy 71.417434 -58.678826) (xy 71.417434 -58.457846) (xy 71.247254 -58.368946) (xy 71.202804 -58.368946)
			(xy 71.202804 -58.767726) (xy 71.247254 -58.767726)
		)
		(stroke
			(width 0)
			(type solid)
		)
		(fill yes)
		(layer "In4.Cu")
		(net "M_H_DQ<11>")
	)
	(gr_poly
		(pts
			(xy 71.417434 -57.68213) (xy 71.417434 -57.46115) (xy 71.247254 -57.37225) (xy 71.202804 -57.37225)
			(xy 71.202804 -57.77103) (xy 71.247254 -57.77103)
		)
		(stroke
			(width 0)
			(type solid)
		)
		(fill yes)
		(layer "In4.Cu")
		(net "M_H_DQ<11>")
	)
	(gr_poly
		(pts
			(xy 71.417434 -56.68518) (xy 71.417434 -56.4642) (xy 71.247254 -56.3753) (xy 71.202804 -56.3753)
			(xy 71.202804 -56.77408) (xy 71.247254 -56.77408)
		)
		(stroke
			(width 0)
			(type solid)
		)
		(fill yes)
		(layer "In4.Cu")
		(net "M_H_DQ<11>")
	)
	(gr_poly
		(pts
			(xy 71.417434 -55.69458) (xy 71.417434 -55.4736) (xy 71.247254 -55.3847) (xy 71.202804 -55.3847)
			(xy 71.202804 -55.78348) (xy 71.247254 -55.78348)
		)
		(stroke
			(width 0)
			(type solid)
		)
		(fill yes)
		(layer "In4.Cu")
		(net "M_H_DQ<11>")
	)
	(gr_poly
		(pts
			(xy 71.429118 -92.383356) (xy 71.521828 -92.182696) (xy 71.404734 -92.030804) (xy 71.364348 -92.012008)
			(xy 71.196962 -92.373958) (xy 71.237348 -92.392754)
		)
		(stroke
			(width 0)
			(type solid)
		)
		(fill yes)
		(layer "In4.Cu")
		(net "M_L_DQ<11>")
	)
	(gr_poly
		(pts
			(xy 71.494904 -102.2731) (xy 71.463408 -102.241858) (xy 71.264018 -102.168198) (xy 71.102474 -102.329742)
			(xy 71.176134 -102.529132) (xy 71.207376 -102.560628)
		)
		(stroke
			(width 0)
			(type solid)
		)
		(fill yes)
		(layer "In4.Cu")
		(net "M_L_DQS_DN<2>")
	)
	(gr_poly
		(pts
			(xy 71.73468 -102.638606) (xy 71.66102 -102.43947) (xy 71.629524 -102.407974) (xy 71.34225 -102.695248)
			(xy 71.373746 -102.726744) (xy 71.572882 -102.800404)
		)
		(stroke
			(width 0)
			(type solid)
		)
		(fill yes)
		(layer "In4.Cu")
		(net "M_L_DQS_DP<2>")
	)
	(gr_poly
		(pts
			(xy 71.737728 -98.97745) (xy 71.693278 -98.97745) (xy 71.523098 -99.06635) (xy 71.523098 -99.28733)
			(xy 71.693278 -99.37623) (xy 71.737728 -99.37623)
		)
		(stroke
			(width 0)
			(type solid)
		)
		(fill yes)
		(layer "In4.Cu")
		(net "M_L_DQ<16>")
	)
	(gr_poly
		(pts
			(xy 71.739252 -52.413662) (xy 71.694802 -52.413662) (xy 71.524622 -52.502562) (xy 71.524622 -52.723542)
			(xy 71.694802 -52.812442) (xy 71.739252 -52.812442)
		)
		(stroke
			(width 0)
			(type solid)
		)
		(fill yes)
		(layer "In4.Cu")
		(net "M_H_DQ<21>")
	)
	(gr_poly
		(pts
			(xy 71.767954 -68.283836) (xy 71.723504 -68.280026) (xy 71.546466 -68.353686) (xy 71.527162 -68.573904)
			(xy 71.68896 -68.677282) (xy 71.733156 -68.681092)
		)
		(stroke
			(width 0)
			(type solid)
		)
		(fill yes)
		(layer "In4.Cu")
		(net "M_H_DQ<5>")
	)
	(gr_poly
		(pts
			(xy 71.845678 -88.524842) (xy 71.948548 -88.36279) (xy 71.838312 -88.171528) (xy 71.646542 -88.179656)
			(xy 71.607934 -88.201754) (xy 71.807324 -88.54694)
		)
		(stroke
			(width 0)
			(type solid)
		)
		(fill yes)
		(layer "In4.Cu")
		(net "M_L_DQ<8>")
	)
	(gr_poly
		(pts
			(xy 71.853552 -48.150272) (xy 71.885048 -48.11903) (xy 71.59752 -47.831502) (xy 71.566278 -47.862998)
			(xy 71.492618 -48.062388) (xy 71.654162 -48.223932)
		)
		(stroke
			(width 0)
			(type solid)
		)
		(fill yes)
		(layer "In4.Cu")
		(net "M_H_DQ<22>")
	)
	(gr_poly
		(pts
			(xy 71.8693 -64.499236) (xy 71.847964 -64.308482) (xy 71.823072 -64.271652) (xy 71.492364 -64.494664)
			(xy 71.517256 -64.531494) (xy 71.686166 -64.62268)
		)
		(stroke
			(width 0)
			(type solid)
		)
		(fill yes)
		(layer "In4.Cu")
		(net "M_H_DQ<12>")
	)
	(gr_poly
		(pts
			(xy 71.870062 -85.521038) (xy 71.87819 -85.329268) (xy 71.686928 -85.218778) (xy 71.524876 -85.321648)
			(xy 71.502524 -85.360002) (xy 71.847964 -85.559646)
		)
		(stroke
			(width 0)
			(type solid)
		)
		(fill yes)
		(layer "In4.Cu")
		(net "M_L_DQ<6>")
	)
	(gr_poly
		(pts
			(xy 71.87184 -50.851054) (xy 71.879968 -50.659284) (xy 71.688706 -50.548794) (xy 71.526654 -50.651664)
			(xy 71.504302 -50.690018) (xy 71.849742 -50.889662)
		)
		(stroke
			(width 0)
			(type solid)
		)
		(fill yes)
		(layer "In4.Cu")
		(net "M_H_DQ<17>")
	)
	(gr_poly
		(pts
			(xy 71.902066 -99.864926) (xy 72.072246 -99.77628) (xy 72.072246 -99.5553) (xy 71.902066 -99.4664)
			(xy 71.85787 -99.466146) (xy 71.857616 -99.86518)
		)
		(stroke
			(width 0)
			(type solid)
		)
		(fill yes)
		(layer "In4.Cu")
		(net "M_L_DQ<16>")
	)
	(gr_poly
		(pts
			(xy 71.94169 -62.733682) (xy 71.939658 -62.541912) (xy 71.743062 -62.441582) (xy 71.586598 -62.55258)
			(xy 71.566278 -62.592458) (xy 71.921624 -62.77356)
		)
		(stroke
			(width 0)
			(type solid)
		)
		(fill yes)
		(layer "In4.Cu")
		(net "M_H_DQ<9>")
	)
	(gr_poly
		(pts
			(xy 71.966074 -82.384646) (xy 71.974202 -82.192876) (xy 71.78294 -82.082386) (xy 71.620888 -82.185256)
			(xy 71.598536 -82.22361) (xy 71.943976 -82.423254)
		)
		(stroke
			(width 0)
			(type solid)
		)
		(fill yes)
		(layer "In4.Cu")
		(net "M_L_DQ<4>")
	)
	(gr_poly
		(pts
			(xy 71.96836 -89.320116) (xy 71.976488 -89.128346) (xy 71.785226 -89.017856) (xy 71.623174 -89.120726)
			(xy 71.600822 -89.15908) (xy 71.946262 -89.35847)
		)
		(stroke
			(width 0)
			(type solid)
		)
		(fill yes)
		(layer "In4.Cu")
		(net "M_L_DQS_DP<10>")
	)
	(gr_poly
		(pts
			(xy 71.96836 -87.338916) (xy 71.976488 -87.147146) (xy 71.785226 -87.036656) (xy 71.623174 -87.139526)
			(xy 71.600822 -87.17788) (xy 71.946262 -87.37727)
		)
		(stroke
			(width 0)
			(type solid)
		)
		(fill yes)
		(layer "In4.Cu")
		(net "M_L_DQ<12>")
	)
	(gr_poly
		(pts
			(xy 71.96836 -84.367116) (xy 71.976488 -84.175346) (xy 71.785226 -84.064856) (xy 71.623174 -84.167726)
			(xy 71.600822 -84.20608) (xy 71.946262 -84.40547)
		)
		(stroke
			(width 0)
			(type solid)
		)
		(fill yes)
		(layer "In4.Cu")
		(net "M_L_DQS_DP<9>")
	)
	(gr_poly
		(pts
			(xy 71.96836 -83.376516) (xy 71.976488 -83.184746) (xy 71.785226 -83.074256) (xy 71.623174 -83.177126)
			(xy 71.600822 -83.21548) (xy 71.946262 -83.41487)
		)
		(stroke
			(width 0)
			(type solid)
		)
		(fill yes)
		(layer "In4.Cu")
		(net "M_L_DQ<0>")
	)
	(gr_poly
		(pts
			(xy 71.97471 -66.630042) (xy 71.966582 -66.438272) (xy 71.944484 -66.399664) (xy 71.599044 -66.599308)
			(xy 71.621396 -66.637662) (xy 71.783448 -66.740532)
		)
		(stroke
			(width 0)
			(type solid)
		)
		(fill yes)
		(layer "In4.Cu")
		(net "M_H_DQS_DP<0>")
	)
	(gr_poly
		(pts
			(xy 71.976488 -69.600826) (xy 71.96836 -69.409056) (xy 71.946262 -69.370448) (xy 71.600822 -69.570092)
			(xy 71.623174 -69.608446) (xy 71.785226 -69.711316)
		)
		(stroke
			(width 0)
			(type solid)
		)
		(fill yes)
		(layer "In4.Cu")
		(net "M_H_DQ<4>")
	)
	(gr_poly
		(pts
			(xy 71.978012 -101.299264) (xy 71.969884 -101.107494) (xy 71.947786 -101.068886) (xy 71.602346 -101.26853)
			(xy 71.624698 -101.306884) (xy 71.78675 -101.409754)
		)
		(stroke
			(width 0)
			(type solid)
		)
		(fill yes)
		(layer "In4.Cu")
		(net "M_L_DQS_DN<11>")
	)
	(gr_poly
		(pts
			(xy 71.978012 -63.656464) (xy 71.969884 -63.464694) (xy 71.947786 -63.426086) (xy 71.602346 -63.62573)
			(xy 71.624698 -63.664084) (xy 71.78675 -63.766954)
		)
		(stroke
			(width 0)
			(type solid)
		)
		(fill yes)
		(layer "In4.Cu")
		(net "M_H_DQ<13>")
	)
	(gr_poly
		(pts
			(xy 71.978012 -61.675264) (xy 71.969884 -61.483494) (xy 71.947786 -61.444886) (xy 71.602346 -61.64453)
			(xy 71.624698 -61.682884) (xy 71.78675 -61.785754)
		)
		(stroke
			(width 0)
			(type solid)
		)
		(fill yes)
		(layer "In4.Cu")
		(net "M_H_DQS_DP<1>")
	)
	(gr_poly
		(pts
			(xy 71.983092 -91.280996) (xy 71.978266 -91.237054) (xy 71.871332 -91.077542) (xy 71.651876 -91.101418)
			(xy 71.581772 -91.280234) (xy 71.586598 -91.32443)
		)
		(stroke
			(width 0)
			(type solid)
		)
		(fill yes)
		(layer "In4.Cu")
		(net "M_L_DQ<10>")
	)
	(gr_poly
		(pts
			(xy 71.9836 -49.879504) (xy 71.9836 -49.835054) (xy 71.5772 -49.835054) (xy 71.5772 -49.879504) (xy 71.6661 -50.072544)
			(xy 71.8947 -50.072544)
		)
		(stroke
			(width 0)
			(type solid)
		)
		(fill yes)
		(layer "In4.Cu")
		(net "M_H_DQS_DP<11>")
	)
	(gr_poly
		(pts
			(xy 71.9836 -49.600104) (xy 71.8947 -49.407064) (xy 71.6661 -49.407064) (xy 71.5772 -49.600104) (xy 71.5772 -49.644554)
			(xy 71.9836 -49.644554)
		)
		(stroke
			(width 0)
			(type solid)
		)
		(fill yes)
		(layer "In4.Cu")
		(net "M_H_DQS_DN<11>")
	)
	(gr_poly
		(pts
			(xy 71.990966 -49.06899) (xy 71.990966 -49.02454) (xy 71.584566 -49.02454) (xy 71.584566 -49.06899)
			(xy 71.673466 -49.26203) (xy 71.902066 -49.26203)
		)
		(stroke
			(width 0)
			(type solid)
		)
		(fill yes)
		(layer "In4.Cu")
		(net "M_H_DQS_DP<2>")
	)
	(gr_poly
		(pts
			(xy 71.990966 -48.78959) (xy 71.902066 -48.59655) (xy 71.673466 -48.59655) (xy 71.584566 -48.78959)
			(xy 71.584566 -48.83404) (xy 71.990966 -48.83404)
		)
		(stroke
			(width 0)
			(type solid)
		)
		(fill yes)
		(layer "In4.Cu")
		(net "M_H_DQS_DN<2>")
	)
	(gr_poly
		(pts
			(xy 72.175878 -89.916) (xy 72.19823 -89.877646) (xy 71.85279 -89.678002) (xy 71.830692 -89.71661)
			(xy 71.822564 -89.90838) (xy 72.013826 -90.01887)
		)
		(stroke
			(width 0)
			(type solid)
		)
		(fill yes)
		(layer "In4.Cu")
		(net "M_L_DQS_DN<10>")
	)
	(gr_poly
		(pts
			(xy 72.175878 -84.963) (xy 72.19823 -84.924646) (xy 71.85279 -84.725002) (xy 71.830692 -84.76361)
			(xy 71.822564 -84.95538) (xy 72.013826 -85.06587)
		)
		(stroke
			(width 0)
			(type solid)
		)
		(fill yes)
		(layer "In4.Cu")
		(net "M_L_DQS_DN<9>")
	)
	(gr_poly
		(pts
			(xy 72.19823 -60.927234) (xy 72.175878 -60.88888) (xy 72.013826 -60.78601) (xy 71.822564 -60.8965)
			(xy 71.830692 -61.08827) (xy 71.85279 -61.126624)
		)
		(stroke
			(width 0)
			(type solid)
		)
		(fill yes)
		(layer "In4.Cu")
		(net "M_H_DQS_DN<1>")
	)
	(gr_poly
		(pts
			(xy 72.200516 -100.54971) (xy 72.178164 -100.511356) (xy 72.016112 -100.408486) (xy 71.82485 -100.518976)
			(xy 71.832978 -100.710746) (xy 71.855076 -100.749354)
		)
		(stroke
			(width 0)
			(type solid)
		)
		(fill yes)
		(layer "In4.Cu")
		(net "M_L_DQS_DP<11>")
	)
	(gr_poly
		(pts
			(xy 72.209406 -101.54666) (xy 72.187054 -101.508052) (xy 72.025002 -101.405182) (xy 71.83374 -101.515672)
			(xy 71.841868 -101.707442) (xy 71.863966 -101.74605)
		)
		(stroke
			(width 0)
			(type solid)
		)
		(fill yes)
		(layer "In4.Cu")
		(net "M_L_DQS_DN<2>")
	)
	(gr_poly
		(pts
			(xy 72.37476 -102.653338) (xy 72.343264 -102.621842) (xy 72.144128 -102.548182) (xy 71.98233 -102.70998)
			(xy 72.05599 -102.909116) (xy 72.087486 -102.940612)
		)
		(stroke
			(width 0)
			(type solid)
		)
		(fill yes)
		(layer "In4.Cu")
		(net "M_L_DQ<22>")
	)
	(gr_poly
		(pts
			(xy 72.53605 -48.213264) (xy 72.53605 -48.168814) (xy 72.12965 -48.168814) (xy 72.12965 -48.213264)
			(xy 72.21855 -48.406304) (xy 72.44715 -48.406304)
		)
		(stroke
			(width 0)
			(type solid)
		)
		(fill yes)
		(layer "In4.Cu")
		(net "M_H_DQ<22>")
	)
	(gr_poly
		(pts
			(xy 72.53605 -47.933864) (xy 72.44715 -47.740824) (xy 72.21855 -47.740824) (xy 72.12965 -47.933864)
			(xy 72.12965 -47.978314) (xy 72.53605 -47.978314)
		)
		(stroke
			(width 0)
			(type solid)
		)
		(fill yes)
		(layer "In4.Cu")
		(net "M_H_DQ<23>")
	)
	(gr_poly
		(pts
			(xy 72.596248 -99.4664) (xy 72.551798 -99.4664) (xy 72.381618 -99.5553) (xy 72.381618 -99.77628)
			(xy 72.551798 -99.86518) (xy 72.596248 -99.86518)
		)
		(stroke
			(width 0)
			(type solid)
		)
		(fill yes)
		(layer "In4.Cu")
		(net "M_L_DQS_DP<11>")
	)
	(gr_poly
		(pts
			(xy 72.596248 -98.4758) (xy 72.551798 -98.4758) (xy 72.381618 -98.5647) (xy 72.381618 -98.78568)
			(xy 72.551798 -98.87458) (xy 72.596248 -98.87458)
		)
		(stroke
			(width 0)
			(type solid)
		)
		(fill yes)
		(layer "In4.Cu")
		(net "M_L_DQS_DP<11>")
	)
	(gr_poly
		(pts
			(xy 72.614282 -103.01859) (xy 72.540622 -102.8192) (xy 72.50938 -102.787704) (xy 72.221852 -103.075232)
			(xy 72.253348 -103.106474) (xy 72.452738 -103.180134)
		)
		(stroke
			(width 0)
			(type solid)
		)
		(fill yes)
		(layer "In4.Cu")
		(net "M_L_DQ<23>")
	)
	(gr_poly
		(pts
			(xy 72.65289 -50.016918) (xy 72.72655 -49.817782) (xy 72.564752 -49.655984) (xy 72.365616 -49.729644)
			(xy 72.33412 -49.76114) (xy 72.621394 -50.048414)
		)
		(stroke
			(width 0)
			(type solid)
		)
		(fill yes)
		(layer "In4.Cu")
		(net "M_H_DQS_DN<11>")
	)
	(gr_poly
		(pts
			(xy 72.73036 -88.989154) (xy 72.738488 -88.797384) (xy 72.547226 -88.686894) (xy 72.385174 -88.789764)
			(xy 72.362822 -88.828118) (xy 72.708262 -89.027762)
		)
		(stroke
			(width 0)
			(type solid)
		)
		(fill yes)
		(layer "In4.Cu")
		(net "M_L_DQ<8>")
	)
	(gr_poly
		(pts
			(xy 72.744076 -52.112926) (xy 72.712326 -51.923696) (xy 72.68591 -51.888136) (xy 72.367394 -52.128674)
			(xy 72.394572 -52.16398) (xy 72.568054 -52.246022)
		)
		(stroke
			(width 0)
			(type solid)
		)
		(fill yes)
		(layer "In4.Cu")
		(net "M_H_DQ<17>")
	)
	(gr_poly
		(pts
			(xy 72.81037 -84.854288) (xy 72.818498 -84.662518) (xy 72.627236 -84.552028) (xy 72.465184 -84.655152)
			(xy 72.442832 -84.693252) (xy 72.788272 -84.892896)
		)
		(stroke
			(width 0)
			(type solid)
		)
		(fill yes)
		(layer "In4.Cu")
		(net "M_L_DQS_DP<9>")
	)
	(gr_poly
		(pts
			(xy 72.813926 -89.813638) (xy 72.822054 -89.621868) (xy 72.630792 -89.511378) (xy 72.46874 -89.614502)
			(xy 72.446388 -89.652602) (xy 72.791828 -89.852246)
		)
		(stroke
			(width 0)
			(type solid)
		)
		(fill yes)
		(layer "In4.Cu")
		(net "M_L_DQS_DP<10>")
	)
	(gr_poly
		(pts
			(xy 72.827134 -100.809552) (xy 72.81926 -100.617782) (xy 72.797162 -100.579174) (xy 72.451722 -100.778818)
			(xy 72.474074 -100.816918) (xy 72.635872 -100.920042)
		)
		(stroke
			(width 0)
			(type solid)
		)
		(fill yes)
		(layer "In4.Cu")
		(net "M_L_DQS_DN<11>")
	)
	(gr_poly
		(pts
			(xy 72.828404 -87.835232) (xy 72.836532 -87.643462) (xy 72.64527 -87.532972) (xy 72.483218 -87.635842)
			(xy 72.460866 -87.67445) (xy 72.806306 -87.87384)
		)
		(stroke
			(width 0)
			(type solid)
		)
		(fill yes)
		(layer "In4.Cu")
		(net "M_L_DQ<12>")
	)
	(gr_poly
		(pts
			(xy 72.828404 -83.872832) (xy 72.836532 -83.681062) (xy 72.64527 -83.570572) (xy 72.483218 -83.673442)
			(xy 72.460866 -83.71205) (xy 72.806306 -83.91144)
		)
		(stroke
			(width 0)
			(type solid)
		)
		(fill yes)
		(layer "In4.Cu")
		(net "M_L_DQ<0>")
	)
	(gr_poly
		(pts
			(xy 72.828404 -82.882232) (xy 72.836532 -82.690462) (xy 72.64527 -82.579972) (xy 72.483218 -82.682842)
			(xy 72.460866 -82.72145) (xy 72.806306 -82.92084)
		)
		(stroke
			(width 0)
			(type solid)
		)
		(fill yes)
		(layer "In4.Cu")
		(net "M_L_DQ<4>")
	)
	(gr_poly
		(pts
			(xy 72.82942 -101.797358) (xy 72.821292 -101.605588) (xy 72.799194 -101.567234) (xy 72.453754 -101.76637)
			(xy 72.476106 -101.804978) (xy 72.638158 -101.907848)
		)
		(stroke
			(width 0)
			(type solid)
		)
		(fill yes)
		(layer "In4.Cu")
		(net "M_L_DQS_DP<2>")
	)
	(gr_poly
		(pts
			(xy 72.96404 -100.366322) (xy 73.13422 -100.277676) (xy 73.13422 -100.056696) (xy 72.964294 -99.967796)
			(xy 72.919844 -99.967542) (xy 72.919844 -100.366576)
		)
		(stroke
			(width 0)
			(type solid)
		)
		(fill yes)
		(layer "In4.Cu")
		(net "M_L_DQS_DN<11>")
	)
	(gr_poly
		(pts
			(xy 73.001632 -49.643284) (xy 73.033128 -49.611788) (xy 72.745854 -49.324514) (xy 72.714358 -49.35601)
			(xy 72.640698 -49.555146) (xy 72.802496 -49.716944)
		)
		(stroke
			(width 0)
			(type solid)
		)
		(fill yes)
		(layer "In4.Cu")
		(net "M_H_DQS_DP<2>")
	)
	(gr_poly
		(pts
			(xy 73.055988 -98.070416) (xy 73.030588 -98.03384) (xy 72.860154 -97.945448) (xy 72.679052 -98.072194)
			(xy 72.703944 -98.26244) (xy 72.729344 -98.298762)
		)
		(stroke
			(width 0)
			(type solid)
		)
		(fill yes)
		(layer "In4.Cu")
		(net "M_L_DQS_DP<11>")
	)
	(gr_poly
		(pts
			(xy 73.0758 -101.02977) (xy 73.0504 -100.993194) (xy 72.879966 -100.904802) (xy 72.698864 -101.031548)
			(xy 72.723756 -101.222048) (xy 72.749156 -101.25837)
		)
		(stroke
			(width 0)
			(type solid)
		)
		(fill yes)
		(layer "In4.Cu")
		(net "M_L_DQS_DN<2>")
	)
	(gr_poly
		(pts
			(xy 73.134474 -99.28733) (xy 73.134474 -99.06635) (xy 72.964294 -98.97745) (xy 72.919844 -98.97745)
			(xy 72.919844 -99.37623) (xy 72.964294 -99.37623)
		)
		(stroke
			(width 0)
			(type solid)
		)
		(fill yes)
		(layer "In4.Cu")
		(net "M_L_DQS_DN<11>")
	)
	(gr_poly
		(pts
			(xy 73.199244 -49.445672) (xy 73.272904 -49.246282) (xy 73.11136 -49.084738) (xy 72.91197 -49.158398)
			(xy 72.880474 -49.18964) (xy 73.168002 -49.477168)
		)
		(stroke
			(width 0)
			(type solid)
		)
		(fill yes)
		(layer "In4.Cu")
		(net "M_H_DQS_DN<2>")
	)
	(gr_poly
		(pts
			(xy 73.276968 -48.834548) (xy 73.308464 -48.803052) (xy 73.02119 -48.515778) (xy 72.989694 -48.547274)
			(xy 72.916034 -48.74641) (xy 73.077832 -48.908208)
		)
		(stroke
			(width 0)
			(type solid)
		)
		(fill yes)
		(layer "In4.Cu")
		(net "M_H_DQ<22>")
	)
	(gr_poly
		(pts
			(xy 73.283572 -47.751492) (xy 73.314814 -47.719996) (xy 73.02754 -47.432722) (xy 72.996044 -47.464218)
			(xy 72.922384 -47.663608) (xy 73.084182 -47.825152)
		)
		(stroke
			(width 0)
			(type solid)
		)
		(fill yes)
		(layer "In4.Cu")
		(net "M_H_DQ<18>")
	)
	(gr_poly
		(pts
			(xy 73.391014 -102.201726) (xy 73.302114 -102.008686) (xy 73.073514 -102.008686) (xy 72.984614 -102.201726)
			(xy 72.984614 -102.246176) (xy 73.391014 -102.246176)
		)
		(stroke
			(width 0)
			(type solid)
		)
		(fill yes)
		(layer "In4.Cu")
		(net "M_L_DQ<22>")
	)
	(gr_poly
		(pts
			(xy 73.454768 -52.425346) (xy 73.410318 -52.425346) (xy 73.240138 -52.514246) (xy 73.240138 -52.735226)
			(xy 73.410318 -52.824126) (xy 73.454768 -52.824126)
		)
		(stroke
			(width 0)
			(type solid)
		)
		(fill yes)
		(layer "In4.Cu")
		(net "M_H_DQS_DP<2>")
	)
	(gr_poly
		(pts
			(xy 73.454768 -51.42865) (xy 73.410318 -51.42865) (xy 73.240138 -51.51755) (xy 73.240138 -51.73853)
			(xy 73.410318 -51.82743) (xy 73.454768 -51.82743)
		)
		(stroke
			(width 0)
			(type solid)
		)
		(fill yes)
		(layer "In4.Cu")
		(net "M_H_DQS_DP<2>")
	)
	(gr_poly
		(pts
			(xy 73.47458 -48.636936) (xy 73.54824 -48.437546) (xy 73.386696 -48.276002) (xy 73.187306 -48.349662)
			(xy 73.15581 -48.380904) (xy 73.443338 -48.668432)
		)
		(stroke
			(width 0)
			(type solid)
		)
		(fill yes)
		(layer "In4.Cu")
		(net "M_H_DQ<23>")
	)
	(gr_poly
		(pts
			(xy 73.48093 -47.554134) (xy 73.55459 -47.354744) (xy 73.393046 -47.192946) (xy 73.193656 -47.266606)
			(xy 73.16216 -47.298102) (xy 73.449434 -47.585376)
		)
		(stroke
			(width 0)
			(type solid)
		)
		(fill yes)
		(layer "In4.Cu")
		(net "M_H_DQ<19>")
	)
	(gr_poly
		(pts
			(xy 73.518014 -102.480364) (xy 73.518014 -102.435914) (xy 73.111614 -102.435914) (xy 73.111614 -102.480364)
			(xy 73.200514 -102.673404) (xy 73.429114 -102.673404)
		)
		(stroke
			(width 0)
			(type solid)
		)
		(fill yes)
		(layer "In4.Cu")
		(net "M_L_DQ<23>")
	)
	(gr_poly
		(pts
			(xy 73.645522 -98.97237) (xy 73.601072 -98.97237) (xy 73.430892 -99.06127) (xy 73.430892 -99.28225)
			(xy 73.601072 -99.37115) (xy 73.645522 -99.37115)
		)
		(stroke
			(width 0)
			(type solid)
		)
		(fill yes)
		(layer "In4.Cu")
		(net "M_L_DQ<22>")
	)
	(gr_poly
		(pts
			(xy 73.774808 -100.87483) (xy 73.671938 -100.712524) (xy 73.63333 -100.690426) (xy 73.43394 -101.035866)
			(xy 73.472548 -101.057964) (xy 73.664318 -101.066092)
		)
		(stroke
			(width 0)
			(type solid)
		)
		(fill yes)
		(layer "In4.Cu")
		(net "M_L_DQS_DP<2>")
	)
	(gr_poly
		(pts
			(xy 73.9775 -49.53508) (xy 74.008996 -49.503584) (xy 73.721722 -49.21631) (xy 73.690226 -49.247806)
			(xy 73.616566 -49.446942) (xy 73.778364 -49.60874)
		)
		(stroke
			(width 0)
			(type solid)
		)
		(fill yes)
		(layer "In4.Cu")
		(net "M_H_DQ<22>")
	)
	(gr_poly
		(pts
			(xy 73.98385 -48.452024) (xy 74.015346 -48.420528) (xy 73.728072 -48.133254) (xy 73.696576 -48.16475)
			(xy 73.622916 -48.363886) (xy 73.784714 -48.525684)
		)
		(stroke
			(width 0)
			(type solid)
		)
		(fill yes)
		(layer "In4.Cu")
		(net "M_H_DQ<18>")
	)
	(gr_poly
		(pts
			(xy 73.992994 -99.77628) (xy 73.992994 -99.5553) (xy 73.822814 -99.4664) (xy 73.778364 -99.4664)
			(xy 73.778364 -99.86518) (xy 73.822814 -99.86518)
		)
		(stroke
			(width 0)
			(type solid)
		)
		(fill yes)
		(layer "In4.Cu")
		(net "M_L_DQ<22>")
	)
	(gr_poly
		(pts
			(xy 73.992994 -53.217826) (xy 73.992994 -52.996846) (xy 73.822814 -52.907946) (xy 73.778364 -52.907946)
			(xy 73.778364 -53.306726) (xy 73.822814 -53.306726)
		)
		(stroke
			(width 0)
			(type solid)
		)
		(fill yes)
		(layer "In4.Cu")
		(net "M_H_DQS_DN<2>")
	)
	(gr_poly
		(pts
			(xy 73.992994 -52.22748) (xy 73.992994 -52.0065) (xy 73.822814 -51.9176) (xy 73.778364 -51.9176)
			(xy 73.778364 -52.31638) (xy 73.822814 -52.31638)
		)
		(stroke
			(width 0)
			(type solid)
		)
		(fill yes)
		(layer "In4.Cu")
		(net "M_H_DQS_DN<2>")
	)
	(gr_poly
		(pts
			(xy 73.992994 -51.249326) (xy 73.992994 -51.028346) (xy 73.822814 -50.939446) (xy 73.778364 -50.939446)
			(xy 73.778364 -51.338226) (xy 73.822814 -51.338226)
		)
		(stroke
			(width 0)
			(type solid)
		)
		(fill yes)
		(layer "In4.Cu")
		(net "M_H_DQS_DN<2>")
	)
	(gr_poly
		(pts
			(xy 74.150982 -101.636068) (xy 74.119486 -101.604572) (xy 73.92035 -101.530912) (xy 73.758552 -101.69271)
			(xy 73.832212 -101.891846) (xy 73.863708 -101.923342)
		)
		(stroke
			(width 0)
			(type solid)
		)
		(fill yes)
		(layer "In4.Cu")
		(net "M_L_DQ<22>")
	)
	(gr_poly
		(pts
			(xy 74.175112 -49.337468) (xy 74.248772 -49.138078) (xy 74.087228 -48.976534) (xy 73.887838 -49.050194)
			(xy 73.856342 -49.081436) (xy 74.14387 -49.368964)
		)
		(stroke
			(width 0)
			(type solid)
		)
		(fill yes)
		(layer "In4.Cu")
		(net "M_H_DQ<23>")
	)
	(gr_poly
		(pts
			(xy 74.181462 -48.254412) (xy 74.255122 -48.055276) (xy 74.093324 -47.893478) (xy 73.894188 -47.967138)
			(xy 73.862692 -47.998634) (xy 74.149966 -48.285908)
		)
		(stroke
			(width 0)
			(type solid)
		)
		(fill yes)
		(layer "In4.Cu")
		(net "M_H_DQ<19>")
	)
	(gr_poly
		(pts
			(xy 74.313288 -99.46386) (xy 74.268838 -99.464114) (xy 74.098912 -99.553014) (xy 74.098912 -99.77374)
			(xy 74.269092 -99.86264) (xy 74.313542 -99.862894)
		)
		(stroke
			(width 0)
			(type solid)
		)
		(fill yes)
		(layer "In4.Cu")
		(net "M_L_DQ<18>")
	)
	(gr_poly
		(pts
			(xy 74.313288 -50.939446) (xy 74.268838 -50.939446) (xy 74.098658 -51.028346) (xy 74.098658 -51.249326)
			(xy 74.268838 -51.338226) (xy 74.313288 -51.338226)
		)
		(stroke
			(width 0)
			(type solid)
		)
		(fill yes)
		(layer "In4.Cu")
		(net "M_H_DQ<22>")
	)
	(gr_poly
		(pts
			(xy 74.390504 -102.00132) (xy 74.316844 -101.80193) (xy 74.285602 -101.770434) (xy 73.998074 -102.057962)
			(xy 74.02957 -102.089204) (xy 74.22896 -102.162864)
		)
		(stroke
			(width 0)
			(type solid)
		)
		(fill yes)
		(layer "In4.Cu")
		(net "M_L_DQ<23>")
	)
	(gr_poly
		(pts
			(xy 74.632058 -52.834794) (xy 74.670412 -52.617116) (xy 74.518266 -52.500022) (xy 74.474324 -52.492402)
			(xy 74.405236 -52.885086) (xy 74.448924 -52.892706)
		)
		(stroke
			(width 0)
			(type solid)
		)
		(fill yes)
		(layer "In4.Cu")
		(net "M_H_DQ<23>")
	)
	(gr_poly
		(pts
			(xy 74.684382 -49.152556) (xy 74.715878 -49.12106) (xy 74.428604 -48.833786) (xy 74.397108 -48.865028)
			(xy 74.323448 -49.064418) (xy 74.484992 -49.226216)
		)
		(stroke
			(width 0)
			(type solid)
		)
		(fill yes)
		(layer "In4.Cu")
		(net "M_H_DQ<18>")
	)
	(gr_poly
		(pts
			(xy 74.751692 -100.317554) (xy 74.774044 -100.2792) (xy 74.42835 -100.07981) (xy 74.406506 -100.118418)
			(xy 74.398378 -100.310188) (xy 74.58964 -100.420424)
		)
		(stroke
			(width 0)
			(type solid)
		)
		(fill yes)
		(layer "In4.Cu")
		(net "M_L_DQ<18>")
	)
	(gr_poly
		(pts
			(xy 74.851514 -101.26218) (xy 74.851514 -101.0412) (xy 74.681334 -100.9523) (xy 74.636884 -100.9523)
			(xy 74.636884 -101.35108) (xy 74.681334 -101.35108)
		)
		(stroke
			(width 0)
			(type solid)
		)
		(fill yes)
		(layer "In4.Cu")
		(net "M_L_DQ<23>")
	)
	(gr_poly
		(pts
			(xy 74.851514 -51.73853) (xy 74.851514 -51.51755) (xy 74.681334 -51.42865) (xy 74.636884 -51.42865)
			(xy 74.636884 -51.82743) (xy 74.681334 -51.82743)
		)
		(stroke
			(width 0)
			(type solid)
		)
		(fill yes)
		(layer "In4.Cu")
		(net "M_H_DQ<23>")
	)
	(gr_poly
		(pts
			(xy 74.851514 -50.74158) (xy 74.851514 -50.5206) (xy 74.681334 -50.4317) (xy 74.636884 -50.4317)
			(xy 74.636884 -50.83048) (xy 74.681334 -50.83048)
		)
		(stroke
			(width 0)
			(type solid)
		)
		(fill yes)
		(layer "In4.Cu")
		(net "M_H_DQ<23>")
	)
	(gr_poly
		(pts
			(xy 74.881994 -48.954944) (xy 74.955654 -48.755554) (xy 74.793856 -48.59401) (xy 74.594466 -48.66767)
			(xy 74.563224 -48.699166) (xy 74.850498 -48.98644)
		)
		(stroke
			(width 0)
			(type solid)
		)
		(fill yes)
		(layer "In4.Cu")
		(net "M_H_DQ<19>")
	)
	(gr_poly
		(pts
			(xy 75.171808 -100.9523) (xy 75.127358 -100.9523) (xy 74.957178 -101.0412) (xy 74.957178 -101.26218)
			(xy 75.127358 -101.35108) (xy 75.171808 -101.35108)
		)
		(stroke
			(width 0)
			(type solid)
		)
		(fill yes)
		(layer "In4.Cu")
		(net "M_L_DQ<18>")
	)
	(gr_poly
		(pts
			(xy 75.171808 -51.42865) (xy 75.127358 -51.42865) (xy 74.957178 -51.51755) (xy 74.957178 -51.73853)
			(xy 75.127358 -51.82743) (xy 75.171808 -51.82743)
		)
		(stroke
			(width 0)
			(type solid)
		)
		(fill yes)
		(layer "In4.Cu")
		(net "M_H_DQ<18>")
	)
	(gr_poly
		(pts
			(xy 75.171808 -50.4317) (xy 75.127358 -50.4317) (xy 74.957178 -50.5206) (xy 74.957178 -50.74158)
			(xy 75.127358 -50.83048) (xy 75.171808 -50.83048)
		)
		(stroke
			(width 0)
			(type solid)
		)
		(fill yes)
		(layer "In4.Cu")
		(net "M_H_DQ<18>")
	)
	(gr_poly
		(pts
			(xy 75.217782 -102.626668) (xy 75.186286 -102.595172) (xy 74.98715 -102.521512) (xy 74.825352 -102.68331)
			(xy 74.899012 -102.882446) (xy 74.930508 -102.913942)
		)
		(stroke
			(width 0)
			(type solid)
		)
		(fill yes)
		(layer "In4.Cu")
		(net "M_L_DQ<18>")
	)
	(gr_poly
		(pts
			(xy 75.353164 -100.185728) (xy 75.437746 -100.013262) (xy 75.306936 -99.835208) (xy 75.117198 -99.864164)
			(xy 75.08113 -99.89058) (xy 75.31735 -100.21189)
		)
		(stroke
			(width 0)
			(type solid)
		)
		(fill yes)
		(layer "In4.Cu")
		(net "M_L_DQ<19>")
	)
	(gr_poly
		(pts
			(xy 75.38339 -101.858064) (xy 75.338686 -101.858064) (xy 75.1459 -101.94671) (xy 75.1459 -102.175564)
			(xy 75.338686 -102.26421) (xy 75.38339 -102.26421)
		)
		(stroke
			(width 0)
			(type solid)
		)
		(fill yes)
		(layer "In4.Cu")
		(net "M_L_DQ<18>")
	)
	(gr_poly
		(pts
			(xy 75.415394 -52.744624) (xy 75.390502 -52.554378) (xy 75.365102 -52.518056) (xy 75.038458 -52.746402)
			(xy 75.064112 -52.782978) (xy 75.234292 -52.87137)
		)
		(stroke
			(width 0)
			(type solid)
		)
		(fill yes)
		(layer "In4.Cu")
		(net "M_H_DQ<19>")
	)
	(gr_poly
		(pts
			(xy 75.457304 -102.99192) (xy 75.383644 -102.79253) (xy 75.352402 -102.761034) (xy 75.064874 -103.048562)
			(xy 75.09637 -103.079804) (xy 75.29576 -103.153464)
		)
		(stroke
			(width 0)
			(type solid)
		)
		(fill yes)
		(layer "In4.Cu")
		(net "M_L_DQ<19>")
	)
	(gr_poly
		(pts
			(xy 75.617832 -102.26421) (xy 75.810872 -102.17531) (xy 75.810872 -101.946964) (xy 75.617832 -101.858064)
			(xy 75.573382 -101.85781) (xy 75.573382 -102.264464)
		)
		(stroke
			(width 0)
			(type solid)
		)
		(fill yes)
		(layer "In4.Cu")
		(net "M_L_DQ<19>")
	)
	(gr_poly
		(pts
			(xy 75.710034 -100.772976) (xy 75.710034 -100.551996) (xy 75.539854 -100.463096) (xy 75.495404 -100.463096)
			(xy 75.495404 -100.861876) (xy 75.539854 -100.861876)
		)
		(stroke
			(width 0)
			(type solid)
		)
		(fill yes)
		(layer "In4.Cu")
		(net "M_L_DQ<19>")
	)
	(gr_poly
		(pts
			(xy 75.710034 -52.239926) (xy 75.710034 -52.018946) (xy 75.539854 -51.930046) (xy 75.495404 -51.930046)
			(xy 75.495404 -52.328826) (xy 75.539854 -52.328826)
		)
		(stroke
			(width 0)
			(type solid)
		)
		(fill yes)
		(layer "In4.Cu")
		(net "M_H_DQ<19>")
	)
	(gr_poly
		(pts
			(xy 75.710034 -51.249326) (xy 75.710034 -51.028346) (xy 75.539854 -50.939446) (xy 75.495404 -50.939446)
			(xy 75.495404 -51.338226) (xy 75.539854 -51.338226)
		)
		(stroke
			(width 0)
			(type solid)
		)
		(fill yes)
		(layer "In4.Cu")
		(net "M_H_DQ<19>")
	)
	(gr_poly
		(pts
			(xy 77.298804 -50.4317) (xy 77.254354 -50.4317) (xy 77.061314 -50.5206) (xy 77.061314 -50.7492) (xy 77.254354 -50.8381)
			(xy 77.298804 -50.8381)
		)
		(stroke
			(width 0)
			(type solid)
		)
		(fill yes)
		(layer "In4.Cu")
		(net "M_J_ECC<4>")
	)
	(gr_poly
		(pts
			(xy 77.558392 -100.88626) (xy 77.513942 -100.88626) (xy 77.320902 -100.97516) (xy 77.320902 -101.20376)
			(xy 77.513942 -101.29266) (xy 77.558392 -101.29266)
		)
		(stroke
			(width 0)
			(type solid)
		)
		(fill yes)
		(layer "In4.Cu")
		(net "M_M_ECC<4>")
	)
	(gr_poly
		(pts
			(xy 77.701394 -51.573684) (xy 77.73289 -51.542188) (xy 77.445616 -51.254914) (xy 77.41412 -51.286156)
			(xy 77.34046 -51.485546) (xy 77.502004 -51.647344)
		)
		(stroke
			(width 0)
			(type solid)
		)
		(fill yes)
		(layer "In4.Cu")
		(net "M_J_ECC<4>")
	)
	(gr_poly
		(pts
			(xy 77.727048 -50.7492) (xy 77.727048 -50.5206) (xy 77.534008 -50.4317) (xy 77.489558 -50.4317) (xy 77.489558 -50.8381)
			(xy 77.534008 -50.8381)
		)
		(stroke
			(width 0)
			(type solid)
		)
		(fill yes)
		(layer "In4.Cu")
		(net "M_J_ECC<5>")
	)
	(gr_poly
		(pts
			(xy 77.747114 -64.81064) (xy 77.702664 -64.81064) (xy 77.532484 -64.89954) (xy 77.532484 -65.12052)
			(xy 77.702664 -65.20942) (xy 77.747114 -65.20942)
		)
		(stroke
			(width 0)
			(type solid)
		)
		(fill yes)
		(layer "In4.Cu")
		(net "M_J_ECC<4>")
	)
	(gr_poly
		(pts
			(xy 77.747114 -63.82004) (xy 77.702664 -63.82004) (xy 77.532484 -63.90894) (xy 77.532484 -64.12992)
			(xy 77.702664 -64.21882) (xy 77.747114 -64.21882)
		)
		(stroke
			(width 0)
			(type solid)
		)
		(fill yes)
		(layer "In4.Cu")
		(net "M_J_ECC<4>")
	)
	(gr_poly
		(pts
			(xy 77.747114 -62.82944) (xy 77.702664 -62.82944) (xy 77.532484 -62.91834) (xy 77.532484 -63.13932)
			(xy 77.702664 -63.22822) (xy 77.747114 -63.22822)
		)
		(stroke
			(width 0)
			(type solid)
		)
		(fill yes)
		(layer "In4.Cu")
		(net "M_J_ECC<4>")
	)
	(gr_poly
		(pts
			(xy 77.747114 -61.83884) (xy 77.702664 -61.83884) (xy 77.532484 -61.92774) (xy 77.532484 -62.14872)
			(xy 77.702664 -62.23762) (xy 77.747114 -62.23762)
		)
		(stroke
			(width 0)
			(type solid)
		)
		(fill yes)
		(layer "In4.Cu")
		(net "M_J_ECC<4>")
	)
	(gr_poly
		(pts
			(xy 77.747114 -60.84824) (xy 77.702664 -60.84824) (xy 77.532484 -60.93714) (xy 77.532484 -61.15812)
			(xy 77.702664 -61.24702) (xy 77.747114 -61.24702)
		)
		(stroke
			(width 0)
			(type solid)
		)
		(fill yes)
		(layer "In4.Cu")
		(net "M_J_ECC<4>")
	)
	(gr_poly
		(pts
			(xy 77.747114 -59.85764) (xy 77.702664 -59.85764) (xy 77.532484 -59.94654) (xy 77.532484 -60.16752)
			(xy 77.702664 -60.25642) (xy 77.747114 -60.25642)
		)
		(stroke
			(width 0)
			(type solid)
		)
		(fill yes)
		(layer "In4.Cu")
		(net "M_J_ECC<4>")
	)
	(gr_poly
		(pts
			(xy 77.747114 -58.864246) (xy 77.702664 -58.864246) (xy 77.532484 -58.953146) (xy 77.532484 -59.174126)
			(xy 77.702664 -59.263026) (xy 77.747114 -59.263026)
		)
		(stroke
			(width 0)
			(type solid)
		)
		(fill yes)
		(layer "In4.Cu")
		(net "M_J_ECC<4>")
	)
	(gr_poly
		(pts
			(xy 77.747114 -57.8612) (xy 77.702664 -57.8612) (xy 77.532484 -57.9501) (xy 77.532484 -58.17108)
			(xy 77.702664 -58.25998) (xy 77.747114 -58.25998)
		)
		(stroke
			(width 0)
			(type solid)
		)
		(fill yes)
		(layer "In4.Cu")
		(net "M_J_ECC<4>")
	)
	(gr_poly
		(pts
			(xy 77.747114 -56.88584) (xy 77.702664 -56.88584) (xy 77.532484 -56.97474) (xy 77.532484 -57.19572)
			(xy 77.702664 -57.28462) (xy 77.747114 -57.28462)
		)
		(stroke
			(width 0)
			(type solid)
		)
		(fill yes)
		(layer "In4.Cu")
		(net "M_J_ECC<4>")
	)
	(gr_poly
		(pts
			(xy 77.747114 -55.89524) (xy 77.702664 -55.89524) (xy 77.532484 -55.98414) (xy 77.532484 -56.20512)
			(xy 77.702664 -56.29402) (xy 77.747114 -56.29402)
		)
		(stroke
			(width 0)
			(type solid)
		)
		(fill yes)
		(layer "In4.Cu")
		(net "M_J_ECC<4>")
	)
	(gr_poly
		(pts
			(xy 77.747114 -54.90464) (xy 77.702664 -54.90464) (xy 77.532484 -54.99354) (xy 77.532484 -55.21452)
			(xy 77.702664 -55.30342) (xy 77.747114 -55.30342)
		)
		(stroke
			(width 0)
			(type solid)
		)
		(fill yes)
		(layer "In4.Cu")
		(net "M_J_ECC<4>")
	)
	(gr_poly
		(pts
			(xy 77.747114 -53.91404) (xy 77.702664 -53.91404) (xy 77.532484 -54.00294) (xy 77.532484 -54.22392)
			(xy 77.702664 -54.31282) (xy 77.747114 -54.31282)
		)
		(stroke
			(width 0)
			(type solid)
		)
		(fill yes)
		(layer "In4.Cu")
		(net "M_J_ECC<4>")
	)
	(gr_poly
		(pts
			(xy 77.747368 -65.800986) (xy 77.702918 -65.800986) (xy 77.532738 -65.889886) (xy 77.532738 -66.110866)
			(xy 77.702918 -66.199766) (xy 77.747368 -66.199766)
		)
		(stroke
			(width 0)
			(type solid)
		)
		(fill yes)
		(layer "In4.Cu")
		(net "M_J_ECC<4>")
	)
	(gr_poly
		(pts
			(xy 77.879956 -52.937156) (xy 77.835506 -52.937156) (xy 77.642466 -53.026056) (xy 77.642466 -53.254656)
			(xy 77.835506 -53.343556) (xy 77.879956 -53.343556)
		)
		(stroke
			(width 0)
			(type solid)
		)
		(fill yes)
		(layer "In4.Cu")
		(net "M_J_ECC<4>")
	)
	(gr_poly
		(pts
			(xy 77.879956 -51.946556) (xy 77.835506 -51.946556) (xy 77.642466 -52.035456) (xy 77.642466 -52.264056)
			(xy 77.835506 -52.352956) (xy 77.879956 -52.352956)
		)
		(stroke
			(width 0)
			(type solid)
		)
		(fill yes)
		(layer "In4.Cu")
		(net "M_J_ECC<4>")
	)
	(gr_poly
		(pts
			(xy 77.90434 -51.380898) (xy 77.978 -51.181762) (xy 77.816202 -51.019964) (xy 77.617066 -51.093624)
			(xy 77.58557 -51.12512) (xy 77.872844 -51.412394)
		)
		(stroke
			(width 0)
			(type solid)
		)
		(fill yes)
		(layer "In4.Cu")
		(net "M_J_ECC<5>")
	)
	(gr_poly
		(pts
			(xy 77.985874 -101.20376) (xy 77.985874 -100.97516) (xy 77.792834 -100.88626) (xy 77.748384 -100.88626)
			(xy 77.748384 -101.29266) (xy 77.792834 -101.29266)
		)
		(stroke
			(width 0)
			(type solid)
		)
		(fill yes)
		(layer "In4.Cu")
		(net "M_M_ECC<5>")
	)
	(gr_poly
		(pts
			(xy 78.285594 -66.597276) (xy 78.285594 -66.376296) (xy 78.115414 -66.287396) (xy 78.070964 -66.287396)
			(xy 78.070964 -66.686176) (xy 78.115414 -66.686176)
		)
		(stroke
			(width 0)
			(type solid)
		)
		(fill yes)
		(layer "In4.Cu")
		(net "M_J_ECC<5>")
	)
	(gr_poly
		(pts
			(xy 78.285594 -65.597786) (xy 78.285594 -65.376806) (xy 78.115414 -65.287906) (xy 78.070964 -65.287906)
			(xy 78.070964 -65.686686) (xy 78.115414 -65.686686)
		)
		(stroke
			(width 0)
			(type solid)
		)
		(fill yes)
		(layer "In4.Cu")
		(net "M_J_ECC<5>")
	)
	(gr_poly
		(pts
			(xy 78.285594 -64.607186) (xy 78.285594 -64.386206) (xy 78.115414 -64.297306) (xy 78.070964 -64.297306)
			(xy 78.070964 -64.696086) (xy 78.115414 -64.696086)
		)
		(stroke
			(width 0)
			(type solid)
		)
		(fill yes)
		(layer "In4.Cu")
		(net "M_J_ECC<5>")
	)
	(gr_poly
		(pts
			(xy 78.285594 -63.616586) (xy 78.285594 -63.395606) (xy 78.115414 -63.306706) (xy 78.070964 -63.306706)
			(xy 78.070964 -63.705486) (xy 78.115414 -63.705486)
		)
		(stroke
			(width 0)
			(type solid)
		)
		(fill yes)
		(layer "In4.Cu")
		(net "M_J_ECC<5>")
	)
	(gr_poly
		(pts
			(xy 78.285594 -62.625986) (xy 78.285594 -62.405006) (xy 78.115414 -62.316106) (xy 78.070964 -62.316106)
			(xy 78.070964 -62.714886) (xy 78.115414 -62.714886)
		)
		(stroke
			(width 0)
			(type solid)
		)
		(fill yes)
		(layer "In4.Cu")
		(net "M_J_ECC<5>")
	)
	(gr_poly
		(pts
			(xy 78.285594 -61.635386) (xy 78.285594 -61.414406) (xy 78.115414 -61.325506) (xy 78.070964 -61.325506)
			(xy 78.070964 -61.724286) (xy 78.115414 -61.724286)
		)
		(stroke
			(width 0)
			(type solid)
		)
		(fill yes)
		(layer "In4.Cu")
		(net "M_J_ECC<5>")
	)
	(gr_poly
		(pts
			(xy 78.285594 -60.644786) (xy 78.285594 -60.423806) (xy 78.115414 -60.334906) (xy 78.070964 -60.334906)
			(xy 78.070964 -60.733686) (xy 78.115414 -60.733686)
		)
		(stroke
			(width 0)
			(type solid)
		)
		(fill yes)
		(layer "In4.Cu")
		(net "M_J_ECC<5>")
	)
	(gr_poly
		(pts
			(xy 78.285594 -59.654186) (xy 78.285594 -59.433206) (xy 78.115414 -59.344306) (xy 78.070964 -59.344306)
			(xy 78.070964 -59.743086) (xy 78.115414 -59.743086)
		)
		(stroke
			(width 0)
			(type solid)
		)
		(fill yes)
		(layer "In4.Cu")
		(net "M_J_ECC<5>")
	)
	(gr_poly
		(pts
			(xy 78.285594 -58.678826) (xy 78.285594 -58.457846) (xy 78.115414 -58.368946) (xy 78.070964 -58.368946)
			(xy 78.070964 -58.767726) (xy 78.115414 -58.767726)
		)
		(stroke
			(width 0)
			(type solid)
		)
		(fill yes)
		(layer "In4.Cu")
		(net "M_J_ECC<5>")
	)
	(gr_poly
		(pts
			(xy 78.285594 -57.67578) (xy 78.285594 -57.4548) (xy 78.115414 -57.3659) (xy 78.070964 -57.3659)
			(xy 78.070964 -57.76468) (xy 78.115414 -57.76468)
		)
		(stroke
			(width 0)
			(type solid)
		)
		(fill yes)
		(layer "In4.Cu")
		(net "M_J_ECC<5>")
	)
	(gr_poly
		(pts
			(xy 78.285594 -56.682386) (xy 78.285594 -56.461406) (xy 78.115414 -56.372506) (xy 78.070964 -56.372506)
			(xy 78.070964 -56.771286) (xy 78.115414 -56.771286)
		)
		(stroke
			(width 0)
			(type solid)
		)
		(fill yes)
		(layer "In4.Cu")
		(net "M_J_ECC<5>")
	)
	(gr_poly
		(pts
			(xy 78.285594 -55.691786) (xy 78.285594 -55.470806) (xy 78.115414 -55.381906) (xy 78.070964 -55.381906)
			(xy 78.070964 -55.780686) (xy 78.115414 -55.780686)
		)
		(stroke
			(width 0)
			(type solid)
		)
		(fill yes)
		(layer "In4.Cu")
		(net "M_J_ECC<5>")
	)
	(gr_poly
		(pts
			(xy 78.285594 -54.701186) (xy 78.285594 -54.480206) (xy 78.115414 -54.391306) (xy 78.070964 -54.391306)
			(xy 78.070964 -54.790086) (xy 78.115414 -54.790086)
		)
		(stroke
			(width 0)
			(type solid)
		)
		(fill yes)
		(layer "In4.Cu")
		(net "M_J_ECC<5>")
	)
	(gr_poly
		(pts
			(xy 78.3082 -53.254656) (xy 78.3082 -53.026056) (xy 78.11516 -52.937156) (xy 78.07071 -52.937156)
			(xy 78.07071 -53.343556) (xy 78.11516 -53.343556)
		)
		(stroke
			(width 0)
			(type solid)
		)
		(fill yes)
		(layer "In4.Cu")
		(net "M_J_ECC<5>")
	)
	(gr_poly
		(pts
			(xy 78.3082 -52.264056) (xy 78.3082 -52.035456) (xy 78.11516 -51.946556) (xy 78.07071 -51.946556)
			(xy 78.07071 -52.352956) (xy 78.11516 -52.352956)
		)
		(stroke
			(width 0)
			(type solid)
		)
		(fill yes)
		(layer "In4.Cu")
		(net "M_J_ECC<5>")
	)
	(gr_poly
		(pts
			(xy 78.469744 -99.182174) (xy 78.438248 -99.150932) (xy 78.238858 -99.077272) (xy 78.077314 -99.238816)
			(xy 78.150974 -99.438206) (xy 78.182216 -99.469702)
		)
		(stroke
			(width 0)
			(type solid)
		)
		(fill yes)
		(layer "In4.Cu")
		(net "M_M_ECC<4>")
	)
	(gr_poly
		(pts
			(xy 78.605634 -97.9805) (xy 78.561184 -97.9805) (xy 78.391004 -98.0694) (xy 78.391004 -98.29038)
			(xy 78.561184 -98.37928) (xy 78.605634 -98.37928)
		)
		(stroke
			(width 0)
			(type solid)
		)
		(fill yes)
		(layer "In4.Cu")
		(net "M_M_ECC<4>")
	)
	(gr_poly
		(pts
			(xy 78.605634 -96.9899) (xy 78.561184 -96.9899) (xy 78.391004 -97.0788) (xy 78.391004 -97.29978)
			(xy 78.561184 -97.38868) (xy 78.605634 -97.38868)
		)
		(stroke
			(width 0)
			(type solid)
		)
		(fill yes)
		(layer "In4.Cu")
		(net "M_M_ECC<4>")
	)
	(gr_poly
		(pts
			(xy 78.605634 -95.9993) (xy 78.561184 -95.9993) (xy 78.391004 -96.0882) (xy 78.391004 -96.30918)
			(xy 78.561184 -96.39808) (xy 78.605634 -96.39808)
		)
		(stroke
			(width 0)
			(type solid)
		)
		(fill yes)
		(layer "In4.Cu")
		(net "M_M_ECC<4>")
	)
	(gr_poly
		(pts
			(xy 78.605634 -95.0087) (xy 78.561184 -95.0087) (xy 78.391004 -95.0976) (xy 78.391004 -95.31858)
			(xy 78.561184 -95.40748) (xy 78.605634 -95.40748)
		)
		(stroke
			(width 0)
			(type solid)
		)
		(fill yes)
		(layer "In4.Cu")
		(net "M_M_ECC<4>")
	)
	(gr_poly
		(pts
			(xy 78.605634 -94.030546) (xy 78.561184 -94.030546) (xy 78.391004 -94.119446) (xy 78.391004 -94.340426)
			(xy 78.561184 -94.429326) (xy 78.605634 -94.429326)
		)
		(stroke
			(width 0)
			(type solid)
		)
		(fill yes)
		(layer "In4.Cu")
		(net "M_M_ECC<4>")
	)
	(gr_poly
		(pts
			(xy 78.605634 -93.03385) (xy 78.561184 -93.03385) (xy 78.391004 -93.12275) (xy 78.391004 -93.34373)
			(xy 78.561184 -93.43263) (xy 78.605634 -93.43263)
		)
		(stroke
			(width 0)
			(type solid)
		)
		(fill yes)
		(layer "In4.Cu")
		(net "M_M_ECC<4>")
	)
	(gr_poly
		(pts
			(xy 78.605634 -92.0369) (xy 78.561184 -92.0369) (xy 78.391004 -92.1258) (xy 78.391004 -92.34678)
			(xy 78.561184 -92.43568) (xy 78.605634 -92.43568)
		)
		(stroke
			(width 0)
			(type solid)
		)
		(fill yes)
		(layer "In4.Cu")
		(net "M_M_ECC<4>")
	)
	(gr_poly
		(pts
			(xy 78.605634 -91.0463) (xy 78.561184 -91.0463) (xy 78.391004 -91.1352) (xy 78.391004 -91.35618)
			(xy 78.561184 -91.44508) (xy 78.605634 -91.44508)
		)
		(stroke
			(width 0)
			(type solid)
		)
		(fill yes)
		(layer "In4.Cu")
		(net "M_M_ECC<4>")
	)
	(gr_poly
		(pts
			(xy 78.605634 -90.0557) (xy 78.561184 -90.0557) (xy 78.391004 -90.1446) (xy 78.391004 -90.36558)
			(xy 78.561184 -90.45448) (xy 78.605634 -90.45448)
		)
		(stroke
			(width 0)
			(type solid)
		)
		(fill yes)
		(layer "In4.Cu")
		(net "M_M_ECC<4>")
	)
	(gr_poly
		(pts
			(xy 78.605634 -89.0651) (xy 78.561184 -89.0651) (xy 78.391004 -89.154) (xy 78.391004 -89.37498) (xy 78.561184 -89.46388)
			(xy 78.605634 -89.46388)
		)
		(stroke
			(width 0)
			(type solid)
		)
		(fill yes)
		(layer "In4.Cu")
		(net "M_M_ECC<4>")
	)
	(gr_poly
		(pts
			(xy 78.605634 -88.0745) (xy 78.561184 -88.0745) (xy 78.391004 -88.1634) (xy 78.391004 -88.38438)
			(xy 78.561184 -88.47328) (xy 78.605634 -88.47328)
		)
		(stroke
			(width 0)
			(type solid)
		)
		(fill yes)
		(layer "In4.Cu")
		(net "M_M_ECC<4>")
	)
	(gr_poly
		(pts
			(xy 78.605634 -87.0839) (xy 78.561184 -87.0839) (xy 78.391004 -87.1728) (xy 78.391004 -87.39378)
			(xy 78.561184 -87.48268) (xy 78.605634 -87.48268)
		)
		(stroke
			(width 0)
			(type solid)
		)
		(fill yes)
		(layer "In4.Cu")
		(net "M_M_ECC<4>")
	)
	(gr_poly
		(pts
			(xy 78.605634 -86.0933) (xy 78.561184 -86.0933) (xy 78.391004 -86.1822) (xy 78.391004 -86.40318)
			(xy 78.561184 -86.49208) (xy 78.605634 -86.49208)
		)
		(stroke
			(width 0)
			(type solid)
		)
		(fill yes)
		(layer "In4.Cu")
		(net "M_M_ECC<4>")
	)
	(gr_poly
		(pts
			(xy 78.605634 -85.1027) (xy 78.561184 -85.1027) (xy 78.391004 -85.1916) (xy 78.391004 -85.41258)
			(xy 78.561184 -85.50148) (xy 78.605634 -85.50148)
		)
		(stroke
			(width 0)
			(type solid)
		)
		(fill yes)
		(layer "In4.Cu")
		(net "M_M_ECC<4>")
	)
	(gr_poly
		(pts
			(xy 78.605634 -84.1121) (xy 78.561184 -84.1121) (xy 78.391004 -84.201) (xy 78.391004 -84.42198) (xy 78.561184 -84.51088)
			(xy 78.605634 -84.51088)
		)
		(stroke
			(width 0)
			(type solid)
		)
		(fill yes)
		(layer "In4.Cu")
		(net "M_M_ECC<4>")
	)
	(gr_poly
		(pts
			(xy 78.605634 -66.287396) (xy 78.561184 -66.287396) (xy 78.391004 -66.376296) (xy 78.391004 -66.597276)
			(xy 78.561184 -66.686176) (xy 78.605634 -66.686176)
		)
		(stroke
			(width 0)
			(type solid)
		)
		(fill yes)
		(layer "In4.Cu")
		(net "M_J_ECC<0>")
	)
	(gr_poly
		(pts
			(xy 78.605634 -65.2907) (xy 78.561184 -65.2907) (xy 78.391004 -65.3796) (xy 78.391004 -65.60058)
			(xy 78.561184 -65.68948) (xy 78.605634 -65.68948)
		)
		(stroke
			(width 0)
			(type solid)
		)
		(fill yes)
		(layer "In4.Cu")
		(net "M_J_ECC<0>")
	)
	(gr_poly
		(pts
			(xy 78.605634 -64.3001) (xy 78.561184 -64.3001) (xy 78.391004 -64.389) (xy 78.391004 -64.60998) (xy 78.561184 -64.69888)
			(xy 78.605634 -64.69888)
		)
		(stroke
			(width 0)
			(type solid)
		)
		(fill yes)
		(layer "In4.Cu")
		(net "M_J_ECC<0>")
	)
	(gr_poly
		(pts
			(xy 78.605634 -63.3095) (xy 78.561184 -63.3095) (xy 78.391004 -63.3984) (xy 78.391004 -63.61938)
			(xy 78.561184 -63.70828) (xy 78.605634 -63.70828)
		)
		(stroke
			(width 0)
			(type solid)
		)
		(fill yes)
		(layer "In4.Cu")
		(net "M_J_ECC<0>")
	)
	(gr_poly
		(pts
			(xy 78.605634 -62.3189) (xy 78.561184 -62.3189) (xy 78.391004 -62.4078) (xy 78.391004 -62.62878)
			(xy 78.561184 -62.71768) (xy 78.605634 -62.71768)
		)
		(stroke
			(width 0)
			(type solid)
		)
		(fill yes)
		(layer "In4.Cu")
		(net "M_J_ECC<0>")
	)
	(gr_poly
		(pts
			(xy 78.605634 -61.3283) (xy 78.561184 -61.3283) (xy 78.391004 -61.4172) (xy 78.391004 -61.63818)
			(xy 78.561184 -61.72708) (xy 78.605634 -61.72708)
		)
		(stroke
			(width 0)
			(type solid)
		)
		(fill yes)
		(layer "In4.Cu")
		(net "M_J_ECC<0>")
	)
	(gr_poly
		(pts
			(xy 78.605634 -60.3377) (xy 78.561184 -60.3377) (xy 78.391004 -60.4266) (xy 78.391004 -60.64758)
			(xy 78.561184 -60.73648) (xy 78.605634 -60.73648)
		)
		(stroke
			(width 0)
			(type solid)
		)
		(fill yes)
		(layer "In4.Cu")
		(net "M_J_ECC<0>")
	)
	(gr_poly
		(pts
			(xy 78.605634 -59.3471) (xy 78.561184 -59.3471) (xy 78.391004 -59.436) (xy 78.391004 -59.65698) (xy 78.561184 -59.74588)
			(xy 78.605634 -59.74588)
		)
		(stroke
			(width 0)
			(type solid)
		)
		(fill yes)
		(layer "In4.Cu")
		(net "M_J_ECC<0>")
	)
	(gr_poly
		(pts
			(xy 78.605634 -58.368946) (xy 78.561184 -58.368946) (xy 78.391004 -58.457846) (xy 78.391004 -58.678826)
			(xy 78.561184 -58.767726) (xy 78.605634 -58.767726)
		)
		(stroke
			(width 0)
			(type solid)
		)
		(fill yes)
		(layer "In4.Cu")
		(net "M_J_ECC<0>")
	)
	(gr_poly
		(pts
			(xy 78.605634 -57.37225) (xy 78.561184 -57.37225) (xy 78.391004 -57.46115) (xy 78.391004 -57.68213)
			(xy 78.561184 -57.77103) (xy 78.605634 -57.77103)
		)
		(stroke
			(width 0)
			(type solid)
		)
		(fill yes)
		(layer "In4.Cu")
		(net "M_J_ECC<0>")
	)
	(gr_poly
		(pts
			(xy 78.605634 -56.3753) (xy 78.561184 -56.3753) (xy 78.391004 -56.4642) (xy 78.391004 -56.68518)
			(xy 78.561184 -56.77408) (xy 78.605634 -56.77408)
		)
		(stroke
			(width 0)
			(type solid)
		)
		(fill yes)
		(layer "In4.Cu")
		(net "M_J_ECC<0>")
	)
	(gr_poly
		(pts
			(xy 78.605634 -55.3847) (xy 78.561184 -55.3847) (xy 78.391004 -55.4736) (xy 78.391004 -55.69458)
			(xy 78.561184 -55.78348) (xy 78.605634 -55.78348)
		)
		(stroke
			(width 0)
			(type solid)
		)
		(fill yes)
		(layer "In4.Cu")
		(net "M_J_ECC<0>")
	)
	(gr_poly
		(pts
			(xy 78.605634 -54.3941) (xy 78.561184 -54.3941) (xy 78.391004 -54.483) (xy 78.391004 -54.70398) (xy 78.561184 -54.79288)
			(xy 78.605634 -54.79288)
		)
		(stroke
			(width 0)
			(type solid)
		)
		(fill yes)
		(layer "In4.Cu")
		(net "M_J_ECC<0>")
	)
	(gr_poly
		(pts
			(xy 78.605634 -53.4035) (xy 78.561184 -53.4035) (xy 78.391004 -53.4924) (xy 78.391004 -53.71338)
			(xy 78.561184 -53.80228) (xy 78.605634 -53.80228)
		)
		(stroke
			(width 0)
			(type solid)
		)
		(fill yes)
		(layer "In4.Cu")
		(net "M_J_ECC<0>")
	)
	(gr_poly
		(pts
			(xy 78.69682 -52.767738) (xy 78.65237 -52.767738) (xy 78.45933 -52.856638) (xy 78.45933 -53.085238)
			(xy 78.65237 -53.174138) (xy 78.69682 -53.174138)
		)
		(stroke
			(width 0)
			(type solid)
		)
		(fill yes)
		(layer "In4.Cu")
		(net "M_J_ECC<0>")
	)
	(gr_poly
		(pts
			(xy 78.69682 -51.777138) (xy 78.65237 -51.777138) (xy 78.45933 -51.866038) (xy 78.45933 -52.094638)
			(xy 78.65237 -52.183538) (xy 78.69682 -52.183538)
		)
		(stroke
			(width 0)
			(type solid)
		)
		(fill yes)
		(layer "In4.Cu")
		(net "M_J_ECC<0>")
	)
	(gr_poly
		(pts
			(xy 78.709012 -99.547426) (xy 78.635352 -99.348036) (xy 78.60411 -99.31654) (xy 78.316582 -99.604068)
			(xy 78.348078 -99.63531) (xy 78.547468 -99.70897)
		)
		(stroke
			(width 0)
			(type solid)
		)
		(fill yes)
		(layer "In4.Cu")
		(net "M_M_ECC<5>")
	)
	(gr_poly
		(pts
			(xy 79.04226 -85.210904) (xy 79.130144 -85.008212) (xy 79.009494 -84.85886) (xy 78.9686 -84.841334)
			(xy 78.810104 -85.207094) (xy 78.850744 -85.224874)
		)
		(stroke
			(width 0)
			(type solid)
		)
		(fill yes)
		(layer "In4.Cu")
		(net "M_M_ECC<5>")
	)
	(gr_poly
		(pts
			(xy 79.12481 -53.085238) (xy 79.12481 -52.856638) (xy 78.93177 -52.767738) (xy 78.88732 -52.767738)
			(xy 78.88732 -53.174138) (xy 78.93177 -53.174138)
		)
		(stroke
			(width 0)
			(type solid)
		)
		(fill yes)
		(layer "In4.Cu")
		(net "M_J_ECC<1>")
	)
	(gr_poly
		(pts
			(xy 79.12481 -52.094638) (xy 79.12481 -51.866038) (xy 78.93177 -51.777138) (xy 78.88732 -51.777138)
			(xy 78.88732 -52.183538) (xy 78.93177 -52.183538)
		)
		(stroke
			(width 0)
			(type solid)
		)
		(fill yes)
		(layer "In4.Cu")
		(net "M_J_ECC<1>")
	)
	(gr_poly
		(pts
			(xy 79.143606 -66.108326) (xy 79.143606 -65.887346) (xy 78.973426 -65.798446) (xy 78.928976 -65.798446)
			(xy 78.928976 -66.197226) (xy 78.973426 -66.197226)
		)
		(stroke
			(width 0)
			(type solid)
		)
		(fill yes)
		(layer "In4.Cu")
		(net "M_J_ECC<1>")
	)
	(gr_poly
		(pts
			(xy 79.14386 -97.807526) (xy 79.14386 -97.586546) (xy 78.97368 -97.497646) (xy 78.92923 -97.497646)
			(xy 78.92923 -97.896426) (xy 78.97368 -97.896426)
		)
		(stroke
			(width 0)
			(type solid)
		)
		(fill yes)
		(layer "In4.Cu")
		(net "M_M_ECC<5>")
	)
	(gr_poly
		(pts
			(xy 79.14386 -96.816926) (xy 79.14386 -96.595946) (xy 78.97368 -96.507046) (xy 78.92923 -96.507046)
			(xy 78.92923 -96.905826) (xy 78.97368 -96.905826)
		)
		(stroke
			(width 0)
			(type solid)
		)
		(fill yes)
		(layer "In4.Cu")
		(net "M_M_ECC<5>")
	)
	(gr_poly
		(pts
			(xy 79.14386 -95.826326) (xy 79.14386 -95.605346) (xy 78.97368 -95.516446) (xy 78.92923 -95.516446)
			(xy 78.92923 -95.915226) (xy 78.97368 -95.915226)
		)
		(stroke
			(width 0)
			(type solid)
		)
		(fill yes)
		(layer "In4.Cu")
		(net "M_M_ECC<5>")
	)
	(gr_poly
		(pts
			(xy 79.14386 -94.829376) (xy 79.14386 -94.608396) (xy 78.97368 -94.519496) (xy 78.92923 -94.519496)
			(xy 78.92923 -94.918276) (xy 78.97368 -94.918276)
		)
		(stroke
			(width 0)
			(type solid)
		)
		(fill yes)
		(layer "In4.Cu")
		(net "M_M_ECC<5>")
	)
	(gr_poly
		(pts
			(xy 79.14386 -93.83268) (xy 79.14386 -93.6117) (xy 78.97368 -93.5228) (xy 78.92923 -93.5228) (xy 78.92923 -93.92158)
			(xy 78.97368 -93.92158)
		)
		(stroke
			(width 0)
			(type solid)
		)
		(fill yes)
		(layer "In4.Cu")
		(net "M_M_ECC<5>")
	)
	(gr_poly
		(pts
			(xy 79.14386 -92.854526) (xy 79.14386 -92.633546) (xy 78.97368 -92.544646) (xy 78.92923 -92.544646)
			(xy 78.92923 -92.943426) (xy 78.97368 -92.943426)
		)
		(stroke
			(width 0)
			(type solid)
		)
		(fill yes)
		(layer "In4.Cu")
		(net "M_M_ECC<5>")
	)
	(gr_poly
		(pts
			(xy 79.14386 -91.863926) (xy 79.14386 -91.642946) (xy 78.97368 -91.554046) (xy 78.92923 -91.554046)
			(xy 78.92923 -91.952826) (xy 78.97368 -91.952826)
		)
		(stroke
			(width 0)
			(type solid)
		)
		(fill yes)
		(layer "In4.Cu")
		(net "M_M_ECC<5>")
	)
	(gr_poly
		(pts
			(xy 79.14386 -90.873326) (xy 79.14386 -90.652346) (xy 78.97368 -90.563446) (xy 78.92923 -90.563446)
			(xy 78.92923 -90.962226) (xy 78.97368 -90.962226)
		)
		(stroke
			(width 0)
			(type solid)
		)
		(fill yes)
		(layer "In4.Cu")
		(net "M_M_ECC<5>")
	)
	(gr_poly
		(pts
			(xy 79.14386 -89.882726) (xy 79.14386 -89.661746) (xy 78.97368 -89.572846) (xy 78.92923 -89.572846)
			(xy 78.92923 -89.971626) (xy 78.97368 -89.971626)
		)
		(stroke
			(width 0)
			(type solid)
		)
		(fill yes)
		(layer "In4.Cu")
		(net "M_M_ECC<5>")
	)
	(gr_poly
		(pts
			(xy 79.14386 -88.892126) (xy 79.14386 -88.671146) (xy 78.97368 -88.582246) (xy 78.92923 -88.582246)
			(xy 78.92923 -88.981026) (xy 78.97368 -88.981026)
		)
		(stroke
			(width 0)
			(type solid)
		)
		(fill yes)
		(layer "In4.Cu")
		(net "M_M_ECC<5>")
	)
	(gr_poly
		(pts
			(xy 79.14386 -87.901526) (xy 79.14386 -87.680546) (xy 78.97368 -87.591646) (xy 78.92923 -87.591646)
			(xy 78.92923 -87.990426) (xy 78.97368 -87.990426)
		)
		(stroke
			(width 0)
			(type solid)
		)
		(fill yes)
		(layer "In4.Cu")
		(net "M_M_ECC<5>")
	)
	(gr_poly
		(pts
			(xy 79.14386 -86.910926) (xy 79.14386 -86.689946) (xy 78.97368 -86.601046) (xy 78.92923 -86.601046)
			(xy 78.92923 -86.999826) (xy 78.97368 -86.999826)
		)
		(stroke
			(width 0)
			(type solid)
		)
		(fill yes)
		(layer "In4.Cu")
		(net "M_M_ECC<5>")
	)
	(gr_poly
		(pts
			(xy 79.14386 -85.920326) (xy 79.14386 -85.699346) (xy 78.97368 -85.610446) (xy 78.92923 -85.610446)
			(xy 78.92923 -86.009226) (xy 78.97368 -86.009226)
		)
		(stroke
			(width 0)
			(type solid)
		)
		(fill yes)
		(layer "In4.Cu")
		(net "M_M_ECC<5>")
	)
	(gr_poly
		(pts
			(xy 79.14386 -65.117726) (xy 79.14386 -64.896746) (xy 78.97368 -64.807846) (xy 78.92923 -64.807846)
			(xy 78.92923 -65.206626) (xy 78.97368 -65.206626)
		)
		(stroke
			(width 0)
			(type solid)
		)
		(fill yes)
		(layer "In4.Cu")
		(net "M_J_ECC<1>")
	)
	(gr_poly
		(pts
			(xy 79.14386 -64.127126) (xy 79.14386 -63.906146) (xy 78.97368 -63.817246) (xy 78.92923 -63.817246)
			(xy 78.92923 -64.216026) (xy 78.97368 -64.216026)
		)
		(stroke
			(width 0)
			(type solid)
		)
		(fill yes)
		(layer "In4.Cu")
		(net "M_J_ECC<1>")
	)
	(gr_poly
		(pts
			(xy 79.14386 -63.136526) (xy 79.14386 -62.915546) (xy 78.97368 -62.826646) (xy 78.92923 -62.826646)
			(xy 78.92923 -63.225426) (xy 78.97368 -63.225426)
		)
		(stroke
			(width 0)
			(type solid)
		)
		(fill yes)
		(layer "In4.Cu")
		(net "M_J_ECC<1>")
	)
	(gr_poly
		(pts
			(xy 79.14386 -62.145926) (xy 79.14386 -61.924946) (xy 78.97368 -61.836046) (xy 78.92923 -61.836046)
			(xy 78.92923 -62.234826) (xy 78.97368 -62.234826)
		)
		(stroke
			(width 0)
			(type solid)
		)
		(fill yes)
		(layer "In4.Cu")
		(net "M_J_ECC<1>")
	)
	(gr_poly
		(pts
			(xy 79.14386 -61.155326) (xy 79.14386 -60.934346) (xy 78.97368 -60.845446) (xy 78.92923 -60.845446)
			(xy 78.92923 -61.244226) (xy 78.97368 -61.244226)
		)
		(stroke
			(width 0)
			(type solid)
		)
		(fill yes)
		(layer "In4.Cu")
		(net "M_J_ECC<1>")
	)
	(gr_poly
		(pts
			(xy 79.14386 -60.164726) (xy 79.14386 -59.943746) (xy 78.97368 -59.854846) (xy 78.92923 -59.854846)
			(xy 78.92923 -60.253626) (xy 78.97368 -60.253626)
		)
		(stroke
			(width 0)
			(type solid)
		)
		(fill yes)
		(layer "In4.Cu")
		(net "M_J_ECC<1>")
	)
	(gr_poly
		(pts
			(xy 79.14386 -59.167776) (xy 79.14386 -58.946796) (xy 78.97368 -58.857896) (xy 78.92923 -58.857896)
			(xy 78.92923 -59.256676) (xy 78.97368 -59.256676)
		)
		(stroke
			(width 0)
			(type solid)
		)
		(fill yes)
		(layer "In4.Cu")
		(net "M_J_ECC<1>")
	)
	(gr_poly
		(pts
			(xy 79.14386 -58.17108) (xy 79.14386 -57.9501) (xy 78.97368 -57.8612) (xy 78.92923 -57.8612) (xy 78.92923 -58.25998)
			(xy 78.97368 -58.25998)
		)
		(stroke
			(width 0)
			(type solid)
		)
		(fill yes)
		(layer "In4.Cu")
		(net "M_J_ECC<1>")
	)
	(gr_poly
		(pts
			(xy 79.14386 -57.192926) (xy 79.14386 -56.971946) (xy 78.97368 -56.883046) (xy 78.92923 -56.883046)
			(xy 78.92923 -57.281826) (xy 78.97368 -57.281826)
		)
		(stroke
			(width 0)
			(type solid)
		)
		(fill yes)
		(layer "In4.Cu")
		(net "M_J_ECC<1>")
	)
	(gr_poly
		(pts
			(xy 79.14386 -56.202326) (xy 79.14386 -55.981346) (xy 78.97368 -55.892446) (xy 78.92923 -55.892446)
			(xy 78.92923 -56.291226) (xy 78.97368 -56.291226)
		)
		(stroke
			(width 0)
			(type solid)
		)
		(fill yes)
		(layer "In4.Cu")
		(net "M_J_ECC<1>")
	)
	(gr_poly
		(pts
			(xy 79.14386 -55.211726) (xy 79.14386 -54.990746) (xy 78.97368 -54.901846) (xy 78.92923 -54.901846)
			(xy 78.92923 -55.300626) (xy 78.97368 -55.300626)
		)
		(stroke
			(width 0)
			(type solid)
		)
		(fill yes)
		(layer "In4.Cu")
		(net "M_J_ECC<1>")
	)
	(gr_poly
		(pts
			(xy 79.14386 -54.221126) (xy 79.14386 -54.000146) (xy 78.97368 -53.911246) (xy 78.92923 -53.911246)
			(xy 78.92923 -54.310026) (xy 78.97368 -54.310026)
		)
		(stroke
			(width 0)
			(type solid)
		)
		(fill yes)
		(layer "In4.Cu")
		(net "M_J_ECC<1>")
	)
	(gr_poly
		(pts
			(xy 79.168244 -51.164998) (xy 79.168244 -50.936398) (xy 78.975204 -50.847498) (xy 78.930754 -50.847498)
			(xy 78.930754 -51.253898) (xy 78.975204 -51.253898)
		)
		(stroke
			(width 0)
			(type solid)
		)
		(fill yes)
		(layer "In4.Cu")
		(net "M_J_ECC<1>")
	)
	(gr_poly
		(pts
			(xy 79.326486 -100.093526) (xy 79.29499 -100.06203) (xy 79.095854 -99.98837) (xy 78.934056 -100.150168)
			(xy 79.007716 -100.349304) (xy 79.039212 -100.3808)
		)
		(stroke
			(width 0)
			(type solid)
		)
		(fill yes)
		(layer "In4.Cu")
		(net "M_M_ECC<0>")
	)
	(gr_poly
		(pts
			(xy 79.349346 -101.277674) (xy 79.349346 -101.049074) (xy 79.156306 -100.960174) (xy 79.111856 -100.960174)
			(xy 79.111856 -101.366574) (xy 79.156306 -101.366574)
		)
		(stroke
			(width 0)
			(type solid)
		)
		(fill yes)
		(layer "In4.Cu")
		(net "M_M_ECC<1>")
	)
	(gr_poly
		(pts
			(xy 79.353664 -99.258374) (xy 79.309214 -99.258374) (xy 79.116174 -99.347274) (xy 79.116174 -99.575874)
			(xy 79.309214 -99.664774) (xy 79.353664 -99.664774)
		)
		(stroke
			(width 0)
			(type solid)
		)
		(fill yes)
		(layer "In4.Cu")
		(net "M_M_ECC<0>")
	)
	(gr_poly
		(pts
			(xy 79.464154 -97.497646) (xy 79.419704 -97.497646) (xy 79.249524 -97.586546) (xy 79.249524 -97.807526)
			(xy 79.419704 -97.896426) (xy 79.464154 -97.896426)
		)
		(stroke
			(width 0)
			(type solid)
		)
		(fill yes)
		(layer "In4.Cu")
		(net "M_M_ECC<0>")
	)
	(gr_poly
		(pts
			(xy 79.464154 -96.507046) (xy 79.419704 -96.507046) (xy 79.249524 -96.595946) (xy 79.249524 -96.816926)
			(xy 79.419704 -96.905826) (xy 79.464154 -96.905826)
		)
		(stroke
			(width 0)
			(type solid)
		)
		(fill yes)
		(layer "In4.Cu")
		(net "M_M_ECC<0>")
	)
	(gr_poly
		(pts
			(xy 79.464154 -95.516446) (xy 79.419704 -95.516446) (xy 79.249524 -95.605346) (xy 79.249524 -95.826326)
			(xy 79.419704 -95.915226) (xy 79.464154 -95.915226)
		)
		(stroke
			(width 0)
			(type solid)
		)
		(fill yes)
		(layer "In4.Cu")
		(net "M_M_ECC<0>")
	)
	(gr_poly
		(pts
			(xy 79.464154 -94.519496) (xy 79.419704 -94.519496) (xy 79.249524 -94.608396) (xy 79.249524 -94.829376)
			(xy 79.419704 -94.918276) (xy 79.464154 -94.918276)
		)
		(stroke
			(width 0)
			(type solid)
		)
		(fill yes)
		(layer "In4.Cu")
		(net "M_M_ECC<0>")
	)
	(gr_poly
		(pts
			(xy 79.464154 -93.5228) (xy 79.419704 -93.5228) (xy 79.249524 -93.6117) (xy 79.249524 -93.83268)
			(xy 79.419704 -93.92158) (xy 79.464154 -93.92158)
		)
		(stroke
			(width 0)
			(type solid)
		)
		(fill yes)
		(layer "In4.Cu")
		(net "M_M_ECC<0>")
	)
	(gr_poly
		(pts
			(xy 79.464154 -92.544646) (xy 79.419704 -92.544646) (xy 79.249524 -92.633546) (xy 79.249524 -92.854526)
			(xy 79.419704 -92.943426) (xy 79.464154 -92.943426)
		)
		(stroke
			(width 0)
			(type solid)
		)
		(fill yes)
		(layer "In4.Cu")
		(net "M_M_ECC<0>")
	)
	(gr_poly
		(pts
			(xy 79.464154 -91.554046) (xy 79.419704 -91.554046) (xy 79.249524 -91.642946) (xy 79.249524 -91.863926)
			(xy 79.419704 -91.952826) (xy 79.464154 -91.952826)
		)
		(stroke
			(width 0)
			(type solid)
		)
		(fill yes)
		(layer "In4.Cu")
		(net "M_M_ECC<0>")
	)
	(gr_poly
		(pts
			(xy 79.464154 -90.563446) (xy 79.419704 -90.563446) (xy 79.249524 -90.652346) (xy 79.249524 -90.873326)
			(xy 79.419704 -90.962226) (xy 79.464154 -90.962226)
		)
		(stroke
			(width 0)
			(type solid)
		)
		(fill yes)
		(layer "In4.Cu")
		(net "M_M_ECC<0>")
	)
	(gr_poly
		(pts
			(xy 79.464154 -89.572846) (xy 79.419704 -89.572846) (xy 79.249524 -89.661746) (xy 79.249524 -89.882726)
			(xy 79.419704 -89.971626) (xy 79.464154 -89.971626)
		)
		(stroke
			(width 0)
			(type solid)
		)
		(fill yes)
		(layer "In4.Cu")
		(net "M_M_ECC<0>")
	)
	(gr_poly
		(pts
			(xy 79.464154 -88.582246) (xy 79.419704 -88.582246) (xy 79.249524 -88.671146) (xy 79.249524 -88.892126)
			(xy 79.419704 -88.981026) (xy 79.464154 -88.981026)
		)
		(stroke
			(width 0)
			(type solid)
		)
		(fill yes)
		(layer "In4.Cu")
		(net "M_M_ECC<0>")
	)
	(gr_poly
		(pts
			(xy 79.464154 -87.591646) (xy 79.419704 -87.591646) (xy 79.249524 -87.680546) (xy 79.249524 -87.901526)
			(xy 79.419704 -87.990426) (xy 79.464154 -87.990426)
		)
		(stroke
			(width 0)
			(type solid)
		)
		(fill yes)
		(layer "In4.Cu")
		(net "M_M_ECC<0>")
	)
	(gr_poly
		(pts
			(xy 79.464154 -86.601046) (xy 79.419704 -86.601046) (xy 79.249524 -86.689946) (xy 79.249524 -86.910926)
			(xy 79.419704 -86.999826) (xy 79.464154 -86.999826)
		)
		(stroke
			(width 0)
			(type solid)
		)
		(fill yes)
		(layer "In4.Cu")
		(net "M_M_ECC<0>")
	)
	(gr_poly
		(pts
			(xy 79.464154 -85.610446) (xy 79.419704 -85.610446) (xy 79.249524 -85.699346) (xy 79.249524 -85.920326)
			(xy 79.419704 -86.009226) (xy 79.464154 -86.009226)
		)
		(stroke
			(width 0)
			(type solid)
		)
		(fill yes)
		(layer "In4.Cu")
		(net "M_M_ECC<0>")
	)
	(gr_poly
		(pts
			(xy 79.464154 -84.619846) (xy 79.419704 -84.619846) (xy 79.249524 -84.708746) (xy 79.249524 -84.929726)
			(xy 79.419704 -85.018626) (xy 79.464154 -85.018626)
		)
		(stroke
			(width 0)
			(type solid)
		)
		(fill yes)
		(layer "In4.Cu")
		(net "M_M_ECC<0>")
	)
	(gr_poly
		(pts
			(xy 79.464154 -83.629246) (xy 79.419704 -83.629246) (xy 79.249524 -83.718146) (xy 79.249524 -83.939126)
			(xy 79.419704 -84.028026) (xy 79.464154 -84.028026)
		)
		(stroke
			(width 0)
			(type solid)
		)
		(fill yes)
		(layer "In4.Cu")
		(net "M_M_ECC<0>")
	)
	(gr_poly
		(pts
			(xy 79.464154 -65.798446) (xy 79.419704 -65.798446) (xy 79.249524 -65.887346) (xy 79.249524 -66.108326)
			(xy 79.419704 -66.197226) (xy 79.464154 -66.197226)
		)
		(stroke
			(width 0)
			(type solid)
		)
		(fill yes)
		(layer "In4.Cu")
		(net "M_J_DQS_DP<17>")
	)
	(gr_poly
		(pts
			(xy 79.464154 -64.807846) (xy 79.419704 -64.807846) (xy 79.249524 -64.896746) (xy 79.249524 -65.117726)
			(xy 79.419704 -65.206626) (xy 79.464154 -65.206626)
		)
		(stroke
			(width 0)
			(type solid)
		)
		(fill yes)
		(layer "In4.Cu")
		(net "M_J_DQS_DP<17>")
	)
	(gr_poly
		(pts
			(xy 79.464154 -63.817246) (xy 79.419704 -63.817246) (xy 79.249524 -63.906146) (xy 79.249524 -64.127126)
			(xy 79.419704 -64.216026) (xy 79.464154 -64.216026)
		)
		(stroke
			(width 0)
			(type solid)
		)
		(fill yes)
		(layer "In4.Cu")
		(net "M_J_DQS_DP<17>")
	)
	(gr_poly
		(pts
			(xy 79.464154 -62.826646) (xy 79.419704 -62.826646) (xy 79.249524 -62.915546) (xy 79.249524 -63.136526)
			(xy 79.419704 -63.225426) (xy 79.464154 -63.225426)
		)
		(stroke
			(width 0)
			(type solid)
		)
		(fill yes)
		(layer "In4.Cu")
		(net "M_J_DQS_DP<17>")
	)
	(gr_poly
		(pts
			(xy 79.464154 -61.836046) (xy 79.419704 -61.836046) (xy 79.249524 -61.924946) (xy 79.249524 -62.145926)
			(xy 79.419704 -62.234826) (xy 79.464154 -62.234826)
		)
		(stroke
			(width 0)
			(type solid)
		)
		(fill yes)
		(layer "In4.Cu")
		(net "M_J_DQS_DP<17>")
	)
	(gr_poly
		(pts
			(xy 79.464154 -60.845446) (xy 79.419704 -60.845446) (xy 79.249524 -60.934346) (xy 79.249524 -61.155326)
			(xy 79.419704 -61.244226) (xy 79.464154 -61.244226)
		)
		(stroke
			(width 0)
			(type solid)
		)
		(fill yes)
		(layer "In4.Cu")
		(net "M_J_DQS_DP<17>")
	)
	(gr_poly
		(pts
			(xy 79.464154 -59.854846) (xy 79.419704 -59.854846) (xy 79.249524 -59.943746) (xy 79.249524 -60.164726)
			(xy 79.419704 -60.253626) (xy 79.464154 -60.253626)
		)
		(stroke
			(width 0)
			(type solid)
		)
		(fill yes)
		(layer "In4.Cu")
		(net "M_J_DQS_DP<17>")
	)
	(gr_poly
		(pts
			(xy 79.464154 -58.857896) (xy 79.419704 -58.857896) (xy 79.249524 -58.946796) (xy 79.249524 -59.167776)
			(xy 79.419704 -59.256676) (xy 79.464154 -59.256676)
		)
		(stroke
			(width 0)
			(type solid)
		)
		(fill yes)
		(layer "In4.Cu")
		(net "M_J_DQS_DP<17>")
	)
	(gr_poly
		(pts
			(xy 79.464154 -57.8612) (xy 79.419704 -57.8612) (xy 79.249524 -57.9501) (xy 79.249524 -58.17108)
			(xy 79.419704 -58.25998) (xy 79.464154 -58.25998)
		)
		(stroke
			(width 0)
			(type solid)
		)
		(fill yes)
		(layer "In4.Cu")
		(net "M_J_DQS_DP<17>")
	)
	(gr_poly
		(pts
			(xy 79.464154 -56.883046) (xy 79.419704 -56.883046) (xy 79.249524 -56.971946) (xy 79.249524 -57.192926)
			(xy 79.419704 -57.281826) (xy 79.464154 -57.281826)
		)
		(stroke
			(width 0)
			(type solid)
		)
		(fill yes)
		(layer "In4.Cu")
		(net "M_J_DQS_DP<17>")
	)
	(gr_poly
		(pts
			(xy 79.464154 -55.892446) (xy 79.419704 -55.892446) (xy 79.249524 -55.981346) (xy 79.249524 -56.202326)
			(xy 79.419704 -56.291226) (xy 79.464154 -56.291226)
		)
		(stroke
			(width 0)
			(type solid)
		)
		(fill yes)
		(layer "In4.Cu")
		(net "M_J_DQS_DP<17>")
	)
	(gr_poly
		(pts
			(xy 79.464154 -54.901846) (xy 79.419704 -54.901846) (xy 79.249524 -54.990746) (xy 79.249524 -55.211726)
			(xy 79.419704 -55.300626) (xy 79.464154 -55.300626)
		)
		(stroke
			(width 0)
			(type solid)
		)
		(fill yes)
		(layer "In4.Cu")
		(net "M_J_DQS_DP<17>")
	)
	(gr_poly
		(pts
			(xy 79.464154 -53.911246) (xy 79.419704 -53.911246) (xy 79.249524 -54.000146) (xy 79.249524 -54.221126)
			(xy 79.419704 -54.310026) (xy 79.464154 -54.310026)
		)
		(stroke
			(width 0)
			(type solid)
		)
		(fill yes)
		(layer "In4.Cu")
		(net "M_J_DQS_DP<17>")
	)
	(gr_poly
		(pts
			(xy 79.566008 -100.458524) (xy 79.492348 -100.259134) (xy 79.460852 -100.227892) (xy 79.173578 -100.515166)
			(xy 79.205074 -100.546662) (xy 79.40421 -100.620322)
		)
		(stroke
			(width 0)
			(type solid)
		)
		(fill yes)
		(layer "In4.Cu")
		(net "M_M_ECC<1>")
	)
	(gr_poly
		(pts
			(xy 79.773272 -51.220878) (xy 79.728822 -51.220878) (xy 79.535782 -51.309778) (xy 79.535782 -51.538378)
			(xy 79.728822 -51.627278) (xy 79.773272 -51.627278)
		)
		(stroke
			(width 0)
			(type solid)
		)
		(fill yes)
		(layer "In4.Cu")
		(net "M_J_DQS_DP<17>")
	)
	(gr_poly
		(pts
			(xy 79.773272 -50.230278) (xy 79.728822 -50.230278) (xy 79.535782 -50.319178) (xy 79.535782 -50.547778)
			(xy 79.728822 -50.636678) (xy 79.773272 -50.636678)
		)
		(stroke
			(width 0)
			(type solid)
		)
		(fill yes)
		(layer "In4.Cu")
		(net "M_J_DQS_DP<17>")
	)
	(gr_poly
		(pts
			(xy 79.781146 -99.321874) (xy 79.781146 -99.093274) (xy 79.588106 -99.004374) (xy 79.543656 -99.004374)
			(xy 79.543656 -99.410774) (xy 79.588106 -99.410774)
		)
		(stroke
			(width 0)
			(type solid)
		)
		(fill yes)
		(layer "In4.Cu")
		(net "M_M_ECC<1>")
	)
	(gr_poly
		(pts
			(xy 79.811626 -84.42325) (xy 79.811626 -84.20227) (xy 79.641446 -84.11337) (xy 79.596996 -84.11337)
			(xy 79.596996 -84.51215) (xy 79.641446 -84.51215)
		)
		(stroke
			(width 0)
			(type solid)
		)
		(fill yes)
		(layer "In4.Cu")
		(net "M_M_ECC<0>")
	)
	(gr_poly
		(pts
			(xy 79.915004 -85.676994) (xy 80.009492 -85.47735) (xy 79.893414 -85.324188) (xy 79.853282 -85.305138)
			(xy 79.682848 -85.665818) (xy 79.72298 -85.684868)
		)
		(stroke
			(width 0)
			(type solid)
		)
		(fill yes)
		(layer "In4.Cu")
		(net "M_M_ECC<1>")
	)
	(gr_poly
		(pts
			(xy 80.00238 -98.29038) (xy 80.00238 -98.0694) (xy 79.8322 -97.9805) (xy 79.78775 -97.9805) (xy 79.78775 -98.37928)
			(xy 79.8322 -98.37928)
		)
		(stroke
			(width 0)
			(type solid)
		)
		(fill yes)
		(layer "In4.Cu")
		(net "M_M_ECC<1>")
	)
	(gr_poly
		(pts
			(xy 80.00238 -97.29978) (xy 80.00238 -97.0788) (xy 79.8322 -96.9899) (xy 79.78775 -96.9899) (xy 79.78775 -97.38868)
			(xy 79.8322 -97.38868)
		)
		(stroke
			(width 0)
			(type solid)
		)
		(fill yes)
		(layer "In4.Cu")
		(net "M_M_ECC<1>")
	)
	(gr_poly
		(pts
			(xy 80.00238 -96.30918) (xy 80.00238 -96.0882) (xy 79.8322 -95.9993) (xy 79.78775 -95.9993) (xy 79.78775 -96.39808)
			(xy 79.8322 -96.39808)
		)
		(stroke
			(width 0)
			(type solid)
		)
		(fill yes)
		(layer "In4.Cu")
		(net "M_M_ECC<1>")
	)
	(gr_poly
		(pts
			(xy 80.00238 -95.31858) (xy 80.00238 -95.0976) (xy 79.8322 -95.0087) (xy 79.78775 -95.0087) (xy 79.78775 -95.40748)
			(xy 79.8322 -95.40748)
		)
		(stroke
			(width 0)
			(type solid)
		)
		(fill yes)
		(layer "In4.Cu")
		(net "M_M_ECC<1>")
	)
	(gr_poly
		(pts
			(xy 80.00238 -94.340426) (xy 80.00238 -94.119446) (xy 79.8322 -94.030546) (xy 79.78775 -94.030546)
			(xy 79.78775 -94.429326) (xy 79.8322 -94.429326)
		)
		(stroke
			(width 0)
			(type solid)
		)
		(fill yes)
		(layer "In4.Cu")
		(net "M_M_ECC<1>")
	)
	(gr_poly
		(pts
			(xy 80.00238 -93.34373) (xy 80.00238 -93.12275) (xy 79.8322 -93.03385) (xy 79.78775 -93.03385) (xy 79.78775 -93.43263)
			(xy 79.8322 -93.43263)
		)
		(stroke
			(width 0)
			(type solid)
		)
		(fill yes)
		(layer "In4.Cu")
		(net "M_M_ECC<1>")
	)
	(gr_poly
		(pts
			(xy 80.00238 -92.34678) (xy 80.00238 -92.1258) (xy 79.8322 -92.0369) (xy 79.78775 -92.0369) (xy 79.78775 -92.43568)
			(xy 79.8322 -92.43568)
		)
		(stroke
			(width 0)
			(type solid)
		)
		(fill yes)
		(layer "In4.Cu")
		(net "M_M_ECC<1>")
	)
	(gr_poly
		(pts
			(xy 80.00238 -91.35618) (xy 80.00238 -91.1352) (xy 79.8322 -91.0463) (xy 79.78775 -91.0463) (xy 79.78775 -91.44508)
			(xy 79.8322 -91.44508)
		)
		(stroke
			(width 0)
			(type solid)
		)
		(fill yes)
		(layer "In4.Cu")
		(net "M_M_ECC<1>")
	)
	(gr_poly
		(pts
			(xy 80.00238 -90.36558) (xy 80.00238 -90.1446) (xy 79.8322 -90.0557) (xy 79.78775 -90.0557) (xy 79.78775 -90.45448)
			(xy 79.8322 -90.45448)
		)
		(stroke
			(width 0)
			(type solid)
		)
		(fill yes)
		(layer "In4.Cu")
		(net "M_M_ECC<1>")
	)
	(gr_poly
		(pts
			(xy 80.00238 -89.37498) (xy 80.00238 -89.154) (xy 79.8322 -89.0651) (xy 79.78775 -89.0651) (xy 79.78775 -89.46388)
			(xy 79.8322 -89.46388)
		)
		(stroke
			(width 0)
			(type solid)
		)
		(fill yes)
		(layer "In4.Cu")
		(net "M_M_ECC<1>")
	)
	(gr_poly
		(pts
			(xy 80.00238 -88.38438) (xy 80.00238 -88.1634) (xy 79.8322 -88.0745) (xy 79.78775 -88.0745) (xy 79.78775 -88.47328)
			(xy 79.8322 -88.47328)
		)
		(stroke
			(width 0)
			(type solid)
		)
		(fill yes)
		(layer "In4.Cu")
		(net "M_M_ECC<1>")
	)
	(gr_poly
		(pts
			(xy 80.00238 -87.39378) (xy 80.00238 -87.1728) (xy 79.8322 -87.0839) (xy 79.78775 -87.0839) (xy 79.78775 -87.48268)
			(xy 79.8322 -87.48268)
		)
		(stroke
			(width 0)
			(type solid)
		)
		(fill yes)
		(layer "In4.Cu")
		(net "M_M_ECC<1>")
	)
	(gr_poly
		(pts
			(xy 80.00238 -86.40318) (xy 80.00238 -86.1822) (xy 79.8322 -86.0933) (xy 79.78775 -86.0933) (xy 79.78775 -86.49208)
			(xy 79.8322 -86.49208)
		)
		(stroke
			(width 0)
			(type solid)
		)
		(fill yes)
		(layer "In4.Cu")
		(net "M_M_ECC<1>")
	)
	(gr_poly
		(pts
			(xy 80.00238 -65.60058) (xy 80.00238 -65.3796) (xy 79.8322 -65.2907) (xy 79.78775 -65.2907) (xy 79.78775 -65.68948)
			(xy 79.8322 -65.68948)
		)
		(stroke
			(width 0)
			(type solid)
		)
		(fill yes)
		(layer "In4.Cu")
		(net "M_J_DQS_DN<17>")
	)
	(gr_poly
		(pts
			(xy 80.00238 -64.60998) (xy 80.00238 -64.389) (xy 79.8322 -64.3001) (xy 79.78775 -64.3001) (xy 79.78775 -64.69888)
			(xy 79.8322 -64.69888)
		)
		(stroke
			(width 0)
			(type solid)
		)
		(fill yes)
		(layer "In4.Cu")
		(net "M_J_DQS_DN<17>")
	)
	(gr_poly
		(pts
			(xy 80.00238 -63.61938) (xy 80.00238 -63.3984) (xy 79.8322 -63.3095) (xy 79.78775 -63.3095) (xy 79.78775 -63.70828)
			(xy 79.8322 -63.70828)
		)
		(stroke
			(width 0)
			(type solid)
		)
		(fill yes)
		(layer "In4.Cu")
		(net "M_J_DQS_DN<17>")
	)
	(gr_poly
		(pts
			(xy 80.00238 -62.62878) (xy 80.00238 -62.4078) (xy 79.8322 -62.3189) (xy 79.78775 -62.3189) (xy 79.78775 -62.71768)
			(xy 79.8322 -62.71768)
		)
		(stroke
			(width 0)
			(type solid)
		)
		(fill yes)
		(layer "In4.Cu")
		(net "M_J_DQS_DN<17>")
	)
	(gr_poly
		(pts
			(xy 80.00238 -61.63818) (xy 80.00238 -61.4172) (xy 79.8322 -61.3283) (xy 79.78775 -61.3283) (xy 79.78775 -61.72708)
			(xy 79.8322 -61.72708)
		)
		(stroke
			(width 0)
			(type solid)
		)
		(fill yes)
		(layer "In4.Cu")
		(net "M_J_DQS_DN<17>")
	)
	(gr_poly
		(pts
			(xy 80.00238 -60.64758) (xy 80.00238 -60.4266) (xy 79.8322 -60.3377) (xy 79.78775 -60.3377) (xy 79.78775 -60.73648)
			(xy 79.8322 -60.73648)
		)
		(stroke
			(width 0)
			(type solid)
		)
		(fill yes)
		(layer "In4.Cu")
		(net "M_J_DQS_DN<17>")
	)
	(gr_poly
		(pts
			(xy 80.00238 -59.65698) (xy 80.00238 -59.436) (xy 79.8322 -59.3471) (xy 79.78775 -59.3471) (xy 79.78775 -59.74588)
			(xy 79.8322 -59.74588)
		)
		(stroke
			(width 0)
			(type solid)
		)
		(fill yes)
		(layer "In4.Cu")
		(net "M_J_DQS_DN<17>")
	)
	(gr_poly
		(pts
			(xy 80.00238 -58.678826) (xy 80.00238 -58.457846) (xy 79.8322 -58.368946) (xy 79.78775 -58.368946)
			(xy 79.78775 -58.767726) (xy 79.8322 -58.767726)
		)
		(stroke
			(width 0)
			(type solid)
		)
		(fill yes)
		(layer "In4.Cu")
		(net "M_J_DQS_DN<17>")
	)
	(gr_poly
		(pts
			(xy 80.00238 -57.68213) (xy 80.00238 -57.46115) (xy 79.8322 -57.37225) (xy 79.78775 -57.37225) (xy 79.78775 -57.77103)
			(xy 79.8322 -57.77103)
		)
		(stroke
			(width 0)
			(type solid)
		)
		(fill yes)
		(layer "In4.Cu")
		(net "M_J_DQS_DN<17>")
	)
	(gr_poly
		(pts
			(xy 80.00238 -56.68518) (xy 80.00238 -56.4642) (xy 79.8322 -56.3753) (xy 79.78775 -56.3753) (xy 79.78775 -56.77408)
			(xy 79.8322 -56.77408)
		)
		(stroke
			(width 0)
			(type solid)
		)
		(fill yes)
		(layer "In4.Cu")
		(net "M_J_DQS_DN<17>")
	)
	(gr_poly
		(pts
			(xy 80.00238 -55.69458) (xy 80.00238 -55.4736) (xy 79.8322 -55.3847) (xy 79.78775 -55.3847) (xy 79.78775 -55.78348)
			(xy 79.8322 -55.78348)
		)
		(stroke
			(width 0)
			(type solid)
		)
		(fill yes)
		(layer "In4.Cu")
		(net "M_J_DQS_DN<17>")
	)
	(gr_poly
		(pts
			(xy 80.00238 -54.70398) (xy 80.00238 -54.483) (xy 79.8322 -54.3941) (xy 79.78775 -54.3941) (xy 79.78775 -54.79288)
			(xy 79.8322 -54.79288)
		)
		(stroke
			(width 0)
			(type solid)
		)
		(fill yes)
		(layer "In4.Cu")
		(net "M_J_DQS_DN<17>")
	)
	(gr_poly
		(pts
			(xy 80.00238 -53.71338) (xy 80.00238 -53.4924) (xy 79.8322 -53.4035) (xy 79.78775 -53.4035) (xy 79.78775 -53.80228)
			(xy 79.8322 -53.80228)
		)
		(stroke
			(width 0)
			(type solid)
		)
		(fill yes)
		(layer "In4.Cu")
		(net "M_J_DQS_DN<17>")
	)
	(gr_poly
		(pts
			(xy 80.09382 -101.224842) (xy 80.04937 -101.224842) (xy 79.85633 -101.313742) (xy 79.85633 -101.542342)
			(xy 80.04937 -101.631242) (xy 80.09382 -101.631242)
		)
		(stroke
			(width 0)
			(type solid)
		)
		(fill yes)
		(layer "In4.Cu")
		(net "M_M_DQS_DP<17>")
	)
	(gr_poly
		(pts
			(xy 80.201262 -51.538378) (xy 80.201262 -51.309778) (xy 80.008222 -51.220878) (xy 79.963772 -51.220878)
			(xy 79.963772 -51.627278) (xy 80.008222 -51.627278)
		)
		(stroke
			(width 0)
			(type solid)
		)
		(fill yes)
		(layer "In4.Cu")
		(net "M_J_DQS_DN<17>")
	)
	(gr_poly
		(pts
			(xy 80.201262 -50.547778) (xy 80.201262 -50.319178) (xy 80.008222 -50.230278) (xy 79.963772 -50.230278)
			(xy 79.963772 -50.636678) (xy 80.008222 -50.636678)
		)
		(stroke
			(width 0)
			(type solid)
		)
		(fill yes)
		(layer "In4.Cu")
		(net "M_J_DQS_DN<17>")
	)
	(gr_poly
		(pts
			(xy 80.322674 -98.97745) (xy 80.278224 -98.97745) (xy 80.108044 -99.06635) (xy 80.108044 -99.28733)
			(xy 80.278224 -99.37623) (xy 80.322674 -99.37623)
		)
		(stroke
			(width 0)
			(type solid)
		)
		(fill yes)
		(layer "In4.Cu")
		(net "M_M_DQS_DP<17>")
	)
	(gr_poly
		(pts
			(xy 80.322674 -97.9805) (xy 80.278224 -97.9805) (xy 80.108044 -98.0694) (xy 80.108044 -98.29038)
			(xy 80.278224 -98.37928) (xy 80.322674 -98.37928)
		)
		(stroke
			(width 0)
			(type solid)
		)
		(fill yes)
		(layer "In4.Cu")
		(net "M_M_DQS_DP<17>")
	)
	(gr_poly
		(pts
			(xy 80.322674 -96.9899) (xy 80.278224 -96.9899) (xy 80.108044 -97.0788) (xy 80.108044 -97.29978)
			(xy 80.278224 -97.38868) (xy 80.322674 -97.38868)
		)
		(stroke
			(width 0)
			(type solid)
		)
		(fill yes)
		(layer "In4.Cu")
		(net "M_M_DQS_DP<17>")
	)
	(gr_poly
		(pts
			(xy 80.322674 -95.9993) (xy 80.278224 -95.9993) (xy 80.108044 -96.0882) (xy 80.108044 -96.30918)
			(xy 80.278224 -96.39808) (xy 80.322674 -96.39808)
		)
		(stroke
			(width 0)
			(type solid)
		)
		(fill yes)
		(layer "In4.Cu")
		(net "M_M_DQS_DP<17>")
	)
	(gr_poly
		(pts
			(xy 80.322674 -95.0087) (xy 80.278224 -95.0087) (xy 80.108044 -95.0976) (xy 80.108044 -95.31858)
			(xy 80.278224 -95.40748) (xy 80.322674 -95.40748)
		)
		(stroke
			(width 0)
			(type solid)
		)
		(fill yes)
		(layer "In4.Cu")
		(net "M_M_DQS_DP<17>")
	)
	(gr_poly
		(pts
			(xy 80.322674 -94.030546) (xy 80.278224 -94.030546) (xy 80.108044 -94.119446) (xy 80.108044 -94.340426)
			(xy 80.278224 -94.429326) (xy 80.322674 -94.429326)
		)
		(stroke
			(width 0)
			(type solid)
		)
		(fill yes)
		(layer "In4.Cu")
		(net "M_M_DQS_DP<17>")
	)
	(gr_poly
		(pts
			(xy 80.322674 -93.03385) (xy 80.278224 -93.03385) (xy 80.108044 -93.12275) (xy 80.108044 -93.34373)
			(xy 80.278224 -93.43263) (xy 80.322674 -93.43263)
		)
		(stroke
			(width 0)
			(type solid)
		)
		(fill yes)
		(layer "In4.Cu")
		(net "M_M_DQS_DP<17>")
	)
	(gr_poly
		(pts
			(xy 80.322674 -92.0369) (xy 80.278224 -92.0369) (xy 80.108044 -92.1258) (xy 80.108044 -92.34678)
			(xy 80.278224 -92.43568) (xy 80.322674 -92.43568)
		)
		(stroke
			(width 0)
			(type solid)
		)
		(fill yes)
		(layer "In4.Cu")
		(net "M_M_DQS_DP<17>")
	)
	(gr_poly
		(pts
			(xy 80.322674 -91.0463) (xy 80.278224 -91.0463) (xy 80.108044 -91.1352) (xy 80.108044 -91.35618)
			(xy 80.278224 -91.44508) (xy 80.322674 -91.44508)
		)
		(stroke
			(width 0)
			(type solid)
		)
		(fill yes)
		(layer "In4.Cu")
		(net "M_M_DQS_DP<17>")
	)
	(gr_poly
		(pts
			(xy 80.322674 -90.0557) (xy 80.278224 -90.0557) (xy 80.108044 -90.1446) (xy 80.108044 -90.36558)
			(xy 80.278224 -90.45448) (xy 80.322674 -90.45448)
		)
		(stroke
			(width 0)
			(type solid)
		)
		(fill yes)
		(layer "In4.Cu")
		(net "M_M_DQS_DP<17>")
	)
	(gr_poly
		(pts
			(xy 80.322674 -89.0651) (xy 80.278224 -89.0651) (xy 80.108044 -89.154) (xy 80.108044 -89.37498) (xy 80.278224 -89.46388)
			(xy 80.322674 -89.46388)
		)
		(stroke
			(width 0)
			(type solid)
		)
		(fill yes)
		(layer "In4.Cu")
		(net "M_M_DQS_DP<17>")
	)
	(gr_poly
		(pts
			(xy 80.322674 -88.0745) (xy 80.278224 -88.0745) (xy 80.108044 -88.1634) (xy 80.108044 -88.38438)
			(xy 80.278224 -88.47328) (xy 80.322674 -88.47328)
		)
		(stroke
			(width 0)
			(type solid)
		)
		(fill yes)
		(layer "In4.Cu")
		(net "M_M_DQS_DP<17>")
	)
	(gr_poly
		(pts
			(xy 80.322674 -87.0839) (xy 80.278224 -87.0839) (xy 80.108044 -87.1728) (xy 80.108044 -87.39378)
			(xy 80.278224 -87.48268) (xy 80.322674 -87.48268)
		)
		(stroke
			(width 0)
			(type solid)
		)
		(fill yes)
		(layer "In4.Cu")
		(net "M_M_DQS_DP<17>")
	)
	(gr_poly
		(pts
			(xy 80.322674 -86.0933) (xy 80.278224 -86.0933) (xy 80.108044 -86.1822) (xy 80.108044 -86.40318)
			(xy 80.278224 -86.49208) (xy 80.322674 -86.49208)
		)
		(stroke
			(width 0)
			(type solid)
		)
		(fill yes)
		(layer "In4.Cu")
		(net "M_M_DQS_DP<17>")
	)
	(gr_poly
		(pts
			(xy 80.322674 -85.1027) (xy 80.278224 -85.1027) (xy 80.108044 -85.1916) (xy 80.108044 -85.41258)
			(xy 80.278224 -85.50148) (xy 80.322674 -85.50148)
		)
		(stroke
			(width 0)
			(type solid)
		)
		(fill yes)
		(layer "In4.Cu")
		(net "M_M_DQS_DP<17>")
	)
	(gr_poly
		(pts
			(xy 80.322674 -84.1121) (xy 80.278224 -84.1121) (xy 80.108044 -84.201) (xy 80.108044 -84.42198) (xy 80.278224 -84.51088)
			(xy 80.322674 -84.51088)
		)
		(stroke
			(width 0)
			(type solid)
		)
		(fill yes)
		(layer "In4.Cu")
		(net "M_M_DQS_DP<17>")
	)
	(gr_poly
		(pts
			(xy 80.322674 -83.1215) (xy 80.278224 -83.1215) (xy 80.108044 -83.2104) (xy 80.108044 -83.43138)
			(xy 80.278224 -83.52028) (xy 80.322674 -83.52028)
		)
		(stroke
			(width 0)
			(type solid)
		)
		(fill yes)
		(layer "In4.Cu")
		(net "M_M_DQS_DP<17>")
	)
	(gr_poly
		(pts
			(xy 80.322674 -67.2719) (xy 80.278224 -67.2719) (xy 80.108044 -67.3608) (xy 80.108044 -67.58178)
			(xy 80.278224 -67.67068) (xy 80.322674 -67.67068)
		)
		(stroke
			(width 0)
			(type solid)
		)
		(fill yes)
		(layer "In4.Cu")
		(net "M_J_DQS_DP<8>")
	)
	(gr_poly
		(pts
			(xy 80.322674 -66.287396) (xy 80.278224 -66.287396) (xy 80.108044 -66.376296) (xy 80.108044 -66.597276)
			(xy 80.278224 -66.686176) (xy 80.322674 -66.686176)
		)
		(stroke
			(width 0)
			(type solid)
		)
		(fill yes)
		(layer "In4.Cu")
		(net "M_J_DQS_DP<8>")
	)
	(gr_poly
		(pts
			(xy 80.322674 -65.2907) (xy 80.278224 -65.2907) (xy 80.108044 -65.3796) (xy 80.108044 -65.60058)
			(xy 80.278224 -65.68948) (xy 80.322674 -65.68948)
		)
		(stroke
			(width 0)
			(type solid)
		)
		(fill yes)
		(layer "In4.Cu")
		(net "M_J_DQS_DP<8>")
	)
	(gr_poly
		(pts
			(xy 80.322674 -64.3001) (xy 80.278224 -64.3001) (xy 80.108044 -64.389) (xy 80.108044 -64.60998) (xy 80.278224 -64.69888)
			(xy 80.322674 -64.69888)
		)
		(stroke
			(width 0)
			(type solid)
		)
		(fill yes)
		(layer "In4.Cu")
		(net "M_J_DQS_DP<8>")
	)
	(gr_poly
		(pts
			(xy 80.322674 -63.3095) (xy 80.278224 -63.3095) (xy 80.108044 -63.3984) (xy 80.108044 -63.61938)
			(xy 80.278224 -63.70828) (xy 80.322674 -63.70828)
		)
		(stroke
			(width 0)
			(type solid)
		)
		(fill yes)
		(layer "In4.Cu")
		(net "M_J_DQS_DP<8>")
	)
	(gr_poly
		(pts
			(xy 80.322674 -62.3189) (xy 80.278224 -62.3189) (xy 80.108044 -62.4078) (xy 80.108044 -62.62878)
			(xy 80.278224 -62.71768) (xy 80.322674 -62.71768)
		)
		(stroke
			(width 0)
			(type solid)
		)
		(fill yes)
		(layer "In4.Cu")
		(net "M_J_DQS_DP<8>")
	)
	(gr_poly
		(pts
			(xy 80.322674 -61.3283) (xy 80.278224 -61.3283) (xy 80.108044 -61.4172) (xy 80.108044 -61.63818)
			(xy 80.278224 -61.72708) (xy 80.322674 -61.72708)
		)
		(stroke
			(width 0)
			(type solid)
		)
		(fill yes)
		(layer "In4.Cu")
		(net "M_J_DQS_DP<8>")
	)
	(gr_poly
		(pts
			(xy 80.322674 -60.3377) (xy 80.278224 -60.3377) (xy 80.108044 -60.4266) (xy 80.108044 -60.64758)
			(xy 80.278224 -60.73648) (xy 80.322674 -60.73648)
		)
		(stroke
			(width 0)
			(type solid)
		)
		(fill yes)
		(layer "In4.Cu")
		(net "M_J_DQS_DP<8>")
	)
	(gr_poly
		(pts
			(xy 80.322674 -59.3471) (xy 80.278224 -59.3471) (xy 80.108044 -59.436) (xy 80.108044 -59.65698) (xy 80.278224 -59.74588)
			(xy 80.322674 -59.74588)
		)
		(stroke
			(width 0)
			(type solid)
		)
		(fill yes)
		(layer "In4.Cu")
		(net "M_J_DQS_DP<8>")
	)
	(gr_poly
		(pts
			(xy 80.322674 -58.368946) (xy 80.278224 -58.368946) (xy 80.108044 -58.457846) (xy 80.108044 -58.678826)
			(xy 80.278224 -58.767726) (xy 80.322674 -58.767726)
		)
		(stroke
			(width 0)
			(type solid)
		)
		(fill yes)
		(layer "In4.Cu")
		(net "M_J_DQS_DP<8>")
	)
	(gr_poly
		(pts
			(xy 80.322674 -57.37225) (xy 80.278224 -57.37225) (xy 80.108044 -57.46115) (xy 80.108044 -57.68213)
			(xy 80.278224 -57.77103) (xy 80.322674 -57.77103)
		)
		(stroke
			(width 0)
			(type solid)
		)
		(fill yes)
		(layer "In4.Cu")
		(net "M_J_DQS_DP<8>")
	)
	(gr_poly
		(pts
			(xy 80.322674 -56.3753) (xy 80.278224 -56.3753) (xy 80.108044 -56.4642) (xy 80.108044 -56.68518)
			(xy 80.278224 -56.77408) (xy 80.322674 -56.77408)
		)
		(stroke
			(width 0)
			(type solid)
		)
		(fill yes)
		(layer "In4.Cu")
		(net "M_J_DQS_DP<8>")
	)
	(gr_poly
		(pts
			(xy 80.322674 -55.3847) (xy 80.278224 -55.3847) (xy 80.108044 -55.4736) (xy 80.108044 -55.69458)
			(xy 80.278224 -55.78348) (xy 80.322674 -55.78348)
		)
		(stroke
			(width 0)
			(type solid)
		)
		(fill yes)
		(layer "In4.Cu")
		(net "M_J_DQS_DP<8>")
	)
	(gr_poly
		(pts
			(xy 80.487012 -54.386734) (xy 80.442562 -54.386734) (xy 80.249522 -54.475634) (xy 80.249522 -54.704234)
			(xy 80.442562 -54.793134) (xy 80.487012 -54.793134)
		)
		(stroke
			(width 0)
			(type solid)
		)
		(fill yes)
		(layer "In4.Cu")
		(net "M_J_DQS_DP<8>")
	)
	(gr_poly
		(pts
			(xy 80.487012 -53.396134) (xy 80.442562 -53.396134) (xy 80.249522 -53.485034) (xy 80.249522 -53.713634)
			(xy 80.442562 -53.802534) (xy 80.487012 -53.802534)
		)
		(stroke
			(width 0)
			(type solid)
		)
		(fill yes)
		(layer "In4.Cu")
		(net "M_J_DQS_DP<8>")
	)
	(gr_poly
		(pts
			(xy 80.52181 -101.542342) (xy 80.52181 -101.313742) (xy 80.32877 -101.224842) (xy 80.28432 -101.224842)
			(xy 80.28432 -101.631242) (xy 80.32877 -101.631242)
		)
		(stroke
			(width 0)
			(type solid)
		)
		(fill yes)
		(layer "In4.Cu")
		(net "M_M_DQS_DN<17>")
	)
	(gr_poly
		(pts
			(xy 80.860646 -99.778566) (xy 80.860646 -99.557586) (xy 80.690466 -99.468686) (xy 80.646016 -99.468686)
			(xy 80.646016 -99.867466) (xy 80.690466 -99.867466)
		)
		(stroke
			(width 0)
			(type solid)
		)
		(fill yes)
		(layer "In4.Cu")
		(net "M_M_DQS_DN<17>")
	)
	(gr_poly
		(pts
			(xy 80.860646 -66.108326) (xy 80.860646 -65.887346) (xy 80.690466 -65.798446) (xy 80.646016 -65.798446)
			(xy 80.646016 -66.197226) (xy 80.690466 -66.197226)
		)
		(stroke
			(width 0)
			(type solid)
		)
		(fill yes)
		(layer "In4.Cu")
		(net "M_J_DQS_DN<8>")
	)
	(gr_poly
		(pts
			(xy 80.8609 -98.798126) (xy 80.8609 -98.577146) (xy 80.69072 -98.488246) (xy 80.64627 -98.488246)
			(xy 80.64627 -98.887026) (xy 80.69072 -98.887026)
		)
		(stroke
			(width 0)
			(type solid)
		)
		(fill yes)
		(layer "In4.Cu")
		(net "M_M_DQS_DN<17>")
	)
	(gr_poly
		(pts
			(xy 80.8609 -97.807526) (xy 80.8609 -97.586546) (xy 80.69072 -97.497646) (xy 80.64627 -97.497646)
			(xy 80.64627 -97.896426) (xy 80.69072 -97.896426)
		)
		(stroke
			(width 0)
			(type solid)
		)
		(fill yes)
		(layer "In4.Cu")
		(net "M_M_DQS_DN<17>")
	)
	(gr_poly
		(pts
			(xy 80.8609 -96.816926) (xy 80.8609 -96.595946) (xy 80.69072 -96.507046) (xy 80.64627 -96.507046)
			(xy 80.64627 -96.905826) (xy 80.69072 -96.905826)
		)
		(stroke
			(width 0)
			(type solid)
		)
		(fill yes)
		(layer "In4.Cu")
		(net "M_M_DQS_DN<17>")
	)
	(gr_poly
		(pts
			(xy 80.8609 -95.826326) (xy 80.8609 -95.605346) (xy 80.69072 -95.516446) (xy 80.64627 -95.516446)
			(xy 80.64627 -95.915226) (xy 80.69072 -95.915226)
		)
		(stroke
			(width 0)
			(type solid)
		)
		(fill yes)
		(layer "In4.Cu")
		(net "M_M_DQS_DN<17>")
	)
	(gr_poly
		(pts
			(xy 80.8609 -94.829376) (xy 80.8609 -94.608396) (xy 80.69072 -94.519496) (xy 80.64627 -94.519496)
			(xy 80.64627 -94.918276) (xy 80.69072 -94.918276)
		)
		(stroke
			(width 0)
			(type solid)
		)
		(fill yes)
		(layer "In4.Cu")
		(net "M_M_DQS_DN<17>")
	)
	(gr_poly
		(pts
			(xy 80.8609 -93.83268) (xy 80.8609 -93.6117) (xy 80.69072 -93.5228) (xy 80.64627 -93.5228) (xy 80.64627 -93.92158)
			(xy 80.69072 -93.92158)
		)
		(stroke
			(width 0)
			(type solid)
		)
		(fill yes)
		(layer "In4.Cu")
		(net "M_M_DQS_DN<17>")
	)
	(gr_poly
		(pts
			(xy 80.8609 -92.854526) (xy 80.8609 -92.633546) (xy 80.69072 -92.544646) (xy 80.64627 -92.544646)
			(xy 80.64627 -92.943426) (xy 80.69072 -92.943426)
		)
		(stroke
			(width 0)
			(type solid)
		)
		(fill yes)
		(layer "In4.Cu")
		(net "M_M_DQS_DN<17>")
	)
	(gr_poly
		(pts
			(xy 80.8609 -91.863926) (xy 80.8609 -91.642946) (xy 80.69072 -91.554046) (xy 80.64627 -91.554046)
			(xy 80.64627 -91.952826) (xy 80.69072 -91.952826)
		)
		(stroke
			(width 0)
			(type solid)
		)
		(fill yes)
		(layer "In4.Cu")
		(net "M_M_DQS_DN<17>")
	)
	(gr_poly
		(pts
			(xy 80.8609 -90.873326) (xy 80.8609 -90.652346) (xy 80.69072 -90.563446) (xy 80.64627 -90.563446)
			(xy 80.64627 -90.962226) (xy 80.69072 -90.962226)
		)
		(stroke
			(width 0)
			(type solid)
		)
		(fill yes)
		(layer "In4.Cu")
		(net "M_M_DQS_DN<17>")
	)
	(gr_poly
		(pts
			(xy 80.8609 -89.882726) (xy 80.8609 -89.661746) (xy 80.69072 -89.572846) (xy 80.64627 -89.572846)
			(xy 80.64627 -89.971626) (xy 80.69072 -89.971626)
		)
		(stroke
			(width 0)
			(type solid)
		)
		(fill yes)
		(layer "In4.Cu")
		(net "M_M_DQS_DN<17>")
	)
	(gr_poly
		(pts
			(xy 80.8609 -88.892126) (xy 80.8609 -88.671146) (xy 80.69072 -88.582246) (xy 80.64627 -88.582246)
			(xy 80.64627 -88.981026) (xy 80.69072 -88.981026)
		)
		(stroke
			(width 0)
			(type solid)
		)
		(fill yes)
		(layer "In4.Cu")
		(net "M_M_DQS_DN<17>")
	)
	(gr_poly
		(pts
			(xy 80.8609 -87.901526) (xy 80.8609 -87.680546) (xy 80.69072 -87.591646) (xy 80.64627 -87.591646)
			(xy 80.64627 -87.990426) (xy 80.69072 -87.990426)
		)
		(stroke
			(width 0)
			(type solid)
		)
		(fill yes)
		(layer "In4.Cu")
		(net "M_M_DQS_DN<17>")
	)
	(gr_poly
		(pts
			(xy 80.8609 -86.910926) (xy 80.8609 -86.689946) (xy 80.69072 -86.601046) (xy 80.64627 -86.601046)
			(xy 80.64627 -86.999826) (xy 80.69072 -86.999826)
		)
		(stroke
			(width 0)
			(type solid)
		)
		(fill yes)
		(layer "In4.Cu")
		(net "M_M_DQS_DN<17>")
	)
	(gr_poly
		(pts
			(xy 80.8609 -85.920326) (xy 80.8609 -85.699346) (xy 80.69072 -85.610446) (xy 80.64627 -85.610446)
			(xy 80.64627 -86.009226) (xy 80.69072 -86.009226)
		)
		(stroke
			(width 0)
			(type solid)
		)
		(fill yes)
		(layer "In4.Cu")
		(net "M_M_DQS_DN<17>")
	)
	(gr_poly
		(pts
			(xy 80.8609 -84.929726) (xy 80.8609 -84.708746) (xy 80.69072 -84.619846) (xy 80.64627 -84.619846)
			(xy 80.64627 -85.018626) (xy 80.69072 -85.018626)
		)
		(stroke
			(width 0)
			(type solid)
		)
		(fill yes)
		(layer "In4.Cu")
		(net "M_M_DQS_DN<17>")
	)
	(gr_poly
		(pts
			(xy 80.8609 -83.939126) (xy 80.8609 -83.718146) (xy 80.69072 -83.629246) (xy 80.64627 -83.629246)
			(xy 80.64627 -84.028026) (xy 80.69072 -84.028026)
		)
		(stroke
			(width 0)
			(type solid)
		)
		(fill yes)
		(layer "In4.Cu")
		(net "M_M_DQS_DN<17>")
	)
	(gr_poly
		(pts
			(xy 80.8609 -67.092576) (xy 80.8609 -66.871596) (xy 80.69072 -66.782696) (xy 80.64627 -66.782696)
			(xy 80.64627 -67.181476) (xy 80.69072 -67.181476)
		)
		(stroke
			(width 0)
			(type solid)
		)
		(fill yes)
		(layer "In4.Cu")
		(net "M_J_DQS_DN<8>")
	)
	(gr_poly
		(pts
			(xy 80.8609 -65.117726) (xy 80.8609 -64.896746) (xy 80.69072 -64.807846) (xy 80.64627 -64.807846)
			(xy 80.64627 -65.206626) (xy 80.69072 -65.206626)
		)
		(stroke
			(width 0)
			(type solid)
		)
		(fill yes)
		(layer "In4.Cu")
		(net "M_J_DQS_DN<8>")
	)
	(gr_poly
		(pts
			(xy 80.8609 -64.127126) (xy 80.8609 -63.906146) (xy 80.69072 -63.817246) (xy 80.64627 -63.817246)
			(xy 80.64627 -64.216026) (xy 80.69072 -64.216026)
		)
		(stroke
			(width 0)
			(type solid)
		)
		(fill yes)
		(layer "In4.Cu")
		(net "M_J_DQS_DN<8>")
	)
	(gr_poly
		(pts
			(xy 80.8609 -63.136526) (xy 80.8609 -62.915546) (xy 80.69072 -62.826646) (xy 80.64627 -62.826646)
			(xy 80.64627 -63.225426) (xy 80.69072 -63.225426)
		)
		(stroke
			(width 0)
			(type solid)
		)
		(fill yes)
		(layer "In4.Cu")
		(net "M_J_DQS_DN<8>")
	)
	(gr_poly
		(pts
			(xy 80.8609 -62.145926) (xy 80.8609 -61.924946) (xy 80.69072 -61.836046) (xy 80.64627 -61.836046)
			(xy 80.64627 -62.234826) (xy 80.69072 -62.234826)
		)
		(stroke
			(width 0)
			(type solid)
		)
		(fill yes)
		(layer "In4.Cu")
		(net "M_J_DQS_DN<8>")
	)
	(gr_poly
		(pts
			(xy 80.8609 -61.155326) (xy 80.8609 -60.934346) (xy 80.69072 -60.845446) (xy 80.64627 -60.845446)
			(xy 80.64627 -61.244226) (xy 80.69072 -61.244226)
		)
		(stroke
			(width 0)
			(type solid)
		)
		(fill yes)
		(layer "In4.Cu")
		(net "M_J_DQS_DN<8>")
	)
	(gr_poly
		(pts
			(xy 80.8609 -60.164726) (xy 80.8609 -59.943746) (xy 80.69072 -59.854846) (xy 80.64627 -59.854846)
			(xy 80.64627 -60.253626) (xy 80.69072 -60.253626)
		)
		(stroke
			(width 0)
			(type solid)
		)
		(fill yes)
		(layer "In4.Cu")
		(net "M_J_DQS_DN<8>")
	)
	(gr_poly
		(pts
			(xy 80.8609 -59.167776) (xy 80.8609 -58.946796) (xy 80.69072 -58.857896) (xy 80.64627 -58.857896)
			(xy 80.64627 -59.256676) (xy 80.69072 -59.256676)
		)
		(stroke
			(width 0)
			(type solid)
		)
		(fill yes)
		(layer "In4.Cu")
		(net "M_J_DQS_DN<8>")
	)
	(gr_poly
		(pts
			(xy 80.8609 -58.17108) (xy 80.8609 -57.9501) (xy 80.69072 -57.8612) (xy 80.64627 -57.8612) (xy 80.64627 -58.25998)
			(xy 80.69072 -58.25998)
		)
		(stroke
			(width 0)
			(type solid)
		)
		(fill yes)
		(layer "In4.Cu")
		(net "M_J_DQS_DN<8>")
	)
	(gr_poly
		(pts
			(xy 80.8609 -57.192926) (xy 80.8609 -56.971946) (xy 80.69072 -56.883046) (xy 80.64627 -56.883046)
			(xy 80.64627 -57.281826) (xy 80.69072 -57.281826)
		)
		(stroke
			(width 0)
			(type solid)
		)
		(fill yes)
		(layer "In4.Cu")
		(net "M_J_DQS_DN<8>")
	)
	(gr_poly
		(pts
			(xy 80.8609 -56.202326) (xy 80.8609 -55.981346) (xy 80.69072 -55.892446) (xy 80.64627 -55.892446)
			(xy 80.64627 -56.291226) (xy 80.69072 -56.291226)
		)
		(stroke
			(width 0)
			(type solid)
		)
		(fill yes)
		(layer "In4.Cu")
		(net "M_J_DQS_DN<8>")
	)
	(gr_poly
		(pts
			(xy 80.888332 -51.758088) (xy 80.843882 -51.758088) (xy 80.650842 -51.846988) (xy 80.650842 -52.075588)
			(xy 80.843882 -52.164488) (xy 80.888332 -52.164488)
		)
		(stroke
			(width 0)
			(type solid)
		)
		(fill yes)
		(layer "In4.Cu")
		(net "M_J_DQS_DP<8>")
	)
	(gr_poly
		(pts
			(xy 80.888332 -50.767488) (xy 80.843882 -50.767488) (xy 80.650842 -50.856388) (xy 80.650842 -51.084988)
			(xy 80.843882 -51.173888) (xy 80.888332 -51.173888)
		)
		(stroke
			(width 0)
			(type solid)
		)
		(fill yes)
		(layer "In4.Cu")
		(net "M_J_DQS_DP<8>")
	)
	(gr_poly
		(pts
			(xy 80.894682 -101.351334) (xy 80.850232 -101.351334) (xy 80.657192 -101.440234) (xy 80.657192 -101.668834)
			(xy 80.850232 -101.757734) (xy 80.894682 -101.757734)
		)
		(stroke
			(width 0)
			(type solid)
		)
		(fill yes)
		(layer "In4.Cu")
		(net "M_M_DQS_DN<8>")
	)
	(gr_poly
		(pts
			(xy 80.915002 -55.085234) (xy 80.915002 -54.856634) (xy 80.721962 -54.767734) (xy 80.677512 -54.767734)
			(xy 80.677512 -55.174134) (xy 80.721962 -55.174134)
		)
		(stroke
			(width 0)
			(type solid)
		)
		(fill yes)
		(layer "In4.Cu")
		(net "M_J_DQS_DN<8>")
	)
	(gr_poly
		(pts
			(xy 80.915002 -54.196234) (xy 80.915002 -53.967634) (xy 80.721962 -53.878734) (xy 80.677512 -53.878734)
			(xy 80.677512 -54.285134) (xy 80.721962 -54.285134)
		)
		(stroke
			(width 0)
			(type solid)
		)
		(fill yes)
		(layer "In4.Cu")
		(net "M_J_DQS_DN<8>")
	)
	(gr_poly
		(pts
			(xy 80.915002 -53.205634) (xy 80.915002 -52.977034) (xy 80.721962 -52.888134) (xy 80.677512 -52.888134)
			(xy 80.677512 -53.294534) (xy 80.721962 -53.294534)
		)
		(stroke
			(width 0)
			(type solid)
		)
		(fill yes)
		(layer "In4.Cu")
		(net "M_J_DQS_DN<8>")
	)
	(gr_poly
		(pts
			(xy 81.119472 -102.748334) (xy 81.075022 -102.748334) (xy 80.881982 -102.837234) (xy 80.881982 -103.065834)
			(xy 81.075022 -103.154734) (xy 81.119472 -103.154734)
		)
		(stroke
			(width 0)
			(type solid)
		)
		(fill yes)
		(layer "In4.Cu")
		(net "M_M_DQS_DN<8>")
	)
	(gr_poly
		(pts
			(xy 81.181194 -96.507046) (xy 81.136744 -96.507046) (xy 80.966564 -96.595946) (xy 80.966564 -96.816926)
			(xy 81.136744 -96.905826) (xy 81.181194 -96.905826)
		)
		(stroke
			(width 0)
			(type solid)
		)
		(fill yes)
		(layer "In4.Cu")
		(net "M_M_DQS_DN<8>")
	)
	(gr_poly
		(pts
			(xy 81.181194 -95.516446) (xy 81.136744 -95.516446) (xy 80.966564 -95.605346) (xy 80.966564 -95.826326)
			(xy 81.136744 -95.915226) (xy 81.181194 -95.915226)
		)
		(stroke
			(width 0)
			(type solid)
		)
		(fill yes)
		(layer "In4.Cu")
		(net "M_M_DQS_DN<8>")
	)
	(gr_poly
		(pts
			(xy 81.181194 -94.519496) (xy 81.136744 -94.519496) (xy 80.966564 -94.608396) (xy 80.966564 -94.829376)
			(xy 81.136744 -94.918276) (xy 81.181194 -94.918276)
		)
		(stroke
			(width 0)
			(type solid)
		)
		(fill yes)
		(layer "In4.Cu")
		(net "M_M_DQS_DN<8>")
	)
	(gr_poly
		(pts
			(xy 81.181194 -93.5228) (xy 81.136744 -93.5228) (xy 80.966564 -93.6117) (xy 80.966564 -93.83268)
			(xy 81.136744 -93.92158) (xy 81.181194 -93.92158)
		)
		(stroke
			(width 0)
			(type solid)
		)
		(fill yes)
		(layer "In4.Cu")
		(net "M_M_DQS_DN<8>")
	)
	(gr_poly
		(pts
			(xy 81.181194 -92.544646) (xy 81.136744 -92.544646) (xy 80.966564 -92.633546) (xy 80.966564 -92.854526)
			(xy 81.136744 -92.943426) (xy 81.181194 -92.943426)
		)
		(stroke
			(width 0)
			(type solid)
		)
		(fill yes)
		(layer "In4.Cu")
		(net "M_M_DQS_DN<8>")
	)
	(gr_poly
		(pts
			(xy 81.181194 -91.554046) (xy 81.136744 -91.554046) (xy 80.966564 -91.642946) (xy 80.966564 -91.863926)
			(xy 81.136744 -91.952826) (xy 81.181194 -91.952826)
		)
		(stroke
			(width 0)
			(type solid)
		)
		(fill yes)
		(layer "In4.Cu")
		(net "M_M_DQS_DN<8>")
	)
	(gr_poly
		(pts
			(xy 81.181194 -90.563446) (xy 81.136744 -90.563446) (xy 80.966564 -90.652346) (xy 80.966564 -90.873326)
			(xy 81.136744 -90.962226) (xy 81.181194 -90.962226)
		)
		(stroke
			(width 0)
			(type solid)
		)
		(fill yes)
		(layer "In4.Cu")
		(net "M_M_DQS_DN<8>")
	)
	(gr_poly
		(pts
			(xy 81.181194 -89.572846) (xy 81.136744 -89.572846) (xy 80.966564 -89.661746) (xy 80.966564 -89.882726)
			(xy 81.136744 -89.971626) (xy 81.181194 -89.971626)
		)
		(stroke
			(width 0)
			(type solid)
		)
		(fill yes)
		(layer "In4.Cu")
		(net "M_M_DQS_DN<8>")
	)
	(gr_poly
		(pts
			(xy 81.181194 -88.582246) (xy 81.136744 -88.582246) (xy 80.966564 -88.671146) (xy 80.966564 -88.892126)
			(xy 81.136744 -88.981026) (xy 81.181194 -88.981026)
		)
		(stroke
			(width 0)
			(type solid)
		)
		(fill yes)
		(layer "In4.Cu")
		(net "M_M_DQS_DN<8>")
	)
	(gr_poly
		(pts
			(xy 81.181194 -87.591646) (xy 81.136744 -87.591646) (xy 80.966564 -87.680546) (xy 80.966564 -87.901526)
			(xy 81.136744 -87.990426) (xy 81.181194 -87.990426)
		)
		(stroke
			(width 0)
			(type solid)
		)
		(fill yes)
		(layer "In4.Cu")
		(net "M_M_DQS_DN<8>")
	)
	(gr_poly
		(pts
			(xy 81.181194 -86.601046) (xy 81.136744 -86.601046) (xy 80.966564 -86.689946) (xy 80.966564 -86.910926)
			(xy 81.136744 -86.999826) (xy 81.181194 -86.999826)
		)
		(stroke
			(width 0)
			(type solid)
		)
		(fill yes)
		(layer "In4.Cu")
		(net "M_M_DQS_DN<8>")
	)
	(gr_poly
		(pts
			(xy 81.181194 -64.807846) (xy 81.136744 -64.807846) (xy 80.966564 -64.896746) (xy 80.966564 -65.117726)
			(xy 81.136744 -65.206626) (xy 81.181194 -65.206626)
		)
		(stroke
			(width 0)
			(type solid)
		)
		(fill yes)
		(layer "In4.Cu")
		(net "M_J_ECC<6>")
	)
	(gr_poly
		(pts
			(xy 81.181194 -63.817246) (xy 81.136744 -63.817246) (xy 80.966564 -63.906146) (xy 80.966564 -64.127126)
			(xy 81.136744 -64.216026) (xy 81.181194 -64.216026)
		)
		(stroke
			(width 0)
			(type solid)
		)
		(fill yes)
		(layer "In4.Cu")
		(net "M_J_ECC<6>")
	)
	(gr_poly
		(pts
			(xy 81.181194 -62.826646) (xy 81.136744 -62.826646) (xy 80.966564 -62.915546) (xy 80.966564 -63.136526)
			(xy 81.136744 -63.225426) (xy 81.181194 -63.225426)
		)
		(stroke
			(width 0)
			(type solid)
		)
		(fill yes)
		(layer "In4.Cu")
		(net "M_J_ECC<6>")
	)
	(gr_poly
		(pts
			(xy 81.181194 -61.836046) (xy 81.136744 -61.836046) (xy 80.966564 -61.924946) (xy 80.966564 -62.145926)
			(xy 81.136744 -62.234826) (xy 81.181194 -62.234826)
		)
		(stroke
			(width 0)
			(type solid)
		)
		(fill yes)
		(layer "In4.Cu")
		(net "M_J_ECC<6>")
	)
	(gr_poly
		(pts
			(xy 81.181194 -60.845446) (xy 81.136744 -60.845446) (xy 80.966564 -60.934346) (xy 80.966564 -61.155326)
			(xy 81.136744 -61.244226) (xy 81.181194 -61.244226)
		)
		(stroke
			(width 0)
			(type solid)
		)
		(fill yes)
		(layer "In4.Cu")
		(net "M_J_ECC<6>")
	)
	(gr_poly
		(pts
			(xy 81.181194 -59.854846) (xy 81.136744 -59.854846) (xy 80.966564 -59.943746) (xy 80.966564 -60.164726)
			(xy 81.136744 -60.253626) (xy 81.181194 -60.253626)
		)
		(stroke
			(width 0)
			(type solid)
		)
		(fill yes)
		(layer "In4.Cu")
		(net "M_J_ECC<6>")
	)
	(gr_poly
		(pts
			(xy 81.181194 -58.857896) (xy 81.136744 -58.857896) (xy 80.966564 -58.946796) (xy 80.966564 -59.167776)
			(xy 81.136744 -59.256676) (xy 81.181194 -59.256676)
		)
		(stroke
			(width 0)
			(type solid)
		)
		(fill yes)
		(layer "In4.Cu")
		(net "M_J_ECC<6>")
	)
	(gr_poly
		(pts
			(xy 81.181194 -57.8612) (xy 81.136744 -57.8612) (xy 80.966564 -57.9501) (xy 80.966564 -58.17108)
			(xy 81.136744 -58.25998) (xy 81.181194 -58.25998)
		)
		(stroke
			(width 0)
			(type solid)
		)
		(fill yes)
		(layer "In4.Cu")
		(net "M_J_ECC<6>")
	)
	(gr_poly
		(pts
			(xy 81.181194 -56.883046) (xy 81.136744 -56.883046) (xy 80.966564 -56.971946) (xy 80.966564 -57.192926)
			(xy 81.136744 -57.281826) (xy 81.181194 -57.281826)
		)
		(stroke
			(width 0)
			(type solid)
		)
		(fill yes)
		(layer "In4.Cu")
		(net "M_J_ECC<6>")
	)
	(gr_poly
		(pts
			(xy 81.181194 -55.892446) (xy 81.136744 -55.892446) (xy 80.966564 -55.981346) (xy 80.966564 -56.202326)
			(xy 81.136744 -56.291226) (xy 81.181194 -56.291226)
		)
		(stroke
			(width 0)
			(type solid)
		)
		(fill yes)
		(layer "In4.Cu")
		(net "M_J_ECC<6>")
	)
	(gr_poly
		(pts
			(xy 81.181448 -65.798446) (xy 81.136998 -65.798446) (xy 80.966818 -65.887346) (xy 80.966818 -66.108326)
			(xy 81.136998 -66.197226) (xy 81.181448 -66.197226)
		)
		(stroke
			(width 0)
			(type solid)
		)
		(fill yes)
		(layer "In4.Cu")
		(net "M_J_ECC<6>")
	)
	(gr_poly
		(pts
			(xy 81.184242 -66.799206) (xy 81.139792 -66.798698) (xy 80.968342 -66.885058) (xy 80.96504 -67.106038)
			(xy 81.13395 -67.197478) (xy 81.178654 -67.197986)
		)
		(stroke
			(width 0)
			(type solid)
		)
		(fill yes)
		(layer "In4.Cu")
		(net "M_J_ECC<6>")
	)
	(gr_poly
		(pts
			(xy 81.254092 -54.483762) (xy 81.209642 -54.483762) (xy 81.016602 -54.572662) (xy 81.016602 -54.801262)
			(xy 81.209642 -54.890162) (xy 81.254092 -54.890162)
		)
		(stroke
			(width 0)
			(type solid)
		)
		(fill yes)
		(layer "In4.Cu")
		(net "M_J_ECC<6>")
	)
	(gr_poly
		(pts
			(xy 81.254092 -53.493162) (xy 81.209642 -53.493162) (xy 81.016602 -53.582062) (xy 81.016602 -53.810662)
			(xy 81.209642 -53.899562) (xy 81.254092 -53.899562)
		)
		(stroke
			(width 0)
			(type solid)
		)
		(fill yes)
		(layer "In4.Cu")
		(net "M_J_ECC<6>")
	)
	(gr_poly
		(pts
			(xy 81.316322 -52.202588) (xy 81.316322 -51.973988) (xy 81.123282 -51.885088) (xy 81.078832 -51.885088)
			(xy 81.078832 -52.291488) (xy 81.123282 -52.291488)
		)
		(stroke
			(width 0)
			(type solid)
		)
		(fill yes)
		(layer "In4.Cu")
		(net "M_J_DQS_DN<8>")
	)
	(gr_poly
		(pts
			(xy 81.316322 -51.211988) (xy 81.316322 -50.983388) (xy 81.123282 -50.894488) (xy 81.078832 -50.894488)
			(xy 81.078832 -51.300888) (xy 81.123282 -51.300888)
		)
		(stroke
			(width 0)
			(type solid)
		)
		(fill yes)
		(layer "In4.Cu")
		(net "M_J_DQS_DN<8>")
	)
	(gr_poly
		(pts
			(xy 81.317592 -99.522534) (xy 81.273142 -99.522534) (xy 81.080102 -99.611434) (xy 81.080102 -99.840034)
			(xy 81.273142 -99.928934) (xy 81.317592 -99.928934)
		)
		(stroke
			(width 0)
			(type solid)
		)
		(fill yes)
		(layer "In4.Cu")
		(net "M_M_DQS_DN<8>")
	)
	(gr_poly
		(pts
			(xy 81.317592 -98.531934) (xy 81.273142 -98.531934) (xy 81.080102 -98.620834) (xy 81.080102 -98.849434)
			(xy 81.273142 -98.938334) (xy 81.317592 -98.938334)
		)
		(stroke
			(width 0)
			(type solid)
		)
		(fill yes)
		(layer "In4.Cu")
		(net "M_M_DQS_DN<8>")
	)
	(gr_poly
		(pts
			(xy 81.317592 -97.541334) (xy 81.273142 -97.541334) (xy 81.080102 -97.630234) (xy 81.080102 -97.858834)
			(xy 81.273142 -97.947734) (xy 81.317592 -97.947734)
		)
		(stroke
			(width 0)
			(type solid)
		)
		(fill yes)
		(layer "In4.Cu")
		(net "M_M_DQS_DN<8>")
	)
	(gr_poly
		(pts
			(xy 81.322672 -101.668834) (xy 81.322672 -101.440234) (xy 81.129632 -101.351334) (xy 81.085182 -101.351334)
			(xy 81.085182 -101.757734) (xy 81.129632 -101.757734)
		)
		(stroke
			(width 0)
			(type solid)
		)
		(fill yes)
		(layer "In4.Cu")
		(net "M_M_DQS_DP<8>")
	)
	(gr_poly
		(pts
			(xy 81.371948 -83.627976) (xy 81.327498 -83.627976) (xy 81.157318 -83.716876) (xy 81.157318 -83.937856)
			(xy 81.327498 -84.026756) (xy 81.371948 -84.026756)
		)
		(stroke
			(width 0)
			(type solid)
		)
		(fill yes)
		(layer "In4.Cu")
		(net "M_M_ECC<6>")
	)
	(gr_poly
		(pts
			(xy 81.547462 -103.065834) (xy 81.547462 -102.837234) (xy 81.354422 -102.748334) (xy 81.309972 -102.748334)
			(xy 81.309972 -103.154734) (xy 81.354422 -103.154734)
		)
		(stroke
			(width 0)
			(type solid)
		)
		(fill yes)
		(layer "In4.Cu")
		(net "M_M_DQS_DP<8>")
	)
	(gr_poly
		(pts
			(xy 81.682082 -54.801262) (xy 81.682082 -54.572662) (xy 81.489042 -54.483762) (xy 81.444592 -54.483762)
			(xy 81.444592 -54.890162) (xy 81.489042 -54.890162)
		)
		(stroke
			(width 0)
			(type solid)
		)
		(fill yes)
		(layer "In4.Cu")
		(net "M_J_ECC<7>")
	)
	(gr_poly
		(pts
			(xy 81.682082 -53.810662) (xy 81.682082 -53.582062) (xy 81.489042 -53.493162) (xy 81.444592 -53.493162)
			(xy 81.444592 -53.899562) (xy 81.489042 -53.899562)
		)
		(stroke
			(width 0)
			(type solid)
		)
		(fill yes)
		(layer "In4.Cu")
		(net "M_J_ECC<7>")
	)
	(gr_poly
		(pts
			(xy 81.70418 -52.611528) (xy 81.672938 -52.580032) (xy 81.473548 -52.506372) (xy 81.31175 -52.667916)
			(xy 81.38541 -52.867306) (xy 81.416906 -52.898802)
		)
		(stroke
			(width 0)
			(type solid)
		)
		(fill yes)
		(layer "In4.Cu")
		(net "M_J_ECC<6>")
	)
	(gr_poly
		(pts
			(xy 81.71942 -96.30918) (xy 81.71942 -96.0882) (xy 81.54924 -95.9993) (xy 81.50479 -95.9993) (xy 81.50479 -96.39808)
			(xy 81.54924 -96.39808)
		)
		(stroke
			(width 0)
			(type solid)
		)
		(fill yes)
		(layer "In4.Cu")
		(net "M_M_DQS_DP<8>")
	)
	(gr_poly
		(pts
			(xy 81.71942 -95.31858) (xy 81.71942 -95.0976) (xy 81.54924 -95.0087) (xy 81.50479 -95.0087) (xy 81.50479 -95.40748)
			(xy 81.54924 -95.40748)
		)
		(stroke
			(width 0)
			(type solid)
		)
		(fill yes)
		(layer "In4.Cu")
		(net "M_M_DQS_DP<8>")
	)
	(gr_poly
		(pts
			(xy 81.71942 -94.340426) (xy 81.71942 -94.119446) (xy 81.54924 -94.030546) (xy 81.50479 -94.030546)
			(xy 81.50479 -94.429326) (xy 81.54924 -94.429326)
		)
		(stroke
			(width 0)
			(type solid)
		)
		(fill yes)
		(layer "In4.Cu")
		(net "M_M_DQS_DP<8>")
	)
	(gr_poly
		(pts
			(xy 81.71942 -93.34373) (xy 81.71942 -93.12275) (xy 81.54924 -93.03385) (xy 81.50479 -93.03385) (xy 81.50479 -93.43263)
			(xy 81.54924 -93.43263)
		)
		(stroke
			(width 0)
			(type solid)
		)
		(fill yes)
		(layer "In4.Cu")
		(net "M_M_DQS_DP<8>")
	)
	(gr_poly
		(pts
			(xy 81.71942 -92.34678) (xy 81.71942 -92.1258) (xy 81.54924 -92.0369) (xy 81.50479 -92.0369) (xy 81.50479 -92.43568)
			(xy 81.54924 -92.43568)
		)
		(stroke
			(width 0)
			(type solid)
		)
		(fill yes)
		(layer "In4.Cu")
		(net "M_M_DQS_DP<8>")
	)
	(gr_poly
		(pts
			(xy 81.71942 -91.35618) (xy 81.71942 -91.1352) (xy 81.54924 -91.0463) (xy 81.50479 -91.0463) (xy 81.50479 -91.44508)
			(xy 81.54924 -91.44508)
		)
		(stroke
			(width 0)
			(type solid)
		)
		(fill yes)
		(layer "In4.Cu")
		(net "M_M_DQS_DP<8>")
	)
	(gr_poly
		(pts
			(xy 81.71942 -90.36558) (xy 81.71942 -90.1446) (xy 81.54924 -90.0557) (xy 81.50479 -90.0557) (xy 81.50479 -90.45448)
			(xy 81.54924 -90.45448)
		)
		(stroke
			(width 0)
			(type solid)
		)
		(fill yes)
		(layer "In4.Cu")
		(net "M_M_DQS_DP<8>")
	)
	(gr_poly
		(pts
			(xy 81.71942 -89.37498) (xy 81.71942 -89.154) (xy 81.54924 -89.0651) (xy 81.50479 -89.0651) (xy 81.50479 -89.46388)
			(xy 81.54924 -89.46388)
		)
		(stroke
			(width 0)
			(type solid)
		)
		(fill yes)
		(layer "In4.Cu")
		(net "M_M_DQS_DP<8>")
	)
	(gr_poly
		(pts
			(xy 81.71942 -88.38438) (xy 81.71942 -88.1634) (xy 81.54924 -88.0745) (xy 81.50479 -88.0745) (xy 81.50479 -88.47328)
			(xy 81.54924 -88.47328)
		)
		(stroke
			(width 0)
			(type solid)
		)
		(fill yes)
		(layer "In4.Cu")
		(net "M_M_DQS_DP<8>")
	)
	(gr_poly
		(pts
			(xy 81.71942 -87.39378) (xy 81.71942 -87.1728) (xy 81.54924 -87.0839) (xy 81.50479 -87.0839) (xy 81.50479 -87.48268)
			(xy 81.54924 -87.48268)
		)
		(stroke
			(width 0)
			(type solid)
		)
		(fill yes)
		(layer "In4.Cu")
		(net "M_M_DQS_DP<8>")
	)
	(gr_poly
		(pts
			(xy 81.71942 -86.40318) (xy 81.71942 -86.1822) (xy 81.54924 -86.0933) (xy 81.50479 -86.0933) (xy 81.50479 -86.49208)
			(xy 81.54924 -86.49208)
		)
		(stroke
			(width 0)
			(type solid)
		)
		(fill yes)
		(layer "In4.Cu")
		(net "M_M_DQS_DP<8>")
	)
	(gr_poly
		(pts
			(xy 81.71942 -84.42198) (xy 81.71942 -84.201) (xy 81.54924 -84.1121) (xy 81.50479 -84.1121) (xy 81.50479 -84.51088)
			(xy 81.54924 -84.51088)
		)
		(stroke
			(width 0)
			(type solid)
		)
		(fill yes)
		(layer "In4.Cu")
		(net "M_M_ECC<6>")
	)
	(gr_poly
		(pts
			(xy 81.71942 -66.597276) (xy 81.71942 -66.376296) (xy 81.54924 -66.287396) (xy 81.50479 -66.287396)
			(xy 81.50479 -66.686176) (xy 81.54924 -66.686176)
		)
		(stroke
			(width 0)
			(type solid)
		)
		(fill yes)
		(layer "In4.Cu")
		(net "M_J_ECC<7>")
	)
	(gr_poly
		(pts
			(xy 81.71942 -65.60058) (xy 81.71942 -65.3796) (xy 81.54924 -65.2907) (xy 81.50479 -65.2907) (xy 81.50479 -65.68948)
			(xy 81.54924 -65.68948)
		)
		(stroke
			(width 0)
			(type solid)
		)
		(fill yes)
		(layer "In4.Cu")
		(net "M_J_ECC<7>")
	)
	(gr_poly
		(pts
			(xy 81.71942 -64.60998) (xy 81.71942 -64.389) (xy 81.54924 -64.3001) (xy 81.50479 -64.3001) (xy 81.50479 -64.69888)
			(xy 81.54924 -64.69888)
		)
		(stroke
			(width 0)
			(type solid)
		)
		(fill yes)
		(layer "In4.Cu")
		(net "M_J_ECC<7>")
	)
	(gr_poly
		(pts
			(xy 81.71942 -63.61938) (xy 81.71942 -63.3984) (xy 81.54924 -63.3095) (xy 81.50479 -63.3095) (xy 81.50479 -63.70828)
			(xy 81.54924 -63.70828)
		)
		(stroke
			(width 0)
			(type solid)
		)
		(fill yes)
		(layer "In4.Cu")
		(net "M_J_ECC<7>")
	)
	(gr_poly
		(pts
			(xy 81.71942 -62.62878) (xy 81.71942 -62.4078) (xy 81.54924 -62.3189) (xy 81.50479 -62.3189) (xy 81.50479 -62.71768)
			(xy 81.54924 -62.71768)
		)
		(stroke
			(width 0)
			(type solid)
		)
		(fill yes)
		(layer "In4.Cu")
		(net "M_J_ECC<7>")
	)
	(gr_poly
		(pts
			(xy 81.71942 -61.63818) (xy 81.71942 -61.4172) (xy 81.54924 -61.3283) (xy 81.50479 -61.3283) (xy 81.50479 -61.72708)
			(xy 81.54924 -61.72708)
		)
		(stroke
			(width 0)
			(type solid)
		)
		(fill yes)
		(layer "In4.Cu")
		(net "M_J_ECC<7>")
	)
	(gr_poly
		(pts
			(xy 81.71942 -60.64758) (xy 81.71942 -60.4266) (xy 81.54924 -60.3377) (xy 81.50479 -60.3377) (xy 81.50479 -60.73648)
			(xy 81.54924 -60.73648)
		)
		(stroke
			(width 0)
			(type solid)
		)
		(fill yes)
		(layer "In4.Cu")
		(net "M_J_ECC<7>")
	)
	(gr_poly
		(pts
			(xy 81.71942 -59.65698) (xy 81.71942 -59.436) (xy 81.54924 -59.3471) (xy 81.50479 -59.3471) (xy 81.50479 -59.74588)
			(xy 81.54924 -59.74588)
		)
		(stroke
			(width 0)
			(type solid)
		)
		(fill yes)
		(layer "In4.Cu")
		(net "M_J_ECC<7>")
	)
	(gr_poly
		(pts
			(xy 81.71942 -58.678826) (xy 81.71942 -58.457846) (xy 81.54924 -58.368946) (xy 81.50479 -58.368946)
			(xy 81.50479 -58.767726) (xy 81.54924 -58.767726)
		)
		(stroke
			(width 0)
			(type solid)
		)
		(fill yes)
		(layer "In4.Cu")
		(net "M_J_ECC<7>")
	)
	(gr_poly
		(pts
			(xy 81.71942 -57.68213) (xy 81.71942 -57.46115) (xy 81.54924 -57.37225) (xy 81.50479 -57.37225) (xy 81.50479 -57.77103)
			(xy 81.54924 -57.77103)
		)
		(stroke
			(width 0)
			(type solid)
		)
		(fill yes)
		(layer "In4.Cu")
		(net "M_J_ECC<7>")
	)
	(gr_poly
		(pts
			(xy 81.71942 -56.68518) (xy 81.71942 -56.4642) (xy 81.54924 -56.3753) (xy 81.50479 -56.3753) (xy 81.50479 -56.77408)
			(xy 81.54924 -56.77408)
		)
		(stroke
			(width 0)
			(type solid)
		)
		(fill yes)
		(layer "In4.Cu")
		(net "M_J_ECC<7>")
	)
	(gr_poly
		(pts
			(xy 81.745582 -99.840034) (xy 81.745582 -99.611434) (xy 81.552542 -99.522534) (xy 81.508092 -99.522534)
			(xy 81.508092 -99.928934) (xy 81.552542 -99.928934)
		)
		(stroke
			(width 0)
			(type solid)
		)
		(fill yes)
		(layer "In4.Cu")
		(net "M_M_DQS_DP<8>")
	)
	(gr_poly
		(pts
			(xy 81.745582 -98.849434) (xy 81.745582 -98.620834) (xy 81.552542 -98.531934) (xy 81.508092 -98.531934)
			(xy 81.508092 -98.938334) (xy 81.552542 -98.938334)
		)
		(stroke
			(width 0)
			(type solid)
		)
		(fill yes)
		(layer "In4.Cu")
		(net "M_M_DQS_DP<8>")
	)
	(gr_poly
		(pts
			(xy 81.745582 -97.858834) (xy 81.745582 -97.630234) (xy 81.552542 -97.541334) (xy 81.508092 -97.541334)
			(xy 81.508092 -97.947734) (xy 81.552542 -97.947734)
		)
		(stroke
			(width 0)
			(type solid)
		)
		(fill yes)
		(layer "In4.Cu")
		(net "M_M_DQS_DP<8>")
	)
	(gr_poly
		(pts
			(xy 81.774792 -100.965254) (xy 81.730342 -100.965254) (xy 81.537302 -101.054154) (xy 81.537302 -101.282754)
			(xy 81.730342 -101.371654) (xy 81.774792 -101.371654)
		)
		(stroke
			(width 0)
			(type solid)
		)
		(fill yes)
		(layer "In4.Cu")
		(net "M_M_ECC<6>")
	)
	(gr_poly
		(pts
			(xy 81.827116 -85.352636) (xy 81.849468 -85.314282) (xy 81.504028 -85.114892) (xy 81.481676 -85.153246)
			(xy 81.473548 -85.345016) (xy 81.665064 -85.455506)
		)
		(stroke
			(width 0)
			(type solid)
		)
		(fill yes)
		(layer "In4.Cu")
		(net "M_M_ECC<6>")
	)
	(gr_poly
		(pts
			(xy 81.879186 -51.91252) (xy 81.834736 -51.912266) (xy 81.641696 -52.001166) (xy 81.641442 -52.229766)
			(xy 81.834736 -52.318666) (xy 81.879186 -52.318666)
		)
		(stroke
			(width 0)
			(type solid)
		)
		(fill yes)
		(layer "In4.Cu")
		(net "M_J_ECC<6>")
	)
	(gr_poly
		(pts
			(xy 81.943956 -52.977034) (xy 81.870296 -52.777644) (xy 81.839054 -52.746148) (xy 81.551526 -53.033422)
			(xy 81.583022 -53.064918) (xy 81.782412 -53.138578)
		)
		(stroke
			(width 0)
			(type solid)
		)
		(fill yes)
		(layer "In4.Cu")
		(net "M_J_ECC<7>")
	)
	(gr_poly
		(pts
			(xy 82.021172 -54.868064) (xy 81.976722 -54.868064) (xy 81.783682 -54.956964) (xy 81.783682 -55.185564)
			(xy 81.976722 -55.274464) (xy 82.021172 -55.274464)
		)
		(stroke
			(width 0)
			(type solid)
		)
		(fill yes)
		(layer "In4.Cu")
		(net "M_J_ECC<2>")
	)
	(gr_poly
		(pts
			(xy 82.021172 -53.877464) (xy 81.976722 -53.877464) (xy 81.783682 -53.966364) (xy 81.783682 -54.194964)
			(xy 81.976722 -54.283864) (xy 82.021172 -54.283864)
		)
		(stroke
			(width 0)
			(type solid)
		)
		(fill yes)
		(layer "In4.Cu")
		(net "M_J_ECC<2>")
	)
	(gr_poly
		(pts
			(xy 82.028792 -99.873054) (xy 81.984342 -99.873054) (xy 81.791302 -99.961954) (xy 81.791302 -100.190554)
			(xy 81.984342 -100.279454) (xy 82.028792 -100.279454)
		)
		(stroke
			(width 0)
			(type solid)
		)
		(fill yes)
		(layer "In4.Cu")
		(net "M_M_ECC<6>")
	)
	(gr_poly
		(pts
			(xy 82.028792 -98.882454) (xy 81.984342 -98.882454) (xy 81.791302 -98.971354) (xy 81.791302 -99.199954)
			(xy 81.984342 -99.288854) (xy 82.028792 -99.288854)
		)
		(stroke
			(width 0)
			(type solid)
		)
		(fill yes)
		(layer "In4.Cu")
		(net "M_M_ECC<6>")
	)
	(gr_poly
		(pts
			(xy 82.039714 -95.9993) (xy 81.995264 -95.9993) (xy 81.825084 -96.0882) (xy 81.825084 -96.30918)
			(xy 81.995264 -96.39808) (xy 82.039714 -96.39808)
		)
		(stroke
			(width 0)
			(type solid)
		)
		(fill yes)
		(layer "In4.Cu")
		(net "M_M_ECC<6>")
	)
	(gr_poly
		(pts
			(xy 82.039714 -95.0087) (xy 81.995264 -95.0087) (xy 81.825084 -95.0976) (xy 81.825084 -95.31858)
			(xy 81.995264 -95.40748) (xy 82.039714 -95.40748)
		)
		(stroke
			(width 0)
			(type solid)
		)
		(fill yes)
		(layer "In4.Cu")
		(net "M_M_ECC<6>")
	)
	(gr_poly
		(pts
			(xy 82.039714 -94.030546) (xy 81.995264 -94.030546) (xy 81.825084 -94.119446) (xy 81.825084 -94.340426)
			(xy 81.995264 -94.429326) (xy 82.039714 -94.429326)
		)
		(stroke
			(width 0)
			(type solid)
		)
		(fill yes)
		(layer "In4.Cu")
		(net "M_M_ECC<6>")
	)
	(gr_poly
		(pts
			(xy 82.039714 -93.03385) (xy 81.995264 -93.03385) (xy 81.825084 -93.12275) (xy 81.825084 -93.34373)
			(xy 81.995264 -93.43263) (xy 82.039714 -93.43263)
		)
		(stroke
			(width 0)
			(type solid)
		)
		(fill yes)
		(layer "In4.Cu")
		(net "M_M_ECC<6>")
	)
	(gr_poly
		(pts
			(xy 82.039714 -92.0369) (xy 81.995264 -92.0369) (xy 81.825084 -92.1258) (xy 81.825084 -92.34678)
			(xy 81.995264 -92.43568) (xy 82.039714 -92.43568)
		)
		(stroke
			(width 0)
			(type solid)
		)
		(fill yes)
		(layer "In4.Cu")
		(net "M_M_ECC<6>")
	)
	(gr_poly
		(pts
			(xy 82.039714 -91.0463) (xy 81.995264 -91.0463) (xy 81.825084 -91.1352) (xy 81.825084 -91.35618)
			(xy 81.995264 -91.44508) (xy 82.039714 -91.44508)
		)
		(stroke
			(width 0)
			(type solid)
		)
		(fill yes)
		(layer "In4.Cu")
		(net "M_M_ECC<6>")
	)
	(gr_poly
		(pts
			(xy 82.039714 -90.0557) (xy 81.995264 -90.0557) (xy 81.825084 -90.1446) (xy 81.825084 -90.36558)
			(xy 81.995264 -90.45448) (xy 82.039714 -90.45448)
		)
		(stroke
			(width 0)
			(type solid)
		)
		(fill yes)
		(layer "In4.Cu")
		(net "M_M_ECC<6>")
	)
	(gr_poly
		(pts
			(xy 82.039714 -89.0651) (xy 81.995264 -89.0651) (xy 81.825084 -89.154) (xy 81.825084 -89.37498) (xy 81.995264 -89.46388)
			(xy 82.039714 -89.46388)
		)
		(stroke
			(width 0)
			(type solid)
		)
		(fill yes)
		(layer "In4.Cu")
		(net "M_M_ECC<6>")
	)
	(gr_poly
		(pts
			(xy 82.039714 -88.0745) (xy 81.995264 -88.0745) (xy 81.825084 -88.1634) (xy 81.825084 -88.38438)
			(xy 81.995264 -88.47328) (xy 82.039714 -88.47328)
		)
		(stroke
			(width 0)
			(type solid)
		)
		(fill yes)
		(layer "In4.Cu")
		(net "M_M_ECC<6>")
	)
	(gr_poly
		(pts
			(xy 82.039714 -87.0839) (xy 81.995264 -87.0839) (xy 81.825084 -87.1728) (xy 81.825084 -87.39378)
			(xy 81.995264 -87.48268) (xy 82.039714 -87.48268)
		)
		(stroke
			(width 0)
			(type solid)
		)
		(fill yes)
		(layer "In4.Cu")
		(net "M_M_ECC<6>")
	)
	(gr_poly
		(pts
			(xy 82.039714 -86.0933) (xy 81.995264 -86.0933) (xy 81.825084 -86.1822) (xy 81.825084 -86.40318)
			(xy 81.995264 -86.49208) (xy 82.039714 -86.49208)
		)
		(stroke
			(width 0)
			(type solid)
		)
		(fill yes)
		(layer "In4.Cu")
		(net "M_M_ECC<6>")
	)
	(gr_poly
		(pts
			(xy 82.039714 -66.2813) (xy 81.995264 -66.2813) (xy 81.825084 -66.3702) (xy 81.825084 -66.59118)
			(xy 81.995264 -66.68008) (xy 82.039714 -66.68008)
		)
		(stroke
			(width 0)
			(type solid)
		)
		(fill yes)
		(layer "In4.Cu")
		(net "M_J_ECC<2>")
	)
	(gr_poly
		(pts
			(xy 82.039714 -65.2907) (xy 81.995264 -65.2907) (xy 81.825084 -65.3796) (xy 81.825084 -65.60058)
			(xy 81.995264 -65.68948) (xy 82.039714 -65.68948)
		)
		(stroke
			(width 0)
			(type solid)
		)
		(fill yes)
		(layer "In4.Cu")
		(net "M_J_ECC<2>")
	)
	(gr_poly
		(pts
			(xy 82.039714 -64.3001) (xy 81.995264 -64.3001) (xy 81.825084 -64.389) (xy 81.825084 -64.60998) (xy 81.995264 -64.69888)
			(xy 82.039714 -64.69888)
		)
		(stroke
			(width 0)
			(type solid)
		)
		(fill yes)
		(layer "In4.Cu")
		(net "M_J_ECC<2>")
	)
	(gr_poly
		(pts
			(xy 82.039714 -63.3095) (xy 81.995264 -63.3095) (xy 81.825084 -63.3984) (xy 81.825084 -63.61938)
			(xy 81.995264 -63.70828) (xy 82.039714 -63.70828)
		)
		(stroke
			(width 0)
			(type solid)
		)
		(fill yes)
		(layer "In4.Cu")
		(net "M_J_ECC<2>")
	)
	(gr_poly
		(pts
			(xy 82.039714 -62.3189) (xy 81.995264 -62.3189) (xy 81.825084 -62.4078) (xy 81.825084 -62.62878)
			(xy 81.995264 -62.71768) (xy 82.039714 -62.71768)
		)
		(stroke
			(width 0)
			(type solid)
		)
		(fill yes)
		(layer "In4.Cu")
		(net "M_J_ECC<2>")
	)
	(gr_poly
		(pts
			(xy 82.039714 -61.3283) (xy 81.995264 -61.3283) (xy 81.825084 -61.4172) (xy 81.825084 -61.63818)
			(xy 81.995264 -61.72708) (xy 82.039714 -61.72708)
		)
		(stroke
			(width 0)
			(type solid)
		)
		(fill yes)
		(layer "In4.Cu")
		(net "M_J_ECC<2>")
	)
	(gr_poly
		(pts
			(xy 82.039714 -60.3377) (xy 81.995264 -60.3377) (xy 81.825084 -60.4266) (xy 81.825084 -60.64758)
			(xy 81.995264 -60.73648) (xy 82.039714 -60.73648)
		)
		(stroke
			(width 0)
			(type solid)
		)
		(fill yes)
		(layer "In4.Cu")
		(net "M_J_ECC<2>")
	)
	(gr_poly
		(pts
			(xy 82.039714 -59.3471) (xy 81.995264 -59.3471) (xy 81.825084 -59.436) (xy 81.825084 -59.65698) (xy 81.995264 -59.74588)
			(xy 82.039714 -59.74588)
		)
		(stroke
			(width 0)
			(type solid)
		)
		(fill yes)
		(layer "In4.Cu")
		(net "M_J_ECC<2>")
	)
	(gr_poly
		(pts
			(xy 82.039714 -58.368946) (xy 81.995264 -58.368946) (xy 81.825084 -58.457846) (xy 81.825084 -58.678826)
			(xy 81.995264 -58.767726) (xy 82.039714 -58.767726)
		)
		(stroke
			(width 0)
			(type solid)
		)
		(fill yes)
		(layer "In4.Cu")
		(net "M_J_ECC<2>")
	)
	(gr_poly
		(pts
			(xy 82.039714 -57.37225) (xy 81.995264 -57.37225) (xy 81.825084 -57.46115) (xy 81.825084 -57.68213)
			(xy 81.995264 -57.77103) (xy 82.039714 -57.77103)
		)
		(stroke
			(width 0)
			(type solid)
		)
		(fill yes)
		(layer "In4.Cu")
		(net "M_J_ECC<2>")
	)
	(gr_poly
		(pts
			(xy 82.039714 -56.3753) (xy 81.995264 -56.3753) (xy 81.825084 -56.4642) (xy 81.825084 -56.68518)
			(xy 81.995264 -56.77408) (xy 82.039714 -56.77408)
		)
		(stroke
			(width 0)
			(type solid)
		)
		(fill yes)
		(layer "In4.Cu")
		(net "M_J_ECC<2>")
	)
	(gr_poly
		(pts
			(xy 82.136234 -50.462688) (xy 82.104992 -50.431192) (xy 81.905602 -50.357532) (xy 81.743804 -50.519076)
			(xy 81.817464 -50.718466) (xy 81.84896 -50.749962)
		)
		(stroke
			(width 0)
			(type solid)
		)
		(fill yes)
		(layer "In4.Cu")
		(net "M_J_ECC<6>")
	)
	(gr_poly
		(pts
			(xy 82.202274 -101.282754) (xy 82.202274 -101.054154) (xy 82.009234 -100.965254) (xy 81.964784 -100.965254)
			(xy 81.964784 -101.371654) (xy 82.009234 -101.371654)
		)
		(stroke
			(width 0)
			(type solid)
		)
		(fill yes)
		(layer "In4.Cu")
		(net "M_M_ECC<7>")
	)
	(gr_poly
		(pts
			(xy 82.218022 -97.005902) (xy 82.173572 -97.005902) (xy 81.980532 -97.094802) (xy 81.980532 -97.323402)
			(xy 82.173572 -97.412302) (xy 82.218022 -97.412302)
		)
		(stroke
			(width 0)
			(type solid)
		)
		(fill yes)
		(layer "In4.Cu")
		(net "M_M_ECC<6>")
	)
	(gr_poly
		(pts
			(xy 82.241136 -85.291168) (xy 82.321654 -85.116924) (xy 82.18678 -84.941918) (xy 81.997804 -84.975446)
			(xy 81.962244 -85.00237) (xy 82.20583 -85.318346)
		)
		(stroke
			(width 0)
			(type solid)
		)
		(fill yes)
		(layer "In4.Cu")
		(net "M_M_ECC<7>")
	)
	(gr_poly
		(pts
			(xy 82.307176 -52.229766) (xy 82.307176 -52.00142) (xy 82.114136 -51.91252) (xy 82.069686 -51.912266)
			(xy 82.069686 -52.318666) (xy 82.114136 -52.318666)
		)
		(stroke
			(width 0)
			(type solid)
		)
		(fill yes)
		(layer "In4.Cu")
		(net "M_J_ECC<7>")
	)
	(gr_poly
		(pts
			(xy 82.449416 -55.185564) (xy 82.449416 -54.956964) (xy 82.256376 -54.868064) (xy 82.211926 -54.868064)
			(xy 82.211926 -55.274464) (xy 82.256376 -55.274464)
		)
		(stroke
			(width 0)
			(type solid)
		)
		(fill yes)
		(layer "In4.Cu")
		(net "M_J_ECC<3>")
	)
	(gr_poly
		(pts
			(xy 82.449416 -54.296564) (xy 82.449416 -54.067964) (xy 82.256376 -53.979064) (xy 82.211926 -53.979064)
			(xy 82.211926 -54.385464) (xy 82.256376 -54.385464)
		)
		(stroke
			(width 0)
			(type solid)
		)
		(fill yes)
		(layer "In4.Cu")
		(net "M_J_ECC<3>")
	)
	(gr_poly
		(pts
			(xy 82.456274 -100.190554) (xy 82.456274 -99.961954) (xy 82.263234 -99.873054) (xy 82.218784 -99.873054)
			(xy 82.218784 -100.279454) (xy 82.263234 -100.279454)
		)
		(stroke
			(width 0)
			(type solid)
		)
		(fill yes)
		(layer "In4.Cu")
		(net "M_M_ECC<7>")
	)
	(gr_poly
		(pts
			(xy 82.456274 -99.199954) (xy 82.456274 -98.971354) (xy 82.263234 -98.882454) (xy 82.218784 -98.882454)
			(xy 82.218784 -99.288854) (xy 82.263234 -99.288854)
		)
		(stroke
			(width 0)
			(type solid)
		)
		(fill yes)
		(layer "In4.Cu")
		(net "M_M_ECC<7>")
	)
	(gr_poly
		(pts
			(xy 82.57794 -95.826326) (xy 82.57794 -95.605346) (xy 82.40776 -95.516446) (xy 82.36331 -95.516446)
			(xy 82.36331 -95.915226) (xy 82.40776 -95.915226)
		)
		(stroke
			(width 0)
			(type solid)
		)
		(fill yes)
		(layer "In4.Cu")
		(net "M_M_ECC<7>")
	)
	(gr_poly
		(pts
			(xy 82.57794 -94.829376) (xy 82.57794 -94.608396) (xy 82.40776 -94.519496) (xy 82.36331 -94.519496)
			(xy 82.36331 -94.918276) (xy 82.40776 -94.918276)
		)
		(stroke
			(width 0)
			(type solid)
		)
		(fill yes)
		(layer "In4.Cu")
		(net "M_M_ECC<7>")
	)
	(gr_poly
		(pts
			(xy 82.57794 -93.83268) (xy 82.57794 -93.6117) (xy 82.40776 -93.5228) (xy 82.36331 -93.5228) (xy 82.36331 -93.92158)
			(xy 82.40776 -93.92158)
		)
		(stroke
			(width 0)
			(type solid)
		)
		(fill yes)
		(layer "In4.Cu")
		(net "M_M_ECC<7>")
	)
	(gr_poly
		(pts
			(xy 82.57794 -92.854526) (xy 82.57794 -92.633546) (xy 82.40776 -92.544646) (xy 82.36331 -92.544646)
			(xy 82.36331 -92.943426) (xy 82.40776 -92.943426)
		)
		(stroke
			(width 0)
			(type solid)
		)
		(fill yes)
		(layer "In4.Cu")
		(net "M_M_ECC<7>")
	)
	(gr_poly
		(pts
			(xy 82.57794 -91.863926) (xy 82.57794 -91.642946) (xy 82.40776 -91.554046) (xy 82.36331 -91.554046)
			(xy 82.36331 -91.952826) (xy 82.40776 -91.952826)
		)
		(stroke
			(width 0)
			(type solid)
		)
		(fill yes)
		(layer "In4.Cu")
		(net "M_M_ECC<7>")
	)
	(gr_poly
		(pts
			(xy 82.57794 -90.873326) (xy 82.57794 -90.652346) (xy 82.40776 -90.563446) (xy 82.36331 -90.563446)
			(xy 82.36331 -90.962226) (xy 82.40776 -90.962226)
		)
		(stroke
			(width 0)
			(type solid)
		)
		(fill yes)
		(layer "In4.Cu")
		(net "M_M_ECC<7>")
	)
	(gr_poly
		(pts
			(xy 82.57794 -89.882726) (xy 82.57794 -89.661746) (xy 82.40776 -89.572846) (xy 82.36331 -89.572846)
			(xy 82.36331 -89.971626) (xy 82.40776 -89.971626)
		)
		(stroke
			(width 0)
			(type solid)
		)
		(fill yes)
		(layer "In4.Cu")
		(net "M_M_ECC<7>")
	)
	(gr_poly
		(pts
			(xy 82.57794 -88.892126) (xy 82.57794 -88.671146) (xy 82.40776 -88.582246) (xy 82.36331 -88.582246)
			(xy 82.36331 -88.981026) (xy 82.40776 -88.981026)
		)
		(stroke
			(width 0)
			(type solid)
		)
		(fill yes)
		(layer "In4.Cu")
		(net "M_M_ECC<7>")
	)
	(gr_poly
		(pts
			(xy 82.57794 -87.901526) (xy 82.57794 -87.680546) (xy 82.40776 -87.591646) (xy 82.36331 -87.591646)
			(xy 82.36331 -87.990426) (xy 82.40776 -87.990426)
		)
		(stroke
			(width 0)
			(type solid)
		)
		(fill yes)
		(layer "In4.Cu")
		(net "M_M_ECC<7>")
	)
	(gr_poly
		(pts
			(xy 82.57794 -86.910926) (xy 82.57794 -86.689946) (xy 82.40776 -86.601046) (xy 82.36331 -86.601046)
			(xy 82.36331 -86.999826) (xy 82.40776 -86.999826)
		)
		(stroke
			(width 0)
			(type solid)
		)
		(fill yes)
		(layer "In4.Cu")
		(net "M_M_ECC<7>")
	)
	(gr_poly
		(pts
			(xy 82.57794 -85.920326) (xy 82.57794 -85.699346) (xy 82.40776 -85.610446) (xy 82.36331 -85.610446)
			(xy 82.36331 -86.009226) (xy 82.40776 -86.009226)
		)
		(stroke
			(width 0)
			(type solid)
		)
		(fill yes)
		(layer "In4.Cu")
		(net "M_M_ECC<7>")
	)
	(gr_poly
		(pts
			(xy 82.57794 -67.098926) (xy 82.57794 -66.877946) (xy 82.40776 -66.789046) (xy 82.36331 -66.789046)
			(xy 82.36331 -67.187826) (xy 82.40776 -67.187826)
		)
		(stroke
			(width 0)
			(type solid)
		)
		(fill yes)
		(layer "In4.Cu")
		(net "M_J_ECC<3>")
	)
	(gr_poly
		(pts
			(xy 82.57794 -66.108326) (xy 82.57794 -65.887346) (xy 82.40776 -65.798446) (xy 82.36331 -65.798446)
			(xy 82.36331 -66.197226) (xy 82.40776 -66.197226)
		)
		(stroke
			(width 0)
			(type solid)
		)
		(fill yes)
		(layer "In4.Cu")
		(net "M_J_ECC<3>")
	)
	(gr_poly
		(pts
			(xy 82.57794 -65.117726) (xy 82.57794 -64.896746) (xy 82.40776 -64.807846) (xy 82.36331 -64.807846)
			(xy 82.36331 -65.206626) (xy 82.40776 -65.206626)
		)
		(stroke
			(width 0)
			(type solid)
		)
		(fill yes)
		(layer "In4.Cu")
		(net "M_J_ECC<3>")
	)
	(gr_poly
		(pts
			(xy 82.57794 -64.127126) (xy 82.57794 -63.906146) (xy 82.40776 -63.817246) (xy 82.36331 -63.817246)
			(xy 82.36331 -64.216026) (xy 82.40776 -64.216026)
		)
		(stroke
			(width 0)
			(type solid)
		)
		(fill yes)
		(layer "In4.Cu")
		(net "M_J_ECC<3>")
	)
	(gr_poly
		(pts
			(xy 82.57794 -63.136526) (xy 82.57794 -62.915546) (xy 82.40776 -62.826646) (xy 82.36331 -62.826646)
			(xy 82.36331 -63.225426) (xy 82.40776 -63.225426)
		)
		(stroke
			(width 0)
			(type solid)
		)
		(fill yes)
		(layer "In4.Cu")
		(net "M_J_ECC<3>")
	)
	(gr_poly
		(pts
			(xy 82.57794 -62.145926) (xy 82.57794 -61.924946) (xy 82.40776 -61.836046) (xy 82.36331 -61.836046)
			(xy 82.36331 -62.234826) (xy 82.40776 -62.234826)
		)
		(stroke
			(width 0)
			(type solid)
		)
		(fill yes)
		(layer "In4.Cu")
		(net "M_J_ECC<3>")
	)
	(gr_poly
		(pts
			(xy 82.57794 -61.155326) (xy 82.57794 -60.934346) (xy 82.40776 -60.845446) (xy 82.36331 -60.845446)
			(xy 82.36331 -61.244226) (xy 82.40776 -61.244226)
		)
		(stroke
			(width 0)
			(type solid)
		)
		(fill yes)
		(layer "In4.Cu")
		(net "M_J_ECC<3>")
	)
	(gr_poly
		(pts
			(xy 82.57794 -60.164726) (xy 82.57794 -59.943746) (xy 82.40776 -59.854846) (xy 82.36331 -59.854846)
			(xy 82.36331 -60.253626) (xy 82.40776 -60.253626)
		)
		(stroke
			(width 0)
			(type solid)
		)
		(fill yes)
		(layer "In4.Cu")
		(net "M_J_ECC<3>")
	)
	(gr_poly
		(pts
			(xy 82.57794 -59.167776) (xy 82.57794 -58.946796) (xy 82.40776 -58.857896) (xy 82.36331 -58.857896)
			(xy 82.36331 -59.256676) (xy 82.40776 -59.256676)
		)
		(stroke
			(width 0)
			(type solid)
		)
		(fill yes)
		(layer "In4.Cu")
		(net "M_J_ECC<3>")
	)
	(gr_poly
		(pts
			(xy 82.57794 -58.17108) (xy 82.57794 -57.9501) (xy 82.40776 -57.8612) (xy 82.36331 -57.8612) (xy 82.36331 -58.25998)
			(xy 82.40776 -58.25998)
		)
		(stroke
			(width 0)
			(type solid)
		)
		(fill yes)
		(layer "In4.Cu")
		(net "M_J_ECC<3>")
	)
	(gr_poly
		(pts
			(xy 82.57794 -57.192926) (xy 82.57794 -56.971946) (xy 82.40776 -56.883046) (xy 82.36331 -56.883046)
			(xy 82.36331 -57.281826) (xy 82.40776 -57.281826)
		)
		(stroke
			(width 0)
			(type solid)
		)
		(fill yes)
		(layer "In4.Cu")
		(net "M_J_ECC<3>")
	)
	(gr_poly
		(pts
			(xy 82.645504 -97.323402) (xy 82.645504 -97.094802) (xy 82.452464 -97.005902) (xy 82.408014 -97.005902)
			(xy 82.408014 -97.412302) (xy 82.452464 -97.412302)
		)
		(stroke
			(width 0)
			(type solid)
		)
		(fill yes)
		(layer "In4.Cu")
		(net "M_M_ECC<7>")
	)
	(gr_poly
		(pts
			(xy 82.702908 -52.689506) (xy 82.671412 -52.658264) (xy 82.472022 -52.584604) (xy 82.310478 -52.746148)
			(xy 82.384138 -52.945538) (xy 82.41538 -52.977034)
		)
		(stroke
			(width 0)
			(type solid)
		)
		(fill yes)
		(layer "In4.Cu")
		(net "M_J_ECC<2>")
	)
	(gr_poly
		(pts
			(xy 82.898234 -95.516446) (xy 82.853784 -95.516446) (xy 82.683604 -95.605346) (xy 82.683604 -95.826326)
			(xy 82.853784 -95.915226) (xy 82.898234 -95.915226)
		)
		(stroke
			(width 0)
			(type solid)
		)
		(fill yes)
		(layer "In4.Cu")
		(net "M_M_ECC<2>")
	)
	(gr_poly
		(pts
			(xy 82.898234 -94.519496) (xy 82.853784 -94.519496) (xy 82.683604 -94.608396) (xy 82.683604 -94.829376)
			(xy 82.853784 -94.918276) (xy 82.898234 -94.918276)
		)
		(stroke
			(width 0)
			(type solid)
		)
		(fill yes)
		(layer "In4.Cu")
		(net "M_M_ECC<2>")
	)
	(gr_poly
		(pts
			(xy 82.898234 -93.5228) (xy 82.853784 -93.5228) (xy 82.683604 -93.6117) (xy 82.683604 -93.83268)
			(xy 82.853784 -93.92158) (xy 82.898234 -93.92158)
		)
		(stroke
			(width 0)
			(type solid)
		)
		(fill yes)
		(layer "In4.Cu")
		(net "M_M_ECC<2>")
	)
	(gr_poly
		(pts
			(xy 82.898234 -92.544646) (xy 82.853784 -92.544646) (xy 82.683604 -92.633546) (xy 82.683604 -92.854526)
			(xy 82.853784 -92.943426) (xy 82.898234 -92.943426)
		)
		(stroke
			(width 0)
			(type solid)
		)
		(fill yes)
		(layer "In4.Cu")
		(net "M_M_ECC<2>")
	)
	(gr_poly
		(pts
			(xy 82.898234 -91.554046) (xy 82.853784 -91.554046) (xy 82.683604 -91.642946) (xy 82.683604 -91.863926)
			(xy 82.853784 -91.952826) (xy 82.898234 -91.952826)
		)
		(stroke
			(width 0)
			(type solid)
		)
		(fill yes)
		(layer "In4.Cu")
		(net "M_M_ECC<2>")
	)
	(gr_poly
		(pts
			(xy 82.898234 -90.563446) (xy 82.853784 -90.563446) (xy 82.683604 -90.652346) (xy 82.683604 -90.873326)
			(xy 82.853784 -90.962226) (xy 82.898234 -90.962226)
		)
		(stroke
			(width 0)
			(type solid)
		)
		(fill yes)
		(layer "In4.Cu")
		(net "M_M_ECC<2>")
	)
	(gr_poly
		(pts
			(xy 82.898234 -89.572846) (xy 82.853784 -89.572846) (xy 82.683604 -89.661746) (xy 82.683604 -89.882726)
			(xy 82.853784 -89.971626) (xy 82.898234 -89.971626)
		)
		(stroke
			(width 0)
			(type solid)
		)
		(fill yes)
		(layer "In4.Cu")
		(net "M_M_ECC<2>")
	)
	(gr_poly
		(pts
			(xy 82.898234 -88.582246) (xy 82.853784 -88.582246) (xy 82.683604 -88.671146) (xy 82.683604 -88.892126)
			(xy 82.853784 -88.981026) (xy 82.898234 -88.981026)
		)
		(stroke
			(width 0)
			(type solid)
		)
		(fill yes)
		(layer "In4.Cu")
		(net "M_M_ECC<2>")
	)
	(gr_poly
		(pts
			(xy 82.898234 -87.591646) (xy 82.853784 -87.591646) (xy 82.683604 -87.680546) (xy 82.683604 -87.901526)
			(xy 82.853784 -87.990426) (xy 82.898234 -87.990426)
		)
		(stroke
			(width 0)
			(type solid)
		)
		(fill yes)
		(layer "In4.Cu")
		(net "M_M_ECC<2>")
	)
	(gr_poly
		(pts
			(xy 82.898234 -86.601046) (xy 82.853784 -86.601046) (xy 82.683604 -86.689946) (xy 82.683604 -86.910926)
			(xy 82.853784 -86.999826) (xy 82.898234 -86.999826)
		)
		(stroke
			(width 0)
			(type solid)
		)
		(fill yes)
		(layer "In4.Cu")
		(net "M_M_ECC<2>")
	)
	(gr_poly
		(pts
			(xy 82.898234 -85.610446) (xy 82.853784 -85.610446) (xy 82.683604 -85.699346) (xy 82.683604 -85.920326)
			(xy 82.853784 -86.009226) (xy 82.898234 -86.009226)
		)
		(stroke
			(width 0)
			(type solid)
		)
		(fill yes)
		(layer "In4.Cu")
		(net "M_M_ECC<2>")
	)
	(gr_poly
		(pts
			(xy 82.942684 -53.055012) (xy 82.869024 -52.855622) (xy 82.837528 -52.82438) (xy 82.550254 -53.111654)
			(xy 82.581496 -53.14315) (xy 82.780886 -53.21681)
		)
		(stroke
			(width 0)
			(type solid)
		)
		(fill yes)
		(layer "In4.Cu")
		(net "M_J_ECC<3>")
	)
	(gr_poly
		(pts
			(xy 82.954876 -51.593242) (xy 82.910426 -51.593242) (xy 82.717386 -51.682142) (xy 82.717386 -51.910742)
			(xy 82.910426 -51.999642) (xy 82.954876 -51.999642)
		)
		(stroke
			(width 0)
			(type solid)
		)
		(fill yes)
		(layer "In4.Cu")
		(net "M_J_ECC<2>")
	)
	(gr_poly
		(pts
			(xy 83.366356 -96.766888) (xy 83.404964 -96.74479) (xy 83.20151 -96.392746) (xy 83.163156 -96.415098)
			(xy 83.040474 -96.58858) (xy 83.154774 -96.786446)
		)
		(stroke
			(width 0)
			(type solid)
		)
		(fill yes)
		(layer "In4.Cu")
		(net "M_M_ECC<2>")
	)
	(gr_poly
		(pts
			(xy 83.382866 -51.910742) (xy 83.382866 -51.682142) (xy 83.189826 -51.593242) (xy 83.145376 -51.593242)
			(xy 83.145376 -51.999642) (xy 83.189826 -51.999642)
		)
		(stroke
			(width 0)
			(type solid)
		)
		(fill yes)
		(layer "In4.Cu")
		(net "M_J_ECC<3>")
	)
	(gr_poly
		(pts
			(xy 83.406488 -50.524918) (xy 83.374992 -50.493676) (xy 83.175602 -50.420016) (xy 83.014058 -50.58156)
			(xy 83.087718 -50.78095) (xy 83.11896 -50.812446)
		)
		(stroke
			(width 0)
			(type solid)
		)
		(fill yes)
		(layer "In4.Cu")
		(net "M_J_ECC<2>")
	)
	(gr_poly
		(pts
			(xy 83.43646 -95.31858) (xy 83.43646 -95.0976) (xy 83.26628 -95.0087) (xy 83.22183 -95.0087) (xy 83.22183 -95.40748)
			(xy 83.26628 -95.40748)
		)
		(stroke
			(width 0)
			(type solid)
		)
		(fill yes)
		(layer "In4.Cu")
		(net "M_M_ECC<3>")
	)
	(gr_poly
		(pts
			(xy 83.43646 -94.340426) (xy 83.43646 -94.119446) (xy 83.26628 -94.030546) (xy 83.22183 -94.030546)
			(xy 83.22183 -94.429326) (xy 83.26628 -94.429326)
		)
		(stroke
			(width 0)
			(type solid)
		)
		(fill yes)
		(layer "In4.Cu")
		(net "M_M_ECC<3>")
	)
	(gr_poly
		(pts
			(xy 83.43646 -93.34373) (xy 83.43646 -93.12275) (xy 83.26628 -93.03385) (xy 83.22183 -93.03385) (xy 83.22183 -93.43263)
			(xy 83.26628 -93.43263)
		)
		(stroke
			(width 0)
			(type solid)
		)
		(fill yes)
		(layer "In4.Cu")
		(net "M_M_ECC<3>")
	)
	(gr_poly
		(pts
			(xy 83.43646 -92.34678) (xy 83.43646 -92.1258) (xy 83.26628 -92.0369) (xy 83.22183 -92.0369) (xy 83.22183 -92.43568)
			(xy 83.26628 -92.43568)
		)
		(stroke
			(width 0)
			(type solid)
		)
		(fill yes)
		(layer "In4.Cu")
		(net "M_M_ECC<3>")
	)
	(gr_poly
		(pts
			(xy 83.43646 -91.35618) (xy 83.43646 -91.1352) (xy 83.26628 -91.0463) (xy 83.22183 -91.0463) (xy 83.22183 -91.44508)
			(xy 83.26628 -91.44508)
		)
		(stroke
			(width 0)
			(type solid)
		)
		(fill yes)
		(layer "In4.Cu")
		(net "M_M_ECC<3>")
	)
	(gr_poly
		(pts
			(xy 83.43646 -90.36558) (xy 83.43646 -90.1446) (xy 83.26628 -90.0557) (xy 83.22183 -90.0557) (xy 83.22183 -90.45448)
			(xy 83.26628 -90.45448)
		)
		(stroke
			(width 0)
			(type solid)
		)
		(fill yes)
		(layer "In4.Cu")
		(net "M_M_ECC<3>")
	)
	(gr_poly
		(pts
			(xy 83.43646 -89.37498) (xy 83.43646 -89.154) (xy 83.26628 -89.0651) (xy 83.22183 -89.0651) (xy 83.22183 -89.46388)
			(xy 83.26628 -89.46388)
		)
		(stroke
			(width 0)
			(type solid)
		)
		(fill yes)
		(layer "In4.Cu")
		(net "M_M_ECC<3>")
	)
	(gr_poly
		(pts
			(xy 83.43646 -88.38438) (xy 83.43646 -88.1634) (xy 83.26628 -88.0745) (xy 83.22183 -88.0745) (xy 83.22183 -88.47328)
			(xy 83.26628 -88.47328)
		)
		(stroke
			(width 0)
			(type solid)
		)
		(fill yes)
		(layer "In4.Cu")
		(net "M_M_ECC<3>")
	)
	(gr_poly
		(pts
			(xy 83.43646 -87.39378) (xy 83.43646 -87.1728) (xy 83.26628 -87.0839) (xy 83.22183 -87.0839) (xy 83.22183 -87.48268)
			(xy 83.26628 -87.48268)
		)
		(stroke
			(width 0)
			(type solid)
		)
		(fill yes)
		(layer "In4.Cu")
		(net "M_M_ECC<3>")
	)
	(gr_poly
		(pts
			(xy 83.43646 -86.40318) (xy 83.43646 -86.1822) (xy 83.26628 -86.0933) (xy 83.22183 -86.0933) (xy 83.22183 -86.49208)
			(xy 83.26628 -86.49208)
		)
		(stroke
			(width 0)
			(type solid)
		)
		(fill yes)
		(layer "In4.Cu")
		(net "M_M_ECC<3>")
	)
	(gr_poly
		(pts
			(xy 83.43646 -85.41258) (xy 83.43646 -85.1916) (xy 83.26628 -85.1027) (xy 83.22183 -85.1027) (xy 83.22183 -85.50148)
			(xy 83.26628 -85.50148)
		)
		(stroke
			(width 0)
			(type solid)
		)
		(fill yes)
		(layer "In4.Cu")
		(net "M_M_ECC<3>")
	)
	(gr_poly
		(pts
			(xy 83.608164 -96.627188) (xy 83.730846 -96.453706) (xy 83.616292 -96.25584) (xy 83.40471 -96.275398)
			(xy 83.366356 -96.29775) (xy 83.569556 -96.64954)
		)
		(stroke
			(width 0)
			(type solid)
		)
		(fill yes)
		(layer "In4.Cu")
		(net "M_M_ECC<3>")
	)
	(gr_poly
		(pts
			(xy 83.628992 -101.78923) (xy 83.584542 -101.78923) (xy 83.391502 -101.87813) (xy 83.391502 -102.10673)
			(xy 83.584542 -102.19563) (xy 83.628992 -102.19563)
		)
		(stroke
			(width 0)
			(type solid)
		)
		(fill yes)
		(layer "In4.Cu")
		(net "M_M_ECC<2>")
	)
	(gr_poly
		(pts
			(xy 83.628992 -100.79863) (xy 83.584542 -100.79863) (xy 83.391502 -100.88753) (xy 83.391502 -101.11613)
			(xy 83.584542 -101.20503) (xy 83.628992 -101.20503)
		)
		(stroke
			(width 0)
			(type solid)
		)
		(fill yes)
		(layer "In4.Cu")
		(net "M_M_ECC<2>")
	)
	(gr_poly
		(pts
			(xy 83.628992 -99.80803) (xy 83.584542 -99.80803) (xy 83.391502 -99.89693) (xy 83.391502 -100.12553)
			(xy 83.584542 -100.21443) (xy 83.628992 -100.21443)
		)
		(stroke
			(width 0)
			(type solid)
		)
		(fill yes)
		(layer "In4.Cu")
		(net "M_M_ECC<2>")
	)
	(gr_poly
		(pts
			(xy 83.628992 -98.81743) (xy 83.584542 -98.81743) (xy 83.391502 -98.90633) (xy 83.391502 -99.13493)
			(xy 83.584542 -99.22383) (xy 83.628992 -99.22383)
		)
		(stroke
			(width 0)
			(type solid)
		)
		(fill yes)
		(layer "In4.Cu")
		(net "M_M_ECC<2>")
	)
	(gr_poly
		(pts
			(xy 83.628992 -97.82683) (xy 83.584542 -97.82683) (xy 83.391502 -97.91573) (xy 83.391502 -98.14433)
			(xy 83.584542 -98.23323) (xy 83.628992 -98.23323)
		)
		(stroke
			(width 0)
			(type solid)
		)
		(fill yes)
		(layer "In4.Cu")
		(net "M_M_ECC<2>")
	)
	(gr_poly
		(pts
			(xy 83.646264 -50.890424) (xy 83.572604 -50.691034) (xy 83.541108 -50.659792) (xy 83.253834 -50.947066)
			(xy 83.285076 -50.978562) (xy 83.484466 -51.052222)
		)
		(stroke
			(width 0)
			(type solid)
		)
		(fill yes)
		(layer "In4.Cu")
		(net "M_J_ECC<3>")
	)
	(gr_poly
		(pts
			(xy 84.056474 -102.10673) (xy 84.056474 -101.87813) (xy 83.863434 -101.78923) (xy 83.818984 -101.78923)
			(xy 83.818984 -102.19563) (xy 83.863434 -102.19563)
		)
		(stroke
			(width 0)
			(type solid)
		)
		(fill yes)
		(layer "In4.Cu")
		(net "M_M_ECC<3>")
	)
	(gr_poly
		(pts
			(xy 84.056474 -101.11613) (xy 84.056474 -100.88753) (xy 83.863434 -100.79863) (xy 83.818984 -100.79863)
			(xy 83.818984 -101.20503) (xy 83.863434 -101.20503)
		)
		(stroke
			(width 0)
			(type solid)
		)
		(fill yes)
		(layer "In4.Cu")
		(net "M_M_ECC<3>")
	)
	(gr_poly
		(pts
			(xy 84.056474 -100.12553) (xy 84.056474 -99.89693) (xy 83.863434 -99.80803) (xy 83.818984 -99.80803)
			(xy 83.818984 -100.21443) (xy 83.863434 -100.21443)
		)
		(stroke
			(width 0)
			(type solid)
		)
		(fill yes)
		(layer "In4.Cu")
		(net "M_M_ECC<3>")
	)
	(gr_poly
		(pts
			(xy 84.056474 -99.13493) (xy 84.056474 -98.90633) (xy 83.863434 -98.81743) (xy 83.818984 -98.81743)
			(xy 83.818984 -99.22383) (xy 83.863434 -99.22383)
		)
		(stroke
			(width 0)
			(type solid)
		)
		(fill yes)
		(layer "In4.Cu")
		(net "M_M_ECC<3>")
	)
	(gr_poly
		(pts
			(xy 84.056474 -98.14433) (xy 84.056474 -97.91573) (xy 83.863434 -97.82683) (xy 83.818984 -97.82683)
			(xy 83.818984 -98.23323) (xy 83.863434 -98.23323)
		)
		(stroke
			(width 0)
			(type solid)
		)
		(fill yes)
		(layer "In4.Cu")
		(net "M_M_ECC<3>")
	)
	(gr_poly
		(pts
			(xy 104.444292 -56.1721) (xy 104.399842 -56.1721) (xy 104.206802 -56.261) (xy 104.206802 -56.4896)
			(xy 104.399842 -56.5785) (xy 104.444292 -56.5785)
		)
		(stroke
			(width 0)
			(type solid)
		)
		(fill yes)
		(layer "In4.Cu")
		(net "M_H_DQ<36>")
	)
	(gr_poly
		(pts
			(xy 104.444292 -55.1815) (xy 104.399842 -55.1815) (xy 104.206802 -55.2704) (xy 104.206802 -55.499)
			(xy 104.399842 -55.5879) (xy 104.444292 -55.5879)
		)
		(stroke
			(width 0)
			(type solid)
		)
		(fill yes)
		(layer "In4.Cu")
		(net "M_H_DQ<36>")
	)
	(gr_poly
		(pts
			(xy 104.444292 -53.7845) (xy 104.399842 -53.7845) (xy 104.206802 -53.8734) (xy 104.206802 -54.102)
			(xy 104.399842 -54.1909) (xy 104.444292 -54.1909)
		)
		(stroke
			(width 0)
			(type solid)
		)
		(fill yes)
		(layer "In4.Cu")
		(net "M_H_DQ<36>")
	)
	(gr_poly
		(pts
			(xy 104.444292 -52.7939) (xy 104.399842 -52.7939) (xy 104.206802 -52.8828) (xy 104.206802 -53.1114)
			(xy 104.399842 -53.2003) (xy 104.444292 -53.2003)
		)
		(stroke
			(width 0)
			(type solid)
		)
		(fill yes)
		(layer "In4.Cu")
		(net "M_H_DQ<36>")
	)
	(gr_poly
		(pts
			(xy 104.872282 -56.4896) (xy 104.872282 -56.261) (xy 104.679242 -56.1721) (xy 104.634792 -56.1721)
			(xy 104.634792 -56.5785) (xy 104.679242 -56.5785)
		)
		(stroke
			(width 0)
			(type solid)
		)
		(fill yes)
		(layer "In4.Cu")
		(net "M_H_DQ<37>")
	)
	(gr_poly
		(pts
			(xy 104.872282 -55.499) (xy 104.872282 -55.2704) (xy 104.679242 -55.1815) (xy 104.634792 -55.1815)
			(xy 104.634792 -55.5879) (xy 104.679242 -55.5879)
		)
		(stroke
			(width 0)
			(type solid)
		)
		(fill yes)
		(layer "In4.Cu")
		(net "M_H_DQ<37>")
	)
	(gr_poly
		(pts
			(xy 104.872282 -54.102) (xy 104.872282 -53.8734) (xy 104.679242 -53.7845) (xy 104.634792 -53.7845)
			(xy 104.634792 -54.1909) (xy 104.679242 -54.1909)
		)
		(stroke
			(width 0)
			(type solid)
		)
		(fill yes)
		(layer "In4.Cu")
		(net "M_H_DQ<37>")
	)
	(gr_poly
		(pts
			(xy 104.872282 -53.1114) (xy 104.872282 -52.8828) (xy 104.679242 -52.7939) (xy 104.634792 -52.7939)
			(xy 104.634792 -53.2003) (xy 104.679242 -53.2003)
		)
		(stroke
			(width 0)
			(type solid)
		)
		(fill yes)
		(layer "In4.Cu")
		(net "M_H_DQ<37>")
	)
	(gr_poly
		(pts
			(xy 105.111042 -57.488328) (xy 105.142284 -57.456832) (xy 104.85501 -57.169558) (xy 104.823514 -57.201054)
			(xy 104.749854 -57.400444) (xy 104.911652 -57.561988)
		)
		(stroke
			(width 0)
			(type solid)
		)
		(fill yes)
		(layer "In4.Cu")
		(net "M_H_DQ<36>")
	)
	(gr_poly
		(pts
			(xy 105.129584 -57.110376) (xy 105.203244 -56.910986) (xy 105.0417 -56.749442) (xy 104.84231 -56.823102)
			(xy 104.810814 -56.854344) (xy 105.098342 -57.141872)
		)
		(stroke
			(width 0)
			(type solid)
		)
		(fill yes)
		(layer "In4.Cu")
		(net "M_H_DQ<37>")
	)
	(gr_poly
		(pts
			(xy 105.204514 -50.812192) (xy 105.160064 -50.812192) (xy 104.967024 -50.901092) (xy 104.967024 -51.129692)
			(xy 105.160064 -51.218592) (xy 105.204514 -51.218592)
		)
		(stroke
			(width 0)
			(type solid)
		)
		(fill yes)
		(layer "In4.Cu")
		(net "M_H_DQ<36>")
	)
	(gr_poly
		(pts
			(xy 105.414064 -54.305454) (xy 105.388918 -54.269132) (xy 105.2195 -54.178962) (xy 105.037382 -54.30393)
			(xy 105.060242 -54.49443) (xy 105.085134 -54.53126)
		)
		(stroke
			(width 0)
			(type solid)
		)
		(fill yes)
		(layer "In4.Cu")
		(net "M_H_DQ<32>")
	)
	(gr_poly
		(pts
			(xy 105.631996 -51.129692) (xy 105.631996 -50.901092) (xy 105.438956 -50.812192) (xy 105.394506 -50.812192)
			(xy 105.394506 -51.218592) (xy 105.438956 -51.218592)
		)
		(stroke
			(width 0)
			(type solid)
		)
		(fill yes)
		(layer "In4.Cu")
		(net "M_H_DQ<37>")
	)
	(gr_poly
		(pts
			(xy 105.860088 -53.222398) (xy 105.815638 -53.222398) (xy 105.645458 -53.311298) (xy 105.645458 -53.532278)
			(xy 105.815638 -53.621178) (xy 105.860088 -53.621178)
		)
		(stroke
			(width 0)
			(type solid)
		)
		(fill yes)
		(layer "In4.Cu")
		(net "M_H_DQ<32>")
	)
	(gr_poly
		(pts
			(xy 105.963212 -49.103788) (xy 105.918762 -49.103788) (xy 105.725722 -49.192688) (xy 105.725722 -49.421288)
			(xy 105.918762 -49.510188) (xy 105.963212 -49.510188)
		)
		(stroke
			(width 0)
			(type solid)
		)
		(fill yes)
		(layer "In4.Cu")
		(net "M_H_DQ<36>")
	)
	(gr_poly
		(pts
			(xy 105.971086 -52.267358) (xy 105.926636 -52.267358) (xy 105.733596 -52.356258) (xy 105.733596 -52.584858)
			(xy 105.926636 -52.673758) (xy 105.971086 -52.673758)
		)
		(stroke
			(width 0)
			(type solid)
		)
		(fill yes)
		(layer "In4.Cu")
		(net "M_H_DQ<32>")
	)
	(gr_poly
		(pts
			(xy 105.971086 -51.276758) (xy 105.926636 -51.276758) (xy 105.733596 -51.365658) (xy 105.733596 -51.594258)
			(xy 105.926636 -51.683158) (xy 105.971086 -51.683158)
		)
		(stroke
			(width 0)
			(type solid)
		)
		(fill yes)
		(layer "In4.Cu")
		(net "M_H_DQ<32>")
	)
	(gr_poly
		(pts
			(xy 106.247692 -47.655988) (xy 106.203242 -47.655988) (xy 106.010202 -47.744888) (xy 106.010202 -47.973488)
			(xy 106.203242 -48.062388) (xy 106.247692 -48.062388)
		)
		(stroke
			(width 0)
			(type solid)
		)
		(fill yes)
		(layer "In4.Cu")
		(net "M_H_DQ<36>")
	)
	(gr_poly
		(pts
			(xy 106.247692 -46.665388) (xy 106.203242 -46.665388) (xy 106.010202 -46.754288) (xy 106.010202 -46.982888)
			(xy 106.203242 -47.071788) (xy 106.247692 -47.071788)
		)
		(stroke
			(width 0)
			(type solid)
		)
		(fill yes)
		(layer "In4.Cu")
		(net "M_H_DQ<36>")
	)
	(gr_poly
		(pts
			(xy 106.308906 -101.746558) (xy 106.264456 -101.746558) (xy 106.071416 -101.835458) (xy 106.071416 -102.064058)
			(xy 106.264456 -102.152958) (xy 106.308906 -102.152958)
		)
		(stroke
			(width 0)
			(type solid)
		)
		(fill yes)
		(layer "In4.Cu")
		(net "M_L_DQ<36>")
	)
	(gr_poly
		(pts
			(xy 106.308906 -100.755958) (xy 106.264456 -100.755958) (xy 106.071416 -100.844858) (xy 106.071416 -101.073458)
			(xy 106.264456 -101.162358) (xy 106.308906 -101.162358)
		)
		(stroke
			(width 0)
			(type solid)
		)
		(fill yes)
		(layer "In4.Cu")
		(net "M_L_DQ<36>")
	)
	(gr_poly
		(pts
			(xy 106.308906 -99.765358) (xy 106.264456 -99.765358) (xy 106.071416 -99.854258) (xy 106.071416 -100.082858)
			(xy 106.264456 -100.171758) (xy 106.308906 -100.171758)
		)
		(stroke
			(width 0)
			(type solid)
		)
		(fill yes)
		(layer "In4.Cu")
		(net "M_L_DQ<36>")
	)
	(gr_poly
		(pts
			(xy 106.351832 -54.796436) (xy 106.328718 -54.75859) (xy 106.163618 -54.660546) (xy 105.975404 -54.77637)
			(xy 105.988866 -54.967886) (xy 106.012234 -55.005732)
		)
		(stroke
			(width 0)
			(type solid)
		)
		(fill yes)
		(layer "In4.Cu")
		(net "M_H_DQS_DP<13>")
	)
	(gr_poly
		(pts
			(xy 106.390948 -49.421288) (xy 106.390948 -49.192688) (xy 106.197908 -49.103788) (xy 106.153458 -49.103788)
			(xy 106.153458 -49.510188) (xy 106.197908 -49.510188)
		)
		(stroke
			(width 0)
			(type solid)
		)
		(fill yes)
		(layer "In4.Cu")
		(net "M_H_DQ<37>")
	)
	(gr_poly
		(pts
			(xy 106.393234 -54.018942) (xy 106.393234 -53.797962) (xy 106.2228 -53.709062) (xy 106.17835 -53.709062)
			(xy 106.178604 -54.107842) (xy 106.223054 -54.107842)
		)
		(stroke
			(width 0)
			(type solid)
		)
		(fill yes)
		(layer "In4.Cu")
		(net "M_H_DQ<33>")
	)
	(gr_poly
		(pts
			(xy 106.398568 -52.584858) (xy 106.398568 -52.356258) (xy 106.205528 -52.267358) (xy 106.161078 -52.267358)
			(xy 106.161078 -52.673758) (xy 106.205528 -52.673758)
		)
		(stroke
			(width 0)
			(type solid)
		)
		(fill yes)
		(layer "In4.Cu")
		(net "M_H_DQ<33>")
	)
	(gr_poly
		(pts
			(xy 106.398568 -51.594258) (xy 106.398568 -51.365658) (xy 106.205528 -51.276758) (xy 106.161078 -51.276758)
			(xy 106.161078 -51.683158) (xy 106.205528 -51.683158)
		)
		(stroke
			(width 0)
			(type solid)
		)
		(fill yes)
		(layer "In4.Cu")
		(net "M_H_DQ<33>")
	)
	(gr_poly
		(pts
			(xy 106.549444 -50.348388) (xy 106.517948 -50.316892) (xy 106.318812 -50.243232) (xy 106.157014 -50.40503)
			(xy 106.230674 -50.604166) (xy 106.26217 -50.635662)
		)
		(stroke
			(width 0)
			(type solid)
		)
		(fill yes)
		(layer "In4.Cu")
		(net "M_H_DQ<32>")
	)
	(gr_poly
		(pts
			(xy 106.660696 -50.842926) (xy 106.587036 -50.643536) (xy 106.55554 -50.61204) (xy 106.268266 -50.899314)
			(xy 106.299508 -50.93081) (xy 106.498898 -51.00447)
		)
		(stroke
			(width 0)
			(type solid)
		)
		(fill yes)
		(layer "In4.Cu")
		(net "M_H_DQ<33>")
	)
	(gr_poly
		(pts
			(xy 106.675174 -47.973488) (xy 106.675174 -47.744888) (xy 106.482134 -47.655988) (xy 106.437684 -47.655988)
			(xy 106.437684 -48.062388) (xy 106.482134 -48.062388)
		)
		(stroke
			(width 0)
			(type solid)
		)
		(fill yes)
		(layer "In4.Cu")
		(net "M_H_DQ<37>")
	)
	(gr_poly
		(pts
			(xy 106.675174 -46.982888) (xy 106.675174 -46.754288) (xy 106.482134 -46.665388) (xy 106.437684 -46.665388)
			(xy 106.437684 -47.071788) (xy 106.482134 -47.071788)
		)
		(stroke
			(width 0)
			(type solid)
		)
		(fill yes)
		(layer "In4.Cu")
		(net "M_H_DQ<37>")
	)
	(gr_poly
		(pts
			(xy 106.715814 -104.31653) (xy 106.671364 -104.31653) (xy 106.478324 -104.40543) (xy 106.478324 -104.63403)
			(xy 106.671364 -104.72293) (xy 106.715814 -104.72293)
		)
		(stroke
			(width 0)
			(type solid)
		)
		(fill yes)
		(layer "In4.Cu")
		(net "M_L_DQ<36>")
	)
	(gr_poly
		(pts
			(xy 106.715814 -103.32593) (xy 106.671364 -103.32593) (xy 106.478324 -103.41483) (xy 106.478324 -103.64343)
			(xy 106.671364 -103.73233) (xy 106.715814 -103.73233)
		)
		(stroke
			(width 0)
			(type solid)
		)
		(fill yes)
		(layer "In4.Cu")
		(net "M_L_DQ<36>")
	)
	(gr_poly
		(pts
			(xy 106.730038 -49.391062) (xy 106.685588 -49.391062) (xy 106.492548 -49.479962) (xy 106.492548 -49.708562)
			(xy 106.685588 -49.797462) (xy 106.730038 -49.797462)
		)
		(stroke
			(width 0)
			(type solid)
		)
		(fill yes)
		(layer "In4.Cu")
		(net "M_H_DQ<32>")
	)
	(gr_poly
		(pts
			(xy 106.736896 -102.064058) (xy 106.736896 -101.835458) (xy 106.543856 -101.746558) (xy 106.499406 -101.746558)
			(xy 106.499406 -102.152958) (xy 106.543856 -102.152958)
		)
		(stroke
			(width 0)
			(type solid)
		)
		(fill yes)
		(layer "In4.Cu")
		(net "M_L_DQ<37>")
	)
	(gr_poly
		(pts
			(xy 106.736896 -101.073458) (xy 106.736896 -100.844858) (xy 106.543856 -100.755958) (xy 106.499406 -100.755958)
			(xy 106.499406 -101.162358) (xy 106.543856 -101.162358)
		)
		(stroke
			(width 0)
			(type solid)
		)
		(fill yes)
		(layer "In4.Cu")
		(net "M_L_DQ<37>")
	)
	(gr_poly
		(pts
			(xy 106.736896 -100.082858) (xy 106.736896 -99.854258) (xy 106.543856 -99.765358) (xy 106.499406 -99.765358)
			(xy 106.499406 -100.171758) (xy 106.543856 -100.171758)
		)
		(stroke
			(width 0)
			(type solid)
		)
		(fill yes)
		(layer "In4.Cu")
		(net "M_L_DQ<37>")
	)
	(gr_poly
		(pts
			(xy 106.757724 -52.24653) (xy 106.713274 -52.24653) (xy 106.520234 -52.33543) (xy 106.520234 -52.56403)
			(xy 106.713274 -52.65293) (xy 106.757724 -52.65293)
		)
		(stroke
			(width 0)
			(type solid)
		)
		(fill yes)
		(layer "In4.Cu")
		(net "M_H_DQS_DP<13>")
	)
	(gr_poly
		(pts
			(xy 106.814874 -98.140012) (xy 106.783378 -98.108516) (xy 106.584242 -98.034856) (xy 106.422444 -98.196654)
			(xy 106.496104 -98.39579) (xy 106.5276 -98.427286)
		)
		(stroke
			(width 0)
			(type solid)
		)
		(fill yes)
		(layer "In4.Cu")
		(net "M_L_DQ<36>")
	)
	(gr_poly
		(pts
			(xy 106.880406 -53.644292) (xy 106.835956 -53.644292) (xy 106.642916 -53.733192) (xy 106.642916 -53.961792)
			(xy 106.835956 -54.050692) (xy 106.880406 -54.050692)
		)
		(stroke
			(width 0)
			(type solid)
		)
		(fill yes)
		(layer "In4.Cu")
		(net "M_H_DQS_DP<13>")
	)
	(gr_poly
		(pts
			(xy 106.987848 -55.05577) (xy 106.97972 -54.864) (xy 106.957622 -54.825646) (xy 106.612182 -55.024782)
			(xy 106.634534 -55.06339) (xy 106.796586 -55.16626)
		)
		(stroke
			(width 0)
			(type solid)
		)
		(fill yes)
		(layer "In4.Cu")
		(net "M_H_DQS_DN<13>")
	)
	(gr_poly
		(pts
			(xy 107.014264 -48.057308) (xy 106.969814 -48.057308) (xy 106.776774 -48.146208) (xy 106.776774 -48.374808)
			(xy 106.969814 -48.463708) (xy 107.014264 -48.463708)
		)
		(stroke
			(width 0)
			(type solid)
		)
		(fill yes)
		(layer "In4.Cu")
		(net "M_H_DQ<32>")
	)
	(gr_poly
		(pts
			(xy 107.014264 -47.066708) (xy 106.969814 -47.066708) (xy 106.776774 -47.155608) (xy 106.776774 -47.384208)
			(xy 106.969814 -47.473108) (xy 107.014264 -47.473108)
		)
		(stroke
			(width 0)
			(type solid)
		)
		(fill yes)
		(layer "In4.Cu")
		(net "M_H_DQ<32>")
	)
	(gr_poly
		(pts
			(xy 107.033314 -101.269292) (xy 106.988864 -101.269292) (xy 106.795824 -101.358192) (xy 106.795824 -101.586792)
			(xy 106.988864 -101.675692) (xy 107.033314 -101.675692)
		)
		(stroke
			(width 0)
			(type solid)
		)
		(fill yes)
		(layer "In4.Cu")
		(net "M_L_DQ<32>")
	)
	(gr_poly
		(pts
			(xy 107.033314 -100.278692) (xy 106.988864 -100.278692) (xy 106.795824 -100.367592) (xy 106.795824 -100.596192)
			(xy 106.988864 -100.685092) (xy 107.033314 -100.685092)
		)
		(stroke
			(width 0)
			(type solid)
		)
		(fill yes)
		(layer "In4.Cu")
		(net "M_L_DQ<32>")
	)
	(gr_poly
		(pts
			(xy 107.033314 -99.288092) (xy 106.988864 -99.288092) (xy 106.795824 -99.376992) (xy 106.795824 -99.605592)
			(xy 106.988864 -99.694492) (xy 107.033314 -99.694492)
		)
		(stroke
			(width 0)
			(type solid)
		)
		(fill yes)
		(layer "In4.Cu")
		(net "M_L_DQ<32>")
	)
	(gr_poly
		(pts
			(xy 107.033314 -97.321624) (xy 106.988864 -97.321624) (xy 106.795824 -97.410524) (xy 106.795824 -97.639124)
			(xy 106.988864 -97.728024) (xy 107.033314 -97.728024)
		)
		(stroke
			(width 0)
			(type solid)
		)
		(fill yes)
		(layer "In4.Cu")
		(net "M_L_DQ<36>")
	)
	(gr_poly
		(pts
			(xy 107.033314 -96.331024) (xy 106.988864 -96.331024) (xy 106.795824 -96.419924) (xy 106.795824 -96.648524)
			(xy 106.988864 -96.737424) (xy 107.033314 -96.737424)
		)
		(stroke
			(width 0)
			(type solid)
		)
		(fill yes)
		(layer "In4.Cu")
		(net "M_L_DQ<36>")
	)
	(gr_poly
		(pts
			(xy 107.054396 -98.50501) (xy 106.980736 -98.305874) (xy 106.94924 -98.274378) (xy 106.661966 -98.561652)
			(xy 106.693462 -98.593148) (xy 106.892598 -98.666808)
		)
		(stroke
			(width 0)
			(type solid)
		)
		(fill yes)
		(layer "In4.Cu")
		(net "M_L_DQ<37>")
	)
	(gr_poly
		(pts
			(xy 107.143804 -104.63403) (xy 107.143804 -104.40543) (xy 106.950764 -104.31653) (xy 106.906314 -104.31653)
			(xy 106.906314 -104.72293) (xy 106.950764 -104.72293)
		)
		(stroke
			(width 0)
			(type solid)
		)
		(fill yes)
		(layer "In4.Cu")
		(net "M_L_DQ<37>")
	)
	(gr_poly
		(pts
			(xy 107.143804 -103.64343) (xy 107.143804 -103.41483) (xy 106.950764 -103.32593) (xy 106.906314 -103.32593)
			(xy 106.906314 -103.73233) (xy 106.950764 -103.73233)
		)
		(stroke
			(width 0)
			(type solid)
		)
		(fill yes)
		(layer "In4.Cu")
		(net "M_L_DQ<37>")
	)
	(gr_poly
		(pts
			(xy 107.157774 -49.708562) (xy 107.157774 -49.479962) (xy 106.964734 -49.391062) (xy 106.920284 -49.391062)
			(xy 106.920284 -49.797462) (xy 106.964734 -49.797462)
		)
		(stroke
			(width 0)
			(type solid)
		)
		(fill yes)
		(layer "In4.Cu")
		(net "M_H_DQ<33>")
	)
	(gr_poly
		(pts
			(xy 107.185714 -52.56403) (xy 107.185714 -52.33543) (xy 106.992674 -52.24653) (xy 106.948224 -52.24653)
			(xy 106.948224 -52.65293) (xy 106.992674 -52.65293)
		)
		(stroke
			(width 0)
			(type solid)
		)
		(fill yes)
		(layer "In4.Cu")
		(net "M_H_DQS_DN<13>")
	)
	(gr_poly
		(pts
			(xy 107.206542 -55.298594) (xy 107.18419 -55.26024) (xy 107.022392 -55.15737) (xy 106.830876 -55.267606)
			(xy 106.839004 -55.459376) (xy 106.861356 -55.498238)
		)
		(stroke
			(width 0)
			(type solid)
		)
		(fill yes)
		(layer "In4.Cu")
		(net "M_H_DQS_DN<4>")
	)
	(gr_poly
		(pts
			(xy 107.212638 -51.371246) (xy 107.181142 -51.33975) (xy 106.982006 -51.26609) (xy 106.820208 -51.427888)
			(xy 106.893868 -51.627024) (xy 106.925364 -51.65852)
		)
		(stroke
			(width 0)
			(type solid)
		)
		(fill yes)
		(layer "In4.Cu")
		(net "M_H_DQS_DP<13>")
	)
	(gr_poly
		(pts
			(xy 107.286044 -57.501028) (xy 107.286044 -57.280048) (xy 107.115864 -57.191148) (xy 107.071414 -57.191148)
			(xy 107.071414 -57.589928) (xy 107.115864 -57.589928)
		)
		(stroke
			(width 0)
			(type solid)
		)
		(fill yes)
		(layer "In4.Cu")
		(net "M_H_DQS_DP<4>")
	)
	(gr_poly
		(pts
			(xy 107.308396 -53.961792) (xy 107.308396 -53.733192) (xy 107.115356 -53.644292) (xy 107.070906 -53.644292)
			(xy 107.070906 -54.050692) (xy 107.115356 -54.050692)
		)
		(stroke
			(width 0)
			(type solid)
		)
		(fill yes)
		(layer "In4.Cu")
		(net "M_H_DQS_DN<13>")
	)
	(gr_poly
		(pts
			(xy 107.441746 -48.374808) (xy 107.441746 -48.146208) (xy 107.248706 -48.057308) (xy 107.204256 -48.057308)
			(xy 107.204256 -48.463708) (xy 107.248706 -48.463708)
		)
		(stroke
			(width 0)
			(type solid)
		)
		(fill yes)
		(layer "In4.Cu")
		(net "M_H_DQ<33>")
	)
	(gr_poly
		(pts
			(xy 107.441746 -47.384208) (xy 107.441746 -47.155608) (xy 107.248706 -47.066708) (xy 107.204256 -47.066708)
			(xy 107.204256 -47.473108) (xy 107.248706 -47.473108)
		)
		(stroke
			(width 0)
			(type solid)
		)
		(fill yes)
		(layer "In4.Cu")
		(net "M_H_DQ<33>")
	)
	(gr_poly
		(pts
			(xy 107.460796 -101.586792) (xy 107.460796 -101.358192) (xy 107.267756 -101.269292) (xy 107.223306 -101.269292)
			(xy 107.223306 -101.675692) (xy 107.267756 -101.675692)
		)
		(stroke
			(width 0)
			(type solid)
		)
		(fill yes)
		(layer "In4.Cu")
		(net "M_L_DQ<33>")
	)
	(gr_poly
		(pts
			(xy 107.460796 -100.596192) (xy 107.460796 -100.367592) (xy 107.267756 -100.278692) (xy 107.223306 -100.278692)
			(xy 107.223306 -100.685092) (xy 107.267756 -100.685092)
		)
		(stroke
			(width 0)
			(type solid)
		)
		(fill yes)
		(layer "In4.Cu")
		(net "M_L_DQ<33>")
	)
	(gr_poly
		(pts
			(xy 107.460796 -97.639124) (xy 107.460796 -97.410524) (xy 107.267756 -97.321624) (xy 107.223306 -97.321624)
			(xy 107.223306 -97.728024) (xy 107.267756 -97.728024)
		)
		(stroke
			(width 0)
			(type solid)
		)
		(fill yes)
		(layer "In4.Cu")
		(net "M_L_DQ<37>")
	)
	(gr_poly
		(pts
			(xy 107.510072 -50.072798) (xy 107.465622 -50.072798) (xy 107.272582 -50.161698) (xy 107.272582 -50.390298)
			(xy 107.465622 -50.479198) (xy 107.510072 -50.479198)
		)
		(stroke
			(width 0)
			(type solid)
		)
		(fill yes)
		(layer "In4.Cu")
		(net "M_H_DQS_DP<13>")
	)
	(gr_poly
		(pts
			(xy 107.510072 -49.082198) (xy 107.465622 -49.082198) (xy 107.272582 -49.171098) (xy 107.272582 -49.399698)
			(xy 107.465622 -49.488598) (xy 107.510072 -49.488598)
		)
		(stroke
			(width 0)
			(type solid)
		)
		(fill yes)
		(layer "In4.Cu")
		(net "M_H_DQS_DP<13>")
	)
	(gr_poly
		(pts
			(xy 107.554014 -51.635152) (xy 107.480354 -51.435762) (xy 107.449112 -51.404266) (xy 107.161584 -51.691794)
			(xy 107.19308 -51.723036) (xy 107.39247 -51.796696)
		)
		(stroke
			(width 0)
			(type solid)
		)
		(fill yes)
		(layer "In4.Cu")
		(net "M_H_DQS_DN<13>")
	)
	(gr_poly
		(pts
			(xy 107.617768 -103.094536) (xy 107.649264 -103.063294) (xy 107.361736 -102.775766) (xy 107.330494 -102.807262)
			(xy 107.256834 -103.006652) (xy 107.418378 -103.168196)
		)
		(stroke
			(width 0)
			(type solid)
		)
		(fill yes)
		(layer "In4.Cu")
		(net "M_L_DQ<32>")
	)
	(gr_poly
		(pts
			(xy 107.738926 -54.229762) (xy 107.694476 -54.229762) (xy 107.501436 -54.318662) (xy 107.501436 -54.547262)
			(xy 107.694476 -54.636162) (xy 107.738926 -54.636162)
		)
		(stroke
			(width 0)
			(type solid)
		)
		(fill yes)
		(layer "In4.Cu")
		(net "M_H_DQS_DN<4>")
	)
	(gr_poly
		(pts
			(xy 107.738926 -53.239162) (xy 107.694476 -53.239162) (xy 107.501436 -53.328062) (xy 107.501436 -53.556662)
			(xy 107.694476 -53.645562) (xy 107.738926 -53.645562)
		)
		(stroke
			(width 0)
			(type solid)
		)
		(fill yes)
		(layer "In4.Cu")
		(net "M_H_DQS_DN<4>")
	)
	(gr_poly
		(pts
			(xy 107.793536 -47.992792) (xy 107.749086 -47.992792) (xy 107.556046 -48.081692) (xy 107.556046 -48.310292)
			(xy 107.749086 -48.399192) (xy 107.793536 -48.399192)
		)
		(stroke
			(width 0)
			(type solid)
		)
		(fill yes)
		(layer "In4.Cu")
		(net "M_H_DQS_DP<13>")
	)
	(gr_poly
		(pts
			(xy 107.814872 -102.897432) (xy 107.888532 -102.698042) (xy 107.726988 -102.536498) (xy 107.527598 -102.610158)
			(xy 107.496102 -102.6414) (xy 107.78363 -102.928928)
		)
		(stroke
			(width 0)
			(type solid)
		)
		(fill yes)
		(layer "In4.Cu")
		(net "M_L_DQ<33>")
	)
	(gr_poly
		(pts
			(xy 107.832144 -55.546244) (xy 107.824016 -55.354474) (xy 107.801664 -55.315866) (xy 107.456478 -55.515256)
			(xy 107.47883 -55.553864) (xy 107.640628 -55.656734)
		)
		(stroke
			(width 0)
			(type solid)
		)
		(fill yes)
		(layer "In4.Cu")
		(net "M_H_DQS_DP<4>")
	)
	(gr_poly
		(pts
			(xy 107.864148 -56.703214) (xy 107.761024 -56.317896) (xy 107.718098 -56.32958) (xy 107.576874 -56.459374)
			(xy 107.634024 -56.672734) (xy 107.821222 -56.714644)
		)
		(stroke
			(width 0)
			(type solid)
		)
		(fill yes)
		(layer "In4.Cu")
		(net "M_H_DQ<39>")
	)
	(gr_poly
		(pts
			(xy 107.890818 -99.292156) (xy 107.846368 -99.292156) (xy 107.676188 -99.381056) (xy 107.676188 -99.602036)
			(xy 107.846368 -99.690936) (xy 107.890818 -99.690936)
		)
		(stroke
			(width 0)
			(type solid)
		)
		(fill yes)
		(layer "In4.Cu")
		(net "M_L_DQS_DP<13>")
	)
	(gr_poly
		(pts
			(xy 107.890818 -98.301556) (xy 107.846368 -98.301556) (xy 107.676188 -98.390456) (xy 107.676188 -98.611436)
			(xy 107.846368 -98.700336) (xy 107.890818 -98.700336)
		)
		(stroke
			(width 0)
			(type solid)
		)
		(fill yes)
		(layer "In4.Cu")
		(net "M_L_DQS_DP<13>")
	)
	(gr_poly
		(pts
			(xy 107.890818 -97.310956) (xy 107.846368 -97.310956) (xy 107.676188 -97.399856) (xy 107.676188 -97.620836)
			(xy 107.846368 -97.709736) (xy 107.890818 -97.709736)
		)
		(stroke
			(width 0)
			(type solid)
		)
		(fill yes)
		(layer "In4.Cu")
		(net "M_L_DQS_DP<13>")
	)
	(gr_poly
		(pts
			(xy 107.938062 -50.923698) (xy 107.938062 -50.695098) (xy 107.745022 -50.606198) (xy 107.700572 -50.606198)
			(xy 107.700572 -51.012598) (xy 107.745022 -51.012598)
		)
		(stroke
			(width 0)
			(type solid)
		)
		(fill yes)
		(layer "In4.Cu")
		(net "M_H_DQS_DN<13>")
	)
	(gr_poly
		(pts
			(xy 107.938062 -49.933098) (xy 107.938062 -49.704498) (xy 107.745022 -49.615598) (xy 107.700572 -49.615598)
			(xy 107.700572 -50.021998) (xy 107.745022 -50.021998)
		)
		(stroke
			(width 0)
			(type solid)
		)
		(fill yes)
		(layer "In4.Cu")
		(net "M_H_DQS_DN<13>")
	)
	(gr_poly
		(pts
			(xy 107.978194 -105.422446) (xy 107.933744 -105.422446) (xy 107.740704 -105.511346) (xy 107.740704 -105.739946)
			(xy 107.933744 -105.828846) (xy 107.978194 -105.828846)
		)
		(stroke
			(width 0)
			(type solid)
		)
		(fill yes)
		(layer "In4.Cu")
		(net "M_L_DQ<32>")
	)
	(gr_poly
		(pts
			(xy 107.978194 -104.431846) (xy 107.933744 -104.431846) (xy 107.740704 -104.520746) (xy 107.740704 -104.749346)
			(xy 107.933744 -104.838246) (xy 107.978194 -104.838246)
		)
		(stroke
			(width 0)
			(type solid)
		)
		(fill yes)
		(layer "In4.Cu")
		(net "M_L_DQ<32>")
	)
	(gr_poly
		(pts
			(xy 107.978194 -103.441246) (xy 107.933744 -103.441246) (xy 107.740704 -103.530146) (xy 107.740704 -103.758746)
			(xy 107.933744 -103.847646) (xy 107.978194 -103.847646)
		)
		(stroke
			(width 0)
			(type solid)
		)
		(fill yes)
		(layer "In4.Cu")
		(net "M_L_DQ<32>")
	)
	(gr_poly
		(pts
			(xy 108.02366 -101.25075) (xy 107.97921 -101.25075) (xy 107.78617 -101.33965) (xy 107.78617 -101.56825)
			(xy 107.97921 -101.65715) (xy 108.02366 -101.65715)
		)
		(stroke
			(width 0)
			(type solid)
		)
		(fill yes)
		(layer "In4.Cu")
		(net "M_L_DQS_DP<13>")
	)
	(gr_poly
		(pts
			(xy 108.02366 -100.26015) (xy 107.97921 -100.26015) (xy 107.78617 -100.34905) (xy 107.78617 -100.57765)
			(xy 107.97921 -100.66655) (xy 108.02366 -100.66655)
		)
		(stroke
			(width 0)
			(type solid)
		)
		(fill yes)
		(layer "In4.Cu")
		(net "M_L_DQS_DP<13>")
	)
	(gr_poly
		(pts
			(xy 108.065316 -55.793894) (xy 108.042964 -55.75554) (xy 107.880912 -55.65267) (xy 107.68965 -55.76316)
			(xy 107.697778 -55.95493) (xy 107.719876 -55.993538)
		)
		(stroke
			(width 0)
			(type solid)
		)
		(fill yes)
		(layer "In4.Cu")
		(net "M_H_DQ<38>")
	)
	(gr_poly
		(pts
			(xy 108.081318 -51.5874) (xy 108.049822 -51.555904) (xy 107.850686 -51.482244) (xy 107.688888 -51.644042)
			(xy 107.762548 -51.843178) (xy 107.794044 -51.874674)
		)
		(stroke
			(width 0)
			(type solid)
		)
		(fill yes)
		(layer "In4.Cu")
		(net "M_H_DQS_DN<4>")
	)
	(gr_poly
		(pts
			(xy 108.166916 -54.648862) (xy 108.166916 -54.420262) (xy 107.973876 -54.331362) (xy 107.929426 -54.331362)
			(xy 107.929426 -54.737762) (xy 107.973876 -54.737762)
		)
		(stroke
			(width 0)
			(type solid)
		)
		(fill yes)
		(layer "In4.Cu")
		(net "M_H_DQS_DP<4>")
	)
	(gr_poly
		(pts
			(xy 108.166916 -53.658262) (xy 108.166916 -53.429662) (xy 107.973876 -53.340762) (xy 107.929426 -53.340762)
			(xy 107.929426 -53.747162) (xy 107.973876 -53.747162)
		)
		(stroke
			(width 0)
			(type solid)
		)
		(fill yes)
		(layer "In4.Cu")
		(net "M_H_DQS_DP<4>")
	)
	(gr_poly
		(pts
			(xy 108.221526 -48.310292) (xy 108.221526 -48.081692) (xy 108.028486 -47.992792) (xy 107.984036 -47.992792)
			(xy 107.984036 -48.399192) (xy 108.028486 -48.399192)
		)
		(stroke
			(width 0)
			(type solid)
		)
		(fill yes)
		(layer "In4.Cu")
		(net "M_H_DQS_DN<13>")
	)
	(gr_poly
		(pts
			(xy 108.277152 -50.639472) (xy 108.232702 -50.639472) (xy 108.039662 -50.728372) (xy 108.039662 -50.956972)
			(xy 108.232702 -51.045872) (xy 108.277152 -51.045872)
		)
		(stroke
			(width 0)
			(type solid)
		)
		(fill yes)
		(layer "In4.Cu")
		(net "M_H_DQS_DN<4>")
	)
	(gr_poly
		(pts
			(xy 108.277152 -49.648872) (xy 108.232702 -49.648872) (xy 108.039662 -49.737772) (xy 108.039662 -49.966372)
			(xy 108.232702 -50.055272) (xy 108.277152 -50.055272)
		)
		(stroke
			(width 0)
			(type solid)
		)
		(fill yes)
		(layer "In4.Cu")
		(net "M_H_DQS_DN<4>")
	)
	(gr_poly
		(pts
			(xy 108.397294 -51.876706) (xy 108.323634 -51.677316) (xy 108.292392 -51.64582) (xy 108.004864 -51.933348)
			(xy 108.03636 -51.96459) (xy 108.23575 -52.03825)
		)
		(stroke
			(width 0)
			(type solid)
		)
		(fill yes)
		(layer "In4.Cu")
		(net "M_H_DQS_DP<4>")
	)
	(gr_poly
		(pts
			(xy 108.405676 -105.739946) (xy 108.405676 -105.511346) (xy 108.212636 -105.422446) (xy 108.168186 -105.422446)
			(xy 108.168186 -105.828846) (xy 108.212636 -105.828846)
		)
		(stroke
			(width 0)
			(type solid)
		)
		(fill yes)
		(layer "In4.Cu")
		(net "M_L_DQ<33>")
	)
	(gr_poly
		(pts
			(xy 108.405676 -104.749346) (xy 108.405676 -104.520746) (xy 108.212636 -104.431846) (xy 108.168186 -104.431846)
			(xy 108.168186 -104.838246) (xy 108.212636 -104.838246)
		)
		(stroke
			(width 0)
			(type solid)
		)
		(fill yes)
		(layer "In4.Cu")
		(net "M_L_DQ<33>")
	)
	(gr_poly
		(pts
			(xy 108.405676 -103.758746) (xy 108.405676 -103.530146) (xy 108.212636 -103.441246) (xy 108.168186 -103.441246)
			(xy 108.168186 -103.847646) (xy 108.212636 -103.847646)
		)
		(stroke
			(width 0)
			(type solid)
		)
		(fill yes)
		(layer "In4.Cu")
		(net "M_L_DQ<33>")
	)
	(gr_poly
		(pts
			(xy 108.429044 -99.106736) (xy 108.429044 -98.885756) (xy 108.258864 -98.796856) (xy 108.214414 -98.796856)
			(xy 108.214414 -99.195636) (xy 108.258864 -99.195636)
		)
		(stroke
			(width 0)
			(type solid)
		)
		(fill yes)
		(layer "In4.Cu")
		(net "M_L_DQS_DN<13>")
	)
	(gr_poly
		(pts
			(xy 108.429044 -98.116136) (xy 108.429044 -97.895156) (xy 108.258864 -97.806256) (xy 108.214414 -97.806256)
			(xy 108.214414 -98.205036) (xy 108.258864 -98.205036)
		)
		(stroke
			(width 0)
			(type solid)
		)
		(fill yes)
		(layer "In4.Cu")
		(net "M_L_DQS_DN<13>")
	)
	(gr_poly
		(pts
			(xy 108.436156 -46.756828) (xy 108.40466 -46.725332) (xy 108.205524 -46.651672) (xy 108.043726 -46.81347)
			(xy 108.117386 -47.012606) (xy 108.148882 -47.044102)
		)
		(stroke
			(width 0)
			(type solid)
		)
		(fill yes)
		(layer "In4.Cu")
		(net "M_H_DQS_DP<13>")
	)
	(gr_poly
		(pts
			(xy 108.45165 -101.56825) (xy 108.45165 -101.33965) (xy 108.25861 -101.25075) (xy 108.21416 -101.25075)
			(xy 108.21416 -101.65715) (xy 108.25861 -101.65715)
		)
		(stroke
			(width 0)
			(type solid)
		)
		(fill yes)
		(layer "In4.Cu")
		(net "M_L_DQS_DN<13>")
	)
	(gr_poly
		(pts
			(xy 108.45165 -100.57765) (xy 108.45165 -100.34905) (xy 108.25861 -100.26015) (xy 108.21416 -100.26015)
			(xy 108.21416 -100.66655) (xy 108.25861 -100.66655)
		)
		(stroke
			(width 0)
			(type solid)
		)
		(fill yes)
		(layer "In4.Cu")
		(net "M_L_DQS_DN<13>")
	)
	(gr_poly
		(pts
			(xy 108.464858 -54.714394) (xy 108.420408 -54.714394) (xy 108.250228 -54.803294) (xy 108.250228 -55.024274)
			(xy 108.420408 -55.113174) (xy 108.464858 -55.113174)
		)
		(stroke
			(width 0)
			(type solid)
		)
		(fill yes)
		(layer "In4.Cu")
		(net "M_H_DQ<38>")
	)
	(gr_poly
		(pts
			(xy 108.464858 -53.723286) (xy 108.420408 -53.723286) (xy 108.250228 -53.812186) (xy 108.250228 -54.033166)
			(xy 108.420408 -54.122066) (xy 108.464858 -54.122066)
		)
		(stroke
			(width 0)
			(type solid)
		)
		(fill yes)
		(layer "In4.Cu")
		(net "M_H_DQ<38>")
	)
	(gr_poly
		(pts
			(xy 108.675932 -47.122334) (xy 108.602272 -46.922944) (xy 108.57103 -46.891448) (xy 108.283502 -47.178976)
			(xy 108.314998 -47.210218) (xy 108.514388 -47.283878)
		)
		(stroke
			(width 0)
			(type solid)
		)
		(fill yes)
		(layer "In4.Cu")
		(net "M_H_DQS_DN<13>")
	)
	(gr_poly
		(pts
			(xy 108.680504 -45.936408) (xy 108.636054 -45.936408) (xy 108.443014 -46.025308) (xy 108.443014 -46.253908)
			(xy 108.636054 -46.342808) (xy 108.680504 -46.342808)
		)
		(stroke
			(width 0)
			(type solid)
		)
		(fill yes)
		(layer "In4.Cu")
		(net "M_H_DQS_DP<13>")
	)
	(gr_poly
		(pts
			(xy 108.691426 -52.617116) (xy 108.646976 -52.617116) (xy 108.453936 -52.706016) (xy 108.453936 -52.934616)
			(xy 108.646976 -53.023516) (xy 108.691426 -53.023516)
		)
		(stroke
			(width 0)
			(type solid)
		)
		(fill yes)
		(layer "In4.Cu")
		(net "M_H_DQ<38>")
	)
	(gr_poly
		(pts
			(xy 108.703364 -56.047386) (xy 108.695236 -55.855616) (xy 108.673138 -55.816754) (xy 108.327952 -56.016398)
			(xy 108.35005 -56.054752) (xy 108.512102 -56.157622)
		)
		(stroke
			(width 0)
			(type solid)
		)
		(fill yes)
		(layer "In4.Cu")
		(net "M_H_DQ<39>")
	)
	(gr_poly
		(pts
			(xy 108.705142 -50.956972) (xy 108.705142 -50.728372) (xy 108.512102 -50.639472) (xy 108.467652 -50.639472)
			(xy 108.467652 -51.045872) (xy 108.512102 -51.045872)
		)
		(stroke
			(width 0)
			(type solid)
		)
		(fill yes)
		(layer "In4.Cu")
		(net "M_H_DQS_DP<4>")
	)
	(gr_poly
		(pts
			(xy 108.705142 -49.966372) (xy 108.705142 -49.737772) (xy 108.512102 -49.648872) (xy 108.467652 -49.648872)
			(xy 108.467652 -50.055272) (xy 108.512102 -50.055272)
		)
		(stroke
			(width 0)
			(type solid)
		)
		(fill yes)
		(layer "In4.Cu")
		(net "M_H_DQS_DP<4>")
	)
	(gr_poly
		(pts
			(xy 108.712254 -102.773988) (xy 108.74375 -102.742746) (xy 108.456222 -102.455218) (xy 108.42498 -102.486714)
			(xy 108.35132 -102.686104) (xy 108.512864 -102.847648)
		)
		(stroke
			(width 0)
			(type solid)
		)
		(fill yes)
		(layer "In4.Cu")
		(net "M_L_DQS_DP<13>")
	)
	(gr_poly
		(pts
			(xy 108.909866 -102.576376) (xy 108.983526 -102.37724) (xy 108.821728 -102.215442) (xy 108.622592 -102.289102)
			(xy 108.591096 -102.320598) (xy 108.87837 -102.607872)
		)
		(stroke
			(width 0)
			(type solid)
		)
		(fill yes)
		(layer "In4.Cu")
		(net "M_L_DQS_DN<13>")
	)
	(gr_poly
		(pts
			(xy 108.92536 -56.288178) (xy 108.903008 -56.249824) (xy 108.740956 -56.146954) (xy 108.549694 -56.257444)
			(xy 108.557822 -56.449214) (xy 108.57992 -56.487822)
		)
		(stroke
			(width 0)
			(type solid)
		)
		(fill yes)
		(layer "In4.Cu")
		(net "M_H_DQ<34>")
	)
	(gr_poly
		(pts
			(xy 108.938822 -47.350934) (xy 108.907326 -47.319438) (xy 108.70819 -47.245778) (xy 108.546392 -47.407576)
			(xy 108.620052 -47.606712) (xy 108.651548 -47.638208)
		)
		(stroke
			(width 0)
			(type solid)
		)
		(fill yes)
		(layer "In4.Cu")
		(net "M_H_DQS_DN<4>")
	)
	(gr_poly
		(pts
			(xy 108.940092 -97.800668) (xy 108.895642 -97.800668) (xy 108.725462 -97.889568) (xy 108.725462 -98.110548)
			(xy 108.895642 -98.199448) (xy 108.940092 -98.199448)
		)
		(stroke
			(width 0)
			(type solid)
		)
		(fill yes)
		(layer "In4.Cu")
		(net "M_L_DQ<38>")
	)
	(gr_poly
		(pts
			(xy 109.003084 -55.51932) (xy 109.003084 -55.29834) (xy 108.832904 -55.20944) (xy 108.788454 -55.20944)
			(xy 108.788454 -55.60822) (xy 108.832904 -55.60822)
		)
		(stroke
			(width 0)
			(type solid)
		)
		(fill yes)
		(layer "In4.Cu")
		(net "M_H_DQ<39>")
	)
	(gr_poly
		(pts
			(xy 109.003084 -54.52872) (xy 109.003084 -54.30774) (xy 108.832904 -54.21884) (xy 108.788454 -54.21884)
			(xy 108.788454 -54.61762) (xy 108.832904 -54.61762)
		)
		(stroke
			(width 0)
			(type solid)
		)
		(fill yes)
		(layer "In4.Cu")
		(net "M_H_DQ<39>")
	)
	(gr_poly
		(pts
			(xy 109.044232 -50.964338) (xy 108.999782 -50.964338) (xy 108.806742 -51.053238) (xy 108.806742 -51.281838)
			(xy 108.999782 -51.370738) (xy 109.044232 -51.370738)
		)
		(stroke
			(width 0)
			(type solid)
		)
		(fill yes)
		(layer "In4.Cu")
		(net "M_H_DQ<38>")
	)
	(gr_poly
		(pts
			(xy 109.044232 -49.973738) (xy 108.999782 -49.973738) (xy 108.806742 -50.062638) (xy 108.806742 -50.291238)
			(xy 108.999782 -50.380138) (xy 109.044232 -50.380138)
		)
		(stroke
			(width 0)
			(type solid)
		)
		(fill yes)
		(layer "In4.Cu")
		(net "M_H_DQ<38>")
	)
	(gr_poly
		(pts
			(xy 109.108494 -46.253908) (xy 109.108494 -46.025308) (xy 108.915454 -45.936408) (xy 108.871004 -45.936408)
			(xy 108.871004 -46.342808) (xy 108.915454 -46.342808)
		)
		(stroke
			(width 0)
			(type solid)
		)
		(fill yes)
		(layer "In4.Cu")
		(net "M_H_DQS_DN<13>")
	)
	(gr_poly
		(pts
			(xy 109.119416 -52.934616) (xy 109.119416 -52.706016) (xy 108.926376 -52.617116) (xy 108.881926 -52.617116)
			(xy 108.881926 -53.023516) (xy 108.926376 -53.023516)
		)
		(stroke
			(width 0)
			(type solid)
		)
		(fill yes)
		(layer "In4.Cu")
		(net "M_H_DQ<39>")
	)
	(gr_poly
		(pts
			(xy 109.176312 -104.883204) (xy 109.131862 -104.883204) (xy 108.938822 -104.972104) (xy 108.938822 -105.200704)
			(xy 109.131862 -105.289604) (xy 109.176312 -105.289604)
		)
		(stroke
			(width 0)
			(type solid)
		)
		(fill yes)
		(layer "In4.Cu")
		(net "M_L_DQS_DP<13>")
	)
	(gr_poly
		(pts
			(xy 109.176312 -103.892604) (xy 109.131862 -103.892604) (xy 108.938822 -103.981504) (xy 108.938822 -104.210104)
			(xy 109.131862 -104.299004) (xy 109.176312 -104.299004)
		)
		(stroke
			(width 0)
			(type solid)
		)
		(fill yes)
		(layer "In4.Cu")
		(net "M_L_DQS_DP<13>")
	)
	(gr_poly
		(pts
			(xy 109.178598 -47.71644) (xy 109.104938 -47.51705) (xy 109.073696 -47.485554) (xy 108.786168 -47.773082)
			(xy 108.817664 -47.804324) (xy 109.017054 -47.877984)
		)
		(stroke
			(width 0)
			(type solid)
		)
		(fill yes)
		(layer "In4.Cu")
		(net "M_H_DQS_DP<4>")
	)
	(gr_poly
		(pts
			(xy 109.287564 -98.617024) (xy 109.287564 -98.396044) (xy 109.117384 -98.307144) (xy 109.072934 -98.307144)
			(xy 109.072934 -98.705924) (xy 109.117384 -98.705924)
		)
		(stroke
			(width 0)
			(type solid)
		)
		(fill yes)
		(layer "In4.Cu")
		(net "M_L_DQ<38>")
	)
	(gr_poly
		(pts
			(xy 109.323124 -55.200804) (xy 109.278674 -55.200804) (xy 109.108494 -55.289704) (xy 109.108494 -55.510684)
			(xy 109.278674 -55.599584) (xy 109.323124 -55.599584)
		)
		(stroke
			(width 0)
			(type solid)
		)
		(fill yes)
		(layer "In4.Cu")
		(net "M_H_DQ<34>")
	)
	(gr_poly
		(pts
			(xy 109.323124 -54.208426) (xy 109.278674 -54.208426) (xy 109.108494 -54.297326) (xy 109.108494 -54.518306)
			(xy 109.278674 -54.607206) (xy 109.323124 -54.607206)
		)
		(stroke
			(width 0)
			(type solid)
		)
		(fill yes)
		(layer "In4.Cu")
		(net "M_H_DQ<34>")
	)
	(gr_poly
		(pts
			(xy 109.431074 -100.9904) (xy 109.46257 -100.959158) (xy 109.175296 -100.67163) (xy 109.1438 -100.703126)
			(xy 109.07014 -100.902516) (xy 109.231684 -101.06406)
		)
		(stroke
			(width 0)
			(type solid)
		)
		(fill yes)
		(layer "In4.Cu")
		(net "M_L_DQS_DN<4>")
	)
	(gr_poly
		(pts
			(xy 109.455966 -53.010816) (xy 109.411516 -53.010816) (xy 109.218476 -53.099716) (xy 109.218476 -53.328316)
			(xy 109.411516 -53.417216) (xy 109.455966 -53.417216)
		)
		(stroke
			(width 0)
			(type solid)
		)
		(fill yes)
		(layer "In4.Cu")
		(net "M_H_DQ<34>")
	)
	(gr_poly
		(pts
			(xy 109.472222 -51.281838) (xy 109.472222 -51.053238) (xy 109.279182 -50.964338) (xy 109.234732 -50.964338)
			(xy 109.234732 -51.370738) (xy 109.279182 -51.370738)
		)
		(stroke
			(width 0)
			(type solid)
		)
		(fill yes)
		(layer "In4.Cu")
		(net "M_H_DQ<39>")
	)
	(gr_poly
		(pts
			(xy 109.472222 -50.291238) (xy 109.472222 -50.062638) (xy 109.279182 -49.973738) (xy 109.234732 -49.973738)
			(xy 109.234732 -50.380138) (xy 109.279182 -50.380138)
		)
		(stroke
			(width 0)
			(type solid)
		)
		(fill yes)
		(layer "In4.Cu")
		(net "M_H_DQ<39>")
	)
	(gr_poly
		(pts
			(xy 109.557312 -56.545226) (xy 109.549184 -56.353456) (xy 109.527086 -56.314848) (xy 109.1819 -56.514492)
			(xy 109.203998 -56.552592) (xy 109.36605 -56.655716)
		)
		(stroke
			(width 0)
			(type solid)
		)
		(fill yes)
		(layer "In4.Cu")
		(net "M_H_DQ<35>")
	)
	(gr_poly
		(pts
			(xy 109.604302 -105.200704) (xy 109.604302 -104.972104) (xy 109.411262 -104.883204) (xy 109.366812 -104.883204)
			(xy 109.366812 -105.289604) (xy 109.411262 -105.289604)
		)
		(stroke
			(width 0)
			(type solid)
		)
		(fill yes)
		(layer "In4.Cu")
		(net "M_L_DQS_DN<13>")
	)
	(gr_poly
		(pts
			(xy 109.604302 -104.210104) (xy 109.604302 -103.981504) (xy 109.411262 -103.892604) (xy 109.366812 -103.892604)
			(xy 109.366812 -104.299004) (xy 109.411262 -104.299004)
		)
		(stroke
			(width 0)
			(type solid)
		)
		(fill yes)
		(layer "In4.Cu")
		(net "M_L_DQS_DN<13>")
	)
	(gr_poly
		(pts
			(xy 109.628686 -100.793042) (xy 109.702346 -100.593652) (xy 109.540802 -100.431854) (xy 109.341412 -100.505514)
			(xy 109.309916 -100.53701) (xy 109.597444 -100.824284)
		)
		(stroke
			(width 0)
			(type solid)
		)
		(fill yes)
		(layer "In4.Cu")
		(net "M_L_DQS_DP<4>")
	)
	(gr_poly
		(pts
			(xy 109.639354 -46.650402) (xy 109.607858 -46.618906) (xy 109.408722 -46.545246) (xy 109.246924 -46.707044)
			(xy 109.320584 -46.90618) (xy 109.35208 -46.937676)
		)
		(stroke
			(width 0)
			(type solid)
		)
		(fill yes)
		(layer "In4.Cu")
		(net "M_H_DQS_DN<4>")
	)
	(gr_poly
		(pts
			(xy 109.792008 -102.353618) (xy 109.747558 -102.353618) (xy 109.554518 -102.442518) (xy 109.554518 -102.671118)
			(xy 109.747558 -102.760018) (xy 109.792008 -102.760018)
		)
		(stroke
			(width 0)
			(type solid)
		)
		(fill yes)
		(layer "In4.Cu")
		(net "M_L_DQS_DN<4>")
	)
	(gr_poly
		(pts
			(xy 109.792008 -101.363018) (xy 109.747558 -101.363018) (xy 109.554518 -101.451918) (xy 109.554518 -101.680518)
			(xy 109.747558 -101.769418) (xy 109.792008 -101.769418)
		)
		(stroke
			(width 0)
			(type solid)
		)
		(fill yes)
		(layer "In4.Cu")
		(net "M_L_DQS_DN<4>")
	)
	(gr_poly
		(pts
			(xy 109.803692 -98.301556) (xy 109.759242 -98.301556) (xy 109.589062 -98.390456) (xy 109.589062 -98.611436)
			(xy 109.759242 -98.700336) (xy 109.803692 -98.700336)
		)
		(stroke
			(width 0)
			(type solid)
		)
		(fill yes)
		(layer "In4.Cu")
		(net "M_L_DQ<34>")
	)
	(gr_poly
		(pts
			(xy 109.811312 -51.142138) (xy 109.766862 -51.142138) (xy 109.573822 -51.231038) (xy 109.573822 -51.459638)
			(xy 109.766862 -51.548538) (xy 109.811312 -51.548538)
		)
		(stroke
			(width 0)
			(type solid)
		)
		(fill yes)
		(layer "In4.Cu")
		(net "M_H_DQ<34>")
	)
	(gr_poly
		(pts
			(xy 109.811312 -49.922938) (xy 109.766862 -49.922938) (xy 109.573822 -50.011838) (xy 109.573822 -50.240438)
			(xy 109.766862 -50.329338) (xy 109.811312 -50.329338)
		)
		(stroke
			(width 0)
			(type solid)
		)
		(fill yes)
		(layer "In4.Cu")
		(net "M_H_DQ<34>")
	)
	(gr_poly
		(pts
			(xy 109.83849 -99.540314) (xy 109.846618 -99.348544) (xy 109.655356 -99.238054) (xy 109.493304 -99.340924)
			(xy 109.470952 -99.379278) (xy 109.816392 -99.578922)
		)
		(stroke
			(width 0)
			(type solid)
		)
		(fill yes)
		(layer "In4.Cu")
		(net "M_L_DQ<39>")
	)
	(gr_poly
		(pts
			(xy 109.861604 -56.024018) (xy 109.861604 -55.803038) (xy 109.691424 -55.714138) (xy 109.646974 -55.714138)
			(xy 109.646974 -56.112918) (xy 109.691424 -56.112918)
		)
		(stroke
			(width 0)
			(type solid)
		)
		(fill yes)
		(layer "In4.Cu")
		(net "M_H_DQ<35>")
	)
	(gr_poly
		(pts
			(xy 109.861604 -55.033418) (xy 109.861604 -54.812438) (xy 109.691424 -54.723538) (xy 109.646974 -54.723538)
			(xy 109.646974 -55.122318) (xy 109.691424 -55.122318)
		)
		(stroke
			(width 0)
			(type solid)
		)
		(fill yes)
		(layer "In4.Cu")
		(net "M_H_DQ<35>")
	)
	(gr_poly
		(pts
			(xy 109.87913 -47.015908) (xy 109.80547 -46.816518) (xy 109.774228 -46.785022) (xy 109.4867 -47.07255)
			(xy 109.518196 -47.103792) (xy 109.717586 -47.177452)
		)
		(stroke
			(width 0)
			(type solid)
		)
		(fill yes)
		(layer "In4.Cu")
		(net "M_H_DQS_DP<4>")
	)
	(gr_poly
		(pts
			(xy 109.883448 -53.328316) (xy 109.883448 -53.099716) (xy 109.690408 -53.010816) (xy 109.645958 -53.010816)
			(xy 109.645958 -53.417216) (xy 109.690408 -53.417216)
		)
		(stroke
			(width 0)
			(type solid)
		)
		(fill yes)
		(layer "In4.Cu")
		(net "M_H_DQ<35>")
	)
	(gr_poly
		(pts
			(xy 109.90707 -47.46752) (xy 109.875574 -47.436278) (xy 109.676184 -47.362618) (xy 109.51464 -47.524162)
			(xy 109.5883 -47.723552) (xy 109.619542 -47.755048)
		)
		(stroke
			(width 0)
			(type solid)
		)
		(fill yes)
		(layer "In4.Cu")
		(net "M_H_DQ<38>")
	)
	(gr_poly
		(pts
			(xy 110.044484 -100.135182) (xy 110.066836 -100.096574) (xy 109.721396 -99.897438) (xy 109.699298 -99.935792)
			(xy 109.69117 -100.127562) (xy 109.882432 -100.238052)
		)
		(stroke
			(width 0)
			(type solid)
		)
		(fill yes)
		(layer "In4.Cu")
		(net "M_L_DQ<38>")
	)
	(gr_poly
		(pts
			(xy 110.052612 -105.372408) (xy 110.008162 -105.372408) (xy 109.815122 -105.461308) (xy 109.815122 -105.689908)
			(xy 110.008162 -105.778808) (xy 110.052612 -105.778808)
		)
		(stroke
			(width 0)
			(type solid)
		)
		(fill yes)
		(layer "In4.Cu")
		(net "M_L_DQS_DN<4>")
	)
	(gr_poly
		(pts
			(xy 110.052612 -104.381808) (xy 110.008162 -104.381808) (xy 109.815122 -104.470708) (xy 109.815122 -104.699308)
			(xy 110.008162 -104.788208) (xy 110.052612 -104.788208)
		)
		(stroke
			(width 0)
			(type solid)
		)
		(fill yes)
		(layer "In4.Cu")
		(net "M_L_DQS_DN<4>")
	)
	(gr_poly
		(pts
			(xy 110.052612 -103.391208) (xy 110.008162 -103.391208) (xy 109.815122 -103.480108) (xy 109.815122 -103.708708)
			(xy 110.008162 -103.797608) (xy 110.052612 -103.797608)
		)
		(stroke
			(width 0)
			(type solid)
		)
		(fill yes)
		(layer "In4.Cu")
		(net "M_L_DQS_DN<4>")
	)
	(gr_poly
		(pts
			(xy 110.146084 -98.116136) (xy 110.146084 -97.895156) (xy 109.975904 -97.806256) (xy 109.931454 -97.806256)
			(xy 109.931454 -98.205036) (xy 109.975904 -98.205036)
		)
		(stroke
			(width 0)
			(type solid)
		)
		(fill yes)
		(layer "In4.Cu")
		(net "M_L_DQ<34>")
	)
	(gr_poly
		(pts
			(xy 110.146338 -47.832772) (xy 110.072678 -47.633382) (xy 110.041436 -47.601886) (xy 109.753908 -47.889414)
			(xy 109.785404 -47.920656) (xy 109.984794 -47.994316)
		)
		(stroke
			(width 0)
			(type solid)
		)
		(fill yes)
		(layer "In4.Cu")
		(net "M_H_DQ<39>")
	)
	(gr_poly
		(pts
			(xy 110.219998 -102.671118) (xy 110.219998 -102.442518) (xy 110.026958 -102.353618) (xy 109.982508 -102.353618)
			(xy 109.982508 -102.760018) (xy 110.026958 -102.760018)
		)
		(stroke
			(width 0)
			(type solid)
		)
		(fill yes)
		(layer "In4.Cu")
		(net "M_L_DQS_DP<4>")
	)
	(gr_poly
		(pts
			(xy 110.219998 -101.680518) (xy 110.219998 -101.451918) (xy 110.026958 -101.363018) (xy 109.982508 -101.363018)
			(xy 109.982508 -101.769418) (xy 110.026958 -101.769418)
		)
		(stroke
			(width 0)
			(type solid)
		)
		(fill yes)
		(layer "In4.Cu")
		(net "M_L_DQS_DP<4>")
	)
	(gr_poly
		(pts
			(xy 110.239302 -51.459638) (xy 110.239302 -51.231038) (xy 110.046262 -51.142138) (xy 110.001812 -51.142138)
			(xy 110.001812 -51.548538) (xy 110.046262 -51.548538)
		)
		(stroke
			(width 0)
			(type solid)
		)
		(fill yes)
		(layer "In4.Cu")
		(net "M_H_DQ<35>")
	)
	(gr_poly
		(pts
			(xy 110.239302 -50.240438) (xy 110.239302 -50.011838) (xy 110.046262 -49.922938) (xy 110.001812 -49.922938)
			(xy 110.001812 -50.329338) (xy 110.046262 -50.329338)
		)
		(stroke
			(width 0)
			(type solid)
		)
		(fill yes)
		(layer "In4.Cu")
		(net "M_H_DQ<35>")
	)
	(gr_poly
		(pts
			(xy 110.480602 -105.689908) (xy 110.480602 -105.461308) (xy 110.287562 -105.372408) (xy 110.243112 -105.372408)
			(xy 110.243112 -105.778808) (xy 110.287562 -105.778808)
		)
		(stroke
			(width 0)
			(type solid)
		)
		(fill yes)
		(layer "In4.Cu")
		(net "M_L_DQS_DP<4>")
	)
	(gr_poly
		(pts
			(xy 110.480602 -104.699308) (xy 110.480602 -104.470708) (xy 110.287562 -104.381808) (xy 110.243112 -104.381808)
			(xy 110.243112 -104.788208) (xy 110.287562 -104.788208)
		)
		(stroke
			(width 0)
			(type solid)
		)
		(fill yes)
		(layer "In4.Cu")
		(net "M_L_DQS_DP<4>")
	)
	(gr_poly
		(pts
			(xy 110.480602 -103.708708) (xy 110.480602 -103.480108) (xy 110.287562 -103.391208) (xy 110.243112 -103.391208)
			(xy 110.243112 -103.797608) (xy 110.287562 -103.797608)
		)
		(stroke
			(width 0)
			(type solid)
		)
		(fill yes)
		(layer "In4.Cu")
		(net "M_L_DQS_DP<4>")
	)
	(gr_poly
		(pts
			(xy 110.559088 -102.376986) (xy 110.514638 -102.376986) (xy 110.321598 -102.465886) (xy 110.321598 -102.694486)
			(xy 110.514638 -102.783386) (xy 110.559088 -102.783386)
		)
		(stroke
			(width 0)
			(type solid)
		)
		(fill yes)
		(layer "In4.Cu")
		(net "M_L_DQ<38>")
	)
	(gr_poly
		(pts
			(xy 110.559088 -101.386386) (xy 110.514638 -101.386386) (xy 110.321598 -101.475286) (xy 110.321598 -101.703886)
			(xy 110.514638 -101.792786) (xy 110.559088 -101.792786)
		)
		(stroke
			(width 0)
			(type solid)
		)
		(fill yes)
		(layer "In4.Cu")
		(net "M_L_DQ<38>")
	)
	(gr_poly
		(pts
			(xy 110.559088 -100.395786) (xy 110.514638 -100.395786) (xy 110.321598 -100.484686) (xy 110.321598 -100.713286)
			(xy 110.514638 -100.802186) (xy 110.559088 -100.802186)
		)
		(stroke
			(width 0)
			(type solid)
		)
		(fill yes)
		(layer "In4.Cu")
		(net "M_L_DQ<38>")
	)
	(gr_poly
		(pts
			(xy 110.570264 -47.888398) (xy 110.538768 -47.856902) (xy 110.339378 -47.783242) (xy 110.177834 -47.94504)
			(xy 110.251494 -48.14443) (xy 110.28299 -48.175672)
		)
		(stroke
			(width 0)
			(type solid)
		)
		(fill yes)
		(layer "In4.Cu")
		(net "M_H_DQ<34>")
	)
	(gr_poly
		(pts
			(xy 110.607602 -46.766988) (xy 110.576106 -46.735746) (xy 110.376716 -46.662086) (xy 110.215172 -46.82363)
			(xy 110.288832 -47.02302) (xy 110.320074 -47.054516)
		)
		(stroke
			(width 0)
			(type solid)
		)
		(fill yes)
		(layer "In4.Cu")
		(net "M_H_DQ<38>")
	)
	(gr_poly
		(pts
			(xy 110.692946 -99.042474) (xy 110.701074 -98.850704) (xy 110.509558 -98.740468) (xy 110.34776 -98.843338)
			(xy 110.325154 -98.881692) (xy 110.670848 -99.081082)
		)
		(stroke
			(width 0)
			(type solid)
		)
		(fill yes)
		(layer "In4.Cu")
		(net "M_L_DQ<35>")
	)
	(gr_poly
		(pts
			(xy 110.69701 -100.035614) (xy 110.705138 -99.843844) (xy 110.513876 -99.733354) (xy 110.351824 -99.836224)
			(xy 110.329472 -99.874578) (xy 110.674912 -100.074222)
		)
		(stroke
			(width 0)
			(type solid)
		)
		(fill yes)
		(layer "In4.Cu")
		(net "M_L_DQ<39>")
	)
	(gr_poly
		(pts
			(xy 110.809786 -48.25365) (xy 110.736126 -48.05426) (xy 110.70463 -48.022764) (xy 110.417356 -48.310038)
			(xy 110.448598 -48.341534) (xy 110.647988 -48.415194)
		)
		(stroke
			(width 0)
			(type solid)
		)
		(fill yes)
		(layer "In4.Cu")
		(net "M_H_DQ<35>")
	)
	(gr_poly
		(pts
			(xy 110.84687 -47.13224) (xy 110.77321 -46.93285) (xy 110.741968 -46.901354) (xy 110.45444 -47.188882)
			(xy 110.485936 -47.220124) (xy 110.685326 -47.293784)
		)
		(stroke
			(width 0)
			(type solid)
		)
		(fill yes)
		(layer "In4.Cu")
		(net "M_H_DQ<39>")
	)
	(gr_poly
		(pts
			(xy 110.904274 -99.640898) (xy 110.926626 -99.60229) (xy 110.581186 -99.403154) (xy 110.559088 -99.441508)
			(xy 110.55096 -99.633278) (xy 110.742222 -99.743768)
		)
		(stroke
			(width 0)
			(type solid)
		)
		(fill yes)
		(layer "In4.Cu")
		(net "M_L_DQ<34>")
	)
	(gr_poly
		(pts
			(xy 110.98657 -102.694486) (xy 110.98657 -102.465886) (xy 110.79353 -102.376986) (xy 110.74908 -102.376986)
			(xy 110.74908 -102.783386) (xy 110.79353 -102.783386)
		)
		(stroke
			(width 0)
			(type solid)
		)
		(fill yes)
		(layer "In4.Cu")
		(net "M_L_DQ<39>")
	)
	(gr_poly
		(pts
			(xy 110.98657 -101.703886) (xy 110.98657 -101.475286) (xy 110.79353 -101.386386) (xy 110.74908 -101.386386)
			(xy 110.74908 -101.792786) (xy 110.79353 -101.792786)
		)
		(stroke
			(width 0)
			(type solid)
		)
		(fill yes)
		(layer "In4.Cu")
		(net "M_L_DQ<39>")
	)
	(gr_poly
		(pts
			(xy 110.98657 -100.713286) (xy 110.98657 -100.484686) (xy 110.79353 -100.395786) (xy 110.74908 -100.395786)
			(xy 110.74908 -100.802186) (xy 110.79353 -100.802186)
		)
		(stroke
			(width 0)
			(type solid)
		)
		(fill yes)
		(layer "In4.Cu")
		(net "M_L_DQ<39>")
	)
	(gr_poly
		(pts
			(xy 111.10849 -103.59009) (xy 111.06404 -103.59009) (xy 110.871 -103.67899) (xy 110.871 -103.90759)
			(xy 111.06404 -103.99649) (xy 111.10849 -103.99649)
		)
		(stroke
			(width 0)
			(type solid)
		)
		(fill yes)
		(layer "In4.Cu")
		(net "M_L_DQ<38>")
	)
	(gr_poly
		(pts
			(xy 111.270796 -47.187866) (xy 111.2393 -47.156624) (xy 111.03991 -47.082964) (xy 110.878366 -47.244508)
			(xy 110.952026 -47.443898) (xy 110.983268 -47.475394)
		)
		(stroke
			(width 0)
			(type solid)
		)
		(fill yes)
		(layer "In4.Cu")
		(net "M_H_DQ<34>")
	)
	(gr_poly
		(pts
			(xy 111.32566 -101.779832) (xy 111.28121 -101.779832) (xy 111.08817 -101.868732) (xy 111.08817 -102.097332)
			(xy 111.28121 -102.186232) (xy 111.32566 -102.186232)
		)
		(stroke
			(width 0)
			(type solid)
		)
		(fill yes)
		(layer "In4.Cu")
		(net "M_L_DQ<34>")
	)
	(gr_poly
		(pts
			(xy 111.32566 -100.789232) (xy 111.28121 -100.789232) (xy 111.08817 -100.878132) (xy 111.08817 -101.106732)
			(xy 111.28121 -101.195632) (xy 111.32566 -101.195632)
		)
		(stroke
			(width 0)
			(type solid)
		)
		(fill yes)
		(layer "In4.Cu")
		(net "M_L_DQ<34>")
	)
	(gr_poly
		(pts
			(xy 111.510064 -47.553118) (xy 111.436404 -47.353728) (xy 111.405162 -47.322232) (xy 111.117634 -47.60976)
			(xy 111.14913 -47.641002) (xy 111.34852 -47.714662)
		)
		(stroke
			(width 0)
			(type solid)
		)
		(fill yes)
		(layer "In4.Cu")
		(net "M_H_DQ<35>")
	)
	(gr_poly
		(pts
			(xy 111.535972 -103.90759) (xy 111.535972 -103.67899) (xy 111.342932 -103.59009) (xy 111.298482 -103.59009)
			(xy 111.298482 -103.99649) (xy 111.342932 -103.99649)
		)
		(stroke
			(width 0)
			(type solid)
		)
		(fill yes)
		(layer "In4.Cu")
		(net "M_L_DQ<39>")
	)
	(gr_poly
		(pts
			(xy 111.551466 -99.537774) (xy 111.559594 -99.346004) (xy 111.368078 -99.235768) (xy 111.20628 -99.338638)
			(xy 111.183674 -99.376992) (xy 111.529368 -99.576382)
		)
		(stroke
			(width 0)
			(type solid)
		)
		(fill yes)
		(layer "In4.Cu")
		(net "M_L_DQ<35>")
	)
	(gr_poly
		(pts
			(xy 111.69269 -100.190046) (xy 111.86287 -100.101146) (xy 111.862616 -99.88042) (xy 111.69269 -99.79152)
			(xy 111.647986 -99.791266) (xy 111.64824 -100.1903)
		)
		(stroke
			(width 0)
			(type solid)
		)
		(fill yes)
		(layer "In4.Cu")
		(net "M_L_DQ<35>")
	)
	(gr_poly
		(pts
			(xy 111.753142 -102.097332) (xy 111.753142 -101.868732) (xy 111.560102 -101.779832) (xy 111.515652 -101.779832)
			(xy 111.515652 -102.186232) (xy 111.560102 -102.186232)
		)
		(stroke
			(width 0)
			(type solid)
		)
		(fill yes)
		(layer "In4.Cu")
		(net "M_L_DQ<35>")
	)
	(gr_poly
		(pts
			(xy 111.753142 -101.106732) (xy 111.753142 -100.878132) (xy 111.560102 -100.789232) (xy 111.515652 -100.789232)
			(xy 111.515652 -101.195632) (xy 111.560102 -101.195632)
		)
		(stroke
			(width 0)
			(type solid)
		)
		(fill yes)
		(layer "In4.Cu")
		(net "M_L_DQ<35>")
	)
	(gr_poly
		(pts
			(xy 111.898684 -58.670698) (xy 111.854234 -58.670698) (xy 111.684054 -58.759598) (xy 111.684054 -58.980578)
			(xy 111.854234 -59.069478) (xy 111.898684 -59.069478)
		)
		(stroke
			(width 0)
			(type solid)
		)
		(fill yes)
		(layer "In4.Cu")
		(net "M_J_DQ<44>")
	)
	(gr_poly
		(pts
			(xy 111.898684 -57.692544) (xy 111.854234 -57.692544) (xy 111.684054 -57.781444) (xy 111.684054 -58.002424)
			(xy 111.854234 -58.091324) (xy 111.898684 -58.091324)
		)
		(stroke
			(width 0)
			(type solid)
		)
		(fill yes)
		(layer "In4.Cu")
		(net "M_J_DQ<44>")
	)
	(gr_poly
		(pts
			(xy 111.898684 -56.701944) (xy 111.854234 -56.701944) (xy 111.684054 -56.790844) (xy 111.684054 -57.011824)
			(xy 111.854234 -57.100724) (xy 111.898684 -57.100724)
		)
		(stroke
			(width 0)
			(type solid)
		)
		(fill yes)
		(layer "In4.Cu")
		(net "M_J_DQ<44>")
	)
	(gr_poly
		(pts
			(xy 111.898684 -55.711344) (xy 111.854234 -55.711344) (xy 111.684054 -55.800244) (xy 111.684054 -56.021224)
			(xy 111.854234 -56.110124) (xy 111.898684 -56.110124)
		)
		(stroke
			(width 0)
			(type solid)
		)
		(fill yes)
		(layer "In4.Cu")
		(net "M_J_DQ<44>")
	)
	(gr_poly
		(pts
			(xy 111.898684 -54.720744) (xy 111.854234 -54.720744) (xy 111.684054 -54.809644) (xy 111.684054 -55.030624)
			(xy 111.854234 -55.119524) (xy 111.898684 -55.119524)
		)
		(stroke
			(width 0)
			(type solid)
		)
		(fill yes)
		(layer "In4.Cu")
		(net "M_J_DQ<44>")
	)
	(gr_poly
		(pts
			(xy 111.898684 -53.730144) (xy 111.854234 -53.730144) (xy 111.684054 -53.819044) (xy 111.684054 -54.040024)
			(xy 111.854234 -54.128924) (xy 111.898684 -54.128924)
		)
		(stroke
			(width 0)
			(type solid)
		)
		(fill yes)
		(layer "In4.Cu")
		(net "M_J_DQ<44>")
	)
	(gr_poly
		(pts
			(xy 111.971074 -46.487588) (xy 111.939832 -46.456092) (xy 111.740442 -46.382432) (xy 111.578644 -46.543976)
			(xy 111.652304 -46.743366) (xy 111.6838 -46.774862)
		)
		(stroke
			(width 0)
			(type solid)
		)
		(fill yes)
		(layer "In4.Cu")
		(net "M_H_DQ<34>")
	)
	(gr_poly
		(pts
			(xy 111.979456 -103.270558) (xy 112.010952 -103.239062) (xy 111.723678 -102.951788) (xy 111.692182 -102.983284)
			(xy 111.618522 -103.18242) (xy 111.78032 -103.344218)
		)
		(stroke
			(width 0)
			(type solid)
		)
		(fill yes)
		(layer "In4.Cu")
		(net "M_L_DQ<34>")
	)
	(gr_poly
		(pts
			(xy 112.210596 -46.852586) (xy 112.136936 -46.653196) (xy 112.10544 -46.621954) (xy 111.818166 -46.909228)
			(xy 111.849662 -46.940724) (xy 112.049052 -47.014384)
		)
		(stroke
			(width 0)
			(type solid)
		)
		(fill yes)
		(layer "In4.Cu")
		(net "M_H_DQ<35>")
	)
	(gr_poly
		(pts
			(xy 112.232186 -103.12908) (xy 112.305846 -102.929944) (xy 112.144048 -102.768146) (xy 111.944912 -102.841806)
			(xy 111.913416 -102.873302) (xy 112.20069 -103.160576)
		)
		(stroke
			(width 0)
			(type solid)
		)
		(fill yes)
		(layer "In4.Cu")
		(net "M_L_DQ<35>")
	)
	(gr_poly
		(pts
			(xy 112.43691 -58.491628) (xy 112.43691 -58.270648) (xy 112.26673 -58.181748) (xy 112.22228 -58.181748)
			(xy 112.22228 -58.580528) (xy 112.26673 -58.580528)
		)
		(stroke
			(width 0)
			(type solid)
		)
		(fill yes)
		(layer "In4.Cu")
		(net "M_J_DQ<45>")
	)
	(gr_poly
		(pts
			(xy 112.43691 -57.494678) (xy 112.43691 -57.273698) (xy 112.26673 -57.184798) (xy 112.22228 -57.184798)
			(xy 112.22228 -57.583578) (xy 112.26673 -57.583578)
		)
		(stroke
			(width 0)
			(type solid)
		)
		(fill yes)
		(layer "In4.Cu")
		(net "M_J_DQ<45>")
	)
	(gr_poly
		(pts
			(xy 112.43691 -56.504078) (xy 112.43691 -56.283098) (xy 112.26673 -56.194198) (xy 112.22228 -56.194198)
			(xy 112.22228 -56.592978) (xy 112.26673 -56.592978)
		)
		(stroke
			(width 0)
			(type solid)
		)
		(fill yes)
		(layer "In4.Cu")
		(net "M_J_DQ<45>")
	)
	(gr_poly
		(pts
			(xy 112.43691 -55.513478) (xy 112.43691 -55.292498) (xy 112.26673 -55.203598) (xy 112.22228 -55.203598)
			(xy 112.22228 -55.602378) (xy 112.26673 -55.602378)
		)
		(stroke
			(width 0)
			(type solid)
		)
		(fill yes)
		(layer "In4.Cu")
		(net "M_J_DQ<45>")
	)
	(gr_poly
		(pts
			(xy 112.43691 -54.522878) (xy 112.43691 -54.301898) (xy 112.26673 -54.212998) (xy 112.22228 -54.212998)
			(xy 112.22228 -54.611778) (xy 112.26673 -54.611778)
		)
		(stroke
			(width 0)
			(type solid)
		)
		(fill yes)
		(layer "In4.Cu")
		(net "M_J_DQ<45>")
	)
	(gr_poly
		(pts
			(xy 112.43691 -53.532278) (xy 112.43691 -53.311298) (xy 112.26673 -53.222398) (xy 112.22228 -53.222398)
			(xy 112.22228 -53.621178) (xy 112.26673 -53.621178)
		)
		(stroke
			(width 0)
			(type solid)
		)
		(fill yes)
		(layer "In4.Cu")
		(net "M_J_DQ<45>")
	)
	(gr_poly
		(pts
			(xy 112.48136 -51.331368) (xy 112.449864 -51.299872) (xy 112.250474 -51.226212) (xy 112.08893 -51.38801)
			(xy 112.16259 -51.5874) (xy 112.194086 -51.618642)
		)
		(stroke
			(width 0)
			(type solid)
		)
		(fill yes)
		(layer "In4.Cu")
		(net "M_J_DQ<44>")
	)
	(gr_poly
		(pts
			(xy 112.698022 -52.660042) (xy 112.653572 -52.660042) (xy 112.460532 -52.748942) (xy 112.460532 -52.977542)
			(xy 112.653572 -53.066442) (xy 112.698022 -53.066442)
		)
		(stroke
			(width 0)
			(type solid)
		)
		(fill yes)
		(layer "In4.Cu")
		(net "M_J_DQ<40>")
	)
	(gr_poly
		(pts
			(xy 112.721136 -51.696874) (xy 112.647476 -51.497484) (xy 112.61598 -51.466242) (xy 112.328706 -51.753516)
			(xy 112.360202 -51.785012) (xy 112.559592 -51.858672)
		)
		(stroke
			(width 0)
			(type solid)
		)
		(fill yes)
		(layer "In4.Cu")
		(net "M_J_DQ<45>")
	)
	(gr_poly
		(pts
			(xy 112.757204 -58.181748) (xy 112.712754 -58.181748) (xy 112.542574 -58.270648) (xy 112.542574 -58.491628)
			(xy 112.712754 -58.580528) (xy 112.757204 -58.580528)
		)
		(stroke
			(width 0)
			(type solid)
		)
		(fill yes)
		(layer "In4.Cu")
		(net "M_J_DQ<40>")
	)
	(gr_poly
		(pts
			(xy 112.757204 -57.184798) (xy 112.712754 -57.184798) (xy 112.542574 -57.273698) (xy 112.542574 -57.494678)
			(xy 112.712754 -57.583578) (xy 112.757204 -57.583578)
		)
		(stroke
			(width 0)
			(type solid)
		)
		(fill yes)
		(layer "In4.Cu")
		(net "M_J_DQ<40>")
	)
	(gr_poly
		(pts
			(xy 112.757204 -56.194198) (xy 112.712754 -56.194198) (xy 112.542574 -56.283098) (xy 112.542574 -56.504078)
			(xy 112.712754 -56.592978) (xy 112.757204 -56.592978)
		)
		(stroke
			(width 0)
			(type solid)
		)
		(fill yes)
		(layer "In4.Cu")
		(net "M_J_DQ<40>")
	)
	(gr_poly
		(pts
			(xy 112.757204 -55.203598) (xy 112.712754 -55.203598) (xy 112.542574 -55.292498) (xy 112.542574 -55.513478)
			(xy 112.712754 -55.602378) (xy 112.757204 -55.602378)
		)
		(stroke
			(width 0)
			(type solid)
		)
		(fill yes)
		(layer "In4.Cu")
		(net "M_J_DQ<40>")
	)
	(gr_poly
		(pts
			(xy 112.757204 -54.212998) (xy 112.712754 -54.212998) (xy 112.542574 -54.301898) (xy 112.542574 -54.522878)
			(xy 112.712754 -54.611778) (xy 112.757204 -54.611778)
		)
		(stroke
			(width 0)
			(type solid)
		)
		(fill yes)
		(layer "In4.Cu")
		(net "M_J_DQ<40>")
	)
	(gr_poly
		(pts
			(xy 113.126012 -52.977542) (xy 113.126012 -52.748942) (xy 112.932972 -52.660042) (xy 112.888522 -52.660042)
			(xy 112.888522 -53.066442) (xy 112.932972 -53.066442)
		)
		(stroke
			(width 0)
			(type solid)
		)
		(fill yes)
		(layer "In4.Cu")
		(net "M_J_DQ<41>")
	)
	(gr_poly
		(pts
			(xy 113.181892 -50.630836) (xy 113.150396 -50.599594) (xy 112.951006 -50.525934) (xy 112.789462 -50.687478)
			(xy 112.863122 -50.886868) (xy 112.894364 -50.918364)
		)
		(stroke
			(width 0)
			(type solid)
		)
		(fill yes)
		(layer "In4.Cu")
		(net "M_J_DQ<44>")
	)
	(gr_poly
		(pts
			(xy 113.29543 -58.002424) (xy 113.29543 -57.781444) (xy 113.12525 -57.692544) (xy 113.0808 -57.692544)
			(xy 113.0808 -58.091324) (xy 113.12525 -58.091324)
		)
		(stroke
			(width 0)
			(type solid)
		)
		(fill yes)
		(layer "In4.Cu")
		(net "M_J_DQ<41>")
	)
	(gr_poly
		(pts
			(xy 113.29543 -57.011824) (xy 113.29543 -56.790844) (xy 113.12525 -56.701944) (xy 113.0808 -56.701944)
			(xy 113.0808 -57.100724) (xy 113.12525 -57.100724)
		)
		(stroke
			(width 0)
			(type solid)
		)
		(fill yes)
		(layer "In4.Cu")
		(net "M_J_DQ<41>")
	)
	(gr_poly
		(pts
			(xy 113.29543 -56.021224) (xy 113.29543 -55.800244) (xy 113.12525 -55.711344) (xy 113.0808 -55.711344)
			(xy 113.0808 -56.110124) (xy 113.12525 -56.110124)
		)
		(stroke
			(width 0)
			(type solid)
		)
		(fill yes)
		(layer "In4.Cu")
		(net "M_J_DQ<41>")
	)
	(gr_poly
		(pts
			(xy 113.29543 -55.030624) (xy 113.29543 -54.809644) (xy 113.12525 -54.720744) (xy 113.0808 -54.720744)
			(xy 113.0808 -55.119524) (xy 113.12525 -55.119524)
		)
		(stroke
			(width 0)
			(type solid)
		)
		(fill yes)
		(layer "In4.Cu")
		(net "M_J_DQ<41>")
	)
	(gr_poly
		(pts
			(xy 113.29543 -54.040024) (xy 113.29543 -53.819044) (xy 113.12525 -53.730144) (xy 113.0808 -53.730144)
			(xy 113.0808 -54.128924) (xy 113.12525 -54.128924)
		)
		(stroke
			(width 0)
			(type solid)
		)
		(fill yes)
		(layer "In4.Cu")
		(net "M_J_DQ<41>")
	)
	(gr_poly
		(pts
			(xy 113.421668 -50.996342) (xy 113.348008 -50.797206) (xy 113.316512 -50.76571) (xy 113.029238 -51.052984)
			(xy 113.060734 -51.08448) (xy 113.25987 -51.15814)
		)
		(stroke
			(width 0)
			(type solid)
		)
		(fill yes)
		(layer "In4.Cu")
		(net "M_J_DQ<45>")
	)
	(gr_poly
		(pts
			(xy 113.497868 -49.71923) (xy 113.453418 -49.719484) (xy 113.260378 -49.808384) (xy 113.260378 -50.03673)
			(xy 113.453418 -50.12563) (xy 113.497868 -50.125884)
		)
		(stroke
			(width 0)
			(type solid)
		)
		(fill yes)
		(layer "In4.Cu")
		(net "M_J_DQ<44>")
	)
	(gr_poly
		(pts
			(xy 113.615724 -57.692544) (xy 113.571274 -57.692544) (xy 113.401094 -57.781444) (xy 113.401094 -58.002424)
			(xy 113.571274 -58.091324) (xy 113.615724 -58.091324)
		)
		(stroke
			(width 0)
			(type solid)
		)
		(fill yes)
		(layer "In4.Cu")
		(net "M_J_DQS_DP<14>")
	)
	(gr_poly
		(pts
			(xy 113.615724 -56.701944) (xy 113.571274 -56.701944) (xy 113.401094 -56.790844) (xy 113.401094 -57.011824)
			(xy 113.571274 -57.100724) (xy 113.615724 -57.100724)
		)
		(stroke
			(width 0)
			(type solid)
		)
		(fill yes)
		(layer "In4.Cu")
		(net "M_J_DQS_DP<14>")
	)
	(gr_poly
		(pts
			(xy 113.615724 -55.711344) (xy 113.571274 -55.711344) (xy 113.401094 -55.800244) (xy 113.401094 -56.021224)
			(xy 113.571274 -56.110124) (xy 113.615724 -56.110124)
		)
		(stroke
			(width 0)
			(type solid)
		)
		(fill yes)
		(layer "In4.Cu")
		(net "M_J_DQS_DP<14>")
	)
	(gr_poly
		(pts
			(xy 113.615724 -54.720744) (xy 113.571274 -54.720744) (xy 113.401094 -54.809644) (xy 113.401094 -55.030624)
			(xy 113.571274 -55.119524) (xy 113.615724 -55.119524)
		)
		(stroke
			(width 0)
			(type solid)
		)
		(fill yes)
		(layer "In4.Cu")
		(net "M_J_DQS_DP<14>")
	)
	(gr_poly
		(pts
			(xy 113.615724 -53.723794) (xy 113.571274 -53.723794) (xy 113.401094 -53.812694) (xy 113.401094 -54.033674)
			(xy 113.571274 -54.122574) (xy 113.615724 -54.122574)
		)
		(stroke
			(width 0)
			(type solid)
		)
		(fill yes)
		(layer "In4.Cu")
		(net "M_J_DQS_DP<14>")
	)
	(gr_poly
		(pts
			(xy 113.697512 -51.222656) (xy 113.666016 -51.191414) (xy 113.466626 -51.117754) (xy 113.305082 -51.279298)
			(xy 113.378742 -51.478688) (xy 113.409984 -51.510184)
		)
		(stroke
			(width 0)
			(type solid)
		)
		(fill yes)
		(layer "In4.Cu")
		(net "M_J_DQ<40>")
	)
	(gr_poly
		(pts
			(xy 113.77295 -59.85002) (xy 113.699798 -59.672474) (xy 113.665762 -59.644026) (xy 113.409222 -59.949334)
			(xy 113.443258 -59.978036) (xy 113.630964 -60.019184)
		)
		(stroke
			(width 0)
			(type solid)
		)
		(fill yes)
		(layer "In4.Cu")
		(net "M_J_DQ<41>")
	)
	(gr_poly
		(pts
			(xy 113.900204 -104.733598) (xy 113.855754 -104.733598) (xy 113.685574 -104.822498) (xy 113.685574 -105.043478)
			(xy 113.855754 -105.132378) (xy 113.900204 -105.132378)
		)
		(stroke
			(width 0)
			(type solid)
		)
		(fill yes)
		(layer "In4.Cu")
		(net "M_M_DQ<44>")
	)
	(gr_poly
		(pts
			(xy 113.900204 -102.752398) (xy 113.855754 -102.752398) (xy 113.685574 -102.841298) (xy 113.685574 -103.062278)
			(xy 113.855754 -103.151178) (xy 113.900204 -103.151178)
		)
		(stroke
			(width 0)
			(type solid)
		)
		(fill yes)
		(layer "In4.Cu")
		(net "M_M_DQ<44>")
	)
	(gr_poly
		(pts
			(xy 113.900204 -101.761798) (xy 113.855754 -101.761798) (xy 113.685574 -101.850698) (xy 113.685574 -102.071678)
			(xy 113.855754 -102.160578) (xy 113.900204 -102.160578)
		)
		(stroke
			(width 0)
			(type solid)
		)
		(fill yes)
		(layer "In4.Cu")
		(net "M_M_DQ<44>")
	)
	(gr_poly
		(pts
			(xy 113.900204 -100.771198) (xy 113.855754 -100.771198) (xy 113.685574 -100.860098) (xy 113.685574 -101.081078)
			(xy 113.855754 -101.169978) (xy 113.900204 -101.169978)
		)
		(stroke
			(width 0)
			(type solid)
		)
		(fill yes)
		(layer "In4.Cu")
		(net "M_M_DQ<44>")
	)
	(gr_poly
		(pts
			(xy 113.900204 -99.780598) (xy 113.855754 -99.780598) (xy 113.685574 -99.869498) (xy 113.685574 -100.090478)
			(xy 113.855754 -100.179378) (xy 113.900204 -100.179378)
		)
		(stroke
			(width 0)
			(type solid)
		)
		(fill yes)
		(layer "In4.Cu")
		(net "M_M_DQ<44>")
	)
	(gr_poly
		(pts
			(xy 113.900204 -98.796602) (xy 113.855754 -98.796602) (xy 113.685574 -98.885502) (xy 113.685574 -99.106482)
			(xy 113.855754 -99.195382) (xy 113.900204 -99.195382)
		)
		(stroke
			(width 0)
			(type solid)
		)
		(fill yes)
		(layer "In4.Cu")
		(net "M_M_DQ<44>")
	)
	(gr_poly
		(pts
			(xy 113.900204 -97.806002) (xy 113.855754 -97.806002) (xy 113.685574 -97.894902) (xy 113.685574 -98.115882)
			(xy 113.855754 -98.204782) (xy 113.900204 -98.204782)
		)
		(stroke
			(width 0)
			(type solid)
		)
		(fill yes)
		(layer "In4.Cu")
		(net "M_M_DQ<44>")
	)
	(gr_poly
		(pts
			(xy 113.900204 -96.815402) (xy 113.855754 -96.815402) (xy 113.685574 -96.904302) (xy 113.685574 -97.125282)
			(xy 113.855754 -97.214182) (xy 113.900204 -97.214182)
		)
		(stroke
			(width 0)
			(type solid)
		)
		(fill yes)
		(layer "In4.Cu")
		(net "M_M_DQ<44>")
	)
	(gr_poly
		(pts
			(xy 113.900204 -95.824802) (xy 113.855754 -95.824802) (xy 113.685574 -95.913702) (xy 113.685574 -96.134682)
			(xy 113.855754 -96.223582) (xy 113.900204 -96.223582)
		)
		(stroke
			(width 0)
			(type solid)
		)
		(fill yes)
		(layer "In4.Cu")
		(net "M_M_DQ<44>")
	)
	(gr_poly
		(pts
			(xy 113.900204 -94.834202) (xy 113.855754 -94.834202) (xy 113.685574 -94.923102) (xy 113.685574 -95.144082)
			(xy 113.855754 -95.232982) (xy 113.900204 -95.232982)
		)
		(stroke
			(width 0)
			(type solid)
		)
		(fill yes)
		(layer "In4.Cu")
		(net "M_M_DQ<44>")
	)
	(gr_poly
		(pts
			(xy 113.925858 -50.036984) (xy 113.925858 -49.808384) (xy 113.732818 -49.719484) (xy 113.688368 -49.719484)
			(xy 113.688368 -50.125884) (xy 113.732818 -50.125884)
		)
		(stroke
			(width 0)
			(type solid)
		)
		(fill yes)
		(layer "In4.Cu")
		(net "M_J_DQ<45>")
	)
	(gr_poly
		(pts
			(xy 113.937288 -51.588162) (xy 113.863628 -51.389026) (xy 113.832132 -51.35753) (xy 113.544858 -51.644804)
			(xy 113.576354 -51.6763) (xy 113.77549 -51.74996)
		)
		(stroke
			(width 0)
			(type solid)
		)
		(fill yes)
		(layer "In4.Cu")
		(net "M_J_DQ<41>")
	)
	(gr_poly
		(pts
			(xy 114.15395 -57.494678) (xy 114.15395 -57.273698) (xy 113.98377 -57.184798) (xy 113.93932 -57.184798)
			(xy 113.93932 -57.583578) (xy 113.98377 -57.583578)
		)
		(stroke
			(width 0)
			(type solid)
		)
		(fill yes)
		(layer "In4.Cu")
		(net "M_J_DQS_DN<14>")
	)
	(gr_poly
		(pts
			(xy 114.15395 -56.504078) (xy 114.15395 -56.283098) (xy 113.98377 -56.194198) (xy 113.93932 -56.194198)
			(xy 113.93932 -56.592978) (xy 113.98377 -56.592978)
		)
		(stroke
			(width 0)
			(type solid)
		)
		(fill yes)
		(layer "In4.Cu")
		(net "M_J_DQS_DN<14>")
	)
	(gr_poly
		(pts
			(xy 114.15395 -55.513478) (xy 114.15395 -55.292498) (xy 113.98377 -55.203598) (xy 113.93932 -55.203598)
			(xy 113.93932 -55.602378) (xy 113.98377 -55.602378)
		)
		(stroke
			(width 0)
			(type solid)
		)
		(fill yes)
		(layer "In4.Cu")
		(net "M_J_DQS_DN<14>")
	)
	(gr_poly
		(pts
			(xy 114.15395 -54.522878) (xy 114.15395 -54.301898) (xy 113.98377 -54.212998) (xy 113.93932 -54.212998)
			(xy 113.93932 -54.611778) (xy 113.98377 -54.611778)
		)
		(stroke
			(width 0)
			(type solid)
		)
		(fill yes)
		(layer "In4.Cu")
		(net "M_J_DQS_DN<14>")
	)
	(gr_poly
		(pts
			(xy 114.286792 -106.533696) (xy 114.242342 -106.533696) (xy 114.049302 -106.622596) (xy 114.049302 -106.851196)
			(xy 114.242342 -106.940096) (xy 114.286792 -106.940096)
		)
		(stroke
			(width 0)
			(type solid)
		)
		(fill yes)
		(layer "In4.Cu")
		(net "M_M_DQ<44>")
	)
	(gr_poly
		(pts
			(xy 114.297968 -49.94529) (xy 114.253518 -49.94529) (xy 114.060478 -50.03419) (xy 114.060478 -50.26279)
			(xy 114.253518 -50.35169) (xy 114.297968 -50.35169)
		)
		(stroke
			(width 0)
			(type solid)
		)
		(fill yes)
		(layer "In4.Cu")
		(net "M_J_DQ<40>")
	)
	(gr_poly
		(pts
			(xy 114.397028 -48.397414) (xy 114.365532 -48.366172) (xy 114.166142 -48.292512) (xy 114.004598 -48.454056)
			(xy 114.078258 -48.653446) (xy 114.1095 -48.684942)
		)
		(stroke
			(width 0)
			(type solid)
		)
		(fill yes)
		(layer "In4.Cu")
		(net "M_J_DQ<44>")
	)
	(gr_poly
		(pts
			(xy 114.43843 -105.551224) (xy 114.43843 -105.330244) (xy 114.26825 -105.241344) (xy 114.2238 -105.241344)
			(xy 114.2238 -105.640124) (xy 114.26825 -105.640124)
		)
		(stroke
			(width 0)
			(type solid)
		)
		(fill yes)
		(layer "In4.Cu")
		(net "M_M_DQ<45>")
	)
	(gr_poly
		(pts
			(xy 114.43843 -104.560624) (xy 114.43843 -104.339644) (xy 114.26825 -104.250744) (xy 114.2238 -104.250744)
			(xy 114.2238 -104.649524) (xy 114.26825 -104.649524)
		)
		(stroke
			(width 0)
			(type solid)
		)
		(fill yes)
		(layer "In4.Cu")
		(net "M_M_DQ<45>")
	)
	(gr_poly
		(pts
			(xy 114.43843 -103.570024) (xy 114.43843 -103.349044) (xy 114.26825 -103.260144) (xy 114.2238 -103.260144)
			(xy 114.2238 -103.658924) (xy 114.26825 -103.658924)
		)
		(stroke
			(width 0)
			(type solid)
		)
		(fill yes)
		(layer "In4.Cu")
		(net "M_M_DQ<45>")
	)
	(gr_poly
		(pts
			(xy 114.43843 -102.579424) (xy 114.43843 -102.358444) (xy 114.26825 -102.269544) (xy 114.2238 -102.269544)
			(xy 114.2238 -102.668324) (xy 114.26825 -102.668324)
		)
		(stroke
			(width 0)
			(type solid)
		)
		(fill yes)
		(layer "In4.Cu")
		(net "M_M_DQ<45>")
	)
	(gr_poly
		(pts
			(xy 114.43843 -101.588824) (xy 114.43843 -101.367844) (xy 114.26825 -101.278944) (xy 114.2238 -101.278944)
			(xy 114.2238 -101.677724) (xy 114.26825 -101.677724)
		)
		(stroke
			(width 0)
			(type solid)
		)
		(fill yes)
		(layer "In4.Cu")
		(net "M_M_DQ<45>")
	)
	(gr_poly
		(pts
			(xy 114.43843 -100.598224) (xy 114.43843 -100.377244) (xy 114.26825 -100.288344) (xy 114.2238 -100.288344)
			(xy 114.2238 -100.687124) (xy 114.26825 -100.687124)
		)
		(stroke
			(width 0)
			(type solid)
		)
		(fill yes)
		(layer "In4.Cu")
		(net "M_M_DQ<45>")
	)
	(gr_poly
		(pts
			(xy 114.43843 -99.607624) (xy 114.43843 -99.386644) (xy 114.26825 -99.297744) (xy 114.2238 -99.297744)
			(xy 114.2238 -99.696524) (xy 114.26825 -99.696524)
		)
		(stroke
			(width 0)
			(type solid)
		)
		(fill yes)
		(layer "In4.Cu")
		(net "M_M_DQ<45>")
	)
	(gr_poly
		(pts
			(xy 114.43843 -98.611182) (xy 114.43843 -98.390202) (xy 114.26825 -98.301302) (xy 114.2238 -98.301302)
			(xy 114.2238 -98.700082) (xy 114.26825 -98.700082)
		)
		(stroke
			(width 0)
			(type solid)
		)
		(fill yes)
		(layer "In4.Cu")
		(net "M_M_DQ<45>")
	)
	(gr_poly
		(pts
			(xy 114.43843 -97.620582) (xy 114.43843 -97.399602) (xy 114.26825 -97.310702) (xy 114.2238 -97.310702)
			(xy 114.2238 -97.709482) (xy 114.26825 -97.709482)
		)
		(stroke
			(width 0)
			(type solid)
		)
		(fill yes)
		(layer "In4.Cu")
		(net "M_M_DQ<45>")
	)
	(gr_poly
		(pts
			(xy 114.43843 -96.629982) (xy 114.43843 -96.409002) (xy 114.26825 -96.320102) (xy 114.2238 -96.320102)
			(xy 114.2238 -96.718882) (xy 114.26825 -96.718882)
		)
		(stroke
			(width 0)
			(type solid)
		)
		(fill yes)
		(layer "In4.Cu")
		(net "M_M_DQ<45>")
	)
	(gr_poly
		(pts
			(xy 114.457988 -47.199804) (xy 114.413538 -47.199804) (xy 114.220498 -47.288704) (xy 114.220498 -47.517304)
			(xy 114.413538 -47.606204) (xy 114.457988 -47.606204)
		)
		(stroke
			(width 0)
			(type solid)
		)
		(fill yes)
		(layer "In4.Cu")
		(net "M_J_DQ<44>")
	)
	(gr_poly
		(pts
			(xy 114.474244 -60.156598) (xy 114.429794 -60.156598) (xy 114.259614 -60.245498) (xy 114.259614 -60.466478)
			(xy 114.429794 -60.555378) (xy 114.474244 -60.555378)
		)
		(stroke
			(width 0)
			(type solid)
		)
		(fill yes)
		(layer "In4.Cu")
		(net "M_J_DQS_DP<5>")
	)
	(gr_poly
		(pts
			(xy 114.474244 -59.172348) (xy 114.429794 -59.172348) (xy 114.259614 -59.261248) (xy 114.259614 -59.482228)
			(xy 114.429794 -59.571128) (xy 114.474244 -59.571128)
		)
		(stroke
			(width 0)
			(type solid)
		)
		(fill yes)
		(layer "In4.Cu")
		(net "M_J_DQS_DP<5>")
	)
	(gr_poly
		(pts
			(xy 114.474244 -58.181748) (xy 114.429794 -58.181748) (xy 114.259614 -58.270648) (xy 114.259614 -58.491628)
			(xy 114.429794 -58.580528) (xy 114.474244 -58.580528)
		)
		(stroke
			(width 0)
			(type solid)
		)
		(fill yes)
		(layer "In4.Cu")
		(net "M_J_DQS_DP<5>")
	)
	(gr_poly
		(pts
			(xy 114.474244 -57.184798) (xy 114.429794 -57.184798) (xy 114.259614 -57.273698) (xy 114.259614 -57.494678)
			(xy 114.429794 -57.583578) (xy 114.474244 -57.583578)
		)
		(stroke
			(width 0)
			(type solid)
		)
		(fill yes)
		(layer "In4.Cu")
		(net "M_J_DQS_DP<5>")
	)
	(gr_poly
		(pts
			(xy 114.474244 -56.194198) (xy 114.429794 -56.194198) (xy 114.259614 -56.283098) (xy 114.259614 -56.504078)
			(xy 114.429794 -56.592978) (xy 114.474244 -56.592978)
		)
		(stroke
			(width 0)
			(type solid)
		)
		(fill yes)
		(layer "In4.Cu")
		(net "M_J_DQS_DP<5>")
	)
	(gr_poly
		(pts
			(xy 114.474244 -55.203598) (xy 114.429794 -55.203598) (xy 114.259614 -55.292498) (xy 114.259614 -55.513478)
			(xy 114.429794 -55.602378) (xy 114.474244 -55.602378)
		)
		(stroke
			(width 0)
			(type solid)
		)
		(fill yes)
		(layer "In4.Cu")
		(net "M_J_DQS_DP<5>")
	)
	(gr_poly
		(pts
			(xy 114.474244 -54.212998) (xy 114.429794 -54.212998) (xy 114.259614 -54.301898) (xy 114.259614 -54.522878)
			(xy 114.429794 -54.611778) (xy 114.474244 -54.611778)
		)
		(stroke
			(width 0)
			(type solid)
		)
		(fill yes)
		(layer "In4.Cu")
		(net "M_J_DQS_DP<5>")
	)
	(gr_poly
		(pts
			(xy 114.636804 -48.763174) (xy 114.563144 -48.563784) (xy 114.531648 -48.532288) (xy 114.244374 -48.819562)
			(xy 114.275616 -48.851058) (xy 114.475006 -48.924718)
		)
		(stroke
			(width 0)
			(type solid)
		)
		(fill yes)
		(layer "In4.Cu")
		(net "M_J_DQ<45>")
	)
	(gr_poly
		(pts
			(xy 114.714782 -106.79684) (xy 114.714782 -106.56824) (xy 114.521742 -106.47934) (xy 114.477292 -106.47934)
			(xy 114.477292 -106.88574) (xy 114.521742 -106.88574)
		)
		(stroke
			(width 0)
			(type solid)
		)
		(fill yes)
		(layer "In4.Cu")
		(net "M_M_DQ<45>")
	)
	(gr_poly
		(pts
			(xy 114.725958 -50.26279) (xy 114.725958 -50.03419) (xy 114.532918 -49.94529) (xy 114.488468 -49.94529)
			(xy 114.488468 -50.35169) (xy 114.532918 -50.35169)
		)
		(stroke
			(width 0)
			(type solid)
		)
		(fill yes)
		(layer "In4.Cu")
		(net "M_J_DQ<41>")
	)
	(gr_poly
		(pts
			(xy 114.758724 -105.230422) (xy 114.714274 -105.230676) (xy 114.544094 -105.319576) (xy 114.544348 -105.540302)
			(xy 114.714274 -105.629202) (xy 114.758978 -105.629456)
		)
		(stroke
			(width 0)
			(type solid)
		)
		(fill yes)
		(layer "In4.Cu")
		(net "M_M_DQ<40>")
	)
	(gr_poly
		(pts
			(xy 114.758724 -104.250744) (xy 114.714274 -104.250744) (xy 114.544094 -104.339644) (xy 114.544094 -104.560624)
			(xy 114.714274 -104.649524) (xy 114.758724 -104.649524)
		)
		(stroke
			(width 0)
			(type solid)
		)
		(fill yes)
		(layer "In4.Cu")
		(net "M_M_DQ<40>")
	)
	(gr_poly
		(pts
			(xy 114.758724 -103.260144) (xy 114.714274 -103.260144) (xy 114.544094 -103.349044) (xy 114.544094 -103.570024)
			(xy 114.714274 -103.658924) (xy 114.758724 -103.658924)
		)
		(stroke
			(width 0)
			(type solid)
		)
		(fill yes)
		(layer "In4.Cu")
		(net "M_M_DQ<40>")
	)
	(gr_poly
		(pts
			(xy 114.758724 -102.269544) (xy 114.714274 -102.269544) (xy 114.544094 -102.358444) (xy 114.544094 -102.579424)
			(xy 114.714274 -102.668324) (xy 114.758724 -102.668324)
		)
		(stroke
			(width 0)
			(type solid)
		)
		(fill yes)
		(layer "In4.Cu")
		(net "M_M_DQ<40>")
	)
	(gr_poly
		(pts
			(xy 114.758724 -101.278944) (xy 114.714274 -101.278944) (xy 114.544094 -101.367844) (xy 114.544094 -101.588824)
			(xy 114.714274 -101.677724) (xy 114.758724 -101.677724)
		)
		(stroke
			(width 0)
			(type solid)
		)
		(fill yes)
		(layer "In4.Cu")
		(net "M_M_DQ<40>")
	)
	(gr_poly
		(pts
			(xy 114.758724 -100.288344) (xy 114.714274 -100.288344) (xy 114.544094 -100.377244) (xy 114.544094 -100.598224)
			(xy 114.714274 -100.687124) (xy 114.758724 -100.687124)
		)
		(stroke
			(width 0)
			(type solid)
		)
		(fill yes)
		(layer "In4.Cu")
		(net "M_M_DQ<40>")
	)
	(gr_poly
		(pts
			(xy 114.758724 -99.291902) (xy 114.714274 -99.291902) (xy 114.544094 -99.380802) (xy 114.544094 -99.601782)
			(xy 114.714274 -99.690682) (xy 114.758724 -99.690682)
		)
		(stroke
			(width 0)
			(type solid)
		)
		(fill yes)
		(layer "In4.Cu")
		(net "M_M_DQ<40>")
	)
	(gr_poly
		(pts
			(xy 114.758724 -98.301302) (xy 114.714274 -98.301302) (xy 114.544094 -98.390202) (xy 114.544094 -98.611182)
			(xy 114.714274 -98.700082) (xy 114.758724 -98.700082)
		)
		(stroke
			(width 0)
			(type solid)
		)
		(fill yes)
		(layer "In4.Cu")
		(net "M_M_DQ<40>")
	)
	(gr_poly
		(pts
			(xy 114.758724 -97.310702) (xy 114.714274 -97.310702) (xy 114.544094 -97.399602) (xy 114.544094 -97.620582)
			(xy 114.714274 -97.709482) (xy 114.758724 -97.709482)
		)
		(stroke
			(width 0)
			(type solid)
		)
		(fill yes)
		(layer "In4.Cu")
		(net "M_M_DQ<40>")
	)
	(gr_poly
		(pts
			(xy 114.758724 -96.320102) (xy 114.714274 -96.320102) (xy 114.544094 -96.409002) (xy 114.544094 -96.629982)
			(xy 114.714274 -96.718882) (xy 114.758724 -96.718882)
		)
		(stroke
			(width 0)
			(type solid)
		)
		(fill yes)
		(layer "In4.Cu")
		(net "M_M_DQ<40>")
	)
	(gr_poly
		(pts
			(xy 114.758724 -95.329502) (xy 114.714274 -95.329502) (xy 114.544094 -95.418402) (xy 114.544094 -95.639382)
			(xy 114.714274 -95.728282) (xy 114.758724 -95.728282)
		)
		(stroke
			(width 0)
			(type solid)
		)
		(fill yes)
		(layer "In4.Cu")
		(net "M_M_DQ<40>")
	)
	(gr_poly
		(pts
			(xy 114.821462 -51.360832) (xy 114.789966 -51.32959) (xy 114.590576 -51.25593) (xy 114.429032 -51.417474)
			(xy 114.502692 -51.616864) (xy 114.533934 -51.64836)
		)
		(stroke
			(width 0)
			(type solid)
		)
		(fill yes)
		(layer "In4.Cu")
		(net "M_J_DQS_DP<14>")
	)
	(gr_poly
		(pts
			(xy 114.909854 -48.986694) (xy 114.878358 -48.955198) (xy 114.678968 -48.881538) (xy 114.517424 -49.043336)
			(xy 114.591084 -49.242726) (xy 114.62258 -49.273968)
		)
		(stroke
			(width 0)
			(type solid)
		)
		(fill yes)
		(layer "In4.Cu")
		(net "M_J_DQ<40>")
	)
	(gr_poly
		(pts
			(xy 114.917474 -47.517304) (xy 114.917474 -47.288704) (xy 114.724434 -47.199804) (xy 114.679984 -47.199804)
			(xy 114.679984 -47.606204) (xy 114.724434 -47.606204)
		)
		(stroke
			(width 0)
			(type solid)
		)
		(fill yes)
		(layer "In4.Cu")
		(net "M_J_DQ<45>")
	)
	(gr_poly
		(pts
			(xy 115.01247 -59.977274) (xy 115.01247 -59.756294) (xy 114.84229 -59.667394) (xy 114.79784 -59.667394)
			(xy 114.79784 -60.066174) (xy 114.84229 -60.066174)
		)
		(stroke
			(width 0)
			(type solid)
		)
		(fill yes)
		(layer "In4.Cu")
		(net "M_J_DQS_DN<5>")
	)
	(gr_poly
		(pts
			(xy 115.01247 -58.980578) (xy 115.01247 -58.759598) (xy 114.84229 -58.670698) (xy 114.79784 -58.670698)
			(xy 114.79784 -59.069478) (xy 114.84229 -59.069478)
		)
		(stroke
			(width 0)
			(type solid)
		)
		(fill yes)
		(layer "In4.Cu")
		(net "M_J_DQS_DN<5>")
	)
	(gr_poly
		(pts
			(xy 115.01247 -58.002424) (xy 115.01247 -57.781444) (xy 114.84229 -57.692544) (xy 114.79784 -57.692544)
			(xy 114.79784 -58.091324) (xy 114.84229 -58.091324)
		)
		(stroke
			(width 0)
			(type solid)
		)
		(fill yes)
		(layer "In4.Cu")
		(net "M_J_DQS_DN<5>")
	)
	(gr_poly
		(pts
			(xy 115.01247 -57.011824) (xy 115.01247 -56.790844) (xy 114.84229 -56.701944) (xy 114.79784 -56.701944)
			(xy 114.79784 -57.100724) (xy 114.84229 -57.100724)
		)
		(stroke
			(width 0)
			(type solid)
		)
		(fill yes)
		(layer "In4.Cu")
		(net "M_J_DQS_DN<5>")
	)
	(gr_poly
		(pts
			(xy 115.01247 -56.021224) (xy 115.01247 -55.800244) (xy 114.84229 -55.711344) (xy 114.79784 -55.711344)
			(xy 114.79784 -56.110124) (xy 114.84229 -56.110124)
		)
		(stroke
			(width 0)
			(type solid)
		)
		(fill yes)
		(layer "In4.Cu")
		(net "M_J_DQS_DN<5>")
	)
	(gr_poly
		(pts
			(xy 115.01247 -55.030624) (xy 115.01247 -54.809644) (xy 114.84229 -54.720744) (xy 114.79784 -54.720744)
			(xy 114.79784 -55.119524) (xy 114.84229 -55.119524)
		)
		(stroke
			(width 0)
			(type solid)
		)
		(fill yes)
		(layer "In4.Cu")
		(net "M_J_DQS_DN<5>")
	)
	(gr_poly
		(pts
			(xy 115.021868 -50.54981) (xy 114.977418 -50.54981) (xy 114.784378 -50.63871) (xy 114.784378 -50.86731)
			(xy 114.977418 -50.95621) (xy 115.021868 -50.95621)
		)
		(stroke
			(width 0)
			(type solid)
		)
		(fill yes)
		(layer "In4.Cu")
		(net "M_J_DQS_DP<14>")
	)
	(gr_poly
		(pts
			(xy 115.061238 -51.726338) (xy 114.987578 -51.527202) (xy 114.956082 -51.495706) (xy 114.668808 -51.78298)
			(xy 114.700304 -51.814476) (xy 114.89944 -51.888136)
		)
		(stroke
			(width 0)
			(type solid)
		)
		(fill yes)
		(layer "In4.Cu")
		(net "M_J_DQS_DN<14>")
	)
	(gr_poly
		(pts
			(xy 115.122452 -95.179388) (xy 115.213384 -94.977966) (xy 115.09502 -94.826836) (xy 115.054634 -94.808548)
			(xy 114.890296 -95.171768) (xy 114.930682 -95.190056)
		)
		(stroke
			(width 0)
			(type solid)
		)
		(fill yes)
		(layer "In4.Cu")
		(net "M_M_DQ<40>")
	)
	(gr_poly
		(pts
			(xy 115.149884 -49.352454) (xy 115.076224 -49.153064) (xy 115.044728 -49.121568) (xy 114.757454 -49.408842)
			(xy 114.788696 -49.440338) (xy 114.988086 -49.513998)
		)
		(stroke
			(width 0)
			(type solid)
		)
		(fill yes)
		(layer "In4.Cu")
		(net "M_J_DQ<41>")
	)
	(gr_poly
		(pts
			(xy 115.200684 -106.082084) (xy 115.22329 -106.04373) (xy 114.877596 -105.84434) (xy 114.855498 -105.882948)
			(xy 114.84737 -106.074718) (xy 115.038886 -106.184954)
		)
		(stroke
			(width 0)
			(type solid)
		)
		(fill yes)
		(layer "In4.Cu")
		(net "M_M_DQ<40>")
	)
	(gr_poly
		(pts
			(xy 115.29695 -105.043478) (xy 115.29695 -104.822498) (xy 115.12677 -104.733598) (xy 115.08232 -104.733598)
			(xy 115.08232 -105.132378) (xy 115.12677 -105.132378)
		)
		(stroke
			(width 0)
			(type solid)
		)
		(fill yes)
		(layer "In4.Cu")
		(net "M_M_DQ<41>")
	)
	(gr_poly
		(pts
			(xy 115.29695 -104.052878) (xy 115.29695 -103.831898) (xy 115.12677 -103.742998) (xy 115.08232 -103.742998)
			(xy 115.08232 -104.141778) (xy 115.12677 -104.141778)
		)
		(stroke
			(width 0)
			(type solid)
		)
		(fill yes)
		(layer "In4.Cu")
		(net "M_M_DQ<41>")
	)
	(gr_poly
		(pts
			(xy 115.29695 -103.062278) (xy 115.29695 -102.841298) (xy 115.12677 -102.752398) (xy 115.08232 -102.752398)
			(xy 115.08232 -103.151178) (xy 115.12677 -103.151178)
		)
		(stroke
			(width 0)
			(type solid)
		)
		(fill yes)
		(layer "In4.Cu")
		(net "M_M_DQ<41>")
	)
	(gr_poly
		(pts
			(xy 115.29695 -102.071678) (xy 115.29695 -101.850698) (xy 115.12677 -101.761798) (xy 115.08232 -101.761798)
			(xy 115.08232 -102.160578) (xy 115.12677 -102.160578)
		)
		(stroke
			(width 0)
			(type solid)
		)
		(fill yes)
		(layer "In4.Cu")
		(net "M_M_DQ<41>")
	)
	(gr_poly
		(pts
			(xy 115.29695 -101.081078) (xy 115.29695 -100.860098) (xy 115.12677 -100.771198) (xy 115.08232 -100.771198)
			(xy 115.08232 -101.169978) (xy 115.12677 -101.169978)
		)
		(stroke
			(width 0)
			(type solid)
		)
		(fill yes)
		(layer "In4.Cu")
		(net "M_M_DQ<41>")
	)
	(gr_poly
		(pts
			(xy 115.29695 -100.097082) (xy 115.29695 -99.876102) (xy 115.12677 -99.787202) (xy 115.08232 -99.787202)
			(xy 115.08232 -100.185982) (xy 115.12677 -100.185982)
		)
		(stroke
			(width 0)
			(type solid)
		)
		(fill yes)
		(layer "In4.Cu")
		(net "M_M_DQ<41>")
	)
	(gr_poly
		(pts
			(xy 115.29695 -99.106482) (xy 115.29695 -98.885502) (xy 115.12677 -98.796602) (xy 115.08232 -98.796602)
			(xy 115.08232 -99.195382) (xy 115.12677 -99.195382)
		)
		(stroke
			(width 0)
			(type solid)
		)
		(fill yes)
		(layer "In4.Cu")
		(net "M_M_DQ<41>")
	)
	(gr_poly
		(pts
			(xy 115.29695 -98.115882) (xy 115.29695 -97.894902) (xy 115.12677 -97.806002) (xy 115.08232 -97.806002)
			(xy 115.08232 -98.204782) (xy 115.12677 -98.204782)
		)
		(stroke
			(width 0)
			(type solid)
		)
		(fill yes)
		(layer "In4.Cu")
		(net "M_M_DQ<41>")
	)
	(gr_poly
		(pts
			(xy 115.29695 -97.125282) (xy 115.29695 -96.904302) (xy 115.12677 -96.815402) (xy 115.08232 -96.815402)
			(xy 115.08232 -97.214182) (xy 115.12677 -97.214182)
		)
		(stroke
			(width 0)
			(type solid)
		)
		(fill yes)
		(layer "In4.Cu")
		(net "M_M_DQ<41>")
	)
	(gr_poly
		(pts
			(xy 115.332764 -57.692544) (xy 115.288314 -57.692544) (xy 115.118134 -57.781444) (xy 115.118134 -58.002424)
			(xy 115.288314 -58.091324) (xy 115.332764 -58.091324)
		)
		(stroke
			(width 0)
			(type solid)
		)
		(fill yes)
		(layer "In4.Cu")
		(net "M_J_DQ<46>")
	)
	(gr_poly
		(pts
			(xy 115.332764 -56.701944) (xy 115.288314 -56.701944) (xy 115.118134 -56.790844) (xy 115.118134 -57.011824)
			(xy 115.288314 -57.100724) (xy 115.332764 -57.100724)
		)
		(stroke
			(width 0)
			(type solid)
		)
		(fill yes)
		(layer "In4.Cu")
		(net "M_J_DQ<46>")
	)
	(gr_poly
		(pts
			(xy 115.332764 -55.711344) (xy 115.288314 -55.711344) (xy 115.118134 -55.800244) (xy 115.118134 -56.021224)
			(xy 115.288314 -56.110124) (xy 115.332764 -56.110124)
		)
		(stroke
			(width 0)
			(type solid)
		)
		(fill yes)
		(layer "In4.Cu")
		(net "M_J_DQ<46>")
	)
	(gr_poly
		(pts
			(xy 115.332764 -54.720744) (xy 115.288314 -54.720744) (xy 115.118134 -54.809644) (xy 115.118134 -55.030624)
			(xy 115.288314 -55.119524) (xy 115.332764 -55.119524)
		)
		(stroke
			(width 0)
			(type solid)
		)
		(fill yes)
		(layer "In4.Cu")
		(net "M_J_DQ<46>")
	)
	(gr_poly
		(pts
			(xy 115.332764 -53.730144) (xy 115.288314 -53.730144) (xy 115.118134 -53.819044) (xy 115.118134 -54.040024)
			(xy 115.288314 -54.128924) (xy 115.332764 -54.128924)
		)
		(stroke
			(width 0)
			(type solid)
		)
		(fill yes)
		(layer "In4.Cu")
		(net "M_J_DQ<46>")
	)
	(gr_poly
		(pts
			(xy 115.449858 -50.86731) (xy 115.449858 -50.63871) (xy 115.256818 -50.54981) (xy 115.212368 -50.54981)
			(xy 115.212368 -50.95621) (xy 115.256818 -50.95621)
		)
		(stroke
			(width 0)
			(type solid)
		)
		(fill yes)
		(layer "In4.Cu")
		(net "M_J_DQS_DN<14>")
	)
	(gr_poly
		(pts
			(xy 115.556538 -51.692556) (xy 115.525042 -51.66106) (xy 115.325906 -51.5874) (xy 115.164108 -51.749198)
			(xy 115.237768 -51.948334) (xy 115.269264 -51.97983)
		)
		(stroke
			(width 0)
			(type solid)
		)
		(fill yes)
		(layer "In4.Cu")
		(net "M_J_DQS_DP<5>")
	)
	(gr_poly
		(pts
			(xy 115.610132 -48.286162) (xy 115.578636 -48.254666) (xy 115.379246 -48.181006) (xy 115.217702 -48.342804)
			(xy 115.291362 -48.542194) (xy 115.322858 -48.573436)
		)
		(stroke
			(width 0)
			(type solid)
		)
		(fill yes)
		(layer "In4.Cu")
		(net "M_J_DQ<40>")
	)
	(gr_poly
		(pts
			(xy 115.617244 -104.733598) (xy 115.572794 -104.733598) (xy 115.402614 -104.822498) (xy 115.402614 -105.043478)
			(xy 115.572794 -105.132378) (xy 115.617244 -105.132378)
		)
		(stroke
			(width 0)
			(type solid)
		)
		(fill yes)
		(layer "In4.Cu")
		(net "M_M_DQS_DP<14>")
	)
	(gr_poly
		(pts
			(xy 115.617244 -103.742998) (xy 115.572794 -103.742998) (xy 115.402614 -103.831898) (xy 115.402614 -104.052878)
			(xy 115.572794 -104.141778) (xy 115.617244 -104.141778)
		)
		(stroke
			(width 0)
			(type solid)
		)
		(fill yes)
		(layer "In4.Cu")
		(net "M_M_DQS_DP<14>")
	)
	(gr_poly
		(pts
			(xy 115.617244 -102.752398) (xy 115.572794 -102.752398) (xy 115.402614 -102.841298) (xy 115.402614 -103.062278)
			(xy 115.572794 -103.151178) (xy 115.617244 -103.151178)
		)
		(stroke
			(width 0)
			(type solid)
		)
		(fill yes)
		(layer "In4.Cu")
		(net "M_M_DQS_DP<14>")
	)
	(gr_poly
		(pts
			(xy 115.617244 -101.761798) (xy 115.572794 -101.761798) (xy 115.402614 -101.850698) (xy 115.402614 -102.071678)
			(xy 115.572794 -102.160578) (xy 115.617244 -102.160578)
		)
		(stroke
			(width 0)
			(type solid)
		)
		(fill yes)
		(layer "In4.Cu")
		(net "M_M_DQS_DP<14>")
	)
	(gr_poly
		(pts
			(xy 115.617244 -100.771198) (xy 115.572794 -100.771198) (xy 115.402614 -100.860098) (xy 115.402614 -101.081078)
			(xy 115.572794 -101.169978) (xy 115.617244 -101.169978)
		)
		(stroke
			(width 0)
			(type solid)
		)
		(fill yes)
		(layer "In4.Cu")
		(net "M_M_DQS_DP<14>")
	)
	(gr_poly
		(pts
			(xy 115.617244 -99.780598) (xy 115.572794 -99.780598) (xy 115.402614 -99.869498) (xy 115.402614 -100.090478)
			(xy 115.572794 -100.179378) (xy 115.617244 -100.179378)
		)
		(stroke
			(width 0)
			(type solid)
		)
		(fill yes)
		(layer "In4.Cu")
		(net "M_M_DQS_DP<14>")
	)
	(gr_poly
		(pts
			(xy 115.617244 -98.789998) (xy 115.572794 -98.789998) (xy 115.402614 -98.878898) (xy 115.402614 -99.099878)
			(xy 115.572794 -99.188778) (xy 115.617244 -99.188778)
		)
		(stroke
			(width 0)
			(type solid)
		)
		(fill yes)
		(layer "In4.Cu")
		(net "M_M_DQS_DP<14>")
	)
	(gr_poly
		(pts
			(xy 115.617244 -97.799398) (xy 115.572794 -97.799398) (xy 115.402614 -97.888298) (xy 115.402614 -98.109278)
			(xy 115.572794 -98.198178) (xy 115.617244 -98.198178)
		)
		(stroke
			(width 0)
			(type solid)
		)
		(fill yes)
		(layer "In4.Cu")
		(net "M_M_DQS_DP<14>")
	)
	(gr_poly
		(pts
			(xy 115.617244 -96.808798) (xy 115.572794 -96.808798) (xy 115.402614 -96.897698) (xy 115.402614 -97.118678)
			(xy 115.572794 -97.207578) (xy 115.617244 -97.207578)
		)
		(stroke
			(width 0)
			(type solid)
		)
		(fill yes)
		(layer "In4.Cu")
		(net "M_M_DQS_DP<14>")
	)
	(gr_poly
		(pts
			(xy 115.617244 -95.818198) (xy 115.572794 -95.818198) (xy 115.402614 -95.907098) (xy 115.402614 -96.128078)
			(xy 115.572794 -96.216978) (xy 115.617244 -96.216978)
		)
		(stroke
			(width 0)
			(type solid)
		)
		(fill yes)
		(layer "In4.Cu")
		(net "M_M_DQS_DP<14>")
	)
	(gr_poly
		(pts
			(xy 115.617244 -94.840044) (xy 115.572794 -94.840044) (xy 115.402614 -94.928944) (xy 115.402614 -95.149924)
			(xy 115.572794 -95.238824) (xy 115.617244 -95.238824)
		)
		(stroke
			(width 0)
			(type solid)
		)
		(fill yes)
		(layer "In4.Cu")
		(net "M_M_DQS_DP<14>")
	)
	(gr_poly
		(pts
			(xy 115.617244 -93.849444) (xy 115.572794 -93.849444) (xy 115.402614 -93.938344) (xy 115.402614 -94.159324)
			(xy 115.572794 -94.248224) (xy 115.617244 -94.248224)
		)
		(stroke
			(width 0)
			(type solid)
		)
		(fill yes)
		(layer "In4.Cu")
		(net "M_M_DQS_DP<14>")
	)
	(gr_poly
		(pts
			(xy 115.748816 -49.263046) (xy 115.71732 -49.23155) (xy 115.518184 -49.15789) (xy 115.356386 -49.319688)
			(xy 115.430046 -49.518824) (xy 115.461542 -49.55032)
		)
		(stroke
			(width 0)
			(type solid)
		)
		(fill yes)
		(layer "In4.Cu")
		(net "M_J_DQS_DP<14>")
	)
	(gr_poly
		(pts
			(xy 115.796314 -52.058062) (xy 115.722654 -51.858672) (xy 115.691412 -51.827176) (xy 115.403884 -52.114704)
			(xy 115.43538 -52.145946) (xy 115.63477 -52.219606)
		)
		(stroke
			(width 0)
			(type solid)
		)
		(fill yes)
		(layer "In4.Cu")
		(net "M_J_DQS_DN<5>")
	)
	(gr_poly
		(pts
			(xy 115.850162 -48.651922) (xy 115.776502 -48.452532) (xy 115.74526 -48.421036) (xy 115.457732 -48.708564)
			(xy 115.489228 -48.739806) (xy 115.688618 -48.813466)
		)
		(stroke
			(width 0)
			(type solid)
		)
		(fill yes)
		(layer "In4.Cu")
		(net "M_J_DQ<41>")
	)
	(gr_poly
		(pts
			(xy 115.85321 -105.982262) (xy 115.861338 -105.790492) (xy 115.670076 -105.680002) (xy 115.508024 -105.782872)
			(xy 115.485672 -105.821226) (xy 115.831112 -106.02087)
		)
		(stroke
			(width 0)
			(type solid)
		)
		(fill yes)
		(layer "In4.Cu")
		(net "M_M_DQ<41>")
	)
	(gr_poly
		(pts
			(xy 115.87099 -59.488324) (xy 115.87099 -59.267344) (xy 115.70081 -59.178444) (xy 115.65636 -59.178444)
			(xy 115.65636 -59.577224) (xy 115.70081 -59.577224)
		)
		(stroke
			(width 0)
			(type solid)
		)
		(fill yes)
		(layer "In4.Cu")
		(net "M_J_DQ<47>")
	)
	(gr_poly
		(pts
			(xy 115.87099 -58.491628) (xy 115.87099 -58.270648) (xy 115.70081 -58.181748) (xy 115.65636 -58.181748)
			(xy 115.65636 -58.580528) (xy 115.70081 -58.580528)
		)
		(stroke
			(width 0)
			(type solid)
		)
		(fill yes)
		(layer "In4.Cu")
		(net "M_J_DQ<47>")
	)
	(gr_poly
		(pts
			(xy 115.87099 -57.494678) (xy 115.87099 -57.273698) (xy 115.70081 -57.184798) (xy 115.65636 -57.184798)
			(xy 115.65636 -57.583578) (xy 115.70081 -57.583578)
		)
		(stroke
			(width 0)
			(type solid)
		)
		(fill yes)
		(layer "In4.Cu")
		(net "M_J_DQ<47>")
	)
	(gr_poly
		(pts
			(xy 115.87099 -56.504078) (xy 115.87099 -56.283098) (xy 115.70081 -56.194198) (xy 115.65636 -56.194198)
			(xy 115.65636 -56.592978) (xy 115.70081 -56.592978)
		)
		(stroke
			(width 0)
			(type solid)
		)
		(fill yes)
		(layer "In4.Cu")
		(net "M_J_DQ<47>")
	)
	(gr_poly
		(pts
			(xy 115.87099 -55.513478) (xy 115.87099 -55.292498) (xy 115.70081 -55.203598) (xy 115.65636 -55.203598)
			(xy 115.65636 -55.602378) (xy 115.70081 -55.602378)
		)
		(stroke
			(width 0)
			(type solid)
		)
		(fill yes)
		(layer "In4.Cu")
		(net "M_J_DQ<47>")
	)
	(gr_poly
		(pts
			(xy 115.87099 -54.522878) (xy 115.87099 -54.301898) (xy 115.70081 -54.212998) (xy 115.65636 -54.212998)
			(xy 115.65636 -54.611778) (xy 115.70081 -54.611778)
		)
		(stroke
			(width 0)
			(type solid)
		)
		(fill yes)
		(layer "In4.Cu")
		(net "M_J_DQ<47>")
	)
	(gr_poly
		(pts
			(xy 115.988592 -49.628552) (xy 115.914932 -49.429162) (xy 115.88369 -49.397666) (xy 115.596162 -49.685194)
			(xy 115.627658 -49.716436) (xy 115.827048 -49.790096)
		)
		(stroke
			(width 0)
			(type solid)
		)
		(fill yes)
		(layer "In4.Cu")
		(net "M_J_DQS_DN<14>")
	)
	(gr_poly
		(pts
			(xy 116.055648 -105.584752) (xy 116.078 -105.546398) (xy 115.732306 -105.347008) (xy 115.710462 -105.385616)
			(xy 115.702334 -105.577386) (xy 115.893596 -105.687622)
		)
		(stroke
			(width 0)
			(type solid)
		)
		(fill yes)
		(layer "In4.Cu")
		(net "M_M_DQS_DP<14>")
	)
	(gr_poly
		(pts
			(xy 116.15547 -106.541824) (xy 116.15547 -106.320844) (xy 115.98529 -106.231944) (xy 115.94084 -106.231944)
			(xy 115.94084 -106.630724) (xy 115.98529 -106.630724)
		)
		(stroke
			(width 0)
			(type solid)
		)
		(fill yes)
		(layer "In4.Cu")
		(net "M_M_DQ<41>")
	)
	(gr_poly
		(pts
			(xy 116.15547 -104.560624) (xy 116.15547 -104.339644) (xy 115.98529 -104.250744) (xy 115.94084 -104.250744)
			(xy 115.94084 -104.649524) (xy 115.98529 -104.649524)
		)
		(stroke
			(width 0)
			(type solid)
		)
		(fill yes)
		(layer "In4.Cu")
		(net "M_M_DQS_DN<14>")
	)
	(gr_poly
		(pts
			(xy 116.15547 -103.570024) (xy 116.15547 -103.349044) (xy 115.98529 -103.260144) (xy 115.94084 -103.260144)
			(xy 115.94084 -103.658924) (xy 115.98529 -103.658924)
		)
		(stroke
			(width 0)
			(type solid)
		)
		(fill yes)
		(layer "In4.Cu")
		(net "M_M_DQS_DN<14>")
	)
	(gr_poly
		(pts
			(xy 116.15547 -102.579424) (xy 116.15547 -102.358444) (xy 115.98529 -102.269544) (xy 115.94084 -102.269544)
			(xy 115.94084 -102.668324) (xy 115.98529 -102.668324)
		)
		(stroke
			(width 0)
			(type solid)
		)
		(fill yes)
		(layer "In4.Cu")
		(net "M_M_DQS_DN<14>")
	)
	(gr_poly
		(pts
			(xy 116.15547 -101.588824) (xy 116.15547 -101.367844) (xy 115.98529 -101.278944) (xy 115.94084 -101.278944)
			(xy 115.94084 -101.677724) (xy 115.98529 -101.677724)
		)
		(stroke
			(width 0)
			(type solid)
		)
		(fill yes)
		(layer "In4.Cu")
		(net "M_M_DQS_DN<14>")
	)
	(gr_poly
		(pts
			(xy 116.15547 -100.598224) (xy 116.15547 -100.377244) (xy 115.98529 -100.288344) (xy 115.94084 -100.288344)
			(xy 115.94084 -100.687124) (xy 115.98529 -100.687124)
		)
		(stroke
			(width 0)
			(type solid)
		)
		(fill yes)
		(layer "In4.Cu")
		(net "M_M_DQS_DN<14>")
	)
	(gr_poly
		(pts
			(xy 116.15547 -99.607624) (xy 116.15547 -99.386644) (xy 115.98529 -99.297744) (xy 115.94084 -99.297744)
			(xy 115.94084 -99.696524) (xy 115.98529 -99.696524)
		)
		(stroke
			(width 0)
			(type solid)
		)
		(fill yes)
		(layer "In4.Cu")
		(net "M_M_DQS_DN<14>")
	)
	(gr_poly
		(pts
			(xy 116.15547 -98.617024) (xy 116.15547 -98.396044) (xy 115.98529 -98.307144) (xy 115.94084 -98.307144)
			(xy 115.94084 -98.705924) (xy 115.98529 -98.705924)
		)
		(stroke
			(width 0)
			(type solid)
		)
		(fill yes)
		(layer "In4.Cu")
		(net "M_M_DQS_DN<14>")
	)
	(gr_poly
		(pts
			(xy 116.15547 -97.626424) (xy 116.15547 -97.405444) (xy 115.98529 -97.316544) (xy 115.94084 -97.316544)
			(xy 115.94084 -97.715324) (xy 115.98529 -97.715324)
		)
		(stroke
			(width 0)
			(type solid)
		)
		(fill yes)
		(layer "In4.Cu")
		(net "M_M_DQS_DN<14>")
	)
	(gr_poly
		(pts
			(xy 116.15547 -96.635824) (xy 116.15547 -96.414844) (xy 115.98529 -96.325944) (xy 115.94084 -96.325944)
			(xy 115.94084 -96.724724) (xy 115.98529 -96.724724)
		)
		(stroke
			(width 0)
			(type solid)
		)
		(fill yes)
		(layer "In4.Cu")
		(net "M_M_DQS_DN<14>")
	)
	(gr_poly
		(pts
			(xy 116.15547 -95.638874) (xy 116.15547 -95.417894) (xy 115.98529 -95.328994) (xy 115.94084 -95.328994)
			(xy 115.94084 -95.727774) (xy 115.98529 -95.727774)
		)
		(stroke
			(width 0)
			(type solid)
		)
		(fill yes)
		(layer "In4.Cu")
		(net "M_M_DQS_DN<14>")
	)
	(gr_poly
		(pts
			(xy 116.15547 -94.642178) (xy 116.15547 -94.421198) (xy 115.98529 -94.332298) (xy 115.94084 -94.332298)
			(xy 115.94084 -94.731078) (xy 115.98529 -94.731078)
		)
		(stroke
			(width 0)
			(type solid)
		)
		(fill yes)
		(layer "In4.Cu")
		(net "M_M_DQS_DN<14>")
	)
	(gr_poly
		(pts
			(xy 116.191284 -58.181748) (xy 116.146834 -58.181748) (xy 115.976654 -58.270648) (xy 115.976654 -58.491628)
			(xy 116.146834 -58.580528) (xy 116.191284 -58.580528)
		)
		(stroke
			(width 0)
			(type solid)
		)
		(fill yes)
		(layer "In4.Cu")
		(net "M_J_DQ<42>")
	)
	(gr_poly
		(pts
			(xy 116.191284 -57.184798) (xy 116.146834 -57.184798) (xy 115.976654 -57.273698) (xy 115.976654 -57.494678)
			(xy 116.146834 -57.583578) (xy 116.191284 -57.583578)
		)
		(stroke
			(width 0)
			(type solid)
		)
		(fill yes)
		(layer "In4.Cu")
		(net "M_J_DQ<42>")
	)
	(gr_poly
		(pts
			(xy 116.191284 -56.194198) (xy 116.146834 -56.194198) (xy 115.976654 -56.283098) (xy 115.976654 -56.504078)
			(xy 116.146834 -56.592978) (xy 116.191284 -56.592978)
		)
		(stroke
			(width 0)
			(type solid)
		)
		(fill yes)
		(layer "In4.Cu")
		(net "M_J_DQ<42>")
	)
	(gr_poly
		(pts
			(xy 116.191284 -55.203598) (xy 116.146834 -55.203598) (xy 115.976654 -55.292498) (xy 115.976654 -55.513478)
			(xy 116.146834 -55.602378) (xy 116.191284 -55.602378)
		)
		(stroke
			(width 0)
			(type solid)
		)
		(fill yes)
		(layer "In4.Cu")
		(net "M_J_DQ<42>")
	)
	(gr_poly
		(pts
			(xy 116.191284 -54.212998) (xy 116.146834 -54.212998) (xy 115.976654 -54.301898) (xy 115.976654 -54.522878)
			(xy 116.146834 -54.611778) (xy 116.191284 -54.611778)
		)
		(stroke
			(width 0)
			(type solid)
		)
		(fill yes)
		(layer "In4.Cu")
		(net "M_J_DQ<42>")
	)
	(gr_poly
		(pts
			(xy 116.449094 -48.562514) (xy 116.417598 -48.531018) (xy 116.218462 -48.457358) (xy 116.056664 -48.619156)
			(xy 116.130324 -48.818292) (xy 116.16182 -48.849788)
		)
		(stroke
			(width 0)
			(type solid)
		)
		(fill yes)
		(layer "In4.Cu")
		(net "M_J_DQS_DP<14>")
	)
	(gr_poly
		(pts
			(xy 116.475764 -104.253284) (xy 116.431314 -104.253284) (xy 116.261134 -104.342184) (xy 116.261134 -104.563164)
			(xy 116.431314 -104.652064) (xy 116.475764 -104.652064)
		)
		(stroke
			(width 0)
			(type solid)
		)
		(fill yes)
		(layer "In4.Cu")
		(net "M_M_DQS_DN<5>")
	)
	(gr_poly
		(pts
			(xy 116.475764 -103.262684) (xy 116.431314 -103.262684) (xy 116.261134 -103.351584) (xy 116.261134 -103.572564)
			(xy 116.431314 -103.661464) (xy 116.475764 -103.661464)
		)
		(stroke
			(width 0)
			(type solid)
		)
		(fill yes)
		(layer "In4.Cu")
		(net "M_M_DQS_DN<5>")
	)
	(gr_poly
		(pts
			(xy 116.475764 -102.272084) (xy 116.431314 -102.272084) (xy 116.261134 -102.360984) (xy 116.261134 -102.581964)
			(xy 116.431314 -102.670864) (xy 116.475764 -102.670864)
		)
		(stroke
			(width 0)
			(type solid)
		)
		(fill yes)
		(layer "In4.Cu")
		(net "M_M_DQS_DN<5>")
	)
	(gr_poly
		(pts
			(xy 116.475764 -101.281484) (xy 116.431314 -101.281484) (xy 116.261134 -101.370384) (xy 116.261134 -101.591364)
			(xy 116.431314 -101.680264) (xy 116.475764 -101.680264)
		)
		(stroke
			(width 0)
			(type solid)
		)
		(fill yes)
		(layer "In4.Cu")
		(net "M_M_DQS_DN<5>")
	)
	(gr_poly
		(pts
			(xy 116.475764 -100.290884) (xy 116.431314 -100.290884) (xy 116.261134 -100.379784) (xy 116.261134 -100.600764)
			(xy 116.431314 -100.689664) (xy 116.475764 -100.689664)
		)
		(stroke
			(width 0)
			(type solid)
		)
		(fill yes)
		(layer "In4.Cu")
		(net "M_M_DQS_DN<5>")
	)
	(gr_poly
		(pts
			(xy 116.475764 -99.291902) (xy 116.431314 -99.291902) (xy 116.261134 -99.380802) (xy 116.261134 -99.601782)
			(xy 116.431314 -99.690682) (xy 116.475764 -99.690682)
		)
		(stroke
			(width 0)
			(type solid)
		)
		(fill yes)
		(layer "In4.Cu")
		(net "M_M_DQS_DN<5>")
	)
	(gr_poly
		(pts
			(xy 116.475764 -98.301302) (xy 116.431314 -98.301302) (xy 116.261134 -98.390202) (xy 116.261134 -98.611182)
			(xy 116.431314 -98.700082) (xy 116.475764 -98.700082)
		)
		(stroke
			(width 0)
			(type solid)
		)
		(fill yes)
		(layer "In4.Cu")
		(net "M_M_DQS_DN<5>")
	)
	(gr_poly
		(pts
			(xy 116.475764 -97.310702) (xy 116.431314 -97.310702) (xy 116.261134 -97.399602) (xy 116.261134 -97.620582)
			(xy 116.431314 -97.709482) (xy 116.475764 -97.709482)
		)
		(stroke
			(width 0)
			(type solid)
		)
		(fill yes)
		(layer "In4.Cu")
		(net "M_M_DQS_DN<5>")
	)
	(gr_poly
		(pts
			(xy 116.666518 -94.338648) (xy 116.622068 -94.338648) (xy 116.451888 -94.427548) (xy 116.451888 -94.648528)
			(xy 116.622068 -94.737428) (xy 116.666518 -94.737428)
		)
		(stroke
			(width 0)
			(type solid)
		)
		(fill yes)
		(layer "In4.Cu")
		(net "M_M_DQ<46>")
	)
	(gr_poly
		(pts
			(xy 116.682774 -51.6255) (xy 116.651278 -51.594004) (xy 116.452142 -51.520344) (xy 116.290344 -51.682142)
			(xy 116.364004 -51.881278) (xy 116.3955 -51.912774)
		)
		(stroke
			(width 0)
			(type solid)
		)
		(fill yes)
		(layer "In4.Cu")
		(net "M_J_DQ<46>")
	)
	(gr_poly
		(pts
			(xy 116.68887 -48.92802) (xy 116.61521 -48.72863) (xy 116.583968 -48.697134) (xy 116.29644 -48.984662)
			(xy 116.327936 -49.015904) (xy 116.527326 -49.089564)
		)
		(stroke
			(width 0)
			(type solid)
		)
		(fill yes)
		(layer "In4.Cu")
		(net "M_J_DQS_DN<14>")
	)
	(gr_poly
		(pts
			(xy 116.70157 -105.480866) (xy 116.709698 -105.289096) (xy 116.518436 -105.178606) (xy 116.356384 -105.28173)
			(xy 116.334032 -105.320084) (xy 116.679472 -105.519474)
		)
		(stroke
			(width 0)
			(type solid)
		)
		(fill yes)
		(layer "In4.Cu")
		(net "M_M_DQS_DN<14>")
	)
	(gr_poly
		(pts
			(xy 116.72951 -58.980578) (xy 116.72951 -58.759598) (xy 116.55933 -58.670698) (xy 116.51488 -58.670698)
			(xy 116.51488 -59.069478) (xy 116.55933 -59.069478)
		)
		(stroke
			(width 0)
			(type solid)
		)
		(fill yes)
		(layer "In4.Cu")
		(net "M_J_DQ<43>")
	)
	(gr_poly
		(pts
			(xy 116.72951 -58.002424) (xy 116.72951 -57.781444) (xy 116.55933 -57.692544) (xy 116.51488 -57.692544)
			(xy 116.51488 -58.091324) (xy 116.55933 -58.091324)
		)
		(stroke
			(width 0)
			(type solid)
		)
		(fill yes)
		(layer "In4.Cu")
		(net "M_J_DQ<43>")
	)
	(gr_poly
		(pts
			(xy 116.72951 -57.011824) (xy 116.72951 -56.790844) (xy 116.55933 -56.701944) (xy 116.51488 -56.701944)
			(xy 116.51488 -57.100724) (xy 116.55933 -57.100724)
		)
		(stroke
			(width 0)
			(type solid)
		)
		(fill yes)
		(layer "In4.Cu")
		(net "M_J_DQ<43>")
	)
	(gr_poly
		(pts
			(xy 116.72951 -56.021224) (xy 116.72951 -55.800244) (xy 116.55933 -55.711344) (xy 116.51488 -55.711344)
			(xy 116.51488 -56.110124) (xy 116.55933 -56.110124)
		)
		(stroke
			(width 0)
			(type solid)
		)
		(fill yes)
		(layer "In4.Cu")
		(net "M_J_DQ<43>")
	)
	(gr_poly
		(pts
			(xy 116.72951 -55.030624) (xy 116.72951 -54.809644) (xy 116.55933 -54.720744) (xy 116.51488 -54.720744)
			(xy 116.51488 -55.119524) (xy 116.55933 -55.119524)
		)
		(stroke
			(width 0)
			(type solid)
		)
		(fill yes)
		(layer "In4.Cu")
		(net "M_J_DQ<43>")
	)
	(gr_poly
		(pts
			(xy 116.72951 -54.033674) (xy 116.72951 -53.812694) (xy 116.55933 -53.723794) (xy 116.51488 -53.723794)
			(xy 116.51488 -54.122574) (xy 116.55933 -54.122574)
		)
		(stroke
			(width 0)
			(type solid)
		)
		(fill yes)
		(layer "In4.Cu")
		(net "M_J_DQ<43>")
	)
	(gr_poly
		(pts
			(xy 116.736114 -49.80178) (xy 116.704618 -49.770284) (xy 116.505482 -49.696624) (xy 116.343684 -49.858422)
			(xy 116.417344 -50.057558) (xy 116.44884 -50.089054)
		)
		(stroke
			(width 0)
			(type solid)
		)
		(fill yes)
		(layer "In4.Cu")
		(net "M_J_DQS_DP<5>")
	)
	(gr_poly
		(pts
			(xy 116.838984 -47.551848) (xy 116.794534 -47.551848) (xy 116.601494 -47.640748) (xy 116.601494 -47.869348)
			(xy 116.794534 -47.958248) (xy 116.838984 -47.958248)
		)
		(stroke
			(width 0)
			(type solid)
		)
		(fill yes)
		(layer "In4.Cu")
		(net "M_J_DQS_DP<14>")
	)
	(gr_poly
		(pts
			(xy 116.929662 -105.098088) (xy 116.952014 -105.059734) (xy 116.606574 -104.860344) (xy 116.584222 -104.898698)
			(xy 116.576094 -105.090722) (xy 116.76761 -105.201212)
		)
		(stroke
			(width 0)
			(type solid)
		)
		(fill yes)
		(layer "In4.Cu")
		(net "M_M_DQS_DN<5>")
	)
	(gr_poly
		(pts
			(xy 116.94668 -52.015136) (xy 116.87302 -51.815746) (xy 116.841778 -51.78425) (xy 116.55425 -52.071778)
			(xy 116.585746 -52.10302) (xy 116.785136 -52.17668)
		)
		(stroke
			(width 0)
			(type solid)
		)
		(fill yes)
		(layer "In4.Cu")
		(net "M_J_DQ<47>")
	)
	(gr_poly
		(pts
			(xy 116.97589 -50.167286) (xy 116.90223 -49.967896) (xy 116.870988 -49.9364) (xy 116.58346 -50.223928)
			(xy 116.614956 -50.25517) (xy 116.814346 -50.32883)
		)
		(stroke
			(width 0)
			(type solid)
		)
		(fill yes)
		(layer "In4.Cu")
		(net "M_J_DQS_DN<5>")
	)
	(gr_poly
		(pts
			(xy 117.007132 -52.449476) (xy 116.975636 -52.418234) (xy 116.776246 -52.344574) (xy 116.614702 -52.506118)
			(xy 116.688362 -52.705508) (xy 116.719604 -52.737004)
		)
		(stroke
			(width 0)
			(type solid)
		)
		(fill yes)
		(layer "In4.Cu")
		(net "M_J_DQ<42>")
	)
	(gr_poly
		(pts
			(xy 117.01399 -104.050084) (xy 117.01399 -103.829104) (xy 116.84381 -103.740204) (xy 116.79936 -103.740204)
			(xy 116.79936 -104.138984) (xy 116.84381 -104.138984)
		)
		(stroke
			(width 0)
			(type solid)
		)
		(fill yes)
		(layer "In4.Cu")
		(net "M_M_DQS_DP<5>")
	)
	(gr_poly
		(pts
			(xy 117.01399 -103.059484) (xy 117.01399 -102.838504) (xy 116.84381 -102.749604) (xy 116.79936 -102.749604)
			(xy 116.79936 -103.148384) (xy 116.84381 -103.148384)
		)
		(stroke
			(width 0)
			(type solid)
		)
		(fill yes)
		(layer "In4.Cu")
		(net "M_M_DQS_DP<5>")
	)
	(gr_poly
		(pts
			(xy 117.01399 -102.068884) (xy 117.01399 -101.847904) (xy 116.84381 -101.759004) (xy 116.79936 -101.759004)
			(xy 116.79936 -102.157784) (xy 116.84381 -102.157784)
		)
		(stroke
			(width 0)
			(type solid)
		)
		(fill yes)
		(layer "In4.Cu")
		(net "M_M_DQS_DP<5>")
	)
	(gr_poly
		(pts
			(xy 117.01399 -101.078284) (xy 117.01399 -100.857304) (xy 116.84381 -100.768404) (xy 116.79936 -100.768404)
			(xy 116.79936 -101.167184) (xy 116.84381 -101.167184)
		)
		(stroke
			(width 0)
			(type solid)
		)
		(fill yes)
		(layer "In4.Cu")
		(net "M_M_DQS_DP<5>")
	)
	(gr_poly
		(pts
			(xy 117.01399 -100.090478) (xy 117.01399 -99.869498) (xy 116.84381 -99.780598) (xy 116.79936 -99.780598)
			(xy 116.79936 -100.179378) (xy 116.84381 -100.179378)
		)
		(stroke
			(width 0)
			(type solid)
		)
		(fill yes)
		(layer "In4.Cu")
		(net "M_M_DQS_DP<5>")
	)
	(gr_poly
		(pts
			(xy 117.01399 -99.106482) (xy 117.01399 -98.885502) (xy 116.84381 -98.796602) (xy 116.79936 -98.796602)
			(xy 116.79936 -99.195382) (xy 116.84381 -99.195382)
		)
		(stroke
			(width 0)
			(type solid)
		)
		(fill yes)
		(layer "In4.Cu")
		(net "M_M_DQS_DP<5>")
	)
	(gr_poly
		(pts
			(xy 117.01399 -98.115882) (xy 117.01399 -97.894902) (xy 116.84381 -97.806002) (xy 116.79936 -97.806002)
			(xy 116.79936 -98.204782) (xy 116.84381 -98.204782)
		)
		(stroke
			(width 0)
			(type solid)
		)
		(fill yes)
		(layer "In4.Cu")
		(net "M_M_DQS_DP<5>")
	)
	(gr_poly
		(pts
			(xy 117.01399 -97.125282) (xy 117.01399 -96.904302) (xy 116.84381 -96.815402) (xy 116.79936 -96.815402)
			(xy 116.79936 -97.214182) (xy 116.84381 -97.214182)
		)
		(stroke
			(width 0)
			(type solid)
		)
		(fill yes)
		(layer "In4.Cu")
		(net "M_M_DQS_DP<5>")
	)
	(gr_poly
		(pts
			(xy 117.049804 -58.670698) (xy 117.005354 -58.670698) (xy 116.835174 -58.759598) (xy 116.835174 -58.980578)
			(xy 117.005354 -59.069478) (xy 117.049804 -59.069478)
		)
		(stroke
			(width 0)
			(type solid)
		)
		(fill yes)
		(layer "In4.Cu")
		(net "M_H_DQ<60>")
	)
	(gr_poly
		(pts
			(xy 117.260624 -52.828952) (xy 117.186964 -52.629562) (xy 117.155722 -52.598066) (xy 116.868194 -52.885594)
			(xy 116.89969 -52.916836) (xy 117.09908 -52.990496)
		)
		(stroke
			(width 0)
			(type solid)
		)
		(fill yes)
		(layer "In4.Cu")
		(net "M_J_DQ<43>")
	)
	(gr_poly
		(pts
			(xy 117.266974 -47.869348) (xy 117.266974 -47.640748) (xy 117.073934 -47.551848) (xy 117.029484 -47.551848)
			(xy 117.029484 -47.958248) (xy 117.073934 -47.958248)
		)
		(stroke
			(width 0)
			(type solid)
		)
		(fill yes)
		(layer "In4.Cu")
		(net "M_J_DQS_DN<14>")
	)
	(gr_poly
		(pts
			(xy 117.334284 -105.721404) (xy 117.289834 -105.721404) (xy 117.119654 -105.810304) (xy 117.119654 -106.031284)
			(xy 117.289834 -106.120184) (xy 117.334284 -106.120184)
		)
		(stroke
			(width 0)
			(type solid)
		)
		(fill yes)
		(layer "In4.Cu")
		(net "M_M_DQS_DN<5>")
	)
	(gr_poly
		(pts
			(xy 117.334284 -103.740204) (xy 117.289834 -103.740204) (xy 117.119654 -103.829104) (xy 117.119654 -104.050084)
			(xy 117.289834 -104.138984) (xy 117.334284 -104.138984)
		)
		(stroke
			(width 0)
			(type solid)
		)
		(fill yes)
		(layer "In4.Cu")
		(net "M_M_DQ<46>")
	)
	(gr_poly
		(pts
			(xy 117.334284 -102.749604) (xy 117.289834 -102.749604) (xy 117.119654 -102.838504) (xy 117.119654 -103.059484)
			(xy 117.289834 -103.148384) (xy 117.334284 -103.148384)
		)
		(stroke
			(width 0)
			(type solid)
		)
		(fill yes)
		(layer "In4.Cu")
		(net "M_M_DQ<46>")
	)
	(gr_poly
		(pts
			(xy 117.334284 -101.76764) (xy 117.289834 -101.76764) (xy 117.119654 -101.85654) (xy 117.119654 -102.07752)
			(xy 117.289834 -102.16642) (xy 117.334284 -102.16642)
		)
		(stroke
			(width 0)
			(type solid)
		)
		(fill yes)
		(layer "In4.Cu")
		(net "M_M_DQ<46>")
	)
	(gr_poly
		(pts
			(xy 117.334284 -100.783136) (xy 117.289834 -100.783136) (xy 117.119654 -100.872036) (xy 117.119654 -101.093016)
			(xy 117.289834 -101.181916) (xy 117.334284 -101.181916)
		)
		(stroke
			(width 0)
			(type solid)
		)
		(fill yes)
		(layer "In4.Cu")
		(net "M_M_DQ<46>")
	)
	(gr_poly
		(pts
			(xy 117.334284 -97.806002) (xy 117.289834 -97.806002) (xy 117.119654 -97.894902) (xy 117.119654 -98.115882)
			(xy 117.289834 -98.204782) (xy 117.334284 -98.204782)
		)
		(stroke
			(width 0)
			(type solid)
		)
		(fill yes)
		(layer "In4.Cu")
		(net "M_M_DQ<46>")
	)
	(gr_poly
		(pts
			(xy 117.334284 -96.815402) (xy 117.289834 -96.815402) (xy 117.119654 -96.904302) (xy 117.119654 -97.125282)
			(xy 117.289834 -97.214182) (xy 117.334284 -97.214182)
		)
		(stroke
			(width 0)
			(type solid)
		)
		(fill yes)
		(layer "In4.Cu")
		(net "M_M_DQ<46>")
	)
	(gr_poly
		(pts
			(xy 117.334538 -99.786948) (xy 117.290088 -99.786948) (xy 117.119908 -99.875848) (xy 117.119908 -100.096828)
			(xy 117.290088 -100.185728) (xy 117.334538 -100.185728)
		)
		(stroke
			(width 0)
			(type solid)
		)
		(fill yes)
		(layer "In4.Cu")
		(net "M_M_DQ<46>")
	)
	(gr_poly
		(pts
			(xy 117.334538 -98.796348) (xy 117.290088 -98.796348) (xy 117.119908 -98.885248) (xy 117.119908 -99.106228)
			(xy 117.290088 -99.195128) (xy 117.334538 -99.195128)
		)
		(stroke
			(width 0)
			(type solid)
		)
		(fill yes)
		(layer "In4.Cu")
		(net "M_M_DQ<46>")
	)
	(gr_poly
		(pts
			(xy 117.383306 -50.924968) (xy 117.35181 -50.893472) (xy 117.152674 -50.819812) (xy 116.990876 -50.98161)
			(xy 117.064536 -51.180746) (xy 117.096032 -51.212242)
		)
		(stroke
			(width 0)
			(type solid)
		)
		(fill yes)
		(layer "In4.Cu")
		(net "M_J_DQ<46>")
	)
	(gr_poly
		(pts
			(xy 117.436646 -49.101248) (xy 117.40515 -49.069752) (xy 117.206014 -48.996092) (xy 117.044216 -49.15789)
			(xy 117.117876 -49.357026) (xy 117.149372 -49.388522)
		)
		(stroke
			(width 0)
			(type solid)
		)
		(fill yes)
		(layer "In4.Cu")
		(net "M_J_DQS_DP<5>")
	)
	(gr_poly
		(pts
			(xy 117.56517 -104.988106) (xy 117.573044 -104.796336) (xy 117.381782 -104.685846) (xy 117.21973 -104.788716)
			(xy 117.197378 -104.827324) (xy 117.542818 -105.026714)
		)
		(stroke
			(width 0)
			(type solid)
		)
		(fill yes)
		(layer "In4.Cu")
		(net "M_M_DQS_DP<5>")
	)
	(gr_poly
		(pts
			(xy 117.587776 -58.502804) (xy 117.587776 -58.281824) (xy 117.417596 -58.192924) (xy 117.373146 -58.192924)
			(xy 117.373146 -58.591704) (xy 117.417596 -58.591704)
		)
		(stroke
			(width 0)
			(type solid)
		)
		(fill yes)
		(layer "In4.Cu")
		(net "M_H_DQ<61>")
	)
	(gr_poly
		(pts
			(xy 117.62359 -95.373698) (xy 117.487446 -94.998794) (xy 117.445536 -95.014034) (xy 117.315996 -95.155766)
			(xy 117.391688 -95.363538) (xy 117.581934 -95.388938)
		)
		(stroke
			(width 0)
			(type solid)
		)
		(fill yes)
		(layer "In4.Cu")
		(net "M_M_DQ<42>")
	)
	(gr_poly
		(pts
			(xy 117.639592 -106.745024) (xy 117.595142 -106.745024) (xy 117.402102 -106.833924) (xy 117.402102 -107.062524)
			(xy 117.595142 -107.151424) (xy 117.639592 -107.151424)
		)
		(stroke
			(width 0)
			(type solid)
		)
		(fill yes)
		(layer "In4.Cu")
		(net "M_M_DQS_DN<5>")
	)
	(gr_poly
		(pts
			(xy 117.647212 -51.314604) (xy 117.573552 -51.115214) (xy 117.54231 -51.083718) (xy 117.254782 -51.371246)
			(xy 117.286278 -51.402488) (xy 117.485668 -51.476148)
		)
		(stroke
			(width 0)
			(type solid)
		)
		(fill yes)
		(layer "In4.Cu")
		(net "M_J_DQ<47>")
	)
	(gr_poly
		(pts
			(xy 117.676422 -49.466754) (xy 117.602762 -49.267364) (xy 117.571266 -49.236122) (xy 117.283992 -49.523396)
			(xy 117.315488 -49.554892) (xy 117.514878 -49.628552)
		)
		(stroke
			(width 0)
			(type solid)
		)
		(fill yes)
		(layer "In4.Cu")
		(net "M_J_DQS_DN<5>")
	)
	(gr_poly
		(pts
			(xy 117.707664 -51.749198) (xy 117.676168 -51.717956) (xy 117.476778 -51.644296) (xy 117.315234 -51.80584)
			(xy 117.388894 -52.00523) (xy 117.420136 -52.036726)
		)
		(stroke
			(width 0)
			(type solid)
		)
		(fill yes)
		(layer "In4.Cu")
		(net "M_J_DQ<42>")
	)
	(gr_poly
		(pts
			(xy 117.772434 -104.593898) (xy 117.79504 -104.555544) (xy 117.449346 -104.356154) (xy 117.427248 -104.394762)
			(xy 117.41912 -104.586532) (xy 117.610636 -104.696768)
		)
		(stroke
			(width 0)
			(type solid)
		)
		(fill yes)
		(layer "In4.Cu")
		(net "M_M_DQ<46>")
	)
	(gr_poly
		(pts
			(xy 117.820186 -47.86376) (xy 117.775736 -47.86376) (xy 117.582696 -47.95266) (xy 117.582696 -48.18126)
			(xy 117.775736 -48.27016) (xy 117.820186 -48.27016)
		)
		(stroke
			(width 0)
			(type solid)
		)
		(fill yes)
		(layer "In4.Cu")
		(net "M_J_DQS_DP<5>")
	)
	(gr_poly
		(pts
			(xy 117.872256 -105.553764) (xy 117.872256 -105.332784) (xy 117.702076 -105.243884) (xy 117.657626 -105.243884)
			(xy 117.657626 -105.642664) (xy 117.70233 -105.642664)
		)
		(stroke
			(width 0)
			(type solid)
		)
		(fill yes)
		(layer "In4.Cu")
		(net "M_M_DQS_DP<5>")
	)
	(gr_poly
		(pts
			(xy 117.87251 -103.572564) (xy 117.87251 -103.351584) (xy 117.70233 -103.262684) (xy 117.65788 -103.262684)
			(xy 117.65788 -103.661464) (xy 117.70233 -103.661464)
		)
		(stroke
			(width 0)
			(type solid)
		)
		(fill yes)
		(layer "In4.Cu")
		(net "M_M_DQ<47>")
	)
	(gr_poly
		(pts
			(xy 117.87251 -102.57917) (xy 117.87251 -102.35819) (xy 117.70233 -102.26929) (xy 117.65788 -102.26929)
			(xy 117.65788 -102.66807) (xy 117.70233 -102.66807)
		)
		(stroke
			(width 0)
			(type solid)
		)
		(fill yes)
		(layer "In4.Cu")
		(net "M_M_DQ<47>")
	)
	(gr_poly
		(pts
			(xy 117.87251 -101.58222) (xy 117.87251 -101.36124) (xy 117.70233 -101.27234) (xy 117.65788 -101.27234)
			(xy 117.65788 -101.67112) (xy 117.70233 -101.67112)
		)
		(stroke
			(width 0)
			(type solid)
		)
		(fill yes)
		(layer "In4.Cu")
		(net "M_M_DQ<47>")
	)
	(gr_poly
		(pts
			(xy 117.87251 -100.58527) (xy 117.87251 -100.36429) (xy 117.70233 -100.27539) (xy 117.65788 -100.27539)
			(xy 117.65788 -100.67417) (xy 117.70233 -100.67417)
		)
		(stroke
			(width 0)
			(type solid)
		)
		(fill yes)
		(layer "In4.Cu")
		(net "M_M_DQ<47>")
	)
	(gr_poly
		(pts
			(xy 117.87251 -99.607624) (xy 117.87251 -99.386644) (xy 117.70233 -99.297744) (xy 117.65788 -99.297744)
			(xy 117.65788 -99.696524) (xy 117.70233 -99.696524)
		)
		(stroke
			(width 0)
			(type solid)
		)
		(fill yes)
		(layer "In4.Cu")
		(net "M_M_DQ<47>")
	)
	(gr_poly
		(pts
			(xy 117.87251 -98.617024) (xy 117.87251 -98.396044) (xy 117.70233 -98.307144) (xy 117.65788 -98.307144)
			(xy 117.65788 -98.705924) (xy 117.70233 -98.705924)
		)
		(stroke
			(width 0)
			(type solid)
		)
		(fill yes)
		(layer "In4.Cu")
		(net "M_M_DQ<47>")
	)
	(gr_poly
		(pts
			(xy 117.87251 -97.626424) (xy 117.87251 -97.405444) (xy 117.70233 -97.316544) (xy 117.65788 -97.316544)
			(xy 117.65788 -97.715324) (xy 117.70233 -97.715324)
		)
		(stroke
			(width 0)
			(type solid)
		)
		(fill yes)
		(layer "In4.Cu")
		(net "M_M_DQ<47>")
	)
	(gr_poly
		(pts
			(xy 117.87251 -96.635824) (xy 117.87251 -96.414844) (xy 117.70233 -96.325944) (xy 117.65788 -96.325944)
			(xy 117.65788 -96.724724) (xy 117.70233 -96.724724)
		)
		(stroke
			(width 0)
			(type solid)
		)
		(fill yes)
		(layer "In4.Cu")
		(net "M_M_DQ<47>")
	)
	(gr_poly
		(pts
			(xy 117.961156 -52.12842) (xy 117.887496 -51.92903) (xy 117.856 -51.897788) (xy 117.568726 -52.185062)
			(xy 117.600222 -52.216558) (xy 117.799612 -52.290218)
		)
		(stroke
			(width 0)
			(type solid)
		)
		(fill yes)
		(layer "In4.Cu")
		(net "M_J_DQ<43>")
	)
	(gr_poly
		(pts
			(xy 118.067582 -107.0229) (xy 118.067582 -106.7943) (xy 117.874542 -106.7054) (xy 117.830092 -106.7054)
			(xy 117.830092 -107.1118) (xy 117.874542 -107.1118)
		)
		(stroke
			(width 0)
			(type solid)
		)
		(fill yes)
		(layer "In4.Cu")
		(net "M_M_DQS_DP<5>")
	)
	(gr_poly
		(pts
			(xy 118.148608 -57.531762) (xy 118.14048 -57.339992) (xy 118.118382 -57.301384) (xy 117.772942 -57.501028)
			(xy 117.795294 -57.539382) (xy 117.957346 -57.642252)
		)
		(stroke
			(width 0)
			(type solid)
		)
		(fill yes)
		(layer "In4.Cu")
		(net "M_H_DQ<61>")
	)
	(gr_poly
		(pts
			(xy 118.178834 -49.466246) (xy 118.147338 -49.435004) (xy 117.947948 -49.361344) (xy 117.786404 -49.522888)
			(xy 117.860064 -49.722278) (xy 117.891306 -49.753774)
		)
		(stroke
			(width 0)
			(type solid)
		)
		(fill yes)
		(layer "In4.Cu")
		(net "M_J_DQ<46>")
	)
	(gr_poly
		(pts
			(xy 118.192804 -105.241344) (xy 118.148354 -105.241344) (xy 117.978174 -105.330244) (xy 117.978174 -105.551224)
			(xy 118.148354 -105.640124) (xy 118.192804 -105.640124)
		)
		(stroke
			(width 0)
			(type solid)
		)
		(fill yes)
		(layer "In4.Cu")
		(net "M_M_DQ<46>")
	)
	(gr_poly
		(pts
			(xy 118.192804 -103.260144) (xy 118.148354 -103.260144) (xy 117.978174 -103.349044) (xy 117.978174 -103.570024)
			(xy 118.148354 -103.658924) (xy 118.192804 -103.658924)
		)
		(stroke
			(width 0)
			(type solid)
		)
		(fill yes)
		(layer "In4.Cu")
		(net "M_M_DQ<42>")
	)
	(gr_poly
		(pts
			(xy 118.192804 -102.263194) (xy 118.148354 -102.263194) (xy 117.978174 -102.352094) (xy 117.978174 -102.573074)
			(xy 118.148354 -102.661974) (xy 118.192804 -102.661974)
		)
		(stroke
			(width 0)
			(type solid)
		)
		(fill yes)
		(layer "In4.Cu")
		(net "M_M_DQ<42>")
	)
	(gr_poly
		(pts
			(xy 118.192804 -101.26345) (xy 118.148354 -101.26345) (xy 117.978174 -101.35235) (xy 117.978174 -101.57333)
			(xy 118.148354 -101.66223) (xy 118.192804 -101.66223)
		)
		(stroke
			(width 0)
			(type solid)
		)
		(fill yes)
		(layer "In4.Cu")
		(net "M_M_DQ<42>")
	)
	(gr_poly
		(pts
			(xy 118.192804 -100.275644) (xy 118.148354 -100.275644) (xy 117.978174 -100.364544) (xy 117.978174 -100.585524)
			(xy 118.148354 -100.674424) (xy 118.192804 -100.674424)
		)
		(stroke
			(width 0)
			(type solid)
		)
		(fill yes)
		(layer "In4.Cu")
		(net "M_M_DQ<42>")
	)
	(gr_poly
		(pts
			(xy 118.192804 -99.291902) (xy 118.148354 -99.291902) (xy 117.978174 -99.380802) (xy 117.978174 -99.601782)
			(xy 118.148354 -99.690682) (xy 118.192804 -99.690682)
		)
		(stroke
			(width 0)
			(type solid)
		)
		(fill yes)
		(layer "In4.Cu")
		(net "M_M_DQ<42>")
	)
	(gr_poly
		(pts
			(xy 118.192804 -98.301302) (xy 118.148354 -98.301302) (xy 117.978174 -98.390202) (xy 117.978174 -98.611182)
			(xy 118.148354 -98.700082) (xy 118.192804 -98.700082)
		)
		(stroke
			(width 0)
			(type solid)
		)
		(fill yes)
		(layer "In4.Cu")
		(net "M_M_DQ<42>")
	)
	(gr_poly
		(pts
			(xy 118.192804 -97.310702) (xy 118.148354 -97.310702) (xy 117.978174 -97.399602) (xy 117.978174 -97.620582)
			(xy 118.148354 -97.709482) (xy 118.192804 -97.709482)
		)
		(stroke
			(width 0)
			(type solid)
		)
		(fill yes)
		(layer "In4.Cu")
		(net "M_M_DQ<42>")
	)
	(gr_poly
		(pts
			(xy 118.192804 -96.320102) (xy 118.148354 -96.320102) (xy 117.978174 -96.409002) (xy 117.978174 -96.629982)
			(xy 118.148354 -96.718882) (xy 118.192804 -96.718882)
		)
		(stroke
			(width 0)
			(type solid)
		)
		(fill yes)
		(layer "In4.Cu")
		(net "M_M_DQ<42>")
	)
	(gr_poly
		(pts
			(xy 118.248176 -48.18126) (xy 118.248176 -47.95266) (xy 118.055136 -47.86376) (xy 118.010686 -47.86376)
			(xy 118.010686 -48.27016) (xy 118.055136 -48.27016)
		)
		(stroke
			(width 0)
			(type solid)
		)
		(fill yes)
		(layer "In4.Cu")
		(net "M_J_DQS_DN<5>")
	)
	(gr_poly
		(pts
			(xy 118.367302 -56.784494) (xy 118.34495 -56.74614) (xy 118.182898 -56.64327) (xy 117.991636 -56.75376)
			(xy 117.999764 -56.94553) (xy 118.021862 -56.983884)
		)
		(stroke
			(width 0)
			(type solid)
		)
		(fill yes)
		(layer "In4.Cu")
		(net "M_H_DQ<60>")
	)
	(gr_poly
		(pts
			(xy 118.418864 -49.832006) (xy 118.345204 -49.632616) (xy 118.313708 -49.601374) (xy 118.026434 -49.888648)
			(xy 118.05793 -49.920144) (xy 118.25732 -49.993804)
		)
		(stroke
			(width 0)
			(type solid)
		)
		(fill yes)
		(layer "In4.Cu")
		(net "M_J_DQ<47>")
	)
	(gr_poly
		(pts
			(xy 118.419626 -104.490774) (xy 118.427754 -104.299004) (xy 118.236238 -104.188768) (xy 118.07444 -104.291638)
			(xy 118.051834 -104.329992) (xy 118.397528 -104.529382)
		)
		(stroke
			(width 0)
			(type solid)
		)
		(fill yes)
		(layer "In4.Cu")
		(net "M_M_DQ<47>")
	)
	(gr_poly
		(pts
			(xy 118.55958 -106.133646) (xy 118.72976 -106.044746) (xy 118.729506 -105.82402) (xy 118.55958 -105.73512)
			(xy 118.514876 -105.734866) (xy 118.51513 -106.1339)
		)
		(stroke
			(width 0)
			(type solid)
		)
		(fill yes)
		(layer "In4.Cu")
		(net "M_M_DQ<47>")
	)
	(gr_poly
		(pts
			(xy 118.56085 -105.143046) (xy 118.73103 -105.054146) (xy 118.730776 -104.83342) (xy 118.56085 -104.74452)
			(xy 118.516146 -104.744266) (xy 118.5164 -105.1433)
		)
		(stroke
			(width 0)
			(type solid)
		)
		(fill yes)
		(layer "In4.Cu")
		(net "M_M_DQ<47>")
	)
	(gr_poly
		(pts
			(xy 118.62943 -104.097582) (xy 118.651782 -104.059228) (xy 118.306342 -103.859584) (xy 118.284244 -103.898192)
			(xy 118.276116 -104.089962) (xy 118.467378 -104.200452)
		)
		(stroke
			(width 0)
			(type solid)
		)
		(fill yes)
		(layer "In4.Cu")
		(net "M_M_DQ<42>")
	)
	(gr_poly
		(pts
			(xy 118.73103 -103.062278) (xy 118.73103 -102.841298) (xy 118.56085 -102.752398) (xy 118.5164 -102.752398)
			(xy 118.5164 -103.151178) (xy 118.56085 -103.151178)
		)
		(stroke
			(width 0)
			(type solid)
		)
		(fill yes)
		(layer "In4.Cu")
		(net "M_M_DQ<43>")
	)
	(gr_poly
		(pts
			(xy 118.73103 -102.08387) (xy 118.73103 -101.86289) (xy 118.56085 -101.77399) (xy 118.5164 -101.77399)
			(xy 118.5164 -102.17277) (xy 118.56085 -102.17277)
		)
		(stroke
			(width 0)
			(type solid)
		)
		(fill yes)
		(layer "In4.Cu")
		(net "M_M_DQ<43>")
	)
	(gr_poly
		(pts
			(xy 118.73103 -101.09581) (xy 118.73103 -100.87483) (xy 118.56085 -100.78593) (xy 118.5164 -100.78593)
			(xy 118.5164 -101.18471) (xy 118.56085 -101.18471)
		)
		(stroke
			(width 0)
			(type solid)
		)
		(fill yes)
		(layer "In4.Cu")
		(net "M_M_DQ<43>")
	)
	(gr_poly
		(pts
			(xy 118.73103 -100.10267) (xy 118.73103 -99.88169) (xy 118.56085 -99.79279) (xy 118.5164 -99.79279)
			(xy 118.5164 -100.19157) (xy 118.56085 -100.19157)
		)
		(stroke
			(width 0)
			(type solid)
		)
		(fill yes)
		(layer "In4.Cu")
		(net "M_M_DQ<43>")
	)
	(gr_poly
		(pts
			(xy 118.73103 -99.106482) (xy 118.73103 -98.885502) (xy 118.56085 -98.796602) (xy 118.5164 -98.796602)
			(xy 118.5164 -99.195382) (xy 118.56085 -99.195382)
		)
		(stroke
			(width 0)
			(type solid)
		)
		(fill yes)
		(layer "In4.Cu")
		(net "M_M_DQ<43>")
	)
	(gr_poly
		(pts
			(xy 118.73103 -98.115882) (xy 118.73103 -97.894902) (xy 118.56085 -97.806002) (xy 118.5164 -97.806002)
			(xy 118.5164 -98.204782) (xy 118.56085 -98.204782)
		)
		(stroke
			(width 0)
			(type solid)
		)
		(fill yes)
		(layer "In4.Cu")
		(net "M_M_DQ<43>")
	)
	(gr_poly
		(pts
			(xy 118.73103 -97.125282) (xy 118.73103 -96.904302) (xy 118.56085 -96.815402) (xy 118.5164 -96.815402)
			(xy 118.5164 -97.214182) (xy 118.56085 -97.214182)
		)
		(stroke
			(width 0)
			(type solid)
		)
		(fill yes)
		(layer "In4.Cu")
		(net "M_M_DQ<43>")
	)
	(gr_poly
		(pts
			(xy 118.73103 -96.134682) (xy 118.73103 -95.913702) (xy 118.56085 -95.824802) (xy 118.5164 -95.824802)
			(xy 118.5164 -96.223582) (xy 118.56085 -96.223582)
		)
		(stroke
			(width 0)
			(type solid)
		)
		(fill yes)
		(layer "In4.Cu")
		(net "M_M_DQ<43>")
	)
	(gr_poly
		(pts
			(xy 118.76659 -53.732938) (xy 118.72214 -53.732938) (xy 118.55196 -53.821838) (xy 118.55196 -54.042818)
			(xy 118.72214 -54.131718) (xy 118.76659 -54.131718)
		)
		(stroke
			(width 0)
			(type solid)
		)
		(fill yes)
		(layer "In4.Cu")
		(net "M_H_DQ<60>")
	)
	(gr_poly
		(pts
			(xy 118.76659 -52.739544) (xy 118.72214 -52.739544) (xy 118.55196 -52.828444) (xy 118.55196 -53.049424)
			(xy 118.72214 -53.138324) (xy 118.76659 -53.138324)
		)
		(stroke
			(width 0)
			(type solid)
		)
		(fill yes)
		(layer "In4.Cu")
		(net "M_H_DQ<60>")
	)
	(gr_poly
		(pts
			(xy 118.766844 -55.711344) (xy 118.722394 -55.711344) (xy 118.552214 -55.800244) (xy 118.552214 -56.021224)
			(xy 118.722394 -56.110124) (xy 118.766844 -56.110124)
		)
		(stroke
			(width 0)
			(type solid)
		)
		(fill yes)
		(layer "In4.Cu")
		(net "M_H_DQ<60>")
	)
	(gr_poly
		(pts
			(xy 118.766844 -54.720744) (xy 118.722394 -54.720744) (xy 118.552214 -54.809644) (xy 118.552214 -55.030624)
			(xy 118.722394 -55.119524) (xy 118.766844 -55.119524)
		)
		(stroke
			(width 0)
			(type solid)
		)
		(fill yes)
		(layer "In4.Cu")
		(net "M_H_DQ<60>")
	)
	(gr_poly
		(pts
			(xy 118.879112 -48.765968) (xy 118.84787 -48.734472) (xy 118.64848 -48.660812) (xy 118.486682 -48.822356)
			(xy 118.560342 -49.021746) (xy 118.591838 -49.053242)
		)
		(stroke
			(width 0)
			(type solid)
		)
		(fill yes)
		(layer "In4.Cu")
		(net "M_J_DQ<46>")
	)
	(gr_poly
		(pts
			(xy 118.940072 -51.48326) (xy 118.901718 -51.461162) (xy 118.709948 -51.453034) (xy 118.599458 -51.644296)
			(xy 118.702328 -51.806348) (xy 118.740936 -51.8287)
		)
		(stroke
			(width 0)
			(type solid)
		)
		(fill yes)
		(layer "In4.Cu")
		(net "M_H_DQ<60>")
	)
	(gr_poly
		(pts
			(xy 118.976648 -47.668688) (xy 118.932198 -47.668688) (xy 118.739158 -47.757588) (xy 118.739158 -47.986188)
			(xy 118.932198 -48.075088) (xy 118.976648 -48.075088)
		)
		(stroke
			(width 0)
			(type solid)
		)
		(fill yes)
		(layer "In4.Cu")
		(net "M_J_DQ<46>")
	)
	(gr_poly
		(pts
			(xy 119.00535 -57.037986) (xy 118.997222 -56.846216) (xy 118.975378 -56.807608) (xy 118.629684 -57.006998)
			(xy 118.652036 -57.045352) (xy 118.814088 -57.148222)
		)
		(stroke
			(width 0)
			(type solid)
		)
		(fill yes)
		(layer "In4.Cu")
		(net "M_H_DQ<61>")
	)
	(gr_poly
		(pts
			(xy 119.005604 -58.028078) (xy 118.997476 -57.836308) (xy 118.975378 -57.7977) (xy 118.629938 -57.997344)
			(xy 118.65229 -58.035698) (xy 118.814342 -58.138568)
		)
		(stroke
			(width 0)
			(type solid)
		)
		(fill yes)
		(layer "In4.Cu")
		(net "M_H_DQ<57>")
	)
	(gr_poly
		(pts
			(xy 119.015256 -49.740312) (xy 118.984014 -49.708816) (xy 118.784624 -49.635156) (xy 118.622826 -49.7967)
			(xy 118.696486 -49.99609) (xy 118.727982 -50.027586)
		)
		(stroke
			(width 0)
			(type solid)
		)
		(fill yes)
		(layer "In4.Cu")
		(net "M_J_DQ<42>")
	)
	(gr_poly
		(pts
			(xy 119.04599 -105.724198) (xy 119.00154 -105.724198) (xy 118.83136 -105.813098) (xy 118.83136 -106.034078)
			(xy 119.00154 -106.122978) (xy 119.04599 -106.122978)
		)
		(stroke
			(width 0)
			(type solid)
		)
		(fill yes)
		(layer "In4.Cu")
		(net "M_M_DQ<42>")
	)
	(gr_poly
		(pts
			(xy 119.051324 -104.733598) (xy 119.006874 -104.733598) (xy 118.836694 -104.822498) (xy 118.836694 -105.043478)
			(xy 119.006874 -105.132378) (xy 119.051324 -105.132378)
		)
		(stroke
			(width 0)
			(type solid)
		)
		(fill yes)
		(layer "In4.Cu")
		(net "M_M_DQ<42>")
	)
	(gr_poly
		(pts
			(xy 119.051324 -102.752398) (xy 119.006874 -102.752398) (xy 118.836694 -102.841298) (xy 118.836694 -103.062278)
			(xy 119.006874 -103.151178) (xy 119.051324 -103.151178)
		)
		(stroke
			(width 0)
			(type solid)
		)
		(fill yes)
		(layer "In4.Cu")
		(net "M_L_DQ<60>")
	)
	(gr_poly
		(pts
			(xy 119.051324 -101.761798) (xy 119.006874 -101.761798) (xy 118.836694 -101.850698) (xy 118.836694 -102.071678)
			(xy 119.006874 -102.160578) (xy 119.051324 -102.160578)
		)
		(stroke
			(width 0)
			(type solid)
		)
		(fill yes)
		(layer "In4.Cu")
		(net "M_L_DQ<60>")
	)
	(gr_poly
		(pts
			(xy 119.051324 -100.771198) (xy 119.006874 -100.771198) (xy 118.836694 -100.860098) (xy 118.836694 -101.081078)
			(xy 119.006874 -101.169978) (xy 119.051324 -101.169978)
		)
		(stroke
			(width 0)
			(type solid)
		)
		(fill yes)
		(layer "In4.Cu")
		(net "M_L_DQ<60>")
	)
	(gr_poly
		(pts
			(xy 119.051324 -99.780598) (xy 119.006874 -99.780598) (xy 118.836694 -99.869498) (xy 118.836694 -100.090478)
			(xy 119.006874 -100.179378) (xy 119.051324 -100.179378)
		)
		(stroke
			(width 0)
			(type solid)
		)
		(fill yes)
		(layer "In4.Cu")
		(net "M_L_DQ<60>")
	)
	(gr_poly
		(pts
			(xy 119.051578 -98.796094) (xy 119.007128 -98.796094) (xy 118.836948 -98.884994) (xy 118.836948 -99.105974)
			(xy 119.007128 -99.194874) (xy 119.051578 -99.194874)
		)
		(stroke
			(width 0)
			(type solid)
		)
		(fill yes)
		(layer "In4.Cu")
		(net "M_L_DQ<60>")
	)
	(gr_poly
		(pts
			(xy 119.051578 -97.805494) (xy 119.007128 -97.805494) (xy 118.836948 -97.894394) (xy 118.836948 -98.115374)
			(xy 119.007128 -98.204274) (xy 119.051578 -98.204274)
		)
		(stroke
			(width 0)
			(type solid)
		)
		(fill yes)
		(layer "In4.Cu")
		(net "M_L_DQ<60>")
	)
	(gr_poly
		(pts
			(xy 119.051578 -96.814894) (xy 119.007128 -96.814894) (xy 118.836948 -96.903794) (xy 118.836948 -97.124774)
			(xy 119.007128 -97.213674) (xy 119.051578 -97.213674)
		)
		(stroke
			(width 0)
			(type solid)
		)
		(fill yes)
		(layer "In4.Cu")
		(net "M_L_DQ<60>")
	)
	(gr_poly
		(pts
			(xy 119.051578 -95.824294) (xy 119.007128 -95.824294) (xy 118.836948 -95.913194) (xy 118.836948 -96.134174)
			(xy 119.007128 -96.223074) (xy 119.051578 -96.223074)
		)
		(stroke
			(width 0)
			(type solid)
		)
		(fill yes)
		(layer "In4.Cu")
		(net "M_L_DQ<60>")
	)
	(gr_poly
		(pts
			(xy 119.119142 -49.131474) (xy 119.045482 -48.932084) (xy 119.013986 -48.900842) (xy 118.726712 -49.188116)
			(xy 118.758208 -49.219612) (xy 118.957598 -49.293272)
		)
		(stroke
			(width 0)
			(type solid)
		)
		(fill yes)
		(layer "In4.Cu")
		(net "M_J_DQ<47>")
	)
	(gr_poly
		(pts
			(xy 119.227346 -57.278778) (xy 119.204994 -57.240424) (xy 119.042942 -57.137554) (xy 118.85168 -57.248044)
			(xy 118.859808 -57.439814) (xy 118.881906 -57.478422)
		)
		(stroke
			(width 0)
			(type solid)
		)
		(fill yes)
		(layer "In4.Cu")
		(net "M_H_DQ<56>")
	)
	(gr_poly
		(pts
			(xy 119.255286 -50.105818) (xy 119.181626 -49.906428) (xy 119.15013 -49.875186) (xy 118.862856 -50.16246)
			(xy 118.894352 -50.193956) (xy 119.093742 -50.267616)
		)
		(stroke
			(width 0)
			(type solid)
		)
		(fill yes)
		(layer "In4.Cu")
		(net "M_J_DQ<43>")
	)
	(gr_poly
		(pts
			(xy 119.281956 -103.998014) (xy 119.290084 -103.806244) (xy 119.098822 -103.695754) (xy 118.93677 -103.798624)
			(xy 118.914418 -103.836978) (xy 119.259858 -104.036622)
		)
		(stroke
			(width 0)
			(type solid)
		)
		(fill yes)
		(layer "In4.Cu")
		(net "M_M_DQ<43>")
	)
	(gr_poly
		(pts
			(xy 119.30507 -55.513478) (xy 119.30507 -55.292498) (xy 119.13489 -55.203598) (xy 119.09044 -55.203598)
			(xy 119.09044 -55.602378) (xy 119.13489 -55.602378)
		)
		(stroke
			(width 0)
			(type solid)
		)
		(fill yes)
		(layer "In4.Cu")
		(net "M_H_DQ<61>")
	)
	(gr_poly
		(pts
			(xy 119.30507 -54.520084) (xy 119.30507 -54.299104) (xy 119.13489 -54.210204) (xy 119.09044 -54.210204)
			(xy 119.09044 -54.608984) (xy 119.13489 -54.608984)
		)
		(stroke
			(width 0)
			(type solid)
		)
		(fill yes)
		(layer "In4.Cu")
		(net "M_H_DQ<61>")
	)
	(gr_poly
		(pts
			(xy 119.30507 -53.529484) (xy 119.30507 -53.308504) (xy 119.13489 -53.219604) (xy 119.09044 -53.219604)
			(xy 119.09044 -53.618384) (xy 119.13489 -53.618384)
		)
		(stroke
			(width 0)
			(type solid)
		)
		(fill yes)
		(layer "In4.Cu")
		(net "M_H_DQ<61>")
	)
	(gr_poly
		(pts
			(xy 119.30507 -52.547774) (xy 119.30507 -52.326794) (xy 119.13489 -52.237894) (xy 119.09044 -52.237894)
			(xy 119.09044 -52.636674) (xy 119.13489 -52.636674)
		)
		(stroke
			(width 0)
			(type solid)
		)
		(fill yes)
		(layer "In4.Cu")
		(net "M_H_DQ<61>")
	)
	(gr_poly
		(pts
			(xy 119.404638 -47.986188) (xy 119.404638 -47.757588) (xy 119.211598 -47.668688) (xy 119.167148 -47.668688)
			(xy 119.167148 -48.075088) (xy 119.211598 -48.075088)
		)
		(stroke
			(width 0)
			(type solid)
		)
		(fill yes)
		(layer "In4.Cu")
		(net "M_J_DQ<47>")
	)
	(gr_poly
		(pts
			(xy 119.489474 -106.575098) (xy 119.511826 -106.536744) (xy 119.166386 -106.3371) (xy 119.144288 -106.375708)
			(xy 119.13616 -106.567478) (xy 119.327422 -106.677968)
		)
		(stroke
			(width 0)
			(type solid)
		)
		(fill yes)
		(layer "In4.Cu")
		(net "M_M_DQ<42>")
	)
	(gr_poly
		(pts
			(xy 119.489728 -103.603552) (xy 119.51208 -103.565198) (xy 119.166386 -103.365808) (xy 119.144542 -103.404416)
			(xy 119.136414 -103.596186) (xy 119.327676 -103.706422)
		)
		(stroke
			(width 0)
			(type solid)
		)
		(fill yes)
		(layer "In4.Cu")
		(net "M_L_DQ<60>")
	)
	(gr_poly
		(pts
			(xy 119.58955 -105.551224) (xy 119.58955 -105.330244) (xy 119.41937 -105.241344) (xy 119.37492 -105.241344)
			(xy 119.37492 -105.640124) (xy 119.41937 -105.640124)
		)
		(stroke
			(width 0)
			(type solid)
		)
		(fill yes)
		(layer "In4.Cu")
		(net "M_M_DQ<43>")
	)
	(gr_poly
		(pts
			(xy 119.58955 -104.560624) (xy 119.58955 -104.339644) (xy 119.41937 -104.250744) (xy 119.37492 -104.250744)
			(xy 119.37492 -104.649524) (xy 119.41937 -104.649524)
		)
		(stroke
			(width 0)
			(type solid)
		)
		(fill yes)
		(layer "In4.Cu")
		(net "M_M_DQ<43>")
	)
	(gr_poly
		(pts
			(xy 119.58955 -102.579424) (xy 119.58955 -102.358444) (xy 119.41937 -102.269544) (xy 119.37492 -102.269544)
			(xy 119.37492 -102.668324) (xy 119.41937 -102.668324)
		)
		(stroke
			(width 0)
			(type solid)
		)
		(fill yes)
		(layer "In4.Cu")
		(net "M_L_DQ<61>")
	)
	(gr_poly
		(pts
			(xy 119.58955 -101.588824) (xy 119.58955 -101.367844) (xy 119.41937 -101.278944) (xy 119.37492 -101.278944)
			(xy 119.37492 -101.677724) (xy 119.41937 -101.677724)
		)
		(stroke
			(width 0)
			(type solid)
		)
		(fill yes)
		(layer "In4.Cu")
		(net "M_L_DQ<61>")
	)
	(gr_poly
		(pts
			(xy 119.58955 -100.598224) (xy 119.58955 -100.377244) (xy 119.41937 -100.288344) (xy 119.37492 -100.288344)
			(xy 119.37492 -100.687124) (xy 119.41937 -100.687124)
		)
		(stroke
			(width 0)
			(type solid)
		)
		(fill yes)
		(layer "In4.Cu")
		(net "M_L_DQ<61>")
	)
	(gr_poly
		(pts
			(xy 119.58955 -99.607624) (xy 119.58955 -99.386644) (xy 119.41937 -99.297744) (xy 119.37492 -99.297744)
			(xy 119.37492 -99.696524) (xy 119.41937 -99.696524)
		)
		(stroke
			(width 0)
			(type solid)
		)
		(fill yes)
		(layer "In4.Cu")
		(net "M_L_DQ<61>")
	)
	(gr_poly
		(pts
			(xy 119.589804 -98.610674) (xy 119.589804 -98.389694) (xy 119.419624 -98.300794) (xy 119.375174 -98.300794)
			(xy 119.375174 -98.699574) (xy 119.419624 -98.699574)
		)
		(stroke
			(width 0)
			(type solid)
		)
		(fill yes)
		(layer "In4.Cu")
		(net "M_L_DQ<61>")
	)
	(gr_poly
		(pts
			(xy 119.589804 -97.620074) (xy 119.589804 -97.399094) (xy 119.419624 -97.310194) (xy 119.375174 -97.310194)
			(xy 119.375174 -97.708974) (xy 119.419624 -97.708974)
		)
		(stroke
			(width 0)
			(type solid)
		)
		(fill yes)
		(layer "In4.Cu")
		(net "M_L_DQ<61>")
	)
	(gr_poly
		(pts
			(xy 119.589804 -96.629474) (xy 119.589804 -96.408494) (xy 119.419624 -96.319594) (xy 119.375174 -96.319594)
			(xy 119.375174 -96.718374) (xy 119.419624 -96.718374)
		)
		(stroke
			(width 0)
			(type solid)
		)
		(fill yes)
		(layer "In4.Cu")
		(net "M_L_DQ<61>")
	)
	(gr_poly
		(pts
			(xy 119.62511 -60.153804) (xy 119.58066 -60.153804) (xy 119.41048 -60.242704) (xy 119.41048 -60.463684)
			(xy 119.58066 -60.552584) (xy 119.62511 -60.552584)
		)
		(stroke
			(width 0)
			(type solid)
		)
		(fill yes)
		(layer "In4.Cu")
		(net "M_H_DQS_DP<7>")
	)
	(gr_poly
		(pts
			(xy 119.62511 -56.191404) (xy 119.58066 -56.191404) (xy 119.41048 -56.280304) (xy 119.41048 -56.501284)
			(xy 119.58066 -56.590184) (xy 119.62511 -56.590184)
		)
		(stroke
			(width 0)
			(type solid)
		)
		(fill yes)
		(layer "In4.Cu")
		(net "M_H_DQ<56>")
	)
	(gr_poly
		(pts
			(xy 119.62511 -55.200804) (xy 119.58066 -55.200804) (xy 119.41048 -55.289704) (xy 119.41048 -55.510684)
			(xy 119.58066 -55.599584) (xy 119.62511 -55.599584)
		)
		(stroke
			(width 0)
			(type solid)
		)
		(fill yes)
		(layer "In4.Cu")
		(net "M_H_DQ<56>")
	)
	(gr_poly
		(pts
			(xy 119.62511 -54.212998) (xy 119.58066 -54.212998) (xy 119.41048 -54.301898) (xy 119.41048 -54.522878)
			(xy 119.58066 -54.611778) (xy 119.62511 -54.611778)
		)
		(stroke
			(width 0)
			(type solid)
		)
		(fill yes)
		(layer "In4.Cu")
		(net "M_H_DQ<56>")
	)
	(gr_poly
		(pts
			(xy 119.62511 -53.222398) (xy 119.58066 -53.222398) (xy 119.41048 -53.311298) (xy 119.41048 -53.532278)
			(xy 119.58066 -53.621178) (xy 119.62511 -53.621178)
		)
		(stroke
			(width 0)
			(type solid)
		)
		(fill yes)
		(layer "In4.Cu")
		(net "M_H_DQ<56>")
	)
	(gr_poly
		(pts
			(xy 119.715788 -49.03978) (xy 119.684292 -49.008284) (xy 119.484902 -48.934624) (xy 119.323358 -49.096422)
			(xy 119.397018 -49.295812) (xy 119.428514 -49.327054)
		)
		(stroke
			(width 0)
			(type solid)
		)
		(fill yes)
		(layer "In4.Cu")
		(net "M_J_DQ<42>")
	)
	(gr_poly
		(pts
			(xy 119.80164 -51.973226) (xy 119.763286 -51.951128) (xy 119.571516 -51.943) (xy 119.461026 -52.134262)
			(xy 119.563896 -52.296314) (xy 119.602504 -52.318666)
		)
		(stroke
			(width 0)
			(type solid)
		)
		(fill yes)
		(layer "In4.Cu")
		(net "M_H_DQ<56>")
	)
	(gr_poly
		(pts
			(xy 119.86387 -58.523632) (xy 119.855742 -58.331862) (xy 119.833644 -58.293508) (xy 119.488204 -58.492898)
			(xy 119.510556 -58.531252) (xy 119.672608 -58.634122)
		)
		(stroke
			(width 0)
			(type solid)
		)
		(fill yes)
		(layer "In4.Cu")
		(net "M_H_DQS_DN<16>")
	)
	(gr_poly
		(pts
			(xy 119.909844 -105.241344) (xy 119.865394 -105.241344) (xy 119.695214 -105.330244) (xy 119.695214 -105.551224)
			(xy 119.865394 -105.640124) (xy 119.909844 -105.640124)
		)
		(stroke
			(width 0)
			(type solid)
		)
		(fill yes)
		(layer "In4.Cu")
		(net "M_L_DQ<60>")
	)
	(gr_poly
		(pts
			(xy 119.909844 -104.250744) (xy 119.865394 -104.250744) (xy 119.695214 -104.339644) (xy 119.695214 -104.560624)
			(xy 119.865394 -104.649524) (xy 119.909844 -104.649524)
		)
		(stroke
			(width 0)
			(type solid)
		)
		(fill yes)
		(layer "In4.Cu")
		(net "M_L_DQ<60>")
	)
	(gr_poly
		(pts
			(xy 119.909844 -102.269544) (xy 119.865394 -102.269544) (xy 119.695214 -102.358444) (xy 119.695214 -102.579424)
			(xy 119.865394 -102.668324) (xy 119.909844 -102.668324)
		)
		(stroke
			(width 0)
			(type solid)
		)
		(fill yes)
		(layer "In4.Cu")
		(net "M_L_DQ<56>")
	)
	(gr_poly
		(pts
			(xy 119.909844 -101.278944) (xy 119.865394 -101.278944) (xy 119.695214 -101.367844) (xy 119.695214 -101.588824)
			(xy 119.865394 -101.677724) (xy 119.909844 -101.677724)
		)
		(stroke
			(width 0)
			(type solid)
		)
		(fill yes)
		(layer "In4.Cu")
		(net "M_L_DQ<56>")
	)
	(gr_poly
		(pts
			(xy 119.909844 -100.288344) (xy 119.865394 -100.288344) (xy 119.695214 -100.377244) (xy 119.695214 -100.598224)
			(xy 119.865394 -100.687124) (xy 119.909844 -100.687124)
		)
		(stroke
			(width 0)
			(type solid)
		)
		(fill yes)
		(layer "In4.Cu")
		(net "M_L_DQ<56>")
	)
	(gr_poly
		(pts
			(xy 119.909844 -99.297744) (xy 119.865394 -99.297744) (xy 119.695214 -99.386644) (xy 119.695214 -99.607624)
			(xy 119.865394 -99.696524) (xy 119.909844 -99.696524)
		)
		(stroke
			(width 0)
			(type solid)
		)
		(fill yes)
		(layer "In4.Cu")
		(net "M_L_DQ<56>")
	)
	(gr_poly
		(pts
			(xy 119.910098 -98.300794) (xy 119.865648 -98.300794) (xy 119.695468 -98.389694) (xy 119.695468 -98.610674)
			(xy 119.865648 -98.699574) (xy 119.910098 -98.699574)
		)
		(stroke
			(width 0)
			(type solid)
		)
		(fill yes)
		(layer "In4.Cu")
		(net "M_L_DQ<56>")
	)
	(gr_poly
		(pts
			(xy 119.910098 -97.310194) (xy 119.865648 -97.310194) (xy 119.695468 -97.399094) (xy 119.695468 -97.620074)
			(xy 119.865648 -97.708974) (xy 119.910098 -97.708974)
		)
		(stroke
			(width 0)
			(type solid)
		)
		(fill yes)
		(layer "In4.Cu")
		(net "M_L_DQ<56>")
	)
	(gr_poly
		(pts
			(xy 119.910098 -96.319594) (xy 119.865648 -96.319594) (xy 119.695468 -96.408494) (xy 119.695468 -96.629474)
			(xy 119.865648 -96.718374) (xy 119.910098 -96.718374)
		)
		(stroke
			(width 0)
			(type solid)
		)
		(fill yes)
		(layer "In4.Cu")
		(net "M_L_DQ<56>")
	)
	(gr_poly
		(pts
			(xy 119.955818 -49.40554) (xy 119.882158 -49.20615) (xy 119.850662 -49.174654) (xy 119.563388 -49.461928)
			(xy 119.59463 -49.493424) (xy 119.79402 -49.567084)
		)
		(stroke
			(width 0)
			(type solid)
		)
		(fill yes)
		(layer "In4.Cu")
		(net "M_J_DQ<43>")
	)
	(gr_poly
		(pts
			(xy 120.08358 -57.775856) (xy 120.061228 -57.737502) (xy 119.899176 -57.634632) (xy 119.707914 -57.745122)
			(xy 119.716042 -57.936892) (xy 119.73814 -57.9755)
		)
		(stroke
			(width 0)
			(type solid)
		)
		(fill yes)
		(layer "In4.Cu")
		(net "M_H_DQS_DP<16>")
	)
	(gr_poly
		(pts
			(xy 120.136666 -103.500174) (xy 120.144794 -103.308404) (xy 119.953278 -103.198168) (xy 119.79148 -103.301038)
			(xy 119.768874 -103.339392) (xy 120.114568 -103.538782)
		)
		(stroke
			(width 0)
			(type solid)
		)
		(fill yes)
		(layer "In4.Cu")
		(net "M_L_DQ<61>")
	)
	(gr_poly
		(pts
			(xy 120.142 -106.47553) (xy 120.150128 -106.28376) (xy 119.958866 -106.17327) (xy 119.796814 -106.27614)
			(xy 119.774462 -106.314494) (xy 120.119902 -106.514138)
		)
		(stroke
			(width 0)
			(type solid)
		)
		(fill yes)
		(layer "In4.Cu")
		(net "M_M_DQ<43>")
	)
	(gr_poly
		(pts
			(xy 120.163336 -54.040024) (xy 120.163336 -53.819044) (xy 119.993156 -53.730144) (xy 119.948706 -53.730144)
			(xy 119.948706 -54.128924) (xy 119.993156 -54.128924)
		)
		(stroke
			(width 0)
			(type solid)
		)
		(fill yes)
		(layer "In4.Cu")
		(net "M_H_DQ<57>")
	)
	(gr_poly
		(pts
			(xy 120.163336 -53.049424) (xy 120.163336 -52.828444) (xy 119.993156 -52.739544) (xy 119.948706 -52.739544)
			(xy 119.948706 -53.138324) (xy 119.993156 -53.138324)
		)
		(stroke
			(width 0)
			(type solid)
		)
		(fill yes)
		(layer "In4.Cu")
		(net "M_H_DQ<57>")
	)
	(gr_poly
		(pts
			(xy 120.16359 -60.977018) (xy 120.16359 -60.756038) (xy 119.99341 -60.667138) (xy 119.94896 -60.667138)
			(xy 119.94896 -61.065918) (xy 119.99341 -61.065918)
		)
		(stroke
			(width 0)
			(type solid)
		)
		(fill yes)
		(layer "In4.Cu")
		(net "M_H_DQS_DN<7>")
	)
	(gr_poly
		(pts
			(xy 120.16359 -59.983624) (xy 120.16359 -59.762644) (xy 119.99341 -59.673744) (xy 119.94896 -59.673744)
			(xy 119.94896 -60.072524) (xy 119.99341 -60.072524)
		)
		(stroke
			(width 0)
			(type solid)
		)
		(fill yes)
		(layer "In4.Cu")
		(net "M_H_DQS_DN<7>")
	)
	(gr_poly
		(pts
			(xy 120.16359 -56.024018) (xy 120.16359 -55.803038) (xy 119.99341 -55.714138) (xy 119.94896 -55.714138)
			(xy 119.94896 -56.112918) (xy 119.99341 -56.112918)
		)
		(stroke
			(width 0)
			(type solid)
		)
		(fill yes)
		(layer "In4.Cu")
		(net "M_H_DQ<57>")
	)
	(gr_poly
		(pts
			(xy 120.16359 -55.033418) (xy 120.16359 -54.812438) (xy 119.99341 -54.723538) (xy 119.94896 -54.723538)
			(xy 119.94896 -55.122318) (xy 119.99341 -55.122318)
		)
		(stroke
			(width 0)
			(type solid)
		)
		(fill yes)
		(layer "In4.Cu")
		(net "M_H_DQ<57>")
	)
	(gr_poly
		(pts
			(xy 120.226328 -47.714662) (xy 120.181878 -47.714662) (xy 119.988838 -47.803562) (xy 119.988838 -48.032162)
			(xy 120.181878 -48.121062) (xy 120.226328 -48.121062)
		)
		(stroke
			(width 0)
			(type solid)
		)
		(fill yes)
		(layer "In4.Cu")
		(net "M_J_DQ<42>")
	)
	(gr_poly
		(pts
			(xy 120.327674 -95.071184) (xy 120.224804 -94.909132) (xy 120.186196 -94.887034) (xy 119.986806 -95.23222)
			(xy 120.025414 -95.254572) (xy 120.217184 -95.2627)
		)
		(stroke
			(width 0)
			(type solid)
		)
		(fill yes)
		(layer "In4.Cu")
		(net "M_L_DQ<56>")
	)
	(gr_poly
		(pts
			(xy 120.351804 -106.082084) (xy 120.37441 -106.04373) (xy 120.028716 -105.84434) (xy 120.006618 -105.882948)
			(xy 119.99849 -106.074718) (xy 120.190006 -106.184954)
		)
		(stroke
			(width 0)
			(type solid)
		)
		(fill yes)
		(layer "In4.Cu")
		(net "M_L_DQ<60>")
	)
	(gr_poly
		(pts
			(xy 120.44807 -105.043478) (xy 120.44807 -104.822498) (xy 120.27789 -104.733598) (xy 120.23344 -104.733598)
			(xy 120.23344 -105.132378) (xy 120.27789 -105.132378)
		)
		(stroke
			(width 0)
			(type solid)
		)
		(fill yes)
		(layer "In4.Cu")
		(net "M_L_DQ<61>")
	)
	(gr_poly
		(pts
			(xy 120.44807 -104.052878) (xy 120.44807 -103.831898) (xy 120.27789 -103.742998) (xy 120.23344 -103.742998)
			(xy 120.23344 -104.141778) (xy 120.27789 -104.141778)
		)
		(stroke
			(width 0)
			(type solid)
		)
		(fill yes)
		(layer "In4.Cu")
		(net "M_L_DQ<61>")
	)
	(gr_poly
		(pts
			(xy 120.44807 -102.071678) (xy 120.44807 -101.850698) (xy 120.27789 -101.761798) (xy 120.23344 -101.761798)
			(xy 120.23344 -102.160578) (xy 120.27789 -102.160578)
		)
		(stroke
			(width 0)
			(type solid)
		)
		(fill yes)
		(layer "In4.Cu")
		(net "M_L_DQ<57>")
	)
	(gr_poly
		(pts
			(xy 120.44807 -101.081078) (xy 120.44807 -100.860098) (xy 120.27789 -100.771198) (xy 120.23344 -100.771198)
			(xy 120.23344 -101.169978) (xy 120.27789 -101.169978)
		)
		(stroke
			(width 0)
			(type solid)
		)
		(fill yes)
		(layer "In4.Cu")
		(net "M_L_DQ<57>")
	)
	(gr_poly
		(pts
			(xy 120.44807 -100.090478) (xy 120.44807 -99.869498) (xy 120.27789 -99.780598) (xy 120.23344 -99.780598)
			(xy 120.23344 -100.179378) (xy 120.27789 -100.179378)
		)
		(stroke
			(width 0)
			(type solid)
		)
		(fill yes)
		(layer "In4.Cu")
		(net "M_L_DQ<57>")
	)
	(gr_poly
		(pts
			(xy 120.448324 -99.105974) (xy 120.448324 -98.884994) (xy 120.278144 -98.796094) (xy 120.233694 -98.796094)
			(xy 120.233694 -99.194874) (xy 120.278144 -99.194874)
		)
		(stroke
			(width 0)
			(type solid)
		)
		(fill yes)
		(layer "In4.Cu")
		(net "M_L_DQ<57>")
	)
	(gr_poly
		(pts
			(xy 120.448324 -98.115374) (xy 120.448324 -97.894394) (xy 120.278144 -97.805494) (xy 120.233694 -97.805494)
			(xy 120.233694 -98.204274) (xy 120.278144 -98.204274)
		)
		(stroke
			(width 0)
			(type solid)
		)
		(fill yes)
		(layer "In4.Cu")
		(net "M_L_DQ<57>")
	)
	(gr_poly
		(pts
			(xy 120.448324 -97.124774) (xy 120.448324 -96.903794) (xy 120.278144 -96.814894) (xy 120.233694 -96.814894)
			(xy 120.233694 -97.213674) (xy 120.278144 -97.213674)
		)
		(stroke
			(width 0)
			(type solid)
		)
		(fill yes)
		(layer "In4.Cu")
		(net "M_L_DQ<57>")
	)
	(gr_poly
		(pts
			(xy 120.48363 -56.701944) (xy 120.43918 -56.701944) (xy 120.269 -56.790844) (xy 120.269 -57.011824)
			(xy 120.43918 -57.100724) (xy 120.48363 -57.100724)
		)
		(stroke
			(width 0)
			(type solid)
		)
		(fill yes)
		(layer "In4.Cu")
		(net "M_H_DQS_DP<16>")
	)
	(gr_poly
		(pts
			(xy 120.48363 -55.711344) (xy 120.43918 -55.711344) (xy 120.269 -55.800244) (xy 120.269 -56.021224)
			(xy 120.43918 -56.110124) (xy 120.48363 -56.110124)
		)
		(stroke
			(width 0)
			(type solid)
		)
		(fill yes)
		(layer "In4.Cu")
		(net "M_H_DQS_DP<16>")
	)
	(gr_poly
		(pts
			(xy 120.48363 -54.720744) (xy 120.43918 -54.720744) (xy 120.269 -54.809644) (xy 120.269 -55.030624)
			(xy 120.43918 -55.119524) (xy 120.48363 -55.119524)
		)
		(stroke
			(width 0)
			(type solid)
		)
		(fill yes)
		(layer "In4.Cu")
		(net "M_H_DQS_DP<16>")
	)
	(gr_poly
		(pts
			(xy 120.48363 -53.730144) (xy 120.43918 -53.730144) (xy 120.269 -53.819044) (xy 120.269 -54.040024)
			(xy 120.43918 -54.128924) (xy 120.48363 -54.128924)
		)
		(stroke
			(width 0)
			(type solid)
		)
		(fill yes)
		(layer "In4.Cu")
		(net "M_H_DQS_DP<16>")
	)
	(gr_poly
		(pts
			(xy 120.642126 -52.137056) (xy 120.650762 -51.945286) (xy 120.631966 -51.9049) (xy 120.270778 -52.073556)
			(xy 120.289574 -52.113688) (xy 120.441974 -52.230528)
		)
		(stroke
			(width 0)
			(type solid)
		)
		(fill yes)
		(layer "In4.Cu")
		(net "M_H_DQ<57>")
	)
	(gr_poly
		(pts
			(xy 120.658128 -52.472082) (xy 120.619774 -52.449984) (xy 120.428004 -52.441856) (xy 120.317514 -52.633118)
			(xy 120.420384 -52.79517) (xy 120.458992 -52.817522)
		)
		(stroke
			(width 0)
			(type solid)
		)
		(fill yes)
		(layer "In4.Cu")
		(net "M_H_DQS_DP<16>")
	)
	(gr_poly
		(pts
			(xy 120.677178 -48.032162) (xy 120.677178 -47.803562) (xy 120.484138 -47.714662) (xy 120.439688 -47.714662)
			(xy 120.439688 -48.121062) (xy 120.484138 -48.121062)
		)
		(stroke
			(width 0)
			(type solid)
		)
		(fill yes)
		(layer "In4.Cu")
		(net "M_J_DQ<43>")
	)
	(gr_poly
		(pts
			(xy 120.76811 -104.730804) (xy 120.72366 -104.730804) (xy 120.55348 -104.819704) (xy 120.55348 -105.040684)
			(xy 120.72366 -105.129584) (xy 120.76811 -105.129584)
		)
		(stroke
			(width 0)
			(type solid)
		)
		(fill yes)
		(layer "In4.Cu")
		(net "M_L_DQ<56>")
	)
	(gr_poly
		(pts
			(xy 120.76811 -103.740204) (xy 120.72366 -103.740204) (xy 120.55348 -103.829104) (xy 120.55348 -104.050084)
			(xy 120.72366 -104.138984) (xy 120.76811 -104.138984)
		)
		(stroke
			(width 0)
			(type solid)
		)
		(fill yes)
		(layer "In4.Cu")
		(net "M_L_DQ<56>")
	)
	(gr_poly
		(pts
			(xy 120.76811 -101.759004) (xy 120.72366 -101.759004) (xy 120.55348 -101.847904) (xy 120.55348 -102.068884)
			(xy 120.72366 -102.157784) (xy 120.76811 -102.157784)
		)
		(stroke
			(width 0)
			(type solid)
		)
		(fill yes)
		(layer "In4.Cu")
		(net "M_L_DQS_DP<16>")
	)
	(gr_poly
		(pts
			(xy 120.76811 -100.768404) (xy 120.72366 -100.768404) (xy 120.55348 -100.857304) (xy 120.55348 -101.078284)
			(xy 120.72366 -101.167184) (xy 120.76811 -101.167184)
		)
		(stroke
			(width 0)
			(type solid)
		)
		(fill yes)
		(layer "In4.Cu")
		(net "M_L_DQS_DP<16>")
	)
	(gr_poly
		(pts
			(xy 120.76811 -99.777804) (xy 120.72366 -99.777804) (xy 120.55348 -99.866704) (xy 120.55348 -100.087684)
			(xy 120.72366 -100.176584) (xy 120.76811 -100.176584)
		)
		(stroke
			(width 0)
			(type solid)
		)
		(fill yes)
		(layer "In4.Cu")
		(net "M_L_DQS_DP<16>")
	)
	(gr_poly
		(pts
			(xy 120.76811 -98.787204) (xy 120.72366 -98.787204) (xy 120.55348 -98.876104) (xy 120.55348 -99.097084)
			(xy 120.72366 -99.185984) (xy 120.76811 -99.185984)
		)
		(stroke
			(width 0)
			(type solid)
		)
		(fill yes)
		(layer "In4.Cu")
		(net "M_L_DQS_DP<16>")
	)
	(gr_poly
		(pts
			(xy 120.76811 -97.805494) (xy 120.72366 -97.805494) (xy 120.55348 -97.894394) (xy 120.55348 -98.115374)
			(xy 120.72366 -98.204274) (xy 120.76811 -98.204274)
		)
		(stroke
			(width 0)
			(type solid)
		)
		(fill yes)
		(layer "In4.Cu")
		(net "M_L_DQS_DP<16>")
	)
	(gr_poly
		(pts
			(xy 120.76811 -96.814894) (xy 120.72366 -96.814894) (xy 120.55348 -96.903794) (xy 120.55348 -97.124774)
			(xy 120.72366 -97.213674) (xy 120.76811 -97.213674)
		)
		(stroke
			(width 0)
			(type solid)
		)
		(fill yes)
		(layer "In4.Cu")
		(net "M_L_DQS_DP<16>")
	)
	(gr_poly
		(pts
			(xy 120.76811 -95.824294) (xy 120.72366 -95.824294) (xy 120.55348 -95.913194) (xy 120.55348 -96.134174)
			(xy 120.72366 -96.223074) (xy 120.76811 -96.223074)
		)
		(stroke
			(width 0)
			(type solid)
		)
		(fill yes)
		(layer "In4.Cu")
		(net "M_L_DQS_DP<16>")
	)
	(gr_poly
		(pts
			(xy 120.76811 -94.833694) (xy 120.72366 -94.833694) (xy 120.55348 -94.922594) (xy 120.55348 -95.143574)
			(xy 120.72366 -95.232474) (xy 120.76811 -95.232474)
		)
		(stroke
			(width 0)
			(type solid)
		)
		(fill yes)
		(layer "In4.Cu")
		(net "M_L_DQS_DP<16>")
	)
	(gr_poly
		(pts
			(xy 120.946418 -58.268108) (xy 120.924066 -58.229754) (xy 120.762014 -58.126884) (xy 120.570752 -58.237374)
			(xy 120.57888 -58.429144) (xy 120.600978 -58.467752)
		)
		(stroke
			(width 0)
			(type solid)
		)
		(fill yes)
		(layer "In4.Cu")
		(net "M_H_DQS_DP<7>")
	)
	(gr_poly
		(pts
			(xy 120.998996 -105.979214) (xy 121.007124 -105.787444) (xy 120.815862 -105.676954) (xy 120.65381 -105.779824)
			(xy 120.631458 -105.818178) (xy 120.976898 -106.017822)
		)
		(stroke
			(width 0)
			(type solid)
		)
		(fill yes)
		(layer "In4.Cu")
		(net "M_L_DQ<61>")
	)
	(gr_poly
		(pts
			(xy 120.99925 -103.00716) (xy 121.007124 -102.81539) (xy 120.815862 -102.7049) (xy 120.65381 -102.80777)
			(xy 120.631458 -102.846378) (xy 120.976898 -103.045768)
		)
		(stroke
			(width 0)
			(type solid)
		)
		(fill yes)
		(layer "In4.Cu")
		(net "M_L_DQ<57>")
	)
	(gr_poly
		(pts
			(xy 121.021856 -56.504078) (xy 121.021856 -56.283098) (xy 120.851676 -56.194198) (xy 120.807226 -56.194198)
			(xy 120.807226 -56.592978) (xy 120.851676 -56.592978)
		)
		(stroke
			(width 0)
			(type solid)
		)
		(fill yes)
		(layer "In4.Cu")
		(net "M_H_DQS_DN<16>")
	)
	(gr_poly
		(pts
			(xy 121.021856 -55.513478) (xy 121.021856 -55.292498) (xy 120.851676 -55.203598) (xy 120.807226 -55.203598)
			(xy 120.807226 -55.602378) (xy 120.851676 -55.602378)
		)
		(stroke
			(width 0)
			(type solid)
		)
		(fill yes)
		(layer "In4.Cu")
		(net "M_H_DQS_DN<16>")
	)
	(gr_poly
		(pts
			(xy 121.021856 -54.522878) (xy 121.021856 -54.301898) (xy 120.851676 -54.212998) (xy 120.807226 -54.212998)
			(xy 120.807226 -54.611778) (xy 120.851676 -54.611778)
		)
		(stroke
			(width 0)
			(type solid)
		)
		(fill yes)
		(layer "In4.Cu")
		(net "M_H_DQS_DN<16>")
	)
	(gr_poly
		(pts
			(xy 121.021856 -53.532278) (xy 121.021856 -53.311298) (xy 120.851676 -53.222398) (xy 120.807226 -53.222398)
			(xy 120.807226 -53.621178) (xy 120.851676 -53.621178)
		)
		(stroke
			(width 0)
			(type solid)
		)
		(fill yes)
		(layer "In4.Cu")
		(net "M_H_DQS_DN<16>")
	)
	(gr_poly
		(pts
			(xy 121.203466 -106.573574) (xy 121.225818 -106.53522) (xy 120.880378 -106.33583) (xy 120.85828 -106.374184)
			(xy 120.850152 -106.565954) (xy 121.041414 -106.676444)
		)
		(stroke
			(width 0)
			(type solid)
		)
		(fill yes)
		(layer "In4.Cu")
		(net "M_L_DQ<60>")
	)
	(gr_poly
		(pts
			(xy 121.20626 -105.584498) (xy 121.228612 -105.546144) (xy 120.883426 -105.3465) (xy 120.861074 -105.385362)
			(xy 120.852946 -105.577132) (xy 121.044462 -105.687368)
		)
		(stroke
			(width 0)
			(type solid)
		)
		(fill yes)
		(layer "In4.Cu")
		(net "M_L_DQ<56>")
	)
	(gr_poly
		(pts
			(xy 121.20626 -102.612698) (xy 121.228612 -102.574344) (xy 120.883426 -102.3747) (xy 120.861074 -102.413562)
			(xy 120.852946 -102.605332) (xy 121.044462 -102.715568)
		)
		(stroke
			(width 0)
			(type solid)
		)
		(fill yes)
		(layer "In4.Cu")
		(net "M_L_DQS_DP<16>")
	)
	(gr_poly
		(pts
			(xy 121.306336 -98.610674) (xy 121.306336 -98.389694) (xy 121.136156 -98.300794) (xy 121.091706 -98.300794)
			(xy 121.091706 -98.699574) (xy 121.136156 -98.699574)
		)
		(stroke
			(width 0)
			(type solid)
		)
		(fill yes)
		(layer "In4.Cu")
		(net "M_L_DQS_DN<16>")
	)
	(gr_poly
		(pts
			(xy 121.306336 -97.620074) (xy 121.306336 -97.399094) (xy 121.136156 -97.310194) (xy 121.091706 -97.310194)
			(xy 121.091706 -97.708974) (xy 121.136156 -97.708974)
		)
		(stroke
			(width 0)
			(type solid)
		)
		(fill yes)
		(layer "In4.Cu")
		(net "M_L_DQS_DN<16>")
	)
	(gr_poly
		(pts
			(xy 121.306336 -96.629474) (xy 121.306336 -96.408494) (xy 121.136156 -96.319594) (xy 121.091706 -96.319594)
			(xy 121.091706 -96.718374) (xy 121.136156 -96.718374)
		)
		(stroke
			(width 0)
			(type solid)
		)
		(fill yes)
		(layer "In4.Cu")
		(net "M_L_DQS_DN<16>")
	)
	(gr_poly
		(pts
			(xy 121.306336 -95.638874) (xy 121.306336 -95.417894) (xy 121.136156 -95.328994) (xy 121.091706 -95.328994)
			(xy 121.091706 -95.727774) (xy 121.136156 -95.727774)
		)
		(stroke
			(width 0)
			(type solid)
		)
		(fill yes)
		(layer "In4.Cu")
		(net "M_L_DQS_DN<16>")
	)
	(gr_poly
		(pts
			(xy 121.306336 -94.648274) (xy 121.306336 -94.427294) (xy 121.136156 -94.338394) (xy 121.091706 -94.338394)
			(xy 121.091706 -94.737174) (xy 121.136156 -94.737174)
		)
		(stroke
			(width 0)
			(type solid)
		)
		(fill yes)
		(layer "In4.Cu")
		(net "M_L_DQS_DN<16>")
	)
	(gr_poly
		(pts
			(xy 121.30659 -104.563418) (xy 121.30659 -104.342438) (xy 121.13641 -104.253538) (xy 121.09196 -104.253538)
			(xy 121.09196 -104.652318) (xy 121.13641 -104.652318)
		)
		(stroke
			(width 0)
			(type solid)
		)
		(fill yes)
		(layer "In4.Cu")
		(net "M_L_DQ<57>")
	)
	(gr_poly
		(pts
			(xy 121.30659 -103.572818) (xy 121.30659 -103.351838) (xy 121.13641 -103.262938) (xy 121.09196 -103.262938)
			(xy 121.09196 -103.661718) (xy 121.13641 -103.661718)
		)
		(stroke
			(width 0)
			(type solid)
		)
		(fill yes)
		(layer "In4.Cu")
		(net "M_L_DQ<57>")
	)
	(gr_poly
		(pts
			(xy 121.30659 -101.591618) (xy 121.30659 -101.370638) (xy 121.13641 -101.281738) (xy 121.09196 -101.281738)
			(xy 121.09196 -101.680518) (xy 121.13641 -101.680518)
		)
		(stroke
			(width 0)
			(type solid)
		)
		(fill yes)
		(layer "In4.Cu")
		(net "M_L_DQS_DN<16>")
	)
	(gr_poly
		(pts
			(xy 121.30659 -100.601018) (xy 121.30659 -100.380038) (xy 121.13641 -100.291138) (xy 121.09196 -100.291138)
			(xy 121.09196 -100.689918) (xy 121.13641 -100.689918)
		)
		(stroke
			(width 0)
			(type solid)
		)
		(fill yes)
		(layer "In4.Cu")
		(net "M_L_DQS_DN<16>")
	)
	(gr_poly
		(pts
			(xy 121.30659 -99.610418) (xy 121.30659 -99.389438) (xy 121.13641 -99.300538) (xy 121.09196 -99.300538)
			(xy 121.09196 -99.699318) (xy 121.13641 -99.699318)
		)
		(stroke
			(width 0)
			(type solid)
		)
		(fill yes)
		(layer "In4.Cu")
		(net "M_L_DQS_DN<16>")
	)
	(gr_poly
		(pts
			(xy 121.34215 -57.184798) (xy 121.2977 -57.184798) (xy 121.12752 -57.273698) (xy 121.12752 -57.494678)
			(xy 121.2977 -57.583578) (xy 121.34215 -57.583578)
		)
		(stroke
			(width 0)
			(type solid)
		)
		(fill yes)
		(layer "In4.Cu")
		(net "M_H_DQS_DP<7>")
	)
	(gr_poly
		(pts
			(xy 121.34215 -56.194198) (xy 121.2977 -56.194198) (xy 121.12752 -56.283098) (xy 121.12752 -56.504078)
			(xy 121.2977 -56.592978) (xy 121.34215 -56.592978)
		)
		(stroke
			(width 0)
			(type solid)
		)
		(fill yes)
		(layer "In4.Cu")
		(net "M_H_DQS_DP<7>")
	)
	(gr_poly
		(pts
			(xy 121.34215 -55.203598) (xy 121.2977 -55.203598) (xy 121.12752 -55.292498) (xy 121.12752 -55.513478)
			(xy 121.2977 -55.602378) (xy 121.34215 -55.602378)
		)
		(stroke
			(width 0)
			(type solid)
		)
		(fill yes)
		(layer "In4.Cu")
		(net "M_H_DQS_DP<7>")
	)
	(gr_poly
		(pts
			(xy 121.34215 -54.212998) (xy 121.2977 -54.212998) (xy 121.12752 -54.301898) (xy 121.12752 -54.522878)
			(xy 121.2977 -54.611778) (xy 121.34215 -54.611778)
		)
		(stroke
			(width 0)
			(type solid)
		)
		(fill yes)
		(layer "In4.Cu")
		(net "M_H_DQS_DP<7>")
	)
	(gr_poly
		(pts
			(xy 121.515632 -52.96916) (xy 121.477278 -52.947062) (xy 121.285508 -52.938934) (xy 121.175018 -53.130196)
			(xy 121.277888 -53.292248) (xy 121.316496 -53.3146)
		)
		(stroke
			(width 0)
			(type solid)
		)
		(fill yes)
		(layer "In4.Cu")
		(net "M_H_DQS_DP<7>")
	)
	(gr_poly
		(pts
			(xy 121.578624 -60.505848) (xy 121.570496 -60.314078) (xy 121.548398 -60.27547) (xy 121.202958 -60.475114)
			(xy 121.22531 -60.513468) (xy 121.387362 -60.616338)
		)
		(stroke
			(width 0)
			(type solid)
		)
		(fill yes)
		(layer "In4.Cu")
		(net "M_H_DQ<59>")
	)
	(gr_poly
		(pts
			(xy 121.58091 -59.513978) (xy 121.572782 -59.322208) (xy 121.550684 -59.2836) (xy 121.205244 -59.483244)
			(xy 121.227596 -59.521598) (xy 121.389648 -59.624468)
		)
		(stroke
			(width 0)
			(type solid)
		)
		(fill yes)
		(layer "In4.Cu")
		(net "M_H_DQ<63>")
	)
	(gr_poly
		(pts
			(xy 121.582434 -52.578762) (xy 121.574306 -52.386992) (xy 121.552208 -52.348384) (xy 121.206768 -52.548028)
			(xy 121.22912 -52.586382) (xy 121.391172 -52.689252)
		)
		(stroke
			(width 0)
			(type solid)
		)
		(fill yes)
		(layer "In4.Cu")
		(net "M_H_DQS_DN<16>")
	)
	(gr_poly
		(pts
			(xy 121.62663 -104.250744) (xy 121.58218 -104.250744) (xy 121.412 -104.339644) (xy 121.412 -104.560624)
			(xy 121.58218 -104.649524) (xy 121.62663 -104.649524)
		)
		(stroke
			(width 0)
			(type solid)
		)
		(fill yes)
		(layer "In4.Cu")
		(net "M_L_DQS_DP<16>")
	)
	(gr_poly
		(pts
			(xy 121.62663 -103.260144) (xy 121.58218 -103.260144) (xy 121.412 -103.349044) (xy 121.412 -103.570024)
			(xy 121.58218 -103.658924) (xy 121.62663 -103.658924)
		)
		(stroke
			(width 0)
			(type solid)
		)
		(fill yes)
		(layer "In4.Cu")
		(net "M_L_DQS_DP<16>")
	)
	(gr_poly
		(pts
			(xy 121.62663 -101.278944) (xy 121.58218 -101.278944) (xy 121.412 -101.367844) (xy 121.412 -101.588824)
			(xy 121.58218 -101.677724) (xy 121.62663 -101.677724)
		)
		(stroke
			(width 0)
			(type solid)
		)
		(fill yes)
		(layer "In4.Cu")
		(net "M_L_DQS_DN<7>")
	)
	(gr_poly
		(pts
			(xy 121.62663 -100.288344) (xy 121.58218 -100.288344) (xy 121.412 -100.377244) (xy 121.412 -100.598224)
			(xy 121.58218 -100.687124) (xy 121.62663 -100.687124)
		)
		(stroke
			(width 0)
			(type solid)
		)
		(fill yes)
		(layer "In4.Cu")
		(net "M_L_DQS_DN<7>")
	)
	(gr_poly
		(pts
			(xy 121.62663 -99.297744) (xy 121.58218 -99.297744) (xy 121.412 -99.386644) (xy 121.412 -99.607624)
			(xy 121.58218 -99.696524) (xy 121.62663 -99.696524)
		)
		(stroke
			(width 0)
			(type solid)
		)
		(fill yes)
		(layer "In4.Cu")
		(net "M_L_DQS_DN<7>")
	)
	(gr_poly
		(pts
			(xy 121.62663 -98.301302) (xy 121.58218 -98.301302) (xy 121.412 -98.390202) (xy 121.412 -98.611182)
			(xy 121.58218 -98.700082) (xy 121.62663 -98.700082)
		)
		(stroke
			(width 0)
			(type solid)
		)
		(fill yes)
		(layer "In4.Cu")
		(net "M_L_DQS_DN<7>")
	)
	(gr_poly
		(pts
			(xy 121.62663 -97.310702) (xy 121.58218 -97.310702) (xy 121.412 -97.399602) (xy 121.412 -97.620582)
			(xy 121.58218 -97.709482) (xy 121.62663 -97.709482)
		)
		(stroke
			(width 0)
			(type solid)
		)
		(fill yes)
		(layer "In4.Cu")
		(net "M_L_DQS_DN<7>")
	)
	(gr_poly
		(pts
			(xy 121.804938 -59.754008) (xy 121.782586 -59.715654) (xy 121.620534 -59.612784) (xy 121.429272 -59.723274)
			(xy 121.4374 -59.915044) (xy 121.459498 -59.953652)
		)
		(stroke
			(width 0)
			(type solid)
		)
		(fill yes)
		(layer "In4.Cu")
		(net "M_H_DQ<58>")
	)
	(gr_poly
		(pts
			(xy 121.853452 -102.509574) (xy 121.86158 -102.317804) (xy 121.670064 -102.207568) (xy 121.508266 -102.310438)
			(xy 121.485914 -102.348792) (xy 121.831354 -102.548182)
		)
		(stroke
			(width 0)
			(type solid)
		)
		(fill yes)
		(layer "In4.Cu")
		(net "M_L_DQS_DN<16>")
	)
	(gr_poly
		(pts
			(xy 121.858786 -105.48493) (xy 121.866914 -105.29316) (xy 121.675652 -105.18267) (xy 121.5136 -105.28554)
			(xy 121.491248 -105.323894) (xy 121.836688 -105.523538)
		)
		(stroke
			(width 0)
			(type solid)
		)
		(fill yes)
		(layer "In4.Cu")
		(net "M_L_DQ<57>")
	)
	(gr_poly
		(pts
			(xy 121.86031 -106.475784) (xy 121.868438 -106.284014) (xy 121.677176 -106.173524) (xy 121.515124 -106.276394)
			(xy 121.492772 -106.314748) (xy 121.838212 -106.514138)
		)
		(stroke
			(width 0)
			(type solid)
		)
		(fill yes)
		(layer "In4.Cu")
		(net "M_L_DQ<61>")
	)
	(gr_poly
		(pts
			(xy 121.862596 -50.79238) (xy 121.8311 -50.761138) (xy 121.63171 -50.687478) (xy 121.470166 -50.849022)
			(xy 121.543826 -51.048412) (xy 121.575068 -51.079908)
		)
		(stroke
			(width 0)
			(type solid)
		)
		(fill yes)
		(layer "In4.Cu")
		(net "M_H_DQ<56>")
	)
	(gr_poly
		(pts
			(xy 121.880376 -57.011824) (xy 121.880376 -56.790844) (xy 121.710196 -56.701944) (xy 121.665746 -56.701944)
			(xy 121.665746 -57.100724) (xy 121.710196 -57.100724)
		)
		(stroke
			(width 0)
			(type solid)
		)
		(fill yes)
		(layer "In4.Cu")
		(net "M_H_DQS_DN<7>")
	)
	(gr_poly
		(pts
			(xy 121.880376 -56.021224) (xy 121.880376 -55.800244) (xy 121.710196 -55.711344) (xy 121.665746 -55.711344)
			(xy 121.665746 -56.110124) (xy 121.710196 -56.110124)
		)
		(stroke
			(width 0)
			(type solid)
		)
		(fill yes)
		(layer "In4.Cu")
		(net "M_H_DQS_DN<7>")
	)
	(gr_poly
		(pts
			(xy 121.880376 -55.030624) (xy 121.880376 -54.809644) (xy 121.710196 -54.720744) (xy 121.665746 -54.720744)
			(xy 121.665746 -55.119524) (xy 121.710196 -55.119524)
		)
		(stroke
			(width 0)
			(type solid)
		)
		(fill yes)
		(layer "In4.Cu")
		(net "M_H_DQS_DN<7>")
	)
	(gr_poly
		(pts
			(xy 121.880376 -54.033674) (xy 121.880376 -53.812694) (xy 121.710196 -53.723794) (xy 121.665746 -53.723794)
			(xy 121.665746 -54.122574) (xy 121.710196 -54.122574)
		)
		(stroke
			(width 0)
			(type solid)
		)
		(fill yes)
		(layer "In4.Cu")
		(net "M_H_DQS_DN<7>")
	)
	(gr_poly
		(pts
			(xy 122.063256 -106.078782) (xy 122.085608 -106.040428) (xy 121.740168 -105.840784) (xy 121.71807 -105.879392)
			(xy 121.709942 -106.071162) (xy 121.901204 -106.181652)
		)
		(stroke
			(width 0)
			(type solid)
		)
		(fill yes)
		(layer "In4.Cu")
		(net "M_L_DQ<56>")
	)
	(gr_poly
		(pts
			(xy 122.06859 -105.091484) (xy 122.090942 -105.05313) (xy 121.745756 -104.853486) (xy 121.723404 -104.892348)
			(xy 121.715276 -105.084118) (xy 121.906792 -105.194354)
		)
		(stroke
			(width 0)
			(type solid)
		)
		(fill yes)
		(layer "In4.Cu")
		(net "M_L_DQS_DP<16>")
	)
	(gr_poly
		(pts
			(xy 122.06859 -102.119684) (xy 122.090942 -102.08133) (xy 121.745756 -101.881686) (xy 121.723404 -101.920548)
			(xy 121.715276 -102.112318) (xy 121.906792 -102.222554)
		)
		(stroke
			(width 0)
			(type solid)
		)
		(fill yes)
		(layer "In4.Cu")
		(net "M_L_DQS_DN<7>")
	)
	(gr_poly
		(pts
			(xy 122.082052 -93.87459) (xy 122.041412 -93.85681) (xy 121.849642 -93.869002) (xy 121.75998 -94.070932)
			(xy 121.879614 -94.2213) (xy 121.920254 -94.23908)
		)
		(stroke
			(width 0)
			(type solid)
		)
		(fill yes)
		(layer "In4.Cu")
		(net "M_L_DQ<62>")
	)
	(gr_poly
		(pts
			(xy 122.101864 -51.157632) (xy 122.028204 -50.958242) (xy 121.996962 -50.926746) (xy 121.709434 -51.214274)
			(xy 121.74093 -51.245516) (xy 121.94032 -51.319176)
		)
		(stroke
			(width 0)
			(type solid)
		)
		(fill yes)
		(layer "In4.Cu")
		(net "M_H_DQ<57>")
	)
	(gr_poly
		(pts
			(xy 122.154696 -95.153988) (xy 122.155458 -94.933008) (xy 121.985532 -94.8436) (xy 121.941082 -94.8436)
			(xy 121.939812 -95.24238) (xy 121.984262 -95.24238)
		)
		(stroke
			(width 0)
			(type solid)
		)
		(fill yes)
		(layer "In4.Cu")
		(net "M_L_DQ<62>")
	)
	(gr_poly
		(pts
			(xy 122.164856 -104.052878) (xy 122.164856 -103.831898) (xy 121.994676 -103.742998) (xy 121.950226 -103.742998)
			(xy 121.950226 -104.141778) (xy 121.994676 -104.141778)
		)
		(stroke
			(width 0)
			(type solid)
		)
		(fill yes)
		(layer "In4.Cu")
		(net "M_L_DQS_DN<16>")
	)
	(gr_poly
		(pts
			(xy 122.164856 -103.062278) (xy 122.164856 -102.841298) (xy 121.994676 -102.752398) (xy 121.950226 -102.752398)
			(xy 121.950226 -103.151178) (xy 121.994676 -103.151178)
		)
		(stroke
			(width 0)
			(type solid)
		)
		(fill yes)
		(layer "In4.Cu")
		(net "M_L_DQS_DN<16>")
	)
	(gr_poly
		(pts
			(xy 122.164856 -101.081078) (xy 122.164856 -100.860098) (xy 121.994676 -100.771198) (xy 121.950226 -100.771198)
			(xy 121.950226 -101.169978) (xy 121.994676 -101.169978)
		)
		(stroke
			(width 0)
			(type solid)
		)
		(fill yes)
		(layer "In4.Cu")
		(net "M_L_DQS_DP<7>")
	)
	(gr_poly
		(pts
			(xy 122.164856 -100.090478) (xy 122.164856 -99.869498) (xy 121.994676 -99.780598) (xy 121.950226 -99.780598)
			(xy 121.950226 -100.179378) (xy 121.994676 -100.179378)
		)
		(stroke
			(width 0)
			(type solid)
		)
		(fill yes)
		(layer "In4.Cu")
		(net "M_L_DQS_DP<7>")
	)
	(gr_poly
		(pts
			(xy 122.164856 -99.106482) (xy 122.164856 -98.885502) (xy 121.994676 -98.796602) (xy 121.950226 -98.796602)
			(xy 121.950226 -99.195382) (xy 121.994676 -99.195382)
		)
		(stroke
			(width 0)
			(type solid)
		)
		(fill yes)
		(layer "In4.Cu")
		(net "M_L_DQS_DP<7>")
	)
	(gr_poly
		(pts
			(xy 122.164856 -98.115882) (xy 122.164856 -97.894902) (xy 121.994676 -97.806002) (xy 121.950226 -97.806002)
			(xy 121.950226 -98.204782) (xy 121.994676 -98.204782)
		)
		(stroke
			(width 0)
			(type solid)
		)
		(fill yes)
		(layer "In4.Cu")
		(net "M_L_DQS_DP<7>")
	)
	(gr_poly
		(pts
			(xy 122.164856 -97.125282) (xy 122.164856 -96.904302) (xy 121.994676 -96.815402) (xy 121.950226 -96.815402)
			(xy 121.950226 -97.214182) (xy 121.994676 -97.214182)
		)
		(stroke
			(width 0)
			(type solid)
		)
		(fill yes)
		(layer "In4.Cu")
		(net "M_L_DQS_DP<7>")
	)
	(gr_poly
		(pts
			(xy 122.20067 -57.692544) (xy 122.15622 -57.692544) (xy 121.98604 -57.781444) (xy 121.98604 -58.002424)
			(xy 122.15622 -58.091324) (xy 122.20067 -58.091324)
		)
		(stroke
			(width 0)
			(type solid)
		)
		(fill yes)
		(layer "In4.Cu")
		(net "M_H_DQ<62>")
	)
	(gr_poly
		(pts
			(xy 122.20067 -56.701944) (xy 122.15622 -56.701944) (xy 121.98604 -56.790844) (xy 121.98604 -57.011824)
			(xy 122.15622 -57.100724) (xy 122.20067 -57.100724)
		)
		(stroke
			(width 0)
			(type solid)
		)
		(fill yes)
		(layer "In4.Cu")
		(net "M_H_DQ<62>")
	)
	(gr_poly
		(pts
			(xy 122.20067 -55.711344) (xy 122.15622 -55.711344) (xy 121.98604 -55.800244) (xy 121.98604 -56.021224)
			(xy 122.15622 -56.110124) (xy 122.20067 -56.110124)
		)
		(stroke
			(width 0)
			(type solid)
		)
		(fill yes)
		(layer "In4.Cu")
		(net "M_H_DQ<62>")
	)
	(gr_poly
		(pts
			(xy 122.20067 -54.720744) (xy 122.15622 -54.720744) (xy 121.98604 -54.809644) (xy 121.98604 -55.030624)
			(xy 122.15622 -55.119524) (xy 122.20067 -55.119524)
		)
		(stroke
			(width 0)
			(type solid)
		)
		(fill yes)
		(layer "In4.Cu")
		(net "M_H_DQ<62>")
	)
	(gr_poly
		(pts
			(xy 122.20067 -53.730144) (xy 122.15622 -53.730144) (xy 121.98604 -53.819044) (xy 121.98604 -54.040024)
			(xy 122.15622 -54.128924) (xy 122.20067 -54.128924)
		)
		(stroke
			(width 0)
			(type solid)
		)
		(fill yes)
		(layer "In4.Cu")
		(net "M_H_DQ<62>")
	)
	(gr_poly
		(pts
			(xy 122.427492 -53.08219) (xy 122.419364 -52.89042) (xy 122.397266 -52.851812) (xy 122.051826 -53.051456)
			(xy 122.074178 -53.08981) (xy 122.23623 -53.19268)
		)
		(stroke
			(width 0)
			(type solid)
		)
		(fill yes)
		(layer "In4.Cu")
		(net "M_H_DQS_DN<7>")
	)
	(gr_poly
		(pts
			(xy 122.437144 -60.010548) (xy 122.429016 -59.818778) (xy 122.406918 -59.78017) (xy 122.061478 -59.979814)
			(xy 122.08383 -60.018168) (xy 122.245882 -60.121038)
		)
		(stroke
			(width 0)
			(type solid)
		)
		(fill yes)
		(layer "In4.Cu")
		(net "M_H_DQ<59>")
	)
	(gr_poly
		(pts
			(xy 122.48515 -103.742998) (xy 122.4407 -103.742998) (xy 122.27052 -103.831898) (xy 122.27052 -104.052878)
			(xy 122.4407 -104.141778) (xy 122.48515 -104.141778)
		)
		(stroke
			(width 0)
			(type solid)
		)
		(fill yes)
		(layer "In4.Cu")
		(net "M_L_DQS_DN<7>")
	)
	(gr_poly
		(pts
			(xy 122.48515 -102.752398) (xy 122.4407 -102.752398) (xy 122.27052 -102.841298) (xy 122.27052 -103.062278)
			(xy 122.4407 -103.151178) (xy 122.48515 -103.151178)
		)
		(stroke
			(width 0)
			(type solid)
		)
		(fill yes)
		(layer "In4.Cu")
		(net "M_L_DQS_DN<7>")
	)
	(gr_poly
		(pts
			(xy 122.48515 -100.771198) (xy 122.4407 -100.771198) (xy 122.27052 -100.860098) (xy 122.27052 -101.081078)
			(xy 122.4407 -101.169978) (xy 122.48515 -101.169978)
		)
		(stroke
			(width 0)
			(type solid)
		)
		(fill yes)
		(layer "In4.Cu")
		(net "M_L_DQ<62>")
	)
	(gr_poly
		(pts
			(xy 122.48515 -99.780598) (xy 122.4407 -99.780598) (xy 122.27052 -99.869498) (xy 122.27052 -100.090478)
			(xy 122.4407 -100.179378) (xy 122.48515 -100.179378)
		)
		(stroke
			(width 0)
			(type solid)
		)
		(fill yes)
		(layer "In4.Cu")
		(net "M_L_DQ<62>")
	)
	(gr_poly
		(pts
			(xy 122.48515 -97.805494) (xy 122.4407 -97.805494) (xy 122.27052 -97.894394) (xy 122.27052 -98.115374)
			(xy 122.4407 -98.204274) (xy 122.48515 -98.204274)
		)
		(stroke
			(width 0)
			(type solid)
		)
		(fill yes)
		(layer "In4.Cu")
		(net "M_L_DQ<62>")
	)
	(gr_poly
		(pts
			(xy 122.48515 -96.814894) (xy 122.4407 -96.814894) (xy 122.27052 -96.903794) (xy 122.27052 -97.124774)
			(xy 122.4407 -97.213674) (xy 122.48515 -97.213674)
		)
		(stroke
			(width 0)
			(type solid)
		)
		(fill yes)
		(layer "In4.Cu")
		(net "M_L_DQ<62>")
	)
	(gr_poly
		(pts
			(xy 122.485404 -98.796094) (xy 122.440954 -98.796094) (xy 122.270774 -98.884994) (xy 122.270774 -99.105974)
			(xy 122.440954 -99.194874) (xy 122.485404 -99.194874)
		)
		(stroke
			(width 0)
			(type solid)
		)
		(fill yes)
		(layer "In4.Cu")
		(net "M_L_DQ<62>")
	)
	(gr_poly
		(pts
			(xy 122.659648 -59.26074) (xy 122.637296 -59.222386) (xy 122.475244 -59.119516) (xy 122.283982 -59.230006)
			(xy 122.29211 -59.421776) (xy 122.314208 -59.460384)
		)
		(stroke
			(width 0)
			(type solid)
		)
		(fill yes)
		(layer "In4.Cu")
		(net "M_H_DQ<58>")
	)
	(gr_poly
		(pts
			(xy 122.708416 -95.986854) (xy 122.77471 -95.806514) (xy 122.626374 -95.642938) (xy 122.440446 -95.691452)
			(xy 122.40768 -95.72117) (xy 122.675396 -96.016572)
		)
		(stroke
			(width 0)
			(type solid)
		)
		(fill yes)
		(layer "In4.Cu")
		(net "M_L_DQ<63>")
	)
	(gr_poly
		(pts
			(xy 122.715528 -102.016306) (xy 122.723656 -101.824536) (xy 122.532394 -101.7143) (xy 122.370342 -101.81717)
			(xy 122.348244 -101.855524) (xy 122.693684 -102.054914)
		)
		(stroke
			(width 0)
			(type solid)
		)
		(fill yes)
		(layer "In4.Cu")
		(net "M_L_DQS_DP<7>")
	)
	(gr_poly
		(pts
			(xy 122.715782 -104.988614) (xy 122.72391 -104.796844) (xy 122.532648 -104.686354) (xy 122.370596 -104.789224)
			(xy 122.348244 -104.827578) (xy 122.693684 -105.027222)
		)
		(stroke
			(width 0)
			(type solid)
		)
		(fill yes)
		(layer "In4.Cu")
		(net "M_L_DQS_DN<16>")
	)
	(gr_poly
		(pts
			(xy 122.71629 -105.979214) (xy 122.724418 -105.787444) (xy 122.533156 -105.676954) (xy 122.371104 -105.779824)
			(xy 122.348752 -105.818178) (xy 122.694192 -106.017822)
		)
		(stroke
			(width 0)
			(type solid)
		)
		(fill yes)
		(layer "In4.Cu")
		(net "M_L_DQ<57>")
	)
	(gr_poly
		(pts
			(xy 122.738896 -57.494678) (xy 122.738896 -57.273698) (xy 122.568716 -57.184798) (xy 122.524266 -57.184798)
			(xy 122.524266 -57.583578) (xy 122.568716 -57.583578)
		)
		(stroke
			(width 0)
			(type solid)
		)
		(fill yes)
		(layer "In4.Cu")
		(net "M_H_DQ<63>")
	)
	(gr_poly
		(pts
			(xy 122.738896 -56.504078) (xy 122.738896 -56.283098) (xy 122.568716 -56.194198) (xy 122.524266 -56.194198)
			(xy 122.524266 -56.592978) (xy 122.568716 -56.592978)
		)
		(stroke
			(width 0)
			(type solid)
		)
		(fill yes)
		(layer "In4.Cu")
		(net "M_H_DQ<63>")
	)
	(gr_poly
		(pts
			(xy 122.738896 -55.513478) (xy 122.738896 -55.292498) (xy 122.568716 -55.203598) (xy 122.524266 -55.203598)
			(xy 122.524266 -55.602378) (xy 122.568716 -55.602378)
		)
		(stroke
			(width 0)
			(type solid)
		)
		(fill yes)
		(layer "In4.Cu")
		(net "M_H_DQ<63>")
	)
	(gr_poly
		(pts
			(xy 122.738896 -54.522878) (xy 122.738896 -54.301898) (xy 122.568716 -54.212998) (xy 122.524266 -54.212998)
			(xy 122.524266 -54.611778) (xy 122.568716 -54.611778)
		)
		(stroke
			(width 0)
			(type solid)
		)
		(fill yes)
		(layer "In4.Cu")
		(net "M_H_DQ<63>")
	)
	(gr_poly
		(pts
			(xy 122.832622 -94.653354) (xy 122.832622 -94.432374) (xy 122.662442 -94.343474) (xy 122.617992 -94.343474)
			(xy 122.617992 -94.742254) (xy 122.662442 -94.742254)
		)
		(stroke
			(width 0)
			(type solid)
		)
		(fill yes)
		(layer "In4.Cu")
		(net "M_L_DQ<58>")
	)
	(gr_poly
		(pts
			(xy 122.832622 -93.662754) (xy 122.832622 -93.441774) (xy 122.662442 -93.352874) (xy 122.617992 -93.352874)
			(xy 122.617992 -93.751654) (xy 122.662442 -93.751654)
		)
		(stroke
			(width 0)
			(type solid)
		)
		(fill yes)
		(layer "In4.Cu")
		(net "M_L_DQ<58>")
	)
	(gr_poly
		(pts
			(xy 122.911362 -51.091846) (xy 122.879866 -51.060604) (xy 122.680476 -50.986944) (xy 122.518932 -51.148488)
			(xy 122.592592 -51.347878) (xy 122.623834 -51.379374)
		)
		(stroke
			(width 0)
			(type solid)
		)
		(fill yes)
		(layer "In4.Cu")
		(net "M_H_DQS_DP<16>")
	)
	(gr_poly
		(pts
			(xy 122.9233 -105.584498) (xy 122.945652 -105.546144) (xy 122.600212 -105.3465) (xy 122.578114 -105.385108)
			(xy 122.569986 -105.576878) (xy 122.761248 -105.687368)
		)
		(stroke
			(width 0)
			(type solid)
		)
		(fill yes)
		(layer "In4.Cu")
		(net "M_L_DQS_DP<16>")
	)
	(gr_poly
		(pts
			(xy 122.923554 -104.594152) (xy 122.945906 -104.555798) (xy 122.600466 -104.356154) (xy 122.578368 -104.395016)
			(xy 122.57024 -104.586786) (xy 122.761502 -104.697022)
		)
		(stroke
			(width 0)
			(type solid)
		)
		(fill yes)
		(layer "In4.Cu")
		(net "M_L_DQS_DN<7>")
	)
	(gr_poly
		(pts
			(xy 122.923554 -101.622352) (xy 122.945906 -101.583998) (xy 122.600466 -101.384354) (xy 122.578368 -101.423216)
			(xy 122.57024 -101.614986) (xy 122.761502 -101.725222)
		)
		(stroke
			(width 0)
			(type solid)
		)
		(fill yes)
		(layer "In4.Cu")
		(net "M_L_DQ<62>")
	)
	(gr_poly
		(pts
			(xy 123.023122 -96.629474) (xy 123.023122 -96.408494) (xy 122.852942 -96.319594) (xy 122.808492 -96.319594)
			(xy 122.808492 -96.718374) (xy 122.852942 -96.718374)
		)
		(stroke
			(width 0)
			(type solid)
		)
		(fill yes)
		(layer "In4.Cu")
		(net "M_L_DQ<63>")
	)
	(gr_poly
		(pts
			(xy 123.023376 -103.570024) (xy 123.023376 -103.349044) (xy 122.853196 -103.260144) (xy 122.808746 -103.260144)
			(xy 122.808746 -103.658924) (xy 122.853196 -103.658924)
		)
		(stroke
			(width 0)
			(type solid)
		)
		(fill yes)
		(layer "In4.Cu")
		(net "M_L_DQS_DP<7>")
	)
	(gr_poly
		(pts
			(xy 123.023376 -102.579424) (xy 123.023376 -102.358444) (xy 122.853196 -102.269544) (xy 122.808746 -102.269544)
			(xy 122.808746 -102.668324) (xy 122.853196 -102.668324)
		)
		(stroke
			(width 0)
			(type solid)
		)
		(fill yes)
		(layer "In4.Cu")
		(net "M_L_DQS_DP<7>")
	)
	(gr_poly
		(pts
			(xy 123.023376 -100.598224) (xy 123.023376 -100.377244) (xy 122.853196 -100.288344) (xy 122.808746 -100.288344)
			(xy 122.808746 -100.687124) (xy 122.853196 -100.687124)
		)
		(stroke
			(width 0)
			(type solid)
		)
		(fill yes)
		(layer "In4.Cu")
		(net "M_L_DQ<63>")
	)
	(gr_poly
		(pts
			(xy 123.023376 -99.607624) (xy 123.023376 -99.386644) (xy 122.853196 -99.297744) (xy 122.808746 -99.297744)
			(xy 122.808746 -99.696524) (xy 122.853196 -99.696524)
		)
		(stroke
			(width 0)
			(type solid)
		)
		(fill yes)
		(layer "In4.Cu")
		(net "M_L_DQ<63>")
	)
	(gr_poly
		(pts
			(xy 123.023376 -98.610674) (xy 123.023376 -98.389694) (xy 122.853196 -98.300794) (xy 122.808746 -98.300794)
			(xy 122.808746 -98.699574) (xy 122.853196 -98.699574)
		)
		(stroke
			(width 0)
			(type solid)
		)
		(fill yes)
		(layer "In4.Cu")
		(net "M_L_DQ<63>")
	)
	(gr_poly
		(pts
			(xy 123.023376 -97.620074) (xy 123.023376 -97.399094) (xy 122.853196 -97.310194) (xy 122.808746 -97.310194)
			(xy 122.808746 -97.708974) (xy 122.853196 -97.708974)
		)
		(stroke
			(width 0)
			(type solid)
		)
		(fill yes)
		(layer "In4.Cu")
		(net "M_L_DQ<63>")
	)
	(gr_poly
		(pts
			(xy 123.05919 -58.181748) (xy 123.01474 -58.181748) (xy 122.84456 -58.270648) (xy 122.84456 -58.491628)
			(xy 123.01474 -58.580528) (xy 123.05919 -58.580528)
		)
		(stroke
			(width 0)
			(type solid)
		)
		(fill yes)
		(layer "In4.Cu")
		(net "M_H_DQ<58>")
	)
	(gr_poly
		(pts
			(xy 123.05919 -57.184798) (xy 123.01474 -57.184798) (xy 122.84456 -57.273698) (xy 122.84456 -57.494678)
			(xy 123.01474 -57.583578) (xy 123.05919 -57.583578)
		)
		(stroke
			(width 0)
			(type solid)
		)
		(fill yes)
		(layer "In4.Cu")
		(net "M_H_DQ<58>")
	)
	(gr_poly
		(pts
			(xy 123.05919 -56.194198) (xy 123.01474 -56.194198) (xy 122.84456 -56.283098) (xy 122.84456 -56.504078)
			(xy 123.01474 -56.592978) (xy 123.05919 -56.592978)
		)
		(stroke
			(width 0)
			(type solid)
		)
		(fill yes)
		(layer "In4.Cu")
		(net "M_H_DQ<58>")
	)
	(gr_poly
		(pts
			(xy 123.05919 -55.203598) (xy 123.01474 -55.203598) (xy 122.84456 -55.292498) (xy 122.84456 -55.513478)
			(xy 123.01474 -55.602378) (xy 123.05919 -55.602378)
		)
		(stroke
			(width 0)
			(type solid)
		)
		(fill yes)
		(layer "In4.Cu")
		(net "M_H_DQ<58>")
	)
	(gr_poly
		(pts
			(xy 123.05919 -54.212998) (xy 123.01474 -54.212998) (xy 122.84456 -54.301898) (xy 122.84456 -54.522878)
			(xy 123.01474 -54.611778) (xy 123.05919 -54.611778)
		)
		(stroke
			(width 0)
			(type solid)
		)
		(fill yes)
		(layer "In4.Cu")
		(net "M_H_DQ<58>")
	)
	(gr_poly
		(pts
			(xy 123.151138 -51.457352) (xy 123.077478 -51.258216) (xy 123.045982 -51.22672) (xy 122.758708 -51.513994)
			(xy 122.790204 -51.54549) (xy 122.98934 -51.61915)
		)
		(stroke
			(width 0)
			(type solid)
		)
		(fill yes)
		(layer "In4.Cu")
		(net "M_H_DQS_DN<16>")
	)
	(gr_poly
		(pts
			(xy 123.297696 -59.514486) (xy 123.289568 -59.322716) (xy 123.26747 -59.283854) (xy 122.922284 -59.483498)
			(xy 122.944382 -59.521852) (xy 123.106434 -59.624722)
		)
		(stroke
			(width 0)
			(type solid)
		)
		(fill yes)
		(layer "In4.Cu")
		(net "M_H_DQ<59>")
	)
	(gr_poly
		(pts
			(xy 123.299474 -53.569362) (xy 123.291346 -53.377592) (xy 123.269248 -53.338984) (xy 122.923808 -53.538628)
			(xy 122.94616 -53.576982) (xy 123.108212 -53.679852)
		)
		(stroke
			(width 0)
			(type solid)
		)
		(fill yes)
		(layer "In4.Cu")
		(net "M_H_DQ<63>")
	)
	(gr_poly
		(pts
			(xy 123.34367 -103.260144) (xy 123.29922 -103.260144) (xy 123.12904 -103.349044) (xy 123.12904 -103.570024)
			(xy 123.29922 -103.658924) (xy 123.34367 -103.658924)
		)
		(stroke
			(width 0)
			(type solid)
		)
		(fill yes)
		(layer "In4.Cu")
		(net "M_L_DQ<62>")
	)
	(gr_poly
		(pts
			(xy 123.34367 -102.269544) (xy 123.29922 -102.269544) (xy 123.12904 -102.358444) (xy 123.12904 -102.579424)
			(xy 123.29922 -102.668324) (xy 123.34367 -102.668324)
		)
		(stroke
			(width 0)
			(type solid)
		)
		(fill yes)
		(layer "In4.Cu")
		(net "M_L_DQ<62>")
	)
	(gr_poly
		(pts
			(xy 123.34367 -100.288344) (xy 123.29922 -100.288344) (xy 123.12904 -100.377244) (xy 123.12904 -100.598224)
			(xy 123.29922 -100.687124) (xy 123.34367 -100.687124)
		)
		(stroke
			(width 0)
			(type solid)
		)
		(fill yes)
		(layer "In4.Cu")
		(net "M_L_DQ<58>")
	)
	(gr_poly
		(pts
			(xy 123.34367 -99.297744) (xy 123.29922 -99.297744) (xy 123.12904 -99.386644) (xy 123.12904 -99.607624)
			(xy 123.29922 -99.696524) (xy 123.34367 -99.696524)
		)
		(stroke
			(width 0)
			(type solid)
		)
		(fill yes)
		(layer "In4.Cu")
		(net "M_L_DQ<58>")
	)
	(gr_poly
		(pts
			(xy 123.34367 -98.307144) (xy 123.29922 -98.307144) (xy 123.12904 -98.396044) (xy 123.12904 -98.617024)
			(xy 123.29922 -98.705924) (xy 123.34367 -98.705924)
		)
		(stroke
			(width 0)
			(type solid)
		)
		(fill yes)
		(layer "In4.Cu")
		(net "M_L_DQ<58>")
	)
	(gr_poly
		(pts
			(xy 123.34367 -97.316544) (xy 123.29922 -97.316544) (xy 123.12904 -97.405444) (xy 123.12904 -97.626424)
			(xy 123.29922 -97.715324) (xy 123.34367 -97.715324)
		)
		(stroke
			(width 0)
			(type solid)
		)
		(fill yes)
		(layer "In4.Cu")
		(net "M_L_DQ<58>")
	)
	(gr_poly
		(pts
			(xy 123.34367 -96.325944) (xy 123.29922 -96.325944) (xy 123.12904 -96.414844) (xy 123.12904 -96.635824)
			(xy 123.29922 -96.724724) (xy 123.34367 -96.724724)
		)
		(stroke
			(width 0)
			(type solid)
		)
		(fill yes)
		(layer "In4.Cu")
		(net "M_L_DQ<58>")
	)
	(gr_poly
		(pts
			(xy 123.518168 -52.82184) (xy 123.495816 -52.783486) (xy 123.333764 -52.680616) (xy 123.142502 -52.791106)
			(xy 123.15063 -52.982876) (xy 123.172728 -53.021484)
		)
		(stroke
			(width 0)
			(type solid)
		)
		(fill yes)
		(layer "In4.Cu")
		(net "M_H_DQ<62>")
	)
	(gr_poly
		(pts
			(xy 123.530868 -95.539052) (xy 123.616212 -95.36684) (xy 123.486164 -95.188278) (xy 123.296172 -95.216726)
			(xy 123.260358 -95.242888) (xy 123.495054 -95.565214)
		)
		(stroke
			(width 0)
			(type solid)
		)
		(fill yes)
		(layer "In4.Cu")
		(net "M_L_DQ<59>")
	)
	(gr_poly
		(pts
			(xy 123.570492 -101.518974) (xy 123.57862 -101.327204) (xy 123.387104 -101.216968) (xy 123.225306 -101.319838)
			(xy 123.2027 -101.358192) (xy 123.54814 -101.557836)
		)
		(stroke
			(width 0)
			(type solid)
		)
		(fill yes)
		(layer "In4.Cu")
		(net "M_L_DQ<63>")
	)
	(gr_poly
		(pts
			(xy 123.575826 -105.48493) (xy 123.583954 -105.29316) (xy 123.392692 -105.18267) (xy 123.23064 -105.28554)
			(xy 123.208288 -105.323894) (xy 123.553728 -105.523538)
		)
		(stroke
			(width 0)
			(type solid)
		)
		(fill yes)
		(layer "In4.Cu")
		(net "M_L_DQS_DN<16>")
	)
	(gr_poly
		(pts
			(xy 123.575826 -104.49433) (xy 123.583954 -104.30256) (xy 123.392692 -104.19207) (xy 123.23064 -104.29494)
			(xy 123.208288 -104.333294) (xy 123.553728 -104.532938)
		)
		(stroke
			(width 0)
			(type solid)
		)
		(fill yes)
		(layer "In4.Cu")
		(net "M_L_DQS_DP<7>")
	)
	(gr_poly
		(pts
			(xy 123.597416 -58.002424) (xy 123.597416 -57.781444) (xy 123.427236 -57.692544) (xy 123.382786 -57.692544)
			(xy 123.382786 -58.091324) (xy 123.427236 -58.091324)
		)
		(stroke
			(width 0)
			(type solid)
		)
		(fill yes)
		(layer "In4.Cu")
		(net "M_H_DQ<59>")
	)
	(gr_poly
		(pts
			(xy 123.597416 -57.011824) (xy 123.597416 -56.790844) (xy 123.427236 -56.701944) (xy 123.382786 -56.701944)
			(xy 123.382786 -57.100724) (xy 123.427236 -57.100724)
		)
		(stroke
			(width 0)
			(type solid)
		)
		(fill yes)
		(layer "In4.Cu")
		(net "M_H_DQ<59>")
	)
	(gr_poly
		(pts
			(xy 123.597416 -56.021224) (xy 123.597416 -55.800244) (xy 123.427236 -55.711344) (xy 123.382786 -55.711344)
			(xy 123.382786 -56.110124) (xy 123.427236 -56.110124)
		)
		(stroke
			(width 0)
			(type solid)
		)
		(fill yes)
		(layer "In4.Cu")
		(net "M_H_DQ<59>")
	)
	(gr_poly
		(pts
			(xy 123.597416 -55.030624) (xy 123.597416 -54.809644) (xy 123.427236 -54.720744) (xy 123.382786 -54.720744)
			(xy 123.382786 -55.119524) (xy 123.427236 -55.119524)
		)
		(stroke
			(width 0)
			(type solid)
		)
		(fill yes)
		(layer "In4.Cu")
		(net "M_H_DQ<59>")
	)
	(gr_poly
		(pts
			(xy 123.780296 -105.088182) (xy 123.802648 -105.049828) (xy 123.457208 -104.850184) (xy 123.43511 -104.889046)
			(xy 123.426982 -105.080816) (xy 123.618244 -105.191052)
		)
		(stroke
			(width 0)
			(type solid)
		)
		(fill yes)
		(layer "In4.Cu")
		(net "M_L_DQS_DN<7>")
	)
	(gr_poly
		(pts
			(xy 123.780296 -101.126036) (xy 123.802394 -101.087682) (xy 123.456954 -100.888292) (xy 123.43511 -100.926646)
			(xy 123.426982 -101.118416) (xy 123.618244 -101.228906)
		)
		(stroke
			(width 0)
			(type solid)
		)
		(fill yes)
		(layer "In4.Cu")
		(net "M_L_DQ<58>")
	)
	(gr_poly
		(pts
			(xy 123.881896 -103.062278) (xy 123.881896 -102.841298) (xy 123.711716 -102.752398) (xy 123.667266 -102.752398)
			(xy 123.667266 -103.151178) (xy 123.711716 -103.151178)
		)
		(stroke
			(width 0)
			(type solid)
		)
		(fill yes)
		(layer "In4.Cu")
		(net "M_L_DQ<63>")
	)
	(gr_poly
		(pts
			(xy 123.881896 -102.071678) (xy 123.881896 -101.850698) (xy 123.711716 -101.761798) (xy 123.667266 -101.761798)
			(xy 123.667266 -102.160578) (xy 123.711716 -102.160578)
		)
		(stroke
			(width 0)
			(type solid)
		)
		(fill yes)
		(layer "In4.Cu")
		(net "M_L_DQ<63>")
	)
	(gr_poly
		(pts
			(xy 123.881896 -100.096828) (xy 123.881896 -99.875848) (xy 123.711716 -99.786948) (xy 123.667266 -99.786948)
			(xy 123.667266 -100.185728) (xy 123.711716 -100.185728)
		)
		(stroke
			(width 0)
			(type solid)
		)
		(fill yes)
		(layer "In4.Cu")
		(net "M_L_DQ<59>")
	)
	(gr_poly
		(pts
			(xy 123.881896 -99.099878) (xy 123.881896 -98.878898) (xy 123.711716 -98.789998) (xy 123.667266 -98.789998)
			(xy 123.667266 -99.188778) (xy 123.711716 -99.188778)
		)
		(stroke
			(width 0)
			(type solid)
		)
		(fill yes)
		(layer "In4.Cu")
		(net "M_L_DQ<59>")
	)
	(gr_poly
		(pts
			(xy 123.881896 -98.109278) (xy 123.881896 -97.888298) (xy 123.711716 -97.799398) (xy 123.667266 -97.799398)
			(xy 123.667266 -98.198178) (xy 123.711716 -98.198178)
		)
		(stroke
			(width 0)
			(type solid)
		)
		(fill yes)
		(layer "In4.Cu")
		(net "M_L_DQ<59>")
	)
	(gr_poly
		(pts
			(xy 123.881896 -97.118678) (xy 123.881896 -96.897698) (xy 123.711716 -96.808798) (xy 123.667266 -96.808798)
			(xy 123.667266 -97.207578) (xy 123.711716 -97.207578)
		)
		(stroke
			(width 0)
			(type solid)
		)
		(fill yes)
		(layer "In4.Cu")
		(net "M_L_DQ<59>")
	)
	(gr_poly
		(pts
			(xy 123.881896 -96.128078) (xy 123.881896 -95.907098) (xy 123.711716 -95.818198) (xy 123.667266 -95.818198)
			(xy 123.667266 -96.216978) (xy 123.711716 -96.216978)
		)
		(stroke
			(width 0)
			(type solid)
		)
		(fill yes)
		(layer "In4.Cu")
		(net "M_L_DQ<59>")
	)
	(gr_poly
		(pts
			(xy 124.20219 -102.752398) (xy 124.15774 -102.752398) (xy 123.98756 -102.841298) (xy 123.98756 -103.062278)
			(xy 124.15774 -103.151178) (xy 124.20219 -103.151178)
		)
		(stroke
			(width 0)
			(type solid)
		)
		(fill yes)
		(layer "In4.Cu")
		(net "M_L_DQ<58>")
	)
	(gr_poly
		(pts
			(xy 124.20219 -101.761798) (xy 124.15774 -101.761798) (xy 123.98756 -101.850698) (xy 123.98756 -102.071678)
			(xy 124.15774 -102.160578) (xy 124.20219 -102.160578)
		)
		(stroke
			(width 0)
			(type solid)
		)
		(fill yes)
		(layer "In4.Cu")
		(net "M_L_DQ<58>")
	)
	(gr_poly
		(pts
			(xy 124.432822 -104.988614) (xy 124.44095 -104.796844) (xy 124.249688 -104.686354) (xy 124.087636 -104.789224)
			(xy 124.065284 -104.827578) (xy 124.410724 -105.027222)
		)
		(stroke
			(width 0)
			(type solid)
		)
		(fill yes)
		(layer "In4.Cu")
		(net "M_L_DQS_DP<7>")
	)
	(gr_poly
		(pts
			(xy 124.432822 -103.998014) (xy 124.44095 -103.806244) (xy 124.249688 -103.695754) (xy 124.087636 -103.798624)
			(xy 124.065284 -103.836978) (xy 124.410724 -104.036622)
		)
		(stroke
			(width 0)
			(type solid)
		)
		(fill yes)
		(layer "In4.Cu")
		(net "M_L_DQ<63>")
	)
	(gr_poly
		(pts
			(xy 124.434346 -101.026976) (xy 124.442474 -100.835206) (xy 124.251212 -100.724716) (xy 124.08916 -100.827586)
			(xy 124.066808 -100.86594) (xy 124.412248 -101.065584)
		)
		(stroke
			(width 0)
			(type solid)
		)
		(fill yes)
		(layer "In4.Cu")
		(net "M_L_DQ<59>")
	)
	(gr_poly
		(pts
			(xy 124.64034 -105.584498) (xy 124.662692 -105.546144) (xy 124.317252 -105.3465) (xy 124.295154 -105.385108)
			(xy 124.287026 -105.576878) (xy 124.478288 -105.687368)
		)
		(stroke
			(width 0)
			(type solid)
		)
		(fill yes)
		(layer "In4.Cu")
		(net "M_L_DQS_DN<7>")
	)
	(gr_poly
		(pts
			(xy 124.64034 -104.593898) (xy 124.662692 -104.555544) (xy 124.317252 -104.3559) (xy 124.295154 -104.394508)
			(xy 124.287026 -104.586278) (xy 124.478288 -104.696768)
		)
		(stroke
			(width 0)
			(type solid)
		)
		(fill yes)
		(layer "In4.Cu")
		(net "M_L_DQ<62>")
	)
	(gr_poly
		(pts
			(xy 124.640594 -103.603552) (xy 124.662692 -103.565198) (xy 124.317252 -103.365808) (xy 124.295408 -103.404416)
			(xy 124.28728 -103.596186) (xy 124.478542 -103.706422)
		)
		(stroke
			(width 0)
			(type solid)
		)
		(fill yes)
		(layer "In4.Cu")
		(net "M_L_DQ<58>")
	)
	(gr_poly
		(pts
			(xy 124.740162 -101.593396) (xy 124.740162 -101.372416) (xy 124.569982 -101.283516) (xy 124.525532 -101.283262)
			(xy 124.525532 -101.682296) (xy 124.569982 -101.682296)
		)
		(stroke
			(width 0)
			(type solid)
		)
		(fill yes)
		(layer "In4.Cu")
		(net "M_L_DQ<59>")
	)
	(gr_poly
		(pts
			(xy 124.740416 -102.579424) (xy 124.740416 -102.358444) (xy 124.570236 -102.269544) (xy 124.525786 -102.269544)
			(xy 124.525786 -102.668324) (xy 124.570236 -102.668324)
		)
		(stroke
			(width 0)
			(type solid)
		)
		(fill yes)
		(layer "In4.Cu")
		(net "M_L_DQ<59>")
	)
	(gr_poly
		(pts
			(xy 124.867162 -52.410106) (xy 124.835666 -52.378864) (xy 124.636276 -52.305204) (xy 124.474732 -52.466748)
			(xy 124.548392 -52.666138) (xy 124.579634 -52.697634)
		)
		(stroke
			(width 0)
			(type solid)
		)
		(fill yes)
		(layer "In4.Cu")
		(net "M_H_DQ<62>")
	)
	(gr_poly
		(pts
			(xy 125.106938 -52.775612) (xy 125.033278 -52.576476) (xy 125.001782 -52.54498) (xy 124.714508 -52.832254)
			(xy 124.746004 -52.86375) (xy 124.94514 -52.93741)
		)
		(stroke
			(width 0)
			(type solid)
		)
		(fill yes)
		(layer "In4.Cu")
		(net "M_H_DQ<63>")
	)
	(gr_poly
		(pts
			(xy 125.292866 -105.48493) (xy 125.300994 -105.29316) (xy 125.109732 -105.18267) (xy 124.94768 -105.28554)
			(xy 124.925328 -105.323894) (xy 125.270768 -105.523538)
		)
		(stroke
			(width 0)
			(type solid)
		)
		(fill yes)
		(layer "In4.Cu")
		(net "M_L_DQS_DP<7>")
	)
	(gr_poly
		(pts
			(xy 125.292866 -104.49433) (xy 125.300994 -104.30256) (xy 125.109732 -104.19207) (xy 124.94768 -104.29494)
			(xy 124.925328 -104.333294) (xy 125.270768 -104.532938)
		)
		(stroke
			(width 0)
			(type solid)
		)
		(fill yes)
		(layer "In4.Cu")
		(net "M_L_DQ<63>")
	)
	(gr_poly
		(pts
			(xy 125.292866 -103.50373) (xy 125.300994 -103.31196) (xy 125.109732 -103.20147) (xy 124.94768 -103.30434)
			(xy 124.925328 -103.342694) (xy 125.270768 -103.542338)
		)
		(stroke
			(width 0)
			(type solid)
		)
		(fill yes)
		(layer "In4.Cu")
		(net "M_L_DQ<59>")
	)
	(gr_poly
		(pts
			(xy 125.497336 -105.088182) (xy 125.519688 -105.049828) (xy 125.174248 -104.850184) (xy 125.15215 -104.888792)
			(xy 125.144022 -105.080562) (xy 125.335284 -105.191052)
		)
		(stroke
			(width 0)
			(type solid)
		)
		(fill yes)
		(layer "In4.Cu")
		(net "M_L_DQ<62>")
	)
	(gr_poly
		(pts
			(xy 125.497336 -104.097582) (xy 125.519688 -104.059228) (xy 125.174248 -103.859584) (xy 125.15215 -103.898192)
			(xy 125.144022 -104.089962) (xy 125.335284 -104.200452)
		)
		(stroke
			(width 0)
			(type solid)
		)
		(fill yes)
		(layer "In4.Cu")
		(net "M_L_DQ<58>")
	)
	(gr_poly
		(pts
			(xy 126.151386 -104.989376) (xy 126.159514 -104.797606) (xy 125.968252 -104.687116) (xy 125.8062 -104.789986)
			(xy 125.783848 -104.82834) (xy 126.129288 -105.02773)
		)
		(stroke
			(width 0)
			(type solid)
		)
		(fill yes)
		(layer "In4.Cu")
		(net "M_L_DQ<63>")
	)
	(gr_poly
		(pts
			(xy 126.151386 -103.998776) (xy 126.159514 -103.807006) (xy 125.968252 -103.696516) (xy 125.8062 -103.799386)
			(xy 125.783848 -103.83774) (xy 126.129288 -104.03713)
		)
		(stroke
			(width 0)
			(type solid)
		)
		(fill yes)
		(layer "In4.Cu")
		(net "M_L_DQ<59>")
	)
	(gr_poly
		(pts
			(xy 126.355856 -104.592882) (xy 126.378208 -104.554528) (xy 126.032768 -104.354884) (xy 126.01067 -104.393492)
			(xy 126.002542 -104.585262) (xy 126.193804 -104.695752)
		)
		(stroke
			(width 0)
			(type solid)
		)
		(fill yes)
		(layer "In4.Cu")
		(net "M_L_DQ<58>")
	)
	(gr_poly
		(pts
			(xy 230.124508 -88.092534) (xy 230.035608 -87.922354) (xy 229.814628 -87.922354) (xy 229.725728 -88.092534)
			(xy 229.725728 -88.136984) (xy 230.124508 -88.136984)
		)
		(stroke
			(width 0)
			(type solid)
		)
		(fill yes)
		(layer "In4.Cu")
		(net "M_E_DQ<2>")
	)
	(gr_poly
		(pts
			(xy 230.243634 -88.383364) (xy 230.243634 -88.338914) (xy 229.844854 -88.339168) (xy 229.845108 -88.383618)
			(xy 229.934008 -88.553544) (xy 230.154734 -88.553544)
		)
		(stroke
			(width 0)
			(type solid)
		)
		(fill yes)
		(layer "In4.Cu")
		(net "M_E_DQ<3>")
	)
	(gr_poly
		(pts
			(xy 230.365808 -64.13373) (xy 230.397304 -64.102488) (xy 230.109776 -63.81496) (xy 230.078534 -63.846456)
			(xy 230.004874 -64.045846) (xy 230.166418 -64.20739)
		)
		(stroke
			(width 0)
			(type solid)
		)
		(fill yes)
		(layer "In4.Cu")
		(net "M_B_DQ<6>")
	)
	(gr_poly
		(pts
			(xy 230.620824 -62.612524) (xy 230.576374 -62.612524) (xy 230.383334 -62.701424) (xy 230.383334 -62.930024)
			(xy 230.576374 -63.018924) (xy 230.620824 -63.018924)
		)
		(stroke
			(width 0)
			(type solid)
		)
		(fill yes)
		(layer "In4.Cu")
		(net "M_B_DQ<2>")
	)
	(gr_poly
		(pts
			(xy 230.709724 -87.036656) (xy 230.709724 -86.992206) (xy 230.303324 -86.992206) (xy 230.303324 -87.036656)
			(xy 230.392224 -87.229696) (xy 230.620824 -87.229696)
		)
		(stroke
			(width 0)
			(type solid)
		)
		(fill yes)
		(layer "In4.Cu")
		(net "M_E_DQ<7>")
	)
	(gr_poly
		(pts
			(xy 230.709724 -86.757764) (xy 230.620824 -86.564724) (xy 230.392224 -86.564724) (xy 230.303324 -86.757764)
			(xy 230.303324 -86.802214) (xy 230.709724 -86.802214)
		)
		(stroke
			(width 0)
			(type solid)
		)
		(fill yes)
		(layer "In4.Cu")
		(net "M_E_DQ<6>")
	)
	(gr_poly
		(pts
			(xy 230.844344 -85.854286) (xy 230.844344 -85.809836) (xy 230.437944 -85.809836) (xy 230.437944 -85.854286)
			(xy 230.526844 -86.047326) (xy 230.755444 -86.047326)
		)
		(stroke
			(width 0)
			(type solid)
		)
		(fill yes)
		(layer "In4.Cu")
		(net "M_E_DQS_DP<0>")
	)
	(gr_poly
		(pts
			(xy 230.844344 -85.574886) (xy 230.755444 -85.381846) (xy 230.526844 -85.381846) (xy 230.437944 -85.574886)
			(xy 230.437944 -85.619336) (xy 230.844344 -85.619336)
		)
		(stroke
			(width 0)
			(type solid)
		)
		(fill yes)
		(layer "In4.Cu")
		(net "M_E_DQS_DN<0>")
	)
	(gr_poly
		(pts
			(xy 230.918512 -64.292226) (xy 230.992172 -64.092836) (xy 230.830628 -63.931292) (xy 230.631238 -64.004952)
			(xy 230.599742 -64.036194) (xy 230.88727 -64.323722)
		)
		(stroke
			(width 0)
			(type solid)
		)
		(fill yes)
		(layer "In4.Cu")
		(net "M_B_DQ<7>")
	)
	(gr_poly
		(pts
			(xy 230.937308 -49.228756) (xy 230.968804 -49.197514) (xy 230.681276 -48.909986) (xy 230.650034 -48.941482)
			(xy 230.576374 -49.140872) (xy 230.737918 -49.302416)
		)
		(stroke
			(width 0)
			(type solid)
		)
		(fill yes)
		(layer "In4.Cu")
		(net "M_B_DQ<20>")
	)
	(gr_poly
		(pts
			(xy 231.048814 -62.879224) (xy 231.048814 -62.650624) (xy 230.855774 -62.561724) (xy 230.811324 -62.561724)
			(xy 230.811324 -62.968124) (xy 230.855774 -62.968124)
		)
		(stroke
			(width 0)
			(type solid)
		)
		(fill yes)
		(layer "In4.Cu")
		(net "M_B_DQ<3>")
	)
	(gr_poly
		(pts
			(xy 231.06634 -64.834262) (xy 231.097582 -64.802766) (xy 230.810308 -64.515492) (xy 230.778812 -64.546988)
			(xy 230.705152 -64.746378) (xy 230.86695 -64.907922)
		)
		(stroke
			(width 0)
			(type solid)
		)
		(fill yes)
		(layer "In4.Cu")
		(net "M_B_DQ<6>")
	)
	(gr_poly
		(pts
			(xy 231.07269 -96.053402) (xy 231.041194 -96.021906) (xy 230.841804 -95.948246) (xy 230.68026 -96.110044)
			(xy 230.75392 -96.30918) (xy 230.785162 -96.340676)
		)
		(stroke
			(width 0)
			(type solid)
		)
		(fill yes)
		(layer "In4.Cu")
		(net "M_E_DQ<14>")
	)
	(gr_poly
		(pts
			(xy 231.115108 -88.092534) (xy 231.026208 -87.922354) (xy 230.805228 -87.922354) (xy 230.716328 -88.092534)
			(xy 230.716328 -88.136984) (xy 231.115108 -88.136984)
		)
		(stroke
			(width 0)
			(type solid)
		)
		(fill yes)
		(layer "In4.Cu")
		(net "M_E_DQ<2>")
	)
	(gr_poly
		(pts
			(xy 231.134666 -49.031398) (xy 231.208326 -48.832008) (xy 231.046782 -48.670464) (xy 230.847392 -48.744124)
			(xy 230.815896 -48.775366) (xy 231.103424 -49.062894)
		)
		(stroke
			(width 0)
			(type solid)
		)
		(fill yes)
		(layer "In4.Cu")
		(net "M_B_DQ<21>")
	)
	(gr_poly
		(pts
			(xy 231.16667 -63.847726) (xy 231.198166 -63.81623) (xy 230.910892 -63.528956) (xy 230.879396 -63.560452)
			(xy 230.805736 -63.759588) (xy 230.967534 -63.921386)
		)
		(stroke
			(width 0)
			(type solid)
		)
		(fill yes)
		(layer "In4.Cu")
		(net "M_B_DQ<2>")
	)
	(gr_poly
		(pts
			(xy 231.234234 -88.383364) (xy 231.234234 -88.338914) (xy 230.835454 -88.339168) (xy 230.835708 -88.383618)
			(xy 230.924608 -88.553544) (xy 231.145334 -88.553544)
		)
		(stroke
			(width 0)
			(type solid)
		)
		(fill yes)
		(layer "In4.Cu")
		(net "M_E_DQ<3>")
	)
	(gr_poly
		(pts
			(xy 231.301798 -89.49944) (xy 231.270302 -89.468198) (xy 231.070912 -89.394538) (xy 230.909368 -89.556082)
			(xy 230.983028 -89.755472) (xy 231.01427 -89.786968)
		)
		(stroke
			(width 0)
			(type solid)
		)
		(fill yes)
		(layer "In4.Cu")
		(net "M_E_DQ<12>")
	)
	(gr_poly
		(pts
			(xy 231.312212 -96.418654) (xy 231.238552 -96.219264) (xy 231.207056 -96.187768) (xy 230.919782 -96.475042)
			(xy 230.951024 -96.506538) (xy 231.150414 -96.580198)
		)
		(stroke
			(width 0)
			(type solid)
		)
		(fill yes)
		(layer "In4.Cu")
		(net "M_E_DQ<15>")
	)
	(gr_poly
		(pts
			(xy 231.364282 -63.650114) (xy 231.437942 -63.450724) (xy 231.276398 -63.28918) (xy 231.077008 -63.36284)
			(xy 231.045512 -63.394082) (xy 231.33304 -63.68161)
		)
		(stroke
			(width 0)
			(type solid)
		)
		(fill yes)
		(layer "In4.Cu")
		(net "M_B_DQ<3>")
	)
	(gr_poly
		(pts
			(xy 231.489504 -62.330838) (xy 231.445054 -62.330838) (xy 231.252014 -62.419738) (xy 231.252014 -62.648338)
			(xy 231.445054 -62.737238) (xy 231.489504 -62.737238)
		)
		(stroke
			(width 0)
			(type solid)
		)
		(fill yes)
		(layer "In4.Cu")
		(net "M_B_DQ<12>")
	)
	(gr_poly
		(pts
			(xy 231.489504 -61.340238) (xy 231.445054 -61.340238) (xy 231.252014 -61.429138) (xy 231.252014 -61.657738)
			(xy 231.445054 -61.746638) (xy 231.489504 -61.746638)
		)
		(stroke
			(width 0)
			(type solid)
		)
		(fill yes)
		(layer "In4.Cu")
		(net "M_B_DQ<12>")
	)
	(gr_poly
		(pts
			(xy 231.541066 -89.864692) (xy 231.467406 -89.665302) (xy 231.436164 -89.633806) (xy 231.148636 -89.921334)
			(xy 231.180132 -89.952576) (xy 231.379522 -90.026236)
		)
		(stroke
			(width 0)
			(type solid)
		)
		(fill yes)
		(layer "In4.Cu")
		(net "M_E_DQ<13>")
	)
	(gr_poly
		(pts
			(xy 231.59212 -91.642438) (xy 231.51846 -91.443302) (xy 231.486964 -91.411806) (xy 231.19969 -91.69908)
			(xy 231.231186 -91.730576) (xy 231.430322 -91.804236)
		)
		(stroke
			(width 0)
			(type solid)
		)
		(fill yes)
		(layer "In4.Cu")
		(net "M_E_DQ<9>")
	)
	(gr_poly
		(pts
			(xy 231.63784 -49.929288) (xy 231.669336 -49.898046) (xy 231.381808 -49.610518) (xy 231.350566 -49.642014)
			(xy 231.276906 -49.841404) (xy 231.43845 -50.002948)
		)
		(stroke
			(width 0)
			(type solid)
		)
		(fill yes)
		(layer "In4.Cu")
		(net "M_B_DQ<20>")
	)
	(gr_poly
		(pts
			(xy 231.689148 -93.823282) (xy 231.657652 -93.791786) (xy 231.458516 -93.718126) (xy 231.296718 -93.879924)
			(xy 231.370378 -94.07906) (xy 231.401874 -94.110556)
		)
		(stroke
			(width 0)
			(type solid)
		)
		(fill yes)
		(layer "In4.Cu")
		(net "M_E_DQS_DN<1>")
	)
	(gr_poly
		(pts
			(xy 231.700324 -87.036656) (xy 231.700324 -86.992206) (xy 231.293924 -86.992206) (xy 231.293924 -87.036656)
			(xy 231.382824 -87.229696) (xy 231.611424 -87.229696)
		)
		(stroke
			(width 0)
			(type solid)
		)
		(fill yes)
		(layer "In4.Cu")
		(net "M_E_DQ<7>")
	)
	(gr_poly
		(pts
			(xy 231.700324 -86.757764) (xy 231.611424 -86.564724) (xy 231.382824 -86.564724) (xy 231.293924 -86.757764)
			(xy 231.293924 -86.802214) (xy 231.700324 -86.802214)
		)
		(stroke
			(width 0)
			(type solid)
		)
		(fill yes)
		(layer "In4.Cu")
		(net "M_E_DQ<6>")
	)
	(gr_poly
		(pts
			(xy 231.73055 -67.12204) (xy 231.73055 -67.07759) (xy 231.32415 -67.07759) (xy 231.32415 -67.12204)
			(xy 231.41305 -67.31508) (xy 231.64165 -67.31508)
		)
		(stroke
			(width 0)
			(type solid)
		)
		(fill yes)
		(layer "In4.Cu")
		(net "M_B_DQS_DP<9>")
	)
	(gr_poly
		(pts
			(xy 231.73055 -66.84264) (xy 231.64165 -66.6496) (xy 231.41305 -66.6496) (xy 231.32415 -66.84264)
			(xy 231.32415 -66.88709) (xy 231.73055 -66.88709)
		)
		(stroke
			(width 0)
			(type solid)
		)
		(fill yes)
		(layer "In4.Cu")
		(net "M_B_DQS_DN<9>")
	)
	(gr_poly
		(pts
			(xy 231.75087 -83.406488) (xy 231.67721 -83.207098) (xy 231.645968 -83.175602) (xy 231.35844 -83.46313)
			(xy 231.389936 -83.494372) (xy 231.589326 -83.568032)
		)
		(stroke
			(width 0)
			(type solid)
		)
		(fill yes)
		(layer "In4.Cu")
		(net "M_E_DQ<1>")
	)
	(gr_poly
		(pts
			(xy 231.773222 -95.35287) (xy 231.741726 -95.321374) (xy 231.542336 -95.247714) (xy 231.380792 -95.409512)
			(xy 231.454452 -95.608648) (xy 231.485694 -95.640144)
		)
		(stroke
			(width 0)
			(type solid)
		)
		(fill yes)
		(layer "In4.Cu")
		(net "M_E_DQ<14>")
	)
	(gr_poly
		(pts
			(xy 231.835198 -49.73193) (xy 231.908858 -49.53254) (xy 231.747314 -49.370996) (xy 231.547924 -49.444656)
			(xy 231.516428 -49.475898) (xy 231.803956 -49.763426)
		)
		(stroke
			(width 0)
			(type solid)
		)
		(fill yes)
		(layer "In4.Cu")
		(net "M_B_DQ<21>")
	)
	(gr_poly
		(pts
			(xy 231.858312 -85.94344) (xy 231.858312 -85.89899) (xy 231.451912 -85.89899) (xy 231.451912 -85.94344)
			(xy 231.540812 -86.13648) (xy 231.769412 -86.13648)
		)
		(stroke
			(width 0)
			(type solid)
		)
		(fill yes)
		(layer "In4.Cu")
		(net "M_E_DQS_DP<0>")
	)
	(gr_poly
		(pts
			(xy 231.858312 -85.66404) (xy 231.769412 -85.471) (xy 231.540812 -85.471) (xy 231.451912 -85.66404)
			(xy 231.451912 -85.70849) (xy 231.858312 -85.70849)
		)
		(stroke
			(width 0)
			(type solid)
		)
		(fill yes)
		(layer "In4.Cu")
		(net "M_E_DQS_DN<0>")
	)
	(gr_poly
		(pts
			(xy 231.917494 -62.140338) (xy 231.917494 -61.911738) (xy 231.724454 -61.822838) (xy 231.680004 -61.822838)
			(xy 231.680004 -62.229238) (xy 231.724454 -62.229238)
		)
		(stroke
			(width 0)
			(type solid)
		)
		(fill yes)
		(layer "In4.Cu")
		(net "M_B_DQ<13>")
	)
	(gr_poly
		(pts
			(xy 231.928924 -94.188788) (xy 231.855264 -93.989398) (xy 231.824022 -93.957902) (xy 231.536494 -94.24543)
			(xy 231.56799 -94.276672) (xy 231.76738 -94.350332)
		)
		(stroke
			(width 0)
			(type solid)
		)
		(fill yes)
		(layer "In4.Cu")
		(net "M_E_DQS_DP<1>")
	)
	(gr_poly
		(pts
			(xy 231.945434 -82.195416) (xy 231.945434 -82.150966) (xy 231.539034 -82.150966) (xy 231.539034 -82.195416)
			(xy 231.627934 -82.388456) (xy 231.856534 -82.388456)
		)
		(stroke
			(width 0)
			(type solid)
		)
		(fill yes)
		(layer "In4.Cu")
		(net "M_E_DQ<5>")
	)
	(gr_poly
		(pts
			(xy 231.945434 -81.916524) (xy 231.856534 -81.723484) (xy 231.627934 -81.723484) (xy 231.539034 -81.916524)
			(xy 231.539034 -81.960974) (xy 231.945434 -81.960974)
		)
		(stroke
			(width 0)
			(type solid)
		)
		(fill yes)
		(layer "In4.Cu")
		(net "M_E_DQ<4>")
	)
	(gr_poly
		(pts
			(xy 232.012744 -95.718122) (xy 231.939084 -95.518732) (xy 231.907588 -95.487236) (xy 231.620314 -95.77451)
			(xy 231.651556 -95.806006) (xy 231.850946 -95.879666)
		)
		(stroke
			(width 0)
			(type solid)
		)
		(fill yes)
		(layer "In4.Cu")
		(net "M_E_DQ<15>")
	)
	(gr_poly
		(pts
			(xy 232.121202 -48.31969) (xy 232.152698 -48.288448) (xy 231.86517 -48.00092) (xy 231.833928 -48.032416)
			(xy 231.760268 -48.231806) (xy 231.921812 -48.39335)
		)
		(stroke
			(width 0)
			(type solid)
		)
		(fill yes)
		(layer "In4.Cu")
		(net "M_B_DQ<16>")
	)
	(gr_poly
		(pts
			(xy 232.18013 -90.942414) (xy 232.091484 -90.749628) (xy 231.86263 -90.749628) (xy 231.77373 -90.942414)
			(xy 231.77373 -90.987118) (xy 232.18013 -90.987118)
		)
		(stroke
			(width 0)
			(type solid)
		)
		(fill yes)
		(layer "In4.Cu")
		(net "M_E_DQ<8>")
	)
	(gr_poly
		(pts
			(xy 232.24871 -58.571638) (xy 232.280206 -58.540396) (xy 231.992678 -58.252868) (xy 231.961436 -58.284364)
			(xy 231.887776 -58.483754) (xy 232.04932 -58.645298)
		)
		(stroke
			(width 0)
			(type solid)
		)
		(fill yes)
		(layer "In4.Cu")
		(net "M_B_DQS_DP<10>")
	)
	(gr_poly
		(pts
			(xy 232.30713 -91.22156) (xy 232.30713 -91.17711) (xy 231.90073 -91.17711) (xy 231.90073 -91.22156)
			(xy 231.98963 -91.4146) (xy 232.218484 -91.4146)
		)
		(stroke
			(width 0)
			(type solid)
		)
		(fill yes)
		(layer "In4.Cu")
		(net "M_E_DQ<9>")
	)
	(gr_poly
		(pts
			(xy 232.31856 -48.122332) (xy 232.39222 -47.922942) (xy 232.230676 -47.761398) (xy 232.031286 -47.835058)
			(xy 231.99979 -47.8663) (xy 232.287318 -48.153828)
		)
		(stroke
			(width 0)
			(type solid)
		)
		(fill yes)
		(layer "In4.Cu")
		(net "M_B_DQ<17>")
	)
	(gr_poly
		(pts
			(xy 232.333546 -82.683096) (xy 232.244646 -82.490056) (xy 232.016046 -82.490056) (xy 231.927146 -82.683096)
			(xy 231.927146 -82.727546) (xy 232.333546 -82.727546)
		)
		(stroke
			(width 0)
			(type solid)
		)
		(fill yes)
		(layer "In4.Cu")
		(net "M_E_DQ<0>")
	)
	(gr_poly
		(pts
			(xy 232.366312 -100.840032) (xy 232.334816 -100.808536) (xy 232.135426 -100.734876) (xy 231.973882 -100.896674)
			(xy 232.047288 -101.096064) (xy 232.078784 -101.127306)
		)
		(stroke
			(width 0)
			(type solid)
		)
		(fill yes)
		(layer "In4.Cu")
		(net "M_E_DQ<20>")
	)
	(gr_poly
		(pts
			(xy 232.38968 -93.12275) (xy 232.358184 -93.091254) (xy 232.159048 -93.017594) (xy 231.99725 -93.179392)
			(xy 232.07091 -93.378528) (xy 232.102406 -93.410024)
		)
		(stroke
			(width 0)
			(type solid)
		)
		(fill yes)
		(layer "In4.Cu")
		(net "M_E_DQS_DN<1>")
	)
	(gr_poly
		(pts
			(xy 232.44556 -61.825124) (xy 232.40111 -61.825378) (xy 232.23093 -61.914278) (xy 232.231184 -62.135004)
			(xy 232.40111 -62.223904) (xy 232.445814 -62.224158)
		)
		(stroke
			(width 0)
			(type solid)
		)
		(fill yes)
		(layer "In4.Cu")
		(net "M_B_DQ<8>")
	)
	(gr_poly
		(pts
			(xy 232.44556 -60.845446) (xy 232.40111 -60.845446) (xy 232.23093 -60.934346) (xy 232.23093 -61.155326)
			(xy 232.40111 -61.244226) (xy 232.44556 -61.244226)
		)
		(stroke
			(width 0)
			(type solid)
		)
		(fill yes)
		(layer "In4.Cu")
		(net "M_B_DQ<8>")
	)
	(gr_poly
		(pts
			(xy 232.446322 -58.374026) (xy 232.519982 -58.17489) (xy 232.358184 -58.013092) (xy 232.159048 -58.086752)
			(xy 232.127552 -58.118248) (xy 232.414826 -58.405522)
		)
		(stroke
			(width 0)
			(type solid)
		)
		(fill yes)
		(layer "In4.Cu")
		(net "M_B_DQS_DN<10>")
	)
	(gr_poly
		(pts
			(xy 232.473754 -94.652338) (xy 232.442258 -94.620842) (xy 232.242868 -94.547182) (xy 232.081324 -94.70898)
			(xy 232.154984 -94.908116) (xy 232.186226 -94.939612)
		)
		(stroke
			(width 0)
			(type solid)
		)
		(fill yes)
		(layer "In4.Cu")
		(net "M_E_DQ<14>")
	)
	(gr_poly
		(pts
			(xy 232.606088 -101.205792) (xy 232.532428 -101.006402) (xy 232.501186 -100.974906) (xy 232.213658 -101.26218)
			(xy 232.245154 -101.293676) (xy 232.444544 -101.367336)
		)
		(stroke
			(width 0)
			(type solid)
		)
		(fill yes)
		(layer "In4.Cu")
		(net "M_E_DQ<21>")
	)
	(gr_poly
		(pts
			(xy 232.629456 -93.488256) (xy 232.555796 -93.288866) (xy 232.524554 -93.25737) (xy 232.237026 -93.544898)
			(xy 232.268522 -93.57614) (xy 232.467912 -93.6498)
		)
		(stroke
			(width 0)
			(type solid)
		)
		(fill yes)
		(layer "In4.Cu")
		(net "M_E_DQS_DP<1>")
	)
	(gr_poly
		(pts
			(xy 232.650538 -68.017136) (xy 232.658666 -67.825366) (xy 232.467404 -67.714876) (xy 232.305352 -67.817746)
			(xy 232.283 -67.856354) (xy 232.62844 -68.055744)
		)
		(stroke
			(width 0)
			(type solid)
		)
		(fill yes)
		(layer "In4.Cu")
		(net "M_B_DQ<1>")
	)
	(gr_poly
		(pts
			(xy 232.650538 -67.026536) (xy 232.658666 -66.834766) (xy 232.467404 -66.724276) (xy 232.305352 -66.827146)
			(xy 232.283 -66.865754) (xy 232.62844 -67.065144)
		)
		(stroke
			(width 0)
			(type solid)
		)
		(fill yes)
		(layer "In4.Cu")
		(net "M_B_DQS_DN<9>")
	)
	(gr_poly
		(pts
			(xy 232.650538 -66.035936) (xy 232.658666 -65.844166) (xy 232.467404 -65.733676) (xy 232.305352 -65.836546)
			(xy 232.283 -65.875154) (xy 232.62844 -66.074544)
		)
		(stroke
			(width 0)
			(type solid)
		)
		(fill yes)
		(layer "In4.Cu")
		(net "M_B_DQS_DN<0>")
	)
	(gr_poly
		(pts
			(xy 232.650538 -65.045336) (xy 232.658666 -64.853566) (xy 232.467404 -64.743076) (xy 232.305352 -64.845946)
			(xy 232.283 -64.884554) (xy 232.62844 -65.083944)
		)
		(stroke
			(width 0)
			(type solid)
		)
		(fill yes)
		(layer "In4.Cu")
		(net "M_B_DQ<7>")
	)
	(gr_poly
		(pts
			(xy 232.650538 -64.054736) (xy 232.658666 -63.862966) (xy 232.467404 -63.752476) (xy 232.305352 -63.855346)
			(xy 232.283 -63.893954) (xy 232.62844 -64.093344)
		)
		(stroke
			(width 0)
			(type solid)
		)
		(fill yes)
		(layer "In4.Cu")
		(net "M_B_DQ<3>")
	)
	(gr_poly
		(pts
			(xy 232.677716 -63.070232) (xy 232.685844 -62.878462) (xy 232.494582 -62.767972) (xy 232.33253 -62.870842)
			(xy 232.310178 -62.90945) (xy 232.655618 -63.10884)
		)
		(stroke
			(width 0)
			(type solid)
		)
		(fill yes)
		(layer "In4.Cu")
		(net "M_B_DQ<13>")
	)
	(gr_poly
		(pts
			(xy 232.679494 -84.929726) (xy 232.65384 -84.739226) (xy 232.628186 -84.703158) (xy 232.302558 -84.933536)
			(xy 232.328212 -84.969858) (xy 232.499154 -85.057488)
		)
		(stroke
			(width 0)
			(type solid)
		)
		(fill yes)
		(layer "In4.Cu")
		(net "M_E_DQS_DN<9>")
	)
	(gr_poly
		(pts
			(xy 232.682288 -88.897206) (xy 232.67416 -88.705436) (xy 232.652062 -88.666828) (xy 232.306622 -88.866472)
			(xy 232.328974 -88.904826) (xy 232.491026 -89.007696)
		)
		(stroke
			(width 0)
			(type solid)
		)
		(fill yes)
		(layer "In4.Cu")
		(net "M_E_DQ<13>")
	)
	(gr_poly
		(pts
			(xy 232.68432 -87.92718) (xy 232.676192 -87.73541) (xy 232.654094 -87.696802) (xy 232.308654 -87.896446)
			(xy 232.331006 -87.9348) (xy 232.493058 -88.03767)
		)
		(stroke
			(width 0)
			(type solid)
		)
		(fill yes)
		(layer "In4.Cu")
		(net "M_E_DQ<3>")
	)
	(gr_poly
		(pts
			(xy 232.68432 -86.93658) (xy 232.676192 -86.74481) (xy 232.654094 -86.706202) (xy 232.308654 -86.905846)
			(xy 232.331006 -86.9442) (xy 232.493058 -87.04707)
		)
		(stroke
			(width 0)
			(type solid)
		)
		(fill yes)
		(layer "In4.Cu")
		(net "M_E_DQ<7>")
	)
	(gr_poly
		(pts
			(xy 232.68432 -85.94598) (xy 232.676192 -85.75421) (xy 232.654094 -85.715602) (xy 232.308654 -85.915246)
			(xy 232.331006 -85.9536) (xy 232.493058 -86.05647)
		)
		(stroke
			(width 0)
			(type solid)
		)
		(fill yes)
		(layer "In4.Cu")
		(net "M_E_DQS_DP<0>")
	)
	(gr_poly
		(pts
			(xy 232.711244 -50.11039) (xy 232.711244 -50.06594) (xy 232.304844 -50.06594) (xy 232.304844 -50.11039)
			(xy 232.393744 -50.30343) (xy 232.622344 -50.30343)
		)
		(stroke
			(width 0)
			(type solid)
		)
		(fill yes)
		(layer "In4.Cu")
		(net "M_B_DQ<20>")
	)
	(gr_poly
		(pts
			(xy 232.711244 -49.831244) (xy 232.622344 -49.638204) (xy 232.393744 -49.638204) (xy 232.304844 -49.831244)
			(xy 232.304844 -49.875694) (xy 232.711244 -49.875694)
		)
		(stroke
			(width 0)
			(type solid)
		)
		(fill yes)
		(layer "In4.Cu")
		(net "M_B_DQ<21>")
	)
	(gr_poly
		(pts
			(xy 232.713276 -95.01759) (xy 232.639616 -94.8182) (xy 232.60812 -94.786704) (xy 232.320846 -95.073978)
			(xy 232.352088 -95.105474) (xy 232.551478 -95.179134)
		)
		(stroke
			(width 0)
			(type solid)
		)
		(fill yes)
		(layer "In4.Cu")
		(net "M_E_DQ<15>")
	)
	(gr_poly
		(pts
			(xy 232.782364 -92.460064) (xy 232.782364 -92.415614) (xy 232.375964 -92.415614) (xy 232.375964 -92.460064)
			(xy 232.464864 -92.653104) (xy 232.693464 -92.653104)
		)
		(stroke
			(width 0)
			(type solid)
		)
		(fill yes)
		(layer "In4.Cu")
		(net "M_E_DQS_DN<10>")
	)
	(gr_poly
		(pts
			(xy 232.782364 -92.180664) (xy 232.693464 -91.987624) (xy 232.464864 -91.987624) (xy 232.375964 -92.180664)
			(xy 232.375964 -92.225114) (xy 232.782364 -92.225114)
		)
		(stroke
			(width 0)
			(type solid)
		)
		(fill yes)
		(layer "In4.Cu")
		(net "M_E_DQS_DP<10>")
	)
	(gr_poly
		(pts
			(xy 232.798366 -83.491832) (xy 232.826814 -83.457796) (xy 232.521506 -83.201256) (xy 232.492804 -83.235292)
			(xy 232.451656 -83.422998) (xy 232.62082 -83.564984)
		)
		(stroke
			(width 0)
			(type solid)
		)
		(fill yes)
		(layer "In4.Cu")
		(net "M_E_DQ<1>")
	)
	(gr_poly
		(pts
			(xy 232.80624 -68.628514) (xy 232.834688 -68.594478) (xy 232.52938 -68.337938) (xy 232.500678 -68.371974)
			(xy 232.45953 -68.55968) (xy 232.628694 -68.701666)
		)
		(stroke
			(width 0)
			(type solid)
		)
		(fill yes)
		(layer "In4.Cu")
		(net "M_B_DQ<0>")
	)
	(gr_poly
		(pts
			(xy 232.821734 -49.020222) (xy 232.85323 -48.98898) (xy 232.565702 -48.701452) (xy 232.53446 -48.732948)
			(xy 232.4608 -48.932338) (xy 232.622344 -49.093882)
		)
		(stroke
			(width 0)
			(type solid)
		)
		(fill yes)
		(layer "In4.Cu")
		(net "M_B_DQ<16>")
	)
	(gr_poly
		(pts
			(xy 232.832148 -84.186776) (xy 232.8037 -84.15274) (xy 232.626154 -84.079588) (xy 232.45699 -84.221574)
			(xy 232.498138 -84.40928) (xy 232.52684 -84.443316)
		)
		(stroke
			(width 0)
			(type solid)
		)
		(fill yes)
		(layer "In4.Cu")
		(net "M_E_DQS_DP<9>")
	)
	(gr_poly
		(pts
			(xy 232.848912 -89.161112) (xy 232.824528 -89.124282) (xy 232.656126 -89.03208) (xy 232.471976 -89.154508)
			(xy 232.49255 -89.34577) (xy 232.517442 -89.3826)
		)
		(stroke
			(width 0)
			(type solid)
		)
		(fill yes)
		(layer "In4.Cu")
		(net "M_E_DQ<8>")
	)
	(gr_poly
		(pts
			(xy 232.885234 -67.62877) (xy 232.907586 -67.590416) (xy 232.562146 -67.390772) (xy 232.540048 -67.42938)
			(xy 232.53192 -67.62115) (xy 232.723182 -67.73164)
		)
		(stroke
			(width 0)
			(type solid)
		)
		(fill yes)
		(layer "In4.Cu")
		(net "M_B_DQS_DP<9>")
	)
	(gr_poly
		(pts
			(xy 232.88752 -63.667386) (xy 232.910126 -63.629032) (xy 232.564432 -63.429642) (xy 232.542334 -63.46825)
			(xy 232.534206 -63.66002) (xy 232.725722 -63.770256)
		)
		(stroke
			(width 0)
			(type solid)
		)
		(fill yes)
		(layer "In4.Cu")
		(net "M_B_DQ<12>")
	)
	(gr_poly
		(pts
			(xy 232.88752 -62.676786) (xy 232.910126 -62.638432) (xy 232.564432 -62.439042) (xy 232.542334 -62.47765)
			(xy 232.534206 -62.66942) (xy 232.725722 -62.779656)
		)
		(stroke
			(width 0)
			(type solid)
		)
		(fill yes)
		(layer "In4.Cu")
		(net "M_B_DQ<8>")
	)
	(gr_poly
		(pts
			(xy 232.906062 -88.16848) (xy 232.88371 -88.130126) (xy 232.721658 -88.027256) (xy 232.530396 -88.137746)
			(xy 232.538524 -88.329516) (xy 232.560622 -88.36787)
		)
		(stroke
			(width 0)
			(type solid)
		)
		(fill yes)
		(layer "In4.Cu")
		(net "M_E_DQ<12>")
	)
	(gr_poly
		(pts
			(xy 232.906062 -87.17788) (xy 232.88371 -87.139526) (xy 232.721658 -87.036656) (xy 232.530396 -87.147146)
			(xy 232.538524 -87.338916) (xy 232.560622 -87.37727)
		)
		(stroke
			(width 0)
			(type solid)
		)
		(fill yes)
		(layer "In4.Cu")
		(net "M_E_DQ<2>")
	)
	(gr_poly
		(pts
			(xy 232.906062 -86.18728) (xy 232.88371 -86.148926) (xy 232.721658 -86.046056) (xy 232.530396 -86.156546)
			(xy 232.538524 -86.348316) (xy 232.560622 -86.38667)
		)
		(stroke
			(width 0)
			(type solid)
		)
		(fill yes)
		(layer "In4.Cu")
		(net "M_E_DQ<6>")
	)
	(gr_poly
		(pts
			(xy 232.906062 -85.19668) (xy 232.88371 -85.158326) (xy 232.721658 -85.055456) (xy 232.530396 -85.165946)
			(xy 232.538524 -85.357716) (xy 232.560622 -85.39607)
		)
		(stroke
			(width 0)
			(type solid)
		)
		(fill yes)
		(layer "In4.Cu")
		(net "M_E_DQS_DN<0>")
	)
	(gr_poly
		(pts
			(xy 232.949242 -59.27217) (xy 232.980484 -59.240674) (xy 232.69321 -58.9534) (xy 232.661714 -58.984896)
			(xy 232.588054 -59.184286) (xy 232.749852 -59.34583)
		)
		(stroke
			(width 0)
			(type solid)
		)
		(fill yes)
		(layer "In4.Cu")
		(net "M_B_DQS_DP<10>")
	)
	(gr_poly
		(pts
			(xy 232.983786 -61.63818) (xy 232.983786 -61.4172) (xy 232.813606 -61.3283) (xy 232.769156 -61.3283)
			(xy 232.769156 -61.72708) (xy 232.813606 -61.72708)
		)
		(stroke
			(width 0)
			(type solid)
		)
		(fill yes)
		(layer "In4.Cu")
		(net "M_B_DQ<9>")
	)
	(gr_poly
		(pts
			(xy 232.983786 -60.64758) (xy 232.983786 -60.4266) (xy 232.813606 -60.3377) (xy 232.769156 -60.3377)
			(xy 232.769156 -60.73648) (xy 232.813606 -60.73648)
		)
		(stroke
			(width 0)
			(type solid)
		)
		(fill yes)
		(layer "In4.Cu")
		(net "M_B_DQ<9>")
	)
	(gr_poly
		(pts
			(xy 233.015536 -95.786702) (xy 232.98404 -95.755206) (xy 232.784904 -95.681546) (xy 232.623106 -95.843344)
			(xy 232.696766 -96.04248) (xy 232.728262 -96.073976)
		)
		(stroke
			(width 0)
			(type solid)
		)
		(fill yes)
		(layer "In4.Cu")
		(net "M_E_DQ<10>")
	)
	(gr_poly
		(pts
			(xy 233.019092 -48.822864) (xy 233.092752 -48.623474) (xy 232.931208 -48.46193) (xy 232.731818 -48.53559)
			(xy 232.700322 -48.566832) (xy 232.98785 -48.85436)
		)
		(stroke
			(width 0)
			(type solid)
		)
		(fill yes)
		(layer "In4.Cu")
		(net "M_B_DQ<17>")
	)
	(gr_poly
		(pts
			(xy 233.02341 -90.589608) (xy 233.02341 -90.360754) (xy 232.83037 -90.272108) (xy 232.78592 -90.272108)
			(xy 232.78592 -90.678508) (xy 232.83037 -90.678508)
		)
		(stroke
			(width 0)
			(type solid)
		)
		(fill yes)
		(layer "In4.Cu")
		(net "M_E_DQ<9>")
	)
	(gr_poly
		(pts
			(xy 233.146854 -59.074558) (xy 233.220514 -58.875168) (xy 233.058716 -58.713624) (xy 232.859326 -58.787284)
			(xy 232.828084 -58.81878) (xy 233.115358 -59.106054)
		)
		(stroke
			(width 0)
			(type solid)
		)
		(fill yes)
		(layer "In4.Cu")
		(net "M_B_DQS_DN<10>")
	)
	(gr_poly
		(pts
			(xy 233.255058 -96.1517) (xy 233.181398 -95.952564) (xy 233.149902 -95.921068) (xy 232.862628 -96.208342)
			(xy 232.894124 -96.239838) (xy 233.09326 -96.313498)
		)
		(stroke
			(width 0)
			(type solid)
		)
		(fill yes)
		(layer "In4.Cu")
		(net "M_E_DQ<11>")
	)
	(gr_poly
		(pts
			(xy 233.293412 -93.135704) (xy 233.293666 -93.091254) (xy 232.887012 -93.091254) (xy 232.887266 -93.135704)
			(xy 232.976166 -93.328744) (xy 233.204512 -93.328744)
		)
		(stroke
			(width 0)
			(type solid)
		)
		(fill yes)
		(layer "In4.Cu")
		(net "M_E_DQS_DP<1>")
	)
	(gr_poly
		(pts
			(xy 233.293412 -92.85605) (xy 233.204766 -92.663264) (xy 232.975912 -92.663264) (xy 232.887266 -92.85605)
			(xy 232.887266 -92.900754) (xy 233.293412 -92.900754)
		)
		(stroke
			(width 0)
			(type solid)
		)
		(fill yes)
		(layer "In4.Cu")
		(net "M_E_DQS_DN<1>")
	)
	(gr_poly
		(pts
			(xy 233.30408 -60.343796) (xy 233.25963 -60.343796) (xy 233.08945 -60.432696) (xy 233.08945 -60.653676)
			(xy 233.25963 -60.742576) (xy 233.30408 -60.742576)
		)
		(stroke
			(width 0)
			(type solid)
		)
		(fill yes)
		(layer "In4.Cu")
		(net "M_B_DQS_DP<10>")
	)
	(gr_poly
		(pts
			(xy 233.304334 -61.323474) (xy 233.259884 -61.323728) (xy 233.089704 -61.412628) (xy 233.089958 -61.633354)
			(xy 233.259884 -61.722254) (xy 233.304588 -61.722508)
		)
		(stroke
			(width 0)
			(type solid)
		)
		(fill yes)
		(layer "In4.Cu")
		(net "M_B_DQS_DP<10>")
	)
	(gr_poly
		(pts
			(xy 233.436668 -90.967814) (xy 233.392218 -90.967814) (xy 233.199178 -91.056714) (xy 233.199178 -91.285314)
			(xy 233.392218 -91.374214) (xy 233.436668 -91.374214)
		)
		(stroke
			(width 0)
			(type solid)
		)
		(fill yes)
		(layer "In4.Cu")
		(net "M_E_DQS_DP<10>")
	)
	(gr_poly
		(pts
			(xy 233.475022 -94.15907) (xy 233.443526 -94.127574) (xy 233.244136 -94.053914) (xy 233.082592 -94.215712)
			(xy 233.156252 -94.414848) (xy 233.187494 -94.446344)
		)
		(stroke
			(width 0)
			(type solid)
		)
		(fill yes)
		(layer "In4.Cu")
		(net "M_E_DQ<14>")
	)
	(gr_poly
		(pts
			(xy 233.48061 -69.527166) (xy 233.495342 -69.335396) (xy 233.30789 -69.218302) (xy 233.142282 -69.315584)
			(xy 233.118914 -69.353176) (xy 233.456988 -69.564758)
		)
		(stroke
			(width 0)
			(type solid)
		)
		(fill yes)
		(layer "In4.Cu")
		(net "M_B_DQ<5>")
	)
	(gr_poly
		(pts
			(xy 233.511598 -100.80244) (xy 233.511598 -100.75799) (xy 233.105198 -100.75799) (xy 233.105198 -100.80244)
			(xy 233.194098 -100.99548) (xy 233.422698 -100.99548)
		)
		(stroke
			(width 0)
			(type solid)
		)
		(fill yes)
		(layer "In4.Cu")
		(net "M_E_DQ<21>")
	)
	(gr_poly
		(pts
			(xy 233.511598 -100.522786) (xy 233.422698 -100.329746) (xy 233.194098 -100.329746) (xy 233.105198 -100.522786)
			(xy 233.105198 -100.567236) (xy 233.511598 -100.567236)
		)
		(stroke
			(width 0)
			(type solid)
		)
		(fill yes)
		(layer "In4.Cu")
		(net "M_E_DQ<20>")
	)
	(gr_poly
		(pts
			(xy 233.527092 -67.522598) (xy 233.53522 -67.330828) (xy 233.343958 -67.220338) (xy 233.181906 -67.323208)
			(xy 233.159554 -67.361562) (xy 233.504994 -67.561206)
		)
		(stroke
			(width 0)
			(type solid)
		)
		(fill yes)
		(layer "In4.Cu")
		(net "M_B_DQS_DN<9>")
	)
	(gr_poly
		(pts
			(xy 233.527092 -66.531998) (xy 233.53522 -66.340228) (xy 233.343958 -66.229738) (xy 233.181906 -66.332608)
			(xy 233.159554 -66.370962) (xy 233.504994 -66.570606)
		)
		(stroke
			(width 0)
			(type solid)
		)
		(fill yes)
		(layer "In4.Cu")
		(net "M_B_DQS_DN<0>")
	)
	(gr_poly
		(pts
			(xy 233.534712 -68.517516) (xy 233.54284 -68.325746) (xy 233.351578 -68.215256) (xy 233.189526 -68.318126)
			(xy 233.167174 -68.35648) (xy 233.512614 -68.55587)
		)
		(stroke
			(width 0)
			(type solid)
		)
		(fill yes)
		(layer "In4.Cu")
		(net "M_B_DQ<1>")
	)
	(gr_poly
		(pts
			(xy 233.534712 -65.545716) (xy 233.54284 -65.353946) (xy 233.351578 -65.243456) (xy 233.189526 -65.346326)
			(xy 233.167174 -65.38468) (xy 233.512614 -65.58407)
		)
		(stroke
			(width 0)
			(type solid)
		)
		(fill yes)
		(layer "In4.Cu")
		(net "M_B_DQ<7>")
	)
	(gr_poly
		(pts
			(xy 233.534712 -64.555116) (xy 233.54284 -64.363346) (xy 233.351578 -64.252856) (xy 233.189526 -64.355726)
			(xy 233.167174 -64.394334) (xy 233.512614 -64.593724)
		)
		(stroke
			(width 0)
			(type solid)
		)
		(fill yes)
		(layer "In4.Cu")
		(net "M_B_DQ<3>")
	)
	(gr_poly
		(pts
			(xy 233.534712 -63.564516) (xy 233.54284 -63.372746) (xy 233.351578 -63.262256) (xy 233.189526 -63.365126)
			(xy 233.167174 -63.403734) (xy 233.512614 -63.603124)
		)
		(stroke
			(width 0)
			(type solid)
		)
		(fill yes)
		(layer "In4.Cu")
		(net "M_B_DQ<13>")
	)
	(gr_poly
		(pts
			(xy 233.534712 -62.573916) (xy 233.54284 -62.382146) (xy 233.351578 -62.271656) (xy 233.189526 -62.374526)
			(xy 233.167174 -62.413134) (xy 233.512614 -62.612524)
		)
		(stroke
			(width 0)
			(type solid)
		)
		(fill yes)
		(layer "In4.Cu")
		(net "M_B_DQ<9>")
	)
	(gr_poly
		(pts
			(xy 233.54284 -82.478626) (xy 233.534712 -82.286856) (xy 233.512614 -82.248248) (xy 233.167174 -82.447638)
			(xy 233.189526 -82.486246) (xy 233.351578 -82.589116)
		)
		(stroke
			(width 0)
			(type solid)
		)
		(fill yes)
		(layer "In4.Cu")
		(net "M_E_DQ<5>")
	)
	(gr_poly
		(pts
			(xy 233.544364 -89.412064) (xy 233.536236 -89.220294) (xy 233.514138 -89.181686) (xy 233.168698 -89.38133)
			(xy 233.19105 -89.419684) (xy 233.353102 -89.522554)
		)
		(stroke
			(width 0)
			(type solid)
		)
		(fill yes)
		(layer "In4.Cu")
		(net "M_E_DQ<9>")
	)
	(gr_poly
		(pts
			(xy 233.544364 -88.421464) (xy 233.536236 -88.229694) (xy 233.514138 -88.191086) (xy 233.168698 -88.39073)
			(xy 233.19105 -88.429084) (xy 233.353102 -88.531954)
		)
		(stroke
			(width 0)
			(type solid)
		)
		(fill yes)
		(layer "In4.Cu")
		(net "M_E_DQ<13>")
	)
	(gr_poly
		(pts
			(xy 233.544364 -87.430864) (xy 233.536236 -87.239094) (xy 233.514138 -87.200486) (xy 233.168698 -87.40013)
			(xy 233.19105 -87.438484) (xy 233.353102 -87.541354)
		)
		(stroke
			(width 0)
			(type solid)
		)
		(fill yes)
		(layer "In4.Cu")
		(net "M_E_DQ<3>")
	)
	(gr_poly
		(pts
			(xy 233.544364 -86.440264) (xy 233.536236 -86.248494) (xy 233.514138 -86.209886) (xy 233.168698 -86.40953)
			(xy 233.19105 -86.447884) (xy 233.353102 -86.550754)
		)
		(stroke
			(width 0)
			(type solid)
		)
		(fill yes)
		(layer "In4.Cu")
		(net "M_E_DQ<7>")
	)
	(gr_poly
		(pts
			(xy 233.544364 -85.449664) (xy 233.536236 -85.257894) (xy 233.514138 -85.219286) (xy 233.168698 -85.41893)
			(xy 233.19105 -85.457284) (xy 233.353102 -85.560154)
		)
		(stroke
			(width 0)
			(type solid)
		)
		(fill yes)
		(layer "In4.Cu")
		(net "M_E_DQS_DP<0>")
	)
	(gr_poly
		(pts
			(xy 233.544364 -84.459064) (xy 233.536236 -84.267294) (xy 233.514138 -84.228686) (xy 233.168698 -84.42833)
			(xy 233.19105 -84.466684) (xy 233.353102 -84.569554)
		)
		(stroke
			(width 0)
			(type solid)
		)
		(fill yes)
		(layer "In4.Cu")
		(net "M_E_DQS_DN<9>")
	)
	(gr_poly
		(pts
			(xy 233.544364 -83.468718) (xy 233.536236 -83.276948) (xy 233.514138 -83.238594) (xy 233.168698 -83.43773)
			(xy 233.19105 -83.476338) (xy 233.353102 -83.579208)
		)
		(stroke
			(width 0)
			(type solid)
		)
		(fill yes)
		(layer "In4.Cu")
		(net "M_E_DQ<1>")
	)
	(gr_poly
		(pts
			(xy 233.617262 -92.354654) (xy 233.543602 -92.155264) (xy 233.512106 -92.123768) (xy 233.224578 -92.411296)
			(xy 233.256074 -92.442792) (xy 233.455464 -92.516452)
		)
		(stroke
			(width 0)
			(type solid)
		)
		(fill yes)
		(layer "In4.Cu")
		(net "M_E_DQS_DN<10>")
	)
	(gr_poly
		(pts
			(xy 233.6292 -50.736754) (xy 233.660696 -50.705512) (xy 233.373168 -50.417984) (xy 233.341926 -50.44948)
			(xy 233.268266 -50.64887) (xy 233.42981 -50.810414)
		)
		(stroke
			(width 0)
			(type solid)
		)
		(fill yes)
		(layer "In4.Cu")
		(net "M_B_DQ<20>")
	)
	(gr_poly
		(pts
			(xy 233.695748 -70.137274) (xy 233.719116 -70.099682) (xy 233.381296 -69.8881) (xy 233.35742 -69.925692)
			(xy 233.342942 -70.117462) (xy 233.53014 -70.234556)
		)
		(stroke
			(width 0)
			(type solid)
		)
		(fill yes)
		(layer "In4.Cu")
		(net "M_B_DQ<4>")
	)
	(gr_poly
		(pts
			(xy 233.697526 -102.539292) (xy 233.623866 -102.340156) (xy 233.59237 -102.30866) (xy 233.305096 -102.595934)
			(xy 233.336592 -102.62743) (xy 233.535728 -102.70109)
		)
		(stroke
			(width 0)
			(type solid)
		)
		(fill yes)
		(layer "In4.Cu")
		(net "M_E_DQ<17>")
	)
	(gr_poly
		(pts
			(xy 233.714544 -94.524322) (xy 233.640884 -94.324932) (xy 233.609388 -94.293436) (xy 233.322114 -94.58071)
			(xy 233.353356 -94.612206) (xy 233.552746 -94.685866)
		)
		(stroke
			(width 0)
			(type solid)
		)
		(fill yes)
		(layer "In4.Cu")
		(net "M_E_DQ<15>")
	)
	(gr_poly
		(pts
			(xy 233.740452 -62.178184) (xy 233.763058 -62.13983) (xy 233.417364 -61.94044) (xy 233.395266 -61.979048)
			(xy 233.387138 -62.170818) (xy 233.578654 -62.281054)
		)
		(stroke
			(width 0)
			(type solid)
		)
		(fill yes)
		(layer "In4.Cu")
		(net "M_B_DQS_DP<10>")
	)
	(gr_poly
		(pts
			(xy 233.74223 -69.1134) (xy 233.764582 -69.075046) (xy 233.419142 -68.875402) (xy 233.397044 -68.91401)
			(xy 233.388916 -69.10578) (xy 233.580178 -69.21627)
		)
		(stroke
			(width 0)
			(type solid)
		)
		(fill yes)
		(layer "In4.Cu")
		(net "M_B_DQ<0>")
	)
	(gr_poly
		(pts
			(xy 233.74223 -66.1416) (xy 233.764582 -66.103246) (xy 233.419142 -65.903602) (xy 233.397044 -65.94221)
			(xy 233.388916 -66.13398) (xy 233.580178 -66.24447)
		)
		(stroke
			(width 0)
			(type solid)
		)
		(fill yes)
		(layer "In4.Cu")
		(net "M_B_DQ<6>")
	)
	(gr_poly
		(pts
			(xy 233.74223 -65.151) (xy 233.764582 -65.112646) (xy 233.419142 -64.913002) (xy 233.397044 -64.95161)
			(xy 233.388916 -65.14338) (xy 233.580178 -65.25387)
		)
		(stroke
			(width 0)
			(type solid)
		)
		(fill yes)
		(layer "In4.Cu")
		(net "M_B_DQ<2>")
	)
	(gr_poly
		(pts
			(xy 233.74223 -64.1604) (xy 233.764582 -64.122046) (xy 233.419142 -63.922402) (xy 233.397044 -63.96101)
			(xy 233.388916 -64.15278) (xy 233.580178 -64.26327)
		)
		(stroke
			(width 0)
			(type solid)
		)
		(fill yes)
		(layer "In4.Cu")
		(net "M_B_DQ<12>")
	)
	(gr_poly
		(pts
			(xy 233.74223 -63.1698) (xy 233.764582 -63.131446) (xy 233.419142 -62.931802) (xy 233.397044 -62.97041)
			(xy 233.388916 -63.16218) (xy 233.580178 -63.27267)
		)
		(stroke
			(width 0)
			(type solid)
		)
		(fill yes)
		(layer "In4.Cu")
		(net "M_B_DQ<8>")
	)
	(gr_poly
		(pts
			(xy 233.742992 -68.123308) (xy 233.765344 -68.084954) (xy 233.419904 -67.88531) (xy 233.397806 -67.923918)
			(xy 233.389678 -68.115688) (xy 233.58094 -68.226178)
		)
		(stroke
			(width 0)
			(type solid)
		)
		(fill yes)
		(layer "In4.Cu")
		(net "M_B_DQS_DP<9>")
	)
	(gr_poly
		(pts
			(xy 233.744008 -67.133216) (xy 233.76636 -67.094862) (xy 233.42092 -66.895218) (xy 233.398822 -66.933826)
			(xy 233.390694 -67.125596) (xy 233.581956 -67.236086)
		)
		(stroke
			(width 0)
			(type solid)
		)
		(fill yes)
		(layer "In4.Cu")
		(net "M_B_DQS_DP<0>")
	)
	(gr_poly
		(pts
			(xy 233.763058 -89.65565) (xy 233.740706 -89.617042) (xy 233.578654 -89.514172) (xy 233.387392 -89.624662)
			(xy 233.39552 -89.816432) (xy 233.417618 -89.85504)
		)
		(stroke
			(width 0)
			(type solid)
		)
		(fill yes)
		(layer "In4.Cu")
		(net "M_E_DQS_DP<10>")
	)
	(gr_poly
		(pts
			(xy 233.763058 -88.66505) (xy 233.740706 -88.626442) (xy 233.578654 -88.523572) (xy 233.387392 -88.634062)
			(xy 233.39552 -88.825832) (xy 233.417618 -88.86444)
		)
		(stroke
			(width 0)
			(type solid)
		)
		(fill yes)
		(layer "In4.Cu")
		(net "M_E_DQ<8>")
	)
	(gr_poly
		(pts
			(xy 233.763058 -87.67445) (xy 233.740706 -87.635842) (xy 233.578654 -87.532972) (xy 233.387392 -87.643462)
			(xy 233.39552 -87.835232) (xy 233.417618 -87.87384)
		)
		(stroke
			(width 0)
			(type solid)
		)
		(fill yes)
		(layer "In4.Cu")
		(net "M_E_DQ<12>")
	)
	(gr_poly
		(pts
			(xy 233.763058 -86.68385) (xy 233.740706 -86.645242) (xy 233.578654 -86.542372) (xy 233.387392 -86.652862)
			(xy 233.39552 -86.844632) (xy 233.417618 -86.88324)
		)
		(stroke
			(width 0)
			(type solid)
		)
		(fill yes)
		(layer "In4.Cu")
		(net "M_E_DQ<2>")
	)
	(gr_poly
		(pts
			(xy 233.763058 -85.69325) (xy 233.740706 -85.654642) (xy 233.578654 -85.551772) (xy 233.387392 -85.662262)
			(xy 233.39552 -85.854032) (xy 233.417618 -85.89264)
		)
		(stroke
			(width 0)
			(type solid)
		)
		(fill yes)
		(layer "In4.Cu")
		(net "M_E_DQ<6>")
	)
	(gr_poly
		(pts
			(xy 233.763058 -84.70265) (xy 233.740706 -84.664042) (xy 233.578654 -84.561172) (xy 233.387392 -84.671662)
			(xy 233.39552 -84.863432) (xy 233.417618 -84.90204)
		)
		(stroke
			(width 0)
			(type solid)
		)
		(fill yes)
		(layer "In4.Cu")
		(net "M_E_DQS_DN<0>")
	)
	(gr_poly
		(pts
			(xy 233.763058 -83.71205) (xy 233.740706 -83.673442) (xy 233.578654 -83.570572) (xy 233.387392 -83.681062)
			(xy 233.39552 -83.872832) (xy 233.417618 -83.91144)
		)
		(stroke
			(width 0)
			(type solid)
		)
		(fill yes)
		(layer "In4.Cu")
		(net "M_E_DQS_DP<9>")
	)
	(gr_poly
		(pts
			(xy 233.763058 -82.72145) (xy 233.740706 -82.682842) (xy 233.578654 -82.579972) (xy 233.387392 -82.690462)
			(xy 233.39552 -82.882232) (xy 233.417618 -82.92084)
		)
		(stroke
			(width 0)
			(type solid)
		)
		(fill yes)
		(layer "In4.Cu")
		(net "M_E_DQ<0>")
	)
	(gr_poly
		(pts
			(xy 233.763058 -81.73085) (xy 233.740706 -81.692242) (xy 233.578654 -81.589372) (xy 233.387392 -81.699862)
			(xy 233.39552 -81.891632) (xy 233.417618 -81.93024)
		)
		(stroke
			(width 0)
			(type solid)
		)
		(fill yes)
		(layer "In4.Cu")
		(net "M_E_DQ<4>")
	)
	(gr_poly
		(pts
			(xy 233.826304 -50.53965) (xy 233.899964 -50.34026) (xy 233.73842 -50.178716) (xy 233.53903 -50.252376)
			(xy 233.507534 -50.283618) (xy 233.795062 -50.571146)
		)
		(stroke
			(width 0)
			(type solid)
		)
		(fill yes)
		(layer "In4.Cu")
		(net "M_B_DQ<21>")
	)
	(gr_poly
		(pts
			(xy 233.842306 -61.14923) (xy 233.842306 -60.92825) (xy 233.672126 -60.83935) (xy 233.627676 -60.83935)
			(xy 233.627676 -61.23813) (xy 233.672126 -61.23813)
		)
		(stroke
			(width 0)
			(type solid)
		)
		(fill yes)
		(layer "In4.Cu")
		(net "M_B_DQS_DN<10>")
	)
	(gr_poly
		(pts
			(xy 233.842306 -60.15863) (xy 233.842306 -59.93765) (xy 233.672126 -59.84875) (xy 233.627676 -59.84875)
			(xy 233.627676 -60.24753) (xy 233.672126 -60.24753)
		)
		(stroke
			(width 0)
			(type solid)
		)
		(fill yes)
		(layer "In4.Cu")
		(net "M_B_DQS_DN<10>")
	)
	(gr_poly
		(pts
			(xy 233.864658 -91.285314) (xy 233.864658 -91.056714) (xy 233.671618 -90.967814) (xy 233.627168 -90.967814)
			(xy 233.627168 -91.374214) (xy 233.671618 -91.374214)
		)
		(stroke
			(width 0)
			(type solid)
		)
		(fill yes)
		(layer "In4.Cu")
		(net "M_E_DQS_DN<10>")
	)
	(gr_poly
		(pts
			(xy 233.879136 -101.753162) (xy 233.84764 -101.721666) (xy 233.648504 -101.648006) (xy 233.486706 -101.809804)
			(xy 233.560366 -102.00894) (xy 233.591862 -102.040436)
		)
		(stroke
			(width 0)
			(type solid)
		)
		(fill yes)
		(layer "In4.Cu")
		(net "M_E_DQ<16>")
	)
	(gr_poly
		(pts
			(xy 233.994706 -92.470732) (xy 233.96321 -92.43949) (xy 233.76382 -92.36583) (xy 233.602276 -92.527374)
			(xy 233.675936 -92.726764) (xy 233.707178 -92.75826)
		)
		(stroke
			(width 0)
			(type solid)
		)
		(fill yes)
		(layer "In4.Cu")
		(net "M_E_DQS_DN<1>")
	)
	(gr_poly
		(pts
			(xy 234.014264 -49.807368) (xy 234.045506 -49.775872) (xy 233.758232 -49.488598) (xy 233.726736 -49.520094)
			(xy 233.653076 -49.719484) (xy 233.814874 -49.881028)
		)
		(stroke
			(width 0)
			(type solid)
		)
		(fill yes)
		(layer "In4.Cu")
		(net "M_B_DQ<16>")
	)
	(gr_poly
		(pts
			(xy 234.1626 -60.828174) (xy 234.118404 -60.828174) (xy 233.948224 -60.917074) (xy 233.948224 -61.138054)
			(xy 234.118404 -61.226954) (xy 234.162854 -61.227208)
		)
		(stroke
			(width 0)
			(type solid)
		)
		(fill yes)
		(layer "In4.Cu")
		(net "M_B_DQS_DP<1>")
	)
	(gr_poly
		(pts
			(xy 234.163108 -91.304618) (xy 234.118658 -91.304618) (xy 233.925618 -91.393518) (xy 233.925618 -91.622118)
			(xy 234.118658 -91.711018) (xy 234.163108 -91.711018)
		)
		(stroke
			(width 0)
			(type solid)
		)
		(fill yes)
		(layer "In4.Cu")
		(net "M_E_DQS_DN<1>")
	)
	(gr_poly
		(pts
			(xy 234.163108 -59.35726) (xy 234.118658 -59.35726) (xy 233.925618 -59.44616) (xy 233.925618 -59.67476)
			(xy 234.118658 -59.76366) (xy 234.163108 -59.76366)
		)
		(stroke
			(width 0)
			(type solid)
		)
		(fill yes)
		(layer "In4.Cu")
		(net "M_B_DQS_DP<1>")
	)
	(gr_poly
		(pts
			(xy 234.175554 -93.458538) (xy 234.144058 -93.427042) (xy 233.944668 -93.353382) (xy 233.783124 -93.51518)
			(xy 233.856784 -93.714316) (xy 233.888026 -93.745812)
		)
		(stroke
			(width 0)
			(type solid)
		)
		(fill yes)
		(layer "In4.Cu")
		(net "M_E_DQ<14>")
	)
	(gr_poly
		(pts
			(xy 234.177586 -48.826928) (xy 234.209082 -48.795432) (xy 233.921808 -48.508158) (xy 233.890312 -48.539654)
			(xy 233.816652 -48.73879) (xy 233.97845 -48.900588)
		)
		(stroke
			(width 0)
			(type solid)
		)
		(fill yes)
		(layer "In4.Cu")
		(net "M_B_DQS_DP<11>")
	)
	(gr_poly
		(pts
			(xy 234.211368 -49.61001) (xy 234.285028 -49.41062) (xy 234.123484 -49.249076) (xy 233.924094 -49.322736)
			(xy 233.892598 -49.354232) (xy 234.179872 -49.641506)
		)
		(stroke
			(width 0)
			(type solid)
		)
		(fill yes)
		(layer "In4.Cu")
		(net "M_B_DQ<17>")
	)
	(gr_poly
		(pts
			(xy 234.234482 -92.836238) (xy 234.160822 -92.637102) (xy 234.129326 -92.605606) (xy 233.842052 -92.89288)
			(xy 233.873548 -92.924376) (xy 234.072684 -92.998036)
		)
		(stroke
			(width 0)
			(type solid)
		)
		(fill yes)
		(layer "In4.Cu")
		(net "M_E_DQS_DP<1>")
	)
	(gr_poly
		(pts
			(xy 234.338876 -93.89999) (xy 234.265216 -93.7006) (xy 234.23372 -93.669104) (xy 233.946446 -93.956378)
			(xy 233.977688 -93.987874) (xy 234.177078 -94.061534)
		)
		(stroke
			(width 0)
			(type solid)
		)
		(fill yes)
		(layer "In4.Cu")
		(net "M_E_DQ<15>")
	)
	(gr_poly
		(pts
			(xy 234.375198 -48.629316) (xy 234.448858 -48.429926) (xy 234.287314 -48.268382) (xy 234.087924 -48.342042)
			(xy 234.056428 -48.373284) (xy 234.343956 -48.660812)
		)
		(stroke
			(width 0)
			(type solid)
		)
		(fill yes)
		(layer "In4.Cu")
		(net "M_B_DQS_DN<11>")
	)
	(gr_poly
		(pts
			(xy 234.382818 -62.074552) (xy 234.390946 -61.882782) (xy 234.199684 -61.772292) (xy 234.037632 -61.875162)
			(xy 234.01528 -61.91377) (xy 234.36072 -62.11316)
		)
		(stroke
			(width 0)
			(type solid)
		)
		(fill yes)
		(layer "In4.Cu")
		(net "M_B_DQS_DN<10>")
	)
	(gr_poly
		(pts
			(xy 234.394756 -70.004432) (xy 234.402884 -69.812662) (xy 234.211622 -69.702172) (xy 234.04957 -69.805042)
			(xy 234.027218 -69.84365) (xy 234.372658 -70.04304)
		)
		(stroke
			(width 0)
			(type solid)
		)
		(fill yes)
		(layer "In4.Cu")
		(net "M_B_DQ<5>")
	)
	(gr_poly
		(pts
			(xy 234.394756 -69.013832) (xy 234.402884 -68.822062) (xy 234.211622 -68.711572) (xy 234.04957 -68.814442)
			(xy 234.027218 -68.85305) (xy 234.372658 -69.05244)
		)
		(stroke
			(width 0)
			(type solid)
		)
		(fill yes)
		(layer "In4.Cu")
		(net "M_B_DQ<1>")
	)
	(gr_poly
		(pts
			(xy 234.394756 -68.023232) (xy 234.402884 -67.831462) (xy 234.211622 -67.720972) (xy 234.04957 -67.823842)
			(xy 234.027218 -67.86245) (xy 234.372658 -68.06184)
		)
		(stroke
			(width 0)
			(type solid)
		)
		(fill yes)
		(layer "In4.Cu")
		(net "M_B_DQS_DN<9>")
	)
	(gr_poly
		(pts
			(xy 234.394756 -67.032632) (xy 234.402884 -66.840862) (xy 234.211622 -66.730372) (xy 234.04957 -66.833242)
			(xy 234.027218 -66.87185) (xy 234.372658 -67.07124)
		)
		(stroke
			(width 0)
			(type solid)
		)
		(fill yes)
		(layer "In4.Cu")
		(net "M_B_DQS_DN<0>")
	)
	(gr_poly
		(pts
			(xy 234.394756 -66.042032) (xy 234.402884 -65.850262) (xy 234.211622 -65.739772) (xy 234.04957 -65.842642)
			(xy 234.027218 -65.88125) (xy 234.372658 -66.08064)
		)
		(stroke
			(width 0)
			(type solid)
		)
		(fill yes)
		(layer "In4.Cu")
		(net "M_B_DQ<7>")
	)
	(gr_poly
		(pts
			(xy 234.394756 -65.051432) (xy 234.402884 -64.859662) (xy 234.211622 -64.749172) (xy 234.04957 -64.852042)
			(xy 234.027218 -64.89065) (xy 234.372658 -65.09004)
		)
		(stroke
			(width 0)
			(type solid)
		)
		(fill yes)
		(layer "In4.Cu")
		(net "M_B_DQ<3>")
	)
	(gr_poly
		(pts
			(xy 234.394756 -64.060832) (xy 234.402884 -63.869062) (xy 234.211622 -63.758572) (xy 234.04957 -63.861442)
			(xy 234.027218 -63.90005) (xy 234.372658 -64.09944)
		)
		(stroke
			(width 0)
			(type solid)
		)
		(fill yes)
		(layer "In4.Cu")
		(net "M_B_DQ<13>")
	)
	(gr_poly
		(pts
			(xy 234.394756 -63.070232) (xy 234.402884 -62.878462) (xy 234.211622 -62.767972) (xy 234.04957 -62.870842)
			(xy 234.027218 -62.90945) (xy 234.372658 -63.10884)
		)
		(stroke
			(width 0)
			(type solid)
		)
		(fill yes)
		(layer "In4.Cu")
		(net "M_B_DQ<9>")
	)
	(gr_poly
		(pts
			(xy 234.398058 -101.83876) (xy 234.324398 -101.639624) (xy 234.292902 -101.608128) (xy 234.005628 -101.895402)
			(xy 234.037124 -101.926898) (xy 234.23626 -102.000558)
		)
		(stroke
			(width 0)
			(type solid)
		)
		(fill yes)
		(layer "In4.Cu")
		(net "M_E_DQ<17>")
	)
	(gr_poly
		(pts
			(xy 234.399074 -100.80625) (xy 234.390946 -100.61448) (xy 234.368848 -100.575872) (xy 234.023408 -100.775262)
			(xy 234.04576 -100.81387) (xy 234.207812 -100.91674)
		)
		(stroke
			(width 0)
			(type solid)
		)
		(fill yes)
		(layer "In4.Cu")
		(net "M_E_DQ<21>")
	)
	(gr_poly
		(pts
			(xy 234.40136 -89.90838) (xy 234.393232 -89.71661) (xy 234.371134 -89.678002) (xy 234.025694 -89.877646)
			(xy 234.048046 -89.916) (xy 234.210098 -90.01887)
		)
		(stroke
			(width 0)
			(type solid)
		)
		(fill yes)
		(layer "In4.Cu")
		(net "M_E_DQS_DN<10>")
	)
	(gr_poly
		(pts
			(xy 234.40136 -88.91778) (xy 234.393232 -88.72601) (xy 234.371134 -88.687402) (xy 234.025694 -88.887046)
			(xy 234.048046 -88.9254) (xy 234.210098 -89.02827)
		)
		(stroke
			(width 0)
			(type solid)
		)
		(fill yes)
		(layer "In4.Cu")
		(net "M_E_DQ<9>")
	)
	(gr_poly
		(pts
			(xy 234.40136 -87.92718) (xy 234.393232 -87.73541) (xy 234.371134 -87.696802) (xy 234.025694 -87.896446)
			(xy 234.048046 -87.9348) (xy 234.210098 -88.03767)
		)
		(stroke
			(width 0)
			(type solid)
		)
		(fill yes)
		(layer "In4.Cu")
		(net "M_E_DQ<13>")
	)
	(gr_poly
		(pts
			(xy 234.40136 -86.93658) (xy 234.393232 -86.74481) (xy 234.371134 -86.706202) (xy 234.025694 -86.905846)
			(xy 234.048046 -86.9442) (xy 234.210098 -87.04707)
		)
		(stroke
			(width 0)
			(type solid)
		)
		(fill yes)
		(layer "In4.Cu")
		(net "M_E_DQ<3>")
	)
	(gr_poly
		(pts
			(xy 234.40136 -85.94598) (xy 234.393232 -85.75421) (xy 234.371134 -85.715602) (xy 234.025694 -85.915246)
			(xy 234.048046 -85.9536) (xy 234.210098 -86.05647)
		)
		(stroke
			(width 0)
			(type solid)
		)
		(fill yes)
		(layer "In4.Cu")
		(net "M_E_DQ<7>")
	)
	(gr_poly
		(pts
			(xy 234.40136 -84.95538) (xy 234.393232 -84.76361) (xy 234.371134 -84.725002) (xy 234.025694 -84.924646)
			(xy 234.048046 -84.963) (xy 234.210098 -85.06587)
		)
		(stroke
			(width 0)
			(type solid)
		)
		(fill yes)
		(layer "In4.Cu")
		(net "M_E_DQS_DP<0>")
	)
	(gr_poly
		(pts
			(xy 234.40136 -83.96478) (xy 234.393232 -83.77301) (xy 234.371134 -83.734402) (xy 234.025694 -83.934046)
			(xy 234.048046 -83.9724) (xy 234.210098 -84.07527)
		)
		(stroke
			(width 0)
			(type solid)
		)
		(fill yes)
		(layer "In4.Cu")
		(net "M_E_DQS_DN<9>")
	)
	(gr_poly
		(pts
			(xy 234.40136 -81.98358) (xy 234.393232 -81.79181) (xy 234.371134 -81.753202) (xy 234.025694 -81.952846)
			(xy 234.048046 -81.9912) (xy 234.210098 -82.09407)
		)
		(stroke
			(width 0)
			(type solid)
		)
		(fill yes)
		(layer "In4.Cu")
		(net "M_E_DQ<5>")
	)
	(gr_poly
		(pts
			(xy 234.402884 -82.973418) (xy 234.394756 -82.781648) (xy 234.372658 -82.743294) (xy 234.027218 -82.94243)
			(xy 234.04957 -82.981038) (xy 234.211622 -83.083908)
		)
		(stroke
			(width 0)
			(type solid)
		)
		(fill yes)
		(layer "In4.Cu")
		(net "M_E_DQ<1>")
	)
	(gr_poly
		(pts
			(xy 234.4293 -95.353886) (xy 234.4293 -95.309436) (xy 234.0229 -95.309436) (xy 234.0229 -95.353886)
			(xy 234.1118 -95.546926) (xy 234.3404 -95.546926)
		)
		(stroke
			(width 0)
			(type solid)
		)
		(fill yes)
		(layer "In4.Cu")
		(net "M_E_DQ<11>")
	)
	(gr_poly
		(pts
			(xy 234.4293 -95.074486) (xy 234.3404 -94.881446) (xy 234.1118 -94.881446) (xy 234.0229 -95.074486)
			(xy 234.0229 -95.118936) (xy 234.4293 -95.118936)
		)
		(stroke
			(width 0)
			(type solid)
		)
		(fill yes)
		(layer "In4.Cu")
		(net "M_E_DQ<10>")
	)
	(gr_poly
		(pts
			(xy 234.591098 -91.368118) (xy 234.591098 -91.139518) (xy 234.398058 -91.050618) (xy 234.353608 -91.050618)
			(xy 234.353608 -91.457018) (xy 234.398058 -91.457018)
		)
		(stroke
			(width 0)
			(type solid)
		)
		(fill yes)
		(layer "In4.Cu")
		(net "M_E_DQS_DP<1>")
	)
	(gr_poly
		(pts
			(xy 234.591098 -59.67476) (xy 234.591098 -59.44616) (xy 234.398058 -59.35726) (xy 234.353608 -59.35726)
			(xy 234.353608 -59.76366) (xy 234.398058 -59.76366)
		)
		(stroke
			(width 0)
			(type solid)
		)
		(fill yes)
		(layer "In4.Cu")
		(net "M_B_DQS_DN<1>")
	)
	(gr_poly
		(pts
			(xy 234.599226 -69.607684) (xy 234.621578 -69.56933) (xy 234.276138 -69.369686) (xy 234.25404 -69.408294)
			(xy 234.245912 -69.600064) (xy 234.437174 -69.710554)
		)
		(stroke
			(width 0)
			(type solid)
		)
		(fill yes)
		(layer "In4.Cu")
		(net "M_B_DQ<0>")
	)
	(gr_poly
		(pts
			(xy 234.599226 -67.626484) (xy 234.621578 -67.58813) (xy 234.276138 -67.388486) (xy 234.25404 -67.427094)
			(xy 234.245912 -67.618864) (xy 234.437174 -67.729354)
		)
		(stroke
			(width 0)
			(type solid)
		)
		(fill yes)
		(layer "In4.Cu")
		(net "M_B_DQS_DP<0>")
	)
	(gr_poly
		(pts
			(xy 234.599226 -66.635884) (xy 234.621578 -66.59753) (xy 234.276138 -66.397886) (xy 234.25404 -66.436494)
			(xy 234.245912 -66.628264) (xy 234.437174 -66.738754)
		)
		(stroke
			(width 0)
			(type solid)
		)
		(fill yes)
		(layer "In4.Cu")
		(net "M_B_DQ<6>")
	)
	(gr_poly
		(pts
			(xy 234.599226 -65.645284) (xy 234.621578 -65.60693) (xy 234.276138 -65.407286) (xy 234.25404 -65.445894)
			(xy 234.245912 -65.637664) (xy 234.437174 -65.748154)
		)
		(stroke
			(width 0)
			(type solid)
		)
		(fill yes)
		(layer "In4.Cu")
		(net "M_B_DQ<2>")
	)
	(gr_poly
		(pts
			(xy 234.599226 -64.654684) (xy 234.621578 -64.61633) (xy 234.276138 -64.416686) (xy 234.25404 -64.455294)
			(xy 234.245912 -64.647064) (xy 234.437174 -64.757554)
		)
		(stroke
			(width 0)
			(type solid)
		)
		(fill yes)
		(layer "In4.Cu")
		(net "M_B_DQ<12>")
	)
	(gr_poly
		(pts
			(xy 234.599226 -63.664084) (xy 234.621578 -63.62573) (xy 234.276138 -63.426086) (xy 234.25404 -63.464694)
			(xy 234.245912 -63.656464) (xy 234.437174 -63.766954)
		)
		(stroke
			(width 0)
			(type solid)
		)
		(fill yes)
		(layer "In4.Cu")
		(net "M_B_DQ<8>")
	)
	(gr_poly
		(pts
			(xy 234.599226 -62.673484) (xy 234.621578 -62.63513) (xy 234.276138 -62.435486) (xy 234.25404 -62.474094)
			(xy 234.245912 -62.665864) (xy 234.437174 -62.776354)
		)
		(stroke
			(width 0)
			(type solid)
		)
		(fill yes)
		(layer "In4.Cu")
		(net "M_B_DQS_DP<10>")
	)
	(gr_poly
		(pts
			(xy 234.599226 -61.682884) (xy 234.621578 -61.64453) (xy 234.275884 -61.44514) (xy 234.25404 -61.483494)
			(xy 234.245912 -61.675264) (xy 234.437174 -61.785754)
		)
		(stroke
			(width 0)
			(type solid)
		)
		(fill yes)
		(layer "In4.Cu")
		(net "M_B_DQS_DP<1>")
	)
	(gr_poly
		(pts
			(xy 234.60075 -68.617846) (xy 234.623102 -68.579238) (xy 234.277662 -68.379848) (xy 234.255564 -68.418456)
			(xy 234.247436 -68.610226) (xy 234.438698 -68.720716)
		)
		(stroke
			(width 0)
			(type solid)
		)
		(fill yes)
		(layer "In4.Cu")
		(net "M_B_DQS_DP<9>")
	)
	(gr_poly
		(pts
			(xy 234.603036 -51.77917) (xy 234.625388 -51.740562) (xy 234.279948 -51.541172) (xy 234.25785 -51.57978)
			(xy 234.249722 -51.77155) (xy 234.440984 -51.88204)
		)
		(stroke
			(width 0)
			(type solid)
		)
		(fill yes)
		(layer "In4.Cu")
		(net "M_B_DQ<20>")
	)
	(gr_poly
		(pts
			(xy 234.608624 -70.603872) (xy 234.630722 -70.565518) (xy 234.285536 -70.366128) (xy 234.263184 -70.404482)
			(xy 234.255056 -70.596506) (xy 234.446572 -70.706996)
		)
		(stroke
			(width 0)
			(type solid)
		)
		(fill yes)
		(layer "In4.Cu")
		(net "M_B_DQ<4>")
	)
	(gr_poly
		(pts
			(xy 234.621578 -100.056442) (xy 234.599226 -100.018088) (xy 234.437174 -99.915218) (xy 234.245912 -100.025708)
			(xy 234.25404 -100.217478) (xy 234.276138 -100.256086)
		)
		(stroke
			(width 0)
			(type solid)
		)
		(fill yes)
		(layer "In4.Cu")
		(net "M_E_DQ<20>")
	)
	(gr_poly
		(pts
			(xy 234.623102 -101.04628) (xy 234.60075 -101.007926) (xy 234.438698 -100.905056) (xy 234.247436 -101.015546)
			(xy 234.255564 -101.207316) (xy 234.277662 -101.24567)
		)
		(stroke
			(width 0)
			(type solid)
		)
		(fill yes)
		(layer "In4.Cu")
		(net "M_E_DQ<16>")
	)
	(gr_poly
		(pts
			(xy 234.623102 -90.14968) (xy 234.60075 -90.111326) (xy 234.438698 -90.008456) (xy 234.247436 -90.118946)
			(xy 234.255564 -90.310716) (xy 234.277662 -90.34907)
		)
		(stroke
			(width 0)
			(type solid)
		)
		(fill yes)
		(layer "In4.Cu")
		(net "M_E_DQS_DN<1>")
	)
	(gr_poly
		(pts
			(xy 234.623102 -89.15908) (xy 234.60075 -89.120726) (xy 234.438698 -89.017856) (xy 234.247436 -89.128346)
			(xy 234.255564 -89.320116) (xy 234.277662 -89.35847)
		)
		(stroke
			(width 0)
			(type solid)
		)
		(fill yes)
		(layer "In4.Cu")
		(net "M_E_DQS_DP<10>")
	)
	(gr_poly
		(pts
			(xy 234.623102 -88.16848) (xy 234.60075 -88.130126) (xy 234.438698 -88.027256) (xy 234.247436 -88.137746)
			(xy 234.255564 -88.329516) (xy 234.277662 -88.36787)
		)
		(stroke
			(width 0)
			(type solid)
		)
		(fill yes)
		(layer "In4.Cu")
		(net "M_E_DQ<8>")
	)
	(gr_poly
		(pts
			(xy 234.623102 -87.17788) (xy 234.60075 -87.139526) (xy 234.438698 -87.036656) (xy 234.247436 -87.147146)
			(xy 234.255564 -87.338916) (xy 234.277662 -87.37727)
		)
		(stroke
			(width 0)
			(type solid)
		)
		(fill yes)
		(layer "In4.Cu")
		(net "M_E_DQ<12>")
	)
	(gr_poly
		(pts
			(xy 234.623102 -86.18728) (xy 234.60075 -86.148926) (xy 234.438698 -86.046056) (xy 234.247436 -86.156546)
			(xy 234.255564 -86.348316) (xy 234.277662 -86.38667)
		)
		(stroke
			(width 0)
			(type solid)
		)
		(fill yes)
		(layer "In4.Cu")
		(net "M_E_DQ<2>")
	)
	(gr_poly
		(pts
			(xy 234.623102 -85.19668) (xy 234.60075 -85.158326) (xy 234.438698 -85.055456) (xy 234.247436 -85.165946)
			(xy 234.255564 -85.357716) (xy 234.277662 -85.39607)
		)
		(stroke
			(width 0)
			(type solid)
		)
		(fill yes)
		(layer "In4.Cu")
		(net "M_E_DQ<6>")
	)
	(gr_poly
		(pts
			(xy 234.623102 -84.20608) (xy 234.60075 -84.167726) (xy 234.438698 -84.064856) (xy 234.247436 -84.175346)
			(xy 234.255564 -84.367116) (xy 234.277662 -84.40547)
		)
		(stroke
			(width 0)
			(type solid)
		)
		(fill yes)
		(layer "In4.Cu")
		(net "M_E_DQS_DN<0>")
	)
	(gr_poly
		(pts
			(xy 234.623102 -83.21548) (xy 234.60075 -83.177126) (xy 234.438698 -83.074256) (xy 234.247436 -83.184746)
			(xy 234.255564 -83.376516) (xy 234.277662 -83.41487)
		)
		(stroke
			(width 0)
			(type solid)
		)
		(fill yes)
		(layer "In4.Cu")
		(net "M_E_DQS_DP<9>")
	)
	(gr_poly
		(pts
			(xy 234.623102 -81.23428) (xy 234.60075 -81.195926) (xy 234.438698 -81.093056) (xy 234.247436 -81.203546)
			(xy 234.255564 -81.395316) (xy 234.277662 -81.43367)
		)
		(stroke
			(width 0)
			(type solid)
		)
		(fill yes)
		(layer "In4.Cu")
		(net "M_E_DQ<4>")
	)
	(gr_poly
		(pts
			(xy 234.630722 -82.220308) (xy 234.608624 -82.181954) (xy 234.446572 -82.07883) (xy 234.255056 -82.18932)
			(xy 234.263184 -82.381344) (xy 234.285536 -82.419698)
		)
		(stroke
			(width 0)
			(type solid)
		)
		(fill yes)
		(layer "In4.Cu")
		(net "M_E_DQ<0>")
	)
	(gr_poly
		(pts
			(xy 234.700572 -60.653676) (xy 234.700572 -60.432696) (xy 234.530392 -60.343796) (xy 234.485942 -60.343796)
			(xy 234.485942 -60.742576) (xy 234.530392 -60.742576)
		)
		(stroke
			(width 0)
			(type solid)
		)
		(fill yes)
		(layer "In4.Cu")
		(net "M_B_DQS_DN<1>")
	)
	(gr_poly
		(pts
			(xy 234.714796 -50.5079) (xy 234.746038 -50.476404) (xy 234.458764 -50.18913) (xy 234.427268 -50.220626)
			(xy 234.353608 -50.420016) (xy 234.515406 -50.58156)
		)
		(stroke
			(width 0)
			(type solid)
		)
		(fill yes)
		(layer "In4.Cu")
		(net "M_B_DQ<16>")
	)
	(gr_poly
		(pts
			(xy 234.878118 -49.52746) (xy 234.909614 -49.495964) (xy 234.62234 -49.20869) (xy 234.590844 -49.240186)
			(xy 234.517184 -49.439322) (xy 234.678982 -49.60112)
		)
		(stroke
			(width 0)
			(type solid)
		)
		(fill yes)
		(layer "In4.Cu")
		(net "M_B_DQS_DP<11>")
	)
	(gr_poly
		(pts
			(xy 234.9119 -50.310542) (xy 234.98556 -50.111152) (xy 234.824016 -49.949608) (xy 234.624626 -50.023268)
			(xy 234.59313 -50.054764) (xy 234.880404 -50.342038)
		)
		(stroke
			(width 0)
			(type solid)
		)
		(fill yes)
		(layer "In4.Cu")
		(net "M_B_DQ<17>")
	)
	(gr_poly
		(pts
			(xy 235.02112 -92.0369) (xy 234.97667 -92.0369) (xy 234.80649 -92.1258) (xy 234.80649 -92.34678)
			(xy 234.97667 -92.43568) (xy 235.02112 -92.43568)
		)
		(stroke
			(width 0)
			(type solid)
		)
		(fill yes)
		(layer "In4.Cu")
		(net "M_E_DQ<14>")
	)
	(gr_poly
		(pts
			(xy 235.02112 -60.343796) (xy 234.97667 -60.343796) (xy 234.80649 -60.432696) (xy 234.80649 -60.653676)
			(xy 234.97667 -60.742576) (xy 235.02112 -60.742576)
		)
		(stroke
			(width 0)
			(type solid)
		)
		(fill yes)
		(layer "In4.Cu")
		(net "M_B_DQ<14>")
	)
	(gr_poly
		(pts
			(xy 235.02112 -59.353196) (xy 234.97667 -59.353196) (xy 234.80649 -59.442096) (xy 234.80649 -59.663076)
			(xy 234.97667 -59.751976) (xy 235.02112 -59.751976)
		)
		(stroke
			(width 0)
			(type solid)
		)
		(fill yes)
		(layer "In4.Cu")
		(net "M_B_DQ<14>")
	)
	(gr_poly
		(pts
			(xy 235.02112 -58.362596) (xy 234.97667 -58.362596) (xy 234.80649 -58.451496) (xy 234.80649 -58.672476)
			(xy 234.97667 -58.761376) (xy 235.02112 -58.761376)
		)
		(stroke
			(width 0)
			(type solid)
		)
		(fill yes)
		(layer "In4.Cu")
		(net "M_B_DQ<14>")
	)
	(gr_poly
		(pts
			(xy 235.02112 -57.371996) (xy 234.97667 -57.371996) (xy 234.80649 -57.460896) (xy 234.80649 -57.681876)
			(xy 234.97667 -57.770776) (xy 235.02112 -57.770776)
		)
		(stroke
			(width 0)
			(type solid)
		)
		(fill yes)
		(layer "In4.Cu")
		(net "M_B_DQ<14>")
	)
	(gr_poly
		(pts
			(xy 235.02112 -56.381396) (xy 234.97667 -56.381396) (xy 234.80649 -56.470296) (xy 234.80649 -56.691276)
			(xy 234.97667 -56.780176) (xy 235.02112 -56.780176)
		)
		(stroke
			(width 0)
			(type solid)
		)
		(fill yes)
		(layer "In4.Cu")
		(net "M_B_DQ<14>")
	)
	(gr_poly
		(pts
			(xy 235.07573 -49.329848) (xy 235.14939 -49.130458) (xy 234.987846 -48.968914) (xy 234.788456 -49.042574)
			(xy 234.75696 -49.073816) (xy 235.044488 -49.361344)
		)
		(stroke
			(width 0)
			(type solid)
		)
		(fill yes)
		(layer "In4.Cu")
		(net "M_B_DQS_DN<11>")
	)
	(gr_poly
		(pts
			(xy 235.211874 -91.04757) (xy 235.167424 -91.04757) (xy 234.997244 -91.13647) (xy 234.997244 -91.35745)
			(xy 235.167424 -91.44635) (xy 235.211874 -91.44635)
		)
		(stroke
			(width 0)
			(type solid)
		)
		(fill yes)
		(layer "In4.Cu")
		(net "M_E_DQ<14>")
	)
	(gr_poly
		(pts
			(xy 235.244132 -82.381344) (xy 235.25226 -82.18932) (xy 235.060744 -82.07883) (xy 234.898692 -82.181954)
			(xy 234.876594 -82.220308) (xy 235.22178 -82.419698)
		)
		(stroke
			(width 0)
			(type solid)
		)
		(fill yes)
		(layer "In4.Cu")
		(net "M_E_DQ<0>")
	)
	(gr_poly
		(pts
			(xy 235.249466 -51.676046) (xy 235.257594 -51.484276) (xy 235.066332 -51.373786) (xy 234.90428 -51.476656)
			(xy 234.881928 -51.51501) (xy 235.227368 -51.714654)
		)
		(stroke
			(width 0)
			(type solid)
		)
		(fill yes)
		(layer "In4.Cu")
		(net "M_B_DQ<21>")
	)
	(gr_poly
		(pts
			(xy 235.25099 -61.582808) (xy 235.259118 -61.391038) (xy 235.067856 -61.280548) (xy 234.905804 -61.383418)
			(xy 234.883452 -61.421772) (xy 235.228892 -61.621162)
		)
		(stroke
			(width 0)
			(type solid)
		)
		(fill yes)
		(layer "In4.Cu")
		(net "M_B_DQS_DN<1>")
	)
	(gr_poly
		(pts
			(xy 235.251752 -83.376516) (xy 235.25988 -83.184746) (xy 235.068618 -83.074256) (xy 234.906566 -83.177126)
			(xy 234.884214 -83.21548) (xy 235.229654 -83.41487)
		)
		(stroke
			(width 0)
			(type solid)
		)
		(fill yes)
		(layer "In4.Cu")
		(net "M_E_DQS_DP<9>")
	)
	(gr_poly
		(pts
			(xy 235.251752 -81.395316) (xy 235.25988 -81.203546) (xy 235.068618 -81.093056) (xy 234.906566 -81.195926)
			(xy 234.884214 -81.23428) (xy 235.229654 -81.43367)
		)
		(stroke
			(width 0)
			(type solid)
		)
		(fill yes)
		(layer "In4.Cu")
		(net "M_E_DQ<4>")
	)
	(gr_poly
		(pts
			(xy 235.252006 -93.380052) (xy 235.244132 -93.188282) (xy 235.222034 -93.149674) (xy 234.876594 -93.349318)
			(xy 234.898946 -93.387418) (xy 235.060744 -93.490542)
		)
		(stroke
			(width 0)
			(type solid)
		)
		(fill yes)
		(layer "In4.Cu")
		(net "M_E_DQ<15>")
	)
	(gr_poly
		(pts
			(xy 235.25226 -70.596506) (xy 235.244132 -70.404482) (xy 235.22178 -70.366128) (xy 234.876594 -70.565518)
			(xy 234.898692 -70.603872) (xy 235.060744 -70.706996)
		)
		(stroke
			(width 0)
			(type solid)
		)
		(fill yes)
		(layer "In4.Cu")
		(net "M_B_DQ<4>")
	)
	(gr_poly
		(pts
			(xy 235.25988 -100.30968) (xy 235.251752 -100.11791) (xy 235.229654 -100.079302) (xy 234.884214 -100.278946)
			(xy 234.906566 -100.3173) (xy 235.068618 -100.42017)
		)
		(stroke
			(width 0)
			(type solid)
		)
		(fill yes)
		(layer "In4.Cu")
		(net "M_E_DQ<21>")
	)
	(gr_poly
		(pts
			(xy 235.25988 -68.610226) (xy 235.251752 -68.418456) (xy 235.229654 -68.379848) (xy 234.884214 -68.579238)
			(xy 234.906566 -68.617846) (xy 235.068618 -68.720716)
		)
		(stroke
			(width 0)
			(type solid)
		)
		(fill yes)
		(layer "In4.Cu")
		(net "M_B_DQS_DP<9>")
	)
	(gr_poly
		(pts
			(xy 235.261404 -101.299264) (xy 235.253276 -101.107494) (xy 235.231178 -101.068886) (xy 234.885738 -101.26853)
			(xy 234.90809 -101.306884) (xy 235.070142 -101.409754)
		)
		(stroke
			(width 0)
			(type solid)
		)
		(fill yes)
		(layer "In4.Cu")
		(net "M_E_DQ<17>")
	)
	(gr_poly
		(pts
			(xy 235.261404 -95.355664) (xy 235.253276 -95.163894) (xy 235.231178 -95.125286) (xy 234.885738 -95.32493)
			(xy 234.90809 -95.363284) (xy 235.070142 -95.466154)
		)
		(stroke
			(width 0)
			(type solid)
		)
		(fill yes)
		(layer "In4.Cu")
		(net "M_E_DQ<11>")
	)
	(gr_poly
		(pts
			(xy 235.261404 -90.402664) (xy 235.253276 -90.210894) (xy 235.231178 -90.172286) (xy 234.885738 -90.37193)
			(xy 234.90809 -90.410284) (xy 235.070142 -90.513154)
		)
		(stroke
			(width 0)
			(type solid)
		)
		(fill yes)
		(layer "In4.Cu")
		(net "M_E_DQS_DP<1>")
	)
	(gr_poly
		(pts
			(xy 235.261404 -89.412064) (xy 235.253276 -89.220294) (xy 235.231178 -89.181686) (xy 234.885738 -89.38133)
			(xy 234.90809 -89.419684) (xy 235.070142 -89.522554)
		)
		(stroke
			(width 0)
			(type solid)
		)
		(fill yes)
		(layer "In4.Cu")
		(net "M_E_DQS_DN<10>")
	)
	(gr_poly
		(pts
			(xy 235.261404 -88.421464) (xy 235.253276 -88.229694) (xy 235.231178 -88.191086) (xy 234.885738 -88.39073)
			(xy 234.90809 -88.429084) (xy 235.070142 -88.531954)
		)
		(stroke
			(width 0)
			(type solid)
		)
		(fill yes)
		(layer "In4.Cu")
		(net "M_E_DQ<9>")
	)
	(gr_poly
		(pts
			(xy 235.261404 -87.430864) (xy 235.253276 -87.239094) (xy 235.231178 -87.200486) (xy 234.885738 -87.40013)
			(xy 234.90809 -87.438484) (xy 235.070142 -87.541354)
		)
		(stroke
			(width 0)
			(type solid)
		)
		(fill yes)
		(layer "In4.Cu")
		(net "M_E_DQ<13>")
	)
	(gr_poly
		(pts
			(xy 235.261404 -69.600064) (xy 235.253276 -69.408294) (xy 235.231178 -69.369686) (xy 234.885738 -69.56933)
			(xy 234.90809 -69.607684) (xy 235.070142 -69.710554)
		)
		(stroke
			(width 0)
			(type solid)
		)
		(fill yes)
		(layer "In4.Cu")
		(net "M_B_DQ<0>")
	)
	(gr_poly
		(pts
			(xy 235.261404 -67.618864) (xy 235.253276 -67.427094) (xy 235.231178 -67.388486) (xy 234.885738 -67.58813)
			(xy 234.90809 -67.626484) (xy 235.070142 -67.729354)
		)
		(stroke
			(width 0)
			(type solid)
		)
		(fill yes)
		(layer "In4.Cu")
		(net "M_B_DQS_DP<0>")
	)
	(gr_poly
		(pts
			(xy 235.314744 -48.271938) (xy 235.34624 -48.240442) (xy 235.058966 -47.953168) (xy 235.02747 -47.984664)
			(xy 234.95381 -48.1838) (xy 235.115608 -48.345598)
		)
		(stroke
			(width 0)
			(type solid)
		)
		(fill yes)
		(layer "In4.Cu")
		(net "M_B_DQS_DP<2>")
	)
	(gr_poly
		(pts
			(xy 235.377736 -103.1113) (xy 235.34624 -103.080058) (xy 235.14685 -103.006398) (xy 234.985306 -103.167942)
			(xy 235.058966 -103.367332) (xy 235.090208 -103.398828)
		)
		(stroke
			(width 0)
			(type solid)
		)
		(fill yes)
		(layer "In4.Cu")
		(net "M_E_DQS_DN<2>")
	)
	(gr_poly
		(pts
			(xy 235.388912 -92.936822) (xy 235.559092 -92.848176) (xy 235.559092 -92.627196) (xy 235.389166 -92.538296)
			(xy 235.344716 -92.538042) (xy 235.344716 -92.937076)
		)
		(stroke
			(width 0)
			(type solid)
		)
		(fill yes)
		(layer "In4.Cu")
		(net "M_E_DQ<15>")
	)
	(gr_poly
		(pts
			(xy 235.457746 -82.981038) (xy 235.480098 -82.94243) (xy 235.134658 -82.743294) (xy 235.11256 -82.781648)
			(xy 235.104432 -82.973418) (xy 235.295694 -83.083908)
		)
		(stroke
			(width 0)
			(type solid)
		)
		(fill yes)
		(layer "In4.Cu")
		(net "M_E_DQ<1>")
	)
	(gr_poly
		(pts
			(xy 235.457746 -52.272438) (xy 235.480098 -52.23383) (xy 235.134658 -52.034694) (xy 235.11256 -52.073048)
			(xy 235.104432 -52.264818) (xy 235.295694 -52.375308)
		)
		(stroke
			(width 0)
			(type solid)
		)
		(fill yes)
		(layer "In4.Cu")
		(net "M_B_DQ<20>")
	)
	(gr_poly
		(pts
			(xy 235.45927 -83.9724) (xy 235.481622 -83.934046) (xy 235.136182 -83.734402) (xy 235.114084 -83.77301)
			(xy 235.105956 -83.96478) (xy 235.297218 -84.07527)
		)
		(stroke
			(width 0)
			(type solid)
		)
		(fill yes)
		(layer "In4.Cu")
		(net "M_E_DQS_DN<9>")
	)
	(gr_poly
		(pts
			(xy 235.45927 -81.9912) (xy 235.481622 -81.952846) (xy 235.136182 -81.753202) (xy 235.114084 -81.79181)
			(xy 235.105956 -81.98358) (xy 235.297218 -82.09407)
		)
		(stroke
			(width 0)
			(type solid)
		)
		(fill yes)
		(layer "In4.Cu")
		(net "M_E_DQ<5>")
	)
	(gr_poly
		(pts
			(xy 235.45927 -51.282854) (xy 235.481622 -51.244246) (xy 235.136182 -51.044856) (xy 235.114084 -51.083464)
			(xy 235.105956 -51.275234) (xy 235.297218 -51.385724)
		)
		(stroke
			(width 0)
			(type solid)
		)
		(fill yes)
		(layer "In4.Cu")
		(net "M_B_DQ<16>")
	)
	(gr_poly
		(pts
			(xy 235.462572 -63.950342) (xy 235.486448 -63.91275) (xy 235.14812 -63.701168) (xy 235.124752 -63.739014)
			(xy 235.109766 -63.930276) (xy 235.297218 -64.04737)
		)
		(stroke
			(width 0)
			(type solid)
		)
		(fill yes)
		(layer "In4.Cu")
		(net "M_B_DQ<8>")
	)
	(gr_poly
		(pts
			(xy 235.466636 -62.183518) (xy 235.488988 -62.145164) (xy 235.143548 -61.94552) (xy 235.12145 -61.984128)
			(xy 235.113322 -62.175898) (xy 235.304584 -62.286388)
		)
		(stroke
			(width 0)
			(type solid)
		)
		(fill yes)
		(layer "In4.Cu")
		(net "M_B_DQS_DP<1>")
	)
	(gr_poly
		(pts
			(xy 235.472478 -55.25516) (xy 235.49483 -55.21706) (xy 235.151422 -55.014622) (xy 235.128816 -55.05323)
			(xy 235.119164 -55.244746) (xy 235.30941 -55.357014)
		)
		(stroke
			(width 0)
			(type solid)
		)
		(fill yes)
		(layer "In4.Cu")
		(net "M_B_DQ<10>")
	)
	(gr_poly
		(pts
			(xy 235.47959 -63.106046) (xy 235.451904 -63.070994) (xy 235.277152 -62.991492) (xy 235.103162 -63.127636)
			(xy 235.137706 -63.316358) (xy 235.165138 -63.35141)
		)
		(stroke
			(width 0)
			(type solid)
		)
		(fill yes)
		(layer "In4.Cu")
		(net "M_B_DQ<9>")
	)
	(gr_poly
		(pts
			(xy 235.480098 -89.65565) (xy 235.457746 -89.617042) (xy 235.295694 -89.514172) (xy 235.104432 -89.624662)
			(xy 235.11256 -89.816432) (xy 235.134658 -89.85504)
		)
		(stroke
			(width 0)
			(type solid)
		)
		(fill yes)
		(layer "In4.Cu")
		(net "M_E_DQS_DN<1>")
	)
	(gr_poly
		(pts
			(xy 235.480098 -88.66505) (xy 235.457746 -88.626442) (xy 235.295694 -88.523572) (xy 235.104432 -88.634062)
			(xy 235.11256 -88.825832) (xy 235.134658 -88.86444)
		)
		(stroke
			(width 0)
			(type solid)
		)
		(fill yes)
		(layer "In4.Cu")
		(net "M_E_DQS_DP<10>")
	)
	(gr_poly
		(pts
			(xy 235.480098 -87.67445) (xy 235.457746 -87.635842) (xy 235.295694 -87.532972) (xy 235.104432 -87.643462)
			(xy 235.11256 -87.835232) (xy 235.134658 -87.87384)
		)
		(stroke
			(width 0)
			(type solid)
		)
		(fill yes)
		(layer "In4.Cu")
		(net "M_E_DQ<8>")
	)
	(gr_poly
		(pts
			(xy 235.480098 -86.68385) (xy 235.457746 -86.645242) (xy 235.295694 -86.542372) (xy 235.104432 -86.652862)
			(xy 235.11256 -86.844632) (xy 235.134658 -86.88324)
		)
		(stroke
			(width 0)
			(type solid)
		)
		(fill yes)
		(layer "In4.Cu")
		(net "M_E_DQ<12>")
	)
	(gr_poly
		(pts
			(xy 235.480098 -85.69325) (xy 235.457746 -85.654642) (xy 235.295694 -85.551772) (xy 235.104432 -85.662262)
			(xy 235.11256 -85.854032) (xy 235.134658 -85.89264)
		)
		(stroke
			(width 0)
			(type solid)
		)
		(fill yes)
		(layer "In4.Cu")
		(net "M_E_DQ<2>")
	)
	(gr_poly
		(pts
			(xy 235.480098 -69.84365) (xy 235.457746 -69.805042) (xy 235.295694 -69.702172) (xy 235.104432 -69.812662)
			(xy 235.11256 -70.004432) (xy 235.134658 -70.04304)
		)
		(stroke
			(width 0)
			(type solid)
		)
		(fill yes)
		(layer "In4.Cu")
		(net "M_B_DQ<5>")
	)
	(gr_poly
		(pts
			(xy 235.480098 -68.85305) (xy 235.457746 -68.814442) (xy 235.295694 -68.711572) (xy 235.104432 -68.822062)
			(xy 235.11256 -69.013832) (xy 235.134658 -69.05244)
		)
		(stroke
			(width 0)
			(type solid)
		)
		(fill yes)
		(layer "In4.Cu")
		(net "M_B_DQ<1>")
	)
	(gr_poly
		(pts
			(xy 235.480098 -66.87185) (xy 235.457746 -66.833242) (xy 235.295694 -66.730372) (xy 235.104432 -66.840862)
			(xy 235.11256 -67.032632) (xy 235.134658 -67.07124)
		)
		(stroke
			(width 0)
			(type solid)
		)
		(fill yes)
		(layer "In4.Cu")
		(net "M_B_DQS_DN<0>")
	)
	(gr_poly
		(pts
			(xy 235.481622 -99.56038) (xy 235.45927 -99.522026) (xy 235.297218 -99.419156) (xy 235.105956 -99.529646)
			(xy 235.114084 -99.721416) (xy 235.136182 -99.75977)
		)
		(stroke
			(width 0)
			(type solid)
		)
		(fill yes)
		(layer "In4.Cu")
		(net "M_E_DQ<20>")
	)
	(gr_poly
		(pts
			(xy 235.483908 -100.54971) (xy 235.461556 -100.511356) (xy 235.299504 -100.408486) (xy 235.108242 -100.518976)
			(xy 235.11637 -100.710746) (xy 235.138468 -100.749354)
		)
		(stroke
			(width 0)
			(type solid)
		)
		(fill yes)
		(layer "In4.Cu")
		(net "M_E_DQ<16>")
	)
	(gr_poly
		(pts
			(xy 235.483908 -94.60611) (xy 235.461556 -94.567756) (xy 235.299504 -94.464886) (xy 235.108242 -94.575376)
			(xy 235.11637 -94.767146) (xy 235.138468 -94.805754)
		)
		(stroke
			(width 0)
			(type solid)
		)
		(fill yes)
		(layer "In4.Cu")
		(net "M_E_DQ<10>")
	)
	(gr_poly
		(pts
			(xy 235.512356 -48.074326) (xy 235.586016 -47.874936) (xy 235.424472 -47.713392) (xy 235.225082 -47.787052)
			(xy 235.193586 -47.818294) (xy 235.481114 -48.105822)
		)
		(stroke
			(width 0)
			(type solid)
		)
		(fill yes)
		(layer "In4.Cu")
		(net "M_B_DQS_DN<2>")
	)
	(gr_poly
		(pts
			(xy 235.559346 -60.158376) (xy 235.559346 -59.937396) (xy 235.389166 -59.848496) (xy 235.344716 -59.848496)
			(xy 235.344716 -60.247276) (xy 235.389166 -60.247276)
		)
		(stroke
			(width 0)
			(type solid)
		)
		(fill yes)
		(layer "In4.Cu")
		(net "M_B_DQ<15>")
	)
	(gr_poly
		(pts
			(xy 235.559346 -59.167776) (xy 235.559346 -58.946796) (xy 235.389166 -58.857896) (xy 235.344716 -58.857896)
			(xy 235.344716 -59.256676) (xy 235.389166 -59.256676)
		)
		(stroke
			(width 0)
			(type solid)
		)
		(fill yes)
		(layer "In4.Cu")
		(net "M_B_DQ<15>")
	)
	(gr_poly
		(pts
			(xy 235.559346 -58.177176) (xy 235.559346 -57.956196) (xy 235.389166 -57.867296) (xy 235.344716 -57.867296)
			(xy 235.344716 -58.266076) (xy 235.389166 -58.266076)
		)
		(stroke
			(width 0)
			(type solid)
		)
		(fill yes)
		(layer "In4.Cu")
		(net "M_B_DQ<15>")
	)
	(gr_poly
		(pts
			(xy 235.559346 -57.186576) (xy 235.559346 -56.965596) (xy 235.389166 -56.876696) (xy 235.344716 -56.876696)
			(xy 235.344716 -57.275476) (xy 235.389166 -57.275476)
		)
		(stroke
			(width 0)
			(type solid)
		)
		(fill yes)
		(layer "In4.Cu")
		(net "M_B_DQ<15>")
	)
	(gr_poly
		(pts
			(xy 235.559346 -56.202326) (xy 235.559346 -55.981346) (xy 235.389166 -55.892446) (xy 235.344716 -55.892446)
			(xy 235.344716 -56.291226) (xy 235.389166 -56.291226)
		)
		(stroke
			(width 0)
			(type solid)
		)
		(fill yes)
		(layer "In4.Cu")
		(net "M_B_DQ<15>")
	)
	(gr_poly
		(pts
			(xy 235.617512 -103.476806) (xy 235.543852 -103.27767) (xy 235.512356 -103.246174) (xy 235.225082 -103.533448)
			(xy 235.256578 -103.564944) (xy 235.455714 -103.638604)
		)
		(stroke
			(width 0)
			(type solid)
		)
		(fill yes)
		(layer "In4.Cu")
		(net "M_E_DQS_DP<2>")
	)
	(gr_poly
		(pts
			(xy 235.637324 -101.744272) (xy 235.605828 -101.712776) (xy 235.406692 -101.639116) (xy 235.244894 -101.800914)
			(xy 235.318554 -102.00005) (xy 235.35005 -102.031546)
		)
		(stroke
			(width 0)
			(type solid)
		)
		(fill yes)
		(layer "In4.Cu")
		(net "M_E_DQS_DP<11>")
	)
	(gr_poly
		(pts
			(xy 235.8771 -102.109778) (xy 235.80344 -101.910388) (xy 235.772198 -101.878892) (xy 235.48467 -102.16642)
			(xy 235.516166 -102.197662) (xy 235.715556 -102.271322)
		)
		(stroke
			(width 0)
			(type solid)
		)
		(fill yes)
		(layer "In4.Cu")
		(net "M_E_DQS_DN<11>")
	)
	(gr_poly
		(pts
			(xy 235.87964 -93.5228) (xy 235.83519 -93.5228) (xy 235.66501 -93.6117) (xy 235.66501 -93.83268)
			(xy 235.83519 -93.92158) (xy 235.87964 -93.92158)
		)
		(stroke
			(width 0)
			(type solid)
		)
		(fill yes)
		(layer "In4.Cu")
		(net "M_E_DQ<10>")
	)
	(gr_poly
		(pts
			(xy 235.87964 -92.544646) (xy 235.83519 -92.544646) (xy 235.66501 -92.633546) (xy 235.66501 -92.854526)
			(xy 235.83519 -92.943426) (xy 235.87964 -92.943426)
		)
		(stroke
			(width 0)
			(type solid)
		)
		(fill yes)
		(layer "In4.Cu")
		(net "M_E_DQ<10>")
	)
	(gr_poly
		(pts
			(xy 235.87964 -59.848496) (xy 235.83519 -59.848496) (xy 235.66501 -59.937396) (xy 235.66501 -60.158376)
			(xy 235.83519 -60.247276) (xy 235.87964 -60.247276)
		)
		(stroke
			(width 0)
			(type solid)
		)
		(fill yes)
		(layer "In4.Cu")
		(net "M_B_DQ<10>")
	)
	(gr_poly
		(pts
			(xy 235.87964 -58.857896) (xy 235.83519 -58.857896) (xy 235.66501 -58.946796) (xy 235.66501 -59.167776)
			(xy 235.83519 -59.256676) (xy 235.87964 -59.256676)
		)
		(stroke
			(width 0)
			(type solid)
		)
		(fill yes)
		(layer "In4.Cu")
		(net "M_B_DQ<10>")
	)
	(gr_poly
		(pts
			(xy 235.87964 -57.8612) (xy 235.83519 -57.8612) (xy 235.66501 -57.9501) (xy 235.66501 -58.17108)
			(xy 235.83519 -58.25998) (xy 235.87964 -58.25998)
		)
		(stroke
			(width 0)
			(type solid)
		)
		(fill yes)
		(layer "In4.Cu")
		(net "M_B_DQ<10>")
	)
	(gr_poly
		(pts
			(xy 235.87964 -56.883046) (xy 235.83519 -56.883046) (xy 235.66501 -56.971946) (xy 235.66501 -57.192926)
			(xy 235.83519 -57.281826) (xy 235.87964 -57.281826)
		)
		(stroke
			(width 0)
			(type solid)
		)
		(fill yes)
		(layer "In4.Cu")
		(net "M_B_DQ<10>")
	)
	(gr_poly
		(pts
			(xy 235.87964 -55.892446) (xy 235.83519 -55.892446) (xy 235.66501 -55.981346) (xy 235.66501 -56.202326)
			(xy 235.83519 -56.291226) (xy 235.87964 -56.291226)
		)
		(stroke
			(width 0)
			(type solid)
		)
		(fill yes)
		(layer "In4.Cu")
		(net "M_B_DQ<10>")
	)
	(gr_poly
		(pts
			(xy 235.993432 -49.879504) (xy 235.993432 -49.835054) (xy 235.587032 -49.835054) (xy 235.587032 -49.879504)
			(xy 235.675932 -50.072544) (xy 235.904532 -50.072544)
		)
		(stroke
			(width 0)
			(type solid)
		)
		(fill yes)
		(layer "In4.Cu")
		(net "M_B_DQS_DP<11>")
	)
	(gr_poly
		(pts
			(xy 235.993432 -49.600104) (xy 235.904532 -49.407064) (xy 235.675932 -49.407064) (xy 235.587032 -49.600104)
			(xy 235.587032 -49.644554) (xy 235.993432 -49.644554)
		)
		(stroke
			(width 0)
			(type solid)
		)
		(fill yes)
		(layer "In4.Cu")
		(net "M_B_DQS_DN<11>")
	)
	(gr_poly
		(pts
			(xy 236.103668 -89.915746) (xy 236.09554 -89.723976) (xy 236.073442 -89.685368) (xy 235.728002 -89.885012)
			(xy 235.750354 -89.923366) (xy 235.912406 -90.026236)
		)
		(stroke
			(width 0)
			(type solid)
		)
		(fill yes)
		(layer "In4.Cu")
		(net "M_E_DQS_DP<1>")
	)
	(gr_poly
		(pts
			(xy 236.109256 -91.552268) (xy 236.069378 -91.532202) (xy 235.877608 -91.534742) (xy 235.777786 -91.731846)
			(xy 235.889546 -91.888056) (xy 235.92917 -91.908122)
		)
		(stroke
			(width 0)
			(type solid)
		)
		(fill yes)
		(layer "In4.Cu")
		(net "M_E_DQ<10>")
	)
	(gr_poly
		(pts
			(xy 236.110526 -94.865952) (xy 236.102652 -94.674182) (xy 236.0803 -94.635574) (xy 235.73486 -94.834964)
			(xy 235.757466 -94.873318) (xy 235.919264 -94.976442)
		)
		(stroke
			(width 0)
			(type solid)
		)
		(fill yes)
		(layer "In4.Cu")
		(net "M_E_DQ<11>")
	)
	(gr_poly
		(pts
			(xy 236.11078 -62.175898) (xy 236.102652 -61.984128) (xy 236.080554 -61.94552) (xy 235.735114 -62.14491)
			(xy 235.757466 -62.183518) (xy 235.919518 -62.286388)
		)
		(stroke
			(width 0)
			(type solid)
		)
		(fill yes)
		(layer "In4.Cu")
		(net "M_B_DQS_DP<1>")
	)
	(gr_poly
		(pts
			(xy 236.111796 -88.825832) (xy 236.119924 -88.634062) (xy 235.928662 -88.523572) (xy 235.76661 -88.626442)
			(xy 235.744258 -88.66505) (xy 236.089698 -88.86444)
		)
		(stroke
			(width 0)
			(type solid)
		)
		(fill yes)
		(layer "In4.Cu")
		(net "M_E_DQS_DP<10>")
	)
	(gr_poly
		(pts
			(xy 236.111796 -87.835232) (xy 236.119924 -87.643462) (xy 235.928662 -87.532972) (xy 235.76661 -87.635842)
			(xy 235.744258 -87.67445) (xy 236.089698 -87.87384)
		)
		(stroke
			(width 0)
			(type solid)
		)
		(fill yes)
		(layer "In4.Cu")
		(net "M_E_DQ<8>")
	)
	(gr_poly
		(pts
			(xy 236.111796 -86.844632) (xy 236.119924 -86.652862) (xy 235.928662 -86.542372) (xy 235.76661 -86.645242)
			(xy 235.744258 -86.68385) (xy 236.089698 -86.88324)
		)
		(stroke
			(width 0)
			(type solid)
		)
		(fill yes)
		(layer "In4.Cu")
		(net "M_E_DQ<12>")
	)
	(gr_poly
		(pts
			(xy 236.111796 -85.854032) (xy 236.119924 -85.662262) (xy 235.928662 -85.551772) (xy 235.76661 -85.654642)
			(xy 235.744258 -85.69325) (xy 236.089698 -85.89264)
		)
		(stroke
			(width 0)
			(type solid)
		)
		(fill yes)
		(layer "In4.Cu")
		(net "M_E_DQ<2>")
	)
	(gr_poly
		(pts
			(xy 236.111796 -83.872832) (xy 236.119924 -83.681062) (xy 235.928662 -83.570572) (xy 235.76661 -83.673442)
			(xy 235.744258 -83.71205) (xy 236.089698 -83.91144)
		)
		(stroke
			(width 0)
			(type solid)
		)
		(fill yes)
		(layer "In4.Cu")
		(net "M_E_DQS_DP<9>")
	)
	(gr_poly
		(pts
			(xy 236.111796 -82.882232) (xy 236.119924 -82.690462) (xy 235.928662 -82.579972) (xy 235.76661 -82.682842)
			(xy 235.744258 -82.72145) (xy 236.089698 -82.92084)
		)
		(stroke
			(width 0)
			(type solid)
		)
		(fill yes)
		(layer "In4.Cu")
		(net "M_E_DQ<0>")
	)
	(gr_poly
		(pts
			(xy 236.111796 -81.891632) (xy 236.119924 -81.699862) (xy 235.928662 -81.589372) (xy 235.76661 -81.692242)
			(xy 235.744258 -81.73085) (xy 236.089698 -81.93024)
		)
		(stroke
			(width 0)
			(type solid)
		)
		(fill yes)
		(layer "In4.Cu")
		(net "M_E_DQ<4>")
	)
	(gr_poly
		(pts
			(xy 236.116114 -100.80625) (xy 236.107986 -100.61448) (xy 236.085888 -100.575872) (xy 235.740448 -100.775262)
			(xy 235.7628 -100.81387) (xy 235.924852 -100.91674)
		)
		(stroke
			(width 0)
			(type solid)
		)
		(fill yes)
		(layer "In4.Cu")
		(net "M_E_DQ<17>")
	)
	(gr_poly
		(pts
			(xy 236.116622 -67.125596) (xy 236.108494 -66.933826) (xy 236.086396 -66.895218) (xy 235.740956 -67.094862)
			(xy 235.763308 -67.133216) (xy 235.92536 -67.236086)
		)
		(stroke
			(width 0)
			(type solid)
		)
		(fill yes)
		(layer "In4.Cu")
		(net "M_B_DQS_DP<0>")
	)
	(gr_poly
		(pts
			(xy 236.1184 -70.09638) (xy 236.110272 -69.90461) (xy 236.088174 -69.866002) (xy 235.742734 -70.065646)
			(xy 235.765086 -70.104) (xy 235.927138 -70.20687)
		)
		(stroke
			(width 0)
			(type solid)
		)
		(fill yes)
		(layer "In4.Cu")
		(net "M_B_DQ<4>")
	)
	(gr_poly
		(pts
			(xy 236.1184 -69.10578) (xy 236.110272 -68.91401) (xy 236.088174 -68.875402) (xy 235.742734 -69.075046)
			(xy 235.765086 -69.1134) (xy 235.927138 -69.21627)
		)
		(stroke
			(width 0)
			(type solid)
		)
		(fill yes)
		(layer "In4.Cu")
		(net "M_B_DQ<0>")
	)
	(gr_poly
		(pts
			(xy 236.1184 -66.13398) (xy 236.110272 -65.94221) (xy 236.088174 -65.903602) (xy 235.742734 -66.103246)
			(xy 235.765086 -66.1416) (xy 235.927138 -66.24447)
		)
		(stroke
			(width 0)
			(type solid)
		)
		(fill yes)
		(layer "In4.Cu")
		(net "M_B_DQ<7>")
	)
	(gr_poly
		(pts
			(xy 236.1184 -64.15278) (xy 236.110272 -63.96101) (xy 236.088174 -63.922402) (xy 235.742734 -64.122046)
			(xy 235.765086 -64.1604) (xy 235.927138 -64.26327)
		)
		(stroke
			(width 0)
			(type solid)
		)
		(fill yes)
		(layer "In4.Cu")
		(net "M_B_DQ<13>")
	)
	(gr_poly
		(pts
			(xy 236.247432 -94.422722) (xy 236.417612 -94.334076) (xy 236.417612 -94.113096) (xy 236.247686 -94.024196)
			(xy 236.202982 -94.024196) (xy 236.202982 -94.422976)
		)
		(stroke
			(width 0)
			(type solid)
		)
		(fill yes)
		(layer "In4.Cu")
		(net "M_E_DQ<11>")
	)
	(gr_poly
		(pts
			(xy 236.31525 -51.562762) (xy 236.337602 -51.524408) (xy 235.992162 -51.325018) (xy 235.970064 -51.363372)
			(xy 235.961936 -51.555142) (xy 236.153198 -51.665632)
		)
		(stroke
			(width 0)
			(type solid)
		)
		(fill yes)
		(layer "In4.Cu")
		(net "M_B_DQ<16>")
	)
	(gr_poly
		(pts
			(xy 236.316266 -87.438484) (xy 236.338618 -87.40013) (xy 235.993178 -87.200486) (xy 235.97108 -87.239094)
			(xy 235.962952 -87.430864) (xy 236.154214 -87.541354)
		)
		(stroke
			(width 0)
			(type solid)
		)
		(fill yes)
		(layer "In4.Cu")
		(net "M_E_DQ<13>")
	)
	(gr_poly
		(pts
			(xy 236.316266 -85.457284) (xy 236.338618 -85.41893) (xy 235.993178 -85.219286) (xy 235.97108 -85.257894)
			(xy 235.962952 -85.449664) (xy 236.154214 -85.560154)
		)
		(stroke
			(width 0)
			(type solid)
		)
		(fill yes)
		(layer "In4.Cu")
		(net "M_E_DQ<6>")
	)
	(gr_poly
		(pts
			(xy 236.316266 -84.466684) (xy 236.338618 -84.42833) (xy 235.993178 -84.228686) (xy 235.97108 -84.267294)
			(xy 235.962952 -84.459064) (xy 236.154214 -84.569554)
		)
		(stroke
			(width 0)
			(type solid)
		)
		(fill yes)
		(layer "In4.Cu")
		(net "M_E_DQS_DN<9>")
	)
	(gr_poly
		(pts
			(xy 236.320076 -82.48777) (xy 236.342428 -82.449162) (xy 235.996988 -82.249772) (xy 235.97489 -82.28838)
			(xy 235.966762 -82.48015) (xy 236.158024 -82.59064)
		)
		(stroke
			(width 0)
			(type solid)
		)
		(fill yes)
		(layer "In4.Cu")
		(net "M_E_DQ<5>")
	)
	(gr_poly
		(pts
			(xy 236.338618 -100.056442) (xy 236.316266 -100.018088) (xy 236.154214 -99.915218) (xy 235.962952 -100.025708)
			(xy 235.97108 -100.217478) (xy 235.993178 -100.256086)
		)
		(stroke
			(width 0)
			(type solid)
		)
		(fill yes)
		(layer "In4.Cu")
		(net "M_E_DQ<16>")
	)
	(gr_poly
		(pts
			(xy 236.340142 -101.04628) (xy 236.31779 -101.007926) (xy 236.155738 -100.905056) (xy 235.964476 -101.015546)
			(xy 235.972604 -101.207316) (xy 235.994702 -101.24567)
		)
		(stroke
			(width 0)
			(type solid)
		)
		(fill yes)
		(layer "In4.Cu")
		(net "M_E_DQS_DP<11>")
	)
	(gr_poly
		(pts
			(xy 236.340142 -69.34708) (xy 236.31779 -69.308726) (xy 236.155738 -69.205856) (xy 235.964476 -69.316346)
			(xy 235.972604 -69.508116) (xy 235.994702 -69.54647)
		)
		(stroke
			(width 0)
			(type solid)
		)
		(fill yes)
		(layer "In4.Cu")
		(net "M_B_DQ<5>")
	)
	(gr_poly
		(pts
			(xy 236.34192 -61.421264) (xy 236.319568 -61.38291) (xy 236.157516 -61.28004) (xy 235.966254 -61.39053)
			(xy 235.974382 -61.5823) (xy 235.99648 -61.620908)
		)
		(stroke
			(width 0)
			(type solid)
		)
		(fill yes)
		(layer "In4.Cu")
		(net "M_B_DQS_DN<1>")
	)
	(gr_poly
		(pts
			(xy 236.347508 -66.370962) (xy 236.325156 -66.332608) (xy 236.163104 -66.229738) (xy 235.971842 -66.340228)
			(xy 235.97997 -66.531998) (xy 236.002068 -66.570606)
		)
		(stroke
			(width 0)
			(type solid)
		)
		(fill yes)
		(layer "In4.Cu")
		(net "M_B_DQS_DN<0>")
	)
	(gr_poly
		(pts
			(xy 236.417866 -93.34373) (xy 236.417866 -93.12275) (xy 236.247686 -93.03385) (xy 236.203236 -93.03385)
			(xy 236.203236 -93.43263) (xy 236.247686 -93.43263)
		)
		(stroke
			(width 0)
			(type solid)
		)
		(fill yes)
		(layer "In4.Cu")
		(net "M_E_DQ<11>")
	)
	(gr_poly
		(pts
			(xy 236.417866 -59.65698) (xy 236.417866 -59.436) (xy 236.247686 -59.3471) (xy 236.203236 -59.3471)
			(xy 236.203236 -59.74588) (xy 236.247686 -59.74588)
		)
		(stroke
			(width 0)
			(type solid)
		)
		(fill yes)
		(layer "In4.Cu")
		(net "M_B_DQ<11>")
	)
	(gr_poly
		(pts
			(xy 236.417866 -58.678826) (xy 236.417866 -58.457846) (xy 236.247686 -58.368946) (xy 236.203236 -58.368946)
			(xy 236.203236 -58.767726) (xy 236.247686 -58.767726)
		)
		(stroke
			(width 0)
			(type solid)
		)
		(fill yes)
		(layer "In4.Cu")
		(net "M_B_DQ<11>")
	)
	(gr_poly
		(pts
			(xy 236.417866 -57.68213) (xy 236.417866 -57.46115) (xy 236.247686 -57.37225) (xy 236.203236 -57.37225)
			(xy 236.203236 -57.77103) (xy 236.247686 -57.77103)
		)
		(stroke
			(width 0)
			(type solid)
		)
		(fill yes)
		(layer "In4.Cu")
		(net "M_B_DQ<11>")
	)
	(gr_poly
		(pts
			(xy 236.417866 -56.68518) (xy 236.417866 -56.4642) (xy 236.247686 -56.3753) (xy 236.203236 -56.3753)
			(xy 236.203236 -56.77408) (xy 236.247686 -56.77408)
		)
		(stroke
			(width 0)
			(type solid)
		)
		(fill yes)
		(layer "In4.Cu")
		(net "M_B_DQ<11>")
	)
	(gr_poly
		(pts
			(xy 236.417866 -55.69458) (xy 236.417866 -55.4736) (xy 236.247686 -55.3847) (xy 236.203236 -55.3847)
			(xy 236.203236 -55.78348) (xy 236.247686 -55.78348)
		)
		(stroke
			(width 0)
			(type solid)
		)
		(fill yes)
		(layer "In4.Cu")
		(net "M_B_DQ<11>")
	)
	(gr_poly
		(pts
			(xy 236.42955 -92.383356) (xy 236.52226 -92.182696) (xy 236.405166 -92.030804) (xy 236.36478 -92.012008)
			(xy 236.197394 -92.373958) (xy 236.23778 -92.392754)
		)
		(stroke
			(width 0)
			(type solid)
		)
		(fill yes)
		(layer "In4.Cu")
		(net "M_E_DQ<11>")
	)
	(gr_poly
		(pts
			(xy 236.495336 -102.2731) (xy 236.46384 -102.241858) (xy 236.26445 -102.168198) (xy 236.102906 -102.329742)
			(xy 236.176566 -102.529132) (xy 236.207808 -102.560628)
		)
		(stroke
			(width 0)
			(type solid)
		)
		(fill yes)
		(layer "In4.Cu")
		(net "M_E_DQS_DN<2>")
	)
	(gr_poly
		(pts
			(xy 236.735112 -102.638606) (xy 236.661452 -102.43947) (xy 236.629956 -102.407974) (xy 236.342682 -102.695248)
			(xy 236.374178 -102.726744) (xy 236.573314 -102.800404)
		)
		(stroke
			(width 0)
			(type solid)
		)
		(fill yes)
		(layer "In4.Cu")
		(net "M_E_DQS_DP<2>")
	)
	(gr_poly
		(pts
			(xy 236.73816 -98.97745) (xy 236.69371 -98.97745) (xy 236.52353 -99.06635) (xy 236.52353 -99.28733)
			(xy 236.69371 -99.37623) (xy 236.73816 -99.37623)
		)
		(stroke
			(width 0)
			(type solid)
		)
		(fill yes)
		(layer "In4.Cu")
		(net "M_E_DQ<16>")
	)
	(gr_poly
		(pts
			(xy 236.739684 -52.413662) (xy 236.695234 -52.413662) (xy 236.525054 -52.502562) (xy 236.525054 -52.723542)
			(xy 236.695234 -52.812442) (xy 236.739684 -52.812442)
		)
		(stroke
			(width 0)
			(type solid)
		)
		(fill yes)
		(layer "In4.Cu")
		(net "M_B_DQ<21>")
	)
	(gr_poly
		(pts
			(xy 236.768386 -68.283836) (xy 236.723936 -68.280026) (xy 236.546898 -68.353686) (xy 236.527594 -68.573904)
			(xy 236.689392 -68.677282) (xy 236.733588 -68.681092)
		)
		(stroke
			(width 0)
			(type solid)
		)
		(fill yes)
		(layer "In4.Cu")
		(net "M_B_DQ<5>")
	)
	(gr_poly
		(pts
			(xy 236.84611 -88.524842) (xy 236.94898 -88.36279) (xy 236.838744 -88.171528) (xy 236.646974 -88.179656)
			(xy 236.608366 -88.201754) (xy 236.807756 -88.54694)
		)
		(stroke
			(width 0)
			(type solid)
		)
		(fill yes)
		(layer "In4.Cu")
		(net "M_E_DQ<8>")
	)
	(gr_poly
		(pts
			(xy 236.853984 -48.150272) (xy 236.88548 -48.11903) (xy 236.597952 -47.831502) (xy 236.56671 -47.862998)
			(xy 236.49305 -48.062388) (xy 236.654594 -48.223932)
		)
		(stroke
			(width 0)
			(type solid)
		)
		(fill yes)
		(layer "In4.Cu")
		(net "M_B_DQ<22>")
	)
	(gr_poly
		(pts
			(xy 236.869732 -64.499236) (xy 236.848396 -64.308482) (xy 236.823504 -64.271652) (xy 236.492796 -64.494664)
			(xy 236.517688 -64.531494) (xy 236.686598 -64.62268)
		)
		(stroke
			(width 0)
			(type solid)
		)
		(fill yes)
		(layer "In4.Cu")
		(net "M_B_DQ<12>")
	)
	(gr_poly
		(pts
			(xy 236.870494 -85.521038) (xy 236.878622 -85.329268) (xy 236.68736 -85.218778) (xy 236.525308 -85.321648)
			(xy 236.502956 -85.360002) (xy 236.848396 -85.559646)
		)
		(stroke
			(width 0)
			(type solid)
		)
		(fill yes)
		(layer "In4.Cu")
		(net "M_E_DQ<6>")
	)
	(gr_poly
		(pts
			(xy 236.872272 -50.851054) (xy 236.8804 -50.659284) (xy 236.689138 -50.548794) (xy 236.527086 -50.651664)
			(xy 236.504734 -50.690018) (xy 236.850174 -50.889662)
		)
		(stroke
			(width 0)
			(type solid)
		)
		(fill yes)
		(layer "In4.Cu")
		(net "M_B_DQ<17>")
	)
	(gr_poly
		(pts
			(xy 236.902498 -99.864926) (xy 237.072678 -99.77628) (xy 237.072678 -99.5553) (xy 236.902498 -99.4664)
			(xy 236.858302 -99.466146) (xy 236.858048 -99.86518)
		)
		(stroke
			(width 0)
			(type solid)
		)
		(fill yes)
		(layer "In4.Cu")
		(net "M_E_DQ<16>")
	)
	(gr_poly
		(pts
			(xy 236.942122 -62.733682) (xy 236.94009 -62.541912) (xy 236.743494 -62.441582) (xy 236.58703 -62.55258)
			(xy 236.56671 -62.592458) (xy 236.922056 -62.77356)
		)
		(stroke
			(width 0)
			(type solid)
		)
		(fill yes)
		(layer "In4.Cu")
		(net "M_B_DQ<9>")
	)
	(gr_poly
		(pts
			(xy 236.966506 -82.384646) (xy 236.974634 -82.192876) (xy 236.783372 -82.082386) (xy 236.62132 -82.185256)
			(xy 236.598968 -82.22361) (xy 236.944408 -82.423254)
		)
		(stroke
			(width 0)
			(type solid)
		)
		(fill yes)
		(layer "In4.Cu")
		(net "M_E_DQ<4>")
	)
	(gr_poly
		(pts
			(xy 236.968792 -89.320116) (xy 236.97692 -89.128346) (xy 236.785658 -89.017856) (xy 236.623606 -89.120726)
			(xy 236.601254 -89.15908) (xy 236.946694 -89.35847)
		)
		(stroke
			(width 0)
			(type solid)
		)
		(fill yes)
		(layer "In4.Cu")
		(net "M_E_DQS_DP<10>")
	)
	(gr_poly
		(pts
			(xy 236.968792 -87.338916) (xy 236.97692 -87.147146) (xy 236.785658 -87.036656) (xy 236.623606 -87.139526)
			(xy 236.601254 -87.17788) (xy 236.946694 -87.37727)
		)
		(stroke
			(width 0)
			(type solid)
		)
		(fill yes)
		(layer "In4.Cu")
		(net "M_E_DQ<12>")
	)
	(gr_poly
		(pts
			(xy 236.968792 -84.367116) (xy 236.97692 -84.175346) (xy 236.785658 -84.064856) (xy 236.623606 -84.167726)
			(xy 236.601254 -84.20608) (xy 236.946694 -84.40547)
		)
		(stroke
			(width 0)
			(type solid)
		)
		(fill yes)
		(layer "In4.Cu")
		(net "M_E_DQS_DP<9>")
	)
	(gr_poly
		(pts
			(xy 236.968792 -83.376516) (xy 236.97692 -83.184746) (xy 236.785658 -83.074256) (xy 236.623606 -83.177126)
			(xy 236.601254 -83.21548) (xy 236.946694 -83.41487)
		)
		(stroke
			(width 0)
			(type solid)
		)
		(fill yes)
		(layer "In4.Cu")
		(net "M_E_DQ<0>")
	)
	(gr_poly
		(pts
			(xy 236.975142 -66.630042) (xy 236.967014 -66.438272) (xy 236.944916 -66.399664) (xy 236.599476 -66.599308)
			(xy 236.621828 -66.637662) (xy 236.78388 -66.740532)
		)
		(stroke
			(width 0)
			(type solid)
		)
		(fill yes)
		(layer "In4.Cu")
		(net "M_B_DQS_DP<0>")
	)
	(gr_poly
		(pts
			(xy 236.97692 -69.600826) (xy 236.968792 -69.409056) (xy 236.946694 -69.370448) (xy 236.601254 -69.570092)
			(xy 236.623606 -69.608446) (xy 236.785658 -69.711316)
		)
		(stroke
			(width 0)
			(type solid)
		)
		(fill yes)
		(layer "In4.Cu")
		(net "M_B_DQ<4>")
	)
	(gr_poly
		(pts
			(xy 236.978444 -101.299264) (xy 236.970316 -101.107494) (xy 236.948218 -101.068886) (xy 236.602778 -101.26853)
			(xy 236.62513 -101.306884) (xy 236.787182 -101.409754)
		)
		(stroke
			(width 0)
			(type solid)
		)
		(fill yes)
		(layer "In4.Cu")
		(net "M_E_DQS_DN<11>")
	)
	(gr_poly
		(pts
			(xy 236.978444 -63.656464) (xy 236.970316 -63.464694) (xy 236.948218 -63.426086) (xy 236.602778 -63.62573)
			(xy 236.62513 -63.664084) (xy 236.787182 -63.766954)
		)
		(stroke
			(width 0)
			(type solid)
		)
		(fill yes)
		(layer "In4.Cu")
		(net "M_B_DQ<13>")
	)
	(gr_poly
		(pts
			(xy 236.978444 -61.675264) (xy 236.970316 -61.483494) (xy 236.948218 -61.444886) (xy 236.602778 -61.64453)
			(xy 236.62513 -61.682884) (xy 236.787182 -61.785754)
		)
		(stroke
			(width 0)
			(type solid)
		)
		(fill yes)
		(layer "In4.Cu")
		(net "M_B_DQS_DP<1>")
	)
	(gr_poly
		(pts
			(xy 236.983524 -91.280996) (xy 236.978698 -91.237054) (xy 236.871764 -91.077542) (xy 236.652308 -91.101418)
			(xy 236.582204 -91.280234) (xy 236.58703 -91.32443)
		)
		(stroke
			(width 0)
			(type solid)
		)
		(fill yes)
		(layer "In4.Cu")
		(net "M_E_DQ<10>")
	)
	(gr_poly
		(pts
			(xy 236.984032 -49.879504) (xy 236.984032 -49.835054) (xy 236.577632 -49.835054) (xy 236.577632 -49.879504)
			(xy 236.666532 -50.072544) (xy 236.895132 -50.072544)
		)
		(stroke
			(width 0)
			(type solid)
		)
		(fill yes)
		(layer "In4.Cu")
		(net "M_B_DQS_DP<11>")
	)
	(gr_poly
		(pts
			(xy 236.984032 -49.600104) (xy 236.895132 -49.407064) (xy 236.666532 -49.407064) (xy 236.577632 -49.600104)
			(xy 236.577632 -49.644554) (xy 236.984032 -49.644554)
		)
		(stroke
			(width 0)
			(type solid)
		)
		(fill yes)
		(layer "In4.Cu")
		(net "M_B_DQS_DN<11>")
	)
	(gr_poly
		(pts
			(xy 236.991398 -49.06899) (xy 236.991398 -49.02454) (xy 236.584998 -49.02454) (xy 236.584998 -49.06899)
			(xy 236.673898 -49.26203) (xy 236.902498 -49.26203)
		)
		(stroke
			(width 0)
			(type solid)
		)
		(fill yes)
		(layer "In4.Cu")
		(net "M_B_DQS_DP<2>")
	)
	(gr_poly
		(pts
			(xy 236.991398 -48.78959) (xy 236.902498 -48.59655) (xy 236.673898 -48.59655) (xy 236.584998 -48.78959)
			(xy 236.584998 -48.83404) (xy 236.991398 -48.83404)
		)
		(stroke
			(width 0)
			(type solid)
		)
		(fill yes)
		(layer "In4.Cu")
		(net "M_B_DQS_DN<2>")
	)
	(gr_poly
		(pts
			(xy 237.17631 -89.916) (xy 237.198662 -89.877646) (xy 236.853222 -89.678002) (xy 236.831124 -89.71661)
			(xy 236.822996 -89.90838) (xy 237.014258 -90.01887)
		)
		(stroke
			(width 0)
			(type solid)
		)
		(fill yes)
		(layer "In4.Cu")
		(net "M_E_DQS_DN<10>")
	)
	(gr_poly
		(pts
			(xy 237.17631 -84.963) (xy 237.198662 -84.924646) (xy 236.853222 -84.725002) (xy 236.831124 -84.76361)
			(xy 236.822996 -84.95538) (xy 237.014258 -85.06587)
		)
		(stroke
			(width 0)
			(type solid)
		)
		(fill yes)
		(layer "In4.Cu")
		(net "M_E_DQS_DN<9>")
	)
	(gr_poly
		(pts
			(xy 237.198662 -60.927234) (xy 237.17631 -60.88888) (xy 237.014258 -60.78601) (xy 236.822996 -60.8965)
			(xy 236.831124 -61.08827) (xy 236.853222 -61.126624)
		)
		(stroke
			(width 0)
			(type solid)
		)
		(fill yes)
		(layer "In4.Cu")
		(net "M_B_DQS_DN<1>")
	)
	(gr_poly
		(pts
			(xy 237.200948 -100.54971) (xy 237.178596 -100.511356) (xy 237.016544 -100.408486) (xy 236.825282 -100.518976)
			(xy 236.83341 -100.710746) (xy 236.855508 -100.749354)
		)
		(stroke
			(width 0)
			(type solid)
		)
		(fill yes)
		(layer "In4.Cu")
		(net "M_E_DQS_DP<11>")
	)
	(gr_poly
		(pts
			(xy 237.209838 -101.54666) (xy 237.187486 -101.508052) (xy 237.025434 -101.405182) (xy 236.834172 -101.515672)
			(xy 236.8423 -101.707442) (xy 236.864398 -101.74605)
		)
		(stroke
			(width 0)
			(type solid)
		)
		(fill yes)
		(layer "In4.Cu")
		(net "M_E_DQS_DN<2>")
	)
	(gr_poly
		(pts
			(xy 237.375192 -102.653338) (xy 237.343696 -102.621842) (xy 237.14456 -102.548182) (xy 236.982762 -102.70998)
			(xy 237.056422 -102.909116) (xy 237.087918 -102.940612)
		)
		(stroke
			(width 0)
			(type solid)
		)
		(fill yes)
		(layer "In4.Cu")
		(net "M_E_DQ<22>")
	)
	(gr_poly
		(pts
			(xy 237.536482 -48.213264) (xy 237.536482 -48.168814) (xy 237.130082 -48.168814) (xy 237.130082 -48.213264)
			(xy 237.218982 -48.406304) (xy 237.447582 -48.406304)
		)
		(stroke
			(width 0)
			(type solid)
		)
		(fill yes)
		(layer "In4.Cu")
		(net "M_B_DQ<22>")
	)
	(gr_poly
		(pts
			(xy 237.536482 -47.933864) (xy 237.447582 -47.740824) (xy 237.218982 -47.740824) (xy 237.130082 -47.933864)
			(xy 237.130082 -47.978314) (xy 237.536482 -47.978314)
		)
		(stroke
			(width 0)
			(type solid)
		)
		(fill yes)
		(layer "In4.Cu")
		(net "M_B_DQ<23>")
	)
	(gr_poly
		(pts
			(xy 237.59668 -99.4664) (xy 237.55223 -99.4664) (xy 237.38205 -99.5553) (xy 237.38205 -99.77628)
			(xy 237.55223 -99.86518) (xy 237.59668 -99.86518)
		)
		(stroke
			(width 0)
			(type solid)
		)
		(fill yes)
		(layer "In4.Cu")
		(net "M_E_DQS_DP<11>")
	)
	(gr_poly
		(pts
			(xy 237.59668 -98.4758) (xy 237.55223 -98.4758) (xy 237.38205 -98.5647) (xy 237.38205 -98.78568)
			(xy 237.55223 -98.87458) (xy 237.59668 -98.87458)
		)
		(stroke
			(width 0)
			(type solid)
		)
		(fill yes)
		(layer "In4.Cu")
		(net "M_E_DQS_DP<11>")
	)
	(gr_poly
		(pts
			(xy 237.614714 -103.01859) (xy 237.541054 -102.8192) (xy 237.509812 -102.787704) (xy 237.222284 -103.075232)
			(xy 237.25378 -103.106474) (xy 237.45317 -103.180134)
		)
		(stroke
			(width 0)
			(type solid)
		)
		(fill yes)
		(layer "In4.Cu")
		(net "M_E_DQ<23>")
	)
	(gr_poly
		(pts
			(xy 237.653322 -50.016918) (xy 237.726982 -49.817782) (xy 237.565184 -49.655984) (xy 237.366048 -49.729644)
			(xy 237.334552 -49.76114) (xy 237.621826 -50.048414)
		)
		(stroke
			(width 0)
			(type solid)
		)
		(fill yes)
		(layer "In4.Cu")
		(net "M_B_DQS_DN<11>")
	)
	(gr_poly
		(pts
			(xy 237.730792 -88.989154) (xy 237.73892 -88.797384) (xy 237.547658 -88.686894) (xy 237.385606 -88.789764)
			(xy 237.363254 -88.828118) (xy 237.708694 -89.027762)
		)
		(stroke
			(width 0)
			(type solid)
		)
		(fill yes)
		(layer "In4.Cu")
		(net "M_E_DQ<8>")
	)
	(gr_poly
		(pts
			(xy 237.744508 -52.112926) (xy 237.712758 -51.923696) (xy 237.686342 -51.888136) (xy 237.367826 -52.128674)
			(xy 237.395004 -52.16398) (xy 237.568486 -52.246022)
		)
		(stroke
			(width 0)
			(type solid)
		)
		(fill yes)
		(layer "In4.Cu")
		(net "M_B_DQ<17>")
	)
	(gr_poly
		(pts
			(xy 237.810802 -84.854288) (xy 237.81893 -84.662518) (xy 237.627668 -84.552028) (xy 237.465616 -84.655152)
			(xy 237.443264 -84.693252) (xy 237.788704 -84.892896)
		)
		(stroke
			(width 0)
			(type solid)
		)
		(fill yes)
		(layer "In4.Cu")
		(net "M_E_DQS_DP<9>")
	)
	(gr_poly
		(pts
			(xy 237.814358 -89.813638) (xy 237.822486 -89.621868) (xy 237.631224 -89.511378) (xy 237.469172 -89.614502)
			(xy 237.44682 -89.652602) (xy 237.79226 -89.852246)
		)
		(stroke
			(width 0)
			(type solid)
		)
		(fill yes)
		(layer "In4.Cu")
		(net "M_E_DQS_DP<10>")
	)
	(gr_poly
		(pts
			(xy 237.827566 -100.809552) (xy 237.819692 -100.617782) (xy 237.797594 -100.579174) (xy 237.452154 -100.778818)
			(xy 237.474506 -100.816918) (xy 237.636304 -100.920042)
		)
		(stroke
			(width 0)
			(type solid)
		)
		(fill yes)
		(layer "In4.Cu")
		(net "M_E_DQS_DN<11>")
	)
	(gr_poly
		(pts
			(xy 237.828836 -87.835232) (xy 237.836964 -87.643462) (xy 237.645702 -87.532972) (xy 237.48365 -87.635842)
			(xy 237.461298 -87.67445) (xy 237.806738 -87.87384)
		)
		(stroke
			(width 0)
			(type solid)
		)
		(fill yes)
		(layer "In4.Cu")
		(net "M_E_DQ<12>")
	)
	(gr_poly
		(pts
			(xy 237.828836 -83.872832) (xy 237.836964 -83.681062) (xy 237.645702 -83.570572) (xy 237.48365 -83.673442)
			(xy 237.461298 -83.71205) (xy 237.806738 -83.91144)
		)
		(stroke
			(width 0)
			(type solid)
		)
		(fill yes)
		(layer "In4.Cu")
		(net "M_E_DQ<0>")
	)
	(gr_poly
		(pts
			(xy 237.828836 -82.882232) (xy 237.836964 -82.690462) (xy 237.645702 -82.579972) (xy 237.48365 -82.682842)
			(xy 237.461298 -82.72145) (xy 237.806738 -82.92084)
		)
		(stroke
			(width 0)
			(type solid)
		)
		(fill yes)
		(layer "In4.Cu")
		(net "M_E_DQ<4>")
	)
	(gr_poly
		(pts
			(xy 237.829852 -101.797358) (xy 237.821724 -101.605588) (xy 237.799626 -101.567234) (xy 237.454186 -101.76637)
			(xy 237.476538 -101.804978) (xy 237.63859 -101.907848)
		)
		(stroke
			(width 0)
			(type solid)
		)
		(fill yes)
		(layer "In4.Cu")
		(net "M_E_DQS_DP<2>")
	)
	(gr_poly
		(pts
			(xy 237.964472 -100.366322) (xy 238.134652 -100.277676) (xy 238.134652 -100.056696) (xy 237.964726 -99.967796)
			(xy 237.920276 -99.967542) (xy 237.920276 -100.366576)
		)
		(stroke
			(width 0)
			(type solid)
		)
		(fill yes)
		(layer "In4.Cu")
		(net "M_E_DQS_DN<11>")
	)
	(gr_poly
		(pts
			(xy 238.002064 -49.643284) (xy 238.03356 -49.611788) (xy 237.746286 -49.324514) (xy 237.71479 -49.35601)
			(xy 237.64113 -49.555146) (xy 237.802928 -49.716944)
		)
		(stroke
			(width 0)
			(type solid)
		)
		(fill yes)
		(layer "In4.Cu")
		(net "M_B_DQS_DP<2>")
	)
	(gr_poly
		(pts
			(xy 238.05642 -98.070416) (xy 238.03102 -98.03384) (xy 237.860586 -97.945448) (xy 237.679484 -98.072194)
			(xy 237.704376 -98.26244) (xy 237.729776 -98.298762)
		)
		(stroke
			(width 0)
			(type solid)
		)
		(fill yes)
		(layer "In4.Cu")
		(net "M_E_DQS_DP<11>")
	)
	(gr_poly
		(pts
			(xy 238.076232 -101.02977) (xy 238.050832 -100.993194) (xy 237.880398 -100.904802) (xy 237.699296 -101.031548)
			(xy 237.724188 -101.222048) (xy 237.749588 -101.25837)
		)
		(stroke
			(width 0)
			(type solid)
		)
		(fill yes)
		(layer "In4.Cu")
		(net "M_E_DQS_DN<2>")
	)
	(gr_poly
		(pts
			(xy 238.134906 -99.28733) (xy 238.134906 -99.06635) (xy 237.964726 -98.97745) (xy 237.920276 -98.97745)
			(xy 237.920276 -99.37623) (xy 237.964726 -99.37623)
		)
		(stroke
			(width 0)
			(type solid)
		)
		(fill yes)
		(layer "In4.Cu")
		(net "M_E_DQS_DN<11>")
	)
	(gr_poly
		(pts
			(xy 238.199676 -49.445672) (xy 238.273336 -49.246282) (xy 238.111792 -49.084738) (xy 237.912402 -49.158398)
			(xy 237.880906 -49.18964) (xy 238.168434 -49.477168)
		)
		(stroke
			(width 0)
			(type solid)
		)
		(fill yes)
		(layer "In4.Cu")
		(net "M_B_DQS_DN<2>")
	)
	(gr_poly
		(pts
			(xy 238.2774 -48.834548) (xy 238.308896 -48.803052) (xy 238.021622 -48.515778) (xy 237.990126 -48.547274)
			(xy 237.916466 -48.74641) (xy 238.078264 -48.908208)
		)
		(stroke
			(width 0)
			(type solid)
		)
		(fill yes)
		(layer "In4.Cu")
		(net "M_B_DQ<22>")
	)
	(gr_poly
		(pts
			(xy 238.284004 -47.751492) (xy 238.315246 -47.719996) (xy 238.027972 -47.432722) (xy 237.996476 -47.464218)
			(xy 237.922816 -47.663608) (xy 238.084614 -47.825152)
		)
		(stroke
			(width 0)
			(type solid)
		)
		(fill yes)
		(layer "In4.Cu")
		(net "M_B_DQ<18>")
	)
	(gr_poly
		(pts
			(xy 238.391446 -102.201726) (xy 238.302546 -102.008686) (xy 238.073946 -102.008686) (xy 237.985046 -102.201726)
			(xy 237.985046 -102.246176) (xy 238.391446 -102.246176)
		)
		(stroke
			(width 0)
			(type solid)
		)
		(fill yes)
		(layer "In4.Cu")
		(net "M_E_DQ<22>")
	)
	(gr_poly
		(pts
			(xy 238.4552 -52.425346) (xy 238.41075 -52.425346) (xy 238.24057 -52.514246) (xy 238.24057 -52.735226)
			(xy 238.41075 -52.824126) (xy 238.4552 -52.824126)
		)
		(stroke
			(width 0)
			(type solid)
		)
		(fill yes)
		(layer "In4.Cu")
		(net "M_B_DQS_DP<2>")
	)
	(gr_poly
		(pts
			(xy 238.4552 -51.42865) (xy 238.41075 -51.42865) (xy 238.24057 -51.51755) (xy 238.24057 -51.73853)
			(xy 238.41075 -51.82743) (xy 238.4552 -51.82743)
		)
		(stroke
			(width 0)
			(type solid)
		)
		(fill yes)
		(layer "In4.Cu")
		(net "M_B_DQS_DP<2>")
	)
	(gr_poly
		(pts
			(xy 238.475012 -48.636936) (xy 238.548672 -48.437546) (xy 238.387128 -48.276002) (xy 238.187738 -48.349662)
			(xy 238.156242 -48.380904) (xy 238.44377 -48.668432)
		)
		(stroke
			(width 0)
			(type solid)
		)
		(fill yes)
		(layer "In4.Cu")
		(net "M_B_DQ<23>")
	)
	(gr_poly
		(pts
			(xy 238.481362 -47.554134) (xy 238.555022 -47.354744) (xy 238.393478 -47.192946) (xy 238.194088 -47.266606)
			(xy 238.162592 -47.298102) (xy 238.449866 -47.585376)
		)
		(stroke
			(width 0)
			(type solid)
		)
		(fill yes)
		(layer "In4.Cu")
		(net "M_B_DQ<19>")
	)
	(gr_poly
		(pts
			(xy 238.518446 -102.480364) (xy 238.518446 -102.435914) (xy 238.112046 -102.435914) (xy 238.112046 -102.480364)
			(xy 238.200946 -102.673404) (xy 238.429546 -102.673404)
		)
		(stroke
			(width 0)
			(type solid)
		)
		(fill yes)
		(layer "In4.Cu")
		(net "M_E_DQ<23>")
	)
	(gr_poly
		(pts
			(xy 238.645954 -98.97237) (xy 238.601504 -98.97237) (xy 238.431324 -99.06127) (xy 238.431324 -99.28225)
			(xy 238.601504 -99.37115) (xy 238.645954 -99.37115)
		)
		(stroke
			(width 0)
			(type solid)
		)
		(fill yes)
		(layer "In4.Cu")
		(net "M_E_DQ<22>")
	)
	(gr_poly
		(pts
			(xy 238.77524 -100.87483) (xy 238.67237 -100.712524) (xy 238.633762 -100.690426) (xy 238.434372 -101.035866)
			(xy 238.47298 -101.057964) (xy 238.66475 -101.066092)
		)
		(stroke
			(width 0)
			(type solid)
		)
		(fill yes)
		(layer "In4.Cu")
		(net "M_E_DQS_DP<2>")
	)
	(gr_poly
		(pts
			(xy 238.977932 -49.53508) (xy 239.009428 -49.503584) (xy 238.722154 -49.21631) (xy 238.690658 -49.247806)
			(xy 238.616998 -49.446942) (xy 238.778796 -49.60874)
		)
		(stroke
			(width 0)
			(type solid)
		)
		(fill yes)
		(layer "In4.Cu")
		(net "M_B_DQ<22>")
	)
	(gr_poly
		(pts
			(xy 238.984282 -48.452024) (xy 239.015778 -48.420528) (xy 238.728504 -48.133254) (xy 238.697008 -48.16475)
			(xy 238.623348 -48.363886) (xy 238.785146 -48.525684)
		)
		(stroke
			(width 0)
			(type solid)
		)
		(fill yes)
		(layer "In4.Cu")
		(net "M_B_DQ<18>")
	)
	(gr_poly
		(pts
			(xy 238.993426 -99.77628) (xy 238.993426 -99.5553) (xy 238.823246 -99.4664) (xy 238.778796 -99.4664)
			(xy 238.778796 -99.86518) (xy 238.823246 -99.86518)
		)
		(stroke
			(width 0)
			(type solid)
		)
		(fill yes)
		(layer "In4.Cu")
		(net "M_E_DQ<22>")
	)
	(gr_poly
		(pts
			(xy 238.993426 -53.217826) (xy 238.993426 -52.996846) (xy 238.823246 -52.907946) (xy 238.778796 -52.907946)
			(xy 238.778796 -53.306726) (xy 238.823246 -53.306726)
		)
		(stroke
			(width 0)
			(type solid)
		)
		(fill yes)
		(layer "In4.Cu")
		(net "M_B_DQS_DN<2>")
	)
	(gr_poly
		(pts
			(xy 238.993426 -52.22748) (xy 238.993426 -52.0065) (xy 238.823246 -51.9176) (xy 238.778796 -51.9176)
			(xy 238.778796 -52.31638) (xy 238.823246 -52.31638)
		)
		(stroke
			(width 0)
			(type solid)
		)
		(fill yes)
		(layer "In4.Cu")
		(net "M_B_DQS_DN<2>")
	)
	(gr_poly
		(pts
			(xy 238.993426 -51.249326) (xy 238.993426 -51.028346) (xy 238.823246 -50.939446) (xy 238.778796 -50.939446)
			(xy 238.778796 -51.338226) (xy 238.823246 -51.338226)
		)
		(stroke
			(width 0)
			(type solid)
		)
		(fill yes)
		(layer "In4.Cu")
		(net "M_B_DQS_DN<2>")
	)
	(gr_poly
		(pts
			(xy 239.151414 -101.636068) (xy 239.119918 -101.604572) (xy 238.920782 -101.530912) (xy 238.758984 -101.69271)
			(xy 238.832644 -101.891846) (xy 238.86414 -101.923342)
		)
		(stroke
			(width 0)
			(type solid)
		)
		(fill yes)
		(layer "In4.Cu")
		(net "M_E_DQ<22>")
	)
	(gr_poly
		(pts
			(xy 239.175544 -49.337468) (xy 239.249204 -49.138078) (xy 239.08766 -48.976534) (xy 238.88827 -49.050194)
			(xy 238.856774 -49.081436) (xy 239.144302 -49.368964)
		)
		(stroke
			(width 0)
			(type solid)
		)
		(fill yes)
		(layer "In4.Cu")
		(net "M_B_DQ<23>")
	)
	(gr_poly
		(pts
			(xy 239.181894 -48.254412) (xy 239.255554 -48.055276) (xy 239.093756 -47.893478) (xy 238.89462 -47.967138)
			(xy 238.863124 -47.998634) (xy 239.150398 -48.285908)
		)
		(stroke
			(width 0)
			(type solid)
		)
		(fill yes)
		(layer "In4.Cu")
		(net "M_B_DQ<19>")
	)
	(gr_poly
		(pts
			(xy 239.31372 -99.46386) (xy 239.26927 -99.464114) (xy 239.099344 -99.553014) (xy 239.099344 -99.77374)
			(xy 239.269524 -99.86264) (xy 239.313974 -99.862894)
		)
		(stroke
			(width 0)
			(type solid)
		)
		(fill yes)
		(layer "In4.Cu")
		(net "M_E_DQ<18>")
	)
	(gr_poly
		(pts
			(xy 239.31372 -50.939446) (xy 239.26927 -50.939446) (xy 239.09909 -51.028346) (xy 239.09909 -51.249326)
			(xy 239.26927 -51.338226) (xy 239.31372 -51.338226)
		)
		(stroke
			(width 0)
			(type solid)
		)
		(fill yes)
		(layer "In4.Cu")
		(net "M_B_DQ<22>")
	)
	(gr_poly
		(pts
			(xy 239.390936 -102.00132) (xy 239.317276 -101.80193) (xy 239.286034 -101.770434) (xy 238.998506 -102.057962)
			(xy 239.030002 -102.089204) (xy 239.229392 -102.162864)
		)
		(stroke
			(width 0)
			(type solid)
		)
		(fill yes)
		(layer "In4.Cu")
		(net "M_E_DQ<23>")
	)
	(gr_poly
		(pts
			(xy 239.63249 -52.834794) (xy 239.670844 -52.617116) (xy 239.518698 -52.500022) (xy 239.474756 -52.492402)
			(xy 239.405668 -52.885086) (xy 239.449356 -52.892706)
		)
		(stroke
			(width 0)
			(type solid)
		)
		(fill yes)
		(layer "In4.Cu")
		(net "M_B_DQ<23>")
	)
	(gr_poly
		(pts
			(xy 239.684814 -49.152556) (xy 239.71631 -49.12106) (xy 239.429036 -48.833786) (xy 239.39754 -48.865028)
			(xy 239.32388 -49.064418) (xy 239.485424 -49.226216)
		)
		(stroke
			(width 0)
			(type solid)
		)
		(fill yes)
		(layer "In4.Cu")
		(net "M_B_DQ<18>")
	)
	(gr_poly
		(pts
			(xy 239.752124 -100.317554) (xy 239.774476 -100.2792) (xy 239.428782 -100.07981) (xy 239.406938 -100.118418)
			(xy 239.39881 -100.310188) (xy 239.590072 -100.420424)
		)
		(stroke
			(width 0)
			(type solid)
		)
		(fill yes)
		(layer "In4.Cu")
		(net "M_E_DQ<18>")
	)
	(gr_poly
		(pts
			(xy 239.851946 -101.26218) (xy 239.851946 -101.0412) (xy 239.681766 -100.9523) (xy 239.637316 -100.9523)
			(xy 239.637316 -101.35108) (xy 239.681766 -101.35108)
		)
		(stroke
			(width 0)
			(type solid)
		)
		(fill yes)
		(layer "In4.Cu")
		(net "M_E_DQ<23>")
	)
	(gr_poly
		(pts
			(xy 239.851946 -51.73853) (xy 239.851946 -51.51755) (xy 239.681766 -51.42865) (xy 239.637316 -51.42865)
			(xy 239.637316 -51.82743) (xy 239.681766 -51.82743)
		)
		(stroke
			(width 0)
			(type solid)
		)
		(fill yes)
		(layer "In4.Cu")
		(net "M_B_DQ<23>")
	)
	(gr_poly
		(pts
			(xy 239.851946 -50.74158) (xy 239.851946 -50.5206) (xy 239.681766 -50.4317) (xy 239.637316 -50.4317)
			(xy 239.637316 -50.83048) (xy 239.681766 -50.83048)
		)
		(stroke
			(width 0)
			(type solid)
		)
		(fill yes)
		(layer "In4.Cu")
		(net "M_B_DQ<23>")
	)
	(gr_poly
		(pts
			(xy 239.882426 -48.954944) (xy 239.956086 -48.755554) (xy 239.794288 -48.59401) (xy 239.594898 -48.66767)
			(xy 239.563656 -48.699166) (xy 239.85093 -48.98644)
		)
		(stroke
			(width 0)
			(type solid)
		)
		(fill yes)
		(layer "In4.Cu")
		(net "M_B_DQ<19>")
	)
	(gr_poly
		(pts
			(xy 240.17224 -100.9523) (xy 240.12779 -100.9523) (xy 239.95761 -101.0412) (xy 239.95761 -101.26218)
			(xy 240.12779 -101.35108) (xy 240.17224 -101.35108)
		)
		(stroke
			(width 0)
			(type solid)
		)
		(fill yes)
		(layer "In4.Cu")
		(net "M_E_DQ<18>")
	)
	(gr_poly
		(pts
			(xy 240.17224 -51.42865) (xy 240.12779 -51.42865) (xy 239.95761 -51.51755) (xy 239.95761 -51.73853)
			(xy 240.12779 -51.82743) (xy 240.17224 -51.82743)
		)
		(stroke
			(width 0)
			(type solid)
		)
		(fill yes)
		(layer "In4.Cu")
		(net "M_B_DQ<18>")
	)
	(gr_poly
		(pts
			(xy 240.17224 -50.4317) (xy 240.12779 -50.4317) (xy 239.95761 -50.5206) (xy 239.95761 -50.74158)
			(xy 240.12779 -50.83048) (xy 240.17224 -50.83048)
		)
		(stroke
			(width 0)
			(type solid)
		)
		(fill yes)
		(layer "In4.Cu")
		(net "M_B_DQ<18>")
	)
	(gr_poly
		(pts
			(xy 240.218214 -102.626668) (xy 240.186718 -102.595172) (xy 239.987582 -102.521512) (xy 239.825784 -102.68331)
			(xy 239.899444 -102.882446) (xy 239.93094 -102.913942)
		)
		(stroke
			(width 0)
			(type solid)
		)
		(fill yes)
		(layer "In4.Cu")
		(net "M_E_DQ<18>")
	)
	(gr_poly
		(pts
			(xy 240.353596 -100.185728) (xy 240.438178 -100.013262) (xy 240.307368 -99.835208) (xy 240.11763 -99.864164)
			(xy 240.081562 -99.89058) (xy 240.317782 -100.21189)
		)
		(stroke
			(width 0)
			(type solid)
		)
		(fill yes)
		(layer "In4.Cu")
		(net "M_E_DQ<19>")
	)
	(gr_poly
		(pts
			(xy 240.383822 -101.858064) (xy 240.339118 -101.858064) (xy 240.146332 -101.94671) (xy 240.146332 -102.175564)
			(xy 240.339118 -102.26421) (xy 240.383822 -102.26421)
		)
		(stroke
			(width 0)
			(type solid)
		)
		(fill yes)
		(layer "In4.Cu")
		(net "M_E_DQ<18>")
	)
	(gr_poly
		(pts
			(xy 240.415826 -52.744624) (xy 240.390934 -52.554378) (xy 240.365534 -52.518056) (xy 240.03889 -52.746402)
			(xy 240.064544 -52.782978) (xy 240.234724 -52.87137)
		)
		(stroke
			(width 0)
			(type solid)
		)
		(fill yes)
		(layer "In4.Cu")
		(net "M_B_DQ<19>")
	)
	(gr_poly
		(pts
			(xy 240.457736 -102.99192) (xy 240.384076 -102.79253) (xy 240.352834 -102.761034) (xy 240.065306 -103.048562)
			(xy 240.096802 -103.079804) (xy 240.296192 -103.153464)
		)
		(stroke
			(width 0)
			(type solid)
		)
		(fill yes)
		(layer "In4.Cu")
		(net "M_E_DQ<19>")
	)
	(gr_poly
		(pts
			(xy 240.618264 -102.26421) (xy 240.811304 -102.17531) (xy 240.811304 -101.946964) (xy 240.618264 -101.858064)
			(xy 240.573814 -101.85781) (xy 240.573814 -102.264464)
		)
		(stroke
			(width 0)
			(type solid)
		)
		(fill yes)
		(layer "In4.Cu")
		(net "M_E_DQ<19>")
	)
	(gr_poly
		(pts
			(xy 240.710466 -100.772976) (xy 240.710466 -100.551996) (xy 240.540286 -100.463096) (xy 240.495836 -100.463096)
			(xy 240.495836 -100.861876) (xy 240.540286 -100.861876)
		)
		(stroke
			(width 0)
			(type solid)
		)
		(fill yes)
		(layer "In4.Cu")
		(net "M_E_DQ<19>")
	)
	(gr_poly
		(pts
			(xy 240.710466 -52.239926) (xy 240.710466 -52.018946) (xy 240.540286 -51.930046) (xy 240.495836 -51.930046)
			(xy 240.495836 -52.328826) (xy 240.540286 -52.328826)
		)
		(stroke
			(width 0)
			(type solid)
		)
		(fill yes)
		(layer "In4.Cu")
		(net "M_B_DQ<19>")
	)
	(gr_poly
		(pts
			(xy 240.710466 -51.249326) (xy 240.710466 -51.028346) (xy 240.540286 -50.939446) (xy 240.495836 -50.939446)
			(xy 240.495836 -51.338226) (xy 240.540286 -51.338226)
		)
		(stroke
			(width 0)
			(type solid)
		)
		(fill yes)
		(layer "In4.Cu")
		(net "M_B_DQ<19>")
	)
	(gr_poly
		(pts
			(xy 242.299236 -50.4317) (xy 242.254786 -50.4317) (xy 242.061746 -50.5206) (xy 242.061746 -50.7492)
			(xy 242.254786 -50.8381) (xy 242.299236 -50.8381)
		)
		(stroke
			(width 0)
			(type solid)
		)
		(fill yes)
		(layer "In4.Cu")
		(net "M_C_ECC<4>")
	)
	(gr_poly
		(pts
			(xy 242.558824 -100.88626) (xy 242.514374 -100.88626) (xy 242.321334 -100.97516) (xy 242.321334 -101.20376)
			(xy 242.514374 -101.29266) (xy 242.558824 -101.29266)
		)
		(stroke
			(width 0)
			(type solid)
		)
		(fill yes)
		(layer "In4.Cu")
		(net "M_F_ECC<4>")
	)
	(gr_poly
		(pts
			(xy 242.701826 -51.573684) (xy 242.733322 -51.542188) (xy 242.446048 -51.254914) (xy 242.414552 -51.286156)
			(xy 242.340892 -51.485546) (xy 242.502436 -51.647344)
		)
		(stroke
			(width 0)
			(type solid)
		)
		(fill yes)
		(layer "In4.Cu")
		(net "M_C_ECC<4>")
	)
	(gr_poly
		(pts
			(xy 242.72748 -50.7492) (xy 242.72748 -50.5206) (xy 242.53444 -50.4317) (xy 242.48999 -50.4317) (xy 242.48999 -50.8381)
			(xy 242.53444 -50.8381)
		)
		(stroke
			(width 0)
			(type solid)
		)
		(fill yes)
		(layer "In4.Cu")
		(net "M_C_ECC<5>")
	)
	(gr_poly
		(pts
			(xy 242.747546 -64.81064) (xy 242.703096 -64.81064) (xy 242.532916 -64.89954) (xy 242.532916 -65.12052)
			(xy 242.703096 -65.20942) (xy 242.747546 -65.20942)
		)
		(stroke
			(width 0)
			(type solid)
		)
		(fill yes)
		(layer "In4.Cu")
		(net "M_C_ECC<4>")
	)
	(gr_poly
		(pts
			(xy 242.747546 -63.82004) (xy 242.703096 -63.82004) (xy 242.532916 -63.90894) (xy 242.532916 -64.12992)
			(xy 242.703096 -64.21882) (xy 242.747546 -64.21882)
		)
		(stroke
			(width 0)
			(type solid)
		)
		(fill yes)
		(layer "In4.Cu")
		(net "M_C_ECC<4>")
	)
	(gr_poly
		(pts
			(xy 242.747546 -62.82944) (xy 242.703096 -62.82944) (xy 242.532916 -62.91834) (xy 242.532916 -63.13932)
			(xy 242.703096 -63.22822) (xy 242.747546 -63.22822)
		)
		(stroke
			(width 0)
			(type solid)
		)
		(fill yes)
		(layer "In4.Cu")
		(net "M_C_ECC<4>")
	)
	(gr_poly
		(pts
			(xy 242.747546 -61.83884) (xy 242.703096 -61.83884) (xy 242.532916 -61.92774) (xy 242.532916 -62.14872)
			(xy 242.703096 -62.23762) (xy 242.747546 -62.23762)
		)
		(stroke
			(width 0)
			(type solid)
		)
		(fill yes)
		(layer "In4.Cu")
		(net "M_C_ECC<4>")
	)
	(gr_poly
		(pts
			(xy 242.747546 -60.84824) (xy 242.703096 -60.84824) (xy 242.532916 -60.93714) (xy 242.532916 -61.15812)
			(xy 242.703096 -61.24702) (xy 242.747546 -61.24702)
		)
		(stroke
			(width 0)
			(type solid)
		)
		(fill yes)
		(layer "In4.Cu")
		(net "M_C_ECC<4>")
	)
	(gr_poly
		(pts
			(xy 242.747546 -59.85764) (xy 242.703096 -59.85764) (xy 242.532916 -59.94654) (xy 242.532916 -60.16752)
			(xy 242.703096 -60.25642) (xy 242.747546 -60.25642)
		)
		(stroke
			(width 0)
			(type solid)
		)
		(fill yes)
		(layer "In4.Cu")
		(net "M_C_ECC<4>")
	)
	(gr_poly
		(pts
			(xy 242.747546 -58.864246) (xy 242.703096 -58.864246) (xy 242.532916 -58.953146) (xy 242.532916 -59.174126)
			(xy 242.703096 -59.263026) (xy 242.747546 -59.263026)
		)
		(stroke
			(width 0)
			(type solid)
		)
		(fill yes)
		(layer "In4.Cu")
		(net "M_C_ECC<4>")
	)
	(gr_poly
		(pts
			(xy 242.747546 -57.8612) (xy 242.703096 -57.8612) (xy 242.532916 -57.9501) (xy 242.532916 -58.17108)
			(xy 242.703096 -58.25998) (xy 242.747546 -58.25998)
		)
		(stroke
			(width 0)
			(type solid)
		)
		(fill yes)
		(layer "In4.Cu")
		(net "M_C_ECC<4>")
	)
	(gr_poly
		(pts
			(xy 242.747546 -56.88584) (xy 242.703096 -56.88584) (xy 242.532916 -56.97474) (xy 242.532916 -57.19572)
			(xy 242.703096 -57.28462) (xy 242.747546 -57.28462)
		)
		(stroke
			(width 0)
			(type solid)
		)
		(fill yes)
		(layer "In4.Cu")
		(net "M_C_ECC<4>")
	)
	(gr_poly
		(pts
			(xy 242.747546 -55.89524) (xy 242.703096 -55.89524) (xy 242.532916 -55.98414) (xy 242.532916 -56.20512)
			(xy 242.703096 -56.29402) (xy 242.747546 -56.29402)
		)
		(stroke
			(width 0)
			(type solid)
		)
		(fill yes)
		(layer "In4.Cu")
		(net "M_C_ECC<4>")
	)
	(gr_poly
		(pts
			(xy 242.747546 -54.90464) (xy 242.703096 -54.90464) (xy 242.532916 -54.99354) (xy 242.532916 -55.21452)
			(xy 242.703096 -55.30342) (xy 242.747546 -55.30342)
		)
		(stroke
			(width 0)
			(type solid)
		)
		(fill yes)
		(layer "In4.Cu")
		(net "M_C_ECC<4>")
	)
	(gr_poly
		(pts
			(xy 242.747546 -53.91404) (xy 242.703096 -53.91404) (xy 242.532916 -54.00294) (xy 242.532916 -54.22392)
			(xy 242.703096 -54.31282) (xy 242.747546 -54.31282)
		)
		(stroke
			(width 0)
			(type solid)
		)
		(fill yes)
		(layer "In4.Cu")
		(net "M_C_ECC<4>")
	)
	(gr_poly
		(pts
			(xy 242.7478 -65.800986) (xy 242.70335 -65.800986) (xy 242.53317 -65.889886) (xy 242.53317 -66.110866)
			(xy 242.70335 -66.199766) (xy 242.7478 -66.199766)
		)
		(stroke
			(width 0)
			(type solid)
		)
		(fill yes)
		(layer "In4.Cu")
		(net "M_C_ECC<4>")
	)
	(gr_poly
		(pts
			(xy 242.880388 -52.937156) (xy 242.835938 -52.937156) (xy 242.642898 -53.026056) (xy 242.642898 -53.254656)
			(xy 242.835938 -53.343556) (xy 242.880388 -53.343556)
		)
		(stroke
			(width 0)
			(type solid)
		)
		(fill yes)
		(layer "In4.Cu")
		(net "M_C_ECC<4>")
	)
	(gr_poly
		(pts
			(xy 242.880388 -51.946556) (xy 242.835938 -51.946556) (xy 242.642898 -52.035456) (xy 242.642898 -52.264056)
			(xy 242.835938 -52.352956) (xy 242.880388 -52.352956)
		)
		(stroke
			(width 0)
			(type solid)
		)
		(fill yes)
		(layer "In4.Cu")
		(net "M_C_ECC<4>")
	)
	(gr_poly
		(pts
			(xy 242.904772 -51.380898) (xy 242.978432 -51.181762) (xy 242.816634 -51.019964) (xy 242.617498 -51.093624)
			(xy 242.586002 -51.12512) (xy 242.873276 -51.412394)
		)
		(stroke
			(width 0)
			(type solid)
		)
		(fill yes)
		(layer "In4.Cu")
		(net "M_C_ECC<5>")
	)
	(gr_poly
		(pts
			(xy 242.986306 -101.20376) (xy 242.986306 -100.97516) (xy 242.793266 -100.88626) (xy 242.748816 -100.88626)
			(xy 242.748816 -101.29266) (xy 242.793266 -101.29266)
		)
		(stroke
			(width 0)
			(type solid)
		)
		(fill yes)
		(layer "In4.Cu")
		(net "M_F_ECC<5>")
	)
	(gr_poly
		(pts
			(xy 243.286026 -66.597276) (xy 243.286026 -66.376296) (xy 243.115846 -66.287396) (xy 243.071396 -66.287396)
			(xy 243.071396 -66.686176) (xy 243.115846 -66.686176)
		)
		(stroke
			(width 0)
			(type solid)
		)
		(fill yes)
		(layer "In4.Cu")
		(net "M_C_ECC<5>")
	)
	(gr_poly
		(pts
			(xy 243.286026 -65.597786) (xy 243.286026 -65.376806) (xy 243.115846 -65.287906) (xy 243.071396 -65.287906)
			(xy 243.071396 -65.686686) (xy 243.115846 -65.686686)
		)
		(stroke
			(width 0)
			(type solid)
		)
		(fill yes)
		(layer "In4.Cu")
		(net "M_C_ECC<5>")
	)
	(gr_poly
		(pts
			(xy 243.286026 -64.607186) (xy 243.286026 -64.386206) (xy 243.115846 -64.297306) (xy 243.071396 -64.297306)
			(xy 243.071396 -64.696086) (xy 243.115846 -64.696086)
		)
		(stroke
			(width 0)
			(type solid)
		)
		(fill yes)
		(layer "In4.Cu")
		(net "M_C_ECC<5>")
	)
	(gr_poly
		(pts
			(xy 243.286026 -63.616586) (xy 243.286026 -63.395606) (xy 243.115846 -63.306706) (xy 243.071396 -63.306706)
			(xy 243.071396 -63.705486) (xy 243.115846 -63.705486)
		)
		(stroke
			(width 0)
			(type solid)
		)
		(fill yes)
		(layer "In4.Cu")
		(net "M_C_ECC<5>")
	)
	(gr_poly
		(pts
			(xy 243.286026 -62.625986) (xy 243.286026 -62.405006) (xy 243.115846 -62.316106) (xy 243.071396 -62.316106)
			(xy 243.071396 -62.714886) (xy 243.115846 -62.714886)
		)
		(stroke
			(width 0)
			(type solid)
		)
		(fill yes)
		(layer "In4.Cu")
		(net "M_C_ECC<5>")
	)
	(gr_poly
		(pts
			(xy 243.286026 -61.635386) (xy 243.286026 -61.414406) (xy 243.115846 -61.325506) (xy 243.071396 -61.325506)
			(xy 243.071396 -61.724286) (xy 243.115846 -61.724286)
		)
		(stroke
			(width 0)
			(type solid)
		)
		(fill yes)
		(layer "In4.Cu")
		(net "M_C_ECC<5>")
	)
	(gr_poly
		(pts
			(xy 243.286026 -60.644786) (xy 243.286026 -60.423806) (xy 243.115846 -60.334906) (xy 243.071396 -60.334906)
			(xy 243.071396 -60.733686) (xy 243.115846 -60.733686)
		)
		(stroke
			(width 0)
			(type solid)
		)
		(fill yes)
		(layer "In4.Cu")
		(net "M_C_ECC<5>")
	)
	(gr_poly
		(pts
			(xy 243.286026 -59.654186) (xy 243.286026 -59.433206) (xy 243.115846 -59.344306) (xy 243.071396 -59.344306)
			(xy 243.071396 -59.743086) (xy 243.115846 -59.743086)
		)
		(stroke
			(width 0)
			(type solid)
		)
		(fill yes)
		(layer "In4.Cu")
		(net "M_C_ECC<5>")
	)
	(gr_poly
		(pts
			(xy 243.286026 -58.678826) (xy 243.286026 -58.457846) (xy 243.115846 -58.368946) (xy 243.071396 -58.368946)
			(xy 243.071396 -58.767726) (xy 243.115846 -58.767726)
		)
		(stroke
			(width 0)
			(type solid)
		)
		(fill yes)
		(layer "In4.Cu")
		(net "M_C_ECC<5>")
	)
	(gr_poly
		(pts
			(xy 243.286026 -57.67578) (xy 243.286026 -57.4548) (xy 243.115846 -57.3659) (xy 243.071396 -57.3659)
			(xy 243.071396 -57.76468) (xy 243.115846 -57.76468)
		)
		(stroke
			(width 0)
			(type solid)
		)
		(fill yes)
		(layer "In4.Cu")
		(net "M_C_ECC<5>")
	)
	(gr_poly
		(pts
			(xy 243.286026 -56.682386) (xy 243.286026 -56.461406) (xy 243.115846 -56.372506) (xy 243.071396 -56.372506)
			(xy 243.071396 -56.771286) (xy 243.115846 -56.771286)
		)
		(stroke
			(width 0)
			(type solid)
		)
		(fill yes)
		(layer "In4.Cu")
		(net "M_C_ECC<5>")
	)
	(gr_poly
		(pts
			(xy 243.286026 -55.691786) (xy 243.286026 -55.470806) (xy 243.115846 -55.381906) (xy 243.071396 -55.381906)
			(xy 243.071396 -55.780686) (xy 243.115846 -55.780686)
		)
		(stroke
			(width 0)
			(type solid)
		)
		(fill yes)
		(layer "In4.Cu")
		(net "M_C_ECC<5>")
	)
	(gr_poly
		(pts
			(xy 243.286026 -54.701186) (xy 243.286026 -54.480206) (xy 243.115846 -54.391306) (xy 243.071396 -54.391306)
			(xy 243.071396 -54.790086) (xy 243.115846 -54.790086)
		)
		(stroke
			(width 0)
			(type solid)
		)
		(fill yes)
		(layer "In4.Cu")
		(net "M_C_ECC<5>")
	)
	(gr_poly
		(pts
			(xy 243.308632 -53.254656) (xy 243.308632 -53.026056) (xy 243.115592 -52.937156) (xy 243.071142 -52.937156)
			(xy 243.071142 -53.343556) (xy 243.115592 -53.343556)
		)
		(stroke
			(width 0)
			(type solid)
		)
		(fill yes)
		(layer "In4.Cu")
		(net "M_C_ECC<5>")
	)
	(gr_poly
		(pts
			(xy 243.308632 -52.264056) (xy 243.308632 -52.035456) (xy 243.115592 -51.946556) (xy 243.071142 -51.946556)
			(xy 243.071142 -52.352956) (xy 243.115592 -52.352956)
		)
		(stroke
			(width 0)
			(type solid)
		)
		(fill yes)
		(layer "In4.Cu")
		(net "M_C_ECC<5>")
	)
	(gr_poly
		(pts
			(xy 243.470176 -99.182174) (xy 243.43868 -99.150932) (xy 243.23929 -99.077272) (xy 243.077746 -99.238816)
			(xy 243.151406 -99.438206) (xy 243.182648 -99.469702)
		)
		(stroke
			(width 0)
			(type solid)
		)
		(fill yes)
		(layer "In4.Cu")
		(net "M_F_ECC<4>")
	)
	(gr_poly
		(pts
			(xy 243.606066 -97.9805) (xy 243.561616 -97.9805) (xy 243.391436 -98.0694) (xy 243.391436 -98.29038)
			(xy 243.561616 -98.37928) (xy 243.606066 -98.37928)
		)
		(stroke
			(width 0)
			(type solid)
		)
		(fill yes)
		(layer "In4.Cu")
		(net "M_F_ECC<4>")
	)
	(gr_poly
		(pts
			(xy 243.606066 -96.9899) (xy 243.561616 -96.9899) (xy 243.391436 -97.0788) (xy 243.391436 -97.29978)
			(xy 243.561616 -97.38868) (xy 243.606066 -97.38868)
		)
		(stroke
			(width 0)
			(type solid)
		)
		(fill yes)
		(layer "In4.Cu")
		(net "M_F_ECC<4>")
	)
	(gr_poly
		(pts
			(xy 243.606066 -95.9993) (xy 243.561616 -95.9993) (xy 243.391436 -96.0882) (xy 243.391436 -96.30918)
			(xy 243.561616 -96.39808) (xy 243.606066 -96.39808)
		)
		(stroke
			(width 0)
			(type solid)
		)
		(fill yes)
		(layer "In4.Cu")
		(net "M_F_ECC<4>")
	)
	(gr_poly
		(pts
			(xy 243.606066 -95.0087) (xy 243.561616 -95.0087) (xy 243.391436 -95.0976) (xy 243.391436 -95.31858)
			(xy 243.561616 -95.40748) (xy 243.606066 -95.40748)
		)
		(stroke
			(width 0)
			(type solid)
		)
		(fill yes)
		(layer "In4.Cu")
		(net "M_F_ECC<4>")
	)
	(gr_poly
		(pts
			(xy 243.606066 -94.030546) (xy 243.561616 -94.030546) (xy 243.391436 -94.119446) (xy 243.391436 -94.340426)
			(xy 243.561616 -94.429326) (xy 243.606066 -94.429326)
		)
		(stroke
			(width 0)
			(type solid)
		)
		(fill yes)
		(layer "In4.Cu")
		(net "M_F_ECC<4>")
	)
	(gr_poly
		(pts
			(xy 243.606066 -93.03385) (xy 243.561616 -93.03385) (xy 243.391436 -93.12275) (xy 243.391436 -93.34373)
			(xy 243.561616 -93.43263) (xy 243.606066 -93.43263)
		)
		(stroke
			(width 0)
			(type solid)
		)
		(fill yes)
		(layer "In4.Cu")
		(net "M_F_ECC<4>")
	)
	(gr_poly
		(pts
			(xy 243.606066 -92.0369) (xy 243.561616 -92.0369) (xy 243.391436 -92.1258) (xy 243.391436 -92.34678)
			(xy 243.561616 -92.43568) (xy 243.606066 -92.43568)
		)
		(stroke
			(width 0)
			(type solid)
		)
		(fill yes)
		(layer "In4.Cu")
		(net "M_F_ECC<4>")
	)
	(gr_poly
		(pts
			(xy 243.606066 -91.0463) (xy 243.561616 -91.0463) (xy 243.391436 -91.1352) (xy 243.391436 -91.35618)
			(xy 243.561616 -91.44508) (xy 243.606066 -91.44508)
		)
		(stroke
			(width 0)
			(type solid)
		)
		(fill yes)
		(layer "In4.Cu")
		(net "M_F_ECC<4>")
	)
	(gr_poly
		(pts
			(xy 243.606066 -90.0557) (xy 243.561616 -90.0557) (xy 243.391436 -90.1446) (xy 243.391436 -90.36558)
			(xy 243.561616 -90.45448) (xy 243.606066 -90.45448)
		)
		(stroke
			(width 0)
			(type solid)
		)
		(fill yes)
		(layer "In4.Cu")
		(net "M_F_ECC<4>")
	)
	(gr_poly
		(pts
			(xy 243.606066 -89.0651) (xy 243.561616 -89.0651) (xy 243.391436 -89.154) (xy 243.391436 -89.37498)
			(xy 243.561616 -89.46388) (xy 243.606066 -89.46388)
		)
		(stroke
			(width 0)
			(type solid)
		)
		(fill yes)
		(layer "In4.Cu")
		(net "M_F_ECC<4>")
	)
	(gr_poly
		(pts
			(xy 243.606066 -88.0745) (xy 243.561616 -88.0745) (xy 243.391436 -88.1634) (xy 243.391436 -88.38438)
			(xy 243.561616 -88.47328) (xy 243.606066 -88.47328)
		)
		(stroke
			(width 0)
			(type solid)
		)
		(fill yes)
		(layer "In4.Cu")
		(net "M_F_ECC<4>")
	)
	(gr_poly
		(pts
			(xy 243.606066 -87.0839) (xy 243.561616 -87.0839) (xy 243.391436 -87.1728) (xy 243.391436 -87.39378)
			(xy 243.561616 -87.48268) (xy 243.606066 -87.48268)
		)
		(stroke
			(width 0)
			(type solid)
		)
		(fill yes)
		(layer "In4.Cu")
		(net "M_F_ECC<4>")
	)
	(gr_poly
		(pts
			(xy 243.606066 -86.0933) (xy 243.561616 -86.0933) (xy 243.391436 -86.1822) (xy 243.391436 -86.40318)
			(xy 243.561616 -86.49208) (xy 243.606066 -86.49208)
		)
		(stroke
			(width 0)
			(type solid)
		)
		(fill yes)
		(layer "In4.Cu")
		(net "M_F_ECC<4>")
	)
	(gr_poly
		(pts
			(xy 243.606066 -85.1027) (xy 243.561616 -85.1027) (xy 243.391436 -85.1916) (xy 243.391436 -85.41258)
			(xy 243.561616 -85.50148) (xy 243.606066 -85.50148)
		)
		(stroke
			(width 0)
			(type solid)
		)
		(fill yes)
		(layer "In4.Cu")
		(net "M_F_ECC<4>")
	)
	(gr_poly
		(pts
			(xy 243.606066 -84.1121) (xy 243.561616 -84.1121) (xy 243.391436 -84.201) (xy 243.391436 -84.42198)
			(xy 243.561616 -84.51088) (xy 243.606066 -84.51088)
		)
		(stroke
			(width 0)
			(type solid)
		)
		(fill yes)
		(layer "In4.Cu")
		(net "M_F_ECC<4>")
	)
	(gr_poly
		(pts
			(xy 243.606066 -66.287396) (xy 243.561616 -66.287396) (xy 243.391436 -66.376296) (xy 243.391436 -66.597276)
			(xy 243.561616 -66.686176) (xy 243.606066 -66.686176)
		)
		(stroke
			(width 0)
			(type solid)
		)
		(fill yes)
		(layer "In4.Cu")
		(net "M_C_ECC<0>")
	)
	(gr_poly
		(pts
			(xy 243.606066 -65.2907) (xy 243.561616 -65.2907) (xy 243.391436 -65.3796) (xy 243.391436 -65.60058)
			(xy 243.561616 -65.68948) (xy 243.606066 -65.68948)
		)
		(stroke
			(width 0)
			(type solid)
		)
		(fill yes)
		(layer "In4.Cu")
		(net "M_C_ECC<0>")
	)
	(gr_poly
		(pts
			(xy 243.606066 -64.3001) (xy 243.561616 -64.3001) (xy 243.391436 -64.389) (xy 243.391436 -64.60998)
			(xy 243.561616 -64.69888) (xy 243.606066 -64.69888)
		)
		(stroke
			(width 0)
			(type solid)
		)
		(fill yes)
		(layer "In4.Cu")
		(net "M_C_ECC<0>")
	)
	(gr_poly
		(pts
			(xy 243.606066 -63.3095) (xy 243.561616 -63.3095) (xy 243.391436 -63.3984) (xy 243.391436 -63.61938)
			(xy 243.561616 -63.70828) (xy 243.606066 -63.70828)
		)
		(stroke
			(width 0)
			(type solid)
		)
		(fill yes)
		(layer "In4.Cu")
		(net "M_C_ECC<0>")
	)
	(gr_poly
		(pts
			(xy 243.606066 -62.3189) (xy 243.561616 -62.3189) (xy 243.391436 -62.4078) (xy 243.391436 -62.62878)
			(xy 243.561616 -62.71768) (xy 243.606066 -62.71768)
		)
		(stroke
			(width 0)
			(type solid)
		)
		(fill yes)
		(layer "In4.Cu")
		(net "M_C_ECC<0>")
	)
	(gr_poly
		(pts
			(xy 243.606066 -61.3283) (xy 243.561616 -61.3283) (xy 243.391436 -61.4172) (xy 243.391436 -61.63818)
			(xy 243.561616 -61.72708) (xy 243.606066 -61.72708)
		)
		(stroke
			(width 0)
			(type solid)
		)
		(fill yes)
		(layer "In4.Cu")
		(net "M_C_ECC<0>")
	)
	(gr_poly
		(pts
			(xy 243.606066 -60.3377) (xy 243.561616 -60.3377) (xy 243.391436 -60.4266) (xy 243.391436 -60.64758)
			(xy 243.561616 -60.73648) (xy 243.606066 -60.73648)
		)
		(stroke
			(width 0)
			(type solid)
		)
		(fill yes)
		(layer "In4.Cu")
		(net "M_C_ECC<0>")
	)
	(gr_poly
		(pts
			(xy 243.606066 -59.3471) (xy 243.561616 -59.3471) (xy 243.391436 -59.436) (xy 243.391436 -59.65698)
			(xy 243.561616 -59.74588) (xy 243.606066 -59.74588)
		)
		(stroke
			(width 0)
			(type solid)
		)
		(fill yes)
		(layer "In4.Cu")
		(net "M_C_ECC<0>")
	)
	(gr_poly
		(pts
			(xy 243.606066 -58.368946) (xy 243.561616 -58.368946) (xy 243.391436 -58.457846) (xy 243.391436 -58.678826)
			(xy 243.561616 -58.767726) (xy 243.606066 -58.767726)
		)
		(stroke
			(width 0)
			(type solid)
		)
		(fill yes)
		(layer "In4.Cu")
		(net "M_C_ECC<0>")
	)
	(gr_poly
		(pts
			(xy 243.606066 -57.37225) (xy 243.561616 -57.37225) (xy 243.391436 -57.46115) (xy 243.391436 -57.68213)
			(xy 243.561616 -57.77103) (xy 243.606066 -57.77103)
		)
		(stroke
			(width 0)
			(type solid)
		)
		(fill yes)
		(layer "In4.Cu")
		(net "M_C_ECC<0>")
	)
	(gr_poly
		(pts
			(xy 243.606066 -56.3753) (xy 243.561616 -56.3753) (xy 243.391436 -56.4642) (xy 243.391436 -56.68518)
			(xy 243.561616 -56.77408) (xy 243.606066 -56.77408)
		)
		(stroke
			(width 0)
			(type solid)
		)
		(fill yes)
		(layer "In4.Cu")
		(net "M_C_ECC<0>")
	)
	(gr_poly
		(pts
			(xy 243.606066 -55.3847) (xy 243.561616 -55.3847) (xy 243.391436 -55.4736) (xy 243.391436 -55.69458)
			(xy 243.561616 -55.78348) (xy 243.606066 -55.78348)
		)
		(stroke
			(width 0)
			(type solid)
		)
		(fill yes)
		(layer "In4.Cu")
		(net "M_C_ECC<0>")
	)
	(gr_poly
		(pts
			(xy 243.606066 -54.3941) (xy 243.561616 -54.3941) (xy 243.391436 -54.483) (xy 243.391436 -54.70398)
			(xy 243.561616 -54.79288) (xy 243.606066 -54.79288)
		)
		(stroke
			(width 0)
			(type solid)
		)
		(fill yes)
		(layer "In4.Cu")
		(net "M_C_ECC<0>")
	)
	(gr_poly
		(pts
			(xy 243.606066 -53.4035) (xy 243.561616 -53.4035) (xy 243.391436 -53.4924) (xy 243.391436 -53.71338)
			(xy 243.561616 -53.80228) (xy 243.606066 -53.80228)
		)
		(stroke
			(width 0)
			(type solid)
		)
		(fill yes)
		(layer "In4.Cu")
		(net "M_C_ECC<0>")
	)
	(gr_poly
		(pts
			(xy 243.697252 -52.767738) (xy 243.652802 -52.767738) (xy 243.459762 -52.856638) (xy 243.459762 -53.085238)
			(xy 243.652802 -53.174138) (xy 243.697252 -53.174138)
		)
		(stroke
			(width 0)
			(type solid)
		)
		(fill yes)
		(layer "In4.Cu")
		(net "M_C_ECC<0>")
	)
	(gr_poly
		(pts
			(xy 243.697252 -51.777138) (xy 243.652802 -51.777138) (xy 243.459762 -51.866038) (xy 243.459762 -52.094638)
			(xy 243.652802 -52.183538) (xy 243.697252 -52.183538)
		)
		(stroke
			(width 0)
			(type solid)
		)
		(fill yes)
		(layer "In4.Cu")
		(net "M_C_ECC<0>")
	)
	(gr_poly
		(pts
			(xy 243.709444 -99.547426) (xy 243.635784 -99.348036) (xy 243.604542 -99.31654) (xy 243.317014 -99.604068)
			(xy 243.34851 -99.63531) (xy 243.5479 -99.70897)
		)
		(stroke
			(width 0)
			(type solid)
		)
		(fill yes)
		(layer "In4.Cu")
		(net "M_F_ECC<5>")
	)
	(gr_poly
		(pts
			(xy 244.042692 -85.210904) (xy 244.130576 -85.008212) (xy 244.009926 -84.85886) (xy 243.969032 -84.841334)
			(xy 243.810536 -85.207094) (xy 243.851176 -85.224874)
		)
		(stroke
			(width 0)
			(type solid)
		)
		(fill yes)
		(layer "In4.Cu")
		(net "M_F_ECC<5>")
	)
	(gr_poly
		(pts
			(xy 244.125242 -53.085238) (xy 244.125242 -52.856638) (xy 243.932202 -52.767738) (xy 243.887752 -52.767738)
			(xy 243.887752 -53.174138) (xy 243.932202 -53.174138)
		)
		(stroke
			(width 0)
			(type solid)
		)
		(fill yes)
		(layer "In4.Cu")
		(net "M_C_ECC<1>")
	)
	(gr_poly
		(pts
			(xy 244.125242 -52.094638) (xy 244.125242 -51.866038) (xy 243.932202 -51.777138) (xy 243.887752 -51.777138)
			(xy 243.887752 -52.183538) (xy 243.932202 -52.183538)
		)
		(stroke
			(width 0)
			(type solid)
		)
		(fill yes)
		(layer "In4.Cu")
		(net "M_C_ECC<1>")
	)
	(gr_poly
		(pts
			(xy 244.144038 -66.108326) (xy 244.144038 -65.887346) (xy 243.973858 -65.798446) (xy 243.929408 -65.798446)
			(xy 243.929408 -66.197226) (xy 243.973858 -66.197226)
		)
		(stroke
			(width 0)
			(type solid)
		)
		(fill yes)
		(layer "In4.Cu")
		(net "M_C_ECC<1>")
	)
	(gr_poly
		(pts
			(xy 244.144292 -97.807526) (xy 244.144292 -97.586546) (xy 243.974112 -97.497646) (xy 243.929662 -97.497646)
			(xy 243.929662 -97.896426) (xy 243.974112 -97.896426)
		)
		(stroke
			(width 0)
			(type solid)
		)
		(fill yes)
		(layer "In4.Cu")
		(net "M_F_ECC<5>")
	)
	(gr_poly
		(pts
			(xy 244.144292 -96.816926) (xy 244.144292 -96.595946) (xy 243.974112 -96.507046) (xy 243.929662 -96.507046)
			(xy 243.929662 -96.905826) (xy 243.974112 -96.905826)
		)
		(stroke
			(width 0)
			(type solid)
		)
		(fill yes)
		(layer "In4.Cu")
		(net "M_F_ECC<5>")
	)
	(gr_poly
		(pts
			(xy 244.144292 -95.826326) (xy 244.144292 -95.605346) (xy 243.974112 -95.516446) (xy 243.929662 -95.516446)
			(xy 243.929662 -95.915226) (xy 243.974112 -95.915226)
		)
		(stroke
			(width 0)
			(type solid)
		)
		(fill yes)
		(layer "In4.Cu")
		(net "M_F_ECC<5>")
	)
	(gr_poly
		(pts
			(xy 244.144292 -94.829376) (xy 244.144292 -94.608396) (xy 243.974112 -94.519496) (xy 243.929662 -94.519496)
			(xy 243.929662 -94.918276) (xy 243.974112 -94.918276)
		)
		(stroke
			(width 0)
			(type solid)
		)
		(fill yes)
		(layer "In4.Cu")
		(net "M_F_ECC<5>")
	)
	(gr_poly
		(pts
			(xy 244.144292 -93.83268) (xy 244.144292 -93.6117) (xy 243.974112 -93.5228) (xy 243.929662 -93.5228)
			(xy 243.929662 -93.92158) (xy 243.974112 -93.92158)
		)
		(stroke
			(width 0)
			(type solid)
		)
		(fill yes)
		(layer "In4.Cu")
		(net "M_F_ECC<5>")
	)
	(gr_poly
		(pts
			(xy 244.144292 -92.854526) (xy 244.144292 -92.633546) (xy 243.974112 -92.544646) (xy 243.929662 -92.544646)
			(xy 243.929662 -92.943426) (xy 243.974112 -92.943426)
		)
		(stroke
			(width 0)
			(type solid)
		)
		(fill yes)
		(layer "In4.Cu")
		(net "M_F_ECC<5>")
	)
	(gr_poly
		(pts
			(xy 244.144292 -91.863926) (xy 244.144292 -91.642946) (xy 243.974112 -91.554046) (xy 243.929662 -91.554046)
			(xy 243.929662 -91.952826) (xy 243.974112 -91.952826)
		)
		(stroke
			(width 0)
			(type solid)
		)
		(fill yes)
		(layer "In4.Cu")
		(net "M_F_ECC<5>")
	)
	(gr_poly
		(pts
			(xy 244.144292 -90.873326) (xy 244.144292 -90.652346) (xy 243.974112 -90.563446) (xy 243.929662 -90.563446)
			(xy 243.929662 -90.962226) (xy 243.974112 -90.962226)
		)
		(stroke
			(width 0)
			(type solid)
		)
		(fill yes)
		(layer "In4.Cu")
		(net "M_F_ECC<5>")
	)
	(gr_poly
		(pts
			(xy 244.144292 -89.882726) (xy 244.144292 -89.661746) (xy 243.974112 -89.572846) (xy 243.929662 -89.572846)
			(xy 243.929662 -89.971626) (xy 243.974112 -89.971626)
		)
		(stroke
			(width 0)
			(type solid)
		)
		(fill yes)
		(layer "In4.Cu")
		(net "M_F_ECC<5>")
	)
	(gr_poly
		(pts
			(xy 244.144292 -88.892126) (xy 244.144292 -88.671146) (xy 243.974112 -88.582246) (xy 243.929662 -88.582246)
			(xy 243.929662 -88.981026) (xy 243.974112 -88.981026)
		)
		(stroke
			(width 0)
			(type solid)
		)
		(fill yes)
		(layer "In4.Cu")
		(net "M_F_ECC<5>")
	)
	(gr_poly
		(pts
			(xy 244.144292 -87.901526) (xy 244.144292 -87.680546) (xy 243.974112 -87.591646) (xy 243.929662 -87.591646)
			(xy 243.929662 -87.990426) (xy 243.974112 -87.990426)
		)
		(stroke
			(width 0)
			(type solid)
		)
		(fill yes)
		(layer "In4.Cu")
		(net "M_F_ECC<5>")
	)
	(gr_poly
		(pts
			(xy 244.144292 -86.910926) (xy 244.144292 -86.689946) (xy 243.974112 -86.601046) (xy 243.929662 -86.601046)
			(xy 243.929662 -86.999826) (xy 243.974112 -86.999826)
		)
		(stroke
			(width 0)
			(type solid)
		)
		(fill yes)
		(layer "In4.Cu")
		(net "M_F_ECC<5>")
	)
	(gr_poly
		(pts
			(xy 244.144292 -85.920326) (xy 244.144292 -85.699346) (xy 243.974112 -85.610446) (xy 243.929662 -85.610446)
			(xy 243.929662 -86.009226) (xy 243.974112 -86.009226)
		)
		(stroke
			(width 0)
			(type solid)
		)
		(fill yes)
		(layer "In4.Cu")
		(net "M_F_ECC<5>")
	)
	(gr_poly
		(pts
			(xy 244.144292 -65.117726) (xy 244.144292 -64.896746) (xy 243.974112 -64.807846) (xy 243.929662 -64.807846)
			(xy 243.929662 -65.206626) (xy 243.974112 -65.206626)
		)
		(stroke
			(width 0)
			(type solid)
		)
		(fill yes)
		(layer "In4.Cu")
		(net "M_C_ECC<1>")
	)
	(gr_poly
		(pts
			(xy 244.144292 -64.127126) (xy 244.144292 -63.906146) (xy 243.974112 -63.817246) (xy 243.929662 -63.817246)
			(xy 243.929662 -64.216026) (xy 243.974112 -64.216026)
		)
		(stroke
			(width 0)
			(type solid)
		)
		(fill yes)
		(layer "In4.Cu")
		(net "M_C_ECC<1>")
	)
	(gr_poly
		(pts
			(xy 244.144292 -63.136526) (xy 244.144292 -62.915546) (xy 243.974112 -62.826646) (xy 243.929662 -62.826646)
			(xy 243.929662 -63.225426) (xy 243.974112 -63.225426)
		)
		(stroke
			(width 0)
			(type solid)
		)
		(fill yes)
		(layer "In4.Cu")
		(net "M_C_ECC<1>")
	)
	(gr_poly
		(pts
			(xy 244.144292 -62.145926) (xy 244.144292 -61.924946) (xy 243.974112 -61.836046) (xy 243.929662 -61.836046)
			(xy 243.929662 -62.234826) (xy 243.974112 -62.234826)
		)
		(stroke
			(width 0)
			(type solid)
		)
		(fill yes)
		(layer "In4.Cu")
		(net "M_C_ECC<1>")
	)
	(gr_poly
		(pts
			(xy 244.144292 -61.155326) (xy 244.144292 -60.934346) (xy 243.974112 -60.845446) (xy 243.929662 -60.845446)
			(xy 243.929662 -61.244226) (xy 243.974112 -61.244226)
		)
		(stroke
			(width 0)
			(type solid)
		)
		(fill yes)
		(layer "In4.Cu")
		(net "M_C_ECC<1>")
	)
	(gr_poly
		(pts
			(xy 244.144292 -60.164726) (xy 244.144292 -59.943746) (xy 243.974112 -59.854846) (xy 243.929662 -59.854846)
			(xy 243.929662 -60.253626) (xy 243.974112 -60.253626)
		)
		(stroke
			(width 0)
			(type solid)
		)
		(fill yes)
		(layer "In4.Cu")
		(net "M_C_ECC<1>")
	)
	(gr_poly
		(pts
			(xy 244.144292 -59.167776) (xy 244.144292 -58.946796) (xy 243.974112 -58.857896) (xy 243.929662 -58.857896)
			(xy 243.929662 -59.256676) (xy 243.974112 -59.256676)
		)
		(stroke
			(width 0)
			(type solid)
		)
		(fill yes)
		(layer "In4.Cu")
		(net "M_C_ECC<1>")
	)
	(gr_poly
		(pts
			(xy 244.144292 -58.17108) (xy 244.144292 -57.9501) (xy 243.974112 -57.8612) (xy 243.929662 -57.8612)
			(xy 243.929662 -58.25998) (xy 243.974112 -58.25998)
		)
		(stroke
			(width 0)
			(type solid)
		)
		(fill yes)
		(layer "In4.Cu")
		(net "M_C_ECC<1>")
	)
	(gr_poly
		(pts
			(xy 244.144292 -57.192926) (xy 244.144292 -56.971946) (xy 243.974112 -56.883046) (xy 243.929662 -56.883046)
			(xy 243.929662 -57.281826) (xy 243.974112 -57.281826)
		)
		(stroke
			(width 0)
			(type solid)
		)
		(fill yes)
		(layer "In4.Cu")
		(net "M_C_ECC<1>")
	)
	(gr_poly
		(pts
			(xy 244.144292 -56.202326) (xy 244.144292 -55.981346) (xy 243.974112 -55.892446) (xy 243.929662 -55.892446)
			(xy 243.929662 -56.291226) (xy 243.974112 -56.291226)
		)
		(stroke
			(width 0)
			(type solid)
		)
		(fill yes)
		(layer "In4.Cu")
		(net "M_C_ECC<1>")
	)
	(gr_poly
		(pts
			(xy 244.144292 -55.211726) (xy 244.144292 -54.990746) (xy 243.974112 -54.901846) (xy 243.929662 -54.901846)
			(xy 243.929662 -55.300626) (xy 243.974112 -55.300626)
		)
		(stroke
			(width 0)
			(type solid)
		)
		(fill yes)
		(layer "In4.Cu")
		(net "M_C_ECC<1>")
	)
	(gr_poly
		(pts
			(xy 244.144292 -54.221126) (xy 244.144292 -54.000146) (xy 243.974112 -53.911246) (xy 243.929662 -53.911246)
			(xy 243.929662 -54.310026) (xy 243.974112 -54.310026)
		)
		(stroke
			(width 0)
			(type solid)
		)
		(fill yes)
		(layer "In4.Cu")
		(net "M_C_ECC<1>")
	)
	(gr_poly
		(pts
			(xy 244.168676 -51.164998) (xy 244.168676 -50.936398) (xy 243.975636 -50.847498) (xy 243.931186 -50.847498)
			(xy 243.931186 -51.253898) (xy 243.975636 -51.253898)
		)
		(stroke
			(width 0)
			(type solid)
		)
		(fill yes)
		(layer "In4.Cu")
		(net "M_C_ECC<1>")
	)
	(gr_poly
		(pts
			(xy 244.326918 -100.093526) (xy 244.295422 -100.06203) (xy 244.096286 -99.98837) (xy 243.934488 -100.150168)
			(xy 244.008148 -100.349304) (xy 244.039644 -100.3808)
		)
		(stroke
			(width 0)
			(type solid)
		)
		(fill yes)
		(layer "In4.Cu")
		(net "M_F_ECC<0>")
	)
	(gr_poly
		(pts
			(xy 244.349778 -101.277674) (xy 244.349778 -101.049074) (xy 244.156738 -100.960174) (xy 244.112288 -100.960174)
			(xy 244.112288 -101.366574) (xy 244.156738 -101.366574)
		)
		(stroke
			(width 0)
			(type solid)
		)
		(fill yes)
		(layer "In4.Cu")
		(net "M_F_ECC<1>")
	)
	(gr_poly
		(pts
			(xy 244.354096 -99.258374) (xy 244.309646 -99.258374) (xy 244.116606 -99.347274) (xy 244.116606 -99.575874)
			(xy 244.309646 -99.664774) (xy 244.354096 -99.664774)
		)
		(stroke
			(width 0)
			(type solid)
		)
		(fill yes)
		(layer "In4.Cu")
		(net "M_F_ECC<0>")
	)
	(gr_poly
		(pts
			(xy 244.464586 -97.497646) (xy 244.420136 -97.497646) (xy 244.249956 -97.586546) (xy 244.249956 -97.807526)
			(xy 244.420136 -97.896426) (xy 244.464586 -97.896426)
		)
		(stroke
			(width 0)
			(type solid)
		)
		(fill yes)
		(layer "In4.Cu")
		(net "M_F_ECC<0>")
	)
	(gr_poly
		(pts
			(xy 244.464586 -96.507046) (xy 244.420136 -96.507046) (xy 244.249956 -96.595946) (xy 244.249956 -96.816926)
			(xy 244.420136 -96.905826) (xy 244.464586 -96.905826)
		)
		(stroke
			(width 0)
			(type solid)
		)
		(fill yes)
		(layer "In4.Cu")
		(net "M_F_ECC<0>")
	)
	(gr_poly
		(pts
			(xy 244.464586 -95.516446) (xy 244.420136 -95.516446) (xy 244.249956 -95.605346) (xy 244.249956 -95.826326)
			(xy 244.420136 -95.915226) (xy 244.464586 -95.915226)
		)
		(stroke
			(width 0)
			(type solid)
		)
		(fill yes)
		(layer "In4.Cu")
		(net "M_F_ECC<0>")
	)
	(gr_poly
		(pts
			(xy 244.464586 -94.519496) (xy 244.420136 -94.519496) (xy 244.249956 -94.608396) (xy 244.249956 -94.829376)
			(xy 244.420136 -94.918276) (xy 244.464586 -94.918276)
		)
		(stroke
			(width 0)
			(type solid)
		)
		(fill yes)
		(layer "In4.Cu")
		(net "M_F_ECC<0>")
	)
	(gr_poly
		(pts
			(xy 244.464586 -93.5228) (xy 244.420136 -93.5228) (xy 244.249956 -93.6117) (xy 244.249956 -93.83268)
			(xy 244.420136 -93.92158) (xy 244.464586 -93.92158)
		)
		(stroke
			(width 0)
			(type solid)
		)
		(fill yes)
		(layer "In4.Cu")
		(net "M_F_ECC<0>")
	)
	(gr_poly
		(pts
			(xy 244.464586 -92.544646) (xy 244.420136 -92.544646) (xy 244.249956 -92.633546) (xy 244.249956 -92.854526)
			(xy 244.420136 -92.943426) (xy 244.464586 -92.943426)
		)
		(stroke
			(width 0)
			(type solid)
		)
		(fill yes)
		(layer "In4.Cu")
		(net "M_F_ECC<0>")
	)
	(gr_poly
		(pts
			(xy 244.464586 -91.554046) (xy 244.420136 -91.554046) (xy 244.249956 -91.642946) (xy 244.249956 -91.863926)
			(xy 244.420136 -91.952826) (xy 244.464586 -91.952826)
		)
		(stroke
			(width 0)
			(type solid)
		)
		(fill yes)
		(layer "In4.Cu")
		(net "M_F_ECC<0>")
	)
	(gr_poly
		(pts
			(xy 244.464586 -90.563446) (xy 244.420136 -90.563446) (xy 244.249956 -90.652346) (xy 244.249956 -90.873326)
			(xy 244.420136 -90.962226) (xy 244.464586 -90.962226)
		)
		(stroke
			(width 0)
			(type solid)
		)
		(fill yes)
		(layer "In4.Cu")
		(net "M_F_ECC<0>")
	)
	(gr_poly
		(pts
			(xy 244.464586 -89.572846) (xy 244.420136 -89.572846) (xy 244.249956 -89.661746) (xy 244.249956 -89.882726)
			(xy 244.420136 -89.971626) (xy 244.464586 -89.971626)
		)
		(stroke
			(width 0)
			(type solid)
		)
		(fill yes)
		(layer "In4.Cu")
		(net "M_F_ECC<0>")
	)
	(gr_poly
		(pts
			(xy 244.464586 -88.582246) (xy 244.420136 -88.582246) (xy 244.249956 -88.671146) (xy 244.249956 -88.892126)
			(xy 244.420136 -88.981026) (xy 244.464586 -88.981026)
		)
		(stroke
			(width 0)
			(type solid)
		)
		(fill yes)
		(layer "In4.Cu")
		(net "M_F_ECC<0>")
	)
	(gr_poly
		(pts
			(xy 244.464586 -87.591646) (xy 244.420136 -87.591646) (xy 244.249956 -87.680546) (xy 244.249956 -87.901526)
			(xy 244.420136 -87.990426) (xy 244.464586 -87.990426)
		)
		(stroke
			(width 0)
			(type solid)
		)
		(fill yes)
		(layer "In4.Cu")
		(net "M_F_ECC<0>")
	)
	(gr_poly
		(pts
			(xy 244.464586 -86.601046) (xy 244.420136 -86.601046) (xy 244.249956 -86.689946) (xy 244.249956 -86.910926)
			(xy 244.420136 -86.999826) (xy 244.464586 -86.999826)
		)
		(stroke
			(width 0)
			(type solid)
		)
		(fill yes)
		(layer "In4.Cu")
		(net "M_F_ECC<0>")
	)
	(gr_poly
		(pts
			(xy 244.464586 -85.610446) (xy 244.420136 -85.610446) (xy 244.249956 -85.699346) (xy 244.249956 -85.920326)
			(xy 244.420136 -86.009226) (xy 244.464586 -86.009226)
		)
		(stroke
			(width 0)
			(type solid)
		)
		(fill yes)
		(layer "In4.Cu")
		(net "M_F_ECC<0>")
	)
	(gr_poly
		(pts
			(xy 244.464586 -84.619846) (xy 244.420136 -84.619846) (xy 244.249956 -84.708746) (xy 244.249956 -84.929726)
			(xy 244.420136 -85.018626) (xy 244.464586 -85.018626)
		)
		(stroke
			(width 0)
			(type solid)
		)
		(fill yes)
		(layer "In4.Cu")
		(net "M_F_ECC<0>")
	)
	(gr_poly
		(pts
			(xy 244.464586 -83.629246) (xy 244.420136 -83.629246) (xy 244.249956 -83.718146) (xy 244.249956 -83.939126)
			(xy 244.420136 -84.028026) (xy 244.464586 -84.028026)
		)
		(stroke
			(width 0)
			(type solid)
		)
		(fill yes)
		(layer "In4.Cu")
		(net "M_F_ECC<0>")
	)
	(gr_poly
		(pts
			(xy 244.464586 -65.798446) (xy 244.420136 -65.798446) (xy 244.249956 -65.887346) (xy 244.249956 -66.108326)
			(xy 244.420136 -66.197226) (xy 244.464586 -66.197226)
		)
		(stroke
			(width 0)
			(type solid)
		)
		(fill yes)
		(layer "In4.Cu")
		(net "M_C_DQS_DP<17>")
	)
	(gr_poly
		(pts
			(xy 244.464586 -64.807846) (xy 244.420136 -64.807846) (xy 244.249956 -64.896746) (xy 244.249956 -65.117726)
			(xy 244.420136 -65.206626) (xy 244.464586 -65.206626)
		)
		(stroke
			(width 0)
			(type solid)
		)
		(fill yes)
		(layer "In4.Cu")
		(net "M_C_DQS_DP<17>")
	)
	(gr_poly
		(pts
			(xy 244.464586 -63.817246) (xy 244.420136 -63.817246) (xy 244.249956 -63.906146) (xy 244.249956 -64.127126)
			(xy 244.420136 -64.216026) (xy 244.464586 -64.216026)
		)
		(stroke
			(width 0)
			(type solid)
		)
		(fill yes)
		(layer "In4.Cu")
		(net "M_C_DQS_DP<17>")
	)
	(gr_poly
		(pts
			(xy 244.464586 -62.826646) (xy 244.420136 -62.826646) (xy 244.249956 -62.915546) (xy 244.249956 -63.136526)
			(xy 244.420136 -63.225426) (xy 244.464586 -63.225426)
		)
		(stroke
			(width 0)
			(type solid)
		)
		(fill yes)
		(layer "In4.Cu")
		(net "M_C_DQS_DP<17>")
	)
	(gr_poly
		(pts
			(xy 244.464586 -61.836046) (xy 244.420136 -61.836046) (xy 244.249956 -61.924946) (xy 244.249956 -62.145926)
			(xy 244.420136 -62.234826) (xy 244.464586 -62.234826)
		)
		(stroke
			(width 0)
			(type solid)
		)
		(fill yes)
		(layer "In4.Cu")
		(net "M_C_DQS_DP<17>")
	)
	(gr_poly
		(pts
			(xy 244.464586 -60.845446) (xy 244.420136 -60.845446) (xy 244.249956 -60.934346) (xy 244.249956 -61.155326)
			(xy 244.420136 -61.244226) (xy 244.464586 -61.244226)
		)
		(stroke
			(width 0)
			(type solid)
		)
		(fill yes)
		(layer "In4.Cu")
		(net "M_C_DQS_DP<17>")
	)
	(gr_poly
		(pts
			(xy 244.464586 -59.854846) (xy 244.420136 -59.854846) (xy 244.249956 -59.943746) (xy 244.249956 -60.164726)
			(xy 244.420136 -60.253626) (xy 244.464586 -60.253626)
		)
		(stroke
			(width 0)
			(type solid)
		)
		(fill yes)
		(layer "In4.Cu")
		(net "M_C_DQS_DP<17>")
	)
	(gr_poly
		(pts
			(xy 244.464586 -58.857896) (xy 244.420136 -58.857896) (xy 244.249956 -58.946796) (xy 244.249956 -59.167776)
			(xy 244.420136 -59.256676) (xy 244.464586 -59.256676)
		)
		(stroke
			(width 0)
			(type solid)
		)
		(fill yes)
		(layer "In4.Cu")
		(net "M_C_DQS_DP<17>")
	)
	(gr_poly
		(pts
			(xy 244.464586 -57.8612) (xy 244.420136 -57.8612) (xy 244.249956 -57.9501) (xy 244.249956 -58.17108)
			(xy 244.420136 -58.25998) (xy 244.464586 -58.25998)
		)
		(stroke
			(width 0)
			(type solid)
		)
		(fill yes)
		(layer "In4.Cu")
		(net "M_C_DQS_DP<17>")
	)
	(gr_poly
		(pts
			(xy 244.464586 -56.883046) (xy 244.420136 -56.883046) (xy 244.249956 -56.971946) (xy 244.249956 -57.192926)
			(xy 244.420136 -57.281826) (xy 244.464586 -57.281826)
		)
		(stroke
			(width 0)
			(type solid)
		)
		(fill yes)
		(layer "In4.Cu")
		(net "M_C_DQS_DP<17>")
	)
	(gr_poly
		(pts
			(xy 244.464586 -55.892446) (xy 244.420136 -55.892446) (xy 244.249956 -55.981346) (xy 244.249956 -56.202326)
			(xy 244.420136 -56.291226) (xy 244.464586 -56.291226)
		)
		(stroke
			(width 0)
			(type solid)
		)
		(fill yes)
		(layer "In4.Cu")
		(net "M_C_DQS_DP<17>")
	)
	(gr_poly
		(pts
			(xy 244.464586 -54.901846) (xy 244.420136 -54.901846) (xy 244.249956 -54.990746) (xy 244.249956 -55.211726)
			(xy 244.420136 -55.300626) (xy 244.464586 -55.300626)
		)
		(stroke
			(width 0)
			(type solid)
		)
		(fill yes)
		(layer "In4.Cu")
		(net "M_C_DQS_DP<17>")
	)
	(gr_poly
		(pts
			(xy 244.464586 -53.911246) (xy 244.420136 -53.911246) (xy 244.249956 -54.000146) (xy 244.249956 -54.221126)
			(xy 244.420136 -54.310026) (xy 244.464586 -54.310026)
		)
		(stroke
			(width 0)
			(type solid)
		)
		(fill yes)
		(layer "In4.Cu")
		(net "M_C_DQS_DP<17>")
	)
	(gr_poly
		(pts
			(xy 244.56644 -100.458524) (xy 244.49278 -100.259134) (xy 244.461284 -100.227892) (xy 244.17401 -100.515166)
			(xy 244.205506 -100.546662) (xy 244.404642 -100.620322)
		)
		(stroke
			(width 0)
			(type solid)
		)
		(fill yes)
		(layer "In4.Cu")
		(net "M_F_ECC<1>")
	)
	(gr_poly
		(pts
			(xy 244.773704 -51.220878) (xy 244.729254 -51.220878) (xy 244.536214 -51.309778) (xy 244.536214 -51.538378)
			(xy 244.729254 -51.627278) (xy 244.773704 -51.627278)
		)
		(stroke
			(width 0)
			(type solid)
		)
		(fill yes)
		(layer "In4.Cu")
		(net "M_C_DQS_DP<17>")
	)
	(gr_poly
		(pts
			(xy 244.773704 -50.230278) (xy 244.729254 -50.230278) (xy 244.536214 -50.319178) (xy 244.536214 -50.547778)
			(xy 244.729254 -50.636678) (xy 244.773704 -50.636678)
		)
		(stroke
			(width 0)
			(type solid)
		)
		(fill yes)
		(layer "In4.Cu")
		(net "M_C_DQS_DP<17>")
	)
	(gr_poly
		(pts
			(xy 244.781578 -99.321874) (xy 244.781578 -99.093274) (xy 244.588538 -99.004374) (xy 244.544088 -99.004374)
			(xy 244.544088 -99.410774) (xy 244.588538 -99.410774)
		)
		(stroke
			(width 0)
			(type solid)
		)
		(fill yes)
		(layer "In4.Cu")
		(net "M_F_ECC<1>")
	)
	(gr_poly
		(pts
			(xy 244.812058 -84.42325) (xy 244.812058 -84.20227) (xy 244.641878 -84.11337) (xy 244.597428 -84.11337)
			(xy 244.597428 -84.51215) (xy 244.641878 -84.51215)
		)
		(stroke
			(width 0)
			(type solid)
		)
		(fill yes)
		(layer "In4.Cu")
		(net "M_F_ECC<0>")
	)
	(gr_poly
		(pts
			(xy 244.915436 -85.676994) (xy 245.009924 -85.47735) (xy 244.893846 -85.324188) (xy 244.853714 -85.305138)
			(xy 244.68328 -85.665818) (xy 244.723412 -85.684868)
		)
		(stroke
			(width 0)
			(type solid)
		)
		(fill yes)
		(layer "In4.Cu")
		(net "M_F_ECC<1>")
	)
	(gr_poly
		(pts
			(xy 245.002812 -98.29038) (xy 245.002812 -98.0694) (xy 244.832632 -97.9805) (xy 244.788182 -97.9805)
			(xy 244.788182 -98.37928) (xy 244.832632 -98.37928)
		)
		(stroke
			(width 0)
			(type solid)
		)
		(fill yes)
		(layer "In4.Cu")
		(net "M_F_ECC<1>")
	)
	(gr_poly
		(pts
			(xy 245.002812 -97.29978) (xy 245.002812 -97.0788) (xy 244.832632 -96.9899) (xy 244.788182 -96.9899)
			(xy 244.788182 -97.38868) (xy 244.832632 -97.38868)
		)
		(stroke
			(width 0)
			(type solid)
		)
		(fill yes)
		(layer "In4.Cu")
		(net "M_F_ECC<1>")
	)
	(gr_poly
		(pts
			(xy 245.002812 -96.30918) (xy 245.002812 -96.0882) (xy 244.832632 -95.9993) (xy 244.788182 -95.9993)
			(xy 244.788182 -96.39808) (xy 244.832632 -96.39808)
		)
		(stroke
			(width 0)
			(type solid)
		)
		(fill yes)
		(layer "In4.Cu")
		(net "M_F_ECC<1>")
	)
	(gr_poly
		(pts
			(xy 245.002812 -95.31858) (xy 245.002812 -95.0976) (xy 244.832632 -95.0087) (xy 244.788182 -95.0087)
			(xy 244.788182 -95.40748) (xy 244.832632 -95.40748)
		)
		(stroke
			(width 0)
			(type solid)
		)
		(fill yes)
		(layer "In4.Cu")
		(net "M_F_ECC<1>")
	)
	(gr_poly
		(pts
			(xy 245.002812 -94.340426) (xy 245.002812 -94.119446) (xy 244.832632 -94.030546) (xy 244.788182 -94.030546)
			(xy 244.788182 -94.429326) (xy 244.832632 -94.429326)
		)
		(stroke
			(width 0)
			(type solid)
		)
		(fill yes)
		(layer "In4.Cu")
		(net "M_F_ECC<1>")
	)
	(gr_poly
		(pts
			(xy 245.002812 -93.34373) (xy 245.002812 -93.12275) (xy 244.832632 -93.03385) (xy 244.788182 -93.03385)
			(xy 244.788182 -93.43263) (xy 244.832632 -93.43263)
		)
		(stroke
			(width 0)
			(type solid)
		)
		(fill yes)
		(layer "In4.Cu")
		(net "M_F_ECC<1>")
	)
	(gr_poly
		(pts
			(xy 245.002812 -92.34678) (xy 245.002812 -92.1258) (xy 244.832632 -92.0369) (xy 244.788182 -92.0369)
			(xy 244.788182 -92.43568) (xy 244.832632 -92.43568)
		)
		(stroke
			(width 0)
			(type solid)
		)
		(fill yes)
		(layer "In4.Cu")
		(net "M_F_ECC<1>")
	)
	(gr_poly
		(pts
			(xy 245.002812 -91.35618) (xy 245.002812 -91.1352) (xy 244.832632 -91.0463) (xy 244.788182 -91.0463)
			(xy 244.788182 -91.44508) (xy 244.832632 -91.44508)
		)
		(stroke
			(width 0)
			(type solid)
		)
		(fill yes)
		(layer "In4.Cu")
		(net "M_F_ECC<1>")
	)
	(gr_poly
		(pts
			(xy 245.002812 -90.36558) (xy 245.002812 -90.1446) (xy 244.832632 -90.0557) (xy 244.788182 -90.0557)
			(xy 244.788182 -90.45448) (xy 244.832632 -90.45448)
		)
		(stroke
			(width 0)
			(type solid)
		)
		(fill yes)
		(layer "In4.Cu")
		(net "M_F_ECC<1>")
	)
	(gr_poly
		(pts
			(xy 245.002812 -89.37498) (xy 245.002812 -89.154) (xy 244.832632 -89.0651) (xy 244.788182 -89.0651)
			(xy 244.788182 -89.46388) (xy 244.832632 -89.46388)
		)
		(stroke
			(width 0)
			(type solid)
		)
		(fill yes)
		(layer "In4.Cu")
		(net "M_F_ECC<1>")
	)
	(gr_poly
		(pts
			(xy 245.002812 -88.38438) (xy 245.002812 -88.1634) (xy 244.832632 -88.0745) (xy 244.788182 -88.0745)
			(xy 244.788182 -88.47328) (xy 244.832632 -88.47328)
		)
		(stroke
			(width 0)
			(type solid)
		)
		(fill yes)
		(layer "In4.Cu")
		(net "M_F_ECC<1>")
	)
	(gr_poly
		(pts
			(xy 245.002812 -87.39378) (xy 245.002812 -87.1728) (xy 244.832632 -87.0839) (xy 244.788182 -87.0839)
			(xy 244.788182 -87.48268) (xy 244.832632 -87.48268)
		)
		(stroke
			(width 0)
			(type solid)
		)
		(fill yes)
		(layer "In4.Cu")
		(net "M_F_ECC<1>")
	)
	(gr_poly
		(pts
			(xy 245.002812 -86.40318) (xy 245.002812 -86.1822) (xy 244.832632 -86.0933) (xy 244.788182 -86.0933)
			(xy 244.788182 -86.49208) (xy 244.832632 -86.49208)
		)
		(stroke
			(width 0)
			(type solid)
		)
		(fill yes)
		(layer "In4.Cu")
		(net "M_F_ECC<1>")
	)
	(gr_poly
		(pts
			(xy 245.002812 -65.60058) (xy 245.002812 -65.3796) (xy 244.832632 -65.2907) (xy 244.788182 -65.2907)
			(xy 244.788182 -65.68948) (xy 244.832632 -65.68948)
		)
		(stroke
			(width 0)
			(type solid)
		)
		(fill yes)
		(layer "In4.Cu")
		(net "M_C_DQS_DN<17>")
	)
	(gr_poly
		(pts
			(xy 245.002812 -64.60998) (xy 245.002812 -64.389) (xy 244.832632 -64.3001) (xy 244.788182 -64.3001)
			(xy 244.788182 -64.69888) (xy 244.832632 -64.69888)
		)
		(stroke
			(width 0)
			(type solid)
		)
		(fill yes)
		(layer "In4.Cu")
		(net "M_C_DQS_DN<17>")
	)
	(gr_poly
		(pts
			(xy 245.002812 -63.61938) (xy 245.002812 -63.3984) (xy 244.832632 -63.3095) (xy 244.788182 -63.3095)
			(xy 244.788182 -63.70828) (xy 244.832632 -63.70828)
		)
		(stroke
			(width 0)
			(type solid)
		)
		(fill yes)
		(layer "In4.Cu")
		(net "M_C_DQS_DN<17>")
	)
	(gr_poly
		(pts
			(xy 245.002812 -62.62878) (xy 245.002812 -62.4078) (xy 244.832632 -62.3189) (xy 244.788182 -62.3189)
			(xy 244.788182 -62.71768) (xy 244.832632 -62.71768)
		)
		(stroke
			(width 0)
			(type solid)
		)
		(fill yes)
		(layer "In4.Cu")
		(net "M_C_DQS_DN<17>")
	)
	(gr_poly
		(pts
			(xy 245.002812 -61.63818) (xy 245.002812 -61.4172) (xy 244.832632 -61.3283) (xy 244.788182 -61.3283)
			(xy 244.788182 -61.72708) (xy 244.832632 -61.72708)
		)
		(stroke
			(width 0)
			(type solid)
		)
		(fill yes)
		(layer "In4.Cu")
		(net "M_C_DQS_DN<17>")
	)
	(gr_poly
		(pts
			(xy 245.002812 -60.64758) (xy 245.002812 -60.4266) (xy 244.832632 -60.3377) (xy 244.788182 -60.3377)
			(xy 244.788182 -60.73648) (xy 244.832632 -60.73648)
		)
		(stroke
			(width 0)
			(type solid)
		)
		(fill yes)
		(layer "In4.Cu")
		(net "M_C_DQS_DN<17>")
	)
	(gr_poly
		(pts
			(xy 245.002812 -59.65698) (xy 245.002812 -59.436) (xy 244.832632 -59.3471) (xy 244.788182 -59.3471)
			(xy 244.788182 -59.74588) (xy 244.832632 -59.74588)
		)
		(stroke
			(width 0)
			(type solid)
		)
		(fill yes)
		(layer "In4.Cu")
		(net "M_C_DQS_DN<17>")
	)
	(gr_poly
		(pts
			(xy 245.002812 -58.678826) (xy 245.002812 -58.457846) (xy 244.832632 -58.368946) (xy 244.788182 -58.368946)
			(xy 244.788182 -58.767726) (xy 244.832632 -58.767726)
		)
		(stroke
			(width 0)
			(type solid)
		)
		(fill yes)
		(layer "In4.Cu")
		(net "M_C_DQS_DN<17>")
	)
	(gr_poly
		(pts
			(xy 245.002812 -57.68213) (xy 245.002812 -57.46115) (xy 244.832632 -57.37225) (xy 244.788182 -57.37225)
			(xy 244.788182 -57.77103) (xy 244.832632 -57.77103)
		)
		(stroke
			(width 0)
			(type solid)
		)
		(fill yes)
		(layer "In4.Cu")
		(net "M_C_DQS_DN<17>")
	)
	(gr_poly
		(pts
			(xy 245.002812 -56.68518) (xy 245.002812 -56.4642) (xy 244.832632 -56.3753) (xy 244.788182 -56.3753)
			(xy 244.788182 -56.77408) (xy 244.832632 -56.77408)
		)
		(stroke
			(width 0)
			(type solid)
		)
		(fill yes)
		(layer "In4.Cu")
		(net "M_C_DQS_DN<17>")
	)
	(gr_poly
		(pts
			(xy 245.002812 -55.69458) (xy 245.002812 -55.4736) (xy 244.832632 -55.3847) (xy 244.788182 -55.3847)
			(xy 244.788182 -55.78348) (xy 244.832632 -55.78348)
		)
		(stroke
			(width 0)
			(type solid)
		)
		(fill yes)
		(layer "In4.Cu")
		(net "M_C_DQS_DN<17>")
	)
	(gr_poly
		(pts
			(xy 245.002812 -54.70398) (xy 245.002812 -54.483) (xy 244.832632 -54.3941) (xy 244.788182 -54.3941)
			(xy 244.788182 -54.79288) (xy 244.832632 -54.79288)
		)
		(stroke
			(width 0)
			(type solid)
		)
		(fill yes)
		(layer "In4.Cu")
		(net "M_C_DQS_DN<17>")
	)
	(gr_poly
		(pts
			(xy 245.002812 -53.71338) (xy 245.002812 -53.4924) (xy 244.832632 -53.4035) (xy 244.788182 -53.4035)
			(xy 244.788182 -53.80228) (xy 244.832632 -53.80228)
		)
		(stroke
			(width 0)
			(type solid)
		)
		(fill yes)
		(layer "In4.Cu")
		(net "M_C_DQS_DN<17>")
	)
	(gr_poly
		(pts
			(xy 245.094252 -101.224842) (xy 245.049802 -101.224842) (xy 244.856762 -101.313742) (xy 244.856762 -101.542342)
			(xy 245.049802 -101.631242) (xy 245.094252 -101.631242)
		)
		(stroke
			(width 0)
			(type solid)
		)
		(fill yes)
		(layer "In4.Cu")
		(net "M_F_DQS_DP<17>")
	)
	(gr_poly
		(pts
			(xy 245.201694 -51.538378) (xy 245.201694 -51.309778) (xy 245.008654 -51.220878) (xy 244.964204 -51.220878)
			(xy 244.964204 -51.627278) (xy 245.008654 -51.627278)
		)
		(stroke
			(width 0)
			(type solid)
		)
		(fill yes)
		(layer "In4.Cu")
		(net "M_C_DQS_DN<17>")
	)
	(gr_poly
		(pts
			(xy 245.201694 -50.547778) (xy 245.201694 -50.319178) (xy 245.008654 -50.230278) (xy 244.964204 -50.230278)
			(xy 244.964204 -50.636678) (xy 245.008654 -50.636678)
		)
		(stroke
			(width 0)
			(type solid)
		)
		(fill yes)
		(layer "In4.Cu")
		(net "M_C_DQS_DN<17>")
	)
	(gr_poly
		(pts
			(xy 245.323106 -98.97745) (xy 245.278656 -98.97745) (xy 245.108476 -99.06635) (xy 245.108476 -99.28733)
			(xy 245.278656 -99.37623) (xy 245.323106 -99.37623)
		)
		(stroke
			(width 0)
			(type solid)
		)
		(fill yes)
		(layer "In4.Cu")
		(net "M_F_DQS_DP<17>")
	)
	(gr_poly
		(pts
			(xy 245.323106 -97.9805) (xy 245.278656 -97.9805) (xy 245.108476 -98.0694) (xy 245.108476 -98.29038)
			(xy 245.278656 -98.37928) (xy 245.323106 -98.37928)
		)
		(stroke
			(width 0)
			(type solid)
		)
		(fill yes)
		(layer "In4.Cu")
		(net "M_F_DQS_DP<17>")
	)
	(gr_poly
		(pts
			(xy 245.323106 -96.9899) (xy 245.278656 -96.9899) (xy 245.108476 -97.0788) (xy 245.108476 -97.29978)
			(xy 245.278656 -97.38868) (xy 245.323106 -97.38868)
		)
		(stroke
			(width 0)
			(type solid)
		)
		(fill yes)
		(layer "In4.Cu")
		(net "M_F_DQS_DP<17>")
	)
	(gr_poly
		(pts
			(xy 245.323106 -95.9993) (xy 245.278656 -95.9993) (xy 245.108476 -96.0882) (xy 245.108476 -96.30918)
			(xy 245.278656 -96.39808) (xy 245.323106 -96.39808)
		)
		(stroke
			(width 0)
			(type solid)
		)
		(fill yes)
		(layer "In4.Cu")
		(net "M_F_DQS_DP<17>")
	)
	(gr_poly
		(pts
			(xy 245.323106 -95.0087) (xy 245.278656 -95.0087) (xy 245.108476 -95.0976) (xy 245.108476 -95.31858)
			(xy 245.278656 -95.40748) (xy 245.323106 -95.40748)
		)
		(stroke
			(width 0)
			(type solid)
		)
		(fill yes)
		(layer "In4.Cu")
		(net "M_F_DQS_DP<17>")
	)
	(gr_poly
		(pts
			(xy 245.323106 -94.030546) (xy 245.278656 -94.030546) (xy 245.108476 -94.119446) (xy 245.108476 -94.340426)
			(xy 245.278656 -94.429326) (xy 245.323106 -94.429326)
		)
		(stroke
			(width 0)
			(type solid)
		)
		(fill yes)
		(layer "In4.Cu")
		(net "M_F_DQS_DP<17>")
	)
	(gr_poly
		(pts
			(xy 245.323106 -93.03385) (xy 245.278656 -93.03385) (xy 245.108476 -93.12275) (xy 245.108476 -93.34373)
			(xy 245.278656 -93.43263) (xy 245.323106 -93.43263)
		)
		(stroke
			(width 0)
			(type solid)
		)
		(fill yes)
		(layer "In4.Cu")
		(net "M_F_DQS_DP<17>")
	)
	(gr_poly
		(pts
			(xy 245.323106 -92.0369) (xy 245.278656 -92.0369) (xy 245.108476 -92.1258) (xy 245.108476 -92.34678)
			(xy 245.278656 -92.43568) (xy 245.323106 -92.43568)
		)
		(stroke
			(width 0)
			(type solid)
		)
		(fill yes)
		(layer "In4.Cu")
		(net "M_F_DQS_DP<17>")
	)
	(gr_poly
		(pts
			(xy 245.323106 -91.0463) (xy 245.278656 -91.0463) (xy 245.108476 -91.1352) (xy 245.108476 -91.35618)
			(xy 245.278656 -91.44508) (xy 245.323106 -91.44508)
		)
		(stroke
			(width 0)
			(type solid)
		)
		(fill yes)
		(layer "In4.Cu")
		(net "M_F_DQS_DP<17>")
	)
	(gr_poly
		(pts
			(xy 245.323106 -90.0557) (xy 245.278656 -90.0557) (xy 245.108476 -90.1446) (xy 245.108476 -90.36558)
			(xy 245.278656 -90.45448) (xy 245.323106 -90.45448)
		)
		(stroke
			(width 0)
			(type solid)
		)
		(fill yes)
		(layer "In4.Cu")
		(net "M_F_DQS_DP<17>")
	)
	(gr_poly
		(pts
			(xy 245.323106 -89.0651) (xy 245.278656 -89.0651) (xy 245.108476 -89.154) (xy 245.108476 -89.37498)
			(xy 245.278656 -89.46388) (xy 245.323106 -89.46388)
		)
		(stroke
			(width 0)
			(type solid)
		)
		(fill yes)
		(layer "In4.Cu")
		(net "M_F_DQS_DP<17>")
	)
	(gr_poly
		(pts
			(xy 245.323106 -88.0745) (xy 245.278656 -88.0745) (xy 245.108476 -88.1634) (xy 245.108476 -88.38438)
			(xy 245.278656 -88.47328) (xy 245.323106 -88.47328)
		)
		(stroke
			(width 0)
			(type solid)
		)
		(fill yes)
		(layer "In4.Cu")
		(net "M_F_DQS_DP<17>")
	)
	(gr_poly
		(pts
			(xy 245.323106 -87.0839) (xy 245.278656 -87.0839) (xy 245.108476 -87.1728) (xy 245.108476 -87.39378)
			(xy 245.278656 -87.48268) (xy 245.323106 -87.48268)
		)
		(stroke
			(width 0)
			(type solid)
		)
		(fill yes)
		(layer "In4.Cu")
		(net "M_F_DQS_DP<17>")
	)
	(gr_poly
		(pts
			(xy 245.323106 -86.0933) (xy 245.278656 -86.0933) (xy 245.108476 -86.1822) (xy 245.108476 -86.40318)
			(xy 245.278656 -86.49208) (xy 245.323106 -86.49208)
		)
		(stroke
			(width 0)
			(type solid)
		)
		(fill yes)
		(layer "In4.Cu")
		(net "M_F_DQS_DP<17>")
	)
	(gr_poly
		(pts
			(xy 245.323106 -85.1027) (xy 245.278656 -85.1027) (xy 245.108476 -85.1916) (xy 245.108476 -85.41258)
			(xy 245.278656 -85.50148) (xy 245.323106 -85.50148)
		)
		(stroke
			(width 0)
			(type solid)
		)
		(fill yes)
		(layer "In4.Cu")
		(net "M_F_DQS_DP<17>")
	)
	(gr_poly
		(pts
			(xy 245.323106 -84.1121) (xy 245.278656 -84.1121) (xy 245.108476 -84.201) (xy 245.108476 -84.42198)
			(xy 245.278656 -84.51088) (xy 245.323106 -84.51088)
		)
		(stroke
			(width 0)
			(type solid)
		)
		(fill yes)
		(layer "In4.Cu")
		(net "M_F_DQS_DP<17>")
	)
	(gr_poly
		(pts
			(xy 245.323106 -83.1215) (xy 245.278656 -83.1215) (xy 245.108476 -83.2104) (xy 245.108476 -83.43138)
			(xy 245.278656 -83.52028) (xy 245.323106 -83.52028)
		)
		(stroke
			(width 0)
			(type solid)
		)
		(fill yes)
		(layer "In4.Cu")
		(net "M_F_DQS_DP<17>")
	)
	(gr_poly
		(pts
			(xy 245.323106 -67.2719) (xy 245.278656 -67.2719) (xy 245.108476 -67.3608) (xy 245.108476 -67.58178)
			(xy 245.278656 -67.67068) (xy 245.323106 -67.67068)
		)
		(stroke
			(width 0)
			(type solid)
		)
		(fill yes)
		(layer "In4.Cu")
		(net "M_C_DQS_DP<8>")
	)
	(gr_poly
		(pts
			(xy 245.323106 -66.287396) (xy 245.278656 -66.287396) (xy 245.108476 -66.376296) (xy 245.108476 -66.597276)
			(xy 245.278656 -66.686176) (xy 245.323106 -66.686176)
		)
		(stroke
			(width 0)
			(type solid)
		)
		(fill yes)
		(layer "In4.Cu")
		(net "M_C_DQS_DP<8>")
	)
	(gr_poly
		(pts
			(xy 245.323106 -65.2907) (xy 245.278656 -65.2907) (xy 245.108476 -65.3796) (xy 245.108476 -65.60058)
			(xy 245.278656 -65.68948) (xy 245.323106 -65.68948)
		)
		(stroke
			(width 0)
			(type solid)
		)
		(fill yes)
		(layer "In4.Cu")
		(net "M_C_DQS_DP<8>")
	)
	(gr_poly
		(pts
			(xy 245.323106 -64.3001) (xy 245.278656 -64.3001) (xy 245.108476 -64.389) (xy 245.108476 -64.60998)
			(xy 245.278656 -64.69888) (xy 245.323106 -64.69888)
		)
		(stroke
			(width 0)
			(type solid)
		)
		(fill yes)
		(layer "In4.Cu")
		(net "M_C_DQS_DP<8>")
	)
	(gr_poly
		(pts
			(xy 245.323106 -63.3095) (xy 245.278656 -63.3095) (xy 245.108476 -63.3984) (xy 245.108476 -63.61938)
			(xy 245.278656 -63.70828) (xy 245.323106 -63.70828)
		)
		(stroke
			(width 0)
			(type solid)
		)
		(fill yes)
		(layer "In4.Cu")
		(net "M_C_DQS_DP<8>")
	)
	(gr_poly
		(pts
			(xy 245.323106 -62.3189) (xy 245.278656 -62.3189) (xy 245.108476 -62.4078) (xy 245.108476 -62.62878)
			(xy 245.278656 -62.71768) (xy 245.323106 -62.71768)
		)
		(stroke
			(width 0)
			(type solid)
		)
		(fill yes)
		(layer "In4.Cu")
		(net "M_C_DQS_DP<8>")
	)
	(gr_poly
		(pts
			(xy 245.323106 -61.3283) (xy 245.278656 -61.3283) (xy 245.108476 -61.4172) (xy 245.108476 -61.63818)
			(xy 245.278656 -61.72708) (xy 245.323106 -61.72708)
		)
		(stroke
			(width 0)
			(type solid)
		)
		(fill yes)
		(layer "In4.Cu")
		(net "M_C_DQS_DP<8>")
	)
	(gr_poly
		(pts
			(xy 245.323106 -60.3377) (xy 245.278656 -60.3377) (xy 245.108476 -60.4266) (xy 245.108476 -60.64758)
			(xy 245.278656 -60.73648) (xy 245.323106 -60.73648)
		)
		(stroke
			(width 0)
			(type solid)
		)
		(fill yes)
		(layer "In4.Cu")
		(net "M_C_DQS_DP<8>")
	)
	(gr_poly
		(pts
			(xy 245.323106 -59.3471) (xy 245.278656 -59.3471) (xy 245.108476 -59.436) (xy 245.108476 -59.65698)
			(xy 245.278656 -59.74588) (xy 245.323106 -59.74588)
		)
		(stroke
			(width 0)
			(type solid)
		)
		(fill yes)
		(layer "In4.Cu")
		(net "M_C_DQS_DP<8>")
	)
	(gr_poly
		(pts
			(xy 245.323106 -58.368946) (xy 245.278656 -58.368946) (xy 245.108476 -58.457846) (xy 245.108476 -58.678826)
			(xy 245.278656 -58.767726) (xy 245.323106 -58.767726)
		)
		(stroke
			(width 0)
			(type solid)
		)
		(fill yes)
		(layer "In4.Cu")
		(net "M_C_DQS_DP<8>")
	)
	(gr_poly
		(pts
			(xy 245.323106 -57.37225) (xy 245.278656 -57.37225) (xy 245.108476 -57.46115) (xy 245.108476 -57.68213)
			(xy 245.278656 -57.77103) (xy 245.323106 -57.77103)
		)
		(stroke
			(width 0)
			(type solid)
		)
		(fill yes)
		(layer "In4.Cu")
		(net "M_C_DQS_DP<8>")
	)
	(gr_poly
		(pts
			(xy 245.323106 -56.3753) (xy 245.278656 -56.3753) (xy 245.108476 -56.4642) (xy 245.108476 -56.68518)
			(xy 245.278656 -56.77408) (xy 245.323106 -56.77408)
		)
		(stroke
			(width 0)
			(type solid)
		)
		(fill yes)
		(layer "In4.Cu")
		(net "M_C_DQS_DP<8>")
	)
	(gr_poly
		(pts
			(xy 245.323106 -55.3847) (xy 245.278656 -55.3847) (xy 245.108476 -55.4736) (xy 245.108476 -55.69458)
			(xy 245.278656 -55.78348) (xy 245.323106 -55.78348)
		)
		(stroke
			(width 0)
			(type solid)
		)
		(fill yes)
		(layer "In4.Cu")
		(net "M_C_DQS_DP<8>")
	)
	(gr_poly
		(pts
			(xy 245.487444 -54.386734) (xy 245.442994 -54.386734) (xy 245.249954 -54.475634) (xy 245.249954 -54.704234)
			(xy 245.442994 -54.793134) (xy 245.487444 -54.793134)
		)
		(stroke
			(width 0)
			(type solid)
		)
		(fill yes)
		(layer "In4.Cu")
		(net "M_C_DQS_DP<8>")
	)
	(gr_poly
		(pts
			(xy 245.487444 -53.396134) (xy 245.442994 -53.396134) (xy 245.249954 -53.485034) (xy 245.249954 -53.713634)
			(xy 245.442994 -53.802534) (xy 245.487444 -53.802534)
		)
		(stroke
			(width 0)
			(type solid)
		)
		(fill yes)
		(layer "In4.Cu")
		(net "M_C_DQS_DP<8>")
	)
	(gr_poly
		(pts
			(xy 245.522242 -101.542342) (xy 245.522242 -101.313742) (xy 245.329202 -101.224842) (xy 245.284752 -101.224842)
			(xy 245.284752 -101.631242) (xy 245.329202 -101.631242)
		)
		(stroke
			(width 0)
			(type solid)
		)
		(fill yes)
		(layer "In4.Cu")
		(net "M_F_DQS_DN<17>")
	)
	(gr_poly
		(pts
			(xy 245.861078 -99.778566) (xy 245.861078 -99.557586) (xy 245.690898 -99.468686) (xy 245.646448 -99.468686)
			(xy 245.646448 -99.867466) (xy 245.690898 -99.867466)
		)
		(stroke
			(width 0)
			(type solid)
		)
		(fill yes)
		(layer "In4.Cu")
		(net "M_F_DQS_DN<17>")
	)
	(gr_poly
		(pts
			(xy 245.861078 -66.108326) (xy 245.861078 -65.887346) (xy 245.690898 -65.798446) (xy 245.646448 -65.798446)
			(xy 245.646448 -66.197226) (xy 245.690898 -66.197226)
		)
		(stroke
			(width 0)
			(type solid)
		)
		(fill yes)
		(layer "In4.Cu")
		(net "M_C_DQS_DN<8>")
	)
	(gr_poly
		(pts
			(xy 245.861332 -98.798126) (xy 245.861332 -98.577146) (xy 245.691152 -98.488246) (xy 245.646702 -98.488246)
			(xy 245.646702 -98.887026) (xy 245.691152 -98.887026)
		)
		(stroke
			(width 0)
			(type solid)
		)
		(fill yes)
		(layer "In4.Cu")
		(net "M_F_DQS_DN<17>")
	)
	(gr_poly
		(pts
			(xy 245.861332 -97.807526) (xy 245.861332 -97.586546) (xy 245.691152 -97.497646) (xy 245.646702 -97.497646)
			(xy 245.646702 -97.896426) (xy 245.691152 -97.896426)
		)
		(stroke
			(width 0)
			(type solid)
		)
		(fill yes)
		(layer "In4.Cu")
		(net "M_F_DQS_DN<17>")
	)
	(gr_poly
		(pts
			(xy 245.861332 -96.816926) (xy 245.861332 -96.595946) (xy 245.691152 -96.507046) (xy 245.646702 -96.507046)
			(xy 245.646702 -96.905826) (xy 245.691152 -96.905826)
		)
		(stroke
			(width 0)
			(type solid)
		)
		(fill yes)
		(layer "In4.Cu")
		(net "M_F_DQS_DN<17>")
	)
	(gr_poly
		(pts
			(xy 245.861332 -95.826326) (xy 245.861332 -95.605346) (xy 245.691152 -95.516446) (xy 245.646702 -95.516446)
			(xy 245.646702 -95.915226) (xy 245.691152 -95.915226)
		)
		(stroke
			(width 0)
			(type solid)
		)
		(fill yes)
		(layer "In4.Cu")
		(net "M_F_DQS_DN<17>")
	)
	(gr_poly
		(pts
			(xy 245.861332 -94.829376) (xy 245.861332 -94.608396) (xy 245.691152 -94.519496) (xy 245.646702 -94.519496)
			(xy 245.646702 -94.918276) (xy 245.691152 -94.918276)
		)
		(stroke
			(width 0)
			(type solid)
		)
		(fill yes)
		(layer "In4.Cu")
		(net "M_F_DQS_DN<17>")
	)
	(gr_poly
		(pts
			(xy 245.861332 -93.83268) (xy 245.861332 -93.6117) (xy 245.691152 -93.5228) (xy 245.646702 -93.5228)
			(xy 245.646702 -93.92158) (xy 245.691152 -93.92158)
		)
		(stroke
			(width 0)
			(type solid)
		)
		(fill yes)
		(layer "In4.Cu")
		(net "M_F_DQS_DN<17>")
	)
	(gr_poly
		(pts
			(xy 245.861332 -92.854526) (xy 245.861332 -92.633546) (xy 245.691152 -92.544646) (xy 245.646702 -92.544646)
			(xy 245.646702 -92.943426) (xy 245.691152 -92.943426)
		)
		(stroke
			(width 0)
			(type solid)
		)
		(fill yes)
		(layer "In4.Cu")
		(net "M_F_DQS_DN<17>")
	)
	(gr_poly
		(pts
			(xy 245.861332 -91.863926) (xy 245.861332 -91.642946) (xy 245.691152 -91.554046) (xy 245.646702 -91.554046)
			(xy 245.646702 -91.952826) (xy 245.691152 -91.952826)
		)
		(stroke
			(width 0)
			(type solid)
		)
		(fill yes)
		(layer "In4.Cu")
		(net "M_F_DQS_DN<17>")
	)
	(gr_poly
		(pts
			(xy 245.861332 -90.873326) (xy 245.861332 -90.652346) (xy 245.691152 -90.563446) (xy 245.646702 -90.563446)
			(xy 245.646702 -90.962226) (xy 245.691152 -90.962226)
		)
		(stroke
			(width 0)
			(type solid)
		)
		(fill yes)
		(layer "In4.Cu")
		(net "M_F_DQS_DN<17>")
	)
	(gr_poly
		(pts
			(xy 245.861332 -89.882726) (xy 245.861332 -89.661746) (xy 245.691152 -89.572846) (xy 245.646702 -89.572846)
			(xy 245.646702 -89.971626) (xy 245.691152 -89.971626)
		)
		(stroke
			(width 0)
			(type solid)
		)
		(fill yes)
		(layer "In4.Cu")
		(net "M_F_DQS_DN<17>")
	)
	(gr_poly
		(pts
			(xy 245.861332 -88.892126) (xy 245.861332 -88.671146) (xy 245.691152 -88.582246) (xy 245.646702 -88.582246)
			(xy 245.646702 -88.981026) (xy 245.691152 -88.981026)
		)
		(stroke
			(width 0)
			(type solid)
		)
		(fill yes)
		(layer "In4.Cu")
		(net "M_F_DQS_DN<17>")
	)
	(gr_poly
		(pts
			(xy 245.861332 -87.901526) (xy 245.861332 -87.680546) (xy 245.691152 -87.591646) (xy 245.646702 -87.591646)
			(xy 245.646702 -87.990426) (xy 245.691152 -87.990426)
		)
		(stroke
			(width 0)
			(type solid)
		)
		(fill yes)
		(layer "In4.Cu")
		(net "M_F_DQS_DN<17>")
	)
	(gr_poly
		(pts
			(xy 245.861332 -86.910926) (xy 245.861332 -86.689946) (xy 245.691152 -86.601046) (xy 245.646702 -86.601046)
			(xy 245.646702 -86.999826) (xy 245.691152 -86.999826)
		)
		(stroke
			(width 0)
			(type solid)
		)
		(fill yes)
		(layer "In4.Cu")
		(net "M_F_DQS_DN<17>")
	)
	(gr_poly
		(pts
			(xy 245.861332 -85.920326) (xy 245.861332 -85.699346) (xy 245.691152 -85.610446) (xy 245.646702 -85.610446)
			(xy 245.646702 -86.009226) (xy 245.691152 -86.009226)
		)
		(stroke
			(width 0)
			(type solid)
		)
		(fill yes)
		(layer "In4.Cu")
		(net "M_F_DQS_DN<17>")
	)
	(gr_poly
		(pts
			(xy 245.861332 -84.929726) (xy 245.861332 -84.708746) (xy 245.691152 -84.619846) (xy 245.646702 -84.619846)
			(xy 245.646702 -85.018626) (xy 245.691152 -85.018626)
		)
		(stroke
			(width 0)
			(type solid)
		)
		(fill yes)
		(layer "In4.Cu")
		(net "M_F_DQS_DN<17>")
	)
	(gr_poly
		(pts
			(xy 245.861332 -83.939126) (xy 245.861332 -83.718146) (xy 245.691152 -83.629246) (xy 245.646702 -83.629246)
			(xy 245.646702 -84.028026) (xy 245.691152 -84.028026)
		)
		(stroke
			(width 0)
			(type solid)
		)
		(fill yes)
		(layer "In4.Cu")
		(net "M_F_DQS_DN<17>")
	)
	(gr_poly
		(pts
			(xy 245.861332 -67.092576) (xy 245.861332 -66.871596) (xy 245.691152 -66.782696) (xy 245.646702 -66.782696)
			(xy 245.646702 -67.181476) (xy 245.691152 -67.181476)
		)
		(stroke
			(width 0)
			(type solid)
		)
		(fill yes)
		(layer "In4.Cu")
		(net "M_C_DQS_DN<8>")
	)
	(gr_poly
		(pts
			(xy 245.861332 -65.117726) (xy 245.861332 -64.896746) (xy 245.691152 -64.807846) (xy 245.646702 -64.807846)
			(xy 245.646702 -65.206626) (xy 245.691152 -65.206626)
		)
		(stroke
			(width 0)
			(type solid)
		)
		(fill yes)
		(layer "In4.Cu")
		(net "M_C_DQS_DN<8>")
	)
	(gr_poly
		(pts
			(xy 245.861332 -64.127126) (xy 245.861332 -63.906146) (xy 245.691152 -63.817246) (xy 245.646702 -63.817246)
			(xy 245.646702 -64.216026) (xy 245.691152 -64.216026)
		)
		(stroke
			(width 0)
			(type solid)
		)
		(fill yes)
		(layer "In4.Cu")
		(net "M_C_DQS_DN<8>")
	)
	(gr_poly
		(pts
			(xy 245.861332 -63.136526) (xy 245.861332 -62.915546) (xy 245.691152 -62.826646) (xy 245.646702 -62.826646)
			(xy 245.646702 -63.225426) (xy 245.691152 -63.225426)
		)
		(stroke
			(width 0)
			(type solid)
		)
		(fill yes)
		(layer "In4.Cu")
		(net "M_C_DQS_DN<8>")
	)
	(gr_poly
		(pts
			(xy 245.861332 -62.145926) (xy 245.861332 -61.924946) (xy 245.691152 -61.836046) (xy 245.646702 -61.836046)
			(xy 245.646702 -62.234826) (xy 245.691152 -62.234826)
		)
		(stroke
			(width 0)
			(type solid)
		)
		(fill yes)
		(layer "In4.Cu")
		(net "M_C_DQS_DN<8>")
	)
	(gr_poly
		(pts
			(xy 245.861332 -61.155326) (xy 245.861332 -60.934346) (xy 245.691152 -60.845446) (xy 245.646702 -60.845446)
			(xy 245.646702 -61.244226) (xy 245.691152 -61.244226)
		)
		(stroke
			(width 0)
			(type solid)
		)
		(fill yes)
		(layer "In4.Cu")
		(net "M_C_DQS_DN<8>")
	)
	(gr_poly
		(pts
			(xy 245.861332 -60.164726) (xy 245.861332 -59.943746) (xy 245.691152 -59.854846) (xy 245.646702 -59.854846)
			(xy 245.646702 -60.253626) (xy 245.691152 -60.253626)
		)
		(stroke
			(width 0)
			(type solid)
		)
		(fill yes)
		(layer "In4.Cu")
		(net "M_C_DQS_DN<8>")
	)
	(gr_poly
		(pts
			(xy 245.861332 -59.167776) (xy 245.861332 -58.946796) (xy 245.691152 -58.857896) (xy 245.646702 -58.857896)
			(xy 245.646702 -59.256676) (xy 245.691152 -59.256676)
		)
		(stroke
			(width 0)
			(type solid)
		)
		(fill yes)
		(layer "In4.Cu")
		(net "M_C_DQS_DN<8>")
	)
	(gr_poly
		(pts
			(xy 245.861332 -58.17108) (xy 245.861332 -57.9501) (xy 245.691152 -57.8612) (xy 245.646702 -57.8612)
			(xy 245.646702 -58.25998) (xy 245.691152 -58.25998)
		)
		(stroke
			(width 0)
			(type solid)
		)
		(fill yes)
		(layer "In4.Cu")
		(net "M_C_DQS_DN<8>")
	)
	(gr_poly
		(pts
			(xy 245.861332 -57.192926) (xy 245.861332 -56.971946) (xy 245.691152 -56.883046) (xy 245.646702 -56.883046)
			(xy 245.646702 -57.281826) (xy 245.691152 -57.281826)
		)
		(stroke
			(width 0)
			(type solid)
		)
		(fill yes)
		(layer "In4.Cu")
		(net "M_C_DQS_DN<8>")
	)
	(gr_poly
		(pts
			(xy 245.861332 -56.202326) (xy 245.861332 -55.981346) (xy 245.691152 -55.892446) (xy 245.646702 -55.892446)
			(xy 245.646702 -56.291226) (xy 245.691152 -56.291226)
		)
		(stroke
			(width 0)
			(type solid)
		)
		(fill yes)
		(layer "In4.Cu")
		(net "M_C_DQS_DN<8>")
	)
	(gr_poly
		(pts
			(xy 245.888764 -51.758088) (xy 245.844314 -51.758088) (xy 245.651274 -51.846988) (xy 245.651274 -52.075588)
			(xy 245.844314 -52.164488) (xy 245.888764 -52.164488)
		)
		(stroke
			(width 0)
			(type solid)
		)
		(fill yes)
		(layer "In4.Cu")
		(net "M_C_DQS_DP<8>")
	)
	(gr_poly
		(pts
			(xy 245.888764 -50.767488) (xy 245.844314 -50.767488) (xy 245.651274 -50.856388) (xy 245.651274 -51.084988)
			(xy 245.844314 -51.173888) (xy 245.888764 -51.173888)
		)
		(stroke
			(width 0)
			(type solid)
		)
		(fill yes)
		(layer "In4.Cu")
		(net "M_C_DQS_DP<8>")
	)
	(gr_poly
		(pts
			(xy 245.895114 -101.351334) (xy 245.850664 -101.351334) (xy 245.657624 -101.440234) (xy 245.657624 -101.668834)
			(xy 245.850664 -101.757734) (xy 245.895114 -101.757734)
		)
		(stroke
			(width 0)
			(type solid)
		)
		(fill yes)
		(layer "In4.Cu")
		(net "M_F_DQS_DN<8>")
	)
	(gr_poly
		(pts
			(xy 245.915434 -55.085234) (xy 245.915434 -54.856634) (xy 245.722394 -54.767734) (xy 245.677944 -54.767734)
			(xy 245.677944 -55.174134) (xy 245.722394 -55.174134)
		)
		(stroke
			(width 0)
			(type solid)
		)
		(fill yes)
		(layer "In4.Cu")
		(net "M_C_DQS_DN<8>")
	)
	(gr_poly
		(pts
			(xy 245.915434 -54.196234) (xy 245.915434 -53.967634) (xy 245.722394 -53.878734) (xy 245.677944 -53.878734)
			(xy 245.677944 -54.285134) (xy 245.722394 -54.285134)
		)
		(stroke
			(width 0)
			(type solid)
		)
		(fill yes)
		(layer "In4.Cu")
		(net "M_C_DQS_DN<8>")
	)
	(gr_poly
		(pts
			(xy 245.915434 -53.205634) (xy 245.915434 -52.977034) (xy 245.722394 -52.888134) (xy 245.677944 -52.888134)
			(xy 245.677944 -53.294534) (xy 245.722394 -53.294534)
		)
		(stroke
			(width 0)
			(type solid)
		)
		(fill yes)
		(layer "In4.Cu")
		(net "M_C_DQS_DN<8>")
	)
	(gr_poly
		(pts
			(xy 246.119904 -102.748334) (xy 246.075454 -102.748334) (xy 245.882414 -102.837234) (xy 245.882414 -103.065834)
			(xy 246.075454 -103.154734) (xy 246.119904 -103.154734)
		)
		(stroke
			(width 0)
			(type solid)
		)
		(fill yes)
		(layer "In4.Cu")
		(net "M_F_DQS_DN<8>")
	)
	(gr_poly
		(pts
			(xy 246.181626 -96.507046) (xy 246.137176 -96.507046) (xy 245.966996 -96.595946) (xy 245.966996 -96.816926)
			(xy 246.137176 -96.905826) (xy 246.181626 -96.905826)
		)
		(stroke
			(width 0)
			(type solid)
		)
		(fill yes)
		(layer "In4.Cu")
		(net "M_F_DQS_DN<8>")
	)
	(gr_poly
		(pts
			(xy 246.181626 -95.516446) (xy 246.137176 -95.516446) (xy 245.966996 -95.605346) (xy 245.966996 -95.826326)
			(xy 246.137176 -95.915226) (xy 246.181626 -95.915226)
		)
		(stroke
			(width 0)
			(type solid)
		)
		(fill yes)
		(layer "In4.Cu")
		(net "M_F_DQS_DN<8>")
	)
	(gr_poly
		(pts
			(xy 246.181626 -94.519496) (xy 246.137176 -94.519496) (xy 245.966996 -94.608396) (xy 245.966996 -94.829376)
			(xy 246.137176 -94.918276) (xy 246.181626 -94.918276)
		)
		(stroke
			(width 0)
			(type solid)
		)
		(fill yes)
		(layer "In4.Cu")
		(net "M_F_DQS_DN<8>")
	)
	(gr_poly
		(pts
			(xy 246.181626 -93.5228) (xy 246.137176 -93.5228) (xy 245.966996 -93.6117) (xy 245.966996 -93.83268)
			(xy 246.137176 -93.92158) (xy 246.181626 -93.92158)
		)
		(stroke
			(width 0)
			(type solid)
		)
		(fill yes)
		(layer "In4.Cu")
		(net "M_F_DQS_DN<8>")
	)
	(gr_poly
		(pts
			(xy 246.181626 -92.544646) (xy 246.137176 -92.544646) (xy 245.966996 -92.633546) (xy 245.966996 -92.854526)
			(xy 246.137176 -92.943426) (xy 246.181626 -92.943426)
		)
		(stroke
			(width 0)
			(type solid)
		)
		(fill yes)
		(layer "In4.Cu")
		(net "M_F_DQS_DN<8>")
	)
	(gr_poly
		(pts
			(xy 246.181626 -91.554046) (xy 246.137176 -91.554046) (xy 245.966996 -91.642946) (xy 245.966996 -91.863926)
			(xy 246.137176 -91.952826) (xy 246.181626 -91.952826)
		)
		(stroke
			(width 0)
			(type solid)
		)
		(fill yes)
		(layer "In4.Cu")
		(net "M_F_DQS_DN<8>")
	)
	(gr_poly
		(pts
			(xy 246.181626 -90.563446) (xy 246.137176 -90.563446) (xy 245.966996 -90.652346) (xy 245.966996 -90.873326)
			(xy 246.137176 -90.962226) (xy 246.181626 -90.962226)
		)
		(stroke
			(width 0)
			(type solid)
		)
		(fill yes)
		(layer "In4.Cu")
		(net "M_F_DQS_DN<8>")
	)
	(gr_poly
		(pts
			(xy 246.181626 -89.572846) (xy 246.137176 -89.572846) (xy 245.966996 -89.661746) (xy 245.966996 -89.882726)
			(xy 246.137176 -89.971626) (xy 246.181626 -89.971626)
		)
		(stroke
			(width 0)
			(type solid)
		)
		(fill yes)
		(layer "In4.Cu")
		(net "M_F_DQS_DN<8>")
	)
	(gr_poly
		(pts
			(xy 246.181626 -88.582246) (xy 246.137176 -88.582246) (xy 245.966996 -88.671146) (xy 245.966996 -88.892126)
			(xy 246.137176 -88.981026) (xy 246.181626 -88.981026)
		)
		(stroke
			(width 0)
			(type solid)
		)
		(fill yes)
		(layer "In4.Cu")
		(net "M_F_DQS_DN<8>")
	)
	(gr_poly
		(pts
			(xy 246.181626 -87.591646) (xy 246.137176 -87.591646) (xy 245.966996 -87.680546) (xy 245.966996 -87.901526)
			(xy 246.137176 -87.990426) (xy 246.181626 -87.990426)
		)
		(stroke
			(width 0)
			(type solid)
		)
		(fill yes)
		(layer "In4.Cu")
		(net "M_F_DQS_DN<8>")
	)
	(gr_poly
		(pts
			(xy 246.181626 -86.601046) (xy 246.137176 -86.601046) (xy 245.966996 -86.689946) (xy 245.966996 -86.910926)
			(xy 246.137176 -86.999826) (xy 246.181626 -86.999826)
		)
		(stroke
			(width 0)
			(type solid)
		)
		(fill yes)
		(layer "In4.Cu")
		(net "M_F_DQS_DN<8>")
	)
	(gr_poly
		(pts
			(xy 246.181626 -64.807846) (xy 246.137176 -64.807846) (xy 245.966996 -64.896746) (xy 245.966996 -65.117726)
			(xy 246.137176 -65.206626) (xy 246.181626 -65.206626)
		)
		(stroke
			(width 0)
			(type solid)
		)
		(fill yes)
		(layer "In4.Cu")
		(net "M_C_ECC<6>")
	)
	(gr_poly
		(pts
			(xy 246.181626 -63.817246) (xy 246.137176 -63.817246) (xy 245.966996 -63.906146) (xy 245.966996 -64.127126)
			(xy 246.137176 -64.216026) (xy 246.181626 -64.216026)
		)
		(stroke
			(width 0)
			(type solid)
		)
		(fill yes)
		(layer "In4.Cu")
		(net "M_C_ECC<6>")
	)
	(gr_poly
		(pts
			(xy 246.181626 -62.826646) (xy 246.137176 -62.826646) (xy 245.966996 -62.915546) (xy 245.966996 -63.136526)
			(xy 246.137176 -63.225426) (xy 246.181626 -63.225426)
		)
		(stroke
			(width 0)
			(type solid)
		)
		(fill yes)
		(layer "In4.Cu")
		(net "M_C_ECC<6>")
	)
	(gr_poly
		(pts
			(xy 246.181626 -61.836046) (xy 246.137176 -61.836046) (xy 245.966996 -61.924946) (xy 245.966996 -62.145926)
			(xy 246.137176 -62.234826) (xy 246.181626 -62.234826)
		)
		(stroke
			(width 0)
			(type solid)
		)
		(fill yes)
		(layer "In4.Cu")
		(net "M_C_ECC<6>")
	)
	(gr_poly
		(pts
			(xy 246.181626 -60.845446) (xy 246.137176 -60.845446) (xy 245.966996 -60.934346) (xy 245.966996 -61.155326)
			(xy 246.137176 -61.244226) (xy 246.181626 -61.244226)
		)
		(stroke
			(width 0)
			(type solid)
		)
		(fill yes)
		(layer "In4.Cu")
		(net "M_C_ECC<6>")
	)
	(gr_poly
		(pts
			(xy 246.181626 -59.854846) (xy 246.137176 -59.854846) (xy 245.966996 -59.943746) (xy 245.966996 -60.164726)
			(xy 246.137176 -60.253626) (xy 246.181626 -60.253626)
		)
		(stroke
			(width 0)
			(type solid)
		)
		(fill yes)
		(layer "In4.Cu")
		(net "M_C_ECC<6>")
	)
	(gr_poly
		(pts
			(xy 246.181626 -58.857896) (xy 246.137176 -58.857896) (xy 245.966996 -58.946796) (xy 245.966996 -59.167776)
			(xy 246.137176 -59.256676) (xy 246.181626 -59.256676)
		)
		(stroke
			(width 0)
			(type solid)
		)
		(fill yes)
		(layer "In4.Cu")
		(net "M_C_ECC<6>")
	)
	(gr_poly
		(pts
			(xy 246.181626 -57.8612) (xy 246.137176 -57.8612) (xy 245.966996 -57.9501) (xy 245.966996 -58.17108)
			(xy 246.137176 -58.25998) (xy 246.181626 -58.25998)
		)
		(stroke
			(width 0)
			(type solid)
		)
		(fill yes)
		(layer "In4.Cu")
		(net "M_C_ECC<6>")
	)
	(gr_poly
		(pts
			(xy 246.181626 -56.883046) (xy 246.137176 -56.883046) (xy 245.966996 -56.971946) (xy 245.966996 -57.192926)
			(xy 246.137176 -57.281826) (xy 246.181626 -57.281826)
		)
		(stroke
			(width 0)
			(type solid)
		)
		(fill yes)
		(layer "In4.Cu")
		(net "M_C_ECC<6>")
	)
	(gr_poly
		(pts
			(xy 246.181626 -55.892446) (xy 246.137176 -55.892446) (xy 245.966996 -55.981346) (xy 245.966996 -56.202326)
			(xy 246.137176 -56.291226) (xy 246.181626 -56.291226)
		)
		(stroke
			(width 0)
			(type solid)
		)
		(fill yes)
		(layer "In4.Cu")
		(net "M_C_ECC<6>")
	)
	(gr_poly
		(pts
			(xy 246.18188 -65.798446) (xy 246.13743 -65.798446) (xy 245.96725 -65.887346) (xy 245.96725 -66.108326)
			(xy 246.13743 -66.197226) (xy 246.18188 -66.197226)
		)
		(stroke
			(width 0)
			(type solid)
		)
		(fill yes)
		(layer "In4.Cu")
		(net "M_C_ECC<6>")
	)
	(gr_poly
		(pts
			(xy 246.184674 -66.799206) (xy 246.140224 -66.798698) (xy 245.968774 -66.885058) (xy 245.965472 -67.106038)
			(xy 246.134382 -67.197478) (xy 246.179086 -67.197986)
		)
		(stroke
			(width 0)
			(type solid)
		)
		(fill yes)
		(layer "In4.Cu")
		(net "M_C_ECC<6>")
	)
	(gr_poly
		(pts
			(xy 246.254524 -54.483762) (xy 246.210074 -54.483762) (xy 246.017034 -54.572662) (xy 246.017034 -54.801262)
			(xy 246.210074 -54.890162) (xy 246.254524 -54.890162)
		)
		(stroke
			(width 0)
			(type solid)
		)
		(fill yes)
		(layer "In4.Cu")
		(net "M_C_ECC<6>")
	)
	(gr_poly
		(pts
			(xy 246.254524 -53.493162) (xy 246.210074 -53.493162) (xy 246.017034 -53.582062) (xy 246.017034 -53.810662)
			(xy 246.210074 -53.899562) (xy 246.254524 -53.899562)
		)
		(stroke
			(width 0)
			(type solid)
		)
		(fill yes)
		(layer "In4.Cu")
		(net "M_C_ECC<6>")
	)
	(gr_poly
		(pts
			(xy 246.316754 -52.202588) (xy 246.316754 -51.973988) (xy 246.123714 -51.885088) (xy 246.079264 -51.885088)
			(xy 246.079264 -52.291488) (xy 246.123714 -52.291488)
		)
		(stroke
			(width 0)
			(type solid)
		)
		(fill yes)
		(layer "In4.Cu")
		(net "M_C_DQS_DN<8>")
	)
	(gr_poly
		(pts
			(xy 246.316754 -51.211988) (xy 246.316754 -50.983388) (xy 246.123714 -50.894488) (xy 246.079264 -50.894488)
			(xy 246.079264 -51.300888) (xy 246.123714 -51.300888)
		)
		(stroke
			(width 0)
			(type solid)
		)
		(fill yes)
		(layer "In4.Cu")
		(net "M_C_DQS_DN<8>")
	)
	(gr_poly
		(pts
			(xy 246.318024 -99.522534) (xy 246.273574 -99.522534) (xy 246.080534 -99.611434) (xy 246.080534 -99.840034)
			(xy 246.273574 -99.928934) (xy 246.318024 -99.928934)
		)
		(stroke
			(width 0)
			(type solid)
		)
		(fill yes)
		(layer "In4.Cu")
		(net "M_F_DQS_DN<8>")
	)
	(gr_poly
		(pts
			(xy 246.318024 -98.531934) (xy 246.273574 -98.531934) (xy 246.080534 -98.620834) (xy 246.080534 -98.849434)
			(xy 246.273574 -98.938334) (xy 246.318024 -98.938334)
		)
		(stroke
			(width 0)
			(type solid)
		)
		(fill yes)
		(layer "In4.Cu")
		(net "M_F_DQS_DN<8>")
	)
	(gr_poly
		(pts
			(xy 246.318024 -97.541334) (xy 246.273574 -97.541334) (xy 246.080534 -97.630234) (xy 246.080534 -97.858834)
			(xy 246.273574 -97.947734) (xy 246.318024 -97.947734)
		)
		(stroke
			(width 0)
			(type solid)
		)
		(fill yes)
		(layer "In4.Cu")
		(net "M_F_DQS_DN<8>")
	)
	(gr_poly
		(pts
			(xy 246.323104 -101.668834) (xy 246.323104 -101.440234) (xy 246.130064 -101.351334) (xy 246.085614 -101.351334)
			(xy 246.085614 -101.757734) (xy 246.130064 -101.757734)
		)
		(stroke
			(width 0)
			(type solid)
		)
		(fill yes)
		(layer "In4.Cu")
		(net "M_F_DQS_DP<8>")
	)
	(gr_poly
		(pts
			(xy 246.37238 -83.627976) (xy 246.32793 -83.627976) (xy 246.15775 -83.716876) (xy 246.15775 -83.937856)
			(xy 246.32793 -84.026756) (xy 246.37238 -84.026756)
		)
		(stroke
			(width 0)
			(type solid)
		)
		(fill yes)
		(layer "In4.Cu")
		(net "M_F_ECC<6>")
	)
	(gr_poly
		(pts
			(xy 246.547894 -103.065834) (xy 246.547894 -102.837234) (xy 246.354854 -102.748334) (xy 246.310404 -102.748334)
			(xy 246.310404 -103.154734) (xy 246.354854 -103.154734)
		)
		(stroke
			(width 0)
			(type solid)
		)
		(fill yes)
		(layer "In4.Cu")
		(net "M_F_DQS_DP<8>")
	)
	(gr_poly
		(pts
			(xy 246.682514 -54.801262) (xy 246.682514 -54.572662) (xy 246.489474 -54.483762) (xy 246.445024 -54.483762)
			(xy 246.445024 -54.890162) (xy 246.489474 -54.890162)
		)
		(stroke
			(width 0)
			(type solid)
		)
		(fill yes)
		(layer "In4.Cu")
		(net "M_C_ECC<7>")
	)
	(gr_poly
		(pts
			(xy 246.682514 -53.810662) (xy 246.682514 -53.582062) (xy 246.489474 -53.493162) (xy 246.445024 -53.493162)
			(xy 246.445024 -53.899562) (xy 246.489474 -53.899562)
		)
		(stroke
			(width 0)
			(type solid)
		)
		(fill yes)
		(layer "In4.Cu")
		(net "M_C_ECC<7>")
	)
	(gr_poly
		(pts
			(xy 246.704612 -52.611528) (xy 246.67337 -52.580032) (xy 246.47398 -52.506372) (xy 246.312182 -52.667916)
			(xy 246.385842 -52.867306) (xy 246.417338 -52.898802)
		)
		(stroke
			(width 0)
			(type solid)
		)
		(fill yes)
		(layer "In4.Cu")
		(net "M_C_ECC<6>")
	)
	(gr_poly
		(pts
			(xy 246.719852 -96.30918) (xy 246.719852 -96.0882) (xy 246.549672 -95.9993) (xy 246.505222 -95.9993)
			(xy 246.505222 -96.39808) (xy 246.549672 -96.39808)
		)
		(stroke
			(width 0)
			(type solid)
		)
		(fill yes)
		(layer "In4.Cu")
		(net "M_F_DQS_DP<8>")
	)
	(gr_poly
		(pts
			(xy 246.719852 -95.31858) (xy 246.719852 -95.0976) (xy 246.549672 -95.0087) (xy 246.505222 -95.0087)
			(xy 246.505222 -95.40748) (xy 246.549672 -95.40748)
		)
		(stroke
			(width 0)
			(type solid)
		)
		(fill yes)
		(layer "In4.Cu")
		(net "M_F_DQS_DP<8>")
	)
	(gr_poly
		(pts
			(xy 246.719852 -94.340426) (xy 246.719852 -94.119446) (xy 246.549672 -94.030546) (xy 246.505222 -94.030546)
			(xy 246.505222 -94.429326) (xy 246.549672 -94.429326)
		)
		(stroke
			(width 0)
			(type solid)
		)
		(fill yes)
		(layer "In4.Cu")
		(net "M_F_DQS_DP<8>")
	)
	(gr_poly
		(pts
			(xy 246.719852 -93.34373) (xy 246.719852 -93.12275) (xy 246.549672 -93.03385) (xy 246.505222 -93.03385)
			(xy 246.505222 -93.43263) (xy 246.549672 -93.43263)
		)
		(stroke
			(width 0)
			(type solid)
		)
		(fill yes)
		(layer "In4.Cu")
		(net "M_F_DQS_DP<8>")
	)
	(gr_poly
		(pts
			(xy 246.719852 -92.34678) (xy 246.719852 -92.1258) (xy 246.549672 -92.0369) (xy 246.505222 -92.0369)
			(xy 246.505222 -92.43568) (xy 246.549672 -92.43568)
		)
		(stroke
			(width 0)
			(type solid)
		)
		(fill yes)
		(layer "In4.Cu")
		(net "M_F_DQS_DP<8>")
	)
	(gr_poly
		(pts
			(xy 246.719852 -91.35618) (xy 246.719852 -91.1352) (xy 246.549672 -91.0463) (xy 246.505222 -91.0463)
			(xy 246.505222 -91.44508) (xy 246.549672 -91.44508)
		)
		(stroke
			(width 0)
			(type solid)
		)
		(fill yes)
		(layer "In4.Cu")
		(net "M_F_DQS_DP<8>")
	)
	(gr_poly
		(pts
			(xy 246.719852 -90.36558) (xy 246.719852 -90.1446) (xy 246.549672 -90.0557) (xy 246.505222 -90.0557)
			(xy 246.505222 -90.45448) (xy 246.549672 -90.45448)
		)
		(stroke
			(width 0)
			(type solid)
		)
		(fill yes)
		(layer "In4.Cu")
		(net "M_F_DQS_DP<8>")
	)
	(gr_poly
		(pts
			(xy 246.719852 -89.37498) (xy 246.719852 -89.154) (xy 246.549672 -89.0651) (xy 246.505222 -89.0651)
			(xy 246.505222 -89.46388) (xy 246.549672 -89.46388)
		)
		(stroke
			(width 0)
			(type solid)
		)
		(fill yes)
		(layer "In4.Cu")
		(net "M_F_DQS_DP<8>")
	)
	(gr_poly
		(pts
			(xy 246.719852 -88.38438) (xy 246.719852 -88.1634) (xy 246.549672 -88.0745) (xy 246.505222 -88.0745)
			(xy 246.505222 -88.47328) (xy 246.549672 -88.47328)
		)
		(stroke
			(width 0)
			(type solid)
		)
		(fill yes)
		(layer "In4.Cu")
		(net "M_F_DQS_DP<8>")
	)
	(gr_poly
		(pts
			(xy 246.719852 -87.39378) (xy 246.719852 -87.1728) (xy 246.549672 -87.0839) (xy 246.505222 -87.0839)
			(xy 246.505222 -87.48268) (xy 246.549672 -87.48268)
		)
		(stroke
			(width 0)
			(type solid)
		)
		(fill yes)
		(layer "In4.Cu")
		(net "M_F_DQS_DP<8>")
	)
	(gr_poly
		(pts
			(xy 246.719852 -86.40318) (xy 246.719852 -86.1822) (xy 246.549672 -86.0933) (xy 246.505222 -86.0933)
			(xy 246.505222 -86.49208) (xy 246.549672 -86.49208)
		)
		(stroke
			(width 0)
			(type solid)
		)
		(fill yes)
		(layer "In4.Cu")
		(net "M_F_DQS_DP<8>")
	)
	(gr_poly
		(pts
			(xy 246.719852 -84.42198) (xy 246.719852 -84.201) (xy 246.549672 -84.1121) (xy 246.505222 -84.1121)
			(xy 246.505222 -84.51088) (xy 246.549672 -84.51088)
		)
		(stroke
			(width 0)
			(type solid)
		)
		(fill yes)
		(layer "In4.Cu")
		(net "M_F_ECC<6>")
	)
	(gr_poly
		(pts
			(xy 246.719852 -66.597276) (xy 246.719852 -66.376296) (xy 246.549672 -66.287396) (xy 246.505222 -66.287396)
			(xy 246.505222 -66.686176) (xy 246.549672 -66.686176)
		)
		(stroke
			(width 0)
			(type solid)
		)
		(fill yes)
		(layer "In4.Cu")
		(net "M_C_ECC<7>")
	)
	(gr_poly
		(pts
			(xy 246.719852 -65.60058) (xy 246.719852 -65.3796) (xy 246.549672 -65.2907) (xy 246.505222 -65.2907)
			(xy 246.505222 -65.68948) (xy 246.549672 -65.68948)
		)
		(stroke
			(width 0)
			(type solid)
		)
		(fill yes)
		(layer "In4.Cu")
		(net "M_C_ECC<7>")
	)
	(gr_poly
		(pts
			(xy 246.719852 -64.60998) (xy 246.719852 -64.389) (xy 246.549672 -64.3001) (xy 246.505222 -64.3001)
			(xy 246.505222 -64.69888) (xy 246.549672 -64.69888)
		)
		(stroke
			(width 0)
			(type solid)
		)
		(fill yes)
		(layer "In4.Cu")
		(net "M_C_ECC<7>")
	)
	(gr_poly
		(pts
			(xy 246.719852 -63.61938) (xy 246.719852 -63.3984) (xy 246.549672 -63.3095) (xy 246.505222 -63.3095)
			(xy 246.505222 -63.70828) (xy 246.549672 -63.70828)
		)
		(stroke
			(width 0)
			(type solid)
		)
		(fill yes)
		(layer "In4.Cu")
		(net "M_C_ECC<7>")
	)
	(gr_poly
		(pts
			(xy 246.719852 -62.62878) (xy 246.719852 -62.4078) (xy 246.549672 -62.3189) (xy 246.505222 -62.3189)
			(xy 246.505222 -62.71768) (xy 246.549672 -62.71768)
		)
		(stroke
			(width 0)
			(type solid)
		)
		(fill yes)
		(layer "In4.Cu")
		(net "M_C_ECC<7>")
	)
	(gr_poly
		(pts
			(xy 246.719852 -61.63818) (xy 246.719852 -61.4172) (xy 246.549672 -61.3283) (xy 246.505222 -61.3283)
			(xy 246.505222 -61.72708) (xy 246.549672 -61.72708)
		)
		(stroke
			(width 0)
			(type solid)
		)
		(fill yes)
		(layer "In4.Cu")
		(net "M_C_ECC<7>")
	)
	(gr_poly
		(pts
			(xy 246.719852 -60.64758) (xy 246.719852 -60.4266) (xy 246.549672 -60.3377) (xy 246.505222 -60.3377)
			(xy 246.505222 -60.73648) (xy 246.549672 -60.73648)
		)
		(stroke
			(width 0)
			(type solid)
		)
		(fill yes)
		(layer "In4.Cu")
		(net "M_C_ECC<7>")
	)
	(gr_poly
		(pts
			(xy 246.719852 -59.65698) (xy 246.719852 -59.436) (xy 246.549672 -59.3471) (xy 246.505222 -59.3471)
			(xy 246.505222 -59.74588) (xy 246.549672 -59.74588)
		)
		(stroke
			(width 0)
			(type solid)
		)
		(fill yes)
		(layer "In4.Cu")
		(net "M_C_ECC<7>")
	)
	(gr_poly
		(pts
			(xy 246.719852 -58.678826) (xy 246.719852 -58.457846) (xy 246.549672 -58.368946) (xy 246.505222 -58.368946)
			(xy 246.505222 -58.767726) (xy 246.549672 -58.767726)
		)
		(stroke
			(width 0)
			(type solid)
		)
		(fill yes)
		(layer "In4.Cu")
		(net "M_C_ECC<7>")
	)
	(gr_poly
		(pts
			(xy 246.719852 -57.68213) (xy 246.719852 -57.46115) (xy 246.549672 -57.37225) (xy 246.505222 -57.37225)
			(xy 246.505222 -57.77103) (xy 246.549672 -57.77103)
		)
		(stroke
			(width 0)
			(type solid)
		)
		(fill yes)
		(layer "In4.Cu")
		(net "M_C_ECC<7>")
	)
	(gr_poly
		(pts
			(xy 246.719852 -56.68518) (xy 246.719852 -56.4642) (xy 246.549672 -56.3753) (xy 246.505222 -56.3753)
			(xy 246.505222 -56.77408) (xy 246.549672 -56.77408)
		)
		(stroke
			(width 0)
			(type solid)
		)
		(fill yes)
		(layer "In4.Cu")
		(net "M_C_ECC<7>")
	)
	(gr_poly
		(pts
			(xy 246.746014 -99.840034) (xy 246.746014 -99.611434) (xy 246.552974 -99.522534) (xy 246.508524 -99.522534)
			(xy 246.508524 -99.928934) (xy 246.552974 -99.928934)
		)
		(stroke
			(width 0)
			(type solid)
		)
		(fill yes)
		(layer "In4.Cu")
		(net "M_F_DQS_DP<8>")
	)
	(gr_poly
		(pts
			(xy 246.746014 -98.849434) (xy 246.746014 -98.620834) (xy 246.552974 -98.531934) (xy 246.508524 -98.531934)
			(xy 246.508524 -98.938334) (xy 246.552974 -98.938334)
		)
		(stroke
			(width 0)
			(type solid)
		)
		(fill yes)
		(layer "In4.Cu")
		(net "M_F_DQS_DP<8>")
	)
	(gr_poly
		(pts
			(xy 246.746014 -97.858834) (xy 246.746014 -97.630234) (xy 246.552974 -97.541334) (xy 246.508524 -97.541334)
			(xy 246.508524 -97.947734) (xy 246.552974 -97.947734)
		)
		(stroke
			(width 0)
			(type solid)
		)
		(fill yes)
		(layer "In4.Cu")
		(net "M_F_DQS_DP<8>")
	)
	(gr_poly
		(pts
			(xy 246.775224 -100.965254) (xy 246.730774 -100.965254) (xy 246.537734 -101.054154) (xy 246.537734 -101.282754)
			(xy 246.730774 -101.371654) (xy 246.775224 -101.371654)
		)
		(stroke
			(width 0)
			(type solid)
		)
		(fill yes)
		(layer "In4.Cu")
		(net "M_F_ECC<6>")
	)
	(gr_poly
		(pts
			(xy 246.827548 -85.352636) (xy 246.8499 -85.314282) (xy 246.50446 -85.114892) (xy 246.482108 -85.153246)
			(xy 246.47398 -85.345016) (xy 246.665496 -85.455506)
		)
		(stroke
			(width 0)
			(type solid)
		)
		(fill yes)
		(layer "In4.Cu")
		(net "M_F_ECC<6>")
	)
	(gr_poly
		(pts
			(xy 246.879618 -51.91252) (xy 246.835168 -51.912266) (xy 246.642128 -52.001166) (xy 246.641874 -52.229766)
			(xy 246.835168 -52.318666) (xy 246.879618 -52.318666)
		)
		(stroke
			(width 0)
			(type solid)
		)
		(fill yes)
		(layer "In4.Cu")
		(net "M_C_ECC<6>")
	)
	(gr_poly
		(pts
			(xy 246.944388 -52.977034) (xy 246.870728 -52.777644) (xy 246.839486 -52.746148) (xy 246.551958 -53.033422)
			(xy 246.583454 -53.064918) (xy 246.782844 -53.138578)
		)
		(stroke
			(width 0)
			(type solid)
		)
		(fill yes)
		(layer "In4.Cu")
		(net "M_C_ECC<7>")
	)
	(gr_poly
		(pts
			(xy 247.021604 -54.868064) (xy 246.977154 -54.868064) (xy 246.784114 -54.956964) (xy 246.784114 -55.185564)
			(xy 246.977154 -55.274464) (xy 247.021604 -55.274464)
		)
		(stroke
			(width 0)
			(type solid)
		)
		(fill yes)
		(layer "In4.Cu")
		(net "M_C_ECC<2>")
	)
	(gr_poly
		(pts
			(xy 247.021604 -53.877464) (xy 246.977154 -53.877464) (xy 246.784114 -53.966364) (xy 246.784114 -54.194964)
			(xy 246.977154 -54.283864) (xy 247.021604 -54.283864)
		)
		(stroke
			(width 0)
			(type solid)
		)
		(fill yes)
		(layer "In4.Cu")
		(net "M_C_ECC<2>")
	)
	(gr_poly
		(pts
			(xy 247.029224 -99.873054) (xy 246.984774 -99.873054) (xy 246.791734 -99.961954) (xy 246.791734 -100.190554)
			(xy 246.984774 -100.279454) (xy 247.029224 -100.279454)
		)
		(stroke
			(width 0)
			(type solid)
		)
		(fill yes)
		(layer "In4.Cu")
		(net "M_F_ECC<6>")
	)
	(gr_poly
		(pts
			(xy 247.029224 -98.882454) (xy 246.984774 -98.882454) (xy 246.791734 -98.971354) (xy 246.791734 -99.199954)
			(xy 246.984774 -99.288854) (xy 247.029224 -99.288854)
		)
		(stroke
			(width 0)
			(type solid)
		)
		(fill yes)
		(layer "In4.Cu")
		(net "M_F_ECC<6>")
	)
	(gr_poly
		(pts
			(xy 247.040146 -95.9993) (xy 246.995696 -95.9993) (xy 246.825516 -96.0882) (xy 246.825516 -96.30918)
			(xy 246.995696 -96.39808) (xy 247.040146 -96.39808)
		)
		(stroke
			(width 0)
			(type solid)
		)
		(fill yes)
		(layer "In4.Cu")
		(net "M_F_ECC<6>")
	)
	(gr_poly
		(pts
			(xy 247.040146 -95.0087) (xy 246.995696 -95.0087) (xy 246.825516 -95.0976) (xy 246.825516 -95.31858)
			(xy 246.995696 -95.40748) (xy 247.040146 -95.40748)
		)
		(stroke
			(width 0)
			(type solid)
		)
		(fill yes)
		(layer "In4.Cu")
		(net "M_F_ECC<6>")
	)
	(gr_poly
		(pts
			(xy 247.040146 -94.030546) (xy 246.995696 -94.030546) (xy 246.825516 -94.119446) (xy 246.825516 -94.340426)
			(xy 246.995696 -94.429326) (xy 247.040146 -94.429326)
		)
		(stroke
			(width 0)
			(type solid)
		)
		(fill yes)
		(layer "In4.Cu")
		(net "M_F_ECC<6>")
	)
	(gr_poly
		(pts
			(xy 247.040146 -93.03385) (xy 246.995696 -93.03385) (xy 246.825516 -93.12275) (xy 246.825516 -93.34373)
			(xy 246.995696 -93.43263) (xy 247.040146 -93.43263)
		)
		(stroke
			(width 0)
			(type solid)
		)
		(fill yes)
		(layer "In4.Cu")
		(net "M_F_ECC<6>")
	)
	(gr_poly
		(pts
			(xy 247.040146 -92.0369) (xy 246.995696 -92.0369) (xy 246.825516 -92.1258) (xy 246.825516 -92.34678)
			(xy 246.995696 -92.43568) (xy 247.040146 -92.43568)
		)
		(stroke
			(width 0)
			(type solid)
		)
		(fill yes)
		(layer "In4.Cu")
		(net "M_F_ECC<6>")
	)
	(gr_poly
		(pts
			(xy 247.040146 -91.0463) (xy 246.995696 -91.0463) (xy 246.825516 -91.1352) (xy 246.825516 -91.35618)
			(xy 246.995696 -91.44508) (xy 247.040146 -91.44508)
		)
		(stroke
			(width 0)
			(type solid)
		)
		(fill yes)
		(layer "In4.Cu")
		(net "M_F_ECC<6>")
	)
	(gr_poly
		(pts
			(xy 247.040146 -90.0557) (xy 246.995696 -90.0557) (xy 246.825516 -90.1446) (xy 246.825516 -90.36558)
			(xy 246.995696 -90.45448) (xy 247.040146 -90.45448)
		)
		(stroke
			(width 0)
			(type solid)
		)
		(fill yes)
		(layer "In4.Cu")
		(net "M_F_ECC<6>")
	)
	(gr_poly
		(pts
			(xy 247.040146 -89.0651) (xy 246.995696 -89.0651) (xy 246.825516 -89.154) (xy 246.825516 -89.37498)
			(xy 246.995696 -89.46388) (xy 247.040146 -89.46388)
		)
		(stroke
			(width 0)
			(type solid)
		)
		(fill yes)
		(layer "In4.Cu")
		(net "M_F_ECC<6>")
	)
	(gr_poly
		(pts
			(xy 247.040146 -88.0745) (xy 246.995696 -88.0745) (xy 246.825516 -88.1634) (xy 246.825516 -88.38438)
			(xy 246.995696 -88.47328) (xy 247.040146 -88.47328)
		)
		(stroke
			(width 0)
			(type solid)
		)
		(fill yes)
		(layer "In4.Cu")
		(net "M_F_ECC<6>")
	)
	(gr_poly
		(pts
			(xy 247.040146 -87.0839) (xy 246.995696 -87.0839) (xy 246.825516 -87.1728) (xy 246.825516 -87.39378)
			(xy 246.995696 -87.48268) (xy 247.040146 -87.48268)
		)
		(stroke
			(width 0)
			(type solid)
		)
		(fill yes)
		(layer "In4.Cu")
		(net "M_F_ECC<6>")
	)
	(gr_poly
		(pts
			(xy 247.040146 -86.0933) (xy 246.995696 -86.0933) (xy 246.825516 -86.1822) (xy 246.825516 -86.40318)
			(xy 246.995696 -86.49208) (xy 247.040146 -86.49208)
		)
		(stroke
			(width 0)
			(type solid)
		)
		(fill yes)
		(layer "In4.Cu")
		(net "M_F_ECC<6>")
	)
	(gr_poly
		(pts
			(xy 247.040146 -66.2813) (xy 246.995696 -66.2813) (xy 246.825516 -66.3702) (xy 246.825516 -66.59118)
			(xy 246.995696 -66.68008) (xy 247.040146 -66.68008)
		)
		(stroke
			(width 0)
			(type solid)
		)
		(fill yes)
		(layer "In4.Cu")
		(net "M_C_ECC<2>")
	)
	(gr_poly
		(pts
			(xy 247.040146 -65.2907) (xy 246.995696 -65.2907) (xy 246.825516 -65.3796) (xy 246.825516 -65.60058)
			(xy 246.995696 -65.68948) (xy 247.040146 -65.68948)
		)
		(stroke
			(width 0)
			(type solid)
		)
		(fill yes)
		(layer "In4.Cu")
		(net "M_C_ECC<2>")
	)
	(gr_poly
		(pts
			(xy 247.040146 -64.3001) (xy 246.995696 -64.3001) (xy 246.825516 -64.389) (xy 246.825516 -64.60998)
			(xy 246.995696 -64.69888) (xy 247.040146 -64.69888)
		)
		(stroke
			(width 0)
			(type solid)
		)
		(fill yes)
		(layer "In4.Cu")
		(net "M_C_ECC<2>")
	)
	(gr_poly
		(pts
			(xy 247.040146 -63.3095) (xy 246.995696 -63.3095) (xy 246.825516 -63.3984) (xy 246.825516 -63.61938)
			(xy 246.995696 -63.70828) (xy 247.040146 -63.70828)
		)
		(stroke
			(width 0)
			(type solid)
		)
		(fill yes)
		(layer "In4.Cu")
		(net "M_C_ECC<2>")
	)
	(gr_poly
		(pts
			(xy 247.040146 -62.3189) (xy 246.995696 -62.3189) (xy 246.825516 -62.4078) (xy 246.825516 -62.62878)
			(xy 246.995696 -62.71768) (xy 247.040146 -62.71768)
		)
		(stroke
			(width 0)
			(type solid)
		)
		(fill yes)
		(layer "In4.Cu")
		(net "M_C_ECC<2>")
	)
	(gr_poly
		(pts
			(xy 247.040146 -61.3283) (xy 246.995696 -61.3283) (xy 246.825516 -61.4172) (xy 246.825516 -61.63818)
			(xy 246.995696 -61.72708) (xy 247.040146 -61.72708)
		)
		(stroke
			(width 0)
			(type solid)
		)
		(fill yes)
		(layer "In4.Cu")
		(net "M_C_ECC<2>")
	)
	(gr_poly
		(pts
			(xy 247.040146 -60.3377) (xy 246.995696 -60.3377) (xy 246.825516 -60.4266) (xy 246.825516 -60.64758)
			(xy 246.995696 -60.73648) (xy 247.040146 -60.73648)
		)
		(stroke
			(width 0)
			(type solid)
		)
		(fill yes)
		(layer "In4.Cu")
		(net "M_C_ECC<2>")
	)
	(gr_poly
		(pts
			(xy 247.040146 -59.3471) (xy 246.995696 -59.3471) (xy 246.825516 -59.436) (xy 246.825516 -59.65698)
			(xy 246.995696 -59.74588) (xy 247.040146 -59.74588)
		)
		(stroke
			(width 0)
			(type solid)
		)
		(fill yes)
		(layer "In4.Cu")
		(net "M_C_ECC<2>")
	)
	(gr_poly
		(pts
			(xy 247.040146 -58.368946) (xy 246.995696 -58.368946) (xy 246.825516 -58.457846) (xy 246.825516 -58.678826)
			(xy 246.995696 -58.767726) (xy 247.040146 -58.767726)
		)
		(stroke
			(width 0)
			(type solid)
		)
		(fill yes)
		(layer "In4.Cu")
		(net "M_C_ECC<2>")
	)
	(gr_poly
		(pts
			(xy 247.040146 -57.37225) (xy 246.995696 -57.37225) (xy 246.825516 -57.46115) (xy 246.825516 -57.68213)
			(xy 246.995696 -57.77103) (xy 247.040146 -57.77103)
		)
		(stroke
			(width 0)
			(type solid)
		)
		(fill yes)
		(layer "In4.Cu")
		(net "M_C_ECC<2>")
	)
	(gr_poly
		(pts
			(xy 247.040146 -56.3753) (xy 246.995696 -56.3753) (xy 246.825516 -56.4642) (xy 246.825516 -56.68518)
			(xy 246.995696 -56.77408) (xy 247.040146 -56.77408)
		)
		(stroke
			(width 0)
			(type solid)
		)
		(fill yes)
		(layer "In4.Cu")
		(net "M_C_ECC<2>")
	)
	(gr_poly
		(pts
			(xy 247.136666 -50.462688) (xy 247.105424 -50.431192) (xy 246.906034 -50.357532) (xy 246.744236 -50.519076)
			(xy 246.817896 -50.718466) (xy 246.849392 -50.749962)
		)
		(stroke
			(width 0)
			(type solid)
		)
		(fill yes)
		(layer "In4.Cu")
		(net "M_C_ECC<6>")
	)
	(gr_poly
		(pts
			(xy 247.202706 -101.282754) (xy 247.202706 -101.054154) (xy 247.009666 -100.965254) (xy 246.965216 -100.965254)
			(xy 246.965216 -101.371654) (xy 247.009666 -101.371654)
		)
		(stroke
			(width 0)
			(type solid)
		)
		(fill yes)
		(layer "In4.Cu")
		(net "M_F_ECC<7>")
	)
	(gr_poly
		(pts
			(xy 247.218454 -97.005902) (xy 247.174004 -97.005902) (xy 246.980964 -97.094802) (xy 246.980964 -97.323402)
			(xy 247.174004 -97.412302) (xy 247.218454 -97.412302)
		)
		(stroke
			(width 0)
			(type solid)
		)
		(fill yes)
		(layer "In4.Cu")
		(net "M_F_ECC<6>")
	)
	(gr_poly
		(pts
			(xy 247.241568 -85.291168) (xy 247.322086 -85.116924) (xy 247.187212 -84.941918) (xy 246.998236 -84.975446)
			(xy 246.962676 -85.00237) (xy 247.206262 -85.318346)
		)
		(stroke
			(width 0)
			(type solid)
		)
		(fill yes)
		(layer "In4.Cu")
		(net "M_F_ECC<7>")
	)
	(gr_poly
		(pts
			(xy 247.307608 -52.229766) (xy 247.307608 -52.00142) (xy 247.114568 -51.91252) (xy 247.070118 -51.912266)
			(xy 247.070118 -52.318666) (xy 247.114568 -52.318666)
		)
		(stroke
			(width 0)
			(type solid)
		)
		(fill yes)
		(layer "In4.Cu")
		(net "M_C_ECC<7>")
	)
	(gr_poly
		(pts
			(xy 247.449848 -55.185564) (xy 247.449848 -54.956964) (xy 247.256808 -54.868064) (xy 247.212358 -54.868064)
			(xy 247.212358 -55.274464) (xy 247.256808 -55.274464)
		)
		(stroke
			(width 0)
			(type solid)
		)
		(fill yes)
		(layer "In4.Cu")
		(net "M_C_ECC<3>")
	)
	(gr_poly
		(pts
			(xy 247.449848 -54.296564) (xy 247.449848 -54.067964) (xy 247.256808 -53.979064) (xy 247.212358 -53.979064)
			(xy 247.212358 -54.385464) (xy 247.256808 -54.385464)
		)
		(stroke
			(width 0)
			(type solid)
		)
		(fill yes)
		(layer "In4.Cu")
		(net "M_C_ECC<3>")
	)
	(gr_poly
		(pts
			(xy 247.456706 -100.190554) (xy 247.456706 -99.961954) (xy 247.263666 -99.873054) (xy 247.219216 -99.873054)
			(xy 247.219216 -100.279454) (xy 247.263666 -100.279454)
		)
		(stroke
			(width 0)
			(type solid)
		)
		(fill yes)
		(layer "In4.Cu")
		(net "M_F_ECC<7>")
	)
	(gr_poly
		(pts
			(xy 247.456706 -99.199954) (xy 247.456706 -98.971354) (xy 247.263666 -98.882454) (xy 247.219216 -98.882454)
			(xy 247.219216 -99.288854) (xy 247.263666 -99.288854)
		)
		(stroke
			(width 0)
			(type solid)
		)
		(fill yes)
		(layer "In4.Cu")
		(net "M_F_ECC<7>")
	)
	(gr_poly
		(pts
			(xy 247.578372 -95.826326) (xy 247.578372 -95.605346) (xy 247.408192 -95.516446) (xy 247.363742 -95.516446)
			(xy 247.363742 -95.915226) (xy 247.408192 -95.915226)
		)
		(stroke
			(width 0)
			(type solid)
		)
		(fill yes)
		(layer "In4.Cu")
		(net "M_F_ECC<7>")
	)
	(gr_poly
		(pts
			(xy 247.578372 -94.829376) (xy 247.578372 -94.608396) (xy 247.408192 -94.519496) (xy 247.363742 -94.519496)
			(xy 247.363742 -94.918276) (xy 247.408192 -94.918276)
		)
		(stroke
			(width 0)
			(type solid)
		)
		(fill yes)
		(layer "In4.Cu")
		(net "M_F_ECC<7>")
	)
	(gr_poly
		(pts
			(xy 247.578372 -93.83268) (xy 247.578372 -93.6117) (xy 247.408192 -93.5228) (xy 247.363742 -93.5228)
			(xy 247.363742 -93.92158) (xy 247.408192 -93.92158)
		)
		(stroke
			(width 0)
			(type solid)
		)
		(fill yes)
		(layer "In4.Cu")
		(net "M_F_ECC<7>")
	)
	(gr_poly
		(pts
			(xy 247.578372 -92.854526) (xy 247.578372 -92.633546) (xy 247.408192 -92.544646) (xy 247.363742 -92.544646)
			(xy 247.363742 -92.943426) (xy 247.408192 -92.943426)
		)
		(stroke
			(width 0)
			(type solid)
		)
		(fill yes)
		(layer "In4.Cu")
		(net "M_F_ECC<7>")
	)
	(gr_poly
		(pts
			(xy 247.578372 -91.863926) (xy 247.578372 -91.642946) (xy 247.408192 -91.554046) (xy 247.363742 -91.554046)
			(xy 247.363742 -91.952826) (xy 247.408192 -91.952826)
		)
		(stroke
			(width 0)
			(type solid)
		)
		(fill yes)
		(layer "In4.Cu")
		(net "M_F_ECC<7>")
	)
	(gr_poly
		(pts
			(xy 247.578372 -90.873326) (xy 247.578372 -90.652346) (xy 247.408192 -90.563446) (xy 247.363742 -90.563446)
			(xy 247.363742 -90.962226) (xy 247.408192 -90.962226)
		)
		(stroke
			(width 0)
			(type solid)
		)
		(fill yes)
		(layer "In4.Cu")
		(net "M_F_ECC<7>")
	)
	(gr_poly
		(pts
			(xy 247.578372 -89.882726) (xy 247.578372 -89.661746) (xy 247.408192 -89.572846) (xy 247.363742 -89.572846)
			(xy 247.363742 -89.971626) (xy 247.408192 -89.971626)
		)
		(stroke
			(width 0)
			(type solid)
		)
		(fill yes)
		(layer "In4.Cu")
		(net "M_F_ECC<7>")
	)
	(gr_poly
		(pts
			(xy 247.578372 -88.892126) (xy 247.578372 -88.671146) (xy 247.408192 -88.582246) (xy 247.363742 -88.582246)
			(xy 247.363742 -88.981026) (xy 247.408192 -88.981026)
		)
		(stroke
			(width 0)
			(type solid)
		)
		(fill yes)
		(layer "In4.Cu")
		(net "M_F_ECC<7>")
	)
	(gr_poly
		(pts
			(xy 247.578372 -87.901526) (xy 247.578372 -87.680546) (xy 247.408192 -87.591646) (xy 247.363742 -87.591646)
			(xy 247.363742 -87.990426) (xy 247.408192 -87.990426)
		)
		(stroke
			(width 0)
			(type solid)
		)
		(fill yes)
		(layer "In4.Cu")
		(net "M_F_ECC<7>")
	)
	(gr_poly
		(pts
			(xy 247.578372 -86.910926) (xy 247.578372 -86.689946) (xy 247.408192 -86.601046) (xy 247.363742 -86.601046)
			(xy 247.363742 -86.999826) (xy 247.408192 -86.999826)
		)
		(stroke
			(width 0)
			(type solid)
		)
		(fill yes)
		(layer "In4.Cu")
		(net "M_F_ECC<7>")
	)
	(gr_poly
		(pts
			(xy 247.578372 -85.920326) (xy 247.578372 -85.699346) (xy 247.408192 -85.610446) (xy 247.363742 -85.610446)
			(xy 247.363742 -86.009226) (xy 247.408192 -86.009226)
		)
		(stroke
			(width 0)
			(type solid)
		)
		(fill yes)
		(layer "In4.Cu")
		(net "M_F_ECC<7>")
	)
	(gr_poly
		(pts
			(xy 247.578372 -67.098926) (xy 247.578372 -66.877946) (xy 247.408192 -66.789046) (xy 247.363742 -66.789046)
			(xy 247.363742 -67.187826) (xy 247.408192 -67.187826)
		)
		(stroke
			(width 0)
			(type solid)
		)
		(fill yes)
		(layer "In4.Cu")
		(net "M_C_ECC<3>")
	)
	(gr_poly
		(pts
			(xy 247.578372 -66.108326) (xy 247.578372 -65.887346) (xy 247.408192 -65.798446) (xy 247.363742 -65.798446)
			(xy 247.363742 -66.197226) (xy 247.408192 -66.197226)
		)
		(stroke
			(width 0)
			(type solid)
		)
		(fill yes)
		(layer "In4.Cu")
		(net "M_C_ECC<3>")
	)
	(gr_poly
		(pts
			(xy 247.578372 -65.117726) (xy 247.578372 -64.896746) (xy 247.408192 -64.807846) (xy 247.363742 -64.807846)
			(xy 247.363742 -65.206626) (xy 247.408192 -65.206626)
		)
		(stroke
			(width 0)
			(type solid)
		)
		(fill yes)
		(layer "In4.Cu")
		(net "M_C_ECC<3>")
	)
	(gr_poly
		(pts
			(xy 247.578372 -64.127126) (xy 247.578372 -63.906146) (xy 247.408192 -63.817246) (xy 247.363742 -63.817246)
			(xy 247.363742 -64.216026) (xy 247.408192 -64.216026)
		)
		(stroke
			(width 0)
			(type solid)
		)
		(fill yes)
		(layer "In4.Cu")
		(net "M_C_ECC<3>")
	)
	(gr_poly
		(pts
			(xy 247.578372 -63.136526) (xy 247.578372 -62.915546) (xy 247.408192 -62.826646) (xy 247.363742 -62.826646)
			(xy 247.363742 -63.225426) (xy 247.408192 -63.225426)
		)
		(stroke
			(width 0)
			(type solid)
		)
		(fill yes)
		(layer "In4.Cu")
		(net "M_C_ECC<3>")
	)
	(gr_poly
		(pts
			(xy 247.578372 -62.145926) (xy 247.578372 -61.924946) (xy 247.408192 -61.836046) (xy 247.363742 -61.836046)
			(xy 247.363742 -62.234826) (xy 247.408192 -62.234826)
		)
		(stroke
			(width 0)
			(type solid)
		)
		(fill yes)
		(layer "In4.Cu")
		(net "M_C_ECC<3>")
	)
	(gr_poly
		(pts
			(xy 247.578372 -61.155326) (xy 247.578372 -60.934346) (xy 247.408192 -60.845446) (xy 247.363742 -60.845446)
			(xy 247.363742 -61.244226) (xy 247.408192 -61.244226)
		)
		(stroke
			(width 0)
			(type solid)
		)
		(fill yes)
		(layer "In4.Cu")
		(net "M_C_ECC<3>")
	)
	(gr_poly
		(pts
			(xy 247.578372 -60.164726) (xy 247.578372 -59.943746) (xy 247.408192 -59.854846) (xy 247.363742 -59.854846)
			(xy 247.363742 -60.253626) (xy 247.408192 -60.253626)
		)
		(stroke
			(width 0)
			(type solid)
		)
		(fill yes)
		(layer "In4.Cu")
		(net "M_C_ECC<3>")
	)
	(gr_poly
		(pts
			(xy 247.578372 -59.167776) (xy 247.578372 -58.946796) (xy 247.408192 -58.857896) (xy 247.363742 -58.857896)
			(xy 247.363742 -59.256676) (xy 247.408192 -59.256676)
		)
		(stroke
			(width 0)
			(type solid)
		)
		(fill yes)
		(layer "In4.Cu")
		(net "M_C_ECC<3>")
	)
	(gr_poly
		(pts
			(xy 247.578372 -58.17108) (xy 247.578372 -57.9501) (xy 247.408192 -57.8612) (xy 247.363742 -57.8612)
			(xy 247.363742 -58.25998) (xy 247.408192 -58.25998)
		)
		(stroke
			(width 0)
			(type solid)
		)
		(fill yes)
		(layer "In4.Cu")
		(net "M_C_ECC<3>")
	)
	(gr_poly
		(pts
			(xy 247.578372 -57.192926) (xy 247.578372 -56.971946) (xy 247.408192 -56.883046) (xy 247.363742 -56.883046)
			(xy 247.363742 -57.281826) (xy 247.408192 -57.281826)
		)
		(stroke
			(width 0)
			(type solid)
		)
		(fill yes)
		(layer "In4.Cu")
		(net "M_C_ECC<3>")
	)
	(gr_poly
		(pts
			(xy 247.645936 -97.323402) (xy 247.645936 -97.094802) (xy 247.452896 -97.005902) (xy 247.408446 -97.005902)
			(xy 247.408446 -97.412302) (xy 247.452896 -97.412302)
		)
		(stroke
			(width 0)
			(type solid)
		)
		(fill yes)
		(layer "In4.Cu")
		(net "M_F_ECC<7>")
	)
	(gr_poly
		(pts
			(xy 247.70334 -52.689506) (xy 247.671844 -52.658264) (xy 247.472454 -52.584604) (xy 247.31091 -52.746148)
			(xy 247.38457 -52.945538) (xy 247.415812 -52.977034)
		)
		(stroke
			(width 0)
			(type solid)
		)
		(fill yes)
		(layer "In4.Cu")
		(net "M_C_ECC<2>")
	)
	(gr_poly
		(pts
			(xy 247.898666 -95.516446) (xy 247.854216 -95.516446) (xy 247.684036 -95.605346) (xy 247.684036 -95.826326)
			(xy 247.854216 -95.915226) (xy 247.898666 -95.915226)
		)
		(stroke
			(width 0)
			(type solid)
		)
		(fill yes)
		(layer "In4.Cu")
		(net "M_F_ECC<2>")
	)
	(gr_poly
		(pts
			(xy 247.898666 -94.519496) (xy 247.854216 -94.519496) (xy 247.684036 -94.608396) (xy 247.684036 -94.829376)
			(xy 247.854216 -94.918276) (xy 247.898666 -94.918276)
		)
		(stroke
			(width 0)
			(type solid)
		)
		(fill yes)
		(layer "In4.Cu")
		(net "M_F_ECC<2>")
	)
	(gr_poly
		(pts
			(xy 247.898666 -93.5228) (xy 247.854216 -93.5228) (xy 247.684036 -93.6117) (xy 247.684036 -93.83268)
			(xy 247.854216 -93.92158) (xy 247.898666 -93.92158)
		)
		(stroke
			(width 0)
			(type solid)
		)
		(fill yes)
		(layer "In4.Cu")
		(net "M_F_ECC<2>")
	)
	(gr_poly
		(pts
			(xy 247.898666 -92.544646) (xy 247.854216 -92.544646) (xy 247.684036 -92.633546) (xy 247.684036 -92.854526)
			(xy 247.854216 -92.943426) (xy 247.898666 -92.943426)
		)
		(stroke
			(width 0)
			(type solid)
		)
		(fill yes)
		(layer "In4.Cu")
		(net "M_F_ECC<2>")
	)
	(gr_poly
		(pts
			(xy 247.898666 -91.554046) (xy 247.854216 -91.554046) (xy 247.684036 -91.642946) (xy 247.684036 -91.863926)
			(xy 247.854216 -91.952826) (xy 247.898666 -91.952826)
		)
		(stroke
			(width 0)
			(type solid)
		)
		(fill yes)
		(layer "In4.Cu")
		(net "M_F_ECC<2>")
	)
	(gr_poly
		(pts
			(xy 247.898666 -90.563446) (xy 247.854216 -90.563446) (xy 247.684036 -90.652346) (xy 247.684036 -90.873326)
			(xy 247.854216 -90.962226) (xy 247.898666 -90.962226)
		)
		(stroke
			(width 0)
			(type solid)
		)
		(fill yes)
		(layer "In4.Cu")
		(net "M_F_ECC<2>")
	)
	(gr_poly
		(pts
			(xy 247.898666 -89.572846) (xy 247.854216 -89.572846) (xy 247.684036 -89.661746) (xy 247.684036 -89.882726)
			(xy 247.854216 -89.971626) (xy 247.898666 -89.971626)
		)
		(stroke
			(width 0)
			(type solid)
		)
		(fill yes)
		(layer "In4.Cu")
		(net "M_F_ECC<2>")
	)
	(gr_poly
		(pts
			(xy 247.898666 -88.582246) (xy 247.854216 -88.582246) (xy 247.684036 -88.671146) (xy 247.684036 -88.892126)
			(xy 247.854216 -88.981026) (xy 247.898666 -88.981026)
		)
		(stroke
			(width 0)
			(type solid)
		)
		(fill yes)
		(layer "In4.Cu")
		(net "M_F_ECC<2>")
	)
	(gr_poly
		(pts
			(xy 247.898666 -87.591646) (xy 247.854216 -87.591646) (xy 247.684036 -87.680546) (xy 247.684036 -87.901526)
			(xy 247.854216 -87.990426) (xy 247.898666 -87.990426)
		)
		(stroke
			(width 0)
			(type solid)
		)
		(fill yes)
		(layer "In4.Cu")
		(net "M_F_ECC<2>")
	)
	(gr_poly
		(pts
			(xy 247.898666 -86.601046) (xy 247.854216 -86.601046) (xy 247.684036 -86.689946) (xy 247.684036 -86.910926)
			(xy 247.854216 -86.999826) (xy 247.898666 -86.999826)
		)
		(stroke
			(width 0)
			(type solid)
		)
		(fill yes)
		(layer "In4.Cu")
		(net "M_F_ECC<2>")
	)
	(gr_poly
		(pts
			(xy 247.898666 -85.610446) (xy 247.854216 -85.610446) (xy 247.684036 -85.699346) (xy 247.684036 -85.920326)
			(xy 247.854216 -86.009226) (xy 247.898666 -86.009226)
		)
		(stroke
			(width 0)
			(type solid)
		)
		(fill yes)
		(layer "In4.Cu")
		(net "M_F_ECC<2>")
	)
	(gr_poly
		(pts
			(xy 247.943116 -53.055012) (xy 247.869456 -52.855622) (xy 247.83796 -52.82438) (xy 247.550686 -53.111654)
			(xy 247.581928 -53.14315) (xy 247.781318 -53.21681)
		)
		(stroke
			(width 0)
			(type solid)
		)
		(fill yes)
		(layer "In4.Cu")
		(net "M_C_ECC<3>")
	)
	(gr_poly
		(pts
			(xy 247.955308 -51.593242) (xy 247.910858 -51.593242) (xy 247.717818 -51.682142) (xy 247.717818 -51.910742)
			(xy 247.910858 -51.999642) (xy 247.955308 -51.999642)
		)
		(stroke
			(width 0)
			(type solid)
		)
		(fill yes)
		(layer "In4.Cu")
		(net "M_C_ECC<2>")
	)
	(gr_poly
		(pts
			(xy 248.366788 -96.766888) (xy 248.405396 -96.74479) (xy 248.201942 -96.392746) (xy 248.163588 -96.415098)
			(xy 248.040906 -96.58858) (xy 248.155206 -96.786446)
		)
		(stroke
			(width 0)
			(type solid)
		)
		(fill yes)
		(layer "In4.Cu")
		(net "M_F_ECC<2>")
	)
	(gr_poly
		(pts
			(xy 248.383298 -51.910742) (xy 248.383298 -51.682142) (xy 248.190258 -51.593242) (xy 248.145808 -51.593242)
			(xy 248.145808 -51.999642) (xy 248.190258 -51.999642)
		)
		(stroke
			(width 0)
			(type solid)
		)
		(fill yes)
		(layer "In4.Cu")
		(net "M_C_ECC<3>")
	)
	(gr_poly
		(pts
			(xy 248.40692 -50.524918) (xy 248.375424 -50.493676) (xy 248.176034 -50.420016) (xy 248.01449 -50.58156)
			(xy 248.08815 -50.78095) (xy 248.119392 -50.812446)
		)
		(stroke
			(width 0)
			(type solid)
		)
		(fill yes)
		(layer "In4.Cu")
		(net "M_C_ECC<2>")
	)
	(gr_poly
		(pts
			(xy 248.436892 -95.31858) (xy 248.436892 -95.0976) (xy 248.266712 -95.0087) (xy 248.222262 -95.0087)
			(xy 248.222262 -95.40748) (xy 248.266712 -95.40748)
		)
		(stroke
			(width 0)
			(type solid)
		)
		(fill yes)
		(layer "In4.Cu")
		(net "M_F_ECC<3>")
	)
	(gr_poly
		(pts
			(xy 248.436892 -94.340426) (xy 248.436892 -94.119446) (xy 248.266712 -94.030546) (xy 248.222262 -94.030546)
			(xy 248.222262 -94.429326) (xy 248.266712 -94.429326)
		)
		(stroke
			(width 0)
			(type solid)
		)
		(fill yes)
		(layer "In4.Cu")
		(net "M_F_ECC<3>")
	)
	(gr_poly
		(pts
			(xy 248.436892 -93.34373) (xy 248.436892 -93.12275) (xy 248.266712 -93.03385) (xy 248.222262 -93.03385)
			(xy 248.222262 -93.43263) (xy 248.266712 -93.43263)
		)
		(stroke
			(width 0)
			(type solid)
		)
		(fill yes)
		(layer "In4.Cu")
		(net "M_F_ECC<3>")
	)
	(gr_poly
		(pts
			(xy 248.436892 -92.34678) (xy 248.436892 -92.1258) (xy 248.266712 -92.0369) (xy 248.222262 -92.0369)
			(xy 248.222262 -92.43568) (xy 248.266712 -92.43568)
		)
		(stroke
			(width 0)
			(type solid)
		)
		(fill yes)
		(layer "In4.Cu")
		(net "M_F_ECC<3>")
	)
	(gr_poly
		(pts
			(xy 248.436892 -91.35618) (xy 248.436892 -91.1352) (xy 248.266712 -91.0463) (xy 248.222262 -91.0463)
			(xy 248.222262 -91.44508) (xy 248.266712 -91.44508)
		)
		(stroke
			(width 0)
			(type solid)
		)
		(fill yes)
		(layer "In4.Cu")
		(net "M_F_ECC<3>")
	)
	(gr_poly
		(pts
			(xy 248.436892 -90.36558) (xy 248.436892 -90.1446) (xy 248.266712 -90.0557) (xy 248.222262 -90.0557)
			(xy 248.222262 -90.45448) (xy 248.266712 -90.45448)
		)
		(stroke
			(width 0)
			(type solid)
		)
		(fill yes)
		(layer "In4.Cu")
		(net "M_F_ECC<3>")
	)
	(gr_poly
		(pts
			(xy 248.436892 -89.37498) (xy 248.436892 -89.154) (xy 248.266712 -89.0651) (xy 248.222262 -89.0651)
			(xy 248.222262 -89.46388) (xy 248.266712 -89.46388)
		)
		(stroke
			(width 0)
			(type solid)
		)
		(fill yes)
		(layer "In4.Cu")
		(net "M_F_ECC<3>")
	)
	(gr_poly
		(pts
			(xy 248.436892 -88.38438) (xy 248.436892 -88.1634) (xy 248.266712 -88.0745) (xy 248.222262 -88.0745)
			(xy 248.222262 -88.47328) (xy 248.266712 -88.47328)
		)
		(stroke
			(width 0)
			(type solid)
		)
		(fill yes)
		(layer "In4.Cu")
		(net "M_F_ECC<3>")
	)
	(gr_poly
		(pts
			(xy 248.436892 -87.39378) (xy 248.436892 -87.1728) (xy 248.266712 -87.0839) (xy 248.222262 -87.0839)
			(xy 248.222262 -87.48268) (xy 248.266712 -87.48268)
		)
		(stroke
			(width 0)
			(type solid)
		)
		(fill yes)
		(layer "In4.Cu")
		(net "M_F_ECC<3>")
	)
	(gr_poly
		(pts
			(xy 248.436892 -86.40318) (xy 248.436892 -86.1822) (xy 248.266712 -86.0933) (xy 248.222262 -86.0933)
			(xy 248.222262 -86.49208) (xy 248.266712 -86.49208)
		)
		(stroke
			(width 0)
			(type solid)
		)
		(fill yes)
		(layer "In4.Cu")
		(net "M_F_ECC<3>")
	)
	(gr_poly
		(pts
			(xy 248.436892 -85.41258) (xy 248.436892 -85.1916) (xy 248.266712 -85.1027) (xy 248.222262 -85.1027)
			(xy 248.222262 -85.50148) (xy 248.266712 -85.50148)
		)
		(stroke
			(width 0)
			(type solid)
		)
		(fill yes)
		(layer "In4.Cu")
		(net "M_F_ECC<3>")
	)
	(gr_poly
		(pts
			(xy 248.608596 -96.627188) (xy 248.731278 -96.453706) (xy 248.616724 -96.25584) (xy 248.405142 -96.275398)
			(xy 248.366788 -96.29775) (xy 248.569988 -96.64954)
		)
		(stroke
			(width 0)
			(type solid)
		)
		(fill yes)
		(layer "In4.Cu")
		(net "M_F_ECC<3>")
	)
	(gr_poly
		(pts
			(xy 248.629424 -101.78923) (xy 248.584974 -101.78923) (xy 248.391934 -101.87813) (xy 248.391934 -102.10673)
			(xy 248.584974 -102.19563) (xy 248.629424 -102.19563)
		)
		(stroke
			(width 0)
			(type solid)
		)
		(fill yes)
		(layer "In4.Cu")
		(net "M_F_ECC<2>")
	)
	(gr_poly
		(pts
			(xy 248.629424 -100.79863) (xy 248.584974 -100.79863) (xy 248.391934 -100.88753) (xy 248.391934 -101.11613)
			(xy 248.584974 -101.20503) (xy 248.629424 -101.20503)
		)
		(stroke
			(width 0)
			(type solid)
		)
		(fill yes)
		(layer "In4.Cu")
		(net "M_F_ECC<2>")
	)
	(gr_poly
		(pts
			(xy 248.629424 -99.80803) (xy 248.584974 -99.80803) (xy 248.391934 -99.89693) (xy 248.391934 -100.12553)
			(xy 248.584974 -100.21443) (xy 248.629424 -100.21443)
		)
		(stroke
			(width 0)
			(type solid)
		)
		(fill yes)
		(layer "In4.Cu")
		(net "M_F_ECC<2>")
	)
	(gr_poly
		(pts
			(xy 248.629424 -98.81743) (xy 248.584974 -98.81743) (xy 248.391934 -98.90633) (xy 248.391934 -99.13493)
			(xy 248.584974 -99.22383) (xy 248.629424 -99.22383)
		)
		(stroke
			(width 0)
			(type solid)
		)
		(fill yes)
		(layer "In4.Cu")
		(net "M_F_ECC<2>")
	)
	(gr_poly
		(pts
			(xy 248.629424 -97.82683) (xy 248.584974 -97.82683) (xy 248.391934 -97.91573) (xy 248.391934 -98.14433)
			(xy 248.584974 -98.23323) (xy 248.629424 -98.23323)
		)
		(stroke
			(width 0)
			(type solid)
		)
		(fill yes)
		(layer "In4.Cu")
		(net "M_F_ECC<2>")
	)
	(gr_poly
		(pts
			(xy 248.646696 -50.890424) (xy 248.573036 -50.691034) (xy 248.54154 -50.659792) (xy 248.254266 -50.947066)
			(xy 248.285508 -50.978562) (xy 248.484898 -51.052222)
		)
		(stroke
			(width 0)
			(type solid)
		)
		(fill yes)
		(layer "In4.Cu")
		(net "M_C_ECC<3>")
	)
	(gr_poly
		(pts
			(xy 249.056906 -102.10673) (xy 249.056906 -101.87813) (xy 248.863866 -101.78923) (xy 248.819416 -101.78923)
			(xy 248.819416 -102.19563) (xy 248.863866 -102.19563)
		)
		(stroke
			(width 0)
			(type solid)
		)
		(fill yes)
		(layer "In4.Cu")
		(net "M_F_ECC<3>")
	)
	(gr_poly
		(pts
			(xy 249.056906 -101.11613) (xy 249.056906 -100.88753) (xy 248.863866 -100.79863) (xy 248.819416 -100.79863)
			(xy 248.819416 -101.20503) (xy 248.863866 -101.20503)
		)
		(stroke
			(width 0)
			(type solid)
		)
		(fill yes)
		(layer "In4.Cu")
		(net "M_F_ECC<3>")
	)
	(gr_poly
		(pts
			(xy 249.056906 -100.12553) (xy 249.056906 -99.89693) (xy 248.863866 -99.80803) (xy 248.819416 -99.80803)
			(xy 248.819416 -100.21443) (xy 248.863866 -100.21443)
		)
		(stroke
			(width 0)
			(type solid)
		)
		(fill yes)
		(layer "In4.Cu")
		(net "M_F_ECC<3>")
	)
	(gr_poly
		(pts
			(xy 249.056906 -99.13493) (xy 249.056906 -98.90633) (xy 248.863866 -98.81743) (xy 248.819416 -98.81743)
			(xy 248.819416 -99.22383) (xy 248.863866 -99.22383)
		)
		(stroke
			(width 0)
			(type solid)
		)
		(fill yes)
		(layer "In4.Cu")
		(net "M_F_ECC<3>")
	)
	(gr_poly
		(pts
			(xy 249.056906 -98.14433) (xy 249.056906 -97.91573) (xy 248.863866 -97.82683) (xy 248.819416 -97.82683)
			(xy 248.819416 -98.23323) (xy 248.863866 -98.23323)
		)
		(stroke
			(width 0)
			(type solid)
		)
		(fill yes)
		(layer "In4.Cu")
		(net "M_F_ECC<3>")
	)
	(gr_poly
		(pts
			(xy 269.444724 -56.1721) (xy 269.400274 -56.1721) (xy 269.207234 -56.261) (xy 269.207234 -56.4896)
			(xy 269.400274 -56.5785) (xy 269.444724 -56.5785)
		)
		(stroke
			(width 0)
			(type solid)
		)
		(fill yes)
		(layer "In4.Cu")
		(net "M_B_DQ<36>")
	)
	(gr_poly
		(pts
			(xy 269.444724 -55.1815) (xy 269.400274 -55.1815) (xy 269.207234 -55.2704) (xy 269.207234 -55.499)
			(xy 269.400274 -55.5879) (xy 269.444724 -55.5879)
		)
		(stroke
			(width 0)
			(type solid)
		)
		(fill yes)
		(layer "In4.Cu")
		(net "M_B_DQ<36>")
	)
	(gr_poly
		(pts
			(xy 269.444724 -53.7845) (xy 269.400274 -53.7845) (xy 269.207234 -53.8734) (xy 269.207234 -54.102)
			(xy 269.400274 -54.1909) (xy 269.444724 -54.1909)
		)
		(stroke
			(width 0)
			(type solid)
		)
		(fill yes)
		(layer "In4.Cu")
		(net "M_B_DQ<36>")
	)
	(gr_poly
		(pts
			(xy 269.444724 -52.7939) (xy 269.400274 -52.7939) (xy 269.207234 -52.8828) (xy 269.207234 -53.1114)
			(xy 269.400274 -53.2003) (xy 269.444724 -53.2003)
		)
		(stroke
			(width 0)
			(type solid)
		)
		(fill yes)
		(layer "In4.Cu")
		(net "M_B_DQ<36>")
	)
	(gr_poly
		(pts
			(xy 269.872714 -56.4896) (xy 269.872714 -56.261) (xy 269.679674 -56.1721) (xy 269.635224 -56.1721)
			(xy 269.635224 -56.5785) (xy 269.679674 -56.5785)
		)
		(stroke
			(width 0)
			(type solid)
		)
		(fill yes)
		(layer "In4.Cu")
		(net "M_B_DQ<37>")
	)
	(gr_poly
		(pts
			(xy 269.872714 -55.499) (xy 269.872714 -55.2704) (xy 269.679674 -55.1815) (xy 269.635224 -55.1815)
			(xy 269.635224 -55.5879) (xy 269.679674 -55.5879)
		)
		(stroke
			(width 0)
			(type solid)
		)
		(fill yes)
		(layer "In4.Cu")
		(net "M_B_DQ<37>")
	)
	(gr_poly
		(pts
			(xy 269.872714 -54.102) (xy 269.872714 -53.8734) (xy 269.679674 -53.7845) (xy 269.635224 -53.7845)
			(xy 269.635224 -54.1909) (xy 269.679674 -54.1909)
		)
		(stroke
			(width 0)
			(type solid)
		)
		(fill yes)
		(layer "In4.Cu")
		(net "M_B_DQ<37>")
	)
	(gr_poly
		(pts
			(xy 269.872714 -53.1114) (xy 269.872714 -52.8828) (xy 269.679674 -52.7939) (xy 269.635224 -52.7939)
			(xy 269.635224 -53.2003) (xy 269.679674 -53.2003)
		)
		(stroke
			(width 0)
			(type solid)
		)
		(fill yes)
		(layer "In4.Cu")
		(net "M_B_DQ<37>")
	)
	(gr_poly
		(pts
			(xy 270.111474 -57.488328) (xy 270.142716 -57.456832) (xy 269.855442 -57.169558) (xy 269.823946 -57.201054)
			(xy 269.750286 -57.400444) (xy 269.912084 -57.561988)
		)
		(stroke
			(width 0)
			(type solid)
		)
		(fill yes)
		(layer "In4.Cu")
		(net "M_B_DQ<36>")
	)
	(gr_poly
		(pts
			(xy 270.130016 -57.110376) (xy 270.203676 -56.910986) (xy 270.042132 -56.749442) (xy 269.842742 -56.823102)
			(xy 269.811246 -56.854344) (xy 270.098774 -57.141872)
		)
		(stroke
			(width 0)
			(type solid)
		)
		(fill yes)
		(layer "In4.Cu")
		(net "M_B_DQ<37>")
	)
	(gr_poly
		(pts
			(xy 270.204946 -50.812192) (xy 270.160496 -50.812192) (xy 269.967456 -50.901092) (xy 269.967456 -51.129692)
			(xy 270.160496 -51.218592) (xy 270.204946 -51.218592)
		)
		(stroke
			(width 0)
			(type solid)
		)
		(fill yes)
		(layer "In4.Cu")
		(net "M_B_DQ<36>")
	)
	(gr_poly
		(pts
			(xy 270.414496 -54.305454) (xy 270.38935 -54.269132) (xy 270.219932 -54.178962) (xy 270.037814 -54.30393)
			(xy 270.060674 -54.49443) (xy 270.085566 -54.53126)
		)
		(stroke
			(width 0)
			(type solid)
		)
		(fill yes)
		(layer "In4.Cu")
		(net "M_B_DQ<32>")
	)
	(gr_poly
		(pts
			(xy 270.632428 -51.129692) (xy 270.632428 -50.901092) (xy 270.439388 -50.812192) (xy 270.394938 -50.812192)
			(xy 270.394938 -51.218592) (xy 270.439388 -51.218592)
		)
		(stroke
			(width 0)
			(type solid)
		)
		(fill yes)
		(layer "In4.Cu")
		(net "M_B_DQ<37>")
	)
	(gr_poly
		(pts
			(xy 270.86052 -53.222398) (xy 270.81607 -53.222398) (xy 270.64589 -53.311298) (xy 270.64589 -53.532278)
			(xy 270.81607 -53.621178) (xy 270.86052 -53.621178)
		)
		(stroke
			(width 0)
			(type solid)
		)
		(fill yes)
		(layer "In4.Cu")
		(net "M_B_DQ<32>")
	)
	(gr_poly
		(pts
			(xy 270.963644 -49.103788) (xy 270.919194 -49.103788) (xy 270.726154 -49.192688) (xy 270.726154 -49.421288)
			(xy 270.919194 -49.510188) (xy 270.963644 -49.510188)
		)
		(stroke
			(width 0)
			(type solid)
		)
		(fill yes)
		(layer "In4.Cu")
		(net "M_B_DQ<36>")
	)
	(gr_poly
		(pts
			(xy 270.971518 -52.267358) (xy 270.927068 -52.267358) (xy 270.734028 -52.356258) (xy 270.734028 -52.584858)
			(xy 270.927068 -52.673758) (xy 270.971518 -52.673758)
		)
		(stroke
			(width 0)
			(type solid)
		)
		(fill yes)
		(layer "In4.Cu")
		(net "M_B_DQ<32>")
	)
	(gr_poly
		(pts
			(xy 270.971518 -51.276758) (xy 270.927068 -51.276758) (xy 270.734028 -51.365658) (xy 270.734028 -51.594258)
			(xy 270.927068 -51.683158) (xy 270.971518 -51.683158)
		)
		(stroke
			(width 0)
			(type solid)
		)
		(fill yes)
		(layer "In4.Cu")
		(net "M_B_DQ<32>")
	)
	(gr_poly
		(pts
			(xy 271.248124 -47.655988) (xy 271.203674 -47.655988) (xy 271.010634 -47.744888) (xy 271.010634 -47.973488)
			(xy 271.203674 -48.062388) (xy 271.248124 -48.062388)
		)
		(stroke
			(width 0)
			(type solid)
		)
		(fill yes)
		(layer "In4.Cu")
		(net "M_B_DQ<36>")
	)
	(gr_poly
		(pts
			(xy 271.248124 -46.665388) (xy 271.203674 -46.665388) (xy 271.010634 -46.754288) (xy 271.010634 -46.982888)
			(xy 271.203674 -47.071788) (xy 271.248124 -47.071788)
		)
		(stroke
			(width 0)
			(type solid)
		)
		(fill yes)
		(layer "In4.Cu")
		(net "M_B_DQ<36>")
	)
	(gr_poly
		(pts
			(xy 271.309338 -101.746558) (xy 271.264888 -101.746558) (xy 271.071848 -101.835458) (xy 271.071848 -102.064058)
			(xy 271.264888 -102.152958) (xy 271.309338 -102.152958)
		)
		(stroke
			(width 0)
			(type solid)
		)
		(fill yes)
		(layer "In4.Cu")
		(net "M_E_DQ<36>")
	)
	(gr_poly
		(pts
			(xy 271.309338 -100.755958) (xy 271.264888 -100.755958) (xy 271.071848 -100.844858) (xy 271.071848 -101.073458)
			(xy 271.264888 -101.162358) (xy 271.309338 -101.162358)
		)
		(stroke
			(width 0)
			(type solid)
		)
		(fill yes)
		(layer "In4.Cu")
		(net "M_E_DQ<36>")
	)
	(gr_poly
		(pts
			(xy 271.309338 -99.765358) (xy 271.264888 -99.765358) (xy 271.071848 -99.854258) (xy 271.071848 -100.082858)
			(xy 271.264888 -100.171758) (xy 271.309338 -100.171758)
		)
		(stroke
			(width 0)
			(type solid)
		)
		(fill yes)
		(layer "In4.Cu")
		(net "M_E_DQ<36>")
	)
	(gr_poly
		(pts
			(xy 271.352264 -54.796436) (xy 271.32915 -54.75859) (xy 271.16405 -54.660546) (xy 270.975836 -54.77637)
			(xy 270.989298 -54.967886) (xy 271.012666 -55.005732)
		)
		(stroke
			(width 0)
			(type solid)
		)
		(fill yes)
		(layer "In4.Cu")
		(net "M_B_DQS_DP<13>")
	)
	(gr_poly
		(pts
			(xy 271.39138 -49.421288) (xy 271.39138 -49.192688) (xy 271.19834 -49.103788) (xy 271.15389 -49.103788)
			(xy 271.15389 -49.510188) (xy 271.19834 -49.510188)
		)
		(stroke
			(width 0)
			(type solid)
		)
		(fill yes)
		(layer "In4.Cu")
		(net "M_B_DQ<37>")
	)
	(gr_poly
		(pts
			(xy 271.393666 -54.018942) (xy 271.393666 -53.797962) (xy 271.223232 -53.709062) (xy 271.178782 -53.709062)
			(xy 271.179036 -54.107842) (xy 271.223486 -54.107842)
		)
		(stroke
			(width 0)
			(type solid)
		)
		(fill yes)
		(layer "In4.Cu")
		(net "M_B_DQ<33>")
	)
	(gr_poly
		(pts
			(xy 271.399 -52.584858) (xy 271.399 -52.356258) (xy 271.20596 -52.267358) (xy 271.16151 -52.267358)
			(xy 271.16151 -52.673758) (xy 271.20596 -52.673758)
		)
		(stroke
			(width 0)
			(type solid)
		)
		(fill yes)
		(layer "In4.Cu")
		(net "M_B_DQ<33>")
	)
	(gr_poly
		(pts
			(xy 271.399 -51.594258) (xy 271.399 -51.365658) (xy 271.20596 -51.276758) (xy 271.16151 -51.276758)
			(xy 271.16151 -51.683158) (xy 271.20596 -51.683158)
		)
		(stroke
			(width 0)
			(type solid)
		)
		(fill yes)
		(layer "In4.Cu")
		(net "M_B_DQ<33>")
	)
	(gr_poly
		(pts
			(xy 271.549876 -50.348388) (xy 271.51838 -50.316892) (xy 271.319244 -50.243232) (xy 271.157446 -50.40503)
			(xy 271.231106 -50.604166) (xy 271.262602 -50.635662)
		)
		(stroke
			(width 0)
			(type solid)
		)
		(fill yes)
		(layer "In4.Cu")
		(net "M_B_DQ<32>")
	)
	(gr_poly
		(pts
			(xy 271.661128 -50.842926) (xy 271.587468 -50.643536) (xy 271.555972 -50.61204) (xy 271.268698 -50.899314)
			(xy 271.29994 -50.93081) (xy 271.49933 -51.00447)
		)
		(stroke
			(width 0)
			(type solid)
		)
		(fill yes)
		(layer "In4.Cu")
		(net "M_B_DQ<33>")
	)
	(gr_poly
		(pts
			(xy 271.675606 -47.973488) (xy 271.675606 -47.744888) (xy 271.482566 -47.655988) (xy 271.438116 -47.655988)
			(xy 271.438116 -48.062388) (xy 271.482566 -48.062388)
		)
		(stroke
			(width 0)
			(type solid)
		)
		(fill yes)
		(layer "In4.Cu")
		(net "M_B_DQ<37>")
	)
	(gr_poly
		(pts
			(xy 271.675606 -46.982888) (xy 271.675606 -46.754288) (xy 271.482566 -46.665388) (xy 271.438116 -46.665388)
			(xy 271.438116 -47.071788) (xy 271.482566 -47.071788)
		)
		(stroke
			(width 0)
			(type solid)
		)
		(fill yes)
		(layer "In4.Cu")
		(net "M_B_DQ<37>")
	)
	(gr_poly
		(pts
			(xy 271.716246 -104.31653) (xy 271.671796 -104.31653) (xy 271.478756 -104.40543) (xy 271.478756 -104.63403)
			(xy 271.671796 -104.72293) (xy 271.716246 -104.72293)
		)
		(stroke
			(width 0)
			(type solid)
		)
		(fill yes)
		(layer "In4.Cu")
		(net "M_E_DQ<36>")
	)
	(gr_poly
		(pts
			(xy 271.716246 -103.32593) (xy 271.671796 -103.32593) (xy 271.478756 -103.41483) (xy 271.478756 -103.64343)
			(xy 271.671796 -103.73233) (xy 271.716246 -103.73233)
		)
		(stroke
			(width 0)
			(type solid)
		)
		(fill yes)
		(layer "In4.Cu")
		(net "M_E_DQ<36>")
	)
	(gr_poly
		(pts
			(xy 271.73047 -49.391062) (xy 271.68602 -49.391062) (xy 271.49298 -49.479962) (xy 271.49298 -49.708562)
			(xy 271.68602 -49.797462) (xy 271.73047 -49.797462)
		)
		(stroke
			(width 0)
			(type solid)
		)
		(fill yes)
		(layer "In4.Cu")
		(net "M_B_DQ<32>")
	)
	(gr_poly
		(pts
			(xy 271.737328 -102.064058) (xy 271.737328 -101.835458) (xy 271.544288 -101.746558) (xy 271.499838 -101.746558)
			(xy 271.499838 -102.152958) (xy 271.544288 -102.152958)
		)
		(stroke
			(width 0)
			(type solid)
		)
		(fill yes)
		(layer "In4.Cu")
		(net "M_E_DQ<37>")
	)
	(gr_poly
		(pts
			(xy 271.737328 -101.073458) (xy 271.737328 -100.844858) (xy 271.544288 -100.755958) (xy 271.499838 -100.755958)
			(xy 271.499838 -101.162358) (xy 271.544288 -101.162358)
		)
		(stroke
			(width 0)
			(type solid)
		)
		(fill yes)
		(layer "In4.Cu")
		(net "M_E_DQ<37>")
	)
	(gr_poly
		(pts
			(xy 271.737328 -100.082858) (xy 271.737328 -99.854258) (xy 271.544288 -99.765358) (xy 271.499838 -99.765358)
			(xy 271.499838 -100.171758) (xy 271.544288 -100.171758)
		)
		(stroke
			(width 0)
			(type solid)
		)
		(fill yes)
		(layer "In4.Cu")
		(net "M_E_DQ<37>")
	)
	(gr_poly
		(pts
			(xy 271.758156 -52.24653) (xy 271.713706 -52.24653) (xy 271.520666 -52.33543) (xy 271.520666 -52.56403)
			(xy 271.713706 -52.65293) (xy 271.758156 -52.65293)
		)
		(stroke
			(width 0)
			(type solid)
		)
		(fill yes)
		(layer "In4.Cu")
		(net "M_B_DQS_DP<13>")
	)
	(gr_poly
		(pts
			(xy 271.815306 -98.140012) (xy 271.78381 -98.108516) (xy 271.584674 -98.034856) (xy 271.422876 -98.196654)
			(xy 271.496536 -98.39579) (xy 271.528032 -98.427286)
		)
		(stroke
			(width 0)
			(type solid)
		)
		(fill yes)
		(layer "In4.Cu")
		(net "M_E_DQ<36>")
	)
	(gr_poly
		(pts
			(xy 271.880838 -53.644292) (xy 271.836388 -53.644292) (xy 271.643348 -53.733192) (xy 271.643348 -53.961792)
			(xy 271.836388 -54.050692) (xy 271.880838 -54.050692)
		)
		(stroke
			(width 0)
			(type solid)
		)
		(fill yes)
		(layer "In4.Cu")
		(net "M_B_DQS_DP<13>")
	)
	(gr_poly
		(pts
			(xy 271.98828 -55.05577) (xy 271.980152 -54.864) (xy 271.958054 -54.825646) (xy 271.612614 -55.024782)
			(xy 271.634966 -55.06339) (xy 271.797018 -55.16626)
		)
		(stroke
			(width 0)
			(type solid)
		)
		(fill yes)
		(layer "In4.Cu")
		(net "M_B_DQS_DN<13>")
	)
	(gr_poly
		(pts
			(xy 272.014696 -48.057308) (xy 271.970246 -48.057308) (xy 271.777206 -48.146208) (xy 271.777206 -48.374808)
			(xy 271.970246 -48.463708) (xy 272.014696 -48.463708)
		)
		(stroke
			(width 0)
			(type solid)
		)
		(fill yes)
		(layer "In4.Cu")
		(net "M_B_DQ<32>")
	)
	(gr_poly
		(pts
			(xy 272.014696 -47.066708) (xy 271.970246 -47.066708) (xy 271.777206 -47.155608) (xy 271.777206 -47.384208)
			(xy 271.970246 -47.473108) (xy 272.014696 -47.473108)
		)
		(stroke
			(width 0)
			(type solid)
		)
		(fill yes)
		(layer "In4.Cu")
		(net "M_B_DQ<32>")
	)
	(gr_poly
		(pts
			(xy 272.033746 -101.269292) (xy 271.989296 -101.269292) (xy 271.796256 -101.358192) (xy 271.796256 -101.586792)
			(xy 271.989296 -101.675692) (xy 272.033746 -101.675692)
		)
		(stroke
			(width 0)
			(type solid)
		)
		(fill yes)
		(layer "In4.Cu")
		(net "M_E_DQ<32>")
	)
	(gr_poly
		(pts
			(xy 272.033746 -100.278692) (xy 271.989296 -100.278692) (xy 271.796256 -100.367592) (xy 271.796256 -100.596192)
			(xy 271.989296 -100.685092) (xy 272.033746 -100.685092)
		)
		(stroke
			(width 0)
			(type solid)
		)
		(fill yes)
		(layer "In4.Cu")
		(net "M_E_DQ<32>")
	)
	(gr_poly
		(pts
			(xy 272.033746 -99.288092) (xy 271.989296 -99.288092) (xy 271.796256 -99.376992) (xy 271.796256 -99.605592)
			(xy 271.989296 -99.694492) (xy 272.033746 -99.694492)
		)
		(stroke
			(width 0)
			(type solid)
		)
		(fill yes)
		(layer "In4.Cu")
		(net "M_E_DQ<32>")
	)
	(gr_poly
		(pts
			(xy 272.033746 -97.321624) (xy 271.989296 -97.321624) (xy 271.796256 -97.410524) (xy 271.796256 -97.639124)
			(xy 271.989296 -97.728024) (xy 272.033746 -97.728024)
		)
		(stroke
			(width 0)
			(type solid)
		)
		(fill yes)
		(layer "In4.Cu")
		(net "M_E_DQ<36>")
	)
	(gr_poly
		(pts
			(xy 272.033746 -96.331024) (xy 271.989296 -96.331024) (xy 271.796256 -96.419924) (xy 271.796256 -96.648524)
			(xy 271.989296 -96.737424) (xy 272.033746 -96.737424)
		)
		(stroke
			(width 0)
			(type solid)
		)
		(fill yes)
		(layer "In4.Cu")
		(net "M_E_DQ<36>")
	)
	(gr_poly
		(pts
			(xy 272.054828 -98.50501) (xy 271.981168 -98.305874) (xy 271.949672 -98.274378) (xy 271.662398 -98.561652)
			(xy 271.693894 -98.593148) (xy 271.89303 -98.666808)
		)
		(stroke
			(width 0)
			(type solid)
		)
		(fill yes)
		(layer "In4.Cu")
		(net "M_E_DQ<37>")
	)
	(gr_poly
		(pts
			(xy 272.144236 -104.63403) (xy 272.144236 -104.40543) (xy 271.951196 -104.31653) (xy 271.906746 -104.31653)
			(xy 271.906746 -104.72293) (xy 271.951196 -104.72293)
		)
		(stroke
			(width 0)
			(type solid)
		)
		(fill yes)
		(layer "In4.Cu")
		(net "M_E_DQ<37>")
	)
	(gr_poly
		(pts
			(xy 272.144236 -103.64343) (xy 272.144236 -103.41483) (xy 271.951196 -103.32593) (xy 271.906746 -103.32593)
			(xy 271.906746 -103.73233) (xy 271.951196 -103.73233)
		)
		(stroke
			(width 0)
			(type solid)
		)
		(fill yes)
		(layer "In4.Cu")
		(net "M_E_DQ<37>")
	)
	(gr_poly
		(pts
			(xy 272.158206 -49.708562) (xy 272.158206 -49.479962) (xy 271.965166 -49.391062) (xy 271.920716 -49.391062)
			(xy 271.920716 -49.797462) (xy 271.965166 -49.797462)
		)
		(stroke
			(width 0)
			(type solid)
		)
		(fill yes)
		(layer "In4.Cu")
		(net "M_B_DQ<33>")
	)
	(gr_poly
		(pts
			(xy 272.186146 -52.56403) (xy 272.186146 -52.33543) (xy 271.993106 -52.24653) (xy 271.948656 -52.24653)
			(xy 271.948656 -52.65293) (xy 271.993106 -52.65293)
		)
		(stroke
			(width 0)
			(type solid)
		)
		(fill yes)
		(layer "In4.Cu")
		(net "M_B_DQS_DN<13>")
	)
	(gr_poly
		(pts
			(xy 272.206974 -55.298594) (xy 272.184622 -55.26024) (xy 272.022824 -55.15737) (xy 271.831308 -55.267606)
			(xy 271.839436 -55.459376) (xy 271.861788 -55.498238)
		)
		(stroke
			(width 0)
			(type solid)
		)
		(fill yes)
		(layer "In4.Cu")
		(net "M_B_DQS_DN<4>")
	)
	(gr_poly
		(pts
			(xy 272.21307 -51.371246) (xy 272.181574 -51.33975) (xy 271.982438 -51.26609) (xy 271.82064 -51.427888)
			(xy 271.8943 -51.627024) (xy 271.925796 -51.65852)
		)
		(stroke
			(width 0)
			(type solid)
		)
		(fill yes)
		(layer "In4.Cu")
		(net "M_B_DQS_DP<13>")
	)
	(gr_poly
		(pts
			(xy 272.286476 -57.501028) (xy 272.286476 -57.280048) (xy 272.116296 -57.191148) (xy 272.071846 -57.191148)
			(xy 272.071846 -57.589928) (xy 272.116296 -57.589928)
		)
		(stroke
			(width 0)
			(type solid)
		)
		(fill yes)
		(layer "In4.Cu")
		(net "M_B_DQS_DP<4>")
	)
	(gr_poly
		(pts
			(xy 272.308828 -53.961792) (xy 272.308828 -53.733192) (xy 272.115788 -53.644292) (xy 272.071338 -53.644292)
			(xy 272.071338 -54.050692) (xy 272.115788 -54.050692)
		)
		(stroke
			(width 0)
			(type solid)
		)
		(fill yes)
		(layer "In4.Cu")
		(net "M_B_DQS_DN<13>")
	)
	(gr_poly
		(pts
			(xy 272.442178 -48.374808) (xy 272.442178 -48.146208) (xy 272.249138 -48.057308) (xy 272.204688 -48.057308)
			(xy 272.204688 -48.463708) (xy 272.249138 -48.463708)
		)
		(stroke
			(width 0)
			(type solid)
		)
		(fill yes)
		(layer "In4.Cu")
		(net "M_B_DQ<33>")
	)
	(gr_poly
		(pts
			(xy 272.442178 -47.384208) (xy 272.442178 -47.155608) (xy 272.249138 -47.066708) (xy 272.204688 -47.066708)
			(xy 272.204688 -47.473108) (xy 272.249138 -47.473108)
		)
		(stroke
			(width 0)
			(type solid)
		)
		(fill yes)
		(layer "In4.Cu")
		(net "M_B_DQ<33>")
	)
	(gr_poly
		(pts
			(xy 272.461228 -101.586792) (xy 272.461228 -101.358192) (xy 272.268188 -101.269292) (xy 272.223738 -101.269292)
			(xy 272.223738 -101.675692) (xy 272.268188 -101.675692)
		)
		(stroke
			(width 0)
			(type solid)
		)
		(fill yes)
		(layer "In4.Cu")
		(net "M_E_DQ<33>")
	)
	(gr_poly
		(pts
			(xy 272.461228 -100.596192) (xy 272.461228 -100.367592) (xy 272.268188 -100.278692) (xy 272.223738 -100.278692)
			(xy 272.223738 -100.685092) (xy 272.268188 -100.685092)
		)
		(stroke
			(width 0)
			(type solid)
		)
		(fill yes)
		(layer "In4.Cu")
		(net "M_E_DQ<33>")
	)
	(gr_poly
		(pts
			(xy 272.461228 -97.639124) (xy 272.461228 -97.410524) (xy 272.268188 -97.321624) (xy 272.223738 -97.321624)
			(xy 272.223738 -97.728024) (xy 272.268188 -97.728024)
		)
		(stroke
			(width 0)
			(type solid)
		)
		(fill yes)
		(layer "In4.Cu")
		(net "M_E_DQ<37>")
	)
	(gr_poly
		(pts
			(xy 272.510504 -50.072798) (xy 272.466054 -50.072798) (xy 272.273014 -50.161698) (xy 272.273014 -50.390298)
			(xy 272.466054 -50.479198) (xy 272.510504 -50.479198)
		)
		(stroke
			(width 0)
			(type solid)
		)
		(fill yes)
		(layer "In4.Cu")
		(net "M_B_DQS_DP<13>")
	)
	(gr_poly
		(pts
			(xy 272.510504 -49.082198) (xy 272.466054 -49.082198) (xy 272.273014 -49.171098) (xy 272.273014 -49.399698)
			(xy 272.466054 -49.488598) (xy 272.510504 -49.488598)
		)
		(stroke
			(width 0)
			(type solid)
		)
		(fill yes)
		(layer "In4.Cu")
		(net "M_B_DQS_DP<13>")
	)
	(gr_poly
		(pts
			(xy 272.554446 -51.635152) (xy 272.480786 -51.435762) (xy 272.449544 -51.404266) (xy 272.162016 -51.691794)
			(xy 272.193512 -51.723036) (xy 272.392902 -51.796696)
		)
		(stroke
			(width 0)
			(type solid)
		)
		(fill yes)
		(layer "In4.Cu")
		(net "M_B_DQS_DN<13>")
	)
	(gr_poly
		(pts
			(xy 272.6182 -103.094536) (xy 272.649696 -103.063294) (xy 272.362168 -102.775766) (xy 272.330926 -102.807262)
			(xy 272.257266 -103.006652) (xy 272.41881 -103.168196)
		)
		(stroke
			(width 0)
			(type solid)
		)
		(fill yes)
		(layer "In4.Cu")
		(net "M_E_DQ<32>")
	)
	(gr_poly
		(pts
			(xy 272.739358 -54.229762) (xy 272.694908 -54.229762) (xy 272.501868 -54.318662) (xy 272.501868 -54.547262)
			(xy 272.694908 -54.636162) (xy 272.739358 -54.636162)
		)
		(stroke
			(width 0)
			(type solid)
		)
		(fill yes)
		(layer "In4.Cu")
		(net "M_B_DQS_DN<4>")
	)
	(gr_poly
		(pts
			(xy 272.739358 -53.239162) (xy 272.694908 -53.239162) (xy 272.501868 -53.328062) (xy 272.501868 -53.556662)
			(xy 272.694908 -53.645562) (xy 272.739358 -53.645562)
		)
		(stroke
			(width 0)
			(type solid)
		)
		(fill yes)
		(layer "In4.Cu")
		(net "M_B_DQS_DN<4>")
	)
	(gr_poly
		(pts
			(xy 272.793968 -47.992792) (xy 272.749518 -47.992792) (xy 272.556478 -48.081692) (xy 272.556478 -48.310292)
			(xy 272.749518 -48.399192) (xy 272.793968 -48.399192)
		)
		(stroke
			(width 0)
			(type solid)
		)
		(fill yes)
		(layer "In4.Cu")
		(net "M_B_DQS_DP<13>")
	)
	(gr_poly
		(pts
			(xy 272.815304 -102.897432) (xy 272.888964 -102.698042) (xy 272.72742 -102.536498) (xy 272.52803 -102.610158)
			(xy 272.496534 -102.6414) (xy 272.784062 -102.928928)
		)
		(stroke
			(width 0)
			(type solid)
		)
		(fill yes)
		(layer "In4.Cu")
		(net "M_E_DQ<33>")
	)
	(gr_poly
		(pts
			(xy 272.832576 -55.546244) (xy 272.824448 -55.354474) (xy 272.802096 -55.315866) (xy 272.45691 -55.515256)
			(xy 272.479262 -55.553864) (xy 272.64106 -55.656734)
		)
		(stroke
			(width 0)
			(type solid)
		)
		(fill yes)
		(layer "In4.Cu")
		(net "M_B_DQS_DP<4>")
	)
	(gr_poly
		(pts
			(xy 272.86458 -56.703214) (xy 272.761456 -56.317896) (xy 272.71853 -56.32958) (xy 272.577306 -56.459374)
			(xy 272.634456 -56.672734) (xy 272.821654 -56.714644)
		)
		(stroke
			(width 0)
			(type solid)
		)
		(fill yes)
		(layer "In4.Cu")
		(net "M_B_DQ<39>")
	)
	(gr_poly
		(pts
			(xy 272.89125 -99.292156) (xy 272.8468 -99.292156) (xy 272.67662 -99.381056) (xy 272.67662 -99.602036)
			(xy 272.8468 -99.690936) (xy 272.89125 -99.690936)
		)
		(stroke
			(width 0)
			(type solid)
		)
		(fill yes)
		(layer "In4.Cu")
		(net "M_E_DQS_DP<13>")
	)
	(gr_poly
		(pts
			(xy 272.89125 -98.301556) (xy 272.8468 -98.301556) (xy 272.67662 -98.390456) (xy 272.67662 -98.611436)
			(xy 272.8468 -98.700336) (xy 272.89125 -98.700336)
		)
		(stroke
			(width 0)
			(type solid)
		)
		(fill yes)
		(layer "In4.Cu")
		(net "M_E_DQS_DP<13>")
	)
	(gr_poly
		(pts
			(xy 272.89125 -97.310956) (xy 272.8468 -97.310956) (xy 272.67662 -97.399856) (xy 272.67662 -97.620836)
			(xy 272.8468 -97.709736) (xy 272.89125 -97.709736)
		)
		(stroke
			(width 0)
			(type solid)
		)
		(fill yes)
		(layer "In4.Cu")
		(net "M_E_DQS_DP<13>")
	)
	(gr_poly
		(pts
			(xy 272.938494 -50.923698) (xy 272.938494 -50.695098) (xy 272.745454 -50.606198) (xy 272.701004 -50.606198)
			(xy 272.701004 -51.012598) (xy 272.745454 -51.012598)
		)
		(stroke
			(width 0)
			(type solid)
		)
		(fill yes)
		(layer "In4.Cu")
		(net "M_B_DQS_DN<13>")
	)
	(gr_poly
		(pts
			(xy 272.938494 -49.933098) (xy 272.938494 -49.704498) (xy 272.745454 -49.615598) (xy 272.701004 -49.615598)
			(xy 272.701004 -50.021998) (xy 272.745454 -50.021998)
		)
		(stroke
			(width 0)
			(type solid)
		)
		(fill yes)
		(layer "In4.Cu")
		(net "M_B_DQS_DN<13>")
	)
	(gr_poly
		(pts
			(xy 272.978626 -105.422446) (xy 272.934176 -105.422446) (xy 272.741136 -105.511346) (xy 272.741136 -105.739946)
			(xy 272.934176 -105.828846) (xy 272.978626 -105.828846)
		)
		(stroke
			(width 0)
			(type solid)
		)
		(fill yes)
		(layer "In4.Cu")
		(net "M_E_DQ<32>")
	)
	(gr_poly
		(pts
			(xy 272.978626 -104.431846) (xy 272.934176 -104.431846) (xy 272.741136 -104.520746) (xy 272.741136 -104.749346)
			(xy 272.934176 -104.838246) (xy 272.978626 -104.838246)
		)
		(stroke
			(width 0)
			(type solid)
		)
		(fill yes)
		(layer "In4.Cu")
		(net "M_E_DQ<32>")
	)
	(gr_poly
		(pts
			(xy 272.978626 -103.441246) (xy 272.934176 -103.441246) (xy 272.741136 -103.530146) (xy 272.741136 -103.758746)
			(xy 272.934176 -103.847646) (xy 272.978626 -103.847646)
		)
		(stroke
			(width 0)
			(type solid)
		)
		(fill yes)
		(layer "In4.Cu")
		(net "M_E_DQ<32>")
	)
	(gr_poly
		(pts
			(xy 273.024092 -101.25075) (xy 272.979642 -101.25075) (xy 272.786602 -101.33965) (xy 272.786602 -101.56825)
			(xy 272.979642 -101.65715) (xy 273.024092 -101.65715)
		)
		(stroke
			(width 0)
			(type solid)
		)
		(fill yes)
		(layer "In4.Cu")
		(net "M_E_DQS_DP<13>")
	)
	(gr_poly
		(pts
			(xy 273.024092 -100.26015) (xy 272.979642 -100.26015) (xy 272.786602 -100.34905) (xy 272.786602 -100.57765)
			(xy 272.979642 -100.66655) (xy 273.024092 -100.66655)
		)
		(stroke
			(width 0)
			(type solid)
		)
		(fill yes)
		(layer "In4.Cu")
		(net "M_E_DQS_DP<13>")
	)
	(gr_poly
		(pts
			(xy 273.065748 -55.793894) (xy 273.043396 -55.75554) (xy 272.881344 -55.65267) (xy 272.690082 -55.76316)
			(xy 272.69821 -55.95493) (xy 272.720308 -55.993538)
		)
		(stroke
			(width 0)
			(type solid)
		)
		(fill yes)
		(layer "In4.Cu")
		(net "M_B_DQ<38>")
	)
	(gr_poly
		(pts
			(xy 273.08175 -51.5874) (xy 273.050254 -51.555904) (xy 272.851118 -51.482244) (xy 272.68932 -51.644042)
			(xy 272.76298 -51.843178) (xy 272.794476 -51.874674)
		)
		(stroke
			(width 0)
			(type solid)
		)
		(fill yes)
		(layer "In4.Cu")
		(net "M_B_DQS_DN<4>")
	)
	(gr_poly
		(pts
			(xy 273.167348 -54.648862) (xy 273.167348 -54.420262) (xy 272.974308 -54.331362) (xy 272.929858 -54.331362)
			(xy 272.929858 -54.737762) (xy 272.974308 -54.737762)
		)
		(stroke
			(width 0)
			(type solid)
		)
		(fill yes)
		(layer "In4.Cu")
		(net "M_B_DQS_DP<4>")
	)
	(gr_poly
		(pts
			(xy 273.167348 -53.658262) (xy 273.167348 -53.429662) (xy 272.974308 -53.340762) (xy 272.929858 -53.340762)
			(xy 272.929858 -53.747162) (xy 272.974308 -53.747162)
		)
		(stroke
			(width 0)
			(type solid)
		)
		(fill yes)
		(layer "In4.Cu")
		(net "M_B_DQS_DP<4>")
	)
	(gr_poly
		(pts
			(xy 273.221958 -48.310292) (xy 273.221958 -48.081692) (xy 273.028918 -47.992792) (xy 272.984468 -47.992792)
			(xy 272.984468 -48.399192) (xy 273.028918 -48.399192)
		)
		(stroke
			(width 0)
			(type solid)
		)
		(fill yes)
		(layer "In4.Cu")
		(net "M_B_DQS_DN<13>")
	)
	(gr_poly
		(pts
			(xy 273.277584 -50.639472) (xy 273.233134 -50.639472) (xy 273.040094 -50.728372) (xy 273.040094 -50.956972)
			(xy 273.233134 -51.045872) (xy 273.277584 -51.045872)
		)
		(stroke
			(width 0)
			(type solid)
		)
		(fill yes)
		(layer "In4.Cu")
		(net "M_B_DQS_DN<4>")
	)
	(gr_poly
		(pts
			(xy 273.277584 -49.648872) (xy 273.233134 -49.648872) (xy 273.040094 -49.737772) (xy 273.040094 -49.966372)
			(xy 273.233134 -50.055272) (xy 273.277584 -50.055272)
		)
		(stroke
			(width 0)
			(type solid)
		)
		(fill yes)
		(layer "In4.Cu")
		(net "M_B_DQS_DN<4>")
	)
	(gr_poly
		(pts
			(xy 273.397726 -51.876706) (xy 273.324066 -51.677316) (xy 273.292824 -51.64582) (xy 273.005296 -51.933348)
			(xy 273.036792 -51.96459) (xy 273.236182 -52.03825)
		)
		(stroke
			(width 0)
			(type solid)
		)
		(fill yes)
		(layer "In4.Cu")
		(net "M_B_DQS_DP<4>")
	)
	(gr_poly
		(pts
			(xy 273.406108 -105.739946) (xy 273.406108 -105.511346) (xy 273.213068 -105.422446) (xy 273.168618 -105.422446)
			(xy 273.168618 -105.828846) (xy 273.213068 -105.828846)
		)
		(stroke
			(width 0)
			(type solid)
		)
		(fill yes)
		(layer "In4.Cu")
		(net "M_E_DQ<33>")
	)
	(gr_poly
		(pts
			(xy 273.406108 -104.749346) (xy 273.406108 -104.520746) (xy 273.213068 -104.431846) (xy 273.168618 -104.431846)
			(xy 273.168618 -104.838246) (xy 273.213068 -104.838246)
		)
		(stroke
			(width 0)
			(type solid)
		)
		(fill yes)
		(layer "In4.Cu")
		(net "M_E_DQ<33>")
	)
	(gr_poly
		(pts
			(xy 273.406108 -103.758746) (xy 273.406108 -103.530146) (xy 273.213068 -103.441246) (xy 273.168618 -103.441246)
			(xy 273.168618 -103.847646) (xy 273.213068 -103.847646)
		)
		(stroke
			(width 0)
			(type solid)
		)
		(fill yes)
		(layer "In4.Cu")
		(net "M_E_DQ<33>")
	)
	(gr_poly
		(pts
			(xy 273.429476 -99.106736) (xy 273.429476 -98.885756) (xy 273.259296 -98.796856) (xy 273.214846 -98.796856)
			(xy 273.214846 -99.195636) (xy 273.259296 -99.195636)
		)
		(stroke
			(width 0)
			(type solid)
		)
		(fill yes)
		(layer "In4.Cu")
		(net "M_E_DQS_DN<13>")
	)
	(gr_poly
		(pts
			(xy 273.429476 -98.116136) (xy 273.429476 -97.895156) (xy 273.259296 -97.806256) (xy 273.214846 -97.806256)
			(xy 273.214846 -98.205036) (xy 273.259296 -98.205036)
		)
		(stroke
			(width 0)
			(type solid)
		)
		(fill yes)
		(layer "In4.Cu")
		(net "M_E_DQS_DN<13>")
	)
	(gr_poly
		(pts
			(xy 273.436588 -46.756828) (xy 273.405092 -46.725332) (xy 273.205956 -46.651672) (xy 273.044158 -46.81347)
			(xy 273.117818 -47.012606) (xy 273.149314 -47.044102)
		)
		(stroke
			(width 0)
			(type solid)
		)
		(fill yes)
		(layer "In4.Cu")
		(net "M_B_DQS_DP<13>")
	)
	(gr_poly
		(pts
			(xy 273.452082 -101.56825) (xy 273.452082 -101.33965) (xy 273.259042 -101.25075) (xy 273.214592 -101.25075)
			(xy 273.214592 -101.65715) (xy 273.259042 -101.65715)
		)
		(stroke
			(width 0)
			(type solid)
		)
		(fill yes)
		(layer "In4.Cu")
		(net "M_E_DQS_DN<13>")
	)
	(gr_poly
		(pts
			(xy 273.452082 -100.57765) (xy 273.452082 -100.34905) (xy 273.259042 -100.26015) (xy 273.214592 -100.26015)
			(xy 273.214592 -100.66655) (xy 273.259042 -100.66655)
		)
		(stroke
			(width 0)
			(type solid)
		)
		(fill yes)
		(layer "In4.Cu")
		(net "M_E_DQS_DN<13>")
	)
	(gr_poly
		(pts
			(xy 273.46529 -54.714394) (xy 273.42084 -54.714394) (xy 273.25066 -54.803294) (xy 273.25066 -55.024274)
			(xy 273.42084 -55.113174) (xy 273.46529 -55.113174)
		)
		(stroke
			(width 0)
			(type solid)
		)
		(fill yes)
		(layer "In4.Cu")
		(net "M_B_DQ<38>")
	)
	(gr_poly
		(pts
			(xy 273.46529 -53.723286) (xy 273.42084 -53.723286) (xy 273.25066 -53.812186) (xy 273.25066 -54.033166)
			(xy 273.42084 -54.122066) (xy 273.46529 -54.122066)
		)
		(stroke
			(width 0)
			(type solid)
		)
		(fill yes)
		(layer "In4.Cu")
		(net "M_B_DQ<38>")
	)
	(gr_poly
		(pts
			(xy 273.676364 -47.122334) (xy 273.602704 -46.922944) (xy 273.571462 -46.891448) (xy 273.283934 -47.178976)
			(xy 273.31543 -47.210218) (xy 273.51482 -47.283878)
		)
		(stroke
			(width 0)
			(type solid)
		)
		(fill yes)
		(layer "In4.Cu")
		(net "M_B_DQS_DN<13>")
	)
	(gr_poly
		(pts
			(xy 273.680936 -45.936408) (xy 273.636486 -45.936408) (xy 273.443446 -46.025308) (xy 273.443446 -46.253908)
			(xy 273.636486 -46.342808) (xy 273.680936 -46.342808)
		)
		(stroke
			(width 0)
			(type solid)
		)
		(fill yes)
		(layer "In4.Cu")
		(net "M_B_DQS_DP<13>")
	)
	(gr_poly
		(pts
			(xy 273.691858 -52.617116) (xy 273.647408 -52.617116) (xy 273.454368 -52.706016) (xy 273.454368 -52.934616)
			(xy 273.647408 -53.023516) (xy 273.691858 -53.023516)
		)
		(stroke
			(width 0)
			(type solid)
		)
		(fill yes)
		(layer "In4.Cu")
		(net "M_B_DQ<38>")
	)
	(gr_poly
		(pts
			(xy 273.703796 -56.047386) (xy 273.695668 -55.855616) (xy 273.67357 -55.816754) (xy 273.328384 -56.016398)
			(xy 273.350482 -56.054752) (xy 273.512534 -56.157622)
		)
		(stroke
			(width 0)
			(type solid)
		)
		(fill yes)
		(layer "In4.Cu")
		(net "M_B_DQ<39>")
	)
	(gr_poly
		(pts
			(xy 273.705574 -50.956972) (xy 273.705574 -50.728372) (xy 273.512534 -50.639472) (xy 273.468084 -50.639472)
			(xy 273.468084 -51.045872) (xy 273.512534 -51.045872)
		)
		(stroke
			(width 0)
			(type solid)
		)
		(fill yes)
		(layer "In4.Cu")
		(net "M_B_DQS_DP<4>")
	)
	(gr_poly
		(pts
			(xy 273.705574 -49.966372) (xy 273.705574 -49.737772) (xy 273.512534 -49.648872) (xy 273.468084 -49.648872)
			(xy 273.468084 -50.055272) (xy 273.512534 -50.055272)
		)
		(stroke
			(width 0)
			(type solid)
		)
		(fill yes)
		(layer "In4.Cu")
		(net "M_B_DQS_DP<4>")
	)
	(gr_poly
		(pts
			(xy 273.712686 -102.773988) (xy 273.744182 -102.742746) (xy 273.456654 -102.455218) (xy 273.425412 -102.486714)
			(xy 273.351752 -102.686104) (xy 273.513296 -102.847648)
		)
		(stroke
			(width 0)
			(type solid)
		)
		(fill yes)
		(layer "In4.Cu")
		(net "M_E_DQS_DP<13>")
	)
	(gr_poly
		(pts
			(xy 273.910298 -102.576376) (xy 273.983958 -102.37724) (xy 273.82216 -102.215442) (xy 273.623024 -102.289102)
			(xy 273.591528 -102.320598) (xy 273.878802 -102.607872)
		)
		(stroke
			(width 0)
			(type solid)
		)
		(fill yes)
		(layer "In4.Cu")
		(net "M_E_DQS_DN<13>")
	)
	(gr_poly
		(pts
			(xy 273.925792 -56.288178) (xy 273.90344 -56.249824) (xy 273.741388 -56.146954) (xy 273.550126 -56.257444)
			(xy 273.558254 -56.449214) (xy 273.580352 -56.487822)
		)
		(stroke
			(width 0)
			(type solid)
		)
		(fill yes)
		(layer "In4.Cu")
		(net "M_B_DQ<34>")
	)
	(gr_poly
		(pts
			(xy 273.939254 -47.350934) (xy 273.907758 -47.319438) (xy 273.708622 -47.245778) (xy 273.546824 -47.407576)
			(xy 273.620484 -47.606712) (xy 273.65198 -47.638208)
		)
		(stroke
			(width 0)
			(type solid)
		)
		(fill yes)
		(layer "In4.Cu")
		(net "M_B_DQS_DN<4>")
	)
	(gr_poly
		(pts
			(xy 273.940524 -97.800668) (xy 273.896074 -97.800668) (xy 273.725894 -97.889568) (xy 273.725894 -98.110548)
			(xy 273.896074 -98.199448) (xy 273.940524 -98.199448)
		)
		(stroke
			(width 0)
			(type solid)
		)
		(fill yes)
		(layer "In4.Cu")
		(net "M_E_DQ<38>")
	)
	(gr_poly
		(pts
			(xy 274.003516 -55.51932) (xy 274.003516 -55.29834) (xy 273.833336 -55.20944) (xy 273.788886 -55.20944)
			(xy 273.788886 -55.60822) (xy 273.833336 -55.60822)
		)
		(stroke
			(width 0)
			(type solid)
		)
		(fill yes)
		(layer "In4.Cu")
		(net "M_B_DQ<39>")
	)
	(gr_poly
		(pts
			(xy 274.003516 -54.52872) (xy 274.003516 -54.30774) (xy 273.833336 -54.21884) (xy 273.788886 -54.21884)
			(xy 273.788886 -54.61762) (xy 273.833336 -54.61762)
		)
		(stroke
			(width 0)
			(type solid)
		)
		(fill yes)
		(layer "In4.Cu")
		(net "M_B_DQ<39>")
	)
	(gr_poly
		(pts
			(xy 274.044664 -50.964338) (xy 274.000214 -50.964338) (xy 273.807174 -51.053238) (xy 273.807174 -51.281838)
			(xy 274.000214 -51.370738) (xy 274.044664 -51.370738)
		)
		(stroke
			(width 0)
			(type solid)
		)
		(fill yes)
		(layer "In4.Cu")
		(net "M_B_DQ<38>")
	)
	(gr_poly
		(pts
			(xy 274.044664 -49.973738) (xy 274.000214 -49.973738) (xy 273.807174 -50.062638) (xy 273.807174 -50.291238)
			(xy 274.000214 -50.380138) (xy 274.044664 -50.380138)
		)
		(stroke
			(width 0)
			(type solid)
		)
		(fill yes)
		(layer "In4.Cu")
		(net "M_B_DQ<38>")
	)
	(gr_poly
		(pts
			(xy 274.108926 -46.253908) (xy 274.108926 -46.025308) (xy 273.915886 -45.936408) (xy 273.871436 -45.936408)
			(xy 273.871436 -46.342808) (xy 273.915886 -46.342808)
		)
		(stroke
			(width 0)
			(type solid)
		)
		(fill yes)
		(layer "In4.Cu")
		(net "M_B_DQS_DN<13>")
	)
	(gr_poly
		(pts
			(xy 274.119848 -52.934616) (xy 274.119848 -52.706016) (xy 273.926808 -52.617116) (xy 273.882358 -52.617116)
			(xy 273.882358 -53.023516) (xy 273.926808 -53.023516)
		)
		(stroke
			(width 0)
			(type solid)
		)
		(fill yes)
		(layer "In4.Cu")
		(net "M_B_DQ<39>")
	)
	(gr_poly
		(pts
			(xy 274.176744 -104.883204) (xy 274.132294 -104.883204) (xy 273.939254 -104.972104) (xy 273.939254 -105.200704)
			(xy 274.132294 -105.289604) (xy 274.176744 -105.289604)
		)
		(stroke
			(width 0)
			(type solid)
		)
		(fill yes)
		(layer "In4.Cu")
		(net "M_E_DQS_DP<13>")
	)
	(gr_poly
		(pts
			(xy 274.176744 -103.892604) (xy 274.132294 -103.892604) (xy 273.939254 -103.981504) (xy 273.939254 -104.210104)
			(xy 274.132294 -104.299004) (xy 274.176744 -104.299004)
		)
		(stroke
			(width 0)
			(type solid)
		)
		(fill yes)
		(layer "In4.Cu")
		(net "M_E_DQS_DP<13>")
	)
	(gr_poly
		(pts
			(xy 274.17903 -47.71644) (xy 274.10537 -47.51705) (xy 274.074128 -47.485554) (xy 273.7866 -47.773082)
			(xy 273.818096 -47.804324) (xy 274.017486 -47.877984)
		)
		(stroke
			(width 0)
			(type solid)
		)
		(fill yes)
		(layer "In4.Cu")
		(net "M_B_DQS_DP<4>")
	)
	(gr_poly
		(pts
			(xy 274.287996 -98.617024) (xy 274.287996 -98.396044) (xy 274.117816 -98.307144) (xy 274.073366 -98.307144)
			(xy 274.073366 -98.705924) (xy 274.117816 -98.705924)
		)
		(stroke
			(width 0)
			(type solid)
		)
		(fill yes)
		(layer "In4.Cu")
		(net "M_E_DQ<38>")
	)
	(gr_poly
		(pts
			(xy 274.323556 -55.200804) (xy 274.279106 -55.200804) (xy 274.108926 -55.289704) (xy 274.108926 -55.510684)
			(xy 274.279106 -55.599584) (xy 274.323556 -55.599584)
		)
		(stroke
			(width 0)
			(type solid)
		)
		(fill yes)
		(layer "In4.Cu")
		(net "M_B_DQ<34>")
	)
	(gr_poly
		(pts
			(xy 274.323556 -54.208426) (xy 274.279106 -54.208426) (xy 274.108926 -54.297326) (xy 274.108926 -54.518306)
			(xy 274.279106 -54.607206) (xy 274.323556 -54.607206)
		)
		(stroke
			(width 0)
			(type solid)
		)
		(fill yes)
		(layer "In4.Cu")
		(net "M_B_DQ<34>")
	)
	(gr_poly
		(pts
			(xy 274.431506 -100.9904) (xy 274.463002 -100.959158) (xy 274.175728 -100.67163) (xy 274.144232 -100.703126)
			(xy 274.070572 -100.902516) (xy 274.232116 -101.06406)
		)
		(stroke
			(width 0)
			(type solid)
		)
		(fill yes)
		(layer "In4.Cu")
		(net "M_E_DQS_DN<4>")
	)
	(gr_poly
		(pts
			(xy 274.456398 -53.010816) (xy 274.411948 -53.010816) (xy 274.218908 -53.099716) (xy 274.218908 -53.328316)
			(xy 274.411948 -53.417216) (xy 274.456398 -53.417216)
		)
		(stroke
			(width 0)
			(type solid)
		)
		(fill yes)
		(layer "In4.Cu")
		(net "M_B_DQ<34>")
	)
	(gr_poly
		(pts
			(xy 274.472654 -51.281838) (xy 274.472654 -51.053238) (xy 274.279614 -50.964338) (xy 274.235164 -50.964338)
			(xy 274.235164 -51.370738) (xy 274.279614 -51.370738)
		)
		(stroke
			(width 0)
			(type solid)
		)
		(fill yes)
		(layer "In4.Cu")
		(net "M_B_DQ<39>")
	)
	(gr_poly
		(pts
			(xy 274.472654 -50.291238) (xy 274.472654 -50.062638) (xy 274.279614 -49.973738) (xy 274.235164 -49.973738)
			(xy 274.235164 -50.380138) (xy 274.279614 -50.380138)
		)
		(stroke
			(width 0)
			(type solid)
		)
		(fill yes)
		(layer "In4.Cu")
		(net "M_B_DQ<39>")
	)
	(gr_poly
		(pts
			(xy 274.557744 -56.545226) (xy 274.549616 -56.353456) (xy 274.527518 -56.314848) (xy 274.182332 -56.514492)
			(xy 274.20443 -56.552592) (xy 274.366482 -56.655716)
		)
		(stroke
			(width 0)
			(type solid)
		)
		(fill yes)
		(layer "In4.Cu")
		(net "M_B_DQ<35>")
	)
	(gr_poly
		(pts
			(xy 274.604734 -105.200704) (xy 274.604734 -104.972104) (xy 274.411694 -104.883204) (xy 274.367244 -104.883204)
			(xy 274.367244 -105.289604) (xy 274.411694 -105.289604)
		)
		(stroke
			(width 0)
			(type solid)
		)
		(fill yes)
		(layer "In4.Cu")
		(net "M_E_DQS_DN<13>")
	)
	(gr_poly
		(pts
			(xy 274.604734 -104.210104) (xy 274.604734 -103.981504) (xy 274.411694 -103.892604) (xy 274.367244 -103.892604)
			(xy 274.367244 -104.299004) (xy 274.411694 -104.299004)
		)
		(stroke
			(width 0)
			(type solid)
		)
		(fill yes)
		(layer "In4.Cu")
		(net "M_E_DQS_DN<13>")
	)
	(gr_poly
		(pts
			(xy 274.629118 -100.793042) (xy 274.702778 -100.593652) (xy 274.541234 -100.431854) (xy 274.341844 -100.505514)
			(xy 274.310348 -100.53701) (xy 274.597876 -100.824284)
		)
		(stroke
			(width 0)
			(type solid)
		)
		(fill yes)
		(layer "In4.Cu")
		(net "M_E_DQS_DP<4>")
	)
	(gr_poly
		(pts
			(xy 274.639786 -46.650402) (xy 274.60829 -46.618906) (xy 274.409154 -46.545246) (xy 274.247356 -46.707044)
			(xy 274.321016 -46.90618) (xy 274.352512 -46.937676)
		)
		(stroke
			(width 0)
			(type solid)
		)
		(fill yes)
		(layer "In4.Cu")
		(net "M_B_DQS_DN<4>")
	)
	(gr_poly
		(pts
			(xy 274.79244 -102.353618) (xy 274.74799 -102.353618) (xy 274.55495 -102.442518) (xy 274.55495 -102.671118)
			(xy 274.74799 -102.760018) (xy 274.79244 -102.760018)
		)
		(stroke
			(width 0)
			(type solid)
		)
		(fill yes)
		(layer "In4.Cu")
		(net "M_E_DQS_DN<4>")
	)
	(gr_poly
		(pts
			(xy 274.79244 -101.363018) (xy 274.74799 -101.363018) (xy 274.55495 -101.451918) (xy 274.55495 -101.680518)
			(xy 274.74799 -101.769418) (xy 274.79244 -101.769418)
		)
		(stroke
			(width 0)
			(type solid)
		)
		(fill yes)
		(layer "In4.Cu")
		(net "M_E_DQS_DN<4>")
	)
	(gr_poly
		(pts
			(xy 274.804124 -98.301556) (xy 274.759674 -98.301556) (xy 274.589494 -98.390456) (xy 274.589494 -98.611436)
			(xy 274.759674 -98.700336) (xy 274.804124 -98.700336)
		)
		(stroke
			(width 0)
			(type solid)
		)
		(fill yes)
		(layer "In4.Cu")
		(net "M_E_DQ<34>")
	)
	(gr_poly
		(pts
			(xy 274.811744 -51.142138) (xy 274.767294 -51.142138) (xy 274.574254 -51.231038) (xy 274.574254 -51.459638)
			(xy 274.767294 -51.548538) (xy 274.811744 -51.548538)
		)
		(stroke
			(width 0)
			(type solid)
		)
		(fill yes)
		(layer "In4.Cu")
		(net "M_B_DQ<34>")
	)
	(gr_poly
		(pts
			(xy 274.811744 -49.922938) (xy 274.767294 -49.922938) (xy 274.574254 -50.011838) (xy 274.574254 -50.240438)
			(xy 274.767294 -50.329338) (xy 274.811744 -50.329338)
		)
		(stroke
			(width 0)
			(type solid)
		)
		(fill yes)
		(layer "In4.Cu")
		(net "M_B_DQ<34>")
	)
	(gr_poly
		(pts
			(xy 274.838922 -99.540314) (xy 274.84705 -99.348544) (xy 274.655788 -99.238054) (xy 274.493736 -99.340924)
			(xy 274.471384 -99.379278) (xy 274.816824 -99.578922)
		)
		(stroke
			(width 0)
			(type solid)
		)
		(fill yes)
		(layer "In4.Cu")
		(net "M_E_DQ<39>")
	)
	(gr_poly
		(pts
			(xy 274.862036 -56.024018) (xy 274.862036 -55.803038) (xy 274.691856 -55.714138) (xy 274.647406 -55.714138)
			(xy 274.647406 -56.112918) (xy 274.691856 -56.112918)
		)
		(stroke
			(width 0)
			(type solid)
		)
		(fill yes)
		(layer "In4.Cu")
		(net "M_B_DQ<35>")
	)
	(gr_poly
		(pts
			(xy 274.862036 -55.033418) (xy 274.862036 -54.812438) (xy 274.691856 -54.723538) (xy 274.647406 -54.723538)
			(xy 274.647406 -55.122318) (xy 274.691856 -55.122318)
		)
		(stroke
			(width 0)
			(type solid)
		)
		(fill yes)
		(layer "In4.Cu")
		(net "M_B_DQ<35>")
	)
	(gr_poly
		(pts
			(xy 274.879562 -47.015908) (xy 274.805902 -46.816518) (xy 274.77466 -46.785022) (xy 274.487132 -47.07255)
			(xy 274.518628 -47.103792) (xy 274.718018 -47.177452)
		)
		(stroke
			(width 0)
			(type solid)
		)
		(fill yes)
		(layer "In4.Cu")
		(net "M_B_DQS_DP<4>")
	)
	(gr_poly
		(pts
			(xy 274.88388 -53.328316) (xy 274.88388 -53.099716) (xy 274.69084 -53.010816) (xy 274.64639 -53.010816)
			(xy 274.64639 -53.417216) (xy 274.69084 -53.417216)
		)
		(stroke
			(width 0)
			(type solid)
		)
		(fill yes)
		(layer "In4.Cu")
		(net "M_B_DQ<35>")
	)
	(gr_poly
		(pts
			(xy 274.907502 -47.46752) (xy 274.876006 -47.436278) (xy 274.676616 -47.362618) (xy 274.515072 -47.524162)
			(xy 274.588732 -47.723552) (xy 274.619974 -47.755048)
		)
		(stroke
			(width 0)
			(type solid)
		)
		(fill yes)
		(layer "In4.Cu")
		(net "M_B_DQ<38>")
	)
	(gr_poly
		(pts
			(xy 275.044916 -100.135182) (xy 275.067268 -100.096574) (xy 274.721828 -99.897438) (xy 274.69973 -99.935792)
			(xy 274.691602 -100.127562) (xy 274.882864 -100.238052)
		)
		(stroke
			(width 0)
			(type solid)
		)
		(fill yes)
		(layer "In4.Cu")
		(net "M_E_DQ<38>")
	)
	(gr_poly
		(pts
			(xy 275.053044 -105.372408) (xy 275.008594 -105.372408) (xy 274.815554 -105.461308) (xy 274.815554 -105.689908)
			(xy 275.008594 -105.778808) (xy 275.053044 -105.778808)
		)
		(stroke
			(width 0)
			(type solid)
		)
		(fill yes)
		(layer "In4.Cu")
		(net "M_E_DQS_DN<4>")
	)
	(gr_poly
		(pts
			(xy 275.053044 -104.381808) (xy 275.008594 -104.381808) (xy 274.815554 -104.470708) (xy 274.815554 -104.699308)
			(xy 275.008594 -104.788208) (xy 275.053044 -104.788208)
		)
		(stroke
			(width 0)
			(type solid)
		)
		(fill yes)
		(layer "In4.Cu")
		(net "M_E_DQS_DN<4>")
	)
	(gr_poly
		(pts
			(xy 275.053044 -103.391208) (xy 275.008594 -103.391208) (xy 274.815554 -103.480108) (xy 274.815554 -103.708708)
			(xy 275.008594 -103.797608) (xy 275.053044 -103.797608)
		)
		(stroke
			(width 0)
			(type solid)
		)
		(fill yes)
		(layer "In4.Cu")
		(net "M_E_DQS_DN<4>")
	)
	(gr_poly
		(pts
			(xy 275.146516 -98.116136) (xy 275.146516 -97.895156) (xy 274.976336 -97.806256) (xy 274.931886 -97.806256)
			(xy 274.931886 -98.205036) (xy 274.976336 -98.205036)
		)
		(stroke
			(width 0)
			(type solid)
		)
		(fill yes)
		(layer "In4.Cu")
		(net "M_E_DQ<34>")
	)
	(gr_poly
		(pts
			(xy 275.14677 -47.832772) (xy 275.07311 -47.633382) (xy 275.041868 -47.601886) (xy 274.75434 -47.889414)
			(xy 274.785836 -47.920656) (xy 274.985226 -47.994316)
		)
		(stroke
			(width 0)
			(type solid)
		)
		(fill yes)
		(layer "In4.Cu")
		(net "M_B_DQ<39>")
	)
	(gr_poly
		(pts
			(xy 275.22043 -102.671118) (xy 275.22043 -102.442518) (xy 275.02739 -102.353618) (xy 274.98294 -102.353618)
			(xy 274.98294 -102.760018) (xy 275.02739 -102.760018)
		)
		(stroke
			(width 0)
			(type solid)
		)
		(fill yes)
		(layer "In4.Cu")
		(net "M_E_DQS_DP<4>")
	)
	(gr_poly
		(pts
			(xy 275.22043 -101.680518) (xy 275.22043 -101.451918) (xy 275.02739 -101.363018) (xy 274.98294 -101.363018)
			(xy 274.98294 -101.769418) (xy 275.02739 -101.769418)
		)
		(stroke
			(width 0)
			(type solid)
		)
		(fill yes)
		(layer "In4.Cu")
		(net "M_E_DQS_DP<4>")
	)
	(gr_poly
		(pts
			(xy 275.239734 -51.459638) (xy 275.239734 -51.231038) (xy 275.046694 -51.142138) (xy 275.002244 -51.142138)
			(xy 275.002244 -51.548538) (xy 275.046694 -51.548538)
		)
		(stroke
			(width 0)
			(type solid)
		)
		(fill yes)
		(layer "In4.Cu")
		(net "M_B_DQ<35>")
	)
	(gr_poly
		(pts
			(xy 275.239734 -50.240438) (xy 275.239734 -50.011838) (xy 275.046694 -49.922938) (xy 275.002244 -49.922938)
			(xy 275.002244 -50.329338) (xy 275.046694 -50.329338)
		)
		(stroke
			(width 0)
			(type solid)
		)
		(fill yes)
		(layer "In4.Cu")
		(net "M_B_DQ<35>")
	)
	(gr_poly
		(pts
			(xy 275.481034 -105.689908) (xy 275.481034 -105.461308) (xy 275.287994 -105.372408) (xy 275.243544 -105.372408)
			(xy 275.243544 -105.778808) (xy 275.287994 -105.778808)
		)
		(stroke
			(width 0)
			(type solid)
		)
		(fill yes)
		(layer "In4.Cu")
		(net "M_E_DQS_DP<4>")
	)
	(gr_poly
		(pts
			(xy 275.481034 -104.699308) (xy 275.481034 -104.470708) (xy 275.287994 -104.381808) (xy 275.243544 -104.381808)
			(xy 275.243544 -104.788208) (xy 275.287994 -104.788208)
		)
		(stroke
			(width 0)
			(type solid)
		)
		(fill yes)
		(layer "In4.Cu")
		(net "M_E_DQS_DP<4>")
	)
	(gr_poly
		(pts
			(xy 275.481034 -103.708708) (xy 275.481034 -103.480108) (xy 275.287994 -103.391208) (xy 275.243544 -103.391208)
			(xy 275.243544 -103.797608) (xy 275.287994 -103.797608)
		)
		(stroke
			(width 0)
			(type solid)
		)
		(fill yes)
		(layer "In4.Cu")
		(net "M_E_DQS_DP<4>")
	)
	(gr_poly
		(pts
			(xy 275.55952 -102.376986) (xy 275.51507 -102.376986) (xy 275.32203 -102.465886) (xy 275.32203 -102.694486)
			(xy 275.51507 -102.783386) (xy 275.55952 -102.783386)
		)
		(stroke
			(width 0)
			(type solid)
		)
		(fill yes)
		(layer "In4.Cu")
		(net "M_E_DQ<38>")
	)
	(gr_poly
		(pts
			(xy 275.55952 -101.386386) (xy 275.51507 -101.386386) (xy 275.32203 -101.475286) (xy 275.32203 -101.703886)
			(xy 275.51507 -101.792786) (xy 275.55952 -101.792786)
		)
		(stroke
			(width 0)
			(type solid)
		)
		(fill yes)
		(layer "In4.Cu")
		(net "M_E_DQ<38>")
	)
	(gr_poly
		(pts
			(xy 275.55952 -100.395786) (xy 275.51507 -100.395786) (xy 275.32203 -100.484686) (xy 275.32203 -100.713286)
			(xy 275.51507 -100.802186) (xy 275.55952 -100.802186)
		)
		(stroke
			(width 0)
			(type solid)
		)
		(fill yes)
		(layer "In4.Cu")
		(net "M_E_DQ<38>")
	)
	(gr_poly
		(pts
			(xy 275.570696 -47.888398) (xy 275.5392 -47.856902) (xy 275.33981 -47.783242) (xy 275.178266 -47.94504)
			(xy 275.251926 -48.14443) (xy 275.283422 -48.175672)
		)
		(stroke
			(width 0)
			(type solid)
		)
		(fill yes)
		(layer "In4.Cu")
		(net "M_B_DQ<34>")
	)
	(gr_poly
		(pts
			(xy 275.608034 -46.766988) (xy 275.576538 -46.735746) (xy 275.377148 -46.662086) (xy 275.215604 -46.82363)
			(xy 275.289264 -47.02302) (xy 275.320506 -47.054516)
		)
		(stroke
			(width 0)
			(type solid)
		)
		(fill yes)
		(layer "In4.Cu")
		(net "M_B_DQ<38>")
	)
	(gr_poly
		(pts
			(xy 275.693378 -99.042474) (xy 275.701506 -98.850704) (xy 275.50999 -98.740468) (xy 275.348192 -98.843338)
			(xy 275.325586 -98.881692) (xy 275.67128 -99.081082)
		)
		(stroke
			(width 0)
			(type solid)
		)
		(fill yes)
		(layer "In4.Cu")
		(net "M_E_DQ<35>")
	)
	(gr_poly
		(pts
			(xy 275.697442 -100.035614) (xy 275.70557 -99.843844) (xy 275.514308 -99.733354) (xy 275.352256 -99.836224)
			(xy 275.329904 -99.874578) (xy 275.675344 -100.074222)
		)
		(stroke
			(width 0)
			(type solid)
		)
		(fill yes)
		(layer "In4.Cu")
		(net "M_E_DQ<39>")
	)
	(gr_poly
		(pts
			(xy 275.810218 -48.25365) (xy 275.736558 -48.05426) (xy 275.705062 -48.022764) (xy 275.417788 -48.310038)
			(xy 275.44903 -48.341534) (xy 275.64842 -48.415194)
		)
		(stroke
			(width 0)
			(type solid)
		)
		(fill yes)
		(layer "In4.Cu")
		(net "M_B_DQ<35>")
	)
	(gr_poly
		(pts
			(xy 275.847302 -47.13224) (xy 275.773642 -46.93285) (xy 275.7424 -46.901354) (xy 275.454872 -47.188882)
			(xy 275.486368 -47.220124) (xy 275.685758 -47.293784)
		)
		(stroke
			(width 0)
			(type solid)
		)
		(fill yes)
		(layer "In4.Cu")
		(net "M_B_DQ<39>")
	)
	(gr_poly
		(pts
			(xy 275.904706 -99.640898) (xy 275.927058 -99.60229) (xy 275.581618 -99.403154) (xy 275.55952 -99.441508)
			(xy 275.551392 -99.633278) (xy 275.742654 -99.743768)
		)
		(stroke
			(width 0)
			(type solid)
		)
		(fill yes)
		(layer "In4.Cu")
		(net "M_E_DQ<34>")
	)
	(gr_poly
		(pts
			(xy 275.987002 -102.694486) (xy 275.987002 -102.465886) (xy 275.793962 -102.376986) (xy 275.749512 -102.376986)
			(xy 275.749512 -102.783386) (xy 275.793962 -102.783386)
		)
		(stroke
			(width 0)
			(type solid)
		)
		(fill yes)
		(layer "In4.Cu")
		(net "M_E_DQ<39>")
	)
	(gr_poly
		(pts
			(xy 275.987002 -101.703886) (xy 275.987002 -101.475286) (xy 275.793962 -101.386386) (xy 275.749512 -101.386386)
			(xy 275.749512 -101.792786) (xy 275.793962 -101.792786)
		)
		(stroke
			(width 0)
			(type solid)
		)
		(fill yes)
		(layer "In4.Cu")
		(net "M_E_DQ<39>")
	)
	(gr_poly
		(pts
			(xy 275.987002 -100.713286) (xy 275.987002 -100.484686) (xy 275.793962 -100.395786) (xy 275.749512 -100.395786)
			(xy 275.749512 -100.802186) (xy 275.793962 -100.802186)
		)
		(stroke
			(width 0)
			(type solid)
		)
		(fill yes)
		(layer "In4.Cu")
		(net "M_E_DQ<39>")
	)
	(gr_poly
		(pts
			(xy 276.108922 -103.59009) (xy 276.064472 -103.59009) (xy 275.871432 -103.67899) (xy 275.871432 -103.90759)
			(xy 276.064472 -103.99649) (xy 276.108922 -103.99649)
		)
		(stroke
			(width 0)
			(type solid)
		)
		(fill yes)
		(layer "In4.Cu")
		(net "M_E_DQ<38>")
	)
	(gr_poly
		(pts
			(xy 276.271228 -47.187866) (xy 276.239732 -47.156624) (xy 276.040342 -47.082964) (xy 275.878798 -47.244508)
			(xy 275.952458 -47.443898) (xy 275.9837 -47.475394)
		)
		(stroke
			(width 0)
			(type solid)
		)
		(fill yes)
		(layer "In4.Cu")
		(net "M_B_DQ<34>")
	)
	(gr_poly
		(pts
			(xy 276.326092 -101.779832) (xy 276.281642 -101.779832) (xy 276.088602 -101.868732) (xy 276.088602 -102.097332)
			(xy 276.281642 -102.186232) (xy 276.326092 -102.186232)
		)
		(stroke
			(width 0)
			(type solid)
		)
		(fill yes)
		(layer "In4.Cu")
		(net "M_E_DQ<34>")
	)
	(gr_poly
		(pts
			(xy 276.326092 -100.789232) (xy 276.281642 -100.789232) (xy 276.088602 -100.878132) (xy 276.088602 -101.106732)
			(xy 276.281642 -101.195632) (xy 276.326092 -101.195632)
		)
		(stroke
			(width 0)
			(type solid)
		)
		(fill yes)
		(layer "In4.Cu")
		(net "M_E_DQ<34>")
	)
	(gr_poly
		(pts
			(xy 276.510496 -47.553118) (xy 276.436836 -47.353728) (xy 276.405594 -47.322232) (xy 276.118066 -47.60976)
			(xy 276.149562 -47.641002) (xy 276.348952 -47.714662)
		)
		(stroke
			(width 0)
			(type solid)
		)
		(fill yes)
		(layer "In4.Cu")
		(net "M_B_DQ<35>")
	)
	(gr_poly
		(pts
			(xy 276.536404 -103.90759) (xy 276.536404 -103.67899) (xy 276.343364 -103.59009) (xy 276.298914 -103.59009)
			(xy 276.298914 -103.99649) (xy 276.343364 -103.99649)
		)
		(stroke
			(width 0)
			(type solid)
		)
		(fill yes)
		(layer "In4.Cu")
		(net "M_E_DQ<39>")
	)
	(gr_poly
		(pts
			(xy 276.551898 -99.537774) (xy 276.560026 -99.346004) (xy 276.36851 -99.235768) (xy 276.206712 -99.338638)
			(xy 276.184106 -99.376992) (xy 276.5298 -99.576382)
		)
		(stroke
			(width 0)
			(type solid)
		)
		(fill yes)
		(layer "In4.Cu")
		(net "M_E_DQ<35>")
	)
	(gr_poly
		(pts
			(xy 276.693122 -100.190046) (xy 276.863302 -100.101146) (xy 276.863048 -99.88042) (xy 276.693122 -99.79152)
			(xy 276.648418 -99.791266) (xy 276.648672 -100.1903)
		)
		(stroke
			(width 0)
			(type solid)
		)
		(fill yes)
		(layer "In4.Cu")
		(net "M_E_DQ<35>")
	)
	(gr_poly
		(pts
			(xy 276.753574 -102.097332) (xy 276.753574 -101.868732) (xy 276.560534 -101.779832) (xy 276.516084 -101.779832)
			(xy 276.516084 -102.186232) (xy 276.560534 -102.186232)
		)
		(stroke
			(width 0)
			(type solid)
		)
		(fill yes)
		(layer "In4.Cu")
		(net "M_E_DQ<35>")
	)
	(gr_poly
		(pts
			(xy 276.753574 -101.106732) (xy 276.753574 -100.878132) (xy 276.560534 -100.789232) (xy 276.516084 -100.789232)
			(xy 276.516084 -101.195632) (xy 276.560534 -101.195632)
		)
		(stroke
			(width 0)
			(type solid)
		)
		(fill yes)
		(layer "In4.Cu")
		(net "M_E_DQ<35>")
	)
	(gr_poly
		(pts
			(xy 276.899116 -58.670698) (xy 276.854666 -58.670698) (xy 276.684486 -58.759598) (xy 276.684486 -58.980578)
			(xy 276.854666 -59.069478) (xy 276.899116 -59.069478)
		)
		(stroke
			(width 0)
			(type solid)
		)
		(fill yes)
		(layer "In4.Cu")
		(net "M_C_DQ<44>")
	)
	(gr_poly
		(pts
			(xy 276.899116 -57.692544) (xy 276.854666 -57.692544) (xy 276.684486 -57.781444) (xy 276.684486 -58.002424)
			(xy 276.854666 -58.091324) (xy 276.899116 -58.091324)
		)
		(stroke
			(width 0)
			(type solid)
		)
		(fill yes)
		(layer "In4.Cu")
		(net "M_C_DQ<44>")
	)
	(gr_poly
		(pts
			(xy 276.899116 -56.701944) (xy 276.854666 -56.701944) (xy 276.684486 -56.790844) (xy 276.684486 -57.011824)
			(xy 276.854666 -57.100724) (xy 276.899116 -57.100724)
		)
		(stroke
			(width 0)
			(type solid)
		)
		(fill yes)
		(layer "In4.Cu")
		(net "M_C_DQ<44>")
	)
	(gr_poly
		(pts
			(xy 276.899116 -55.711344) (xy 276.854666 -55.711344) (xy 276.684486 -55.800244) (xy 276.684486 -56.021224)
			(xy 276.854666 -56.110124) (xy 276.899116 -56.110124)
		)
		(stroke
			(width 0)
			(type solid)
		)
		(fill yes)
		(layer "In4.Cu")
		(net "M_C_DQ<44>")
	)
	(gr_poly
		(pts
			(xy 276.899116 -54.720744) (xy 276.854666 -54.720744) (xy 276.684486 -54.809644) (xy 276.684486 -55.030624)
			(xy 276.854666 -55.119524) (xy 276.899116 -55.119524)
		)
		(stroke
			(width 0)
			(type solid)
		)
		(fill yes)
		(layer "In4.Cu")
		(net "M_C_DQ<44>")
	)
	(gr_poly
		(pts
			(xy 276.899116 -53.730144) (xy 276.854666 -53.730144) (xy 276.684486 -53.819044) (xy 276.684486 -54.040024)
			(xy 276.854666 -54.128924) (xy 276.899116 -54.128924)
		)
		(stroke
			(width 0)
			(type solid)
		)
		(fill yes)
		(layer "In4.Cu")
		(net "M_C_DQ<44>")
	)
	(gr_poly
		(pts
			(xy 276.971506 -46.487588) (xy 276.940264 -46.456092) (xy 276.740874 -46.382432) (xy 276.579076 -46.543976)
			(xy 276.652736 -46.743366) (xy 276.684232 -46.774862)
		)
		(stroke
			(width 0)
			(type solid)
		)
		(fill yes)
		(layer "In4.Cu")
		(net "M_B_DQ<34>")
	)
	(gr_poly
		(pts
			(xy 276.979888 -103.270558) (xy 277.011384 -103.239062) (xy 276.72411 -102.951788) (xy 276.692614 -102.983284)
			(xy 276.618954 -103.18242) (xy 276.780752 -103.344218)
		)
		(stroke
			(width 0)
			(type solid)
		)
		(fill yes)
		(layer "In4.Cu")
		(net "M_E_DQ<34>")
	)
	(gr_poly
		(pts
			(xy 277.211028 -46.852586) (xy 277.137368 -46.653196) (xy 277.105872 -46.621954) (xy 276.818598 -46.909228)
			(xy 276.850094 -46.940724) (xy 277.049484 -47.014384)
		)
		(stroke
			(width 0)
			(type solid)
		)
		(fill yes)
		(layer "In4.Cu")
		(net "M_B_DQ<35>")
	)
	(gr_poly
		(pts
			(xy 277.232618 -103.12908) (xy 277.306278 -102.929944) (xy 277.14448 -102.768146) (xy 276.945344 -102.841806)
			(xy 276.913848 -102.873302) (xy 277.201122 -103.160576)
		)
		(stroke
			(width 0)
			(type solid)
		)
		(fill yes)
		(layer "In4.Cu")
		(net "M_E_DQ<35>")
	)
	(gr_poly
		(pts
			(xy 277.437342 -58.491628) (xy 277.437342 -58.270648) (xy 277.267162 -58.181748) (xy 277.222712 -58.181748)
			(xy 277.222712 -58.580528) (xy 277.267162 -58.580528)
		)
		(stroke
			(width 0)
			(type solid)
		)
		(fill yes)
		(layer "In4.Cu")
		(net "M_C_DQ<45>")
	)
	(gr_poly
		(pts
			(xy 277.437342 -57.494678) (xy 277.437342 -57.273698) (xy 277.267162 -57.184798) (xy 277.222712 -57.184798)
			(xy 277.222712 -57.583578) (xy 277.267162 -57.583578)
		)
		(stroke
			(width 0)
			(type solid)
		)
		(fill yes)
		(layer "In4.Cu")
		(net "M_C_DQ<45>")
	)
	(gr_poly
		(pts
			(xy 277.437342 -56.504078) (xy 277.437342 -56.283098) (xy 277.267162 -56.194198) (xy 277.222712 -56.194198)
			(xy 277.222712 -56.592978) (xy 277.267162 -56.592978)
		)
		(stroke
			(width 0)
			(type solid)
		)
		(fill yes)
		(layer "In4.Cu")
		(net "M_C_DQ<45>")
	)
	(gr_poly
		(pts
			(xy 277.437342 -55.513478) (xy 277.437342 -55.292498) (xy 277.267162 -55.203598) (xy 277.222712 -55.203598)
			(xy 277.222712 -55.602378) (xy 277.267162 -55.602378)
		)
		(stroke
			(width 0)
			(type solid)
		)
		(fill yes)
		(layer "In4.Cu")
		(net "M_C_DQ<45>")
	)
	(gr_poly
		(pts
			(xy 277.437342 -54.522878) (xy 277.437342 -54.301898) (xy 277.267162 -54.212998) (xy 277.222712 -54.212998)
			(xy 277.222712 -54.611778) (xy 277.267162 -54.611778)
		)
		(stroke
			(width 0)
			(type solid)
		)
		(fill yes)
		(layer "In4.Cu")
		(net "M_C_DQ<45>")
	)
	(gr_poly
		(pts
			(xy 277.437342 -53.532278) (xy 277.437342 -53.311298) (xy 277.267162 -53.222398) (xy 277.222712 -53.222398)
			(xy 277.222712 -53.621178) (xy 277.267162 -53.621178)
		)
		(stroke
			(width 0)
			(type solid)
		)
		(fill yes)
		(layer "In4.Cu")
		(net "M_C_DQ<45>")
	)
	(gr_poly
		(pts
			(xy 277.481792 -51.331368) (xy 277.450296 -51.299872) (xy 277.250906 -51.226212) (xy 277.089362 -51.38801)
			(xy 277.163022 -51.5874) (xy 277.194518 -51.618642)
		)
		(stroke
			(width 0)
			(type solid)
		)
		(fill yes)
		(layer "In4.Cu")
		(net "M_C_DQ<44>")
	)
	(gr_poly
		(pts
			(xy 277.698454 -52.660042) (xy 277.654004 -52.660042) (xy 277.460964 -52.748942) (xy 277.460964 -52.977542)
			(xy 277.654004 -53.066442) (xy 277.698454 -53.066442)
		)
		(stroke
			(width 0)
			(type solid)
		)
		(fill yes)
		(layer "In4.Cu")
		(net "M_C_DQ<40>")
	)
	(gr_poly
		(pts
			(xy 277.721568 -51.696874) (xy 277.647908 -51.497484) (xy 277.616412 -51.466242) (xy 277.329138 -51.753516)
			(xy 277.360634 -51.785012) (xy 277.560024 -51.858672)
		)
		(stroke
			(width 0)
			(type solid)
		)
		(fill yes)
		(layer "In4.Cu")
		(net "M_C_DQ<45>")
	)
	(gr_poly
		(pts
			(xy 277.757636 -58.181748) (xy 277.713186 -58.181748) (xy 277.543006 -58.270648) (xy 277.543006 -58.491628)
			(xy 277.713186 -58.580528) (xy 277.757636 -58.580528)
		)
		(stroke
			(width 0)
			(type solid)
		)
		(fill yes)
		(layer "In4.Cu")
		(net "M_C_DQ<40>")
	)
	(gr_poly
		(pts
			(xy 277.757636 -57.184798) (xy 277.713186 -57.184798) (xy 277.543006 -57.273698) (xy 277.543006 -57.494678)
			(xy 277.713186 -57.583578) (xy 277.757636 -57.583578)
		)
		(stroke
			(width 0)
			(type solid)
		)
		(fill yes)
		(layer "In4.Cu")
		(net "M_C_DQ<40>")
	)
	(gr_poly
		(pts
			(xy 277.757636 -56.194198) (xy 277.713186 -56.194198) (xy 277.543006 -56.283098) (xy 277.543006 -56.504078)
			(xy 277.713186 -56.592978) (xy 277.757636 -56.592978)
		)
		(stroke
			(width 0)
			(type solid)
		)
		(fill yes)
		(layer "In4.Cu")
		(net "M_C_DQ<40>")
	)
	(gr_poly
		(pts
			(xy 277.757636 -55.203598) (xy 277.713186 -55.203598) (xy 277.543006 -55.292498) (xy 277.543006 -55.513478)
			(xy 277.713186 -55.602378) (xy 277.757636 -55.602378)
		)
		(stroke
			(width 0)
			(type solid)
		)
		(fill yes)
		(layer "In4.Cu")
		(net "M_C_DQ<40>")
	)
	(gr_poly
		(pts
			(xy 277.757636 -54.212998) (xy 277.713186 -54.212998) (xy 277.543006 -54.301898) (xy 277.543006 -54.522878)
			(xy 277.713186 -54.611778) (xy 277.757636 -54.611778)
		)
		(stroke
			(width 0)
			(type solid)
		)
		(fill yes)
		(layer "In4.Cu")
		(net "M_C_DQ<40>")
	)
	(gr_poly
		(pts
			(xy 278.126444 -52.977542) (xy 278.126444 -52.748942) (xy 277.933404 -52.660042) (xy 277.888954 -52.660042)
			(xy 277.888954 -53.066442) (xy 277.933404 -53.066442)
		)
		(stroke
			(width 0)
			(type solid)
		)
		(fill yes)
		(layer "In4.Cu")
		(net "M_C_DQ<41>")
	)
	(gr_poly
		(pts
			(xy 278.182324 -50.630836) (xy 278.150828 -50.599594) (xy 277.951438 -50.525934) (xy 277.789894 -50.687478)
			(xy 277.863554 -50.886868) (xy 277.894796 -50.918364)
		)
		(stroke
			(width 0)
			(type solid)
		)
		(fill yes)
		(layer "In4.Cu")
		(net "M_C_DQ<44>")
	)
	(gr_poly
		(pts
			(xy 278.295862 -58.002424) (xy 278.295862 -57.781444) (xy 278.125682 -57.692544) (xy 278.081232 -57.692544)
			(xy 278.081232 -58.091324) (xy 278.125682 -58.091324)
		)
		(stroke
			(width 0)
			(type solid)
		)
		(fill yes)
		(layer "In4.Cu")
		(net "M_C_DQ<41>")
	)
	(gr_poly
		(pts
			(xy 278.295862 -57.011824) (xy 278.295862 -56.790844) (xy 278.125682 -56.701944) (xy 278.081232 -56.701944)
			(xy 278.081232 -57.100724) (xy 278.125682 -57.100724)
		)
		(stroke
			(width 0)
			(type solid)
		)
		(fill yes)
		(layer "In4.Cu")
		(net "M_C_DQ<41>")
	)
	(gr_poly
		(pts
			(xy 278.295862 -56.021224) (xy 278.295862 -55.800244) (xy 278.125682 -55.711344) (xy 278.081232 -55.711344)
			(xy 278.081232 -56.110124) (xy 278.125682 -56.110124)
		)
		(stroke
			(width 0)
			(type solid)
		)
		(fill yes)
		(layer "In4.Cu")
		(net "M_C_DQ<41>")
	)
	(gr_poly
		(pts
			(xy 278.295862 -55.030624) (xy 278.295862 -54.809644) (xy 278.125682 -54.720744) (xy 278.081232 -54.720744)
			(xy 278.081232 -55.119524) (xy 278.125682 -55.119524)
		)
		(stroke
			(width 0)
			(type solid)
		)
		(fill yes)
		(layer "In4.Cu")
		(net "M_C_DQ<41>")
	)
	(gr_poly
		(pts
			(xy 278.295862 -54.040024) (xy 278.295862 -53.819044) (xy 278.125682 -53.730144) (xy 278.081232 -53.730144)
			(xy 278.081232 -54.128924) (xy 278.125682 -54.128924)
		)
		(stroke
			(width 0)
			(type solid)
		)
		(fill yes)
		(layer "In4.Cu")
		(net "M_C_DQ<41>")
	)
	(gr_poly
		(pts
			(xy 278.4221 -50.996342) (xy 278.34844 -50.797206) (xy 278.316944 -50.76571) (xy 278.02967 -51.052984)
			(xy 278.061166 -51.08448) (xy 278.260302 -51.15814)
		)
		(stroke
			(width 0)
			(type solid)
		)
		(fill yes)
		(layer "In4.Cu")
		(net "M_C_DQ<45>")
	)
	(gr_poly
		(pts
			(xy 278.4983 -49.71923) (xy 278.45385 -49.719484) (xy 278.26081 -49.808384) (xy 278.26081 -50.03673)
			(xy 278.45385 -50.12563) (xy 278.4983 -50.125884)
		)
		(stroke
			(width 0)
			(type solid)
		)
		(fill yes)
		(layer "In4.Cu")
		(net "M_C_DQ<44>")
	)
	(gr_poly
		(pts
			(xy 278.616156 -57.692544) (xy 278.571706 -57.692544) (xy 278.401526 -57.781444) (xy 278.401526 -58.002424)
			(xy 278.571706 -58.091324) (xy 278.616156 -58.091324)
		)
		(stroke
			(width 0)
			(type solid)
		)
		(fill yes)
		(layer "In4.Cu")
		(net "M_C_DQS_DP<14>")
	)
	(gr_poly
		(pts
			(xy 278.616156 -56.701944) (xy 278.571706 -56.701944) (xy 278.401526 -56.790844) (xy 278.401526 -57.011824)
			(xy 278.571706 -57.100724) (xy 278.616156 -57.100724)
		)
		(stroke
			(width 0)
			(type solid)
		)
		(fill yes)
		(layer "In4.Cu")
		(net "M_C_DQS_DP<14>")
	)
	(gr_poly
		(pts
			(xy 278.616156 -55.711344) (xy 278.571706 -55.711344) (xy 278.401526 -55.800244) (xy 278.401526 -56.021224)
			(xy 278.571706 -56.110124) (xy 278.616156 -56.110124)
		)
		(stroke
			(width 0)
			(type solid)
		)
		(fill yes)
		(layer "In4.Cu")
		(net "M_C_DQS_DP<14>")
	)
	(gr_poly
		(pts
			(xy 278.616156 -54.720744) (xy 278.571706 -54.720744) (xy 278.401526 -54.809644) (xy 278.401526 -55.030624)
			(xy 278.571706 -55.119524) (xy 278.616156 -55.119524)
		)
		(stroke
			(width 0)
			(type solid)
		)
		(fill yes)
		(layer "In4.Cu")
		(net "M_C_DQS_DP<14>")
	)
	(gr_poly
		(pts
			(xy 278.616156 -53.723794) (xy 278.571706 -53.723794) (xy 278.401526 -53.812694) (xy 278.401526 -54.033674)
			(xy 278.571706 -54.122574) (xy 278.616156 -54.122574)
		)
		(stroke
			(width 0)
			(type solid)
		)
		(fill yes)
		(layer "In4.Cu")
		(net "M_C_DQS_DP<14>")
	)
	(gr_poly
		(pts
			(xy 278.697944 -51.222656) (xy 278.666448 -51.191414) (xy 278.467058 -51.117754) (xy 278.305514 -51.279298)
			(xy 278.379174 -51.478688) (xy 278.410416 -51.510184)
		)
		(stroke
			(width 0)
			(type solid)
		)
		(fill yes)
		(layer "In4.Cu")
		(net "M_C_DQ<40>")
	)
	(gr_poly
		(pts
			(xy 278.773382 -59.85002) (xy 278.70023 -59.672474) (xy 278.666194 -59.644026) (xy 278.409654 -59.949334)
			(xy 278.44369 -59.978036) (xy 278.631396 -60.019184)
		)
		(stroke
			(width 0)
			(type solid)
		)
		(fill yes)
		(layer "In4.Cu")
		(net "M_C_DQ<41>")
	)
	(gr_poly
		(pts
			(xy 278.900636 -104.733598) (xy 278.856186 -104.733598) (xy 278.686006 -104.822498) (xy 278.686006 -105.043478)
			(xy 278.856186 -105.132378) (xy 278.900636 -105.132378)
		)
		(stroke
			(width 0)
			(type solid)
		)
		(fill yes)
		(layer "In4.Cu")
		(net "M_F_DQ<44>")
	)
	(gr_poly
		(pts
			(xy 278.900636 -102.752398) (xy 278.856186 -102.752398) (xy 278.686006 -102.841298) (xy 278.686006 -103.062278)
			(xy 278.856186 -103.151178) (xy 278.900636 -103.151178)
		)
		(stroke
			(width 0)
			(type solid)
		)
		(fill yes)
		(layer "In4.Cu")
		(net "M_F_DQ<44>")
	)
	(gr_poly
		(pts
			(xy 278.900636 -101.761798) (xy 278.856186 -101.761798) (xy 278.686006 -101.850698) (xy 278.686006 -102.071678)
			(xy 278.856186 -102.160578) (xy 278.900636 -102.160578)
		)
		(stroke
			(width 0)
			(type solid)
		)
		(fill yes)
		(layer "In4.Cu")
		(net "M_F_DQ<44>")
	)
	(gr_poly
		(pts
			(xy 278.900636 -100.771198) (xy 278.856186 -100.771198) (xy 278.686006 -100.860098) (xy 278.686006 -101.081078)
			(xy 278.856186 -101.169978) (xy 278.900636 -101.169978)
		)
		(stroke
			(width 0)
			(type solid)
		)
		(fill yes)
		(layer "In4.Cu")
		(net "M_F_DQ<44>")
	)
	(gr_poly
		(pts
			(xy 278.900636 -99.780598) (xy 278.856186 -99.780598) (xy 278.686006 -99.869498) (xy 278.686006 -100.090478)
			(xy 278.856186 -100.179378) (xy 278.900636 -100.179378)
		)
		(stroke
			(width 0)
			(type solid)
		)
		(fill yes)
		(layer "In4.Cu")
		(net "M_F_DQ<44>")
	)
	(gr_poly
		(pts
			(xy 278.900636 -98.796602) (xy 278.856186 -98.796602) (xy 278.686006 -98.885502) (xy 278.686006 -99.106482)
			(xy 278.856186 -99.195382) (xy 278.900636 -99.195382)
		)
		(stroke
			(width 0)
			(type solid)
		)
		(fill yes)
		(layer "In4.Cu")
		(net "M_F_DQ<44>")
	)
	(gr_poly
		(pts
			(xy 278.900636 -97.806002) (xy 278.856186 -97.806002) (xy 278.686006 -97.894902) (xy 278.686006 -98.115882)
			(xy 278.856186 -98.204782) (xy 278.900636 -98.204782)
		)
		(stroke
			(width 0)
			(type solid)
		)
		(fill yes)
		(layer "In4.Cu")
		(net "M_F_DQ<44>")
	)
	(gr_poly
		(pts
			(xy 278.900636 -96.815402) (xy 278.856186 -96.815402) (xy 278.686006 -96.904302) (xy 278.686006 -97.125282)
			(xy 278.856186 -97.214182) (xy 278.900636 -97.214182)
		)
		(stroke
			(width 0)
			(type solid)
		)
		(fill yes)
		(layer "In4.Cu")
		(net "M_F_DQ<44>")
	)
	(gr_poly
		(pts
			(xy 278.900636 -95.824802) (xy 278.856186 -95.824802) (xy 278.686006 -95.913702) (xy 278.686006 -96.134682)
			(xy 278.856186 -96.223582) (xy 278.900636 -96.223582)
		)
		(stroke
			(width 0)
			(type solid)
		)
		(fill yes)
		(layer "In4.Cu")
		(net "M_F_DQ<44>")
	)
	(gr_poly
		(pts
			(xy 278.900636 -94.834202) (xy 278.856186 -94.834202) (xy 278.686006 -94.923102) (xy 278.686006 -95.144082)
			(xy 278.856186 -95.232982) (xy 278.900636 -95.232982)
		)
		(stroke
			(width 0)
			(type solid)
		)
		(fill yes)
		(layer "In4.Cu")
		(net "M_F_DQ<44>")
	)
	(gr_poly
		(pts
			(xy 278.92629 -50.036984) (xy 278.92629 -49.808384) (xy 278.73325 -49.719484) (xy 278.6888 -49.719484)
			(xy 278.6888 -50.125884) (xy 278.73325 -50.125884)
		)
		(stroke
			(width 0)
			(type solid)
		)
		(fill yes)
		(layer "In4.Cu")
		(net "M_C_DQ<45>")
	)
	(gr_poly
		(pts
			(xy 278.93772 -51.588162) (xy 278.86406 -51.389026) (xy 278.832564 -51.35753) (xy 278.54529 -51.644804)
			(xy 278.576786 -51.6763) (xy 278.775922 -51.74996)
		)
		(stroke
			(width 0)
			(type solid)
		)
		(fill yes)
		(layer "In4.Cu")
		(net "M_C_DQ<41>")
	)
	(gr_poly
		(pts
			(xy 279.154382 -57.494678) (xy 279.154382 -57.273698) (xy 278.984202 -57.184798) (xy 278.939752 -57.184798)
			(xy 278.939752 -57.583578) (xy 278.984202 -57.583578)
		)
		(stroke
			(width 0)
			(type solid)
		)
		(fill yes)
		(layer "In4.Cu")
		(net "M_C_DQS_DN<14>")
	)
	(gr_poly
		(pts
			(xy 279.154382 -56.504078) (xy 279.154382 -56.283098) (xy 278.984202 -56.194198) (xy 278.939752 -56.194198)
			(xy 278.939752 -56.592978) (xy 278.984202 -56.592978)
		)
		(stroke
			(width 0)
			(type solid)
		)
		(fill yes)
		(layer "In4.Cu")
		(net "M_C_DQS_DN<14>")
	)
	(gr_poly
		(pts
			(xy 279.154382 -55.513478) (xy 279.154382 -55.292498) (xy 278.984202 -55.203598) (xy 278.939752 -55.203598)
			(xy 278.939752 -55.602378) (xy 278.984202 -55.602378)
		)
		(stroke
			(width 0)
			(type solid)
		)
		(fill yes)
		(layer "In4.Cu")
		(net "M_C_DQS_DN<14>")
	)
	(gr_poly
		(pts
			(xy 279.154382 -54.522878) (xy 279.154382 -54.301898) (xy 278.984202 -54.212998) (xy 278.939752 -54.212998)
			(xy 278.939752 -54.611778) (xy 278.984202 -54.611778)
		)
		(stroke
			(width 0)
			(type solid)
		)
		(fill yes)
		(layer "In4.Cu")
		(net "M_C_DQS_DN<14>")
	)
	(gr_poly
		(pts
			(xy 279.287224 -106.533696) (xy 279.242774 -106.533696) (xy 279.049734 -106.622596) (xy 279.049734 -106.851196)
			(xy 279.242774 -106.940096) (xy 279.287224 -106.940096)
		)
		(stroke
			(width 0)
			(type solid)
		)
		(fill yes)
		(layer "In4.Cu")
		(net "M_F_DQ<44>")
	)
	(gr_poly
		(pts
			(xy 279.2984 -49.94529) (xy 279.25395 -49.94529) (xy 279.06091 -50.03419) (xy 279.06091 -50.26279)
			(xy 279.25395 -50.35169) (xy 279.2984 -50.35169)
		)
		(stroke
			(width 0)
			(type solid)
		)
		(fill yes)
		(layer "In4.Cu")
		(net "M_C_DQ<40>")
	)
	(gr_poly
		(pts
			(xy 279.39746 -48.397414) (xy 279.365964 -48.366172) (xy 279.166574 -48.292512) (xy 279.00503 -48.454056)
			(xy 279.07869 -48.653446) (xy 279.109932 -48.684942)
		)
		(stroke
			(width 0)
			(type solid)
		)
		(fill yes)
		(layer "In4.Cu")
		(net "M_C_DQ<44>")
	)
	(gr_poly
		(pts
			(xy 279.438862 -105.551224) (xy 279.438862 -105.330244) (xy 279.268682 -105.241344) (xy 279.224232 -105.241344)
			(xy 279.224232 -105.640124) (xy 279.268682 -105.640124)
		)
		(stroke
			(width 0)
			(type solid)
		)
		(fill yes)
		(layer "In4.Cu")
		(net "M_F_DQ<45>")
	)
	(gr_poly
		(pts
			(xy 279.438862 -104.560624) (xy 279.438862 -104.339644) (xy 279.268682 -104.250744) (xy 279.224232 -104.250744)
			(xy 279.224232 -104.649524) (xy 279.268682 -104.649524)
		)
		(stroke
			(width 0)
			(type solid)
		)
		(fill yes)
		(layer "In4.Cu")
		(net "M_F_DQ<45>")
	)
	(gr_poly
		(pts
			(xy 279.438862 -103.570024) (xy 279.438862 -103.349044) (xy 279.268682 -103.260144) (xy 279.224232 -103.260144)
			(xy 279.224232 -103.658924) (xy 279.268682 -103.658924)
		)
		(stroke
			(width 0)
			(type solid)
		)
		(fill yes)
		(layer "In4.Cu")
		(net "M_F_DQ<45>")
	)
	(gr_poly
		(pts
			(xy 279.438862 -102.579424) (xy 279.438862 -102.358444) (xy 279.268682 -102.269544) (xy 279.224232 -102.269544)
			(xy 279.224232 -102.668324) (xy 279.268682 -102.668324)
		)
		(stroke
			(width 0)
			(type solid)
		)
		(fill yes)
		(layer "In4.Cu")
		(net "M_F_DQ<45>")
	)
	(gr_poly
		(pts
			(xy 279.438862 -101.588824) (xy 279.438862 -101.367844) (xy 279.268682 -101.278944) (xy 279.224232 -101.278944)
			(xy 279.224232 -101.677724) (xy 279.268682 -101.677724)
		)
		(stroke
			(width 0)
			(type solid)
		)
		(fill yes)
		(layer "In4.Cu")
		(net "M_F_DQ<45>")
	)
	(gr_poly
		(pts
			(xy 279.438862 -100.598224) (xy 279.438862 -100.377244) (xy 279.268682 -100.288344) (xy 279.224232 -100.288344)
			(xy 279.224232 -100.687124) (xy 279.268682 -100.687124)
		)
		(stroke
			(width 0)
			(type solid)
		)
		(fill yes)
		(layer "In4.Cu")
		(net "M_F_DQ<45>")
	)
	(gr_poly
		(pts
			(xy 279.438862 -99.607624) (xy 279.438862 -99.386644) (xy 279.268682 -99.297744) (xy 279.224232 -99.297744)
			(xy 279.224232 -99.696524) (xy 279.268682 -99.696524)
		)
		(stroke
			(width 0)
			(type solid)
		)
		(fill yes)
		(layer "In4.Cu")
		(net "M_F_DQ<45>")
	)
	(gr_poly
		(pts
			(xy 279.438862 -98.611182) (xy 279.438862 -98.390202) (xy 279.268682 -98.301302) (xy 279.224232 -98.301302)
			(xy 279.224232 -98.700082) (xy 279.268682 -98.700082)
		)
		(stroke
			(width 0)
			(type solid)
		)
		(fill yes)
		(layer "In4.Cu")
		(net "M_F_DQ<45>")
	)
	(gr_poly
		(pts
			(xy 279.438862 -97.620582) (xy 279.438862 -97.399602) (xy 279.268682 -97.310702) (xy 279.224232 -97.310702)
			(xy 279.224232 -97.709482) (xy 279.268682 -97.709482)
		)
		(stroke
			(width 0)
			(type solid)
		)
		(fill yes)
		(layer "In4.Cu")
		(net "M_F_DQ<45>")
	)
	(gr_poly
		(pts
			(xy 279.438862 -96.629982) (xy 279.438862 -96.409002) (xy 279.268682 -96.320102) (xy 279.224232 -96.320102)
			(xy 279.224232 -96.718882) (xy 279.268682 -96.718882)
		)
		(stroke
			(width 0)
			(type solid)
		)
		(fill yes)
		(layer "In4.Cu")
		(net "M_F_DQ<45>")
	)
	(gr_poly
		(pts
			(xy 279.45842 -47.199804) (xy 279.41397 -47.199804) (xy 279.22093 -47.288704) (xy 279.22093 -47.517304)
			(xy 279.41397 -47.606204) (xy 279.45842 -47.606204)
		)
		(stroke
			(width 0)
			(type solid)
		)
		(fill yes)
		(layer "In4.Cu")
		(net "M_C_DQ<44>")
	)
	(gr_poly
		(pts
			(xy 279.474676 -60.156598) (xy 279.430226 -60.156598) (xy 279.260046 -60.245498) (xy 279.260046 -60.466478)
			(xy 279.430226 -60.555378) (xy 279.474676 -60.555378)
		)
		(stroke
			(width 0)
			(type solid)
		)
		(fill yes)
		(layer "In4.Cu")
		(net "M_C_DQS_DP<5>")
	)
	(gr_poly
		(pts
			(xy 279.474676 -59.172348) (xy 279.430226 -59.172348) (xy 279.260046 -59.261248) (xy 279.260046 -59.482228)
			(xy 279.430226 -59.571128) (xy 279.474676 -59.571128)
		)
		(stroke
			(width 0)
			(type solid)
		)
		(fill yes)
		(layer "In4.Cu")
		(net "M_C_DQS_DP<5>")
	)
	(gr_poly
		(pts
			(xy 279.474676 -58.181748) (xy 279.430226 -58.181748) (xy 279.260046 -58.270648) (xy 279.260046 -58.491628)
			(xy 279.430226 -58.580528) (xy 279.474676 -58.580528)
		)
		(stroke
			(width 0)
			(type solid)
		)
		(fill yes)
		(layer "In4.Cu")
		(net "M_C_DQS_DP<5>")
	)
	(gr_poly
		(pts
			(xy 279.474676 -57.184798) (xy 279.430226 -57.184798) (xy 279.260046 -57.273698) (xy 279.260046 -57.494678)
			(xy 279.430226 -57.583578) (xy 279.474676 -57.583578)
		)
		(stroke
			(width 0)
			(type solid)
		)
		(fill yes)
		(layer "In4.Cu")
		(net "M_C_DQS_DP<5>")
	)
	(gr_poly
		(pts
			(xy 279.474676 -56.194198) (xy 279.430226 -56.194198) (xy 279.260046 -56.283098) (xy 279.260046 -56.504078)
			(xy 279.430226 -56.592978) (xy 279.474676 -56.592978)
		)
		(stroke
			(width 0)
			(type solid)
		)
		(fill yes)
		(layer "In4.Cu")
		(net "M_C_DQS_DP<5>")
	)
	(gr_poly
		(pts
			(xy 279.474676 -55.203598) (xy 279.430226 -55.203598) (xy 279.260046 -55.292498) (xy 279.260046 -55.513478)
			(xy 279.430226 -55.602378) (xy 279.474676 -55.602378)
		)
		(stroke
			(width 0)
			(type solid)
		)
		(fill yes)
		(layer "In4.Cu")
		(net "M_C_DQS_DP<5>")
	)
	(gr_poly
		(pts
			(xy 279.474676 -54.212998) (xy 279.430226 -54.212998) (xy 279.260046 -54.301898) (xy 279.260046 -54.522878)
			(xy 279.430226 -54.611778) (xy 279.474676 -54.611778)
		)
		(stroke
			(width 0)
			(type solid)
		)
		(fill yes)
		(layer "In4.Cu")
		(net "M_C_DQS_DP<5>")
	)
	(gr_poly
		(pts
			(xy 279.637236 -48.763174) (xy 279.563576 -48.563784) (xy 279.53208 -48.532288) (xy 279.244806 -48.819562)
			(xy 279.276048 -48.851058) (xy 279.475438 -48.924718)
		)
		(stroke
			(width 0)
			(type solid)
		)
		(fill yes)
		(layer "In4.Cu")
		(net "M_C_DQ<45>")
	)
	(gr_poly
		(pts
			(xy 279.715214 -106.79684) (xy 279.715214 -106.56824) (xy 279.522174 -106.47934) (xy 279.477724 -106.47934)
			(xy 279.477724 -106.88574) (xy 279.522174 -106.88574)
		)
		(stroke
			(width 0)
			(type solid)
		)
		(fill yes)
		(layer "In4.Cu")
		(net "M_F_DQ<45>")
	)
	(gr_poly
		(pts
			(xy 279.72639 -50.26279) (xy 279.72639 -50.03419) (xy 279.53335 -49.94529) (xy 279.4889 -49.94529)
			(xy 279.4889 -50.35169) (xy 279.53335 -50.35169)
		)
		(stroke
			(width 0)
			(type solid)
		)
		(fill yes)
		(layer "In4.Cu")
		(net "M_C_DQ<41>")
	)
	(gr_poly
		(pts
			(xy 279.759156 -105.230422) (xy 279.714706 -105.230676) (xy 279.544526 -105.319576) (xy 279.54478 -105.540302)
			(xy 279.714706 -105.629202) (xy 279.75941 -105.629456)
		)
		(stroke
			(width 0)
			(type solid)
		)
		(fill yes)
		(layer "In4.Cu")
		(net "M_F_DQ<40>")
	)
	(gr_poly
		(pts
			(xy 279.759156 -104.250744) (xy 279.714706 -104.250744) (xy 279.544526 -104.339644) (xy 279.544526 -104.560624)
			(xy 279.714706 -104.649524) (xy 279.759156 -104.649524)
		)
		(stroke
			(width 0)
			(type solid)
		)
		(fill yes)
		(layer "In4.Cu")
		(net "M_F_DQ<40>")
	)
	(gr_poly
		(pts
			(xy 279.759156 -103.260144) (xy 279.714706 -103.260144) (xy 279.544526 -103.349044) (xy 279.544526 -103.570024)
			(xy 279.714706 -103.658924) (xy 279.759156 -103.658924)
		)
		(stroke
			(width 0)
			(type solid)
		)
		(fill yes)
		(layer "In4.Cu")
		(net "M_F_DQ<40>")
	)
	(gr_poly
		(pts
			(xy 279.759156 -102.269544) (xy 279.714706 -102.269544) (xy 279.544526 -102.358444) (xy 279.544526 -102.579424)
			(xy 279.714706 -102.668324) (xy 279.759156 -102.668324)
		)
		(stroke
			(width 0)
			(type solid)
		)
		(fill yes)
		(layer "In4.Cu")
		(net "M_F_DQ<40>")
	)
	(gr_poly
		(pts
			(xy 279.759156 -101.278944) (xy 279.714706 -101.278944) (xy 279.544526 -101.367844) (xy 279.544526 -101.588824)
			(xy 279.714706 -101.677724) (xy 279.759156 -101.677724)
		)
		(stroke
			(width 0)
			(type solid)
		)
		(fill yes)
		(layer "In4.Cu")
		(net "M_F_DQ<40>")
	)
	(gr_poly
		(pts
			(xy 279.759156 -100.288344) (xy 279.714706 -100.288344) (xy 279.544526 -100.377244) (xy 279.544526 -100.598224)
			(xy 279.714706 -100.687124) (xy 279.759156 -100.687124)
		)
		(stroke
			(width 0)
			(type solid)
		)
		(fill yes)
		(layer "In4.Cu")
		(net "M_F_DQ<40>")
	)
	(gr_poly
		(pts
			(xy 279.759156 -99.291902) (xy 279.714706 -99.291902) (xy 279.544526 -99.380802) (xy 279.544526 -99.601782)
			(xy 279.714706 -99.690682) (xy 279.759156 -99.690682)
		)
		(stroke
			(width 0)
			(type solid)
		)
		(fill yes)
		(layer "In4.Cu")
		(net "M_F_DQ<40>")
	)
	(gr_poly
		(pts
			(xy 279.759156 -98.301302) (xy 279.714706 -98.301302) (xy 279.544526 -98.390202) (xy 279.544526 -98.611182)
			(xy 279.714706 -98.700082) (xy 279.759156 -98.700082)
		)
		(stroke
			(width 0)
			(type solid)
		)
		(fill yes)
		(layer "In4.Cu")
		(net "M_F_DQ<40>")
	)
	(gr_poly
		(pts
			(xy 279.759156 -97.310702) (xy 279.714706 -97.310702) (xy 279.544526 -97.399602) (xy 279.544526 -97.620582)
			(xy 279.714706 -97.709482) (xy 279.759156 -97.709482)
		)
		(stroke
			(width 0)
			(type solid)
		)
		(fill yes)
		(layer "In4.Cu")
		(net "M_F_DQ<40>")
	)
	(gr_poly
		(pts
			(xy 279.759156 -96.320102) (xy 279.714706 -96.320102) (xy 279.544526 -96.409002) (xy 279.544526 -96.629982)
			(xy 279.714706 -96.718882) (xy 279.759156 -96.718882)
		)
		(stroke
			(width 0)
			(type solid)
		)
		(fill yes)
		(layer "In4.Cu")
		(net "M_F_DQ<40>")
	)
	(gr_poly
		(pts
			(xy 279.759156 -95.329502) (xy 279.714706 -95.329502) (xy 279.544526 -95.418402) (xy 279.544526 -95.639382)
			(xy 279.714706 -95.728282) (xy 279.759156 -95.728282)
		)
		(stroke
			(width 0)
			(type solid)
		)
		(fill yes)
		(layer "In4.Cu")
		(net "M_F_DQ<40>")
	)
	(gr_poly
		(pts
			(xy 279.821894 -51.360832) (xy 279.790398 -51.32959) (xy 279.591008 -51.25593) (xy 279.429464 -51.417474)
			(xy 279.503124 -51.616864) (xy 279.534366 -51.64836)
		)
		(stroke
			(width 0)
			(type solid)
		)
		(fill yes)
		(layer "In4.Cu")
		(net "M_C_DQS_DP<14>")
	)
	(gr_poly
		(pts
			(xy 279.910286 -48.986694) (xy 279.87879 -48.955198) (xy 279.6794 -48.881538) (xy 279.517856 -49.043336)
			(xy 279.591516 -49.242726) (xy 279.623012 -49.273968)
		)
		(stroke
			(width 0)
			(type solid)
		)
		(fill yes)
		(layer "In4.Cu")
		(net "M_C_DQ<40>")
	)
	(gr_poly
		(pts
			(xy 279.917906 -47.517304) (xy 279.917906 -47.288704) (xy 279.724866 -47.199804) (xy 279.680416 -47.199804)
			(xy 279.680416 -47.606204) (xy 279.724866 -47.606204)
		)
		(stroke
			(width 0)
			(type solid)
		)
		(fill yes)
		(layer "In4.Cu")
		(net "M_C_DQ<45>")
	)
	(gr_poly
		(pts
			(xy 280.012902 -59.977274) (xy 280.012902 -59.756294) (xy 279.842722 -59.667394) (xy 279.798272 -59.667394)
			(xy 279.798272 -60.066174) (xy 279.842722 -60.066174)
		)
		(stroke
			(width 0)
			(type solid)
		)
		(fill yes)
		(layer "In4.Cu")
		(net "M_C_DQS_DN<5>")
	)
	(gr_poly
		(pts
			(xy 280.012902 -58.980578) (xy 280.012902 -58.759598) (xy 279.842722 -58.670698) (xy 279.798272 -58.670698)
			(xy 279.798272 -59.069478) (xy 279.842722 -59.069478)
		)
		(stroke
			(width 0)
			(type solid)
		)
		(fill yes)
		(layer "In4.Cu")
		(net "M_C_DQS_DN<5>")
	)
	(gr_poly
		(pts
			(xy 280.012902 -58.002424) (xy 280.012902 -57.781444) (xy 279.842722 -57.692544) (xy 279.798272 -57.692544)
			(xy 279.798272 -58.091324) (xy 279.842722 -58.091324)
		)
		(stroke
			(width 0)
			(type solid)
		)
		(fill yes)
		(layer "In4.Cu")
		(net "M_C_DQS_DN<5>")
	)
	(gr_poly
		(pts
			(xy 280.012902 -57.011824) (xy 280.012902 -56.790844) (xy 279.842722 -56.701944) (xy 279.798272 -56.701944)
			(xy 279.798272 -57.100724) (xy 279.842722 -57.100724)
		)
		(stroke
			(width 0)
			(type solid)
		)
		(fill yes)
		(layer "In4.Cu")
		(net "M_C_DQS_DN<5>")
	)
	(gr_poly
		(pts
			(xy 280.012902 -56.021224) (xy 280.012902 -55.800244) (xy 279.842722 -55.711344) (xy 279.798272 -55.711344)
			(xy 279.798272 -56.110124) (xy 279.842722 -56.110124)
		)
		(stroke
			(width 0)
			(type solid)
		)
		(fill yes)
		(layer "In4.Cu")
		(net "M_C_DQS_DN<5>")
	)
	(gr_poly
		(pts
			(xy 280.012902 -55.030624) (xy 280.012902 -54.809644) (xy 279.842722 -54.720744) (xy 279.798272 -54.720744)
			(xy 279.798272 -55.119524) (xy 279.842722 -55.119524)
		)
		(stroke
			(width 0)
			(type solid)
		)
		(fill yes)
		(layer "In4.Cu")
		(net "M_C_DQS_DN<5>")
	)
	(gr_poly
		(pts
			(xy 280.0223 -50.54981) (xy 279.97785 -50.54981) (xy 279.78481 -50.63871) (xy 279.78481 -50.86731)
			(xy 279.97785 -50.95621) (xy 280.0223 -50.95621)
		)
		(stroke
			(width 0)
			(type solid)
		)
		(fill yes)
		(layer "In4.Cu")
		(net "M_C_DQS_DP<14>")
	)
	(gr_poly
		(pts
			(xy 280.06167 -51.726338) (xy 279.98801 -51.527202) (xy 279.956514 -51.495706) (xy 279.66924 -51.78298)
			(xy 279.700736 -51.814476) (xy 279.899872 -51.888136)
		)
		(stroke
			(width 0)
			(type solid)
		)
		(fill yes)
		(layer "In4.Cu")
		(net "M_C_DQS_DN<14>")
	)
	(gr_poly
		(pts
			(xy 280.122884 -95.179388) (xy 280.213816 -94.977966) (xy 280.095452 -94.826836) (xy 280.055066 -94.808548)
			(xy 279.890728 -95.171768) (xy 279.931114 -95.190056)
		)
		(stroke
			(width 0)
			(type solid)
		)
		(fill yes)
		(layer "In4.Cu")
		(net "M_F_DQ<40>")
	)
	(gr_poly
		(pts
			(xy 280.150316 -49.352454) (xy 280.076656 -49.153064) (xy 280.04516 -49.121568) (xy 279.757886 -49.408842)
			(xy 279.789128 -49.440338) (xy 279.988518 -49.513998)
		)
		(stroke
			(width 0)
			(type solid)
		)
		(fill yes)
		(layer "In4.Cu")
		(net "M_C_DQ<41>")
	)
	(gr_poly
		(pts
			(xy 280.201116 -106.082084) (xy 280.223722 -106.04373) (xy 279.878028 -105.84434) (xy 279.85593 -105.882948)
			(xy 279.847802 -106.074718) (xy 280.039318 -106.184954)
		)
		(stroke
			(width 0)
			(type solid)
		)
		(fill yes)
		(layer "In4.Cu")
		(net "M_F_DQ<40>")
	)
	(gr_poly
		(pts
			(xy 280.297382 -105.043478) (xy 280.297382 -104.822498) (xy 280.127202 -104.733598) (xy 280.082752 -104.733598)
			(xy 280.082752 -105.132378) (xy 280.127202 -105.132378)
		)
		(stroke
			(width 0)
			(type solid)
		)
		(fill yes)
		(layer "In4.Cu")
		(net "M_F_DQ<41>")
	)
	(gr_poly
		(pts
			(xy 280.297382 -104.052878) (xy 280.297382 -103.831898) (xy 280.127202 -103.742998) (xy 280.082752 -103.742998)
			(xy 280.082752 -104.141778) (xy 280.127202 -104.141778)
		)
		(stroke
			(width 0)
			(type solid)
		)
		(fill yes)
		(layer "In4.Cu")
		(net "M_F_DQ<41>")
	)
	(gr_poly
		(pts
			(xy 280.297382 -103.062278) (xy 280.297382 -102.841298) (xy 280.127202 -102.752398) (xy 280.082752 -102.752398)
			(xy 280.082752 -103.151178) (xy 280.127202 -103.151178)
		)
		(stroke
			(width 0)
			(type solid)
		)
		(fill yes)
		(layer "In4.Cu")
		(net "M_F_DQ<41>")
	)
	(gr_poly
		(pts
			(xy 280.297382 -102.071678) (xy 280.297382 -101.850698) (xy 280.127202 -101.761798) (xy 280.082752 -101.761798)
			(xy 280.082752 -102.160578) (xy 280.127202 -102.160578)
		)
		(stroke
			(width 0)
			(type solid)
		)
		(fill yes)
		(layer "In4.Cu")
		(net "M_F_DQ<41>")
	)
	(gr_poly
		(pts
			(xy 280.297382 -101.081078) (xy 280.297382 -100.860098) (xy 280.127202 -100.771198) (xy 280.082752 -100.771198)
			(xy 280.082752 -101.169978) (xy 280.127202 -101.169978)
		)
		(stroke
			(width 0)
			(type solid)
		)
		(fill yes)
		(layer "In4.Cu")
		(net "M_F_DQ<41>")
	)
	(gr_poly
		(pts
			(xy 280.297382 -100.097082) (xy 280.297382 -99.876102) (xy 280.127202 -99.787202) (xy 280.082752 -99.787202)
			(xy 280.082752 -100.185982) (xy 280.127202 -100.185982)
		)
		(stroke
			(width 0)
			(type solid)
		)
		(fill yes)
		(layer "In4.Cu")
		(net "M_F_DQ<41>")
	)
	(gr_poly
		(pts
			(xy 280.297382 -99.106482) (xy 280.297382 -98.885502) (xy 280.127202 -98.796602) (xy 280.082752 -98.796602)
			(xy 280.082752 -99.195382) (xy 280.127202 -99.195382)
		)
		(stroke
			(width 0)
			(type solid)
		)
		(fill yes)
		(layer "In4.Cu")
		(net "M_F_DQ<41>")
	)
	(gr_poly
		(pts
			(xy 280.297382 -98.115882) (xy 280.297382 -97.894902) (xy 280.127202 -97.806002) (xy 280.082752 -97.806002)
			(xy 280.082752 -98.204782) (xy 280.127202 -98.204782)
		)
		(stroke
			(width 0)
			(type solid)
		)
		(fill yes)
		(layer "In4.Cu")
		(net "M_F_DQ<41>")
	)
	(gr_poly
		(pts
			(xy 280.297382 -97.125282) (xy 280.297382 -96.904302) (xy 280.127202 -96.815402) (xy 280.082752 -96.815402)
			(xy 280.082752 -97.214182) (xy 280.127202 -97.214182)
		)
		(stroke
			(width 0)
			(type solid)
		)
		(fill yes)
		(layer "In4.Cu")
		(net "M_F_DQ<41>")
	)
	(gr_poly
		(pts
			(xy 280.333196 -57.692544) (xy 280.288746 -57.692544) (xy 280.118566 -57.781444) (xy 280.118566 -58.002424)
			(xy 280.288746 -58.091324) (xy 280.333196 -58.091324)
		)
		(stroke
			(width 0)
			(type solid)
		)
		(fill yes)
		(layer "In4.Cu")
		(net "M_C_DQ<46>")
	)
	(gr_poly
		(pts
			(xy 280.333196 -56.701944) (xy 280.288746 -56.701944) (xy 280.118566 -56.790844) (xy 280.118566 -57.011824)
			(xy 280.288746 -57.100724) (xy 280.333196 -57.100724)
		)
		(stroke
			(width 0)
			(type solid)
		)
		(fill yes)
		(layer "In4.Cu")
		(net "M_C_DQ<46>")
	)
	(gr_poly
		(pts
			(xy 280.333196 -55.711344) (xy 280.288746 -55.711344) (xy 280.118566 -55.800244) (xy 280.118566 -56.021224)
			(xy 280.288746 -56.110124) (xy 280.333196 -56.110124)
		)
		(stroke
			(width 0)
			(type solid)
		)
		(fill yes)
		(layer "In4.Cu")
		(net "M_C_DQ<46>")
	)
	(gr_poly
		(pts
			(xy 280.333196 -54.720744) (xy 280.288746 -54.720744) (xy 280.118566 -54.809644) (xy 280.118566 -55.030624)
			(xy 280.288746 -55.119524) (xy 280.333196 -55.119524)
		)
		(stroke
			(width 0)
			(type solid)
		)
		(fill yes)
		(layer "In4.Cu")
		(net "M_C_DQ<46>")
	)
	(gr_poly
		(pts
			(xy 280.333196 -53.730144) (xy 280.288746 -53.730144) (xy 280.118566 -53.819044) (xy 280.118566 -54.040024)
			(xy 280.288746 -54.128924) (xy 280.333196 -54.128924)
		)
		(stroke
			(width 0)
			(type solid)
		)
		(fill yes)
		(layer "In4.Cu")
		(net "M_C_DQ<46>")
	)
	(gr_poly
		(pts
			(xy 280.45029 -50.86731) (xy 280.45029 -50.63871) (xy 280.25725 -50.54981) (xy 280.2128 -50.54981)
			(xy 280.2128 -50.95621) (xy 280.25725 -50.95621)
		)
		(stroke
			(width 0)
			(type solid)
		)
		(fill yes)
		(layer "In4.Cu")
		(net "M_C_DQS_DN<14>")
	)
	(gr_poly
		(pts
			(xy 280.55697 -51.692556) (xy 280.525474 -51.66106) (xy 280.326338 -51.5874) (xy 280.16454 -51.749198)
			(xy 280.2382 -51.948334) (xy 280.269696 -51.97983)
		)
		(stroke
			(width 0)
			(type solid)
		)
		(fill yes)
		(layer "In4.Cu")
		(net "M_C_DQS_DP<5>")
	)
	(gr_poly
		(pts
			(xy 280.610564 -48.286162) (xy 280.579068 -48.254666) (xy 280.379678 -48.181006) (xy 280.218134 -48.342804)
			(xy 280.291794 -48.542194) (xy 280.32329 -48.573436)
		)
		(stroke
			(width 0)
			(type solid)
		)
		(fill yes)
		(layer "In4.Cu")
		(net "M_C_DQ<40>")
	)
	(gr_poly
		(pts
			(xy 280.617676 -104.733598) (xy 280.573226 -104.733598) (xy 280.403046 -104.822498) (xy 280.403046 -105.043478)
			(xy 280.573226 -105.132378) (xy 280.617676 -105.132378)
		)
		(stroke
			(width 0)
			(type solid)
		)
		(fill yes)
		(layer "In4.Cu")
		(net "M_F_DQS_DP<14>")
	)
	(gr_poly
		(pts
			(xy 280.617676 -103.742998) (xy 280.573226 -103.742998) (xy 280.403046 -103.831898) (xy 280.403046 -104.052878)
			(xy 280.573226 -104.141778) (xy 280.617676 -104.141778)
		)
		(stroke
			(width 0)
			(type solid)
		)
		(fill yes)
		(layer "In4.Cu")
		(net "M_F_DQS_DP<14>")
	)
	(gr_poly
		(pts
			(xy 280.617676 -102.752398) (xy 280.573226 -102.752398) (xy 280.403046 -102.841298) (xy 280.403046 -103.062278)
			(xy 280.573226 -103.151178) (xy 280.617676 -103.151178)
		)
		(stroke
			(width 0)
			(type solid)
		)
		(fill yes)
		(layer "In4.Cu")
		(net "M_F_DQS_DP<14>")
	)
	(gr_poly
		(pts
			(xy 280.617676 -101.761798) (xy 280.573226 -101.761798) (xy 280.403046 -101.850698) (xy 280.403046 -102.071678)
			(xy 280.573226 -102.160578) (xy 280.617676 -102.160578)
		)
		(stroke
			(width 0)
			(type solid)
		)
		(fill yes)
		(layer "In4.Cu")
		(net "M_F_DQS_DP<14>")
	)
	(gr_poly
		(pts
			(xy 280.617676 -100.771198) (xy 280.573226 -100.771198) (xy 280.403046 -100.860098) (xy 280.403046 -101.081078)
			(xy 280.573226 -101.169978) (xy 280.617676 -101.169978)
		)
		(stroke
			(width 0)
			(type solid)
		)
		(fill yes)
		(layer "In4.Cu")
		(net "M_F_DQS_DP<14>")
	)
	(gr_poly
		(pts
			(xy 280.617676 -99.780598) (xy 280.573226 -99.780598) (xy 280.403046 -99.869498) (xy 280.403046 -100.090478)
			(xy 280.573226 -100.179378) (xy 280.617676 -100.179378)
		)
		(stroke
			(width 0)
			(type solid)
		)
		(fill yes)
		(layer "In4.Cu")
		(net "M_F_DQS_DP<14>")
	)
	(gr_poly
		(pts
			(xy 280.617676 -98.789998) (xy 280.573226 -98.789998) (xy 280.403046 -98.878898) (xy 280.403046 -99.099878)
			(xy 280.573226 -99.188778) (xy 280.617676 -99.188778)
		)
		(stroke
			(width 0)
			(type solid)
		)
		(fill yes)
		(layer "In4.Cu")
		(net "M_F_DQS_DP<14>")
	)
	(gr_poly
		(pts
			(xy 280.617676 -97.799398) (xy 280.573226 -97.799398) (xy 280.403046 -97.888298) (xy 280.403046 -98.109278)
			(xy 280.573226 -98.198178) (xy 280.617676 -98.198178)
		)
		(stroke
			(width 0)
			(type solid)
		)
		(fill yes)
		(layer "In4.Cu")
		(net "M_F_DQS_DP<14>")
	)
	(gr_poly
		(pts
			(xy 280.617676 -96.808798) (xy 280.573226 -96.808798) (xy 280.403046 -96.897698) (xy 280.403046 -97.118678)
			(xy 280.573226 -97.207578) (xy 280.617676 -97.207578)
		)
		(stroke
			(width 0)
			(type solid)
		)
		(fill yes)
		(layer "In4.Cu")
		(net "M_F_DQS_DP<14>")
	)
	(gr_poly
		(pts
			(xy 280.617676 -95.818198) (xy 280.573226 -95.818198) (xy 280.403046 -95.907098) (xy 280.403046 -96.128078)
			(xy 280.573226 -96.216978) (xy 280.617676 -96.216978)
		)
		(stroke
			(width 0)
			(type solid)
		)
		(fill yes)
		(layer "In4.Cu")
		(net "M_F_DQS_DP<14>")
	)
	(gr_poly
		(pts
			(xy 280.617676 -94.840044) (xy 280.573226 -94.840044) (xy 280.403046 -94.928944) (xy 280.403046 -95.149924)
			(xy 280.573226 -95.238824) (xy 280.617676 -95.238824)
		)
		(stroke
			(width 0)
			(type solid)
		)
		(fill yes)
		(layer "In4.Cu")
		(net "M_F_DQS_DP<14>")
	)
	(gr_poly
		(pts
			(xy 280.617676 -93.849444) (xy 280.573226 -93.849444) (xy 280.403046 -93.938344) (xy 280.403046 -94.159324)
			(xy 280.573226 -94.248224) (xy 280.617676 -94.248224)
		)
		(stroke
			(width 0)
			(type solid)
		)
		(fill yes)
		(layer "In4.Cu")
		(net "M_F_DQS_DP<14>")
	)
	(gr_poly
		(pts
			(xy 280.749248 -49.263046) (xy 280.717752 -49.23155) (xy 280.518616 -49.15789) (xy 280.356818 -49.319688)
			(xy 280.430478 -49.518824) (xy 280.461974 -49.55032)
		)
		(stroke
			(width 0)
			(type solid)
		)
		(fill yes)
		(layer "In4.Cu")
		(net "M_C_DQS_DP<14>")
	)
	(gr_poly
		(pts
			(xy 280.796746 -52.058062) (xy 280.723086 -51.858672) (xy 280.691844 -51.827176) (xy 280.404316 -52.114704)
			(xy 280.435812 -52.145946) (xy 280.635202 -52.219606)
		)
		(stroke
			(width 0)
			(type solid)
		)
		(fill yes)
		(layer "In4.Cu")
		(net "M_C_DQS_DN<5>")
	)
	(gr_poly
		(pts
			(xy 280.850594 -48.651922) (xy 280.776934 -48.452532) (xy 280.745692 -48.421036) (xy 280.458164 -48.708564)
			(xy 280.48966 -48.739806) (xy 280.68905 -48.813466)
		)
		(stroke
			(width 0)
			(type solid)
		)
		(fill yes)
		(layer "In4.Cu")
		(net "M_C_DQ<41>")
	)
	(gr_poly
		(pts
			(xy 280.853642 -105.982262) (xy 280.86177 -105.790492) (xy 280.670508 -105.680002) (xy 280.508456 -105.782872)
			(xy 280.486104 -105.821226) (xy 280.831544 -106.02087)
		)
		(stroke
			(width 0)
			(type solid)
		)
		(fill yes)
		(layer "In4.Cu")
		(net "M_F_DQ<41>")
	)
	(gr_poly
		(pts
			(xy 280.871422 -59.488324) (xy 280.871422 -59.267344) (xy 280.701242 -59.178444) (xy 280.656792 -59.178444)
			(xy 280.656792 -59.577224) (xy 280.701242 -59.577224)
		)
		(stroke
			(width 0)
			(type solid)
		)
		(fill yes)
		(layer "In4.Cu")
		(net "M_C_DQ<47>")
	)
	(gr_poly
		(pts
			(xy 280.871422 -58.491628) (xy 280.871422 -58.270648) (xy 280.701242 -58.181748) (xy 280.656792 -58.181748)
			(xy 280.656792 -58.580528) (xy 280.701242 -58.580528)
		)
		(stroke
			(width 0)
			(type solid)
		)
		(fill yes)
		(layer "In4.Cu")
		(net "M_C_DQ<47>")
	)
	(gr_poly
		(pts
			(xy 280.871422 -57.494678) (xy 280.871422 -57.273698) (xy 280.701242 -57.184798) (xy 280.656792 -57.184798)
			(xy 280.656792 -57.583578) (xy 280.701242 -57.583578)
		)
		(stroke
			(width 0)
			(type solid)
		)
		(fill yes)
		(layer "In4.Cu")
		(net "M_C_DQ<47>")
	)
	(gr_poly
		(pts
			(xy 280.871422 -56.504078) (xy 280.871422 -56.283098) (xy 280.701242 -56.194198) (xy 280.656792 -56.194198)
			(xy 280.656792 -56.592978) (xy 280.701242 -56.592978)
		)
		(stroke
			(width 0)
			(type solid)
		)
		(fill yes)
		(layer "In4.Cu")
		(net "M_C_DQ<47>")
	)
	(gr_poly
		(pts
			(xy 280.871422 -55.513478) (xy 280.871422 -55.292498) (xy 280.701242 -55.203598) (xy 280.656792 -55.203598)
			(xy 280.656792 -55.602378) (xy 280.701242 -55.602378)
		)
		(stroke
			(width 0)
			(type solid)
		)
		(fill yes)
		(layer "In4.Cu")
		(net "M_C_DQ<47>")
	)
	(gr_poly
		(pts
			(xy 280.871422 -54.522878) (xy 280.871422 -54.301898) (xy 280.701242 -54.212998) (xy 280.656792 -54.212998)
			(xy 280.656792 -54.611778) (xy 280.701242 -54.611778)
		)
		(stroke
			(width 0)
			(type solid)
		)
		(fill yes)
		(layer "In4.Cu")
		(net "M_C_DQ<47>")
	)
	(gr_poly
		(pts
			(xy 280.989024 -49.628552) (xy 280.915364 -49.429162) (xy 280.884122 -49.397666) (xy 280.596594 -49.685194)
			(xy 280.62809 -49.716436) (xy 280.82748 -49.790096)
		)
		(stroke
			(width 0)
			(type solid)
		)
		(fill yes)
		(layer "In4.Cu")
		(net "M_C_DQS_DN<14>")
	)
	(gr_poly
		(pts
			(xy 281.05608 -105.584752) (xy 281.078432 -105.546398) (xy 280.732738 -105.347008) (xy 280.710894 -105.385616)
			(xy 280.702766 -105.577386) (xy 280.894028 -105.687622)
		)
		(stroke
			(width 0)
			(type solid)
		)
		(fill yes)
		(layer "In4.Cu")
		(net "M_F_DQS_DP<14>")
	)
	(gr_poly
		(pts
			(xy 281.155902 -106.541824) (xy 281.155902 -106.320844) (xy 280.985722 -106.231944) (xy 280.941272 -106.231944)
			(xy 280.941272 -106.630724) (xy 280.985722 -106.630724)
		)
		(stroke
			(width 0)
			(type solid)
		)
		(fill yes)
		(layer "In4.Cu")
		(net "M_F_DQ<41>")
	)
	(gr_poly
		(pts
			(xy 281.155902 -104.560624) (xy 281.155902 -104.339644) (xy 280.985722 -104.250744) (xy 280.941272 -104.250744)
			(xy 280.941272 -104.649524) (xy 280.985722 -104.649524)
		)
		(stroke
			(width 0)
			(type solid)
		)
		(fill yes)
		(layer "In4.Cu")
		(net "M_F_DQS_DN<14>")
	)
	(gr_poly
		(pts
			(xy 281.155902 -103.570024) (xy 281.155902 -103.349044) (xy 280.985722 -103.260144) (xy 280.941272 -103.260144)
			(xy 280.941272 -103.658924) (xy 280.985722 -103.658924)
		)
		(stroke
			(width 0)
			(type solid)
		)
		(fill yes)
		(layer "In4.Cu")
		(net "M_F_DQS_DN<14>")
	)
	(gr_poly
		(pts
			(xy 281.155902 -102.579424) (xy 281.155902 -102.358444) (xy 280.985722 -102.269544) (xy 280.941272 -102.269544)
			(xy 280.941272 -102.668324) (xy 280.985722 -102.668324)
		)
		(stroke
			(width 0)
			(type solid)
		)
		(fill yes)
		(layer "In4.Cu")
		(net "M_F_DQS_DN<14>")
	)
	(gr_poly
		(pts
			(xy 281.155902 -101.588824) (xy 281.155902 -101.367844) (xy 280.985722 -101.278944) (xy 280.941272 -101.278944)
			(xy 280.941272 -101.677724) (xy 280.985722 -101.677724)
		)
		(stroke
			(width 0)
			(type solid)
		)
		(fill yes)
		(layer "In4.Cu")
		(net "M_F_DQS_DN<14>")
	)
	(gr_poly
		(pts
			(xy 281.155902 -100.598224) (xy 281.155902 -100.377244) (xy 280.985722 -100.288344) (xy 280.941272 -100.288344)
			(xy 280.941272 -100.687124) (xy 280.985722 -100.687124)
		)
		(stroke
			(width 0)
			(type solid)
		)
		(fill yes)
		(layer "In4.Cu")
		(net "M_F_DQS_DN<14>")
	)
	(gr_poly
		(pts
			(xy 281.155902 -99.607624) (xy 281.155902 -99.386644) (xy 280.985722 -99.297744) (xy 280.941272 -99.297744)
			(xy 280.941272 -99.696524) (xy 280.985722 -99.696524)
		)
		(stroke
			(width 0)
			(type solid)
		)
		(fill yes)
		(layer "In4.Cu")
		(net "M_F_DQS_DN<14>")
	)
	(gr_poly
		(pts
			(xy 281.155902 -98.617024) (xy 281.155902 -98.396044) (xy 280.985722 -98.307144) (xy 280.941272 -98.307144)
			(xy 280.941272 -98.705924) (xy 280.985722 -98.705924)
		)
		(stroke
			(width 0)
			(type solid)
		)
		(fill yes)
		(layer "In4.Cu")
		(net "M_F_DQS_DN<14>")
	)
	(gr_poly
		(pts
			(xy 281.155902 -97.626424) (xy 281.155902 -97.405444) (xy 280.985722 -97.316544) (xy 280.941272 -97.316544)
			(xy 280.941272 -97.715324) (xy 280.985722 -97.715324)
		)
		(stroke
			(width 0)
			(type solid)
		)
		(fill yes)
		(layer "In4.Cu")
		(net "M_F_DQS_DN<14>")
	)
	(gr_poly
		(pts
			(xy 281.155902 -96.635824) (xy 281.155902 -96.414844) (xy 280.985722 -96.325944) (xy 280.941272 -96.325944)
			(xy 280.941272 -96.724724) (xy 280.985722 -96.724724)
		)
		(stroke
			(width 0)
			(type solid)
		)
		(fill yes)
		(layer "In4.Cu")
		(net "M_F_DQS_DN<14>")
	)
	(gr_poly
		(pts
			(xy 281.155902 -95.638874) (xy 281.155902 -95.417894) (xy 280.985722 -95.328994) (xy 280.941272 -95.328994)
			(xy 280.941272 -95.727774) (xy 280.985722 -95.727774)
		)
		(stroke
			(width 0)
			(type solid)
		)
		(fill yes)
		(layer "In4.Cu")
		(net "M_F_DQS_DN<14>")
	)
	(gr_poly
		(pts
			(xy 281.155902 -94.642178) (xy 281.155902 -94.421198) (xy 280.985722 -94.332298) (xy 280.941272 -94.332298)
			(xy 280.941272 -94.731078) (xy 280.985722 -94.731078)
		)
		(stroke
			(width 0)
			(type solid)
		)
		(fill yes)
		(layer "In4.Cu")
		(net "M_F_DQS_DN<14>")
	)
	(gr_poly
		(pts
			(xy 281.191716 -58.181748) (xy 281.147266 -58.181748) (xy 280.977086 -58.270648) (xy 280.977086 -58.491628)
			(xy 281.147266 -58.580528) (xy 281.191716 -58.580528)
		)
		(stroke
			(width 0)
			(type solid)
		)
		(fill yes)
		(layer "In4.Cu")
		(net "M_C_DQ<42>")
	)
	(gr_poly
		(pts
			(xy 281.191716 -57.184798) (xy 281.147266 -57.184798) (xy 280.977086 -57.273698) (xy 280.977086 -57.494678)
			(xy 281.147266 -57.583578) (xy 281.191716 -57.583578)
		)
		(stroke
			(width 0)
			(type solid)
		)
		(fill yes)
		(layer "In4.Cu")
		(net "M_C_DQ<42>")
	)
	(gr_poly
		(pts
			(xy 281.191716 -56.194198) (xy 281.147266 -56.194198) (xy 280.977086 -56.283098) (xy 280.977086 -56.504078)
			(xy 281.147266 -56.592978) (xy 281.191716 -56.592978)
		)
		(stroke
			(width 0)
			(type solid)
		)
		(fill yes)
		(layer "In4.Cu")
		(net "M_C_DQ<42>")
	)
	(gr_poly
		(pts
			(xy 281.191716 -55.203598) (xy 281.147266 -55.203598) (xy 280.977086 -55.292498) (xy 280.977086 -55.513478)
			(xy 281.147266 -55.602378) (xy 281.191716 -55.602378)
		)
		(stroke
			(width 0)
			(type solid)
		)
		(fill yes)
		(layer "In4.Cu")
		(net "M_C_DQ<42>")
	)
	(gr_poly
		(pts
			(xy 281.191716 -54.212998) (xy 281.147266 -54.212998) (xy 280.977086 -54.301898) (xy 280.977086 -54.522878)
			(xy 281.147266 -54.611778) (xy 281.191716 -54.611778)
		)
		(stroke
			(width 0)
			(type solid)
		)
		(fill yes)
		(layer "In4.Cu")
		(net "M_C_DQ<42>")
	)
	(gr_poly
		(pts
			(xy 281.449526 -48.562514) (xy 281.41803 -48.531018) (xy 281.218894 -48.457358) (xy 281.057096 -48.619156)
			(xy 281.130756 -48.818292) (xy 281.162252 -48.849788)
		)
		(stroke
			(width 0)
			(type solid)
		)
		(fill yes)
		(layer "In4.Cu")
		(net "M_C_DQS_DP<14>")
	)
	(gr_poly
		(pts
			(xy 281.476196 -104.253284) (xy 281.431746 -104.253284) (xy 281.261566 -104.342184) (xy 281.261566 -104.563164)
			(xy 281.431746 -104.652064) (xy 281.476196 -104.652064)
		)
		(stroke
			(width 0)
			(type solid)
		)
		(fill yes)
		(layer "In4.Cu")
		(net "M_F_DQS_DN<5>")
	)
	(gr_poly
		(pts
			(xy 281.476196 -103.262684) (xy 281.431746 -103.262684) (xy 281.261566 -103.351584) (xy 281.261566 -103.572564)
			(xy 281.431746 -103.661464) (xy 281.476196 -103.661464)
		)
		(stroke
			(width 0)
			(type solid)
		)
		(fill yes)
		(layer "In4.Cu")
		(net "M_F_DQS_DN<5>")
	)
	(gr_poly
		(pts
			(xy 281.476196 -102.272084) (xy 281.431746 -102.272084) (xy 281.261566 -102.360984) (xy 281.261566 -102.581964)
			(xy 281.431746 -102.670864) (xy 281.476196 -102.670864)
		)
		(stroke
			(width 0)
			(type solid)
		)
		(fill yes)
		(layer "In4.Cu")
		(net "M_F_DQS_DN<5>")
	)
	(gr_poly
		(pts
			(xy 281.476196 -101.281484) (xy 281.431746 -101.281484) (xy 281.261566 -101.370384) (xy 281.261566 -101.591364)
			(xy 281.431746 -101.680264) (xy 281.476196 -101.680264)
		)
		(stroke
			(width 0)
			(type solid)
		)
		(fill yes)
		(layer "In4.Cu")
		(net "M_F_DQS_DN<5>")
	)
	(gr_poly
		(pts
			(xy 281.476196 -100.290884) (xy 281.431746 -100.290884) (xy 281.261566 -100.379784) (xy 281.261566 -100.600764)
			(xy 281.431746 -100.689664) (xy 281.476196 -100.689664)
		)
		(stroke
			(width 0)
			(type solid)
		)
		(fill yes)
		(layer "In4.Cu")
		(net "M_F_DQS_DN<5>")
	)
	(gr_poly
		(pts
			(xy 281.476196 -99.291902) (xy 281.431746 -99.291902) (xy 281.261566 -99.380802) (xy 281.261566 -99.601782)
			(xy 281.431746 -99.690682) (xy 281.476196 -99.690682)
		)
		(stroke
			(width 0)
			(type solid)
		)
		(fill yes)
		(layer "In4.Cu")
		(net "M_F_DQS_DN<5>")
	)
	(gr_poly
		(pts
			(xy 281.476196 -98.301302) (xy 281.431746 -98.301302) (xy 281.261566 -98.390202) (xy 281.261566 -98.611182)
			(xy 281.431746 -98.700082) (xy 281.476196 -98.700082)
		)
		(stroke
			(width 0)
			(type solid)
		)
		(fill yes)
		(layer "In4.Cu")
		(net "M_F_DQS_DN<5>")
	)
	(gr_poly
		(pts
			(xy 281.476196 -97.310702) (xy 281.431746 -97.310702) (xy 281.261566 -97.399602) (xy 281.261566 -97.620582)
			(xy 281.431746 -97.709482) (xy 281.476196 -97.709482)
		)
		(stroke
			(width 0)
			(type solid)
		)
		(fill yes)
		(layer "In4.Cu")
		(net "M_F_DQS_DN<5>")
	)
	(gr_poly
		(pts
			(xy 281.66695 -94.338648) (xy 281.6225 -94.338648) (xy 281.45232 -94.427548) (xy 281.45232 -94.648528)
			(xy 281.6225 -94.737428) (xy 281.66695 -94.737428)
		)
		(stroke
			(width 0)
			(type solid)
		)
		(fill yes)
		(layer "In4.Cu")
		(net "M_F_DQ<46>")
	)
	(gr_poly
		(pts
			(xy 281.683206 -51.6255) (xy 281.65171 -51.594004) (xy 281.452574 -51.520344) (xy 281.290776 -51.682142)
			(xy 281.364436 -51.881278) (xy 281.395932 -51.912774)
		)
		(stroke
			(width 0)
			(type solid)
		)
		(fill yes)
		(layer "In4.Cu")
		(net "M_C_DQ<46>")
	)
	(gr_poly
		(pts
			(xy 281.689302 -48.92802) (xy 281.615642 -48.72863) (xy 281.5844 -48.697134) (xy 281.296872 -48.984662)
			(xy 281.328368 -49.015904) (xy 281.527758 -49.089564)
		)
		(stroke
			(width 0)
			(type solid)
		)
		(fill yes)
		(layer "In4.Cu")
		(net "M_C_DQS_DN<14>")
	)
	(gr_poly
		(pts
			(xy 281.702002 -105.480866) (xy 281.71013 -105.289096) (xy 281.518868 -105.178606) (xy 281.356816 -105.28173)
			(xy 281.334464 -105.320084) (xy 281.679904 -105.519474)
		)
		(stroke
			(width 0)
			(type solid)
		)
		(fill yes)
		(layer "In4.Cu")
		(net "M_F_DQS_DN<14>")
	)
	(gr_poly
		(pts
			(xy 281.729942 -58.980578) (xy 281.729942 -58.759598) (xy 281.559762 -58.670698) (xy 281.515312 -58.670698)
			(xy 281.515312 -59.069478) (xy 281.559762 -59.069478)
		)
		(stroke
			(width 0)
			(type solid)
		)
		(fill yes)
		(layer "In4.Cu")
		(net "M_C_DQ<43>")
	)
	(gr_poly
		(pts
			(xy 281.729942 -58.002424) (xy 281.729942 -57.781444) (xy 281.559762 -57.692544) (xy 281.515312 -57.692544)
			(xy 281.515312 -58.091324) (xy 281.559762 -58.091324)
		)
		(stroke
			(width 0)
			(type solid)
		)
		(fill yes)
		(layer "In4.Cu")
		(net "M_C_DQ<43>")
	)
	(gr_poly
		(pts
			(xy 281.729942 -57.011824) (xy 281.729942 -56.790844) (xy 281.559762 -56.701944) (xy 281.515312 -56.701944)
			(xy 281.515312 -57.100724) (xy 281.559762 -57.100724)
		)
		(stroke
			(width 0)
			(type solid)
		)
		(fill yes)
		(layer "In4.Cu")
		(net "M_C_DQ<43>")
	)
	(gr_poly
		(pts
			(xy 281.729942 -56.021224) (xy 281.729942 -55.800244) (xy 281.559762 -55.711344) (xy 281.515312 -55.711344)
			(xy 281.515312 -56.110124) (xy 281.559762 -56.110124)
		)
		(stroke
			(width 0)
			(type solid)
		)
		(fill yes)
		(layer "In4.Cu")
		(net "M_C_DQ<43>")
	)
	(gr_poly
		(pts
			(xy 281.729942 -55.030624) (xy 281.729942 -54.809644) (xy 281.559762 -54.720744) (xy 281.515312 -54.720744)
			(xy 281.515312 -55.119524) (xy 281.559762 -55.119524)
		)
		(stroke
			(width 0)
			(type solid)
		)
		(fill yes)
		(layer "In4.Cu")
		(net "M_C_DQ<43>")
	)
	(gr_poly
		(pts
			(xy 281.729942 -54.033674) (xy 281.729942 -53.812694) (xy 281.559762 -53.723794) (xy 281.515312 -53.723794)
			(xy 281.515312 -54.122574) (xy 281.559762 -54.122574)
		)
		(stroke
			(width 0)
			(type solid)
		)
		(fill yes)
		(layer "In4.Cu")
		(net "M_C_DQ<43>")
	)
	(gr_poly
		(pts
			(xy 281.736546 -49.80178) (xy 281.70505 -49.770284) (xy 281.505914 -49.696624) (xy 281.344116 -49.858422)
			(xy 281.417776 -50.057558) (xy 281.449272 -50.089054)
		)
		(stroke
			(width 0)
			(type solid)
		)
		(fill yes)
		(layer "In4.Cu")
		(net "M_C_DQS_DP<5>")
	)
	(gr_poly
		(pts
			(xy 281.839416 -47.551848) (xy 281.794966 -47.551848) (xy 281.601926 -47.640748) (xy 281.601926 -47.869348)
			(xy 281.794966 -47.958248) (xy 281.839416 -47.958248)
		)
		(stroke
			(width 0)
			(type solid)
		)
		(fill yes)
		(layer "In4.Cu")
		(net "M_C_DQS_DP<14>")
	)
	(gr_poly
		(pts
			(xy 281.930094 -105.098088) (xy 281.952446 -105.059734) (xy 281.607006 -104.860344) (xy 281.584654 -104.898698)
			(xy 281.576526 -105.090722) (xy 281.768042 -105.201212)
		)
		(stroke
			(width 0)
			(type solid)
		)
		(fill yes)
		(layer "In4.Cu")
		(net "M_F_DQS_DN<5>")
	)
	(gr_poly
		(pts
			(xy 281.947112 -52.015136) (xy 281.873452 -51.815746) (xy 281.84221 -51.78425) (xy 281.554682 -52.071778)
			(xy 281.586178 -52.10302) (xy 281.785568 -52.17668)
		)
		(stroke
			(width 0)
			(type solid)
		)
		(fill yes)
		(layer "In4.Cu")
		(net "M_C_DQ<47>")
	)
	(gr_poly
		(pts
			(xy 281.976322 -50.167286) (xy 281.902662 -49.967896) (xy 281.87142 -49.9364) (xy 281.583892 -50.223928)
			(xy 281.615388 -50.25517) (xy 281.814778 -50.32883)
		)
		(stroke
			(width 0)
			(type solid)
		)
		(fill yes)
		(layer "In4.Cu")
		(net "M_C_DQS_DN<5>")
	)
	(gr_poly
		(pts
			(xy 282.007564 -52.449476) (xy 281.976068 -52.418234) (xy 281.776678 -52.344574) (xy 281.615134 -52.506118)
			(xy 281.688794 -52.705508) (xy 281.720036 -52.737004)
		)
		(stroke
			(width 0)
			(type solid)
		)
		(fill yes)
		(layer "In4.Cu")
		(net "M_C_DQ<42>")
	)
	(gr_poly
		(pts
			(xy 282.014422 -104.050084) (xy 282.014422 -103.829104) (xy 281.844242 -103.740204) (xy 281.799792 -103.740204)
			(xy 281.799792 -104.138984) (xy 281.844242 -104.138984)
		)
		(stroke
			(width 0)
			(type solid)
		)
		(fill yes)
		(layer "In4.Cu")
		(net "M_F_DQS_DP<5>")
	)
	(gr_poly
		(pts
			(xy 282.014422 -103.059484) (xy 282.014422 -102.838504) (xy 281.844242 -102.749604) (xy 281.799792 -102.749604)
			(xy 281.799792 -103.148384) (xy 281.844242 -103.148384)
		)
		(stroke
			(width 0)
			(type solid)
		)
		(fill yes)
		(layer "In4.Cu")
		(net "M_F_DQS_DP<5>")
	)
	(gr_poly
		(pts
			(xy 282.014422 -102.068884) (xy 282.014422 -101.847904) (xy 281.844242 -101.759004) (xy 281.799792 -101.759004)
			(xy 281.799792 -102.157784) (xy 281.844242 -102.157784)
		)
		(stroke
			(width 0)
			(type solid)
		)
		(fill yes)
		(layer "In4.Cu")
		(net "M_F_DQS_DP<5>")
	)
	(gr_poly
		(pts
			(xy 282.014422 -101.078284) (xy 282.014422 -100.857304) (xy 281.844242 -100.768404) (xy 281.799792 -100.768404)
			(xy 281.799792 -101.167184) (xy 281.844242 -101.167184)
		)
		(stroke
			(width 0)
			(type solid)
		)
		(fill yes)
		(layer "In4.Cu")
		(net "M_F_DQS_DP<5>")
	)
	(gr_poly
		(pts
			(xy 282.014422 -100.090478) (xy 282.014422 -99.869498) (xy 281.844242 -99.780598) (xy 281.799792 -99.780598)
			(xy 281.799792 -100.179378) (xy 281.844242 -100.179378)
		)
		(stroke
			(width 0)
			(type solid)
		)
		(fill yes)
		(layer "In4.Cu")
		(net "M_F_DQS_DP<5>")
	)
	(gr_poly
		(pts
			(xy 282.014422 -99.106482) (xy 282.014422 -98.885502) (xy 281.844242 -98.796602) (xy 281.799792 -98.796602)
			(xy 281.799792 -99.195382) (xy 281.844242 -99.195382)
		)
		(stroke
			(width 0)
			(type solid)
		)
		(fill yes)
		(layer "In4.Cu")
		(net "M_F_DQS_DP<5>")
	)
	(gr_poly
		(pts
			(xy 282.014422 -98.115882) (xy 282.014422 -97.894902) (xy 281.844242 -97.806002) (xy 281.799792 -97.806002)
			(xy 281.799792 -98.204782) (xy 281.844242 -98.204782)
		)
		(stroke
			(width 0)
			(type solid)
		)
		(fill yes)
		(layer "In4.Cu")
		(net "M_F_DQS_DP<5>")
	)
	(gr_poly
		(pts
			(xy 282.014422 -97.125282) (xy 282.014422 -96.904302) (xy 281.844242 -96.815402) (xy 281.799792 -96.815402)
			(xy 281.799792 -97.214182) (xy 281.844242 -97.214182)
		)
		(stroke
			(width 0)
			(type solid)
		)
		(fill yes)
		(layer "In4.Cu")
		(net "M_F_DQS_DP<5>")
	)
	(gr_poly
		(pts
			(xy 282.050236 -58.670698) (xy 282.005786 -58.670698) (xy 281.835606 -58.759598) (xy 281.835606 -58.980578)
			(xy 282.005786 -59.069478) (xy 282.050236 -59.069478)
		)
		(stroke
			(width 0)
			(type solid)
		)
		(fill yes)
		(layer "In4.Cu")
		(net "M_B_DQ<60>")
	)
	(gr_poly
		(pts
			(xy 282.261056 -52.828952) (xy 282.187396 -52.629562) (xy 282.156154 -52.598066) (xy 281.868626 -52.885594)
			(xy 281.900122 -52.916836) (xy 282.099512 -52.990496)
		)
		(stroke
			(width 0)
			(type solid)
		)
		(fill yes)
		(layer "In4.Cu")
		(net "M_C_DQ<43>")
	)
	(gr_poly
		(pts
			(xy 282.267406 -47.869348) (xy 282.267406 -47.640748) (xy 282.074366 -47.551848) (xy 282.029916 -47.551848)
			(xy 282.029916 -47.958248) (xy 282.074366 -47.958248)
		)
		(stroke
			(width 0)
			(type solid)
		)
		(fill yes)
		(layer "In4.Cu")
		(net "M_C_DQS_DN<14>")
	)
	(gr_poly
		(pts
			(xy 282.334716 -105.721404) (xy 282.290266 -105.721404) (xy 282.120086 -105.810304) (xy 282.120086 -106.031284)
			(xy 282.290266 -106.120184) (xy 282.334716 -106.120184)
		)
		(stroke
			(width 0)
			(type solid)
		)
		(fill yes)
		(layer "In4.Cu")
		(net "M_F_DQS_DN<5>")
	)
	(gr_poly
		(pts
			(xy 282.334716 -103.740204) (xy 282.290266 -103.740204) (xy 282.120086 -103.829104) (xy 282.120086 -104.050084)
			(xy 282.290266 -104.138984) (xy 282.334716 -104.138984)
		)
		(stroke
			(width 0)
			(type solid)
		)
		(fill yes)
		(layer "In4.Cu")
		(net "M_F_DQ<46>")
	)
	(gr_poly
		(pts
			(xy 282.334716 -102.749604) (xy 282.290266 -102.749604) (xy 282.120086 -102.838504) (xy 282.120086 -103.059484)
			(xy 282.290266 -103.148384) (xy 282.334716 -103.148384)
		)
		(stroke
			(width 0)
			(type solid)
		)
		(fill yes)
		(layer "In4.Cu")
		(net "M_F_DQ<46>")
	)
	(gr_poly
		(pts
			(xy 282.334716 -101.76764) (xy 282.290266 -101.76764) (xy 282.120086 -101.85654) (xy 282.120086 -102.07752)
			(xy 282.290266 -102.16642) (xy 282.334716 -102.16642)
		)
		(stroke
			(width 0)
			(type solid)
		)
		(fill yes)
		(layer "In4.Cu")
		(net "M_F_DQ<46>")
	)
	(gr_poly
		(pts
			(xy 282.334716 -100.783136) (xy 282.290266 -100.783136) (xy 282.120086 -100.872036) (xy 282.120086 -101.093016)
			(xy 282.290266 -101.181916) (xy 282.334716 -101.181916)
		)
		(stroke
			(width 0)
			(type solid)
		)
		(fill yes)
		(layer "In4.Cu")
		(net "M_F_DQ<46>")
	)
	(gr_poly
		(pts
			(xy 282.334716 -97.806002) (xy 282.290266 -97.806002) (xy 282.120086 -97.894902) (xy 282.120086 -98.115882)
			(xy 282.290266 -98.204782) (xy 282.334716 -98.204782)
		)
		(stroke
			(width 0)
			(type solid)
		)
		(fill yes)
		(layer "In4.Cu")
		(net "M_F_DQ<46>")
	)
	(gr_poly
		(pts
			(xy 282.334716 -96.815402) (xy 282.290266 -96.815402) (xy 282.120086 -96.904302) (xy 282.120086 -97.125282)
			(xy 282.290266 -97.214182) (xy 282.334716 -97.214182)
		)
		(stroke
			(width 0)
			(type solid)
		)
		(fill yes)
		(layer "In4.Cu")
		(net "M_F_DQ<46>")
	)
	(gr_poly
		(pts
			(xy 282.33497 -99.786948) (xy 282.29052 -99.786948) (xy 282.12034 -99.875848) (xy 282.12034 -100.096828)
			(xy 282.29052 -100.185728) (xy 282.33497 -100.185728)
		)
		(stroke
			(width 0)
			(type solid)
		)
		(fill yes)
		(layer "In4.Cu")
		(net "M_F_DQ<46>")
	)
	(gr_poly
		(pts
			(xy 282.33497 -98.796348) (xy 282.29052 -98.796348) (xy 282.12034 -98.885248) (xy 282.12034 -99.106228)
			(xy 282.29052 -99.195128) (xy 282.33497 -99.195128)
		)
		(stroke
			(width 0)
			(type solid)
		)
		(fill yes)
		(layer "In4.Cu")
		(net "M_F_DQ<46>")
	)
	(gr_poly
		(pts
			(xy 282.383738 -50.924968) (xy 282.352242 -50.893472) (xy 282.153106 -50.819812) (xy 281.991308 -50.98161)
			(xy 282.064968 -51.180746) (xy 282.096464 -51.212242)
		)
		(stroke
			(width 0)
			(type solid)
		)
		(fill yes)
		(layer "In4.Cu")
		(net "M_C_DQ<46>")
	)
	(gr_poly
		(pts
			(xy 282.437078 -49.101248) (xy 282.405582 -49.069752) (xy 282.206446 -48.996092) (xy 282.044648 -49.15789)
			(xy 282.118308 -49.357026) (xy 282.149804 -49.388522)
		)
		(stroke
			(width 0)
			(type solid)
		)
		(fill yes)
		(layer "In4.Cu")
		(net "M_C_DQS_DP<5>")
	)
	(gr_poly
		(pts
			(xy 282.565602 -104.988106) (xy 282.573476 -104.796336) (xy 282.382214 -104.685846) (xy 282.220162 -104.788716)
			(xy 282.19781 -104.827324) (xy 282.54325 -105.026714)
		)
		(stroke
			(width 0)
			(type solid)
		)
		(fill yes)
		(layer "In4.Cu")
		(net "M_F_DQS_DP<5>")
	)
	(gr_poly
		(pts
			(xy 282.588208 -58.502804) (xy 282.588208 -58.281824) (xy 282.418028 -58.192924) (xy 282.373578 -58.192924)
			(xy 282.373578 -58.591704) (xy 282.418028 -58.591704)
		)
		(stroke
			(width 0)
			(type solid)
		)
		(fill yes)
		(layer "In4.Cu")
		(net "M_B_DQ<61>")
	)
	(gr_poly
		(pts
			(xy 282.624022 -95.373698) (xy 282.487878 -94.998794) (xy 282.445968 -95.014034) (xy 282.316428 -95.155766)
			(xy 282.39212 -95.363538) (xy 282.582366 -95.388938)
		)
		(stroke
			(width 0)
			(type solid)
		)
		(fill yes)
		(layer "In4.Cu")
		(net "M_F_DQ<42>")
	)
	(gr_poly
		(pts
			(xy 282.640024 -106.745024) (xy 282.595574 -106.745024) (xy 282.402534 -106.833924) (xy 282.402534 -107.062524)
			(xy 282.595574 -107.151424) (xy 282.640024 -107.151424)
		)
		(stroke
			(width 0)
			(type solid)
		)
		(fill yes)
		(layer "In4.Cu")
		(net "M_F_DQS_DN<5>")
	)
	(gr_poly
		(pts
			(xy 282.647644 -51.314604) (xy 282.573984 -51.115214) (xy 282.542742 -51.083718) (xy 282.255214 -51.371246)
			(xy 282.28671 -51.402488) (xy 282.4861 -51.476148)
		)
		(stroke
			(width 0)
			(type solid)
		)
		(fill yes)
		(layer "In4.Cu")
		(net "M_C_DQ<47>")
	)
	(gr_poly
		(pts
			(xy 282.676854 -49.466754) (xy 282.603194 -49.267364) (xy 282.571698 -49.236122) (xy 282.284424 -49.523396)
			(xy 282.31592 -49.554892) (xy 282.51531 -49.628552)
		)
		(stroke
			(width 0)
			(type solid)
		)
		(fill yes)
		(layer "In4.Cu")
		(net "M_C_DQS_DN<5>")
	)
	(gr_poly
		(pts
			(xy 282.708096 -51.749198) (xy 282.6766 -51.717956) (xy 282.47721 -51.644296) (xy 282.315666 -51.80584)
			(xy 282.389326 -52.00523) (xy 282.420568 -52.036726)
		)
		(stroke
			(width 0)
			(type solid)
		)
		(fill yes)
		(layer "In4.Cu")
		(net "M_C_DQ<42>")
	)
	(gr_poly
		(pts
			(xy 282.772866 -104.593898) (xy 282.795472 -104.555544) (xy 282.449778 -104.356154) (xy 282.42768 -104.394762)
			(xy 282.419552 -104.586532) (xy 282.611068 -104.696768)
		)
		(stroke
			(width 0)
			(type solid)
		)
		(fill yes)
		(layer "In4.Cu")
		(net "M_F_DQ<46>")
	)
	(gr_poly
		(pts
			(xy 282.820618 -47.86376) (xy 282.776168 -47.86376) (xy 282.583128 -47.95266) (xy 282.583128 -48.18126)
			(xy 282.776168 -48.27016) (xy 282.820618 -48.27016)
		)
		(stroke
			(width 0)
			(type solid)
		)
		(fill yes)
		(layer "In4.Cu")
		(net "M_C_DQS_DP<5>")
	)
	(gr_poly
		(pts
			(xy 282.872688 -105.553764) (xy 282.872688 -105.332784) (xy 282.702508 -105.243884) (xy 282.658058 -105.243884)
			(xy 282.658058 -105.642664) (xy 282.702762 -105.642664)
		)
		(stroke
			(width 0)
			(type solid)
		)
		(fill yes)
		(layer "In4.Cu")
		(net "M_F_DQS_DP<5>")
	)
	(gr_poly
		(pts
			(xy 282.872942 -103.572564) (xy 282.872942 -103.351584) (xy 282.702762 -103.262684) (xy 282.658312 -103.262684)
			(xy 282.658312 -103.661464) (xy 282.702762 -103.661464)
		)
		(stroke
			(width 0)
			(type solid)
		)
		(fill yes)
		(layer "In4.Cu")
		(net "M_F_DQ<47>")
	)
	(gr_poly
		(pts
			(xy 282.872942 -102.57917) (xy 282.872942 -102.35819) (xy 282.702762 -102.26929) (xy 282.658312 -102.26929)
			(xy 282.658312 -102.66807) (xy 282.702762 -102.66807)
		)
		(stroke
			(width 0)
			(type solid)
		)
		(fill yes)
		(layer "In4.Cu")
		(net "M_F_DQ<47>")
	)
	(gr_poly
		(pts
			(xy 282.872942 -101.58222) (xy 282.872942 -101.36124) (xy 282.702762 -101.27234) (xy 282.658312 -101.27234)
			(xy 282.658312 -101.67112) (xy 282.702762 -101.67112)
		)
		(stroke
			(width 0)
			(type solid)
		)
		(fill yes)
		(layer "In4.Cu")
		(net "M_F_DQ<47>")
	)
	(gr_poly
		(pts
			(xy 282.872942 -100.58527) (xy 282.872942 -100.36429) (xy 282.702762 -100.27539) (xy 282.658312 -100.27539)
			(xy 282.658312 -100.67417) (xy 282.702762 -100.67417)
		)
		(stroke
			(width 0)
			(type solid)
		)
		(fill yes)
		(layer "In4.Cu")
		(net "M_F_DQ<47>")
	)
	(gr_poly
		(pts
			(xy 282.872942 -99.607624) (xy 282.872942 -99.386644) (xy 282.702762 -99.297744) (xy 282.658312 -99.297744)
			(xy 282.658312 -99.696524) (xy 282.702762 -99.696524)
		)
		(stroke
			(width 0)
			(type solid)
		)
		(fill yes)
		(layer "In4.Cu")
		(net "M_F_DQ<47>")
	)
	(gr_poly
		(pts
			(xy 282.872942 -98.617024) (xy 282.872942 -98.396044) (xy 282.702762 -98.307144) (xy 282.658312 -98.307144)
			(xy 282.658312 -98.705924) (xy 282.702762 -98.705924)
		)
		(stroke
			(width 0)
			(type solid)
		)
		(fill yes)
		(layer "In4.Cu")
		(net "M_F_DQ<47>")
	)
	(gr_poly
		(pts
			(xy 282.872942 -97.626424) (xy 282.872942 -97.405444) (xy 282.702762 -97.316544) (xy 282.658312 -97.316544)
			(xy 282.658312 -97.715324) (xy 282.702762 -97.715324)
		)
		(stroke
			(width 0)
			(type solid)
		)
		(fill yes)
		(layer "In4.Cu")
		(net "M_F_DQ<47>")
	)
	(gr_poly
		(pts
			(xy 282.872942 -96.635824) (xy 282.872942 -96.414844) (xy 282.702762 -96.325944) (xy 282.658312 -96.325944)
			(xy 282.658312 -96.724724) (xy 282.702762 -96.724724)
		)
		(stroke
			(width 0)
			(type solid)
		)
		(fill yes)
		(layer "In4.Cu")
		(net "M_F_DQ<47>")
	)
	(gr_poly
		(pts
			(xy 282.961588 -52.12842) (xy 282.887928 -51.92903) (xy 282.856432 -51.897788) (xy 282.569158 -52.185062)
			(xy 282.600654 -52.216558) (xy 282.800044 -52.290218)
		)
		(stroke
			(width 0)
			(type solid)
		)
		(fill yes)
		(layer "In4.Cu")
		(net "M_C_DQ<43>")
	)
	(gr_poly
		(pts
			(xy 283.068014 -107.0229) (xy 283.068014 -106.7943) (xy 282.874974 -106.7054) (xy 282.830524 -106.7054)
			(xy 282.830524 -107.1118) (xy 282.874974 -107.1118)
		)
		(stroke
			(width 0)
			(type solid)
		)
		(fill yes)
		(layer "In4.Cu")
		(net "M_F_DQS_DP<5>")
	)
	(gr_poly
		(pts
			(xy 283.14904 -57.531762) (xy 283.140912 -57.339992) (xy 283.118814 -57.301384) (xy 282.773374 -57.501028)
			(xy 282.795726 -57.539382) (xy 282.957778 -57.642252)
		)
		(stroke
			(width 0)
			(type solid)
		)
		(fill yes)
		(layer "In4.Cu")
		(net "M_B_DQ<61>")
	)
	(gr_poly
		(pts
			(xy 283.179266 -49.466246) (xy 283.14777 -49.435004) (xy 282.94838 -49.361344) (xy 282.786836 -49.522888)
			(xy 282.860496 -49.722278) (xy 282.891738 -49.753774)
		)
		(stroke
			(width 0)
			(type solid)
		)
		(fill yes)
		(layer "In4.Cu")
		(net "M_C_DQ<46>")
	)
	(gr_poly
		(pts
			(xy 283.193236 -105.241344) (xy 283.148786 -105.241344) (xy 282.978606 -105.330244) (xy 282.978606 -105.551224)
			(xy 283.148786 -105.640124) (xy 283.193236 -105.640124)
		)
		(stroke
			(width 0)
			(type solid)
		)
		(fill yes)
		(layer "In4.Cu")
		(net "M_F_DQ<46>")
	)
	(gr_poly
		(pts
			(xy 283.193236 -103.260144) (xy 283.148786 -103.260144) (xy 282.978606 -103.349044) (xy 282.978606 -103.570024)
			(xy 283.148786 -103.658924) (xy 283.193236 -103.658924)
		)
		(stroke
			(width 0)
			(type solid)
		)
		(fill yes)
		(layer "In4.Cu")
		(net "M_F_DQ<42>")
	)
	(gr_poly
		(pts
			(xy 283.193236 -102.263194) (xy 283.148786 -102.263194) (xy 282.978606 -102.352094) (xy 282.978606 -102.573074)
			(xy 283.148786 -102.661974) (xy 283.193236 -102.661974)
		)
		(stroke
			(width 0)
			(type solid)
		)
		(fill yes)
		(layer "In4.Cu")
		(net "M_F_DQ<42>")
	)
	(gr_poly
		(pts
			(xy 283.193236 -101.26345) (xy 283.148786 -101.26345) (xy 282.978606 -101.35235) (xy 282.978606 -101.57333)
			(xy 283.148786 -101.66223) (xy 283.193236 -101.66223)
		)
		(stroke
			(width 0)
			(type solid)
		)
		(fill yes)
		(layer "In4.Cu")
		(net "M_F_DQ<42>")
	)
	(gr_poly
		(pts
			(xy 283.193236 -100.275644) (xy 283.148786 -100.275644) (xy 282.978606 -100.364544) (xy 282.978606 -100.585524)
			(xy 283.148786 -100.674424) (xy 283.193236 -100.674424)
		)
		(stroke
			(width 0)
			(type solid)
		)
		(fill yes)
		(layer "In4.Cu")
		(net "M_F_DQ<42>")
	)
	(gr_poly
		(pts
			(xy 283.193236 -99.291902) (xy 283.148786 -99.291902) (xy 282.978606 -99.380802) (xy 282.978606 -99.601782)
			(xy 283.148786 -99.690682) (xy 283.193236 -99.690682)
		)
		(stroke
			(width 0)
			(type solid)
		)
		(fill yes)
		(layer "In4.Cu")
		(net "M_F_DQ<42>")
	)
	(gr_poly
		(pts
			(xy 283.193236 -98.301302) (xy 283.148786 -98.301302) (xy 282.978606 -98.390202) (xy 282.978606 -98.611182)
			(xy 283.148786 -98.700082) (xy 283.193236 -98.700082)
		)
		(stroke
			(width 0)
			(type solid)
		)
		(fill yes)
		(layer "In4.Cu")
		(net "M_F_DQ<42>")
	)
	(gr_poly
		(pts
			(xy 283.193236 -97.310702) (xy 283.148786 -97.310702) (xy 282.978606 -97.399602) (xy 282.978606 -97.620582)
			(xy 283.148786 -97.709482) (xy 283.193236 -97.709482)
		)
		(stroke
			(width 0)
			(type solid)
		)
		(fill yes)
		(layer "In4.Cu")
		(net "M_F_DQ<42>")
	)
	(gr_poly
		(pts
			(xy 283.193236 -96.320102) (xy 283.148786 -96.320102) (xy 282.978606 -96.409002) (xy 282.978606 -96.629982)
			(xy 283.148786 -96.718882) (xy 283.193236 -96.718882)
		)
		(stroke
			(width 0)
			(type solid)
		)
		(fill yes)
		(layer "In4.Cu")
		(net "M_F_DQ<42>")
	)
	(gr_poly
		(pts
			(xy 283.248608 -48.18126) (xy 283.248608 -47.95266) (xy 283.055568 -47.86376) (xy 283.011118 -47.86376)
			(xy 283.011118 -48.27016) (xy 283.055568 -48.27016)
		)
		(stroke
			(width 0)
			(type solid)
		)
		(fill yes)
		(layer "In4.Cu")
		(net "M_C_DQS_DN<5>")
	)
	(gr_poly
		(pts
			(xy 283.367734 -56.784494) (xy 283.345382 -56.74614) (xy 283.18333 -56.64327) (xy 282.992068 -56.75376)
			(xy 283.000196 -56.94553) (xy 283.022294 -56.983884)
		)
		(stroke
			(width 0)
			(type solid)
		)
		(fill yes)
		(layer "In4.Cu")
		(net "M_B_DQ<60>")
	)
	(gr_poly
		(pts
			(xy 283.419296 -49.832006) (xy 283.345636 -49.632616) (xy 283.31414 -49.601374) (xy 283.026866 -49.888648)
			(xy 283.058362 -49.920144) (xy 283.257752 -49.993804)
		)
		(stroke
			(width 0)
			(type solid)
		)
		(fill yes)
		(layer "In4.Cu")
		(net "M_C_DQ<47>")
	)
	(gr_poly
		(pts
			(xy 283.420058 -104.490774) (xy 283.428186 -104.299004) (xy 283.23667 -104.188768) (xy 283.074872 -104.291638)
			(xy 283.052266 -104.329992) (xy 283.39796 -104.529382)
		)
		(stroke
			(width 0)
			(type solid)
		)
		(fill yes)
		(layer "In4.Cu")
		(net "M_F_DQ<47>")
	)
	(gr_poly
		(pts
			(xy 283.560012 -106.133646) (xy 283.730192 -106.044746) (xy 283.729938 -105.82402) (xy 283.560012 -105.73512)
			(xy 283.515308 -105.734866) (xy 283.515562 -106.1339)
		)
		(stroke
			(width 0)
			(type solid)
		)
		(fill yes)
		(layer "In4.Cu")
		(net "M_F_DQ<47>")
	)
	(gr_poly
		(pts
			(xy 283.561282 -105.143046) (xy 283.731462 -105.054146) (xy 283.731208 -104.83342) (xy 283.561282 -104.74452)
			(xy 283.516578 -104.744266) (xy 283.516832 -105.1433)
		)
		(stroke
			(width 0)
			(type solid)
		)
		(fill yes)
		(layer "In4.Cu")
		(net "M_F_DQ<47>")
	)
	(gr_poly
		(pts
			(xy 283.629862 -104.097582) (xy 283.652214 -104.059228) (xy 283.306774 -103.859584) (xy 283.284676 -103.898192)
			(xy 283.276548 -104.089962) (xy 283.46781 -104.200452)
		)
		(stroke
			(width 0)
			(type solid)
		)
		(fill yes)
		(layer "In4.Cu")
		(net "M_F_DQ<42>")
	)
	(gr_poly
		(pts
			(xy 283.731462 -103.062278) (xy 283.731462 -102.841298) (xy 283.561282 -102.752398) (xy 283.516832 -102.752398)
			(xy 283.516832 -103.151178) (xy 283.561282 -103.151178)
		)
		(stroke
			(width 0)
			(type solid)
		)
		(fill yes)
		(layer "In4.Cu")
		(net "M_F_DQ<43>")
	)
	(gr_poly
		(pts
			(xy 283.731462 -102.08387) (xy 283.731462 -101.86289) (xy 283.561282 -101.77399) (xy 283.516832 -101.77399)
			(xy 283.516832 -102.17277) (xy 283.561282 -102.17277)
		)
		(stroke
			(width 0)
			(type solid)
		)
		(fill yes)
		(layer "In4.Cu")
		(net "M_F_DQ<43>")
	)
	(gr_poly
		(pts
			(xy 283.731462 -101.09581) (xy 283.731462 -100.87483) (xy 283.561282 -100.78593) (xy 283.516832 -100.78593)
			(xy 283.516832 -101.18471) (xy 283.561282 -101.18471)
		)
		(stroke
			(width 0)
			(type solid)
		)
		(fill yes)
		(layer "In4.Cu")
		(net "M_F_DQ<43>")
	)
	(gr_poly
		(pts
			(xy 283.731462 -100.10267) (xy 283.731462 -99.88169) (xy 283.561282 -99.79279) (xy 283.516832 -99.79279)
			(xy 283.516832 -100.19157) (xy 283.561282 -100.19157)
		)
		(stroke
			(width 0)
			(type solid)
		)
		(fill yes)
		(layer "In4.Cu")
		(net "M_F_DQ<43>")
	)
	(gr_poly
		(pts
			(xy 283.731462 -99.106482) (xy 283.731462 -98.885502) (xy 283.561282 -98.796602) (xy 283.516832 -98.796602)
			(xy 283.516832 -99.195382) (xy 283.561282 -99.195382)
		)
		(stroke
			(width 0)
			(type solid)
		)
		(fill yes)
		(layer "In4.Cu")
		(net "M_F_DQ<43>")
	)
	(gr_poly
		(pts
			(xy 283.731462 -98.115882) (xy 283.731462 -97.894902) (xy 283.561282 -97.806002) (xy 283.516832 -97.806002)
			(xy 283.516832 -98.204782) (xy 283.561282 -98.204782)
		)
		(stroke
			(width 0)
			(type solid)
		)
		(fill yes)
		(layer "In4.Cu")
		(net "M_F_DQ<43>")
	)
	(gr_poly
		(pts
			(xy 283.731462 -97.125282) (xy 283.731462 -96.904302) (xy 283.561282 -96.815402) (xy 283.516832 -96.815402)
			(xy 283.516832 -97.214182) (xy 283.561282 -97.214182)
		)
		(stroke
			(width 0)
			(type solid)
		)
		(fill yes)
		(layer "In4.Cu")
		(net "M_F_DQ<43>")
	)
	(gr_poly
		(pts
			(xy 283.731462 -96.134682) (xy 283.731462 -95.913702) (xy 283.561282 -95.824802) (xy 283.516832 -95.824802)
			(xy 283.516832 -96.223582) (xy 283.561282 -96.223582)
		)
		(stroke
			(width 0)
			(type solid)
		)
		(fill yes)
		(layer "In4.Cu")
		(net "M_F_DQ<43>")
	)
	(gr_poly
		(pts
			(xy 283.767022 -53.732938) (xy 283.722572 -53.732938) (xy 283.552392 -53.821838) (xy 283.552392 -54.042818)
			(xy 283.722572 -54.131718) (xy 283.767022 -54.131718)
		)
		(stroke
			(width 0)
			(type solid)
		)
		(fill yes)
		(layer "In4.Cu")
		(net "M_B_DQ<60>")
	)
	(gr_poly
		(pts
			(xy 283.767022 -52.739544) (xy 283.722572 -52.739544) (xy 283.552392 -52.828444) (xy 283.552392 -53.049424)
			(xy 283.722572 -53.138324) (xy 283.767022 -53.138324)
		)
		(stroke
			(width 0)
			(type solid)
		)
		(fill yes)
		(layer "In4.Cu")
		(net "M_B_DQ<60>")
	)
	(gr_poly
		(pts
			(xy 283.767276 -55.711344) (xy 283.722826 -55.711344) (xy 283.552646 -55.800244) (xy 283.552646 -56.021224)
			(xy 283.722826 -56.110124) (xy 283.767276 -56.110124)
		)
		(stroke
			(width 0)
			(type solid)
		)
		(fill yes)
		(layer "In4.Cu")
		(net "M_B_DQ<60>")
	)
	(gr_poly
		(pts
			(xy 283.767276 -54.720744) (xy 283.722826 -54.720744) (xy 283.552646 -54.809644) (xy 283.552646 -55.030624)
			(xy 283.722826 -55.119524) (xy 283.767276 -55.119524)
		)
		(stroke
			(width 0)
			(type solid)
		)
		(fill yes)
		(layer "In4.Cu")
		(net "M_B_DQ<60>")
	)
	(gr_poly
		(pts
			(xy 283.879544 -48.765968) (xy 283.848302 -48.734472) (xy 283.648912 -48.660812) (xy 283.487114 -48.822356)
			(xy 283.560774 -49.021746) (xy 283.59227 -49.053242)
		)
		(stroke
			(width 0)
			(type solid)
		)
		(fill yes)
		(layer "In4.Cu")
		(net "M_C_DQ<46>")
	)
	(gr_poly
		(pts
			(xy 283.940504 -51.48326) (xy 283.90215 -51.461162) (xy 283.71038 -51.453034) (xy 283.59989 -51.644296)
			(xy 283.70276 -51.806348) (xy 283.741368 -51.8287)
		)
		(stroke
			(width 0)
			(type solid)
		)
		(fill yes)
		(layer "In4.Cu")
		(net "M_B_DQ<60>")
	)
	(gr_poly
		(pts
			(xy 283.97708 -47.668688) (xy 283.93263 -47.668688) (xy 283.73959 -47.757588) (xy 283.73959 -47.986188)
			(xy 283.93263 -48.075088) (xy 283.97708 -48.075088)
		)
		(stroke
			(width 0)
			(type solid)
		)
		(fill yes)
		(layer "In4.Cu")
		(net "M_C_DQ<46>")
	)
	(gr_poly
		(pts
			(xy 284.005782 -57.037986) (xy 283.997654 -56.846216) (xy 283.97581 -56.807608) (xy 283.630116 -57.006998)
			(xy 283.652468 -57.045352) (xy 283.81452 -57.148222)
		)
		(stroke
			(width 0)
			(type solid)
		)
		(fill yes)
		(layer "In4.Cu")
		(net "M_B_DQ<61>")
	)
	(gr_poly
		(pts
			(xy 284.006036 -58.028078) (xy 283.997908 -57.836308) (xy 283.97581 -57.7977) (xy 283.63037 -57.997344)
			(xy 283.652722 -58.035698) (xy 283.814774 -58.138568)
		)
		(stroke
			(width 0)
			(type solid)
		)
		(fill yes)
		(layer "In4.Cu")
		(net "M_B_DQ<57>")
	)
	(gr_poly
		(pts
			(xy 284.015688 -49.740312) (xy 283.984446 -49.708816) (xy 283.785056 -49.635156) (xy 283.623258 -49.7967)
			(xy 283.696918 -49.99609) (xy 283.728414 -50.027586)
		)
		(stroke
			(width 0)
			(type solid)
		)
		(fill yes)
		(layer "In4.Cu")
		(net "M_C_DQ<42>")
	)
	(gr_poly
		(pts
			(xy 284.046422 -105.724198) (xy 284.001972 -105.724198) (xy 283.831792 -105.813098) (xy 283.831792 -106.034078)
			(xy 284.001972 -106.122978) (xy 284.046422 -106.122978)
		)
		(stroke
			(width 0)
			(type solid)
		)
		(fill yes)
		(layer "In4.Cu")
		(net "M_F_DQ<42>")
	)
	(gr_poly
		(pts
			(xy 284.051756 -104.733598) (xy 284.007306 -104.733598) (xy 283.837126 -104.822498) (xy 283.837126 -105.043478)
			(xy 284.007306 -105.132378) (xy 284.051756 -105.132378)
		)
		(stroke
			(width 0)
			(type solid)
		)
		(fill yes)
		(layer "In4.Cu")
		(net "M_F_DQ<42>")
	)
	(gr_poly
		(pts
			(xy 284.051756 -102.752398) (xy 284.007306 -102.752398) (xy 283.837126 -102.841298) (xy 283.837126 -103.062278)
			(xy 284.007306 -103.151178) (xy 284.051756 -103.151178)
		)
		(stroke
			(width 0)
			(type solid)
		)
		(fill yes)
		(layer "In4.Cu")
		(net "M_E_DQ<60>")
	)
	(gr_poly
		(pts
			(xy 284.051756 -101.761798) (xy 284.007306 -101.761798) (xy 283.837126 -101.850698) (xy 283.837126 -102.071678)
			(xy 284.007306 -102.160578) (xy 284.051756 -102.160578)
		)
		(stroke
			(width 0)
			(type solid)
		)
		(fill yes)
		(layer "In4.Cu")
		(net "M_E_DQ<60>")
	)
	(gr_poly
		(pts
			(xy 284.051756 -100.771198) (xy 284.007306 -100.771198) (xy 283.837126 -100.860098) (xy 283.837126 -101.081078)
			(xy 284.007306 -101.169978) (xy 284.051756 -101.169978)
		)
		(stroke
			(width 0)
			(type solid)
		)
		(fill yes)
		(layer "In4.Cu")
		(net "M_E_DQ<60>")
	)
	(gr_poly
		(pts
			(xy 284.051756 -99.780598) (xy 284.007306 -99.780598) (xy 283.837126 -99.869498) (xy 283.837126 -100.090478)
			(xy 284.007306 -100.179378) (xy 284.051756 -100.179378)
		)
		(stroke
			(width 0)
			(type solid)
		)
		(fill yes)
		(layer "In4.Cu")
		(net "M_E_DQ<60>")
	)
	(gr_poly
		(pts
			(xy 284.05201 -98.796094) (xy 284.00756 -98.796094) (xy 283.83738 -98.884994) (xy 283.83738 -99.105974)
			(xy 284.00756 -99.194874) (xy 284.05201 -99.194874)
		)
		(stroke
			(width 0)
			(type solid)
		)
		(fill yes)
		(layer "In4.Cu")
		(net "M_E_DQ<60>")
	)
	(gr_poly
		(pts
			(xy 284.05201 -97.805494) (xy 284.00756 -97.805494) (xy 283.83738 -97.894394) (xy 283.83738 -98.115374)
			(xy 284.00756 -98.204274) (xy 284.05201 -98.204274)
		)
		(stroke
			(width 0)
			(type solid)
		)
		(fill yes)
		(layer "In4.Cu")
		(net "M_E_DQ<60>")
	)
	(gr_poly
		(pts
			(xy 284.05201 -96.814894) (xy 284.00756 -96.814894) (xy 283.83738 -96.903794) (xy 283.83738 -97.124774)
			(xy 284.00756 -97.213674) (xy 284.05201 -97.213674)
		)
		(stroke
			(width 0)
			(type solid)
		)
		(fill yes)
		(layer "In4.Cu")
		(net "M_E_DQ<60>")
	)
	(gr_poly
		(pts
			(xy 284.05201 -95.824294) (xy 284.00756 -95.824294) (xy 283.83738 -95.913194) (xy 283.83738 -96.134174)
			(xy 284.00756 -96.223074) (xy 284.05201 -96.223074)
		)
		(stroke
			(width 0)
			(type solid)
		)
		(fill yes)
		(layer "In4.Cu")
		(net "M_E_DQ<60>")
	)
	(gr_poly
		(pts
			(xy 284.119574 -49.131474) (xy 284.045914 -48.932084) (xy 284.014418 -48.900842) (xy 283.727144 -49.188116)
			(xy 283.75864 -49.219612) (xy 283.95803 -49.293272)
		)
		(stroke
			(width 0)
			(type solid)
		)
		(fill yes)
		(layer "In4.Cu")
		(net "M_C_DQ<47>")
	)
	(gr_poly
		(pts
			(xy 284.227778 -57.278778) (xy 284.205426 -57.240424) (xy 284.043374 -57.137554) (xy 283.852112 -57.248044)
			(xy 283.86024 -57.439814) (xy 283.882338 -57.478422)
		)
		(stroke
			(width 0)
			(type solid)
		)
		(fill yes)
		(layer "In4.Cu")
		(net "M_B_DQ<56>")
	)
	(gr_poly
		(pts
			(xy 284.255718 -50.105818) (xy 284.182058 -49.906428) (xy 284.150562 -49.875186) (xy 283.863288 -50.16246)
			(xy 283.894784 -50.193956) (xy 284.094174 -50.267616)
		)
		(stroke
			(width 0)
			(type solid)
		)
		(fill yes)
		(layer "In4.Cu")
		(net "M_C_DQ<43>")
	)
	(gr_poly
		(pts
			(xy 284.282388 -103.998014) (xy 284.290516 -103.806244) (xy 284.099254 -103.695754) (xy 283.937202 -103.798624)
			(xy 283.91485 -103.836978) (xy 284.26029 -104.036622)
		)
		(stroke
			(width 0)
			(type solid)
		)
		(fill yes)
		(layer "In4.Cu")
		(net "M_F_DQ<43>")
	)
	(gr_poly
		(pts
			(xy 284.305502 -55.513478) (xy 284.305502 -55.292498) (xy 284.135322 -55.203598) (xy 284.090872 -55.203598)
			(xy 284.090872 -55.602378) (xy 284.135322 -55.602378)
		)
		(stroke
			(width 0)
			(type solid)
		)
		(fill yes)
		(layer "In4.Cu")
		(net "M_B_DQ<61>")
	)
	(gr_poly
		(pts
			(xy 284.305502 -54.520084) (xy 284.305502 -54.299104) (xy 284.135322 -54.210204) (xy 284.090872 -54.210204)
			(xy 284.090872 -54.608984) (xy 284.135322 -54.608984)
		)
		(stroke
			(width 0)
			(type solid)
		)
		(fill yes)
		(layer "In4.Cu")
		(net "M_B_DQ<61>")
	)
	(gr_poly
		(pts
			(xy 284.305502 -53.529484) (xy 284.305502 -53.308504) (xy 284.135322 -53.219604) (xy 284.090872 -53.219604)
			(xy 284.090872 -53.618384) (xy 284.135322 -53.618384)
		)
		(stroke
			(width 0)
			(type solid)
		)
		(fill yes)
		(layer "In4.Cu")
		(net "M_B_DQ<61>")
	)
	(gr_poly
		(pts
			(xy 284.305502 -52.547774) (xy 284.305502 -52.326794) (xy 284.135322 -52.237894) (xy 284.090872 -52.237894)
			(xy 284.090872 -52.636674) (xy 284.135322 -52.636674)
		)
		(stroke
			(width 0)
			(type solid)
		)
		(fill yes)
		(layer "In4.Cu")
		(net "M_B_DQ<61>")
	)
	(gr_poly
		(pts
			(xy 284.40507 -47.986188) (xy 284.40507 -47.757588) (xy 284.21203 -47.668688) (xy 284.16758 -47.668688)
			(xy 284.16758 -48.075088) (xy 284.21203 -48.075088)
		)
		(stroke
			(width 0)
			(type solid)
		)
		(fill yes)
		(layer "In4.Cu")
		(net "M_C_DQ<47>")
	)
	(gr_poly
		(pts
			(xy 284.489906 -106.575098) (xy 284.512258 -106.536744) (xy 284.166818 -106.3371) (xy 284.14472 -106.375708)
			(xy 284.136592 -106.567478) (xy 284.327854 -106.677968)
		)
		(stroke
			(width 0)
			(type solid)
		)
		(fill yes)
		(layer "In4.Cu")
		(net "M_F_DQ<42>")
	)
	(gr_poly
		(pts
			(xy 284.49016 -103.603552) (xy 284.512512 -103.565198) (xy 284.166818 -103.365808) (xy 284.144974 -103.404416)
			(xy 284.136846 -103.596186) (xy 284.328108 -103.706422)
		)
		(stroke
			(width 0)
			(type solid)
		)
		(fill yes)
		(layer "In4.Cu")
		(net "M_E_DQ<60>")
	)
	(gr_poly
		(pts
			(xy 284.589982 -105.551224) (xy 284.589982 -105.330244) (xy 284.419802 -105.241344) (xy 284.375352 -105.241344)
			(xy 284.375352 -105.640124) (xy 284.419802 -105.640124)
		)
		(stroke
			(width 0)
			(type solid)
		)
		(fill yes)
		(layer "In4.Cu")
		(net "M_F_DQ<43>")
	)
	(gr_poly
		(pts
			(xy 284.589982 -104.560624) (xy 284.589982 -104.339644) (xy 284.419802 -104.250744) (xy 284.375352 -104.250744)
			(xy 284.375352 -104.649524) (xy 284.419802 -104.649524)
		)
		(stroke
			(width 0)
			(type solid)
		)
		(fill yes)
		(layer "In4.Cu")
		(net "M_F_DQ<43>")
	)
	(gr_poly
		(pts
			(xy 284.589982 -102.579424) (xy 284.589982 -102.358444) (xy 284.419802 -102.269544) (xy 284.375352 -102.269544)
			(xy 284.375352 -102.668324) (xy 284.419802 -102.668324)
		)
		(stroke
			(width 0)
			(type solid)
		)
		(fill yes)
		(layer "In4.Cu")
		(net "M_E_DQ<61>")
	)
	(gr_poly
		(pts
			(xy 284.589982 -101.588824) (xy 284.589982 -101.367844) (xy 284.419802 -101.278944) (xy 284.375352 -101.278944)
			(xy 284.375352 -101.677724) (xy 284.419802 -101.677724)
		)
		(stroke
			(width 0)
			(type solid)
		)
		(fill yes)
		(layer "In4.Cu")
		(net "M_E_DQ<61>")
	)
	(gr_poly
		(pts
			(xy 284.589982 -100.598224) (xy 284.589982 -100.377244) (xy 284.419802 -100.288344) (xy 284.375352 -100.288344)
			(xy 284.375352 -100.687124) (xy 284.419802 -100.687124)
		)
		(stroke
			(width 0)
			(type solid)
		)
		(fill yes)
		(layer "In4.Cu")
		(net "M_E_DQ<61>")
	)
	(gr_poly
		(pts
			(xy 284.589982 -99.607624) (xy 284.589982 -99.386644) (xy 284.419802 -99.297744) (xy 284.375352 -99.297744)
			(xy 284.375352 -99.696524) (xy 284.419802 -99.696524)
		)
		(stroke
			(width 0)
			(type solid)
		)
		(fill yes)
		(layer "In4.Cu")
		(net "M_E_DQ<61>")
	)
	(gr_poly
		(pts
			(xy 284.590236 -98.610674) (xy 284.590236 -98.389694) (xy 284.420056 -98.300794) (xy 284.375606 -98.300794)
			(xy 284.375606 -98.699574) (xy 284.420056 -98.699574)
		)
		(stroke
			(width 0)
			(type solid)
		)
		(fill yes)
		(layer "In4.Cu")
		(net "M_E_DQ<61>")
	)
	(gr_poly
		(pts
			(xy 284.590236 -97.620074) (xy 284.590236 -97.399094) (xy 284.420056 -97.310194) (xy 284.375606 -97.310194)
			(xy 284.375606 -97.708974) (xy 284.420056 -97.708974)
		)
		(stroke
			(width 0)
			(type solid)
		)
		(fill yes)
		(layer "In4.Cu")
		(net "M_E_DQ<61>")
	)
	(gr_poly
		(pts
			(xy 284.590236 -96.629474) (xy 284.590236 -96.408494) (xy 284.420056 -96.319594) (xy 284.375606 -96.319594)
			(xy 284.375606 -96.718374) (xy 284.420056 -96.718374)
		)
		(stroke
			(width 0)
			(type solid)
		)
		(fill yes)
		(layer "In4.Cu")
		(net "M_E_DQ<61>")
	)
	(gr_poly
		(pts
			(xy 284.625542 -60.153804) (xy 284.581092 -60.153804) (xy 284.410912 -60.242704) (xy 284.410912 -60.463684)
			(xy 284.581092 -60.552584) (xy 284.625542 -60.552584)
		)
		(stroke
			(width 0)
			(type solid)
		)
		(fill yes)
		(layer "In4.Cu")
		(net "M_B_DQS_DP<7>")
	)
	(gr_poly
		(pts
			(xy 284.625542 -56.191404) (xy 284.581092 -56.191404) (xy 284.410912 -56.280304) (xy 284.410912 -56.501284)
			(xy 284.581092 -56.590184) (xy 284.625542 -56.590184)
		)
		(stroke
			(width 0)
			(type solid)
		)
		(fill yes)
		(layer "In4.Cu")
		(net "M_B_DQ<56>")
	)
	(gr_poly
		(pts
			(xy 284.625542 -55.200804) (xy 284.581092 -55.200804) (xy 284.410912 -55.289704) (xy 284.410912 -55.510684)
			(xy 284.581092 -55.599584) (xy 284.625542 -55.599584)
		)
		(stroke
			(width 0)
			(type solid)
		)
		(fill yes)
		(layer "In4.Cu")
		(net "M_B_DQ<56>")
	)
	(gr_poly
		(pts
			(xy 284.625542 -54.212998) (xy 284.581092 -54.212998) (xy 284.410912 -54.301898) (xy 284.410912 -54.522878)
			(xy 284.581092 -54.611778) (xy 284.625542 -54.611778)
		)
		(stroke
			(width 0)
			(type solid)
		)
		(fill yes)
		(layer "In4.Cu")
		(net "M_B_DQ<56>")
	)
	(gr_poly
		(pts
			(xy 284.625542 -53.222398) (xy 284.581092 -53.222398) (xy 284.410912 -53.311298) (xy 284.410912 -53.532278)
			(xy 284.581092 -53.621178) (xy 284.625542 -53.621178)
		)
		(stroke
			(width 0)
			(type solid)
		)
		(fill yes)
		(layer "In4.Cu")
		(net "M_B_DQ<56>")
	)
	(gr_poly
		(pts
			(xy 284.71622 -49.03978) (xy 284.684724 -49.008284) (xy 284.485334 -48.934624) (xy 284.32379 -49.096422)
			(xy 284.39745 -49.295812) (xy 284.428946 -49.327054)
		)
		(stroke
			(width 0)
			(type solid)
		)
		(fill yes)
		(layer "In4.Cu")
		(net "M_C_DQ<42>")
	)
	(gr_poly
		(pts
			(xy 284.802072 -51.973226) (xy 284.763718 -51.951128) (xy 284.571948 -51.943) (xy 284.461458 -52.134262)
			(xy 284.564328 -52.296314) (xy 284.602936 -52.318666)
		)
		(stroke
			(width 0)
			(type solid)
		)
		(fill yes)
		(layer "In4.Cu")
		(net "M_B_DQ<56>")
	)
	(gr_poly
		(pts
			(xy 284.864302 -58.523632) (xy 284.856174 -58.331862) (xy 284.834076 -58.293508) (xy 284.488636 -58.492898)
			(xy 284.510988 -58.531252) (xy 284.67304 -58.634122)
		)
		(stroke
			(width 0)
			(type solid)
		)
		(fill yes)
		(layer "In4.Cu")
		(net "M_B_DQS_DN<16>")
	)
	(gr_poly
		(pts
			(xy 284.910276 -105.241344) (xy 284.865826 -105.241344) (xy 284.695646 -105.330244) (xy 284.695646 -105.551224)
			(xy 284.865826 -105.640124) (xy 284.910276 -105.640124)
		)
		(stroke
			(width 0)
			(type solid)
		)
		(fill yes)
		(layer "In4.Cu")
		(net "M_E_DQ<60>")
	)
	(gr_poly
		(pts
			(xy 284.910276 -104.250744) (xy 284.865826 -104.250744) (xy 284.695646 -104.339644) (xy 284.695646 -104.560624)
			(xy 284.865826 -104.649524) (xy 284.910276 -104.649524)
		)
		(stroke
			(width 0)
			(type solid)
		)
		(fill yes)
		(layer "In4.Cu")
		(net "M_E_DQ<60>")
	)
	(gr_poly
		(pts
			(xy 284.910276 -102.269544) (xy 284.865826 -102.269544) (xy 284.695646 -102.358444) (xy 284.695646 -102.579424)
			(xy 284.865826 -102.668324) (xy 284.910276 -102.668324)
		)
		(stroke
			(width 0)
			(type solid)
		)
		(fill yes)
		(layer "In4.Cu")
		(net "M_E_DQ<56>")
	)
	(gr_poly
		(pts
			(xy 284.910276 -101.278944) (xy 284.865826 -101.278944) (xy 284.695646 -101.367844) (xy 284.695646 -101.588824)
			(xy 284.865826 -101.677724) (xy 284.910276 -101.677724)
		)
		(stroke
			(width 0)
			(type solid)
		)
		(fill yes)
		(layer "In4.Cu")
		(net "M_E_DQ<56>")
	)
	(gr_poly
		(pts
			(xy 284.910276 -100.288344) (xy 284.865826 -100.288344) (xy 284.695646 -100.377244) (xy 284.695646 -100.598224)
			(xy 284.865826 -100.687124) (xy 284.910276 -100.687124)
		)
		(stroke
			(width 0)
			(type solid)
		)
		(fill yes)
		(layer "In4.Cu")
		(net "M_E_DQ<56>")
	)
	(gr_poly
		(pts
			(xy 284.910276 -99.297744) (xy 284.865826 -99.297744) (xy 284.695646 -99.386644) (xy 284.695646 -99.607624)
			(xy 284.865826 -99.696524) (xy 284.910276 -99.696524)
		)
		(stroke
			(width 0)
			(type solid)
		)
		(fill yes)
		(layer "In4.Cu")
		(net "M_E_DQ<56>")
	)
	(gr_poly
		(pts
			(xy 284.91053 -98.300794) (xy 284.86608 -98.300794) (xy 284.6959 -98.389694) (xy 284.6959 -98.610674)
			(xy 284.86608 -98.699574) (xy 284.91053 -98.699574)
		)
		(stroke
			(width 0)
			(type solid)
		)
		(fill yes)
		(layer "In4.Cu")
		(net "M_E_DQ<56>")
	)
	(gr_poly
		(pts
			(xy 284.91053 -97.310194) (xy 284.86608 -97.310194) (xy 284.6959 -97.399094) (xy 284.6959 -97.620074)
			(xy 284.86608 -97.708974) (xy 284.91053 -97.708974)
		)
		(stroke
			(width 0)
			(type solid)
		)
		(fill yes)
		(layer "In4.Cu")
		(net "M_E_DQ<56>")
	)
	(gr_poly
		(pts
			(xy 284.91053 -96.319594) (xy 284.86608 -96.319594) (xy 284.6959 -96.408494) (xy 284.6959 -96.629474)
			(xy 284.86608 -96.718374) (xy 284.91053 -96.718374)
		)
		(stroke
			(width 0)
			(type solid)
		)
		(fill yes)
		(layer "In4.Cu")
		(net "M_E_DQ<56>")
	)
	(gr_poly
		(pts
			(xy 284.95625 -49.40554) (xy 284.88259 -49.20615) (xy 284.851094 -49.174654) (xy 284.56382 -49.461928)
			(xy 284.595062 -49.493424) (xy 284.794452 -49.567084)
		)
		(stroke
			(width 0)
			(type solid)
		)
		(fill yes)
		(layer "In4.Cu")
		(net "M_C_DQ<43>")
	)
	(gr_poly
		(pts
			(xy 285.084012 -57.775856) (xy 285.06166 -57.737502) (xy 284.899608 -57.634632) (xy 284.708346 -57.745122)
			(xy 284.716474 -57.936892) (xy 284.738572 -57.9755)
		)
		(stroke
			(width 0)
			(type solid)
		)
		(fill yes)
		(layer "In4.Cu")
		(net "M_B_DQS_DP<16>")
	)
	(gr_poly
		(pts
			(xy 285.137098 -103.500174) (xy 285.145226 -103.308404) (xy 284.95371 -103.198168) (xy 284.791912 -103.301038)
			(xy 284.769306 -103.339392) (xy 285.115 -103.538782)
		)
		(stroke
			(width 0)
			(type solid)
		)
		(fill yes)
		(layer "In4.Cu")
		(net "M_E_DQ<61>")
	)
	(gr_poly
		(pts
			(xy 285.142432 -106.47553) (xy 285.15056 -106.28376) (xy 284.959298 -106.17327) (xy 284.797246 -106.27614)
			(xy 284.774894 -106.314494) (xy 285.120334 -106.514138)
		)
		(stroke
			(width 0)
			(type solid)
		)
		(fill yes)
		(layer "In4.Cu")
		(net "M_F_DQ<43>")
	)
	(gr_poly
		(pts
			(xy 285.163768 -54.040024) (xy 285.163768 -53.819044) (xy 284.993588 -53.730144) (xy 284.949138 -53.730144)
			(xy 284.949138 -54.128924) (xy 284.993588 -54.128924)
		)
		(stroke
			(width 0)
			(type solid)
		)
		(fill yes)
		(layer "In4.Cu")
		(net "M_B_DQ<57>")
	)
	(gr_poly
		(pts
			(xy 285.163768 -53.049424) (xy 285.163768 -52.828444) (xy 284.993588 -52.739544) (xy 284.949138 -52.739544)
			(xy 284.949138 -53.138324) (xy 284.993588 -53.138324)
		)
		(stroke
			(width 0)
			(type solid)
		)
		(fill yes)
		(layer "In4.Cu")
		(net "M_B_DQ<57>")
	)
	(gr_poly
		(pts
			(xy 285.164022 -60.977018) (xy 285.164022 -60.756038) (xy 284.993842 -60.667138) (xy 284.949392 -60.667138)
			(xy 284.949392 -61.065918) (xy 284.993842 -61.065918)
		)
		(stroke
			(width 0)
			(type solid)
		)
		(fill yes)
		(layer "In4.Cu")
		(net "M_B_DQS_DN<7>")
	)
	(gr_poly
		(pts
			(xy 285.164022 -59.983624) (xy 285.164022 -59.762644) (xy 284.993842 -59.673744) (xy 284.949392 -59.673744)
			(xy 284.949392 -60.072524) (xy 284.993842 -60.072524)
		)
		(stroke
			(width 0)
			(type solid)
		)
		(fill yes)
		(layer "In4.Cu")
		(net "M_B_DQS_DN<7>")
	)
	(gr_poly
		(pts
			(xy 285.164022 -56.024018) (xy 285.164022 -55.803038) (xy 284.993842 -55.714138) (xy 284.949392 -55.714138)
			(xy 284.949392 -56.112918) (xy 284.993842 -56.112918)
		)
		(stroke
			(width 0)
			(type solid)
		)
		(fill yes)
		(layer "In4.Cu")
		(net "M_B_DQ<57>")
	)
	(gr_poly
		(pts
			(xy 285.164022 -55.033418) (xy 285.164022 -54.812438) (xy 284.993842 -54.723538) (xy 284.949392 -54.723538)
			(xy 284.949392 -55.122318) (xy 284.993842 -55.122318)
		)
		(stroke
			(width 0)
			(type solid)
		)
		(fill yes)
		(layer "In4.Cu")
		(net "M_B_DQ<57>")
	)
	(gr_poly
		(pts
			(xy 285.22676 -47.714662) (xy 285.18231 -47.714662) (xy 284.98927 -47.803562) (xy 284.98927 -48.032162)
			(xy 285.18231 -48.121062) (xy 285.22676 -48.121062)
		)
		(stroke
			(width 0)
			(type solid)
		)
		(fill yes)
		(layer "In4.Cu")
		(net "M_C_DQ<42>")
	)
	(gr_poly
		(pts
			(xy 285.328106 -95.071184) (xy 285.225236 -94.909132) (xy 285.186628 -94.887034) (xy 284.987238 -95.23222)
			(xy 285.025846 -95.254572) (xy 285.217616 -95.2627)
		)
		(stroke
			(width 0)
			(type solid)
		)
		(fill yes)
		(layer "In4.Cu")
		(net "M_E_DQ<56>")
	)
	(gr_poly
		(pts
			(xy 285.352236 -106.082084) (xy 285.374842 -106.04373) (xy 285.029148 -105.84434) (xy 285.00705 -105.882948)
			(xy 284.998922 -106.074718) (xy 285.190438 -106.184954)
		)
		(stroke
			(width 0)
			(type solid)
		)
		(fill yes)
		(layer "In4.Cu")
		(net "M_E_DQ<60>")
	)
	(gr_poly
		(pts
			(xy 285.448502 -105.043478) (xy 285.448502 -104.822498) (xy 285.278322 -104.733598) (xy 285.233872 -104.733598)
			(xy 285.233872 -105.132378) (xy 285.278322 -105.132378)
		)
		(stroke
			(width 0)
			(type solid)
		)
		(fill yes)
		(layer "In4.Cu")
		(net "M_E_DQ<61>")
	)
	(gr_poly
		(pts
			(xy 285.448502 -104.052878) (xy 285.448502 -103.831898) (xy 285.278322 -103.742998) (xy 285.233872 -103.742998)
			(xy 285.233872 -104.141778) (xy 285.278322 -104.141778)
		)
		(stroke
			(width 0)
			(type solid)
		)
		(fill yes)
		(layer "In4.Cu")
		(net "M_E_DQ<61>")
	)
	(gr_poly
		(pts
			(xy 285.448502 -102.071678) (xy 285.448502 -101.850698) (xy 285.278322 -101.761798) (xy 285.233872 -101.761798)
			(xy 285.233872 -102.160578) (xy 285.278322 -102.160578)
		)
		(stroke
			(width 0)
			(type solid)
		)
		(fill yes)
		(layer "In4.Cu")
		(net "M_E_DQ<57>")
	)
	(gr_poly
		(pts
			(xy 285.448502 -101.081078) (xy 285.448502 -100.860098) (xy 285.278322 -100.771198) (xy 285.233872 -100.771198)
			(xy 285.233872 -101.169978) (xy 285.278322 -101.169978)
		)
		(stroke
			(width 0)
			(type solid)
		)
		(fill yes)
		(layer "In4.Cu")
		(net "M_E_DQ<57>")
	)
	(gr_poly
		(pts
			(xy 285.448502 -100.090478) (xy 285.448502 -99.869498) (xy 285.278322 -99.780598) (xy 285.233872 -99.780598)
			(xy 285.233872 -100.179378) (xy 285.278322 -100.179378)
		)
		(stroke
			(width 0)
			(type solid)
		)
		(fill yes)
		(layer "In4.Cu")
		(net "M_E_DQ<57>")
	)
	(gr_poly
		(pts
			(xy 285.448756 -99.105974) (xy 285.448756 -98.884994) (xy 285.278576 -98.796094) (xy 285.234126 -98.796094)
			(xy 285.234126 -99.194874) (xy 285.278576 -99.194874)
		)
		(stroke
			(width 0)
			(type solid)
		)
		(fill yes)
		(layer "In4.Cu")
		(net "M_E_DQ<57>")
	)
	(gr_poly
		(pts
			(xy 285.448756 -98.115374) (xy 285.448756 -97.894394) (xy 285.278576 -97.805494) (xy 285.234126 -97.805494)
			(xy 285.234126 -98.204274) (xy 285.278576 -98.204274)
		)
		(stroke
			(width 0)
			(type solid)
		)
		(fill yes)
		(layer "In4.Cu")
		(net "M_E_DQ<57>")
	)
	(gr_poly
		(pts
			(xy 285.448756 -97.124774) (xy 285.448756 -96.903794) (xy 285.278576 -96.814894) (xy 285.234126 -96.814894)
			(xy 285.234126 -97.213674) (xy 285.278576 -97.213674)
		)
		(stroke
			(width 0)
			(type solid)
		)
		(fill yes)
		(layer "In4.Cu")
		(net "M_E_DQ<57>")
	)
	(gr_poly
		(pts
			(xy 285.484062 -56.701944) (xy 285.439612 -56.701944) (xy 285.269432 -56.790844) (xy 285.269432 -57.011824)
			(xy 285.439612 -57.100724) (xy 285.484062 -57.100724)
		)
		(stroke
			(width 0)
			(type solid)
		)
		(fill yes)
		(layer "In4.Cu")
		(net "M_B_DQS_DP<16>")
	)
	(gr_poly
		(pts
			(xy 285.484062 -55.711344) (xy 285.439612 -55.711344) (xy 285.269432 -55.800244) (xy 285.269432 -56.021224)
			(xy 285.439612 -56.110124) (xy 285.484062 -56.110124)
		)
		(stroke
			(width 0)
			(type solid)
		)
		(fill yes)
		(layer "In4.Cu")
		(net "M_B_DQS_DP<16>")
	)
	(gr_poly
		(pts
			(xy 285.484062 -54.720744) (xy 285.439612 -54.720744) (xy 285.269432 -54.809644) (xy 285.269432 -55.030624)
			(xy 285.439612 -55.119524) (xy 285.484062 -55.119524)
		)
		(stroke
			(width 0)
			(type solid)
		)
		(fill yes)
		(layer "In4.Cu")
		(net "M_B_DQS_DP<16>")
	)
	(gr_poly
		(pts
			(xy 285.484062 -53.730144) (xy 285.439612 -53.730144) (xy 285.269432 -53.819044) (xy 285.269432 -54.040024)
			(xy 285.439612 -54.128924) (xy 285.484062 -54.128924)
		)
		(stroke
			(width 0)
			(type solid)
		)
		(fill yes)
		(layer "In4.Cu")
		(net "M_B_DQS_DP<16>")
	)
	(gr_poly
		(pts
			(xy 285.642558 -52.137056) (xy 285.651194 -51.945286) (xy 285.632398 -51.9049) (xy 285.27121 -52.073556)
			(xy 285.290006 -52.113688) (xy 285.442406 -52.230528)
		)
		(stroke
			(width 0)
			(type solid)
		)
		(fill yes)
		(layer "In4.Cu")
		(net "M_B_DQ<57>")
	)
	(gr_poly
		(pts
			(xy 285.65856 -52.472082) (xy 285.620206 -52.449984) (xy 285.428436 -52.441856) (xy 285.317946 -52.633118)
			(xy 285.420816 -52.79517) (xy 285.459424 -52.817522)
		)
		(stroke
			(width 0)
			(type solid)
		)
		(fill yes)
		(layer "In4.Cu")
		(net "M_B_DQS_DP<16>")
	)
	(gr_poly
		(pts
			(xy 285.67761 -48.032162) (xy 285.67761 -47.803562) (xy 285.48457 -47.714662) (xy 285.44012 -47.714662)
			(xy 285.44012 -48.121062) (xy 285.48457 -48.121062)
		)
		(stroke
			(width 0)
			(type solid)
		)
		(fill yes)
		(layer "In4.Cu")
		(net "M_C_DQ<43>")
	)
	(gr_poly
		(pts
			(xy 285.768542 -104.730804) (xy 285.724092 -104.730804) (xy 285.553912 -104.819704) (xy 285.553912 -105.040684)
			(xy 285.724092 -105.129584) (xy 285.768542 -105.129584)
		)
		(stroke
			(width 0)
			(type solid)
		)
		(fill yes)
		(layer "In4.Cu")
		(net "M_E_DQ<56>")
	)
	(gr_poly
		(pts
			(xy 285.768542 -103.740204) (xy 285.724092 -103.740204) (xy 285.553912 -103.829104) (xy 285.553912 -104.050084)
			(xy 285.724092 -104.138984) (xy 285.768542 -104.138984)
		)
		(stroke
			(width 0)
			(type solid)
		)
		(fill yes)
		(layer "In4.Cu")
		(net "M_E_DQ<56>")
	)
	(gr_poly
		(pts
			(xy 285.768542 -101.759004) (xy 285.724092 -101.759004) (xy 285.553912 -101.847904) (xy 285.553912 -102.068884)
			(xy 285.724092 -102.157784) (xy 285.768542 -102.157784)
		)
		(stroke
			(width 0)
			(type solid)
		)
		(fill yes)
		(layer "In4.Cu")
		(net "M_E_DQS_DP<16>")
	)
	(gr_poly
		(pts
			(xy 285.768542 -100.768404) (xy 285.724092 -100.768404) (xy 285.553912 -100.857304) (xy 285.553912 -101.078284)
			(xy 285.724092 -101.167184) (xy 285.768542 -101.167184)
		)
		(stroke
			(width 0)
			(type solid)
		)
		(fill yes)
		(layer "In4.Cu")
		(net "M_E_DQS_DP<16>")
	)
	(gr_poly
		(pts
			(xy 285.768542 -99.777804) (xy 285.724092 -99.777804) (xy 285.553912 -99.866704) (xy 285.553912 -100.087684)
			(xy 285.724092 -100.176584) (xy 285.768542 -100.176584)
		)
		(stroke
			(width 0)
			(type solid)
		)
		(fill yes)
		(layer "In4.Cu")
		(net "M_E_DQS_DP<16>")
	)
	(gr_poly
		(pts
			(xy 285.768542 -98.787204) (xy 285.724092 -98.787204) (xy 285.553912 -98.876104) (xy 285.553912 -99.097084)
			(xy 285.724092 -99.185984) (xy 285.768542 -99.185984)
		)
		(stroke
			(width 0)
			(type solid)
		)
		(fill yes)
		(layer "In4.Cu")
		(net "M_E_DQS_DP<16>")
	)
	(gr_poly
		(pts
			(xy 285.768542 -97.805494) (xy 285.724092 -97.805494) (xy 285.553912 -97.894394) (xy 285.553912 -98.115374)
			(xy 285.724092 -98.204274) (xy 285.768542 -98.204274)
		)
		(stroke
			(width 0)
			(type solid)
		)
		(fill yes)
		(layer "In4.Cu")
		(net "M_E_DQS_DP<16>")
	)
	(gr_poly
		(pts
			(xy 285.768542 -96.814894) (xy 285.724092 -96.814894) (xy 285.553912 -96.903794) (xy 285.553912 -97.124774)
			(xy 285.724092 -97.213674) (xy 285.768542 -97.213674)
		)
		(stroke
			(width 0)
			(type solid)
		)
		(fill yes)
		(layer "In4.Cu")
		(net "M_E_DQS_DP<16>")
	)
	(gr_poly
		(pts
			(xy 285.768542 -95.824294) (xy 285.724092 -95.824294) (xy 285.553912 -95.913194) (xy 285.553912 -96.134174)
			(xy 285.724092 -96.223074) (xy 285.768542 -96.223074)
		)
		(stroke
			(width 0)
			(type solid)
		)
		(fill yes)
		(layer "In4.Cu")
		(net "M_E_DQS_DP<16>")
	)
	(gr_poly
		(pts
			(xy 285.768542 -94.833694) (xy 285.724092 -94.833694) (xy 285.553912 -94.922594) (xy 285.553912 -95.143574)
			(xy 285.724092 -95.232474) (xy 285.768542 -95.232474)
		)
		(stroke
			(width 0)
			(type solid)
		)
		(fill yes)
		(layer "In4.Cu")
		(net "M_E_DQS_DP<16>")
	)
	(gr_poly
		(pts
			(xy 285.94685 -58.268108) (xy 285.924498 -58.229754) (xy 285.762446 -58.126884) (xy 285.571184 -58.237374)
			(xy 285.579312 -58.429144) (xy 285.60141 -58.467752)
		)
		(stroke
			(width 0)
			(type solid)
		)
		(fill yes)
		(layer "In4.Cu")
		(net "M_B_DQS_DP<7>")
	)
	(gr_poly
		(pts
			(xy 285.999428 -105.979214) (xy 286.007556 -105.787444) (xy 285.816294 -105.676954) (xy 285.654242 -105.779824)
			(xy 285.63189 -105.818178) (xy 285.97733 -106.017822)
		)
		(stroke
			(width 0)
			(type solid)
		)
		(fill yes)
		(layer "In4.Cu")
		(net "M_E_DQ<61>")
	)
	(gr_poly
		(pts
			(xy 285.999682 -103.00716) (xy 286.007556 -102.81539) (xy 285.816294 -102.7049) (xy 285.654242 -102.80777)
			(xy 285.63189 -102.846378) (xy 285.97733 -103.045768)
		)
		(stroke
			(width 0)
			(type solid)
		)
		(fill yes)
		(layer "In4.Cu")
		(net "M_E_DQ<57>")
	)
	(gr_poly
		(pts
			(xy 286.022288 -56.504078) (xy 286.022288 -56.283098) (xy 285.852108 -56.194198) (xy 285.807658 -56.194198)
			(xy 285.807658 -56.592978) (xy 285.852108 -56.592978)
		)
		(stroke
			(width 0)
			(type solid)
		)
		(fill yes)
		(layer "In4.Cu")
		(net "M_B_DQS_DN<16>")
	)
	(gr_poly
		(pts
			(xy 286.022288 -55.513478) (xy 286.022288 -55.292498) (xy 285.852108 -55.203598) (xy 285.807658 -55.203598)
			(xy 285.807658 -55.602378) (xy 285.852108 -55.602378)
		)
		(stroke
			(width 0)
			(type solid)
		)
		(fill yes)
		(layer "In4.Cu")
		(net "M_B_DQS_DN<16>")
	)
	(gr_poly
		(pts
			(xy 286.022288 -54.522878) (xy 286.022288 -54.301898) (xy 285.852108 -54.212998) (xy 285.807658 -54.212998)
			(xy 285.807658 -54.611778) (xy 285.852108 -54.611778)
		)
		(stroke
			(width 0)
			(type solid)
		)
		(fill yes)
		(layer "In4.Cu")
		(net "M_B_DQS_DN<16>")
	)
	(gr_poly
		(pts
			(xy 286.022288 -53.532278) (xy 286.022288 -53.311298) (xy 285.852108 -53.222398) (xy 285.807658 -53.222398)
			(xy 285.807658 -53.621178) (xy 285.852108 -53.621178)
		)
		(stroke
			(width 0)
			(type solid)
		)
		(fill yes)
		(layer "In4.Cu")
		(net "M_B_DQS_DN<16>")
	)
	(gr_poly
		(pts
			(xy 286.203898 -106.573574) (xy 286.22625 -106.53522) (xy 285.88081 -106.33583) (xy 285.858712 -106.374184)
			(xy 285.850584 -106.565954) (xy 286.041846 -106.676444)
		)
		(stroke
			(width 0)
			(type solid)
		)
		(fill yes)
		(layer "In4.Cu")
		(net "M_E_DQ<60>")
	)
	(gr_poly
		(pts
			(xy 286.206692 -105.584498) (xy 286.229044 -105.546144) (xy 285.883858 -105.3465) (xy 285.861506 -105.385362)
			(xy 285.853378 -105.577132) (xy 286.044894 -105.687368)
		)
		(stroke
			(width 0)
			(type solid)
		)
		(fill yes)
		(layer "In4.Cu")
		(net "M_E_DQ<56>")
	)
	(gr_poly
		(pts
			(xy 286.206692 -102.612698) (xy 286.229044 -102.574344) (xy 285.883858 -102.3747) (xy 285.861506 -102.413562)
			(xy 285.853378 -102.605332) (xy 286.044894 -102.715568)
		)
		(stroke
			(width 0)
			(type solid)
		)
		(fill yes)
		(layer "In4.Cu")
		(net "M_E_DQS_DP<16>")
	)
	(gr_poly
		(pts
			(xy 286.306768 -98.610674) (xy 286.306768 -98.389694) (xy 286.136588 -98.300794) (xy 286.092138 -98.300794)
			(xy 286.092138 -98.699574) (xy 286.136588 -98.699574)
		)
		(stroke
			(width 0)
			(type solid)
		)
		(fill yes)
		(layer "In4.Cu")
		(net "M_E_DQS_DN<16>")
	)
	(gr_poly
		(pts
			(xy 286.306768 -97.620074) (xy 286.306768 -97.399094) (xy 286.136588 -97.310194) (xy 286.092138 -97.310194)
			(xy 286.092138 -97.708974) (xy 286.136588 -97.708974)
		)
		(stroke
			(width 0)
			(type solid)
		)
		(fill yes)
		(layer "In4.Cu")
		(net "M_E_DQS_DN<16>")
	)
	(gr_poly
		(pts
			(xy 286.306768 -96.629474) (xy 286.306768 -96.408494) (xy 286.136588 -96.319594) (xy 286.092138 -96.319594)
			(xy 286.092138 -96.718374) (xy 286.136588 -96.718374)
		)
		(stroke
			(width 0)
			(type solid)
		)
		(fill yes)
		(layer "In4.Cu")
		(net "M_E_DQS_DN<16>")
	)
	(gr_poly
		(pts
			(xy 286.306768 -95.638874) (xy 286.306768 -95.417894) (xy 286.136588 -95.328994) (xy 286.092138 -95.328994)
			(xy 286.092138 -95.727774) (xy 286.136588 -95.727774)
		)
		(stroke
			(width 0)
			(type solid)
		)
		(fill yes)
		(layer "In4.Cu")
		(net "M_E_DQS_DN<16>")
	)
	(gr_poly
		(pts
			(xy 286.306768 -94.648274) (xy 286.306768 -94.427294) (xy 286.136588 -94.338394) (xy 286.092138 -94.338394)
			(xy 286.092138 -94.737174) (xy 286.136588 -94.737174)
		)
		(stroke
			(width 0)
			(type solid)
		)
		(fill yes)
		(layer "In4.Cu")
		(net "M_E_DQS_DN<16>")
	)
	(gr_poly
		(pts
			(xy 286.307022 -104.563418) (xy 286.307022 -104.342438) (xy 286.136842 -104.253538) (xy 286.092392 -104.253538)
			(xy 286.092392 -104.652318) (xy 286.136842 -104.652318)
		)
		(stroke
			(width 0)
			(type solid)
		)
		(fill yes)
		(layer "In4.Cu")
		(net "M_E_DQ<57>")
	)
	(gr_poly
		(pts
			(xy 286.307022 -103.572818) (xy 286.307022 -103.351838) (xy 286.136842 -103.262938) (xy 286.092392 -103.262938)
			(xy 286.092392 -103.661718) (xy 286.136842 -103.661718)
		)
		(stroke
			(width 0)
			(type solid)
		)
		(fill yes)
		(layer "In4.Cu")
		(net "M_E_DQ<57>")
	)
	(gr_poly
		(pts
			(xy 286.307022 -101.591618) (xy 286.307022 -101.370638) (xy 286.136842 -101.281738) (xy 286.092392 -101.281738)
			(xy 286.092392 -101.680518) (xy 286.136842 -101.680518)
		)
		(stroke
			(width 0)
			(type solid)
		)
		(fill yes)
		(layer "In4.Cu")
		(net "M_E_DQS_DN<16>")
	)
	(gr_poly
		(pts
			(xy 286.307022 -100.601018) (xy 286.307022 -100.380038) (xy 286.136842 -100.291138) (xy 286.092392 -100.291138)
			(xy 286.092392 -100.689918) (xy 286.136842 -100.689918)
		)
		(stroke
			(width 0)
			(type solid)
		)
		(fill yes)
		(layer "In4.Cu")
		(net "M_E_DQS_DN<16>")
	)
	(gr_poly
		(pts
			(xy 286.307022 -99.610418) (xy 286.307022 -99.389438) (xy 286.136842 -99.300538) (xy 286.092392 -99.300538)
			(xy 286.092392 -99.699318) (xy 286.136842 -99.699318)
		)
		(stroke
			(width 0)
			(type solid)
		)
		(fill yes)
		(layer "In4.Cu")
		(net "M_E_DQS_DN<16>")
	)
	(gr_poly
		(pts
			(xy 286.342582 -57.184798) (xy 286.298132 -57.184798) (xy 286.127952 -57.273698) (xy 286.127952 -57.494678)
			(xy 286.298132 -57.583578) (xy 286.342582 -57.583578)
		)
		(stroke
			(width 0)
			(type solid)
		)
		(fill yes)
		(layer "In4.Cu")
		(net "M_B_DQS_DP<7>")
	)
	(gr_poly
		(pts
			(xy 286.342582 -56.194198) (xy 286.298132 -56.194198) (xy 286.127952 -56.283098) (xy 286.127952 -56.504078)
			(xy 286.298132 -56.592978) (xy 286.342582 -56.592978)
		)
		(stroke
			(width 0)
			(type solid)
		)
		(fill yes)
		(layer "In4.Cu")
		(net "M_B_DQS_DP<7>")
	)
	(gr_poly
		(pts
			(xy 286.342582 -55.203598) (xy 286.298132 -55.203598) (xy 286.127952 -55.292498) (xy 286.127952 -55.513478)
			(xy 286.298132 -55.602378) (xy 286.342582 -55.602378)
		)
		(stroke
			(width 0)
			(type solid)
		)
		(fill yes)
		(layer "In4.Cu")
		(net "M_B_DQS_DP<7>")
	)
	(gr_poly
		(pts
			(xy 286.342582 -54.212998) (xy 286.298132 -54.212998) (xy 286.127952 -54.301898) (xy 286.127952 -54.522878)
			(xy 286.298132 -54.611778) (xy 286.342582 -54.611778)
		)
		(stroke
			(width 0)
			(type solid)
		)
		(fill yes)
		(layer "In4.Cu")
		(net "M_B_DQS_DP<7>")
	)
	(gr_poly
		(pts
			(xy 286.516064 -52.96916) (xy 286.47771 -52.947062) (xy 286.28594 -52.938934) (xy 286.17545 -53.130196)
			(xy 286.27832 -53.292248) (xy 286.316928 -53.3146)
		)
		(stroke
			(width 0)
			(type solid)
		)
		(fill yes)
		(layer "In4.Cu")
		(net "M_B_DQS_DP<7>")
	)
	(gr_poly
		(pts
			(xy 286.579056 -60.505848) (xy 286.570928 -60.314078) (xy 286.54883 -60.27547) (xy 286.20339 -60.475114)
			(xy 286.225742 -60.513468) (xy 286.387794 -60.616338)
		)
		(stroke
			(width 0)
			(type solid)
		)
		(fill yes)
		(layer "In4.Cu")
		(net "M_B_DQ<59>")
	)
	(gr_poly
		(pts
			(xy 286.581342 -59.513978) (xy 286.573214 -59.322208) (xy 286.551116 -59.2836) (xy 286.205676 -59.483244)
			(xy 286.228028 -59.521598) (xy 286.39008 -59.624468)
		)
		(stroke
			(width 0)
			(type solid)
		)
		(fill yes)
		(layer "In4.Cu")
		(net "M_B_DQ<63>")
	)
	(gr_poly
		(pts
			(xy 286.582866 -52.578762) (xy 286.574738 -52.386992) (xy 286.55264 -52.348384) (xy 286.2072 -52.548028)
			(xy 286.229552 -52.586382) (xy 286.391604 -52.689252)
		)
		(stroke
			(width 0)
			(type solid)
		)
		(fill yes)
		(layer "In4.Cu")
		(net "M_B_DQS_DN<16>")
	)
	(gr_poly
		(pts
			(xy 286.627062 -104.250744) (xy 286.582612 -104.250744) (xy 286.412432 -104.339644) (xy 286.412432 -104.560624)
			(xy 286.582612 -104.649524) (xy 286.627062 -104.649524)
		)
		(stroke
			(width 0)
			(type solid)
		)
		(fill yes)
		(layer "In4.Cu")
		(net "M_E_DQS_DP<16>")
	)
	(gr_poly
		(pts
			(xy 286.627062 -103.260144) (xy 286.582612 -103.260144) (xy 286.412432 -103.349044) (xy 286.412432 -103.570024)
			(xy 286.582612 -103.658924) (xy 286.627062 -103.658924)
		)
		(stroke
			(width 0)
			(type solid)
		)
		(fill yes)
		(layer "In4.Cu")
		(net "M_E_DQS_DP<16>")
	)
	(gr_poly
		(pts
			(xy 286.627062 -101.278944) (xy 286.582612 -101.278944) (xy 286.412432 -101.367844) (xy 286.412432 -101.588824)
			(xy 286.582612 -101.677724) (xy 286.627062 -101.677724)
		)
		(stroke
			(width 0)
			(type solid)
		)
		(fill yes)
		(layer "In4.Cu")
		(net "M_E_DQS_DN<7>")
	)
	(gr_poly
		(pts
			(xy 286.627062 -100.288344) (xy 286.582612 -100.288344) (xy 286.412432 -100.377244) (xy 286.412432 -100.598224)
			(xy 286.582612 -100.687124) (xy 286.627062 -100.687124)
		)
		(stroke
			(width 0)
			(type solid)
		)
		(fill yes)
		(layer "In4.Cu")
		(net "M_E_DQS_DN<7>")
	)
	(gr_poly
		(pts
			(xy 286.627062 -99.297744) (xy 286.582612 -99.297744) (xy 286.412432 -99.386644) (xy 286.412432 -99.607624)
			(xy 286.582612 -99.696524) (xy 286.627062 -99.696524)
		)
		(stroke
			(width 0)
			(type solid)
		)
		(fill yes)
		(layer "In4.Cu")
		(net "M_E_DQS_DN<7>")
	)
	(gr_poly
		(pts
			(xy 286.627062 -98.301302) (xy 286.582612 -98.301302) (xy 286.412432 -98.390202) (xy 286.412432 -98.611182)
			(xy 286.582612 -98.700082) (xy 286.627062 -98.700082)
		)
		(stroke
			(width 0)
			(type solid)
		)
		(fill yes)
		(layer "In4.Cu")
		(net "M_E_DQS_DN<7>")
	)
	(gr_poly
		(pts
			(xy 286.627062 -97.310702) (xy 286.582612 -97.310702) (xy 286.412432 -97.399602) (xy 286.412432 -97.620582)
			(xy 286.582612 -97.709482) (xy 286.627062 -97.709482)
		)
		(stroke
			(width 0)
			(type solid)
		)
		(fill yes)
		(layer "In4.Cu")
		(net "M_E_DQS_DN<7>")
	)
	(gr_poly
		(pts
			(xy 286.80537 -59.754008) (xy 286.783018 -59.715654) (xy 286.620966 -59.612784) (xy 286.429704 -59.723274)
			(xy 286.437832 -59.915044) (xy 286.45993 -59.953652)
		)
		(stroke
			(width 0)
			(type solid)
		)
		(fill yes)
		(layer "In4.Cu")
		(net "M_B_DQ<58>")
	)
	(gr_poly
		(pts
			(xy 286.853884 -102.509574) (xy 286.862012 -102.317804) (xy 286.670496 -102.207568) (xy 286.508698 -102.310438)
			(xy 286.486346 -102.348792) (xy 286.831786 -102.548182)
		)
		(stroke
			(width 0)
			(type solid)
		)
		(fill yes)
		(layer "In4.Cu")
		(net "M_E_DQS_DN<16>")
	)
	(gr_poly
		(pts
			(xy 286.859218 -105.48493) (xy 286.867346 -105.29316) (xy 286.676084 -105.18267) (xy 286.514032 -105.28554)
			(xy 286.49168 -105.323894) (xy 286.83712 -105.523538)
		)
		(stroke
			(width 0)
			(type solid)
		)
		(fill yes)
		(layer "In4.Cu")
		(net "M_E_DQ<57>")
	)
	(gr_poly
		(pts
			(xy 286.860742 -106.475784) (xy 286.86887 -106.284014) (xy 286.677608 -106.173524) (xy 286.515556 -106.276394)
			(xy 286.493204 -106.314748) (xy 286.838644 -106.514138)
		)
		(stroke
			(width 0)
			(type solid)
		)
		(fill yes)
		(layer "In4.Cu")
		(net "M_E_DQ<61>")
	)
	(gr_poly
		(pts
			(xy 286.863028 -50.79238) (xy 286.831532 -50.761138) (xy 286.632142 -50.687478) (xy 286.470598 -50.849022)
			(xy 286.544258 -51.048412) (xy 286.5755 -51.079908)
		)
		(stroke
			(width 0)
			(type solid)
		)
		(fill yes)
		(layer "In4.Cu")
		(net "M_B_DQ<56>")
	)
	(gr_poly
		(pts
			(xy 286.880808 -57.011824) (xy 286.880808 -56.790844) (xy 286.710628 -56.701944) (xy 286.666178 -56.701944)
			(xy 286.666178 -57.100724) (xy 286.710628 -57.100724)
		)
		(stroke
			(width 0)
			(type solid)
		)
		(fill yes)
		(layer "In4.Cu")
		(net "M_B_DQS_DN<7>")
	)
	(gr_poly
		(pts
			(xy 286.880808 -56.021224) (xy 286.880808 -55.800244) (xy 286.710628 -55.711344) (xy 286.666178 -55.711344)
			(xy 286.666178 -56.110124) (xy 286.710628 -56.110124)
		)
		(stroke
			(width 0)
			(type solid)
		)
		(fill yes)
		(layer "In4.Cu")
		(net "M_B_DQS_DN<7>")
	)
	(gr_poly
		(pts
			(xy 286.880808 -55.030624) (xy 286.880808 -54.809644) (xy 286.710628 -54.720744) (xy 286.666178 -54.720744)
			(xy 286.666178 -55.119524) (xy 286.710628 -55.119524)
		)
		(stroke
			(width 0)
			(type solid)
		)
		(fill yes)
		(layer "In4.Cu")
		(net "M_B_DQS_DN<7>")
	)
	(gr_poly
		(pts
			(xy 286.880808 -54.033674) (xy 286.880808 -53.812694) (xy 286.710628 -53.723794) (xy 286.666178 -53.723794)
			(xy 286.666178 -54.122574) (xy 286.710628 -54.122574)
		)
		(stroke
			(width 0)
			(type solid)
		)
		(fill yes)
		(layer "In4.Cu")
		(net "M_B_DQS_DN<7>")
	)
	(gr_poly
		(pts
			(xy 287.063688 -106.078782) (xy 287.08604 -106.040428) (xy 286.7406 -105.840784) (xy 286.718502 -105.879392)
			(xy 286.710374 -106.071162) (xy 286.901636 -106.181652)
		)
		(stroke
			(width 0)
			(type solid)
		)
		(fill yes)
		(layer "In4.Cu")
		(net "M_E_DQ<56>")
	)
	(gr_poly
		(pts
			(xy 287.069022 -105.091484) (xy 287.091374 -105.05313) (xy 286.746188 -104.853486) (xy 286.723836 -104.892348)
			(xy 286.715708 -105.084118) (xy 286.907224 -105.194354)
		)
		(stroke
			(width 0)
			(type solid)
		)
		(fill yes)
		(layer "In4.Cu")
		(net "M_E_DQS_DP<16>")
	)
	(gr_poly
		(pts
			(xy 287.069022 -102.119684) (xy 287.091374 -102.08133) (xy 286.746188 -101.881686) (xy 286.723836 -101.920548)
			(xy 286.715708 -102.112318) (xy 286.907224 -102.222554)
		)
		(stroke
			(width 0)
			(type solid)
		)
		(fill yes)
		(layer "In4.Cu")
		(net "M_E_DQS_DN<7>")
	)
	(gr_poly
		(pts
			(xy 287.082484 -93.87459) (xy 287.041844 -93.85681) (xy 286.850074 -93.869002) (xy 286.760412 -94.070932)
			(xy 286.880046 -94.2213) (xy 286.920686 -94.23908)
		)
		(stroke
			(width 0)
			(type solid)
		)
		(fill yes)
		(layer "In4.Cu")
		(net "M_E_DQ<62>")
	)
	(gr_poly
		(pts
			(xy 287.102296 -51.157632) (xy 287.028636 -50.958242) (xy 286.997394 -50.926746) (xy 286.709866 -51.214274)
			(xy 286.741362 -51.245516) (xy 286.940752 -51.319176)
		)
		(stroke
			(width 0)
			(type solid)
		)
		(fill yes)
		(layer "In4.Cu")
		(net "M_B_DQ<57>")
	)
	(gr_poly
		(pts
			(xy 287.155128 -95.153988) (xy 287.15589 -94.933008) (xy 286.985964 -94.8436) (xy 286.941514 -94.8436)
			(xy 286.940244 -95.24238) (xy 286.984694 -95.24238)
		)
		(stroke
			(width 0)
			(type solid)
		)
		(fill yes)
		(layer "In4.Cu")
		(net "M_E_DQ<62>")
	)
	(gr_poly
		(pts
			(xy 287.165288 -104.052878) (xy 287.165288 -103.831898) (xy 286.995108 -103.742998) (xy 286.950658 -103.742998)
			(xy 286.950658 -104.141778) (xy 286.995108 -104.141778)
		)
		(stroke
			(width 0)
			(type solid)
		)
		(fill yes)
		(layer "In4.Cu")
		(net "M_E_DQS_DN<16>")
	)
	(gr_poly
		(pts
			(xy 287.165288 -103.062278) (xy 287.165288 -102.841298) (xy 286.995108 -102.752398) (xy 286.950658 -102.752398)
			(xy 286.950658 -103.151178) (xy 286.995108 -103.151178)
		)
		(stroke
			(width 0)
			(type solid)
		)
		(fill yes)
		(layer "In4.Cu")
		(net "M_E_DQS_DN<16>")
	)
	(gr_poly
		(pts
			(xy 287.165288 -101.081078) (xy 287.165288 -100.860098) (xy 286.995108 -100.771198) (xy 286.950658 -100.771198)
			(xy 286.950658 -101.169978) (xy 286.995108 -101.169978)
		)
		(stroke
			(width 0)
			(type solid)
		)
		(fill yes)
		(layer "In4.Cu")
		(net "M_E_DQS_DP<7>")
	)
	(gr_poly
		(pts
			(xy 287.165288 -100.090478) (xy 287.165288 -99.869498) (xy 286.995108 -99.780598) (xy 286.950658 -99.780598)
			(xy 286.950658 -100.179378) (xy 286.995108 -100.179378)
		)
		(stroke
			(width 0)
			(type solid)
		)
		(fill yes)
		(layer "In4.Cu")
		(net "M_E_DQS_DP<7>")
	)
	(gr_poly
		(pts
			(xy 287.165288 -99.106482) (xy 287.165288 -98.885502) (xy 286.995108 -98.796602) (xy 286.950658 -98.796602)
			(xy 286.950658 -99.195382) (xy 286.995108 -99.195382)
		)
		(stroke
			(width 0)
			(type solid)
		)
		(fill yes)
		(layer "In4.Cu")
		(net "M_E_DQS_DP<7>")
	)
	(gr_poly
		(pts
			(xy 287.165288 -98.115882) (xy 287.165288 -97.894902) (xy 286.995108 -97.806002) (xy 286.950658 -97.806002)
			(xy 286.950658 -98.204782) (xy 286.995108 -98.204782)
		)
		(stroke
			(width 0)
			(type solid)
		)
		(fill yes)
		(layer "In4.Cu")
		(net "M_E_DQS_DP<7>")
	)
	(gr_poly
		(pts
			(xy 287.165288 -97.125282) (xy 287.165288 -96.904302) (xy 286.995108 -96.815402) (xy 286.950658 -96.815402)
			(xy 286.950658 -97.214182) (xy 286.995108 -97.214182)
		)
		(stroke
			(width 0)
			(type solid)
		)
		(fill yes)
		(layer "In4.Cu")
		(net "M_E_DQS_DP<7>")
	)
	(gr_poly
		(pts
			(xy 287.201102 -57.692544) (xy 287.156652 -57.692544) (xy 286.986472 -57.781444) (xy 286.986472 -58.002424)
			(xy 287.156652 -58.091324) (xy 287.201102 -58.091324)
		)
		(stroke
			(width 0)
			(type solid)
		)
		(fill yes)
		(layer "In4.Cu")
		(net "M_B_DQ<62>")
	)
	(gr_poly
		(pts
			(xy 287.201102 -56.701944) (xy 287.156652 -56.701944) (xy 286.986472 -56.790844) (xy 286.986472 -57.011824)
			(xy 287.156652 -57.100724) (xy 287.201102 -57.100724)
		)
		(stroke
			(width 0)
			(type solid)
		)
		(fill yes)
		(layer "In4.Cu")
		(net "M_B_DQ<62>")
	)
	(gr_poly
		(pts
			(xy 287.201102 -55.711344) (xy 287.156652 -55.711344) (xy 286.986472 -55.800244) (xy 286.986472 -56.021224)
			(xy 287.156652 -56.110124) (xy 287.201102 -56.110124)
		)
		(stroke
			(width 0)
			(type solid)
		)
		(fill yes)
		(layer "In4.Cu")
		(net "M_B_DQ<62>")
	)
	(gr_poly
		(pts
			(xy 287.201102 -54.720744) (xy 287.156652 -54.720744) (xy 286.986472 -54.809644) (xy 286.986472 -55.030624)
			(xy 287.156652 -55.119524) (xy 287.201102 -55.119524)
		)
		(stroke
			(width 0)
			(type solid)
		)
		(fill yes)
		(layer "In4.Cu")
		(net "M_B_DQ<62>")
	)
	(gr_poly
		(pts
			(xy 287.201102 -53.730144) (xy 287.156652 -53.730144) (xy 286.986472 -53.819044) (xy 286.986472 -54.040024)
			(xy 287.156652 -54.128924) (xy 287.201102 -54.128924)
		)
		(stroke
			(width 0)
			(type solid)
		)
		(fill yes)
		(layer "In4.Cu")
		(net "M_B_DQ<62>")
	)
	(gr_poly
		(pts
			(xy 287.427924 -53.08219) (xy 287.419796 -52.89042) (xy 287.397698 -52.851812) (xy 287.052258 -53.051456)
			(xy 287.07461 -53.08981) (xy 287.236662 -53.19268)
		)
		(stroke
			(width 0)
			(type solid)
		)
		(fill yes)
		(layer "In4.Cu")
		(net "M_B_DQS_DN<7>")
	)
	(gr_poly
		(pts
			(xy 287.437576 -60.010548) (xy 287.429448 -59.818778) (xy 287.40735 -59.78017) (xy 287.06191 -59.979814)
			(xy 287.084262 -60.018168) (xy 287.246314 -60.121038)
		)
		(stroke
			(width 0)
			(type solid)
		)
		(fill yes)
		(layer "In4.Cu")
		(net "M_B_DQ<59>")
	)
	(gr_poly
		(pts
			(xy 287.485582 -103.742998) (xy 287.441132 -103.742998) (xy 287.270952 -103.831898) (xy 287.270952 -104.052878)
			(xy 287.441132 -104.141778) (xy 287.485582 -104.141778)
		)
		(stroke
			(width 0)
			(type solid)
		)
		(fill yes)
		(layer "In4.Cu")
		(net "M_E_DQS_DN<7>")
	)
	(gr_poly
		(pts
			(xy 287.485582 -102.752398) (xy 287.441132 -102.752398) (xy 287.270952 -102.841298) (xy 287.270952 -103.062278)
			(xy 287.441132 -103.151178) (xy 287.485582 -103.151178)
		)
		(stroke
			(width 0)
			(type solid)
		)
		(fill yes)
		(layer "In4.Cu")
		(net "M_E_DQS_DN<7>")
	)
	(gr_poly
		(pts
			(xy 287.485582 -100.771198) (xy 287.441132 -100.771198) (xy 287.270952 -100.860098) (xy 287.270952 -101.081078)
			(xy 287.441132 -101.169978) (xy 287.485582 -101.169978)
		)
		(stroke
			(width 0)
			(type solid)
		)
		(fill yes)
		(layer "In4.Cu")
		(net "M_E_DQ<62>")
	)
	(gr_poly
		(pts
			(xy 287.485582 -99.780598) (xy 287.441132 -99.780598) (xy 287.270952 -99.869498) (xy 287.270952 -100.090478)
			(xy 287.441132 -100.179378) (xy 287.485582 -100.179378)
		)
		(stroke
			(width 0)
			(type solid)
		)
		(fill yes)
		(layer "In4.Cu")
		(net "M_E_DQ<62>")
	)
	(gr_poly
		(pts
			(xy 287.485582 -97.805494) (xy 287.441132 -97.805494) (xy 287.270952 -97.894394) (xy 287.270952 -98.115374)
			(xy 287.441132 -98.204274) (xy 287.485582 -98.204274)
		)
		(stroke
			(width 0)
			(type solid)
		)
		(fill yes)
		(layer "In4.Cu")
		(net "M_E_DQ<62>")
	)
	(gr_poly
		(pts
			(xy 287.485582 -96.814894) (xy 287.441132 -96.814894) (xy 287.270952 -96.903794) (xy 287.270952 -97.124774)
			(xy 287.441132 -97.213674) (xy 287.485582 -97.213674)
		)
		(stroke
			(width 0)
			(type solid)
		)
		(fill yes)
		(layer "In4.Cu")
		(net "M_E_DQ<62>")
	)
	(gr_poly
		(pts
			(xy 287.485836 -98.796094) (xy 287.441386 -98.796094) (xy 287.271206 -98.884994) (xy 287.271206 -99.105974)
			(xy 287.441386 -99.194874) (xy 287.485836 -99.194874)
		)
		(stroke
			(width 0)
			(type solid)
		)
		(fill yes)
		(layer "In4.Cu")
		(net "M_E_DQ<62>")
	)
	(gr_poly
		(pts
			(xy 287.66008 -59.26074) (xy 287.637728 -59.222386) (xy 287.475676 -59.119516) (xy 287.284414 -59.230006)
			(xy 287.292542 -59.421776) (xy 287.31464 -59.460384)
		)
		(stroke
			(width 0)
			(type solid)
		)
		(fill yes)
		(layer "In4.Cu")
		(net "M_B_DQ<58>")
	)
	(gr_poly
		(pts
			(xy 287.708848 -95.986854) (xy 287.775142 -95.806514) (xy 287.626806 -95.642938) (xy 287.440878 -95.691452)
			(xy 287.408112 -95.72117) (xy 287.675828 -96.016572)
		)
		(stroke
			(width 0)
			(type solid)
		)
		(fill yes)
		(layer "In4.Cu")
		(net "M_E_DQ<63>")
	)
	(gr_poly
		(pts
			(xy 287.71596 -102.016306) (xy 287.724088 -101.824536) (xy 287.532826 -101.7143) (xy 287.370774 -101.81717)
			(xy 287.348676 -101.855524) (xy 287.694116 -102.054914)
		)
		(stroke
			(width 0)
			(type solid)
		)
		(fill yes)
		(layer "In4.Cu")
		(net "M_E_DQS_DP<7>")
	)
	(gr_poly
		(pts
			(xy 287.716214 -104.988614) (xy 287.724342 -104.796844) (xy 287.53308 -104.686354) (xy 287.371028 -104.789224)
			(xy 287.348676 -104.827578) (xy 287.694116 -105.027222)
		)
		(stroke
			(width 0)
			(type solid)
		)
		(fill yes)
		(layer "In4.Cu")
		(net "M_E_DQS_DN<16>")
	)
	(gr_poly
		(pts
			(xy 287.716722 -105.979214) (xy 287.72485 -105.787444) (xy 287.533588 -105.676954) (xy 287.371536 -105.779824)
			(xy 287.349184 -105.818178) (xy 287.694624 -106.017822)
		)
		(stroke
			(width 0)
			(type solid)
		)
		(fill yes)
		(layer "In4.Cu")
		(net "M_E_DQ<57>")
	)
	(gr_poly
		(pts
			(xy 287.739328 -57.494678) (xy 287.739328 -57.273698) (xy 287.569148 -57.184798) (xy 287.524698 -57.184798)
			(xy 287.524698 -57.583578) (xy 287.569148 -57.583578)
		)
		(stroke
			(width 0)
			(type solid)
		)
		(fill yes)
		(layer "In4.Cu")
		(net "M_B_DQ<63>")
	)
	(gr_poly
		(pts
			(xy 287.739328 -56.504078) (xy 287.739328 -56.283098) (xy 287.569148 -56.194198) (xy 287.524698 -56.194198)
			(xy 287.524698 -56.592978) (xy 287.569148 -56.592978)
		)
		(stroke
			(width 0)
			(type solid)
		)
		(fill yes)
		(layer "In4.Cu")
		(net "M_B_DQ<63>")
	)
	(gr_poly
		(pts
			(xy 287.739328 -55.513478) (xy 287.739328 -55.292498) (xy 287.569148 -55.203598) (xy 287.524698 -55.203598)
			(xy 287.524698 -55.602378) (xy 287.569148 -55.602378)
		)
		(stroke
			(width 0)
			(type solid)
		)
		(fill yes)
		(layer "In4.Cu")
		(net "M_B_DQ<63>")
	)
	(gr_poly
		(pts
			(xy 287.739328 -54.522878) (xy 287.739328 -54.301898) (xy 287.569148 -54.212998) (xy 287.524698 -54.212998)
			(xy 287.524698 -54.611778) (xy 287.569148 -54.611778)
		)
		(stroke
			(width 0)
			(type solid)
		)
		(fill yes)
		(layer "In4.Cu")
		(net "M_B_DQ<63>")
	)
	(gr_poly
		(pts
			(xy 287.833054 -94.653354) (xy 287.833054 -94.432374) (xy 287.662874 -94.343474) (xy 287.618424 -94.343474)
			(xy 287.618424 -94.742254) (xy 287.662874 -94.742254)
		)
		(stroke
			(width 0)
			(type solid)
		)
		(fill yes)
		(layer "In4.Cu")
		(net "M_E_DQ<58>")
	)
	(gr_poly
		(pts
			(xy 287.833054 -93.662754) (xy 287.833054 -93.441774) (xy 287.662874 -93.352874) (xy 287.618424 -93.352874)
			(xy 287.618424 -93.751654) (xy 287.662874 -93.751654)
		)
		(stroke
			(width 0)
			(type solid)
		)
		(fill yes)
		(layer "In4.Cu")
		(net "M_E_DQ<58>")
	)
	(gr_poly
		(pts
			(xy 287.911794 -51.091846) (xy 287.880298 -51.060604) (xy 287.680908 -50.986944) (xy 287.519364 -51.148488)
			(xy 287.593024 -51.347878) (xy 287.624266 -51.379374)
		)
		(stroke
			(width 0)
			(type solid)
		)
		(fill yes)
		(layer "In4.Cu")
		(net "M_B_DQS_DP<16>")
	)
	(gr_poly
		(pts
			(xy 287.923732 -105.584498) (xy 287.946084 -105.546144) (xy 287.600644 -105.3465) (xy 287.578546 -105.385108)
			(xy 287.570418 -105.576878) (xy 287.76168 -105.687368)
		)
		(stroke
			(width 0)
			(type solid)
		)
		(fill yes)
		(layer "In4.Cu")
		(net "M_E_DQS_DP<16>")
	)
	(gr_poly
		(pts
			(xy 287.923986 -104.594152) (xy 287.946338 -104.555798) (xy 287.600898 -104.356154) (xy 287.5788 -104.395016)
			(xy 287.570672 -104.586786) (xy 287.761934 -104.697022)
		)
		(stroke
			(width 0)
			(type solid)
		)
		(fill yes)
		(layer "In4.Cu")
		(net "M_E_DQS_DN<7>")
	)
	(gr_poly
		(pts
			(xy 287.923986 -101.622352) (xy 287.946338 -101.583998) (xy 287.600898 -101.384354) (xy 287.5788 -101.423216)
			(xy 287.570672 -101.614986) (xy 287.761934 -101.725222)
		)
		(stroke
			(width 0)
			(type solid)
		)
		(fill yes)
		(layer "In4.Cu")
		(net "M_E_DQ<62>")
	)
	(gr_poly
		(pts
			(xy 288.023554 -96.629474) (xy 288.023554 -96.408494) (xy 287.853374 -96.319594) (xy 287.808924 -96.319594)
			(xy 287.808924 -96.718374) (xy 287.853374 -96.718374)
		)
		(stroke
			(width 0)
			(type solid)
		)
		(fill yes)
		(layer "In4.Cu")
		(net "M_E_DQ<63>")
	)
	(gr_poly
		(pts
			(xy 288.023808 -103.570024) (xy 288.023808 -103.349044) (xy 287.853628 -103.260144) (xy 287.809178 -103.260144)
			(xy 287.809178 -103.658924) (xy 287.853628 -103.658924)
		)
		(stroke
			(width 0)
			(type solid)
		)
		(fill yes)
		(layer "In4.Cu")
		(net "M_E_DQS_DP<7>")
	)
	(gr_poly
		(pts
			(xy 288.023808 -102.579424) (xy 288.023808 -102.358444) (xy 287.853628 -102.269544) (xy 287.809178 -102.269544)
			(xy 287.809178 -102.668324) (xy 287.853628 -102.668324)
		)
		(stroke
			(width 0)
			(type solid)
		)
		(fill yes)
		(layer "In4.Cu")
		(net "M_E_DQS_DP<7>")
	)
	(gr_poly
		(pts
			(xy 288.023808 -100.598224) (xy 288.023808 -100.377244) (xy 287.853628 -100.288344) (xy 287.809178 -100.288344)
			(xy 287.809178 -100.687124) (xy 287.853628 -100.687124)
		)
		(stroke
			(width 0)
			(type solid)
		)
		(fill yes)
		(layer "In4.Cu")
		(net "M_E_DQ<63>")
	)
	(gr_poly
		(pts
			(xy 288.023808 -99.607624) (xy 288.023808 -99.386644) (xy 287.853628 -99.297744) (xy 287.809178 -99.297744)
			(xy 287.809178 -99.696524) (xy 287.853628 -99.696524)
		)
		(stroke
			(width 0)
			(type solid)
		)
		(fill yes)
		(layer "In4.Cu")
		(net "M_E_DQ<63>")
	)
	(gr_poly
		(pts
			(xy 288.023808 -98.610674) (xy 288.023808 -98.389694) (xy 287.853628 -98.300794) (xy 287.809178 -98.300794)
			(xy 287.809178 -98.699574) (xy 287.853628 -98.699574)
		)
		(stroke
			(width 0)
			(type solid)
		)
		(fill yes)
		(layer "In4.Cu")
		(net "M_E_DQ<63>")
	)
	(gr_poly
		(pts
			(xy 288.023808 -97.620074) (xy 288.023808 -97.399094) (xy 287.853628 -97.310194) (xy 287.809178 -97.310194)
			(xy 287.809178 -97.708974) (xy 287.853628 -97.708974)
		)
		(stroke
			(width 0)
			(type solid)
		)
		(fill yes)
		(layer "In4.Cu")
		(net "M_E_DQ<63>")
	)
	(gr_poly
		(pts
			(xy 288.059622 -58.181748) (xy 288.015172 -58.181748) (xy 287.844992 -58.270648) (xy 287.844992 -58.491628)
			(xy 288.015172 -58.580528) (xy 288.059622 -58.580528)
		)
		(stroke
			(width 0)
			(type solid)
		)
		(fill yes)
		(layer "In4.Cu")
		(net "M_B_DQ<58>")
	)
	(gr_poly
		(pts
			(xy 288.059622 -57.184798) (xy 288.015172 -57.184798) (xy 287.844992 -57.273698) (xy 287.844992 -57.494678)
			(xy 288.015172 -57.583578) (xy 288.059622 -57.583578)
		)
		(stroke
			(width 0)
			(type solid)
		)
		(fill yes)
		(layer "In4.Cu")
		(net "M_B_DQ<58>")
	)
	(gr_poly
		(pts
			(xy 288.059622 -56.194198) (xy 288.015172 -56.194198) (xy 287.844992 -56.283098) (xy 287.844992 -56.504078)
			(xy 288.015172 -56.592978) (xy 288.059622 -56.592978)
		)
		(stroke
			(width 0)
			(type solid)
		)
		(fill yes)
		(layer "In4.Cu")
		(net "M_B_DQ<58>")
	)
	(gr_poly
		(pts
			(xy 288.059622 -55.203598) (xy 288.015172 -55.203598) (xy 287.844992 -55.292498) (xy 287.844992 -55.513478)
			(xy 288.015172 -55.602378) (xy 288.059622 -55.602378)
		)
		(stroke
			(width 0)
			(type solid)
		)
		(fill yes)
		(layer "In4.Cu")
		(net "M_B_DQ<58>")
	)
	(gr_poly
		(pts
			(xy 288.059622 -54.212998) (xy 288.015172 -54.212998) (xy 287.844992 -54.301898) (xy 287.844992 -54.522878)
			(xy 288.015172 -54.611778) (xy 288.059622 -54.611778)
		)
		(stroke
			(width 0)
			(type solid)
		)
		(fill yes)
		(layer "In4.Cu")
		(net "M_B_DQ<58>")
	)
	(gr_poly
		(pts
			(xy 288.15157 -51.457352) (xy 288.07791 -51.258216) (xy 288.046414 -51.22672) (xy 287.75914 -51.513994)
			(xy 287.790636 -51.54549) (xy 287.989772 -51.61915)
		)
		(stroke
			(width 0)
			(type solid)
		)
		(fill yes)
		(layer "In4.Cu")
		(net "M_B_DQS_DN<16>")
	)
	(gr_poly
		(pts
			(xy 288.298128 -59.514486) (xy 288.29 -59.322716) (xy 288.267902 -59.283854) (xy 287.922716 -59.483498)
			(xy 287.944814 -59.521852) (xy 288.106866 -59.624722)
		)
		(stroke
			(width 0)
			(type solid)
		)
		(fill yes)
		(layer "In4.Cu")
		(net "M_B_DQ<59>")
	)
	(gr_poly
		(pts
			(xy 288.299906 -53.569362) (xy 288.291778 -53.377592) (xy 288.26968 -53.338984) (xy 287.92424 -53.538628)
			(xy 287.946592 -53.576982) (xy 288.108644 -53.679852)
		)
		(stroke
			(width 0)
			(type solid)
		)
		(fill yes)
		(layer "In4.Cu")
		(net "M_B_DQ<63>")
	)
	(gr_poly
		(pts
			(xy 288.344102 -103.260144) (xy 288.299652 -103.260144) (xy 288.129472 -103.349044) (xy 288.129472 -103.570024)
			(xy 288.299652 -103.658924) (xy 288.344102 -103.658924)
		)
		(stroke
			(width 0)
			(type solid)
		)
		(fill yes)
		(layer "In4.Cu")
		(net "M_E_DQ<62>")
	)
	(gr_poly
		(pts
			(xy 288.344102 -102.269544) (xy 288.299652 -102.269544) (xy 288.129472 -102.358444) (xy 288.129472 -102.579424)
			(xy 288.299652 -102.668324) (xy 288.344102 -102.668324)
		)
		(stroke
			(width 0)
			(type solid)
		)
		(fill yes)
		(layer "In4.Cu")
		(net "M_E_DQ<62>")
	)
	(gr_poly
		(pts
			(xy 288.344102 -100.288344) (xy 288.299652 -100.288344) (xy 288.129472 -100.377244) (xy 288.129472 -100.598224)
			(xy 288.299652 -100.687124) (xy 288.344102 -100.687124)
		)
		(stroke
			(width 0)
			(type solid)
		)
		(fill yes)
		(layer "In4.Cu")
		(net "M_E_DQ<58>")
	)
	(gr_poly
		(pts
			(xy 288.344102 -99.297744) (xy 288.299652 -99.297744) (xy 288.129472 -99.386644) (xy 288.129472 -99.607624)
			(xy 288.299652 -99.696524) (xy 288.344102 -99.696524)
		)
		(stroke
			(width 0)
			(type solid)
		)
		(fill yes)
		(layer "In4.Cu")
		(net "M_E_DQ<58>")
	)
	(gr_poly
		(pts
			(xy 288.344102 -98.307144) (xy 288.299652 -98.307144) (xy 288.129472 -98.396044) (xy 288.129472 -98.617024)
			(xy 288.299652 -98.705924) (xy 288.344102 -98.705924)
		)
		(stroke
			(width 0)
			(type solid)
		)
		(fill yes)
		(layer "In4.Cu")
		(net "M_E_DQ<58>")
	)
	(gr_poly
		(pts
			(xy 288.344102 -97.316544) (xy 288.299652 -97.316544) (xy 288.129472 -97.405444) (xy 288.129472 -97.626424)
			(xy 288.299652 -97.715324) (xy 288.344102 -97.715324)
		)
		(stroke
			(width 0)
			(type solid)
		)
		(fill yes)
		(layer "In4.Cu")
		(net "M_E_DQ<58>")
	)
	(gr_poly
		(pts
			(xy 288.344102 -96.325944) (xy 288.299652 -96.325944) (xy 288.129472 -96.414844) (xy 288.129472 -96.635824)
			(xy 288.299652 -96.724724) (xy 288.344102 -96.724724)
		)
		(stroke
			(width 0)
			(type solid)
		)
		(fill yes)
		(layer "In4.Cu")
		(net "M_E_DQ<58>")
	)
	(gr_poly
		(pts
			(xy 288.5186 -52.82184) (xy 288.496248 -52.783486) (xy 288.334196 -52.680616) (xy 288.142934 -52.791106)
			(xy 288.151062 -52.982876) (xy 288.17316 -53.021484)
		)
		(stroke
			(width 0)
			(type solid)
		)
		(fill yes)
		(layer "In4.Cu")
		(net "M_B_DQ<62>")
	)
	(gr_poly
		(pts
			(xy 288.5313 -95.539052) (xy 288.616644 -95.36684) (xy 288.486596 -95.188278) (xy 288.296604 -95.216726)
			(xy 288.26079 -95.242888) (xy 288.495486 -95.565214)
		)
		(stroke
			(width 0)
			(type solid)
		)
		(fill yes)
		(layer "In4.Cu")
		(net "M_E_DQ<59>")
	)
	(gr_poly
		(pts
			(xy 288.570924 -101.518974) (xy 288.579052 -101.327204) (xy 288.387536 -101.216968) (xy 288.225738 -101.319838)
			(xy 288.203132 -101.358192) (xy 288.548572 -101.557836)
		)
		(stroke
			(width 0)
			(type solid)
		)
		(fill yes)
		(layer "In4.Cu")
		(net "M_E_DQ<63>")
	)
	(gr_poly
		(pts
			(xy 288.576258 -105.48493) (xy 288.584386 -105.29316) (xy 288.393124 -105.18267) (xy 288.231072 -105.28554)
			(xy 288.20872 -105.323894) (xy 288.55416 -105.523538)
		)
		(stroke
			(width 0)
			(type solid)
		)
		(fill yes)
		(layer "In4.Cu")
		(net "M_E_DQS_DN<16>")
	)
	(gr_poly
		(pts
			(xy 288.576258 -104.49433) (xy 288.584386 -104.30256) (xy 288.393124 -104.19207) (xy 288.231072 -104.29494)
			(xy 288.20872 -104.333294) (xy 288.55416 -104.532938)
		)
		(stroke
			(width 0)
			(type solid)
		)
		(fill yes)
		(layer "In4.Cu")
		(net "M_E_DQS_DP<7>")
	)
	(gr_poly
		(pts
			(xy 288.597848 -58.002424) (xy 288.597848 -57.781444) (xy 288.427668 -57.692544) (xy 288.383218 -57.692544)
			(xy 288.383218 -58.091324) (xy 288.427668 -58.091324)
		)
		(stroke
			(width 0)
			(type solid)
		)
		(fill yes)
		(layer "In4.Cu")
		(net "M_B_DQ<59>")
	)
	(gr_poly
		(pts
			(xy 288.597848 -57.011824) (xy 288.597848 -56.790844) (xy 288.427668 -56.701944) (xy 288.383218 -56.701944)
			(xy 288.383218 -57.100724) (xy 288.427668 -57.100724)
		)
		(stroke
			(width 0)
			(type solid)
		)
		(fill yes)
		(layer "In4.Cu")
		(net "M_B_DQ<59>")
	)
	(gr_poly
		(pts
			(xy 288.597848 -56.021224) (xy 288.597848 -55.800244) (xy 288.427668 -55.711344) (xy 288.383218 -55.711344)
			(xy 288.383218 -56.110124) (xy 288.427668 -56.110124)
		)
		(stroke
			(width 0)
			(type solid)
		)
		(fill yes)
		(layer "In4.Cu")
		(net "M_B_DQ<59>")
	)
	(gr_poly
		(pts
			(xy 288.597848 -55.030624) (xy 288.597848 -54.809644) (xy 288.427668 -54.720744) (xy 288.383218 -54.720744)
			(xy 288.383218 -55.119524) (xy 288.427668 -55.119524)
		)
		(stroke
			(width 0)
			(type solid)
		)
		(fill yes)
		(layer "In4.Cu")
		(net "M_B_DQ<59>")
	)
	(gr_poly
		(pts
			(xy 288.780728 -105.088182) (xy 288.80308 -105.049828) (xy 288.45764 -104.850184) (xy 288.435542 -104.889046)
			(xy 288.427414 -105.080816) (xy 288.618676 -105.191052)
		)
		(stroke
			(width 0)
			(type solid)
		)
		(fill yes)
		(layer "In4.Cu")
		(net "M_E_DQS_DN<7>")
	)
	(gr_poly
		(pts
			(xy 288.780728 -101.126036) (xy 288.802826 -101.087682) (xy 288.457386 -100.888292) (xy 288.435542 -100.926646)
			(xy 288.427414 -101.118416) (xy 288.618676 -101.228906)
		)
		(stroke
			(width 0)
			(type solid)
		)
		(fill yes)
		(layer "In4.Cu")
		(net "M_E_DQ<58>")
	)
	(gr_poly
		(pts
			(xy 288.882328 -103.062278) (xy 288.882328 -102.841298) (xy 288.712148 -102.752398) (xy 288.667698 -102.752398)
			(xy 288.667698 -103.151178) (xy 288.712148 -103.151178)
		)
		(stroke
			(width 0)
			(type solid)
		)
		(fill yes)
		(layer "In4.Cu")
		(net "M_E_DQ<63>")
	)
	(gr_poly
		(pts
			(xy 288.882328 -102.071678) (xy 288.882328 -101.850698) (xy 288.712148 -101.761798) (xy 288.667698 -101.761798)
			(xy 288.667698 -102.160578) (xy 288.712148 -102.160578)
		)
		(stroke
			(width 0)
			(type solid)
		)
		(fill yes)
		(layer "In4.Cu")
		(net "M_E_DQ<63>")
	)
	(gr_poly
		(pts
			(xy 288.882328 -100.096828) (xy 288.882328 -99.875848) (xy 288.712148 -99.786948) (xy 288.667698 -99.786948)
			(xy 288.667698 -100.185728) (xy 288.712148 -100.185728)
		)
		(stroke
			(width 0)
			(type solid)
		)
		(fill yes)
		(layer "In4.Cu")
		(net "M_E_DQ<59>")
	)
	(gr_poly
		(pts
			(xy 288.882328 -99.099878) (xy 288.882328 -98.878898) (xy 288.712148 -98.789998) (xy 288.667698 -98.789998)
			(xy 288.667698 -99.188778) (xy 288.712148 -99.188778)
		)
		(stroke
			(width 0)
			(type solid)
		)
		(fill yes)
		(layer "In4.Cu")
		(net "M_E_DQ<59>")
	)
	(gr_poly
		(pts
			(xy 288.882328 -98.109278) (xy 288.882328 -97.888298) (xy 288.712148 -97.799398) (xy 288.667698 -97.799398)
			(xy 288.667698 -98.198178) (xy 288.712148 -98.198178)
		)
		(stroke
			(width 0)
			(type solid)
		)
		(fill yes)
		(layer "In4.Cu")
		(net "M_E_DQ<59>")
	)
	(gr_poly
		(pts
			(xy 288.882328 -97.118678) (xy 288.882328 -96.897698) (xy 288.712148 -96.808798) (xy 288.667698 -96.808798)
			(xy 288.667698 -97.207578) (xy 288.712148 -97.207578)
		)
		(stroke
			(width 0)
			(type solid)
		)
		(fill yes)
		(layer "In4.Cu")
		(net "M_E_DQ<59>")
	)
	(gr_poly
		(pts
			(xy 288.882328 -96.128078) (xy 288.882328 -95.907098) (xy 288.712148 -95.818198) (xy 288.667698 -95.818198)
			(xy 288.667698 -96.216978) (xy 288.712148 -96.216978)
		)
		(stroke
			(width 0)
			(type solid)
		)
		(fill yes)
		(layer "In4.Cu")
		(net "M_E_DQ<59>")
	)
	(gr_poly
		(pts
			(xy 289.202622 -102.752398) (xy 289.158172 -102.752398) (xy 288.987992 -102.841298) (xy 288.987992 -103.062278)
			(xy 289.158172 -103.151178) (xy 289.202622 -103.151178)
		)
		(stroke
			(width 0)
			(type solid)
		)
		(fill yes)
		(layer "In4.Cu")
		(net "M_E_DQ<58>")
	)
	(gr_poly
		(pts
			(xy 289.202622 -101.761798) (xy 289.158172 -101.761798) (xy 288.987992 -101.850698) (xy 288.987992 -102.071678)
			(xy 289.158172 -102.160578) (xy 289.202622 -102.160578)
		)
		(stroke
			(width 0)
			(type solid)
		)
		(fill yes)
		(layer "In4.Cu")
		(net "M_E_DQ<58>")
	)
	(gr_poly
		(pts
			(xy 289.433254 -104.988614) (xy 289.441382 -104.796844) (xy 289.25012 -104.686354) (xy 289.088068 -104.789224)
			(xy 289.065716 -104.827578) (xy 289.411156 -105.027222)
		)
		(stroke
			(width 0)
			(type solid)
		)
		(fill yes)
		(layer "In4.Cu")
		(net "M_E_DQS_DP<7>")
	)
	(gr_poly
		(pts
			(xy 289.433254 -103.998014) (xy 289.441382 -103.806244) (xy 289.25012 -103.695754) (xy 289.088068 -103.798624)
			(xy 289.065716 -103.836978) (xy 289.411156 -104.036622)
		)
		(stroke
			(width 0)
			(type solid)
		)
		(fill yes)
		(layer "In4.Cu")
		(net "M_E_DQ<63>")
	)
	(gr_poly
		(pts
			(xy 289.434778 -101.026976) (xy 289.442906 -100.835206) (xy 289.251644 -100.724716) (xy 289.089592 -100.827586)
			(xy 289.06724 -100.86594) (xy 289.41268 -101.065584)
		)
		(stroke
			(width 0)
			(type solid)
		)
		(fill yes)
		(layer "In4.Cu")
		(net "M_E_DQ<59>")
	)
	(gr_poly
		(pts
			(xy 289.640772 -105.584498) (xy 289.663124 -105.546144) (xy 289.317684 -105.3465) (xy 289.295586 -105.385108)
			(xy 289.287458 -105.576878) (xy 289.47872 -105.687368)
		)
		(stroke
			(width 0)
			(type solid)
		)
		(fill yes)
		(layer "In4.Cu")
		(net "M_E_DQS_DN<7>")
	)
	(gr_poly
		(pts
			(xy 289.640772 -104.593898) (xy 289.663124 -104.555544) (xy 289.317684 -104.3559) (xy 289.295586 -104.394508)
			(xy 289.287458 -104.586278) (xy 289.47872 -104.696768)
		)
		(stroke
			(width 0)
			(type solid)
		)
		(fill yes)
		(layer "In4.Cu")
		(net "M_E_DQ<62>")
	)
	(gr_poly
		(pts
			(xy 289.641026 -103.603552) (xy 289.663124 -103.565198) (xy 289.317684 -103.365808) (xy 289.29584 -103.404416)
			(xy 289.287712 -103.596186) (xy 289.478974 -103.706422)
		)
		(stroke
			(width 0)
			(type solid)
		)
		(fill yes)
		(layer "In4.Cu")
		(net "M_E_DQ<58>")
	)
	(gr_poly
		(pts
			(xy 289.740594 -101.593396) (xy 289.740594 -101.372416) (xy 289.570414 -101.283516) (xy 289.525964 -101.283262)
			(xy 289.525964 -101.682296) (xy 289.570414 -101.682296)
		)
		(stroke
			(width 0)
			(type solid)
		)
		(fill yes)
		(layer "In4.Cu")
		(net "M_E_DQ<59>")
	)
	(gr_poly
		(pts
			(xy 289.740848 -102.579424) (xy 289.740848 -102.358444) (xy 289.570668 -102.269544) (xy 289.526218 -102.269544)
			(xy 289.526218 -102.668324) (xy 289.570668 -102.668324)
		)
		(stroke
			(width 0)
			(type solid)
		)
		(fill yes)
		(layer "In4.Cu")
		(net "M_E_DQ<59>")
	)
	(gr_poly
		(pts
			(xy 289.867594 -52.410106) (xy 289.836098 -52.378864) (xy 289.636708 -52.305204) (xy 289.475164 -52.466748)
			(xy 289.548824 -52.666138) (xy 289.580066 -52.697634)
		)
		(stroke
			(width 0)
			(type solid)
		)
		(fill yes)
		(layer "In4.Cu")
		(net "M_B_DQ<62>")
	)
	(gr_poly
		(pts
			(xy 290.10737 -52.775612) (xy 290.03371 -52.576476) (xy 290.002214 -52.54498) (xy 289.71494 -52.832254)
			(xy 289.746436 -52.86375) (xy 289.945572 -52.93741)
		)
		(stroke
			(width 0)
			(type solid)
		)
		(fill yes)
		(layer "In4.Cu")
		(net "M_B_DQ<63>")
	)
	(gr_poly
		(pts
			(xy 290.293298 -105.48493) (xy 290.301426 -105.29316) (xy 290.110164 -105.18267) (xy 289.948112 -105.28554)
			(xy 289.92576 -105.323894) (xy 290.2712 -105.523538)
		)
		(stroke
			(width 0)
			(type solid)
		)
		(fill yes)
		(layer "In4.Cu")
		(net "M_E_DQS_DP<7>")
	)
	(gr_poly
		(pts
			(xy 290.293298 -104.49433) (xy 290.301426 -104.30256) (xy 290.110164 -104.19207) (xy 289.948112 -104.29494)
			(xy 289.92576 -104.333294) (xy 290.2712 -104.532938)
		)
		(stroke
			(width 0)
			(type solid)
		)
		(fill yes)
		(layer "In4.Cu")
		(net "M_E_DQ<63>")
	)
	(gr_poly
		(pts
			(xy 290.293298 -103.50373) (xy 290.301426 -103.31196) (xy 290.110164 -103.20147) (xy 289.948112 -103.30434)
			(xy 289.92576 -103.342694) (xy 290.2712 -103.542338)
		)
		(stroke
			(width 0)
			(type solid)
		)
		(fill yes)
		(layer "In4.Cu")
		(net "M_E_DQ<59>")
	)
	(gr_poly
		(pts
			(xy 290.497768 -105.088182) (xy 290.52012 -105.049828) (xy 290.17468 -104.850184) (xy 290.152582 -104.888792)
			(xy 290.144454 -105.080562) (xy 290.335716 -105.191052)
		)
		(stroke
			(width 0)
			(type solid)
		)
		(fill yes)
		(layer "In4.Cu")
		(net "M_E_DQ<62>")
	)
	(gr_poly
		(pts
			(xy 290.497768 -104.097582) (xy 290.52012 -104.059228) (xy 290.17468 -103.859584) (xy 290.152582 -103.898192)
			(xy 290.144454 -104.089962) (xy 290.335716 -104.200452)
		)
		(stroke
			(width 0)
			(type solid)
		)
		(fill yes)
		(layer "In4.Cu")
		(net "M_E_DQ<58>")
	)
	(gr_poly
		(pts
			(xy 291.151818 -104.989376) (xy 291.159946 -104.797606) (xy 290.968684 -104.687116) (xy 290.806632 -104.789986)
			(xy 290.78428 -104.82834) (xy 291.12972 -105.02773)
		)
		(stroke
			(width 0)
			(type solid)
		)
		(fill yes)
		(layer "In4.Cu")
		(net "M_E_DQ<63>")
	)
	(gr_poly
		(pts
			(xy 291.151818 -103.998776) (xy 291.159946 -103.807006) (xy 290.968684 -103.696516) (xy 290.806632 -103.799386)
			(xy 290.78428 -103.83774) (xy 291.12972 -104.03713)
		)
		(stroke
			(width 0)
			(type solid)
		)
		(fill yes)
		(layer "In4.Cu")
		(net "M_E_DQ<59>")
	)
	(gr_poly
		(pts
			(xy 291.356288 -104.592882) (xy 291.37864 -104.554528) (xy 291.0332 -104.354884) (xy 291.011102 -104.393492)
			(xy 291.002974 -104.585262) (xy 291.194236 -104.695752)
		)
		(stroke
			(width 0)
			(type solid)
		)
		(fill yes)
		(layer "In4.Cu")
		(net "M_E_DQ<58>")
	)
	(gr_poly
		(pts
			(xy 408.84348 -100.706936) (xy 408.84348 -98.173794) (xy 408.7241 -98.054414) (xy 405.636984 -98.054414)
			(xy 405.636984 -100.708714) (xy 408.827732 -100.708714)
		)
		(stroke
			(width 0)
			(type solid)
		)
		(fill yes)
		(layer "In4.Cu")
		(net "GND")
	)
	(gr_poly
		(pts
			(xy 475.5134 -40.0558) (xy 472.8718 -40.0558) (xy 472.8718 -43.307) (xy 474.69552 -43.307) (xy 474.73108 -43.307)
			(xy 475.5134 -43.307)
		)
		(stroke
			(width 0)
			(type solid)
		)
		(fill yes)
		(layer "In4.Cu")
		(net "GND")
	)
	(gr_poly
		(pts
			(xy 367.6396 -108.67898) (xy 367.6396 -108.64342) (xy 367.6396 -105.9942) (xy 364.998 -105.9942)
			(xy 364.998 -108.9152) (xy 365.218726 -109.135926) (xy 365.23422 -109.1438) (xy 367.6396 -109.1438)
		)
		(stroke
			(width 0)
			(type solid)
		)
		(fill yes)
		(layer "In4.Cu")
		(net "GND")
	)
	(gr_line
		(start 0.299974 -104.76992)
		(end 0.739648 -104.76992)
		(stroke
			(width 0.05715)
			(type default)
		)
		(layer "In4.Cu")
	)
	(gr_line
		(start 0.299974 -100.769928)
		(end 0.739648 -100.769928)
		(stroke
			(width 0.05715)
			(type default)
		)
		(layer "In4.Cu")
	)
	(gr_line
		(start 0.51435 -107.9119)
		(end 0.889 -107.9119)
		(stroke
			(width 0.05715)
			(type default)
		)
		(layer "In4.Cu")
	)
	(gr_line
		(start 0.739648 -104.76992)
		(end 0.791718 -104.82199)
		(stroke
			(width 0.05715)
			(type default)
		)
		(layer "In4.Cu")
	)
	(gr_line
		(start 0.739648 -100.769928)
		(end 0.791718 -100.821998)
		(stroke
			(width 0.05715)
			(type default)
		)
		(layer "In4.Cu")
	)
	(gr_line
		(start 0.889 -107.9119)
		(end 0.94107 -107.85983)
		(stroke
			(width 0.05715)
			(type default)
		)
		(layer "In4.Cu")
	)
	(gr_line
		(start 1.0033 -106.872278)
		(end 1.0033 -106.891328)
		(stroke
			(width 0.05715)
			(type default)
		)
		(layer "In4.Cu")
	)
	(gr_line
		(start 1.146048 -106.582718)
		(end 1.146048 -106.601768)
		(stroke
			(width 0.05715)
			(type default)
		)
		(layer "In4.Cu")
	)
	(gr_line
		(start 1.208278 -104.82199)
		(end 1.260348 -104.76992)
		(stroke
			(width 0.05715)
			(type default)
		)
		(layer "In4.Cu")
	)
	(gr_line
		(start 1.208278 -100.821998)
		(end 1.260348 -100.769928)
		(stroke
			(width 0.05715)
			(type default)
		)
		(layer "In4.Cu")
	)
	(gr_line
		(start 1.260348 -104.76992)
		(end 1.700022 -104.76992)
		(stroke
			(width 0.05715)
			(type default)
		)
		(layer "In4.Cu")
	)
	(gr_line
		(start 1.260348 -100.769928)
		(end 1.700022 -100.769928)
		(stroke
			(width 0.05715)
			(type default)
		)
		(layer "In4.Cu")
	)
	(gr_line
		(start 1.35763 -107.85983)
		(end 1.4097 -107.9119)
		(stroke
			(width 0.05715)
			(type default)
		)
		(layer "In4.Cu")
	)
	(gr_line
		(start 1.4097 -107.9119)
		(end 1.78435 -107.9119)
		(stroke
			(width 0.05715)
			(type default)
		)
		(layer "In4.Cu")
	)
	(gr_line
		(start 1.599946 -90.769948)
		(end 2.044954 -90.769948)
		(stroke
			(width 0.05715)
			(type default)
		)
		(layer "In4.Cu")
	)
	(gr_line
		(start 2.044954 -90.769948)
		(end 2.091944 -90.722958)
		(stroke
			(width 0.05715)
			(type default)
		)
		(layer "In4.Cu")
	)
	(gr_line
		(start 2.508504 -90.722958)
		(end 2.555494 -90.769948)
		(stroke
			(width 0.05715)
			(type default)
		)
		(layer "In4.Cu")
	)
	(gr_line
		(start 2.555494 -90.769948)
		(end 2.999994 -90.769948)
		(stroke
			(width 0.05715)
			(type default)
		)
		(layer "In4.Cu")
	)
	(gr_line
		(start 2.739644 -112.21339)
		(end 3.114294 -112.21339)
		(stroke
			(width 0.05715)
			(type default)
		)
		(layer "In4.Cu")
	)
	(gr_line
		(start 3.05435 -107.9119)
		(end 3.429 -107.9119)
		(stroke
			(width 0.05715)
			(type default)
		)
		(layer "In4.Cu")
	)
	(gr_line
		(start 3.114294 -112.21339)
		(end 3.166364 -112.16132)
		(stroke
			(width 0.05715)
			(type default)
		)
		(layer "In4.Cu")
	)
	(gr_line
		(start 3.429 -107.9119)
		(end 3.48107 -107.85983)
		(stroke
			(width 0.05715)
			(type default)
		)
		(layer "In4.Cu")
	)
	(gr_line
		(start 3.5433 -107.286552)
		(end 3.56616 -107.24896)
		(stroke
			(width 0.05715)
			(type default)
		)
		(layer "In4.Cu")
	)
	(gr_line
		(start 3.582924 -112.16132)
		(end 3.634994 -112.21339)
		(stroke
			(width 0.05715)
			(type default)
		)
		(layer "In4.Cu")
	)
	(gr_line
		(start 3.634994 -112.21339)
		(end 4.009644 -112.21339)
		(stroke
			(width 0.05715)
			(type default)
		)
		(layer "In4.Cu")
	)
	(gr_line
		(start 3.862832 -106.76128)
		(end 3.90144 -106.69778)
		(stroke
			(width 0.05715)
			(type default)
		)
		(layer "In4.Cu")
	)
	(gr_line
		(start 3.89763 -107.85983)
		(end 3.9497 -107.9119)
		(stroke
			(width 0.05715)
			(type default)
		)
		(layer "In4.Cu")
	)
	(gr_line
		(start 3.90144 -106.69778)
		(end 3.97256 -106.676698)
		(stroke
			(width 0.05715)
			(type default)
		)
		(layer "In4.Cu")
	)
	(gr_line
		(start 3.9497 -107.9119)
		(end 4.32435 -107.9119)
		(stroke
			(width 0.05715)
			(type default)
		)
		(layer "In4.Cu")
	)
	(gr_line
		(start 4.499864 -92.769944)
		(end 5.051298 -93.321378)
		(stroke
			(width 0.05715)
			(type default)
		)
		(layer "In4.Cu")
	)
	(gr_line
		(start 4.672838 -111.65332)
		(end 4.731766 -111.594392)
		(stroke
			(width 0.05715)
			(type default)
		)
		(layer "In4.Cu")
	)
	(gr_line
		(start 5.104384 -111.222028)
		(end 5.112766 -111.201962)
		(stroke
			(width 0.05715)
			(type default)
		)
		(layer "In4.Cu")
	)
	(gr_line
		(start 5.346192 -92.939362)
		(end 5.346192 -93.029532)
		(stroke
			(width 0.05715)
			(type default)
		)
		(layer "In4.Cu")
	)
	(gr_line
		(start 5.346192 -92.939362)
		(end 5.51561 -92.769944)
		(stroke
			(width 0.05715)
			(type default)
		)
		(layer "In4.Cu")
	)
	(gr_line
		(start 5.51561 -92.769944)
		(end 5.899912 -92.769944)
		(stroke
			(width 0.05715)
			(type default)
		)
		(layer "In4.Cu")
	)
	(gr_line
		(start 5.80009 -94.76994)
		(end 6.116066 -94.76994)
		(stroke
			(width 0.05715)
			(type default)
		)
		(layer "In4.Cu")
	)
	(gr_line
		(start 5.80009 -90.769948)
		(end 6.239764 -90.769948)
		(stroke
			(width 0.05715)
			(type default)
		)
		(layer "In4.Cu")
	)
	(gr_line
		(start 5.884926 -89.422986)
		(end 6.047486 -89.585546)
		(stroke
			(width 0.05715)
			(type default)
		)
		(layer "In4.Cu")
	)
	(gr_line
		(start 6.047486 -89.585546)
		(end 6.390386 -89.585546)
		(stroke
			(width 0.05715)
			(type default)
		)
		(layer "In4.Cu")
	)
	(gr_line
		(start 6.116066 -94.76994)
		(end 6.331966 -94.98584)
		(stroke
			(width 0.05715)
			(type default)
		)
		(layer "In4.Cu")
	)
	(gr_line
		(start 6.124702 -107.993688)
		(end 6.133084 -107.973622)
		(stroke
			(width 0.05715)
			(type default)
		)
		(layer "In4.Cu")
	)
	(gr_line
		(start 6.133084 -107.973622)
		(end 6.148578 -107.958128)
		(stroke
			(width 0.05715)
			(type default)
		)
		(layer "In4.Cu")
	)
	(gr_line
		(start 6.177026 -89.128346)
		(end 6.260846 -89.128346)
		(stroke
			(width 0.05715)
			(type default)
		)
		(layer "In4.Cu")
	)
	(gr_line
		(start 6.209538 -112.549686)
		(end 6.209538 -112.865916)
		(stroke
			(width 0.05715)
			(type default)
		)
		(layer "In4.Cu")
	)
	(gr_line
		(start 6.209538 -112.549686)
		(end 6.261608 -112.497616)
		(stroke
			(width 0.05715)
			(type default)
		)
		(layer "In4.Cu")
	)
	(gr_line
		(start 6.209538 -112.028986)
		(end 6.261608 -112.081056)
		(stroke
			(width 0.05715)
			(type default)
		)
		(layer "In4.Cu")
	)
	(gr_line
		(start 6.209538 -111.595916)
		(end 6.209538 -112.028986)
		(stroke
			(width 0.05715)
			(type default)
		)
		(layer "In4.Cu")
	)
	(gr_line
		(start 6.239764 -90.769948)
		(end 6.291834 -90.822018)
		(stroke
			(width 0.05715)
			(type default)
		)
		(layer "In4.Cu")
	)
	(gr_line
		(start 6.390386 -89.585546)
		(end 6.552946 -89.422986)
		(stroke
			(width 0.05715)
			(type default)
		)
		(layer "In4.Cu")
	)
	(gr_line
		(start 6.704076 -95.816674)
		(end 6.788404 -95.816674)
		(stroke
			(width 0.05715)
			(type default)
		)
		(layer "In4.Cu")
	)
	(gr_line
		(start 6.708394 -90.822018)
		(end 6.760464 -90.769948)
		(stroke
			(width 0.05715)
			(type default)
		)
		(layer "In4.Cu")
	)
	(gr_line
		(start 6.74878 -94.98584)
		(end 6.96468 -94.76994)
		(stroke
			(width 0.05715)
			(type default)
		)
		(layer "In4.Cu")
	)
	(gr_line
		(start 6.760464 -90.769948)
		(end 7.199884 -90.769948)
		(stroke
			(width 0.05715)
			(type default)
		)
		(layer "In4.Cu")
	)
	(gr_line
		(start 6.764528 -93.7006)
		(end 6.927088 -93.53804)
		(stroke
			(width 0.05715)
			(type default)
		)
		(layer "In4.Cu")
	)
	(gr_line
		(start 6.900926 -89.422986)
		(end 7.063486 -89.585546)
		(stroke
			(width 0.05715)
			(type default)
		)
		(layer "In4.Cu")
	)
	(gr_line
		(start 6.927088 -93.53804)
		(end 7.269988 -93.53804)
		(stroke
			(width 0.05715)
			(type default)
		)
		(layer "In4.Cu")
	)
	(gr_line
		(start 6.96468 -94.76994)
		(end 7.199884 -94.76994)
		(stroke
			(width 0.05715)
			(type default)
		)
		(layer "In4.Cu")
	)
	(gr_line
		(start 7.056628 -93.99524)
		(end 7.140448 -93.99524)
		(stroke
			(width 0.05715)
			(type default)
		)
		(layer "In4.Cu")
	)
	(gr_line
		(start 7.063486 -89.585546)
		(end 7.406386 -89.585546)
		(stroke
			(width 0.05715)
			(type default)
		)
		(layer "In4.Cu")
	)
	(gr_line
		(start 7.15264 -111.090202)
		(end 7.3152 -111.252762)
		(stroke
			(width 0.05715)
			(type default)
		)
		(layer "In4.Cu")
	)
	(gr_line
		(start 7.15264 -110.747302)
		(end 7.15264 -111.090202)
		(stroke
			(width 0.05715)
			(type default)
		)
		(layer "In4.Cu")
	)
	(gr_line
		(start 7.15264 -110.747302)
		(end 7.3152 -110.584742)
		(stroke
			(width 0.05715)
			(type default)
		)
		(layer "In4.Cu")
	)
	(gr_line
		(start 7.15264 -110.074202)
		(end 7.3152 -110.236762)
		(stroke
			(width 0.05715)
			(type default)
		)
		(layer "In4.Cu")
	)
	(gr_line
		(start 7.15264 -109.731302)
		(end 7.15264 -110.074202)
		(stroke
			(width 0.05715)
			(type default)
		)
		(layer "In4.Cu")
	)
	(gr_line
		(start 7.15264 -109.731302)
		(end 7.3152 -109.568742)
		(stroke
			(width 0.05715)
			(type default)
		)
		(layer "In4.Cu")
	)
	(gr_line
		(start 7.15264 -109.058202)
		(end 7.3152 -109.220762)
		(stroke
			(width 0.05715)
			(type default)
		)
		(layer "In4.Cu")
	)
	(gr_line
		(start 7.15264 -108.715302)
		(end 7.15264 -109.058202)
		(stroke
			(width 0.05715)
			(type default)
		)
		(layer "In4.Cu")
	)
	(gr_line
		(start 7.15264 -108.715302)
		(end 7.3152 -108.552742)
		(stroke
			(width 0.05715)
			(type default)
		)
		(layer "In4.Cu")
	)
	(gr_line
		(start 7.193026 -89.128346)
		(end 7.276846 -89.128346)
		(stroke
			(width 0.05715)
			(type default)
		)
		(layer "In4.Cu")
	)
	(gr_line
		(start 7.269988 -93.53804)
		(end 7.432548 -93.7006)
		(stroke
			(width 0.05715)
			(type default)
		)
		(layer "In4.Cu")
	)
	(gr_line
		(start 7.406386 -89.585546)
		(end 7.568946 -89.422986)
		(stroke
			(width 0.05715)
			(type default)
		)
		(layer "In4.Cu")
	)
	(gr_line
		(start 7.507478 -105.926128)
		(end 7.542022 -105.915714)
		(stroke
			(width 0.05715)
			(type default)
		)
		(layer "In4.Cu")
	)
	(gr_line
		(start 7.542022 -105.915714)
		(end 7.567422 -105.890314)
		(stroke
			(width 0.05715)
			(type default)
		)
		(layer "In4.Cu")
	)
	(gr_line
		(start 7.60984 -110.876842)
		(end 7.60984 -110.960662)
		(stroke
			(width 0.05715)
			(type default)
		)
		(layer "In4.Cu")
	)
	(gr_line
		(start 7.60984 -109.860842)
		(end 7.60984 -109.944662)
		(stroke
			(width 0.05715)
			(type default)
		)
		(layer "In4.Cu")
	)
	(gr_line
		(start 7.60984 -108.844842)
		(end 7.60984 -108.928662)
		(stroke
			(width 0.05715)
			(type default)
		)
		(layer "In4.Cu")
	)
	(gr_line
		(start 7.726426 -95.524574)
		(end 7.785354 -95.58401)
		(stroke
			(width 0.05715)
			(type default)
		)
		(layer "In4.Cu")
	)
	(gr_line
		(start 7.741158 -107.550458)
		(end 7.741158 -107.780582)
		(stroke
			(width 0.05715)
			(type default)
		)
		(layer "In4.Cu")
	)
	(gr_line
		(start 7.741158 -107.550458)
		(end 7.983474 -107.308142)
		(stroke
			(width 0.05715)
			(type default)
		)
		(layer "In4.Cu")
	)
	(gr_line
		(start 7.780528 -93.7006)
		(end 7.953248 -93.52788)
		(stroke
			(width 0.05715)
			(type default)
		)
		(layer "In4.Cu")
	)
	(gr_line
		(start 7.786624 -96.00057)
		(end 8.207248 -96.425258)
		(stroke
			(width 0.05715)
			(type default)
		)
		(layer "In4.Cu")
	)
	(gr_line
		(start 7.916926 -89.422986)
		(end 8.079486 -89.585546)
		(stroke
			(width 0.05715)
			(type default)
		)
		(layer "In4.Cu")
	)
	(gr_line
		(start 7.953248 -93.52788)
		(end 8.258048 -93.52788)
		(stroke
			(width 0.05715)
			(type default)
		)
		(layer "In4.Cu")
	)
	(gr_line
		(start 7.971282 -95.76816)
		(end 8.201152 -95.76943)
		(stroke
			(width 0.05715)
			(type default)
		)
		(layer "In4.Cu")
	)
	(gr_line
		(start 7.983474 -107.308142)
		(end 8.213598 -107.308142)
		(stroke
			(width 0.05715)
			(type default)
		)
		(layer "In4.Cu")
	)
	(gr_line
		(start 8.011922 -91.628976)
		(end 8.07085 -91.687904)
		(stroke
			(width 0.05715)
			(type default)
		)
		(layer "In4.Cu")
	)
	(gr_line
		(start 8.072628 -93.99524)
		(end 8.138668 -93.99524)
		(stroke
			(width 0.05715)
			(type default)
		)
		(layer "In4.Cu")
	)
	(gr_line
		(start 8.079486 -89.585546)
		(end 8.422386 -89.585546)
		(stroke
			(width 0.05715)
			(type default)
		)
		(layer "In4.Cu")
	)
	(gr_line
		(start 8.156194 -107.782106)
		(end 8.215122 -107.723178)
		(stroke
			(width 0.05715)
			(type default)
		)
		(layer "In4.Cu")
	)
	(gr_line
		(start 8.201152 -95.76943)
		(end 8.442452 -96.013016)
		(stroke
			(width 0.05715)
			(type default)
		)
		(layer "In4.Cu")
	)
	(gr_line
		(start 8.208772 -105.24871)
		(end 8.2677 -105.189782)
		(stroke
			(width 0.05715)
			(type default)
		)
		(layer "In4.Cu")
	)
	(gr_line
		(start 8.209026 -89.128346)
		(end 8.292846 -89.128346)
		(stroke
			(width 0.05715)
			(type default)
		)
		(layer "In4.Cu")
	)
	(gr_line
		(start 8.242046 -100.397056)
		(end 8.484362 -100.639372)
		(stroke
			(width 0.05715)
			(type default)
		)
		(layer "In4.Cu")
	)
	(gr_line
		(start 8.242046 -100.166932)
		(end 8.242046 -100.397056)
		(stroke
			(width 0.05715)
			(type default)
		)
		(layer "In4.Cu")
	)
	(gr_line
		(start 8.258048 -93.52788)
		(end 8.430768 -93.7006)
		(stroke
			(width 0.05715)
			(type default)
		)
		(layer "In4.Cu")
	)
	(gr_line
		(start 8.422386 -89.585546)
		(end 8.584946 -89.422986)
		(stroke
			(width 0.05715)
			(type default)
		)
		(layer "In4.Cu")
	)
	(gr_line
		(start 8.441436 -96.242886)
		(end 8.442452 -96.013016)
		(stroke
			(width 0.05715)
			(type default)
		)
		(layer "In4.Cu")
	)
	(gr_line
		(start 8.45947 -106.832146)
		(end 8.45947 -107.06227)
		(stroke
			(width 0.05715)
			(type default)
		)
		(layer "In4.Cu")
	)
	(gr_line
		(start 8.45947 -106.832146)
		(end 8.70204 -106.589576)
		(stroke
			(width 0.05715)
			(type default)
		)
		(layer "In4.Cu")
	)
	(gr_line
		(start 8.484362 -100.639372)
		(end 8.714486 -100.639372)
		(stroke
			(width 0.05715)
			(type default)
		)
		(layer "In4.Cu")
	)
	(gr_line
		(start 8.50265 -96.7232)
		(end 8.921496 -97.14611)
		(stroke
			(width 0.05715)
			(type default)
		)
		(layer "In4.Cu")
	)
	(gr_line
		(start 8.657082 -100.165408)
		(end 8.71601 -100.224336)
		(stroke
			(width 0.05715)
			(type default)
		)
		(layer "In4.Cu")
	)
	(gr_line
		(start 8.686292 -96.490028)
		(end 8.916162 -96.491298)
		(stroke
			(width 0.05715)
			(type default)
		)
		(layer "In4.Cu")
	)
	(gr_line
		(start 8.70204 -106.589576)
		(end 8.932164 -106.589576)
		(stroke
			(width 0.05715)
			(type default)
		)
		(layer "In4.Cu")
	)
	(gr_line
		(start 8.867394 -93.70314)
		(end 8.926322 -93.762068)
		(stroke
			(width 0.05715)
			(type default)
		)
		(layer "In4.Cu")
	)
	(gr_line
		(start 8.874506 -107.063794)
		(end 8.933688 -107.004612)
		(stroke
			(width 0.05715)
			(type default)
		)
		(layer "In4.Cu")
	)
	(gr_line
		(start 8.916162 -96.491298)
		(end 9.157462 -96.734884)
		(stroke
			(width 0.05715)
			(type default)
		)
		(layer "In4.Cu")
	)
	(gr_line
		(start 8.92048 -97.75698)
		(end 8.979408 -97.815908)
		(stroke
			(width 0.05715)
			(type default)
		)
		(layer "In4.Cu")
	)
	(gr_line
		(start 8.960358 -101.115368)
		(end 9.202928 -101.357938)
		(stroke
			(width 0.05715)
			(type default)
		)
		(layer "In4.Cu")
	)
	(gr_line
		(start 8.960358 -100.885244)
		(end 8.960358 -101.115368)
		(stroke
			(width 0.05715)
			(type default)
		)
		(layer "In4.Cu")
	)
	(gr_line
		(start 9.156446 -96.964754)
		(end 9.157462 -96.734884)
		(stroke
			(width 0.05715)
			(type default)
		)
		(layer "In4.Cu")
	)
	(gr_line
		(start 9.178036 -106.11358)
		(end 9.178036 -106.343704)
		(stroke
			(width 0.05715)
			(type default)
		)
		(layer "In4.Cu")
	)
	(gr_line
		(start 9.178036 -106.11358)
		(end 9.420352 -105.871264)
		(stroke
			(width 0.05715)
			(type default)
		)
		(layer "In4.Cu")
	)
	(gr_line
		(start 9.202928 -101.357938)
		(end 9.433052 -101.357938)
		(stroke
			(width 0.05715)
			(type default)
		)
		(layer "In4.Cu")
	)
	(gr_line
		(start 9.21766 -97.445068)
		(end 9.636506 -97.867978)
		(stroke
			(width 0.05715)
			(type default)
		)
		(layer "In4.Cu")
	)
	(gr_line
		(start 9.375394 -100.88372)
		(end 9.434576 -100.942902)
		(stroke
			(width 0.05715)
			(type default)
		)
		(layer "In4.Cu")
	)
	(gr_line
		(start 9.401048 -97.211896)
		(end 9.631172 -97.213166)
		(stroke
			(width 0.05715)
			(type default)
		)
		(layer "In4.Cu")
	)
	(gr_line
		(start 9.420352 -105.871264)
		(end 9.650476 -105.871264)
		(stroke
			(width 0.05715)
			(type default)
		)
		(layer "In4.Cu")
	)
	(gr_line
		(start 9.593072 -106.345228)
		(end 9.652 -106.2863)
		(stroke
			(width 0.05715)
			(type default)
		)
		(layer "In4.Cu")
	)
	(gr_line
		(start 9.631172 -97.213166)
		(end 9.872472 -97.456752)
		(stroke
			(width 0.05715)
			(type default)
		)
		(layer "In4.Cu")
	)
	(gr_line
		(start 9.774174 -98.61042)
		(end 9.782556 -98.630486)
		(stroke
			(width 0.05715)
			(type default)
		)
		(layer "In4.Cu")
	)
	(gr_line
		(start 9.871456 -97.686876)
		(end 9.872472 -97.456752)
		(stroke
			(width 0.05715)
			(type default)
		)
		(layer "In4.Cu")
	)
	(gr_line
		(start 10.030968 -94.866714)
		(end 10.046462 -94.882208)
		(stroke
			(width 0.05715)
			(type default)
		)
		(layer "In4.Cu")
	)
	(gr_line
		(start 10.046462 -94.882208)
		(end 10.054844 -94.902274)
		(stroke
			(width 0.05715)
			(type default)
		)
		(layer "In4.Cu")
	)
	(gr_line
		(start 10.369042 -98.781362)
		(end 10.597642 -99.333812)
		(stroke
			(width 0.05715)
			(type default)
		)
		(layer "In4.Cu")
	)
	(gr_line
		(start 10.425684 -94.042484)
		(end 10.434066 -94.06255)
		(stroke
			(width 0.05715)
			(type default)
		)
		(layer "In4.Cu")
	)
	(gr_line
		(start 10.48004 -98.304858)
		(end 10.493248 -98.318066)
		(stroke
			(width 0.05715)
			(type default)
		)
		(layer "In4.Cu")
	)
	(gr_line
		(start 10.493248 -98.318066)
		(end 10.500868 -98.336354)
		(stroke
			(width 0.05715)
			(type default)
		)
		(layer "In4.Cu")
	)
	(gr_line
		(start 10.627614 -98.636074)
		(end 10.840212 -98.724212)
		(stroke
			(width 0.05715)
			(type default)
		)
		(layer "In4.Cu")
	)
	(gr_line
		(start 10.840212 -98.724212)
		(end 10.97153 -99.04095)
		(stroke
			(width 0.05715)
			(type default)
		)
		(layer "In4.Cu")
	)
	(gr_line
		(start 10.883392 -99.253548)
		(end 10.97153 -99.04095)
		(stroke
			(width 0.05715)
			(type default)
		)
		(layer "In4.Cu")
	)
	(gr_line
		(start 10.919206 -92.559632)
		(end 11.051794 -92.69222)
		(stroke
			(width 0.05715)
			(type default)
		)
		(layer "In4.Cu")
	)
	(gr_line
		(start 10.919206 -92.216732)
		(end 10.919206 -92.559632)
		(stroke
			(width 0.05715)
			(type default)
		)
		(layer "In4.Cu")
	)
	(gr_line
		(start 10.919206 -92.216732)
		(end 11.051794 -92.084144)
		(stroke
			(width 0.05715)
			(type default)
		)
		(layer "In4.Cu")
	)
	(gr_line
		(start 10.978642 -101.519228)
		(end 10.986008 -101.5365)
		(stroke
			(width 0.05715)
			(type default)
		)
		(layer "In4.Cu")
	)
	(gr_line
		(start 11.054334 -93.901006)
		(end 11.059414 -93.914722)
		(stroke
			(width 0.05715)
			(type default)
		)
		(layer "In4.Cu")
	)
	(gr_line
		(start 11.346434 -92.376244)
		(end 11.346434 -92.40012)
		(stroke
			(width 0.05715)
			(type default)
		)
		(layer "In4.Cu")
	)
	(gr_line
		(start 11.738864 -101.325426)
		(end 11.74623 -101.342698)
		(stroke
			(width 0.05715)
			(type default)
		)
		(layer "In4.Cu")
	)
	(gr_line
		(start 12.2174 -101.97338)
		(end 12.2174 -102.03942)
		(stroke
			(width 0.05715)
			(type default)
		)
		(layer "In4.Cu")
	)
	(gr_line
		(start 12.250166 -104.613964)
		(end 12.309094 -104.672892)
		(stroke
			(width 0.05715)
			(type default)
		)
		(layer "In4.Cu")
	)
	(gr_line
		(start 12.25169 -104.198928)
		(end 12.481814 -104.198928)
		(stroke
			(width 0.05715)
			(type default)
		)
		(layer "In4.Cu")
	)
	(gr_line
		(start 12.46124 -107.26801)
		(end 12.51331 -107.32008)
		(stroke
			(width 0.05715)
			(type default)
		)
		(layer "In4.Cu")
	)
	(gr_line
		(start 12.46124 -106.85145)
		(end 12.51331 -106.79938)
		(stroke
			(width 0.05715)
			(type default)
		)
		(layer "In4.Cu")
	)
	(gr_line
		(start 12.464034 -99.725988)
		(end 12.472416 -99.746054)
		(stroke
			(width 0.05715)
			(type default)
		)
		(layer "In4.Cu")
	)
	(gr_line
		(start 12.481814 -104.198928)
		(end 12.72413 -104.441244)
		(stroke
			(width 0.05715)
			(type default)
		)
		(layer "In4.Cu")
	)
	(gr_line
		(start 12.502134 -100.812854)
		(end 12.5095 -100.830126)
		(stroke
			(width 0.05715)
			(type default)
		)
		(layer "In4.Cu")
	)
	(gr_line
		(start 12.51204 -102.33152)
		(end 12.68476 -102.1588)
		(stroke
			(width 0.05715)
			(type default)
		)
		(layer "In4.Cu")
	)
	(gr_line
		(start 12.51204 -101.68128)
		(end 12.68476 -101.854)
		(stroke
			(width 0.05715)
			(type default)
		)
		(layer "In4.Cu")
	)
	(gr_line
		(start 12.51331 -107.32008)
		(end 12.51331 -107.69473)
		(stroke
			(width 0.05715)
			(type default)
		)
		(layer "In4.Cu")
	)
	(gr_line
		(start 12.51331 -106.42473)
		(end 12.51331 -106.79938)
		(stroke
			(width 0.05715)
			(type default)
		)
		(layer "In4.Cu")
	)
	(gr_line
		(start 12.68476 -101.854)
		(end 12.68476 -102.1588)
		(stroke
			(width 0.05715)
			(type default)
		)
		(layer "In4.Cu")
	)
	(gr_line
		(start 12.72413 -104.441244)
		(end 12.72413 -104.671368)
		(stroke
			(width 0.05715)
			(type default)
		)
		(layer "In4.Cu")
	)
	(gr_line
		(start 13.104368 -99.372928)
		(end 13.113512 -99.397058)
		(stroke
			(width 0.05715)
			(type default)
		)
		(layer "In4.Cu")
	)
	(gr_line
		(start 13.31214 -104.9147)
		(end 13.4747 -104.75214)
		(stroke
			(width 0.05715)
			(type default)
		)
		(layer "In4.Cu")
	)
	(gr_line
		(start 13.4747 -104.75214)
		(end 13.8176 -104.75214)
		(stroke
			(width 0.05715)
			(type default)
		)
		(layer "In4.Cu")
	)
	(gr_line
		(start 13.60424 -105.20934)
		(end 13.68806 -105.20934)
		(stroke
			(width 0.05715)
			(type default)
		)
		(layer "In4.Cu")
	)
	(gr_line
		(start 13.612114 -100.885752)
		(end 13.63218 -100.894134)
		(stroke
			(width 0.05715)
			(type default)
		)
		(layer "In4.Cu")
	)
	(gr_line
		(start 13.777976 -103.028496)
		(end 13.777976 -103.313992)
		(stroke
			(width 0.05715)
			(type default)
		)
		(layer "In4.Cu")
	)
	(gr_line
		(start 13.8176 -104.75214)
		(end 13.98016 -104.9147)
		(stroke
			(width 0.05715)
			(type default)
		)
		(layer "In4.Cu")
	)
	(gr_line
		(start 13.835126 -103.673402)
		(end 14.321282 -103.673402)
		(stroke
			(width 0.05715)
			(type default)
		)
		(layer "In4.Cu")
	)
	(gr_line
		(start 14.704314 -104.9147)
		(end 14.866874 -104.75214)
		(stroke
			(width 0.05715)
			(type default)
		)
		(layer "In4.Cu")
	)
	(gr_line
		(start 14.866874 -104.75214)
		(end 15.209774 -104.75214)
		(stroke
			(width 0.05715)
			(type default)
		)
		(layer "In4.Cu")
	)
	(gr_line
		(start 14.996414 -105.20934)
		(end 15.080234 -105.20934)
		(stroke
			(width 0.05715)
			(type default)
		)
		(layer "In4.Cu")
	)
	(gr_line
		(start 15.209774 -104.75214)
		(end 15.372334 -104.9147)
		(stroke
			(width 0.05715)
			(type default)
		)
		(layer "In4.Cu")
	)
	(gr_line
		(start 15.41145 -106.457496)
		(end 15.470378 -106.398568)
		(stroke
			(width 0.05715)
			(type default)
		)
		(layer "In4.Cu")
	)
	(gr_line
		(start 15.412974 -106.872532)
		(end 15.643098 -106.872532)
		(stroke
			(width 0.05715)
			(type default)
		)
		(layer "In4.Cu")
	)
	(gr_line
		(start 15.4432 -108.61675)
		(end 15.49527 -108.66882)
		(stroke
			(width 0.05715)
			(type default)
		)
		(layer "In4.Cu")
	)
	(gr_line
		(start 15.4432 -108.20019)
		(end 15.49527 -108.14812)
		(stroke
			(width 0.05715)
			(type default)
		)
		(layer "In4.Cu")
	)
	(gr_line
		(start 15.49527 -108.66882)
		(end 15.49527 -109.04347)
		(stroke
			(width 0.05715)
			(type default)
		)
		(layer "In4.Cu")
	)
	(gr_line
		(start 15.49527 -107.77347)
		(end 15.49527 -108.14812)
		(stroke
			(width 0.05715)
			(type default)
		)
		(layer "In4.Cu")
	)
	(gr_line
		(start 15.564104 -101.694234)
		(end 15.581376 -101.7016)
		(stroke
			(width 0.05715)
			(type default)
		)
		(layer "In4.Cu")
	)
	(gr_line
		(start 15.643098 -106.872532)
		(end 15.885414 -106.630216)
		(stroke
			(width 0.05715)
			(type default)
		)
		(layer "In4.Cu")
	)
	(gr_line
		(start 15.885414 -106.400092)
		(end 15.885414 -106.630216)
		(stroke
			(width 0.05715)
			(type default)
		)
		(layer "In4.Cu")
	)
	(gr_line
		(start 15.93596 -100.0252)
		(end 16.22044 -100.0252)
		(stroke
			(width 0.05715)
			(type default)
		)
		(layer "In4.Cu")
	)
	(gr_line
		(start 15.960344 -104.441244)
		(end 15.960344 -104.671368)
		(stroke
			(width 0.05715)
			(type default)
		)
		(layer "In4.Cu")
	)
	(gr_line
		(start 15.960344 -104.441244)
		(end 16.20266 -104.198928)
		(stroke
			(width 0.05715)
			(type default)
		)
		(layer "In4.Cu")
	)
	(gr_line
		(start 16.008096 -103.031544)
		(end 16.546322 -103.031544)
		(stroke
			(width 0.05715)
			(type default)
		)
		(layer "In4.Cu")
	)
	(gr_line
		(start 16.129762 -105.739184)
		(end 16.188944 -105.680002)
		(stroke
			(width 0.05715)
			(type default)
		)
		(layer "In4.Cu")
	)
	(gr_line
		(start 16.131286 -106.15422)
		(end 16.36141 -106.15422)
		(stroke
			(width 0.05715)
			(type default)
		)
		(layer "In4.Cu")
	)
	(gr_line
		(start 16.20266 -104.198928)
		(end 16.432784 -104.198928)
		(stroke
			(width 0.05715)
			(type default)
		)
		(layer "In4.Cu")
	)
	(gr_line
		(start 16.22044 -100.3173)
		(end 16.22552 -100.31222)
		(stroke
			(width 0.05715)
			(type default)
		)
		(layer "In4.Cu")
	)
	(gr_line
		(start 16.22044 -100.0252)
		(end 16.334486 -99.911154)
		(stroke
			(width 0.05715)
			(type default)
		)
		(layer "In4.Cu")
	)
	(gr_line
		(start 16.22552 -100.31222)
		(end 16.32585 -100.31222)
		(stroke
			(width 0.05715)
			(type default)
		)
		(layer "In4.Cu")
	)
	(gr_line
		(start 16.32585 -100.31222)
		(end 16.334486 -100.320856)
		(stroke
			(width 0.05715)
			(type default)
		)
		(layer "In4.Cu")
	)
	(gr_line
		(start 16.338042 -100.324412)
		(end 16.44015 -100.42652)
		(stroke
			(width 0.05715)
			(type default)
		)
		(layer "In4.Cu")
	)
	(gr_line
		(start 16.338042 -99.907598)
		(end 16.44015 -99.80549)
		(stroke
			(width 0.05715)
			(type default)
		)
		(layer "In4.Cu")
	)
	(gr_line
		(start 16.36141 -106.15422)
		(end 16.60398 -105.91165)
		(stroke
			(width 0.05715)
			(type default)
		)
		(layer "In4.Cu")
	)
	(gr_line
		(start 16.37538 -104.672892)
		(end 16.434308 -104.613964)
		(stroke
			(width 0.05715)
			(type default)
		)
		(layer "In4.Cu")
	)
	(gr_line
		(start 16.44015 -100.42652)
		(end 16.44015 -100.74783)
		(stroke
			(width 0.05715)
			(type default)
		)
		(layer "In4.Cu")
	)
	(gr_line
		(start 16.44015 -99.47783)
		(end 16.44015 -99.80549)
		(stroke
			(width 0.05715)
			(type default)
		)
		(layer "In4.Cu")
	)
	(gr_line
		(start 16.60398 -105.681526)
		(end 16.60398 -105.91165)
		(stroke
			(width 0.05715)
			(type default)
		)
		(layer "In4.Cu")
	)
	(gr_line
		(start 16.607536 -102.427532)
		(end 16.607536 -102.676198)
		(stroke
			(width 0.05715)
			(type default)
		)
		(layer "In4.Cu")
	)
	(gr_line
		(start 16.848328 -105.020618)
		(end 16.90751 -104.961436)
		(stroke
			(width 0.05715)
			(type default)
		)
		(layer "In4.Cu")
	)
	(gr_line
		(start 16.849852 -105.435654)
		(end 17.079976 -105.435654)
		(stroke
			(width 0.05715)
			(type default)
		)
		(layer "In4.Cu")
	)
	(gr_line
		(start 17.079976 -105.435654)
		(end 17.322546 -105.193084)
		(stroke
			(width 0.05715)
			(type default)
		)
		(layer "In4.Cu")
	)
	(gr_line
		(start 17.322546 -104.96296)
		(end 17.322546 -105.193084)
		(stroke
			(width 0.05715)
			(type default)
		)
		(layer "In4.Cu")
	)
	(gr_line
		(start 21.90242 -157.036262)
		(end 21.90242 -157.5435)
		(stroke
			(width 0.0635)
			(type default)
		)
		(layer "In4.Cu")
	)
	(gr_line
		(start 22.263608 -157.034738)
		(end 22.69744 -157.46857)
		(stroke
			(width 0.0635)
			(type default)
		)
		(layer "In4.Cu")
	)
	(gr_line
		(start 22.69744 -157.46857)
		(end 22.69744 -157.55874)
		(stroke
			(width 0.0635)
			(type default)
		)
		(layer "In4.Cu")
	)
	(gr_line
		(start 42.58056 -102.829868)
		(end 42.761154 -103.010462)
		(stroke
			(width 0.0635)
			(type default)
		)
		(layer "In4.Cu")
	)
	(gr_line
		(start 42.59072 -103.74376)
		(end 42.694606 -103.74376)
		(stroke
			(width 0.0635)
			(type default)
		)
		(layer "In4.Cu")
	)
	(gr_line
		(start 42.694606 -103.74376)
		(end 43.6372 -102.801166)
		(stroke
			(width 0.0635)
			(type default)
		)
		(layer "In4.Cu")
	)
	(gr_line
		(start 42.761154 -103.010462)
		(end 43.06697 -103.010462)
		(stroke
			(width 0.0635)
			(type default)
		)
		(layer "In4.Cu")
	)
	(gr_line
		(start 43.06697 -103.010462)
		(end 43.30954 -102.767892)
		(stroke
			(width 0.0635)
			(type default)
		)
		(layer "In4.Cu")
	)
	(gr_line
		(start 43.636438 -102.767892)
		(end 43.6372 -102.768654)
		(stroke
			(width 0.0635)
			(type default)
		)
		(layer "In4.Cu")
	)
	(gr_line
		(start 66.246502 -80.65135)
		(end 66.2686 -80.65135)
		(stroke
			(width 0.04445)
			(type default)
		)
		(layer "In4.Cu")
	)
	(gr_line
		(start 66.246502 -80.42275)
		(end 66.2686 -80.42275)
		(stroke
			(width 0.04445)
			(type default)
		)
		(layer "In4.Cu")
	)
	(gr_line
		(start 66.2686 -80.65135)
		(end 66.28765 -80.6323)
		(stroke
			(width 0.04445)
			(type default)
		)
		(layer "In4.Cu")
	)
	(gr_line
		(start 66.2686 -80.42275)
		(end 66.28765 -80.4418)
		(stroke
			(width 0.04445)
			(type default)
		)
		(layer "In4.Cu")
	)
	(gr_line
		(start 74.88936 -82.241136)
		(end 74.919332 -82.241136)
		(stroke
			(width 0.04445)
			(type default)
		)
		(layer "In4.Cu")
	)
	(gr_line
		(start 75.697842 -81.749138)
		(end 75.74026 -81.70672)
		(stroke
			(width 0.04445)
			(type default)
		)
		(layer "In4.Cu")
	)
	(gr_line
		(start 75.704954 -81.940654)
		(end 75.74026 -81.97596)
		(stroke
			(width 0.04445)
			(type default)
		)
		(layer "In4.Cu")
	)
	(gr_line
		(start 75.742038 -81.977738)
		(end 75.762866 -81.998566)
		(stroke
			(width 0.04445)
			(type default)
		)
		(layer "In4.Cu")
	)
	(gr_line
		(start 75.742038 -81.704942)
		(end 75.762866 -81.684114)
		(stroke
			(width 0.04445)
			(type default)
		)
		(layer "In4.Cu")
	)
	(gr_line
		(start 75.762866 -81.998566)
		(end 75.762866 -82.33664)
		(stroke
			(width 0.04445)
			(type default)
		)
		(layer "In4.Cu")
	)
	(gr_line
		(start 75.762866 -81.34604)
		(end 75.762866 -81.684114)
		(stroke
			(width 0.04445)
			(type default)
		)
		(layer "In4.Cu")
	)
	(gr_line
		(start 120.500902 -87.603584)
		(end 120.639332 -87.742014)
		(stroke
			(width 0.04445)
			(type default)
		)
		(layer "In4.Cu")
	)
	(gr_arc
		(start 120.768618 -88.073992)
		(mid 120.738837 -87.894428)
		(end 120.639332 -87.742014)
		(stroke
			(width 0.04445)
			(type default)
		)
		(layer "In4.Cu")
	)
	(gr_line
		(start 120.987566 -87.951564)
		(end 121.066306 -87.930228)
		(stroke
			(width 0.04445)
			(type default)
		)
		(layer "In4.Cu")
	)
	(gr_line
		(start 121.066306 -87.930228)
		(end 121.359168 -88.099138)
		(stroke
			(width 0.04445)
			(type default)
		)
		(layer "In4.Cu")
	)
	(gr_line
		(start 121.90349 -88.842088)
		(end 121.924572 -88.763348)
		(stroke
			(width 0.04445)
			(type default)
		)
		(layer "In4.Cu")
	)
	(gr_line
		(start 121.924572 -88.763348)
		(end 122.217688 -88.594184)
		(stroke
			(width 0.04445)
			(type default)
		)
		(layer "In4.Cu")
	)
	(gr_arc
		(start 121.92762 -89.109296)
		(mid 121.645775 -89.030263)
		(end 121.359168 -89.089738)
		(stroke
			(width 0.04445)
			(type default)
		)
		(layer "In4.Cu")
	)
	(gr_line
		(start 122.217688 -72.40651)
		(end 122.217688 -72.744584)
		(stroke
			(width 0.04445)
			(type default)
		)
		(layer "In4.Cu")
	)
	(gr_line
		(start 122.217688 -72.40651)
		(end 122.238516 -72.385682)
		(stroke
			(width 0.04445)
			(type default)
		)
		(layer "In4.Cu")
	)
	(gr_line
		(start 122.217688 -72.092058)
		(end 122.238516 -72.112886)
		(stroke
			(width 0.04445)
			(type default)
		)
		(layer "In4.Cu")
	)
	(gr_line
		(start 122.217688 -71.753984)
		(end 122.217688 -72.092058)
		(stroke
			(width 0.04445)
			(type default)
		)
		(layer "In4.Cu")
	)
	(gr_line
		(start 122.240294 -72.383904)
		(end 122.2756 -72.348598)
		(stroke
			(width 0.04445)
			(type default)
		)
		(layer "In4.Cu")
	)
	(gr_line
		(start 122.240294 -72.114664)
		(end 122.282966 -72.157336)
		(stroke
			(width 0.04445)
			(type default)
		)
		(layer "In4.Cu")
	)
	(gr_line
		(start 123.058428 -72.840088)
		(end 123.093988 -72.840088)
		(stroke
			(width 0.04445)
			(type default)
		)
		(layer "In4.Cu")
	)
	(gr_line
		(start 123.076208 -69.93001)
		(end 123.076208 -70.268084)
		(stroke
			(width 0.04445)
			(type default)
		)
		(layer "In4.Cu")
	)
	(gr_line
		(start 123.076208 -69.93001)
		(end 123.096782 -69.909436)
		(stroke
			(width 0.04445)
			(type default)
		)
		(layer "In4.Cu")
	)
	(gr_line
		(start 123.076208 -69.615812)
		(end 123.096782 -69.636386)
		(stroke
			(width 0.04445)
			(type default)
		)
		(layer "In4.Cu")
	)
	(gr_line
		(start 123.076208 -69.277738)
		(end 123.076208 -69.615812)
		(stroke
			(width 0.04445)
			(type default)
		)
		(layer "In4.Cu")
	)
	(gr_line
		(start 123.09856 -69.907658)
		(end 123.13412 -69.872098)
		(stroke
			(width 0.04445)
			(type default)
		)
		(layer "In4.Cu")
	)
	(gr_line
		(start 123.09856 -69.638164)
		(end 123.140978 -69.680582)
		(stroke
			(width 0.04445)
			(type default)
		)
		(layer "In4.Cu")
	)
	(gr_line
		(start 123.916948 -72.154034)
		(end 123.952508 -72.154034)
		(stroke
			(width 0.04445)
			(type default)
		)
		(layer "In4.Cu")
	)
	(gr_arc
		(start 124.814838 -70.668388)
		(mid 124.813187 -70.668386)
		(end 124.811536 -70.668388)
		(stroke
			(width 0.04445)
			(type default)
		)
		(layer "In4.Cu")
	)
	(gr_line
		(start 125.651768 -65.810384)
		(end 125.944884 -65.979548)
		(stroke
			(width 0.04445)
			(type default)
		)
		(layer "In4.Cu")
	)
	(gr_line
		(start 125.944884 -65.979548)
		(end 125.990096 -65.967356)
		(stroke
			(width 0.04445)
			(type default)
		)
		(layer "In4.Cu")
	)
	(gr_line
		(start 125.992128 -65.599818)
		(end 125.998478 -65.610486)
		(stroke
			(width 0.04445)
			(type default)
		)
		(layer "In4.Cu")
	)
	(gr_line
		(start 125.996192 -65.965578)
		(end 126.023624 -65.958212)
		(stroke
			(width 0.04445)
			(type default)
		)
		(layer "In4.Cu")
	)
	(gr_line
		(start 125.998478 -65.610486)
		(end 126.003304 -65.619122)
		(stroke
			(width 0.04445)
			(type default)
		)
		(layer "In4.Cu")
	)
	(gr_line
		(start 126.158752 -65.5066)
		(end 126.163578 -65.515236)
		(stroke
			(width 0.04445)
			(type default)
		)
		(layer "In4.Cu")
	)
	(gr_line
		(start 126.163578 -65.515236)
		(end 126.169928 -65.525904)
		(stroke
			(width 0.04445)
			(type default)
		)
		(layer "In4.Cu")
	)
	(gr_line
		(start 126.193296 -66.047366)
		(end 126.20117 -66.076576)
		(stroke
			(width 0.04445)
			(type default)
		)
		(layer "In4.Cu")
	)
	(gr_line
		(start 126.202948 -66.08318)
		(end 126.217172 -66.136774)
		(stroke
			(width 0.04445)
			(type default)
		)
		(layer "In4.Cu")
	)
	(gr_line
		(start 126.217172 -66.136774)
		(end 126.510288 -66.305938)
		(stroke
			(width 0.04445)
			(type default)
		)
		(layer "In4.Cu")
	)
	(gr_line
		(start 126.488698 -64.724788)
		(end 126.521464 -64.724788)
		(stroke
			(width 0.04445)
			(type default)
		)
		(layer "In4.Cu")
	)
	(gr_line
		(start 126.495302 -64.915288)
		(end 126.528068 -64.915288)
		(stroke
			(width 0.04445)
			(type default)
		)
		(layer "In4.Cu")
	)
	(gr_line
		(start 127.351028 -64.229234)
		(end 127.383794 -64.229234)
		(stroke
			(width 0.04445)
			(type default)
		)
		(layer "In4.Cu")
	)
	(gr_line
		(start 127.357632 -64.419734)
		(end 127.390398 -64.419734)
		(stroke
			(width 0.04445)
			(type default)
		)
		(layer "In4.Cu")
	)
	(gr_line
		(start 128.205738 -63.734188)
		(end 128.238504 -63.734188)
		(stroke
			(width 0.04445)
			(type default)
		)
		(layer "In4.Cu")
	)
	(gr_line
		(start 128.212342 -63.924688)
		(end 128.245108 -63.924688)
		(stroke
			(width 0.04445)
			(type default)
		)
		(layer "In4.Cu")
	)
	(gr_line
		(start 129.068068 -63.238634)
		(end 129.100834 -63.238634)
		(stroke
			(width 0.04445)
			(type default)
		)
		(layer "In4.Cu")
	)
	(gr_line
		(start 129.074672 -63.429134)
		(end 129.107438 -63.429134)
		(stroke
			(width 0.04445)
			(type default)
		)
		(layer "In4.Cu")
	)
	(gr_line
		(start 130.781298 -63.429134)
		(end 130.824478 -63.429134)
		(stroke
			(width 0.04445)
			(type default)
		)
		(layer "In4.Cu")
	)
	(gr_line
		(start 130.787902 -63.238634)
		(end 130.817874 -63.238634)
		(stroke
			(width 0.04445)
			(type default)
		)
		(layer "In4.Cu")
	)
	(gr_line
		(start 131.149598 -63.038736)
		(end 131.155948 -63.028068)
		(stroke
			(width 0.04445)
			(type default)
		)
		(layer "In4.Cu")
	)
	(gr_line
		(start 131.639818 -89.489788)
		(end 131.6863 -89.489788)
		(stroke
			(width 0.04445)
			(type default)
		)
		(layer "In4.Cu")
	)
	(gr_line
		(start 131.648454 -70.668134)
		(end 131.679188 -70.668134)
		(stroke
			(width 0.04445)
			(type default)
		)
		(layer "In4.Cu")
	)
	(gr_line
		(start 131.999736 -63.120016)
		(end 132.007864 -63.13424)
		(stroke
			(width 0.04445)
			(type default)
		)
		(layer "In4.Cu")
	)
	(gr_line
		(start 132.173218 -63.038482)
		(end 132.17652 -63.044324)
		(stroke
			(width 0.04445)
			(type default)
		)
		(layer "In4.Cu")
	)
	(gr_line
		(start 132.494782 -90.175334)
		(end 132.541264 -90.175334)
		(stroke
			(width 0.04445)
			(type default)
		)
		(layer "In4.Cu")
	)
	(gr_line
		(start 132.519166 -63.429388)
		(end 132.519928 -63.429388)
		(stroke
			(width 0.04445)
			(type default)
		)
		(layer "In4.Cu")
	)
	(gr_line
		(start 133.363208 -70.858888)
		(end 133.39318 -70.858888)
		(stroke
			(width 0.04445)
			(type default)
		)
		(layer "In4.Cu")
	)
	(gr_line
		(start 140.231368 -70.858888)
		(end 140.26134 -70.858888)
		(stroke
			(width 0.04445)
			(type default)
		)
		(layer "In4.Cu")
	)
	(gr_line
		(start 140.892276 -73.154286)
		(end 141.080998 -73.343008)
		(stroke
			(width 0.04445)
			(type default)
		)
		(layer "In4.Cu")
	)
	(gr_line
		(start 140.892276 -73.032112)
		(end 140.892276 -73.154286)
		(stroke
			(width 0.04445)
			(type default)
		)
		(layer "In4.Cu")
	)
	(gr_line
		(start 141.080998 -73.343008)
		(end 141.203172 -73.343008)
		(stroke
			(width 0.04445)
			(type default)
		)
		(layer "In4.Cu")
	)
	(gr_line
		(start 141.087094 -88.994234)
		(end 141.122654 -88.994234)
		(stroke
			(width 0.04445)
			(type default)
		)
		(layer "In4.Cu")
	)
	(gr_line
		(start 141.163548 -73.030334)
		(end 141.20495 -73.071736)
		(stroke
			(width 0.04445)
			(type default)
		)
		(layer "In4.Cu")
	)
	(gr_line
		(start 141.356334 -88.001094)
		(end 141.442694 -87.914734)
		(stroke
			(width 0.04445)
			(type default)
		)
		(layer "In4.Cu")
	)
	(gr_line
		(start 141.442694 -87.914734)
		(end 141.709394 -87.914734)
		(stroke
			(width 0.04445)
			(type default)
		)
		(layer "In4.Cu")
	)
	(gr_line
		(start 141.451584 -63.038736)
		(end 141.537182 -62.859666)
		(stroke
			(width 0.04445)
			(type default)
		)
		(layer "In4.Cu")
	)
	(gr_line
		(start 141.54658 -62.843156)
		(end 141.6304 -62.7126)
		(stroke
			(width 0.04445)
			(type default)
		)
		(layer "In4.Cu")
	)
	(gr_line
		(start 141.546834 -88.194134)
		(end 141.605254 -88.194134)
		(stroke
			(width 0.04445)
			(type default)
		)
		(layer "In4.Cu")
	)
	(gr_line
		(start 141.616684 -63.133986)
		(end 141.6812 -63.0174)
		(stroke
			(width 0.04445)
			(type default)
		)
		(layer "In4.Cu")
	)
	(gr_line
		(start 141.6304 -62.7126)
		(end 141.986 -62.662562)
		(stroke
			(width 0.04445)
			(type default)
		)
		(layer "In4.Cu")
	)
	(gr_line
		(start 141.6812 -63.0174)
		(end 141.713966 -62.984634)
		(stroke
			(width 0.04445)
			(type default)
		)
		(layer "In4.Cu")
	)
	(gr_line
		(start 141.709394 -87.914734)
		(end 141.795754 -88.001094)
		(stroke
			(width 0.04445)
			(type default)
		)
		(layer "In4.Cu")
	)
	(gr_line
		(start 141.724634 -62.973966)
		(end 141.7574 -62.9412)
		(stroke
			(width 0.04445)
			(type default)
		)
		(layer "In4.Cu")
	)
	(gr_line
		(start 141.7574 -62.9412)
		(end 141.986 -62.916562)
		(stroke
			(width 0.04445)
			(type default)
		)
		(layer "In4.Cu")
	)
	(gr_line
		(start 142.067534 -88.001094)
		(end 142.153894 -87.914734)
		(stroke
			(width 0.04445)
			(type default)
		)
		(layer "In4.Cu")
	)
	(gr_line
		(start 142.153894 -87.914734)
		(end 142.420594 -87.914734)
		(stroke
			(width 0.04445)
			(type default)
		)
		(layer "In4.Cu")
	)
	(gr_line
		(start 142.258034 -88.194134)
		(end 142.316454 -88.194134)
		(stroke
			(width 0.04445)
			(type default)
		)
		(layer "In4.Cu")
	)
	(gr_line
		(start 142.420594 -87.914734)
		(end 142.506954 -88.001094)
		(stroke
			(width 0.04445)
			(type default)
		)
		(layer "In4.Cu")
	)
	(gr_line
		(start 142.58544 -71.849488)
		(end 142.62481 -71.888858)
		(stroke
			(width 0.04445)
			(type default)
		)
		(layer "In4.Cu")
	)
	(gr_line
		(start 142.58544 -71.658988)
		(end 142.62481 -71.619618)
		(stroke
			(width 0.04445)
			(type default)
		)
		(layer "In4.Cu")
	)
	(gr_line
		(start 142.626588 -71.890636)
		(end 142.63624 -71.900288)
		(stroke
			(width 0.04445)
			(type default)
		)
		(layer "In4.Cu")
	)
	(gr_line
		(start 142.626588 -71.61784)
		(end 142.63624 -71.608188)
		(stroke
			(width 0.04445)
			(type default)
		)
		(layer "In4.Cu")
	)
	(gr_line
		(start 142.63624 -71.900288)
		(end 142.658338 -71.900288)
		(stroke
			(width 0.04445)
			(type default)
		)
		(layer "In4.Cu")
	)
	(gr_line
		(start 142.63624 -71.608188)
		(end 142.658338 -71.608188)
		(stroke
			(width 0.04445)
			(type default)
		)
		(layer "In4.Cu")
	)
	(gr_line
		(start 142.749524 -76.350368)
		(end 142.835884 -76.436728)
		(stroke
			(width 0.04445)
			(type default)
		)
		(layer "In4.Cu")
	)
	(gr_line
		(start 142.749524 -76.083668)
		(end 142.749524 -76.350368)
		(stroke
			(width 0.04445)
			(type default)
		)
		(layer "In4.Cu")
	)
	(gr_line
		(start 142.749524 -76.083668)
		(end 142.835884 -75.997308)
		(stroke
			(width 0.04445)
			(type default)
		)
		(layer "In4.Cu")
	)
	(gr_line
		(start 142.749524 -75.639168)
		(end 142.835884 -75.725528)
		(stroke
			(width 0.04445)
			(type default)
		)
		(layer "In4.Cu")
	)
	(gr_line
		(start 142.749524 -75.372468)
		(end 142.749524 -75.639168)
		(stroke
			(width 0.04445)
			(type default)
		)
		(layer "In4.Cu")
	)
	(gr_line
		(start 142.749524 -75.372468)
		(end 142.835884 -75.286108)
		(stroke
			(width 0.04445)
			(type default)
		)
		(layer "In4.Cu")
	)
	(gr_line
		(start 142.787624 -76.756768)
		(end 142.787624 -76.778866)
		(stroke
			(width 0.04445)
			(type default)
		)
		(layer "In4.Cu")
	)
	(gr_line
		(start 142.787624 -76.756768)
		(end 142.797276 -76.747116)
		(stroke
			(width 0.04445)
			(type default)
		)
		(layer "In4.Cu")
	)
	(gr_line
		(start 142.799054 -76.745338)
		(end 142.838424 -76.705968)
		(stroke
			(width 0.04445)
			(type default)
		)
		(layer "In4.Cu")
	)
	(gr_line
		(start 143.028924 -76.705968)
		(end 143.068294 -76.745338)
		(stroke
			(width 0.04445)
			(type default)
		)
		(layer "In4.Cu")
	)
	(gr_line
		(start 143.028924 -76.187808)
		(end 143.028924 -76.246228)
		(stroke
			(width 0.04445)
			(type default)
		)
		(layer "In4.Cu")
	)
	(gr_line
		(start 143.028924 -75.476608)
		(end 143.028924 -75.535028)
		(stroke
			(width 0.04445)
			(type default)
		)
		(layer "In4.Cu")
	)
	(gr_line
		(start 143.070072 -76.747116)
		(end 143.079724 -76.756768)
		(stroke
			(width 0.04445)
			(type default)
		)
		(layer "In4.Cu")
	)
	(gr_line
		(start 143.079724 -76.756768)
		(end 143.079724 -76.778866)
		(stroke
			(width 0.04445)
			(type default)
		)
		(layer "In4.Cu")
	)
	(gr_line
		(start 143.525494 -88.194134)
		(end 143.564864 -88.233504)
		(stroke
			(width 0.04445)
			(type default)
		)
		(layer "In4.Cu")
	)
	(gr_line
		(start 143.525494 -88.003634)
		(end 143.564864 -87.964264)
		(stroke
			(width 0.04445)
			(type default)
		)
		(layer "In4.Cu")
	)
	(gr_line
		(start 143.566642 -88.235282)
		(end 143.576294 -88.244934)
		(stroke
			(width 0.04445)
			(type default)
		)
		(layer "In4.Cu")
	)
	(gr_line
		(start 143.566642 -87.962486)
		(end 143.576294 -87.952834)
		(stroke
			(width 0.04445)
			(type default)
		)
		(layer "In4.Cu")
	)
	(gr_line
		(start 143.576294 -88.244934)
		(end 143.598392 -88.244934)
		(stroke
			(width 0.04445)
			(type default)
		)
		(layer "In4.Cu")
	)
	(gr_line
		(start 143.576294 -87.952834)
		(end 143.598392 -87.952834)
		(stroke
			(width 0.04445)
			(type default)
		)
		(layer "In4.Cu")
	)
	(gr_line
		(start 143.724376 -75.539854)
		(end 143.724376 -75.623674)
		(stroke
			(width 0.05715)
			(type default)
		)
		(layer "In4.Cu")
	)
	(gr_line
		(start 143.724376 -74.523854)
		(end 143.724376 -74.607674)
		(stroke
			(width 0.05715)
			(type default)
		)
		(layer "In4.Cu")
	)
	(gr_line
		(start 143.724376 -73.507854)
		(end 143.724376 -73.591674)
		(stroke
			(width 0.05715)
			(type default)
		)
		(layer "In4.Cu")
	)
	(gr_line
		(start 144.019016 -75.915774)
		(end 144.181576 -75.753214)
		(stroke
			(width 0.05715)
			(type default)
		)
		(layer "In4.Cu")
	)
	(gr_line
		(start 144.019016 -75.247754)
		(end 144.181576 -75.410314)
		(stroke
			(width 0.05715)
			(type default)
		)
		(layer "In4.Cu")
	)
	(gr_line
		(start 144.019016 -74.899774)
		(end 144.181576 -74.737214)
		(stroke
			(width 0.05715)
			(type default)
		)
		(layer "In4.Cu")
	)
	(gr_line
		(start 144.019016 -74.231754)
		(end 144.181576 -74.394314)
		(stroke
			(width 0.05715)
			(type default)
		)
		(layer "In4.Cu")
	)
	(gr_line
		(start 144.019016 -73.883774)
		(end 144.181576 -73.721214)
		(stroke
			(width 0.05715)
			(type default)
		)
		(layer "In4.Cu")
	)
	(gr_line
		(start 144.019016 -73.215754)
		(end 144.181576 -73.378314)
		(stroke
			(width 0.05715)
			(type default)
		)
		(layer "In4.Cu")
	)
	(gr_line
		(start 144.033748 -101.031294)
		(end 144.033748 -101.115114)
		(stroke
			(width 0.05715)
			(type default)
		)
		(layer "In4.Cu")
	)
	(gr_line
		(start 144.033748 -100.015294)
		(end 144.033748 -100.099114)
		(stroke
			(width 0.05715)
			(type default)
		)
		(layer "In4.Cu")
	)
	(gr_line
		(start 144.033748 -98.999294)
		(end 144.033748 -99.083114)
		(stroke
			(width 0.05715)
			(type default)
		)
		(layer "In4.Cu")
	)
	(gr_line
		(start 144.033748 -94.50959)
		(end 144.033748 -94.59341)
		(stroke
			(width 0.05715)
			(type default)
		)
		(layer "In4.Cu")
	)
	(gr_line
		(start 144.033748 -93.49359)
		(end 144.033748 -93.57741)
		(stroke
			(width 0.05715)
			(type default)
		)
		(layer "In4.Cu")
	)
	(gr_line
		(start 144.033748 -92.47759)
		(end 144.033748 -92.56141)
		(stroke
			(width 0.05715)
			(type default)
		)
		(layer "In4.Cu")
	)
	(gr_line
		(start 144.033748 -91.46159)
		(end 144.033748 -91.54541)
		(stroke
			(width 0.05715)
			(type default)
		)
		(layer "In4.Cu")
	)
	(gr_line
		(start 144.033748 -89.704164)
		(end 144.033748 -89.726262)
		(stroke
			(width 0.04445)
			(type default)
		)
		(layer "In4.Cu")
	)
	(gr_line
		(start 144.033748 -89.704164)
		(end 144.0434 -89.694512)
		(stroke
			(width 0.04445)
			(type default)
		)
		(layer "In4.Cu")
	)
	(gr_line
		(start 144.045178 -89.692734)
		(end 144.084548 -89.653364)
		(stroke
			(width 0.04445)
			(type default)
		)
		(layer "In4.Cu")
	)
	(gr_line
		(start 144.181576 -75.410314)
		(end 144.181576 -75.753214)
		(stroke
			(width 0.05715)
			(type default)
		)
		(layer "In4.Cu")
	)
	(gr_line
		(start 144.181576 -74.394314)
		(end 144.181576 -74.737214)
		(stroke
			(width 0.05715)
			(type default)
		)
		(layer "In4.Cu")
	)
	(gr_line
		(start 144.181576 -73.378314)
		(end 144.181576 -73.721214)
		(stroke
			(width 0.05715)
			(type default)
		)
		(layer "In4.Cu")
	)
	(gr_line
		(start 144.275048 -89.653364)
		(end 144.314418 -89.692734)
		(stroke
			(width 0.04445)
			(type default)
		)
		(layer "In4.Cu")
	)
	(gr_line
		(start 144.316196 -89.694512)
		(end 144.325848 -89.704164)
		(stroke
			(width 0.04445)
			(type default)
		)
		(layer "In4.Cu")
	)
	(gr_line
		(start 144.325848 -89.704164)
		(end 144.325848 -89.726262)
		(stroke
			(width 0.04445)
			(type default)
		)
		(layer "In4.Cu")
	)
	(gr_line
		(start 144.328388 -101.407214)
		(end 144.490948 -101.244654)
		(stroke
			(width 0.05715)
			(type default)
		)
		(layer "In4.Cu")
	)
	(gr_line
		(start 144.328388 -100.739194)
		(end 144.490948 -100.901754)
		(stroke
			(width 0.05715)
			(type default)
		)
		(layer "In4.Cu")
	)
	(gr_line
		(start 144.328388 -100.391214)
		(end 144.490948 -100.228654)
		(stroke
			(width 0.05715)
			(type default)
		)
		(layer "In4.Cu")
	)
	(gr_line
		(start 144.328388 -99.723194)
		(end 144.490948 -99.885754)
		(stroke
			(width 0.05715)
			(type default)
		)
		(layer "In4.Cu")
	)
	(gr_line
		(start 144.328388 -99.375214)
		(end 144.490948 -99.212654)
		(stroke
			(width 0.05715)
			(type default)
		)
		(layer "In4.Cu")
	)
	(gr_line
		(start 144.328388 -98.707194)
		(end 144.490948 -98.869754)
		(stroke
			(width 0.05715)
			(type default)
		)
		(layer "In4.Cu")
	)
	(gr_line
		(start 144.328388 -94.88551)
		(end 144.490948 -94.72295)
		(stroke
			(width 0.05715)
			(type default)
		)
		(layer "In4.Cu")
	)
	(gr_line
		(start 144.328388 -94.21749)
		(end 144.490948 -94.38005)
		(stroke
			(width 0.05715)
			(type default)
		)
		(layer "In4.Cu")
	)
	(gr_line
		(start 144.328388 -93.86951)
		(end 144.490948 -93.70695)
		(stroke
			(width 0.05715)
			(type default)
		)
		(layer "In4.Cu")
	)
	(gr_line
		(start 144.328388 -93.20149)
		(end 144.490948 -93.36405)
		(stroke
			(width 0.05715)
			(type default)
		)
		(layer "In4.Cu")
	)
	(gr_line
		(start 144.328388 -92.85351)
		(end 144.490948 -92.69095)
		(stroke
			(width 0.05715)
			(type default)
		)
		(layer "In4.Cu")
	)
	(gr_line
		(start 144.328388 -92.18549)
		(end 144.490948 -92.34805)
		(stroke
			(width 0.05715)
			(type default)
		)
		(layer "In4.Cu")
	)
	(gr_line
		(start 144.328388 -91.83751)
		(end 144.490948 -91.67495)
		(stroke
			(width 0.05715)
			(type default)
		)
		(layer "In4.Cu")
	)
	(gr_line
		(start 144.328388 -91.16949)
		(end 144.490948 -91.33205)
		(stroke
			(width 0.05715)
			(type default)
		)
		(layer "In4.Cu")
	)
	(gr_line
		(start 144.490948 -100.901754)
		(end 144.490948 -101.244654)
		(stroke
			(width 0.05715)
			(type default)
		)
		(layer "In4.Cu")
	)
	(gr_line
		(start 144.490948 -99.885754)
		(end 144.490948 -100.228654)
		(stroke
			(width 0.05715)
			(type default)
		)
		(layer "In4.Cu")
	)
	(gr_line
		(start 144.490948 -98.869754)
		(end 144.490948 -99.212654)
		(stroke
			(width 0.05715)
			(type default)
		)
		(layer "In4.Cu")
	)
	(gr_line
		(start 144.490948 -94.38005)
		(end 144.490948 -94.72295)
		(stroke
			(width 0.05715)
			(type default)
		)
		(layer "In4.Cu")
	)
	(gr_line
		(start 144.490948 -93.36405)
		(end 144.490948 -93.70695)
		(stroke
			(width 0.05715)
			(type default)
		)
		(layer "In4.Cu")
	)
	(gr_line
		(start 144.490948 -92.34805)
		(end 144.490948 -92.69095)
		(stroke
			(width 0.05715)
			(type default)
		)
		(layer "In4.Cu")
	)
	(gr_line
		(start 144.490948 -91.33205)
		(end 144.490948 -91.67495)
		(stroke
			(width 0.05715)
			(type default)
		)
		(layer "In4.Cu")
	)
	(gr_line
		(start 156.071824 -62.67323)
		(end 156.071824 -62.745366)
		(stroke
			(width 0.0635)
			(type default)
		)
		(layer "In4.Cu")
	)
	(gr_line
		(start 156.071824 -62.218824)
		(end 156.071824 -62.66815)
		(stroke
			(width 0.0635)
			(type default)
		)
		(layer "In4.Cu")
	)
	(gr_line
		(start 156.25191 -62.92469)
		(end 156.323284 -62.92469)
		(stroke
			(width 0.0635)
			(type default)
		)
		(layer "In4.Cu")
	)
	(gr_line
		(start 156.328364 -62.92469)
		(end 156.77769 -62.92469)
		(stroke
			(width 0.0635)
			(type default)
		)
		(layer "In4.Cu")
	)
	(gr_line
		(start 156.47924 -77.953616)
		(end 156.538168 -78.012544)
		(stroke
			(width 0.05715)
			(type default)
		)
		(layer "In4.Cu")
	)
	(gr_line
		(start 156.480764 -77.53858)
		(end 156.710888 -77.53858)
		(stroke
			(width 0.05715)
			(type default)
		)
		(layer "In4.Cu")
	)
	(gr_line
		(start 156.710888 -77.53858)
		(end 156.953204 -77.780896)
		(stroke
			(width 0.05715)
			(type default)
		)
		(layer "In4.Cu")
	)
	(gr_line
		(start 156.953204 -77.780896)
		(end 156.953204 -78.01102)
		(stroke
			(width 0.05715)
			(type default)
		)
		(layer "In4.Cu")
	)
	(gr_line
		(start 157.197552 -78.671928)
		(end 157.256734 -78.73111)
		(stroke
			(width 0.05715)
			(type default)
		)
		(layer "In4.Cu")
	)
	(gr_line
		(start 157.199076 -78.256892)
		(end 157.4292 -78.256892)
		(stroke
			(width 0.05715)
			(type default)
		)
		(layer "In4.Cu")
	)
	(gr_line
		(start 157.4292 -78.256892)
		(end 157.67177 -78.499462)
		(stroke
			(width 0.05715)
			(type default)
		)
		(layer "In4.Cu")
	)
	(gr_line
		(start 157.67177 -78.499462)
		(end 157.67177 -78.729586)
		(stroke
			(width 0.05715)
			(type default)
		)
		(layer "In4.Cu")
	)
	(gr_line
		(start 158.415482 -79.12862)
		(end 158.578042 -78.96606)
		(stroke
			(width 0.05715)
			(type default)
		)
		(layer "In4.Cu")
	)
	(gr_line
		(start 158.578042 -78.96606)
		(end 158.920942 -78.96606)
		(stroke
			(width 0.05715)
			(type default)
		)
		(layer "In4.Cu")
	)
	(gr_line
		(start 158.707582 -79.42326)
		(end 158.791402 -79.42326)
		(stroke
			(width 0.05715)
			(type default)
		)
		(layer "In4.Cu")
	)
	(gr_line
		(start 158.920942 -78.96606)
		(end 159.083502 -79.12862)
		(stroke
			(width 0.05715)
			(type default)
		)
		(layer "In4.Cu")
	)
	(gr_line
		(start 159.537146 -75.28306)
		(end 159.699706 -75.1205)
		(stroke
			(width 0.05715)
			(type default)
		)
		(layer "In4.Cu")
	)
	(gr_line
		(start 159.699706 -75.1205)
		(end 160.042606 -75.1205)
		(stroke
			(width 0.05715)
			(type default)
		)
		(layer "In4.Cu")
	)
	(gr_line
		(start 159.829246 -75.5777)
		(end 159.913066 -75.5777)
		(stroke
			(width 0.05715)
			(type default)
		)
		(layer "In4.Cu")
	)
	(gr_line
		(start 160.042606 -75.1205)
		(end 160.205166 -75.28306)
		(stroke
			(width 0.05715)
			(type default)
		)
		(layer "In4.Cu")
	)
	(gr_line
		(start 160.553146 -75.28306)
		(end 160.715706 -75.1205)
		(stroke
			(width 0.05715)
			(type default)
		)
		(layer "In4.Cu")
	)
	(gr_line
		(start 160.715706 -75.1205)
		(end 161.058606 -75.1205)
		(stroke
			(width 0.05715)
			(type default)
		)
		(layer "In4.Cu")
	)
	(gr_line
		(start 160.845246 -75.5777)
		(end 160.929066 -75.5777)
		(stroke
			(width 0.05715)
			(type default)
		)
		(layer "In4.Cu")
	)
	(gr_line
		(start 161.058606 -75.1205)
		(end 161.221166 -75.28306)
		(stroke
			(width 0.05715)
			(type default)
		)
		(layer "In4.Cu")
	)
	(gr_line
		(start 161.89833 -77.55128)
		(end 161.9504 -77.60335)
		(stroke
			(width 0.05715)
			(type default)
		)
		(layer "In4.Cu")
	)
	(gr_line
		(start 161.89833 -77.13472)
		(end 161.9504 -77.08265)
		(stroke
			(width 0.05715)
			(type default)
		)
		(layer "In4.Cu")
	)
	(gr_line
		(start 161.898584 -85.26653)
		(end 161.970974 -85.33892)
		(stroke
			(width 0.05715)
			(type default)
		)
		(layer "In4.Cu")
	)
	(gr_line
		(start 161.898584 -84.84997)
		(end 161.970974 -84.77758)
		(stroke
			(width 0.05715)
			(type default)
		)
		(layer "In4.Cu")
	)
	(gr_line
		(start 161.9504 -77.60335)
		(end 161.9504 -77.978)
		(stroke
			(width 0.05715)
			(type default)
		)
		(layer "In4.Cu")
	)
	(gr_line
		(start 161.9504 -76.708)
		(end 161.9504 -77.08265)
		(stroke
			(width 0.05715)
			(type default)
		)
		(layer "In4.Cu")
	)
	(gr_line
		(start 161.970974 -85.33892)
		(end 161.970974 -85.69706)
		(stroke
			(width 0.05715)
			(type default)
		)
		(layer "In4.Cu")
	)
	(gr_line
		(start 161.970974 -84.42706)
		(end 161.970974 -84.77758)
		(stroke
			(width 0.05715)
			(type default)
		)
		(layer "In4.Cu")
	)
	(gr_line
		(start 164.895276 -89.206324)
		(end 165.321996 -89.633044)
		(stroke
			(width 0.05715)
			(type default)
		)
		(layer "In4.Cu")
	)
	(gr_line
		(start 165.738556 -89.633044)
		(end 166.165276 -89.206324)
		(stroke
			(width 0.05715)
			(type default)
		)
		(layer "In4.Cu")
	)
	(gr_line
		(start 166.7383 -89.078816)
		(end 166.7383 -89.094818)
		(stroke
			(width 0.05715)
			(type default)
		)
		(layer "In4.Cu")
	)
	(gr_line
		(start 166.878 -88.789256)
		(end 166.878 -88.805258)
		(stroke
			(width 0.05715)
			(type default)
		)
		(layer "In4.Cu")
	)
	(gr_line
		(start 167.562276 -89.206324)
		(end 167.75303 -89.206324)
		(stroke
			(width 0.05715)
			(type default)
		)
		(layer "In4.Cu")
	)
	(gr_line
		(start 167.75303 -89.206324)
		(end 167.846248 -89.299542)
		(stroke
			(width 0.05715)
			(type default)
		)
		(layer "In4.Cu")
	)
	(gr_line
		(start 168.262808 -89.299542)
		(end 168.356026 -89.206324)
		(stroke
			(width 0.05715)
			(type default)
		)
		(layer "In4.Cu")
	)
	(gr_line
		(start 168.356026 -89.206324)
		(end 168.705276 -89.206324)
		(stroke
			(width 0.05715)
			(type default)
		)
		(layer "In4.Cu")
	)
	(gr_line
		(start 187.429648 -80.137)
		(end 187.429648 -80.601312)
		(stroke
			(width 0.0635)
			(type default)
		)
		(layer "In4.Cu")
	)
	(gr_line
		(start 187.660788 -80.829912)
		(end 188.344048 -80.146652)
		(stroke
			(width 0.0635)
			(type default)
		)
		(layer "In4.Cu")
	)
	(gr_line
		(start 204.210158 -103.12654)
		(end 204.563218 -103.4796)
		(stroke
			(width 0.0635)
			(type default)
		)
		(layer "In4.Cu")
	)
	(gr_line
		(start 204.3176 -102.8954)
		(end 204.6224 -102.5906)
		(stroke
			(width 0.0635)
			(type default)
		)
		(layer "In4.Cu")
	)
	(gr_line
		(start 292.36924 -98.500184)
		(end 292.662356 -98.331274)
		(stroke
			(width 0.04445)
			(type default)
		)
		(layer "In4.Cu")
	)
	(gr_line
		(start 292.662356 -98.331274)
		(end 292.749732 -98.354896)
		(stroke
			(width 0.04445)
			(type default)
		)
		(layer "In4.Cu")
	)
	(gr_line
		(start 292.91407 -98.25101)
		(end 292.934644 -98.174048)
		(stroke
			(width 0.04445)
			(type default)
		)
		(layer "In4.Cu")
	)
	(gr_line
		(start 292.934644 -98.174048)
		(end 293.22776 -98.005138)
		(stroke
			(width 0.04445)
			(type default)
		)
		(layer "In4.Cu")
	)
	(gr_line
		(start 293.22776 -100.976684)
		(end 293.604442 -100.976684)
		(stroke
			(width 0.04445)
			(type default)
		)
		(layer "In4.Cu")
	)
	(gr_line
		(start 293.22776 -99.648264)
		(end 293.22776 -99.986338)
		(stroke
			(width 0.04445)
			(type default)
		)
		(layer "In4.Cu")
	)
	(gr_line
		(start 293.22776 -99.648264)
		(end 293.248588 -99.627436)
		(stroke
			(width 0.04445)
			(type default)
		)
		(layer "In4.Cu")
	)
	(gr_line
		(start 293.22776 -99.333812)
		(end 293.248588 -99.35464)
		(stroke
			(width 0.04445)
			(type default)
		)
		(layer "In4.Cu")
	)
	(gr_line
		(start 293.22776 -98.995738)
		(end 293.22776 -99.333812)
		(stroke
			(width 0.04445)
			(type default)
		)
		(layer "In4.Cu")
	)
	(gr_line
		(start 293.250366 -99.625658)
		(end 293.285672 -99.590352)
		(stroke
			(width 0.04445)
			(type default)
		)
		(layer "In4.Cu")
	)
	(gr_line
		(start 293.250366 -99.356418)
		(end 293.292784 -99.398836)
		(stroke
			(width 0.04445)
			(type default)
		)
		(layer "In4.Cu")
	)
	(gr_line
		(start 293.772082 -100.729288)
		(end 293.793164 -100.650548)
		(stroke
			(width 0.04445)
			(type default)
		)
		(layer "In4.Cu")
	)
	(gr_line
		(start 293.793164 -100.650548)
		(end 294.08628 -100.481638)
		(stroke
			(width 0.04445)
			(type default)
		)
		(layer "In4.Cu")
	)
	(gr_arc
		(start 293.86022 -101.027484)
		(mid 293.734827 -100.989519)
		(end 293.604442 -100.976684)
		(stroke
			(width 0.04445)
			(type default)
		)
		(layer "In4.Cu")
	)
	(gr_line
		(start 294.08628 -99.490784)
		(end 294.379396 -99.659948)
		(stroke
			(width 0.04445)
			(type default)
		)
		(layer "In4.Cu")
	)
	(gr_line
		(start 294.379396 -99.659948)
		(end 294.466772 -99.636326)
		(stroke
			(width 0.04445)
			(type default)
		)
		(layer "In4.Cu")
	)
	(gr_line
		(start 294.43299 -95.328486)
		(end 294.437816 -95.337122)
		(stroke
			(width 0.04445)
			(type default)
		)
		(layer "In4.Cu")
	)
	(gr_line
		(start 294.593264 -94.234)
		(end 294.59809 -94.242636)
		(stroke
			(width 0.04445)
			(type default)
		)
		(layer "In4.Cu")
	)
	(gr_line
		(start 294.63111 -99.740212)
		(end 294.651684 -99.817174)
		(stroke
			(width 0.04445)
			(type default)
		)
		(layer "In4.Cu")
	)
	(gr_line
		(start 294.651684 -99.817174)
		(end 294.9448 -99.986338)
		(stroke
			(width 0.04445)
			(type default)
		)
		(layer "In4.Cu")
	)
	(gr_line
		(start 294.879522 -97.601786)
		(end 294.922194 -97.644458)
		(stroke
			(width 0.04445)
			(type default)
		)
		(layer "In4.Cu")
	)
	(gr_line
		(start 294.886888 -97.410524)
		(end 294.922194 -97.375218)
		(stroke
			(width 0.04445)
			(type default)
		)
		(layer "In4.Cu")
	)
	(gr_line
		(start 294.923972 -97.646236)
		(end 294.9448 -97.667064)
		(stroke
			(width 0.04445)
			(type default)
		)
		(layer "In4.Cu")
	)
	(gr_line
		(start 294.923972 -97.37344)
		(end 294.96766 -97.329752)
		(stroke
			(width 0.04445)
			(type default)
		)
		(layer "In4.Cu")
	)
	(gr_line
		(start 294.9448 -97.667064)
		(end 294.9448 -98.005138)
		(stroke
			(width 0.04445)
			(type default)
		)
		(layer "In4.Cu")
	)
	(gr_line
		(start 294.9448 -97.014538)
		(end 294.96766 -97.037398)
		(stroke
			(width 0.04445)
			(type default)
		)
		(layer "In4.Cu")
	)
	(gr_line
		(start 294.96766 -97.037398)
		(end 294.96766 -97.329752)
		(stroke
			(width 0.04445)
			(type default)
		)
		(layer "In4.Cu")
	)
	(gr_line
		(start 295.451784 -95.337122)
		(end 295.45661 -95.328486)
		(stroke
			(width 0.04445)
			(type default)
		)
		(layer "In4.Cu")
	)
	(gr_line
		(start 295.456864 -101.671882)
		(end 295.460166 -101.677724)
		(stroke
			(width 0.04445)
			(type default)
		)
		(layer "In4.Cu")
	)
	(gr_line
		(start 295.788334 -99.890834)
		(end 295.818306 -99.890834)
		(stroke
			(width 0.04445)
			(type default)
		)
		(layer "In4.Cu")
	)
	(gr_line
		(start 295.80332 -97.509584)
		(end 296.096436 -97.678748)
		(stroke
			(width 0.04445)
			(type default)
		)
		(layer "In4.Cu")
	)
	(gr_line
		(start 296.096436 -97.678748)
		(end 296.173398 -97.65792)
		(stroke
			(width 0.04445)
			(type default)
		)
		(layer "In4.Cu")
	)
	(gr_line
		(start 296.15003 -95.328486)
		(end 296.154856 -95.337122)
		(stroke
			(width 0.04445)
			(type default)
		)
		(layer "In4.Cu")
	)
	(gr_line
		(start 296.345356 -97.748598)
		(end 296.368724 -97.835974)
		(stroke
			(width 0.04445)
			(type default)
		)
		(layer "In4.Cu")
	)
	(gr_line
		(start 296.368724 -97.835974)
		(end 296.66184 -98.005138)
		(stroke
			(width 0.04445)
			(type default)
		)
		(layer "In4.Cu")
	)
	(gr_line
		(start 296.66184 -102.620064)
		(end 296.66184 -102.958138)
		(stroke
			(width 0.04445)
			(type default)
		)
		(layer "In4.Cu")
	)
	(gr_line
		(start 296.66184 -102.620064)
		(end 296.682668 -102.599236)
		(stroke
			(width 0.04445)
			(type default)
		)
		(layer "In4.Cu")
	)
	(gr_line
		(start 296.66184 -102.305612)
		(end 296.682668 -102.32644)
		(stroke
			(width 0.04445)
			(type default)
		)
		(layer "In4.Cu")
	)
	(gr_line
		(start 296.66184 -101.967538)
		(end 296.66184 -102.305612)
		(stroke
			(width 0.04445)
			(type default)
		)
		(layer "In4.Cu")
	)
	(gr_line
		(start 296.66184 -97.014538)
		(end 296.954702 -96.845628)
		(stroke
			(width 0.04445)
			(type default)
		)
		(layer "In4.Cu")
	)
	(gr_line
		(start 296.66184 -95.685864)
		(end 296.66184 -96.023938)
		(stroke
			(width 0.04445)
			(type default)
		)
		(layer "In4.Cu")
	)
	(gr_line
		(start 296.66184 -95.685864)
		(end 296.682668 -95.665036)
		(stroke
			(width 0.04445)
			(type default)
		)
		(layer "In4.Cu")
	)
	(gr_line
		(start 296.66184 -95.371158)
		(end 296.682668 -95.391986)
		(stroke
			(width 0.04445)
			(type default)
		)
		(layer "In4.Cu")
	)
	(gr_line
		(start 296.66184 -95.033084)
		(end 296.66184 -95.371158)
		(stroke
			(width 0.04445)
			(type default)
		)
		(layer "In4.Cu")
	)
	(gr_line
		(start 296.684446 -102.597458)
		(end 296.719498 -102.562406)
		(stroke
			(width 0.04445)
			(type default)
		)
		(layer "In4.Cu")
	)
	(gr_line
		(start 296.684446 -102.328218)
		(end 296.726864 -102.370636)
		(stroke
			(width 0.04445)
			(type default)
		)
		(layer "In4.Cu")
	)
	(gr_line
		(start 296.684446 -95.663258)
		(end 296.727118 -95.620586)
		(stroke
			(width 0.04445)
			(type default)
		)
		(layer "In4.Cu")
	)
	(gr_line
		(start 296.684446 -95.393764)
		(end 296.719498 -95.428816)
		(stroke
			(width 0.04445)
			(type default)
		)
		(layer "In4.Cu")
	)
	(gr_line
		(start 296.954702 -96.845628)
		(end 296.97553 -96.768158)
		(stroke
			(width 0.04445)
			(type default)
		)
		(layer "In4.Cu")
	)
	(gr_line
		(start 297.004994 -95.238824)
		(end 297.008296 -95.232982)
		(stroke
			(width 0.04445)
			(type default)
		)
		(layer "In4.Cu")
	)
	(gr_line
		(start 297.139106 -96.664018)
		(end 297.227244 -96.687894)
		(stroke
			(width 0.04445)
			(type default)
		)
		(layer "In4.Cu")
	)
	(gr_line
		(start 297.17365 -100.28174)
		(end 297.176952 -100.275898)
		(stroke
			(width 0.04445)
			(type default)
		)
		(layer "In4.Cu")
	)
	(gr_line
		(start 297.17365 -94.33814)
		(end 297.176952 -94.332298)
		(stroke
			(width 0.04445)
			(type default)
		)
		(layer "In4.Cu")
	)
	(gr_line
		(start 297.227244 -96.687894)
		(end 297.520106 -96.518984)
		(stroke
			(width 0.04445)
			(type default)
		)
		(layer "In4.Cu")
	)
	(gr_line
		(start 297.520106 -102.462584)
		(end 297.771312 -102.607618)
		(stroke
			(width 0.04445)
			(type default)
		)
		(layer "In4.Cu")
	)
	(gr_line
		(start 297.771312 -102.607618)
		(end 297.900852 -102.607618)
		(stroke
			(width 0.04445)
			(type default)
		)
		(layer "In4.Cu")
	)
	(gr_line
		(start 297.98137 -103.685086)
		(end 297.981878 -103.68534)
		(stroke
			(width 0.04445)
			(type default)
		)
		(layer "In4.Cu")
	)
	(gr_line
		(start 297.981878 -103.68534)
		(end 297.982386 -103.685594)
		(stroke
			(width 0.04445)
			(type default)
		)
		(layer "In4.Cu")
	)
	(gr_line
		(start 298.064936 -102.712012)
		(end 298.08551 -102.788974)
		(stroke
			(width 0.04445)
			(type default)
		)
		(layer "In4.Cu")
	)
	(gr_line
		(start 298.08551 -102.788974)
		(end 298.378626 -102.958138)
		(stroke
			(width 0.04445)
			(type default)
		)
		(layer "In4.Cu")
	)
	(gr_line
		(start 298.378626 -101.967538)
		(end 298.603162 -101.837998)
		(stroke
			(width 0.04445)
			(type default)
		)
		(layer "In4.Cu")
	)
	(gr_line
		(start 298.603162 -101.837998)
		(end 298.745656 -101.837998)
		(stroke
			(width 0.04445)
			(type default)
		)
		(layer "In4.Cu")
	)
	(gr_line
		(start 298.745656 -101.837998)
		(end 298.760134 -101.82352)
		(stroke
			(width 0.04445)
			(type default)
		)
		(layer "In4.Cu")
	)
	(gr_line
		(start 298.923456 -101.71811)
		(end 298.94403 -101.641148)
		(stroke
			(width 0.04445)
			(type default)
		)
		(layer "In4.Cu")
	)
	(gr_line
		(start 298.94403 -101.641148)
		(end 299.237146 -101.471984)
		(stroke
			(width 0.04445)
			(type default)
		)
		(layer "In4.Cu")
	)
	(gr_line
		(start 299.20565 -102.862634)
		(end 299.237146 -102.867714)
		(stroke
			(width 0.04445)
			(type default)
		)
		(layer "In4.Cu")
	)
	(gr_line
		(start 299.237146 -100.481384)
		(end 299.530262 -100.650294)
		(stroke
			(width 0.04445)
			(type default)
		)
		(layer "In4.Cu")
	)
	(gr_line
		(start 299.4279 -101.872034)
		(end 299.433488 -101.874574)
		(stroke
			(width 0.04445)
			(type default)
		)
		(layer "In4.Cu")
	)
	(gr_line
		(start 299.530262 -100.650294)
		(end 299.55363 -100.737924)
		(stroke
			(width 0.04445)
			(type default)
		)
		(layer "In4.Cu")
	)
	(gr_line
		(start 299.725334 -100.828602)
		(end 299.80255 -100.807774)
		(stroke
			(width 0.04445)
			(type default)
		)
		(layer "In4.Cu")
	)
	(gr_line
		(start 299.80255 -100.807774)
		(end 300.095666 -100.976684)
		(stroke
			(width 0.04445)
			(type default)
		)
		(layer "In4.Cu")
	)
	(gr_line
		(start 299.83557 -104.452928)
		(end 299.841158 -104.455468)
		(stroke
			(width 0.04445)
			(type default)
		)
		(layer "In4.Cu")
	)
	(gr_arc
		(start 300.095666 -75.221338)
		(mid 300.405453 -75.256385)
		(end 300.707552 -75.179428)
		(stroke
			(width 0.04445)
			(type default)
		)
		(layer "In4.Cu")
	)
	(gr_line
		(start 300.580806 -102.555548)
		(end 300.586394 -102.558088)
		(stroke
			(width 0.04445)
			(type default)
		)
		(layer "In4.Cu")
	)
	(gr_line
		(start 300.59503 -99.667568)
		(end 300.632114 -99.594924)
		(stroke
			(width 0.04445)
			(type default)
		)
		(layer "In4.Cu")
	)
	(gr_arc
		(start 300.59503 -99.667568)
		(mid 300.615648 -99.704305)
		(end 300.639988 -99.738688)
		(stroke
			(width 0.04445)
			(type default)
		)
		(layer "In4.Cu")
	)
	(gr_line
		(start 300.632114 -99.594924)
		(end 300.954186 -99.490784)
		(stroke
			(width 0.04445)
			(type default)
		)
		(layer "In4.Cu")
	)
	(gr_line
		(start 300.639988 -75.468734)
		(end 300.66107 -75.547474)
		(stroke
			(width 0.04445)
			(type default)
		)
		(layer "In4.Cu")
	)
	(gr_line
		(start 300.66107 -75.547474)
		(end 300.954186 -75.716384)
		(stroke
			(width 0.04445)
			(type default)
		)
		(layer "In4.Cu")
	)
	(gr_line
		(start 300.749716 -104.455468)
		(end 300.789086 -104.494838)
		(stroke
			(width 0.04445)
			(type default)
		)
		(layer "In4.Cu")
	)
	(gr_line
		(start 300.749716 -104.264968)
		(end 300.789086 -104.225598)
		(stroke
			(width 0.04445)
			(type default)
		)
		(layer "In4.Cu")
	)
	(gr_line
		(start 300.790864 -104.496616)
		(end 300.800516 -104.506268)
		(stroke
			(width 0.04445)
			(type default)
		)
		(layer "In4.Cu")
	)
	(gr_line
		(start 300.790864 -104.22382)
		(end 300.800516 -104.214168)
		(stroke
			(width 0.04445)
			(type default)
		)
		(layer "In4.Cu")
	)
	(gr_line
		(start 300.800516 -104.506268)
		(end 300.822614 -104.506268)
		(stroke
			(width 0.04445)
			(type default)
		)
		(layer "In4.Cu")
	)
	(gr_line
		(start 300.800516 -104.214168)
		(end 300.822614 -104.214168)
		(stroke
			(width 0.04445)
			(type default)
		)
		(layer "In4.Cu")
	)
	(gr_arc
		(start 300.83125 -100.068888)
		(mid 300.465767 -100.007036)
		(end 300.095666 -99.986338)
		(stroke
			(width 0.04445)
			(type default)
		)
		(layer "In4.Cu")
	)
	(gr_line
		(start 300.954186 -101.161088)
		(end 300.954186 -101.471984)
		(stroke
			(width 0.04445)
			(type default)
		)
		(layer "In4.Cu")
	)
	(gr_line
		(start 300.954186 -101.161088)
		(end 301.001938 -101.113336)
		(stroke
			(width 0.04445)
			(type default)
		)
		(layer "In4.Cu")
	)
	(gr_line
		(start 300.954186 -100.792788)
		(end 301.001938 -100.84054)
		(stroke
			(width 0.04445)
			(type default)
		)
		(layer "In4.Cu")
	)
	(gr_line
		(start 300.954186 -100.481384)
		(end 300.954186 -100.792788)
		(stroke
			(width 0.04445)
			(type default)
		)
		(layer "In4.Cu")
	)
	(gr_line
		(start 300.954186 -98.500184)
		(end 301.247302 -98.669348)
		(stroke
			(width 0.04445)
			(type default)
		)
		(layer "In4.Cu")
	)
	(gr_line
		(start 300.954186 -88.594184)
		(end 301.205392 -88.449404)
		(stroke
			(width 0.04445)
			(type default)
		)
		(layer "In4.Cu")
	)
	(gr_line
		(start 300.954186 -87.26551)
		(end 300.954186 -87.603584)
		(stroke
			(width 0.04445)
			(type default)
		)
		(layer "In4.Cu")
	)
	(gr_line
		(start 300.954186 -87.26551)
		(end 300.975014 -87.244682)
		(stroke
			(width 0.04445)
			(type default)
		)
		(layer "In4.Cu")
	)
	(gr_line
		(start 300.954186 -86.951058)
		(end 300.975014 -86.971886)
		(stroke
			(width 0.04445)
			(type default)
		)
		(layer "In4.Cu")
	)
	(gr_line
		(start 300.954186 -86.612984)
		(end 300.954186 -86.951058)
		(stroke
			(width 0.04445)
			(type default)
		)
		(layer "In4.Cu")
	)
	(gr_line
		(start 300.954186 -80.33131)
		(end 300.954186 -80.669384)
		(stroke
			(width 0.04445)
			(type default)
		)
		(layer "In4.Cu")
	)
	(gr_line
		(start 300.954186 -80.33131)
		(end 300.975014 -80.310482)
		(stroke
			(width 0.04445)
			(type default)
		)
		(layer "In4.Cu")
	)
	(gr_line
		(start 300.954186 -80.016858)
		(end 300.975014 -80.037686)
		(stroke
			(width 0.04445)
			(type default)
		)
		(layer "In4.Cu")
	)
	(gr_line
		(start 300.954186 -79.678784)
		(end 300.954186 -80.016858)
		(stroke
			(width 0.04445)
			(type default)
		)
		(layer "In4.Cu")
	)
	(gr_line
		(start 300.954186 -77.697584)
		(end 301.247302 -77.866748)
		(stroke
			(width 0.04445)
			(type default)
		)
		(layer "In4.Cu")
	)
	(gr_line
		(start 300.976792 -87.242904)
		(end 301.012098 -87.207598)
		(stroke
			(width 0.04445)
			(type default)
		)
		(layer "In4.Cu")
	)
	(gr_line
		(start 300.976792 -86.973664)
		(end 301.019464 -87.016336)
		(stroke
			(width 0.04445)
			(type default)
		)
		(layer "In4.Cu")
	)
	(gr_line
		(start 300.976792 -80.308704)
		(end 301.012098 -80.273398)
		(stroke
			(width 0.04445)
			(type default)
		)
		(layer "In4.Cu")
	)
	(gr_line
		(start 300.976792 -80.039464)
		(end 301.019464 -80.082136)
		(stroke
			(width 0.04445)
			(type default)
		)
		(layer "In4.Cu")
	)
	(gr_line
		(start 301.003716 -101.111558)
		(end 301.043086 -101.072188)
		(stroke
			(width 0.04445)
			(type default)
		)
		(layer "In4.Cu")
	)
	(gr_line
		(start 301.003716 -100.842318)
		(end 301.043086 -100.881688)
		(stroke
			(width 0.04445)
			(type default)
		)
		(layer "In4.Cu")
	)
	(gr_line
		(start 301.06493 -103.081328)
		(end 301.15129 -103.167688)
		(stroke
			(width 0.04445)
			(type default)
		)
		(layer "In4.Cu")
	)
	(gr_line
		(start 301.15129 -103.167688)
		(end 301.43069 -103.167688)
		(stroke
			(width 0.04445)
			(type default)
		)
		(layer "In4.Cu")
	)
	(gr_line
		(start 301.205392 -88.449404)
		(end 301.334932 -88.449404)
		(stroke
			(width 0.04445)
			(type default)
		)
		(layer "In4.Cu")
	)
	(gr_line
		(start 301.247302 -98.669348)
		(end 301.334678 -98.645726)
		(stroke
			(width 0.04445)
			(type default)
		)
		(layer "In4.Cu")
	)
	(gr_line
		(start 301.247302 -77.866748)
		(end 301.334678 -77.843126)
		(stroke
			(width 0.04445)
			(type default)
		)
		(layer "In4.Cu")
	)
	(gr_line
		(start 301.25543 -102.888288)
		(end 301.32655 -102.888288)
		(stroke
			(width 0.04445)
			(type default)
		)
		(layer "In4.Cu")
	)
	(gr_line
		(start 301.300896 -100.281486)
		(end 301.300896 -100.28174)
		(stroke
			(width 0.04445)
			(type default)
		)
		(layer "In4.Cu")
	)
	(gr_line
		(start 301.43069 -103.167688)
		(end 301.51705 -103.081328)
		(stroke
			(width 0.04445)
			(type default)
		)
		(layer "In4.Cu")
	)
	(gr_line
		(start 301.450502 -101.843078)
		(end 301.527972 -101.74859)
		(stroke
			(width 0.04445)
			(type default)
		)
		(layer "In4.Cu")
	)
	(gr_line
		(start 301.497492 -102.032562)
		(end 301.879 -101.99497)
		(stroke
			(width 0.04445)
			(type default)
		)
		(layer "In4.Cu")
	)
	(gr_line
		(start 301.499016 -98.749612)
		(end 301.53991 -98.90252)
		(stroke
			(width 0.04445)
			(type default)
		)
		(layer "In4.Cu")
	)
	(gr_line
		(start 301.499016 -88.34501)
		(end 301.51959 -88.268048)
		(stroke
			(width 0.04445)
			(type default)
		)
		(layer "In4.Cu")
	)
	(gr_line
		(start 301.499016 -77.947012)
		(end 301.51959 -78.023974)
		(stroke
			(width 0.04445)
			(type default)
		)
		(layer "In4.Cu")
	)
	(gr_line
		(start 301.51959 -88.268048)
		(end 301.812706 -88.099138)
		(stroke
			(width 0.04445)
			(type default)
		)
		(layer "In4.Cu")
	)
	(gr_line
		(start 301.51959 -78.023974)
		(end 301.812706 -78.193138)
		(stroke
			(width 0.04445)
			(type default)
		)
		(layer "In4.Cu")
	)
	(gr_line
		(start 301.527972 -101.74859)
		(end 301.793402 -101.722428)
		(stroke
			(width 0.04445)
			(type default)
		)
		(layer "In4.Cu")
	)
	(gr_line
		(start 301.53991 -98.90252)
		(end 301.73676 -99.016058)
		(stroke
			(width 0.04445)
			(type default)
		)
		(layer "In4.Cu")
	)
	(gr_line
		(start 301.73676 -99.016058)
		(end 301.812706 -98.995738)
		(stroke
			(width 0.04445)
			(type default)
		)
		(layer "In4.Cu")
	)
	(gr_line
		(start 301.793402 -101.722428)
		(end 301.88789 -101.799898)
		(stroke
			(width 0.04445)
			(type default)
		)
		(layer "In4.Cu")
	)
	(gr_line
		(start 301.80153 -103.081328)
		(end 301.88789 -103.167688)
		(stroke
			(width 0.04445)
			(type default)
		)
		(layer "In4.Cu")
	)
	(gr_line
		(start 301.812706 -98.005138)
		(end 302.105822 -97.835974)
		(stroke
			(width 0.04445)
			(type default)
		)
		(layer "In4.Cu")
	)
	(gr_line
		(start 301.812706 -87.108538)
		(end 302.063912 -87.253318)
		(stroke
			(width 0.04445)
			(type default)
		)
		(layer "In4.Cu")
	)
	(gr_line
		(start 301.812706 -84.136738)
		(end 302.105822 -83.967574)
		(stroke
			(width 0.04445)
			(type default)
		)
		(layer "In4.Cu")
	)
	(gr_line
		(start 301.812706 -82.808064)
		(end 301.812706 -83.146138)
		(stroke
			(width 0.04445)
			(type default)
		)
		(layer "In4.Cu")
	)
	(gr_line
		(start 301.812706 -82.808064)
		(end 301.833534 -82.787236)
		(stroke
			(width 0.04445)
			(type default)
		)
		(layer "In4.Cu")
	)
	(gr_line
		(start 301.812706 -82.493358)
		(end 301.833534 -82.514186)
		(stroke
			(width 0.04445)
			(type default)
		)
		(layer "In4.Cu")
	)
	(gr_line
		(start 301.812706 -82.155284)
		(end 301.812706 -82.493358)
		(stroke
			(width 0.04445)
			(type default)
		)
		(layer "In4.Cu")
	)
	(gr_line
		(start 301.812706 -80.174338)
		(end 302.105822 -80.343248)
		(stroke
			(width 0.04445)
			(type default)
		)
		(layer "In4.Cu")
	)
	(gr_line
		(start 301.812706 -77.202538)
		(end 302.105822 -77.033374)
		(stroke
			(width 0.04445)
			(type default)
		)
		(layer "In4.Cu")
	)
	(gr_line
		(start 301.812706 -75.873864)
		(end 301.812706 -76.211938)
		(stroke
			(width 0.04445)
			(type default)
		)
		(layer "In4.Cu")
	)
	(gr_line
		(start 301.812706 -75.873864)
		(end 301.833534 -75.853036)
		(stroke
			(width 0.04445)
			(type default)
		)
		(layer "In4.Cu")
	)
	(gr_line
		(start 301.812706 -75.559412)
		(end 301.833534 -75.58024)
		(stroke
			(width 0.04445)
			(type default)
		)
		(layer "In4.Cu")
	)
	(gr_line
		(start 301.812706 -75.221338)
		(end 301.812706 -75.559412)
		(stroke
			(width 0.04445)
			(type default)
		)
		(layer "In4.Cu")
	)
	(gr_line
		(start 301.835312 -82.785458)
		(end 301.877984 -82.742786)
		(stroke
			(width 0.04445)
			(type default)
		)
		(layer "In4.Cu")
	)
	(gr_line
		(start 301.835312 -82.515964)
		(end 301.870618 -82.55127)
		(stroke
			(width 0.04445)
			(type default)
		)
		(layer "In4.Cu")
	)
	(gr_line
		(start 301.835312 -75.851258)
		(end 301.877984 -75.808586)
		(stroke
			(width 0.04445)
			(type default)
		)
		(layer "In4.Cu")
	)
	(gr_line
		(start 301.835312 -75.582018)
		(end 301.870618 -75.617324)
		(stroke
			(width 0.04445)
			(type default)
		)
		(layer "In4.Cu")
	)
	(gr_line
		(start 301.88789 -103.167688)
		(end 302.16729 -103.167688)
		(stroke
			(width 0.04445)
			(type default)
		)
		(layer "In4.Cu")
	)
	(gr_line
		(start 301.933864 -104.214168)
		(end 301.953168 -104.222296)
		(stroke
			(width 0.05715)
			(type default)
		)
		(layer "In4.Cu")
	)
	(gr_line
		(start 301.99203 -102.888288)
		(end 302.06315 -102.888288)
		(stroke
			(width 0.04445)
			(type default)
		)
		(layer "In4.Cu")
	)
	(gr_line
		(start 302.018446 -100.576888)
		(end 302.024034 -100.574348)
		(stroke
			(width 0.04445)
			(type default)
		)
		(layer "In4.Cu")
	)
	(gr_line
		(start 302.063912 -87.253318)
		(end 302.193452 -87.253318)
		(stroke
			(width 0.04445)
			(type default)
		)
		(layer "In4.Cu")
	)
	(gr_line
		(start 302.105822 -97.835974)
		(end 302.193198 -97.859596)
		(stroke
			(width 0.04445)
			(type default)
		)
		(layer "In4.Cu")
	)
	(gr_line
		(start 302.105822 -83.967574)
		(end 302.193198 -83.991196)
		(stroke
			(width 0.04445)
			(type default)
		)
		(layer "In4.Cu")
	)
	(gr_line
		(start 302.105822 -80.343248)
		(end 302.193198 -80.319626)
		(stroke
			(width 0.04445)
			(type default)
		)
		(layer "In4.Cu")
	)
	(gr_line
		(start 302.105822 -77.033374)
		(end 302.12919 -76.945998)
		(stroke
			(width 0.04445)
			(type default)
		)
		(layer "In4.Cu")
	)
	(gr_line
		(start 302.158146 -101.773228)
		(end 302.235616 -101.67874)
		(stroke
			(width 0.04445)
			(type default)
		)
		(layer "In4.Cu")
	)
	(gr_line
		(start 302.16729 -103.167688)
		(end 302.25365 -103.081328)
		(stroke
			(width 0.04445)
			(type default)
		)
		(layer "In4.Cu")
	)
	(gr_line
		(start 302.20539 -101.962712)
		(end 302.586898 -101.92512)
		(stroke
			(width 0.04445)
			(type default)
		)
		(layer "In4.Cu")
	)
	(gr_line
		(start 302.235616 -101.67874)
		(end 302.501046 -101.652578)
		(stroke
			(width 0.04445)
			(type default)
		)
		(layer "In4.Cu")
	)
	(gr_line
		(start 302.301148 -76.85532)
		(end 302.37811 -76.876148)
		(stroke
			(width 0.04445)
			(type default)
		)
		(layer "In4.Cu")
	)
	(gr_line
		(start 302.357536 -97.75571)
		(end 302.37811 -97.678748)
		(stroke
			(width 0.04445)
			(type default)
		)
		(layer "In4.Cu")
	)
	(gr_line
		(start 302.357536 -87.357712)
		(end 302.37811 -87.434674)
		(stroke
			(width 0.04445)
			(type default)
		)
		(layer "In4.Cu")
	)
	(gr_line
		(start 302.357536 -83.88731)
		(end 302.37811 -83.810348)
		(stroke
			(width 0.04445)
			(type default)
		)
		(layer "In4.Cu")
	)
	(gr_line
		(start 302.357536 -80.423512)
		(end 302.37811 -80.500474)
		(stroke
			(width 0.04445)
			(type default)
		)
		(layer "In4.Cu")
	)
	(gr_line
		(start 302.37811 -97.678748)
		(end 302.671226 -97.509584)
		(stroke
			(width 0.04445)
			(type default)
		)
		(layer "In4.Cu")
	)
	(gr_line
		(start 302.37811 -87.434674)
		(end 302.671226 -87.603584)
		(stroke
			(width 0.04445)
			(type default)
		)
		(layer "In4.Cu")
	)
	(gr_line
		(start 302.37811 -83.810348)
		(end 302.671226 -83.641184)
		(stroke
			(width 0.04445)
			(type default)
		)
		(layer "In4.Cu")
	)
	(gr_line
		(start 302.37811 -80.500474)
		(end 302.671226 -80.669384)
		(stroke
			(width 0.04445)
			(type default)
		)
		(layer "In4.Cu")
	)
	(gr_line
		(start 302.37811 -76.876148)
		(end 302.671226 -76.706984)
		(stroke
			(width 0.04445)
			(type default)
		)
		(layer "In4.Cu")
	)
	(gr_line
		(start 302.501046 -101.652578)
		(end 302.595534 -101.730048)
		(stroke
			(width 0.04445)
			(type default)
		)
		(layer "In4.Cu")
	)
	(gr_line
		(start 302.532034 -101.072188)
		(end 302.537622 -101.069648)
		(stroke
			(width 0.04445)
			(type default)
		)
		(layer "In4.Cu")
	)
	(gr_line
		(start 302.645318 -103.392986)
		(end 302.83404 -103.581708)
		(stroke
			(width 0.04445)
			(type default)
		)
		(layer "In4.Cu")
	)
	(gr_line
		(start 302.645318 -103.270812)
		(end 302.645318 -103.392986)
		(stroke
			(width 0.04445)
			(type default)
		)
		(layer "In4.Cu")
	)
	(gr_arc
		(start 302.649636 -84.231734)
		(mid 302.651287 -84.231737)
		(end 302.652938 -84.231734)
		(stroke
			(width 0.04445)
			(type default)
		)
		(layer "In4.Cu")
	)
	(gr_line
		(start 302.653446 -87.013034)
		(end 302.689006 -87.013034)
		(stroke
			(width 0.04445)
			(type default)
		)
		(layer "In4.Cu")
	)
	(gr_line
		(start 302.653446 -76.116434)
		(end 302.689006 -76.116434)
		(stroke
			(width 0.04445)
			(type default)
		)
		(layer "In4.Cu")
	)
	(gr_line
		(start 302.671226 -86.612984)
		(end 303.028604 -86.612984)
		(stroke
			(width 0.04445)
			(type default)
		)
		(layer "In4.Cu")
	)
	(gr_line
		(start 302.671226 -85.28431)
		(end 302.671226 -85.622384)
		(stroke
			(width 0.04445)
			(type default)
		)
		(layer "In4.Cu")
	)
	(gr_line
		(start 302.671226 -85.28431)
		(end 302.692054 -85.263482)
		(stroke
			(width 0.04445)
			(type default)
		)
		(layer "In4.Cu")
	)
	(gr_line
		(start 302.671226 -84.969858)
		(end 302.692054 -84.990686)
		(stroke
			(width 0.04445)
			(type default)
		)
		(layer "In4.Cu")
	)
	(gr_line
		(start 302.671226 -84.631784)
		(end 302.671226 -84.969858)
		(stroke
			(width 0.04445)
			(type default)
		)
		(layer "In4.Cu")
	)
	(gr_line
		(start 302.671226 -79.678784)
		(end 302.964342 -79.509874)
		(stroke
			(width 0.04445)
			(type default)
		)
		(layer "In4.Cu")
	)
	(gr_line
		(start 302.671226 -78.350364)
		(end 302.671226 -78.688438)
		(stroke
			(width 0.04445)
			(type default)
		)
		(layer "In4.Cu")
	)
	(gr_line
		(start 302.671226 -78.350364)
		(end 302.692054 -78.329536)
		(stroke
			(width 0.04445)
			(type default)
		)
		(layer "In4.Cu")
	)
	(gr_line
		(start 302.671226 -78.035658)
		(end 302.692054 -78.056486)
		(stroke
			(width 0.04445)
			(type default)
		)
		(layer "In4.Cu")
	)
	(gr_line
		(start 302.671226 -77.697584)
		(end 302.671226 -78.035658)
		(stroke
			(width 0.04445)
			(type default)
		)
		(layer "In4.Cu")
	)
	(gr_line
		(start 302.693832 -85.261704)
		(end 302.729138 -85.226398)
		(stroke
			(width 0.04445)
			(type default)
		)
		(layer "In4.Cu")
	)
	(gr_line
		(start 302.693832 -84.992464)
		(end 302.736504 -85.035136)
		(stroke
			(width 0.04445)
			(type default)
		)
		(layer "In4.Cu")
	)
	(gr_line
		(start 302.693832 -78.327758)
		(end 302.729138 -78.292452)
		(stroke
			(width 0.04445)
			(type default)
		)
		(layer "In4.Cu")
	)
	(gr_line
		(start 302.693832 -78.058264)
		(end 302.736504 -78.100936)
		(stroke
			(width 0.04445)
			(type default)
		)
		(layer "In4.Cu")
	)
	(gr_line
		(start 302.777906 -99.2378)
		(end 302.825658 -99.2378)
		(stroke
			(width 0.04445)
			(type default)
		)
		(layer "In4.Cu")
	)
	(gr_line
		(start 302.83404 -103.581708)
		(end 302.956214 -103.581708)
		(stroke
			(width 0.04445)
			(type default)
		)
		(layer "In4.Cu")
	)
	(gr_line
		(start 302.836326 -98.359214)
		(end 302.84293 -98.362008)
		(stroke
			(width 0.04445)
			(type default)
		)
		(layer "In4.Cu")
	)
	(gr_line
		(start 302.86579 -101.703378)
		(end 302.94326 -101.60889)
		(stroke
			(width 0.04445)
			(type default)
		)
		(layer "In4.Cu")
	)
	(gr_line
		(start 302.913034 -101.892862)
		(end 303.294542 -101.85527)
		(stroke
			(width 0.04445)
			(type default)
		)
		(layer "In4.Cu")
	)
	(gr_line
		(start 302.91659 -103.269034)
		(end 302.957992 -103.310436)
		(stroke
			(width 0.04445)
			(type default)
		)
		(layer "In4.Cu")
	)
	(gr_line
		(start 302.94326 -101.60889)
		(end 303.20869 -101.582728)
		(stroke
			(width 0.04445)
			(type default)
		)
		(layer "In4.Cu")
	)
	(gr_line
		(start 302.964342 -79.509874)
		(end 303.051718 -79.533496)
		(stroke
			(width 0.04445)
			(type default)
		)
		(layer "In4.Cu")
	)
	(gr_arc
		(start 302.977804 -83.357466)
		(mid 302.832148 -83.000715)
		(end 302.671226 -82.650584)
		(stroke
			(width 0.04445)
			(type default)
		)
		(layer "In4.Cu")
	)
	(gr_line
		(start 303.15789 -82.99831)
		(end 303.23663 -82.976974)
		(stroke
			(width 0.04445)
			(type default)
		)
		(layer "In4.Cu")
	)
	(gr_line
		(start 303.20869 -101.582728)
		(end 303.303178 -101.660198)
		(stroke
			(width 0.04445)
			(type default)
		)
		(layer "In4.Cu")
	)
	(gr_line
		(start 303.21123 -105.059734)
		(end 303.228502 -105.0671)
		(stroke
			(width 0.05715)
			(type default)
		)
		(layer "In4.Cu")
	)
	(gr_line
		(start 303.215548 -86.365588)
		(end 303.23663 -86.286848)
		(stroke
			(width 0.04445)
			(type default)
		)
		(layer "In4.Cu")
	)
	(gr_line
		(start 303.216056 -79.42961)
		(end 303.23663 -79.352648)
		(stroke
			(width 0.04445)
			(type default)
		)
		(layer "In4.Cu")
	)
	(gr_line
		(start 303.23663 -86.286848)
		(end 303.43602 -86.17204)
		(stroke
			(width 0.04445)
			(type default)
		)
		(layer "In4.Cu")
	)
	(gr_line
		(start 303.23663 -82.976974)
		(end 303.529746 -83.146138)
		(stroke
			(width 0.04445)
			(type default)
		)
		(layer "In4.Cu")
	)
	(gr_line
		(start 303.23663 -79.352648)
		(end 303.529746 -79.183738)
		(stroke
			(width 0.04445)
			(type default)
		)
		(layer "In4.Cu")
	)
	(gr_arc
		(start 303.31156 -86.667086)
		(mid 303.172644 -86.626636)
		(end 303.028604 -86.612984)
		(stroke
			(width 0.04445)
			(type default)
		)
		(layer "In4.Cu")
	)
	(gr_line
		(start 303.43348 -99.784154)
		(end 303.43602 -99.783138)
		(stroke
			(width 0.04445)
			(type default)
		)
		(layer "In4.Cu")
	)
	(gr_line
		(start 303.43602 -99.783138)
		(end 303.440592 -99.78136)
		(stroke
			(width 0.04445)
			(type default)
		)
		(layer "In4.Cu")
	)
	(gr_line
		(start 303.43602 -86.17204)
		(end 303.529746 -86.117938)
		(stroke
			(width 0.04445)
			(type default)
		)
		(layer "In4.Cu")
	)
	(gr_line
		(start 303.450244 -98.613468)
		(end 303.455832 -98.616008)
		(stroke
			(width 0.04445)
			(type default)
		)
		(layer "In4.Cu")
	)
	(gr_line
		(start 303.511966 -83.736688)
		(end 303.547526 -83.736688)
		(stroke
			(width 0.04445)
			(type default)
		)
		(layer "In4.Cu")
	)
	(gr_line
		(start 303.573434 -101.633528)
		(end 303.650904 -101.53904)
		(stroke
			(width 0.04445)
			(type default)
		)
		(layer "In4.Cu")
	)
	(gr_line
		(start 303.620678 -101.823012)
		(end 304.002186 -101.78542)
		(stroke
			(width 0.04445)
			(type default)
		)
		(layer "In4.Cu")
	)
	(gr_line
		(start 303.650904 -101.53904)
		(end 303.916334 -101.512878)
		(stroke
			(width 0.04445)
			(type default)
		)
		(layer "In4.Cu")
	)
	(gr_line
		(start 303.758854 -100.35794)
		(end 303.764442 -100.3554)
		(stroke
			(width 0.04445)
			(type default)
		)
		(layer "In4.Cu")
	)
	(gr_line
		(start 303.796192 -99.02571)
		(end 303.807368 -99.025456)
		(stroke
			(width 0.04445)
			(type default)
		)
		(layer "In4.Cu")
	)
	(gr_line
		(start 303.807368 -99.025456)
		(end 303.817274 -99.02952)
		(stroke
			(width 0.04445)
			(type default)
		)
		(layer "In4.Cu")
	)
	(gr_line
		(start 303.836578 -76.758292)
		(end 303.864264 -76.753466)
		(stroke
			(width 0.04445)
			(type default)
		)
		(layer "In4.Cu")
	)
	(gr_line
		(start 303.864264 -76.753466)
		(end 303.866042 -76.753212)
		(stroke
			(width 0.04445)
			(type default)
		)
		(layer "In4.Cu")
	)
	(gr_line
		(start 303.866042 -76.753212)
		(end 303.887632 -76.731622)
		(stroke
			(width 0.04445)
			(type default)
		)
		(layer "In4.Cu")
	)
	(gr_line
		(start 303.916334 -101.512878)
		(end 304.010822 -101.590602)
		(stroke
			(width 0.04445)
			(type default)
		)
		(layer "In4.Cu")
	)
	(gr_line
		(start 304.019712 -99.322382)
		(end 304.066702 -99.435412)
		(stroke
			(width 0.04445)
			(type default)
		)
		(layer "In4.Cu")
	)
	(gr_line
		(start 304.066702 -99.435412)
		(end 304.313082 -99.537266)
		(stroke
			(width 0.04445)
			(type default)
		)
		(layer "In4.Cu")
	)
	(gr_line
		(start 304.11928 -99.154488)
		(end 304.47361 -99.301046)
		(stroke
			(width 0.04445)
			(type default)
		)
		(layer "In4.Cu")
	)
	(gr_line
		(start 304.17897 -76.170536)
		(end 304.213006 -76.1365)
		(stroke
			(width 0.04445)
			(type default)
		)
		(layer "In4.Cu")
	)
	(gr_line
		(start 304.281078 -101.563678)
		(end 304.358548 -101.46919)
		(stroke
			(width 0.04445)
			(type default)
		)
		(layer "In4.Cu")
	)
	(gr_line
		(start 304.28692 -100.3554)
		(end 304.292508 -100.35794)
		(stroke
			(width 0.04445)
			(type default)
		)
		(layer "In4.Cu")
	)
	(gr_line
		(start 304.313082 -99.537266)
		(end 304.425858 -99.490276)
		(stroke
			(width 0.04445)
			(type default)
		)
		(layer "In4.Cu")
	)
	(gr_line
		(start 304.328322 -101.753162)
		(end 304.70983 -101.71557)
		(stroke
			(width 0.04445)
			(type default)
		)
		(layer "In4.Cu")
	)
	(gr_line
		(start 304.358548 -101.46919)
		(end 304.623978 -101.443028)
		(stroke
			(width 0.04445)
			(type default)
		)
		(layer "In4.Cu")
	)
	(gr_arc
		(start 304.373788 -79.278734)
		(mid 304.37201 -79.278857)
		(end 304.370232 -79.278988)
		(stroke
			(width 0.04445)
			(type default)
		)
		(layer "In4.Cu")
	)
	(gr_line
		(start 304.3936 -99.78136)
		(end 304.399188 -99.7839)
		(stroke
			(width 0.04445)
			(type default)
		)
		(layer "In4.Cu")
	)
	(gr_line
		(start 304.4444 -104.3305)
		(end 304.48377 -104.36987)
		(stroke
			(width 0.04445)
			(type default)
		)
		(layer "In4.Cu")
	)
	(gr_line
		(start 304.4444 -104.14)
		(end 304.48377 -104.10063)
		(stroke
			(width 0.04445)
			(type default)
		)
		(layer "In4.Cu")
	)
	(gr_line
		(start 304.47234 -76.32954)
		(end 304.571146 -76.428346)
		(stroke
			(width 0.04445)
			(type default)
		)
		(layer "In4.Cu")
	)
	(gr_line
		(start 304.485548 -104.371648)
		(end 304.4952 -104.3813)
		(stroke
			(width 0.04445)
			(type default)
		)
		(layer "In4.Cu")
	)
	(gr_line
		(start 304.485548 -104.098852)
		(end 304.4952 -104.0892)
		(stroke
			(width 0.04445)
			(type default)
		)
		(layer "In4.Cu")
	)
	(gr_line
		(start 304.4952 -104.3813)
		(end 304.517298 -104.3813)
		(stroke
			(width 0.04445)
			(type default)
		)
		(layer "In4.Cu")
	)
	(gr_line
		(start 304.4952 -104.0892)
		(end 304.517298 -104.0892)
		(stroke
			(width 0.04445)
			(type default)
		)
		(layer "In4.Cu")
	)
	(gr_line
		(start 304.54981 -102.558088)
		(end 304.55616 -102.558088)
		(stroke
			(width 0.04445)
			(type default)
		)
		(layer "In4.Cu")
	)
	(gr_line
		(start 304.56251 -92.159074)
		(end 304.661316 -92.25788)
		(stroke
			(width 0.04445)
			(type default)
		)
		(layer "In4.Cu")
	)
	(gr_line
		(start 304.571146 -76.428346)
		(end 304.748946 -76.428346)
		(stroke
			(width 0.04445)
			(type default)
		)
		(layer "In4.Cu")
	)
	(gr_line
		(start 304.59426 -102.367588)
		(end 304.599848 -102.370128)
		(stroke
			(width 0.04445)
			(type default)
		)
		(layer "In4.Cu")
	)
	(gr_line
		(start 304.59934 -77.21854)
		(end 304.698146 -77.317346)
		(stroke
			(width 0.04445)
			(type default)
		)
		(layer "In4.Cu")
	)
	(gr_line
		(start 304.620676 -93.793818)
		(end 304.626264 -93.791278)
		(stroke
			(width 0.04445)
			(type default)
		)
		(layer "In4.Cu")
	)
	(gr_line
		(start 304.623978 -101.443028)
		(end 304.718466 -101.520752)
		(stroke
			(width 0.04445)
			(type default)
		)
		(layer "In4.Cu")
	)
	(gr_line
		(start 304.645568 -98.22307)
		(end 304.721514 -98.109024)
		(stroke
			(width 0.04445)
			(type default)
		)
		(layer "In4.Cu")
	)
	(gr_line
		(start 304.661316 -92.25788)
		(end 304.839116 -92.25788)
		(stroke
			(width 0.04445)
			(type default)
		)
		(layer "In4.Cu")
	)
	(gr_line
		(start 304.681636 -79.085694)
		(end 304.780442 -78.986888)
		(stroke
			(width 0.04445)
			(type default)
		)
		(layer "In4.Cu")
	)
	(gr_line
		(start 304.696622 -102.616)
		(end 304.70221 -102.61854)
		(stroke
			(width 0.04445)
			(type default)
		)
		(layer "In4.Cu")
	)
	(gr_line
		(start 304.698146 -77.317346)
		(end 304.875946 -77.317346)
		(stroke
			(width 0.04445)
			(type default)
		)
		(layer "In4.Cu")
	)
	(gr_line
		(start 304.710592 -98.406966)
		(end 305.021488 -98.34499)
		(stroke
			(width 0.04445)
			(type default)
		)
		(layer "In4.Cu")
	)
	(gr_line
		(start 304.721514 -98.109024)
		(end 304.896012 -98.07448)
		(stroke
			(width 0.04445)
			(type default)
		)
		(layer "In4.Cu")
	)
	(gr_line
		(start 304.74031 -102.42804)
		(end 304.74666 -102.42804)
		(stroke
			(width 0.04445)
			(type default)
		)
		(layer "In4.Cu")
	)
	(gr_line
		(start 304.748946 -76.428346)
		(end 304.847752 -76.32954)
		(stroke
			(width 0.04445)
			(type default)
		)
		(layer "In4.Cu")
	)
	(gr_line
		(start 304.769012 -90.706448)
		(end 304.769774 -90.705686)
		(stroke
			(width 0.04445)
			(type default)
		)
		(layer "In4.Cu")
	)
	(gr_line
		(start 304.780442 -78.986888)
		(end 304.958242 -78.986888)
		(stroke
			(width 0.04445)
			(type default)
		)
		(layer "In4.Cu")
	)
	(gr_line
		(start 304.839116 -92.25788)
		(end 304.937922 -92.159074)
		(stroke
			(width 0.04445)
			(type default)
		)
		(layer "In4.Cu")
	)
	(gr_line
		(start 304.875946 -77.317346)
		(end 304.974752 -77.21854)
		(stroke
			(width 0.04445)
			(type default)
		)
		(layer "In4.Cu")
	)
	(gr_line
		(start 304.88636 -100.191316)
		(end 304.891948 -100.193856)
		(stroke
			(width 0.04445)
			(type default)
		)
		(layer "In4.Cu")
	)
	(gr_line
		(start 304.896012 -98.07448)
		(end 305.010058 -98.150426)
		(stroke
			(width 0.04445)
			(type default)
		)
		(layer "In4.Cu")
	)
	(gr_line
		(start 304.922174 -93.788738)
		(end 305.020726 -93.690186)
		(stroke
			(width 0.04445)
			(type default)
		)
		(layer "In4.Cu")
	)
	(gr_line
		(start 304.93843 -99.699572)
		(end 304.944018 -99.702112)
		(stroke
			(width 0.04445)
			(type default)
		)
		(layer "In4.Cu")
	)
	(gr_line
		(start 304.958242 -78.986888)
		(end 305.057048 -79.085694)
		(stroke
			(width 0.04445)
			(type default)
		)
		(layer "In4.Cu")
	)
	(gr_line
		(start 304.961798 -100.840794)
		(end 304.967386 -100.843334)
		(stroke
			(width 0.04445)
			(type default)
		)
		(layer "In4.Cu")
	)
	(gr_line
		(start 304.994564 -90.48115)
		(end 305.001168 -90.478356)
		(stroke
			(width 0.04445)
			(type default)
		)
		(layer "In4.Cu")
	)
	(gr_line
		(start 305.020726 -93.690186)
		(end 305.198526 -93.690186)
		(stroke
			(width 0.04445)
			(type default)
		)
		(layer "In4.Cu")
	)
	(gr_line
		(start 305.02225 -102.4255)
		(end 305.10861 -102.33914)
		(stroke
			(width 0.04445)
			(type default)
		)
		(layer "In4.Cu")
	)
	(gr_line
		(start 305.030632 -76.32954)
		(end 305.129438 -76.428346)
		(stroke
			(width 0.04445)
			(type default)
		)
		(layer "In4.Cu")
	)
	(gr_line
		(start 305.10861 -102.33914)
		(end 305.38801 -102.33914)
		(stroke
			(width 0.04445)
			(type default)
		)
		(layer "In4.Cu")
	)
	(gr_line
		(start 305.120802 -92.159074)
		(end 305.219608 -92.25788)
		(stroke
			(width 0.04445)
			(type default)
		)
		(layer "In4.Cu")
	)
	(gr_line
		(start 305.129438 -76.428346)
		(end 305.307238 -76.428346)
		(stroke
			(width 0.04445)
			(type default)
		)
		(layer "In4.Cu")
	)
	(gr_line
		(start 305.157632 -77.21854)
		(end 305.256438 -77.317346)
		(stroke
			(width 0.04445)
			(type default)
		)
		(layer "In4.Cu")
	)
	(gr_line
		(start 305.18862 -98.114866)
		(end 305.26482 -98.00082)
		(stroke
			(width 0.04445)
			(type default)
		)
		(layer "In4.Cu")
	)
	(gr_line
		(start 305.198526 -93.690186)
		(end 305.297078 -93.788738)
		(stroke
			(width 0.04445)
			(type default)
		)
		(layer "In4.Cu")
	)
	(gr_line
		(start 305.21275 -102.61854)
		(end 305.28387 -102.61854)
		(stroke
			(width 0.04445)
			(type default)
		)
		(layer "In4.Cu")
	)
	(gr_line
		(start 305.219608 -92.25788)
		(end 305.397408 -92.25788)
		(stroke
			(width 0.04445)
			(type default)
		)
		(layer "In4.Cu")
	)
	(gr_line
		(start 305.221386 -79.924148)
		(end 305.320192 -80.022954)
		(stroke
			(width 0.04445)
			(type default)
		)
		(layer "In4.Cu")
	)
	(gr_line
		(start 305.23434 -89.79154)
		(end 305.308 -89.8652)
		(stroke
			(width 0.04445)
			(type default)
		)
		(layer "In4.Cu")
	)
	(gr_line
		(start 305.237388 -99.702112)
		(end 305.242976 -99.699572)
		(stroke
			(width 0.04445)
			(type default)
		)
		(layer "In4.Cu")
	)
	(gr_line
		(start 305.239928 -79.085694)
		(end 305.338734 -78.986888)
		(stroke
			(width 0.04445)
			(type default)
		)
		(layer "In4.Cu")
	)
	(gr_arc
		(start 305.246786 -95.623634)
		(mid 305.239673 -95.623697)
		(end 305.232562 -95.623888)
		(stroke
			(width 0.04445)
			(type default)
		)
		(layer "In4.Cu")
	)
	(gr_line
		(start 305.25339 -98.299016)
		(end 305.565556 -98.236786)
		(stroke
			(width 0.04445)
			(type default)
		)
		(layer "In4.Cu")
	)
	(gr_line
		(start 305.256438 -77.317346)
		(end 305.434238 -77.317346)
		(stroke
			(width 0.04445)
			(type default)
		)
		(layer "In4.Cu")
	)
	(gr_line
		(start 305.257962 -93.1926)
		(end 305.26355 -93.19006)
		(stroke
			(width 0.04445)
			(type default)
		)
		(layer "In4.Cu")
	)
	(gr_line
		(start 305.26482 -98.00082)
		(end 305.439318 -97.966276)
		(stroke
			(width 0.04445)
			(type default)
		)
		(layer "In4.Cu")
	)
	(gr_line
		(start 305.29657 -96.6597)
		(end 305.302158 -96.65716)
		(stroke
			(width 0.04445)
			(type default)
		)
		(layer "In4.Cu")
	)
	(gr_line
		(start 305.307238 -76.428346)
		(end 305.406044 -76.32954)
		(stroke
			(width 0.04445)
			(type default)
		)
		(layer "In4.Cu")
	)
	(gr_line
		(start 305.308 -89.8652)
		(end 305.53152 -89.8652)
		(stroke
			(width 0.04445)
			(type default)
		)
		(layer "In4.Cu")
	)
	(gr_line
		(start 305.310286 -100.193856)
		(end 305.315874 -100.191316)
		(stroke
			(width 0.04445)
			(type default)
		)
		(layer "In4.Cu")
	)
	(gr_line
		(start 305.320192 -80.022954)
		(end 305.497992 -80.022954)
		(stroke
			(width 0.04445)
			(type default)
		)
		(layer "In4.Cu")
	)
	(gr_line
		(start 305.338734 -78.986888)
		(end 305.516534 -78.986888)
		(stroke
			(width 0.04445)
			(type default)
		)
		(layer "In4.Cu")
	)
	(gr_line
		(start 305.341274 -90.33764)
		(end 305.346862 -90.3351)
		(stroke
			(width 0.04445)
			(type default)
		)
		(layer "In4.Cu")
	)
	(gr_line
		(start 305.38801 -102.33914)
		(end 305.47437 -102.4255)
		(stroke
			(width 0.04445)
			(type default)
		)
		(layer "In4.Cu")
	)
	(gr_line
		(start 305.397408 -92.25788)
		(end 305.496214 -92.159074)
		(stroke
			(width 0.04445)
			(type default)
		)
		(layer "In4.Cu")
	)
	(gr_line
		(start 305.428904 -100.843334)
		(end 305.434492 -100.840794)
		(stroke
			(width 0.04445)
			(type default)
		)
		(layer "In4.Cu")
	)
	(gr_line
		(start 305.434238 -77.317346)
		(end 305.533044 -77.21854)
		(stroke
			(width 0.04445)
			(type default)
		)
		(layer "In4.Cu")
	)
	(gr_line
		(start 305.439318 -97.966276)
		(end 305.553364 -98.042222)
		(stroke
			(width 0.04445)
			(type default)
		)
		(layer "In4.Cu")
	)
	(gr_line
		(start 305.497992 -80.022954)
		(end 305.596798 -79.924148)
		(stroke
			(width 0.04445)
			(type default)
		)
		(layer "In4.Cu")
	)
	(gr_line
		(start 305.516534 -78.986888)
		(end 305.61534 -79.085694)
		(stroke
			(width 0.04445)
			(type default)
		)
		(layer "In4.Cu")
	)
	(gr_line
		(start 305.53152 -89.8652)
		(end 305.60518 -89.79154)
		(stroke
			(width 0.04445)
			(type default)
		)
		(layer "In4.Cu")
	)
	(gr_line
		(start 305.565302 -90.52814)
		(end 305.661822 -90.62466)
		(stroke
			(width 0.04445)
			(type default)
		)
		(layer "In4.Cu")
	)
	(gr_line
		(start 305.575462 -99.562158)
		(end 305.582066 -99.559364)
		(stroke
			(width 0.04445)
			(type default)
		)
		(layer "In4.Cu")
	)
	(gr_line
		(start 305.588924 -76.32954)
		(end 305.68773 -76.428346)
		(stroke
			(width 0.04445)
			(type default)
		)
		(layer "In4.Cu")
	)
	(gr_line
		(start 305.661822 -90.62466)
		(end 305.839622 -90.62466)
		(stroke
			(width 0.04445)
			(type default)
		)
		(layer "In4.Cu")
	)
	(gr_line
		(start 305.669188 -97.134426)
		(end 305.68519 -97.132902)
		(stroke
			(width 0.04445)
			(type default)
		)
		(layer "In4.Cu")
	)
	(gr_line
		(start 305.679094 -92.159074)
		(end 305.7779 -92.25788)
		(stroke
			(width 0.04445)
			(type default)
		)
		(layer "In4.Cu")
	)
	(gr_line
		(start 305.683158 -100.53193)
		(end 305.688746 -100.52939)
		(stroke
			(width 0.04445)
			(type default)
		)
		(layer "In4.Cu")
	)
	(gr_line
		(start 305.68519 -97.132902)
		(end 305.698906 -97.123758)
		(stroke
			(width 0.04445)
			(type default)
		)
		(layer "In4.Cu")
	)
	(gr_line
		(start 305.68773 -76.428346)
		(end 305.86553 -76.428346)
		(stroke
			(width 0.04445)
			(type default)
		)
		(layer "In4.Cu")
	)
	(gr_line
		(start 305.690778 -104.3813)
		(end 305.70805 -104.373934)
		(stroke
			(width 0.05715)
			(type default)
		)
		(layer "In4.Cu")
	)
	(gr_line
		(start 305.718718 -93.776546)
		(end 305.847242 -93.723714)
		(stroke
			(width 0.04445)
			(type default)
		)
		(layer "In4.Cu")
	)
	(gr_line
		(start 305.719226 -95.416624)
		(end 305.823366 -95.416624)
		(stroke
			(width 0.04445)
			(type default)
		)
		(layer "In4.Cu")
	)
	(gr_line
		(start 305.72075 -93.981778)
		(end 305.726846 -93.979238)
		(stroke
			(width 0.04445)
			(type default)
		)
		(layer "In4.Cu")
	)
	(gr_line
		(start 305.75885 -102.4255)
		(end 305.84521 -102.33914)
		(stroke
			(width 0.04445)
			(type default)
		)
		(layer "In4.Cu")
	)
	(gr_line
		(start 305.7779 -92.25788)
		(end 305.9557 -92.25788)
		(stroke
			(width 0.04445)
			(type default)
		)
		(layer "In4.Cu")
	)
	(gr_line
		(start 305.779678 -79.924148)
		(end 305.878484 -80.022954)
		(stroke
			(width 0.04445)
			(type default)
		)
		(layer "In4.Cu")
	)
	(gr_line
		(start 305.786536 -93.9546)
		(end 305.930046 -93.895418)
		(stroke
			(width 0.04445)
			(type default)
		)
		(layer "In4.Cu")
	)
	(gr_line
		(start 305.791108 -96.454976)
		(end 305.797712 -96.452182)
		(stroke
			(width 0.04445)
			(type default)
		)
		(layer "In4.Cu")
	)
	(gr_line
		(start 305.812952 -82.360008)
		(end 305.911758 -82.261202)
		(stroke
			(width 0.04445)
			(type default)
		)
		(layer "In4.Cu")
	)
	(gr_line
		(start 305.823366 -95.416624)
		(end 305.981862 -95.258128)
		(stroke
			(width 0.04445)
			(type default)
		)
		(layer "In4.Cu")
	)
	(gr_line
		(start 305.839622 -90.62466)
		(end 305.936142 -90.52814)
		(stroke
			(width 0.04445)
			(type default)
		)
		(layer "In4.Cu")
	)
	(gr_line
		(start 305.84521 -102.33914)
		(end 306.12461 -102.33914)
		(stroke
			(width 0.04445)
			(type default)
		)
		(layer "In4.Cu")
	)
	(gr_line
		(start 305.847242 -93.72346)
		(end 305.847242 -93.723714)
		(stroke
			(width 0.04445)
			(type default)
		)
		(layer "In4.Cu")
	)
	(gr_line
		(start 305.848766 -93.720158)
		(end 305.902106 -93.59138)
		(stroke
			(width 0.04445)
			(type default)
		)
		(layer "In4.Cu")
	)
	(gr_line
		(start 305.850036 -105.0671)
		(end 305.867816 -105.059734)
		(stroke
			(width 0.05715)
			(type default)
		)
		(layer "In4.Cu")
	)
	(gr_line
		(start 305.86553 -76.428346)
		(end 305.964336 -76.32954)
		(stroke
			(width 0.04445)
			(type default)
		)
		(layer "In4.Cu")
	)
	(gr_line
		(start 305.878484 -80.022954)
		(end 306.056284 -80.022954)
		(stroke
			(width 0.04445)
			(type default)
		)
		(layer "In4.Cu")
	)
	(gr_line
		(start 305.902106 -93.59138)
		(end 306.066698 -93.523562)
		(stroke
			(width 0.04445)
			(type default)
		)
		(layer "In4.Cu")
	)
	(gr_line
		(start 305.911758 -82.261202)
		(end 306.089558 -82.261202)
		(stroke
			(width 0.04445)
			(type default)
		)
		(layer "In4.Cu")
	)
	(gr_line
		(start 305.94935 -102.61854)
		(end 306.02047 -102.61854)
		(stroke
			(width 0.04445)
			(type default)
		)
		(layer "In4.Cu")
	)
	(gr_line
		(start 305.950112 -93.887036)
		(end 306.242974 -93.766386)
		(stroke
			(width 0.04445)
			(type default)
		)
		(layer "In4.Cu")
	)
	(gr_line
		(start 305.9557 -92.25788)
		(end 306.054506 -92.159074)
		(stroke
			(width 0.04445)
			(type default)
		)
		(layer "In4.Cu")
	)
	(gr_line
		(start 305.981862 -95.153988)
		(end 305.981862 -95.258128)
		(stroke
			(width 0.04445)
			(type default)
		)
		(layer "In4.Cu")
	)
	(gr_line
		(start 306.018946 -83.06816)
		(end 306.115466 -82.97164)
		(stroke
			(width 0.04445)
			(type default)
		)
		(layer "In4.Cu")
	)
	(gr_line
		(start 306.025296 -89.374218)
		(end 306.036218 -89.363296)
		(stroke
			(width 0.04445)
			(type default)
		)
		(layer "In4.Cu")
	)
	(gr_line
		(start 306.027074 -89.64549)
		(end 306.131214 -89.64549)
		(stroke
			(width 0.04445)
			(type default)
		)
		(layer "In4.Cu")
	)
	(gr_line
		(start 306.056284 -80.022954)
		(end 306.15509 -79.924148)
		(stroke
			(width 0.04445)
			(type default)
		)
		(layer "In4.Cu")
	)
	(gr_line
		(start 306.066698 -93.523562)
		(end 306.19573 -93.577156)
		(stroke
			(width 0.04445)
			(type default)
		)
		(layer "In4.Cu")
	)
	(gr_line
		(start 306.075588 -88.23325)
		(end 306.075588 -88.370156)
		(stroke
			(width 0.04445)
			(type default)
		)
		(layer "In4.Cu")
	)
	(gr_line
		(start 306.075588 -88.23325)
		(end 306.201318 -88.10752)
		(stroke
			(width 0.04445)
			(type default)
		)
		(layer "In4.Cu")
	)
	(gr_line
		(start 306.089558 -82.261202)
		(end 306.188364 -82.360008)
		(stroke
			(width 0.04445)
			(type default)
		)
		(layer "In4.Cu")
	)
	(gr_line
		(start 306.109624 -83.780884)
		(end 306.14366 -83.746848)
		(stroke
			(width 0.04445)
			(type default)
		)
		(layer "In4.Cu")
	)
	(gr_line
		(start 306.110894 -95.024956)
		(end 306.215034 -95.024956)
		(stroke
			(width 0.04445)
			(type default)
		)
		(layer "In4.Cu")
	)
	(gr_line
		(start 306.115466 -82.97164)
		(end 306.293266 -82.97164)
		(stroke
			(width 0.04445)
			(type default)
		)
		(layer "In4.Cu")
	)
	(gr_line
		(start 306.12461 -102.33914)
		(end 306.21097 -102.4255)
		(stroke
			(width 0.04445)
			(type default)
		)
		(layer "In4.Cu")
	)
	(gr_line
		(start 306.131214 -89.64549)
		(end 306.30749 -89.469214)
		(stroke
			(width 0.04445)
			(type default)
		)
		(layer "In4.Cu")
	)
	(gr_line
		(start 306.147216 -76.32954)
		(end 306.243736 -76.42606)
		(stroke
			(width 0.04445)
			(type default)
		)
		(layer "In4.Cu")
	)
	(gr_line
		(start 306.152042 -96.631252)
		(end 306.204112 -96.50476)
		(stroke
			(width 0.04445)
			(type default)
		)
		(layer "In4.Cu")
	)
	(gr_line
		(start 306.201318 -88.10752)
		(end 306.338478 -88.10752)
		(stroke
			(width 0.04445)
			(type default)
		)
		(layer "In4.Cu")
	)
	(gr_line
		(start 306.204112 -96.50476)
		(end 306.368704 -96.436688)
		(stroke
			(width 0.04445)
			(type default)
		)
		(layer "In4.Cu")
	)
	(gr_line
		(start 306.206652 -101.657912)
		(end 306.246022 -101.697282)
		(stroke
			(width 0.04445)
			(type default)
		)
		(layer "In4.Cu")
	)
	(gr_line
		(start 306.206652 -101.467412)
		(end 306.246022 -101.428042)
		(stroke
			(width 0.04445)
			(type default)
		)
		(layer "In4.Cu")
	)
	(gr_line
		(start 306.215034 -95.024956)
		(end 306.37353 -94.86646)
		(stroke
			(width 0.04445)
			(type default)
		)
		(layer "In4.Cu")
	)
	(gr_line
		(start 306.218082 -96.812608)
		(end 306.231544 -96.80702)
		(stroke
			(width 0.04445)
			(type default)
		)
		(layer "In4.Cu")
	)
	(gr_line
		(start 306.234846 -92.156534)
		(end 306.240434 -92.153994)
		(stroke
			(width 0.04445)
			(type default)
		)
		(layer "In4.Cu")
	)
	(gr_line
		(start 306.243736 -76.42606)
		(end 306.421536 -76.42606)
		(stroke
			(width 0.04445)
			(type default)
		)
		(layer "In4.Cu")
	)
	(gr_line
		(start 306.2478 -101.69906)
		(end 306.257452 -101.708712)
		(stroke
			(width 0.04445)
			(type default)
		)
		(layer "In4.Cu")
	)
	(gr_line
		(start 306.2478 -101.426264)
		(end 306.257452 -101.416612)
		(stroke
			(width 0.04445)
			(type default)
		)
		(layer "In4.Cu")
	)
	(gr_line
		(start 306.252626 -96.798384)
		(end 306.543456 -96.677988)
		(stroke
			(width 0.04445)
			(type default)
		)
		(layer "In4.Cu")
	)
	(gr_line
		(start 306.257452 -101.708712)
		(end 306.27955 -101.708712)
		(stroke
			(width 0.04445)
			(type default)
		)
		(layer "In4.Cu")
	)
	(gr_line
		(start 306.257452 -101.416612)
		(end 306.27955 -101.416612)
		(stroke
			(width 0.04445)
			(type default)
		)
		(layer "In4.Cu")
	)
	(gr_line
		(start 306.293266 -82.97164)
		(end 306.389786 -83.06816)
		(stroke
			(width 0.04445)
			(type default)
		)
		(layer "In4.Cu")
	)
	(gr_line
		(start 306.297584 -85.030818)
		(end 306.396136 -84.932266)
		(stroke
			(width 0.04445)
			(type default)
		)
		(layer "In4.Cu")
	)
	(gr_line
		(start 306.30749 -89.365074)
		(end 306.30749 -89.469214)
		(stroke
			(width 0.04445)
			(type default)
		)
		(layer "In4.Cu")
	)
	(gr_line
		(start 306.328572 -93.525086)
		(end 306.363116 -93.510862)
		(stroke
			(width 0.04445)
			(type default)
		)
		(layer "In4.Cu")
	)
	(gr_line
		(start 306.34686 -88.371934)
		(end 306.45481 -88.263984)
		(stroke
			(width 0.04445)
			(type default)
		)
		(layer "In4.Cu")
	)
	(gr_line
		(start 306.364386 -93.50756)
		(end 306.41798 -93.378528)
		(stroke
			(width 0.04445)
			(type default)
		)
		(layer "In4.Cu")
	)
	(gr_line
		(start 306.368704 -96.436688)
		(end 306.495196 -96.489012)
		(stroke
			(width 0.04445)
			(type default)
		)
		(layer "In4.Cu")
	)
	(gr_line
		(start 306.371244 -82.360008)
		(end 306.47005 -82.261202)
		(stroke
			(width 0.04445)
			(type default)
		)
		(layer "In4.Cu")
	)
	(gr_line
		(start 306.37353 -94.76232)
		(end 306.37353 -94.86646)
		(stroke
			(width 0.04445)
			(type default)
		)
		(layer "In4.Cu")
	)
	(gr_line
		(start 306.396136 -84.932266)
		(end 306.573936 -84.932266)
		(stroke
			(width 0.04445)
			(type default)
		)
		(layer "In4.Cu")
	)
	(gr_line
		(start 306.414678 -93.69552)
		(end 306.44211 -93.68409)
		(stroke
			(width 0.04445)
			(type default)
		)
		(layer "In4.Cu")
	)
	(gr_line
		(start 306.41798 -93.378528)
		(end 306.582572 -93.31071)
		(stroke
			(width 0.04445)
			(type default)
		)
		(layer "In4.Cu")
	)
	(gr_line
		(start 306.420266 -103.76027)
		(end 306.508404 -103.547672)
		(stroke
			(width 0.05715)
			(type default)
		)
		(layer "In4.Cu")
	)
	(gr_line
		(start 306.421536 -76.42606)
		(end 306.518056 -76.32954)
		(stroke
			(width 0.04445)
			(type default)
		)
		(layer "In4.Cu")
	)
	(gr_line
		(start 306.442872 -92.070428)
		(end 306.449476 -92.067634)
		(stroke
			(width 0.04445)
			(type default)
		)
		(layer "In4.Cu")
	)
	(gr_line
		(start 306.452778 -88.946736)
		(end 306.4637 -88.935814)
		(stroke
			(width 0.04445)
			(type default)
		)
		(layer "In4.Cu")
	)
	(gr_line
		(start 306.454556 -89.218008)
		(end 306.558696 -89.218008)
		(stroke
			(width 0.04445)
			(type default)
		)
		(layer "In4.Cu")
	)
	(gr_line
		(start 306.465986 -93.674184)
		(end 306.759356 -93.55328)
		(stroke
			(width 0.04445)
			(type default)
		)
		(layer "In4.Cu")
	)
	(gr_line
		(start 306.467256 -87.841582)
		(end 306.467256 -87.978742)
		(stroke
			(width 0.04445)
			(type default)
		)
		(layer "In4.Cu")
	)
	(gr_line
		(start 306.467256 -87.841582)
		(end 306.592986 -87.715852)
		(stroke
			(width 0.04445)
			(type default)
		)
		(layer "In4.Cu")
	)
	(gr_line
		(start 306.47005 -82.261202)
		(end 306.64785 -82.261202)
		(stroke
			(width 0.04445)
			(type default)
		)
		(layer "In4.Cu")
	)
	(gr_line
		(start 306.47132 -74.325734)
		(end 306.51069 -74.365104)
		(stroke
			(width 0.04445)
			(type default)
		)
		(layer "In4.Cu")
	)
	(gr_line
		(start 306.47132 -74.135234)
		(end 306.51069 -74.095864)
		(stroke
			(width 0.04445)
			(type default)
		)
		(layer "In4.Cu")
	)
	(gr_line
		(start 306.5018 -78.288388)
		(end 306.54117 -78.327758)
		(stroke
			(width 0.04445)
			(type default)
		)
		(layer "In4.Cu")
	)
	(gr_line
		(start 306.5018 -78.097888)
		(end 306.54117 -78.058518)
		(stroke
			(width 0.04445)
			(type default)
		)
		(layer "In4.Cu")
	)
	(gr_line
		(start 306.508404 -103.547672)
		(end 306.825142 -103.416608)
		(stroke
			(width 0.05715)
			(type default)
		)
		(layer "In4.Cu")
	)
	(gr_line
		(start 306.512468 -74.366882)
		(end 306.52212 -74.376534)
		(stroke
			(width 0.04445)
			(type default)
		)
		(layer "In4.Cu")
	)
	(gr_line
		(start 306.512468 -74.094086)
		(end 306.52212 -74.084434)
		(stroke
			(width 0.04445)
			(type default)
		)
		(layer "In4.Cu")
	)
	(gr_line
		(start 306.52212 -74.376534)
		(end 306.544218 -74.376534)
		(stroke
			(width 0.04445)
			(type default)
		)
		(layer "In4.Cu")
	)
	(gr_line
		(start 306.52212 -74.084434)
		(end 306.544218 -74.084434)
		(stroke
			(width 0.04445)
			(type default)
		)
		(layer "In4.Cu")
	)
	(gr_line
		(start 306.540662 -100.71989)
		(end 306.580032 -100.75926)
		(stroke
			(width 0.04445)
			(type default)
		)
		(layer "In4.Cu")
	)
	(gr_line
		(start 306.540662 -100.52939)
		(end 306.580032 -100.49002)
		(stroke
			(width 0.04445)
			(type default)
		)
		(layer "In4.Cu")
	)
	(gr_line
		(start 306.54117 -89.932764)
		(end 306.54117 -89.988136)
		(stroke
			(width 0.04445)
			(type default)
		)
		(layer "In4.Cu")
	)
	(gr_line
		(start 306.54117 -89.916508)
		(end 306.54117 -89.930224)
		(stroke
			(width 0.04445)
			(type default)
		)
		(layer "In4.Cu")
	)
	(gr_line
		(start 306.54117 -89.916508)
		(end 306.556664 -89.901014)
		(stroke
			(width 0.04445)
			(type default)
		)
		(layer "In4.Cu")
	)
	(gr_line
		(start 306.542948 -78.329536)
		(end 306.5526 -78.339188)
		(stroke
			(width 0.04445)
			(type default)
		)
		(layer "In4.Cu")
	)
	(gr_line
		(start 306.542948 -78.05674)
		(end 306.5526 -78.047088)
		(stroke
			(width 0.04445)
			(type default)
		)
		(layer "In4.Cu")
	)
	(gr_line
		(start 306.548536 -77.216)
		(end 306.587906 -77.25537)
		(stroke
			(width 0.04445)
			(type default)
		)
		(layer "In4.Cu")
	)
	(gr_line
		(start 306.548536 -77.0255)
		(end 306.587906 -76.98613)
		(stroke
			(width 0.04445)
			(type default)
		)
		(layer "In4.Cu")
	)
	(gr_line
		(start 306.5526 -78.339188)
		(end 306.574698 -78.339188)
		(stroke
			(width 0.04445)
			(type default)
		)
		(layer "In4.Cu")
	)
	(gr_line
		(start 306.5526 -78.047088)
		(end 306.574698 -78.047088)
		(stroke
			(width 0.04445)
			(type default)
		)
		(layer "In4.Cu")
	)
	(gr_line
		(start 306.558696 -89.218008)
		(end 306.734972 -89.041732)
		(stroke
			(width 0.04445)
			(type default)
		)
		(layer "In4.Cu")
	)
	(gr_line
		(start 306.560982 -79.278734)
		(end 306.583588 -79.262986)
		(stroke
			(width 0.04445)
			(type default)
		)
		(layer "In4.Cu")
	)
	(gr_line
		(start 306.56403 -83.937348)
		(end 306.6034 -83.976718)
		(stroke
			(width 0.04445)
			(type default)
		)
		(layer "In4.Cu")
	)
	(gr_line
		(start 306.56403 -83.746848)
		(end 306.6034 -83.707478)
		(stroke
			(width 0.04445)
			(type default)
		)
		(layer "In4.Cu")
	)
	(gr_line
		(start 306.565808 -104.019096)
		(end 307.118258 -103.790496)
		(stroke
			(width 0.05715)
			(type default)
		)
		(layer "In4.Cu")
	)
	(gr_line
		(start 306.572666 -83.06816)
		(end 306.669186 -82.97164)
		(stroke
			(width 0.04445)
			(type default)
		)
		(layer "In4.Cu")
	)
	(gr_line
		(start 306.573936 -84.932266)
		(end 306.672488 -85.030818)
		(stroke
			(width 0.04445)
			(type default)
		)
		(layer "In4.Cu")
	)
	(gr_line
		(start 306.577238 -92.646246)
		(end 306.583842 -92.643452)
		(stroke
			(width 0.04445)
			(type default)
		)
		(layer "In4.Cu")
	)
	(gr_line
		(start 306.58181 -100.761038)
		(end 306.591462 -100.77069)
		(stroke
			(width 0.04445)
			(type default)
		)
		(layer "In4.Cu")
	)
	(gr_line
		(start 306.58181 -100.488242)
		(end 306.591462 -100.47859)
		(stroke
			(width 0.04445)
			(type default)
		)
		(layer "In4.Cu")
	)
	(gr_line
		(start 306.582572 -93.31071)
		(end 306.711604 -93.364304)
		(stroke
			(width 0.04445)
			(type default)
		)
		(layer "In4.Cu")
	)
	(gr_line
		(start 306.589684 -77.257148)
		(end 306.599336 -77.2668)
		(stroke
			(width 0.04445)
			(type default)
		)
		(layer "In4.Cu")
	)
	(gr_line
		(start 306.589684 -76.984352)
		(end 306.599336 -76.9747)
		(stroke
			(width 0.04445)
			(type default)
		)
		(layer "In4.Cu")
	)
	(gr_line
		(start 306.591462 -100.77069)
		(end 306.61356 -100.77069)
		(stroke
			(width 0.04445)
			(type default)
		)
		(layer "In4.Cu")
	)
	(gr_line
		(start 306.591462 -100.47859)
		(end 306.61356 -100.47859)
		(stroke
			(width 0.04445)
			(type default)
		)
		(layer "In4.Cu")
	)
	(gr_line
		(start 306.592986 -87.715852)
		(end 306.730146 -87.715852)
		(stroke
			(width 0.04445)
			(type default)
		)
		(layer "In4.Cu")
	)
	(gr_line
		(start 306.599336 -77.2668)
		(end 306.621434 -77.2668)
		(stroke
			(width 0.04445)
			(type default)
		)
		(layer "In4.Cu")
	)
	(gr_line
		(start 306.599336 -76.9747)
		(end 306.621434 -76.9747)
		(stroke
			(width 0.04445)
			(type default)
		)
		(layer "In4.Cu")
	)
	(gr_line
		(start 306.605178 -83.978496)
		(end 306.61483 -83.988148)
		(stroke
			(width 0.04445)
			(type default)
		)
		(layer "In4.Cu")
	)
	(gr_line
		(start 306.605178 -83.7057)
		(end 306.61483 -83.696048)
		(stroke
			(width 0.04445)
			(type default)
		)
		(layer "In4.Cu")
	)
	(gr_line
		(start 306.61483 -83.988148)
		(end 306.636928 -83.988148)
		(stroke
			(width 0.04445)
			(type default)
		)
		(layer "In4.Cu")
	)
	(gr_line
		(start 306.61483 -83.696048)
		(end 306.636928 -83.696048)
		(stroke
			(width 0.04445)
			(type default)
		)
		(layer "In4.Cu")
	)
	(gr_line
		(start 306.62372 -88.095074)
		(end 306.846986 -87.872062)
		(stroke
			(width 0.04445)
			(type default)
		)
		(layer "In4.Cu")
	)
	(gr_line
		(start 306.640992 -92.316808)
		(end 306.647596 -92.314014)
		(stroke
			(width 0.04445)
			(type default)
		)
		(layer "In4.Cu")
	)
	(gr_line
		(start 306.64785 -82.261202)
		(end 306.746656 -82.360008)
		(stroke
			(width 0.04445)
			(type default)
		)
		(layer "In4.Cu")
	)
	(gr_line
		(start 306.659534 -78.98003)
		(end 306.682902 -78.964028)
		(stroke
			(width 0.04445)
			(type default)
		)
		(layer "In4.Cu")
	)
	(gr_line
		(start 306.669186 -82.97164)
		(end 306.846986 -82.97164)
		(stroke
			(width 0.04445)
			(type default)
		)
		(layer "In4.Cu")
	)
	(gr_line
		(start 306.674774 -91.572842)
		(end 306.681378 -91.570048)
		(stroke
			(width 0.04445)
			(type default)
		)
		(layer "In4.Cu")
	)
	(gr_line
		(start 306.67579 -90.123264)
		(end 306.73167 -90.123264)
		(stroke
			(width 0.04445)
			(type default)
		)
		(layer "In4.Cu")
	)
	(gr_line
		(start 306.692554 -75.316334)
		(end 306.731924 -75.355704)
		(stroke
			(width 0.04445)
			(type default)
		)
		(layer "In4.Cu")
	)
	(gr_line
		(start 306.692554 -75.125834)
		(end 306.731924 -75.086464)
		(stroke
			(width 0.04445)
			(type default)
		)
		(layer "In4.Cu")
	)
	(gr_line
		(start 306.733702 -75.357482)
		(end 306.743354 -75.367134)
		(stroke
			(width 0.04445)
			(type default)
		)
		(layer "In4.Cu")
	)
	(gr_line
		(start 306.733702 -75.084686)
		(end 306.743354 -75.075034)
		(stroke
			(width 0.04445)
			(type default)
		)
		(layer "In4.Cu")
	)
	(gr_line
		(start 306.73421 -90.123264)
		(end 306.747926 -90.123264)
		(stroke
			(width 0.04445)
			(type default)
		)
		(layer "In4.Cu")
	)
	(gr_line
		(start 306.734972 -88.937592)
		(end 306.734972 -89.041732)
		(stroke
			(width 0.04445)
			(type default)
		)
		(layer "In4.Cu")
	)
	(gr_line
		(start 306.743354 -75.367134)
		(end 306.765452 -75.367134)
		(stroke
			(width 0.04445)
			(type default)
		)
		(layer "In4.Cu")
	)
	(gr_line
		(start 306.743354 -75.075034)
		(end 306.765452 -75.075034)
		(stroke
			(width 0.04445)
			(type default)
		)
		(layer "In4.Cu")
	)
	(gr_line
		(start 306.747926 -90.123264)
		(end 306.76342 -90.10777)
		(stroke
			(width 0.04445)
			(type default)
		)
		(layer "In4.Cu")
	)
	(gr_line
		(start 306.765452 -76.327)
		(end 306.804822 -76.36637)
		(stroke
			(width 0.04445)
			(type default)
		)
		(layer "In4.Cu")
	)
	(gr_line
		(start 306.765452 -76.1365)
		(end 306.804822 -76.09713)
		(stroke
			(width 0.04445)
			(type default)
		)
		(layer "In4.Cu")
	)
	(gr_line
		(start 306.8066 -95.7453)
		(end 306.84597 -95.78467)
		(stroke
			(width 0.04445)
			(type default)
		)
		(layer "In4.Cu")
	)
	(gr_line
		(start 306.8066 -95.5548)
		(end 306.84597 -95.51543)
		(stroke
			(width 0.04445)
			(type default)
		)
		(layer "In4.Cu")
	)
	(gr_line
		(start 306.8066 -76.368148)
		(end 306.816252 -76.3778)
		(stroke
			(width 0.04445)
			(type default)
		)
		(layer "In4.Cu")
	)
	(gr_line
		(start 306.8066 -76.095352)
		(end 306.816252 -76.0857)
		(stroke
			(width 0.04445)
			(type default)
		)
		(layer "In4.Cu")
	)
	(gr_line
		(start 306.816252 -76.3778)
		(end 306.83835 -76.3778)
		(stroke
			(width 0.04445)
			(type default)
		)
		(layer "In4.Cu")
	)
	(gr_line
		(start 306.816252 -76.0857)
		(end 306.83835 -76.0857)
		(stroke
			(width 0.04445)
			(type default)
		)
		(layer "In4.Cu")
	)
	(gr_line
		(start 306.825142 -103.416608)
		(end 307.037994 -103.504746)
		(stroke
			(width 0.05715)
			(type default)
		)
		(layer "In4.Cu")
	)
	(gr_line
		(start 306.838858 -97.416874)
		(end 306.85359 -97.409)
		(stroke
			(width 0.04445)
			(type default)
		)
		(layer "In4.Cu")
	)
	(gr_line
		(start 306.846986 -82.97164)
		(end 306.943506 -83.06816)
		(stroke
			(width 0.04445)
			(type default)
		)
		(layer "In4.Cu")
	)
	(gr_line
		(start 306.847748 -95.786448)
		(end 306.8574 -95.7961)
		(stroke
			(width 0.04445)
			(type default)
		)
		(layer "In4.Cu")
	)
	(gr_line
		(start 306.847748 -95.513652)
		(end 306.8574 -95.504)
		(stroke
			(width 0.04445)
			(type default)
		)
		(layer "In4.Cu")
	)
	(gr_line
		(start 306.8574 -95.7961)
		(end 306.879498 -95.7961)
		(stroke
			(width 0.04445)
			(type default)
		)
		(layer "In4.Cu")
	)
	(gr_line
		(start 306.8574 -95.504)
		(end 306.879498 -95.504)
		(stroke
			(width 0.04445)
			(type default)
		)
		(layer "In4.Cu")
	)
	(gr_line
		(start 306.877212 -85.030818)
		(end 306.975764 -84.932266)
		(stroke
			(width 0.04445)
			(type default)
		)
		(layer "In4.Cu")
	)
	(gr_line
		(start 306.88026 -88.519254)
		(end 306.891182 -88.508332)
		(stroke
			(width 0.04445)
			(type default)
		)
		(layer "In4.Cu")
	)
	(gr_line
		(start 306.882038 -88.790526)
		(end 306.986178 -88.790526)
		(stroke
			(width 0.04445)
			(type default)
		)
		(layer "In4.Cu")
	)
	(gr_line
		(start 306.906422 -99.335844)
		(end 306.910232 -99.33432)
		(stroke
			(width 0.04445)
			(type default)
		)
		(layer "In4.Cu")
	)
	(gr_line
		(start 306.907184 -102.61854)
		(end 306.946554 -102.65791)
		(stroke
			(width 0.04445)
			(type default)
		)
		(layer "In4.Cu")
	)
	(gr_line
		(start 306.907184 -102.42804)
		(end 306.946554 -102.38867)
		(stroke
			(width 0.04445)
			(type default)
		)
		(layer "In4.Cu")
	)
	(gr_line
		(start 306.917598 -93.279468)
		(end 306.943506 -93.216476)
		(stroke
			(width 0.04445)
			(type default)
		)
		(layer "In4.Cu")
	)
	(gr_line
		(start 306.929536 -82.360008)
		(end 307.028342 -82.261202)
		(stroke
			(width 0.04445)
			(type default)
		)
		(layer "In4.Cu")
	)
	(gr_line
		(start 306.941982 -74.376534)
		(end 307.001926 -74.315066)
		(stroke
			(width 0.05715)
			(type default)
		)
		(layer "In4.Cu")
	)
	(gr_line
		(start 306.943506 -93.216476)
		(end 306.96408 -93.208094)
		(stroke
			(width 0.04445)
			(type default)
		)
		(layer "In4.Cu")
	)
	(gr_line
		(start 306.948332 -102.659688)
		(end 306.957984 -102.66934)
		(stroke
			(width 0.04445)
			(type default)
		)
		(layer "In4.Cu")
	)
	(gr_line
		(start 306.948332 -102.386892)
		(end 306.957984 -102.37724)
		(stroke
			(width 0.04445)
			(type default)
		)
		(layer "In4.Cu")
	)
	(gr_line
		(start 306.957984 -102.66934)
		(end 306.980082 -102.66934)
		(stroke
			(width 0.04445)
			(type default)
		)
		(layer "In4.Cu")
	)
	(gr_line
		(start 306.957984 -102.37724)
		(end 306.980082 -102.37724)
		(stroke
			(width 0.04445)
			(type default)
		)
		(layer "In4.Cu")
	)
	(gr_line
		(start 306.96281 -96.298258)
		(end 306.968398 -96.295718)
		(stroke
			(width 0.04445)
			(type default)
		)
		(layer "In4.Cu")
	)
	(gr_line
		(start 306.96535 -77.2668)
		(end 306.993544 -77.252576)
		(stroke
			(width 0.05715)
			(type default)
		)
		(layer "In4.Cu")
	)
	(gr_line
		(start 306.97551 -79.921608)
		(end 307.01488 -79.960978)
		(stroke
			(width 0.04445)
			(type default)
		)
		(layer "In4.Cu")
	)
	(gr_line
		(start 306.97551 -79.731108)
		(end 307.01488 -79.691738)
		(stroke
			(width 0.04445)
			(type default)
		)
		(layer "In4.Cu")
	)
	(gr_line
		(start 306.975764 -84.932266)
		(end 307.153564 -84.932266)
		(stroke
			(width 0.04445)
			(type default)
		)
		(layer "In4.Cu")
	)
	(gr_line
		(start 306.986178 -88.790526)
		(end 307.162454 -88.61425)
		(stroke
			(width 0.04445)
			(type default)
		)
		(layer "In4.Cu")
	)
	(gr_line
		(start 306.99202 -93.460062)
		(end 307.055012 -93.486732)
		(stroke
			(width 0.04445)
			(type default)
		)
		(layer "In4.Cu")
	)
	(gr_line
		(start 307.003704 -79.154528)
		(end 307.043074 -79.193898)
		(stroke
			(width 0.04445)
			(type default)
		)
		(layer "In4.Cu")
	)
	(gr_line
		(start 307.003704 -78.964028)
		(end 307.043074 -78.924658)
		(stroke
			(width 0.04445)
			(type default)
		)
		(layer "In4.Cu")
	)
	(gr_line
		(start 307.00726 -76.3778)
		(end 307.041042 -76.358496)
		(stroke
			(width 0.05715)
			(type default)
		)
		(layer "In4.Cu")
	)
	(gr_line
		(start 307.016658 -79.962756)
		(end 307.02631 -79.972408)
		(stroke
			(width 0.04445)
			(type default)
		)
		(layer "In4.Cu")
	)
	(gr_line
		(start 307.016658 -79.68996)
		(end 307.02631 -79.680308)
		(stroke
			(width 0.04445)
			(type default)
		)
		(layer "In4.Cu")
	)
	(gr_line
		(start 307.02631 -79.972408)
		(end 307.048408 -79.972408)
		(stroke
			(width 0.04445)
			(type default)
		)
		(layer "In4.Cu")
	)
	(gr_line
		(start 307.02631 -79.680308)
		(end 307.048408 -79.680308)
		(stroke
			(width 0.04445)
			(type default)
		)
		(layer "In4.Cu")
	)
	(gr_line
		(start 307.028342 -82.261202)
		(end 307.206142 -82.261202)
		(stroke
			(width 0.04445)
			(type default)
		)
		(layer "In4.Cu")
	)
	(gr_line
		(start 307.044852 -79.195676)
		(end 307.054504 -79.205328)
		(stroke
			(width 0.04445)
			(type default)
		)
		(layer "In4.Cu")
	)
	(gr_line
		(start 307.044852 -78.92288)
		(end 307.054504 -78.913228)
		(stroke
			(width 0.04445)
			(type default)
		)
		(layer "In4.Cu")
	)
	(gr_line
		(start 307.054504 -79.205328)
		(end 307.076602 -79.205328)
		(stroke
			(width 0.04445)
			(type default)
		)
		(layer "In4.Cu")
	)
	(gr_line
		(start 307.054504 -78.913228)
		(end 307.076602 -78.913228)
		(stroke
			(width 0.04445)
			(type default)
		)
		(layer "In4.Cu")
	)
	(gr_line
		(start 307.055012 -93.486732)
		(end 307.075586 -93.478096)
		(stroke
			(width 0.04445)
			(type default)
		)
		(layer "In4.Cu")
	)
	(gr_line
		(start 307.093874 -99.52482)
		(end 307.133244 -99.56419)
		(stroke
			(width 0.04445)
			(type default)
		)
		(layer "In4.Cu")
	)
	(gr_line
		(start 307.093874 -99.33432)
		(end 307.133244 -99.29495)
		(stroke
			(width 0.04445)
			(type default)
		)
		(layer "In4.Cu")
	)
	(gr_line
		(start 307.094636 -80.622648)
		(end 307.134006 -80.662018)
		(stroke
			(width 0.04445)
			(type default)
		)
		(layer "In4.Cu")
	)
	(gr_line
		(start 307.094636 -80.432148)
		(end 307.134006 -80.392778)
		(stroke
			(width 0.04445)
			(type default)
		)
		(layer "In4.Cu")
	)
	(gr_line
		(start 307.111908 -75.367134)
		(end 307.1749 -75.29195)
		(stroke
			(width 0.05715)
			(type default)
		)
		(layer "In4.Cu")
	)
	(gr_line
		(start 307.135022 -99.565968)
		(end 307.144674 -99.57562)
		(stroke
			(width 0.04445)
			(type default)
		)
		(layer "In4.Cu")
	)
	(gr_line
		(start 307.135022 -99.293172)
		(end 307.144674 -99.28352)
		(stroke
			(width 0.04445)
			(type default)
		)
		(layer "In4.Cu")
	)
	(gr_line
		(start 307.135784 -80.663796)
		(end 307.145436 -80.673448)
		(stroke
			(width 0.04445)
			(type default)
		)
		(layer "In4.Cu")
	)
	(gr_line
		(start 307.135784 -80.391)
		(end 307.145436 -80.381348)
		(stroke
			(width 0.04445)
			(type default)
		)
		(layer "In4.Cu")
	)
	(gr_line
		(start 307.144674 -99.57562)
		(end 307.166772 -99.57562)
		(stroke
			(width 0.04445)
			(type default)
		)
		(layer "In4.Cu")
	)
	(gr_line
		(start 307.144674 -99.28352)
		(end 307.166772 -99.28352)
		(stroke
			(width 0.04445)
			(type default)
		)
		(layer "In4.Cu")
	)
	(gr_line
		(start 307.145436 -80.673448)
		(end 307.167534 -80.673448)
		(stroke
			(width 0.04445)
			(type default)
		)
		(layer "In4.Cu")
	)
	(gr_line
		(start 307.145436 -80.381348)
		(end 307.167534 -80.381348)
		(stroke
			(width 0.04445)
			(type default)
		)
		(layer "In4.Cu")
	)
	(gr_line
		(start 307.153564 -84.932266)
		(end 307.252116 -85.030818)
		(stroke
			(width 0.04445)
			(type default)
		)
		(layer "In4.Cu")
	)
	(gr_line
		(start 307.15839 -98.87585)
		(end 307.19776 -98.91522)
		(stroke
			(width 0.04445)
			(type default)
		)
		(layer "In4.Cu")
	)
	(gr_line
		(start 307.15839 -98.68535)
		(end 307.19776 -98.64598)
		(stroke
			(width 0.04445)
			(type default)
		)
		(layer "In4.Cu")
	)
	(gr_line
		(start 307.162454 -88.51011)
		(end 307.162454 -88.61425)
		(stroke
			(width 0.04445)
			(type default)
		)
		(layer "In4.Cu")
	)
	(gr_line
		(start 307.173122 -78.339188)
		(end 307.21427 -78.311502)
		(stroke
			(width 0.05715)
			(type default)
		)
		(layer "In4.Cu")
	)
	(gr_line
		(start 307.199538 -98.916998)
		(end 307.20919 -98.92665)
		(stroke
			(width 0.04445)
			(type default)
		)
		(layer "In4.Cu")
	)
	(gr_line
		(start 307.199538 -98.644202)
		(end 307.20919 -98.63455)
		(stroke
			(width 0.04445)
			(type default)
		)
		(layer "In4.Cu")
	)
	(gr_line
		(start 307.206142 -82.261202)
		(end 307.304948 -82.360008)
		(stroke
			(width 0.04445)
			(type default)
		)
		(layer "In4.Cu")
	)
	(gr_line
		(start 307.20919 -98.92665)
		(end 307.231034 -98.92665)
		(stroke
			(width 0.04445)
			(type default)
		)
		(layer "In4.Cu")
	)
	(gr_line
		(start 307.20919 -98.63455)
		(end 307.231288 -98.63455)
		(stroke
			(width 0.04445)
			(type default)
		)
		(layer "In4.Cu")
	)
	(gr_line
		(start 307.218842 -92.07754)
		(end 307.22443 -92.075)
		(stroke
			(width 0.04445)
			(type default)
		)
		(layer "In4.Cu")
	)
	(gr_line
		(start 307.231034 -98.92665)
		(end 307.231288 -98.926904)
		(stroke
			(width 0.05715)
			(type default)
		)
		(layer "In4.Cu")
	)
	(gr_line
		(start 307.282088 -96.486218)
		(end 307.321458 -96.525588)
		(stroke
			(width 0.04445)
			(type default)
		)
		(layer "In4.Cu")
	)
	(gr_line
		(start 307.282088 -96.295718)
		(end 307.321458 -96.256348)
		(stroke
			(width 0.04445)
			(type default)
		)
		(layer "In4.Cu")
	)
	(gr_line
		(start 307.291486 -81.75498)
		(end 307.330856 -81.79435)
		(stroke
			(width 0.04445)
			(type default)
		)
		(layer "In4.Cu")
	)
	(gr_line
		(start 307.291486 -81.56448)
		(end 307.330856 -81.52511)
		(stroke
			(width 0.04445)
			(type default)
		)
		(layer "In4.Cu")
	)
	(gr_line
		(start 307.3146 -97.5995)
		(end 307.35397 -97.63887)
		(stroke
			(width 0.04445)
			(type default)
		)
		(layer "In4.Cu")
	)
	(gr_line
		(start 307.3146 -97.409)
		(end 307.35397 -97.36963)
		(stroke
			(width 0.04445)
			(type default)
		)
		(layer "In4.Cu")
	)
	(gr_line
		(start 307.314854 -83.2612)
		(end 307.354224 -83.30057)
		(stroke
			(width 0.04445)
			(type default)
		)
		(layer "In4.Cu")
	)
	(gr_line
		(start 307.314854 -83.0707)
		(end 307.354224 -83.03133)
		(stroke
			(width 0.04445)
			(type default)
		)
		(layer "In4.Cu")
	)
	(gr_line
		(start 307.323236 -96.527366)
		(end 307.332888 -96.537018)
		(stroke
			(width 0.04445)
			(type default)
		)
		(layer "In4.Cu")
	)
	(gr_line
		(start 307.323236 -96.25457)
		(end 307.332888 -96.244918)
		(stroke
			(width 0.04445)
			(type default)
		)
		(layer "In4.Cu")
	)
	(gr_line
		(start 307.332634 -81.796128)
		(end 307.342286 -81.80578)
		(stroke
			(width 0.04445)
			(type default)
		)
		(layer "In4.Cu")
	)
	(gr_line
		(start 307.332634 -81.523332)
		(end 307.342286 -81.51368)
		(stroke
			(width 0.04445)
			(type default)
		)
		(layer "In4.Cu")
	)
	(gr_line
		(start 307.332888 -96.537018)
		(end 307.354986 -96.537018)
		(stroke
			(width 0.04445)
			(type default)
		)
		(layer "In4.Cu")
	)
	(gr_line
		(start 307.332888 -96.244918)
		(end 307.354986 -96.244918)
		(stroke
			(width 0.04445)
			(type default)
		)
		(layer "In4.Cu")
	)
	(gr_line
		(start 307.342286 -81.80578)
		(end 307.364384 -81.80578)
		(stroke
			(width 0.04445)
			(type default)
		)
		(layer "In4.Cu")
	)
	(gr_line
		(start 307.342286 -81.51368)
		(end 307.364384 -81.51368)
		(stroke
			(width 0.04445)
			(type default)
		)
		(layer "In4.Cu")
	)
	(gr_line
		(start 307.355748 -97.640648)
		(end 307.3654 -97.6503)
		(stroke
			(width 0.04445)
			(type default)
		)
		(layer "In4.Cu")
	)
	(gr_line
		(start 307.355748 -97.367852)
		(end 307.3654 -97.3582)
		(stroke
			(width 0.04445)
			(type default)
		)
		(layer "In4.Cu")
	)
	(gr_line
		(start 307.356002 -83.302348)
		(end 307.365654 -83.312)
		(stroke
			(width 0.04445)
			(type default)
		)
		(layer "In4.Cu")
	)
	(gr_line
		(start 307.356002 -83.029552)
		(end 307.365654 -83.0199)
		(stroke
			(width 0.04445)
			(type default)
		)
		(layer "In4.Cu")
	)
	(gr_line
		(start 307.3654 -97.6503)
		(end 307.387498 -97.6503)
		(stroke
			(width 0.04445)
			(type default)
		)
		(layer "In4.Cu")
	)
	(gr_line
		(start 307.3654 -97.3582)
		(end 307.387498 -97.3582)
		(stroke
			(width 0.04445)
			(type default)
		)
		(layer "In4.Cu")
	)
	(gr_line
		(start 307.3654 -92.2655)
		(end 307.40477 -92.30487)
		(stroke
			(width 0.04445)
			(type default)
		)
		(layer "In4.Cu")
	)
	(gr_line
		(start 307.3654 -92.075)
		(end 307.40477 -92.03563)
		(stroke
			(width 0.04445)
			(type default)
		)
		(layer "In4.Cu")
	)
	(gr_line
		(start 307.365654 -83.312)
		(end 307.387752 -83.312)
		(stroke
			(width 0.04445)
			(type default)
		)
		(layer "In4.Cu")
	)
	(gr_line
		(start 307.365654 -83.0199)
		(end 307.387752 -83.0199)
		(stroke
			(width 0.04445)
			(type default)
		)
		(layer "In4.Cu")
	)
	(gr_line
		(start 307.377084 -79.205328)
		(end 307.418232 -79.177642)
		(stroke
			(width 0.05715)
			(type default)
		)
		(layer "In4.Cu")
	)
	(gr_line
		(start 307.406548 -92.306648)
		(end 307.4162 -92.3163)
		(stroke
			(width 0.04445)
			(type default)
		)
		(layer "In4.Cu")
	)
	(gr_line
		(start 307.406548 -92.033852)
		(end 307.4162 -92.0242)
		(stroke
			(width 0.04445)
			(type default)
		)
		(layer "In4.Cu")
	)
	(gr_line
		(start 307.4162 -92.3163)
		(end 307.438298 -92.3163)
		(stroke
			(width 0.04445)
			(type default)
		)
		(layer "In4.Cu")
	)
	(gr_line
		(start 307.4162 -92.0242)
		(end 307.438298 -92.0242)
		(stroke
			(width 0.04445)
			(type default)
		)
		(layer "In4.Cu")
	)
	(gr_line
		(start 307.420264 -87.029036)
		(end 307.4543 -86.995)
		(stroke
			(width 0.04445)
			(type default)
		)
		(layer "In4.Cu")
	)
	(gr_line
		(start 307.442616 -76.129642)
		(end 307.453538 -76.123292)
		(stroke
			(width 0.05715)
			(type default)
		)
		(layer "In4.Cu")
	)
	(gr_line
		(start 307.453538 -76.123292)
		(end 307.46192 -76.113894)
		(stroke
			(width 0.05715)
			(type default)
		)
		(layer "In4.Cu")
	)
	(gr_line
		(start 307.45938 -67.141852)
		(end 307.462428 -67.166744)
		(stroke
			(width 0.05715)
			(type default)
		)
		(layer "In4.Cu")
	)
	(gr_line
		(start 307.45938 -67.141852)
		(end 307.466746 -67.117976)
		(stroke
			(width 0.05715)
			(type default)
		)
		(layer "In4.Cu")
	)
	(gr_line
		(start 307.46192 -85.030818)
		(end 307.515006 -84.977732)
		(stroke
			(width 0.04445)
			(type default)
		)
		(layer "In4.Cu")
	)
	(gr_line
		(start 307.491384 -82.360516)
		(end 307.530754 -82.321146)
		(stroke
			(width 0.04445)
			(type default)
		)
		(layer "In4.Cu")
	)
	(gr_line
		(start 307.493416 -82.553048)
		(end 307.530754 -82.590386)
		(stroke
			(width 0.04445)
			(type default)
		)
		(layer "In4.Cu")
	)
	(gr_line
		(start 307.503322 -103.630984)
		(end 307.523388 -103.622602)
		(stroke
			(width 0.05715)
			(type default)
		)
		(layer "In4.Cu")
	)
	(gr_line
		(start 307.515006 -84.977732)
		(end 307.692806 -84.977732)
		(stroke
			(width 0.04445)
			(type default)
		)
		(layer "In4.Cu")
	)
	(gr_line
		(start 307.523388 -103.622602)
		(end 307.538882 -103.607108)
		(stroke
			(width 0.05715)
			(type default)
		)
		(layer "In4.Cu")
	)
	(gr_line
		(start 307.532024 -85.721952)
		(end 307.618384 -85.808312)
		(stroke
			(width 0.04445)
			(type default)
		)
		(layer "In4.Cu")
	)
	(gr_line
		(start 307.532532 -82.592164)
		(end 307.542184 -82.601816)
		(stroke
			(width 0.04445)
			(type default)
		)
		(layer "In4.Cu")
	)
	(gr_line
		(start 307.532532 -82.319368)
		(end 307.542184 -82.309716)
		(stroke
			(width 0.04445)
			(type default)
		)
		(layer "In4.Cu")
	)
	(gr_line
		(start 307.542184 -82.601816)
		(end 307.564282 -82.601816)
		(stroke
			(width 0.04445)
			(type default)
		)
		(layer "In4.Cu")
	)
	(gr_line
		(start 307.542184 -82.309716)
		(end 307.564282 -82.309716)
		(stroke
			(width 0.04445)
			(type default)
		)
		(layer "In4.Cu")
	)
	(gr_line
		(start 307.544724 -94.633288)
		(end 307.584094 -94.672658)
		(stroke
			(width 0.04445)
			(type default)
		)
		(layer "In4.Cu")
	)
	(gr_line
		(start 307.544724 -94.442788)
		(end 307.584094 -94.403418)
		(stroke
			(width 0.04445)
			(type default)
		)
		(layer "In4.Cu")
	)
	(gr_line
		(start 307.585872 -94.674436)
		(end 307.595524 -94.684088)
		(stroke
			(width 0.04445)
			(type default)
		)
		(layer "In4.Cu")
	)
	(gr_line
		(start 307.585872 -94.40164)
		(end 307.595524 -94.391988)
		(stroke
			(width 0.04445)
			(type default)
		)
		(layer "In4.Cu")
	)
	(gr_line
		(start 307.588666 -88.288622)
		(end 307.662326 -88.362282)
		(stroke
			(width 0.04445)
			(type default)
		)
		(layer "In4.Cu")
	)
	(gr_line
		(start 307.591714 -100.77069)
		(end 307.650642 -100.711762)
		(stroke
			(width 0.05715)
			(type default)
		)
		(layer "In4.Cu")
	)
	(gr_line
		(start 307.59527 -68.251324)
		(end 307.599334 -68.284344)
		(stroke
			(width 0.05715)
			(type default)
		)
		(layer "In4.Cu")
	)
	(gr_line
		(start 307.595524 -94.684088)
		(end 307.617622 -94.684088)
		(stroke
			(width 0.04445)
			(type default)
		)
		(layer "In4.Cu")
	)
	(gr_line
		(start 307.595524 -94.391988)
		(end 307.617622 -94.391988)
		(stroke
			(width 0.04445)
			(type default)
		)
		(layer "In4.Cu")
	)
	(gr_line
		(start 307.599334 -68.284344)
		(end 307.61813 -68.31203)
		(stroke
			(width 0.05715)
			(type default)
		)
		(layer "In4.Cu")
	)
	(gr_line
		(start 307.618384 -85.808312)
		(end 307.885084 -85.808312)
		(stroke
			(width 0.04445)
			(type default)
		)
		(layer "In4.Cu")
	)
	(gr_line
		(start 307.622194 -79.972408)
		(end 307.664358 -79.944214)
		(stroke
			(width 0.05715)
			(type default)
		)
		(layer "In4.Cu")
	)
	(gr_line
		(start 307.662326 -88.362282)
		(end 307.911246 -88.362282)
		(stroke
			(width 0.04445)
			(type default)
		)
		(layer "In4.Cu")
	)
	(gr_line
		(start 307.664358 -95.7961)
		(end 307.723286 -95.737172)
		(stroke
			(width 0.05715)
			(type default)
		)
		(layer "In4.Cu")
	)
	(gr_line
		(start 307.692806 -84.977732)
		(end 307.745892 -85.030818)
		(stroke
			(width 0.04445)
			(type default)
		)
		(layer "In4.Cu")
	)
	(gr_line
		(start 307.710586 -81.80578)
		(end 307.76545 -81.755996)
		(stroke
			(width 0.05715)
			(type default)
		)
		(layer "In4.Cu")
	)
	(gr_line
		(start 307.722524 -85.528912)
		(end 307.780944 -85.528912)
		(stroke
			(width 0.04445)
			(type default)
		)
		(layer "In4.Cu")
	)
	(gr_line
		(start 307.726334 -80.381348)
		(end 307.819552 -80.381348)
		(stroke
			(width 0.05715)
			(type default)
		)
		(layer "In4.Cu")
	)
	(gr_line
		(start 307.753766 -92.3163)
		(end 307.771038 -92.308934)
		(stroke
			(width 0.05715)
			(type default)
		)
		(layer "In4.Cu")
	)
	(gr_line
		(start 307.779166 -88.095582)
		(end 307.794406 -88.095582)
		(stroke
			(width 0.04445)
			(type default)
		)
		(layer "In4.Cu")
	)
	(gr_line
		(start 307.79339 -104.262936)
		(end 307.813456 -104.254554)
		(stroke
			(width 0.05715)
			(type default)
		)
		(layer "In4.Cu")
	)
	(gr_line
		(start 307.7972 -86.5505)
		(end 307.83657 -86.58987)
		(stroke
			(width 0.04445)
			(type default)
		)
		(layer "In4.Cu")
	)
	(gr_line
		(start 307.7972 -86.36)
		(end 307.83657 -86.32063)
		(stroke
			(width 0.04445)
			(type default)
		)
		(layer "In4.Cu")
	)
	(gr_line
		(start 307.812186 -76.838556)
		(end 307.827172 -76.830936)
		(stroke
			(width 0.05715)
			(type default)
		)
		(layer "In4.Cu")
	)
	(gr_line
		(start 307.813456 -104.254554)
		(end 307.82895 -104.23906)
		(stroke
			(width 0.05715)
			(type default)
		)
		(layer "In4.Cu")
	)
	(gr_line
		(start 307.827172 -76.830936)
		(end 307.83784 -76.819252)
		(stroke
			(width 0.05715)
			(type default)
		)
		(layer "In4.Cu")
	)
	(gr_line
		(start 307.830728 -73.464674)
		(end 307.844698 -73.450196)
		(stroke
			(width 0.05715)
			(type default)
		)
		(layer "In4.Cu")
	)
	(gr_line
		(start 307.838348 -86.591648)
		(end 307.848 -86.6013)
		(stroke
			(width 0.04445)
			(type default)
		)
		(layer "In4.Cu")
	)
	(gr_line
		(start 307.838348 -86.318852)
		(end 307.848 -86.3092)
		(stroke
			(width 0.04445)
			(type default)
		)
		(layer "In4.Cu")
	)
	(gr_line
		(start 307.844698 -73.450196)
		(end 307.852318 -73.431908)
		(stroke
			(width 0.05715)
			(type default)
		)
		(layer "In4.Cu")
	)
	(gr_line
		(start 307.84546 -91.088718)
		(end 307.851048 -91.086178)
		(stroke
			(width 0.04445)
			(type default)
		)
		(layer "In4.Cu")
	)
	(gr_line
		(start 307.845968 -65.89649)
		(end 307.856382 -65.863216)
		(stroke
			(width 0.05715)
			(type default)
		)
		(layer "In4.Cu")
	)
	(gr_line
		(start 307.848 -86.6013)
		(end 307.870098 -86.6013)
		(stroke
			(width 0.04445)
			(type default)
		)
		(layer "In4.Cu")
	)
	(gr_line
		(start 307.848 -86.3092)
		(end 307.870098 -86.3092)
		(stroke
			(width 0.04445)
			(type default)
		)
		(layer "In4.Cu")
	)
	(gr_line
		(start 307.854858 -94.684088)
		(end 307.913786 -94.62516)
		(stroke
			(width 0.05715)
			(type default)
		)
		(layer "In4.Cu")
	)
	(gr_line
		(start 307.856382 -65.863216)
		(end 307.88102 -65.838832)
		(stroke
			(width 0.05715)
			(type default)
		)
		(layer "In4.Cu")
	)
	(gr_line
		(start 307.878988 -82.601816)
		(end 307.933852 -82.552032)
		(stroke
			(width 0.05715)
			(type default)
		)
		(layer "In4.Cu")
	)
	(gr_line
		(start 307.885084 -85.808312)
		(end 307.971444 -85.721952)
		(stroke
			(width 0.04445)
			(type default)
		)
		(layer "In4.Cu")
	)
	(gr_line
		(start 307.911246 -88.362282)
		(end 307.984906 -88.288622)
		(stroke
			(width 0.04445)
			(type default)
		)
		(layer "In4.Cu")
	)
	(gr_line
		(start 307.932582 -80.673448)
		(end 307.98897 -80.622394)
		(stroke
			(width 0.05715)
			(type default)
		)
		(layer "In4.Cu")
	)
	(gr_line
		(start 308.015894 -80.597756)
		(end 308.015894 -80.59801)
		(stroke
			(width 0.05715)
			(type default)
		)
		(layer "In4.Cu")
	)
	(gr_line
		(start 308.10581 -83.312)
		(end 308.147974 -83.283806)
		(stroke
			(width 0.05715)
			(type default)
		)
		(layer "In4.Cu")
	)
	(gr_line
		(start 308.204362 -74.063352)
		(end 308.209696 -74.057002)
		(stroke
			(width 0.05715)
			(type default)
		)
		(layer "In4.Cu")
	)
	(gr_line
		(start 308.209696 -74.057002)
		(end 308.21249 -74.049636)
		(stroke
			(width 0.05715)
			(type default)
		)
		(layer "In4.Cu")
	)
	(gr_line
		(start 308.212998 -87.1855)
		(end 308.252368 -87.22487)
		(stroke
			(width 0.04445)
			(type default)
		)
		(layer "In4.Cu")
	)
	(gr_line
		(start 308.212998 -86.995)
		(end 308.252368 -86.95563)
		(stroke
			(width 0.04445)
			(type default)
		)
		(layer "In4.Cu")
	)
	(gr_line
		(start 308.246526 -88.286082)
		(end 308.250082 -88.284558)
		(stroke
			(width 0.04445)
			(type default)
		)
		(layer "In4.Cu")
	)
	(gr_line
		(start 308.254146 -87.226648)
		(end 308.263798 -87.2363)
		(stroke
			(width 0.04445)
			(type default)
		)
		(layer "In4.Cu")
	)
	(gr_line
		(start 308.254146 -86.953852)
		(end 308.263798 -86.9442)
		(stroke
			(width 0.04445)
			(type default)
		)
		(layer "In4.Cu")
	)
	(gr_line
		(start 308.263798 -87.2363)
		(end 308.285896 -87.2363)
		(stroke
			(width 0.04445)
			(type default)
		)
		(layer "In4.Cu")
	)
	(gr_line
		(start 308.263798 -86.9442)
		(end 308.285896 -86.9442)
		(stroke
			(width 0.04445)
			(type default)
		)
		(layer "In4.Cu")
	)
	(gr_line
		(start 308.294024 -77.590142)
		(end 308.29885 -77.58684)
		(stroke
			(width 0.05715)
			(type default)
		)
		(layer "In4.Cu")
	)
	(gr_line
		(start 308.298342 -91.276678)
		(end 308.30393 -91.274138)
		(stroke
			(width 0.04445)
			(type default)
		)
		(layer "In4.Cu")
	)
	(gr_line
		(start 308.29885 -77.58684)
		(end 308.30266 -77.582268)
		(stroke
			(width 0.05715)
			(type default)
		)
		(layer "In4.Cu")
	)
	(gr_line
		(start 308.324504 -55.151528)
		(end 308.327552 -55.11927)
		(stroke
			(width 0.05715)
			(type default)
		)
		(layer "In4.Cu")
	)
	(gr_line
		(start 308.324504 -55.151528)
		(end 308.336188 -55.181754)
		(stroke
			(width 0.05715)
			(type default)
		)
		(layer "In4.Cu")
	)
	(gr_line
		(start 308.333648 -83.988148)
		(end 308.374796 -83.960462)
		(stroke
			(width 0.05715)
			(type default)
		)
		(layer "In4.Cu")
	)
	(gr_line
		(start 308.349142 -89.1286)
		(end 308.366414 -89.121234)
		(stroke
			(width 0.05715)
			(type default)
		)
		(layer "In4.Cu")
	)
	(gr_line
		(start 308.385718 -85.223858)
		(end 308.41061 -85.205824)
		(stroke
			(width 0.04445)
			(type default)
		)
		(layer "In4.Cu")
	)
	(gr_line
		(start 308.396894 -88.024716)
		(end 308.714394 -87.903558)
		(stroke
			(width 0.04445)
			(type default)
		)
		(layer "In4.Cu")
	)
	(gr_line
		(start 308.439312 -88.214962)
		(end 308.564026 -88.270842)
		(stroke
			(width 0.04445)
			(type default)
		)
		(layer "In4.Cu")
	)
	(gr_line
		(start 308.491382 -84.908644)
		(end 308.501796 -84.841334)
		(stroke
			(width 0.04445)
			(type default)
		)
		(layer "In4.Cu")
	)
	(gr_line
		(start 308.501796 -84.841334)
		(end 308.519576 -84.82838)
		(stroke
			(width 0.04445)
			(type default)
		)
		(layer "In4.Cu")
	)
	(gr_line
		(start 308.527704 -52.319936)
		(end 308.527704 -52.320698)
		(stroke
			(width 0.05715)
			(type default)
		)
		(layer "In4.Cu")
	)
	(gr_line
		(start 308.527704 -52.314602)
		(end 308.527958 -52.319682)
		(stroke
			(width 0.05715)
			(type default)
		)
		(layer "In4.Cu")
	)
	(gr_line
		(start 308.527704 -52.314602)
		(end 308.528974 -52.310284)
		(stroke
			(width 0.05715)
			(type default)
		)
		(layer "In4.Cu")
	)
	(gr_line
		(start 308.55793 -91.169236)
		(end 308.564534 -91.166442)
		(stroke
			(width 0.04445)
			(type default)
		)
		(layer "In4.Cu")
	)
	(gr_line
		(start 308.564026 -88.270842)
		(end 308.754272 -88.198452)
		(stroke
			(width 0.04445)
			(type default)
		)
		(layer "In4.Cu")
	)
	(gr_line
		(start 308.606444 -55.881016)
		(end 308.61762 -55.909972)
		(stroke
			(width 0.05715)
			(type default)
		)
		(layer "In4.Cu")
	)
	(gr_line
		(start 308.606698 -85.066124)
		(end 308.689502 -85.066124)
		(stroke
			(width 0.04445)
			(type default)
		)
		(layer "In4.Cu")
	)
	(gr_line
		(start 308.61762 -55.909972)
		(end 308.64048 -55.930546)
		(stroke
			(width 0.05715)
			(type default)
		)
		(layer "In4.Cu")
	)
	(gr_line
		(start 308.627526 -90.77833)
		(end 308.627526 -90.833956)
		(stroke
			(width 0.04445)
			(type default)
		)
		(layer "In4.Cu")
	)
	(gr_line
		(start 308.627526 -90.762074)
		(end 308.627526 -90.77579)
		(stroke
			(width 0.04445)
			(type default)
		)
		(layer "In4.Cu")
	)
	(gr_line
		(start 308.627526 -90.762074)
		(end 308.64302 -90.74658)
		(stroke
			(width 0.04445)
			(type default)
		)
		(layer "In4.Cu")
	)
	(gr_line
		(start 308.689502 -85.066124)
		(end 308.691534 -85.0646)
		(stroke
			(width 0.04445)
			(type default)
		)
		(layer "In4.Cu")
	)
	(gr_line
		(start 308.754272 -88.198452)
		(end 308.810152 -88.07323)
		(stroke
			(width 0.04445)
			(type default)
		)
		(layer "In4.Cu")
	)
	(gr_line
		(start 308.762146 -90.96883)
		(end 308.818026 -90.96883)
		(stroke
			(width 0.04445)
			(type default)
		)
		(layer "In4.Cu")
	)
	(gr_line
		(start 308.820566 -90.96883)
		(end 308.834282 -90.96883)
		(stroke
			(width 0.04445)
			(type default)
		)
		(layer "In4.Cu")
	)
	(gr_line
		(start 308.82844 -69.571616)
		(end 308.840886 -69.58965)
		(stroke
			(width 0.05715)
			(type default)
		)
		(layer "In4.Cu")
	)
	(gr_line
		(start 308.834282 -90.96883)
		(end 308.849776 -90.953336)
		(stroke
			(width 0.04445)
			(type default)
		)
		(layer "In4.Cu")
	)
	(gr_line
		(start 308.8386 -91.867228)
		(end 308.858666 -91.858846)
		(stroke
			(width 0.05715)
			(type default)
		)
		(layer "In4.Cu")
	)
	(gr_line
		(start 308.839108 -51.192684)
		(end 308.84114 -51.18481)
		(stroke
			(width 0.05715)
			(type default)
		)
		(layer "In4.Cu")
	)
	(gr_line
		(start 308.840886 -69.58965)
		(end 308.84495 -69.610986)
		(stroke
			(width 0.05715)
			(type default)
		)
		(layer "In4.Cu")
	)
	(gr_line
		(start 308.84114 -51.18481)
		(end 308.845966 -51.17719)
		(stroke
			(width 0.05715)
			(type default)
		)
		(layer "In4.Cu")
	)
	(gr_line
		(start 308.9275 -85.719412)
		(end 308.953916 -85.6996)
		(stroke
			(width 0.04445)
			(type default)
		)
		(layer "In4.Cu")
	)
	(gr_line
		(start 308.938676 -87.818468)
		(end 308.968648 -87.757)
		(stroke
			(width 0.04445)
			(type default)
		)
		(layer "In4.Cu")
	)
	(gr_line
		(start 308.968648 -87.757)
		(end 308.989476 -87.749634)
		(stroke
			(width 0.04445)
			(type default)
		)
		(layer "In4.Cu")
	)
	(gr_line
		(start 308.970934 -86.6013)
		(end 309.014622 -86.571328)
		(stroke
			(width 0.05715)
			(type default)
		)
		(layer "In4.Cu")
	)
	(gr_line
		(start 309.0037 -88.002618)
		(end 309.065422 -88.032844)
		(stroke
			(width 0.04445)
			(type default)
		)
		(layer "In4.Cu")
	)
	(gr_line
		(start 309.014876 -85.414104)
		(end 309.02148 -85.364066)
		(stroke
			(width 0.04445)
			(type default)
		)
		(layer "In4.Cu")
	)
	(gr_line
		(start 309.017162 -70.619112)
		(end 309.036974 -70.57136)
		(stroke
			(width 0.05715)
			(type default)
		)
		(layer "In4.Cu")
	)
	(gr_line
		(start 309.02148 -85.364066)
		(end 309.039006 -85.350858)
		(stroke
			(width 0.04445)
			(type default)
		)
		(layer "In4.Cu")
	)
	(gr_line
		(start 309.026814 -70.52056)
		(end 309.036974 -70.57136)
		(stroke
			(width 0.05715)
			(type default)
		)
		(layer "In4.Cu")
	)
	(gr_line
		(start 309.065422 -88.032844)
		(end 309.086504 -88.025224)
		(stroke
			(width 0.04445)
			(type default)
		)
		(layer "In4.Cu")
	)
	(gr_line
		(start 309.110126 -85.584538)
		(end 309.19801 -85.596984)
		(stroke
			(width 0.04445)
			(type default)
		)
		(layer "In4.Cu")
	)
	(gr_line
		(start 309.153306 -87.2363)
		(end 309.193692 -87.20963)
		(stroke
			(width 0.05715)
			(type default)
		)
		(layer "In4.Cu")
	)
	(gr_line
		(start 309.19801 -85.596984)
		(end 309.215536 -85.583776)
		(stroke
			(width 0.04445)
			(type default)
		)
		(layer "In4.Cu")
	)
	(gr_line
		(start 309.251096 -50.560478)
		(end 309.255668 -50.55362)
		(stroke
			(width 0.05715)
			(type default)
		)
		(layer "In4.Cu")
	)
	(gr_line
		(start 309.255668 -50.55362)
		(end 309.262018 -50.54854)
		(stroke
			(width 0.05715)
			(type default)
		)
		(layer "In4.Cu")
	)
	(gr_line
		(start 309.256938 -74.078084)
		(end 309.264812 -74.069194)
		(stroke
			(width 0.05715)
			(type default)
		)
		(layer "In4.Cu")
	)
	(gr_line
		(start 309.264812 -74.069194)
		(end 309.269638 -74.057764)
		(stroke
			(width 0.05715)
			(type default)
		)
		(layer "In4.Cu")
	)
	(gr_line
		(start 309.287926 -53.217826)
		(end 309.29453 -53.278786)
		(stroke
			(width 0.05715)
			(type default)
		)
		(layer "In4.Cu")
	)
	(gr_line
		(start 309.29453 -53.278786)
		(end 309.336694 -53.323744)
		(stroke
			(width 0.05715)
			(type default)
		)
		(layer "In4.Cu")
	)
	(gr_line
		(start 309.434484 -51.450494)
		(end 309.436516 -51.443382)
		(stroke
			(width 0.05715)
			(type default)
		)
		(layer "In4.Cu")
	)
	(gr_line
		(start 309.436516 -51.443382)
		(end 309.44058 -51.43754)
		(stroke
			(width 0.05715)
			(type default)
		)
		(layer "In4.Cu")
	)
	(gr_line
		(start 309.54599 -85.333078)
		(end 309.555642 -85.325712)
		(stroke
			(width 0.05715)
			(type default)
		)
		(layer "In4.Cu")
	)
	(gr_line
		(start 309.555642 -85.325712)
		(end 309.5625 -85.315298)
		(stroke
			(width 0.05715)
			(type default)
		)
		(layer "In4.Cu")
	)
	(gr_line
		(start 309.556404 -66.123058)
		(end 309.565802 -66.177414)
		(stroke
			(width 0.05715)
			(type default)
		)
		(layer "In4.Cu")
	)
	(gr_line
		(start 309.556404 -66.123058)
		(end 309.580026 -66.074036)
		(stroke
			(width 0.05715)
			(type default)
		)
		(layer "In4.Cu")
	)
	(gr_line
		(start 309.593488 -74.92492)
		(end 309.603648 -74.913998)
		(stroke
			(width 0.05715)
			(type default)
		)
		(layer "In4.Cu")
	)
	(gr_line
		(start 309.603648 -74.913998)
		(end 309.608982 -74.90079)
		(stroke
			(width 0.05715)
			(type default)
		)
		(layer "In4.Cu")
	)
	(gr_line
		(start 309.740046 -50.984404)
		(end 309.743856 -50.978816)
		(stroke
			(width 0.05715)
			(type default)
		)
		(layer "In4.Cu")
	)
	(gr_line
		(start 309.743856 -50.978816)
		(end 309.74919 -50.974498)
		(stroke
			(width 0.05715)
			(type default)
		)
		(layer "In4.Cu")
	)
	(gr_line
		(start 309.853838 -85.99424)
		(end 309.8673 -85.985096)
		(stroke
			(width 0.05715)
			(type default)
		)
		(layer "In4.Cu")
	)
	(gr_line
		(start 309.8673 -85.985096)
		(end 309.876698 -85.97138)
		(stroke
			(width 0.05715)
			(type default)
		)
		(layer "In4.Cu")
	)
	(gr_line
		(start 310.241442 -75.220068)
		(end 310.245506 -75.214988)
		(stroke
			(width 0.05715)
			(type default)
		)
		(layer "In4.Cu")
	)
	(gr_line
		(start 310.245506 -75.214988)
		(end 310.248046 -75.209146)
		(stroke
			(width 0.05715)
			(type default)
		)
		(layer "In4.Cu")
	)
	(gr_line
		(start 310.274462 -64.619378)
		(end 310.295544 -64.575436)
		(stroke
			(width 0.05715)
			(type default)
		)
		(layer "In4.Cu")
	)
	(gr_line
		(start 310.295544 -64.575436)
		(end 310.336946 -64.549528)
		(stroke
			(width 0.05715)
			(type default)
		)
		(layer "In4.Cu")
	)
	(gr_line
		(start 310.318912 -68.965064)
		(end 310.337454 -68.92036)
		(stroke
			(width 0.05715)
			(type default)
		)
		(layer "In4.Cu")
	)
	(gr_line
		(start 310.319166 -68.964556)
		(end 310.319166 -68.96481)
		(stroke
			(width 0.05715)
			(type default)
		)
		(layer "In4.Cu")
	)
	(gr_line
		(start 310.329326 -68.873116)
		(end 310.337454 -68.92036)
		(stroke
			(width 0.05715)
			(type default)
		)
		(layer "In4.Cu")
	)
	(gr_line
		(start 310.431688 -63.72987)
		(end 310.453786 -63.708026)
		(stroke
			(width 0.05715)
			(type default)
		)
		(layer "In4.Cu")
	)
	(gr_line
		(start 310.453786 -63.708026)
		(end 310.463438 -63.67907)
		(stroke
			(width 0.05715)
			(type default)
		)
		(layer "In4.Cu")
	)
	(gr_line
		(start 310.45658 -86.381082)
		(end 310.480964 -86.36508)
		(stroke
			(width 0.05715)
			(type default)
		)
		(layer "In4.Cu")
	)
	(gr_line
		(start 310.480964 -86.36508)
		(end 310.49595 -86.340696)
		(stroke
			(width 0.05715)
			(type default)
		)
		(layer "In4.Cu")
	)
	(gr_line
		(start 310.701944 -54.35092)
		(end 310.72582 -54.37632)
		(stroke
			(width 0.05715)
			(type default)
		)
		(layer "In4.Cu")
	)
	(gr_line
		(start 310.71312 -75.756516)
		(end 310.717184 -75.751436)
		(stroke
			(width 0.05715)
			(type default)
		)
		(layer "In4.Cu")
	)
	(gr_line
		(start 310.717184 -75.751436)
		(end 310.719724 -75.745594)
		(stroke
			(width 0.05715)
			(type default)
		)
		(layer "In4.Cu")
	)
	(gr_line
		(start 310.72582 -54.37632)
		(end 310.735472 -54.410102)
		(stroke
			(width 0.05715)
			(type default)
		)
		(layer "In4.Cu")
	)
	(gr_line
		(start 310.736996 -88.140032)
		(end 310.757062 -88.13165)
		(stroke
			(width 0.05715)
			(type default)
		)
		(layer "In4.Cu")
	)
	(gr_line
		(start 310.896254 -85.132672)
		(end 310.899048 -85.1281)
		(stroke
			(width 0.05715)
			(type default)
		)
		(layer "In4.Cu")
	)
	(gr_line
		(start 310.899048 -85.1281)
		(end 310.903366 -85.124036)
		(stroke
			(width 0.05715)
			(type default)
		)
		(layer "In4.Cu")
	)
	(gr_line
		(start 311.03189 -64.460882)
		(end 311.079134 -64.431418)
		(stroke
			(width 0.05715)
			(type default)
		)
		(layer "In4.Cu")
	)
	(gr_line
		(start 311.079134 -64.431418)
		(end 311.10047 -64.380872)
		(stroke
			(width 0.05715)
			(type default)
		)
		(layer "In4.Cu")
	)
	(gr_line
		(start 311.229756 -76.20127)
		(end 311.23382 -76.19619)
		(stroke
			(width 0.05715)
			(type default)
		)
		(layer "In4.Cu")
	)
	(gr_line
		(start 311.23382 -76.19619)
		(end 311.23636 -76.190348)
		(stroke
			(width 0.05715)
			(type default)
		)
		(layer "In4.Cu")
	)
	(gr_line
		(start 311.36717 -61.016896)
		(end 311.367424 -61.016388)
		(stroke
			(width 0.05715)
			(type default)
		)
		(layer "In4.Cu")
	)
	(gr_line
		(start 311.367424 -61.016134)
		(end 311.380632 -60.977272)
		(stroke
			(width 0.05715)
			(type default)
		)
		(layer "In4.Cu")
	)
	(gr_line
		(start 311.372504 -60.936632)
		(end 311.380632 -60.977272)
		(stroke
			(width 0.05715)
			(type default)
		)
		(layer "In4.Cu")
	)
	(gr_line
		(start 311.662826 -76.856082)
		(end 311.66689 -76.851002)
		(stroke
			(width 0.05715)
			(type default)
		)
		(layer "In4.Cu")
	)
	(gr_line
		(start 311.66689 -76.851002)
		(end 311.66943 -76.84516)
		(stroke
			(width 0.05715)
			(type default)
		)
		(layer "In4.Cu")
	)
	(gr_line
		(start 312.036206 -62.166246)
		(end 312.039 -62.16015)
		(stroke
			(width 0.05715)
			(type default)
		)
		(layer "In4.Cu")
	)
	(gr_line
		(start 312.039 -62.16015)
		(end 312.039762 -62.15253)
		(stroke
			(width 0.05715)
			(type default)
		)
		(layer "In4.Cu")
	)
	(gr_line
		(start 312.103008 -77.466952)
		(end 312.107072 -77.461872)
		(stroke
			(width 0.05715)
			(type default)
		)
		(layer "In4.Cu")
	)
	(gr_line
		(start 312.107072 -77.461872)
		(end 312.109612 -77.45603)
		(stroke
			(width 0.05715)
			(type default)
		)
		(layer "In4.Cu")
	)
	(gr_line
		(start 312.25744 -59.761628)
		(end 312.262266 -59.7789)
		(stroke
			(width 0.05715)
			(type default)
		)
		(layer "In4.Cu")
	)
	(gr_line
		(start 312.260488 -59.79668)
		(end 312.262266 -59.7789)
		(stroke
			(width 0.05715)
			(type default)
		)
		(layer "In4.Cu")
	)
	(gr_line
		(start 312.469022 -52.652168)
		(end 312.478166 -52.704238)
		(stroke
			(width 0.05715)
			(type default)
		)
		(layer "In4.Cu")
	)
	(gr_line
		(start 312.469022 -52.652168)
		(end 312.490358 -52.60467)
		(stroke
			(width 0.05715)
			(type default)
		)
		(layer "In4.Cu")
	)
	(gr_line
		(start 312.478166 -52.703984)
		(end 312.47842 -52.704746)
		(stroke
			(width 0.05715)
			(type default)
		)
		(layer "In4.Cu")
	)
	(gr_line
		(start 312.485278 -54.969664)
		(end 312.490866 -54.941978)
		(stroke
			(width 0.05715)
			(type default)
		)
		(layer "In4.Cu")
	)
	(gr_line
		(start 312.485278 -54.969664)
		(end 312.492136 -54.99735)
		(stroke
			(width 0.05715)
			(type default)
		)
		(layer "In4.Cu")
	)
	(gr_line
		(start 312.492136 -54.997096)
		(end 312.492136 -54.99735)
		(stroke
			(width 0.05715)
			(type default)
		)
		(layer "In4.Cu")
	)
	(gr_line
		(start 312.505598 -56.373776)
		(end 312.508138 -56.392572)
		(stroke
			(width 0.05715)
			(type default)
		)
		(layer "In4.Cu")
	)
	(gr_line
		(start 312.505598 -56.373776)
		(end 312.51017 -56.355488)
		(stroke
			(width 0.05715)
			(type default)
		)
		(layer "In4.Cu")
	)
	(gr_line
		(start 312.554366 -78.066138)
		(end 312.55843 -78.061058)
		(stroke
			(width 0.05715)
			(type default)
		)
		(layer "In4.Cu")
	)
	(gr_line
		(start 312.55843 -78.061058)
		(end 312.56097 -78.055216)
		(stroke
			(width 0.05715)
			(type default)
		)
		(layer "In4.Cu")
	)
	(gr_line
		(start 312.964576 -55.748936)
		(end 312.973212 -55.715154)
		(stroke
			(width 0.05715)
			(type default)
		)
		(layer "In4.Cu")
	)
	(gr_line
		(start 312.964576 -55.681372)
		(end 312.973212 -55.715154)
		(stroke
			(width 0.05715)
			(type default)
		)
		(layer "In4.Cu")
	)
	(gr_line
		(start 312.988706 -53.937154)
		(end 312.992262 -53.919374)
		(stroke
			(width 0.05715)
			(type default)
		)
		(layer "In4.Cu")
	)
	(gr_line
		(start 312.989214 -53.90261)
		(end 312.992262 -53.919374)
		(stroke
			(width 0.05715)
			(type default)
		)
		(layer "In4.Cu")
	)
	(gr_line
		(start 313.011312 -65.024762)
		(end 313.013344 -65.019936)
		(stroke
			(width 0.05715)
			(type default)
		)
		(layer "In4.Cu")
	)
	(gr_line
		(start 313.013344 -65.019936)
		(end 313.013852 -65.014348)
		(stroke
			(width 0.05715)
			(type default)
		)
		(layer "In4.Cu")
	)
	(gr_line
		(start 313.025028 -78.623668)
		(end 313.029092 -78.618588)
		(stroke
			(width 0.05715)
			(type default)
		)
		(layer "In4.Cu")
	)
	(gr_line
		(start 313.029092 -78.618588)
		(end 313.031632 -78.612746)
		(stroke
			(width 0.05715)
			(type default)
		)
		(layer "In4.Cu")
	)
	(gr_line
		(start 313.135264 -52.755038)
		(end 313.144662 -52.807616)
		(stroke
			(width 0.05715)
			(type default)
		)
		(layer "In4.Cu")
	)
	(gr_line
		(start 313.135264 -52.755038)
		(end 313.1566 -52.70754)
		(stroke
			(width 0.05715)
			(type default)
		)
		(layer "In4.Cu")
	)
	(gr_line
		(start 313.140598 -54.94401)
		(end 313.146186 -54.916324)
		(stroke
			(width 0.05715)
			(type default)
		)
		(layer "In4.Cu")
	)
	(gr_line
		(start 313.140598 -54.94401)
		(end 313.147456 -54.971696)
		(stroke
			(width 0.05715)
			(type default)
		)
		(layer "In4.Cu")
	)
	(gr_line
		(start 313.19089 -56.35752)
		(end 313.193684 -56.377078)
		(stroke
			(width 0.05715)
			(type default)
		)
		(layer "In4.Cu")
	)
	(gr_line
		(start 313.19089 -56.35752)
		(end 313.195462 -56.339232)
		(stroke
			(width 0.05715)
			(type default)
		)
		(layer "In4.Cu")
	)
	(gr_line
		(start 313.193684 -56.376824)
		(end 313.193684 -56.377078)
		(stroke
			(width 0.05715)
			(type default)
		)
		(layer "In4.Cu")
	)
	(gr_line
		(start 313.509152 -79.120746)
		(end 313.513216 -79.115666)
		(stroke
			(width 0.05715)
			(type default)
		)
		(layer "In4.Cu")
	)
	(gr_line
		(start 313.513216 -79.115666)
		(end 313.515756 -79.109824)
		(stroke
			(width 0.05715)
			(type default)
		)
		(layer "In4.Cu")
	)
	(gr_line
		(start 313.635898 -55.785512)
		(end 313.644534 -55.751222)
		(stroke
			(width 0.05715)
			(type default)
		)
		(layer "In4.Cu")
	)
	(gr_line
		(start 313.635898 -55.717186)
		(end 313.644534 -55.751222)
		(stroke
			(width 0.05715)
			(type default)
		)
		(layer "In4.Cu")
	)
	(gr_line
		(start 313.637168 -53.942996)
		(end 313.640724 -53.92547)
		(stroke
			(width 0.05715)
			(type default)
		)
		(layer "In4.Cu")
	)
	(gr_line
		(start 313.637676 -53.908706)
		(end 313.640724 -53.92547)
		(stroke
			(width 0.05715)
			(type default)
		)
		(layer "In4.Cu")
	)
	(gr_line
		(start 313.691016 -65.044066)
		(end 313.693302 -65.038986)
		(stroke
			(width 0.05715)
			(type default)
		)
		(layer "In4.Cu")
	)
	(gr_line
		(start 313.693302 -65.038986)
		(end 313.69381 -65.033398)
		(stroke
			(width 0.05715)
			(type default)
		)
		(layer "In4.Cu")
	)
	(gr_line
		(start 313.79668 -54.913022)
		(end 313.802268 -54.885844)
		(stroke
			(width 0.05715)
			(type default)
		)
		(layer "In4.Cu")
	)
	(gr_line
		(start 313.79668 -54.913022)
		(end 313.803538 -54.9402)
		(stroke
			(width 0.05715)
			(type default)
		)
		(layer "In4.Cu")
	)
	(gr_line
		(start 313.798204 -52.840382)
		(end 313.807602 -52.89296)
		(stroke
			(width 0.05715)
			(type default)
		)
		(layer "In4.Cu")
	)
	(gr_line
		(start 313.798204 -52.840382)
		(end 313.81954 -52.792884)
		(stroke
			(width 0.05715)
			(type default)
		)
		(layer "In4.Cu")
	)
	(gr_line
		(start 313.803538 -54.940454)
		(end 313.803538 -54.940962)
		(stroke
			(width 0.05715)
			(type default)
		)
		(layer "In4.Cu")
	)
	(gr_line
		(start 313.84875 -56.372252)
		(end 313.852306 -56.39435)
		(stroke
			(width 0.05715)
			(type default)
		)
		(layer "In4.Cu")
	)
	(gr_line
		(start 313.84875 -56.372252)
		(end 313.854084 -56.350916)
		(stroke
			(width 0.05715)
			(type default)
		)
		(layer "In4.Cu")
	)
	(gr_line
		(start 313.873896 -49.518316)
		(end 313.887104 -49.489106)
		(stroke
			(width 0.05715)
			(type default)
		)
		(layer "In4.Cu")
	)
	(gr_line
		(start 313.887104 -49.489106)
		(end 313.911996 -49.46904)
		(stroke
			(width 0.05715)
			(type default)
		)
		(layer "In4.Cu")
	)
	(gr_line
		(start 314.0202 -79.559912)
		(end 314.024264 -79.554832)
		(stroke
			(width 0.05715)
			(type default)
		)
		(layer "In4.Cu")
	)
	(gr_line
		(start 314.024264 -79.554832)
		(end 314.026804 -79.54899)
		(stroke
			(width 0.05715)
			(type default)
		)
		(layer "In4.Cu")
	)
	(gr_line
		(start 314.103004 -60.570364)
		(end 314.110116 -60.592208)
		(stroke
			(width 0.05715)
			(type default)
		)
		(layer "In4.Cu")
	)
	(gr_line
		(start 314.10783 -60.616084)
		(end 314.110116 -60.592208)
		(stroke
			(width 0.05715)
			(type default)
		)
		(layer "In4.Cu")
	)
	(gr_line
		(start 314.286392 -53.950108)
		(end 314.289948 -53.932328)
		(stroke
			(width 0.05715)
			(type default)
		)
		(layer "In4.Cu")
	)
	(gr_line
		(start 314.2869 -53.914548)
		(end 314.289948 -53.932328)
		(stroke
			(width 0.05715)
			(type default)
		)
		(layer "In4.Cu")
	)
	(gr_line
		(start 314.291726 -65.446148)
		(end 314.293758 -65.441322)
		(stroke
			(width 0.05715)
			(type default)
		)
		(layer "In4.Cu")
	)
	(gr_line
		(start 314.293758 -65.441322)
		(end 314.294266 -65.435734)
		(stroke
			(width 0.05715)
			(type default)
		)
		(layer "In4.Cu")
	)
	(gr_line
		(start 314.299092 -55.78221)
		(end 314.308236 -55.746142)
		(stroke
			(width 0.05715)
			(type default)
		)
		(layer "In4.Cu")
	)
	(gr_line
		(start 314.299346 -55.710582)
		(end 314.308236 -55.746142)
		(stroke
			(width 0.05715)
			(type default)
		)
		(layer "In4.Cu")
	)
	(gr_line
		(start 314.319666 -50.112676)
		(end 314.332874 -50.083466)
		(stroke
			(width 0.05715)
			(type default)
		)
		(layer "In4.Cu")
	)
	(gr_line
		(start 314.332874 -50.083466)
		(end 314.357766 -50.0634)
		(stroke
			(width 0.05715)
			(type default)
		)
		(layer "In4.Cu")
	)
	(gr_line
		(start 314.534296 -79.995522)
		(end 314.538868 -79.989934)
		(stroke
			(width 0.05715)
			(type default)
		)
		(layer "In4.Cu")
	)
	(gr_line
		(start 314.538868 -79.989934)
		(end 314.541662 -79.98333)
		(stroke
			(width 0.05715)
			(type default)
		)
		(layer "In4.Cu")
	)
	(gr_line
		(start 314.679584 -46.176438)
		(end 314.70727 -46.154086)
		(stroke
			(width 0.05715)
			(type default)
		)
		(layer "In4.Cu")
	)
	(gr_line
		(start 314.70727 -46.154086)
		(end 314.74156 -46.147736)
		(stroke
			(width 0.05715)
			(type default)
		)
		(layer "In4.Cu")
	)
	(gr_line
		(start 314.776612 -50.658268)
		(end 314.78982 -50.629058)
		(stroke
			(width 0.05715)
			(type default)
		)
		(layer "In4.Cu")
	)
	(gr_line
		(start 314.78982 -50.629058)
		(end 314.814712 -50.608992)
		(stroke
			(width 0.05715)
			(type default)
		)
		(layer "In4.Cu")
	)
	(gr_line
		(start 314.831222 -64.62268)
		(end 314.919614 -64.836294)
		(stroke
			(width 0.05715)
			(type default)
		)
		(layer "In4.Cu")
	)
	(gr_line
		(start 314.831222 -64.62268)
		(end 314.96254 -64.305942)
		(stroke
			(width 0.05715)
			(type default)
		)
		(layer "In4.Cu")
	)
	(gr_line
		(start 314.914788 -46.80458)
		(end 314.942728 -46.782228)
		(stroke
			(width 0.05715)
			(type default)
		)
		(layer "In4.Cu")
	)
	(gr_line
		(start 314.942728 -46.782228)
		(end 314.978034 -46.77537)
		(stroke
			(width 0.05715)
			(type default)
		)
		(layer "In4.Cu")
	)
	(gr_line
		(start 314.96254 -64.305942)
		(end 315.176154 -64.217296)
		(stroke
			(width 0.05715)
			(type default)
		)
		(layer "In4.Cu")
	)
	(gr_line
		(start 315.096398 -80.344772)
		(end 315.099446 -80.340962)
		(stroke
			(width 0.05715)
			(type default)
		)
		(layer "In4.Cu")
	)
	(gr_line
		(start 315.099446 -80.340962)
		(end 315.101732 -80.335882)
		(stroke
			(width 0.05715)
			(type default)
		)
		(layer "In4.Cu")
	)
	(gr_line
		(start 315.203332 -64.921638)
		(end 315.434472 -64.3636)
		(stroke
			(width 0.05715)
			(type default)
		)
		(layer "In4.Cu")
	)
	(gr_line
		(start 315.698378 -80.614774)
		(end 315.701426 -80.610964)
		(stroke
			(width 0.05715)
			(type default)
		)
		(layer "In4.Cu")
	)
	(gr_line
		(start 315.701426 -80.610964)
		(end 315.703712 -80.605884)
		(stroke
			(width 0.05715)
			(type default)
		)
		(layer "In4.Cu")
	)
	(gr_line
		(start 316.015624 -81.958688)
		(end 316.024006 -81.938622)
		(stroke
			(width 0.05715)
			(type default)
		)
		(layer "In4.Cu")
	)
	(gr_line
		(start 316.545976 -82.342736)
		(end 316.554358 -82.32267)
		(stroke
			(width 0.05715)
			(type default)
		)
		(layer "In4.Cu")
	)
	(gr_line
		(start 316.872874 -47.0789)
		(end 316.89929 -47.05731)
		(stroke
			(width 0.05715)
			(type default)
		)
		(layer "In4.Cu")
	)
	(gr_line
		(start 316.89929 -47.05731)
		(end 316.93358 -47.050706)
		(stroke
			(width 0.05715)
			(type default)
		)
		(layer "In4.Cu")
	)
	(gr_line
		(start 317.111634 -82.691478)
		(end 317.120016 -82.671412)
		(stroke
			(width 0.05715)
			(type default)
		)
		(layer "In4.Cu")
	)
	(gr_line
		(start 317.364364 -47.637192)
		(end 317.39205 -47.61484)
		(stroke
			(width 0.05715)
			(type default)
		)
		(layer "In4.Cu")
	)
	(gr_line
		(start 317.39205 -47.61484)
		(end 317.42634 -47.60849)
		(stroke
			(width 0.05715)
			(type default)
		)
		(layer "In4.Cu")
	)
	(gr_line
		(start 317.709042 -83.00847)
		(end 317.717424 -82.988404)
		(stroke
			(width 0.05715)
			(type default)
		)
		(layer "In4.Cu")
	)
	(gr_line
		(start 317.78829 -48.208184)
		(end 317.816738 -48.185324)
		(stroke
			(width 0.05715)
			(type default)
		)
		(layer "In4.Cu")
	)
	(gr_line
		(start 317.816738 -48.185324)
		(end 317.852298 -48.178466)
		(stroke
			(width 0.05715)
			(type default)
		)
		(layer "In4.Cu")
	)
	(gr_line
		(start 318.259968 -83.364832)
		(end 318.26835 -83.344766)
		(stroke
			(width 0.05715)
			(type default)
		)
		(layer "In4.Cu")
	)
	(gr_line
		(start 318.79794 -83.741768)
		(end 318.813434 -83.726274)
		(stroke
			(width 0.05715)
			(type default)
		)
		(layer "In4.Cu")
	)
	(gr_line
		(start 318.813434 -83.726274)
		(end 318.821816 -83.706208)
		(stroke
			(width 0.05715)
			(type default)
		)
		(layer "In4.Cu")
	)
	(gr_line
		(start 319.362836 -84.09813)
		(end 319.37833 -84.082636)
		(stroke
			(width 0.05715)
			(type default)
		)
		(layer "In4.Cu")
	)
	(gr_line
		(start 319.37833 -84.082636)
		(end 319.378838 -84.08162)
		(stroke
			(width 0.05715)
			(type default)
		)
		(layer "In4.Cu")
	)
	(gr_line
		(start 319.378838 -84.08162)
		(end 319.386712 -84.062316)
		(stroke
			(width 0.05715)
			(type default)
		)
		(layer "In4.Cu")
	)
	(gr_line
		(start 319.927732 -84.440522)
		(end 319.943226 -84.425028)
		(stroke
			(width 0.05715)
			(type default)
		)
		(layer "In4.Cu")
	)
	(gr_line
		(start 319.943226 -84.425028)
		(end 319.951608 -84.404962)
		(stroke
			(width 0.05715)
			(type default)
		)
		(layer "In4.Cu")
	)
	(gr_line
		(start 319.973198 -45.146214)
		(end 319.977262 -45.145452)
		(stroke
			(width 0.05715)
			(type default)
		)
		(layer "In4.Cu")
	)
	(gr_line
		(start 319.977262 -45.145452)
		(end 319.980818 -45.14596)
		(stroke
			(width 0.05715)
			(type default)
		)
		(layer "In4.Cu")
	)
	(gr_line
		(start 320.016886 -46.461934)
		(end 320.022474 -46.460918)
		(stroke
			(width 0.05715)
			(type default)
		)
		(layer "In4.Cu")
	)
	(gr_line
		(start 320.022474 -46.460918)
		(end 320.028316 -46.461426)
		(stroke
			(width 0.05715)
			(type default)
		)
		(layer "In4.Cu")
	)
	(gr_line
		(start 320.043048 -45.802296)
		(end 320.04889 -45.80128)
		(stroke
			(width 0.05715)
			(type default)
		)
		(layer "In4.Cu")
	)
	(gr_line
		(start 320.04889 -45.80128)
		(end 320.054732 -45.801788)
		(stroke
			(width 0.05715)
			(type default)
		)
		(layer "In4.Cu")
	)
	(gr_line
		(start 320.052446 -47.105824)
		(end 320.058034 -47.104808)
		(stroke
			(width 0.05715)
			(type default)
		)
		(layer "In4.Cu")
	)
	(gr_line
		(start 320.058034 -47.104808)
		(end 320.063876 -47.105316)
		(stroke
			(width 0.05715)
			(type default)
		)
		(layer "In4.Cu")
	)
	(gr_line
		(start 320.073274 -47.75327)
		(end 320.079116 -47.752254)
		(stroke
			(width 0.05715)
			(type default)
		)
		(layer "In4.Cu")
	)
	(gr_line
		(start 320.079116 -47.752254)
		(end 320.084958 -47.752762)
		(stroke
			(width 0.05715)
			(type default)
		)
		(layer "In4.Cu")
	)
	(gr_line
		(start 320.641472 -84.844382)
		(end 320.649854 -84.824316)
		(stroke
			(width 0.05715)
			(type default)
		)
		(layer "In4.Cu")
	)
	(gr_line
		(start 321.198748 -85.201506)
		(end 321.20713 -85.18144)
		(stroke
			(width 0.05715)
			(type default)
		)
		(layer "In4.Cu")
	)
	(gr_line
		(start 321.749166 -85.571838)
		(end 321.757548 -85.551772)
		(stroke
			(width 0.05715)
			(type default)
		)
		(layer "In4.Cu")
	)
	(gr_line
		(start 322.180966 -86.181438)
		(end 322.19646 -86.165944)
		(stroke
			(width 0.05715)
			(type default)
		)
		(layer "In4.Cu")
	)
	(gr_line
		(start 322.19646 -86.165944)
		(end 322.204842 -86.145878)
		(stroke
			(width 0.05715)
			(type default)
		)
		(layer "In4.Cu")
	)
	(gr_line
		(start 322.596002 -52.685442)
		(end 322.624704 -52.643786)
		(stroke
			(width 0.05715)
			(type default)
		)
		(layer "In4.Cu")
	)
	(gr_line
		(start 322.624704 -52.643786)
		(end 322.670932 -52.62499)
		(stroke
			(width 0.05715)
			(type default)
		)
		(layer "In4.Cu")
	)
	(gr_line
		(start 322.749418 -86.511384)
		(end 322.758816 -86.489032)
		(stroke
			(width 0.05715)
			(type default)
		)
		(layer "In4.Cu")
	)
	(gr_line
		(start 323.013832 -53.20284)
		(end 323.042534 -53.161184)
		(stroke
			(width 0.05715)
			(type default)
		)
		(layer "In4.Cu")
	)
	(gr_line
		(start 323.042534 -53.161184)
		(end 323.043296 -53.160676)
		(stroke
			(width 0.05715)
			(type default)
		)
		(layer "In4.Cu")
	)
	(gr_line
		(start 323.043296 -53.160676)
		(end 323.09054 -53.141626)
		(stroke
			(width 0.05715)
			(type default)
		)
		(layer "In4.Cu")
	)
	(gr_line
		(start 323.282564 -86.929976)
		(end 323.290438 -86.91118)
		(stroke
			(width 0.05715)
			(type default)
		)
		(layer "In4.Cu")
	)
	(gr_line
		(start 323.43344 -53.717952)
		(end 323.462142 -53.676296)
		(stroke
			(width 0.05715)
			(type default)
		)
		(layer "In4.Cu")
	)
	(gr_line
		(start 323.462142 -53.676296)
		(end 323.508878 -53.657246)
		(stroke
			(width 0.05715)
			(type default)
		)
		(layer "In4.Cu")
	)
	(gr_line
		(start 323.666358 -52.53482)
		(end 323.711824 -52.516278)
		(stroke
			(width 0.05715)
			(type default)
		)
		(layer "In4.Cu")
	)
	(gr_line
		(start 323.711824 -52.516278)
		(end 323.739256 -52.476146)
		(stroke
			(width 0.05715)
			(type default)
		)
		(layer "In4.Cu")
	)
	(gr_line
		(start 323.792342 -87.36076)
		(end 323.807582 -87.34552)
		(stroke
			(width 0.05715)
			(type default)
		)
		(layer "In4.Cu")
	)
	(gr_line
		(start 323.807582 -87.34552)
		(end 323.81571 -87.325962)
		(stroke
			(width 0.05715)
			(type default)
		)
		(layer "In4.Cu")
	)
	(gr_line
		(start 323.853302 -54.232556)
		(end 323.881242 -54.19217)
		(stroke
			(width 0.05715)
			(type default)
		)
		(layer "In4.Cu")
	)
	(gr_line
		(start 323.881242 -54.19217)
		(end 323.882004 -54.191662)
		(stroke
			(width 0.05715)
			(type default)
		)
		(layer "In4.Cu")
	)
	(gr_line
		(start 323.882004 -54.191662)
		(end 323.927978 -54.172866)
		(stroke
			(width 0.05715)
			(type default)
		)
		(layer "In4.Cu")
	)
	(gr_line
		(start 324.099936 -53.046122)
		(end 324.146164 -53.027326)
		(stroke
			(width 0.05715)
			(type default)
		)
		(layer "In4.Cu")
	)
	(gr_line
		(start 324.146164 -53.027326)
		(end 324.17385 -52.986686)
		(stroke
			(width 0.05715)
			(type default)
		)
		(layer "In4.Cu")
	)
	(gr_line
		(start 324.27291 -54.747668)
		(end 324.30085 -54.707282)
		(stroke
			(width 0.05715)
			(type default)
		)
		(layer "In4.Cu")
	)
	(gr_line
		(start 324.30085 -54.707282)
		(end 324.301358 -54.707028)
		(stroke
			(width 0.05715)
			(type default)
		)
		(layer "In4.Cu")
	)
	(gr_line
		(start 324.301358 -54.706774)
		(end 324.301358 -54.707028)
		(stroke
			(width 0.05715)
			(type default)
		)
		(layer "In4.Cu")
	)
	(gr_line
		(start 324.301358 -54.706774)
		(end 324.348094 -54.687724)
		(stroke
			(width 0.05715)
			(type default)
		)
		(layer "In4.Cu")
	)
	(gr_line
		(start 324.343268 -87.7316)
		(end 324.35673 -87.718138)
		(stroke
			(width 0.05715)
			(type default)
		)
		(layer "In4.Cu")
	)
	(gr_line
		(start 324.35673 -87.718138)
		(end 324.36435 -87.700358)
		(stroke
			(width 0.05715)
			(type default)
		)
		(layer "In4.Cu")
	)
	(gr_line
		(start 324.537578 -53.553868)
		(end 324.58279 -53.535326)
		(stroke
			(width 0.05715)
			(type default)
		)
		(layer "In4.Cu")
	)
	(gr_line
		(start 324.58279 -53.535326)
		(end 324.61073 -53.49494)
		(stroke
			(width 0.05715)
			(type default)
		)
		(layer "In4.Cu")
	)
	(gr_line
		(start 324.692264 -55.262526)
		(end 324.720204 -55.22214)
		(stroke
			(width 0.05715)
			(type default)
		)
		(layer "In4.Cu")
	)
	(gr_line
		(start 324.720204 -55.22214)
		(end 324.720712 -55.221886)
		(stroke
			(width 0.05715)
			(type default)
		)
		(layer "In4.Cu")
	)
	(gr_line
		(start 324.720712 -55.221886)
		(end 324.765924 -55.203344)
		(stroke
			(width 0.05715)
			(type default)
		)
		(layer "In4.Cu")
	)
	(gr_line
		(start 324.729094 -45.894752)
		(end 324.750684 -45.897038)
		(stroke
			(width 0.05715)
			(type default)
		)
		(layer "In4.Cu")
	)
	(gr_line
		(start 324.750684 -45.897038)
		(end 324.772274 -45.89018)
		(stroke
			(width 0.05715)
			(type default)
		)
		(layer "In4.Cu")
	)
	(gr_line
		(start 324.791578 -50.428906)
		(end 324.803262 -50.411888)
		(stroke
			(width 0.05715)
			(type default)
		)
		(layer "In4.Cu")
	)
	(gr_line
		(start 324.803262 -50.411888)
		(end 324.820534 -50.400712)
		(stroke
			(width 0.05715)
			(type default)
		)
		(layer "In4.Cu")
	)
	(gr_line
		(start 324.8279 -46.587918)
		(end 324.851014 -46.590204)
		(stroke
			(width 0.05715)
			(type default)
		)
		(layer "In4.Cu")
	)
	(gr_line
		(start 324.851014 -46.590204)
		(end 324.873112 -46.583092)
		(stroke
			(width 0.05715)
			(type default)
		)
		(layer "In4.Cu")
	)
	(gr_line
		(start 324.856856 -47.250858)
		(end 324.87997 -47.253144)
		(stroke
			(width 0.05715)
			(type default)
		)
		(layer "In4.Cu")
	)
	(gr_line
		(start 324.87997 -47.253144)
		(end 324.902068 -47.246032)
		(stroke
			(width 0.05715)
			(type default)
		)
		(layer "In4.Cu")
	)
	(gr_line
		(start 324.933056 -47.898812)
		(end 324.95617 -47.901098)
		(stroke
			(width 0.05715)
			(type default)
		)
		(layer "In4.Cu")
	)
	(gr_line
		(start 324.95617 -47.901098)
		(end 324.978268 -47.893986)
		(stroke
			(width 0.05715)
			(type default)
		)
		(layer "In4.Cu")
	)
	(gr_line
		(start 324.974458 -54.061614)
		(end 325.019924 -54.043072)
		(stroke
			(width 0.05715)
			(type default)
		)
		(layer "In4.Cu")
	)
	(gr_line
		(start 325.002906 -48.550322)
		(end 325.02602 -48.552608)
		(stroke
			(width 0.05715)
			(type default)
		)
		(layer "In4.Cu")
	)
	(gr_line
		(start 325.019924 -54.043072)
		(end 325.047864 -54.002686)
		(stroke
			(width 0.05715)
			(type default)
		)
		(layer "In4.Cu")
	)
	(gr_line
		(start 325.02602 -48.552608)
		(end 325.048118 -48.545496)
		(stroke
			(width 0.05715)
			(type default)
		)
		(layer "In4.Cu")
	)
	(gr_line
		(start 325.111618 -55.777638)
		(end 325.139558 -55.737252)
		(stroke
			(width 0.05715)
			(type default)
		)
		(layer "In4.Cu")
	)
	(gr_line
		(start 325.139558 -55.737252)
		(end 325.185024 -55.71871)
		(stroke
			(width 0.05715)
			(type default)
		)
		(layer "In4.Cu")
	)
	(gr_line
		(start 325.26478 -50.884328)
		(end 325.276464 -50.86731)
		(stroke
			(width 0.05715)
			(type default)
		)
		(layer "In4.Cu")
	)
	(gr_line
		(start 325.276464 -50.86731)
		(end 325.292974 -50.856642)
		(stroke
			(width 0.05715)
			(type default)
		)
		(layer "In4.Cu")
	)
	(gr_line
		(start 325.395082 -54.576218)
		(end 325.440548 -54.557676)
		(stroke
			(width 0.05715)
			(type default)
		)
		(layer "In4.Cu")
	)
	(gr_line
		(start 325.440548 -54.557676)
		(end 325.468488 -54.51729)
		(stroke
			(width 0.05715)
			(type default)
		)
		(layer "In4.Cu")
	)
	(gr_line
		(start 325.531734 -56.292242)
		(end 325.559674 -56.251856)
		(stroke
			(width 0.05715)
			(type default)
		)
		(layer "In4.Cu")
	)
	(gr_line
		(start 325.559674 -56.251856)
		(end 325.60514 -56.233314)
		(stroke
			(width 0.05715)
			(type default)
		)
		(layer "In4.Cu")
	)
	(gr_line
		(start 325.735442 -51.342798)
		(end 325.747126 -51.32578)
		(stroke
			(width 0.05715)
			(type default)
		)
		(layer "In4.Cu")
	)
	(gr_line
		(start 325.747126 -51.32578)
		(end 325.763636 -51.315112)
		(stroke
			(width 0.05715)
			(type default)
		)
		(layer "In4.Cu")
	)
	(gr_line
		(start 325.827136 -55.085996)
		(end 325.872602 -55.067454)
		(stroke
			(width 0.05715)
			(type default)
		)
		(layer "In4.Cu")
	)
	(gr_line
		(start 325.872602 -55.067454)
		(end 325.900542 -55.027068)
		(stroke
			(width 0.05715)
			(type default)
		)
		(layer "In4.Cu")
	)
	(gr_line
		(start 326.208644 -51.79822)
		(end 326.220582 -51.780694)
		(stroke
			(width 0.05715)
			(type default)
		)
		(layer "In4.Cu")
	)
	(gr_line
		(start 326.220582 -51.780694)
		(end 326.23887 -51.768756)
		(stroke
			(width 0.05715)
			(type default)
		)
		(layer "In4.Cu")
	)
	(gr_line
		(start 326.256904 -55.59679)
		(end 326.30237 -55.578248)
		(stroke
			(width 0.05715)
			(type default)
		)
		(layer "In4.Cu")
	)
	(gr_line
		(start 326.30237 -55.578248)
		(end 326.33031 -55.537862)
		(stroke
			(width 0.05715)
			(type default)
		)
		(layer "In4.Cu")
	)
	(gr_line
		(start 326.659494 -52.269644)
		(end 326.671178 -52.252626)
		(stroke
			(width 0.05715)
			(type default)
		)
		(layer "In4.Cu")
	)
	(gr_line
		(start 326.671178 -52.252626)
		(end 326.687688 -52.241958)
		(stroke
			(width 0.05715)
			(type default)
		)
		(layer "In4.Cu")
	)
	(gr_line
		(start 326.68845 -56.106822)
		(end 326.733916 -56.08828)
		(stroke
			(width 0.05715)
			(type default)
		)
		(layer "In4.Cu")
	)
	(gr_line
		(start 326.733916 -56.08828)
		(end 326.761856 -56.047894)
		(stroke
			(width 0.05715)
			(type default)
		)
		(layer "In4.Cu")
	)
	(gr_line
		(start 327.126092 -52.728622)
		(end 327.137776 -52.711604)
		(stroke
			(width 0.05715)
			(type default)
		)
		(layer "In4.Cu")
	)
	(gr_line
		(start 327.137776 -52.711604)
		(end 327.154286 -52.700936)
		(stroke
			(width 0.05715)
			(type default)
		)
		(layer "In4.Cu")
	)
	(gr_line
		(start 327.58761 -53.194204)
		(end 327.599294 -53.177186)
		(stroke
			(width 0.05715)
			(type default)
		)
		(layer "In4.Cu")
	)
	(gr_line
		(start 327.599294 -53.177186)
		(end 327.615804 -53.166518)
		(stroke
			(width 0.05715)
			(type default)
		)
		(layer "In4.Cu")
	)
	(gr_line
		(start 328.048112 -53.66131)
		(end 328.059796 -53.644292)
		(stroke
			(width 0.05715)
			(type default)
		)
		(layer "In4.Cu")
	)
	(gr_line
		(start 328.059796 -53.644292)
		(end 328.076306 -53.633624)
		(stroke
			(width 0.05715)
			(type default)
		)
		(layer "In4.Cu")
	)
	(gr_line
		(start 328.336402 -44.76115)
		(end 328.398632 -44.741592)
		(stroke
			(width 0.05715)
			(type default)
		)
		(layer "In4.Cu")
	)
	(gr_line
		(start 328.398632 -44.741592)
		(end 328.4347 -44.68749)
		(stroke
			(width 0.05715)
			(type default)
		)
		(layer "In4.Cu")
	)
	(gr_line
		(start 328.542142 -54.102762)
		(end 328.553826 -54.085744)
		(stroke
			(width 0.05715)
			(type default)
		)
		(layer "In4.Cu")
	)
	(gr_line
		(start 328.553826 -54.085744)
		(end 328.570336 -54.075076)
		(stroke
			(width 0.05715)
			(type default)
		)
		(layer "In4.Cu")
	)
	(gr_line
		(start 328.5744 4.318)
		(end 329.226164 3.666236)
		(stroke
			(width 0.0635)
			(type default)
		)
		(layer "In4.Cu")
	)
	(gr_line
		(start 328.629264 3.437382)
		(end 328.969624 3.097022)
		(stroke
			(width 0.0635)
			(type default)
		)
		(layer "In4.Cu")
	)
	(gr_line
		(start 328.939144 -54.647338)
		(end 328.950574 -54.63032)
		(stroke
			(width 0.05715)
			(type default)
		)
		(layer "In4.Cu")
	)
	(gr_line
		(start 328.950574 -54.63032)
		(end 328.968354 -54.618636)
		(stroke
			(width 0.05715)
			(type default)
		)
		(layer "In4.Cu")
	)
	(gr_line
		(start 329.105768 -47.627032)
		(end 329.107038 -47.62627)
		(stroke
			(width 0.05715)
			(type default)
		)
		(layer "In4.Cu")
	)
	(gr_line
		(start 329.107038 -47.62627)
		(end 329.108562 -47.625762)
		(stroke
			(width 0.05715)
			(type default)
		)
		(layer "In4.Cu")
	)
	(gr_line
		(start 329.226164 3.666236)
		(end 329.226164 3.351022)
		(stroke
			(width 0.0635)
			(type default)
		)
		(layer "In4.Cu")
	)
	(gr_line
		(start 329.347576 -55.178706)
		(end 329.359006 -55.161688)
		(stroke
			(width 0.05715)
			(type default)
		)
		(layer "In4.Cu")
	)
	(gr_line
		(start 329.359006 -55.161688)
		(end 329.376786 -55.150004)
		(stroke
			(width 0.05715)
			(type default)
		)
		(layer "In4.Cu")
	)
	(gr_line
		(start 329.374246 -48.212756)
		(end 329.376278 -48.211486)
		(stroke
			(width 0.05715)
			(type default)
		)
		(layer "In4.Cu")
	)
	(gr_line
		(start 329.376278 -48.211486)
		(end 329.378564 -48.210724)
		(stroke
			(width 0.05715)
			(type default)
		)
		(layer "In4.Cu")
	)
	(gr_line
		(start 329.657202 -48.792384)
		(end 329.659234 -48.791114)
		(stroke
			(width 0.05715)
			(type default)
		)
		(layer "In4.Cu")
	)
	(gr_line
		(start 329.659234 -48.791114)
		(end 329.661266 -48.790352)
		(stroke
			(width 0.05715)
			(type default)
		)
		(layer "In4.Cu")
	)
	(gr_line
		(start 329.936602 -49.377092)
		(end 329.939396 -49.375314)
		(stroke
			(width 0.05715)
			(type default)
		)
		(layer "In4.Cu")
	)
	(gr_line
		(start 329.939396 -49.375314)
		(end 329.942444 -49.374298)
		(stroke
			(width 0.05715)
			(type default)
		)
		(layer "In4.Cu")
	)
	(gr_line
		(start 329.97521 -69.051424)
		(end 329.98664 -69.034406)
		(stroke
			(width 0.05715)
			(type default)
		)
		(layer "In4.Cu")
	)
	(gr_line
		(start 329.98664 -69.034406)
		(end 330.00442 -69.022722)
		(stroke
			(width 0.05715)
			(type default)
		)
		(layer "In4.Cu")
	)
	(gr_line
		(start 330.117958 -41.635934)
		(end 330.13015 -41.617646)
		(stroke
			(width 0.05715)
			(type default)
		)
		(layer "In4.Cu")
	)
	(gr_line
		(start 330.13015 -41.617646)
		(end 330.148438 -41.605454)
		(stroke
			(width 0.05715)
			(type default)
		)
		(layer "In4.Cu")
	)
	(gr_line
		(start 330.220574 -49.953926)
		(end 330.221844 -49.953164)
		(stroke
			(width 0.05715)
			(type default)
		)
		(layer "In4.Cu")
	)
	(gr_line
		(start 330.221844 -49.953164)
		(end 330.223368 -49.952656)
		(stroke
			(width 0.05715)
			(type default)
		)
		(layer "In4.Cu")
	)
	(gr_line
		(start 330.391516 -69.567552)
		(end 330.402946 -69.550534)
		(stroke
			(width 0.05715)
			(type default)
		)
		(layer "In4.Cu")
	)
	(gr_line
		(start 330.402946 -69.550534)
		(end 330.420726 -69.53885)
		(stroke
			(width 0.05715)
			(type default)
		)
		(layer "In4.Cu")
	)
	(gr_line
		(start 330.468986 -50.554128)
		(end 330.471018 -50.552858)
		(stroke
			(width 0.05715)
			(type default)
		)
		(layer "In4.Cu")
	)
	(gr_line
		(start 330.471018 -50.552858)
		(end 330.473304 -50.552096)
		(stroke
			(width 0.05715)
			(type default)
		)
		(layer "In4.Cu")
	)
	(gr_line
		(start 330.648564 -51.201828)
		(end 330.651358 -51.20005)
		(stroke
			(width 0.05715)
			(type default)
		)
		(layer "In4.Cu")
	)
	(gr_line
		(start 330.651358 -51.20005)
		(end 330.654406 -51.199034)
		(stroke
			(width 0.05715)
			(type default)
		)
		(layer "In4.Cu")
	)
	(gr_line
		(start 330.825348 -70.058534)
		(end 330.836778 -70.041516)
		(stroke
			(width 0.05715)
			(type default)
		)
		(layer "In4.Cu")
	)
	(gr_line
		(start 330.830428 -55.186834)
		(end 330.840588 -55.171848)
		(stroke
			(width 0.05715)
			(type default)
		)
		(layer "In4.Cu")
	)
	(gr_line
		(start 330.836778 -70.041516)
		(end 330.854558 -70.029832)
		(stroke
			(width 0.05715)
			(type default)
		)
		(layer "In4.Cu")
	)
	(gr_line
		(start 330.840588 -55.171848)
		(end 330.855574 -55.161942)
		(stroke
			(width 0.05715)
			(type default)
		)
		(layer "In4.Cu")
	)
	(gr_line
		(start 330.929488 -51.785266)
		(end 330.932536 -51.783488)
		(stroke
			(width 0.05715)
			(type default)
		)
		(layer "In4.Cu")
	)
	(gr_line
		(start 330.932536 -51.783488)
		(end 330.935838 -51.782472)
		(stroke
			(width 0.05715)
			(type default)
		)
		(layer "In4.Cu")
	)
	(gr_line
		(start 330.981812 -62.848998)
		(end 330.993496 -62.83198)
		(stroke
			(width 0.05715)
			(type default)
		)
		(layer "In4.Cu")
	)
	(gr_line
		(start 330.993496 -62.83198)
		(end 331.010006 -62.821312)
		(stroke
			(width 0.05715)
			(type default)
		)
		(layer "In4.Cu")
	)
	(gr_line
		(start 331.197712 -52.372768)
		(end 331.200506 -52.37099)
		(stroke
			(width 0.05715)
			(type default)
		)
		(layer "In4.Cu")
	)
	(gr_line
		(start 331.200506 -52.37099)
		(end 331.203554 -52.369974)
		(stroke
			(width 0.05715)
			(type default)
		)
		(layer "In4.Cu")
	)
	(gr_line
		(start 331.234034 -55.720996)
		(end 331.244194 -55.70601)
		(stroke
			(width 0.05715)
			(type default)
		)
		(layer "In4.Cu")
	)
	(gr_line
		(start 331.234542 -70.585076)
		(end 331.245972 -70.568058)
		(stroke
			(width 0.05715)
			(type default)
		)
		(layer "In4.Cu")
	)
	(gr_line
		(start 331.244194 -55.70601)
		(end 331.25918 -55.696104)
		(stroke
			(width 0.05715)
			(type default)
		)
		(layer "In4.Cu")
	)
	(gr_line
		(start 331.245972 -70.568058)
		(end 331.263752 -70.556374)
		(stroke
			(width 0.05715)
			(type default)
		)
		(layer "In4.Cu")
	)
	(gr_line
		(start 331.351128 -40.803576)
		(end 331.368908 -40.791892)
		(stroke
			(width 0.05715)
			(type default)
		)
		(layer "In4.Cu")
	)
	(gr_line
		(start 331.368908 -40.791892)
		(end 331.388974 -40.788082)
		(stroke
			(width 0.05715)
			(type default)
		)
		(layer "In4.Cu")
	)
	(gr_line
		(start 331.463396 -52.977796)
		(end 331.46492 -52.97678)
		(stroke
			(width 0.05715)
			(type default)
		)
		(layer "In4.Cu")
	)
	(gr_line
		(start 331.46492 -52.97678)
		(end 331.466952 -52.976272)
		(stroke
			(width 0.05715)
			(type default)
		)
		(layer "In4.Cu")
	)
	(gr_line
		(start 331.5335 -63.465456)
		(end 331.545438 -63.44793)
		(stroke
			(width 0.05715)
			(type default)
		)
		(layer "In4.Cu")
	)
	(gr_line
		(start 331.545438 -63.44793)
		(end 331.56398 -63.435738)
		(stroke
			(width 0.05715)
			(type default)
		)
		(layer "In4.Cu")
	)
	(gr_line
		(start 331.677772 -71.062342)
		(end 331.689202 -71.045324)
		(stroke
			(width 0.05715)
			(type default)
		)
		(layer "In4.Cu")
	)
	(gr_line
		(start 331.689202 -71.045324)
		(end 331.706982 -71.03364)
		(stroke
			(width 0.05715)
			(type default)
		)
		(layer "In4.Cu")
	)
	(gr_line
		(start 331.711046 -56.183022)
		(end 331.720952 -56.168544)
		(stroke
			(width 0.05715)
			(type default)
		)
		(layer "In4.Cu")
	)
	(gr_line
		(start 331.720952 -56.168544)
		(end 331.736954 -56.157876)
		(stroke
			(width 0.05715)
			(type default)
		)
		(layer "In4.Cu")
	)
	(gr_line
		(start 331.735176 -53.597556)
		(end 331.7367 -53.59654)
		(stroke
			(width 0.05715)
			(type default)
		)
		(layer "In4.Cu")
	)
	(gr_line
		(start 331.7367 -53.59654)
		(end 331.738986 -53.595778)
		(stroke
			(width 0.05715)
			(type default)
		)
		(layer "In4.Cu")
	)
	(gr_line
		(start 331.94117 -44.345352)
		(end 331.945742 -44.343828)
		(stroke
			(width 0.05715)
			(type default)
		)
		(layer "In4.Cu")
	)
	(gr_line
		(start 331.945742 -44.343828)
		(end 331.949552 -44.341288)
		(stroke
			(width 0.05715)
			(type default)
		)
		(layer "In4.Cu")
	)
	(gr_line
		(start 331.966316 -63.99784)
		(end 331.978254 -63.980314)
		(stroke
			(width 0.05715)
			(type default)
		)
		(layer "In4.Cu")
	)
	(gr_line
		(start 331.978254 -63.980314)
		(end 331.99578 -63.96863)
		(stroke
			(width 0.05715)
			(type default)
		)
		(layer "In4.Cu")
	)
	(gr_line
		(start 332.135226 -71.522336)
		(end 332.146656 -71.505318)
		(stroke
			(width 0.05715)
			(type default)
		)
		(layer "In4.Cu")
	)
	(gr_line
		(start 332.146402 -54.30774)
		(end 332.147672 -54.306724)
		(stroke
			(width 0.05715)
			(type default)
		)
		(layer "In4.Cu")
	)
	(gr_line
		(start 332.146656 -71.505318)
		(end 332.164436 -71.493634)
		(stroke
			(width 0.05715)
			(type default)
		)
		(layer "In4.Cu")
	)
	(gr_line
		(start 332.147672 -54.306724)
		(end 332.149704 -54.305962)
		(stroke
			(width 0.05715)
			(type default)
		)
		(layer "In4.Cu")
	)
	(gr_line
		(start 332.162404 -56.648096)
		(end 332.17231 -56.633618)
		(stroke
			(width 0.05715)
			(type default)
		)
		(layer "In4.Cu")
	)
	(gr_line
		(start 332.17231 -56.633618)
		(end 332.188312 -56.62295)
		(stroke
			(width 0.05715)
			(type default)
		)
		(layer "In4.Cu")
	)
	(gr_line
		(start 332.524862 -54.858412)
		(end 332.526894 -54.856888)
		(stroke
			(width 0.05715)
			(type default)
		)
		(layer "In4.Cu")
	)
	(gr_line
		(start 332.526894 -54.856888)
		(end 332.529688 -54.855872)
		(stroke
			(width 0.05715)
			(type default)
		)
		(layer "In4.Cu")
	)
	(gr_line
		(start 332.563978 -57.18556)
		(end 332.574138 -57.170574)
		(stroke
			(width 0.05715)
			(type default)
		)
		(layer "In4.Cu")
	)
	(gr_line
		(start 332.574138 -57.170574)
		(end 332.589124 -57.160668)
		(stroke
			(width 0.05715)
			(type default)
		)
		(layer "In4.Cu")
	)
	(gr_line
		(start 332.60157 -55.586122)
		(end 332.642718 -55.558944)
		(stroke
			(width 0.05715)
			(type default)
		)
		(layer "In4.Cu")
	)
	(gr_line
		(start 332.775814 -56.23433)
		(end 332.817724 -56.206644)
		(stroke
			(width 0.05715)
			(type default)
		)
		(layer "In4.Cu")
	)
	(gr_line
		(start 332.974696 -57.709562)
		(end 332.984856 -57.694576)
		(stroke
			(width 0.05715)
			(type default)
		)
		(layer "In4.Cu")
	)
	(gr_line
		(start 332.984856 -57.694576)
		(end 332.999842 -57.68467)
		(stroke
			(width 0.05715)
			(type default)
		)
		(layer "In4.Cu")
	)
	(gr_line
		(start 333.017114 -61.521594)
		(end 333.032862 -61.511434)
		(stroke
			(width 0.05715)
			(type default)
		)
		(layer "In4.Cu")
	)
	(gr_line
		(start 333.029052 -56.869584)
		(end 333.0702 -56.842406)
		(stroke
			(width 0.05715)
			(type default)
		)
		(layer "In4.Cu")
	)
	(gr_line
		(start 333.032862 -61.511434)
		(end 333.051658 -61.507878)
		(stroke
			(width 0.05715)
			(type default)
		)
		(layer "In4.Cu")
	)
	(gr_line
		(start 333.075534 -43.590718)
		(end 333.093822 -43.578526)
		(stroke
			(width 0.05715)
			(type default)
		)
		(layer "In4.Cu")
	)
	(gr_line
		(start 333.093822 -43.578526)
		(end 333.106014 -43.560492)
		(stroke
			(width 0.05715)
			(type default)
		)
		(layer "In4.Cu")
	)
	(gr_line
		(start 333.19085 -40.725598)
		(end 333.209646 -40.722042)
		(stroke
			(width 0.05715)
			(type default)
		)
		(layer "In4.Cu")
	)
	(gr_line
		(start 333.209646 -40.722042)
		(end 333.226156 -40.71112)
		(stroke
			(width 0.05715)
			(type default)
		)
		(layer "In4.Cu")
	)
	(gr_line
		(start 333.2607 -41.256966)
		(end 333.35976 -41.19118)
		(stroke
			(width 0.05715)
			(type default)
		)
		(layer "In4.Cu")
	)
	(gr_line
		(start 333.268828 -58.402474)
		(end 333.293466 -58.366914)
		(stroke
			(width 0.05715)
			(type default)
		)
		(layer "In4.Cu")
	)
	(gr_line
		(start 333.271368 -57.5056)
		(end 333.312262 -57.478422)
		(stroke
			(width 0.05715)
			(type default)
		)
		(layer "In4.Cu")
	)
	(gr_line
		(start 333.293466 -58.366914)
		(end 333.33309 -58.34888)
		(stroke
			(width 0.05715)
			(type default)
		)
		(layer "In4.Cu")
	)
	(gr_line
		(start 333.321406 -62.298834)
		(end 333.337154 -62.288674)
		(stroke
			(width 0.05715)
			(type default)
		)
		(layer "In4.Cu")
	)
	(gr_line
		(start 333.337154 -62.288674)
		(end 333.355188 -62.285372)
		(stroke
			(width 0.05715)
			(type default)
		)
		(layer "In4.Cu")
	)
	(gr_line
		(start 333.364078 -43.173142)
		(end 333.374746 -43.156886)
		(stroke
			(width 0.05715)
			(type default)
		)
		(layer "In4.Cu")
	)
	(gr_line
		(start 333.374746 -43.156886)
		(end 333.378556 -43.137836)
		(stroke
			(width 0.05715)
			(type default)
		)
		(layer "In4.Cu")
	)
	(gr_line
		(start 333.564484 -62.936374)
		(end 333.581502 -62.925198)
		(stroke
			(width 0.05715)
			(type default)
		)
		(layer "In4.Cu")
	)
	(gr_line
		(start 333.581502 -62.925198)
		(end 333.600806 -62.921642)
		(stroke
			(width 0.05715)
			(type default)
		)
		(layer "In4.Cu")
	)
	(gr_line
		(start 333.762858 -58.154316)
		(end 333.785464 -58.144156)
		(stroke
			(width 0.05715)
			(type default)
		)
		(layer "In4.Cu")
	)
	(gr_line
		(start 334.218534 -62.801246)
		(end 334.24241 -62.796674)
		(stroke
			(width 0.05715)
			(type default)
		)
		(layer "In4.Cu")
	)
	(gr_line
		(start 334.24241 -62.796674)
		(end 334.265778 -62.802262)
		(stroke
			(width 0.05715)
			(type default)
		)
		(layer "In4.Cu")
	)
	(gr_line
		(start 334.346804 -62.092078)
		(end 334.37068 -62.087506)
		(stroke
			(width 0.05715)
			(type default)
		)
		(layer "In4.Cu")
	)
	(gr_line
		(start 334.37068 -62.087506)
		(end 334.394048 -62.093094)
		(stroke
			(width 0.05715)
			(type default)
		)
		(layer "In4.Cu")
	)
	(gr_line
		(start 334.384904 -53.591968)
		(end 334.391254 -53.589936)
		(stroke
			(width 0.05715)
			(type default)
		)
		(layer "In4.Cu")
	)
	(gr_line
		(start 334.447388 -61.241686)
		(end 334.471772 -61.237114)
		(stroke
			(width 0.05715)
			(type default)
		)
		(layer "In4.Cu")
	)
	(gr_line
		(start 334.471772 -61.237114)
		(end 334.495902 -61.242702)
		(stroke
			(width 0.05715)
			(type default)
		)
		(layer "In4.Cu")
	)
	(gr_line
		(start 334.494378 -54.226968)
		(end 334.500728 -54.224936)
		(stroke
			(width 0.05715)
			(type default)
		)
		(layer "In4.Cu")
	)
	(gr_line
		(start 335.263998 -39.929308)
		(end 335.305654 -39.901876)
		(stroke
			(width 0.05715)
			(type default)
		)
		(layer "In4.Cu")
	)
	(gr_line
		(start 335.631282 -43.84929)
		(end 335.663286 -43.83913)
		(stroke
			(width 0.05715)
			(type default)
		)
		(layer "In4.Cu")
	)
	(gr_line
		(start 335.812638 -38.646608)
		(end 335.854294 -38.619176)
		(stroke
			(width 0.05715)
			(type default)
		)
		(layer "In4.Cu")
	)
	(gr_line
		(start 336.712052 -13.499084)
		(end 337.185 -13.092938)
		(stroke
			(width 0.0635)
			(type default)
		)
		(layer "In4.Cu")
	)
	(gr_line
		(start 336.869024 -13.755624)
		(end 337.172808 -14.108176)
		(stroke
			(width 0.0635)
			(type default)
		)
		(layer "In4.Cu")
	)
	(gr_line
		(start 337.04784 -64.387476)
		(end 337.064858 -64.3763)
		(stroke
			(width 0.05715)
			(type default)
		)
		(layer "In4.Cu")
	)
	(gr_line
		(start 337.064858 -64.3763)
		(end 337.084162 -64.372744)
		(stroke
			(width 0.05715)
			(type default)
		)
		(layer "In4.Cu")
	)
	(gr_line
		(start 337.162648 -44.405296)
		(end 337.198462 -44.393866)
		(stroke
			(width 0.05715)
			(type default)
		)
		(layer "In4.Cu")
	)
	(gr_line
		(start 337.164934 -45.747432)
		(end 337.201256 -45.736002)
		(stroke
			(width 0.05715)
			(type default)
		)
		(layer "In4.Cu")
	)
	(gr_line
		(start 337.172808 -45.075094)
		(end 337.209384 -45.06341)
		(stroke
			(width 0.05715)
			(type default)
		)
		(layer "In4.Cu")
	)
	(gr_line
		(start 337.187286 -43.723306)
		(end 337.2231 -43.711876)
		(stroke
			(width 0.05715)
			(type default)
		)
		(layer "In4.Cu")
	)
	(gr_line
		(start 337.198462 -44.393866)
		(end 337.236054 -44.401486)
		(stroke
			(width 0.05715)
			(type default)
		)
		(layer "In4.Cu")
	)
	(gr_line
		(start 337.201256 -45.736002)
		(end 337.238848 -45.743622)
		(stroke
			(width 0.05715)
			(type default)
		)
		(layer "In4.Cu")
	)
	(gr_line
		(start 337.202018 -46.405546)
		(end 337.238594 -46.393862)
		(stroke
			(width 0.05715)
			(type default)
		)
		(layer "In4.Cu")
	)
	(gr_line
		(start 337.209384 -45.06341)
		(end 337.246976 -45.07103)
		(stroke
			(width 0.05715)
			(type default)
		)
		(layer "In4.Cu")
	)
	(gr_line
		(start 337.2231 -43.711876)
		(end 337.260692 -43.719496)
		(stroke
			(width 0.05715)
			(type default)
		)
		(layer "In4.Cu")
	)
	(gr_line
		(start 337.233006 -47.070518)
		(end 337.269582 -47.058834)
		(stroke
			(width 0.05715)
			(type default)
		)
		(layer "In4.Cu")
	)
	(gr_line
		(start 337.238594 -46.393862)
		(end 337.276186 -46.401482)
		(stroke
			(width 0.05715)
			(type default)
		)
		(layer "In4.Cu")
	)
	(gr_line
		(start 337.260438 -47.729394)
		(end 337.297014 -47.717964)
		(stroke
			(width 0.05715)
			(type default)
		)
		(layer "In4.Cu")
	)
	(gr_line
		(start 337.269582 -47.058834)
		(end 337.307174 -47.066454)
		(stroke
			(width 0.05715)
			(type default)
		)
		(layer "In4.Cu")
	)
	(gr_line
		(start 337.297014 -47.717964)
		(end 337.33486 -47.725584)
		(stroke
			(width 0.05715)
			(type default)
		)
		(layer "In4.Cu")
	)
	(gr_line
		(start 337.316826 -48.39335)
		(end 337.353402 -48.38192)
		(stroke
			(width 0.05715)
			(type default)
		)
		(layer "In4.Cu")
	)
	(gr_line
		(start 337.350862 -64.978026)
		(end 337.36788 -64.96685)
		(stroke
			(width 0.05715)
			(type default)
		)
		(layer "In4.Cu")
	)
	(gr_line
		(start 337.353402 -48.38192)
		(end 337.390994 -48.38954)
		(stroke
			(width 0.05715)
			(type default)
		)
		(layer "In4.Cu")
	)
	(gr_line
		(start 337.36788 -64.96685)
		(end 337.387184 -64.963294)
		(stroke
			(width 0.05715)
			(type default)
		)
		(layer "In4.Cu")
	)
	(gr_line
		(start 337.398106 -49.074324)
		(end 337.433666 -49.062894)
		(stroke
			(width 0.05715)
			(type default)
		)
		(layer "In4.Cu")
	)
	(gr_line
		(start 337.412076 -49.741582)
		(end 337.447636 -49.730152)
		(stroke
			(width 0.05715)
			(type default)
		)
		(layer "In4.Cu")
	)
	(gr_line
		(start 337.433666 -49.062894)
		(end 337.471258 -49.070514)
		(stroke
			(width 0.05715)
			(type default)
		)
		(layer "In4.Cu")
	)
	(gr_line
		(start 337.440016 -50.405792)
		(end 337.476084 -50.394362)
		(stroke
			(width 0.05715)
			(type default)
		)
		(layer "In4.Cu")
	)
	(gr_line
		(start 337.447636 -49.730152)
		(end 337.485228 -49.737772)
		(stroke
			(width 0.05715)
			(type default)
		)
		(layer "In4.Cu")
	)
	(gr_line
		(start 337.472782 -51.086004)
		(end 337.50885 -51.074574)
		(stroke
			(width 0.05715)
			(type default)
		)
		(layer "In4.Cu")
	)
	(gr_line
		(start 337.476084 -50.394362)
		(end 337.513676 -50.401982)
		(stroke
			(width 0.05715)
			(type default)
		)
		(layer "In4.Cu")
	)
	(gr_line
		(start 337.50885 -51.074574)
		(end 337.546696 -51.082194)
		(stroke
			(width 0.05715)
			(type default)
		)
		(layer "In4.Cu")
	)
	(gr_line
		(start 337.561428 -51.764438)
		(end 337.597496 -51.753008)
		(stroke
			(width 0.05715)
			(type default)
		)
		(layer "In4.Cu")
	)
	(gr_line
		(start 337.597496 -51.753008)
		(end 337.635088 -51.760628)
		(stroke
			(width 0.05715)
			(type default)
		)
		(layer "In4.Cu")
	)
	(gr_line
		(start 337.62315 -65.57518)
		(end 337.640168 -65.564004)
		(stroke
			(width 0.05715)
			(type default)
		)
		(layer "In4.Cu")
	)
	(gr_line
		(start 337.640168 -65.564004)
		(end 337.659472 -65.560448)
		(stroke
			(width 0.05715)
			(type default)
		)
		(layer "In4.Cu")
	)
	(gr_line
		(start 337.678268 -63.892684)
		(end 337.701128 -63.898018)
		(stroke
			(width 0.05715)
			(type default)
		)
		(layer "In4.Cu")
	)
	(gr_line
		(start 337.701128 -63.898018)
		(end 337.725004 -63.893446)
		(stroke
			(width 0.05715)
			(type default)
		)
		(layer "In4.Cu")
	)
	(gr_line
		(start 337.70316 -62.287404)
		(end 337.72602 -62.292738)
		(stroke
			(width 0.05715)
			(type default)
		)
		(layer "In4.Cu")
	)
	(gr_line
		(start 337.72602 -62.292738)
		(end 337.749896 -62.288166)
		(stroke
			(width 0.05715)
			(type default)
		)
		(layer "In4.Cu")
	)
	(gr_line
		(start 337.882738 -63.201296)
		(end 337.909154 -63.207392)
		(stroke
			(width 0.05715)
			(type default)
		)
		(layer "In4.Cu")
	)
	(gr_line
		(start 337.909154 -63.207392)
		(end 337.933538 -63.202566)
		(stroke
			(width 0.05715)
			(type default)
		)
		(layer "In4.Cu")
	)
	(gr_line
		(start 337.935824 -66.164714)
		(end 337.953858 -66.15303)
		(stroke
			(width 0.05715)
			(type default)
		)
		(layer "In4.Cu")
	)
	(gr_line
		(start 337.953858 -66.15303)
		(end 337.974178 -66.148966)
		(stroke
			(width 0.05715)
			(type default)
		)
		(layer "In4.Cu")
	)
	(gr_line
		(start 338.191856 -66.764408)
		(end 338.208874 -66.753232)
		(stroke
			(width 0.05715)
			(type default)
		)
		(layer "In4.Cu")
	)
	(gr_line
		(start 338.208874 -66.753232)
		(end 338.228178 -66.749676)
		(stroke
			(width 0.05715)
			(type default)
		)
		(layer "In4.Cu")
	)
	(gr_line
		(start 338.436458 -67.365626)
		(end 338.453476 -67.35445)
		(stroke
			(width 0.05715)
			(type default)
		)
		(layer "In4.Cu")
	)
	(gr_line
		(start 338.453476 -67.35445)
		(end 338.47278 -67.350894)
		(stroke
			(width 0.05715)
			(type default)
		)
		(layer "In4.Cu")
	)
	(gr_line
		(start 339.189822 -45.097954)
		(end 339.210904 -45.102272)
		(stroke
			(width 0.05715)
			(type default)
		)
		(layer "In4.Cu")
	)
	(gr_line
		(start 339.190076 -44.410884)
		(end 339.211158 -44.415202)
		(stroke
			(width 0.05715)
			(type default)
		)
		(layer "In4.Cu")
	)
	(gr_line
		(start 339.210904 -45.102272)
		(end 339.23224 -45.097954)
		(stroke
			(width 0.05715)
			(type default)
		)
		(layer "In4.Cu")
	)
	(gr_line
		(start 339.211158 -44.415202)
		(end 339.232494 -44.410884)
		(stroke
			(width 0.05715)
			(type default)
		)
		(layer "In4.Cu")
	)
	(gr_line
		(start 339.23859 -45.775118)
		(end 339.259672 -45.779436)
		(stroke
			(width 0.05715)
			(type default)
		)
		(layer "In4.Cu")
	)
	(gr_line
		(start 339.259672 -45.779436)
		(end 339.281008 -45.775118)
		(stroke
			(width 0.05715)
			(type default)
		)
		(layer "In4.Cu")
	)
	(gr_line
		(start 339.268816 -46.456092)
		(end 339.289898 -46.46041)
		(stroke
			(width 0.05715)
			(type default)
		)
		(layer "In4.Cu")
	)
	(gr_line
		(start 339.289898 -46.46041)
		(end 339.311234 -46.456092)
		(stroke
			(width 0.05715)
			(type default)
		)
		(layer "In4.Cu")
	)
	(gr_line
		(start 339.360764 -47.124112)
		(end 339.3821 -47.12843)
		(stroke
			(width 0.05715)
			(type default)
		)
		(layer "In4.Cu")
	)
	(gr_line
		(start 339.3821 -47.12843)
		(end 339.403436 -47.124112)
		(stroke
			(width 0.05715)
			(type default)
		)
		(layer "In4.Cu")
	)
	(gr_line
		(start 339.429344 -47.796958)
		(end 339.45068 -47.801276)
		(stroke
			(width 0.05715)
			(type default)
		)
		(layer "In4.Cu")
	)
	(gr_line
		(start 339.45068 -47.801276)
		(end 339.472016 -47.796958)
		(stroke
			(width 0.05715)
			(type default)
		)
		(layer "In4.Cu")
	)
	(gr_line
		(start 339.512148 -48.46701)
		(end 339.533484 -48.471328)
		(stroke
			(width 0.05715)
			(type default)
		)
		(layer "In4.Cu")
	)
	(gr_line
		(start 339.533484 -48.471328)
		(end 339.55482 -48.46701)
		(stroke
			(width 0.05715)
			(type default)
		)
		(layer "In4.Cu")
	)
	(gr_line
		(start 339.594952 -49.137062)
		(end 339.616034 -49.14138)
		(stroke
			(width 0.05715)
			(type default)
		)
		(layer "In4.Cu")
	)
	(gr_line
		(start 339.616034 -49.14138)
		(end 339.63737 -49.137062)
		(stroke
			(width 0.05715)
			(type default)
		)
		(layer "In4.Cu")
	)
	(gr_line
		(start 339.650578 -49.812448)
		(end 339.671914 -49.816766)
		(stroke
			(width 0.05715)
			(type default)
		)
		(layer "In4.Cu")
	)
	(gr_line
		(start 339.671914 -49.816766)
		(end 339.69325 -49.812448)
		(stroke
			(width 0.05715)
			(type default)
		)
		(layer "In4.Cu")
	)
	(gr_line
		(start 339.705696 -50.488088)
		(end 339.727032 -50.492406)
		(stroke
			(width 0.05715)
			(type default)
		)
		(layer "In4.Cu")
	)
	(gr_line
		(start 339.727032 -50.492406)
		(end 339.748368 -50.488088)
		(stroke
			(width 0.05715)
			(type default)
		)
		(layer "In4.Cu")
	)
	(gr_line
		(start 339.7758 -51.161188)
		(end 339.796882 -51.165506)
		(stroke
			(width 0.05715)
			(type default)
		)
		(layer "In4.Cu")
	)
	(gr_line
		(start 339.796882 -51.165506)
		(end 339.818218 -51.161188)
		(stroke
			(width 0.05715)
			(type default)
		)
		(layer "In4.Cu")
	)
	(gr_line
		(start 339.808312 -51.840892)
		(end 339.829648 -51.84521)
		(stroke
			(width 0.05715)
			(type default)
		)
		(layer "In4.Cu")
	)
	(gr_line
		(start 339.829648 -51.84521)
		(end 339.850984 -51.840892)
		(stroke
			(width 0.05715)
			(type default)
		)
		(layer "In4.Cu")
	)
	(gr_line
		(start 339.873844 -52.514754)
		(end 339.89518 -52.519072)
		(stroke
			(width 0.05715)
			(type default)
		)
		(layer "In4.Cu")
	)
	(gr_line
		(start 339.89518 -52.519072)
		(end 339.916516 -52.514754)
		(stroke
			(width 0.05715)
			(type default)
		)
		(layer "In4.Cu")
	)
	(gr_line
		(start 340.70925 -80.8228)
		(end 340.70925 -81.19745)
		(stroke
			(width 0.05715)
			(type default)
		)
		(layer "In4.Cu")
	)
	(gr_line
		(start 340.70925 -80.8228)
		(end 340.76132 -80.77073)
		(stroke
			(width 0.05715)
			(type default)
		)
		(layer "In4.Cu")
	)
	(gr_line
		(start 340.70925 -80.3021)
		(end 340.76132 -80.35417)
		(stroke
			(width 0.05715)
			(type default)
		)
		(layer "In4.Cu")
	)
	(gr_line
		(start 340.70925 -79.92745)
		(end 340.70925 -80.3021)
		(stroke
			(width 0.05715)
			(type default)
		)
		(layer "In4.Cu")
	)
	(gr_line
		(start 340.87689 -44.076366)
		(end 340.946486 -44.062142)
		(stroke
			(width 0.05715)
			(type default)
		)
		(layer "In4.Cu")
	)
	(gr_line
		(start 340.946486 -44.045378)
		(end 340.946486 -44.062142)
		(stroke
			(width 0.05715)
			(type default)
		)
		(layer "In4.Cu")
	)
	(gr_line
		(start 341.405718 -45.044614)
		(end 341.427054 -45.040296)
		(stroke
			(width 0.05715)
			(type default)
		)
		(layer "In4.Cu")
	)
	(gr_line
		(start 341.427054 -45.040296)
		(end 341.44839 -45.044614)
		(stroke
			(width 0.05715)
			(type default)
		)
		(layer "In4.Cu")
	)
	(gr_line
		(start 341.468202 -44.345098)
		(end 341.489538 -44.34078)
		(stroke
			(width 0.05715)
			(type default)
		)
		(layer "In4.Cu")
	)
	(gr_line
		(start 341.47125 -45.718222)
		(end 341.492586 -45.713904)
		(stroke
			(width 0.05715)
			(type default)
		)
		(layer "In4.Cu")
	)
	(gr_line
		(start 341.489538 -44.34078)
		(end 341.510874 -44.345098)
		(stroke
			(width 0.05715)
			(type default)
		)
		(layer "In4.Cu")
	)
	(gr_line
		(start 341.492586 -45.713904)
		(end 341.513922 -45.718222)
		(stroke
			(width 0.05715)
			(type default)
		)
		(layer "In4.Cu")
	)
	(gr_line
		(start 341.52967 -46.3931)
		(end 341.551006 -46.388782)
		(stroke
			(width 0.05715)
			(type default)
		)
		(layer "In4.Cu")
	)
	(gr_line
		(start 341.551006 -46.388782)
		(end 341.572342 -46.3931)
		(stroke
			(width 0.05715)
			(type default)
		)
		(layer "In4.Cu")
	)
	(gr_line
		(start 341.60968 -47.06366)
		(end 341.631016 -47.059342)
		(stroke
			(width 0.05715)
			(type default)
		)
		(layer "In4.Cu")
	)
	(gr_line
		(start 341.631016 -47.059342)
		(end 341.652352 -47.06366)
		(stroke
			(width 0.05715)
			(type default)
		)
		(layer "In4.Cu")
	)
	(gr_line
		(start 341.697056 -47.73295)
		(end 341.718392 -47.728632)
		(stroke
			(width 0.05715)
			(type default)
		)
		(layer "In4.Cu")
	)
	(gr_line
		(start 341.718392 -47.728632)
		(end 341.739728 -47.73295)
		(stroke
			(width 0.05715)
			(type default)
		)
		(layer "In4.Cu")
	)
	(gr_line
		(start 341.775796 -48.403764)
		(end 341.797132 -48.399446)
		(stroke
			(width 0.05715)
			(type default)
		)
		(layer "In4.Cu")
	)
	(gr_line
		(start 341.797132 -48.399446)
		(end 341.818468 -48.403764)
		(stroke
			(width 0.05715)
			(type default)
		)
		(layer "In4.Cu")
	)
	(gr_line
		(start 341.845138 -49.07661)
		(end 341.866474 -49.072292)
		(stroke
			(width 0.05715)
			(type default)
		)
		(layer "In4.Cu")
	)
	(gr_line
		(start 341.866474 -49.072292)
		(end 341.88781 -49.07661)
		(stroke
			(width 0.05715)
			(type default)
		)
		(layer "In4.Cu")
	)
	(gr_line
		(start 341.921846 -49.747678)
		(end 341.943182 -49.74336)
		(stroke
			(width 0.05715)
			(type default)
		)
		(layer "In4.Cu")
	)
	(gr_line
		(start 341.943182 -49.74336)
		(end 341.964518 -49.747678)
		(stroke
			(width 0.05715)
			(type default)
		)
		(layer "In4.Cu")
	)
	(gr_line
		(start 341.977726 -50.423318)
		(end 341.999062 -50.419)
		(stroke
			(width 0.05715)
			(type default)
		)
		(layer "In4.Cu")
	)
	(gr_line
		(start 341.999062 -50.419)
		(end 342.020398 -50.423318)
		(stroke
			(width 0.05715)
			(type default)
		)
		(layer "In4.Cu")
	)
	(gr_line
		(start 342.058244 -51.093624)
		(end 342.07958 -51.089306)
		(stroke
			(width 0.05715)
			(type default)
		)
		(layer "In4.Cu")
	)
	(gr_line
		(start 342.07958 -51.089306)
		(end 342.100916 -51.093624)
		(stroke
			(width 0.05715)
			(type default)
		)
		(layer "In4.Cu")
	)
	(gr_line
		(start 342.13927 -51.764184)
		(end 342.160606 -51.759866)
		(stroke
			(width 0.05715)
			(type default)
		)
		(layer "In4.Cu")
	)
	(gr_line
		(start 342.160606 -51.759866)
		(end 342.181942 -51.764184)
		(stroke
			(width 0.05715)
			(type default)
		)
		(layer "In4.Cu")
	)
	(gr_line
		(start 342.680036 -81.57083)
		(end 342.942672 -81.308194)
		(stroke
			(width 0.05715)
			(type default)
		)
		(layer "In4.Cu")
	)
	(gr_line
		(start 342.680036 -80.628744)
		(end 342.942672 -80.89138)
		(stroke
			(width 0.05715)
			(type default)
		)
		(layer "In4.Cu")
	)
	(gr_line
		(start 343.09177 -60.951364)
		(end 343.115646 -60.946792)
		(stroke
			(width 0.05715)
			(type default)
		)
		(layer "In4.Cu")
	)
	(gr_line
		(start 343.115646 -66.447416)
		(end 343.139522 -66.442844)
		(stroke
			(width 0.05715)
			(type default)
		)
		(layer "In4.Cu")
	)
	(gr_line
		(start 343.115646 -60.946792)
		(end 343.13876 -60.95238)
		(stroke
			(width 0.05715)
			(type default)
		)
		(layer "In4.Cu")
	)
	(gr_line
		(start 343.139522 -66.442844)
		(end 343.162636 -66.448432)
		(stroke
			(width 0.05715)
			(type default)
		)
		(layer "In4.Cu")
	)
	(gr_line
		(start 343.151714 -65.790572)
		(end 343.175336 -65.786)
		(stroke
			(width 0.05715)
			(type default)
		)
		(layer "In4.Cu")
	)
	(gr_line
		(start 343.175336 -65.786)
		(end 343.19845 -65.791588)
		(stroke
			(width 0.05715)
			(type default)
		)
		(layer "In4.Cu")
	)
	(gr_line
		(start 343.214198 -65.128394)
		(end 343.23782 -65.123822)
		(stroke
			(width 0.05715)
			(type default)
		)
		(layer "In4.Cu")
	)
	(gr_line
		(start 343.23782 -65.123822)
		(end 343.260934 -65.12941)
		(stroke
			(width 0.05715)
			(type default)
		)
		(layer "In4.Cu")
	)
	(gr_line
		(start 343.268808 -64.46774)
		(end 343.29243 -64.463168)
		(stroke
			(width 0.05715)
			(type default)
		)
		(layer "In4.Cu")
	)
	(gr_line
		(start 343.29243 -64.463168)
		(end 343.315544 -64.468756)
		(stroke
			(width 0.05715)
			(type default)
		)
		(layer "In4.Cu")
	)
	(gr_line
		(start 343.304114 -63.810896)
		(end 343.32799 -63.806324)
		(stroke
			(width 0.05715)
			(type default)
		)
		(layer "In4.Cu")
	)
	(gr_line
		(start 343.32799 -63.806324)
		(end 343.35085 -63.811658)
		(stroke
			(width 0.05715)
			(type default)
		)
		(layer "In4.Cu")
	)
	(gr_line
		(start 343.329006 -63.156084)
		(end 343.352882 -63.151512)
		(stroke
			(width 0.05715)
			(type default)
		)
		(layer "In4.Cu")
	)
	(gr_line
		(start 343.337642 -75.627484)
		(end 343.369392 -75.610212)
		(stroke
			(width 0.05715)
			(type default)
		)
		(layer "In4.Cu")
	)
	(gr_line
		(start 343.352882 -63.151512)
		(end 343.375742 -63.156846)
		(stroke
			(width 0.05715)
			(type default)
		)
		(layer "In4.Cu")
	)
	(gr_line
		(start 343.373456 -62.497462)
		(end 343.397332 -62.49289)
		(stroke
			(width 0.05715)
			(type default)
		)
		(layer "In4.Cu")
	)
	(gr_line
		(start 343.380314 -61.846206)
		(end 343.40419 -61.841634)
		(stroke
			(width 0.05715)
			(type default)
		)
		(layer "In4.Cu")
	)
	(gr_line
		(start 343.397332 -62.49289)
		(end 343.420446 -62.498478)
		(stroke
			(width 0.05715)
			(type default)
		)
		(layer "In4.Cu")
	)
	(gr_line
		(start 343.40419 -61.841634)
		(end 343.427304 -61.847222)
		(stroke
			(width 0.05715)
			(type default)
		)
		(layer "In4.Cu")
	)
	(gr_line
		(start 343.555066 -45.058838)
		(end 343.58453 -45.064934)
		(stroke
			(width 0.05715)
			(type default)
		)
		(layer "In4.Cu")
	)
	(gr_line
		(start 343.58453 -45.064934)
		(end 343.613486 -45.05706)
		(stroke
			(width 0.05715)
			(type default)
		)
		(layer "In4.Cu")
	)
	(gr_line
		(start 343.650062 -45.790612)
		(end 343.679526 -45.796708)
		(stroke
			(width 0.05715)
			(type default)
		)
		(layer "In4.Cu")
	)
	(gr_line
		(start 343.679526 -45.796708)
		(end 343.708482 -45.788834)
		(stroke
			(width 0.05715)
			(type default)
		)
		(layer "In4.Cu")
	)
	(gr_line
		(start 343.728294 -46.466506)
		(end 343.757758 -46.472602)
		(stroke
			(width 0.05715)
			(type default)
		)
		(layer "In4.Cu")
	)
	(gr_line
		(start 343.757758 -46.472602)
		(end 343.786714 -46.464728)
		(stroke
			(width 0.05715)
			(type default)
		)
		(layer "In4.Cu")
	)
	(gr_line
		(start 343.799668 -47.144178)
		(end 343.829132 -47.150274)
		(stroke
			(width 0.05715)
			(type default)
		)
		(layer "In4.Cu")
	)
	(gr_line
		(start 343.829132 -47.150274)
		(end 343.858088 -47.1424)
		(stroke
			(width 0.05715)
			(type default)
		)
		(layer "In4.Cu")
	)
	(gr_line
		(start 343.848944 -47.808388)
		(end 343.878408 -47.814484)
		(stroke
			(width 0.05715)
			(type default)
		)
		(layer "In4.Cu")
	)
	(gr_line
		(start 343.878408 -47.814484)
		(end 343.907364 -47.80661)
		(stroke
			(width 0.05715)
			(type default)
		)
		(layer "In4.Cu")
	)
	(gr_line
		(start 343.889838 -48.468534)
		(end 343.919302 -48.47463)
		(stroke
			(width 0.05715)
			(type default)
		)
		(layer "In4.Cu")
	)
	(gr_line
		(start 343.91473 -49.12868)
		(end 343.944194 -49.134776)
		(stroke
			(width 0.05715)
			(type default)
		)
		(layer "In4.Cu")
	)
	(gr_line
		(start 343.915746 -49.787302)
		(end 343.94521 -49.793398)
		(stroke
			(width 0.05715)
			(type default)
		)
		(layer "In4.Cu")
	)
	(gr_line
		(start 343.919302 -48.47463)
		(end 343.948258 -48.466756)
		(stroke
			(width 0.05715)
			(type default)
		)
		(layer "In4.Cu")
	)
	(gr_line
		(start 343.943178 -51.11242)
		(end 343.972642 -51.118516)
		(stroke
			(width 0.05715)
			(type default)
		)
		(layer "In4.Cu")
	)
	(gr_line
		(start 343.944194 -49.134776)
		(end 343.97315 -49.126902)
		(stroke
			(width 0.05715)
			(type default)
		)
		(layer "In4.Cu")
	)
	(gr_line
		(start 343.94521 -49.793398)
		(end 343.974166 -49.785524)
		(stroke
			(width 0.05715)
			(type default)
		)
		(layer "In4.Cu")
	)
	(gr_line
		(start 343.946226 -50.449226)
		(end 343.97569 -50.455322)
		(stroke
			(width 0.05715)
			(type default)
		)
		(layer "In4.Cu")
	)
	(gr_line
		(start 343.971118 -51.772312)
		(end 344.000582 -51.778408)
		(stroke
			(width 0.05715)
			(type default)
		)
		(layer "In4.Cu")
	)
	(gr_line
		(start 343.972642 -51.118516)
		(end 344.002868 -51.110642)
		(stroke
			(width 0.05715)
			(type default)
		)
		(layer "In4.Cu")
	)
	(gr_line
		(start 343.97569 -50.455322)
		(end 344.004646 -50.447448)
		(stroke
			(width 0.05715)
			(type default)
		)
		(layer "In4.Cu")
	)
	(gr_line
		(start 344.000582 -51.778408)
		(end 344.029538 -51.770534)
		(stroke
			(width 0.05715)
			(type default)
		)
		(layer "In4.Cu")
	)
	(gr_line
		(start 344.049604 -66.954654)
		(end 344.072718 -66.960242)
		(stroke
			(width 0.05715)
			(type default)
		)
		(layer "In4.Cu")
	)
	(gr_line
		(start 344.072718 -66.960242)
		(end 344.096594 -66.95567)
		(stroke
			(width 0.05715)
			(type default)
		)
		(layer "In4.Cu")
	)
	(gr_line
		(start 344.084148 -66.298064)
		(end 344.107262 -66.303652)
		(stroke
			(width 0.05715)
			(type default)
		)
		(layer "In4.Cu")
	)
	(gr_line
		(start 344.107262 -66.303652)
		(end 344.131138 -66.29908)
		(stroke
			(width 0.05715)
			(type default)
		)
		(layer "In4.Cu")
	)
	(gr_line
		(start 344.146378 -65.635886)
		(end 344.169492 -65.641474)
		(stroke
			(width 0.05715)
			(type default)
		)
		(layer "In4.Cu")
	)
	(gr_line
		(start 344.153998 -52.4637)
		(end 344.18524 -52.47005)
		(stroke
			(width 0.05715)
			(type default)
		)
		(layer "In4.Cu")
	)
	(gr_line
		(start 344.169492 -65.641474)
		(end 344.193368 -65.636902)
		(stroke
			(width 0.05715)
			(type default)
		)
		(layer "In4.Cu")
	)
	(gr_line
		(start 344.18524 -52.47005)
		(end 344.216228 -52.461668)
		(stroke
			(width 0.05715)
			(type default)
		)
		(layer "In4.Cu")
	)
	(gr_line
		(start 344.201242 -64.975232)
		(end 344.224356 -64.98082)
		(stroke
			(width 0.05715)
			(type default)
		)
		(layer "In4.Cu")
	)
	(gr_line
		(start 344.224356 -64.98082)
		(end 344.248232 -64.976248)
		(stroke
			(width 0.05715)
			(type default)
		)
		(layer "In4.Cu")
	)
	(gr_line
		(start 344.238072 -64.318134)
		(end 344.261186 -64.323722)
		(stroke
			(width 0.05715)
			(type default)
		)
		(layer "In4.Cu")
	)
	(gr_line
		(start 344.261186 -64.323722)
		(end 344.285062 -64.31915)
		(stroke
			(width 0.05715)
			(type default)
		)
		(layer "In4.Cu")
	)
	(gr_line
		(start 344.26525 -63.663068)
		(end 344.28811 -63.668402)
		(stroke
			(width 0.05715)
			(type default)
		)
		(layer "In4.Cu")
	)
	(gr_line
		(start 344.28811 -63.668402)
		(end 344.311986 -63.66383)
		(stroke
			(width 0.05715)
			(type default)
		)
		(layer "In4.Cu")
	)
	(gr_line
		(start 344.305636 -63.004954)
		(end 344.32875 -63.010542)
		(stroke
			(width 0.05715)
			(type default)
		)
		(layer "In4.Cu")
	)
	(gr_line
		(start 344.31224 -62.353698)
		(end 344.335354 -62.359286)
		(stroke
			(width 0.05715)
			(type default)
		)
		(layer "In4.Cu")
	)
	(gr_line
		(start 344.32875 -63.010542)
		(end 344.352372 -63.00597)
		(stroke
			(width 0.05715)
			(type default)
		)
		(layer "In4.Cu")
	)
	(gr_line
		(start 344.335354 -62.359286)
		(end 344.35923 -62.354714)
		(stroke
			(width 0.05715)
			(type default)
		)
		(layer "In4.Cu")
	)
	(gr_line
		(start 344.360754 -61.53785)
		(end 344.383868 -61.543438)
		(stroke
			(width 0.05715)
			(type default)
		)
		(layer "In4.Cu")
	)
	(gr_line
		(start 344.383868 -61.543438)
		(end 344.407744 -61.538866)
		(stroke
			(width 0.05715)
			(type default)
		)
		(layer "In4.Cu")
	)
	(gr_line
		(start 344.401648 -44.845986)
		(end 344.47226 -44.82719)
		(stroke
			(width 0.05715)
			(type default)
		)
		(layer "In4.Cu")
	)
	(gr_line
		(start 344.47226 -44.82719)
		(end 344.512646 -44.765976)
		(stroke
			(width 0.05715)
			(type default)
		)
		(layer "In4.Cu")
	)
	(gr_line
		(start 344.813636 -44.31157)
		(end 344.824558 -44.29506)
		(stroke
			(width 0.05715)
			(type default)
		)
		(layer "In4.Cu")
	)
	(gr_line
		(start 344.824558 -44.29506)
		(end 344.828622 -44.275502)
		(stroke
			(width 0.05715)
			(type default)
		)
		(layer "In4.Cu")
	)
	(gr_line
		(start 345.04884 -75.25512)
		(end 345.074748 -75.229212)
		(stroke
			(width 0.05715)
			(type default)
		)
		(layer "In4.Cu")
	)
	(gr_line
		(start 345.074748 -75.229212)
		(end 345.109546 -75.218544)
		(stroke
			(width 0.05715)
			(type default)
		)
		(layer "In4.Cu")
	)
	(gr_line
		(start 345.396566 -45.33646)
		(end 345.466416 -45.317664)
		(stroke
			(width 0.05715)
			(type default)
		)
		(layer "In4.Cu")
	)
	(gr_line
		(start 345.466416 -45.317664)
		(end 345.506294 -45.257212)
		(stroke
			(width 0.05715)
			(type default)
		)
		(layer "In4.Cu")
	)
	(gr_line
		(start 345.514676 -80.98155)
		(end 345.788996 -80.70723)
		(stroke
			(width 0.05715)
			(type default)
		)
		(layer "In4.Cu")
	)
	(gr_line
		(start 345.514676 -80.01635)
		(end 345.788996 -80.29067)
		(stroke
			(width 0.05715)
			(type default)
		)
		(layer "In4.Cu")
	)
	(gr_line
		(start 345.828874 -66.32067)
		(end 345.85275 -66.316098)
		(stroke
			(width 0.05715)
			(type default)
		)
		(layer "In4.Cu")
	)
	(gr_line
		(start 345.84386 -65.668144)
		(end 345.867736 -65.663572)
		(stroke
			(width 0.05715)
			(type default)
		)
		(layer "In4.Cu")
	)
	(gr_line
		(start 345.851734 -65.016634)
		(end 345.87561 -65.012062)
		(stroke
			(width 0.05715)
			(type default)
		)
		(layer "In4.Cu")
	)
	(gr_line
		(start 345.85275 -66.316098)
		(end 345.87561 -66.321432)
		(stroke
			(width 0.05715)
			(type default)
		)
		(layer "In4.Cu")
	)
	(gr_line
		(start 345.856052 -64.365378)
		(end 345.879928 -64.360806)
		(stroke
			(width 0.05715)
			(type default)
		)
		(layer "In4.Cu")
	)
	(gr_line
		(start 345.867736 -65.663572)
		(end 345.890596 -65.668906)
		(stroke
			(width 0.05715)
			(type default)
		)
		(layer "In4.Cu")
	)
	(gr_line
		(start 345.87561 -65.012062)
		(end 345.89847 -65.017396)
		(stroke
			(width 0.05715)
			(type default)
		)
		(layer "In4.Cu")
	)
	(gr_line
		(start 345.879928 -64.360806)
		(end 345.902788 -64.36614)
		(stroke
			(width 0.05715)
			(type default)
		)
		(layer "In4.Cu")
	)
	(gr_line
		(start 345.889072 -63.709042)
		(end 345.912948 -63.70447)
		(stroke
			(width 0.05715)
			(type default)
		)
		(layer "In4.Cu")
	)
	(gr_line
		(start 345.895676 -63.057786)
		(end 345.919552 -63.053214)
		(stroke
			(width 0.05715)
			(type default)
		)
		(layer "In4.Cu")
	)
	(gr_line
		(start 345.912948 -63.70447)
		(end 345.935808 -63.709804)
		(stroke
			(width 0.05715)
			(type default)
		)
		(layer "In4.Cu")
	)
	(gr_line
		(start 345.919552 -63.053214)
		(end 345.942412 -63.058548)
		(stroke
			(width 0.05715)
			(type default)
		)
		(layer "In4.Cu")
	)
	(gr_line
		(start 345.919806 -62.402974)
		(end 345.943682 -62.398402)
		(stroke
			(width 0.05715)
			(type default)
		)
		(layer "In4.Cu")
	)
	(gr_line
		(start 345.926918 -61.751718)
		(end 345.950794 -61.747146)
		(stroke
			(width 0.05715)
			(type default)
		)
		(layer "In4.Cu")
	)
	(gr_line
		(start 345.943682 -62.398402)
		(end 345.966542 -62.403736)
		(stroke
			(width 0.05715)
			(type default)
		)
		(layer "In4.Cu")
	)
	(gr_line
		(start 345.950794 -61.747146)
		(end 345.973654 -61.75248)
		(stroke
			(width 0.05715)
			(type default)
		)
		(layer "In4.Cu")
	)
	(gr_line
		(start 345.989656 -60.93333)
		(end 346.013532 -60.928758)
		(stroke
			(width 0.05715)
			(type default)
		)
		(layer "In4.Cu")
	)
	(gr_line
		(start 346.013532 -60.928758)
		(end 346.036392 -60.934092)
		(stroke
			(width 0.05715)
			(type default)
		)
		(layer "In4.Cu")
	)
	(gr_line
		(start 346.051124 -44.434506)
		(end 346.062046 -44.417996)
		(stroke
			(width 0.05715)
			(type default)
		)
		(layer "In4.Cu")
	)
	(gr_line
		(start 346.062046 -44.417996)
		(end 346.06611 -44.398438)
		(stroke
			(width 0.05715)
			(type default)
		)
		(layer "In4.Cu")
	)
	(gr_line
		(start 346.742512 -35.971734)
		(end 346.762578 -35.976052)
		(stroke
			(width 0.05715)
			(type default)
		)
		(layer "In4.Cu")
	)
	(gr_line
		(start 346.762578 -35.976052)
		(end 346.782644 -35.972242)
		(stroke
			(width 0.05715)
			(type default)
		)
		(layer "In4.Cu")
	)
	(gr_line
		(start 346.800424 -35.288982)
		(end 346.820744 -35.2933)
		(stroke
			(width 0.05715)
			(type default)
		)
		(layer "In4.Cu")
	)
	(gr_line
		(start 346.820744 -35.2933)
		(end 346.841064 -35.28949)
		(stroke
			(width 0.05715)
			(type default)
		)
		(layer "In4.Cu")
	)
	(gr_line
		(start 347.060774 -66.896996)
		(end 347.083888 -66.902584)
		(stroke
			(width 0.05715)
			(type default)
		)
		(layer "In4.Cu")
	)
	(gr_line
		(start 347.075506 -66.24447)
		(end 347.098366 -66.249804)
		(stroke
			(width 0.05715)
			(type default)
		)
		(layer "In4.Cu")
	)
	(gr_line
		(start 347.08338 -65.59296)
		(end 347.10624 -65.598294)
		(stroke
			(width 0.05715)
			(type default)
		)
		(layer "In4.Cu")
	)
	(gr_line
		(start 347.083888 -66.902584)
		(end 347.107764 -66.898012)
		(stroke
			(width 0.05715)
			(type default)
		)
		(layer "In4.Cu")
	)
	(gr_line
		(start 347.087698 -64.941704)
		(end 347.11132 -64.947292)
		(stroke
			(width 0.05715)
			(type default)
		)
		(layer "In4.Cu")
	)
	(gr_line
		(start 347.098366 -66.249804)
		(end 347.122242 -66.245232)
		(stroke
			(width 0.05715)
			(type default)
		)
		(layer "In4.Cu")
	)
	(gr_line
		(start 347.10624 -65.598294)
		(end 347.130116 -65.593722)
		(stroke
			(width 0.05715)
			(type default)
		)
		(layer "In4.Cu")
	)
	(gr_line
		(start 347.11132 -64.947292)
		(end 347.135196 -64.94272)
		(stroke
			(width 0.05715)
			(type default)
		)
		(layer "In4.Cu")
	)
	(gr_line
		(start 347.120718 -64.285368)
		(end 347.14434 -64.290956)
		(stroke
			(width 0.05715)
			(type default)
		)
		(layer "In4.Cu")
	)
	(gr_line
		(start 347.127322 -63.634112)
		(end 347.150944 -63.6397)
		(stroke
			(width 0.05715)
			(type default)
		)
		(layer "In4.Cu")
	)
	(gr_line
		(start 347.14434 -64.290956)
		(end 347.168216 -64.286384)
		(stroke
			(width 0.05715)
			(type default)
		)
		(layer "In4.Cu")
	)
	(gr_line
		(start 347.150944 -63.6397)
		(end 347.17482 -63.635128)
		(stroke
			(width 0.05715)
			(type default)
		)
		(layer "In4.Cu")
	)
	(gr_line
		(start 347.151452 -62.9793)
		(end 347.175074 -62.984888)
		(stroke
			(width 0.05715)
			(type default)
		)
		(layer "In4.Cu")
	)
	(gr_line
		(start 347.158564 -62.328044)
		(end 347.182186 -62.333632)
		(stroke
			(width 0.05715)
			(type default)
		)
		(layer "In4.Cu")
	)
	(gr_line
		(start 347.175074 -62.984888)
		(end 347.19895 -62.980316)
		(stroke
			(width 0.05715)
			(type default)
		)
		(layer "In4.Cu")
	)
	(gr_line
		(start 347.182186 -62.333632)
		(end 347.206062 -62.32906)
		(stroke
			(width 0.05715)
			(type default)
		)
		(layer "In4.Cu")
	)
	(gr_line
		(start 347.231208 -61.511942)
		(end 347.254068 -61.517276)
		(stroke
			(width 0.05715)
			(type default)
		)
		(layer "In4.Cu")
	)
	(gr_line
		(start 347.254068 -61.517276)
		(end 347.277944 -61.512704)
		(stroke
			(width 0.05715)
			(type default)
		)
		(layer "In4.Cu")
	)
	(gr_line
		(start 347.404944 -54.261766)
		(end 347.449902 -54.229762)
		(stroke
			(width 0.05715)
			(type default)
		)
		(layer "In4.Cu")
	)
	(gr_line
		(start 347.452442 -55.851044)
		(end 347.4974 -55.81904)
		(stroke
			(width 0.05715)
			(type default)
		)
		(layer "In4.Cu")
	)
	(gr_line
		(start 347.622876 -54.896766)
		(end 347.667834 -54.864762)
		(stroke
			(width 0.05715)
			(type default)
		)
		(layer "In4.Cu")
	)
	(gr_line
		(start 347.74632 -56.498744)
		(end 347.790516 -56.467248)
		(stroke
			(width 0.05715)
			(type default)
		)
		(layer "In4.Cu")
	)
	(gr_line
		(start 347.830648 -75.351894)
		(end 347.856556 -75.325986)
		(stroke
			(width 0.05715)
			(type default)
		)
		(layer "In4.Cu")
	)
	(gr_line
		(start 347.856556 -75.325986)
		(end 347.891354 -75.315318)
		(stroke
			(width 0.05715)
			(type default)
		)
		(layer "In4.Cu")
	)
	(gr_line
		(start 348.25686 -81.07553)
		(end 348.53118 -80.80121)
		(stroke
			(width 0.05715)
			(type default)
		)
		(layer "In4.Cu")
	)
	(gr_line
		(start 348.25686 -80.11033)
		(end 348.53118 -80.38465)
		(stroke
			(width 0.05715)
			(type default)
		)
		(layer "In4.Cu")
	)
	(gr_line
		(start 348.495112 -116.36375)
		(end 348.867984 -116.36375)
		(stroke
			(width 0.05715)
			(type default)
		)
		(layer "In4.Cu")
	)
	(gr_line
		(start 348.577154 -57.134506)
		(end 348.58579 -57.131712)
		(stroke
			(width 0.05715)
			(type default)
		)
		(layer "In4.Cu")
	)
	(gr_line
		(start 348.59341 -66.311526)
		(end 348.617286 -66.306954)
		(stroke
			(width 0.05715)
			(type default)
		)
		(layer "In4.Cu")
	)
	(gr_line
		(start 348.601284 -65.660016)
		(end 348.62516 -65.655444)
		(stroke
			(width 0.05715)
			(type default)
		)
		(layer "In4.Cu")
	)
	(gr_line
		(start 348.609158 -65.008506)
		(end 348.633034 -65.003934)
		(stroke
			(width 0.05715)
			(type default)
		)
		(layer "In4.Cu")
	)
	(gr_line
		(start 348.617032 -64.356996)
		(end 348.640908 -64.352424)
		(stroke
			(width 0.05715)
			(type default)
		)
		(layer "In4.Cu")
	)
	(gr_line
		(start 348.617286 -66.306954)
		(end 348.6404 -66.312542)
		(stroke
			(width 0.05715)
			(type default)
		)
		(layer "In4.Cu")
	)
	(gr_line
		(start 348.624906 -63.705486)
		(end 348.648782 -63.700914)
		(stroke
			(width 0.05715)
			(type default)
		)
		(layer "In4.Cu")
	)
	(gr_line
		(start 348.62516 -65.655444)
		(end 348.648274 -65.661032)
		(stroke
			(width 0.05715)
			(type default)
		)
		(layer "In4.Cu")
	)
	(gr_line
		(start 348.63278 -63.053976)
		(end 348.656656 -63.049404)
		(stroke
			(width 0.05715)
			(type default)
		)
		(layer "In4.Cu")
	)
	(gr_line
		(start 348.633034 -65.003934)
		(end 348.656148 -65.009522)
		(stroke
			(width 0.05715)
			(type default)
		)
		(layer "In4.Cu")
	)
	(gr_line
		(start 348.640654 -62.402466)
		(end 348.66453 -62.397894)
		(stroke
			(width 0.05715)
			(type default)
		)
		(layer "In4.Cu")
	)
	(gr_line
		(start 348.640908 -64.352424)
		(end 348.664022 -64.358012)
		(stroke
			(width 0.05715)
			(type default)
		)
		(layer "In4.Cu")
	)
	(gr_line
		(start 348.648528 -61.750956)
		(end 348.672404 -61.746384)
		(stroke
			(width 0.05715)
			(type default)
		)
		(layer "In4.Cu")
	)
	(gr_line
		(start 348.648782 -63.700914)
		(end 348.671896 -63.706502)
		(stroke
			(width 0.05715)
			(type default)
		)
		(layer "In4.Cu")
	)
	(gr_line
		(start 348.656656 -63.049404)
		(end 348.67977 -63.054992)
		(stroke
			(width 0.05715)
			(type default)
		)
		(layer "In4.Cu")
	)
	(gr_line
		(start 348.663514 -60.945522)
		(end 348.68739 -60.94095)
		(stroke
			(width 0.05715)
			(type default)
		)
		(layer "In4.Cu")
	)
	(gr_line
		(start 348.66453 -62.397894)
		(end 348.687644 -62.403482)
		(stroke
			(width 0.05715)
			(type default)
		)
		(layer "In4.Cu")
	)
	(gr_line
		(start 348.672404 -61.746384)
		(end 348.695518 -61.751972)
		(stroke
			(width 0.05715)
			(type default)
		)
		(layer "In4.Cu")
	)
	(gr_line
		(start 348.678246 -57.770522)
		(end 348.686882 -57.767728)
		(stroke
			(width 0.05715)
			(type default)
		)
		(layer "In4.Cu")
	)
	(gr_line
		(start 348.68739 -60.94095)
		(end 348.710504 -60.946538)
		(stroke
			(width 0.05715)
			(type default)
		)
		(layer "In4.Cu")
	)
	(gr_line
		(start 348.776544 -58.436256)
		(end 348.78518 -58.433462)
		(stroke
			(width 0.05715)
			(type default)
		)
		(layer "In4.Cu")
	)
	(gr_line
		(start 348.867984 -116.36375)
		(end 348.912688 -116.319046)
		(stroke
			(width 0.05715)
			(type default)
		)
		(layer "In4.Cu")
	)
	(gr_line
		(start 349.34398 -116.319046)
		(end 349.388684 -116.36375)
		(stroke
			(width 0.05715)
			(type default)
		)
		(layer "In4.Cu")
	)
	(gr_line
		(start 349.388684 -116.36375)
		(end 349.765112 -116.36375)
		(stroke
			(width 0.05715)
			(type default)
		)
		(layer "In4.Cu")
	)
	(gr_line
		(start 349.784416 -76.083668)
		(end 349.841566 -76.02601)
		(stroke
			(width 0.05715)
			(type default)
		)
		(layer "In4.Cu")
	)
	(gr_line
		(start 349.853758 -66.896488)
		(end 349.879158 -66.90233)
		(stroke
			(width 0.05715)
			(type default)
		)
		(layer "In4.Cu")
	)
	(gr_line
		(start 349.865442 -66.244724)
		(end 349.888556 -66.250312)
		(stroke
			(width 0.05715)
			(type default)
		)
		(layer "In4.Cu")
	)
	(gr_line
		(start 349.871792 -65.593468)
		(end 349.894906 -65.599056)
		(stroke
			(width 0.05715)
			(type default)
		)
		(layer "In4.Cu")
	)
	(gr_line
		(start 349.879158 -66.90233)
		(end 349.904304 -66.89725)
		(stroke
			(width 0.05715)
			(type default)
		)
		(layer "In4.Cu")
	)
	(gr_line
		(start 349.879666 -64.941958)
		(end 349.90278 -64.947546)
		(stroke
			(width 0.05715)
			(type default)
		)
		(layer "In4.Cu")
	)
	(gr_line
		(start 349.88754 -64.290448)
		(end 349.910654 -64.296036)
		(stroke
			(width 0.05715)
			(type default)
		)
		(layer "In4.Cu")
	)
	(gr_line
		(start 349.888556 -66.250312)
		(end 349.912178 -66.24574)
		(stroke
			(width 0.05715)
			(type default)
		)
		(layer "In4.Cu")
	)
	(gr_line
		(start 349.894906 -65.599056)
		(end 349.918528 -65.594484)
		(stroke
			(width 0.05715)
			(type default)
		)
		(layer "In4.Cu")
	)
	(gr_line
		(start 349.895414 -63.638938)
		(end 349.918528 -63.644526)
		(stroke
			(width 0.05715)
			(type default)
		)
		(layer "In4.Cu")
	)
	(gr_line
		(start 349.90278 -64.947546)
		(end 349.926402 -64.942974)
		(stroke
			(width 0.05715)
			(type default)
		)
		(layer "In4.Cu")
	)
	(gr_line
		(start 349.903288 -62.987428)
		(end 349.926402 -62.993016)
		(stroke
			(width 0.05715)
			(type default)
		)
		(layer "In4.Cu")
	)
	(gr_line
		(start 349.910654 -64.296036)
		(end 349.934276 -64.291464)
		(stroke
			(width 0.05715)
			(type default)
		)
		(layer "In4.Cu")
	)
	(gr_line
		(start 349.911162 -62.335918)
		(end 349.934276 -62.341506)
		(stroke
			(width 0.05715)
			(type default)
		)
		(layer "In4.Cu")
	)
	(gr_line
		(start 349.918528 -63.644526)
		(end 349.94215 -63.639954)
		(stroke
			(width 0.05715)
			(type default)
		)
		(layer "In4.Cu")
	)
	(gr_line
		(start 349.923608 -61.53023)
		(end 349.949008 -61.536072)
		(stroke
			(width 0.05715)
			(type default)
		)
		(layer "In4.Cu")
	)
	(gr_line
		(start 349.926402 -62.993016)
		(end 349.950024 -62.988444)
		(stroke
			(width 0.05715)
			(type default)
		)
		(layer "In4.Cu")
	)
	(gr_line
		(start 349.934276 -62.341506)
		(end 349.957898 -62.336934)
		(stroke
			(width 0.05715)
			(type default)
		)
		(layer "In4.Cu")
	)
	(gr_line
		(start 349.949008 -61.536072)
		(end 349.974154 -61.530992)
		(stroke
			(width 0.05715)
			(type default)
		)
		(layer "In4.Cu")
	)
	(gr_line
		(start 350.290892 -75.571096)
		(end 350.300036 -75.561698)
		(stroke
			(width 0.05715)
			(type default)
		)
		(layer "In4.Cu")
	)
	(gr_line
		(start 350.300036 -75.561698)
		(end 350.312736 -75.555602)
		(stroke
			(width 0.05715)
			(type default)
		)
		(layer "In4.Cu")
	)
	(gr_line
		(start 350.741996 -66.435986)
		(end 350.761554 -66.432176)
		(stroke
			(width 0.05715)
			(type default)
		)
		(layer "In4.Cu")
	)
	(gr_line
		(start 350.749616 -81.215738)
		(end 351.023936 -80.941418)
		(stroke
			(width 0.05715)
			(type default)
		)
		(layer "In4.Cu")
	)
	(gr_line
		(start 350.749616 -80.250538)
		(end 351.023936 -80.524858)
		(stroke
			(width 0.05715)
			(type default)
		)
		(layer "In4.Cu")
	)
	(gr_line
		(start 350.754696 -65.783714)
		(end 350.774254 -65.779904)
		(stroke
			(width 0.05715)
			(type default)
		)
		(layer "In4.Cu")
	)
	(gr_line
		(start 350.761554 -66.432176)
		(end 350.781874 -66.43624)
		(stroke
			(width 0.05715)
			(type default)
		)
		(layer "In4.Cu")
	)
	(gr_line
		(start 350.769936 -56.398668)
		(end 350.775778 -56.396636)
		(stroke
			(width 0.05715)
			(type default)
		)
		(layer "In4.Cu")
	)
	(gr_line
		(start 350.774254 -65.779904)
		(end 350.794574 -65.783968)
		(stroke
			(width 0.05715)
			(type default)
		)
		(layer "In4.Cu")
	)
	(gr_line
		(start 350.775778 -56.396636)
		(end 350.780858 -56.39308)
		(stroke
			(width 0.05715)
			(type default)
		)
		(layer "In4.Cu")
	)
	(gr_line
		(start 350.78035 -72.808338)
		(end 350.814894 -72.79767)
		(stroke
			(width 0.05715)
			(type default)
		)
		(layer "In4.Cu")
	)
	(gr_line
		(start 350.814386 -73.475342)
		(end 350.84893 -73.464674)
		(stroke
			(width 0.05715)
			(type default)
		)
		(layer "In4.Cu")
	)
	(gr_line
		(start 350.814894 -72.79767)
		(end 350.850454 -72.804782)
		(stroke
			(width 0.05715)
			(type default)
		)
		(layer "In4.Cu")
	)
	(gr_line
		(start 350.825308 -65.120012)
		(end 350.844866 -65.116202)
		(stroke
			(width 0.05715)
			(type default)
		)
		(layer "In4.Cu")
	)
	(gr_line
		(start 350.844866 -65.116202)
		(end 350.865186 -65.120266)
		(stroke
			(width 0.05715)
			(type default)
		)
		(layer "In4.Cu")
	)
	(gr_line
		(start 350.84893 -73.464674)
		(end 350.88449 -73.471786)
		(stroke
			(width 0.05715)
			(type default)
		)
		(layer "In4.Cu")
	)
	(gr_line
		(start 350.908112 -63.803784)
		(end 350.92767 -63.799974)
		(stroke
			(width 0.05715)
			(type default)
		)
		(layer "In4.Cu")
	)
	(gr_line
		(start 350.90989 -64.453262)
		(end 350.929448 -64.449452)
		(stroke
			(width 0.05715)
			(type default)
		)
		(layer "In4.Cu")
	)
	(gr_line
		(start 350.92767 -63.799974)
		(end 350.94799 -63.804038)
		(stroke
			(width 0.05715)
			(type default)
		)
		(layer "In4.Cu")
	)
	(gr_line
		(start 350.929448 -64.449452)
		(end 350.949768 -64.453516)
		(stroke
			(width 0.05715)
			(type default)
		)
		(layer "In4.Cu")
	)
	(gr_line
		(start 351.199958 -53.697632)
		(end 351.219516 -53.683916)
		(stroke
			(width 0.05715)
			(type default)
		)
		(layer "In4.Cu")
	)
	(gr_line
		(start 351.219516 -53.683916)
		(end 351.242122 -53.679598)
		(stroke
			(width 0.05715)
			(type default)
		)
		(layer "In4.Cu")
	)
	(gr_line
		(start 351.384108 -74.24801)
		(end 351.418652 -74.237342)
		(stroke
			(width 0.05715)
			(type default)
		)
		(layer "In4.Cu")
	)
	(gr_line
		(start 351.418652 -74.237342)
		(end 351.454212 -74.244454)
		(stroke
			(width 0.05715)
			(type default)
		)
		(layer "In4.Cu")
	)
	(gr_line
		(start 351.432114 -51.037236)
		(end 351.442782 -51.029616)
		(stroke
			(width 0.05715)
			(type default)
		)
		(layer "In4.Cu")
	)
	(gr_line
		(start 351.437448 -63.05042)
		(end 351.461324 -63.045848)
		(stroke
			(width 0.05715)
			(type default)
		)
		(layer "In4.Cu")
	)
	(gr_line
		(start 351.442782 -51.029616)
		(end 351.455482 -51.02606)
		(stroke
			(width 0.05715)
			(type default)
		)
		(layer "In4.Cu")
	)
	(gr_line
		(start 351.445322 -62.39891)
		(end 351.469198 -62.394338)
		(stroke
			(width 0.05715)
			(type default)
		)
		(layer "In4.Cu")
	)
	(gr_line
		(start 351.453196 -61.7474)
		(end 351.477072 -61.742828)
		(stroke
			(width 0.05715)
			(type default)
		)
		(layer "In4.Cu")
	)
	(gr_line
		(start 351.461324 -63.045848)
		(end 351.48393 -63.051182)
		(stroke
			(width 0.05715)
			(type default)
		)
		(layer "In4.Cu")
	)
	(gr_line
		(start 351.46742 -60.941712)
		(end 351.491042 -60.93714)
		(stroke
			(width 0.05715)
			(type default)
		)
		(layer "In4.Cu")
	)
	(gr_line
		(start 351.469198 -62.394338)
		(end 351.492058 -62.399672)
		(stroke
			(width 0.05715)
			(type default)
		)
		(layer "In4.Cu")
	)
	(gr_line
		(start 351.477072 -61.742828)
		(end 351.499932 -61.748162)
		(stroke
			(width 0.05715)
			(type default)
		)
		(layer "In4.Cu")
	)
	(gr_line
		(start 351.491042 -60.93714)
		(end 351.514156 -60.942728)
		(stroke
			(width 0.05715)
			(type default)
		)
		(layer "In4.Cu")
	)
	(gr_line
		(start 351.578164 -51.721766)
		(end 351.588578 -51.7144)
		(stroke
			(width 0.05715)
			(type default)
		)
		(layer "In4.Cu")
	)
	(gr_line
		(start 351.588578 -51.7144)
		(end 351.60077 -51.711098)
		(stroke
			(width 0.05715)
			(type default)
		)
		(layer "In4.Cu")
	)
	(gr_line
		(start 351.750884 -52.43195)
		(end 351.759774 -52.4256)
		(stroke
			(width 0.05715)
			(type default)
		)
		(layer "In4.Cu")
	)
	(gr_line
		(start 351.759774 -52.4256)
		(end 351.76968 -52.422806)
		(stroke
			(width 0.05715)
			(type default)
		)
		(layer "In4.Cu")
	)
	(gr_line
		(start 351.843848 -37.61105)
		(end 351.861628 -37.603684)
		(stroke
			(width 0.05715)
			(type default)
		)
		(layer "In4.Cu")
	)
	(gr_line
		(start 351.951036 -40.15105)
		(end 351.973388 -40.141144)
		(stroke
			(width 0.05715)
			(type default)
		)
		(layer "In4.Cu")
	)
	(gr_line
		(start 352.03003 -38.88105)
		(end 352.04781 -38.873684)
		(stroke
			(width 0.05715)
			(type default)
		)
		(layer "In4.Cu")
	)
	(gr_line
		(start 352.244406 -75.068684)
		(end 352.264218 -75.06462)
		(stroke
			(width 0.05715)
			(type default)
		)
		(layer "In4.Cu")
	)
	(gr_line
		(start 352.259138 -40.013128)
		(end 352.290634 -39.998904)
		(stroke
			(width 0.05715)
			(type default)
		)
		(layer "In4.Cu")
	)
	(gr_line
		(start 352.264218 -75.06462)
		(end 352.28403 -75.068684)
		(stroke
			(width 0.05715)
			(type default)
		)
		(layer "In4.Cu")
	)
	(gr_line
		(start 352.280728 -38.777164)
		(end 352.316288 -38.762686)
		(stroke
			(width 0.05715)
			(type default)
		)
		(layer "In4.Cu")
	)
	(gr_line
		(start 352.290634 -39.998904)
		(end 352.311716 -39.972488)
		(stroke
			(width 0.05715)
			(type default)
		)
		(layer "In4.Cu")
	)
	(gr_line
		(start 352.316288 -38.762686)
		(end 352.340418 -38.731952)
		(stroke
			(width 0.05715)
			(type default)
		)
		(layer "In4.Cu")
	)
	(gr_line
		(start 352.352356 -37.400738)
		(end 352.389186 -37.385752)
		(stroke
			(width 0.05715)
			(type default)
		)
		(layer "In4.Cu")
	)
	(gr_line
		(start 352.389186 -37.385752)
		(end 352.413824 -37.353748)
		(stroke
			(width 0.05715)
			(type default)
		)
		(layer "In4.Cu")
	)
	(gr_line
		(start 352.748342 -61.53023)
		(end 352.77298 -61.536072)
		(stroke
			(width 0.05715)
			(type default)
		)
		(layer "In4.Cu")
	)
	(gr_line
		(start 352.77298 -61.536072)
		(end 352.797872 -61.530992)
		(stroke
			(width 0.05715)
			(type default)
		)
		(layer "In4.Cu")
	)
	(gr_line
		(start 352.80346 -75.468988)
		(end 352.823272 -75.473052)
		(stroke
			(width 0.05715)
			(type default)
		)
		(layer "In4.Cu")
	)
	(gr_line
		(start 352.80346 -74.808588)
		(end 352.823272 -74.812652)
		(stroke
			(width 0.05715)
			(type default)
		)
		(layer "In4.Cu")
	)
	(gr_line
		(start 352.80346 -74.148188)
		(end 352.823272 -74.152252)
		(stroke
			(width 0.05715)
			(type default)
		)
		(layer "In4.Cu")
	)
	(gr_line
		(start 352.80346 -73.487788)
		(end 352.823272 -73.491852)
		(stroke
			(width 0.05715)
			(type default)
		)
		(layer "In4.Cu")
	)
	(gr_line
		(start 352.823272 -75.473052)
		(end 352.843084 -75.468988)
		(stroke
			(width 0.05715)
			(type default)
		)
		(layer "In4.Cu")
	)
	(gr_line
		(start 352.823272 -74.812652)
		(end 352.843084 -74.808588)
		(stroke
			(width 0.05715)
			(type default)
		)
		(layer "In4.Cu")
	)
	(gr_line
		(start 352.823272 -74.152252)
		(end 352.843084 -74.148188)
		(stroke
			(width 0.05715)
			(type default)
		)
		(layer "In4.Cu")
	)
	(gr_line
		(start 352.823272 -73.491852)
		(end 352.843084 -73.487788)
		(stroke
			(width 0.05715)
			(type default)
		)
		(layer "In4.Cu")
	)
	(gr_line
		(start 352.895408 -36.257992)
		(end 352.901504 -36.249864)
		(stroke
			(width 0.05715)
			(type default)
		)
		(layer "In4.Cu")
	)
	(gr_line
		(start 352.901504 -36.249864)
		(end 352.910648 -36.243768)
		(stroke
			(width 0.05715)
			(type default)
		)
		(layer "In4.Cu")
	)
	(gr_line
		(start 353.001834 -75.895962)
		(end 353.036886 -75.885548)
		(stroke
			(width 0.05715)
			(type default)
		)
		(layer "In4.Cu")
	)
	(gr_line
		(start 353.187254 -36.05657)
		(end 353.232466 -35.830764)
		(stroke
			(width 0.05715)
			(type default)
		)
		(layer "In4.Cu")
	)
	(gr_line
		(start 353.232466 -35.830764)
		(end 353.517962 -35.640518)
		(stroke
			(width 0.05715)
			(type default)
		)
		(layer "In4.Cu")
	)
	(gr_line
		(start 353.265994 -41.3639)
		(end 353.30511 -41.339262)
		(stroke
			(width 0.05715)
			(type default)
		)
		(layer "In4.Cu")
	)
	(gr_line
		(start 353.301808 -75.080622)
		(end 353.32162 -75.076558)
		(stroke
			(width 0.05715)
			(type default)
		)
		(layer "In4.Cu")
	)
	(gr_line
		(start 353.301808 -74.420222)
		(end 353.32162 -74.416158)
		(stroke
			(width 0.05715)
			(type default)
		)
		(layer "In4.Cu")
	)
	(gr_line
		(start 353.31654 -73.757028)
		(end 353.336352 -73.752964)
		(stroke
			(width 0.05715)
			(type default)
		)
		(layer "In4.Cu")
	)
	(gr_line
		(start 353.31654 -73.096628)
		(end 353.336352 -73.092564)
		(stroke
			(width 0.05715)
			(type default)
		)
		(layer "In4.Cu")
	)
	(gr_line
		(start 353.32162 -75.076558)
		(end 353.341432 -75.080622)
		(stroke
			(width 0.05715)
			(type default)
		)
		(layer "In4.Cu")
	)
	(gr_line
		(start 353.32162 -74.416158)
		(end 353.341432 -74.420222)
		(stroke
			(width 0.05715)
			(type default)
		)
		(layer "In4.Cu")
	)
	(gr_line
		(start 353.336352 -73.752964)
		(end 353.356164 -73.757028)
		(stroke
			(width 0.05715)
			(type default)
		)
		(layer "In4.Cu")
	)
	(gr_line
		(start 353.336352 -73.092564)
		(end 353.356164 -73.096628)
		(stroke
			(width 0.05715)
			(type default)
		)
		(layer "In4.Cu")
	)
	(gr_line
		(start 353.351084 -80.868012)
		(end 353.625404 -81.142332)
		(stroke
			(width 0.05715)
			(type default)
		)
		(layer "In4.Cu")
	)
	(gr_line
		(start 353.351084 -80.451452)
		(end 353.625404 -80.177132)
		(stroke
			(width 0.05715)
			(type default)
		)
		(layer "In4.Cu")
	)
	(gr_line
		(start 353.379024 -36.282884)
		(end 353.878896 -35.949636)
		(stroke
			(width 0.05715)
			(type default)
		)
		(layer "In4.Cu")
	)
	(gr_line
		(start 353.417886 -75.772518)
		(end 353.451414 -75.762612)
		(stroke
			(width 0.05715)
			(type default)
		)
		(layer "In4.Cu")
	)
	(gr_line
		(start 353.451414 -75.762612)
		(end 353.485196 -75.76947)
		(stroke
			(width 0.05715)
			(type default)
		)
		(layer "In4.Cu")
	)
	(gr_line
		(start 353.517962 -35.640518)
		(end 353.743768 -35.68573)
		(stroke
			(width 0.05715)
			(type default)
		)
		(layer "In4.Cu")
	)
	(gr_line
		(start 353.614736 -116.668042)
		(end 353.630738 -116.698268)
		(stroke
			(width 0.05715)
			(type default)
		)
		(layer "In4.Cu")
	)
	(gr_line
		(start 353.701858 -41.088818)
		(end 353.722178 -41.075864)
		(stroke
			(width 0.05715)
			(type default)
		)
		(layer "In4.Cu")
	)
	(gr_line
		(start 353.722178 -41.075864)
		(end 353.735386 -41.055798)
		(stroke
			(width 0.05715)
			(type default)
		)
		(layer "In4.Cu")
	)
	(gr_line
		(start 353.746054 -36.486338)
		(end 353.752404 -36.478464)
		(stroke
			(width 0.05715)
			(type default)
		)
		(layer "In4.Cu")
	)
	(gr_line
		(start 353.752404 -36.478464)
		(end 353.760786 -36.472876)
		(stroke
			(width 0.05715)
			(type default)
		)
		(layer "In4.Cu")
	)
	(gr_line
		(start 353.777296 -75.464416)
		(end 353.797108 -75.46848)
		(stroke
			(width 0.05715)
			(type default)
		)
		(layer "In4.Cu")
	)
	(gr_line
		(start 353.777296 -74.804016)
		(end 353.797108 -74.80808)
		(stroke
			(width 0.05715)
			(type default)
		)
		(layer "In4.Cu")
	)
	(gr_line
		(start 353.793044 -73.480422)
		(end 353.812856 -73.484486)
		(stroke
			(width 0.05715)
			(type default)
		)
		(layer "In4.Cu")
	)
	(gr_line
		(start 353.793552 -74.140822)
		(end 353.813364 -74.144886)
		(stroke
			(width 0.05715)
			(type default)
		)
		(layer "In4.Cu")
	)
	(gr_line
		(start 353.79406 -74.141076)
		(end 353.813364 -74.144886)
		(stroke
			(width 0.05715)
			(type default)
		)
		(layer "In4.Cu")
	)
	(gr_line
		(start 353.797108 -75.46848)
		(end 353.81692 -75.464416)
		(stroke
			(width 0.05715)
			(type default)
		)
		(layer "In4.Cu")
	)
	(gr_line
		(start 353.797108 -74.80808)
		(end 353.81692 -74.804016)
		(stroke
			(width 0.05715)
			(type default)
		)
		(layer "In4.Cu")
	)
	(gr_line
		(start 353.800156 -76.129388)
		(end 353.819968 -76.133452)
		(stroke
			(width 0.05715)
			(type default)
		)
		(layer "In4.Cu")
	)
	(gr_line
		(start 353.804982 -62.585346)
		(end 353.830128 -62.591188)
		(stroke
			(width 0.05715)
			(type default)
		)
		(layer "In4.Cu")
	)
	(gr_line
		(start 353.812856 -73.484486)
		(end 353.832668 -73.480422)
		(stroke
			(width 0.05715)
			(type default)
		)
		(layer "In4.Cu")
	)
	(gr_line
		(start 353.813364 -74.144886)
		(end 353.83343 -74.140822)
		(stroke
			(width 0.05715)
			(type default)
		)
		(layer "In4.Cu")
	)
	(gr_line
		(start 353.819968 -76.133452)
		(end 353.83978 -76.129388)
		(stroke
			(width 0.05715)
			(type default)
		)
		(layer "In4.Cu")
	)
	(gr_line
		(start 353.830128 -62.591188)
		(end 353.854766 -62.586108)
		(stroke
			(width 0.05715)
			(type default)
		)
		(layer "In4.Cu")
	)
	(gr_line
		(start 353.854258 -53.860954)
		(end 353.873816 -53.847238)
		(stroke
			(width 0.05715)
			(type default)
		)
		(layer "In4.Cu")
	)
	(gr_line
		(start 353.861624 -40.86733)
		(end 353.865942 -40.845994)
		(stroke
			(width 0.05715)
			(type default)
		)
		(layer "In4.Cu")
	)
	(gr_line
		(start 353.873816 -53.847238)
		(end 353.896422 -53.84292)
		(stroke
			(width 0.05715)
			(type default)
		)
		(layer "In4.Cu")
	)
	(gr_line
		(start 353.958398 -63.274448)
		(end 353.983544 -63.28029)
		(stroke
			(width 0.05715)
			(type default)
		)
		(layer "In4.Cu")
	)
	(gr_line
		(start 353.96551 -63.930022)
		(end 353.990148 -63.935864)
		(stroke
			(width 0.05715)
			(type default)
		)
		(layer "In4.Cu")
	)
	(gr_line
		(start 353.983544 -63.28029)
		(end 354.008182 -63.27521)
		(stroke
			(width 0.05715)
			(type default)
		)
		(layer "In4.Cu")
	)
	(gr_line
		(start 353.990148 -63.935864)
		(end 354.014786 -63.930784)
		(stroke
			(width 0.05715)
			(type default)
		)
		(layer "In4.Cu")
	)
	(gr_line
		(start 354.011484 -38.626796)
		(end 354.017834 -38.59403)
		(stroke
			(width 0.05715)
			(type default)
		)
		(layer "In4.Cu")
	)
	(gr_line
		(start 354.017834 -38.59403)
		(end 354.03917 -38.567106)
		(stroke
			(width 0.05715)
			(type default)
		)
		(layer "In4.Cu")
	)
	(gr_line
		(start 354.196142 -60.953142)
		(end 354.215192 -60.949332)
		(stroke
			(width 0.05715)
			(type default)
		)
		(layer "In4.Cu")
	)
	(gr_line
		(start 354.21316 -123.084336)
		(end 354.22459 -123.035822)
		(stroke
			(width 0.05715)
			(type default)
		)
		(layer "In4.Cu")
	)
	(gr_line
		(start 354.21316 -123.084336)
		(end 354.23094 -123.13158)
		(stroke
			(width 0.05715)
			(type default)
		)
		(layer "In4.Cu")
	)
	(gr_line
		(start 354.215192 -60.949332)
		(end 354.234242 -60.953142)
		(stroke
			(width 0.05715)
			(type default)
		)
		(layer "In4.Cu")
	)
	(gr_line
		(start 354.250244 -53.772308)
		(end 354.273612 -53.767482)
		(stroke
			(width 0.05715)
			(type default)
		)
		(layer "In4.Cu")
	)
	(gr_line
		(start 354.273612 -53.767482)
		(end 354.297234 -53.772816)
		(stroke
			(width 0.05715)
			(type default)
		)
		(layer "In4.Cu")
	)
	(gr_line
		(start 354.275898 -75.07605)
		(end 354.29571 -75.071986)
		(stroke
			(width 0.05715)
			(type default)
		)
		(layer "In4.Cu")
	)
	(gr_line
		(start 354.275898 -74.41565)
		(end 354.29571 -74.411586)
		(stroke
			(width 0.05715)
			(type default)
		)
		(layer "In4.Cu")
	)
	(gr_line
		(start 354.275898 -73.755504)
		(end 354.29571 -73.75144)
		(stroke
			(width 0.05715)
			(type default)
		)
		(layer "In4.Cu")
	)
	(gr_line
		(start 354.275898 -73.095104)
		(end 354.29571 -73.09104)
		(stroke
			(width 0.05715)
			(type default)
		)
		(layer "In4.Cu")
	)
	(gr_line
		(start 354.29571 -75.071986)
		(end 354.315268 -75.07605)
		(stroke
			(width 0.05715)
			(type default)
		)
		(layer "In4.Cu")
	)
	(gr_line
		(start 354.29571 -74.411586)
		(end 354.315268 -74.41565)
		(stroke
			(width 0.05715)
			(type default)
		)
		(layer "In4.Cu")
	)
	(gr_line
		(start 354.29571 -73.75144)
		(end 354.315268 -73.755504)
		(stroke
			(width 0.05715)
			(type default)
		)
		(layer "In4.Cu")
	)
	(gr_line
		(start 354.29571 -73.09104)
		(end 354.315268 -73.095104)
		(stroke
			(width 0.05715)
			(type default)
		)
		(layer "In4.Cu")
	)
	(gr_line
		(start 354.298504 -75.741022)
		(end 354.318316 -75.736958)
		(stroke
			(width 0.05715)
			(type default)
		)
		(layer "In4.Cu")
	)
	(gr_line
		(start 354.318316 -75.736958)
		(end 354.338128 -75.741022)
		(stroke
			(width 0.05715)
			(type default)
		)
		(layer "In4.Cu")
	)
	(gr_line
		(start 354.37318 -115.93703)
		(end 354.42525 -115.9891)
		(stroke
			(width 0.05715)
			(type default)
		)
		(layer "In4.Cu")
	)
	(gr_line
		(start 354.37318 -115.520216)
		(end 354.42525 -115.468146)
		(stroke
			(width 0.05715)
			(type default)
		)
		(layer "In4.Cu")
	)
	(gr_line
		(start 354.389944 -53.049932)
		(end 354.408994 -53.046122)
		(stroke
			(width 0.05715)
			(type default)
		)
		(layer "In4.Cu")
	)
	(gr_line
		(start 354.408994 -53.046122)
		(end 354.428552 -53.050186)
		(stroke
			(width 0.05715)
			(type default)
		)
		(layer "In4.Cu")
	)
	(gr_line
		(start 354.42525 -115.9891)
		(end 354.42525 -116.220494)
		(stroke
			(width 0.05715)
			(type default)
		)
		(layer "In4.Cu")
	)
	(gr_line
		(start 354.42525 -115.204494)
		(end 354.42525 -115.468146)
		(stroke
			(width 0.05715)
			(type default)
		)
		(layer "In4.Cu")
	)
	(gr_line
		(start 354.506022 -36.746688)
		(end 354.510848 -36.740846)
		(stroke
			(width 0.05715)
			(type default)
		)
		(layer "In4.Cu")
	)
	(gr_line
		(start 354.510848 -36.740846)
		(end 354.516436 -36.73729)
		(stroke
			(width 0.05715)
			(type default)
		)
		(layer "In4.Cu")
	)
	(gr_line
		(start 354.607876 -117.920262)
		(end 354.608638 -117.921786)
		(stroke
			(width 0.05715)
			(type default)
		)
		(layer "In4.Cu")
	)
	(gr_line
		(start 354.608638 -117.921786)
		(end 354.609146 -117.923818)
		(stroke
			(width 0.05715)
			(type default)
		)
		(layer "In4.Cu")
	)
	(gr_line
		(start 354.64496 -33.86201)
		(end 354.666804 -33.857946)
		(stroke
			(width 0.05715)
			(type default)
		)
		(layer "In4.Cu")
	)
	(gr_line
		(start 354.666804 -33.857946)
		(end 354.685346 -33.845754)
		(stroke
			(width 0.05715)
			(type default)
		)
		(layer "In4.Cu")
	)
	(gr_line
		(start 354.796852 -76.129388)
		(end 354.816664 -76.133452)
		(stroke
			(width 0.05715)
			(type default)
		)
		(layer "In4.Cu")
	)
	(gr_line
		(start 354.796852 -75.468988)
		(end 354.816664 -75.473052)
		(stroke
			(width 0.05715)
			(type default)
		)
		(layer "In4.Cu")
	)
	(gr_line
		(start 354.796852 -74.808588)
		(end 354.816664 -74.812652)
		(stroke
			(width 0.05715)
			(type default)
		)
		(layer "In4.Cu")
	)
	(gr_line
		(start 354.796852 -74.148442)
		(end 354.816664 -74.152506)
		(stroke
			(width 0.05715)
			(type default)
		)
		(layer "In4.Cu")
	)
	(gr_line
		(start 354.796852 -73.488042)
		(end 354.816664 -73.492106)
		(stroke
			(width 0.05715)
			(type default)
		)
		(layer "In4.Cu")
	)
	(gr_line
		(start 354.797106 -74.148442)
		(end 354.816664 -74.152506)
		(stroke
			(width 0.05715)
			(type default)
		)
		(layer "In4.Cu")
	)
	(gr_line
		(start 354.797106 -73.488042)
		(end 354.816664 -73.492106)
		(stroke
			(width 0.05715)
			(type default)
		)
		(layer "In4.Cu")
	)
	(gr_line
		(start 354.816664 -76.133452)
		(end 354.836476 -76.129388)
		(stroke
			(width 0.05715)
			(type default)
		)
		(layer "In4.Cu")
	)
	(gr_line
		(start 354.816664 -75.473052)
		(end 354.836476 -75.468988)
		(stroke
			(width 0.05715)
			(type default)
		)
		(layer "In4.Cu")
	)
	(gr_line
		(start 354.816664 -74.812652)
		(end 354.836476 -74.808588)
		(stroke
			(width 0.05715)
			(type default)
		)
		(layer "In4.Cu")
	)
	(gr_line
		(start 354.816664 -74.152506)
		(end 354.836476 -74.148442)
		(stroke
			(width 0.05715)
			(type default)
		)
		(layer "In4.Cu")
	)
	(gr_line
		(start 354.816664 -73.492106)
		(end 354.836476 -73.488042)
		(stroke
			(width 0.05715)
			(type default)
		)
		(layer "In4.Cu")
	)
	(gr_line
		(start 354.889054 -61.381894)
		(end 354.908104 -61.385704)
		(stroke
			(width 0.05715)
			(type default)
		)
		(layer "In4.Cu")
	)
	(gr_line
		(start 354.894896 -34.473896)
		(end 354.918264 -34.469578)
		(stroke
			(width 0.05715)
			(type default)
		)
		(layer "In4.Cu")
	)
	(gr_line
		(start 354.908104 -61.385704)
		(end 354.927662 -61.38164)
		(stroke
			(width 0.05715)
			(type default)
		)
		(layer "In4.Cu")
	)
	(gr_line
		(start 354.918264 -34.469578)
		(end 354.93833 -34.45637)
		(stroke
			(width 0.05715)
			(type default)
		)
		(layer "In4.Cu")
	)
	(gr_line
		(start 355.13772 -120.38584)
		(end 355.14407 -120.358662)
		(stroke
			(width 0.05715)
			(type default)
		)
		(layer "In4.Cu")
	)
	(gr_line
		(start 355.138228 -120.331738)
		(end 355.14407 -120.358662)
		(stroke
			(width 0.05715)
			(type default)
		)
		(layer "In4.Cu")
	)
	(gr_line
		(start 355.194108 -62.318392)
		(end 355.209348 -62.315344)
		(stroke
			(width 0.05715)
			(type default)
		)
		(layer "In4.Cu")
	)
	(gr_line
		(start 355.209348 -62.315344)
		(end 355.222048 -62.307216)
		(stroke
			(width 0.05715)
			(type default)
		)
		(layer "In4.Cu")
	)
	(gr_line
		(start 355.241352 -37.056822)
		(end 355.24567 -37.051234)
		(stroke
			(width 0.05715)
			(type default)
		)
		(layer "In4.Cu")
	)
	(gr_line
		(start 355.24567 -37.051234)
		(end 355.251258 -37.047678)
		(stroke
			(width 0.05715)
			(type default)
		)
		(layer "In4.Cu")
	)
	(gr_line
		(start 355.2952 -75.741022)
		(end 355.315012 -75.736958)
		(stroke
			(width 0.05715)
			(type default)
		)
		(layer "In4.Cu")
	)
	(gr_line
		(start 355.2952 -75.080622)
		(end 355.315012 -75.076558)
		(stroke
			(width 0.05715)
			(type default)
		)
		(layer "In4.Cu")
	)
	(gr_line
		(start 355.2952 -74.420222)
		(end 355.315012 -74.416158)
		(stroke
			(width 0.05715)
			(type default)
		)
		(layer "In4.Cu")
	)
	(gr_line
		(start 355.2952 -73.760076)
		(end 355.315012 -73.756012)
		(stroke
			(width 0.05715)
			(type default)
		)
		(layer "In4.Cu")
	)
	(gr_line
		(start 355.2952 -73.09993)
		(end 355.315012 -73.095866)
		(stroke
			(width 0.05715)
			(type default)
		)
		(layer "In4.Cu")
	)
	(gr_line
		(start 355.303582 -61.306964)
		(end 355.323902 -61.3029)
		(stroke
			(width 0.05715)
			(type default)
		)
		(layer "In4.Cu")
	)
	(gr_line
		(start 355.315012 -75.736958)
		(end 355.334824 -75.741022)
		(stroke
			(width 0.05715)
			(type default)
		)
		(layer "In4.Cu")
	)
	(gr_line
		(start 355.315012 -75.076558)
		(end 355.33457 -75.080622)
		(stroke
			(width 0.05715)
			(type default)
		)
		(layer "In4.Cu")
	)
	(gr_line
		(start 355.315012 -74.416158)
		(end 355.33457 -74.420222)
		(stroke
			(width 0.05715)
			(type default)
		)
		(layer "In4.Cu")
	)
	(gr_line
		(start 355.315012 -73.756012)
		(end 355.33457 -73.760076)
		(stroke
			(width 0.05715)
			(type default)
		)
		(layer "In4.Cu")
	)
	(gr_line
		(start 355.315012 -73.095866)
		(end 355.334824 -73.09993)
		(stroke
			(width 0.05715)
			(type default)
		)
		(layer "In4.Cu")
	)
	(gr_line
		(start 355.323902 -61.3029)
		(end 355.341428 -61.291216)
		(stroke
			(width 0.05715)
			(type default)
		)
		(layer "In4.Cu")
	)
	(gr_line
		(start 355.365812 -64.984884)
		(end 355.384862 -64.988694)
		(stroke
			(width 0.05715)
			(type default)
		)
		(layer "In4.Cu")
	)
	(gr_line
		(start 355.384862 -64.988694)
		(end 355.403912 -64.984884)
		(stroke
			(width 0.05715)
			(type default)
		)
		(layer "In4.Cu")
	)
	(gr_line
		(start 355.404166 -66.326512)
		(end 355.423216 -66.330322)
		(stroke
			(width 0.05715)
			(type default)
		)
		(layer "In4.Cu")
	)
	(gr_line
		(start 355.420422 -65.645792)
		(end 355.439472 -65.649602)
		(stroke
			(width 0.05715)
			(type default)
		)
		(layer "In4.Cu")
	)
	(gr_line
		(start 355.423216 -66.330322)
		(end 355.442774 -66.326258)
		(stroke
			(width 0.05715)
			(type default)
		)
		(layer "In4.Cu")
	)
	(gr_line
		(start 355.439472 -65.649602)
		(end 355.458522 -65.645792)
		(stroke
			(width 0.05715)
			(type default)
		)
		(layer "In4.Cu")
	)
	(gr_line
		(start 355.45268 -67.013582)
		(end 355.47173 -67.017392)
		(stroke
			(width 0.05715)
			(type default)
		)
		(layer "In4.Cu")
	)
	(gr_line
		(start 355.47173 -67.017392)
		(end 355.49078 -67.013582)
		(stroke
			(width 0.05715)
			(type default)
		)
		(layer "In4.Cu")
	)
	(gr_line
		(start 355.47554 -67.672712)
		(end 355.49459 -67.676522)
		(stroke
			(width 0.05715)
			(type default)
		)
		(layer "In4.Cu")
	)
	(gr_line
		(start 355.49459 -67.676522)
		(end 355.51364 -67.672712)
		(stroke
			(width 0.05715)
			(type default)
		)
		(layer "In4.Cu")
	)
	(gr_line
		(start 355.4984 -118.267988)
		(end 355.4984 -118.351808)
		(stroke
			(width 0.05715)
			(type default)
		)
		(layer "In4.Cu")
	)
	(gr_line
		(start 355.4984 -117.251988)
		(end 355.4984 -117.335808)
		(stroke
			(width 0.05715)
			(type default)
		)
		(layer "In4.Cu")
	)
	(gr_line
		(start 355.525578 -124.78258)
		(end 355.537008 -124.734066)
		(stroke
			(width 0.05715)
			(type default)
		)
		(layer "In4.Cu")
	)
	(gr_line
		(start 355.525578 -124.78258)
		(end 355.543358 -124.829824)
		(stroke
			(width 0.05715)
			(type default)
		)
		(layer "In4.Cu")
	)
	(gr_line
		(start 355.57587 -62.961774)
		(end 355.594666 -62.958218)
		(stroke
			(width 0.05715)
			(type default)
		)
		(layer "In4.Cu")
	)
	(gr_line
		(start 355.594666 -62.958218)
		(end 355.611176 -62.947296)
		(stroke
			(width 0.05715)
			(type default)
		)
		(layer "In4.Cu")
	)
	(gr_line
		(start 355.741732 -81.319878)
		(end 356.016052 -81.045558)
		(stroke
			(width 0.05715)
			(type default)
		)
		(layer "In4.Cu")
	)
	(gr_line
		(start 355.741732 -80.354678)
		(end 356.016052 -80.628998)
		(stroke
			(width 0.05715)
			(type default)
		)
		(layer "In4.Cu")
	)
	(gr_line
		(start 355.79304 -118.643908)
		(end 355.9556 -118.481348)
		(stroke
			(width 0.05715)
			(type default)
		)
		(layer "In4.Cu")
	)
	(gr_line
		(start 355.79304 -117.975888)
		(end 355.9556 -118.138448)
		(stroke
			(width 0.05715)
			(type default)
		)
		(layer "In4.Cu")
	)
	(gr_line
		(start 355.79304 -117.627908)
		(end 355.9556 -117.465348)
		(stroke
			(width 0.05715)
			(type default)
		)
		(layer "In4.Cu")
	)
	(gr_line
		(start 355.79304 -116.959888)
		(end 355.9556 -117.122448)
		(stroke
			(width 0.05715)
			(type default)
		)
		(layer "In4.Cu")
	)
	(gr_line
		(start 355.793548 -76.129388)
		(end 355.81336 -76.133452)
		(stroke
			(width 0.05715)
			(type default)
		)
		(layer "In4.Cu")
	)
	(gr_line
		(start 355.81336 -76.133452)
		(end 355.833172 -76.129388)
		(stroke
			(width 0.05715)
			(type default)
		)
		(layer "In4.Cu")
	)
	(gr_line
		(start 355.818948 -75.474068)
		(end 355.83876 -75.478132)
		(stroke
			(width 0.05715)
			(type default)
		)
		(layer "In4.Cu")
	)
	(gr_line
		(start 355.818948 -74.813668)
		(end 355.83876 -74.817732)
		(stroke
			(width 0.05715)
			(type default)
		)
		(layer "In4.Cu")
	)
	(gr_line
		(start 355.818948 -74.153522)
		(end 355.83876 -74.157586)
		(stroke
			(width 0.05715)
			(type default)
		)
		(layer "In4.Cu")
	)
	(gr_line
		(start 355.819202 -74.153522)
		(end 355.83876 -74.157586)
		(stroke
			(width 0.05715)
			(type default)
		)
		(layer "In4.Cu")
	)
	(gr_line
		(start 355.819456 -73.493376)
		(end 355.83876 -73.497186)
		(stroke
			(width 0.05715)
			(type default)
		)
		(layer "In4.Cu")
	)
	(gr_line
		(start 355.83876 -75.478132)
		(end 355.858572 -75.474068)
		(stroke
			(width 0.05715)
			(type default)
		)
		(layer "In4.Cu")
	)
	(gr_line
		(start 355.83876 -74.817732)
		(end 355.858572 -74.813668)
		(stroke
			(width 0.05715)
			(type default)
		)
		(layer "In4.Cu")
	)
	(gr_line
		(start 355.83876 -74.157586)
		(end 355.858572 -74.153522)
		(stroke
			(width 0.05715)
			(type default)
		)
		(layer "In4.Cu")
	)
	(gr_line
		(start 355.83876 -73.497186)
		(end 355.85908 -73.493122)
		(stroke
			(width 0.05715)
			(type default)
		)
		(layer "In4.Cu")
	)
	(gr_line
		(start 355.912928 -55.034434)
		(end 355.921564 -55.03164)
		(stroke
			(width 0.05715)
			(type default)
		)
		(layer "In4.Cu")
	)
	(gr_line
		(start 355.955092 -110.0582)
		(end 355.955092 -110.43285)
		(stroke
			(width 0.05715)
			(type default)
		)
		(layer "In4.Cu")
	)
	(gr_line
		(start 355.955092 -110.0582)
		(end 356.007162 -110.00613)
		(stroke
			(width 0.05715)
			(type default)
		)
		(layer "In4.Cu")
	)
	(gr_line
		(start 355.955092 -109.5375)
		(end 356.007162 -109.58957)
		(stroke
			(width 0.05715)
			(type default)
		)
		(layer "In4.Cu")
	)
	(gr_line
		(start 355.955092 -109.16285)
		(end 355.955092 -109.5375)
		(stroke
			(width 0.05715)
			(type default)
		)
		(layer "In4.Cu")
	)
	(gr_line
		(start 355.9556 -118.138448)
		(end 355.9556 -118.481348)
		(stroke
			(width 0.05715)
			(type default)
		)
		(layer "In4.Cu")
	)
	(gr_line
		(start 355.9556 -117.122448)
		(end 355.9556 -117.465348)
		(stroke
			(width 0.05715)
			(type default)
		)
		(layer "In4.Cu")
	)
	(gr_line
		(start 356.018846 -127.92837)
		(end 356.04069 -127.98679)
		(stroke
			(width 0.05715)
			(type default)
		)
		(layer "In4.Cu")
	)
	(gr_line
		(start 356.04069 -127.98679)
		(end 356.093014 -128.01981)
		(stroke
			(width 0.05715)
			(type default)
		)
		(layer "In4.Cu")
	)
	(gr_line
		(start 356.102666 -55.669434)
		(end 356.111302 -55.66664)
		(stroke
			(width 0.05715)
			(type default)
		)
		(layer "In4.Cu")
	)
	(gr_line
		(start 356.117906 -64.84239)
		(end 356.168452 -64.83223)
		(stroke
			(width 0.05715)
			(type default)
		)
		(layer "In4.Cu")
	)
	(gr_line
		(start 356.168452 -64.83223)
		(end 356.204774 -64.796162)
		(stroke
			(width 0.05715)
			(type default)
		)
		(layer "In4.Cu")
	)
	(gr_line
		(start 356.196138 -124.740162)
		(end 356.208584 -124.686822)
		(stroke
			(width 0.05715)
			(type default)
		)
		(layer "In4.Cu")
	)
	(gr_line
		(start 356.196138 -124.740162)
		(end 356.216712 -124.791216)
		(stroke
			(width 0.05715)
			(type default)
		)
		(layer "In4.Cu")
	)
	(gr_line
		(start 356.216712 -124.79147)
		(end 356.216966 -124.792232)
		(stroke
			(width 0.05715)
			(type default)
		)
		(layer "In4.Cu")
	)
	(gr_line
		(start 356.25278 -115.920774)
		(end 356.30485 -115.972844)
		(stroke
			(width 0.05715)
			(type default)
		)
		(layer "In4.Cu")
	)
	(gr_line
		(start 356.25278 -115.504214)
		(end 356.30485 -115.452144)
		(stroke
			(width 0.05715)
			(type default)
		)
		(layer "In4.Cu")
	)
	(gr_line
		(start 356.290626 -32.775398)
		(end 356.308914 -32.763206)
		(stroke
			(width 0.05715)
			(type default)
		)
		(layer "In4.Cu")
	)
	(gr_line
		(start 356.291896 -75.741022)
		(end 356.311708 -75.736958)
		(stroke
			(width 0.05715)
			(type default)
		)
		(layer "In4.Cu")
	)
	(gr_line
		(start 356.30485 -115.972844)
		(end 356.30485 -116.220494)
		(stroke
			(width 0.05715)
			(type default)
		)
		(layer "In4.Cu")
	)
	(gr_line
		(start 356.30485 -115.204494)
		(end 356.30485 -115.452144)
		(stroke
			(width 0.05715)
			(type default)
		)
		(layer "In4.Cu")
	)
	(gr_line
		(start 356.308914 -32.763206)
		(end 356.321106 -32.744918)
		(stroke
			(width 0.05715)
			(type default)
		)
		(layer "In4.Cu")
	)
	(gr_line
		(start 356.311708 -75.736958)
		(end 356.33152 -75.741022)
		(stroke
			(width 0.05715)
			(type default)
		)
		(layer "In4.Cu")
	)
	(gr_line
		(start 356.317296 -75.085702)
		(end 356.337108 -75.081638)
		(stroke
			(width 0.05715)
			(type default)
		)
		(layer "In4.Cu")
	)
	(gr_line
		(start 356.317296 -74.425302)
		(end 356.337108 -74.421238)
		(stroke
			(width 0.05715)
			(type default)
		)
		(layer "In4.Cu")
	)
	(gr_line
		(start 356.317296 -73.765156)
		(end 356.337108 -73.761092)
		(stroke
			(width 0.05715)
			(type default)
		)
		(layer "In4.Cu")
	)
	(gr_line
		(start 356.317296 -73.105264)
		(end 356.337108 -73.1012)
		(stroke
			(width 0.05715)
			(type default)
		)
		(layer "In4.Cu")
	)
	(gr_line
		(start 356.337108 -75.081638)
		(end 356.35692 -75.085702)
		(stroke
			(width 0.05715)
			(type default)
		)
		(layer "In4.Cu")
	)
	(gr_line
		(start 356.337108 -74.421238)
		(end 356.35692 -74.425302)
		(stroke
			(width 0.05715)
			(type default)
		)
		(layer "In4.Cu")
	)
	(gr_line
		(start 356.337108 -73.761092)
		(end 356.35692 -73.765156)
		(stroke
			(width 0.05715)
			(type default)
		)
		(layer "In4.Cu")
	)
	(gr_line
		(start 356.337108 -73.1012)
		(end 356.35692 -73.105264)
		(stroke
			(width 0.05715)
			(type default)
		)
		(layer "In4.Cu")
	)
	(gr_line
		(start 356.339648 -122.562874)
		(end 356.339648 -122.563382)
		(stroke
			(width 0.05715)
			(type default)
		)
		(layer "In4.Cu")
	)
	(gr_line
		(start 356.339648 -122.562874)
		(end 356.346252 -122.534172)
		(stroke
			(width 0.05715)
			(type default)
		)
		(layer "In4.Cu")
	)
	(gr_line
		(start 356.339902 -122.505724)
		(end 356.346252 -122.534172)
		(stroke
			(width 0.05715)
			(type default)
		)
		(layer "In4.Cu")
	)
	(gr_line
		(start 356.424484 -54.554374)
		(end 356.467156 -54.564026)
		(stroke
			(width 0.05715)
			(type default)
		)
		(layer "In4.Cu")
	)
	(gr_line
		(start 356.43058 -121.261124)
		(end 356.445312 -121.327672)
		(stroke
			(width 0.05715)
			(type default)
		)
		(layer "In4.Cu")
	)
	(gr_line
		(start 356.43058 -121.261124)
		(end 356.461568 -121.201688)
		(stroke
			(width 0.05715)
			(type default)
		)
		(layer "In4.Cu")
	)
	(gr_line
		(start 356.437692 -127.230124)
		(end 356.459536 -127.288544)
		(stroke
			(width 0.05715)
			(type default)
		)
		(layer "In4.Cu")
	)
	(gr_line
		(start 356.445058 -121.327672)
		(end 356.445312 -121.328688)
		(stroke
			(width 0.05715)
			(type default)
		)
		(layer "In4.Cu")
	)
	(gr_line
		(start 356.458012 -65.44564)
		(end 356.506018 -65.436242)
		(stroke
			(width 0.05715)
			(type default)
		)
		(layer "In4.Cu")
	)
	(gr_line
		(start 356.459536 -127.288544)
		(end 356.512114 -127.321818)
		(stroke
			(width 0.05715)
			(type default)
		)
		(layer "In4.Cu")
	)
	(gr_line
		(start 356.467156 -54.564026)
		(end 356.507288 -54.55031)
		(stroke
			(width 0.05715)
			(type default)
		)
		(layer "In4.Cu")
	)
	(gr_line
		(start 356.468426 -128.257046)
		(end 356.97795 -128.578864)
		(stroke
			(width 0.05715)
			(type default)
		)
		(layer "In4.Cu")
	)
	(gr_line
		(start 356.496874 -55.32374)
		(end 356.50551 -55.320946)
		(stroke
			(width 0.05715)
			(type default)
		)
		(layer "In4.Cu")
	)
	(gr_line
		(start 356.506018 -65.436242)
		(end 356.541324 -65.40119)
		(stroke
			(width 0.05715)
			(type default)
		)
		(layer "In4.Cu")
	)
	(gr_line
		(start 356.509574 -53.76291)
		(end 356.548182 -53.770784)
		(stroke
			(width 0.05715)
			(type default)
		)
		(layer "In4.Cu")
	)
	(gr_line
		(start 356.548182 -53.770784)
		(end 356.585012 -53.758338)
		(stroke
			(width 0.05715)
			(type default)
		)
		(layer "In4.Cu")
	)
	(gr_line
		(start 356.555802 -43.042332)
		(end 356.565962 -43.039538)
		(stroke
			(width 0.05715)
			(type default)
		)
		(layer "In4.Cu")
	)
	(gr_line
		(start 356.565962 -43.039538)
		(end 356.57409 -43.03395)
		(stroke
			(width 0.05715)
			(type default)
		)
		(layer "In4.Cu")
	)
	(gr_line
		(start 356.597458 -127.989838)
		(end 356.821994 -127.939038)
		(stroke
			(width 0.05715)
			(type default)
		)
		(layer "In4.Cu")
	)
	(gr_line
		(start 356.609904 -55.95874)
		(end 356.61854 -55.955946)
		(stroke
			(width 0.05715)
			(type default)
		)
		(layer "In4.Cu")
	)
	(gr_line
		(start 356.727252 -63.86703)
		(end 356.785672 -63.809118)
		(stroke
			(width 0.05715)
			(type default)
		)
		(layer "In4.Cu")
	)
	(gr_line
		(start 356.736904 -66.068448)
		(end 356.78618 -66.058542)
		(stroke
			(width 0.05715)
			(type default)
		)
		(layer "In4.Cu")
	)
	(gr_line
		(start 356.749858 -43.687238)
		(end 356.760018 -43.684444)
		(stroke
			(width 0.05715)
			(type default)
		)
		(layer "In4.Cu")
	)
	(gr_line
		(start 356.760018 -43.684444)
		(end 356.768908 -43.678602)
		(stroke
			(width 0.05715)
			(type default)
		)
		(layer "In4.Cu")
	)
	(gr_line
		(start 356.77475 -33.231836)
		(end 356.786942 -33.213548)
		(stroke
			(width 0.05715)
			(type default)
		)
		(layer "In4.Cu")
	)
	(gr_line
		(start 356.78618 -66.058542)
		(end 356.821232 -66.02349)
		(stroke
			(width 0.05715)
			(type default)
		)
		(layer "In4.Cu")
	)
	(gr_line
		(start 356.790244 -76.129388)
		(end 356.810056 -76.133452)
		(stroke
			(width 0.05715)
			(type default)
		)
		(layer "In4.Cu")
	)
	(gr_line
		(start 356.790244 -75.468988)
		(end 356.810056 -75.473052)
		(stroke
			(width 0.05715)
			(type default)
		)
		(layer "In4.Cu")
	)
	(gr_line
		(start 356.790244 -74.808588)
		(end 356.810056 -74.812652)
		(stroke
			(width 0.05715)
			(type default)
		)
		(layer "In4.Cu")
	)
	(gr_line
		(start 356.790244 -74.148442)
		(end 356.810056 -74.152506)
		(stroke
			(width 0.05715)
			(type default)
		)
		(layer "In4.Cu")
	)
	(gr_line
		(start 356.790244 -73.48855)
		(end 356.809548 -73.49236)
		(stroke
			(width 0.05715)
			(type default)
		)
		(layer "In4.Cu")
	)
	(gr_line
		(start 356.790498 -73.48855)
		(end 356.809548 -73.49236)
		(stroke
			(width 0.05715)
			(type default)
		)
		(layer "In4.Cu")
	)
	(gr_line
		(start 356.791514 -60.324238)
		(end 356.809802 -60.312046)
		(stroke
			(width 0.05715)
			(type default)
		)
		(layer "In4.Cu")
	)
	(gr_line
		(start 356.809548 -73.49236)
		(end 356.828344 -73.48855)
		(stroke
			(width 0.05715)
			(type default)
		)
		(layer "In4.Cu")
	)
	(gr_line
		(start 356.809548 -73.49236)
		(end 356.828598 -73.48855)
		(stroke
			(width 0.05715)
			(type default)
		)
		(layer "In4.Cu")
	)
	(gr_line
		(start 356.809802 -60.312046)
		(end 356.821994 -60.294012)
		(stroke
			(width 0.05715)
			(type default)
		)
		(layer "In4.Cu")
	)
	(gr_line
		(start 356.810056 -76.133452)
		(end 356.829868 -76.129388)
		(stroke
			(width 0.05715)
			(type default)
		)
		(layer "In4.Cu")
	)
	(gr_line
		(start 356.810056 -75.473052)
		(end 356.829868 -75.468988)
		(stroke
			(width 0.05715)
			(type default)
		)
		(layer "In4.Cu")
	)
	(gr_line
		(start 356.810056 -74.812652)
		(end 356.829868 -74.808588)
		(stroke
			(width 0.05715)
			(type default)
		)
		(layer "In4.Cu")
	)
	(gr_line
		(start 356.810056 -74.152506)
		(end 356.829614 -74.148442)
		(stroke
			(width 0.05715)
			(type default)
		)
		(layer "In4.Cu")
	)
	(gr_line
		(start 356.821994 -127.939038)
		(end 357.112062 -128.122172)
		(stroke
			(width 0.05715)
			(type default)
		)
		(layer "In4.Cu")
	)
	(gr_line
		(start 356.895146 -124.592334)
		(end 356.906576 -124.54382)
		(stroke
			(width 0.05715)
			(type default)
		)
		(layer "In4.Cu")
	)
	(gr_line
		(start 356.895146 -124.592334)
		(end 356.912926 -124.639578)
		(stroke
			(width 0.05715)
			(type default)
		)
		(layer "In4.Cu")
	)
	(gr_line
		(start 356.977442 -104.973374)
		(end 357.630476 -104.32034)
		(stroke
			(width 0.05715)
			(type default)
		)
		(layer "In4.Cu")
	)
	(gr_line
		(start 356.977442 -103.703374)
		(end 357.299768 -104.0257)
		(stroke
			(width 0.05715)
			(type default)
		)
		(layer "In4.Cu")
	)
	(gr_line
		(start 357.001064 -64.533272)
		(end 357.05923 -64.475614)
		(stroke
			(width 0.05715)
			(type default)
		)
		(layer "In4.Cu")
	)
	(gr_line
		(start 357.001826 -122.557286)
		(end 357.00208 -122.55627)
		(stroke
			(width 0.05715)
			(type default)
		)
		(layer "In4.Cu")
	)
	(gr_line
		(start 357.001826 -122.556524)
		(end 357.008176 -122.529346)
		(stroke
			(width 0.05715)
			(type default)
		)
		(layer "In4.Cu")
	)
	(gr_line
		(start 357.002334 -122.502422)
		(end 357.008176 -122.529346)
		(stroke
			(width 0.05715)
			(type default)
		)
		(layer "In4.Cu")
	)
	(gr_line
		(start 357.018844 -66.708274)
		(end 357.06812 -66.698368)
		(stroke
			(width 0.05715)
			(type default)
		)
		(layer "In4.Cu")
	)
	(gr_line
		(start 357.03637 -44.288202)
		(end 357.04653 -44.285408)
		(stroke
			(width 0.05715)
			(type default)
		)
		(layer "In4.Cu")
	)
	(gr_line
		(start 357.04653 -44.285408)
		(end 357.05542 -44.279566)
		(stroke
			(width 0.05715)
			(type default)
		)
		(layer "In4.Cu")
	)
	(gr_line
		(start 357.048308 -126.854204)
		(end 357.069898 -126.908052)
		(stroke
			(width 0.05715)
			(type default)
		)
		(layer "In4.Cu")
	)
	(gr_line
		(start 357.06812 -66.698368)
		(end 357.103172 -66.663316)
		(stroke
			(width 0.05715)
			(type default)
		)
		(layer "In4.Cu")
	)
	(gr_line
		(start 357.069898 -126.908052)
		(end 357.119174 -126.939294)
		(stroke
			(width 0.05715)
			(type default)
		)
		(layer "In4.Cu")
	)
	(gr_line
		(start 357.112062 -128.122172)
		(end 357.162608 -128.346708)
		(stroke
			(width 0.05715)
			(type default)
		)
		(layer "In4.Cu")
	)
	(gr_line
		(start 357.113586 -121.35104)
		(end 357.128318 -121.418604)
		(stroke
			(width 0.05715)
			(type default)
		)
		(layer "In4.Cu")
	)
	(gr_line
		(start 357.113586 -121.35104)
		(end 357.144574 -121.291604)
		(stroke
			(width 0.05715)
			(type default)
		)
		(layer "In4.Cu")
	)
	(gr_line
		(start 357.229664 -33.715452)
		(end 357.247952 -33.70326)
		(stroke
			(width 0.05715)
			(type default)
		)
		(layer "In4.Cu")
	)
	(gr_line
		(start 357.246428 -65.187576)
		(end 357.30434 -65.129664)
		(stroke
			(width 0.05715)
			(type default)
		)
		(layer "In4.Cu")
	)
	(gr_line
		(start 357.247952 -33.70326)
		(end 357.260144 -33.684972)
		(stroke
			(width 0.05715)
			(type default)
		)
		(layer "In4.Cu")
	)
	(gr_line
		(start 357.288592 -75.741022)
		(end 357.308404 -75.736958)
		(stroke
			(width 0.05715)
			(type default)
		)
		(layer "In4.Cu")
	)
	(gr_line
		(start 357.288592 -75.080622)
		(end 357.308404 -75.076558)
		(stroke
			(width 0.05715)
			(type default)
		)
		(layer "In4.Cu")
	)
	(gr_line
		(start 357.288592 -74.420222)
		(end 357.308404 -74.416158)
		(stroke
			(width 0.05715)
			(type default)
		)
		(layer "In4.Cu")
	)
	(gr_line
		(start 357.288592 -73.099422)
		(end 357.30815 -73.095358)
		(stroke
			(width 0.05715)
			(type default)
		)
		(layer "In4.Cu")
	)
	(gr_line
		(start 357.288846 -73.759822)
		(end 357.308404 -73.755758)
		(stroke
			(width 0.05715)
			(type default)
		)
		(layer "In4.Cu")
	)
	(gr_line
		(start 357.299768 -104.0257)
		(end 357.338376 -104.0257)
		(stroke
			(width 0.05715)
			(type default)
		)
		(layer "In4.Cu")
	)
	(gr_line
		(start 357.30815 -73.095358)
		(end 357.327962 -73.099422)
		(stroke
			(width 0.05715)
			(type default)
		)
		(layer "In4.Cu")
	)
	(gr_line
		(start 357.308404 -75.736958)
		(end 357.328216 -75.741022)
		(stroke
			(width 0.05715)
			(type default)
		)
		(layer "In4.Cu")
	)
	(gr_line
		(start 357.308404 -75.076558)
		(end 357.328216 -75.080622)
		(stroke
			(width 0.05715)
			(type default)
		)
		(layer "In4.Cu")
	)
	(gr_line
		(start 357.308404 -74.416158)
		(end 357.327962 -74.420222)
		(stroke
			(width 0.05715)
			(type default)
		)
		(layer "In4.Cu")
	)
	(gr_line
		(start 357.308404 -73.755758)
		(end 357.327962 -73.759822)
		(stroke
			(width 0.05715)
			(type default)
		)
		(layer "In4.Cu")
	)
	(gr_line
		(start 357.32593 -128.798574)
		(end 357.837486 -129.121662)
		(stroke
			(width 0.05715)
			(type default)
		)
		(layer "In4.Cu")
	)
	(gr_line
		(start 357.336344 -67.307968)
		(end 357.38562 -67.298316)
		(stroke
			(width 0.05715)
			(type default)
		)
		(layer "In4.Cu")
	)
	(gr_line
		(start 357.376222 -44.867576)
		(end 357.386382 -44.864782)
		(stroke
			(width 0.05715)
			(type default)
		)
		(layer "In4.Cu")
	)
	(gr_line
		(start 357.386382 -44.864782)
		(end 357.395272 -44.85894)
		(stroke
			(width 0.05715)
			(type default)
		)
		(layer "In4.Cu")
	)
	(gr_line
		(start 357.418132 -106.691938)
		(end 357.418132 -107.08005)
		(stroke
			(width 0.05715)
			(type default)
		)
		(layer "In4.Cu")
	)
	(gr_line
		(start 357.418132 -106.691938)
		(end 357.470202 -106.639868)
		(stroke
			(width 0.05715)
			(type default)
		)
		(layer "In4.Cu")
	)
	(gr_line
		(start 357.418132 -106.171238)
		(end 357.470202 -106.223308)
		(stroke
			(width 0.05715)
			(type default)
		)
		(layer "In4.Cu")
	)
	(gr_line
		(start 357.418132 -105.81005)
		(end 357.418132 -106.171238)
		(stroke
			(width 0.05715)
			(type default)
		)
		(layer "In4.Cu")
	)
	(gr_line
		(start 357.456486 -128.532128)
		(end 357.681022 -128.481582)
		(stroke
			(width 0.05715)
			(type default)
		)
		(layer "In4.Cu")
	)
	(gr_line
		(start 357.510588 -42.413936)
		(end 357.52786 -42.402506)
		(stroke
			(width 0.05715)
			(type default)
		)
		(layer "In4.Cu")
	)
	(gr_line
		(start 357.519478 -65.836038)
		(end 357.57739 -65.778126)
		(stroke
			(width 0.05715)
			(type default)
		)
		(layer "In4.Cu")
	)
	(gr_line
		(start 357.52786 -42.402506)
		(end 357.539798 -42.384726)
		(stroke
			(width 0.05715)
			(type default)
		)
		(layer "In4.Cu")
	)
	(gr_line
		(start 357.571548 -126.406402)
		(end 357.592376 -126.463044)
		(stroke
			(width 0.05715)
			(type default)
		)
		(layer "In4.Cu")
	)
	(gr_line
		(start 357.576882 -124.522484)
		(end 357.588312 -124.47397)
		(stroke
			(width 0.05715)
			(type default)
		)
		(layer "In4.Cu")
	)
	(gr_line
		(start 357.576882 -124.522484)
		(end 357.594662 -124.569728)
		(stroke
			(width 0.05715)
			(type default)
		)
		(layer "In4.Cu")
	)
	(gr_line
		(start 357.592376 -126.463044)
		(end 357.645208 -126.496572)
		(stroke
			(width 0.05715)
			(type default)
		)
		(layer "In4.Cu")
	)
	(gr_line
		(start 357.665782 -122.561096)
		(end 357.666036 -122.56008)
		(stroke
			(width 0.05715)
			(type default)
		)
		(layer "In4.Cu")
	)
	(gr_line
		(start 357.666036 -122.559826)
		(end 357.672132 -122.533156)
		(stroke
			(width 0.05715)
			(type default)
		)
		(layer "In4.Cu")
	)
	(gr_line
		(start 357.66629 -122.506232)
		(end 357.672132 -122.533156)
		(stroke
			(width 0.05715)
			(type default)
		)
		(layer "In4.Cu")
	)
	(gr_line
		(start 357.679498 -45.453554)
		(end 357.689658 -45.45076)
		(stroke
			(width 0.05715)
			(type default)
		)
		(layer "In4.Cu")
	)
	(gr_line
		(start 357.681022 -128.481582)
		(end 357.97109 -128.664716)
		(stroke
			(width 0.05715)
			(type default)
		)
		(layer "In4.Cu")
	)
	(gr_line
		(start 357.689658 -45.45076)
		(end 357.698548 -45.444918)
		(stroke
			(width 0.05715)
			(type default)
		)
		(layer "In4.Cu")
	)
	(gr_line
		(start 357.692198 -34.203386)
		(end 357.710486 -34.191194)
		(stroke
			(width 0.05715)
			(type default)
		)
		(layer "In4.Cu")
	)
	(gr_line
		(start 357.710486 -34.191194)
		(end 357.722678 -34.172906)
		(stroke
			(width 0.05715)
			(type default)
		)
		(layer "In4.Cu")
	)
	(gr_line
		(start 357.743252 -119.363998)
		(end 357.7463 -119.357902)
		(stroke
			(width 0.05715)
			(type default)
		)
		(layer "In4.Cu")
	)
	(gr_line
		(start 357.7463 -119.357902)
		(end 357.758492 -119.33428)
		(stroke
			(width 0.05715)
			(type default)
		)
		(layer "In4.Cu")
	)
	(gr_line
		(start 357.775002 -74.806302)
		(end 357.794814 -74.810366)
		(stroke
			(width 0.05715)
			(type default)
		)
		(layer "In4.Cu")
	)
	(gr_line
		(start 357.775002 -74.145902)
		(end 357.794814 -74.149966)
		(stroke
			(width 0.05715)
			(type default)
		)
		(layer "In4.Cu")
	)
	(gr_line
		(start 357.775002 -73.485502)
		(end 357.794814 -73.489566)
		(stroke
			(width 0.05715)
			(type default)
		)
		(layer "In4.Cu")
	)
	(gr_line
		(start 357.775256 -74.145902)
		(end 357.794814 -74.149966)
		(stroke
			(width 0.05715)
			(type default)
		)
		(layer "In4.Cu")
	)
	(gr_line
		(start 357.78694 -76.129388)
		(end 357.806752 -76.133452)
		(stroke
			(width 0.05715)
			(type default)
		)
		(layer "In4.Cu")
	)
	(gr_line
		(start 357.78694 -75.468988)
		(end 357.806752 -75.473052)
		(stroke
			(width 0.05715)
			(type default)
		)
		(layer "In4.Cu")
	)
	(gr_line
		(start 357.794814 -74.810366)
		(end 357.814372 -74.806302)
		(stroke
			(width 0.05715)
			(type default)
		)
		(layer "In4.Cu")
	)
	(gr_line
		(start 357.794814 -74.149966)
		(end 357.814372 -74.145902)
		(stroke
			(width 0.05715)
			(type default)
		)
		(layer "In4.Cu")
	)
	(gr_line
		(start 357.794814 -73.489566)
		(end 357.814372 -73.485502)
		(stroke
			(width 0.05715)
			(type default)
		)
		(layer "In4.Cu")
	)
	(gr_line
		(start 357.796338 -121.440956)
		(end 357.81107 -121.507504)
		(stroke
			(width 0.05715)
			(type default)
		)
		(layer "In4.Cu")
	)
	(gr_line
		(start 357.796338 -121.440956)
		(end 357.82758 -121.380504)
		(stroke
			(width 0.05715)
			(type default)
		)
		(layer "In4.Cu")
	)
	(gr_line
		(start 357.806752 -76.133452)
		(end 357.82631 -76.129388)
		(stroke
			(width 0.05715)
			(type default)
		)
		(layer "In4.Cu")
	)
	(gr_line
		(start 357.806752 -76.133452)
		(end 357.826564 -76.129388)
		(stroke
			(width 0.05715)
			(type default)
		)
		(layer "In4.Cu")
	)
	(gr_line
		(start 357.806752 -75.473052)
		(end 357.82631 -75.468988)
		(stroke
			(width 0.05715)
			(type default)
		)
		(layer "In4.Cu")
	)
	(gr_line
		(start 357.810816 -121.507504)
		(end 357.81107 -121.50852)
		(stroke
			(width 0.05715)
			(type default)
		)
		(layer "In4.Cu")
	)
	(gr_line
		(start 357.884984 -63.156846)
		(end 357.93426 -63.147194)
		(stroke
			(width 0.05715)
			(type default)
		)
		(layer "In4.Cu")
	)
	(gr_line
		(start 357.895144 -53.318918)
		(end 357.895906 -53.318664)
		(stroke
			(width 0.05715)
			(type default)
		)
		(layer "In4.Cu")
	)
	(gr_line
		(start 357.895906 -53.318664)
		(end 357.896922 -53.318156)
		(stroke
			(width 0.05715)
			(type default)
		)
		(layer "In4.Cu")
	)
	(gr_line
		(start 357.944674 -41.773856)
		(end 357.955596 -41.757346)
		(stroke
			(width 0.05715)
			(type default)
		)
		(layer "In4.Cu")
	)
	(gr_line
		(start 357.955596 -41.757092)
		(end 357.955596 -41.757346)
		(stroke
			(width 0.05715)
			(type default)
		)
		(layer "In4.Cu")
	)
	(gr_line
		(start 357.955596 -41.757092)
		(end 357.959406 -41.73855)
		(stroke
			(width 0.05715)
			(type default)
		)
		(layer "In4.Cu")
	)
	(gr_line
		(start 357.9622 -110.0582)
		(end 357.9622 -110.43285)
		(stroke
			(width 0.05715)
			(type default)
		)
		(layer "In4.Cu")
	)
	(gr_line
		(start 357.9622 -110.0582)
		(end 358.01427 -110.00613)
		(stroke
			(width 0.05715)
			(type default)
		)
		(layer "In4.Cu")
	)
	(gr_line
		(start 357.9622 -109.5375)
		(end 358.01427 -109.58957)
		(stroke
			(width 0.05715)
			(type default)
		)
		(layer "In4.Cu")
	)
	(gr_line
		(start 357.9622 -109.16285)
		(end 357.9622 -109.5375)
		(stroke
			(width 0.05715)
			(type default)
		)
		(layer "In4.Cu")
	)
	(gr_line
		(start 357.97109 -128.664716)
		(end 358.02189 -128.889252)
		(stroke
			(width 0.05715)
			(type default)
		)
		(layer "In4.Cu")
	)
	(gr_line
		(start 358.0003 -42.863516)
		(end 358.017572 -42.852086)
		(stroke
			(width 0.05715)
			(type default)
		)
		(layer "In4.Cu")
	)
	(gr_line
		(start 358.017572 -42.852086)
		(end 358.029002 -42.834814)
		(stroke
			(width 0.05715)
			(type default)
		)
		(layer "In4.Cu")
	)
	(gr_line
		(start 358.066848 -46.00829)
		(end 358.076246 -46.00575)
		(stroke
			(width 0.05715)
			(type default)
		)
		(layer "In4.Cu")
	)
	(gr_line
		(start 358.076246 -46.00575)
		(end 358.084882 -46.000162)
		(stroke
			(width 0.05715)
			(type default)
		)
		(layer "In4.Cu")
	)
	(gr_line
		(start 358.126792 -125.998478)
		(end 358.148636 -126.056898)
		(stroke
			(width 0.05715)
			(type default)
		)
		(layer "In4.Cu")
	)
	(gr_line
		(start 358.148636 -126.056898)
		(end 358.201214 -126.090172)
		(stroke
			(width 0.05715)
			(type default)
		)
		(layer "In4.Cu")
	)
	(gr_line
		(start 358.172766 -34.651188)
		(end 358.191054 -34.638996)
		(stroke
			(width 0.05715)
			(type default)
		)
		(layer "In4.Cu")
	)
	(gr_line
		(start 358.185974 -129.341626)
		(end 358.695752 -129.663444)
		(stroke
			(width 0.05715)
			(type default)
		)
		(layer "In4.Cu")
	)
	(gr_line
		(start 358.191054 -34.638996)
		(end 358.203246 -34.620708)
		(stroke
			(width 0.05715)
			(type default)
		)
		(layer "In4.Cu")
	)
	(gr_line
		(start 358.20858 -115.920774)
		(end 358.26065 -115.972844)
		(stroke
			(width 0.05715)
			(type default)
		)
		(layer "In4.Cu")
	)
	(gr_line
		(start 358.20858 -115.504214)
		(end 358.26065 -115.452144)
		(stroke
			(width 0.05715)
			(type default)
		)
		(layer "In4.Cu")
	)
	(gr_line
		(start 358.26065 -115.972844)
		(end 358.26065 -116.220494)
		(stroke
			(width 0.05715)
			(type default)
		)
		(layer "In4.Cu")
	)
	(gr_line
		(start 358.26065 -115.204494)
		(end 358.26065 -115.452144)
		(stroke
			(width 0.05715)
			(type default)
		)
		(layer "In4.Cu")
	)
	(gr_line
		(start 358.272588 -74.417936)
		(end 358.292146 -74.413872)
		(stroke
			(width 0.05715)
			(type default)
		)
		(layer "In4.Cu")
	)
	(gr_line
		(start 358.272588 -73.757536)
		(end 358.292146 -73.753472)
		(stroke
			(width 0.05715)
			(type default)
		)
		(layer "In4.Cu")
	)
	(gr_line
		(start 358.272588 -73.097136)
		(end 358.292146 -73.093072)
		(stroke
			(width 0.05715)
			(type default)
		)
		(layer "In4.Cu")
	)
	(gr_line
		(start 358.285034 -75.741022)
		(end 358.304846 -75.736958)
		(stroke
			(width 0.05715)
			(type default)
		)
		(layer "In4.Cu")
	)
	(gr_line
		(start 358.285034 -75.080622)
		(end 358.304846 -75.076558)
		(stroke
			(width 0.05715)
			(type default)
		)
		(layer "In4.Cu")
	)
	(gr_line
		(start 358.292146 -74.413872)
		(end 358.311958 -74.417936)
		(stroke
			(width 0.05715)
			(type default)
		)
		(layer "In4.Cu")
	)
	(gr_line
		(start 358.292146 -73.753472)
		(end 358.311958 -73.757536)
		(stroke
			(width 0.05715)
			(type default)
		)
		(layer "In4.Cu")
	)
	(gr_line
		(start 358.292146 -73.093072)
		(end 358.311958 -73.097136)
		(stroke
			(width 0.05715)
			(type default)
		)
		(layer "In4.Cu")
	)
	(gr_line
		(start 358.304846 -75.736958)
		(end 358.324658 -75.741022)
		(stroke
			(width 0.05715)
			(type default)
		)
		(layer "In4.Cu")
	)
	(gr_line
		(start 358.304846 -75.076558)
		(end 358.324658 -75.080622)
		(stroke
			(width 0.05715)
			(type default)
		)
		(layer "In4.Cu")
	)
	(gr_line
		(start 358.310688 -46.613572)
		(end 358.320848 -46.610778)
		(stroke
			(width 0.05715)
			(type default)
		)
		(layer "In4.Cu")
	)
	(gr_line
		(start 358.315514 -129.074672)
		(end 358.540304 -129.024126)
		(stroke
			(width 0.05715)
			(type default)
		)
		(layer "In4.Cu")
	)
	(gr_line
		(start 358.320848 -46.610778)
		(end 358.329738 -46.604936)
		(stroke
			(width 0.05715)
			(type default)
		)
		(layer "In4.Cu")
	)
	(gr_line
		(start 358.329738 -122.564144)
		(end 358.336088 -122.536966)
		(stroke
			(width 0.05715)
			(type default)
		)
		(layer "In4.Cu")
	)
	(gr_line
		(start 358.330246 -122.510042)
		(end 358.336088 -122.536966)
		(stroke
			(width 0.05715)
			(type default)
		)
		(layer "In4.Cu")
	)
	(gr_line
		(start 358.384856 -53.920136)
		(end 358.389174 -53.918866)
		(stroke
			(width 0.05715)
			(type default)
		)
		(layer "In4.Cu")
	)
	(gr_line
		(start 358.389174 -53.918866)
		(end 358.39273 -53.916326)
		(stroke
			(width 0.05715)
			(type default)
		)
		(layer "In4.Cu")
	)
	(gr_line
		(start 358.437942 -43.36415)
		(end 358.455214 -43.35272)
		(stroke
			(width 0.05715)
			(type default)
		)
		(layer "In4.Cu")
	)
	(gr_line
		(start 358.455214 -43.35272)
		(end 358.466644 -43.335448)
		(stroke
			(width 0.05715)
			(type default)
		)
		(layer "In4.Cu")
	)
	(gr_line
		(start 358.540304 -129.024126)
		(end 358.830118 -129.20726)
		(stroke
			(width 0.05715)
			(type default)
		)
		(layer "In4.Cu")
	)
	(gr_line
		(start 358.554528 -42.041064)
		(end 358.564942 -42.025316)
		(stroke
			(width 0.05715)
			(type default)
		)
		(layer "In4.Cu")
	)
	(gr_line
		(start 358.564942 -42.025316)
		(end 358.568752 -42.006774)
		(stroke
			(width 0.05715)
			(type default)
		)
		(layer "In4.Cu")
	)
	(gr_line
		(start 358.568752 -54.628288)
		(end 358.57307 -54.627018)
		(stroke
			(width 0.05715)
			(type default)
		)
		(layer "In4.Cu")
	)
	(gr_line
		(start 358.57307 -54.627018)
		(end 358.576626 -54.624478)
		(stroke
			(width 0.05715)
			(type default)
		)
		(layer "In4.Cu")
	)
	(gr_line
		(start 358.60228 -35.162236)
		(end 358.620568 -35.150044)
		(stroke
			(width 0.05715)
			(type default)
		)
		(layer "In4.Cu")
	)
	(gr_line
		(start 358.620568 -35.150044)
		(end 358.63276 -35.131756)
		(stroke
			(width 0.05715)
			(type default)
		)
		(layer "In4.Cu")
	)
	(gr_line
		(start 358.671622 -47.178214)
		(end 358.681782 -47.17542)
		(stroke
			(width 0.05715)
			(type default)
		)
		(layer "In4.Cu")
	)
	(gr_line
		(start 358.681782 -47.17542)
		(end 358.690672 -47.169578)
		(stroke
			(width 0.05715)
			(type default)
		)
		(layer "In4.Cu")
	)
	(gr_line
		(start 358.783382 -76.129388)
		(end 358.803194 -76.133452)
		(stroke
			(width 0.05715)
			(type default)
		)
		(layer "In4.Cu")
	)
	(gr_line
		(start 358.783382 -75.468988)
		(end 358.803194 -75.473052)
		(stroke
			(width 0.05715)
			(type default)
		)
		(layer "In4.Cu")
	)
	(gr_line
		(start 358.783382 -74.808842)
		(end 358.803194 -74.812906)
		(stroke
			(width 0.05715)
			(type default)
		)
		(layer "In4.Cu")
	)
	(gr_line
		(start 358.783382 -74.148442)
		(end 358.803194 -74.152506)
		(stroke
			(width 0.05715)
			(type default)
		)
		(layer "In4.Cu")
	)
	(gr_line
		(start 358.783382 -73.488042)
		(end 358.803194 -73.492106)
		(stroke
			(width 0.05715)
			(type default)
		)
		(layer "In4.Cu")
	)
	(gr_line
		(start 358.803194 -76.133452)
		(end 358.823006 -76.129388)
		(stroke
			(width 0.05715)
			(type default)
		)
		(layer "In4.Cu")
	)
	(gr_line
		(start 358.803194 -75.473052)
		(end 358.823006 -75.468988)
		(stroke
			(width 0.05715)
			(type default)
		)
		(layer "In4.Cu")
	)
	(gr_line
		(start 358.803194 -74.812906)
		(end 358.823006 -74.808842)
		(stroke
			(width 0.05715)
			(type default)
		)
		(layer "In4.Cu")
	)
	(gr_line
		(start 358.803194 -74.152506)
		(end 358.822752 -74.148442)
		(stroke
			(width 0.05715)
			(type default)
		)
		(layer "In4.Cu")
	)
	(gr_line
		(start 358.803194 -73.492106)
		(end 358.822752 -73.488042)
		(stroke
			(width 0.05715)
			(type default)
		)
		(layer "In4.Cu")
	)
	(gr_line
		(start 358.830118 -129.20726)
		(end 358.880918 -129.431796)
		(stroke
			(width 0.05715)
			(type default)
		)
		(layer "In4.Cu")
	)
	(gr_line
		(start 358.888284 -43.87088)
		(end 358.905556 -43.85945)
		(stroke
			(width 0.05715)
			(type default)
		)
		(layer "In4.Cu")
	)
	(gr_line
		(start 358.905556 -43.85945)
		(end 358.916986 -43.842178)
		(stroke
			(width 0.05715)
			(type default)
		)
		(layer "In4.Cu")
	)
	(gr_line
		(start 358.946196 -35.35426)
		(end 358.950006 -35.33521)
		(stroke
			(width 0.05715)
			(type default)
		)
		(layer "In4.Cu")
	)
	(gr_line
		(start 358.950006 -35.33521)
		(end 358.960674 -35.318954)
		(stroke
			(width 0.05715)
			(type default)
		)
		(layer "In4.Cu")
	)
	(gr_line
		(start 358.959658 -55.17007)
		(end 358.963976 -55.1688)
		(stroke
			(width 0.05715)
			(type default)
		)
		(layer "In4.Cu")
	)
	(gr_line
		(start 358.963976 -55.1688)
		(end 358.967532 -55.16626)
		(stroke
			(width 0.05715)
			(type default)
		)
		(layer "In4.Cu")
	)
	(gr_line
		(start 359.000298 -81.288382)
		(end 359.274618 -81.014062)
		(stroke
			(width 0.05715)
			(type default)
		)
		(layer "In4.Cu")
	)
	(gr_line
		(start 359.000298 -80.323182)
		(end 359.274618 -80.597502)
		(stroke
			(width 0.05715)
			(type default)
		)
		(layer "In4.Cu")
	)
	(gr_line
		(start 359.008934 -47.75454)
		(end 359.019094 -47.751746)
		(stroke
			(width 0.05715)
			(type default)
		)
		(layer "In4.Cu")
	)
	(gr_line
		(start 359.019094 -47.751746)
		(end 359.027984 -47.745904)
		(stroke
			(width 0.05715)
			(type default)
		)
		(layer "In4.Cu")
	)
	(gr_line
		(start 359.046018 -129.884424)
		(end 359.553002 -130.204718)
		(stroke
			(width 0.05715)
			(type default)
		)
		(layer "In4.Cu")
	)
	(gr_line
		(start 359.16997 -42.27322)
		(end 359.180892 -42.25671)
		(stroke
			(width 0.05715)
			(type default)
		)
		(layer "In4.Cu")
	)
	(gr_line
		(start 359.174796 -129.617216)
		(end 359.399332 -129.56667)
		(stroke
			(width 0.05715)
			(type default)
		)
		(layer "In4.Cu")
	)
	(gr_line
		(start 359.180892 -42.25671)
		(end 359.184956 -42.237152)
		(stroke
			(width 0.05715)
			(type default)
		)
		(layer "In4.Cu")
	)
	(gr_line
		(start 359.270554 -73.762108)
		(end 359.29062 -73.758044)
		(stroke
			(width 0.05715)
			(type default)
		)
		(layer "In4.Cu")
	)
	(gr_line
		(start 359.271062 -73.101708)
		(end 359.29062 -73.097644)
		(stroke
			(width 0.05715)
			(type default)
		)
		(layer "In4.Cu")
	)
	(gr_line
		(start 359.277412 -48.352202)
		(end 359.285794 -48.349916)
		(stroke
			(width 0.05715)
			(type default)
		)
		(layer "In4.Cu")
	)
	(gr_line
		(start 359.28173 -75.741022)
		(end 359.301542 -75.736958)
		(stroke
			(width 0.05715)
			(type default)
		)
		(layer "In4.Cu")
	)
	(gr_line
		(start 359.28173 -75.080622)
		(end 359.301542 -75.076558)
		(stroke
			(width 0.05715)
			(type default)
		)
		(layer "In4.Cu")
	)
	(gr_line
		(start 359.28173 -74.420476)
		(end 359.301542 -74.416412)
		(stroke
			(width 0.05715)
			(type default)
		)
		(layer "In4.Cu")
	)
	(gr_line
		(start 359.285794 -48.349916)
		(end 359.29316 -48.34509)
		(stroke
			(width 0.05715)
			(type default)
		)
		(layer "In4.Cu")
	)
	(gr_line
		(start 359.29062 -73.758044)
		(end 359.309924 -73.761854)
		(stroke
			(width 0.05715)
			(type default)
		)
		(layer "In4.Cu")
	)
	(gr_line
		(start 359.29062 -73.097644)
		(end 359.310178 -73.101708)
		(stroke
			(width 0.05715)
			(type default)
		)
		(layer "In4.Cu")
	)
	(gr_line
		(start 359.301542 -75.736958)
		(end 359.321354 -75.741022)
		(stroke
			(width 0.05715)
			(type default)
		)
		(layer "In4.Cu")
	)
	(gr_line
		(start 359.301542 -75.076558)
		(end 359.321354 -75.080622)
		(stroke
			(width 0.05715)
			(type default)
		)
		(layer "In4.Cu")
	)
	(gr_line
		(start 359.301542 -74.416412)
		(end 359.321354 -74.420476)
		(stroke
			(width 0.05715)
			(type default)
		)
		(layer "In4.Cu")
	)
	(gr_line
		(start 359.358184 -44.346622)
		(end 359.375456 -44.335192)
		(stroke
			(width 0.05715)
			(type default)
		)
		(layer "In4.Cu")
	)
	(gr_line
		(start 359.375456 -44.335192)
		(end 359.386886 -44.31792)
		(stroke
			(width 0.05715)
			(type default)
		)
		(layer "In4.Cu")
	)
	(gr_line
		(start 359.399332 -129.56667)
		(end 359.689146 -129.749804)
		(stroke
			(width 0.05715)
			(type default)
		)
		(layer "In4.Cu")
	)
	(gr_line
		(start 359.405428 -106.250486)
		(end 359.486962 -106.33202)
		(stroke
			(width 0.05715)
			(type default)
		)
		(layer "In4.Cu")
	)
	(gr_line
		(start 359.405428 -105.92816)
		(end 359.405428 -106.250486)
		(stroke
			(width 0.05715)
			(type default)
		)
		(layer "In4.Cu")
	)
	(gr_line
		(start 359.446322 -106.789474)
		(end 359.447084 -107.174284)
		(stroke
			(width 0.05715)
			(type default)
		)
		(layer "In4.Cu")
	)
	(gr_line
		(start 359.446322 -106.789474)
		(end 359.486962 -106.748834)
		(stroke
			(width 0.05715)
			(type default)
		)
		(layer "In4.Cu")
	)
	(gr_line
		(start 359.484676 -79.4004)
		(end 359.543604 -79.459328)
		(stroke
			(width 0.05715)
			(type default)
		)
		(layer "In4.Cu")
	)
	(gr_line
		(start 359.568242 -35.590734)
		(end 359.572306 -35.570922)
		(stroke
			(width 0.05715)
			(type default)
		)
		(layer "In4.Cu")
	)
	(gr_line
		(start 359.572306 -35.570922)
		(end 359.583482 -35.553904)
		(stroke
			(width 0.05715)
			(type default)
		)
		(layer "In4.Cu")
	)
	(gr_line
		(start 359.609136 -80.659732)
		(end 359.668064 -80.71866)
		(stroke
			(width 0.05715)
			(type default)
		)
		(layer "In4.Cu")
	)
	(gr_line
		(start 359.689146 -129.749804)
		(end 359.739946 -129.974086)
		(stroke
			(width 0.05715)
			(type default)
		)
		(layer "In4.Cu")
	)
	(gr_line
		(start 359.710482 -49.052988)
		(end 359.71734 -49.05121)
		(stroke
			(width 0.05715)
			(type default)
		)
		(layer "In4.Cu")
	)
	(gr_line
		(start 359.71734 -49.05121)
		(end 359.724198 -49.046892)
		(stroke
			(width 0.05715)
			(type default)
		)
		(layer "In4.Cu")
	)
	(gr_line
		(start 359.721404 -80.050386)
		(end 359.96245 -80.291432)
		(stroke
			(width 0.05715)
			(type default)
		)
		(layer "In4.Cu")
	)
	(gr_line
		(start 359.768394 -44.885864)
		(end 359.785666 -44.874434)
		(stroke
			(width 0.05715)
			(type default)
		)
		(layer "In4.Cu")
	)
	(gr_line
		(start 359.770172 -74.150728)
		(end 359.78973 -74.154792)
		(stroke
			(width 0.05715)
			(type default)
		)
		(layer "In4.Cu")
	)
	(gr_line
		(start 359.770172 -73.490328)
		(end 359.78973 -73.494392)
		(stroke
			(width 0.05715)
			(type default)
		)
		(layer "In4.Cu")
	)
	(gr_line
		(start 359.780078 -76.129388)
		(end 359.79989 -76.133452)
		(stroke
			(width 0.05715)
			(type default)
		)
		(layer "In4.Cu")
	)
	(gr_line
		(start 359.780078 -75.468988)
		(end 359.79989 -75.473052)
		(stroke
			(width 0.05715)
			(type default)
		)
		(layer "In4.Cu")
	)
	(gr_line
		(start 359.780078 -74.808842)
		(end 359.79989 -74.812906)
		(stroke
			(width 0.05715)
			(type default)
		)
		(layer "In4.Cu")
	)
	(gr_line
		(start 359.784396 -42.531284)
		(end 359.79481 -42.515282)
		(stroke
			(width 0.05715)
			(type default)
		)
		(layer "In4.Cu")
	)
	(gr_line
		(start 359.785666 -44.874434)
		(end 359.797096 -44.857162)
		(stroke
			(width 0.05715)
			(type default)
		)
		(layer "In4.Cu")
	)
	(gr_line
		(start 359.78973 -74.154792)
		(end 359.809288 -74.150728)
		(stroke
			(width 0.05715)
			(type default)
		)
		(layer "In4.Cu")
	)
	(gr_line
		(start 359.78973 -74.154792)
		(end 359.809542 -74.150728)
		(stroke
			(width 0.05715)
			(type default)
		)
		(layer "In4.Cu")
	)
	(gr_line
		(start 359.78973 -73.494392)
		(end 359.809288 -73.490328)
		(stroke
			(width 0.05715)
			(type default)
		)
		(layer "In4.Cu")
	)
	(gr_line
		(start 359.78973 -73.494392)
		(end 359.809542 -73.490328)
		(stroke
			(width 0.05715)
			(type default)
		)
		(layer "In4.Cu")
	)
	(gr_line
		(start 359.79481 -42.515282)
		(end 359.79862 -42.496486)
		(stroke
			(width 0.05715)
			(type default)
		)
		(layer "In4.Cu")
	)
	(gr_line
		(start 359.79989 -76.133452)
		(end 359.819448 -76.129388)
		(stroke
			(width 0.05715)
			(type default)
		)
		(layer "In4.Cu")
	)
	(gr_line
		(start 359.79989 -76.133452)
		(end 359.819702 -76.129388)
		(stroke
			(width 0.05715)
			(type default)
		)
		(layer "In4.Cu")
	)
	(gr_line
		(start 359.79989 -75.473052)
		(end 359.819702 -75.468988)
		(stroke
			(width 0.05715)
			(type default)
		)
		(layer "In4.Cu")
	)
	(gr_line
		(start 359.79989 -74.812906)
		(end 359.819702 -74.808842)
		(stroke
			(width 0.05715)
			(type default)
		)
		(layer "In4.Cu")
	)
	(gr_line
		(start 359.814876 -55.275988)
		(end 359.825544 -55.259732)
		(stroke
			(width 0.05715)
			(type default)
		)
		(layer "In4.Cu")
	)
	(gr_line
		(start 359.825544 -55.259732)
		(end 359.8418 -55.249064)
		(stroke
			(width 0.05715)
			(type default)
		)
		(layer "In4.Cu")
	)
	(gr_line
		(start 359.904792 -79.817214)
		(end 360.13517 -79.817214)
		(stroke
			(width 0.05715)
			(type default)
		)
		(layer "In4.Cu")
	)
	(gr_line
		(start 359.908856 -116.59362)
		(end 359.923842 -116.564918)
		(stroke
			(width 0.05715)
			(type default)
		)
		(layer "In4.Cu")
	)
	(gr_line
		(start 360.13517 -79.817214)
		(end 360.377486 -80.059784)
		(stroke
			(width 0.05715)
			(type default)
		)
		(layer "In4.Cu")
	)
	(gr_line
		(start 360.178858 -49.587658)
		(end 360.184954 -49.58588)
		(stroke
			(width 0.05715)
			(type default)
		)
		(layer "In4.Cu")
	)
	(gr_line
		(start 360.17962 -35.88004)
		(end 360.183938 -35.859212)
		(stroke
			(width 0.05715)
			(type default)
		)
		(layer "In4.Cu")
	)
	(gr_line
		(start 360.183938 -35.859212)
		(end 360.195622 -35.841686)
		(stroke
			(width 0.05715)
			(type default)
		)
		(layer "In4.Cu")
	)
	(gr_line
		(start 360.184954 -49.58588)
		(end 360.190034 -49.582578)
		(stroke
			(width 0.05715)
			(type default)
		)
		(layer "In4.Cu")
	)
	(gr_line
		(start 360.278172 -75.741022)
		(end 360.297984 -75.736958)
		(stroke
			(width 0.05715)
			(type default)
		)
		(layer "In4.Cu")
	)
	(gr_line
		(start 360.278172 -75.080876)
		(end 360.297984 -75.076812)
		(stroke
			(width 0.05715)
			(type default)
		)
		(layer "In4.Cu")
	)
	(gr_line
		(start 360.278172 -73.76033)
		(end 360.297984 -73.756266)
		(stroke
			(width 0.05715)
			(type default)
		)
		(layer "In4.Cu")
	)
	(gr_line
		(start 360.278172 -73.09993)
		(end 360.297984 -73.095866)
		(stroke
			(width 0.05715)
			(type default)
		)
		(layer "In4.Cu")
	)
	(gr_line
		(start 360.27868 -74.420476)
		(end 360.298492 -74.416412)
		(stroke
			(width 0.05715)
			(type default)
		)
		(layer "In4.Cu")
	)
	(gr_line
		(start 360.281728 -45.31233)
		(end 360.299 -45.3009)
		(stroke
			(width 0.05715)
			(type default)
		)
		(layer "In4.Cu")
	)
	(gr_line
		(start 360.297984 -75.736958)
		(end 360.317542 -75.741022)
		(stroke
			(width 0.05715)
			(type default)
		)
		(layer "In4.Cu")
	)
	(gr_line
		(start 360.297984 -75.076812)
		(end 360.317796 -75.080876)
		(stroke
			(width 0.05715)
			(type default)
		)
		(layer "In4.Cu")
	)
	(gr_line
		(start 360.297984 -73.756266)
		(end 360.317796 -73.76033)
		(stroke
			(width 0.05715)
			(type default)
		)
		(layer "In4.Cu")
	)
	(gr_line
		(start 360.297984 -73.095866)
		(end 360.317796 -73.09993)
		(stroke
			(width 0.05715)
			(type default)
		)
		(layer "In4.Cu")
	)
	(gr_line
		(start 360.298492 -74.416412)
		(end 360.318304 -74.420476)
		(stroke
			(width 0.05715)
			(type default)
		)
		(layer "In4.Cu")
	)
	(gr_line
		(start 360.299 -45.3009)
		(end 360.31043 -45.283628)
		(stroke
			(width 0.05715)
			(type default)
		)
		(layer "In4.Cu")
	)
	(gr_line
		(start 360.377486 -80.059784)
		(end 360.377486 -80.289908)
		(stroke
			(width 0.05715)
			(type default)
		)
		(layer "In4.Cu")
	)
	(gr_line
		(start 360.404156 -42.780712)
		(end 360.41457 -42.76471)
		(stroke
			(width 0.05715)
			(type default)
		)
		(layer "In4.Cu")
	)
	(gr_line
		(start 360.41457 -42.76471)
		(end 360.41838 -42.745914)
		(stroke
			(width 0.05715)
			(type default)
		)
		(layer "In4.Cu")
	)
	(gr_line
		(start 360.444796 -89.08796)
		(end 360.44886 -89.108026)
		(stroke
			(width 0.05715)
			(type default)
		)
		(layer "In4.Cu")
	)
	(gr_line
		(start 360.444796 -89.08796)
		(end 360.44886 -89.068402)
		(stroke
			(width 0.05715)
			(type default)
		)
		(layer "In4.Cu")
	)
	(gr_line
		(start 360.556556 -116.751608)
		(end 360.571542 -116.722906)
		(stroke
			(width 0.05715)
			(type default)
		)
		(layer "In4.Cu")
	)
	(gr_line
		(start 360.599228 -26.327862)
		(end 360.60888 -26.31313)
		(stroke
			(width 0.05715)
			(type default)
		)
		(layer "In4.Cu")
	)
	(gr_line
		(start 360.60888 -26.31313)
		(end 360.61269 -26.295858)
		(stroke
			(width 0.05715)
			(type default)
		)
		(layer "In4.Cu")
	)
	(gr_line
		(start 360.62158 -80.950816)
		(end 360.681016 -81.010252)
		(stroke
			(width 0.05715)
			(type default)
		)
		(layer "In4.Cu")
	)
	(gr_line
		(start 360.623358 -80.53578)
		(end 360.853482 -80.53578)
		(stroke
			(width 0.05715)
			(type default)
		)
		(layer "In4.Cu")
	)
	(gr_line
		(start 360.763058 -45.797978)
		(end 360.78033 -45.786548)
		(stroke
			(width 0.05715)
			(type default)
		)
		(layer "In4.Cu")
	)
	(gr_line
		(start 360.78033 -45.786548)
		(end 360.79176 -45.769276)
		(stroke
			(width 0.05715)
			(type default)
		)
		(layer "In4.Cu")
	)
	(gr_line
		(start 360.79176 -36.126166)
		(end 360.795824 -36.106354)
		(stroke
			(width 0.05715)
			(type default)
		)
		(layer "In4.Cu")
	)
	(gr_line
		(start 360.795824 -36.106354)
		(end 360.807 -36.089336)
		(stroke
			(width 0.05715)
			(type default)
		)
		(layer "In4.Cu")
	)
	(gr_line
		(start 360.82986 -83.015836)
		(end 360.839512 -83.06562)
		(stroke
			(width 0.05715)
			(type default)
		)
		(layer "In4.Cu")
	)
	(gr_line
		(start 360.853482 -80.53578)
		(end 361.096052 -80.778096)
		(stroke
			(width 0.05715)
			(type default)
		)
		(layer "In4.Cu")
	)
	(gr_line
		(start 360.90479 -75.8571)
		(end 360.93273 -75.862688)
		(stroke
			(width 0.05715)
			(type default)
		)
		(layer "In4.Cu")
	)
	(gr_line
		(start 360.93273 -75.862688)
		(end 360.95559 -75.879706)
		(stroke
			(width 0.05715)
			(type default)
		)
		(layer "In4.Cu")
	)
	(gr_line
		(start 360.973116 -125.444504)
		(end 360.97718 -125.46457)
		(stroke
			(width 0.05715)
			(type default)
		)
		(layer "In4.Cu")
	)
	(gr_line
		(start 360.973116 -125.444504)
		(end 360.97718 -125.424692)
		(stroke
			(width 0.05715)
			(type default)
		)
		(layer "In4.Cu")
	)
	(gr_line
		(start 360.973116 -124.447808)
		(end 360.97718 -124.467874)
		(stroke
			(width 0.05715)
			(type default)
		)
		(layer "In4.Cu")
	)
	(gr_line
		(start 360.973116 -124.447808)
		(end 360.97718 -124.427996)
		(stroke
			(width 0.05715)
			(type default)
		)
		(layer "In4.Cu")
	)
	(gr_line
		(start 360.973116 -123.451112)
		(end 360.97718 -123.471178)
		(stroke
			(width 0.05715)
			(type default)
		)
		(layer "In4.Cu")
	)
	(gr_line
		(start 360.973116 -123.451112)
		(end 360.97718 -123.4313)
		(stroke
			(width 0.05715)
			(type default)
		)
		(layer "In4.Cu")
	)
	(gr_line
		(start 360.973116 -122.454416)
		(end 360.97718 -122.474482)
		(stroke
			(width 0.05715)
			(type default)
		)
		(layer "In4.Cu")
	)
	(gr_line
		(start 360.973116 -122.454416)
		(end 360.97718 -122.434604)
		(stroke
			(width 0.05715)
			(type default)
		)
		(layer "In4.Cu")
	)
	(gr_line
		(start 360.973116 -121.45772)
		(end 360.97718 -121.477786)
		(stroke
			(width 0.05715)
			(type default)
		)
		(layer "In4.Cu")
	)
	(gr_line
		(start 360.973116 -121.45772)
		(end 360.97718 -121.437908)
		(stroke
			(width 0.05715)
			(type default)
		)
		(layer "In4.Cu")
	)
	(gr_line
		(start 360.973116 -120.461024)
		(end 360.97718 -120.48109)
		(stroke
			(width 0.05715)
			(type default)
		)
		(layer "In4.Cu")
	)
	(gr_line
		(start 360.973116 -120.461024)
		(end 360.97718 -120.441212)
		(stroke
			(width 0.05715)
			(type default)
		)
		(layer "In4.Cu")
	)
	(gr_line
		(start 360.9975 -53.361844)
		(end 361.010454 -53.3527)
		(stroke
			(width 0.05715)
			(type default)
		)
		(layer "In4.Cu")
	)
	(gr_line
		(start 361.001818 -43.037506)
		(end 361.01274 -43.020996)
		(stroke
			(width 0.05715)
			(type default)
		)
		(layer "In4.Cu")
	)
	(gr_line
		(start 361.010454 -53.3527)
		(end 361.025694 -53.348382)
		(stroke
			(width 0.05715)
			(type default)
		)
		(layer "In4.Cu")
	)
	(gr_line
		(start 361.01274 -43.020996)
		(end 361.016804 -43.001692)
		(stroke
			(width 0.05715)
			(type default)
		)
		(layer "In4.Cu")
	)
	(gr_line
		(start 361.074462 -51.649376)
		(end 361.082844 -51.643534)
		(stroke
			(width 0.05715)
			(type default)
		)
		(layer "In4.Cu")
	)
	(gr_line
		(start 361.082844 -51.643534)
		(end 361.09275 -51.640486)
		(stroke
			(width 0.05715)
			(type default)
		)
		(layer "In4.Cu")
	)
	(gr_line
		(start 361.096052 -80.778096)
		(end 361.096052 -81.008474)
		(stroke
			(width 0.05715)
			(type default)
		)
		(layer "In4.Cu")
	)
	(gr_line
		(start 361.098592 -89.056718)
		(end 361.102656 -89.076784)
		(stroke
			(width 0.05715)
			(type default)
		)
		(layer "In4.Cu")
	)
	(gr_line
		(start 361.098592 -89.056718)
		(end 361.102656 -89.03716)
		(stroke
			(width 0.05715)
			(type default)
		)
		(layer "In4.Cu")
	)
	(gr_line
		(start 361.108498 -77.477874)
		(end 361.112562 -77.49794)
		(stroke
			(width 0.05715)
			(type default)
		)
		(layer "In4.Cu")
	)
	(gr_line
		(start 361.108498 -77.477874)
		(end 361.112562 -77.497432)
		(stroke
			(width 0.05715)
			(type default)
		)
		(layer "In4.Cu")
	)
	(gr_line
		(start 361.108498 -77.477874)
		(end 361.112562 -77.458316)
		(stroke
			(width 0.05715)
			(type default)
		)
		(layer "In4.Cu")
	)
	(gr_line
		(start 361.108498 -77.477874)
		(end 361.112562 -77.457808)
		(stroke
			(width 0.05715)
			(type default)
		)
		(layer "In4.Cu")
	)
	(gr_line
		(start 361.136184 -126.269242)
		(end 361.140502 -126.290832)
		(stroke
			(width 0.05715)
			(type default)
		)
		(layer "In4.Cu")
	)
	(gr_line
		(start 361.140502 -126.290832)
		(end 361.15244 -126.308612)
		(stroke
			(width 0.05715)
			(type default)
		)
		(layer "In4.Cu")
	)
	(gr_line
		(start 361.174284 -75.25004)
		(end 361.202224 -75.255628)
		(stroke
			(width 0.05715)
			(type default)
		)
		(layer "In4.Cu")
	)
	(gr_line
		(start 361.183682 -88.626696)
		(end 361.29976 -88.040464)
		(stroke
			(width 0.05715)
			(type default)
		)
		(layer "In4.Cu")
	)
	(gr_line
		(start 361.202224 -75.255628)
		(end 361.225084 -75.272646)
		(stroke
			(width 0.05715)
			(type default)
		)
		(layer "In4.Cu")
	)
	(gr_line
		(start 361.205526 -46.304962)
		(end 361.222798 -46.293532)
		(stroke
			(width 0.05715)
			(type default)
		)
		(layer "In4.Cu")
	)
	(gr_line
		(start 361.222798 -46.293532)
		(end 361.234228 -46.27626)
		(stroke
			(width 0.05715)
			(type default)
		)
		(layer "In4.Cu")
	)
	(gr_line
		(start 361.265724 -98.607626)
		(end 361.269788 -98.627692)
		(stroke
			(width 0.05715)
			(type default)
		)
		(layer "In4.Cu")
	)
	(gr_line
		(start 361.265724 -98.607626)
		(end 361.269788 -98.588068)
		(stroke
			(width 0.05715)
			(type default)
		)
		(layer "In4.Cu")
	)
	(gr_line
		(start 361.300268 -2.937002)
		(end 361.674918 -2.937002)
		(stroke
			(width 0.05715)
			(type default)
		)
		(layer "In4.Cu")
	)
	(gr_line
		(start 361.322366 -52.311808)
		(end 361.332018 -52.30495)
		(stroke
			(width 0.05715)
			(type default)
		)
		(layer "In4.Cu")
	)
	(gr_line
		(start 361.331764 -76.160122)
		(end 361.367324 -76.186538)
		(stroke
			(width 0.05715)
			(type default)
		)
		(layer "In4.Cu")
	)
	(gr_line
		(start 361.332018 -52.30495)
		(end 361.34421 -52.301394)
		(stroke
			(width 0.05715)
			(type default)
		)
		(layer "In4.Cu")
	)
	(gr_line
		(start 361.335574 -82.38617)
		(end 361.372658 -82.423254)
		(stroke
			(width 0.05715)
			(type default)
		)
		(layer "In4.Cu")
	)
	(gr_line
		(start 361.365546 -124.966222)
		(end 361.36961 -124.946156)
		(stroke
			(width 0.05715)
			(type default)
		)
		(layer "In4.Cu")
	)
	(gr_line
		(start 361.365546 -124.926344)
		(end 361.36961 -124.946156)
		(stroke
			(width 0.05715)
			(type default)
		)
		(layer "In4.Cu")
	)
	(gr_line
		(start 361.365546 -123.969526)
		(end 361.36961 -123.94946)
		(stroke
			(width 0.05715)
			(type default)
		)
		(layer "In4.Cu")
	)
	(gr_line
		(start 361.365546 -123.929648)
		(end 361.36961 -123.94946)
		(stroke
			(width 0.05715)
			(type default)
		)
		(layer "In4.Cu")
	)
	(gr_line
		(start 361.365546 -122.97283)
		(end 361.36961 -122.952764)
		(stroke
			(width 0.05715)
			(type default)
		)
		(layer "In4.Cu")
	)
	(gr_line
		(start 361.365546 -122.932952)
		(end 361.36961 -122.952764)
		(stroke
			(width 0.05715)
			(type default)
		)
		(layer "In4.Cu")
	)
	(gr_line
		(start 361.365546 -121.976134)
		(end 361.36961 -121.956068)
		(stroke
			(width 0.05715)
			(type default)
		)
		(layer "In4.Cu")
	)
	(gr_line
		(start 361.365546 -121.936256)
		(end 361.36961 -121.956068)
		(stroke
			(width 0.05715)
			(type default)
		)
		(layer "In4.Cu")
	)
	(gr_line
		(start 361.365546 -120.979438)
		(end 361.36961 -120.959372)
		(stroke
			(width 0.05715)
			(type default)
		)
		(layer "In4.Cu")
	)
	(gr_line
		(start 361.365546 -120.93956)
		(end 361.36961 -120.959372)
		(stroke
			(width 0.05715)
			(type default)
		)
		(layer "In4.Cu")
	)
	(gr_line
		(start 361.365546 -119.982742)
		(end 361.36961 -119.962676)
		(stroke
			(width 0.05715)
			(type default)
		)
		(layer "In4.Cu")
	)
	(gr_line
		(start 361.365546 -119.943118)
		(end 361.36961 -119.962676)
		(stroke
			(width 0.05715)
			(type default)
		)
		(layer "In4.Cu")
	)
	(gr_line
		(start 361.367324 -76.186538)
		(end 361.384088 -76.22794)
		(stroke
			(width 0.05715)
			(type default)
		)
		(layer "In4.Cu")
	)
	(gr_line
		(start 361.372658 -82.423254)
		(end 361.382818 -82.474308)
		(stroke
			(width 0.05715)
			(type default)
		)
		(layer "In4.Cu")
	)
	(gr_line
		(start 361.38104 -87.629238)
		(end 361.497118 -87.042752)
		(stroke
			(width 0.05715)
			(type default)
		)
		(layer "In4.Cu")
	)
	(gr_line
		(start 361.383072 -85.851492)
		(end 361.387136 -85.831426)
		(stroke
			(width 0.05715)
			(type default)
		)
		(layer "In4.Cu")
	)
	(gr_line
		(start 361.383072 -85.811868)
		(end 361.387136 -85.831426)
		(stroke
			(width 0.05715)
			(type default)
		)
		(layer "In4.Cu")
	)
	(gr_line
		(start 361.420918 -36.331906)
		(end 361.424728 -36.31311)
		(stroke
			(width 0.05715)
			(type default)
		)
		(layer "In4.Cu")
	)
	(gr_line
		(start 361.424728 -36.312856)
		(end 361.424728 -36.31311)
		(stroke
			(width 0.05715)
			(type default)
		)
		(layer "In4.Cu")
	)
	(gr_line
		(start 361.424728 -36.312856)
		(end 361.435396 -36.296854)
		(stroke
			(width 0.05715)
			(type default)
		)
		(layer "In4.Cu")
	)
	(gr_line
		(start 361.430824 -50.610516)
		(end 361.438444 -50.605436)
		(stroke
			(width 0.05715)
			(type default)
		)
		(layer "In4.Cu")
	)
	(gr_line
		(start 361.438444 -50.605436)
		(end 361.447334 -50.602896)
		(stroke
			(width 0.05715)
			(type default)
		)
		(layer "In4.Cu")
	)
	(gr_line
		(start 361.44327 -74.642726)
		(end 361.47121 -74.648314)
		(stroke
			(width 0.05715)
			(type default)
		)
		(layer "In4.Cu")
	)
	(gr_line
		(start 361.456224 -26.209244)
		(end 361.465876 -26.194512)
		(stroke
			(width 0.05715)
			(type default)
		)
		(layer "In4.Cu")
	)
	(gr_line
		(start 361.465876 -88.718644)
		(end 361.657138 -88.590374)
		(stroke
			(width 0.05715)
			(type default)
		)
		(layer "In4.Cu")
	)
	(gr_line
		(start 361.465876 -26.194512)
		(end 361.469686 -26.17724)
		(stroke
			(width 0.05715)
			(type default)
		)
		(layer "In4.Cu")
	)
	(gr_line
		(start 361.47121 -74.648314)
		(end 361.49407 -74.665332)
		(stroke
			(width 0.05715)
			(type default)
		)
		(layer "In4.Cu")
	)
	(gr_line
		(start 361.478576 -54.160674)
		(end 361.485942 -54.155594)
		(stroke
			(width 0.05715)
			(type default)
		)
		(layer "In4.Cu")
	)
	(gr_line
		(start 361.485942 -54.155594)
		(end 361.495086 -54.153054)
		(stroke
			(width 0.05715)
			(type default)
		)
		(layer "In4.Cu")
	)
	(gr_line
		(start 361.546902 -76.630276)
		(end 361.56519 -76.675742)
		(stroke
			(width 0.05715)
			(type default)
		)
		(layer "In4.Cu")
	)
	(gr_line
		(start 361.555792 -76.723494)
		(end 361.56519 -76.675742)
		(stroke
			(width 0.05715)
			(type default)
		)
		(layer "In4.Cu")
	)
	(gr_line
		(start 361.59567 -88.062816)
		(end 361.723686 -88.254078)
		(stroke
			(width 0.05715)
			(type default)
		)
		(layer "In4.Cu")
	)
	(gr_line
		(start 361.61599 -43.311318)
		(end 361.626404 -43.295316)
		(stroke
			(width 0.05715)
			(type default)
		)
		(layer "In4.Cu")
	)
	(gr_line
		(start 361.626404 -43.295316)
		(end 361.630214 -43.27652)
		(stroke
			(width 0.05715)
			(type default)
		)
		(layer "In4.Cu")
	)
	(gr_line
		(start 361.628436 -123.476512)
		(end 361.6325 -123.496578)
		(stroke
			(width 0.05715)
			(type default)
		)
		(layer "In4.Cu")
	)
	(gr_line
		(start 361.628436 -123.476512)
		(end 361.6325 -123.4567)
		(stroke
			(width 0.05715)
			(type default)
		)
		(layer "In4.Cu")
	)
	(gr_line
		(start 361.633516 -125.444504)
		(end 361.63758 -125.464824)
		(stroke
			(width 0.05715)
			(type default)
		)
		(layer "In4.Cu")
	)
	(gr_line
		(start 361.633516 -125.444504)
		(end 361.63758 -125.424692)
		(stroke
			(width 0.05715)
			(type default)
		)
		(layer "In4.Cu")
	)
	(gr_line
		(start 361.633516 -124.447808)
		(end 361.63758 -124.467874)
		(stroke
			(width 0.05715)
			(type default)
		)
		(layer "In4.Cu")
	)
	(gr_line
		(start 361.633516 -124.447808)
		(end 361.63758 -124.427996)
		(stroke
			(width 0.05715)
			(type default)
		)
		(layer "In4.Cu")
	)
	(gr_line
		(start 361.633516 -122.454416)
		(end 361.63758 -122.474482)
		(stroke
			(width 0.05715)
			(type default)
		)
		(layer "In4.Cu")
	)
	(gr_line
		(start 361.633516 -122.454416)
		(end 361.63758 -122.434604)
		(stroke
			(width 0.05715)
			(type default)
		)
		(layer "In4.Cu")
	)
	(gr_line
		(start 361.633516 -120.461024)
		(end 361.63758 -120.48109)
		(stroke
			(width 0.05715)
			(type default)
		)
		(layer "In4.Cu")
	)
	(gr_line
		(start 361.633516 -120.461024)
		(end 361.63758 -120.441212)
		(stroke
			(width 0.05715)
			(type default)
		)
		(layer "In4.Cu")
	)
	(gr_line
		(start 361.638088 -121.434606)
		(end 361.642152 -121.454672)
		(stroke
			(width 0.05715)
			(type default)
		)
		(layer "In4.Cu")
	)
	(gr_line
		(start 361.638088 -121.434606)
		(end 361.642152 -121.41454)
		(stroke
			(width 0.05715)
			(type default)
		)
		(layer "In4.Cu")
	)
	(gr_line
		(start 361.657138 -88.590374)
		(end 361.723686 -88.254078)
		(stroke
			(width 0.05715)
			(type default)
		)
		(layer "In4.Cu")
	)
	(gr_line
		(start 361.66298 -87.721694)
		(end 361.854242 -87.593678)
		(stroke
			(width 0.05715)
			(type default)
		)
		(layer "In4.Cu")
	)
	(gr_line
		(start 361.674918 -2.937002)
		(end 361.726988 -2.989072)
		(stroke
			(width 0.05715)
			(type default)
		)
		(layer "In4.Cu")
	)
	(gr_line
		(start 361.69981 -36.426902)
		(end 361.69981 -36.42741)
		(stroke
			(width 0.05715)
			(type default)
		)
		(layer "In4.Cu")
	)
	(gr_line
		(start 361.713272 -74.03592)
		(end 361.741212 -74.041508)
		(stroke
			(width 0.05715)
			(type default)
		)
		(layer "In4.Cu")
	)
	(gr_line
		(start 361.72013 -46.739302)
		(end 361.737402 -46.727872)
		(stroke
			(width 0.05715)
			(type default)
		)
		(layer "In4.Cu")
	)
	(gr_line
		(start 361.737402 -46.727872)
		(end 361.748832 -46.7106)
		(stroke
			(width 0.05715)
			(type default)
		)
		(layer "In4.Cu")
	)
	(gr_line
		(start 361.737402 -6.021832)
		(end 361.811062 -6.356604)
		(stroke
			(width 0.05715)
			(type default)
		)
		(layer "In4.Cu")
	)
	(gr_line
		(start 361.737402 -6.021832)
		(end 361.8611 -5.827776)
		(stroke
			(width 0.05715)
			(type default)
		)
		(layer "In4.Cu")
	)
	(gr_line
		(start 361.741212 -74.041508)
		(end 361.741466 -74.041254)
		(stroke
			(width 0.05715)
			(type default)
		)
		(layer "In4.Cu")
	)
	(gr_line
		(start 361.741466 -74.041254)
		(end 361.765342 -74.059034)
		(stroke
			(width 0.05715)
			(type default)
		)
		(layer "In4.Cu")
	)
	(gr_line
		(start 361.748578 -80.711294)
		(end 361.754166 -80.739234)
		(stroke
			(width 0.05715)
			(type default)
		)
		(layer "In4.Cu")
	)
	(gr_line
		(start 361.749086 -126.030736)
		(end 361.753404 -126.052326)
		(stroke
			(width 0.05715)
			(type default)
		)
		(layer "In4.Cu")
	)
	(gr_line
		(start 361.753404 -126.052326)
		(end 361.765342 -126.070106)
		(stroke
			(width 0.05715)
			(type default)
		)
		(layer "In4.Cu")
	)
	(gr_line
		(start 361.754166 -80.73898)
		(end 361.754166 -80.739234)
		(stroke
			(width 0.05715)
			(type default)
		)
		(layer "In4.Cu")
	)
	(gr_line
		(start 361.754166 -80.73898)
		(end 361.770676 -80.760824)
		(stroke
			(width 0.05715)
			(type default)
		)
		(layer "In4.Cu")
	)
	(gr_line
		(start 361.768644 -77.477874)
		(end 361.772708 -77.49794)
		(stroke
			(width 0.05715)
			(type default)
		)
		(layer "In4.Cu")
	)
	(gr_line
		(start 361.768644 -77.477874)
		(end 361.772708 -77.458316)
		(stroke
			(width 0.05715)
			(type default)
		)
		(layer "In4.Cu")
	)
	(gr_line
		(start 361.792774 -87.06612)
		(end 361.92079 -87.257382)
		(stroke
			(width 0.05715)
			(type default)
		)
		(layer "In4.Cu")
	)
	(gr_line
		(start 361.811062 -6.356604)
		(end 362.004864 -6.480302)
		(stroke
			(width 0.05715)
			(type default)
		)
		(layer "In4.Cu")
	)
	(gr_line
		(start 361.844336 -89.487756)
		(end 361.848654 -89.509346)
		(stroke
			(width 0.05715)
			(type default)
		)
		(layer "In4.Cu")
	)
	(gr_line
		(start 361.844336 -89.487756)
		(end 361.848908 -89.465404)
		(stroke
			(width 0.05715)
			(type default)
		)
		(layer "In4.Cu")
	)
	(gr_line
		(start 361.854242 -87.593678)
		(end 361.92079 -87.257382)
		(stroke
			(width 0.05715)
			(type default)
		)
		(layer "In4.Cu")
	)
	(gr_line
		(start 361.864148 -75.748896)
		(end 361.899708 -75.775566)
		(stroke
			(width 0.05715)
			(type default)
		)
		(layer "In4.Cu")
	)
	(gr_line
		(start 361.887008 -81.802732)
		(end 361.924092 -81.839816)
		(stroke
			(width 0.05715)
			(type default)
		)
		(layer "In4.Cu")
	)
	(gr_line
		(start 361.899708 -75.775566)
		(end 361.916472 -75.816968)
		(stroke
			(width 0.05715)
			(type default)
		)
		(layer "In4.Cu")
	)
	(gr_line
		(start 361.924092 -81.839816)
		(end 361.934252 -81.89087)
		(stroke
			(width 0.05715)
			(type default)
		)
		(layer "In4.Cu")
	)
	(gr_line
		(start 361.955842 -7.013956)
		(end 362.029756 -7.348982)
		(stroke
			(width 0.05715)
			(type default)
		)
		(layer "In4.Cu")
	)
	(gr_line
		(start 361.955842 -7.013956)
		(end 362.079794 -6.820408)
		(stroke
			(width 0.05715)
			(type default)
		)
		(layer "In4.Cu")
	)
	(gr_line
		(start 361.959652 -98.437446)
		(end 361.963716 -98.457512)
		(stroke
			(width 0.05715)
			(type default)
		)
		(layer "In4.Cu")
	)
	(gr_line
		(start 361.959652 -98.437446)
		(end 361.963716 -98.417888)
		(stroke
			(width 0.05715)
			(type default)
		)
		(layer "In4.Cu")
	)
	(gr_line
		(start 361.98175 -73.428606)
		(end 362.00969 -73.434194)
		(stroke
			(width 0.05715)
			(type default)
		)
		(layer "In4.Cu")
	)
	(gr_line
		(start 362.00969 -73.434194)
		(end 362.010452 -73.434448)
		(stroke
			(width 0.05715)
			(type default)
		)
		(layer "In4.Cu")
	)
	(gr_line
		(start 362.010452 -73.434448)
		(end 362.033312 -73.451466)
		(stroke
			(width 0.05715)
			(type default)
		)
		(layer "In4.Cu")
	)
	(gr_line
		(start 362.015278 -36.621974)
		(end 362.019342 -36.602162)
		(stroke
			(width 0.05715)
			(type default)
		)
		(layer "In4.Cu")
	)
	(gr_line
		(start 362.019342 -36.602162)
		(end 362.030518 -36.585144)
		(stroke
			(width 0.05715)
			(type default)
		)
		(layer "In4.Cu")
	)
	(gr_line
		(start 362.020866 -123.995434)
		(end 362.02493 -123.97486)
		(stroke
			(width 0.05715)
			(type default)
		)
		(layer "In4.Cu")
	)
	(gr_line
		(start 362.020866 -123.955048)
		(end 362.02493 -123.97486)
		(stroke
			(width 0.05715)
			(type default)
		)
		(layer "In4.Cu")
	)
	(gr_line
		(start 362.025946 -124.966222)
		(end 362.03001 -124.946156)
		(stroke
			(width 0.05715)
			(type default)
		)
		(layer "In4.Cu")
	)
	(gr_line
		(start 362.025946 -124.926344)
		(end 362.03001 -124.946156)
		(stroke
			(width 0.05715)
			(type default)
		)
		(layer "In4.Cu")
	)
	(gr_line
		(start 362.025946 -122.97283)
		(end 362.03001 -122.952764)
		(stroke
			(width 0.05715)
			(type default)
		)
		(layer "In4.Cu")
	)
	(gr_line
		(start 362.025946 -122.932952)
		(end 362.03001 -122.952764)
		(stroke
			(width 0.05715)
			(type default)
		)
		(layer "In4.Cu")
	)
	(gr_line
		(start 362.025946 -120.979946)
		(end 362.03001 -120.959372)
		(stroke
			(width 0.05715)
			(type default)
		)
		(layer "In4.Cu")
	)
	(gr_line
		(start 362.025946 -120.93956)
		(end 362.03001 -120.959372)
		(stroke
			(width 0.05715)
			(type default)
		)
		(layer "In4.Cu")
	)
	(gr_line
		(start 362.029756 -7.348982)
		(end 362.223558 -7.472934)
		(stroke
			(width 0.05715)
			(type default)
		)
		(layer "In4.Cu")
	)
	(gr_line
		(start 362.030518 -121.953528)
		(end 362.034582 -121.933462)
		(stroke
			(width 0.05715)
			(type default)
		)
		(layer "In4.Cu")
	)
	(gr_line
		(start 362.030518 -121.91365)
		(end 362.034582 -121.933462)
		(stroke
			(width 0.05715)
			(type default)
		)
		(layer "In4.Cu")
	)
	(gr_line
		(start 362.030518 -119.960136)
		(end 362.034582 -119.94007)
		(stroke
			(width 0.05715)
			(type default)
		)
		(layer "In4.Cu")
	)
	(gr_line
		(start 362.030518 -119.920258)
		(end 362.034582 -119.94007)
		(stroke
			(width 0.05715)
			(type default)
		)
		(layer "In4.Cu")
	)
	(gr_line
		(start 362.036868 -85.819996)
		(end 362.040932 -85.79993)
		(stroke
			(width 0.05715)
			(type default)
		)
		(layer "In4.Cu")
	)
	(gr_line
		(start 362.036868 -85.780372)
		(end 362.040932 -85.79993)
		(stroke
			(width 0.05715)
			(type default)
		)
		(layer "In4.Cu")
	)
	(gr_line
		(start 362.091224 -95.941642)
		(end 362.095288 -95.921576)
		(stroke
			(width 0.05715)
			(type default)
		)
		(layer "In4.Cu")
	)
	(gr_line
		(start 362.091224 -95.902018)
		(end 362.095288 -95.921576)
		(stroke
			(width 0.05715)
			(type default)
		)
		(layer "In4.Cu")
	)
	(gr_line
		(start 362.143548 -2.989072)
		(end 362.195618 -2.937002)
		(stroke
			(width 0.05715)
			(type default)
		)
		(layer "In4.Cu")
	)
	(gr_line
		(start 362.156502 -5.799328)
		(end 362.284772 -6.381496)
		(stroke
			(width 0.05715)
			(type default)
		)
		(layer "In4.Cu")
	)
	(gr_line
		(start 362.15955 -127.802894)
		(end 362.188506 -127.846074)
		(stroke
			(width 0.05715)
			(type default)
		)
		(layer "In4.Cu")
	)
	(gr_line
		(start 362.174536 -8.006334)
		(end 362.248196 -8.341106)
		(stroke
			(width 0.05715)
			(type default)
		)
		(layer "In4.Cu")
	)
	(gr_line
		(start 362.174536 -8.006334)
		(end 362.298234 -7.812532)
		(stroke
			(width 0.05715)
			(type default)
		)
		(layer "In4.Cu")
	)
	(gr_line
		(start 362.188506 -127.846074)
		(end 362.23702 -127.865378)
		(stroke
			(width 0.05715)
			(type default)
		)
		(layer "In4.Cu")
	)
	(gr_line
		(start 362.195618 -2.937002)
		(end 362.570268 -2.937002)
		(stroke
			(width 0.05715)
			(type default)
		)
		(layer "In4.Cu")
	)
	(gr_line
		(start 362.208826 -43.628056)
		(end 362.219748 -43.611546)
		(stroke
			(width 0.05715)
			(type default)
		)
		(layer "In4.Cu")
	)
	(gr_line
		(start 362.219748 -76.566522)
		(end 362.238036 -76.611988)
		(stroke
			(width 0.05715)
			(type default)
		)
		(layer "In4.Cu")
	)
	(gr_line
		(start 362.219748 -43.611546)
		(end 362.223812 -43.591988)
		(stroke
			(width 0.05715)
			(type default)
		)
		(layer "In4.Cu")
	)
	(gr_line
		(start 362.228638 -76.65974)
		(end 362.238036 -76.611988)
		(stroke
			(width 0.05715)
			(type default)
		)
		(layer "In4.Cu")
	)
	(gr_line
		(start 362.240068 -26.215594)
		(end 362.250736 -26.199592)
		(stroke
			(width 0.05715)
			(type default)
		)
		(layer "In4.Cu")
	)
	(gr_line
		(start 362.248196 -8.341106)
		(end 362.441998 -8.464804)
		(stroke
			(width 0.05715)
			(type default)
		)
		(layer "In4.Cu")
	)
	(gr_line
		(start 362.250736 -26.199592)
		(end 362.2548 -26.180542)
		(stroke
			(width 0.05715)
			(type default)
		)
		(layer "In4.Cu")
	)
	(gr_line
		(start 362.293662 -124.447808)
		(end 362.297726 -124.467874)
		(stroke
			(width 0.05715)
			(type default)
		)
		(layer "In4.Cu")
	)
	(gr_line
		(start 362.293662 -124.447808)
		(end 362.297726 -124.427996)
		(stroke
			(width 0.05715)
			(type default)
		)
		(layer "In4.Cu")
	)
	(gr_line
		(start 362.293662 -122.454416)
		(end 362.297726 -122.474482)
		(stroke
			(width 0.05715)
			(type default)
		)
		(layer "In4.Cu")
	)
	(gr_line
		(start 362.293662 -122.454416)
		(end 362.297726 -122.434858)
		(stroke
			(width 0.05715)
			(type default)
		)
		(layer "In4.Cu")
	)
	(gr_line
		(start 362.293662 -120.461024)
		(end 362.297726 -120.48109)
		(stroke
			(width 0.05715)
			(type default)
		)
		(layer "In4.Cu")
	)
	(gr_line
		(start 362.293662 -120.461024)
		(end 362.297726 -120.441466)
		(stroke
			(width 0.05715)
			(type default)
		)
		(layer "In4.Cu")
	)
	(gr_line
		(start 362.293916 -123.449842)
		(end 362.29798 -123.469908)
		(stroke
			(width 0.05715)
			(type default)
		)
		(layer "In4.Cu")
	)
	(gr_line
		(start 362.293916 -123.449842)
		(end 362.29798 -123.43003)
		(stroke
			(width 0.05715)
			(type default)
		)
		(layer "In4.Cu")
	)
	(gr_line
		(start 362.296202 -125.432566)
		(end 362.300266 -125.45314)
		(stroke
			(width 0.05715)
			(type default)
		)
		(layer "In4.Cu")
	)
	(gr_line
		(start 362.296202 -125.432566)
		(end 362.300266 -125.412754)
		(stroke
			(width 0.05715)
			(type default)
		)
		(layer "In4.Cu")
	)
	(gr_line
		(start 362.302806 -121.412)
		(end 362.30687 -121.43232)
		(stroke
			(width 0.05715)
			(type default)
		)
		(layer "In4.Cu")
	)
	(gr_line
		(start 362.302806 -121.412)
		(end 362.30687 -121.392188)
		(stroke
			(width 0.05715)
			(type default)
		)
		(layer "In4.Cu")
	)
	(gr_line
		(start 362.355384 -80.4418)
		(end 362.360972 -80.46974)
		(stroke
			(width 0.05715)
			(type default)
		)
		(layer "In4.Cu")
	)
	(gr_line
		(start 362.360972 -80.46974)
		(end 362.37799 -80.4926)
		(stroke
			(width 0.05715)
			(type default)
		)
		(layer "In4.Cu")
	)
	(gr_line
		(start 362.369862 -125.805438)
		(end 362.37418 -125.827028)
		(stroke
			(width 0.05715)
			(type default)
		)
		(layer "In4.Cu")
	)
	(gr_line
		(start 362.37418 -125.827028)
		(end 362.386118 -125.844808)
		(stroke
			(width 0.05715)
			(type default)
		)
		(layer "In4.Cu")
	)
	(gr_line
		(start 362.375196 -6.79196)
		(end 362.50372 -7.375144)
		(stroke
			(width 0.05715)
			(type default)
		)
		(layer "In4.Cu")
	)
	(gr_line
		(start 362.392976 -8.998458)
		(end 362.46689 -9.33323)
		(stroke
			(width 0.05715)
			(type default)
		)
		(layer "In4.Cu")
	)
	(gr_line
		(start 362.392976 -8.998458)
		(end 362.516928 -8.804656)
		(stroke
			(width 0.05715)
			(type default)
		)
		(layer "In4.Cu")
	)
	(gr_line
		(start 362.396532 -75.337924)
		(end 362.432092 -75.364594)
		(stroke
			(width 0.05715)
			(type default)
		)
		(layer "In4.Cu")
	)
	(gr_line
		(start 362.42879 -77.477874)
		(end 362.432854 -77.49794)
		(stroke
			(width 0.05715)
			(type default)
		)
		(layer "In4.Cu")
	)
	(gr_line
		(start 362.42879 -77.477874)
		(end 362.432854 -77.458316)
		(stroke
			(width 0.05715)
			(type default)
		)
		(layer "In4.Cu")
	)
	(gr_line
		(start 362.430314 -81.157572)
		(end 362.447332 -81.180432)
		(stroke
			(width 0.05715)
			(type default)
		)
		(layer "In4.Cu")
	)
	(gr_line
		(start 362.432092 -75.364594)
		(end 362.448856 -75.405996)
		(stroke
			(width 0.05715)
			(type default)
		)
		(layer "In4.Cu")
	)
	(gr_line
		(start 362.447332 -81.180432)
		(end 362.452666 -81.208372)
		(stroke
			(width 0.05715)
			(type default)
		)
		(layer "In4.Cu")
	)
	(gr_line
		(start 362.46689 -9.33323)
		(end 362.660692 -9.457182)
		(stroke
			(width 0.05715)
			(type default)
		)
		(layer "In4.Cu")
	)
	(gr_line
		(start 362.491782 -106.628946)
		(end 362.495846 -106.649012)
		(stroke
			(width 0.05715)
			(type default)
		)
		(layer "In4.Cu")
	)
	(gr_line
		(start 362.491782 -106.628946)
		(end 362.495846 -106.609134)
		(stroke
			(width 0.05715)
			(type default)
		)
		(layer "In4.Cu")
	)
	(gr_line
		(start 362.494068 -107.612688)
		(end 362.498132 -107.632754)
		(stroke
			(width 0.05715)
			(type default)
		)
		(layer "In4.Cu")
	)
	(gr_line
		(start 362.494068 -107.612688)
		(end 362.498132 -107.592876)
		(stroke
			(width 0.05715)
			(type default)
		)
		(layer "In4.Cu")
	)
	(gr_line
		(start 362.494322 -105.61955)
		(end 362.498386 -105.639616)
		(stroke
			(width 0.05715)
			(type default)
		)
		(layer "In4.Cu")
	)
	(gr_line
		(start 362.494322 -105.61955)
		(end 362.498386 -105.599992)
		(stroke
			(width 0.05715)
			(type default)
		)
		(layer "In4.Cu")
	)
	(gr_line
		(start 362.57484 -127.270764)
		(end 362.603796 -127.313944)
		(stroke
			(width 0.05715)
			(type default)
		)
		(layer "In4.Cu")
	)
	(gr_line
		(start 362.59135 -89.052146)
		(end 362.595414 -89.072212)
		(stroke
			(width 0.05715)
			(type default)
		)
		(layer "In4.Cu")
	)
	(gr_line
		(start 362.59135 -89.052146)
		(end 362.595414 -89.071704)
		(stroke
			(width 0.05715)
			(type default)
		)
		(layer "In4.Cu")
	)
	(gr_line
		(start 362.59135 -89.052146)
		(end 362.595414 -89.032588)
		(stroke
			(width 0.05715)
			(type default)
		)
		(layer "In4.Cu")
	)
	(gr_line
		(start 362.59135 -89.052146)
		(end 362.595414 -89.03208)
		(stroke
			(width 0.05715)
			(type default)
		)
		(layer "In4.Cu")
	)
	(gr_line
		(start 362.59389 -7.78637)
		(end 362.72089 -8.363712)
		(stroke
			(width 0.05715)
			(type default)
		)
		(layer "In4.Cu")
	)
	(gr_line
		(start 362.603796 -127.313944)
		(end 362.65231 -127.333248)
		(stroke
			(width 0.05715)
			(type default)
		)
		(layer "In4.Cu")
	)
	(gr_line
		(start 362.628434 -98.396298)
		(end 362.632498 -98.416364)
		(stroke
			(width 0.05715)
			(type default)
		)
		(layer "In4.Cu")
	)
	(gr_line
		(start 362.628434 -98.396298)
		(end 362.632498 -98.376486)
		(stroke
			(width 0.05715)
			(type default)
		)
		(layer "In4.Cu")
	)
	(gr_line
		(start 362.633006 -36.86048)
		(end 362.63707 -36.840668)
		(stroke
			(width 0.05715)
			(type default)
		)
		(layer "In4.Cu")
	)
	(gr_line
		(start 362.63707 -36.840668)
		(end 362.647992 -36.824158)
		(stroke
			(width 0.05715)
			(type default)
		)
		(layer "In4.Cu")
	)
	(gr_line
		(start 362.686092 -122.97283)
		(end 362.690156 -122.952764)
		(stroke
			(width 0.05715)
			(type default)
		)
		(layer "In4.Cu")
	)
	(gr_line
		(start 362.686092 -122.932952)
		(end 362.690156 -122.952764)
		(stroke
			(width 0.05715)
			(type default)
		)
		(layer "In4.Cu")
	)
	(gr_line
		(start 362.686092 -120.979692)
		(end 362.690156 -120.959372)
		(stroke
			(width 0.05715)
			(type default)
		)
		(layer "In4.Cu")
	)
	(gr_line
		(start 362.686092 -120.93956)
		(end 362.690156 -120.959372)
		(stroke
			(width 0.05715)
			(type default)
		)
		(layer "In4.Cu")
	)
	(gr_line
		(start 362.686346 -124.966222)
		(end 362.69041 -124.946156)
		(stroke
			(width 0.05715)
			(type default)
		)
		(layer "In4.Cu")
	)
	(gr_line
		(start 362.686346 -124.926598)
		(end 362.69041 -124.946156)
		(stroke
			(width 0.05715)
			(type default)
		)
		(layer "In4.Cu")
	)
	(gr_line
		(start 362.686346 -123.968256)
		(end 362.69041 -123.94819)
		(stroke
			(width 0.05715)
			(type default)
		)
		(layer "In4.Cu")
	)
	(gr_line
		(start 362.686346 -123.928378)
		(end 362.69041 -123.94819)
		(stroke
			(width 0.05715)
			(type default)
		)
		(layer "In4.Cu")
	)
	(gr_line
		(start 362.695236 -121.930922)
		(end 362.6993 -121.910856)
		(stroke
			(width 0.05715)
			(type default)
		)
		(layer "In4.Cu")
	)
	(gr_line
		(start 362.695236 -121.891044)
		(end 362.6993 -121.910856)
		(stroke
			(width 0.05715)
			(type default)
		)
		(layer "In4.Cu")
	)
	(gr_line
		(start 362.696506 -119.930672)
		(end 362.70057 -119.910606)
		(stroke
			(width 0.05715)
			(type default)
		)
		(layer "In4.Cu")
	)
	(gr_line
		(start 362.696506 -119.890794)
		(end 362.70057 -119.910606)
		(stroke
			(width 0.05715)
			(type default)
		)
		(layer "In4.Cu")
	)
	(gr_line
		(start 362.75137 -95.941642)
		(end 362.755434 -95.921576)
		(stroke
			(width 0.05715)
			(type default)
		)
		(layer "In4.Cu")
	)
	(gr_line
		(start 362.75137 -95.902018)
		(end 362.755434 -95.921576)
		(stroke
			(width 0.05715)
			(type default)
		)
		(layer "In4.Cu")
	)
	(gr_line
		(start 362.776008 -99.141788)
		(end 362.892086 -99.72802)
		(stroke
			(width 0.05715)
			(type default)
		)
		(layer "In4.Cu")
	)
	(gr_line
		(start 362.785914 -86.236302)
		(end 362.789978 -86.216236)
		(stroke
			(width 0.05715)
			(type default)
		)
		(layer "In4.Cu")
	)
	(gr_line
		(start 362.785914 -86.196678)
		(end 362.789978 -86.216236)
		(stroke
			(width 0.05715)
			(type default)
		)
		(layer "In4.Cu")
	)
	(gr_line
		(start 362.812584 -8.77951)
		(end 362.939838 -9.356598)
		(stroke
			(width 0.05715)
			(type default)
		)
		(layer "In4.Cu")
	)
	(gr_line
		(start 362.816902 -109.2454)
		(end 362.820458 -109.262672)
		(stroke
			(width 0.05715)
			(type default)
		)
		(layer "In4.Cu")
	)
	(gr_line
		(start 362.820458 -109.262672)
		(end 362.829856 -109.277404)
		(stroke
			(width 0.05715)
			(type default)
		)
		(layer "In4.Cu")
	)
	(gr_line
		(start 362.86821 -105.235756)
		(end 362.872274 -105.21569)
		(stroke
			(width 0.05715)
			(type default)
		)
		(layer "In4.Cu")
	)
	(gr_line
		(start 362.86821 -105.196132)
		(end 362.872274 -105.21569)
		(stroke
			(width 0.05715)
			(type default)
		)
		(layer "In4.Cu")
	)
	(gr_line
		(start 362.875322 -26.443686)
		(end 362.884974 -26.428954)
		(stroke
			(width 0.05715)
			(type default)
		)
		(layer "In4.Cu")
	)
	(gr_line
		(start 362.883196 -43.784774)
		(end 362.894118 -43.76801)
		(stroke
			(width 0.05715)
			(type default)
		)
		(layer "In4.Cu")
	)
	(gr_line
		(start 362.884212 -107.146344)
		(end 362.888276 -107.126278)
		(stroke
			(width 0.05715)
			(type default)
		)
		(layer "In4.Cu")
	)
	(gr_line
		(start 362.884212 -107.10672)
		(end 362.888276 -107.126278)
		(stroke
			(width 0.05715)
			(type default)
		)
		(layer "In4.Cu")
	)
	(gr_line
		(start 362.884974 -26.428954)
		(end 362.888784 -26.411682)
		(stroke
			(width 0.05715)
			(type default)
		)
		(layer "In4.Cu")
	)
	(gr_line
		(start 362.886752 -106.137964)
		(end 362.890816 -106.117898)
		(stroke
			(width 0.05715)
			(type default)
		)
		(layer "In4.Cu")
	)
	(gr_line
		(start 362.886752 -106.098086)
		(end 362.890816 -106.117898)
		(stroke
			(width 0.05715)
			(type default)
		)
		(layer "In4.Cu")
	)
	(gr_line
		(start 362.892594 -76.502768)
		(end 362.910882 -76.548234)
		(stroke
			(width 0.05715)
			(type default)
		)
		(layer "In4.Cu")
	)
	(gr_line
		(start 362.894118 -43.76801)
		(end 362.897674 -43.749214)
		(stroke
			(width 0.05715)
			(type default)
		)
		(layer "In4.Cu")
	)
	(gr_line
		(start 362.901484 -76.59624)
		(end 362.910882 -76.548234)
		(stroke
			(width 0.05715)
			(type default)
		)
		(layer "In4.Cu")
	)
	(gr_line
		(start 362.92917 -74.927206)
		(end 362.96473 -74.953622)
		(stroke
			(width 0.05715)
			(type default)
		)
		(layer "In4.Cu")
	)
	(gr_line
		(start 362.962444 -80.17256)
		(end 362.967524 -80.19923)
		(stroke
			(width 0.05715)
			(type default)
		)
		(layer "In4.Cu")
	)
	(gr_line
		(start 362.96473 -74.953622)
		(end 362.981494 -74.995024)
		(stroke
			(width 0.05715)
			(type default)
		)
		(layer "In4.Cu")
	)
	(gr_line
		(start 362.967524 -80.19923)
		(end 362.967778 -80.199738)
		(stroke
			(width 0.05715)
			(type default)
		)
		(layer "In4.Cu")
	)
	(gr_line
		(start 362.967778 -80.199992)
		(end 362.984796 -80.222852)
		(stroke
			(width 0.05715)
			(type default)
		)
		(layer "In4.Cu")
	)
	(gr_line
		(start 362.967778 -80.199738)
		(end 362.967778 -80.199992)
		(stroke
			(width 0.05715)
			(type default)
		)
		(layer "In4.Cu")
	)
	(gr_line
		(start 362.973112 -100.137722)
		(end 363.088936 -100.723192)
		(stroke
			(width 0.05715)
			(type default)
		)
		(layer "In4.Cu")
	)
	(gr_line
		(start 362.98759 -126.736856)
		(end 363.017562 -126.781306)
		(stroke
			(width 0.05715)
			(type default)
		)
		(layer "In4.Cu")
	)
	(gr_line
		(start 363.004862 -49.116488)
		(end 363.00791 -49.115472)
		(stroke
			(width 0.05715)
			(type default)
		)
		(layer "In4.Cu")
	)
	(gr_line
		(start 363.017562 -126.781306)
		(end 363.0676 -126.801118)
		(stroke
			(width 0.05715)
			(type default)
		)
		(layer "In4.Cu")
	)
	(gr_line
		(start 363.038136 -80.889094)
		(end 363.053376 -80.909668)
		(stroke
			(width 0.05715)
			(type default)
		)
		(layer "In4.Cu")
	)
	(gr_line
		(start 363.053376 -80.909668)
		(end 363.054646 -80.911446)
		(stroke
			(width 0.05715)
			(type default)
		)
		(layer "In4.Cu")
	)
	(gr_line
		(start 363.054646 -80.911446)
		(end 363.060234 -80.939132)
		(stroke
			(width 0.05715)
			(type default)
		)
		(layer "In4.Cu")
	)
	(gr_line
		(start 363.057948 -99.049078)
		(end 363.24921 -99.177094)
		(stroke
			(width 0.05715)
			(type default)
		)
		(layer "In4.Cu")
	)
	(gr_line
		(start 363.073442 -37.952172)
		(end 363.077252 -37.933884)
		(stroke
			(width 0.05715)
			(type default)
		)
		(layer "In4.Cu")
	)
	(gr_line
		(start 363.077252 -37.933884)
		(end 363.087412 -37.918898)
		(stroke
			(width 0.05715)
			(type default)
		)
		(layer "In4.Cu")
	)
	(gr_line
		(start 363.08919 -77.478382)
		(end 363.093 -77.459586)
		(stroke
			(width 0.05715)
			(type default)
		)
		(layer "In4.Cu")
	)
	(gr_line
		(start 363.08919 -77.478382)
		(end 363.093 -77.45857)
		(stroke
			(width 0.05715)
			(type default)
		)
		(layer "In4.Cu")
	)
	(gr_line
		(start 363.08919 -77.478382)
		(end 363.093254 -77.498702)
		(stroke
			(width 0.05715)
			(type default)
		)
		(layer "In4.Cu")
	)
	(gr_line
		(start 363.08919 -77.478382)
		(end 363.093254 -77.498448)
		(stroke
			(width 0.05715)
			(type default)
		)
		(layer "In4.Cu")
	)
	(gr_line
		(start 363.152436 -55.18785)
		(end 363.152436 -55.418228)
		(stroke
			(width 0.05715)
			(type default)
		)
		(layer "In4.Cu")
	)
	(gr_line
		(start 363.152436 -55.18785)
		(end 363.395006 -54.945534)
		(stroke
			(width 0.05715)
			(type default)
		)
		(layer "In4.Cu")
	)
	(gr_line
		(start 363.154468 -107.612688)
		(end 363.158532 -107.632754)
		(stroke
			(width 0.05715)
			(type default)
		)
		(layer "In4.Cu")
	)
	(gr_line
		(start 363.154468 -107.612688)
		(end 363.158532 -107.592876)
		(stroke
			(width 0.05715)
			(type default)
		)
		(layer "In4.Cu")
	)
	(gr_line
		(start 363.154722 -106.616246)
		(end 363.158786 -106.636566)
		(stroke
			(width 0.05715)
			(type default)
		)
		(layer "In4.Cu")
	)
	(gr_line
		(start 363.154722 -106.616246)
		(end 363.158786 -106.596434)
		(stroke
			(width 0.05715)
			(type default)
		)
		(layer "In4.Cu")
	)
	(gr_line
		(start 363.154722 -105.61955)
		(end 363.158786 -105.639616)
		(stroke
			(width 0.05715)
			(type default)
		)
		(layer "In4.Cu")
	)
	(gr_line
		(start 363.154722 -105.61955)
		(end 363.158786 -105.599738)
		(stroke
			(width 0.05715)
			(type default)
		)
		(layer "In4.Cu")
	)
	(gr_line
		(start 363.187742 -99.704906)
		(end 363.315758 -99.51339)
		(stroke
			(width 0.05715)
			(type default)
		)
		(layer "In4.Cu")
	)
	(gr_line
		(start 363.24921 -99.177094)
		(end 363.315758 -99.51339)
		(stroke
			(width 0.05715)
			(type default)
		)
		(layer "In4.Cu")
	)
	(gr_line
		(start 363.255052 -100.045774)
		(end 363.446314 -100.17379)
		(stroke
			(width 0.05715)
			(type default)
		)
		(layer "In4.Cu")
	)
	(gr_line
		(start 363.311694 -89.190576)
		(end 363.378242 -89.526872)
		(stroke
			(width 0.05715)
			(type default)
		)
		(layer "In4.Cu")
	)
	(gr_line
		(start 363.311694 -89.190576)
		(end 363.43971 -88.999314)
		(stroke
			(width 0.05715)
			(type default)
		)
		(layer "In4.Cu")
	)
	(gr_line
		(start 363.35208 -88.543892)
		(end 363.356144 -88.563958)
		(stroke
			(width 0.05715)
			(type default)
		)
		(layer "In4.Cu")
	)
	(gr_line
		(start 363.35208 -88.543892)
		(end 363.356144 -88.524334)
		(stroke
			(width 0.05715)
			(type default)
		)
		(layer "In4.Cu")
	)
	(gr_line
		(start 363.378242 -89.526872)
		(end 363.569504 -89.655142)
		(stroke
			(width 0.05715)
			(type default)
		)
		(layer "In4.Cu")
	)
	(gr_line
		(start 363.384846 -100.701348)
		(end 363.512862 -100.510086)
		(stroke
			(width 0.05715)
			(type default)
		)
		(layer "In4.Cu")
	)
	(gr_line
		(start 363.385354 -108.78058)
		(end 363.38891 -108.797852)
		(stroke
			(width 0.05715)
			(type default)
		)
		(layer "In4.Cu")
	)
	(gr_line
		(start 363.385608 -55.601616)
		(end 363.626654 -55.36057)
		(stroke
			(width 0.05715)
			(type default)
		)
		(layer "In4.Cu")
	)
	(gr_line
		(start 363.38891 -108.797852)
		(end 363.398308 -108.812584)
		(stroke
			(width 0.05715)
			(type default)
		)
		(layer "In4.Cu")
	)
	(gr_line
		(start 363.395006 -54.945534)
		(end 363.62513 -54.945534)
		(stroke
			(width 0.05715)
			(type default)
		)
		(layer "In4.Cu")
	)
	(gr_line
		(start 363.41177 -95.941896)
		(end 363.415834 -95.92183)
		(stroke
			(width 0.05715)
			(type default)
		)
		(layer "In4.Cu")
	)
	(gr_line
		(start 363.41177 -95.902272)
		(end 363.415834 -95.92183)
		(stroke
			(width 0.05715)
			(type default)
		)
		(layer "In4.Cu")
	)
	(gr_line
		(start 363.436154 -97.648522)
		(end 363.440218 -97.668588)
		(stroke
			(width 0.05715)
			(type default)
		)
		(layer "In4.Cu")
	)
	(gr_line
		(start 363.436154 -97.648522)
		(end 363.440218 -97.668334)
		(stroke
			(width 0.05715)
			(type default)
		)
		(layer "In4.Cu")
	)
	(gr_line
		(start 363.436154 -97.648522)
		(end 363.440218 -97.628964)
		(stroke
			(width 0.05715)
			(type default)
		)
		(layer "In4.Cu")
	)
	(gr_line
		(start 363.436154 -97.648522)
		(end 363.440218 -97.628456)
		(stroke
			(width 0.05715)
			(type default)
		)
		(layer "In4.Cu")
	)
	(gr_line
		(start 363.443266 -86.252304)
		(end 363.44733 -86.232238)
		(stroke
			(width 0.05715)
			(type default)
		)
		(layer "In4.Cu")
	)
	(gr_line
		(start 363.443266 -86.21268)
		(end 363.44733 -86.232238)
		(stroke
			(width 0.05715)
			(type default)
		)
		(layer "In4.Cu")
	)
	(gr_line
		(start 363.446314 -100.17379)
		(end 363.512862 -100.510086)
		(stroke
			(width 0.05715)
			(type default)
		)
		(layer "In4.Cu")
	)
	(gr_line
		(start 363.461554 -74.51598)
		(end 363.497114 -74.54265)
		(stroke
			(width 0.05715)
			(type default)
		)
		(layer "In4.Cu")
	)
	(gr_line
		(start 363.466634 -44.115482)
		(end 363.477556 -44.098718)
		(stroke
			(width 0.05715)
			(type default)
		)
		(layer "In4.Cu")
	)
	(gr_line
		(start 363.477556 -44.098718)
		(end 363.481112 -44.079922)
		(stroke
			(width 0.05715)
			(type default)
		)
		(layer "In4.Cu")
	)
	(gr_line
		(start 363.48035 -1.970024)
		(end 363.855 -1.970024)
		(stroke
			(width 0.05715)
			(type default)
		)
		(layer "In4.Cu")
	)
	(gr_line
		(start 363.497114 -74.54265)
		(end 363.513878 -74.584052)
		(stroke
			(width 0.05715)
			(type default)
		)
		(layer "In4.Cu")
	)
	(gr_line
		(start 363.509052 -90.187272)
		(end 363.5756 -90.523568)
		(stroke
			(width 0.05715)
			(type default)
		)
		(layer "In4.Cu")
	)
	(gr_line
		(start 363.509052 -90.187272)
		(end 363.637068 -89.99601)
		(stroke
			(width 0.05715)
			(type default)
		)
		(layer "In4.Cu")
	)
	(gr_line
		(start 363.51972 -110.350808)
		(end 363.541818 -110.385098)
		(stroke
			(width 0.05715)
			(type default)
		)
		(layer "In4.Cu")
	)
	(gr_line
		(start 363.532674 -26.626058)
		(end 363.542326 -26.611326)
		(stroke
			(width 0.05715)
			(type default)
		)
		(layer "In4.Cu")
	)
	(gr_line
		(start 363.541818 -110.385098)
		(end 363.57814 -110.40364)
		(stroke
			(width 0.05715)
			(type default)
		)
		(layer "In4.Cu")
	)
	(gr_line
		(start 363.542326 -26.611326)
		(end 363.546136 -26.594054)
		(stroke
			(width 0.05715)
			(type default)
		)
		(layer "In4.Cu")
	)
	(gr_line
		(start 363.546898 -107.134406)
		(end 363.550962 -107.11434)
		(stroke
			(width 0.05715)
			(type default)
		)
		(layer "In4.Cu")
	)
	(gr_line
		(start 363.546898 -107.094528)
		(end 363.550962 -107.11434)
		(stroke
			(width 0.05715)
			(type default)
		)
		(layer "In4.Cu")
	)
	(gr_line
		(start 363.547152 -106.137964)
		(end 363.551216 -106.117898)
		(stroke
			(width 0.05715)
			(type default)
		)
		(layer "In4.Cu")
	)
	(gr_line
		(start 363.547152 -106.098086)
		(end 363.551216 -106.117898)
		(stroke
			(width 0.05715)
			(type default)
		)
		(layer "In4.Cu")
	)
	(gr_line
		(start 363.56163 -105.068116)
		(end 363.565694 -105.047542)
		(stroke
			(width 0.05715)
			(type default)
		)
		(layer "In4.Cu")
	)
	(gr_line
		(start 363.56163 -105.027984)
		(end 363.565694 -105.047542)
		(stroke
			(width 0.05715)
			(type default)
		)
		(layer "In4.Cu")
	)
	(gr_line
		(start 363.56544 -76.439014)
		(end 363.583728 -76.48448)
		(stroke
			(width 0.05715)
			(type default)
		)
		(layer "In4.Cu")
	)
	(gr_line
		(start 363.56925 -79.90332)
		(end 363.574838 -79.93126)
		(stroke
			(width 0.05715)
			(type default)
		)
		(layer "In4.Cu")
	)
	(gr_line
		(start 363.57433 -76.532232)
		(end 363.583728 -76.48448)
		(stroke
			(width 0.05715)
			(type default)
		)
		(layer "In4.Cu")
	)
	(gr_line
		(start 363.574838 -79.93126)
		(end 363.591856 -79.95412)
		(stroke
			(width 0.05715)
			(type default)
		)
		(layer "In4.Cu")
	)
	(gr_line
		(start 363.5756 -90.523568)
		(end 363.766862 -90.651584)
		(stroke
			(width 0.05715)
			(type default)
		)
		(layer "In4.Cu")
	)
	(gr_line
		(start 363.592618 -12.367006)
		(end 363.597952 -12.342368)
		(stroke
			(width 0.05715)
			(type default)
		)
		(layer "In4.Cu")
	)
	(gr_line
		(start 363.592618 -12.31773)
		(end 363.597952 -12.342368)
		(stroke
			(width 0.05715)
			(type default)
		)
		(layer "In4.Cu")
	)
	(gr_line
		(start 363.644688 -80.6196)
		(end 363.661198 -80.641444)
		(stroke
			(width 0.05715)
			(type default)
		)
		(layer "In4.Cu")
	)
	(gr_line
		(start 363.661198 -80.641444)
		(end 363.666278 -80.668114)
		(stroke
			(width 0.05715)
			(type default)
		)
		(layer "In4.Cu")
	)
	(gr_line
		(start 363.706156 -91.183968)
		(end 363.772704 -91.520264)
		(stroke
			(width 0.05715)
			(type default)
		)
		(layer "In4.Cu")
	)
	(gr_line
		(start 363.706156 -91.183968)
		(end 363.834172 -90.992706)
		(stroke
			(width 0.05715)
			(type default)
		)
		(layer "In4.Cu")
	)
	(gr_line
		(start 363.726984 -38.118288)
		(end 363.730794 -38.098222)
		(stroke
			(width 0.05715)
			(type default)
		)
		(layer "In4.Cu")
	)
	(gr_line
		(start 363.730794 -38.098222)
		(end 363.742224 -38.08095)
		(stroke
			(width 0.05715)
			(type default)
		)
		(layer "In4.Cu")
	)
	(gr_line
		(start 363.73562 -88.976962)
		(end 363.851698 -89.563194)
		(stroke
			(width 0.05715)
			(type default)
		)
		(layer "In4.Cu")
	)
	(gr_line
		(start 363.749336 -77.477874)
		(end 363.74959 -77.477874)
		(stroke
			(width 0.05715)
			(type default)
		)
		(layer "In4.Cu")
	)
	(gr_line
		(start 363.749336 -77.477874)
		(end 363.753146 -77.497686)
		(stroke
			(width 0.05715)
			(type default)
		)
		(layer "In4.Cu")
	)
	(gr_line
		(start 363.749336 -77.477874)
		(end 363.7534 -77.498448)
		(stroke
			(width 0.05715)
			(type default)
		)
		(layer "In4.Cu")
	)
	(gr_line
		(start 363.74959 -77.477874)
		(end 363.753146 -77.460348)
		(stroke
			(width 0.05715)
			(type default)
		)
		(layer "In4.Cu")
	)
	(gr_line
		(start 363.74959 -77.477874)
		(end 363.753146 -77.459332)
		(stroke
			(width 0.05715)
			(type default)
		)
		(layer "In4.Cu")
	)
	(gr_line
		(start 363.772704 -91.520264)
		(end 363.963966 -91.648534)
		(stroke
			(width 0.05715)
			(type default)
		)
		(layer "In4.Cu")
	)
	(gr_line
		(start 363.811566 -107.595416)
		(end 363.81563 -107.615736)
		(stroke
			(width 0.05715)
			(type default)
		)
		(layer "In4.Cu")
	)
	(gr_line
		(start 363.811566 -107.595416)
		(end 363.81563 -107.575604)
		(stroke
			(width 0.05715)
			(type default)
		)
		(layer "In4.Cu")
	)
	(gr_line
		(start 363.814868 -106.616246)
		(end 363.818932 -106.636312)
		(stroke
			(width 0.05715)
			(type default)
		)
		(layer "In4.Cu")
	)
	(gr_line
		(start 363.814868 -106.616246)
		(end 363.818932 -106.596434)
		(stroke
			(width 0.05715)
			(type default)
		)
		(layer "In4.Cu")
	)
	(gr_line
		(start 363.814868 -105.61955)
		(end 363.818932 -105.639616)
		(stroke
			(width 0.05715)
			(type default)
		)
		(layer "In4.Cu")
	)
	(gr_line
		(start 363.814868 -105.61955)
		(end 363.818932 -105.599738)
		(stroke
			(width 0.05715)
			(type default)
		)
		(layer "In4.Cu")
	)
	(gr_line
		(start 363.855 -1.970024)
		(end 363.90707 -2.022094)
		(stroke
			(width 0.05715)
			(type default)
		)
		(layer "In4.Cu")
	)
	(gr_line
		(start 363.903514 -92.180664)
		(end 363.970062 -92.51696)
		(stroke
			(width 0.05715)
			(type default)
		)
		(layer "In4.Cu")
	)
	(gr_line
		(start 363.903514 -92.180664)
		(end 364.03153 -91.989402)
		(stroke
			(width 0.05715)
			(type default)
		)
		(layer "In4.Cu")
	)
	(gr_line
		(start 363.914436 -108.11764)
		(end 363.915198 -108.121196)
		(stroke
			(width 0.05715)
			(type default)
		)
		(layer "In4.Cu")
	)
	(gr_line
		(start 363.915198 -108.121196)
		(end 363.916722 -108.123736)
		(stroke
			(width 0.05715)
			(type default)
		)
		(layer "In4.Cu")
	)
	(gr_line
		(start 363.932978 -89.973912)
		(end 364.048548 -90.558874)
		(stroke
			(width 0.05715)
			(type default)
		)
		(layer "In4.Cu")
	)
	(gr_line
		(start 363.970062 -92.51696)
		(end 364.161324 -92.64523)
		(stroke
			(width 0.05715)
			(type default)
		)
		(layer "In4.Cu")
	)
	(gr_line
		(start 363.994192 -80.494124)
		(end 363.994446 -80.494124)
		(stroke
			(width 0.05715)
			(type default)
		)
		(layer "In4.Cu")
	)
	(gr_line
		(start 364.103412 -86.252304)
		(end 364.107476 -86.232238)
		(stroke
			(width 0.05715)
			(type default)
		)
		(layer "In4.Cu")
	)
	(gr_line
		(start 364.103412 -86.21268)
		(end 364.107476 -86.232238)
		(stroke
			(width 0.05715)
			(type default)
		)
		(layer "In4.Cu")
	)
	(gr_line
		(start 364.11408 -109.926628)
		(end 364.136178 -109.960918)
		(stroke
			(width 0.05715)
			(type default)
		)
		(layer "In4.Cu")
	)
	(gr_line
		(start 364.127034 -88.432386)
		(end 364.193582 -88.768682)
		(stroke
			(width 0.05715)
			(type default)
		)
		(layer "In4.Cu")
	)
	(gr_line
		(start 364.127034 -88.432386)
		(end 364.25505 -88.24087)
		(stroke
			(width 0.05715)
			(type default)
		)
		(layer "In4.Cu")
	)
	(gr_line
		(start 364.130336 -90.97137)
		(end 364.245906 -91.556332)
		(stroke
			(width 0.05715)
			(type default)
		)
		(layer "In4.Cu")
	)
	(gr_line
		(start 364.136178 -109.960918)
		(end 364.1725 -109.97946)
		(stroke
			(width 0.05715)
			(type default)
		)
		(layer "In4.Cu")
	)
	(gr_line
		(start 364.158276 -95.50527)
		(end 364.16234 -95.485204)
		(stroke
			(width 0.05715)
			(type default)
		)
		(layer "In4.Cu")
	)
	(gr_line
		(start 364.158276 -95.465646)
		(end 364.16234 -95.485204)
		(stroke
			(width 0.05715)
			(type default)
		)
		(layer "In4.Cu")
	)
	(gr_line
		(start 364.16488 -87.773002)
		(end 364.168944 -87.793576)
		(stroke
			(width 0.05715)
			(type default)
		)
		(layer "In4.Cu")
	)
	(gr_line
		(start 364.16488 -87.773002)
		(end 364.168944 -87.753444)
		(stroke
			(width 0.05715)
			(type default)
		)
		(layer "In4.Cu")
	)
	(gr_line
		(start 364.175294 -26.817828)
		(end 364.184946 -26.803096)
		(stroke
			(width 0.05715)
			(type default)
		)
		(layer "In4.Cu")
	)
	(gr_line
		(start 364.175802 -79.63281)
		(end 364.181136 -79.65948)
		(stroke
			(width 0.05715)
			(type default)
		)
		(layer "In4.Cu")
	)
	(gr_line
		(start 364.176056 -79.633572)
		(end 364.181136 -79.65948)
		(stroke
			(width 0.05715)
			(type default)
		)
		(layer "In4.Cu")
	)
	(gr_line
		(start 364.181136 -79.65948)
		(end 364.181644 -79.661258)
		(stroke
			(width 0.05715)
			(type default)
		)
		(layer "In4.Cu")
	)
	(gr_line
		(start 364.181644 -79.661258)
		(end 364.198154 -79.683356)
		(stroke
			(width 0.05715)
			(type default)
		)
		(layer "In4.Cu")
	)
	(gr_line
		(start 364.181644 -79.661258)
		(end 364.198662 -79.684118)
		(stroke
			(width 0.05715)
			(type default)
		)
		(layer "In4.Cu")
	)
	(gr_line
		(start 364.184946 -26.803096)
		(end 364.188756 -26.785824)
		(stroke
			(width 0.05715)
			(type default)
		)
		(layer "In4.Cu")
	)
	(gr_line
		(start 364.193582 -88.768682)
		(end 364.384844 -88.896952)
		(stroke
			(width 0.05715)
			(type default)
		)
		(layer "In4.Cu")
	)
	(gr_line
		(start 364.203996 -107.117134)
		(end 364.20806 -107.097068)
		(stroke
			(width 0.05715)
			(type default)
		)
		(layer "In4.Cu")
	)
	(gr_line
		(start 364.203996 -107.07751)
		(end 364.20806 -107.097068)
		(stroke
			(width 0.05715)
			(type default)
		)
		(layer "In4.Cu")
	)
	(gr_line
		(start 364.207298 -106.137964)
		(end 364.211362 -106.117898)
		(stroke
			(width 0.05715)
			(type default)
		)
		(layer "In4.Cu")
	)
	(gr_line
		(start 364.207298 -106.098086)
		(end 364.211362 -106.117898)
		(stroke
			(width 0.05715)
			(type default)
		)
		(layer "In4.Cu")
	)
	(gr_line
		(start 364.214156 -53.410104)
		(end 364.22076 -53.4035)
		(stroke
			(width 0.05715)
			(type default)
		)
		(layer "In4.Cu")
	)
	(gr_line
		(start 364.221776 -97.015554)
		(end 364.22584 -97.03562)
		(stroke
			(width 0.05715)
			(type default)
		)
		(layer "In4.Cu")
	)
	(gr_line
		(start 364.221776 -97.015554)
		(end 364.22584 -96.995742)
		(stroke
			(width 0.05715)
			(type default)
		)
		(layer "In4.Cu")
	)
	(gr_line
		(start 364.230158 -105.025952)
		(end 364.234222 -105.005886)
		(stroke
			(width 0.05715)
			(type default)
		)
		(layer "In4.Cu")
	)
	(gr_line
		(start 364.230158 -104.986328)
		(end 364.234222 -105.005886)
		(stroke
			(width 0.05715)
			(type default)
		)
		(layer "In4.Cu")
	)
	(gr_line
		(start 364.23854 -76.37526)
		(end 364.256828 -76.420726)
		(stroke
			(width 0.05715)
			(type default)
		)
		(layer "In4.Cu")
	)
	(gr_line
		(start 364.24743 -76.468732)
		(end 364.256828 -76.420726)
		(stroke
			(width 0.05715)
			(type default)
		)
		(layer "In4.Cu")
	)
	(gr_line
		(start 364.251494 -80.350106)
		(end 364.268258 -80.372712)
		(stroke
			(width 0.05715)
			(type default)
		)
		(layer "In4.Cu")
	)
	(gr_line
		(start 364.268258 -80.372458)
		(end 364.268258 -80.372712)
		(stroke
			(width 0.05715)
			(type default)
		)
		(layer "In4.Cu")
	)
	(gr_line
		(start 364.268258 -80.372458)
		(end 364.273592 -80.399636)
		(stroke
			(width 0.05715)
			(type default)
		)
		(layer "In4.Cu")
	)
	(gr_line
		(start 364.305596 -38.468808)
		(end 364.30966 -38.448742)
		(stroke
			(width 0.05715)
			(type default)
		)
		(layer "In4.Cu")
	)
	(gr_line
		(start 364.30966 -38.448742)
		(end 364.320582 -38.432232)
		(stroke
			(width 0.05715)
			(type default)
		)
		(layer "In4.Cu")
	)
	(gr_line
		(start 364.316518 -54.257448)
		(end 364.375446 -54.19852)
		(stroke
			(width 0.05715)
			(type default)
		)
		(layer "In4.Cu")
	)
	(gr_line
		(start 364.32363 -2.022094)
		(end 364.3757 -1.970024)
		(stroke
			(width 0.05715)
			(type default)
		)
		(layer "In4.Cu")
	)
	(gr_line
		(start 364.324138 -89.429082)
		(end 364.390686 -89.765378)
		(stroke
			(width 0.05715)
			(type default)
		)
		(layer "In4.Cu")
	)
	(gr_line
		(start 364.324138 -89.429082)
		(end 364.452408 -89.23782)
		(stroke
			(width 0.05715)
			(type default)
		)
		(layer "In4.Cu")
	)
	(gr_line
		(start 364.327186 -91.96705)
		(end 364.44301 -92.553028)
		(stroke
			(width 0.05715)
			(type default)
		)
		(layer "In4.Cu")
	)
	(gr_line
		(start 364.36935 -8.26135)
		(end 364.53191 -8.42391)
		(stroke
			(width 0.05715)
			(type default)
		)
		(layer "In4.Cu")
	)
	(gr_line
		(start 364.36935 -7.91845)
		(end 364.36935 -8.26135)
		(stroke
			(width 0.05715)
			(type default)
		)
		(layer "In4.Cu")
	)
	(gr_line
		(start 364.36935 -7.91845)
		(end 364.53191 -7.75589)
		(stroke
			(width 0.05715)
			(type default)
		)
		(layer "In4.Cu")
	)
	(gr_line
		(start 364.36935 -7.24535)
		(end 364.53191 -7.40791)
		(stroke
			(width 0.05715)
			(type default)
		)
		(layer "In4.Cu")
	)
	(gr_line
		(start 364.36935 -6.90245)
		(end 364.36935 -7.24535)
		(stroke
			(width 0.05715)
			(type default)
		)
		(layer "In4.Cu")
	)
	(gr_line
		(start 364.36935 -6.90245)
		(end 364.53191 -6.73989)
		(stroke
			(width 0.05715)
			(type default)
		)
		(layer "In4.Cu")
	)
	(gr_line
		(start 364.36935 -6.22935)
		(end 364.53191 -6.39191)
		(stroke
			(width 0.05715)
			(type default)
		)
		(layer "In4.Cu")
	)
	(gr_line
		(start 364.36935 -5.88645)
		(end 364.36935 -6.22935)
		(stroke
			(width 0.05715)
			(type default)
		)
		(layer "In4.Cu")
	)
	(gr_line
		(start 364.36935 -5.88645)
		(end 364.53191 -5.72389)
		(stroke
			(width 0.05715)
			(type default)
		)
		(layer "In4.Cu")
	)
	(gr_line
		(start 364.36935 -5.21335)
		(end 364.53191 -5.37591)
		(stroke
			(width 0.05715)
			(type default)
		)
		(layer "In4.Cu")
	)
	(gr_line
		(start 364.36935 -4.87045)
		(end 364.36935 -5.21335)
		(stroke
			(width 0.05715)
			(type default)
		)
		(layer "In4.Cu")
	)
	(gr_line
		(start 364.36935 -4.87045)
		(end 364.53191 -4.70789)
		(stroke
			(width 0.05715)
			(type default)
		)
		(layer "In4.Cu")
	)
	(gr_line
		(start 364.3757 -1.970024)
		(end 364.75035 -1.970024)
		(stroke
			(width 0.05715)
			(type default)
		)
		(layer "In4.Cu")
	)
	(gr_line
		(start 364.386622 -50.061368)
		(end 364.424214 -50.050446)
		(stroke
			(width 0.05715)
			(type default)
		)
		(layer "In4.Cu")
	)
	(gr_line
		(start 364.390686 -89.765378)
		(end 364.581948 -89.893394)
		(stroke
			(width 0.05715)
			(type default)
		)
		(layer "In4.Cu")
	)
	(gr_line
		(start 364.424214 -50.050446)
		(end 364.4519 -50.02276)
		(stroke
			(width 0.05715)
			(type default)
		)
		(layer "In4.Cu")
	)
	(gr_line
		(start 364.507526 -50.927254)
		(end 364.543086 -50.91684)
		(stroke
			(width 0.05715)
			(type default)
		)
		(layer "In4.Cu")
	)
	(gr_line
		(start 364.521496 -90.425778)
		(end 364.588044 -90.762074)
		(stroke
			(width 0.05715)
			(type default)
		)
		(layer "In4.Cu")
	)
	(gr_line
		(start 364.521496 -90.425778)
		(end 364.649512 -90.234516)
		(stroke
			(width 0.05715)
			(type default)
		)
		(layer "In4.Cu")
	)
	(gr_line
		(start 364.543086 -50.91684)
		(end 364.569756 -50.89017)
		(stroke
			(width 0.05715)
			(type default)
		)
		(layer "In4.Cu")
	)
	(gr_line
		(start 364.550706 -88.21674)
		(end 364.667292 -88.805766)
		(stroke
			(width 0.05715)
			(type default)
		)
		(layer "In4.Cu")
	)
	(gr_line
		(start 364.565184 -109.41431)
		(end 364.591092 -109.465618)
		(stroke
			(width 0.05715)
			(type default)
		)
		(layer "In4.Cu")
	)
	(gr_line
		(start 364.588044 -90.762074)
		(end 364.779306 -90.889836)
		(stroke
			(width 0.05715)
			(type default)
		)
		(layer "In4.Cu")
	)
	(gr_line
		(start 364.591092 -109.465618)
		(end 364.6424 -109.49178)
		(stroke
			(width 0.05715)
			(type default)
		)
		(layer "In4.Cu")
	)
	(gr_line
		(start 364.617254 -110.6043)
		(end 364.654592 -110.62335)
		(stroke
			(width 0.05715)
			(type default)
		)
		(layer "In4.Cu")
	)
	(gr_line
		(start 364.654592 -110.62335)
		(end 364.676436 -110.658148)
		(stroke
			(width 0.05715)
			(type default)
		)
		(layer "In4.Cu")
	)
	(gr_line
		(start 364.748064 -89.215468)
		(end 364.863634 -89.80043)
		(stroke
			(width 0.05715)
			(type default)
		)
		(layer "In4.Cu")
	)
	(gr_line
		(start 364.763812 -86.252304)
		(end 364.767876 -86.232238)
		(stroke
			(width 0.05715)
			(type default)
		)
		(layer "In4.Cu")
	)
	(gr_line
		(start 364.763812 -86.21268)
		(end 364.767876 -86.232238)
		(stroke
			(width 0.05715)
			(type default)
		)
		(layer "In4.Cu")
	)
	(gr_line
		(start 364.786672 -27.107642)
		(end 364.796324 -27.09291)
		(stroke
			(width 0.05715)
			(type default)
		)
		(layer "In4.Cu")
	)
	(gr_line
		(start 364.796324 -27.09291)
		(end 364.800134 -27.075638)
		(stroke
			(width 0.05715)
			(type default)
		)
		(layer "In4.Cu")
	)
	(gr_line
		(start 364.803182 -54.961028)
		(end 364.86211 -54.9021)
		(stroke
			(width 0.05715)
			(type default)
		)
		(layer "In4.Cu")
	)
	(gr_line
		(start 364.82655 -8.04799)
		(end 364.82655 -8.13181)
		(stroke
			(width 0.05715)
			(type default)
		)
		(layer "In4.Cu")
	)
	(gr_line
		(start 364.82655 -7.03199)
		(end 364.82655 -7.11581)
		(stroke
			(width 0.05715)
			(type default)
		)
		(layer "In4.Cu")
	)
	(gr_line
		(start 364.82655 -6.01599)
		(end 364.82655 -6.09981)
		(stroke
			(width 0.05715)
			(type default)
		)
		(layer "In4.Cu")
	)
	(gr_line
		(start 364.82655 -4.99999)
		(end 364.82655 -5.08381)
		(stroke
			(width 0.05715)
			(type default)
		)
		(layer "In4.Cu")
	)
	(gr_line
		(start 364.857792 -80.079088)
		(end 364.87481 -80.101948)
		(stroke
			(width 0.05715)
			(type default)
		)
		(layer "In4.Cu")
	)
	(gr_line
		(start 364.87481 -80.101948)
		(end 364.880398 -80.129888)
		(stroke
			(width 0.05715)
			(type default)
		)
		(layer "In4.Cu")
	)
	(gr_line
		(start 364.90275 -105.063798)
		(end 364.916212 -105.132886)
		(stroke
			(width 0.05715)
			(type default)
		)
		(layer "In4.Cu")
	)
	(gr_line
		(start 364.916212 -105.132886)
		(end 364.971584 -105.176828)
		(stroke
			(width 0.05715)
			(type default)
		)
		(layer "In4.Cu")
	)
	(gr_line
		(start 364.919006 -94.996762)
		(end 364.92307 -94.976696)
		(stroke
			(width 0.05715)
			(type default)
		)
		(layer "In4.Cu")
	)
	(gr_line
		(start 364.919006 -94.957138)
		(end 364.92307 -94.976696)
		(stroke
			(width 0.05715)
			(type default)
		)
		(layer "In4.Cu")
	)
	(gr_line
		(start 364.92561 -51.583336)
		(end 364.963456 -51.572414)
		(stroke
			(width 0.05715)
			(type default)
		)
		(layer "In4.Cu")
	)
	(gr_line
		(start 364.945168 -90.211402)
		(end 365.060738 -90.796364)
		(stroke
			(width 0.05715)
			(type default)
		)
		(layer "In4.Cu")
	)
	(gr_line
		(start 364.963456 -51.572414)
		(end 364.991396 -51.544474)
		(stroke
			(width 0.05715)
			(type default)
		)
		(layer "In4.Cu")
	)
	(gr_line
		(start 364.99038 -100.897436)
		(end 364.997492 -100.93325)
		(stroke
			(width 0.05715)
			(type default)
		)
		(layer "In4.Cu")
	)
	(gr_line
		(start 364.997492 -100.93325)
		(end 365.021114 -100.961444)
		(stroke
			(width 0.05715)
			(type default)
		)
		(layer "In4.Cu")
	)
	(gr_line
		(start 365.024416 -88.31072)
		(end 365.029496 -88.285574)
		(stroke
			(width 0.05715)
			(type default)
		)
		(layer "In4.Cu")
	)
	(gr_line
		(start 365.024416 -88.31072)
		(end 365.029496 -88.285066)
		(stroke
			(width 0.05715)
			(type default)
		)
		(layer "In4.Cu")
	)
	(gr_line
		(start 365.024416 -88.31072)
		(end 365.030258 -88.336374)
		(stroke
			(width 0.05715)
			(type default)
		)
		(layer "In4.Cu")
	)
	(gr_line
		(start 365.024416 -88.31072)
		(end 365.030258 -88.33612)
		(stroke
			(width 0.05715)
			(type default)
		)
		(layer "In4.Cu")
	)
	(gr_line
		(start 365.067342 -110.106968)
		(end 365.104426 -110.125764)
		(stroke
			(width 0.05715)
			(type default)
		)
		(layer "In4.Cu")
	)
	(gr_line
		(start 365.100108 -111.327438)
		(end 365.125 -111.367062)
		(stroke
			(width 0.05715)
			(type default)
		)
		(layer "In4.Cu")
	)
	(gr_line
		(start 365.104426 -110.12551)
		(end 365.104426 -110.125764)
		(stroke
			(width 0.05715)
			(type default)
		)
		(layer "In4.Cu")
	)
	(gr_line
		(start 365.104426 -110.12551)
		(end 365.12754 -110.161832)
		(stroke
			(width 0.05715)
			(type default)
		)
		(layer "In4.Cu")
	)
	(gr_line
		(start 365.153194 -97.726754)
		(end 365.219742 -98.06305)
		(stroke
			(width 0.05715)
			(type default)
		)
		(layer "In4.Cu")
	)
	(gr_line
		(start 365.153194 -97.726754)
		(end 365.289084 -97.523554)
		(stroke
			(width 0.05715)
			(type default)
		)
		(layer "In4.Cu")
	)
	(gr_line
		(start 365.219742 -98.06305)
		(end 365.422942 -98.199194)
		(stroke
			(width 0.05715)
			(type default)
		)
		(layer "In4.Cu")
	)
	(gr_line
		(start 365.224314 -97.184464)
		(end 365.228378 -97.20453)
		(stroke
			(width 0.05715)
			(type default)
		)
		(layer "In4.Cu")
	)
	(gr_line
		(start 365.224314 -97.184464)
		(end 365.228378 -97.164906)
		(stroke
			(width 0.05715)
			(type default)
		)
		(layer "In4.Cu")
	)
	(gr_line
		(start 365.354616 -98.743262)
		(end 365.421164 -99.079812)
		(stroke
			(width 0.05715)
			(type default)
		)
		(layer "In4.Cu")
	)
	(gr_line
		(start 365.354616 -98.743262)
		(end 365.490506 -98.539808)
		(stroke
			(width 0.05715)
			(type default)
		)
		(layer "In4.Cu")
	)
	(gr_line
		(start 365.402622 -8.811768)
		(end 365.406432 -8.792718)
		(stroke
			(width 0.05715)
			(type default)
		)
		(layer "In4.Cu")
	)
	(gr_line
		(start 365.402622 -8.811768)
		(end 365.406686 -8.831834)
		(stroke
			(width 0.05715)
			(type default)
		)
		(layer "In4.Cu")
	)
	(gr_line
		(start 365.421164 -99.079812)
		(end 365.624364 -99.215702)
		(stroke
			(width 0.05715)
			(type default)
		)
		(layer "In4.Cu")
	)
	(gr_line
		(start 365.495332 -7.505954)
		(end 365.562642 -7.169658)
		(stroke
			(width 0.05715)
			(type default)
		)
		(layer "In4.Cu")
	)
	(gr_line
		(start 365.495332 -7.505954)
		(end 365.623094 -7.69747)
		(stroke
			(width 0.05715)
			(type default)
		)
		(layer "In4.Cu")
	)
	(gr_line
		(start 365.500666 -27.204924)
		(end 365.510318 -27.190192)
		(stroke
			(width 0.05715)
			(type default)
		)
		(layer "In4.Cu")
	)
	(gr_line
		(start 365.510318 -27.190192)
		(end 365.514128 -27.17292)
		(stroke
			(width 0.05715)
			(type default)
		)
		(layer "In4.Cu")
	)
	(gr_line
		(start 365.5187 -109.609382)
		(end 365.556546 -109.628686)
		(stroke
			(width 0.05715)
			(type default)
		)
		(layer "In4.Cu")
	)
	(gr_line
		(start 365.520732 -105.61193)
		(end 365.602774 -105.676954)
		(stroke
			(width 0.05715)
			(type default)
		)
		(layer "In4.Cu")
	)
	(gr_line
		(start 365.548418 -90.577162)
		(end 365.551974 -90.592402)
		(stroke
			(width 0.05715)
			(type default)
		)
		(layer "In4.Cu")
	)
	(gr_line
		(start 365.548672 -90.577416)
		(end 365.551974 -90.592402)
		(stroke
			(width 0.05715)
			(type default)
		)
		(layer "In4.Cu")
	)
	(gr_line
		(start 365.551974 -90.592402)
		(end 365.561118 -90.606118)
		(stroke
			(width 0.05715)
			(type default)
		)
		(layer "In4.Cu")
	)
	(gr_line
		(start 365.551974 -90.592402)
		(end 365.561118 -90.605864)
		(stroke
			(width 0.05715)
			(type default)
		)
		(layer "In4.Cu")
	)
	(gr_line
		(start 365.556546 -109.628686)
		(end 365.577882 -109.662976)
		(stroke
			(width 0.05715)
			(type default)
		)
		(layer "In4.Cu")
	)
	(gr_line
		(start 365.562642 -7.169658)
		(end 365.754158 -7.04215)
		(stroke
			(width 0.05715)
			(type default)
		)
		(layer "In4.Cu")
	)
	(gr_line
		(start 365.576866 -87.024464)
		(end 365.58093 -87.004398)
		(stroke
			(width 0.05715)
			(type default)
		)
		(layer "In4.Cu")
	)
	(gr_line
		(start 365.576866 -86.98484)
		(end 365.58093 -87.004398)
		(stroke
			(width 0.05715)
			(type default)
		)
		(layer "In4.Cu")
	)
	(gr_line
		(start 365.58474 -97.499424)
		(end 365.70539 -98.108008)
		(stroke
			(width 0.05715)
			(type default)
		)
		(layer "In4.Cu")
	)
	(gr_line
		(start 365.602774 -105.676954)
		(end 365.704628 -105.653332)
		(stroke
			(width 0.05715)
			(type default)
		)
		(layer "In4.Cu")
	)
	(gr_line
		(start 365.650272 -110.324138)
		(end 365.970312 -110.829852)
		(stroke
			(width 0.05715)
			(type default)
		)
		(layer "In4.Cu")
	)
	(gr_line
		(start 365.694722 -6.509766)
		(end 365.762032 -6.17347)
		(stroke
			(width 0.05715)
			(type default)
		)
		(layer "In4.Cu")
	)
	(gr_line
		(start 365.694722 -6.509766)
		(end 365.82223 -6.701028)
		(stroke
			(width 0.05715)
			(type default)
		)
		(layer "In4.Cu")
	)
	(gr_line
		(start 365.737648 -88.10371)
		(end 365.741966 -88.081358)
		(stroke
			(width 0.05715)
			(type default)
		)
		(layer "In4.Cu")
	)
	(gr_line
		(start 365.737648 -88.10371)
		(end 365.74222 -88.080596)
		(stroke
			(width 0.05715)
			(type default)
		)
		(layer "In4.Cu")
	)
	(gr_line
		(start 365.737648 -88.10371)
		(end 365.742474 -88.126062)
		(stroke
			(width 0.05715)
			(type default)
		)
		(layer "In4.Cu")
	)
	(gr_line
		(start 365.737648 -88.10371)
		(end 365.742474 -88.125808)
		(stroke
			(width 0.05715)
			(type default)
		)
		(layer "In4.Cu")
	)
	(gr_line
		(start 365.742474 -88.126062)
		(end 365.742728 -88.126824)
		(stroke
			(width 0.05715)
			(type default)
		)
		(layer "In4.Cu")
	)
	(gr_line
		(start 365.760508 -111.1631)
		(end 365.7854 -111.20247)
		(stroke
			(width 0.05715)
			(type default)
		)
		(layer "In4.Cu")
	)
	(gr_line
		(start 365.762032 -6.17347)
		(end 365.953294 -6.045962)
		(stroke
			(width 0.05715)
			(type default)
		)
		(layer "In4.Cu")
	)
	(gr_line
		(start 365.786162 -98.515932)
		(end 365.906812 -99.124516)
		(stroke
			(width 0.05715)
			(type default)
		)
		(layer "In4.Cu")
	)
	(gr_line
		(start 365.80572 -118.885462)
		(end 365.864902 -118.944644)
		(stroke
			(width 0.05715)
			(type default)
		)
		(layer "In4.Cu")
	)
	(gr_line
		(start 365.807244 -118.470426)
		(end 366.037368 -118.470426)
		(stroke
			(width 0.05715)
			(type default)
		)
		(layer "In4.Cu")
	)
	(gr_line
		(start 365.814102 -9.42594)
		(end 365.818928 -9.403334)
		(stroke
			(width 0.05715)
			(type default)
		)
		(layer "In4.Cu")
	)
	(gr_line
		(start 365.814356 -9.380474)
		(end 365.818928 -9.403334)
		(stroke
			(width 0.05715)
			(type default)
		)
		(layer "In4.Cu")
	)
	(gr_line
		(start 365.880904 -110.13694)
		(end 366.105186 -110.187486)
		(stroke
			(width 0.05715)
			(type default)
		)
		(layer "In4.Cu")
	)
	(gr_line
		(start 365.894112 -5.513324)
		(end 365.961168 -5.177282)
		(stroke
			(width 0.05715)
			(type default)
		)
		(layer "In4.Cu")
	)
	(gr_line
		(start 365.894112 -5.513324)
		(end 366.02162 -5.70484)
		(stroke
			(width 0.05715)
			(type default)
		)
		(layer "In4.Cu")
	)
	(gr_line
		(start 365.911384 -132.489956)
		(end 365.952532 -132.506212)
		(stroke
			(width 0.05715)
			(type default)
		)
		(layer "In4.Cu")
	)
	(gr_line
		(start 365.915702 -95.102426)
		(end 365.92383 -95.110554)
		(stroke
			(width 0.05715)
			(type default)
		)
		(layer "In4.Cu")
	)
	(gr_line
		(start 365.91875 -7.720838)
		(end 366.036098 -7.134606)
		(stroke
			(width 0.05715)
			(type default)
		)
		(layer "In4.Cu")
	)
	(gr_line
		(start 365.919766 -95.176594)
		(end 365.92383 -95.156274)
		(stroke
			(width 0.05715)
			(type default)
		)
		(layer "In4.Cu")
	)
	(gr_line
		(start 365.92383 -95.110554)
		(end 365.92383 -95.156274)
		(stroke
			(width 0.05715)
			(type default)
		)
		(layer "In4.Cu")
	)
	(gr_line
		(start 365.952532 -132.506212)
		(end 365.979202 -132.541518)
		(stroke
			(width 0.05715)
			(type default)
		)
		(layer "In4.Cu")
	)
	(gr_line
		(start 365.961168 -5.177282)
		(end 366.15243 -5.049774)
		(stroke
			(width 0.05715)
			(type default)
		)
		(layer "In4.Cu")
	)
	(gr_line
		(start 365.983266 -33.5661)
		(end 365.993934 -33.549844)
		(stroke
			(width 0.05715)
			(type default)
		)
		(layer "In4.Cu")
	)
	(gr_line
		(start 365.9886 -101.040692)
		(end 365.99241 -101.061012)
		(stroke
			(width 0.05715)
			(type default)
		)
		(layer "In4.Cu")
	)
	(gr_line
		(start 365.989616 -10.520426)
		(end 366.00384 -10.453116)
		(stroke
			(width 0.05715)
			(type default)
		)
		(layer "In4.Cu")
	)
	(gr_line
		(start 365.99241 -101.061012)
		(end 366.004348 -101.079046)
		(stroke
			(width 0.05715)
			(type default)
		)
		(layer "In4.Cu")
	)
	(gr_line
		(start 365.993934 -33.549844)
		(end 366.010698 -33.538668)
		(stroke
			(width 0.05715)
			(type default)
		)
		(layer "In4.Cu")
	)
	(gr_line
		(start 366.00384 -10.453116)
		(end 366.059212 -10.41019)
		(stroke
			(width 0.05715)
			(type default)
		)
		(layer "In4.Cu")
	)
	(gr_line
		(start 366.037368 -118.470426)
		(end 366.279938 -118.712996)
		(stroke
			(width 0.05715)
			(type default)
		)
		(layer "In4.Cu")
	)
	(gr_line
		(start 366.072674 -89.618312)
		(end 366.076992 -89.637616)
		(stroke
			(width 0.05715)
			(type default)
		)
		(layer "In4.Cu")
	)
	(gr_line
		(start 366.076992 -89.637616)
		(end 366.088168 -89.654126)
		(stroke
			(width 0.05715)
			(type default)
		)
		(layer "In4.Cu")
	)
	(gr_line
		(start 366.10036 -2.937002)
		(end 366.47501 -2.937002)
		(stroke
			(width 0.05715)
			(type default)
		)
		(layer "In4.Cu")
	)
	(gr_line
		(start 366.105186 -110.187486)
		(end 366.288574 -110.4773)
		(stroke
			(width 0.05715)
			(type default)
		)
		(layer "In4.Cu")
	)
	(gr_line
		(start 366.118394 -6.722364)
		(end 366.23498 -6.139942)
		(stroke
			(width 0.05715)
			(type default)
		)
		(layer "In4.Cu")
	)
	(gr_line
		(start 366.1283 -116.01704)
		(end 366.187228 -116.075968)
		(stroke
			(width 0.05715)
			(type default)
		)
		(layer "In4.Cu")
	)
	(gr_line
		(start 366.179862 -102.34295)
		(end 366.182656 -102.346506)
		(stroke
			(width 0.05715)
			(type default)
		)
		(layer "In4.Cu")
	)
	(gr_line
		(start 366.182656 -102.346506)
		(end 366.186466 -102.349046)
		(stroke
			(width 0.05715)
			(type default)
		)
		(layer "In4.Cu")
	)
	(gr_line
		(start 366.188498 -101.356668)
		(end 366.200436 -101.374448)
		(stroke
			(width 0.05715)
			(type default)
		)
		(layer "In4.Cu")
	)
	(gr_line
		(start 366.200436 -101.374448)
		(end 366.217708 -101.385878)
		(stroke
			(width 0.05715)
			(type default)
		)
		(layer "In4.Cu")
	)
	(gr_line
		(start 366.218978 -4.730496)
		(end 366.222788 -4.711446)
		(stroke
			(width 0.05715)
			(type default)
		)
		(layer "In4.Cu")
	)
	(gr_line
		(start 366.222788 -4.711446)
		(end 366.233456 -4.695698)
		(stroke
			(width 0.05715)
			(type default)
		)
		(layer "In4.Cu")
	)
	(gr_line
		(start 366.238028 -110.701836)
		(end 366.288574 -110.4773)
		(stroke
			(width 0.05715)
			(type default)
		)
		(layer "In4.Cu")
	)
	(gr_line
		(start 366.242854 -87.05469)
		(end 366.246918 -87.034624)
		(stroke
			(width 0.05715)
			(type default)
		)
		(layer "In4.Cu")
	)
	(gr_line
		(start 366.242854 -87.015066)
		(end 366.246918 -87.034624)
		(stroke
			(width 0.05715)
			(type default)
		)
		(layer "In4.Cu")
	)
	(gr_line
		(start 366.27054 -27.256994)
		(end 366.2807 -27.2415)
		(stroke
			(width 0.05715)
			(type default)
		)
		(layer "In4.Cu")
	)
	(gr_line
		(start 366.279938 -118.712996)
		(end 366.279938 -118.94312)
		(stroke
			(width 0.05715)
			(type default)
		)
		(layer "In4.Cu")
	)
	(gr_line
		(start 366.2807 -27.2415)
		(end 366.28451 -27.223466)
		(stroke
			(width 0.05715)
			(type default)
		)
		(layer "In4.Cu")
	)
	(gr_line
		(start 366.316514 -131.953254)
		(end 366.359948 -131.970526)
		(stroke
			(width 0.05715)
			(type default)
		)
		(layer "In4.Cu")
	)
	(gr_line
		(start 366.31753 -5.726938)
		(end 366.434116 -5.143246)
		(stroke
			(width 0.05715)
			(type default)
		)
		(layer "In4.Cu")
	)
	(gr_line
		(start 366.33277 -12.169902)
		(end 366.347756 -12.100306)
		(stroke
			(width 0.05715)
			(type default)
		)
		(layer "In4.Cu")
	)
	(gr_line
		(start 366.33912 -90.31605)
		(end 366.382046 -90.089482)
		(stroke
			(width 0.05715)
			(type default)
		)
		(layer "In4.Cu")
	)
	(gr_line
		(start 366.33912 -90.31605)
		(end 366.53216 -90.599514)
		(stroke
			(width 0.05715)
			(type default)
		)
		(layer "In4.Cu")
	)
	(gr_line
		(start 366.347756 -12.100306)
		(end 366.40389 -12.057634)
		(stroke
			(width 0.05715)
			(type default)
		)
		(layer "In4.Cu")
	)
	(gr_line
		(start 366.356138 -132.45084)
		(end 366.715294 -132.927344)
		(stroke
			(width 0.05715)
			(type default)
		)
		(layer "In4.Cu")
	)
	(gr_line
		(start 366.359948 -131.970526)
		(end 366.386618 -132.005832)
		(stroke
			(width 0.05715)
			(type default)
		)
		(layer "In4.Cu")
	)
	(gr_line
		(start 366.395762 -110.95609)
		(end 366.4204 -110.994952)
		(stroke
			(width 0.05715)
			(type default)
		)
		(layer "In4.Cu")
	)
	(gr_line
		(start 366.398556 -30.030166)
		(end 366.445038 -29.96057)
		(stroke
			(width 0.05715)
			(type default)
		)
		(layer "In4.Cu")
	)
	(gr_line
		(start 366.421416 -47.639732)
		(end 366.480344 -47.580804)
		(stroke
			(width 0.05715)
			(type default)
		)
		(layer "In4.Cu")
	)
	(gr_line
		(start 366.42675 -34.046414)
		(end 366.437418 -34.030158)
		(stroke
			(width 0.05715)
			(type default)
		)
		(layer "In4.Cu")
	)
	(gr_line
		(start 366.437418 -34.030158)
		(end 366.453674 -34.01949)
		(stroke
			(width 0.05715)
			(type default)
		)
		(layer "In4.Cu")
	)
	(gr_line
		(start 366.445038 -29.96057)
		(end 366.527334 -29.94406)
		(stroke
			(width 0.05715)
			(type default)
		)
		(layer "In4.Cu")
	)
	(gr_line
		(start 366.47501 -2.937002)
		(end 366.52708 -2.989072)
		(stroke
			(width 0.05715)
			(type default)
		)
		(layer "In4.Cu")
	)
	(gr_line
		(start 366.524286 -119.604028)
		(end 366.583214 -119.662956)
		(stroke
			(width 0.05715)
			(type default)
		)
		(layer "In4.Cu")
	)
	(gr_line
		(start 366.52581 -119.188992)
		(end 366.755934 -119.188992)
		(stroke
			(width 0.05715)
			(type default)
		)
		(layer "In4.Cu")
	)
	(gr_line
		(start 366.53216 -90.599514)
		(end 366.75822 -90.64244)
		(stroke
			(width 0.05715)
			(type default)
		)
		(layer "In4.Cu")
	)
	(gr_line
		(start 366.548162 -116.437156)
		(end 366.563656 -116.45265)
		(stroke
			(width 0.04445)
			(type default)
		)
		(layer "In4.Cu")
	)
	(gr_line
		(start 366.563656 -116.45265)
		(end 366.577372 -116.45265)
		(stroke
			(width 0.04445)
			(type default)
		)
		(layer "In4.Cu")
	)
	(gr_line
		(start 366.569752 -132.244846)
		(end 366.79759 -132.27685)
		(stroke
			(width 0.05715)
			(type default)
		)
		(layer "In4.Cu")
	)
	(gr_line
		(start 366.579912 -116.45265)
		(end 366.635792 -116.45265)
		(stroke
			(width 0.04445)
			(type default)
		)
		(layer "In4.Cu")
	)
	(gr_line
		(start 366.620552 -117.774212)
		(end 366.67948 -117.83314)
		(stroke
			(width 0.05715)
			(type default)
		)
		(layer "In4.Cu")
	)
	(gr_line
		(start 366.622076 -117.359176)
		(end 366.8522 -117.359176)
		(stroke
			(width 0.05715)
			(type default)
		)
		(layer "In4.Cu")
	)
	(gr_line
		(start 366.64392 -89.950544)
		(end 366.98301 -90.448638)
		(stroke
			(width 0.05715)
			(type default)
		)
		(layer "In4.Cu")
	)
	(gr_line
		(start 366.713008 -52.086256)
		(end 366.751616 -52.075588)
		(stroke
			(width 0.05715)
			(type default)
		)
		(layer "In4.Cu")
	)
	(gr_line
		(start 366.751616 -52.075588)
		(end 366.77981 -52.047394)
		(stroke
			(width 0.05715)
			(type default)
		)
		(layer "In4.Cu")
	)
	(gr_line
		(start 366.754918 -116.230654)
		(end 366.770412 -116.246148)
		(stroke
			(width 0.04445)
			(type default)
		)
		(layer "In4.Cu")
	)
	(gr_line
		(start 366.755934 -119.188992)
		(end 366.99825 -119.431308)
		(stroke
			(width 0.05715)
			(type default)
		)
		(layer "In4.Cu")
	)
	(gr_line
		(start 366.770412 -116.26215)
		(end 366.770412 -116.317776)
		(stroke
			(width 0.04445)
			(type default)
		)
		(layer "In4.Cu")
	)
	(gr_line
		(start 366.770412 -116.246148)
		(end 366.770412 -116.25961)
		(stroke
			(width 0.04445)
			(type default)
		)
		(layer "In4.Cu")
	)
	(gr_line
		(start 366.771682 -48.274732)
		(end 366.83061 -48.215804)
		(stroke
			(width 0.05715)
			(type default)
		)
		(layer "In4.Cu")
	)
	(gr_line
		(start 366.781588 -30.613096)
		(end 366.82807 -30.543246)
		(stroke
			(width 0.05715)
			(type default)
		)
		(layer "In4.Cu")
	)
	(gr_line
		(start 366.79759 -132.27685)
		(end 367.004092 -132.550662)
		(stroke
			(width 0.05715)
			(type default)
		)
		(layer "In4.Cu")
	)
	(gr_line
		(start 366.82807 -30.543246)
		(end 366.909096 -30.52699)
		(stroke
			(width 0.05715)
			(type default)
		)
		(layer "In4.Cu")
	)
	(gr_line
		(start 366.840516 -4.31546)
		(end 366.88141 -4.274566)
		(stroke
			(width 0.05715)
			(type default)
		)
		(layer "In4.Cu")
	)
	(gr_line
		(start 366.8522 -117.359176)
		(end 367.094516 -117.601492)
		(stroke
			(width 0.05715)
			(type default)
		)
		(layer "In4.Cu")
	)
	(gr_line
		(start 366.910874 -91.155774)
		(end 366.954054 -90.929714)
		(stroke
			(width 0.05715)
			(type default)
		)
		(layer "In4.Cu")
	)
	(gr_line
		(start 366.910874 -91.155774)
		(end 367.103914 -91.439238)
		(stroke
			(width 0.05715)
			(type default)
		)
		(layer "In4.Cu")
	)
	(gr_line
		(start 366.92967 -12.578588)
		(end 366.94364 -12.512548)
		(stroke
			(width 0.05715)
			(type default)
		)
		(layer "In4.Cu")
	)
	(gr_line
		(start 366.94364 -12.512548)
		(end 366.997234 -12.471146)
		(stroke
			(width 0.05715)
			(type default)
		)
		(layer "In4.Cu")
	)
	(gr_line
		(start 366.94364 -2.989072)
		(end 366.99571 -2.937002)
		(stroke
			(width 0.05715)
			(type default)
		)
		(layer "In4.Cu")
	)
	(gr_line
		(start 366.945418 -34.486596)
		(end 366.956086 -34.47034)
		(stroke
			(width 0.05715)
			(type default)
		)
		(layer "In4.Cu")
	)
	(gr_line
		(start 366.956086 -34.47034)
		(end 366.972342 -34.459672)
		(stroke
			(width 0.05715)
			(type default)
		)
		(layer "In4.Cu")
	)
	(gr_line
		(start 366.968024 -133.26237)
		(end 367.326672 -133.738112)
		(stroke
			(width 0.05715)
			(type default)
		)
		(layer "In4.Cu")
	)
	(gr_line
		(start 366.972088 -132.778246)
		(end 367.004092 -132.550662)
		(stroke
			(width 0.05715)
			(type default)
		)
		(layer "In4.Cu")
	)
	(gr_line
		(start 366.980978 -116.797836)
		(end 367.02238 -116.839238)
		(stroke
			(width 0.04445)
			(type default)
		)
		(layer "In4.Cu")
	)
	(gr_line
		(start 366.982756 -116.526564)
		(end 367.10493 -116.526564)
		(stroke
			(width 0.04445)
			(type default)
		)
		(layer "In4.Cu")
	)
	(gr_line
		(start 366.99571 -2.937002)
		(end 367.37036 -2.937002)
		(stroke
			(width 0.05715)
			(type default)
		)
		(layer "In4.Cu")
	)
	(gr_line
		(start 366.99825 -119.431308)
		(end 366.99825 -119.661432)
		(stroke
			(width 0.05715)
			(type default)
		)
		(layer "In4.Cu")
	)
	(gr_line
		(start 367.094516 -117.601492)
		(end 367.094516 -117.831616)
		(stroke
			(width 0.05715)
			(type default)
		)
		(layer "In4.Cu")
	)
	(gr_line
		(start 367.103914 -91.439238)
		(end 367.329974 -91.482164)
		(stroke
			(width 0.05715)
			(type default)
		)
		(layer "In4.Cu")
	)
	(gr_line
		(start 367.10493 -116.526564)
		(end 367.293652 -116.715286)
		(stroke
			(width 0.04445)
			(type default)
		)
		(layer "In4.Cu")
	)
	(gr_line
		(start 367.112804 -27.157934)
		(end 367.123472 -27.141678)
		(stroke
			(width 0.05715)
			(type default)
		)
		(layer "In4.Cu")
	)
	(gr_line
		(start 367.123472 -27.141678)
		(end 367.127282 -27.122628)
		(stroke
			(width 0.05715)
			(type default)
		)
		(layer "In4.Cu")
	)
	(gr_line
		(start 367.143538 -11.492738)
		(end 367.174526 -11.2649)
		(stroke
			(width 0.05715)
			(type default)
		)
		(layer "In4.Cu")
	)
	(gr_line
		(start 367.174526 -11.2649)
		(end 367.447576 -11.057382)
		(stroke
			(width 0.05715)
			(type default)
		)
		(layer "In4.Cu")
	)
	(gr_line
		(start 367.181384 -133.056122)
		(end 367.409222 -133.088126)
		(stroke
			(width 0.05715)
			(type default)
		)
		(layer "In4.Cu")
	)
	(gr_line
		(start 367.213134 -48.909732)
		(end 367.272062 -48.850804)
		(stroke
			(width 0.05715)
			(type default)
		)
		(layer "In4.Cu")
	)
	(gr_line
		(start 367.216944 -90.7923)
		(end 367.554002 -91.2876)
		(stroke
			(width 0.05715)
			(type default)
		)
		(layer "In4.Cu")
	)
	(gr_line
		(start 367.293652 -116.715286)
		(end 367.293652 -116.83746)
		(stroke
			(width 0.04445)
			(type default)
		)
		(layer "In4.Cu")
	)
	(gr_line
		(start 367.295176 -24.79294)
		(end 367.298986 -24.77389)
		(stroke
			(width 0.05715)
			(type default)
		)
		(layer "In4.Cu")
	)
	(gr_line
		(start 367.298986 -24.77389)
		(end 367.309654 -24.757888)
		(stroke
			(width 0.05715)
			(type default)
		)
		(layer "In4.Cu")
	)
	(gr_line
		(start 367.338356 -102.772972)
		(end 367.354866 -102.784148)
		(stroke
			(width 0.05715)
			(type default)
		)
		(layer "In4.Cu")
	)
	(gr_line
		(start 367.338864 -118.492524)
		(end 367.397792 -118.551452)
		(stroke
			(width 0.05715)
			(type default)
		)
		(layer "In4.Cu")
	)
	(gr_line
		(start 367.340388 -118.077488)
		(end 367.570512 -118.077488)
		(stroke
			(width 0.05715)
			(type default)
		)
		(layer "In4.Cu")
	)
	(gr_line
		(start 367.349532 -11.706606)
		(end 367.82629 -11.344402)
		(stroke
			(width 0.05715)
			(type default)
		)
		(layer "In4.Cu")
	)
	(gr_line
		(start 367.354866 -102.784148)
		(end 367.366042 -102.800658)
		(stroke
			(width 0.05715)
			(type default)
		)
		(layer "In4.Cu")
	)
	(gr_line
		(start 367.409222 -133.088126)
		(end 367.615724 -133.361938)
		(stroke
			(width 0.05715)
			(type default)
		)
		(layer "In4.Cu")
	)
	(gr_line
		(start 367.447576 -11.057382)
		(end 367.675414 -11.088624)
		(stroke
			(width 0.05715)
			(type default)
		)
		(layer "In4.Cu")
	)
	(gr_line
		(start 367.482628 -91.995498)
		(end 367.525808 -91.769438)
		(stroke
			(width 0.05715)
			(type default)
		)
		(layer "In4.Cu")
	)
	(gr_line
		(start 367.482628 -91.995498)
		(end 367.675668 -92.278962)
		(stroke
			(width 0.05715)
			(type default)
		)
		(layer "In4.Cu")
	)
	(gr_line
		(start 367.483898 -117.300756)
		(end 367.5253 -117.342158)
		(stroke
			(width 0.04445)
			(type default)
		)
		(layer "In4.Cu")
	)
	(gr_line
		(start 367.485676 -117.029484)
		(end 367.60785 -117.029484)
		(stroke
			(width 0.04445)
			(type default)
		)
		(layer "In4.Cu")
	)
	(gr_line
		(start 367.528094 -12.92606)
		(end 367.543334 -12.85494)
		(stroke
			(width 0.05715)
			(type default)
		)
		(layer "In4.Cu")
	)
	(gr_line
		(start 367.543334 -12.85494)
		(end 367.602008 -12.810998)
		(stroke
			(width 0.05715)
			(type default)
		)
		(layer "In4.Cu")
	)
	(gr_line
		(start 367.551208 -129.212848)
		(end 367.677954 -129.404618)
		(stroke
			(width 0.05715)
			(type default)
		)
		(layer "In4.Cu")
	)
	(gr_line
		(start 367.570512 -118.077488)
		(end 367.812828 -118.319804)
		(stroke
			(width 0.05715)
			(type default)
		)
		(layer "In4.Cu")
	)
	(gr_line
		(start 367.58372 -133.589522)
		(end 367.615724 -133.361938)
		(stroke
			(width 0.05715)
			(type default)
		)
		(layer "In4.Cu")
	)
	(gr_line
		(start 367.60785 -117.029484)
		(end 367.796572 -117.218206)
		(stroke
			(width 0.04445)
			(type default)
		)
		(layer "In4.Cu")
	)
	(gr_line
		(start 367.644934 -128.931162)
		(end 368.23015 -129.050288)
		(stroke
			(width 0.05715)
			(type default)
		)
		(layer "In4.Cu")
	)
	(gr_line
		(start 367.655856 -104.898952)
		(end 367.701322 -104.888284)
		(stroke
			(width 0.05715)
			(type default)
		)
		(layer "In4.Cu")
	)
	(gr_line
		(start 367.675668 -92.278962)
		(end 367.901474 -92.321634)
		(stroke
			(width 0.05715)
			(type default)
		)
		(layer "In4.Cu")
	)
	(gr_line
		(start 367.675668 -92.278962)
		(end 367.901728 -92.321888)
		(stroke
			(width 0.05715)
			(type default)
		)
		(layer "In4.Cu")
	)
	(gr_line
		(start 367.677954 -129.404618)
		(end 368.013996 -129.472944)
		(stroke
			(width 0.05715)
			(type default)
		)
		(layer "In4.Cu")
	)
	(gr_line
		(start 367.701322 -104.888284)
		(end 367.745264 -104.903524)
		(stroke
			(width 0.05715)
			(type default)
		)
		(layer "In4.Cu")
	)
	(gr_line
		(start 367.771172 -27.333448)
		(end 367.782348 -27.316684)
		(stroke
			(width 0.05715)
			(type default)
		)
		(layer "In4.Cu")
	)
	(gr_line
		(start 367.782348 -27.316684)
		(end 367.786412 -27.296872)
		(stroke
			(width 0.05715)
			(type default)
		)
		(layer "In4.Cu")
	)
	(gr_line
		(start 367.788444 -91.631516)
		(end 368.125502 -92.126816)
		(stroke
			(width 0.05715)
			(type default)
		)
		(layer "In4.Cu")
	)
	(gr_line
		(start 367.791238 -9.440926)
		(end 367.839498 -9.403842)
		(stroke
			(width 0.05715)
			(type default)
		)
		(layer "In4.Cu")
	)
	(gr_line
		(start 367.796572 -117.218206)
		(end 367.796572 -117.34038)
		(stroke
			(width 0.04445)
			(type default)
		)
		(layer "In4.Cu")
	)
	(gr_line
		(start 367.812828 -118.319804)
		(end 367.812828 -118.549928)
		(stroke
			(width 0.05715)
			(type default)
		)
		(layer "In4.Cu")
	)
	(gr_line
		(start 367.838228 -25.595072)
		(end 367.857786 -25.49906)
		(stroke
			(width 0.05715)
			(type default)
		)
		(layer "In4.Cu")
	)
	(gr_line
		(start 367.839498 -9.403842)
		(end 367.855754 -9.34466)
		(stroke
			(width 0.05715)
			(type default)
		)
		(layer "In4.Cu")
	)
	(gr_line
		(start 367.840514 -50.57394)
		(end 367.899442 -50.515012)
		(stroke
			(width 0.05715)
			(type default)
		)
		(layer "In4.Cu")
	)
	(gr_line
		(start 367.850674 -115.593876)
		(end 367.850674 -115.59413)
		(stroke
			(width 0.05715)
			(type default)
		)
		(layer "In4.Cu")
	)
	(gr_line
		(start 367.850928 -115.594384)
		(end 367.866422 -115.609878)
		(stroke
			(width 0.04445)
			(type default)
		)
		(layer "In4.Cu")
	)
	(gr_line
		(start 367.857786 -25.49906)
		(end 367.9444 -25.451816)
		(stroke
			(width 0.05715)
			(type default)
		)
		(layer "In4.Cu")
	)
	(gr_line
		(start 367.866422 -115.609878)
		(end 367.879884 -115.609878)
		(stroke
			(width 0.04445)
			(type default)
		)
		(layer "In4.Cu")
	)
	(gr_line
		(start 367.868962 -7.5565)
		(end 367.959132 -7.225792)
		(stroke
			(width 0.05715)
			(type default)
		)
		(layer "In4.Cu")
	)
	(gr_line
		(start 367.868962 -7.5565)
		(end 367.983262 -7.756398)
		(stroke
			(width 0.05715)
			(type default)
		)
		(layer "In4.Cu")
	)
	(gr_line
		(start 367.875566 -104.079294)
		(end 367.887504 -104.09682)
		(stroke
			(width 0.05715)
			(type default)
		)
		(layer "In4.Cu")
	)
	(gr_line
		(start 367.882424 -115.609878)
		(end 367.938558 -115.609878)
		(stroke
			(width 0.04445)
			(type default)
		)
		(layer "In4.Cu")
	)
	(gr_line
		(start 367.887504 -104.09682)
		(end 367.904522 -104.10825)
		(stroke
			(width 0.05715)
			(type default)
		)
		(layer "In4.Cu")
	)
	(gr_line
		(start 367.952528 -10.878312)
		(end 367.983516 -10.65022)
		(stroke
			(width 0.05715)
			(type default)
		)
		(layer "In4.Cu")
	)
	(gr_line
		(start 367.959132 -7.225792)
		(end 368.15903 -7.111746)
		(stroke
			(width 0.05715)
			(type default)
		)
		(layer "In4.Cu")
	)
	(gr_line
		(start 367.97615 -115.304316)
		(end 367.97615 -115.306094)
		(stroke
			(width 0.05715)
			(type default)
		)
		(layer "In4.Cu")
	)
	(gr_line
		(start 367.983516 -10.65022)
		(end 368.256566 -10.442702)
		(stroke
			(width 0.05715)
			(type default)
		)
		(layer "In4.Cu")
	)
	(gr_line
		(start 368.00028 -136.375902)
		(end 368.01552 -136.408668)
		(stroke
			(width 0.05715)
			(type default)
		)
		(layer "In4.Cu")
	)
	(gr_line
		(start 368.013996 -129.472944)
		(end 368.20602 -129.345944)
		(stroke
			(width 0.05715)
			(type default)
		)
		(layer "In4.Cu")
	)
	(gr_line
		(start 368.01552 -136.408668)
		(end 368.044476 -136.430258)
		(stroke
			(width 0.05715)
			(type default)
		)
		(layer "In4.Cu")
	)
	(gr_line
		(start 368.05743 -115.387374)
		(end 368.072924 -115.402868)
		(stroke
			(width 0.04445)
			(type default)
		)
		(layer "In4.Cu")
	)
	(gr_line
		(start 368.072924 -115.402868)
		(end 368.072924 -115.47475)
		(stroke
			(width 0.04445)
			(type default)
		)
		(layer "In4.Cu")
	)
	(gr_line
		(start 368.11331 -117.529864)
		(end 368.19967 -117.443504)
		(stroke
			(width 0.04445)
			(type default)
		)
		(layer "In4.Cu")
	)
	(gr_line
		(start 368.12601 -114.001804)
		(end 368.192558 -113.665508)
		(stroke
			(width 0.05715)
			(type default)
		)
		(layer "In4.Cu")
	)
	(gr_line
		(start 368.12601 -114.001804)
		(end 368.25428 -114.193066)
		(stroke
			(width 0.05715)
			(type default)
		)
		(layer "In4.Cu")
	)
	(gr_line
		(start 368.13617 -6.576314)
		(end 368.226594 -6.245606)
		(stroke
			(width 0.05715)
			(type default)
		)
		(layer "In4.Cu")
	)
	(gr_line
		(start 368.13617 -6.576314)
		(end 368.25047 -6.775958)
		(stroke
			(width 0.05715)
			(type default)
		)
		(layer "In4.Cu")
	)
	(gr_line
		(start 368.158776 -11.091672)
		(end 368.634518 -10.73023)
		(stroke
			(width 0.05715)
			(type default)
		)
		(layer "In4.Cu")
	)
	(gr_line
		(start 368.192558 -113.665508)
		(end 368.38382 -113.537238)
		(stroke
			(width 0.05715)
			(type default)
		)
		(layer "In4.Cu")
	)
	(gr_line
		(start 368.19332 -13.253466)
		(end 368.208052 -13.18387)
		(stroke
			(width 0.05715)
			(type default)
		)
		(layer "In4.Cu")
	)
	(gr_line
		(start 368.19967 -117.443504)
		(end 368.46637 -117.443504)
		(stroke
			(width 0.04445)
			(type default)
		)
		(layer "In4.Cu")
	)
	(gr_line
		(start 368.208052 -13.18387)
		(end 368.265964 -13.140944)
		(stroke
			(width 0.05715)
			(type default)
		)
		(layer "In4.Cu")
	)
	(gr_line
		(start 368.226594 -6.245606)
		(end 368.426238 -6.13156)
		(stroke
			(width 0.05715)
			(type default)
		)
		(layer "In4.Cu")
	)
	(gr_line
		(start 368.256566 -10.442702)
		(end 368.484658 -10.473944)
		(stroke
			(width 0.05715)
			(type default)
		)
		(layer "In4.Cu")
	)
	(gr_line
		(start 368.276378 -7.801864)
		(end 368.434112 -7.223252)
		(stroke
			(width 0.05715)
			(type default)
		)
		(layer "In4.Cu")
	)
	(gr_line
		(start 368.297714 -1.419606)
		(end 368.300762 -1.422654)
		(stroke
			(width 0.05715)
			(type default)
		)
		(layer "In4.Cu")
	)
	(gr_line
		(start 368.300762 -1.422654)
		(end 368.685572 -1.422654)
		(stroke
			(width 0.05715)
			(type default)
		)
		(layer "In4.Cu")
	)
	(gr_line
		(start 368.30381 -117.722904)
		(end 368.36223 -117.722904)
		(stroke
			(width 0.04445)
			(type default)
		)
		(layer "In4.Cu")
	)
	(gr_line
		(start 368.323114 -113.005108)
		(end 368.389662 -112.668812)
		(stroke
			(width 0.05715)
			(type default)
		)
		(layer "In4.Cu")
	)
	(gr_line
		(start 368.323114 -113.005108)
		(end 368.451384 -113.19637)
		(stroke
			(width 0.05715)
			(type default)
		)
		(layer "In4.Cu")
	)
	(gr_line
		(start 368.337338 -23.217632)
		(end 368.34953 -23.199344)
		(stroke
			(width 0.05715)
			(type default)
		)
		(layer "In4.Cu")
	)
	(gr_line
		(start 368.34953 -23.199344)
		(end 368.367564 -23.187152)
		(stroke
			(width 0.05715)
			(type default)
		)
		(layer "In4.Cu")
	)
	(gr_line
		(start 368.36477 -95.803974)
		(end 368.378232 -95.737934)
		(stroke
			(width 0.05715)
			(type default)
		)
		(layer "In4.Cu")
	)
	(gr_line
		(start 368.36477 -95.803974)
		(end 368.378232 -95.73768)
		(stroke
			(width 0.05715)
			(type default)
		)
		(layer "In4.Cu")
	)
	(gr_line
		(start 368.36477 -95.803974)
		(end 368.39652 -95.863918)
		(stroke
			(width 0.05715)
			(type default)
		)
		(layer "In4.Cu")
	)
	(gr_line
		(start 368.36477 -95.803974)
		(end 368.39652 -95.863664)
		(stroke
			(width 0.05715)
			(type default)
		)
		(layer "In4.Cu")
	)
	(gr_line
		(start 368.378232 -95.737172)
		(end 368.378232 -95.73768)
		(stroke
			(width 0.05715)
			(type default)
		)
		(layer "In4.Cu")
	)
	(gr_line
		(start 368.389662 -112.668812)
		(end 368.580924 -112.540542)
		(stroke
			(width 0.05715)
			(type default)
		)
		(layer "In4.Cu")
	)
	(gr_line
		(start 368.403632 -5.596128)
		(end 368.493802 -5.26542)
		(stroke
			(width 0.05715)
			(type default)
		)
		(layer "In4.Cu")
	)
	(gr_line
		(start 368.403632 -5.596128)
		(end 368.517678 -5.795772)
		(stroke
			(width 0.05715)
			(type default)
		)
		(layer "In4.Cu")
	)
	(gr_line
		(start 368.46637 -117.443504)
		(end 368.55273 -117.529864)
		(stroke
			(width 0.04445)
			(type default)
		)
		(layer "In4.Cu")
	)
	(gr_line
		(start 368.480594 -132.112512)
		(end 368.480848 -132.112766)
		(stroke
			(width 0.05715)
			(type default)
		)
		(layer "In4.Cu")
	)
	(gr_line
		(start 368.480848 -132.112766)
		(end 368.481102 -132.11302)
		(stroke
			(width 0.05715)
			(type default)
		)
		(layer "In4.Cu")
	)
	(gr_line
		(start 368.48161 -114.561874)
		(end 368.491262 -114.51209)
		(stroke
			(width 0.05715)
			(type default)
		)
		(layer "In4.Cu")
	)
	(gr_line
		(start 368.493802 -5.26542)
		(end 368.693446 -5.15112)
		(stroke
			(width 0.05715)
			(type default)
		)
		(layer "In4.Cu")
	)
	(gr_line
		(start 368.50447 -109.949996)
		(end 368.508534 -109.970316)
		(stroke
			(width 0.05715)
			(type default)
		)
		(layer "In4.Cu")
	)
	(gr_line
		(start 368.50447 -109.949996)
		(end 368.508534 -109.970062)
		(stroke
			(width 0.05715)
			(type default)
		)
		(layer "In4.Cu")
	)
	(gr_line
		(start 368.50447 -109.949488)
		(end 368.50447 -109.949996)
		(stroke
			(width 0.05715)
			(type default)
		)
		(layer "In4.Cu")
	)
	(gr_line
		(start 368.50447 -109.949488)
		(end 368.508534 -109.929676)
		(stroke
			(width 0.05715)
			(type default)
		)
		(layer "In4.Cu")
	)
	(gr_line
		(start 368.50447 -109.949488)
		(end 368.508534 -109.928914)
		(stroke
			(width 0.05715)
			(type default)
		)
		(layer "In4.Cu")
	)
	(gr_line
		(start 368.506756 -110.933992)
		(end 368.510566 -110.953042)
		(stroke
			(width 0.05715)
			(type default)
		)
		(layer "In4.Cu")
	)
	(gr_line
		(start 368.506756 -110.933992)
		(end 368.51082 -110.954312)
		(stroke
			(width 0.05715)
			(type default)
		)
		(layer "In4.Cu")
	)
	(gr_line
		(start 368.506756 -110.933992)
		(end 368.51082 -110.913926)
		(stroke
			(width 0.05715)
			(type default)
		)
		(layer "In4.Cu")
	)
	(gr_line
		(start 368.506756 -110.933992)
		(end 368.51082 -110.913672)
		(stroke
			(width 0.05715)
			(type default)
		)
		(layer "In4.Cu")
	)
	(gr_line
		(start 368.506756 -107.943904)
		(end 368.51082 -107.96397)
		(stroke
			(width 0.05715)
			(type default)
		)
		(layer "In4.Cu")
	)
	(gr_line
		(start 368.506756 -107.943904)
		(end 368.51082 -107.963462)
		(stroke
			(width 0.05715)
			(type default)
		)
		(layer "In4.Cu")
	)
	(gr_line
		(start 368.506756 -107.943904)
		(end 368.51082 -107.924346)
		(stroke
			(width 0.05715)
			(type default)
		)
		(layer "In4.Cu")
	)
	(gr_line
		(start 368.506756 -107.943904)
		(end 368.51082 -107.923838)
		(stroke
			(width 0.05715)
			(type default)
		)
		(layer "In4.Cu")
	)
	(gr_line
		(start 368.511836 -108.9152)
		(end 368.51209 -108.9152)
		(stroke
			(width 0.05715)
			(type default)
		)
		(layer "In4.Cu")
	)
	(gr_line
		(start 368.511836 -108.9152)
		(end 368.5159 -108.935012)
		(stroke
			(width 0.05715)
			(type default)
		)
		(layer "In4.Cu")
	)
	(gr_line
		(start 368.51209 -108.9152)
		(end 368.515646 -108.897166)
		(stroke
			(width 0.05715)
			(type default)
		)
		(layer "In4.Cu")
	)
	(gr_line
		(start 368.51209 -108.9152)
		(end 368.515646 -108.896912)
		(stroke
			(width 0.05715)
			(type default)
		)
		(layer "In4.Cu")
	)
	(gr_line
		(start 368.515646 -108.896404)
		(end 368.515646 -108.896912)
		(stroke
			(width 0.05715)
			(type default)
		)
		(layer "In4.Cu")
	)
	(gr_line
		(start 368.5159 -100.45954)
		(end 368.520472 -100.43541)
		(stroke
			(width 0.05715)
			(type default)
		)
		(layer "In4.Cu")
	)
	(gr_line
		(start 368.5159 -100.45954)
		(end 368.520726 -100.434648)
		(stroke
			(width 0.05715)
			(type default)
		)
		(layer "In4.Cu")
	)
	(gr_line
		(start 368.5159 -100.45954)
		(end 368.521488 -100.483924)
		(stroke
			(width 0.05715)
			(type default)
		)
		(layer "In4.Cu")
	)
	(gr_line
		(start 368.5159 -100.45954)
		(end 368.521488 -100.483162)
		(stroke
			(width 0.05715)
			(type default)
		)
		(layer "In4.Cu")
	)
	(gr_line
		(start 368.518694 -135.95477)
		(end 368.533934 -135.987536)
		(stroke
			(width 0.05715)
			(type default)
		)
		(layer "In4.Cu")
	)
	(gr_line
		(start 368.52225 -97.21088)
		(end 368.526568 -97.232216)
		(stroke
			(width 0.05715)
			(type default)
		)
		(layer "In4.Cu")
	)
	(gr_line
		(start 368.52225 -97.21088)
		(end 368.526568 -97.189544)
		(stroke
			(width 0.05715)
			(type default)
		)
		(layer "In4.Cu")
	)
	(gr_line
		(start 368.533934 -135.987536)
		(end 368.563144 -136.009634)
		(stroke
			(width 0.05715)
			(type default)
		)
		(layer "In4.Cu")
	)
	(gr_line
		(start 368.537744 -105.178098)
		(end 368.660426 -105.22077)
		(stroke
			(width 0.05715)
			(type default)
		)
		(layer "In4.Cu")
	)
	(gr_line
		(start 368.544094 -6.820408)
		(end 368.70132 -6.24332)
		(stroke
			(width 0.05715)
			(type default)
		)
		(layer "In4.Cu")
	)
	(gr_line
		(start 368.546634 -129.415286)
		(end 368.673634 -129.60731)
		(stroke
			(width 0.05715)
			(type default)
		)
		(layer "In4.Cu")
	)
	(gr_line
		(start 368.55019 -114.214656)
		(end 368.66576 -113.62944)
		(stroke
			(width 0.05715)
			(type default)
		)
		(layer "In4.Cu")
	)
	(gr_line
		(start 368.55527 -115.98529)
		(end 368.64163 -116.07165)
		(stroke
			(width 0.04445)
			(type default)
		)
		(layer "In4.Cu")
	)
	(gr_line
		(start 368.563652 -103.762302)
		(end 368.575082 -103.779066)
		(stroke
			(width 0.05715)
			(type default)
		)
		(layer "In4.Cu")
	)
	(gr_line
		(start 368.575082 -103.779066)
		(end 368.591338 -103.789988)
		(stroke
			(width 0.05715)
			(type default)
		)
		(layer "In4.Cu")
	)
	(gr_line
		(start 368.594386 -98.394266)
		(end 368.598704 -98.415348)
		(stroke
			(width 0.05715)
			(type default)
		)
		(layer "In4.Cu")
	)
	(gr_line
		(start 368.594386 -98.394266)
		(end 368.598704 -98.37293)
		(stroke
			(width 0.05715)
			(type default)
		)
		(layer "In4.Cu")
	)
	(gr_line
		(start 368.636804 -119.904764)
		(end 368.799364 -119.742204)
		(stroke
			(width 0.05715)
			(type default)
		)
		(layer "In4.Cu")
	)
	(gr_line
		(start 368.639852 -129.1336)
		(end 369.226084 -129.25298)
		(stroke
			(width 0.05715)
			(type default)
		)
		(layer "In4.Cu")
	)
	(gr_line
		(start 368.640614 -32.13862)
		(end 368.659156 -32.126174)
		(stroke
			(width 0.05715)
			(type default)
		)
		(layer "In4.Cu")
	)
	(gr_line
		(start 368.64163 -116.07165)
		(end 368.90833 -116.07165)
		(stroke
			(width 0.04445)
			(type default)
		)
		(layer "In4.Cu")
	)
	(gr_line
		(start 368.659156 -32.126174)
		(end 368.671094 -32.107632)
		(stroke
			(width 0.05715)
			(type default)
		)
		(layer "In4.Cu")
	)
	(gr_line
		(start 368.660426 -105.22077)
		(end 368.685572 -105.347516)
		(stroke
			(width 0.05715)
			(type default)
		)
		(layer "In4.Cu")
	)
	(gr_line
		(start 368.673634 -129.60731)
		(end 369.009676 -129.675636)
		(stroke
			(width 0.05715)
			(type default)
		)
		(layer "In4.Cu")
	)
	(gr_line
		(start 368.685572 -1.422654)
		(end 368.72291 -1.459992)
		(stroke
			(width 0.05715)
			(type default)
		)
		(layer "In4.Cu")
	)
	(gr_line
		(start 368.695478 -136.918954)
		(end 368.71656 -136.934702)
		(stroke
			(width 0.05715)
			(type default)
		)
		(layer "In4.Cu")
	)
	(gr_line
		(start 368.71656 -136.934702)
		(end 368.742214 -136.94029)
		(stroke
			(width 0.05715)
			(type default)
		)
		(layer "In4.Cu")
	)
	(gr_line
		(start 368.720878 -14.275816)
		(end 368.735356 -14.207236)
		(stroke
			(width 0.05715)
			(type default)
		)
		(layer "In4.Cu")
	)
	(gr_line
		(start 368.735356 -14.207236)
		(end 368.79022 -14.164818)
		(stroke
			(width 0.05715)
			(type default)
		)
		(layer "In4.Cu")
	)
	(gr_line
		(start 368.74577 -115.79225)
		(end 368.80419 -115.79225)
		(stroke
			(width 0.04445)
			(type default)
		)
		(layer "In4.Cu")
	)
	(gr_line
		(start 368.74704 -101.470714)
		(end 368.754152 -101.501702)
		(stroke
			(width 0.05715)
			(type default)
		)
		(layer "In4.Cu")
	)
	(gr_line
		(start 368.747294 -113.218214)
		(end 368.863118 -112.63249)
		(stroke
			(width 0.05715)
			(type default)
		)
		(layer "In4.Cu")
	)
	(gr_line
		(start 368.754152 -101.501702)
		(end 368.774218 -101.52634)
		(stroke
			(width 0.05715)
			(type default)
		)
		(layer "In4.Cu")
	)
	(gr_line
		(start 368.797586 -94.841568)
		(end 368.845084 -94.911418)
		(stroke
			(width 0.05715)
			(type default)
		)
		(layer "In4.Cu")
	)
	(gr_line
		(start 368.799364 -119.742204)
		(end 369.142264 -119.742204)
		(stroke
			(width 0.05715)
			(type default)
		)
		(layer "In4.Cu")
	)
	(gr_line
		(start 368.809778 -31.359094)
		(end 368.8207 -31.342076)
		(stroke
			(width 0.05715)
			(type default)
		)
		(layer "In4.Cu")
	)
	(gr_line
		(start 368.811302 -5.83946)
		(end 368.968528 -5.262626)
		(stroke
			(width 0.05715)
			(type default)
		)
		(layer "In4.Cu")
	)
	(gr_line
		(start 368.8207 -31.342076)
		(end 368.83721 -31.3309)
		(stroke
			(width 0.05715)
			(type default)
		)
		(layer "In4.Cu")
	)
	(gr_line
		(start 368.82451 -117.529864)
		(end 368.91087 -117.443504)
		(stroke
			(width 0.04445)
			(type default)
		)
		(layer "In4.Cu")
	)
	(gr_line
		(start 368.828066 -94.99473)
		(end 368.845084 -94.911418)
		(stroke
			(width 0.05715)
			(type default)
		)
		(layer "In4.Cu")
	)
	(gr_line
		(start 368.8969 -110.467394)
		(end 368.900964 -110.447328)
		(stroke
			(width 0.05715)
			(type default)
		)
		(layer "In4.Cu")
	)
	(gr_line
		(start 368.8969 -110.42777)
		(end 368.900964 -110.447328)
		(stroke
			(width 0.05715)
			(type default)
		)
		(layer "In4.Cu")
	)
	(gr_line
		(start 368.89944 -108.462826)
		(end 368.903504 -108.442252)
		(stroke
			(width 0.05715)
			(type default)
		)
		(layer "In4.Cu")
	)
	(gr_line
		(start 368.89944 -108.422694)
		(end 368.903504 -108.442252)
		(stroke
			(width 0.05715)
			(type default)
		)
		(layer "In4.Cu")
	)
	(gr_line
		(start 368.904266 -109.434122)
		(end 368.90833 -109.413548)
		(stroke
			(width 0.05715)
			(type default)
		)
		(layer "In4.Cu")
	)
	(gr_line
		(start 368.904266 -109.39399)
		(end 368.90833 -109.413548)
		(stroke
			(width 0.05715)
			(type default)
		)
		(layer "In4.Cu")
	)
	(gr_line
		(start 368.90833 -116.07165)
		(end 368.99469 -115.98529)
		(stroke
			(width 0.04445)
			(type default)
		)
		(layer "In4.Cu")
	)
	(gr_line
		(start 368.91087 -117.443504)
		(end 369.17757 -117.443504)
		(stroke
			(width 0.04445)
			(type default)
		)
		(layer "In4.Cu")
	)
	(gr_line
		(start 368.928904 -120.199404)
		(end 369.012724 -120.199404)
		(stroke
			(width 0.05715)
			(type default)
		)
		(layer "In4.Cu")
	)
	(gr_line
		(start 368.960908 -96.30537)
		(end 368.991896 -96.364044)
		(stroke
			(width 0.05715)
			(type default)
		)
		(layer "In4.Cu")
	)
	(gr_line
		(start 368.967512 -10.477246)
		(end 369.002564 -10.450576)
		(stroke
			(width 0.05715)
			(type default)
		)
		(layer "In4.Cu")
	)
	(gr_line
		(start 368.970306 -136.315196)
		(end 368.991388 -136.330944)
		(stroke
			(width 0.05715)
			(type default)
		)
		(layer "In4.Cu")
	)
	(gr_line
		(start 368.972592 -98.00082)
		(end 368.97691 -97.979484)
		(stroke
			(width 0.05715)
			(type default)
		)
		(layer "In4.Cu")
	)
	(gr_line
		(start 368.972592 -97.958148)
		(end 368.97691 -97.979484)
		(stroke
			(width 0.05715)
			(type default)
		)
		(layer "In4.Cu")
	)
	(gr_line
		(start 368.97818 -113.884202)
		(end 368.984276 -113.852706)
		(stroke
			(width 0.05715)
			(type default)
		)
		(layer "In4.Cu")
	)
	(gr_line
		(start 368.97818 -113.884202)
		(end 368.98707 -113.915698)
		(stroke
			(width 0.05715)
			(type default)
		)
		(layer "In4.Cu")
	)
	(gr_line
		(start 368.978942 -96.432878)
		(end 368.979196 -96.432116)
		(stroke
			(width 0.05715)
			(type default)
		)
		(layer "In4.Cu")
	)
	(gr_line
		(start 368.979196 -96.43237)
		(end 368.992658 -96.365568)
		(stroke
			(width 0.05715)
			(type default)
		)
		(layer "In4.Cu")
	)
	(gr_line
		(start 368.991388 -136.330944)
		(end 369.017042 -136.336532)
		(stroke
			(width 0.05715)
			(type default)
		)
		(layer "In4.Cu")
	)
	(gr_line
		(start 368.991896 -96.364044)
		(end 368.992658 -96.365568)
		(stroke
			(width 0.05715)
			(type default)
		)
		(layer "In4.Cu")
	)
	(gr_line
		(start 368.997992 -111.949738)
		(end 369.002056 -111.929672)
		(stroke
			(width 0.05715)
			(type default)
		)
		(layer "In4.Cu")
	)
	(gr_line
		(start 368.997992 -111.910114)
		(end 369.002056 -111.929672)
		(stroke
			(width 0.05715)
			(type default)
		)
		(layer "In4.Cu")
	)
	(gr_line
		(start 368.997992 -106.96702)
		(end 369.002056 -106.946954)
		(stroke
			(width 0.05715)
			(type default)
		)
		(layer "In4.Cu")
	)
	(gr_line
		(start 368.997992 -106.927396)
		(end 369.002056 -106.946954)
		(stroke
			(width 0.05715)
			(type default)
		)
		(layer "In4.Cu")
	)
	(gr_line
		(start 369.002564 -10.450576)
		(end 369.002818 -10.450576)
		(stroke
			(width 0.05715)
			(type default)
		)
		(layer "In4.Cu")
	)
	(gr_line
		(start 369.002818 -10.450576)
		(end 369.019328 -10.408666)
		(stroke
			(width 0.05715)
			(type default)
		)
		(layer "In4.Cu")
	)
	(gr_line
		(start 369.009676 -129.675636)
		(end 369.201446 -129.548636)
		(stroke
			(width 0.05715)
			(type default)
		)
		(layer "In4.Cu")
	)
	(gr_line
		(start 369.01501 -117.722904)
		(end 369.07343 -117.722904)
		(stroke
			(width 0.04445)
			(type default)
		)
		(layer "In4.Cu")
	)
	(gr_line
		(start 369.05311 -99.181412)
		(end 369.057174 -99.201478)
		(stroke
			(width 0.05715)
			(type default)
		)
		(layer "In4.Cu")
	)
	(gr_line
		(start 369.053364 -99.221544)
		(end 369.053364 -99.222052)
		(stroke
			(width 0.05715)
			(type default)
		)
		(layer "In4.Cu")
	)
	(gr_line
		(start 369.053364 -99.22129)
		(end 369.057174 -99.201478)
		(stroke
			(width 0.05715)
			(type default)
		)
		(layer "In4.Cu")
	)
	(gr_line
		(start 369.078764 -4.85775)
		(end 369.078764 -4.858004)
		(stroke
			(width 0.05715)
			(type default)
		)
		(layer "In4.Cu")
	)
	(gr_line
		(start 369.133628 -104.58196)
		(end 369.203732 -104.629204)
		(stroke
			(width 0.05715)
			(type default)
		)
		(layer "In4.Cu")
	)
	(gr_line
		(start 369.139724 -1.459992)
		(end 369.18011 -1.419606)
		(stroke
			(width 0.05715)
			(type default)
		)
		(layer "In4.Cu")
	)
	(gr_line
		(start 369.142264 -119.742204)
		(end 369.304824 -119.904764)
		(stroke
			(width 0.05715)
			(type default)
		)
		(layer "In4.Cu")
	)
	(gr_line
		(start 369.145312 -95.609918)
		(end 369.158774 -95.543878)
		(stroke
			(width 0.05715)
			(type default)
		)
		(layer "In4.Cu")
	)
	(gr_line
		(start 369.145312 -95.609918)
		(end 369.158774 -95.543624)
		(stroke
			(width 0.05715)
			(type default)
		)
		(layer "In4.Cu")
	)
	(gr_line
		(start 369.145312 -95.609918)
		(end 369.177062 -95.669862)
		(stroke
			(width 0.05715)
			(type default)
		)
		(layer "In4.Cu")
	)
	(gr_line
		(start 369.145312 -95.609918)
		(end 369.177062 -95.669608)
		(stroke
			(width 0.05715)
			(type default)
		)
		(layer "In4.Cu")
	)
	(gr_line
		(start 369.158774 -95.543116)
		(end 369.158774 -95.543624)
		(stroke
			(width 0.05715)
			(type default)
		)
		(layer "In4.Cu")
	)
	(gr_line
		(start 369.167156 -110.933738)
		(end 369.17122 -110.953804)
		(stroke
			(width 0.05715)
			(type default)
		)
		(layer "In4.Cu")
	)
	(gr_line
		(start 369.167156 -110.933738)
		(end 369.17122 -110.913926)
		(stroke
			(width 0.05715)
			(type default)
		)
		(layer "In4.Cu")
	)
	(gr_line
		(start 369.167156 -109.937296)
		(end 369.17122 -109.957362)
		(stroke
			(width 0.05715)
			(type default)
		)
		(layer "In4.Cu")
	)
	(gr_line
		(start 369.167156 -109.936788)
		(end 369.167156 -109.937296)
		(stroke
			(width 0.05715)
			(type default)
		)
		(layer "In4.Cu")
	)
	(gr_line
		(start 369.167156 -109.936788)
		(end 369.17122 -109.916214)
		(stroke
			(width 0.05715)
			(type default)
		)
		(layer "In4.Cu")
	)
	(gr_line
		(start 369.167156 -107.943904)
		(end 369.17122 -107.96397)
		(stroke
			(width 0.05715)
			(type default)
		)
		(layer "In4.Cu")
	)
	(gr_line
		(start 369.167156 -107.943904)
		(end 369.17122 -107.924346)
		(stroke
			(width 0.05715)
			(type default)
		)
		(layer "In4.Cu")
	)
	(gr_line
		(start 369.168426 -108.934504)
		(end 369.17249 -108.95457)
		(stroke
			(width 0.05715)
			(type default)
		)
		(layer "In4.Cu")
	)
	(gr_line
		(start 369.168426 -108.934504)
		(end 369.17249 -108.914692)
		(stroke
			(width 0.05715)
			(type default)
		)
		(layer "In4.Cu")
	)
	(gr_line
		(start 369.177062 -114.58448)
		(end 369.187476 -114.621056)
		(stroke
			(width 0.05715)
			(type default)
		)
		(layer "In4.Cu")
	)
	(gr_line
		(start 369.177316 -32.554418)
		(end 369.19281 -32.544258)
		(stroke
			(width 0.05715)
			(type default)
		)
		(layer "In4.Cu")
	)
	(gr_line
		(start 369.17757 -117.443504)
		(end 369.26393 -117.529864)
		(stroke
			(width 0.04445)
			(type default)
		)
		(layer "In4.Cu")
	)
	(gr_line
		(start 369.18011 -1.419606)
		(end 369.567714 -1.419606)
		(stroke
			(width 0.05715)
			(type default)
		)
		(layer "In4.Cu")
	)
	(gr_line
		(start 369.186968 -97.22866)
		(end 369.191286 -97.249996)
		(stroke
			(width 0.05715)
			(type default)
		)
		(layer "In4.Cu")
	)
	(gr_line
		(start 369.186968 -97.22866)
		(end 369.191286 -97.249742)
		(stroke
			(width 0.05715)
			(type default)
		)
		(layer "In4.Cu")
	)
	(gr_line
		(start 369.186968 -97.22866)
		(end 369.191286 -97.207324)
		(stroke
			(width 0.05715)
			(type default)
		)
		(layer "In4.Cu")
	)
	(gr_line
		(start 369.19281 -32.544258)
		(end 369.203478 -32.528256)
		(stroke
			(width 0.05715)
			(type default)
		)
		(layer "In4.Cu")
	)
	(gr_line
		(start 369.198906 -100.320094)
		(end 369.20297 -100.340414)
		(stroke
			(width 0.05715)
			(type default)
		)
		(layer "In4.Cu")
	)
	(gr_line
		(start 369.198906 -100.320094)
		(end 369.20297 -100.339906)
		(stroke
			(width 0.05715)
			(type default)
		)
		(layer "In4.Cu")
	)
	(gr_line
		(start 369.198906 -100.320094)
		(end 369.20297 -100.300028)
		(stroke
			(width 0.05715)
			(type default)
		)
		(layer "In4.Cu")
	)
	(gr_line
		(start 369.198906 -100.320094)
		(end 369.20297 -100.299774)
		(stroke
			(width 0.05715)
			(type default)
		)
		(layer "In4.Cu")
	)
	(gr_line
		(start 369.203732 -104.629204)
		(end 369.220242 -104.712262)
		(stroke
			(width 0.05715)
			(type default)
		)
		(layer "In4.Cu")
	)
	(gr_line
		(start 369.256818 -98.406712)
		(end 369.261136 -98.428048)
		(stroke
			(width 0.05715)
			(type default)
		)
		(layer "In4.Cu")
	)
	(gr_line
		(start 369.256818 -98.406712)
		(end 369.261136 -98.38563)
		(stroke
			(width 0.05715)
			(type default)
		)
		(layer "In4.Cu")
	)
	(gr_line
		(start 369.26647 -115.98529)
		(end 369.35283 -116.07165)
		(stroke
			(width 0.04445)
			(type default)
		)
		(layer "In4.Cu")
	)
	(gr_line
		(start 369.27028 -31.905956)
		(end 369.28044 -31.89097)
		(stroke
			(width 0.05715)
			(type default)
		)
		(layer "In4.Cu")
	)
	(gr_line
		(start 369.27028 -29.69387)
		(end 369.290346 -29.69006)
		(stroke
			(width 0.05715)
			(type default)
		)
		(layer "In4.Cu")
	)
	(gr_line
		(start 369.28044 -31.89097)
		(end 369.294918 -31.88081)
		(stroke
			(width 0.05715)
			(type default)
		)
		(layer "In4.Cu")
	)
	(gr_line
		(start 369.290346 -29.69006)
		(end 369.307872 -29.678376)
		(stroke
			(width 0.05715)
			(type default)
		)
		(layer "In4.Cu")
	)
	(gr_line
		(start 369.316 -118.237)
		(end 369.43792 -118.35892)
		(stroke
			(width 0.05715)
			(type default)
		)
		(layer "In4.Cu")
	)
	(gr_line
		(start 369.316 -116.7892)
		(end 369.672616 -117.145816)
		(stroke
			(width 0.04445)
			(type default)
		)
		(layer "In4.Cu")
	)
	(gr_line
		(start 369.316 -115.3414)
		(end 369.43792 -115.21948)
		(stroke
			(width 0.05715)
			(type default)
		)
		(layer "In4.Cu")
	)
	(gr_line
		(start 369.33124 -128.224026)
		(end 369.376198 -128.23317)
		(stroke
			(width 0.05715)
			(type default)
		)
		(layer "In4.Cu")
	)
	(gr_line
		(start 369.338352 -128.912874)
		(end 369.38331 -128.922018)
		(stroke
			(width 0.05715)
			(type default)
		)
		(layer "In4.Cu")
	)
	(gr_line
		(start 369.35283 -116.07165)
		(end 369.61953 -116.07165)
		(stroke
			(width 0.04445)
			(type default)
		)
		(layer "In4.Cu")
	)
	(gr_line
		(start 369.375436 -101.223826)
		(end 369.382294 -101.258878)
		(stroke
			(width 0.05715)
			(type default)
		)
		(layer "In4.Cu")
	)
	(gr_line
		(start 369.37569 -101.22408)
		(end 369.382294 -101.258878)
		(stroke
			(width 0.05715)
			(type default)
		)
		(layer "In4.Cu")
	)
	(gr_line
		(start 369.376198 -128.23317)
		(end 369.41887 -128.217168)
		(stroke
			(width 0.05715)
			(type default)
		)
		(layer "In4.Cu")
	)
	(gr_line
		(start 369.382294 -101.258878)
		(end 369.4049 -101.286564)
		(stroke
			(width 0.05715)
			(type default)
		)
		(layer "In4.Cu")
	)
	(gr_line
		(start 369.38331 -128.922018)
		(end 369.426236 -128.906016)
		(stroke
			(width 0.05715)
			(type default)
		)
		(layer "In4.Cu")
	)
	(gr_line
		(start 369.452398 -136.429242)
		(end 369.502436 -136.43991)
		(stroke
			(width 0.05715)
			(type default)
		)
		(layer "In4.Cu")
	)
	(gr_line
		(start 369.45697 -115.79225)
		(end 369.51539 -115.79225)
		(stroke
			(width 0.04445)
			(type default)
		)
		(layer "In4.Cu")
	)
	(gr_line
		(start 369.502436 -136.43991)
		(end 369.549426 -136.421114)
		(stroke
			(width 0.05715)
			(type default)
		)
		(layer "In4.Cu")
	)
	(gr_line
		(start 369.515644 -137.105136)
		(end 369.565174 -137.115804)
		(stroke
			(width 0.05715)
			(type default)
		)
		(layer "In4.Cu")
	)
	(gr_line
		(start 369.516914 -129.610358)
		(end 369.540282 -129.615184)
		(stroke
			(width 0.05715)
			(type default)
		)
		(layer "In4.Cu")
	)
	(gr_line
		(start 369.540282 -129.615184)
		(end 369.562888 -129.610104)
		(stroke
			(width 0.05715)
			(type default)
		)
		(layer "In4.Cu")
	)
	(gr_line
		(start 369.557808 -10.852912)
		(end 369.592352 -10.825988)
		(stroke
			(width 0.05715)
			(type default)
		)
		(layer "In4.Cu")
	)
	(gr_line
		(start 369.559586 -110.455456)
		(end 369.56365 -110.43539)
		(stroke
			(width 0.05715)
			(type default)
		)
		(layer "In4.Cu")
	)
	(gr_line
		(start 369.559586 -110.415578)
		(end 369.56365 -110.43539)
		(stroke
			(width 0.05715)
			(type default)
		)
		(layer "In4.Cu")
	)
	(gr_line
		(start 369.559586 -108.462826)
		(end 369.56365 -108.442252)
		(stroke
			(width 0.05715)
			(type default)
		)
		(layer "In4.Cu")
	)
	(gr_line
		(start 369.559586 -108.42244)
		(end 369.56365 -108.442252)
		(stroke
			(width 0.05715)
			(type default)
		)
		(layer "In4.Cu")
	)
	(gr_line
		(start 369.560856 -109.452918)
		(end 369.56492 -109.432852)
		(stroke
			(width 0.05715)
			(type default)
		)
		(layer "In4.Cu")
	)
	(gr_line
		(start 369.560856 -109.41304)
		(end 369.56492 -109.432852)
		(stroke
			(width 0.05715)
			(type default)
		)
		(layer "In4.Cu")
	)
	(gr_line
		(start 369.565174 -137.115804)
		(end 369.612164 -137.097008)
		(stroke
			(width 0.05715)
			(type default)
		)
		(layer "In4.Cu")
	)
	(gr_line
		(start 369.5827 -29.494988)
		(end 369.64874 -29.450792)
		(stroke
			(width 0.05715)
			(type default)
		)
		(layer "In4.Cu")
	)
	(gr_line
		(start 369.592352 -10.825988)
		(end 369.608354 -10.785094)
		(stroke
			(width 0.05715)
			(type default)
		)
		(layer "In4.Cu")
	)
	(gr_line
		(start 369.61699 -30.275022)
		(end 369.639088 -30.27045)
		(stroke
			(width 0.05715)
			(type default)
		)
		(layer "In4.Cu")
	)
	(gr_line
		(start 369.61953 -116.07165)
		(end 369.70589 -115.98529)
		(stroke
			(width 0.04445)
			(type default)
		)
		(layer "In4.Cu")
	)
	(gr_line
		(start 369.635786 -98.010472)
		(end 369.640104 -97.98939)
		(stroke
			(width 0.05715)
			(type default)
		)
		(layer "In4.Cu")
	)
	(gr_line
		(start 369.635786 -97.968054)
		(end 369.640104 -97.98939)
		(stroke
			(width 0.05715)
			(type default)
		)
		(layer "In4.Cu")
	)
	(gr_line
		(start 369.638072 -94.348046)
		(end 369.68684 -94.419928)
		(stroke
			(width 0.05715)
			(type default)
		)
		(layer "In4.Cu")
	)
	(gr_line
		(start 369.639088 -30.27045)
		(end 369.65763 -30.25775)
		(stroke
			(width 0.05715)
			(type default)
		)
		(layer "In4.Cu")
	)
	(gr_line
		(start 369.64874 -29.450792)
		(end 369.666266 -29.373322)
		(stroke
			(width 0.05715)
			(type default)
		)
		(layer "In4.Cu")
	)
	(gr_line
		(start 369.652804 -119.904764)
		(end 369.815364 -119.742204)
		(stroke
			(width 0.05715)
			(type default)
		)
		(layer "In4.Cu")
	)
	(gr_line
		(start 369.658138 -111.951008)
		(end 369.662202 -111.930434)
		(stroke
			(width 0.05715)
			(type default)
		)
		(layer "In4.Cu")
	)
	(gr_line
		(start 369.658138 -111.910622)
		(end 369.662202 -111.930434)
		(stroke
			(width 0.05715)
			(type default)
		)
		(layer "In4.Cu")
	)
	(gr_line
		(start 369.658392 -106.967274)
		(end 369.662456 -106.947208)
		(stroke
			(width 0.05715)
			(type default)
		)
		(layer "In4.Cu")
	)
	(gr_line
		(start 369.658392 -106.92765)
		(end 369.662456 -106.947208)
		(stroke
			(width 0.05715)
			(type default)
		)
		(layer "In4.Cu")
	)
	(gr_line
		(start 369.669314 -94.50578)
		(end 369.669568 -94.505018)
		(stroke
			(width 0.05715)
			(type default)
		)
		(layer "In4.Cu")
	)
	(gr_line
		(start 369.669568 -94.505272)
		(end 369.68684 -94.419928)
		(stroke
			(width 0.05715)
			(type default)
		)
		(layer "In4.Cu")
	)
	(gr_line
		(start 369.688872 -96.012254)
		(end 369.720622 -96.071944)
		(stroke
			(width 0.05715)
			(type default)
		)
		(layer "In4.Cu")
	)
	(gr_line
		(start 369.706906 -96.139254)
		(end 369.720622 -96.071944)
		(stroke
			(width 0.05715)
			(type default)
		)
		(layer "In4.Cu")
	)
	(gr_line
		(start 369.713256 -99.225354)
		(end 369.71732 -99.20478)
		(stroke
			(width 0.05715)
			(type default)
		)
		(layer "In4.Cu")
	)
	(gr_line
		(start 369.713256 -99.185222)
		(end 369.71732 -99.20478)
		(stroke
			(width 0.05715)
			(type default)
		)
		(layer "In4.Cu")
	)
	(gr_line
		(start 369.719098 -104.194356)
		(end 369.787424 -104.24033)
		(stroke
			(width 0.05715)
			(type default)
		)
		(layer "In4.Cu")
	)
	(gr_line
		(start 369.787424 -104.24033)
		(end 369.803426 -104.321102)
		(stroke
			(width 0.05715)
			(type default)
		)
		(layer "In4.Cu")
	)
	(gr_line
		(start 369.791742 -32.930338)
		(end 369.807998 -32.91967)
		(stroke
			(width 0.05715)
			(type default)
		)
		(layer "In4.Cu")
	)
	(gr_line
		(start 369.807998 -32.91967)
		(end 369.819428 -32.902652)
		(stroke
			(width 0.05715)
			(type default)
		)
		(layer "In4.Cu")
	)
	(gr_line
		(start 369.815364 -119.742204)
		(end 370.158264 -119.742204)
		(stroke
			(width 0.05715)
			(type default)
		)
		(layer "In4.Cu")
	)
	(gr_line
		(start 369.827302 -109.937296)
		(end 369.831366 -109.957616)
		(stroke
			(width 0.05715)
			(type default)
		)
		(layer "In4.Cu")
	)
	(gr_line
		(start 369.827302 -109.937296)
		(end 369.831366 -109.917738)
		(stroke
			(width 0.05715)
			(type default)
		)
		(layer "In4.Cu")
	)
	(gr_line
		(start 369.827556 -107.943904)
		(end 369.83162 -107.96397)
		(stroke
			(width 0.05715)
			(type default)
		)
		(layer "In4.Cu")
	)
	(gr_line
		(start 369.827556 -107.943904)
		(end 369.83162 -107.923838)
		(stroke
			(width 0.05715)
			(type default)
		)
		(layer "In4.Cu")
	)
	(gr_line
		(start 369.828572 -108.934504)
		(end 369.832636 -108.95457)
		(stroke
			(width 0.05715)
			(type default)
		)
		(layer "In4.Cu")
	)
	(gr_line
		(start 369.828572 -108.934504)
		(end 369.832636 -108.914692)
		(stroke
			(width 0.05715)
			(type default)
		)
		(layer "In4.Cu")
	)
	(gr_line
		(start 369.838224 -102.367842)
		(end 369.84813 -102.380034)
		(stroke
			(width 0.05715)
			(type default)
		)
		(layer "In4.Cu")
	)
	(gr_line
		(start 369.84813 -102.380034)
		(end 369.85321 -102.39502)
		(stroke
			(width 0.05715)
			(type default)
		)
		(layer "In4.Cu")
	)
	(gr_line
		(start 369.85448 -118.35892)
		(end 369.9764 -118.237)
		(stroke
			(width 0.05715)
			(type default)
		)
		(layer "In4.Cu")
	)
	(gr_line
		(start 369.85448 -115.21948)
		(end 369.9764 -115.3414)
		(stroke
			(width 0.05715)
			(type default)
		)
		(layer "In4.Cu")
	)
	(gr_line
		(start 369.865656 -116.899944)
		(end 369.865656 -116.955316)
		(stroke
			(width 0.04445)
			(type default)
		)
		(layer "In4.Cu")
	)
	(gr_line
		(start 369.865656 -116.899944)
		(end 369.9764 -116.7892)
		(stroke
			(width 0.04445)
			(type default)
		)
		(layer "In4.Cu")
	)
	(gr_line
		(start 369.893596 -32.264096)
		(end 369.904264 -32.24784)
		(stroke
			(width 0.05715)
			(type default)
		)
		(layer "In4.Cu")
	)
	(gr_line
		(start 369.903502 -110.323376)
		(end 369.908582 -110.348776)
		(stroke
			(width 0.05715)
			(type default)
		)
		(layer "In4.Cu")
	)
	(gr_line
		(start 369.904264 -32.24784)
		(end 369.920266 -32.236918)
		(stroke
			(width 0.05715)
			(type default)
		)
		(layer "In4.Cu")
	)
	(gr_line
		(start 369.908582 -110.348776)
		(end 369.923314 -110.36935)
		(stroke
			(width 0.05715)
			(type default)
		)
		(layer "In4.Cu")
	)
	(gr_line
		(start 369.944904 -120.199404)
		(end 370.028724 -120.199404)
		(stroke
			(width 0.05715)
			(type default)
		)
		(layer "In4.Cu")
	)
	(gr_line
		(start 369.97767 -115.98529)
		(end 370.06403 -116.07165)
		(stroke
			(width 0.04445)
			(type default)
		)
		(layer "In4.Cu")
	)
	(gr_line
		(start 370.06403 -116.07165)
		(end 370.33073 -116.07165)
		(stroke
			(width 0.04445)
			(type default)
		)
		(layer "In4.Cu")
	)
	(gr_line
		(start 370.096288 -133.665722)
		(end 370.102892 -133.670802)
		(stroke
			(width 0.05715)
			(type default)
		)
		(layer "In4.Cu")
	)
	(gr_line
		(start 370.102892 -133.670802)
		(end 370.11102 -133.673596)
		(stroke
			(width 0.05715)
			(type default)
		)
		(layer "In4.Cu")
	)
	(gr_line
		(start 370.158264 -119.742204)
		(end 370.320824 -119.904764)
		(stroke
			(width 0.05715)
			(type default)
		)
		(layer "In4.Cu")
	)
	(gr_line
		(start 370.16817 -115.79225)
		(end 370.22659 -115.79225)
		(stroke
			(width 0.04445)
			(type default)
		)
		(layer "In4.Cu")
	)
	(gr_line
		(start 370.198396 -29.886402)
		(end 370.262658 -29.842206)
		(stroke
			(width 0.05715)
			(type default)
		)
		(layer "In4.Cu")
	)
	(gr_line
		(start 370.219732 -108.462826)
		(end 370.223796 -108.442252)
		(stroke
			(width 0.05715)
			(type default)
		)
		(layer "In4.Cu")
	)
	(gr_line
		(start 370.219732 -108.42244)
		(end 370.223796 -108.442252)
		(stroke
			(width 0.05715)
			(type default)
		)
		(layer "In4.Cu")
	)
	(gr_line
		(start 370.221256 -109.452918)
		(end 370.22532 -109.432852)
		(stroke
			(width 0.05715)
			(type default)
		)
		(layer "In4.Cu")
	)
	(gr_line
		(start 370.221256 -109.413294)
		(end 370.22532 -109.432852)
		(stroke
			(width 0.05715)
			(type default)
		)
		(layer "In4.Cu")
	)
	(gr_line
		(start 370.262658 -29.842206)
		(end 370.279676 -29.766006)
		(stroke
			(width 0.05715)
			(type default)
		)
		(layer "In4.Cu")
	)
	(gr_line
		(start 370.318284 -106.968544)
		(end 370.322348 -106.948478)
		(stroke
			(width 0.05715)
			(type default)
		)
		(layer "In4.Cu")
	)
	(gr_line
		(start 370.318284 -106.928666)
		(end 370.322348 -106.948478)
		(stroke
			(width 0.05715)
			(type default)
		)
		(layer "In4.Cu")
	)
	(gr_line
		(start 370.324126 -113.3221)
		(end 370.365528 -113.280698)
		(stroke
			(width 0.04445)
			(type default)
		)
		(layer "In4.Cu")
	)
	(gr_line
		(start 370.325904 -113.593372)
		(end 370.448078 -113.593372)
		(stroke
			(width 0.04445)
			(type default)
		)
		(layer "In4.Cu")
	)
	(gr_line
		(start 370.33073 -116.07165)
		(end 370.41709 -115.98529)
		(stroke
			(width 0.04445)
			(type default)
		)
		(layer "In4.Cu")
	)
	(gr_line
		(start 370.36502 -24.955754)
		(end 370.386102 -24.86152)
		(stroke
			(width 0.05715)
			(type default)
		)
		(layer "In4.Cu")
	)
	(gr_line
		(start 370.365274 -8.03656)
		(end 370.374418 -8.013192)
		(stroke
			(width 0.05715)
			(type default)
		)
		(layer "In4.Cu")
	)
	(gr_line
		(start 370.386102 -24.86152)
		(end 370.472208 -24.8158)
		(stroke
			(width 0.05715)
			(type default)
		)
		(layer "In4.Cu")
	)
	(gr_line
		(start 370.412264 -129.121408)
		(end 370.466112 -129.109216)
		(stroke
			(width 0.05715)
			(type default)
		)
		(layer "In4.Cu")
	)
	(gr_line
		(start 370.421662 -102.070154)
		(end 370.431568 -102.082346)
		(stroke
			(width 0.05715)
			(type default)
		)
		(layer "In4.Cu")
	)
	(gr_line
		(start 370.431568 -102.082346)
		(end 370.436648 -102.097332)
		(stroke
			(width 0.05715)
			(type default)
		)
		(layer "In4.Cu")
	)
	(gr_line
		(start 370.448078 -113.593372)
		(end 370.6368 -113.40465)
		(stroke
			(width 0.04445)
			(type default)
		)
		(layer "In4.Cu")
	)
	(gr_line
		(start 370.466112 -129.109216)
		(end 370.517166 -129.130806)
		(stroke
			(width 0.05715)
			(type default)
		)
		(layer "In4.Cu")
	)
	(gr_line
		(start 370.55044 -5.281168)
		(end 370.642134 -5.492242)
		(stroke
			(width 0.05715)
			(type default)
		)
		(layer "In4.Cu")
	)
	(gr_line
		(start 370.55044 -5.281168)
		(end 370.676424 -4.962144)
		(stroke
			(width 0.05715)
			(type default)
		)
		(layer "In4.Cu")
	)
	(gr_line
		(start 370.6368 -113.282476)
		(end 370.6368 -113.40465)
		(stroke
			(width 0.04445)
			(type default)
		)
		(layer "In4.Cu")
	)
	(gr_line
		(start 370.676424 -4.962144)
		(end 370.887244 -4.870704)
		(stroke
			(width 0.05715)
			(type default)
		)
		(layer "In4.Cu")
	)
	(gr_line
		(start 370.701316 -107.032552)
		(end 370.719096 -107.123738)
		(stroke
			(width 0.05715)
			(type default)
		)
		(layer "In4.Cu")
	)
	(gr_line
		(start 370.717318 -112.873028)
		(end 370.717318 -112.928908)
		(stroke
			(width 0.04445)
			(type default)
		)
		(layer "In4.Cu")
	)
	(gr_line
		(start 370.717318 -112.856772)
		(end 370.717318 -112.870488)
		(stroke
			(width 0.04445)
			(type default)
		)
		(layer "In4.Cu")
	)
	(gr_line
		(start 370.717318 -112.856772)
		(end 370.732812 -112.841278)
		(stroke
			(width 0.04445)
			(type default)
		)
		(layer "In4.Cu")
	)
	(gr_line
		(start 370.719096 -107.123738)
		(end 370.799868 -107.170982)
		(stroke
			(width 0.05715)
			(type default)
		)
		(layer "In4.Cu")
	)
	(gr_line
		(start 370.736622 -135.635746)
		(end 370.783358 -135.617204)
		(stroke
			(width 0.05715)
			(type default)
		)
		(layer "In4.Cu")
	)
	(gr_line
		(start 370.783358 -135.617204)
		(end 370.83238 -135.627364)
		(stroke
			(width 0.05715)
			(type default)
		)
		(layer "In4.Cu")
	)
	(gr_line
		(start 370.783612 -30.339792)
		(end 370.84762 -30.295342)
		(stroke
			(width 0.05715)
			(type default)
		)
		(layer "In4.Cu")
	)
	(gr_line
		(start 370.80063 -136.311132)
		(end 370.847366 -136.29259)
		(stroke
			(width 0.05715)
			(type default)
		)
		(layer "In4.Cu")
	)
	(gr_line
		(start 370.805964 -133.90753)
		(end 370.846096 -133.920992)
		(stroke
			(width 0.05715)
			(type default)
		)
		(layer "In4.Cu")
	)
	(gr_line
		(start 370.846096 -133.920992)
		(end 370.887752 -133.912102)
		(stroke
			(width 0.05715)
			(type default)
		)
		(layer "In4.Cu")
	)
	(gr_line
		(start 370.847366 -136.29259)
		(end 370.895372 -136.30275)
		(stroke
			(width 0.05715)
			(type default)
		)
		(layer "In4.Cu")
	)
	(gr_line
		(start 370.84762 -30.295342)
		(end 370.864638 -30.217872)
		(stroke
			(width 0.05715)
			(type default)
		)
		(layer "In4.Cu")
	)
	(gr_line
		(start 370.852192 -113.063528)
		(end 370.907818 -113.063528)
		(stroke
			(width 0.04445)
			(type default)
		)
		(layer "In4.Cu")
	)
	(gr_line
		(start 370.900198 -2.937002)
		(end 371.274848 -2.937002)
		(stroke
			(width 0.05715)
			(type default)
		)
		(layer "In4.Cu")
	)
	(gr_line
		(start 370.910358 -113.063528)
		(end 370.92382 -113.063528)
		(stroke
			(width 0.04445)
			(type default)
		)
		(layer "In4.Cu")
	)
	(gr_line
		(start 370.923312 -4.336034)
		(end 371.015006 -4.547108)
		(stroke
			(width 0.05715)
			(type default)
		)
		(layer "In4.Cu")
	)
	(gr_line
		(start 370.923312 -4.336034)
		(end 371.049042 -4.01701)
		(stroke
			(width 0.05715)
			(type default)
		)
		(layer "In4.Cu")
	)
	(gr_line
		(start 370.92382 -113.063528)
		(end 370.939314 -113.048034)
		(stroke
			(width 0.04445)
			(type default)
		)
		(layer "In4.Cu")
	)
	(gr_line
		(start 370.929154 -5.56768)
		(end 371.147848 -5.012436)
		(stroke
			(width 0.05715)
			(type default)
		)
		(layer "In4.Cu")
	)
	(gr_line
		(start 370.954554 -25.387808)
		(end 370.975128 -25.29459)
		(stroke
			(width 0.05715)
			(type default)
		)
		(layer "In4.Cu")
	)
	(gr_line
		(start 370.975128 -25.29459)
		(end 371.059456 -25.249124)
		(stroke
			(width 0.05715)
			(type default)
		)
		(layer "In4.Cu")
	)
	(gr_line
		(start 371.00002 -131.903216)
		(end 371.027452 -131.909312)
		(stroke
			(width 0.05715)
			(type default)
		)
		(layer "In4.Cu")
	)
	(gr_line
		(start 371.000528 -132.566918)
		(end 371.02796 -132.573014)
		(stroke
			(width 0.05715)
			(type default)
		)
		(layer "In4.Cu")
	)
	(gr_line
		(start 371.027452 -131.909312)
		(end 371.055138 -131.903216)
		(stroke
			(width 0.05715)
			(type default)
		)
		(layer "In4.Cu")
	)
	(gr_line
		(start 371.02796 -132.573014)
		(end 371.055392 -132.566918)
		(stroke
			(width 0.05715)
			(type default)
		)
		(layer "In4.Cu")
	)
	(gr_line
		(start 371.049042 -4.01701)
		(end 371.260116 -3.92557)
		(stroke
			(width 0.05715)
			(type default)
		)
		(layer "In4.Cu")
	)
	(gr_line
		(start 371.060218 -111.45393)
		(end 371.07495 -111.474504)
		(stroke
			(width 0.05715)
			(type default)
		)
		(layer "In4.Cu")
	)
	(gr_line
		(start 371.07495 -111.474504)
		(end 371.08003 -111.499396)
		(stroke
			(width 0.05715)
			(type default)
		)
		(layer "In4.Cu")
	)
	(gr_line
		(start 371.093746 -21.721318)
		(end 371.158516 -21.678138)
		(stroke
			(width 0.05715)
			(type default)
		)
		(layer "In4.Cu")
	)
	(gr_line
		(start 371.155976 -105.156)
		(end 371.16893 -105.195116)
		(stroke
			(width 0.05715)
			(type default)
		)
		(layer "In4.Cu")
	)
	(gr_line
		(start 371.158516 -21.678138)
		(end 371.176042 -21.602446)
		(stroke
			(width 0.05715)
			(type default)
		)
		(layer "In4.Cu")
	)
	(gr_line
		(start 371.16893 -105.195116)
		(end 371.20068 -105.222548)
		(stroke
			(width 0.05715)
			(type default)
		)
		(layer "In4.Cu")
	)
	(gr_line
		(start 371.2464 -114.299238)
		(end 371.36832 -114.177318)
		(stroke
			(width 0.05715)
			(type default)
		)
		(layer "In4.Cu")
	)
	(gr_line
		(start 371.274848 -2.937002)
		(end 371.326918 -2.989072)
		(stroke
			(width 0.05715)
			(type default)
		)
		(layer "In4.Cu")
	)
	(gr_line
		(start 371.287802 -23.954486)
		(end 371.37086 -23.90902)
		(stroke
			(width 0.05715)
			(type default)
		)
		(layer "In4.Cu")
	)
	(gr_line
		(start 371.2972 -118.575836)
		(end 371.425216 -118.703852)
		(stroke
			(width 0.05715)
			(type default)
		)
		(layer "In4.Cu")
	)
	(gr_line
		(start 371.2972 -118.237)
		(end 371.2972 -118.575836)
		(stroke
			(width 0.05715)
			(type default)
		)
		(layer "In4.Cu")
	)
	(gr_line
		(start 371.2972 -116.490496)
		(end 371.2972 -116.7892)
		(stroke
			(width 0.04445)
			(type default)
		)
		(layer "In4.Cu")
	)
	(gr_line
		(start 371.2972 -116.490496)
		(end 371.470428 -116.317268)
		(stroke
			(width 0.04445)
			(type default)
		)
		(layer "In4.Cu")
	)
	(gr_line
		(start 371.2972 -115.3414)
		(end 371.491002 -115.147598)
		(stroke
			(width 0.04445)
			(type default)
		)
		(layer "In4.Cu")
	)
	(gr_line
		(start 371.30228 -4.62153)
		(end 371.52072 -4.067302)
		(stroke
			(width 0.05715)
			(type default)
		)
		(layer "In4.Cu")
	)
	(gr_line
		(start 371.36705 -30.801818)
		(end 371.432328 -30.756606)
		(stroke
			(width 0.05715)
			(type default)
		)
		(layer "In4.Cu")
	)
	(gr_line
		(start 371.37086 -23.90902)
		(end 371.392196 -23.81758)
		(stroke
			(width 0.05715)
			(type default)
		)
		(layer "In4.Cu")
	)
	(gr_line
		(start 371.422422 -10.324846)
		(end 371.458998 -10.297668)
		(stroke
			(width 0.05715)
			(type default)
		)
		(layer "In4.Cu")
	)
	(gr_line
		(start 371.432328 -30.756606)
		(end 371.448584 -30.679898)
		(stroke
			(width 0.05715)
			(type default)
		)
		(layer "In4.Cu")
	)
	(gr_line
		(start 371.458998 -10.297668)
		(end 371.475508 -10.254996)
		(stroke
			(width 0.05715)
			(type default)
		)
		(layer "In4.Cu")
	)
	(gr_line
		(start 371.472206 -116.31549)
		(end 371.511576 -116.27612)
		(stroke
			(width 0.04445)
			(type default)
		)
		(layer "In4.Cu")
	)
	(gr_line
		(start 371.49278 -115.14582)
		(end 371.5131 -115.1255)
		(stroke
			(width 0.04445)
			(type default)
		)
		(layer "In4.Cu")
	)
	(gr_line
		(start 371.495828 -116.213128)
		(end 371.511576 -116.228876)
		(stroke
			(width 0.04445)
			(type default)
		)
		(layer "In4.Cu")
	)
	(gr_line
		(start 371.50167 -115.02009)
		(end 371.5131 -115.03152)
		(stroke
			(width 0.04445)
			(type default)
		)
		(layer "In4.Cu")
	)
	(gr_line
		(start 371.528594 -25.826466)
		(end 371.549422 -25.731724)
		(stroke
			(width 0.05715)
			(type default)
		)
		(layer "In4.Cu")
	)
	(gr_line
		(start 371.549422 -25.731724)
		(end 371.634766 -25.685242)
		(stroke
			(width 0.05715)
			(type default)
		)
		(layer "In4.Cu")
	)
	(gr_line
		(start 371.558058 -6.596126)
		(end 371.558058 -6.826504)
		(stroke
			(width 0.05715)
			(type default)
		)
		(layer "In4.Cu")
	)
	(gr_line
		(start 371.558058 -6.596126)
		(end 371.800628 -6.353556)
		(stroke
			(width 0.05715)
			(type default)
		)
		(layer "In4.Cu")
	)
	(gr_line
		(start 371.675152 -3.676396)
		(end 371.681248 -3.660648)
		(stroke
			(width 0.05715)
			(type default)
		)
		(layer "In4.Cu")
	)
	(gr_line
		(start 371.702076 -116.27612)
		(end 371.741446 -116.31549)
		(stroke
			(width 0.04445)
			(type default)
		)
		(layer "In4.Cu")
	)
	(gr_line
		(start 371.7036 -115.0874)
		(end 371.76202 -115.14582)
		(stroke
			(width 0.04445)
			(type default)
		)
		(layer "In4.Cu")
	)
	(gr_line
		(start 371.705632 -107.699048)
		(end 371.710966 -107.702096)
		(stroke
			(width 0.05715)
			(type default)
		)
		(layer "In4.Cu")
	)
	(gr_line
		(start 371.710966 -107.702096)
		(end 371.717316 -107.70362)
		(stroke
			(width 0.05715)
			(type default)
		)
		(layer "In4.Cu")
	)
	(gr_line
		(start 371.743224 -116.317268)
		(end 371.9576 -116.531644)
		(stroke
			(width 0.04445)
			(type default)
		)
		(layer "In4.Cu")
	)
	(gr_line
		(start 371.743478 -2.989072)
		(end 371.795548 -2.937002)
		(stroke
			(width 0.05715)
			(type default)
		)
		(layer "In4.Cu")
	)
	(gr_line
		(start 371.763798 -115.147598)
		(end 371.9576 -115.3414)
		(stroke
			(width 0.04445)
			(type default)
		)
		(layer "In4.Cu")
	)
	(gr_line
		(start 371.78488 -114.177318)
		(end 371.9068 -114.299238)
		(stroke
			(width 0.05715)
			(type default)
		)
		(layer "In4.Cu")
	)
	(gr_line
		(start 371.795548 -2.937002)
		(end 372.170198 -2.937002)
		(stroke
			(width 0.05715)
			(type default)
		)
		(layer "In4.Cu")
	)
	(gr_line
		(start 371.800628 -6.353556)
		(end 372.031006 -6.353556)
		(stroke
			(width 0.05715)
			(type default)
		)
		(layer "In4.Cu")
	)
	(gr_line
		(start 371.841776 -118.703852)
		(end 371.9576 -118.588028)
		(stroke
			(width 0.05715)
			(type default)
		)
		(layer "In4.Cu")
	)
	(gr_line
		(start 371.87378 -24.402542)
		(end 371.958108 -24.357838)
		(stroke
			(width 0.05715)
			(type default)
		)
		(layer "In4.Cu")
	)
	(gr_line
		(start 371.941344 -133.3881)
		(end 371.972586 -133.381496)
		(stroke
			(width 0.05715)
			(type default)
		)
		(layer "In4.Cu")
	)
	(gr_line
		(start 371.9576 -118.237)
		(end 371.9576 -118.588028)
		(stroke
			(width 0.05715)
			(type default)
		)
		(layer "In4.Cu")
	)
	(gr_line
		(start 371.9576 -116.531644)
		(end 371.9576 -116.7892)
		(stroke
			(width 0.04445)
			(type default)
		)
		(layer "In4.Cu")
	)
	(gr_line
		(start 371.958108 -24.357838)
		(end 371.979952 -24.264366)
		(stroke
			(width 0.05715)
			(type default)
		)
		(layer "In4.Cu")
	)
	(gr_line
		(start 371.968014 -31.180278)
		(end 372.0338 -31.135066)
		(stroke
			(width 0.05715)
			(type default)
		)
		(layer "In4.Cu")
	)
	(gr_line
		(start 371.972586 -133.381496)
		(end 372.003828 -133.38937)
		(stroke
			(width 0.05715)
			(type default)
		)
		(layer "In4.Cu")
	)
	(gr_line
		(start 371.973094 -6.828028)
		(end 372.215156 -6.585966)
		(stroke
			(width 0.05715)
			(type default)
		)
		(layer "In4.Cu")
	)
	(gr_line
		(start 372.0338 -31.135066)
		(end 372.050056 -31.05658)
		(stroke
			(width 0.05715)
			(type default)
		)
		(layer "In4.Cu")
	)
	(gr_line
		(start 372.07317 -26.318972)
		(end 372.093236 -26.22423)
		(stroke
			(width 0.05715)
			(type default)
		)
		(layer "In4.Cu")
	)
	(gr_line
		(start 372.073932 -107.790996)
		(end 372.194582 -107.987338)
		(stroke
			(width 0.05715)
			(type default)
		)
		(layer "In4.Cu")
	)
	(gr_line
		(start 372.093236 -26.22423)
		(end 372.17858 -26.177494)
		(stroke
			(width 0.05715)
			(type default)
		)
		(layer "In4.Cu")
	)
	(gr_line
		(start 372.138702 -7.735062)
		(end 372.147338 -7.712964)
		(stroke
			(width 0.05715)
			(type default)
		)
		(layer "In4.Cu")
	)
	(gr_line
		(start 372.176294 -107.512612)
		(end 372.7577 -107.65155)
		(stroke
			(width 0.05715)
			(type default)
		)
		(layer "In4.Cu")
	)
	(gr_line
		(start 372.194582 -107.987338)
		(end 372.528084 -108.06684)
		(stroke
			(width 0.05715)
			(type default)
		)
		(layer "In4.Cu")
	)
	(gr_line
		(start 372.199662 -106.08437)
		(end 372.210584 -106.093768)
		(stroke
			(width 0.05715)
			(type default)
		)
		(layer "In4.Cu")
	)
	(gr_line
		(start 372.210584 -106.093768)
		(end 372.224046 -106.098848)
		(stroke
			(width 0.05715)
			(type default)
		)
		(layer "In4.Cu")
	)
	(gr_line
		(start 372.214648 -132.00888)
		(end 372.259098 -131.998974)
		(stroke
			(width 0.05715)
			(type default)
		)
		(layer "In4.Cu")
	)
	(gr_line
		(start 372.238524 -126.849378)
		(end 372.279164 -126.834138)
		(stroke
			(width 0.05715)
			(type default)
		)
		(layer "In4.Cu")
	)
	(gr_line
		(start 372.239794 -10.5537)
		(end 372.277386 -10.52576)
		(stroke
			(width 0.05715)
			(type default)
		)
		(layer "In4.Cu")
	)
	(gr_line
		(start 372.251986 -131.33705)
		(end 372.29669 -131.327144)
		(stroke
			(width 0.05715)
			(type default)
		)
		(layer "In4.Cu")
	)
	(gr_line
		(start 372.259098 -131.998974)
		(end 372.301262 -132.013706)
		(stroke
			(width 0.05715)
			(type default)
		)
		(layer "In4.Cu")
	)
	(gr_line
		(start 372.276624 -5.87756)
		(end 372.276624 -6.107938)
		(stroke
			(width 0.05715)
			(type default)
		)
		(layer "In4.Cu")
	)
	(gr_line
		(start 372.276624 -5.87756)
		(end 372.519194 -5.635244)
		(stroke
			(width 0.05715)
			(type default)
		)
		(layer "In4.Cu")
	)
	(gr_line
		(start 372.277386 -10.52576)
		(end 372.294658 -10.48258)
		(stroke
			(width 0.05715)
			(type default)
		)
		(layer "In4.Cu")
	)
	(gr_line
		(start 372.279164 -126.834138)
		(end 372.322344 -126.842266)
		(stroke
			(width 0.05715)
			(type default)
		)
		(layer "In4.Cu")
	)
	(gr_line
		(start 372.296436 -127.51943)
		(end 372.337076 -127.50419)
		(stroke
			(width 0.05715)
			(type default)
		)
		(layer "In4.Cu")
	)
	(gr_line
		(start 372.29669 -131.327144)
		(end 372.338854 -131.341876)
		(stroke
			(width 0.05715)
			(type default)
		)
		(layer "In4.Cu")
	)
	(gr_line
		(start 372.337076 -127.50419)
		(end 372.380256 -127.512318)
		(stroke
			(width 0.05715)
			(type default)
		)
		(layer "In4.Cu")
	)
	(gr_line
		(start 372.467632 -24.82215)
		(end 372.551452 -24.776938)
		(stroke
			(width 0.05715)
			(type default)
		)
		(layer "In4.Cu")
	)
	(gr_line
		(start 372.482618 -14.710664)
		(end 372.489476 -14.681708)
		(stroke
			(width 0.05715)
			(type default)
		)
		(layer "In4.Cu")
	)
	(gr_line
		(start 372.489476 -14.681708)
		(end 372.508272 -14.658848)
		(stroke
			(width 0.05715)
			(type default)
		)
		(layer "In4.Cu")
	)
	(gr_line
		(start 372.509796 -6.291326)
		(end 372.932706 -5.868416)
		(stroke
			(width 0.05715)
			(type default)
		)
		(layer "In4.Cu")
	)
	(gr_line
		(start 372.519194 -5.635244)
		(end 372.749318 -5.635244)
		(stroke
			(width 0.05715)
			(type default)
		)
		(layer "In4.Cu")
	)
	(gr_line
		(start 372.528084 -108.06684)
		(end 372.724426 -107.946444)
		(stroke
			(width 0.05715)
			(type default)
		)
		(layer "In4.Cu")
	)
	(gr_line
		(start 372.551452 -24.776938)
		(end 372.573042 -24.684482)
		(stroke
			(width 0.05715)
			(type default)
		)
		(layer "In4.Cu")
	)
	(gr_line
		(start 372.617492 -133.546088)
		(end 372.641876 -133.552438)
		(stroke
			(width 0.05715)
			(type default)
		)
		(layer "In4.Cu")
	)
	(gr_line
		(start 372.641876 -133.552438)
		(end 372.660926 -133.56717)
		(stroke
			(width 0.05715)
			(type default)
		)
		(layer "In4.Cu")
	)
	(gr_line
		(start 372.645432 -26.741882)
		(end 372.665244 -26.646632)
		(stroke
			(width 0.05715)
			(type default)
		)
		(layer "In4.Cu")
	)
	(gr_line
		(start 372.665244 -26.646632)
		(end 372.750334 -26.599896)
		(stroke
			(width 0.05715)
			(type default)
		)
		(layer "In4.Cu")
	)
	(gr_line
		(start 372.765066 -136.694672)
		(end 372.772178 -136.696196)
		(stroke
			(width 0.05715)
			(type default)
		)
		(layer "In4.Cu")
	)
	(gr_line
		(start 372.771162 -8.501126)
		(end 372.779544 -8.47979)
		(stroke
			(width 0.05715)
			(type default)
		)
		(layer "In4.Cu")
	)
	(gr_line
		(start 372.772178 -136.696196)
		(end 372.779036 -136.700006)
		(stroke
			(width 0.05715)
			(type default)
		)
		(layer "In4.Cu")
	)
	(gr_line
		(start 372.779544 -8.47979)
		(end 372.796308 -8.463026)
		(stroke
			(width 0.05715)
			(type default)
		)
		(layer "In4.Cu")
	)
	(gr_line
		(start 372.79199 -106.309922)
		(end 372.833646 -106.325416)
		(stroke
			(width 0.05715)
			(type default)
		)
		(layer "In4.Cu")
	)
	(gr_line
		(start 372.833646 -106.325416)
		(end 372.877334 -106.317034)
		(stroke
			(width 0.05715)
			(type default)
		)
		(layer "In4.Cu")
	)
	(gr_line
		(start 372.994936 -5.389372)
		(end 372.99519 -5.159248)
		(stroke
			(width 0.05715)
			(type default)
		)
		(layer "In4.Cu")
	)
	(gr_line
		(start 372.99519 -5.159248)
		(end 373.237506 -4.916932)
		(stroke
			(width 0.05715)
			(type default)
		)
		(layer "In4.Cu")
	)
	(gr_line
		(start 372.997222 -136.08177)
		(end 373.004334 -136.083294)
		(stroke
			(width 0.05715)
			(type default)
		)
		(layer "In4.Cu")
	)
	(gr_line
		(start 373.004334 -136.083294)
		(end 373.011192 -136.087104)
		(stroke
			(width 0.05715)
			(type default)
		)
		(layer "In4.Cu")
	)
	(gr_line
		(start 373.063008 -25.241504)
		(end 373.144796 -25.197054)
		(stroke
			(width 0.05715)
			(type default)
		)
		(layer "In4.Cu")
	)
	(gr_line
		(start 373.074946 -108.030264)
		(end 373.202962 -108.238544)
		(stroke
			(width 0.05715)
			(type default)
		)
		(layer "In4.Cu")
	)
	(gr_line
		(start 373.095012 -111.327438)
		(end 373.171466 -111.544354)
		(stroke
			(width 0.05715)
			(type default)
		)
		(layer "In4.Cu")
	)
	(gr_line
		(start 373.095012 -111.327438)
		(end 373.243094 -111.018066)
		(stroke
			(width 0.05715)
			(type default)
		)
		(layer "In4.Cu")
	)
	(gr_line
		(start 373.10568 -112.36452)
		(end 373.111014 -112.353344)
		(stroke
			(width 0.05715)
			(type default)
		)
		(layer "In4.Cu")
	)
	(gr_line
		(start 373.123714 -15.102332)
		(end 373.13108 -15.070836)
		(stroke
			(width 0.05715)
			(type default)
		)
		(layer "In4.Cu")
	)
	(gr_line
		(start 373.13108 -15.070836)
		(end 373.151654 -15.04569)
		(stroke
			(width 0.05715)
			(type default)
		)
		(layer "In4.Cu")
	)
	(gr_line
		(start 373.144796 -25.197054)
		(end 373.165878 -25.106884)
		(stroke
			(width 0.05715)
			(type default)
		)
		(layer "In4.Cu")
	)
	(gr_line
		(start 373.178578 -107.752134)
		(end 373.790464 -107.898184)
		(stroke
			(width 0.05715)
			(type default)
		)
		(layer "In4.Cu")
	)
	(gr_line
		(start 373.202962 -108.238544)
		(end 373.548656 -108.321094)
		(stroke
			(width 0.05715)
			(type default)
		)
		(layer "In4.Cu")
	)
	(gr_line
		(start 373.224552 -1.419606)
		(end 373.599202 -1.419606)
		(stroke
			(width 0.05715)
			(type default)
		)
		(layer "In4.Cu")
	)
	(gr_line
		(start 373.227346 -5.573776)
		(end 373.469154 -5.331968)
		(stroke
			(width 0.05715)
			(type default)
		)
		(layer "In4.Cu")
	)
	(gr_line
		(start 373.2276 -114.299238)
		(end 373.34952 -114.177318)
		(stroke
			(width 0.05715)
			(type default)
		)
		(layer "In4.Cu")
	)
	(gr_line
		(start 373.237506 -4.916932)
		(end 373.46763 -4.916932)
		(stroke
			(width 0.05715)
			(type default)
		)
		(layer "In4.Cu")
	)
	(gr_line
		(start 373.243094 -111.018066)
		(end 373.46001 -110.941866)
		(stroke
			(width 0.05715)
			(type default)
		)
		(layer "In4.Cu")
	)
	(gr_line
		(start 373.315484 -6.311138)
		(end 373.315484 -6.541516)
		(stroke
			(width 0.05715)
			(type default)
		)
		(layer "In4.Cu")
	)
	(gr_line
		(start 373.315484 -6.311138)
		(end 373.558054 -6.068822)
		(stroke
			(width 0.05715)
			(type default)
		)
		(layer "In4.Cu")
	)
	(gr_line
		(start 373.41175 -113.232692)
		(end 373.470678 -113.173764)
		(stroke
			(width 0.05715)
			(type default)
		)
		(layer "In4.Cu")
	)
	(gr_line
		(start 373.452644 -111.639858)
		(end 373.710454 -111.101124)
		(stroke
			(width 0.05715)
			(type default)
		)
		(layer "In4.Cu")
	)
	(gr_line
		(start 373.51081 -105.896156)
		(end 373.54637 -105.889298)
		(stroke
			(width 0.05715)
			(type default)
		)
		(layer "In4.Cu")
	)
	(gr_line
		(start 373.54637 -105.889298)
		(end 373.581168 -105.90022)
		(stroke
			(width 0.05715)
			(type default)
		)
		(layer "In4.Cu")
	)
	(gr_line
		(start 373.548656 -108.321094)
		(end 373.756936 -108.193078)
		(stroke
			(width 0.05715)
			(type default)
		)
		(layer "In4.Cu")
	)
	(gr_line
		(start 373.558054 -6.068822)
		(end 373.788178 -6.068822)
		(stroke
			(width 0.05715)
			(type default)
		)
		(layer "In4.Cu")
	)
	(gr_line
		(start 373.586248 -110.683802)
		(end 373.611394 -110.631224)
		(stroke
			(width 0.05715)
			(type default)
		)
		(layer "In4.Cu")
	)
	(gr_line
		(start 373.599202 -1.419606)
		(end 373.647716 -1.46812)
		(stroke
			(width 0.05715)
			(type default)
		)
		(layer "In4.Cu")
	)
	(gr_line
		(start 373.611394 -110.631224)
		(end 373.662194 -110.604554)
		(stroke
			(width 0.05715)
			(type default)
		)
		(layer "In4.Cu")
	)
	(gr_line
		(start 373.611394 -110.631224)
		(end 373.662956 -110.604046)
		(stroke
			(width 0.05715)
			(type default)
		)
		(layer "In4.Cu")
	)
	(gr_line
		(start 373.644414 -25.709118)
		(end 373.726964 -25.66416)
		(stroke
			(width 0.05715)
			(type default)
		)
		(layer "In4.Cu")
	)
	(gr_line
		(start 373.726964 -25.66416)
		(end 373.748046 -25.573228)
		(stroke
			(width 0.05715)
			(type default)
		)
		(layer "In4.Cu")
	)
	(gr_line
		(start 373.73052 -6.54304)
		(end 373.789702 -6.483858)
		(stroke
			(width 0.05715)
			(type default)
		)
		(layer "In4.Cu")
	)
	(gr_line
		(start 373.743982 -15.407894)
		(end 373.751348 -15.376398)
		(stroke
			(width 0.05715)
			(type default)
		)
		(layer "In4.Cu")
	)
	(gr_line
		(start 373.751348 -15.376398)
		(end 373.771922 -15.351252)
		(stroke
			(width 0.05715)
			(type default)
		)
		(layer "In4.Cu")
	)
	(gr_line
		(start 373.76608 -114.177318)
		(end 373.888 -114.299238)
		(stroke
			(width 0.05715)
			(type default)
		)
		(layer "In4.Cu")
	)
	(gr_line
		(start 373.866918 -134.499604)
		(end 373.877586 -134.507986)
		(stroke
			(width 0.05715)
			(type default)
		)
		(layer "In4.Cu")
	)
	(gr_line
		(start 373.877586 -134.507986)
		(end 373.884698 -134.518908)
		(stroke
			(width 0.05715)
			(type default)
		)
		(layer "In4.Cu")
	)
	(gr_line
		(start 374.03405 -5.592826)
		(end 374.03405 -5.82295)
		(stroke
			(width 0.05715)
			(type default)
		)
		(layer "In4.Cu")
	)
	(gr_line
		(start 374.03405 -5.592826)
		(end 374.276366 -5.350256)
		(stroke
			(width 0.05715)
			(type default)
		)
		(layer "In4.Cu")
	)
	(gr_line
		(start 374.06453 -1.46812)
		(end 374.113044 -1.419606)
		(stroke
			(width 0.05715)
			(type default)
		)
		(layer "In4.Cu")
	)
	(gr_line
		(start 374.113044 -1.419606)
		(end 374.494552 -1.419606)
		(stroke
			(width 0.05715)
			(type default)
		)
		(layer "In4.Cu")
	)
	(gr_line
		(start 374.212866 -7.278878)
		(end 374.212866 -7.509002)
		(stroke
			(width 0.05715)
			(type default)
		)
		(layer "In4.Cu")
	)
	(gr_line
		(start 374.212866 -7.278878)
		(end 374.455182 -7.036562)
		(stroke
			(width 0.05715)
			(type default)
		)
		(layer "In4.Cu")
	)
	(gr_line
		(start 374.21566 -26.127456)
		(end 374.296432 -26.08326)
		(stroke
			(width 0.05715)
			(type default)
		)
		(layer "In4.Cu")
	)
	(gr_line
		(start 374.239282 -10.299192)
		(end 374.242838 -10.296398)
		(stroke
			(width 0.05715)
			(type default)
		)
		(layer "In4.Cu")
	)
	(gr_line
		(start 374.242838 -10.296398)
		(end 374.245886 -10.292334)
		(stroke
			(width 0.05715)
			(type default)
		)
		(layer "In4.Cu")
	)
	(gr_line
		(start 374.276366 -5.350256)
		(end 374.506744 -5.350256)
		(stroke
			(width 0.05715)
			(type default)
		)
		(layer "In4.Cu")
	)
	(gr_line
		(start 374.296432 -26.08326)
		(end 374.317514 -25.992836)
		(stroke
			(width 0.05715)
			(type default)
		)
		(layer "In4.Cu")
	)
	(gr_line
		(start 374.334024 -108.027978)
		(end 374.391174 -108.041694)
		(stroke
			(width 0.05715)
			(type default)
		)
		(layer "In4.Cu")
	)
	(gr_line
		(start 374.364758 -15.711932)
		(end 374.371362 -15.683484)
		(stroke
			(width 0.05715)
			(type default)
		)
		(layer "In4.Cu")
	)
	(gr_line
		(start 374.371362 -15.683484)
		(end 374.390158 -15.660878)
		(stroke
			(width 0.05715)
			(type default)
		)
		(layer "In4.Cu")
	)
	(gr_line
		(start 374.391174 -108.041694)
		(end 374.428766 -108.086906)
		(stroke
			(width 0.05715)
			(type default)
		)
		(layer "In4.Cu")
	)
	(gr_line
		(start 374.41378 -132.363718)
		(end 374.458484 -132.378958)
		(stroke
			(width 0.05715)
			(type default)
		)
		(layer "In4.Cu")
	)
	(gr_line
		(start 374.4214 -130.643884)
		(end 374.451372 -130.648964)
		(stroke
			(width 0.05715)
			(type default)
		)
		(layer "In4.Cu")
	)
	(gr_line
		(start 374.43918 -109.359446)
		(end 374.451118 -109.407452)
		(stroke
			(width 0.05715)
			(type default)
		)
		(layer "In4.Cu")
	)
	(gr_line
		(start 374.43918 -109.359446)
		(end 374.451118 -109.406944)
		(stroke
			(width 0.05715)
			(type default)
		)
		(layer "In4.Cu")
	)
	(gr_line
		(start 374.43918 -109.359446)
		(end 374.455436 -109.312964)
		(stroke
			(width 0.05715)
			(type default)
		)
		(layer "In4.Cu")
	)
	(gr_line
		(start 374.43918 -109.359446)
		(end 374.455436 -109.312456)
		(stroke
			(width 0.05715)
			(type default)
		)
		(layer "In4.Cu")
	)
	(gr_line
		(start 374.449086 -5.824474)
		(end 374.508268 -5.765292)
		(stroke
			(width 0.05715)
			(type default)
		)
		(layer "In4.Cu")
	)
	(gr_line
		(start 374.451372 -130.648964)
		(end 374.480328 -130.640328)
		(stroke
			(width 0.05715)
			(type default)
		)
		(layer "In4.Cu")
	)
	(gr_line
		(start 374.455182 -7.036562)
		(end 374.685306 -7.036562)
		(stroke
			(width 0.05715)
			(type default)
		)
		(layer "In4.Cu")
	)
	(gr_line
		(start 374.458484 -132.378958)
		(end 374.504712 -132.36829)
		(stroke
			(width 0.05715)
			(type default)
		)
		(layer "In4.Cu")
	)
	(gr_line
		(start 374.544844 -136.064752)
		(end 374.555766 -136.081516)
		(stroke
			(width 0.05715)
			(type default)
		)
		(layer "In4.Cu")
	)
	(gr_line
		(start 374.555766 -136.081516)
		(end 374.573038 -136.093454)
		(stroke
			(width 0.05715)
			(type default)
		)
		(layer "In4.Cu")
	)
	(gr_line
		(start 374.567958 -106.212132)
		(end 374.654572 -106.239564)
		(stroke
			(width 0.05715)
			(type default)
		)
		(layer "In4.Cu")
	)
	(gr_line
		(start 374.584976 -110.44809)
		(end 374.654572 -110.411514)
		(stroke
			(width 0.05715)
			(type default)
		)
		(layer "In4.Cu")
	)
	(gr_line
		(start 374.627902 -7.510526)
		(end 374.68683 -7.451598)
		(stroke
			(width 0.05715)
			(type default)
		)
		(layer "In4.Cu")
	)
	(gr_line
		(start 374.654572 -110.411514)
		(end 374.67921 -110.33633)
		(stroke
			(width 0.05715)
			(type default)
		)
		(layer "In4.Cu")
	)
	(gr_line
		(start 374.654572 -106.239564)
		(end 374.69318 -106.321098)
		(stroke
			(width 0.05715)
			(type default)
		)
		(layer "In4.Cu")
	)
	(gr_line
		(start 374.741948 -108.462318)
		(end 374.76557 -108.490766)
		(stroke
			(width 0.05715)
			(type default)
		)
		(layer "In4.Cu")
	)
	(gr_line
		(start 374.752362 -4.874514)
		(end 374.752362 -5.104638)
		(stroke
			(width 0.05715)
			(type default)
		)
		(layer "In4.Cu")
	)
	(gr_line
		(start 374.752362 -4.874514)
		(end 374.994932 -4.631944)
		(stroke
			(width 0.05715)
			(type default)
		)
		(layer "In4.Cu")
	)
	(gr_line
		(start 374.76557 -108.490766)
		(end 374.772936 -108.526834)
		(stroke
			(width 0.05715)
			(type default)
		)
		(layer "In4.Cu")
	)
	(gr_line
		(start 374.785382 -138.176254)
		(end 374.786398 -138.177016)
		(stroke
			(width 0.05715)
			(type default)
		)
		(layer "In4.Cu")
	)
	(gr_line
		(start 374.786398 -138.177016)
		(end 374.787414 -138.17727)
		(stroke
			(width 0.05715)
			(type default)
		)
		(layer "In4.Cu")
	)
	(gr_line
		(start 374.837706 -109.856524)
		(end 374.852184 -109.812836)
		(stroke
			(width 0.05715)
			(type default)
		)
		(layer "In4.Cu")
	)
	(gr_line
		(start 374.841262 -109.768386)
		(end 374.852184 -109.812836)
		(stroke
			(width 0.05715)
			(type default)
		)
		(layer "In4.Cu")
	)
	(gr_line
		(start 374.856502 -109.049058)
		(end 374.870472 -109.008418)
		(stroke
			(width 0.05715)
			(type default)
		)
		(layer "In4.Cu")
	)
	(gr_line
		(start 374.86209 -108.967016)
		(end 374.870472 -109.008418)
		(stroke
			(width 0.05715)
			(type default)
		)
		(layer "In4.Cu")
	)
	(gr_line
		(start 374.876568 -112.181132)
		(end 374.88495 -112.17275)
		(stroke
			(width 0.05715)
			(type default)
		)
		(layer "In4.Cu")
	)
	(gr_line
		(start 374.88495 -112.17275)
		(end 374.890284 -112.162082)
		(stroke
			(width 0.05715)
			(type default)
		)
		(layer "In4.Cu")
	)
	(gr_line
		(start 374.931178 -6.560566)
		(end 374.931178 -6.79069)
		(stroke
			(width 0.05715)
			(type default)
		)
		(layer "In4.Cu")
	)
	(gr_line
		(start 374.931178 -6.560566)
		(end 375.173748 -6.317996)
		(stroke
			(width 0.05715)
			(type default)
		)
		(layer "In4.Cu")
	)
	(gr_line
		(start 374.963944 -110.607602)
		(end 374.977914 -110.656878)
		(stroke
			(width 0.05715)
			(type default)
		)
		(layer "In4.Cu")
	)
	(gr_line
		(start 374.963944 -110.607602)
		(end 374.978168 -110.658656)
		(stroke
			(width 0.05715)
			(type default)
		)
		(layer "In4.Cu")
	)
	(gr_line
		(start 374.963944 -110.607602)
		(end 374.9802 -110.558326)
		(stroke
			(width 0.05715)
			(type default)
		)
		(layer "In4.Cu")
	)
	(gr_line
		(start 374.963944 -110.607602)
		(end 374.9802 -110.558072)
		(stroke
			(width 0.05715)
			(type default)
		)
		(layer "In4.Cu")
	)
	(gr_line
		(start 374.9802 -110.558072)
		(end 374.980454 -110.55731)
		(stroke
			(width 0.05715)
			(type default)
		)
		(layer "In4.Cu")
	)
	(gr_line
		(start 374.984772 -16.019018)
		(end 374.992138 -15.987522)
		(stroke
			(width 0.05715)
			(type default)
		)
		(layer "In4.Cu")
	)
	(gr_line
		(start 374.992138 -15.987522)
		(end 375.012712 -15.962376)
		(stroke
			(width 0.05715)
			(type default)
		)
		(layer "In4.Cu")
	)
	(gr_line
		(start 374.994932 -4.631944)
		(end 375.225056 -4.631944)
		(stroke
			(width 0.05715)
			(type default)
		)
		(layer "In4.Cu")
	)
	(gr_line
		(start 375.010934 -136.394952)
		(end 375.02211 -136.402826)
		(stroke
			(width 0.05715)
			(type default)
		)
		(layer "In4.Cu")
	)
	(gr_line
		(start 375.02211 -136.402826)
		(end 375.035572 -136.406382)
		(stroke
			(width 0.05715)
			(type default)
		)
		(layer "In4.Cu")
	)
	(gr_line
		(start 375.05894 -137.586466)
		(end 375.059956 -137.587228)
		(stroke
			(width 0.05715)
			(type default)
		)
		(layer "In4.Cu")
	)
	(gr_line
		(start 375.059956 -137.587228)
		(end 375.060972 -137.587482)
		(stroke
			(width 0.05715)
			(type default)
		)
		(layer "In4.Cu")
	)
	(gr_line
		(start 375.114312 -109.390434)
		(end 375.125488 -109.435138)
		(stroke
			(width 0.05715)
			(type default)
		)
		(layer "In4.Cu")
	)
	(gr_line
		(start 375.114312 -109.390434)
		(end 375.125742 -109.436408)
		(stroke
			(width 0.05715)
			(type default)
		)
		(layer "In4.Cu")
	)
	(gr_line
		(start 375.114312 -109.390434)
		(end 375.13006 -109.345476)
		(stroke
			(width 0.05715)
			(type default)
		)
		(layer "In4.Cu")
	)
	(gr_line
		(start 375.114312 -109.390434)
		(end 375.13006 -109.344968)
		(stroke
			(width 0.05715)
			(type default)
		)
		(layer "In4.Cu")
	)
	(gr_line
		(start 375.167398 -5.106162)
		(end 375.22658 -5.04698)
		(stroke
			(width 0.05715)
			(type default)
		)
		(layer "In4.Cu")
	)
	(gr_line
		(start 375.173748 -6.317996)
		(end 375.403872 -6.317996)
		(stroke
			(width 0.05715)
			(type default)
		)
		(layer "In4.Cu")
	)
	(gr_line
		(start 375.174764 -132.899912)
		(end 375.208546 -132.906516)
		(stroke
			(width 0.05715)
			(type default)
		)
		(layer "In4.Cu")
	)
	(gr_line
		(start 375.208546 -132.906516)
		(end 375.235216 -132.927598)
		(stroke
			(width 0.05715)
			(type default)
		)
		(layer "In4.Cu")
	)
	(gr_line
		(start 375.346214 -6.792214)
		(end 375.405396 -6.733032)
		(stroke
			(width 0.05715)
			(type default)
		)
		(layer "In4.Cu")
	)
	(gr_line
		(start 375.361962 -57.7215)
		(end 375.39676 -57.7215)
		(stroke
			(width 0.05715)
			(type default)
		)
		(layer "In4.Cu")
	)
	(gr_line
		(start 375.36628 -127.712216)
		(end 375.387362 -127.71628)
		(stroke
			(width 0.05715)
			(type default)
		)
		(layer "In4.Cu")
	)
	(gr_line
		(start 375.376694 -111.17707)
		(end 375.40946 -111.11103)
		(stroke
			(width 0.05715)
			(type default)
		)
		(layer "In4.Cu")
	)
	(gr_line
		(start 375.376948 -128.373378)
		(end 375.39803 -128.377442)
		(stroke
			(width 0.05715)
			(type default)
		)
		(layer "In4.Cu")
	)
	(gr_line
		(start 375.387362 -127.71628)
		(end 375.407936 -127.711708)
		(stroke
			(width 0.05715)
			(type default)
		)
		(layer "In4.Cu")
	)
	(gr_line
		(start 375.389394 -111.039402)
		(end 375.40946 -111.11103)
		(stroke
			(width 0.05715)
			(type default)
		)
		(layer "In4.Cu")
	)
	(gr_line
		(start 375.39803 -128.377442)
		(end 375.418604 -128.37287)
		(stroke
			(width 0.05715)
			(type default)
		)
		(layer "In4.Cu")
	)
	(gr_line
		(start 375.470928 -4.155948)
		(end 375.470928 -4.386072)
		(stroke
			(width 0.05715)
			(type default)
		)
		(layer "In4.Cu")
	)
	(gr_line
		(start 375.470928 -4.155948)
		(end 375.713244 -3.913632)
		(stroke
			(width 0.05715)
			(type default)
		)
		(layer "In4.Cu")
	)
	(gr_line
		(start 375.511314 -109.88294)
		(end 375.511568 -109.882178)
		(stroke
			(width 0.05715)
			(type default)
		)
		(layer "In4.Cu")
	)
	(gr_line
		(start 375.511568 -109.881924)
		(end 375.525792 -109.838744)
		(stroke
			(width 0.05715)
			(type default)
		)
		(layer "In4.Cu")
	)
	(gr_line
		(start 375.514616 -109.792262)
		(end 375.526046 -109.838744)
		(stroke
			(width 0.05715)
			(type default)
		)
		(layer "In4.Cu")
	)
	(gr_line
		(start 375.525792 -109.838744)
		(end 375.526046 -109.838744)
		(stroke
			(width 0.05715)
			(type default)
		)
		(layer "In4.Cu")
	)
	(gr_line
		(start 375.526554 -109.094016)
		(end 375.540524 -109.053376)
		(stroke
			(width 0.05715)
			(type default)
		)
		(layer "In4.Cu")
	)
	(gr_line
		(start 375.532142 -109.012482)
		(end 375.540524 -109.053376)
		(stroke
			(width 0.05715)
			(type default)
		)
		(layer "In4.Cu")
	)
	(gr_line
		(start 375.60504 -16.324326)
		(end 375.611898 -16.295116)
		(stroke
			(width 0.05715)
			(type default)
		)
		(layer "In4.Cu")
	)
	(gr_line
		(start 375.611898 -16.295116)
		(end 375.630694 -16.272256)
		(stroke
			(width 0.05715)
			(type default)
		)
		(layer "In4.Cu")
	)
	(gr_line
		(start 375.64949 -5.842)
		(end 375.64949 -6.072378)
		(stroke
			(width 0.05715)
			(type default)
		)
		(layer "In4.Cu")
	)
	(gr_line
		(start 375.64949 -5.842)
		(end 375.89206 -5.599684)
		(stroke
			(width 0.05715)
			(type default)
		)
		(layer "In4.Cu")
	)
	(gr_line
		(start 375.651522 -57.563004)
		(end 375.68632 -57.563004)
		(stroke
			(width 0.05715)
			(type default)
		)
		(layer "In4.Cu")
	)
	(gr_line
		(start 375.673874 -136.574022)
		(end 375.704354 -136.581896)
		(stroke
			(width 0.05715)
			(type default)
		)
		(layer "In4.Cu")
	)
	(gr_line
		(start 375.70029 -2.937002)
		(end 376.07494 -2.937002)
		(stroke
			(width 0.05715)
			(type default)
		)
		(layer "In4.Cu")
	)
	(gr_line
		(start 375.704354 -136.581896)
		(end 375.734072 -136.575546)
		(stroke
			(width 0.05715)
			(type default)
		)
		(layer "In4.Cu")
	)
	(gr_line
		(start 375.713244 -3.913632)
		(end 375.943368 -3.913632)
		(stroke
			(width 0.05715)
			(type default)
		)
		(layer "In4.Cu")
	)
	(gr_line
		(start 375.885964 -4.387596)
		(end 375.944892 -4.328668)
		(stroke
			(width 0.05715)
			(type default)
		)
		(layer "In4.Cu")
	)
	(gr_line
		(start 375.89206 -5.599684)
		(end 376.122184 -5.599684)
		(stroke
			(width 0.05715)
			(type default)
		)
		(layer "In4.Cu")
	)
	(gr_line
		(start 375.994422 -133.900164)
		(end 376.012456 -133.914388)
		(stroke
			(width 0.05715)
			(type default)
		)
		(layer "In4.Cu")
	)
	(gr_line
		(start 376.012456 -133.914388)
		(end 376.034046 -133.920484)
		(stroke
			(width 0.05715)
			(type default)
		)
		(layer "In4.Cu")
	)
	(gr_line
		(start 376.064526 -6.073902)
		(end 376.123708 -6.01472)
		(stroke
			(width 0.05715)
			(type default)
		)
		(layer "In4.Cu")
	)
	(gr_line
		(start 376.07494 -2.937002)
		(end 376.12701 -2.989072)
		(stroke
			(width 0.05715)
			(type default)
		)
		(layer "In4.Cu")
	)
	(gr_line
		(start 376.111516 -127.256286)
		(end 376.137932 -127.250444)
		(stroke
			(width 0.05715)
			(type default)
		)
		(layer "In4.Cu")
	)
	(gr_line
		(start 376.116088 -127.918972)
		(end 376.140726 -127.913638)
		(stroke
			(width 0.05715)
			(type default)
		)
		(layer "In4.Cu")
	)
	(gr_line
		(start 376.137932 -127.250444)
		(end 376.164348 -127.256032)
		(stroke
			(width 0.05715)
			(type default)
		)
		(layer "In4.Cu")
	)
	(gr_line
		(start 376.140726 -127.913638)
		(end 376.164602 -127.918718)
		(stroke
			(width 0.05715)
			(type default)
		)
		(layer "In4.Cu")
	)
	(gr_line
		(start 376.156982 -129.843022)
		(end 376.190764 -129.833116)
		(stroke
			(width 0.05715)
			(type default)
		)
		(layer "In4.Cu")
	)
	(gr_line
		(start 376.190764 -129.833116)
		(end 376.225308 -129.840228)
		(stroke
			(width 0.05715)
			(type default)
		)
		(layer "In4.Cu")
	)
	(gr_line
		(start 376.191018 -16.671036)
		(end 376.197876 -16.641826)
		(stroke
			(width 0.05715)
			(type default)
		)
		(layer "In4.Cu")
	)
	(gr_line
		(start 376.197876 -16.641826)
		(end 376.216672 -16.618966)
		(stroke
			(width 0.05715)
			(type default)
		)
		(layer "In4.Cu")
	)
	(gr_line
		(start 376.30989 -131.648454)
		(end 376.333512 -131.642866)
		(stroke
			(width 0.05715)
			(type default)
		)
		(layer "In4.Cu")
	)
	(gr_line
		(start 376.333512 -131.642866)
		(end 376.357642 -131.647438)
		(stroke
			(width 0.05715)
			(type default)
		)
		(layer "In4.Cu")
	)
	(gr_line
		(start 376.508264 -137.954258)
		(end 376.547634 -137.964164)
		(stroke
			(width 0.05715)
			(type default)
		)
		(layer "In4.Cu")
	)
	(gr_line
		(start 376.536458 -138.619484)
		(end 376.575066 -138.62939)
		(stroke
			(width 0.05715)
			(type default)
		)
		(layer "In4.Cu")
	)
	(gr_line
		(start 376.54357 -2.989072)
		(end 376.59564 -2.937002)
		(stroke
			(width 0.05715)
			(type default)
		)
		(layer "In4.Cu")
	)
	(gr_line
		(start 376.547634 -137.964164)
		(end 376.587004 -137.953242)
		(stroke
			(width 0.05715)
			(type default)
		)
		(layer "In4.Cu")
	)
	(gr_line
		(start 376.575066 -138.62939)
		(end 376.614436 -138.618214)
		(stroke
			(width 0.05715)
			(type default)
		)
		(layer "In4.Cu")
	)
	(gr_line
		(start 376.59564 -2.937002)
		(end 376.97029 -2.937002)
		(stroke
			(width 0.05715)
			(type default)
		)
		(layer "In4.Cu")
	)
	(gr_line
		(start 376.68835 -10.749788)
		(end 376.700796 -10.734802)
		(stroke
			(width 0.05715)
			(type default)
		)
		(layer "In4.Cu")
	)
	(gr_line
		(start 376.700796 -10.734802)
		(end 376.71756 -10.725912)
		(stroke
			(width 0.05715)
			(type default)
		)
		(layer "In4.Cu")
	)
	(gr_line
		(start 377.108974 -131.792726)
		(end 377.136406 -131.79806)
		(stroke
			(width 0.05715)
			(type default)
		)
		(layer "In4.Cu")
	)
	(gr_line
		(start 377.116086 -11.290046)
		(end 377.128532 -11.27506)
		(stroke
			(width 0.05715)
			(type default)
		)
		(layer "In4.Cu")
	)
	(gr_line
		(start 377.127262 -127.760222)
		(end 377.156726 -127.766572)
		(stroke
			(width 0.05715)
			(type default)
		)
		(layer "In4.Cu")
	)
	(gr_line
		(start 377.128532 -11.27506)
		(end 377.14555 -11.265916)
		(stroke
			(width 0.05715)
			(type default)
		)
		(layer "In4.Cu")
	)
	(gr_line
		(start 377.136406 -131.79806)
		(end 377.158758 -131.81457)
		(stroke
			(width 0.05715)
			(type default)
		)
		(layer "In4.Cu")
	)
	(gr_line
		(start 377.139454 -128.425194)
		(end 377.169172 -128.431544)
		(stroke
			(width 0.05715)
			(type default)
		)
		(layer "In4.Cu")
	)
	(gr_line
		(start 377.14682 -134.23011)
		(end 377.175522 -134.238238)
		(stroke
			(width 0.05715)
			(type default)
		)
		(layer "In4.Cu")
	)
	(gr_line
		(start 377.156726 -127.766572)
		(end 377.18619 -127.759206)
		(stroke
			(width 0.05715)
			(type default)
		)
		(layer "In4.Cu")
	)
	(gr_line
		(start 377.166886 -137.790174)
		(end 377.182126 -137.785856)
		(stroke
			(width 0.05715)
			(type default)
		)
		(layer "In4.Cu")
	)
	(gr_line
		(start 377.169172 -128.431544)
		(end 377.198382 -128.424178)
		(stroke
			(width 0.05715)
			(type default)
		)
		(layer "In4.Cu")
	)
	(gr_line
		(start 377.175522 -134.238238)
		(end 377.204986 -134.23265)
		(stroke
			(width 0.05715)
			(type default)
		)
		(layer "In4.Cu")
	)
	(gr_line
		(start 377.182126 -137.785856)
		(end 377.194318 -137.776712)
		(stroke
			(width 0.05715)
			(type default)
		)
		(layer "In4.Cu")
	)
	(gr_line
		(start 377.419108 -5.359908)
		(end 377.443238 -5.325872)
		(stroke
			(width 0.05715)
			(type default)
		)
		(layer "In4.Cu")
	)
	(gr_line
		(start 377.443238 -5.325872)
		(end 377.4821 -5.308854)
		(stroke
			(width 0.05715)
			(type default)
		)
		(layer "In4.Cu")
	)
	(gr_line
		(start 377.456446 -138.381486)
		(end 377.470924 -138.377422)
		(stroke
			(width 0.05715)
			(type default)
		)
		(layer "In4.Cu")
	)
	(gr_line
		(start 377.470924 -138.377422)
		(end 377.482354 -138.36904)
		(stroke
			(width 0.05715)
			(type default)
		)
		(layer "In4.Cu")
	)
	(gr_line
		(start 377.485148 -135.900668)
		(end 377.61037 -135.707628)
		(stroke
			(width 0.05715)
			(type default)
		)
		(layer "In4.Cu")
	)
	(gr_line
		(start 377.551442 -11.820144)
		(end 377.563888 -11.805158)
		(stroke
			(width 0.05715)
			(type default)
		)
		(layer "In4.Cu")
	)
	(gr_line
		(start 377.563888 -11.805158)
		(end 377.580906 -11.796014)
		(stroke
			(width 0.05715)
			(type default)
		)
		(layer "In4.Cu")
	)
	(gr_line
		(start 377.581668 -136.181338)
		(end 378.166122 -136.056624)
		(stroke
			(width 0.05715)
			(type default)
		)
		(layer "In4.Cu")
	)
	(gr_line
		(start 377.61037 -135.707628)
		(end 377.94565 -135.636)
		(stroke
			(width 0.05715)
			(type default)
		)
		(layer "In4.Cu")
	)
	(gr_line
		(start 377.94565 -135.636)
		(end 378.138944 -135.761222)
		(stroke
			(width 0.05715)
			(type default)
		)
		(layer "In4.Cu")
	)
	(gr_line
		(start 377.986544 -12.350242)
		(end 377.99899 -12.335256)
		(stroke
			(width 0.05715)
			(type default)
		)
		(layer "In4.Cu")
	)
	(gr_line
		(start 377.995434 -130.509264)
		(end 378.022104 -130.514852)
		(stroke
			(width 0.05715)
			(type default)
		)
		(layer "In4.Cu")
	)
	(gr_line
		(start 377.99899 -12.335256)
		(end 378.016008 -12.326112)
		(stroke
			(width 0.05715)
			(type default)
		)
		(layer "In4.Cu")
	)
	(gr_line
		(start 378.022104 -130.514852)
		(end 378.04852 -130.508502)
		(stroke
			(width 0.05715)
			(type default)
		)
		(layer "In4.Cu")
	)
	(gr_line
		(start 378.14758 -1.754886)
		(end 378.52223 -1.754886)
		(stroke
			(width 0.05715)
			(type default)
		)
		(layer "In4.Cu")
	)
	(gr_line
		(start 378.191522 -7.495286)
		(end 378.213874 -7.724394)
		(stroke
			(width 0.05715)
			(type default)
		)
		(layer "In4.Cu")
	)
	(gr_line
		(start 378.191522 -7.495286)
		(end 378.409454 -7.230618)
		(stroke
			(width 0.05715)
			(type default)
		)
		(layer "In4.Cu")
	)
	(gr_line
		(start 378.271024 -136.623298)
		(end 378.28982 -136.609582)
		(stroke
			(width 0.05715)
			(type default)
		)
		(layer "In4.Cu")
	)
	(gr_line
		(start 378.28982 -136.609582)
		(end 378.311918 -136.604502)
		(stroke
			(width 0.05715)
			(type default)
		)
		(layer "In4.Cu")
	)
	(gr_line
		(start 378.409454 -7.230618)
		(end 378.638562 -7.208266)
		(stroke
			(width 0.05715)
			(type default)
		)
		(layer "In4.Cu")
	)
	(gr_line
		(start 378.423678 -12.879324)
		(end 378.435362 -12.864846)
		(stroke
			(width 0.05715)
			(type default)
		)
		(layer "In4.Cu")
	)
	(gr_line
		(start 378.435362 -12.864846)
		(end 378.45238 -12.855702)
		(stroke
			(width 0.05715)
			(type default)
		)
		(layer "In4.Cu")
	)
	(gr_line
		(start 378.46381 -7.883906)
		(end 378.843794 -7.422642)
		(stroke
			(width 0.05715)
			(type default)
		)
		(layer "In4.Cu")
	)
	(gr_line
		(start 378.478796 -135.688578)
		(end 378.604018 -135.495538)
		(stroke
			(width 0.05715)
			(type default)
		)
		(layer "In4.Cu")
	)
	(gr_line
		(start 378.517912 -137.245852)
		(end 378.535946 -137.232644)
		(stroke
			(width 0.05715)
			(type default)
		)
		(layer "In4.Cu")
	)
	(gr_line
		(start 378.52223 -1.754886)
		(end 378.5743 -1.806956)
		(stroke
			(width 0.05715)
			(type default)
		)
		(layer "In4.Cu")
	)
	(gr_line
		(start 378.535946 -137.232644)
		(end 378.557536 -137.227564)
		(stroke
			(width 0.05715)
			(type default)
		)
		(layer "In4.Cu")
	)
	(gr_line
		(start 378.574554 -135.969502)
		(end 379.160278 -135.844534)
		(stroke
			(width 0.05715)
			(type default)
		)
		(layer "In4.Cu")
	)
	(gr_line
		(start 378.604018 -135.495538)
		(end 378.939298 -135.42391)
		(stroke
			(width 0.05715)
			(type default)
		)
		(layer "In4.Cu")
	)
	(gr_line
		(start 378.604526 -133.674104)
		(end 378.63526 -133.668262)
		(stroke
			(width 0.05715)
			(type default)
		)
		(layer "In4.Cu")
	)
	(gr_line
		(start 378.63526 -133.668262)
		(end 378.664978 -133.676898)
		(stroke
			(width 0.05715)
			(type default)
		)
		(layer "In4.Cu")
	)
	(gr_line
		(start 378.732542 -9.979914)
		(end 378.759974 -9.965436)
		(stroke
			(width 0.05715)
			(type default)
		)
		(layer "In4.Cu")
	)
	(gr_line
		(start 378.747528 -133.335776)
		(end 378.759466 -133.344412)
		(stroke
			(width 0.05715)
			(type default)
		)
		(layer "In4.Cu")
	)
	(gr_line
		(start 378.759466 -133.344412)
		(end 378.773436 -133.348476)
		(stroke
			(width 0.05715)
			(type default)
		)
		(layer "In4.Cu")
	)
	(gr_line
		(start 378.759974 -9.965436)
		(end 378.778008 -9.940036)
		(stroke
			(width 0.05715)
			(type default)
		)
		(layer "In4.Cu")
	)
	(gr_line
		(start 378.83719 -6.710934)
		(end 378.859542 -6.940042)
		(stroke
			(width 0.05715)
			(type default)
		)
		(layer "In4.Cu")
	)
	(gr_line
		(start 378.83719 -6.710934)
		(end 379.055376 -6.446012)
		(stroke
			(width 0.05715)
			(type default)
		)
		(layer "In4.Cu")
	)
	(gr_line
		(start 378.857764 -13.410438)
		(end 378.869448 -13.39596)
		(stroke
			(width 0.05715)
			(type default)
		)
		(layer "In4.Cu")
	)
	(gr_line
		(start 378.869448 -13.39596)
		(end 378.886466 -13.386816)
		(stroke
			(width 0.05715)
			(type default)
		)
		(layer "In4.Cu")
	)
	(gr_line
		(start 378.939298 -135.42391)
		(end 379.132592 -135.549132)
		(stroke
			(width 0.05715)
			(type default)
		)
		(layer "In4.Cu")
	)
	(gr_line
		(start 378.99086 -1.806956)
		(end 379.04293 -1.754886)
		(stroke
			(width 0.05715)
			(type default)
		)
		(layer "In4.Cu")
	)
	(gr_line
		(start 379.04293 -1.754886)
		(end 379.41758 -1.754886)
		(stroke
			(width 0.05715)
			(type default)
		)
		(layer "In4.Cu")
	)
	(gr_line
		(start 379.055376 -6.446012)
		(end 379.284484 -6.423914)
		(stroke
			(width 0.05715)
			(type default)
		)
		(layer "In4.Cu")
	)
	(gr_line
		(start 379.108716 -7.101078)
		(end 379.490478 -6.637274)
		(stroke
			(width 0.05715)
			(type default)
		)
		(layer "In4.Cu")
	)
	(gr_line
		(start 379.220476 -8.534146)
		(end 379.258322 -8.760968)
		(stroke
			(width 0.05715)
			(type default)
		)
		(layer "In4.Cu")
	)
	(gr_line
		(start 379.220476 -8.534146)
		(end 379.419612 -8.255)
		(stroke
			(width 0.05715)
			(type default)
		)
		(layer "In4.Cu")
	)
	(gr_line
		(start 379.419612 -8.255)
		(end 379.646688 -8.217154)
		(stroke
			(width 0.05715)
			(type default)
		)
		(layer "In4.Cu")
	)
	(gr_line
		(start 379.445266 -135.484616)
		(end 379.470666 -135.479282)
		(stroke
			(width 0.05715)
			(type default)
		)
		(layer "In4.Cu")
	)
	(gr_line
		(start 379.470666 -135.479536)
		(end 379.471936 -135.479282)
		(stroke
			(width 0.05715)
			(type default)
		)
		(layer "In4.Cu")
	)
	(gr_line
		(start 379.470666 -135.479282)
		(end 379.470666 -135.479536)
		(stroke
			(width 0.05715)
			(type default)
		)
		(layer "In4.Cu")
	)
	(gr_line
		(start 379.471936 -135.479282)
		(end 379.496574 -135.484616)
		(stroke
			(width 0.05715)
			(type default)
		)
		(layer "In4.Cu")
	)
	(gr_line
		(start 379.483112 -5.926328)
		(end 379.50521 -6.15569)
		(stroke
			(width 0.05715)
			(type default)
		)
		(layer "In4.Cu")
	)
	(gr_line
		(start 379.483112 -5.926328)
		(end 379.701044 -5.66166)
		(stroke
			(width 0.05715)
			(type default)
		)
		(layer "In4.Cu")
	)
	(gr_line
		(start 379.518672 -8.903462)
		(end 379.866906 -8.416036)
		(stroke
			(width 0.05715)
			(type default)
		)
		(layer "In4.Cu")
	)
	(gr_line
		(start 379.612398 -133.590792)
		(end 379.660404 -133.604762)
		(stroke
			(width 0.05715)
			(type default)
		)
		(layer "In4.Cu")
	)
	(gr_line
		(start 379.660404 -133.604762)
		(end 379.708156 -133.59003)
		(stroke
			(width 0.05715)
			(type default)
		)
		(layer "In4.Cu")
	)
	(gr_line
		(start 379.701044 -5.66166)
		(end 379.930406 -5.639308)
		(stroke
			(width 0.05715)
			(type default)
		)
		(layer "In4.Cu")
	)
	(gr_line
		(start 379.753368 -6.317996)
		(end 380.136654 -5.852414)
		(stroke
			(width 0.05715)
			(type default)
		)
		(layer "In4.Cu")
	)
	(gr_line
		(start 379.795786 -134.307326)
		(end 379.843792 -134.321296)
		(stroke
			(width 0.05715)
			(type default)
		)
		(layer "In4.Cu")
	)
	(gr_line
		(start 379.811026 -7.707376)
		(end 379.848872 -7.934198)
		(stroke
			(width 0.05715)
			(type default)
		)
		(layer "In4.Cu")
	)
	(gr_line
		(start 379.811026 -7.707376)
		(end 380.010416 -7.428484)
		(stroke
			(width 0.05715)
			(type default)
		)
		(layer "In4.Cu")
	)
	(gr_line
		(start 379.843792 -134.321296)
		(end 379.891544 -134.306564)
		(stroke
			(width 0.05715)
			(type default)
		)
		(layer "In4.Cu")
	)
	(gr_line
		(start 379.881892 -136.2456)
		(end 379.908816 -136.239504)
		(stroke
			(width 0.05715)
			(type default)
		)
		(layer "In4.Cu")
	)
	(gr_line
		(start 379.908816 -136.239504)
		(end 379.93574 -136.245346)
		(stroke
			(width 0.05715)
			(type default)
		)
		(layer "In4.Cu")
	)
	(gr_line
		(start 379.916944 -136.916922)
		(end 379.943868 -136.910826)
		(stroke
			(width 0.05715)
			(type default)
		)
		(layer "In4.Cu")
	)
	(gr_line
		(start 379.943868 -136.910826)
		(end 379.969776 -136.916668)
		(stroke
			(width 0.05715)
			(type default)
		)
		(layer "In4.Cu")
	)
	(gr_line
		(start 380.010416 -7.428484)
		(end 380.237238 -7.390384)
		(stroke
			(width 0.05715)
			(type default)
		)
		(layer "In4.Cu")
	)
	(gr_line
		(start 380.109476 -8.076438)
		(end 380.457456 -7.589266)
		(stroke
			(width 0.05715)
			(type default)
		)
		(layer "In4.Cu")
	)
	(gr_line
		(start 380.231904 -133.427978)
		(end 380.244858 -133.423914)
		(stroke
			(width 0.05715)
			(type default)
		)
		(layer "In4.Cu")
	)
	(gr_line
		(start 380.244858 -133.423914)
		(end 380.255272 -133.415786)
		(stroke
			(width 0.05715)
			(type default)
		)
		(layer "In4.Cu")
	)
	(gr_line
		(start 380.418594 -9.509252)
		(end 380.423166 -9.506712)
		(stroke
			(width 0.05715)
			(type default)
		)
		(layer "In4.Cu")
	)
	(gr_line
		(start 380.423166 -9.506712)
		(end 380.428754 -9.505442)
		(stroke
			(width 0.05715)
			(type default)
		)
		(layer "In4.Cu")
	)
	(gr_line
		(start 380.645162 -10.151364)
		(end 380.649734 -10.148824)
		(stroke
			(width 0.05715)
			(type default)
		)
		(layer "In4.Cu")
	)
	(gr_line
		(start 380.649734 -10.148824)
		(end 380.655322 -10.147554)
		(stroke
			(width 0.05715)
			(type default)
		)
		(layer "In4.Cu")
	)
	(gr_line
		(start 380.735586 -127.232156)
		(end 380.773178 -127.222504)
		(stroke
			(width 0.05715)
			(type default)
		)
		(layer "In4.Cu")
	)
	(gr_line
		(start 380.773178 -127.222504)
		(end 380.811278 -127.233172)
		(stroke
			(width 0.05715)
			(type default)
		)
		(layer "In4.Cu")
	)
	(gr_line
		(start 380.775718 -4.615942)
		(end 380.797054 -4.590034)
		(stroke
			(width 0.05715)
			(type default)
		)
		(layer "In4.Cu")
	)
	(gr_line
		(start 380.797054 -4.590034)
		(end 380.827788 -4.576572)
		(stroke
			(width 0.05715)
			(type default)
		)
		(layer "In4.Cu")
	)
	(gr_line
		(start 380.819914 -6.578854)
		(end 380.864872 -6.516116)
		(stroke
			(width 0.05715)
			(type default)
		)
		(layer "In4.Cu")
	)
	(gr_line
		(start 380.827534 -132.614162)
		(end 380.834138 -132.609336)
		(stroke
			(width 0.05715)
			(type default)
		)
		(layer "In4.Cu")
	)
	(gr_line
		(start 380.834138 -132.609336)
		(end 380.841758 -132.606542)
		(stroke
			(width 0.05715)
			(type default)
		)
		(layer "In4.Cu")
	)
	(gr_line
		(start 380.864872 -6.516116)
		(end 380.939548 -6.50113)
		(stroke
			(width 0.05715)
			(type default)
		)
		(layer "In4.Cu")
	)
	(gr_line
		(start 380.877826 -10.790174)
		(end 380.882398 -10.787634)
		(stroke
			(width 0.05715)
			(type default)
		)
		(layer "In4.Cu")
	)
	(gr_line
		(start 380.882398 -10.787634)
		(end 380.887986 -10.786364)
		(stroke
			(width 0.05715)
			(type default)
		)
		(layer "In4.Cu")
	)
	(gr_line
		(start 380.88824 -133.692392)
		(end 380.93523 -133.677914)
		(stroke
			(width 0.05715)
			(type default)
		)
		(layer "In4.Cu")
	)
	(gr_line
		(start 380.93523 -133.677914)
		(end 380.982728 -133.691376)
		(stroke
			(width 0.05715)
			(type default)
		)
		(layer "In4.Cu")
	)
	(gr_line
		(start 381.070866 -136.13257)
		(end 381.110236 -136.14146)
		(stroke
			(width 0.05715)
			(type default)
		)
		(layer "In4.Cu")
	)
	(gr_line
		(start 381.110236 -136.14146)
		(end 381.149352 -136.129268)
		(stroke
			(width 0.05715)
			(type default)
		)
		(layer "In4.Cu")
	)
	(gr_line
		(start 381.114554 -11.426952)
		(end 381.119126 -11.424412)
		(stroke
			(width 0.05715)
			(type default)
		)
		(layer "In4.Cu")
	)
	(gr_line
		(start 381.119126 -11.424412)
		(end 381.124714 -11.423142)
		(stroke
			(width 0.05715)
			(type default)
		)
		(layer "In4.Cu")
	)
	(gr_line
		(start 381.128778 -136.808972)
		(end 381.168148 -136.817862)
		(stroke
			(width 0.05715)
			(type default)
		)
		(layer "In4.Cu")
	)
	(gr_line
		(start 381.14732 -137.476484)
		(end 381.18669 -137.485374)
		(stroke
			(width 0.05715)
			(type default)
		)
		(layer "In4.Cu")
	)
	(gr_line
		(start 381.168148 -136.817862)
		(end 381.207264 -136.80567)
		(stroke
			(width 0.05715)
			(type default)
		)
		(layer "In4.Cu")
	)
	(gr_line
		(start 381.18669 -137.485374)
		(end 381.225806 -137.473182)
		(stroke
			(width 0.05715)
			(type default)
		)
		(layer "In4.Cu")
	)
	(gr_line
		(start 381.25781 -49.101248)
		(end 381.316738 -49.04232)
		(stroke
			(width 0.05715)
			(type default)
		)
		(layer "In4.Cu")
	)
	(gr_line
		(start 381.35052 -12.065254)
		(end 381.35306 -12.06373)
		(stroke
			(width 0.05715)
			(type default)
		)
		(layer "In4.Cu")
	)
	(gr_line
		(start 381.35306 -12.06373)
		(end 381.356108 -12.062968)
		(stroke
			(width 0.05715)
			(type default)
		)
		(layer "In4.Cu")
	)
	(gr_line
		(start 381.696976 -129.59588)
		(end 381.735584 -129.62001)
		(stroke
			(width 0.05715)
			(type default)
		)
		(layer "In4.Cu")
	)
	(gr_line
		(start 381.812546 -48.133)
		(end 381.812546 -48.133254)
		(stroke
			(width 0.05715)
			(type default)
		)
		(layer "In4.Cu")
	)
	(gr_line
		(start 381.89154 -134.25297)
		(end 381.931164 -134.264146)
		(stroke
			(width 0.05715)
			(type default)
		)
		(layer "In4.Cu")
	)
	(gr_line
		(start 381.931164 -134.264146)
		(end 381.970026 -134.254748)
		(stroke
			(width 0.05715)
			(type default)
		)
		(layer "In4.Cu")
	)
	(gr_line
		(start 381.988568 -3.334512)
		(end 382.039876 -3.31216)
		(stroke
			(width 0.05715)
			(type default)
		)
		(layer "In4.Cu")
	)
	(gr_line
		(start 382.019302 -48.339756)
		(end 382.102106 -48.339756)
		(stroke
			(width 0.05715)
			(type default)
		)
		(layer "In4.Cu")
	)
	(gr_line
		(start 382.03759 -132.188966)
		(end 382.077976 -132.174996)
		(stroke
			(width 0.05715)
			(type default)
		)
		(layer "In4.Cu")
	)
	(gr_line
		(start 382.039876 -3.31216)
		(end 382.094232 -3.323844)
		(stroke
			(width 0.05715)
			(type default)
		)
		(layer "In4.Cu")
	)
	(gr_line
		(start 382.077976 -132.174996)
		(end 382.119632 -132.183632)
		(stroke
			(width 0.05715)
			(type default)
		)
		(layer "In4.Cu")
	)
	(gr_line
		(start 382.118362 -4.011422)
		(end 382.16967 -3.98907)
		(stroke
			(width 0.05715)
			(type default)
		)
		(layer "In4.Cu")
	)
	(gr_line
		(start 382.16967 -3.98907)
		(end 382.223518 -4.0005)
		(stroke
			(width 0.05715)
			(type default)
		)
		(layer "In4.Cu")
	)
	(gr_line
		(start 382.351534 -3.676904)
		(end 382.934972 -3.800856)
		(stroke
			(width 0.05715)
			(type default)
		)
		(layer "In4.Cu")
	)
	(gr_line
		(start 382.378204 -3.381502)
		(end 382.57099 -3.256026)
		(stroke
			(width 0.05715)
			(type default)
		)
		(layer "In4.Cu")
	)
	(gr_line
		(start 382.382014 -135.435086)
		(end 382.417828 -135.42391)
		(stroke
			(width 0.05715)
			(type default)
		)
		(layer "In4.Cu")
	)
	(gr_line
		(start 382.417828 -135.42391)
		(end 382.454404 -135.431276)
		(stroke
			(width 0.05715)
			(type default)
		)
		(layer "In4.Cu")
	)
	(gr_line
		(start 382.448816 -136.10844)
		(end 382.483614 -136.097264)
		(stroke
			(width 0.05715)
			(type default)
		)
		(layer "In4.Cu")
	)
	(gr_line
		(start 382.466088 -136.77646)
		(end 382.501648 -136.765284)
		(stroke
			(width 0.05715)
			(type default)
		)
		(layer "In4.Cu")
	)
	(gr_line
		(start 382.483614 -136.097264)
		(end 382.519682 -136.10463)
		(stroke
			(width 0.05715)
			(type default)
		)
		(layer "In4.Cu")
	)
	(gr_line
		(start 382.501648 -136.765284)
		(end 382.538224 -136.77265)
		(stroke
			(width 0.05715)
			(type default)
		)
		(layer "In4.Cu")
	)
	(gr_line
		(start 382.57099 -3.256026)
		(end 382.906524 -3.3274)
		(stroke
			(width 0.05715)
			(type default)
		)
		(layer "In4.Cu")
	)
	(gr_line
		(start 382.665224 -6.150356)
		(end 382.742948 -6.134608)
		(stroke
			(width 0.05715)
			(type default)
		)
		(layer "In4.Cu")
	)
	(gr_line
		(start 382.742948 -9.011666)
		(end 382.868424 -8.818372)
		(stroke
			(width 0.05715)
			(type default)
		)
		(layer "In4.Cu")
	)
	(gr_line
		(start 382.742948 -6.134608)
		(end 382.810258 -6.176518)
		(stroke
			(width 0.05715)
			(type default)
		)
		(layer "In4.Cu")
	)
	(gr_line
		(start 382.836928 -9.292844)
		(end 383.423922 -9.16813)
		(stroke
			(width 0.05715)
			(type default)
		)
		(layer "In4.Cu")
	)
	(gr_line
		(start 382.868424 -8.818372)
		(end 383.203958 -8.747252)
		(stroke
			(width 0.05715)
			(type default)
		)
		(layer "In4.Cu")
	)
	(gr_line
		(start 382.906524 -3.3274)
		(end 383.031746 -3.520186)
		(stroke
			(width 0.05715)
			(type default)
		)
		(layer "In4.Cu")
	)
	(gr_line
		(start 382.978406 -130.742436)
		(end 382.983486 -130.745738)
		(stroke
			(width 0.05715)
			(type default)
		)
		(layer "In4.Cu")
	)
	(gr_line
		(start 382.980692 -128.51384)
		(end 383.011426 -128.530096)
		(stroke
			(width 0.05715)
			(type default)
		)
		(layer "In4.Cu")
	)
	(gr_line
		(start 382.983486 -130.745738)
		(end 382.989836 -130.747516)
		(stroke
			(width 0.05715)
			(type default)
		)
		(layer "In4.Cu")
	)
	(gr_line
		(start 383.203958 -8.747252)
		(end 383.396744 -8.872728)
		(stroke
			(width 0.05715)
			(type default)
		)
		(layer "In4.Cu")
	)
	(gr_line
		(start 383.252726 -133.643624)
		(end 383.278126 -133.637274)
		(stroke
			(width 0.05715)
			(type default)
		)
		(layer "In4.Cu")
	)
	(gr_line
		(start 383.278126 -133.637274)
		(end 383.304542 -133.642608)
		(stroke
			(width 0.05715)
			(type default)
		)
		(layer "In4.Cu")
	)
	(gr_line
		(start 383.345944 -3.887978)
		(end 383.930144 -4.012184)
		(stroke
			(width 0.05715)
			(type default)
		)
		(layer "In4.Cu")
	)
	(gr_line
		(start 383.372106 -3.592322)
		(end 383.564892 -3.4671)
		(stroke
			(width 0.05715)
			(type default)
		)
		(layer "In4.Cu")
	)
	(gr_line
		(start 383.380488 -54.378606)
		(end 383.39395 -54.378606)
		(stroke
			(width 0.05715)
			(type default)
		)
		(layer "In4.Cu")
	)
	(gr_line
		(start 383.564892 -3.4671)
		(end 383.900426 -3.53822)
		(stroke
			(width 0.05715)
			(type default)
		)
		(layer "In4.Cu")
	)
	(gr_line
		(start 383.64668 -54.218078)
		(end 383.68351 -54.218078)
		(stroke
			(width 0.05715)
			(type default)
		)
		(layer "In4.Cu")
	)
	(gr_line
		(start 383.73685 -8.800338)
		(end 383.862072 -8.607298)
		(stroke
			(width 0.05715)
			(type default)
		)
		(layer "In4.Cu")
	)
	(gr_line
		(start 383.831592 -9.081516)
		(end 384.417316 -8.957056)
		(stroke
			(width 0.05715)
			(type default)
		)
		(layer "In4.Cu")
	)
	(gr_line
		(start 383.862072 -8.607298)
		(end 384.197606 -8.536178)
		(stroke
			(width 0.05715)
			(type default)
		)
		(layer "In4.Cu")
	)
	(gr_line
		(start 383.900426 -3.53822)
		(end 384.025902 -3.73126)
		(stroke
			(width 0.05715)
			(type default)
		)
		(layer "In4.Cu")
	)
	(gr_line
		(start 383.900934 -136.017254)
		(end 383.9337 -136.023858)
		(stroke
			(width 0.05715)
			(type default)
		)
		(layer "In4.Cu")
	)
	(gr_line
		(start 383.928874 -136.682734)
		(end 383.96164 -136.689338)
		(stroke
			(width 0.05715)
			(type default)
		)
		(layer "In4.Cu")
	)
	(gr_line
		(start 383.9337 -136.023858)
		(end 383.965958 -136.014714)
		(stroke
			(width 0.05715)
			(type default)
		)
		(layer "In4.Cu")
	)
	(gr_line
		(start 383.949194 -137.351008)
		(end 383.98196 -137.357612)
		(stroke
			(width 0.05715)
			(type default)
		)
		(layer "In4.Cu")
	)
	(gr_line
		(start 383.96164 -136.689338)
		(end 383.99339 -136.680194)
		(stroke
			(width 0.05715)
			(type default)
		)
		(layer "In4.Cu")
	)
	(gr_line
		(start 383.9718 -125.748542)
		(end 384.000502 -125.74143)
		(stroke
			(width 0.05715)
			(type default)
		)
		(layer "In4.Cu")
	)
	(gr_line
		(start 383.98196 -137.357612)
		(end 384.01371 -137.348468)
		(stroke
			(width 0.05715)
			(type default)
		)
		(layer "In4.Cu")
	)
	(gr_line
		(start 384.000502 -125.741684)
		(end 384.027172 -125.747272)
		(stroke
			(width 0.05715)
			(type default)
		)
		(layer "In4.Cu")
	)
	(gr_line
		(start 384.000502 -125.74143)
		(end 384.000502 -125.741684)
		(stroke
			(width 0.05715)
			(type default)
		)
		(layer "In4.Cu")
	)
	(gr_line
		(start 384.146806 -11.470132)
		(end 384.170682 -11.465052)
		(stroke
			(width 0.05715)
			(type default)
		)
		(layer "In4.Cu")
	)
	(gr_line
		(start 384.170682 -11.465052)
		(end 384.193796 -11.469878)
		(stroke
			(width 0.05715)
			(type default)
		)
		(layer "In4.Cu")
	)
	(gr_line
		(start 384.197606 -8.536178)
		(end 384.390646 -8.661654)
		(stroke
			(width 0.05715)
			(type default)
		)
		(layer "In4.Cu")
	)
	(gr_line
		(start 384.252724 -135.626094)
		(end 384.364484 -135.424926)
		(stroke
			(width 0.05715)
			(type default)
		)
		(layer "In4.Cu")
	)
	(gr_line
		(start 384.340608 -4.099306)
		(end 384.922522 -4.22275)
		(stroke
			(width 0.05715)
			(type default)
		)
		(layer "In4.Cu")
	)
	(gr_line
		(start 384.363468 -128.237996)
		(end 384.400044 -128.25984)
		(stroke
			(width 0.05715)
			(type default)
		)
		(layer "In4.Cu")
	)
	(gr_line
		(start 384.364484 -135.424926)
		(end 384.694176 -135.330692)
		(stroke
			(width 0.05715)
			(type default)
		)
		(layer "In4.Cu")
	)
	(gr_line
		(start 384.366008 -3.803396)
		(end 384.558794 -3.678174)
		(stroke
			(width 0.05715)
			(type default)
		)
		(layer "In4.Cu")
	)
	(gr_line
		(start 384.367532 -135.899906)
		(end 384.944112 -135.73506)
		(stroke
			(width 0.05715)
			(type default)
		)
		(layer "In4.Cu")
	)
	(gr_line
		(start 384.45186 -7.544054)
		(end 384.463036 -7.550912)
		(stroke
			(width 0.05715)
			(type default)
		)
		(layer "In4.Cu")
	)
	(gr_line
		(start 384.463036 -7.550912)
		(end 384.47599 -7.553706)
		(stroke
			(width 0.05715)
			(type default)
		)
		(layer "In4.Cu")
	)
	(gr_line
		(start 384.48361 -11.829034)
		(end 385.068318 -11.951208)
		(stroke
			(width 0.05715)
			(type default)
		)
		(layer "In4.Cu")
	)
	(gr_line
		(start 384.50901 -11.533378)
		(end 384.701796 -11.407394)
		(stroke
			(width 0.05715)
			(type default)
		)
		(layer "In4.Cu")
	)
	(gr_line
		(start 384.558794 -3.678174)
		(end 384.894328 -3.749294)
		(stroke
			(width 0.05715)
			(type default)
		)
		(layer "In4.Cu")
	)
	(gr_line
		(start 384.694176 -135.330692)
		(end 384.895598 -135.442452)
		(stroke
			(width 0.05715)
			(type default)
		)
		(layer "In4.Cu")
	)
	(gr_line
		(start 384.701796 -11.407394)
		(end 385.03733 -11.477498)
		(stroke
			(width 0.05715)
			(type default)
		)
		(layer "In4.Cu")
	)
	(gr_line
		(start 384.7211 -10.659872)
		(end 384.744976 -10.654792)
		(stroke
			(width 0.05715)
			(type default)
		)
		(layer "In4.Cu")
	)
	(gr_line
		(start 384.730498 -8.589264)
		(end 384.855974 -8.396224)
		(stroke
			(width 0.05715)
			(type default)
		)
		(layer "In4.Cu")
	)
	(gr_line
		(start 384.744976 -10.654792)
		(end 384.76809 -10.659618)
		(stroke
			(width 0.05715)
			(type default)
		)
		(layer "In4.Cu")
	)
	(gr_line
		(start 384.824986 -8.870442)
		(end 385.412996 -8.745728)
		(stroke
			(width 0.05715)
			(type default)
		)
		(layer "In4.Cu")
	)
	(gr_line
		(start 384.855974 -8.396224)
		(end 385.191508 -8.325104)
		(stroke
			(width 0.05715)
			(type default)
		)
		(layer "In4.Cu")
	)
	(gr_line
		(start 384.894328 -3.749294)
		(end 385.019296 -3.94208)
		(stroke
			(width 0.05715)
			(type default)
		)
		(layer "In4.Cu")
	)
	(gr_line
		(start 384.957828 -125.936248)
		(end 384.976624 -125.940058)
		(stroke
			(width 0.05715)
			(type default)
		)
		(layer "In4.Cu")
	)
	(gr_line
		(start 384.976624 -125.940058)
		(end 384.992626 -125.950472)
		(stroke
			(width 0.05715)
			(type default)
		)
		(layer "In4.Cu")
	)
	(gr_line
		(start 385.03733 -11.477498)
		(end 385.163314 -11.67003)
		(stroke
			(width 0.05715)
			(type default)
		)
		(layer "In4.Cu")
	)
	(gr_line
		(start 385.047744 -7.675118)
		(end 385.632452 -7.799324)
		(stroke
			(width 0.05715)
			(type default)
		)
		(layer "In4.Cu")
	)
	(gr_line
		(start 385.074922 -7.379716)
		(end 385.267962 -7.25424)
		(stroke
			(width 0.05715)
			(type default)
		)
		(layer "In4.Cu")
	)
	(gr_line
		(start 385.149852 -11.038078)
		(end 385.734052 -11.159998)
		(stroke
			(width 0.05715)
			(type default)
		)
		(layer "In4.Cu")
	)
	(gr_line
		(start 385.175252 -10.742422)
		(end 385.368038 -10.616184)
		(stroke
			(width 0.05715)
			(type default)
		)
		(layer "In4.Cu")
	)
	(gr_line
		(start 385.191508 -8.325104)
		(end 385.384548 -8.450326)
		(stroke
			(width 0.05715)
			(type default)
		)
		(layer "In4.Cu")
	)
	(gr_line
		(start 385.229608 -135.346948)
		(end 385.341368 -135.145526)
		(stroke
			(width 0.05715)
			(type default)
		)
		(layer "In4.Cu")
	)
	(gr_line
		(start 385.267962 -7.25424)
		(end 385.603242 -7.325614)
		(stroke
			(width 0.05715)
			(type default)
		)
		(layer "In4.Cu")
	)
	(gr_line
		(start 385.285996 -9.852152)
		(end 385.308856 -9.847326)
		(stroke
			(width 0.05715)
			(type default)
		)
		(layer "In4.Cu")
	)
	(gr_line
		(start 385.308602 -131.063746)
		(end 385.311142 -131.064508)
		(stroke
			(width 0.05715)
			(type default)
		)
		(layer "In4.Cu")
	)
	(gr_line
		(start 385.308856 -9.847326)
		(end 385.331716 -9.851898)
		(stroke
			(width 0.05715)
			(type default)
		)
		(layer "In4.Cu")
	)
	(gr_line
		(start 385.311142 -131.064508)
		(end 385.313428 -131.065778)
		(stroke
			(width 0.05715)
			(type default)
		)
		(layer "In4.Cu")
	)
	(gr_line
		(start 385.341368 -135.145526)
		(end 385.67106 -135.051292)
		(stroke
			(width 0.05715)
			(type default)
		)
		(layer "In4.Cu")
	)
	(gr_line
		(start 385.343146 -135.621014)
		(end 385.91998 -135.456168)
		(stroke
			(width 0.05715)
			(type default)
		)
		(layer "In4.Cu")
	)
	(gr_line
		(start 385.368038 -10.616184)
		(end 385.703572 -10.686288)
		(stroke
			(width 0.05715)
			(type default)
		)
		(layer "In4.Cu")
	)
	(gr_line
		(start 385.47929 -12.03706)
		(end 386.062982 -12.15898)
		(stroke
			(width 0.05715)
			(type default)
		)
		(layer "In4.Cu")
	)
	(gr_line
		(start 385.49326 -131.513834)
		(end 385.550664 -131.736846)
		(stroke
			(width 0.05715)
			(type default)
		)
		(layer "In4.Cu")
	)
	(gr_line
		(start 385.503928 -11.74115)
		(end 385.696206 -11.615166)
		(stroke
			(width 0.05715)
			(type default)
		)
		(layer "In4.Cu")
	)
	(gr_line
		(start 385.550664 -131.736846)
		(end 385.846066 -131.91109)
		(stroke
			(width 0.05715)
			(type default)
		)
		(layer "In4.Cu")
	)
	(gr_line
		(start 385.603242 -7.325614)
		(end 385.728464 -7.5184)
		(stroke
			(width 0.05715)
			(type default)
		)
		(layer "In4.Cu")
	)
	(gr_line
		(start 385.67106 -135.051292)
		(end 385.872228 -135.163052)
		(stroke
			(width 0.05715)
			(type default)
		)
		(layer "In4.Cu")
	)
	(gr_line
		(start 385.67233 -131.27736)
		(end 385.745482 -131.32054)
		(stroke
			(width 0.05715)
			(type default)
		)
		(layer "In4.Cu")
	)
	(gr_line
		(start 385.696206 -11.615166)
		(end 386.031994 -11.685524)
		(stroke
			(width 0.05715)
			(type default)
		)
		(layer "In4.Cu")
	)
	(gr_line
		(start 385.703572 -10.686288)
		(end 385.829302 -10.87882)
		(stroke
			(width 0.05715)
			(type default)
		)
		(layer "In4.Cu")
	)
	(gr_line
		(start 385.729226 -9.069324)
		(end 385.75234 -9.064244)
		(stroke
			(width 0.05715)
			(type default)
		)
		(layer "In4.Cu")
	)
	(gr_line
		(start 385.745482 -131.32054)
		(end 385.745736 -131.321048)
		(stroke
			(width 0.05715)
			(type default)
		)
		(layer "In4.Cu")
	)
	(gr_line
		(start 385.745736 -131.321048)
		(end 386.187696 -131.581906)
		(stroke
			(width 0.05715)
			(type default)
		)
		(layer "In4.Cu")
	)
	(gr_line
		(start 385.75234 -9.064244)
		(end 385.775454 -9.069324)
		(stroke
			(width 0.05715)
			(type default)
		)
		(layer "In4.Cu")
	)
	(gr_line
		(start 385.810252 -126.491746)
		(end 385.827524 -126.503176)
		(stroke
			(width 0.05715)
			(type default)
		)
		(layer "In4.Cu")
	)
	(gr_line
		(start 385.827524 -126.503176)
		(end 385.838954 -126.520448)
		(stroke
			(width 0.05715)
			(type default)
		)
		(layer "In4.Cu")
	)
	(gr_line
		(start 385.846066 -131.91109)
		(end 386.068824 -131.853686)
		(stroke
			(width 0.05715)
			(type default)
		)
		(layer "In4.Cu")
	)
	(gr_line
		(start 385.87426 -4.42468)
		(end 385.897374 -4.42976)
		(stroke
			(width 0.05715)
			(type default)
		)
		(layer "In4.Cu")
	)
	(gr_line
		(start 385.897374 -4.42976)
		(end 385.920488 -4.42468)
		(stroke
			(width 0.05715)
			(type default)
		)
		(layer "In4.Cu")
	)
	(gr_line
		(start 385.96316 -5.09397)
		(end 385.986274 -5.09905)
		(stroke
			(width 0.05715)
			(type default)
		)
		(layer "In4.Cu")
	)
	(gr_line
		(start 385.986274 -5.09905)
		(end 386.009388 -5.09397)
		(stroke
			(width 0.05715)
			(type default)
		)
		(layer "In4.Cu")
	)
	(gr_line
		(start 386.00126 -8.322056)
		(end 386.024374 -8.316976)
		(stroke
			(width 0.05715)
			(type default)
		)
		(layer "In4.Cu")
	)
	(gr_line
		(start 386.024374 -8.316976)
		(end 386.047488 -8.322056)
		(stroke
			(width 0.05715)
			(type default)
		)
		(layer "In4.Cu")
	)
	(gr_line
		(start 386.031994 -11.685524)
		(end 386.157978 -11.878056)
		(stroke
			(width 0.05715)
			(type default)
		)
		(layer "In4.Cu")
	)
	(gr_line
		(start 386.122926 -129.28854)
		(end 386.158232 -129.309622)
		(stroke
			(width 0.05715)
			(type default)
		)
		(layer "In4.Cu")
	)
	(gr_line
		(start 386.134864 -136.438132)
		(end 386.166614 -136.428988)
		(stroke
			(width 0.05715)
			(type default)
		)
		(layer "In4.Cu")
	)
	(gr_line
		(start 386.144516 -11.24585)
		(end 386.729224 -11.368024)
		(stroke
			(width 0.05715)
			(type default)
		)
		(layer "In4.Cu")
	)
	(gr_line
		(start 386.158232 -129.309622)
		(end 386.178298 -129.345182)
		(stroke
			(width 0.05715)
			(type default)
		)
		(layer "In4.Cu")
	)
	(gr_line
		(start 386.166614 -136.428988)
		(end 386.19938 -136.435592)
		(stroke
			(width 0.05715)
			(type default)
		)
		(layer "In4.Cu")
	)
	(gr_line
		(start 386.169916 -10.950194)
		(end 386.362448 -10.823956)
		(stroke
			(width 0.05715)
			(type default)
		)
		(layer "In4.Cu")
	)
	(gr_line
		(start 386.362448 -10.823956)
		(end 386.698236 -10.89406)
		(stroke
			(width 0.05715)
			(type default)
		)
		(layer "In4.Cu")
	)
	(gr_line
		(start 386.368036 -132.03047)
		(end 386.425694 -132.253228)
		(stroke
			(width 0.05715)
			(type default)
		)
		(layer "In4.Cu")
	)
	(gr_line
		(start 386.425694 -132.253228)
		(end 386.720842 -132.427726)
		(stroke
			(width 0.05715)
			(type default)
		)
		(layer "In4.Cu")
	)
	(gr_line
		(start 386.47243 -12.244832)
		(end 387.057646 -12.367006)
		(stroke
			(width 0.05715)
			(type default)
		)
		(layer "In4.Cu")
	)
	(gr_line
		(start 386.498084 -11.949176)
		(end 386.690616 -11.823192)
		(stroke
			(width 0.05715)
			(type default)
		)
		(layer "In4.Cu")
	)
	(gr_line
		(start 386.50418 -135.658606)
		(end 386.536438 -135.649462)
		(stroke
			(width 0.05715)
			(type default)
		)
		(layer "In4.Cu")
	)
	(gr_line
		(start 386.507736 -134.983982)
		(end 386.539486 -134.974838)
		(stroke
			(width 0.05715)
			(type default)
		)
		(layer "In4.Cu")
	)
	(gr_line
		(start 386.536438 -135.649462)
		(end 386.569204 -135.656066)
		(stroke
			(width 0.05715)
			(type default)
		)
		(layer "In4.Cu")
	)
	(gr_line
		(start 386.539486 -134.974838)
		(end 386.572252 -134.981442)
		(stroke
			(width 0.05715)
			(type default)
		)
		(layer "In4.Cu")
	)
	(gr_line
		(start 386.548884 -131.795266)
		(end 387.061964 -132.098034)
		(stroke
			(width 0.05715)
			(type default)
		)
		(layer "In4.Cu")
	)
	(gr_line
		(start 386.645912 -10.412476)
		(end 387.228334 -10.528808)
		(stroke
			(width 0.05715)
			(type default)
		)
		(layer "In4.Cu")
	)
	(gr_line
		(start 386.667248 -10.116566)
		(end 386.859018 -9.989058)
		(stroke
			(width 0.05715)
			(type default)
		)
		(layer "In4.Cu")
	)
	(gr_line
		(start 386.690616 -11.823192)
		(end 387.026404 -11.893296)
		(stroke
			(width 0.05715)
			(type default)
		)
		(layer "In4.Cu")
	)
	(gr_line
		(start 386.698236 -10.89406)
		(end 386.82422 -11.086846)
		(stroke
			(width 0.05715)
			(type default)
		)
		(layer "In4.Cu")
	)
	(gr_line
		(start 386.720842 -132.427726)
		(end 386.9436 -132.370068)
		(stroke
			(width 0.05715)
			(type default)
		)
		(layer "In4.Cu")
	)
	(gr_line
		(start 386.859018 -9.989058)
		(end 387.19506 -10.056114)
		(stroke
			(width 0.05715)
			(type default)
		)
		(layer "In4.Cu")
	)
	(gr_line
		(start 386.872734 -128.08204)
		(end 386.883656 -128.09855)
		(stroke
			(width 0.05715)
			(type default)
		)
		(layer "In4.Cu")
	)
	(gr_line
		(start 386.883656 -128.09855)
		(end 386.88772 -128.117854)
		(stroke
			(width 0.05715)
			(type default)
		)
		(layer "In4.Cu")
	)
	(gr_line
		(start 386.965952 -129.96926)
		(end 386.967476 -129.976626)
		(stroke
			(width 0.05715)
			(type default)
		)
		(layer "In4.Cu")
	)
	(gr_line
		(start 386.967476 -129.976626)
		(end 386.971286 -129.983484)
		(stroke
			(width 0.05715)
			(type default)
		)
		(layer "In4.Cu")
	)
	(gr_line
		(start 387.026404 -11.893296)
		(end 387.152388 -12.085828)
		(stroke
			(width 0.05715)
			(type default)
		)
		(layer "In4.Cu")
	)
	(gr_line
		(start 387.138926 -11.453622)
		(end 387.723634 -11.575796)
		(stroke
			(width 0.05715)
			(type default)
		)
		(layer "In4.Cu")
	)
	(gr_line
		(start 387.164326 -11.157712)
		(end 387.357112 -11.031728)
		(stroke
			(width 0.05715)
			(type default)
		)
		(layer "In4.Cu")
	)
	(gr_line
		(start 387.176772 -131.70789)
		(end 387.196584 -131.742942)
		(stroke
			(width 0.05715)
			(type default)
		)
		(layer "In4.Cu")
	)
	(gr_line
		(start 387.19506 -10.056114)
		(end 387.322822 -10.24763)
		(stroke
			(width 0.05715)
			(type default)
		)
		(layer "In4.Cu")
	)
	(gr_line
		(start 387.196584 -131.742942)
		(end 387.230874 -131.763008)
		(stroke
			(width 0.05715)
			(type default)
		)
		(layer "In4.Cu")
	)
	(gr_line
		(start 387.357112 -11.031728)
		(end 387.692646 -11.101832)
		(stroke
			(width 0.05715)
			(type default)
		)
		(layer "In4.Cu")
	)
	(gr_line
		(start 387.6421 -10.611866)
		(end 388.225792 -10.728452)
		(stroke
			(width 0.05715)
			(type default)
		)
		(layer "In4.Cu")
	)
	(gr_line
		(start 387.66369 -10.315702)
		(end 387.855206 -10.188194)
		(stroke
			(width 0.05715)
			(type default)
		)
		(layer "In4.Cu")
	)
	(gr_line
		(start 387.690614 -131.257294)
		(end 387.71195 -131.294886)
		(stroke
			(width 0.05715)
			(type default)
		)
		(layer "In4.Cu")
	)
	(gr_line
		(start 387.692646 -11.101832)
		(end 387.818376 -11.294364)
		(stroke
			(width 0.05715)
			(type default)
		)
		(layer "In4.Cu")
	)
	(gr_line
		(start 387.71195 -131.294886)
		(end 387.74878 -131.31673)
		(stroke
			(width 0.05715)
			(type default)
		)
		(layer "In4.Cu")
	)
	(gr_line
		(start 387.855206 -10.188194)
		(end 388.191248 -10.25525)
		(stroke
			(width 0.05715)
			(type default)
		)
		(layer "In4.Cu")
	)
	(gr_line
		(start 388.135368 -133.0706)
		(end 388.142988 -133.075172)
		(stroke
			(width 0.05715)
			(type default)
		)
		(layer "In4.Cu")
	)
	(gr_line
		(start 388.142988 -133.075172)
		(end 388.15264 -133.077204)
		(stroke
			(width 0.05715)
			(type default)
		)
		(layer "In4.Cu")
	)
	(gr_line
		(start 388.191248 -10.25525)
		(end 388.31901 -10.446766)
		(stroke
			(width 0.05715)
			(type default)
		)
		(layer "In4.Cu")
	)
	(gr_line
		(start 388.379208 -3.604006)
		(end 388.402322 -3.598926)
		(stroke
			(width 0.05715)
			(type default)
		)
		(layer "In4.Cu")
	)
	(gr_line
		(start 388.379716 -4.292092)
		(end 388.40283 -4.287012)
		(stroke
			(width 0.05715)
			(type default)
		)
		(layer "In4.Cu")
	)
	(gr_line
		(start 388.402322 -3.598926)
		(end 388.425436 -3.604006)
		(stroke
			(width 0.05715)
			(type default)
		)
		(layer "In4.Cu")
	)
	(gr_line
		(start 388.40283 -4.287012)
		(end 388.425944 -4.292092)
		(stroke
			(width 0.05715)
			(type default)
		)
		(layer "In4.Cu")
	)
	(gr_line
		(start 388.428738 -132.470144)
		(end 388.436358 -132.474716)
		(stroke
			(width 0.05715)
			(type default)
		)
		(layer "In4.Cu")
	)
	(gr_line
		(start 388.436358 -132.474716)
		(end 388.44601 -132.476748)
		(stroke
			(width 0.05715)
			(type default)
		)
		(layer "In4.Cu")
	)
	(gr_line
		(start 388.597902 -137.210546)
		(end 389.18642 -137.32764)
		(stroke
			(width 0.05715)
			(type default)
		)
		(layer "In4.Cu")
	)
	(gr_line
		(start 388.621778 -136.91489)
		(end 388.813294 -136.787128)
		(stroke
			(width 0.05715)
			(type default)
		)
		(layer "In4.Cu")
	)
	(gr_line
		(start 388.66572 -131.858004)
		(end 388.67334 -131.862576)
		(stroke
			(width 0.05715)
			(type default)
		)
		(layer "In4.Cu")
	)
	(gr_line
		(start 388.67334 -131.862576)
		(end 388.682992 -131.864608)
		(stroke
			(width 0.05715)
			(type default)
		)
		(layer "In4.Cu")
	)
	(gr_line
		(start 388.712964 -3.96367)
		(end 389.297926 -4.087876)
		(stroke
			(width 0.05715)
			(type default)
		)
		(layer "In4.Cu")
	)
	(gr_line
		(start 388.74065 -3.668268)
		(end 388.933436 -3.543046)
		(stroke
			(width 0.05715)
			(type default)
		)
		(layer "In4.Cu")
	)
	(gr_line
		(start 388.813294 -136.787128)
		(end 389.14959 -136.85393)
		(stroke
			(width 0.05715)
			(type default)
		)
		(layer "In4.Cu")
	)
	(gr_line
		(start 388.933436 -3.543046)
		(end 389.26897 -3.614166)
		(stroke
			(width 0.05715)
			(type default)
		)
		(layer "In4.Cu")
	)
	(gr_line
		(start 389.14959 -136.85393)
		(end 389.277606 -137.045192)
		(stroke
			(width 0.05715)
			(type default)
		)
		(layer "In4.Cu")
	)
	(gr_line
		(start 389.26897 -3.614166)
		(end 389.394446 -3.807206)
		(stroke
			(width 0.05715)
			(type default)
		)
		(layer "In4.Cu")
	)
	(gr_line
		(start 389.48487 -10.15619)
		(end 389.525002 -10.164826)
		(stroke
			(width 0.05715)
			(type default)
		)
		(layer "In4.Cu")
	)
	(gr_line
		(start 389.525002 -10.164826)
		(end 389.565134 -10.15111)
		(stroke
			(width 0.05715)
			(type default)
		)
		(layer "In4.Cu")
	)
	(gr_line
		(start 389.53313 -129.29362)
		(end 389.76935 -129.0574)
		(stroke
			(width 0.05715)
			(type default)
		)
		(layer "In4.Cu")
	)
	(gr_line
		(start 389.53313 -128.40462)
		(end 389.76935 -128.64084)
		(stroke
			(width 0.05715)
			(type default)
		)
		(layer "In4.Cu")
	)
	(gr_line
		(start 389.59409 -137.408666)
		(end 390.182608 -137.525506)
		(stroke
			(width 0.05715)
			(type default)
		)
		(layer "In4.Cu")
	)
	(gr_line
		(start 389.61822 -137.11301)
		(end 389.809736 -136.985248)
		(stroke
			(width 0.05715)
			(type default)
		)
		(layer "In4.Cu")
	)
	(gr_line
		(start 389.690864 -12.917424)
		(end 389.711946 -12.921742)
		(stroke
			(width 0.05715)
			(type default)
		)
		(layer "In4.Cu")
	)
	(gr_line
		(start 389.711946 -12.921742)
		(end 389.732266 -12.917678)
		(stroke
			(width 0.05715)
			(type default)
		)
		(layer "In4.Cu")
	)
	(gr_line
		(start 389.725154 -9.400794)
		(end 389.765794 -9.40943)
		(stroke
			(width 0.05715)
			(type default)
		)
		(layer "In4.Cu")
	)
	(gr_line
		(start 389.765794 -9.40943)
		(end 389.805926 -9.395714)
		(stroke
			(width 0.05715)
			(type default)
		)
		(layer "In4.Cu")
	)
	(gr_line
		(start 389.80745 -8.68553)
		(end 389.84809 -8.694166)
		(stroke
			(width 0.05715)
			(type default)
		)
		(layer "In4.Cu")
	)
	(gr_line
		(start 389.809736 -136.985248)
		(end 390.146032 -137.05205)
		(stroke
			(width 0.05715)
			(type default)
		)
		(layer "In4.Cu")
	)
	(gr_line
		(start 389.84809 -8.694166)
		(end 389.888222 -8.68045)
		(stroke
			(width 0.05715)
			(type default)
		)
		(layer "In4.Cu")
	)
	(gr_line
		(start 390.146032 -137.05205)
		(end 390.274048 -137.243566)
		(stroke
			(width 0.05715)
			(type default)
		)
		(layer "In4.Cu")
	)
	(gr_line
		(start 390.24433 -12.102084)
		(end 390.265412 -12.106656)
		(stroke
			(width 0.05715)
			(type default)
		)
		(layer "In4.Cu")
	)
	(gr_line
		(start 390.265412 -12.106656)
		(end 390.28624 -12.102592)
		(stroke
			(width 0.05715)
			(type default)
		)
		(layer "In4.Cu")
	)
	(gr_line
		(start 390.546336 -134.23773)
		(end 390.567418 -134.242048)
		(stroke
			(width 0.05715)
			(type default)
		)
		(layer "In4.Cu")
	)
	(gr_line
		(start 390.548622 -133.576568)
		(end 390.569704 -133.580886)
		(stroke
			(width 0.05715)
			(type default)
		)
		(layer "In4.Cu")
	)
	(gr_line
		(start 390.5504 -132.915406)
		(end 390.571482 -132.919724)
		(stroke
			(width 0.05715)
			(type default)
		)
		(layer "In4.Cu")
	)
	(gr_line
		(start 390.552686 -132.254244)
		(end 390.573768 -132.258562)
		(stroke
			(width 0.05715)
			(type default)
		)
		(layer "In4.Cu")
	)
	(gr_line
		(start 390.567418 -134.242048)
		(end 390.587992 -134.23773)
		(stroke
			(width 0.05715)
			(type default)
		)
		(layer "In4.Cu")
	)
	(gr_line
		(start 390.569704 -133.580886)
		(end 390.590278 -133.576568)
		(stroke
			(width 0.05715)
			(type default)
		)
		(layer "In4.Cu")
	)
	(gr_line
		(start 390.571482 -132.919724)
		(end 390.592056 -132.915406)
		(stroke
			(width 0.05715)
			(type default)
		)
		(layer "In4.Cu")
	)
	(gr_line
		(start 390.573768 -132.258562)
		(end 390.594342 -132.254244)
		(stroke
			(width 0.05715)
			(type default)
		)
		(layer "In4.Cu")
	)
	(gr_line
		(start 390.58977 -137.606786)
		(end 391.180828 -137.724388)
		(stroke
			(width 0.05715)
			(type default)
		)
		(layer "In4.Cu")
	)
	(gr_line
		(start 390.614662 -137.31113)
		(end 390.806178 -137.183368)
		(stroke
			(width 0.05715)
			(type default)
		)
		(layer "In4.Cu")
	)
	(gr_line
		(start 390.806178 -137.183368)
		(end 391.142474 -137.25017)
		(stroke
			(width 0.05715)
			(type default)
		)
		(layer "In4.Cu")
	)
	(gr_line
		(start 390.851136 -49.266602)
		(end 390.90854 -49.266602)
		(stroke
			(width 0.05715)
			(type default)
		)
		(layer "In4.Cu")
	)
	(gr_line
		(start 390.985248 -11.280394)
		(end 391.004298 -11.284204)
		(stroke
			(width 0.05715)
			(type default)
		)
		(layer "In4.Cu")
	)
	(gr_line
		(start 391.004298 -11.284204)
		(end 391.023348 -11.280394)
		(stroke
			(width 0.05715)
			(type default)
		)
		(layer "In4.Cu")
	)
	(gr_line
		(start 391.140696 -49.0855)
		(end 391.1981 -49.0855)
		(stroke
			(width 0.05715)
			(type default)
		)
		(layer "In4.Cu")
	)
	(gr_line
		(start 391.142474 -137.25017)
		(end 391.27049 -137.441686)
		(stroke
			(width 0.05715)
			(type default)
		)
		(layer "In4.Cu")
	)
	(gr_line
		(start 391.273284 -5.195316)
		(end 391.296398 -5.200396)
		(stroke
			(width 0.05715)
			(type default)
		)
		(layer "In4.Cu")
	)
	(gr_line
		(start 391.273284 -4.50723)
		(end 391.296398 -4.51231)
		(stroke
			(width 0.05715)
			(type default)
		)
		(layer "In4.Cu")
	)
	(gr_line
		(start 391.296398 -5.200396)
		(end 391.319512 -5.195316)
		(stroke
			(width 0.05715)
			(type default)
		)
		(layer "In4.Cu")
	)
	(gr_line
		(start 391.296398 -4.51231)
		(end 391.319512 -4.50723)
		(stroke
			(width 0.05715)
			(type default)
		)
		(layer "In4.Cu")
	)
	(gr_line
		(start 391.583926 -137.804652)
		(end 392.179048 -137.923016)
		(stroke
			(width 0.05715)
			(type default)
		)
		(layer "In4.Cu")
	)
	(gr_line
		(start 391.611104 -137.50925)
		(end 391.80262 -137.381488)
		(stroke
			(width 0.05715)
			(type default)
		)
		(layer "In4.Cu")
	)
	(gr_line
		(start 391.80262 -137.381488)
		(end 392.138916 -137.44829)
		(stroke
			(width 0.05715)
			(type default)
		)
		(layer "In4.Cu")
	)
	(gr_line
		(start 391.992104 -4.754118)
		(end 392.015218 -4.749038)
		(stroke
			(width 0.05715)
			(type default)
		)
		(layer "In4.Cu")
	)
	(gr_line
		(start 392.015218 -4.749038)
		(end 392.038332 -4.754118)
		(stroke
			(width 0.05715)
			(type default)
		)
		(layer "In4.Cu")
	)
	(gr_line
		(start 392.138916 -137.44829)
		(end 392.266932 -137.639806)
		(stroke
			(width 0.05715)
			(type default)
		)
		(layer "In4.Cu")
	)
	(gr_line
		(start 392.353292 -3.176524)
		(end 392.517884 -3.176524)
		(stroke
			(width 0.05715)
			(type default)
		)
		(layer "In4.Cu")
	)
	(gr_line
		(start 392.517884 -3.176524)
		(end 392.63828 -3.29692)
		(stroke
			(width 0.05715)
			(type default)
		)
		(layer "In4.Cu")
	)
	(gr_line
		(start 392.600434 -4.234942)
		(end 392.649456 -4.224528)
		(stroke
			(width 0.05715)
			(type default)
		)
		(layer "In4.Cu")
	)
	(gr_line
		(start 392.649456 -4.224528)
		(end 392.685016 -4.188968)
		(stroke
			(width 0.05715)
			(type default)
		)
		(layer "In4.Cu")
	)
	(gr_line
		(start 392.684254 -126.040134)
		(end 392.846814 -125.877574)
		(stroke
			(width 0.05715)
			(type default)
		)
		(layer "In4.Cu")
	)
	(gr_line
		(start 392.726926 -133.50875)
		(end 392.752326 -133.50367)
		(stroke
			(width 0.05715)
			(type default)
		)
		(layer "In4.Cu")
	)
	(gr_line
		(start 392.730228 -132.186426)
		(end 392.755628 -132.181346)
		(stroke
			(width 0.05715)
			(type default)
		)
		(layer "In4.Cu")
	)
	(gr_line
		(start 392.735054 -132.846064)
		(end 392.760454 -132.840984)
		(stroke
			(width 0.05715)
			(type default)
		)
		(layer "In4.Cu")
	)
	(gr_line
		(start 392.75131 -131.5212)
		(end 392.77671 -131.51612)
		(stroke
			(width 0.05715)
			(type default)
		)
		(layer "In4.Cu")
	)
	(gr_line
		(start 392.752326 -133.50367)
		(end 392.776456 -133.509258)
		(stroke
			(width 0.05715)
			(type default)
		)
		(layer "In4.Cu")
	)
	(gr_line
		(start 392.755628 -132.181346)
		(end 392.78052 -132.186934)
		(stroke
			(width 0.05715)
			(type default)
		)
		(layer "In4.Cu")
	)
	(gr_line
		(start 392.760454 -132.840984)
		(end 392.784584 -132.846572)
		(stroke
			(width 0.05715)
			(type default)
		)
		(layer "In4.Cu")
	)
	(gr_line
		(start 392.77671 -131.51612)
		(end 392.80084 -131.521708)
		(stroke
			(width 0.05715)
			(type default)
		)
		(layer "In4.Cu")
	)
	(gr_line
		(start 392.846814 -125.877574)
		(end 393.189714 -125.877574)
		(stroke
			(width 0.05715)
			(type default)
		)
		(layer "In4.Cu")
	)
	(gr_line
		(start 392.930126 -3.944112)
		(end 392.9888 -3.885438)
		(stroke
			(width 0.05715)
			(type default)
		)
		(layer "In4.Cu")
	)
	(gr_line
		(start 392.976354 -126.334774)
		(end 393.060174 -126.334774)
		(stroke
			(width 0.05715)
			(type default)
		)
		(layer "In4.Cu")
	)
	(gr_line
		(start 393.05484 -3.29692)
		(end 393.175236 -3.176524)
		(stroke
			(width 0.05715)
			(type default)
		)
		(layer "In4.Cu")
	)
	(gr_line
		(start 393.175236 -3.176524)
		(end 393.369292 -3.176524)
		(stroke
			(width 0.05715)
			(type default)
		)
		(layer "In4.Cu")
	)
	(gr_line
		(start 393.189714 -125.877574)
		(end 393.352274 -126.040134)
		(stroke
			(width 0.05715)
			(type default)
		)
		(layer "In4.Cu")
	)
	(gr_line
		(start 393.216892 -5.302758)
		(end 393.240006 -5.307838)
		(stroke
			(width 0.05715)
			(type default)
		)
		(layer "In4.Cu")
	)
	(gr_line
		(start 393.240006 -5.307838)
		(end 393.26312 -5.302758)
		(stroke
			(width 0.05715)
			(type default)
		)
		(layer "In4.Cu")
	)
	(gr_line
		(start 393.700254 -126.040134)
		(end 393.862814 -125.877574)
		(stroke
			(width 0.05715)
			(type default)
		)
		(layer "In4.Cu")
	)
	(gr_line
		(start 393.862814 -125.877574)
		(end 394.205714 -125.877574)
		(stroke
			(width 0.05715)
			(type default)
		)
		(layer "In4.Cu")
	)
	(gr_line
		(start 393.992354 -126.334774)
		(end 394.076174 -126.334774)
		(stroke
			(width 0.05715)
			(type default)
		)
		(layer "In4.Cu")
	)
	(gr_line
		(start 394.205714 -125.877574)
		(end 394.368274 -126.040134)
		(stroke
			(width 0.05715)
			(type default)
		)
		(layer "In4.Cu")
	)
	(gr_line
		(start 394.327126 -132.838698)
		(end 394.353288 -132.84454)
		(stroke
			(width 0.05715)
			(type default)
		)
		(layer "In4.Cu")
	)
	(gr_line
		(start 394.329666 -134.16153)
		(end 394.355828 -134.167372)
		(stroke
			(width 0.05715)
			(type default)
		)
		(layer "In4.Cu")
	)
	(gr_line
		(start 394.334746 -133.498844)
		(end 394.360908 -133.504686)
		(stroke
			(width 0.05715)
			(type default)
		)
		(layer "In4.Cu")
	)
	(gr_line
		(start 394.344906 -132.17271)
		(end 394.371068 -132.178552)
		(stroke
			(width 0.05715)
			(type default)
		)
		(layer "In4.Cu")
	)
	(gr_line
		(start 394.353288 -132.84454)
		(end 394.379196 -132.838952)
		(stroke
			(width 0.05715)
			(type default)
		)
		(layer "In4.Cu")
	)
	(gr_line
		(start 394.355828 -134.167372)
		(end 394.38199 -134.161784)
		(stroke
			(width 0.05715)
			(type default)
		)
		(layer "In4.Cu")
	)
	(gr_line
		(start 394.360908 -133.504686)
		(end 394.38707 -133.499098)
		(stroke
			(width 0.05715)
			(type default)
		)
		(layer "In4.Cu")
	)
	(gr_line
		(start 394.371068 -132.178552)
		(end 394.39723 -132.172964)
		(stroke
			(width 0.05715)
			(type default)
		)
		(layer "In4.Cu")
	)
	(gr_line
		(start 394.498322 -5.04063)
		(end 394.547344 -5.030216)
		(stroke
			(width 0.05715)
			(type default)
		)
		(layer "In4.Cu")
	)
	(gr_line
		(start 394.547344 -5.030216)
		(end 394.582904 -4.994656)
		(stroke
			(width 0.05715)
			(type default)
		)
		(layer "In4.Cu")
	)
	(gr_line
		(start 394.716254 -126.040134)
		(end 394.878814 -125.877574)
		(stroke
			(width 0.05715)
			(type default)
		)
		(layer "In4.Cu")
	)
	(gr_line
		(start 394.753592 -3.125724)
		(end 394.986256 -3.125724)
		(stroke
			(width 0.05715)
			(type default)
		)
		(layer "In4.Cu")
	)
	(gr_line
		(start 394.829538 -10.518902)
		(end 394.849604 -10.515092)
		(stroke
			(width 0.05715)
			(type default)
		)
		(layer "In4.Cu")
	)
	(gr_line
		(start 394.849604 -10.515092)
		(end 394.867384 -10.503408)
		(stroke
			(width 0.05715)
			(type default)
		)
		(layer "In4.Cu")
	)
	(gr_line
		(start 394.878814 -125.877574)
		(end 395.221714 -125.877574)
		(stroke
			(width 0.05715)
			(type default)
		)
		(layer "In4.Cu")
	)
	(gr_line
		(start 394.986256 -3.125724)
		(end 395.085062 -3.22453)
		(stroke
			(width 0.05715)
			(type default)
		)
		(layer "In4.Cu")
	)
	(gr_line
		(start 395.008354 -126.334774)
		(end 395.092174 -126.334774)
		(stroke
			(width 0.05715)
			(type default)
		)
		(layer "In4.Cu")
	)
	(gr_line
		(start 395.221714 -125.877574)
		(end 395.384274 -126.040134)
		(stroke
			(width 0.05715)
			(type default)
		)
		(layer "In4.Cu")
	)
	(gr_line
		(start 395.314424 -6.825234)
		(end 395.342618 -6.815582)
		(stroke
			(width 0.05715)
			(type default)
		)
		(layer "In4.Cu")
	)
	(gr_line
		(start 395.391386 -10.154412)
		(end 395.40942 -10.14222)
		(stroke
			(width 0.05715)
			(type default)
		)
		(layer "In4.Cu")
	)
	(gr_line
		(start 395.40942 -10.14222)
		(end 395.421612 -10.124186)
		(stroke
			(width 0.05715)
			(type default)
		)
		(layer "In4.Cu")
	)
	(gr_line
		(start 395.501622 -3.22453)
		(end 395.600428 -3.125724)
		(stroke
			(width 0.05715)
			(type default)
		)
		(layer "In4.Cu")
	)
	(gr_line
		(start 395.600428 -3.125724)
		(end 395.769592 -3.125724)
		(stroke
			(width 0.05715)
			(type default)
		)
		(layer "In4.Cu")
	)
	(gr_line
		(start 395.623034 -9.294622)
		(end 395.635226 -9.276334)
		(stroke
			(width 0.05715)
			(type default)
		)
		(layer "In4.Cu")
	)
	(gr_line
		(start 395.635226 -9.276334)
		(end 395.653514 -9.264142)
		(stroke
			(width 0.05715)
			(type default)
		)
		(layer "In4.Cu")
	)
	(gr_line
		(start 395.732254 -126.040134)
		(end 395.894814 -125.877574)
		(stroke
			(width 0.05715)
			(type default)
		)
		(layer "In4.Cu")
	)
	(gr_line
		(start 395.783308 -10.729214)
		(end 395.912086 -10.53846)
		(stroke
			(width 0.05715)
			(type default)
		)
		(layer "In4.Cu")
	)
	(gr_line
		(start 395.872716 -11.01217)
		(end 396.46098 -10.897362)
		(stroke
			(width 0.05715)
			(type default)
		)
		(layer "In4.Cu")
	)
	(gr_line
		(start 395.894814 -125.877574)
		(end 396.237714 -125.877574)
		(stroke
			(width 0.05715)
			(type default)
		)
		(layer "In4.Cu")
	)
	(gr_line
		(start 395.912086 -10.53846)
		(end 396.248636 -10.472674)
		(stroke
			(width 0.05715)
			(type default)
		)
		(layer "In4.Cu")
	)
	(gr_line
		(start 395.972538 -133.527546)
		(end 396.001748 -133.521196)
		(stroke
			(width 0.05715)
			(type default)
		)
		(layer "In4.Cu")
	)
	(gr_line
		(start 395.986 -132.863336)
		(end 396.01521 -132.856986)
		(stroke
			(width 0.05715)
			(type default)
		)
		(layer "In4.Cu")
	)
	(gr_line
		(start 395.9987 -132.198364)
		(end 396.028418 -132.192014)
		(stroke
			(width 0.05715)
			(type default)
		)
		(layer "In4.Cu")
	)
	(gr_line
		(start 396.001748 -133.521196)
		(end 396.030704 -133.528562)
		(stroke
			(width 0.05715)
			(type default)
		)
		(layer "In4.Cu")
	)
	(gr_line
		(start 396.011908 -131.533646)
		(end 396.041626 -131.527296)
		(stroke
			(width 0.05715)
			(type default)
		)
		(layer "In4.Cu")
	)
	(gr_line
		(start 396.01521 -132.856986)
		(end 396.044166 -132.864352)
		(stroke
			(width 0.05715)
			(type default)
		)
		(layer "In4.Cu")
	)
	(gr_line
		(start 396.024354 -126.334774)
		(end 396.108174 -126.334774)
		(stroke
			(width 0.05715)
			(type default)
		)
		(layer "In4.Cu")
	)
	(gr_line
		(start 396.028418 -132.192014)
		(end 396.057882 -132.19938)
		(stroke
			(width 0.05715)
			(type default)
		)
		(layer "In4.Cu")
	)
	(gr_line
		(start 396.041626 -131.527296)
		(end 396.07109 -131.534662)
		(stroke
			(width 0.05715)
			(type default)
		)
		(layer "In4.Cu")
	)
	(gr_line
		(start 396.237714 -125.877574)
		(end 396.400274 -126.040134)
		(stroke
			(width 0.05715)
			(type default)
		)
		(layer "In4.Cu")
	)
	(gr_line
		(start 396.248636 -10.472674)
		(end 396.439136 -10.601198)
		(stroke
			(width 0.05715)
			(type default)
		)
		(layer "In4.Cu")
	)
	(gr_line
		(start 396.872714 -10.81659)
		(end 396.892018 -10.813034)
		(stroke
			(width 0.05715)
			(type default)
		)
		(layer "In4.Cu")
	)
	(gr_line
		(start 396.892018 -10.813034)
		(end 396.909036 -10.801858)
		(stroke
			(width 0.05715)
			(type default)
		)
		(layer "In4.Cu")
	)
	(gr_line
		(start 397.128492 -3.176524)
		(end 397.364966 -3.176524)
		(stroke
			(width 0.05715)
			(type default)
		)
		(layer "In4.Cu")
	)
	(gr_line
		(start 397.189198 -8.240014)
		(end 397.205454 -8.229346)
		(stroke
			(width 0.05715)
			(type default)
		)
		(layer "In4.Cu")
	)
	(gr_line
		(start 397.205454 -8.229092)
		(end 397.205454 -8.229346)
		(stroke
			(width 0.05715)
			(type default)
		)
		(layer "In4.Cu")
	)
	(gr_line
		(start 397.205454 -8.229092)
		(end 397.22552 -8.225282)
		(stroke
			(width 0.05715)
			(type default)
		)
		(layer "In4.Cu")
	)
	(gr_line
		(start 397.364966 -3.176524)
		(end 397.474186 -3.285744)
		(stroke
			(width 0.05715)
			(type default)
		)
		(layer "In4.Cu")
	)
	(gr_line
		(start 397.567658 -132.214874)
		(end 397.625062 -132.229352)
		(stroke
			(width 0.05715)
			(type default)
		)
		(layer "In4.Cu")
	)
	(gr_line
		(start 397.625062 -132.229352)
		(end 397.679926 -132.206746)
		(stroke
			(width 0.05715)
			(type default)
		)
		(layer "In4.Cu")
	)
	(gr_line
		(start 397.64335 -132.901944)
		(end 397.701008 -132.916422)
		(stroke
			(width 0.05715)
			(type default)
		)
		(layer "In4.Cu")
	)
	(gr_line
		(start 397.696182 -133.58368)
		(end 397.754094 -133.598158)
		(stroke
			(width 0.05715)
			(type default)
		)
		(layer "In4.Cu")
	)
	(gr_line
		(start 397.701008 -132.916422)
		(end 397.755872 -132.893816)
		(stroke
			(width 0.05715)
			(type default)
		)
		(layer "In4.Cu")
	)
	(gr_line
		(start 397.754094 -133.598158)
		(end 397.808196 -133.575552)
		(stroke
			(width 0.05715)
			(type default)
		)
		(layer "In4.Cu")
	)
	(gr_line
		(start 397.884142 -134.299198)
		(end 397.941546 -134.313676)
		(stroke
			(width 0.05715)
			(type default)
		)
		(layer "In4.Cu")
	)
	(gr_line
		(start 397.890746 -3.285744)
		(end 397.999966 -3.176524)
		(stroke
			(width 0.05715)
			(type default)
		)
		(layer "In4.Cu")
	)
	(gr_line
		(start 397.924274 -6.62051)
		(end 397.953738 -6.610604)
		(stroke
			(width 0.05715)
			(type default)
		)
		(layer "In4.Cu")
	)
	(gr_line
		(start 397.941546 -134.313676)
		(end 397.99641 -134.29107)
		(stroke
			(width 0.05715)
			(type default)
		)
		(layer "In4.Cu")
	)
	(gr_line
		(start 397.956532 -10.103612)
		(end 397.97482 -10.09142)
		(stroke
			(width 0.05715)
			(type default)
		)
		(layer "In4.Cu")
	)
	(gr_line
		(start 397.999966 -3.176524)
		(end 398.144492 -3.176524)
		(stroke
			(width 0.05715)
			(type default)
		)
		(layer "In4.Cu")
	)
	(gr_line
		(start 398.043146 -8.359648)
		(end 398.063212 -8.355838)
		(stroke
			(width 0.05715)
			(type default)
		)
		(layer "In4.Cu")
	)
	(gr_line
		(start 398.063212 -8.355838)
		(end 398.080992 -8.344154)
		(stroke
			(width 0.05715)
			(type default)
		)
		(layer "In4.Cu")
	)
	(gr_line
		(start 398.4752 -8.8138)
		(end 398.493742 -8.801354)
		(stroke
			(width 0.05715)
			(type default)
		)
		(layer "In4.Cu")
	)
	(gr_line
		(start 398.824196 -11.099292)
		(end 398.843246 -11.095482)
		(stroke
			(width 0.05715)
			(type default)
		)
		(layer "In4.Cu")
	)
	(gr_line
		(start 398.843246 -11.095482)
		(end 398.859502 -11.084814)
		(stroke
			(width 0.05715)
			(type default)
		)
		(layer "In4.Cu")
	)
	(gr_line
		(start 398.976088 -6.933692)
		(end 399.004282 -6.92404)
		(stroke
			(width 0.05715)
			(type default)
		)
		(layer "In4.Cu")
	)
	(gr_line
		(start 399.554192 -3.176524)
		(end 399.776442 -3.176524)
		(stroke
			(width 0.05715)
			(type default)
		)
		(layer "In4.Cu")
	)
	(gr_line
		(start 399.776442 -3.176524)
		(end 399.856452 -3.256534)
		(stroke
			(width 0.05715)
			(type default)
		)
		(layer "In4.Cu")
	)
	(gr_line
		(start 400.135852 -5.145786)
		(end 400.135852 -5.37591)
		(stroke
			(width 0.05715)
			(type default)
		)
		(layer "In4.Cu")
	)
	(gr_line
		(start 400.135852 -5.145786)
		(end 400.378168 -4.90347)
		(stroke
			(width 0.05715)
			(type default)
		)
		(layer "In4.Cu")
	)
	(gr_line
		(start 400.273012 -3.256534)
		(end 400.353022 -3.176524)
		(stroke
			(width 0.05715)
			(type default)
		)
		(layer "In4.Cu")
	)
	(gr_line
		(start 400.353022 -3.176524)
		(end 400.570192 -3.176524)
		(stroke
			(width 0.05715)
			(type default)
		)
		(layer "In4.Cu")
	)
	(gr_line
		(start 400.378168 -4.90347)
		(end 400.608292 -4.90347)
		(stroke
			(width 0.05715)
			(type default)
		)
		(layer "In4.Cu")
	)
	(gr_line
		(start 400.473926 -9.23925)
		(end 400.518884 -9.465056)
		(stroke
			(width 0.05715)
			(type default)
		)
		(layer "In4.Cu")
	)
	(gr_line
		(start 400.473926 -9.23925)
		(end 400.663918 -8.954008)
		(stroke
			(width 0.05715)
			(type default)
		)
		(layer "In4.Cu")
	)
	(gr_line
		(start 400.54022 -9.96442)
		(end 400.552412 -9.946386)
		(stroke
			(width 0.05715)
			(type default)
		)
		(layer "In4.Cu")
	)
	(gr_line
		(start 400.550888 -5.377434)
		(end 400.609816 -5.318506)
		(stroke
			(width 0.05715)
			(type default)
		)
		(layer "In4.Cu")
	)
	(gr_line
		(start 400.663918 -8.954008)
		(end 400.889724 -8.90905)
		(stroke
			(width 0.05715)
			(type default)
		)
		(layer "In4.Cu")
	)
	(gr_line
		(start 400.783552 -9.599676)
		(end 401.115276 -9.101836)
		(stroke
			(width 0.05715)
			(type default)
		)
		(layer "In4.Cu")
	)
	(gr_line
		(start 400.854164 -4.578096)
		(end 400.854164 -4.6609)
		(stroke
			(width 0.05715)
			(type default)
		)
		(layer "In4.Cu")
	)
	(gr_line
		(start 400.854164 -4.427474)
		(end 400.854164 -4.573016)
		(stroke
			(width 0.05715)
			(type default)
		)
		(layer "In4.Cu")
	)
	(gr_line
		(start 400.854164 -4.427474)
		(end 401.096734 -4.184904)
		(stroke
			(width 0.05715)
			(type default)
		)
		(layer "In4.Cu")
	)
	(gr_line
		(start 401.060666 -4.867656)
		(end 401.06092 -4.867656)
		(stroke
			(width 0.05715)
			(type default)
		)
		(layer "In4.Cu")
	)
	(gr_line
		(start 401.096734 -4.184904)
		(end 401.327112 -4.184904)
		(stroke
			(width 0.05715)
			(type default)
		)
		(layer "In4.Cu")
	)
	(gr_line
		(start 401.240498 -7.321804)
		(end 401.25523 -7.311898)
		(stroke
			(width 0.05715)
			(type default)
		)
		(layer "In4.Cu")
	)
	(gr_line
		(start 401.25523 -7.311898)
		(end 401.265136 -7.297674)
		(stroke
			(width 0.05715)
			(type default)
		)
		(layer "In4.Cu")
	)
	(gr_line
		(start 401.2692 -4.659376)
		(end 401.328636 -4.59994)
		(stroke
			(width 0.05715)
			(type default)
		)
		(layer "In4.Cu")
	)
	(gr_line
		(start 401.827492 -2.88417)
		(end 402.202142 -2.88417)
		(stroke
			(width 0.05715)
			(type default)
		)
		(layer "In4.Cu")
	)
	(gr_line
		(start 402.202142 -2.88417)
		(end 402.254212 -2.93624)
		(stroke
			(width 0.05715)
			(type default)
		)
		(layer "In4.Cu")
	)
	(gr_line
		(start 402.493226 -5.018532)
		(end 402.527516 -4.969256)
		(stroke
			(width 0.05715)
			(type default)
		)
		(layer "In4.Cu")
	)
	(gr_line
		(start 402.527516 -4.969256)
		(end 402.583904 -4.949952)
		(stroke
			(width 0.05715)
			(type default)
		)
		(layer "In4.Cu")
	)
	(gr_line
		(start 402.670772 -2.93624)
		(end 402.722842 -2.88417)
		(stroke
			(width 0.05715)
			(type default)
		)
		(layer "In4.Cu")
	)
	(gr_line
		(start 402.722842 -2.88417)
		(end 403.097492 -2.88417)
		(stroke
			(width 0.05715)
			(type default)
		)
		(layer "In4.Cu")
	)
	(gr_line
		(start 402.854414 -3.632708)
		(end 402.913088 -3.574034)
		(stroke
			(width 0.05715)
			(type default)
		)
		(layer "In4.Cu")
	)
	(gr_line
		(start 403.154134 -5.516118)
		(end 403.190964 -5.461)
		(stroke
			(width 0.05715)
			(type default)
		)
		(layer "In4.Cu")
	)
	(gr_line
		(start 403.190964 -5.461)
		(end 403.253702 -5.441696)
		(stroke
			(width 0.05715)
			(type default)
		)
		(layer "In4.Cu")
	)
	(gr_line
		(start 403.22119 -55.948834)
		(end 403.250908 -55.948834)
		(stroke
			(width 0.05715)
			(type default)
		)
		(layer "In4.Cu")
	)
	(gr_line
		(start 403.51075 -56.10225)
		(end 403.540468 -56.10225)
		(stroke
			(width 0.05715)
			(type default)
		)
		(layer "In4.Cu")
	)
	(gr_line
		(start 404.329392 -2.897124)
		(end 404.564342 -2.897124)
		(stroke
			(width 0.05715)
			(type default)
		)
		(layer "In4.Cu")
	)
	(gr_line
		(start 404.564342 -2.897124)
		(end 404.616412 -2.949194)
		(stroke
			(width 0.05715)
			(type default)
		)
		(layer "In4.Cu")
	)
	(gr_line
		(start 404.889462 -140.45057)
		(end 404.908512 -140.45438)
		(stroke
			(width 0.05715)
			(type default)
		)
		(layer "In4.Cu")
	)
	(gr_line
		(start 404.908512 -140.45438)
		(end 404.92807 -140.450316)
		(stroke
			(width 0.05715)
			(type default)
		)
		(layer "In4.Cu")
	)
	(gr_line
		(start 405.032972 -2.949194)
		(end 405.085042 -2.897124)
		(stroke
			(width 0.05715)
			(type default)
		)
		(layer "In4.Cu")
	)
	(gr_line
		(start 405.085042 -2.897124)
		(end 405.345392 -2.897124)
		(stroke
			(width 0.05715)
			(type default)
		)
		(layer "In4.Cu")
	)
	(gr_line
		(start 405.367744 -139.694158)
		(end 405.386794 -139.697968)
		(stroke
			(width 0.05715)
			(type default)
		)
		(layer "In4.Cu")
	)
	(gr_line
		(start 405.386794 -139.697968)
		(end 405.406352 -139.693904)
		(stroke
			(width 0.05715)
			(type default)
		)
		(layer "In4.Cu")
	)
	(gr_line
		(start 405.387556 -138.331448)
		(end 405.406606 -138.335258)
		(stroke
			(width 0.05715)
			(type default)
		)
		(layer "In4.Cu")
	)
	(gr_line
		(start 405.395938 -139.023344)
		(end 405.414988 -139.027154)
		(stroke
			(width 0.05715)
			(type default)
		)
		(layer "In4.Cu")
	)
	(gr_line
		(start 405.406606 -138.335258)
		(end 405.426164 -138.331194)
		(stroke
			(width 0.05715)
			(type default)
		)
		(layer "In4.Cu")
	)
	(gr_line
		(start 405.414988 -139.027154)
		(end 405.434546 -139.02309)
		(stroke
			(width 0.05715)
			(type default)
		)
		(layer "In4.Cu")
	)
	(gr_line
		(start 405.73452 -125.835664)
		(end 405.95804 -125.612144)
		(stroke
			(width 0.05715)
			(type default)
		)
		(layer "In4.Cu")
	)
	(gr_line
		(start 406.222708 -50.08245)
		(end 406.281382 -50.14087)
		(stroke
			(width 0.05715)
			(type default)
		)
		(layer "In4.Cu")
	)
	(gr_line
		(start 406.3746 -125.612144)
		(end 406.59812 -125.835664)
		(stroke
			(width 0.05715)
			(type default)
		)
		(layer "In4.Cu")
	)
	(gr_line
		(start 406.628092 -2.88417)
		(end 406.977342 -2.88417)
		(stroke
			(width 0.05715)
			(type default)
		)
		(layer "In4.Cu")
	)
	(gr_line
		(start 406.634696 -126.944628)
		(end 406.656032 -126.93523)
		(stroke
			(width 0.05715)
			(type default)
		)
		(layer "In4.Cu")
	)
	(gr_line
		(start 406.977342 -2.88417)
		(end 407.039572 -2.9464)
		(stroke
			(width 0.05715)
			(type default)
		)
		(layer "In4.Cu")
	)
	(gr_line
		(start 407.096722 -3.715766)
		(end 407.149046 -3.697732)
		(stroke
			(width 0.05715)
			(type default)
		)
		(layer "In4.Cu")
	)
	(gr_line
		(start 407.149046 -3.697732)
		(end 407.18105 -3.653028)
		(stroke
			(width 0.05715)
			(type default)
		)
		(layer "In4.Cu")
	)
	(gr_line
		(start 407.351992 -3.413506)
		(end 407.383742 -3.36931)
		(stroke
			(width 0.05715)
			(type default)
		)
		(layer "In4.Cu")
	)
	(gr_line
		(start 407.448766 -51.718464)
		(end 407.50744 -51.776884)
		(stroke
			(width 0.05715)
			(type default)
		)
		(layer "In4.Cu")
	)
	(gr_line
		(start 407.456386 -2.9464)
		(end 407.518616 -2.88417)
		(stroke
			(width 0.05715)
			(type default)
		)
		(layer "In4.Cu")
	)
	(gr_line
		(start 407.518616 -2.88417)
		(end 407.898092 -2.88417)
		(stroke
			(width 0.05715)
			(type default)
		)
		(layer "In4.Cu")
	)
	(gr_line
		(start 407.710894 -129.951988)
		(end 407.758392 -129.93243)
		(stroke
			(width 0.05715)
			(type default)
		)
		(layer "In4.Cu")
	)
	(gr_line
		(start 407.758392 -129.93243)
		(end 407.809192 -129.94259)
		(stroke
			(width 0.05715)
			(type default)
		)
		(layer "In4.Cu")
	)
	(gr_line
		(start 407.823924 -126.420372)
		(end 407.840434 -126.413006)
		(stroke
			(width 0.05715)
			(type default)
		)
		(layer "In4.Cu")
	)
	(gr_line
		(start 408.079448 -137.801096)
		(end 408.104594 -137.796016)
		(stroke
			(width 0.05715)
			(type default)
		)
		(layer "In4.Cu")
	)
	(gr_line
		(start 408.104594 -137.796016)
		(end 408.124914 -137.781284)
		(stroke
			(width 0.05715)
			(type default)
		)
		(layer "In4.Cu")
	)
	(gr_line
		(start 408.31389 -138.44778)
		(end 408.339036 -138.4427)
		(stroke
			(width 0.05715)
			(type default)
		)
		(layer "In4.Cu")
	)
	(gr_line
		(start 408.339036 -138.4427)
		(end 408.359356 -138.427968)
		(stroke
			(width 0.05715)
			(type default)
		)
		(layer "In4.Cu")
	)
	(gr_line
		(start 408.58186 -139.059412)
		(end 408.607006 -139.054332)
		(stroke
			(width 0.05715)
			(type default)
		)
		(layer "In4.Cu")
	)
	(gr_line
		(start 408.607006 -139.054332)
		(end 408.627326 -139.0396)
		(stroke
			(width 0.05715)
			(type default)
		)
		(layer "In4.Cu")
	)
	(gr_line
		(start 408.861768 -139.66317)
		(end 408.886914 -139.658344)
		(stroke
			(width 0.05715)
			(type default)
		)
		(layer "In4.Cu")
	)
	(gr_line
		(start 408.886914 -139.658344)
		(end 408.90825 -139.643104)
		(stroke
			(width 0.05715)
			(type default)
		)
		(layer "In4.Cu")
	)
	(gr_line
		(start 408.897582 -1.37795)
		(end 409.096972 -1.37795)
		(stroke
			(width 0.05715)
			(type default)
		)
		(layer "In4.Cu")
	)
	(gr_line
		(start 409.096972 -1.378204)
		(end 409.283154 -1.564386)
		(stroke
			(width 0.05715)
			(type default)
		)
		(layer "In4.Cu")
	)
	(gr_line
		(start 409.096972 -1.37795)
		(end 409.096972 -1.378204)
		(stroke
			(width 0.05715)
			(type default)
		)
		(layer "In4.Cu")
	)
	(gr_line
		(start 409.166568 -3.930904)
		(end 409.201112 -3.920236)
		(stroke
			(width 0.05715)
			(type default)
		)
		(layer "In4.Cu")
	)
	(gr_line
		(start 409.427934 -127.238252)
		(end 409.447492 -127.234188)
		(stroke
			(width 0.05715)
			(type default)
		)
		(layer "In4.Cu")
	)
	(gr_line
		(start 409.447492 -127.234188)
		(end 409.46705 -127.238252)
		(stroke
			(width 0.05715)
			(type default)
		)
		(layer "In4.Cu")
	)
	(gr_line
		(start 409.449524 -124.803916)
		(end 409.454604 -124.79401)
		(stroke
			(width 0.05715)
			(type default)
		)
		(layer "In4.Cu")
	)
	(gr_line
		(start 409.468066 -127.90678)
		(end 409.487878 -127.902716)
		(stroke
			(width 0.05715)
			(type default)
		)
		(layer "In4.Cu")
	)
	(gr_line
		(start 409.475686 -128.565402)
		(end 409.495498 -128.561338)
		(stroke
			(width 0.05715)
			(type default)
		)
		(layer "In4.Cu")
	)
	(gr_line
		(start 409.487878 -127.902716)
		(end 409.507436 -127.90678)
		(stroke
			(width 0.05715)
			(type default)
		)
		(layer "In4.Cu")
	)
	(gr_line
		(start 409.495498 -128.561338)
		(end 409.515056 -128.565402)
		(stroke
			(width 0.05715)
			(type default)
		)
		(layer "In4.Cu")
	)
	(gr_line
		(start 409.615386 -123.819158)
		(end 409.620466 -123.809252)
		(stroke
			(width 0.05715)
			(type default)
		)
		(layer "In4.Cu")
	)
	(gr_line
		(start 409.620466 -123.809252)
		(end 409.62834 -123.801378)
		(stroke
			(width 0.05715)
			(type default)
		)
		(layer "In4.Cu")
	)
	(gr_line
		(start 409.699714 -1.564386)
		(end 409.88615 -1.37795)
		(stroke
			(width 0.05715)
			(type default)
		)
		(layer "In4.Cu")
	)
	(gr_line
		(start 409.766008 -136.247378)
		(end 409.78836 -136.231376)
		(stroke
			(width 0.05715)
			(type default)
		)
		(layer "In4.Cu")
	)
	(gr_line
		(start 409.78836 -136.231376)
		(end 409.815284 -136.226296)
		(stroke
			(width 0.05715)
			(type default)
		)
		(layer "In4.Cu")
	)
	(gr_line
		(start 409.83789 -123.591828)
		(end 409.896818 -123.5329)
		(stroke
			(width 0.05715)
			(type default)
		)
		(layer "In4.Cu")
	)
	(gr_line
		(start 409.88615 -1.37795)
		(end 410.167582 -1.37795)
		(stroke
			(width 0.05715)
			(type default)
		)
		(layer "In4.Cu")
	)
	(gr_line
		(start 409.974796 -130.673602)
		(end 410.007054 -130.680206)
		(stroke
			(width 0.05715)
			(type default)
		)
		(layer "In4.Cu")
	)
	(gr_line
		(start 410.007054 -130.680206)
		(end 410.039058 -130.671062)
		(stroke
			(width 0.05715)
			(type default)
		)
		(layer "In4.Cu")
	)
	(gr_line
		(start 410.023818 -128.306576)
		(end 410.043376 -128.31064)
		(stroke
			(width 0.05715)
			(type default)
		)
		(layer "In4.Cu")
	)
	(gr_line
		(start 410.02458 -127.646176)
		(end 410.044138 -127.65024)
		(stroke
			(width 0.05715)
			(type default)
		)
		(layer "In4.Cu")
	)
	(gr_line
		(start 410.031438 -128.965198)
		(end 410.05125 -128.969262)
		(stroke
			(width 0.05715)
			(type default)
		)
		(layer "In4.Cu")
	)
	(gr_line
		(start 410.043376 -128.31064)
		(end 410.063188 -128.306576)
		(stroke
			(width 0.05715)
			(type default)
		)
		(layer "In4.Cu")
	)
	(gr_line
		(start 410.044138 -127.65024)
		(end 410.06395 -127.646176)
		(stroke
			(width 0.05715)
			(type default)
		)
		(layer "In4.Cu")
	)
	(gr_line
		(start 410.05125 -128.969262)
		(end 410.070808 -128.965198)
		(stroke
			(width 0.05715)
			(type default)
		)
		(layer "In4.Cu")
	)
	(gr_line
		(start 410.060648 -136.851136)
		(end 410.083 -136.835134)
		(stroke
			(width 0.05715)
			(type default)
		)
		(layer "In4.Cu")
	)
	(gr_line
		(start 410.083 -136.835134)
		(end 410.109924 -136.830054)
		(stroke
			(width 0.05715)
			(type default)
		)
		(layer "In4.Cu")
	)
	(gr_line
		(start 410.335476 -137.457942)
		(end 410.356812 -137.442702)
		(stroke
			(width 0.05715)
			(type default)
		)
		(layer "In4.Cu")
	)
	(gr_line
		(start 410.356812 -137.442448)
		(end 410.356812 -137.442702)
		(stroke
			(width 0.05715)
			(type default)
		)
		(layer "In4.Cu")
	)
	(gr_line
		(start 410.356812 -137.442448)
		(end 410.383736 -137.437368)
		(stroke
			(width 0.05715)
			(type default)
		)
		(layer "In4.Cu")
	)
	(gr_line
		(start 410.521912 -127.917956)
		(end 410.542486 -127.913892)
		(stroke
			(width 0.05715)
			(type default)
		)
		(layer "In4.Cu")
	)
	(gr_line
		(start 410.522674 -127.25781)
		(end 410.542486 -127.253746)
		(stroke
			(width 0.05715)
			(type default)
		)
		(layer "In4.Cu")
	)
	(gr_line
		(start 410.522928 -128.578102)
		(end 410.542486 -128.574038)
		(stroke
			(width 0.05715)
			(type default)
		)
		(layer "In4.Cu")
	)
	(gr_line
		(start 410.542486 -128.574038)
		(end 410.562044 -128.578102)
		(stroke
			(width 0.05715)
			(type default)
		)
		(layer "In4.Cu")
	)
	(gr_line
		(start 410.542486 -127.913892)
		(end 410.561282 -127.917702)
		(stroke
			(width 0.05715)
			(type default)
		)
		(layer "In4.Cu")
	)
	(gr_line
		(start 410.542486 -127.253746)
		(end 410.562044 -127.25781)
		(stroke
			(width 0.05715)
			(type default)
		)
		(layer "In4.Cu")
	)
	(gr_line
		(start 410.609542 -138.066272)
		(end 410.631894 -138.05027)
		(stroke
			(width 0.05715)
			(type default)
		)
		(layer "In4.Cu")
	)
	(gr_line
		(start 410.631894 -138.05027)
		(end 410.658818 -138.04519)
		(stroke
			(width 0.05715)
			(type default)
		)
		(layer "In4.Cu")
	)
	(gr_line
		(start 410.668216 -130.185668)
		(end 410.719778 -130.170936)
		(stroke
			(width 0.05715)
			(type default)
		)
		(layer "In4.Cu")
	)
	(gr_line
		(start 410.719778 -130.170936)
		(end 410.77007 -130.187954)
		(stroke
			(width 0.05715)
			(type default)
		)
		(layer "In4.Cu")
	)
	(gr_line
		(start 411.022038 -128.966722)
		(end 411.041596 -128.970786)
		(stroke
			(width 0.05715)
			(type default)
		)
		(layer "In4.Cu")
	)
	(gr_line
		(start 411.02788 -128.307846)
		(end 411.047438 -128.31191)
		(stroke
			(width 0.05715)
			(type default)
		)
		(layer "In4.Cu")
	)
	(gr_line
		(start 411.041596 -128.970786)
		(end 411.061154 -128.966722)
		(stroke
			(width 0.05715)
			(type default)
		)
		(layer "In4.Cu")
	)
	(gr_line
		(start 411.045152 -127.651256)
		(end 411.06471 -127.65532)
		(stroke
			(width 0.05715)
			(type default)
		)
		(layer "In4.Cu")
	)
	(gr_line
		(start 411.047438 -128.31191)
		(end 411.066996 -128.307846)
		(stroke
			(width 0.05715)
			(type default)
		)
		(layer "In4.Cu")
	)
	(gr_line
		(start 411.06471 -127.65532)
		(end 411.084268 -127.651256)
		(stroke
			(width 0.05715)
			(type default)
		)
		(layer "In4.Cu")
	)
	(gr_line
		(start 411.550104 -50.847244)
		(end 411.712664 -50.684684)
		(stroke
			(width 0.05715)
			(type default)
		)
		(layer "In4.Cu")
	)
	(gr_line
		(start 411.634178 -55.82793)
		(end 411.796738 -55.66537)
		(stroke
			(width 0.05715)
			(type default)
		)
		(layer "In4.Cu")
	)
	(gr_line
		(start 411.712664 -50.684684)
		(end 412.055564 -50.684684)
		(stroke
			(width 0.05715)
			(type default)
		)
		(layer "In4.Cu")
	)
	(gr_line
		(start 411.796738 -55.66537)
		(end 412.139638 -55.66537)
		(stroke
			(width 0.05715)
			(type default)
		)
		(layer "In4.Cu")
	)
	(gr_line
		(start 411.842204 -51.141884)
		(end 411.926024 -51.141884)
		(stroke
			(width 0.05715)
			(type default)
		)
		(layer "In4.Cu")
	)
	(gr_line
		(start 411.926278 -56.12257)
		(end 412.010098 -56.12257)
		(stroke
			(width 0.05715)
			(type default)
		)
		(layer "In4.Cu")
	)
	(gr_line
		(start 412.055564 -50.684684)
		(end 412.218124 -50.847244)
		(stroke
			(width 0.05715)
			(type default)
		)
		(layer "In4.Cu")
	)
	(gr_line
		(start 412.139638 -55.66537)
		(end 412.302198 -55.82793)
		(stroke
			(width 0.05715)
			(type default)
		)
		(layer "In4.Cu")
	)
	(gr_line
		(start 412.566104 -50.847244)
		(end 412.728664 -50.684684)
		(stroke
			(width 0.05715)
			(type default)
		)
		(layer "In4.Cu")
	)
	(gr_line
		(start 412.728664 -50.684684)
		(end 413.071564 -50.684684)
		(stroke
			(width 0.05715)
			(type default)
		)
		(layer "In4.Cu")
	)
	(gr_line
		(start 412.858204 -51.141884)
		(end 412.942024 -51.141884)
		(stroke
			(width 0.05715)
			(type default)
		)
		(layer "In4.Cu")
	)
	(gr_line
		(start 412.930848 -131.223512)
		(end 412.999174 -131.246626)
		(stroke
			(width 0.05715)
			(type default)
		)
		(layer "In4.Cu")
	)
	(gr_line
		(start 412.999174 -131.246626)
		(end 413.065214 -131.218686)
		(stroke
			(width 0.05715)
			(type default)
		)
		(layer "In4.Cu")
	)
	(gr_line
		(start 413.071564 -50.684684)
		(end 413.234124 -50.847244)
		(stroke
			(width 0.05715)
			(type default)
		)
		(layer "In4.Cu")
	)
	(gr_line
		(start 413.519366 -137.506456)
		(end 413.556704 -137.499344)
		(stroke
			(width 0.05715)
			(type default)
		)
		(layer "In4.Cu")
	)
	(gr_line
		(start 413.556704 -137.499344)
		(end 413.592518 -137.511282)
		(stroke
			(width 0.05715)
			(type default)
		)
		(layer "In4.Cu")
	)
	(gr_line
		(start 413.560006 -136.839706)
		(end 413.597852 -136.832594)
		(stroke
			(width 0.05715)
			(type default)
		)
		(layer "In4.Cu")
	)
	(gr_line
		(start 413.597852 -136.832594)
		(end 413.634682 -136.844786)
		(stroke
			(width 0.05715)
			(type default)
		)
		(layer "In4.Cu")
	)
	(gr_line
		(start 413.60471 -136.172194)
		(end 413.642048 -136.165082)
		(stroke
			(width 0.05715)
			(type default)
		)
		(layer "In4.Cu")
	)
	(gr_line
		(start 413.618426 -48.08728)
		(end 413.780986 -47.92472)
		(stroke
			(width 0.05715)
			(type default)
		)
		(layer "In4.Cu")
	)
	(gr_line
		(start 413.642048 -136.165082)
		(end 413.678878 -136.177274)
		(stroke
			(width 0.05715)
			(type default)
		)
		(layer "In4.Cu")
	)
	(gr_line
		(start 413.64789 -135.504428)
		(end 413.685736 -135.497316)
		(stroke
			(width 0.05715)
			(type default)
		)
		(layer "In4.Cu")
	)
	(gr_line
		(start 413.685736 -135.497316)
		(end 413.72155 -135.509254)
		(stroke
			(width 0.05715)
			(type default)
		)
		(layer "In4.Cu")
	)
	(gr_line
		(start 413.780986 -47.92472)
		(end 414.123886 -47.92472)
		(stroke
			(width 0.05715)
			(type default)
		)
		(layer "In4.Cu")
	)
	(gr_line
		(start 413.83077 -126.509272)
		(end 413.875474 -126.490984)
		(stroke
			(width 0.05715)
			(type default)
		)
		(layer "In4.Cu")
	)
	(gr_line
		(start 413.875474 -126.490984)
		(end 413.923734 -126.500382)
		(stroke
			(width 0.05715)
			(type default)
		)
		(layer "In4.Cu")
	)
	(gr_line
		(start 413.894778 -127.182118)
		(end 413.939482 -127.16383)
		(stroke
			(width 0.05715)
			(type default)
		)
		(layer "In4.Cu")
	)
	(gr_line
		(start 413.910526 -48.38192)
		(end 413.994346 -48.38192)
		(stroke
			(width 0.05715)
			(type default)
		)
		(layer "In4.Cu")
	)
	(gr_line
		(start 413.939482 -127.16383)
		(end 413.987488 -127.173228)
		(stroke
			(width 0.05715)
			(type default)
		)
		(layer "In4.Cu")
	)
	(gr_line
		(start 413.965898 -127.85217)
		(end 414.010602 -127.833882)
		(stroke
			(width 0.05715)
			(type default)
		)
		(layer "In4.Cu")
	)
	(gr_line
		(start 414.010602 -127.833882)
		(end 414.058862 -127.84328)
		(stroke
			(width 0.05715)
			(type default)
		)
		(layer "In4.Cu")
	)
	(gr_line
		(start 414.123886 -47.92472)
		(end 414.286446 -48.08728)
		(stroke
			(width 0.05715)
			(type default)
		)
		(layer "In4.Cu")
	)
	(gr_line
		(start 414.568132 -127.586232)
		(end 414.58769 -127.590296)
		(stroke
			(width 0.05715)
			(type default)
		)
		(layer "In4.Cu")
	)
	(gr_line
		(start 414.569148 -126.925832)
		(end 414.588706 -126.929896)
		(stroke
			(width 0.05715)
			(type default)
		)
		(layer "In4.Cu")
	)
	(gr_line
		(start 414.579562 -128.244092)
		(end 414.59912 -128.248156)
		(stroke
			(width 0.05715)
			(type default)
		)
		(layer "In4.Cu")
	)
	(gr_line
		(start 414.58769 -127.590296)
		(end 414.607248 -127.586232)
		(stroke
			(width 0.05715)
			(type default)
		)
		(layer "In4.Cu")
	)
	(gr_line
		(start 414.588706 -126.929896)
		(end 414.608518 -126.925832)
		(stroke
			(width 0.05715)
			(type default)
		)
		(layer "In4.Cu")
	)
	(gr_line
		(start 414.59912 -128.248156)
		(end 414.618932 -128.244092)
		(stroke
			(width 0.05715)
			(type default)
		)
		(layer "In4.Cu")
	)
	(gr_line
		(start 414.634426 -48.08728)
		(end 414.796986 -47.92472)
		(stroke
			(width 0.05715)
			(type default)
		)
		(layer "In4.Cu")
	)
	(gr_line
		(start 414.796986 -47.92472)
		(end 415.139886 -47.92472)
		(stroke
			(width 0.05715)
			(type default)
		)
		(layer "In4.Cu")
	)
	(gr_line
		(start 414.926526 -48.38192)
		(end 415.010346 -48.38192)
		(stroke
			(width 0.05715)
			(type default)
		)
		(layer "In4.Cu")
	)
	(gr_line
		(start 415.068004 -127.857504)
		(end 415.088578 -127.85344)
		(stroke
			(width 0.05715)
			(type default)
		)
		(layer "In4.Cu")
	)
	(gr_line
		(start 415.071814 -127.196596)
		(end 415.092388 -127.192532)
		(stroke
			(width 0.05715)
			(type default)
		)
		(layer "In4.Cu")
	)
	(gr_line
		(start 415.075624 -126.535688)
		(end 415.096198 -126.531624)
		(stroke
			(width 0.05715)
			(type default)
		)
		(layer "In4.Cu")
	)
	(gr_line
		(start 415.088578 -127.85344)
		(end 415.10966 -127.857758)
		(stroke
			(width 0.05715)
			(type default)
		)
		(layer "In4.Cu")
	)
	(gr_line
		(start 415.092388 -127.192532)
		(end 415.113724 -127.19685)
		(stroke
			(width 0.05715)
			(type default)
		)
		(layer "In4.Cu")
	)
	(gr_line
		(start 415.096198 -126.531624)
		(end 415.117534 -126.535942)
		(stroke
			(width 0.05715)
			(type default)
		)
		(layer "In4.Cu")
	)
	(gr_line
		(start 415.139886 -47.92472)
		(end 415.302446 -48.08728)
		(stroke
			(width 0.05715)
			(type default)
		)
		(layer "In4.Cu")
	)
	(gr_line
		(start 415.809684 -138.553698)
		(end 415.847276 -138.566144)
		(stroke
			(width 0.05715)
			(type default)
		)
		(layer "In4.Cu")
	)
	(gr_line
		(start 415.847276 -138.566144)
		(end 415.886646 -138.558016)
		(stroke
			(width 0.05715)
			(type default)
		)
		(layer "In4.Cu")
	)
	(gr_line
		(start 415.848546 -137.88644)
		(end 415.886138 -137.898886)
		(stroke
			(width 0.05715)
			(type default)
		)
		(layer "In4.Cu")
	)
	(gr_line
		(start 415.882328 -137.215118)
		(end 415.91992 -137.227564)
		(stroke
			(width 0.05715)
			(type default)
		)
		(layer "In4.Cu")
	)
	(gr_line
		(start 415.886138 -137.898886)
		(end 415.925254 -137.890758)
		(stroke
			(width 0.05715)
			(type default)
		)
		(layer "In4.Cu")
	)
	(gr_line
		(start 415.918396 -136.545066)
		(end 415.958274 -136.558274)
		(stroke
			(width 0.05715)
			(type default)
		)
		(layer "In4.Cu")
	)
	(gr_line
		(start 415.91992 -137.227818)
		(end 415.960814 -137.219182)
		(stroke
			(width 0.05715)
			(type default)
		)
		(layer "In4.Cu")
	)
	(gr_line
		(start 415.91992 -137.227564)
		(end 415.91992 -137.227818)
		(stroke
			(width 0.05715)
			(type default)
		)
		(layer "In4.Cu")
	)
	(gr_line
		(start 415.958274 -136.558274)
		(end 415.999168 -136.549638)
		(stroke
			(width 0.05715)
			(type default)
		)
		(layer "In4.Cu")
	)
	(gr_line
		(start 416.020758 -127.685038)
		(end 416.051492 -127.691388)
		(stroke
			(width 0.05715)
			(type default)
		)
		(layer "In4.Cu")
	)
	(gr_line
		(start 416.020758 -127.023368)
		(end 416.051492 -127.029718)
		(stroke
			(width 0.05715)
			(type default)
		)
		(layer "In4.Cu")
	)
	(gr_line
		(start 416.051492 -127.691388)
		(end 416.081718 -127.68326)
		(stroke
			(width 0.05715)
			(type default)
		)
		(layer "In4.Cu")
	)
	(gr_line
		(start 416.051492 -127.029718)
		(end 416.081718 -127.02159)
		(stroke
			(width 0.05715)
			(type default)
		)
		(layer "In4.Cu")
	)
	(gr_line
		(start 416.059874 -128.35509)
		(end 416.092132 -128.361948)
		(stroke
			(width 0.05715)
			(type default)
		)
		(layer "In4.Cu")
	)
	(gr_line
		(start 416.092132 -128.361948)
		(end 416.12439 -128.353312)
		(stroke
			(width 0.05715)
			(type default)
		)
		(layer "In4.Cu")
	)
	(gr_line
		(start 417.858956 -136.161526)
		(end 417.867084 -136.159748)
		(stroke
			(width 0.05715)
			(type default)
		)
		(layer "In4.Cu")
	)
	(gr_line
		(start 417.867084 -136.159748)
		(end 417.873942 -136.155938)
		(stroke
			(width 0.05715)
			(type default)
		)
		(layer "In4.Cu")
	)
	(gr_line
		(start 417.98875 -128.823974)
		(end 418.007292 -128.8161)
		(stroke
			(width 0.05715)
			(type default)
		)
		(layer "In4.Cu")
	)
	(gr_line
		(start 418.051234 -136.783318)
		(end 418.059362 -136.78154)
		(stroke
			(width 0.05715)
			(type default)
		)
		(layer "In4.Cu")
	)
	(gr_line
		(start 418.059362 -136.78154)
		(end 418.06622 -136.777476)
		(stroke
			(width 0.05715)
			(type default)
		)
		(layer "In4.Cu")
	)
	(gr_line
		(start 418.31387 -137.39241)
		(end 418.321998 -137.390632)
		(stroke
			(width 0.05715)
			(type default)
		)
		(layer "In4.Cu")
	)
	(gr_line
		(start 418.321998 -137.390632)
		(end 418.328856 -137.386568)
		(stroke
			(width 0.05715)
			(type default)
		)
		(layer "In4.Cu")
	)
	(gr_line
		(start 418.57422 -137.997438)
		(end 418.582348 -137.99566)
		(stroke
			(width 0.05715)
			(type default)
		)
		(layer "In4.Cu")
	)
	(gr_line
		(start 418.582348 -137.99566)
		(end 418.589206 -137.991596)
		(stroke
			(width 0.05715)
			(type default)
		)
		(layer "In4.Cu")
	)
	(gr_line
		(start 418.654992 -135.715248)
		(end 418.685726 -135.697722)
		(stroke
			(width 0.05715)
			(type default)
		)
		(layer "In4.Cu")
	)
	(gr_line
		(start 418.685726 -135.697722)
		(end 418.705538 -135.666734)
		(stroke
			(width 0.05715)
			(type default)
		)
		(layer "In4.Cu")
	)
	(gr_line
		(start 418.71011 -126.67107)
		(end 418.739828 -126.663196)
		(stroke
			(width 0.05715)
			(type default)
		)
		(layer "In4.Cu")
	)
	(gr_line
		(start 418.710618 -127.352298)
		(end 418.744654 -127.343154)
		(stroke
			(width 0.05715)
			(type default)
		)
		(layer "In4.Cu")
	)
	(gr_line
		(start 418.720016 -126.006606)
		(end 418.749734 -125.998732)
		(stroke
			(width 0.05715)
			(type default)
		)
		(layer "In4.Cu")
	)
	(gr_line
		(start 418.739828 -126.663196)
		(end 418.769546 -126.669292)
		(stroke
			(width 0.05715)
			(type default)
		)
		(layer "In4.Cu")
	)
	(gr_line
		(start 418.744654 -127.343154)
		(end 418.779198 -127.351282)
		(stroke
			(width 0.05715)
			(type default)
		)
		(layer "In4.Cu")
	)
	(gr_line
		(start 418.749734 -125.998732)
		(end 418.779452 -126.004828)
		(stroke
			(width 0.05715)
			(type default)
		)
		(layer "In4.Cu")
	)
	(gr_line
		(start 419.127432 -136.178798)
		(end 419.158928 -136.161018)
		(stroke
			(width 0.05715)
			(type default)
		)
		(layer "In4.Cu")
	)
	(gr_line
		(start 419.158928 -136.161018)
		(end 419.178486 -136.130538)
		(stroke
			(width 0.05715)
			(type default)
		)
		(layer "In4.Cu")
	)
	(gr_line
		(start 419.572694 -136.684512)
		(end 419.60419 -136.666732)
		(stroke
			(width 0.05715)
			(type default)
		)
		(layer "In4.Cu")
	)
	(gr_line
		(start 419.60419 -136.666732)
		(end 419.623748 -136.636252)
		(stroke
			(width 0.05715)
			(type default)
		)
		(layer "In4.Cu")
	)
	(gr_line
		(start 420.023798 -137.181844)
		(end 420.055294 -137.164064)
		(stroke
			(width 0.05715)
			(type default)
		)
		(layer "In4.Cu")
	)
	(gr_line
		(start 420.055294 -137.164064)
		(end 420.074852 -137.133584)
		(stroke
			(width 0.05715)
			(type default)
		)
		(layer "In4.Cu")
	)
	(gr_line
		(start 420.26332 -132.678424)
		(end 420.271702 -132.66547)
		(stroke
			(width 0.05715)
			(type default)
		)
		(layer "In4.Cu")
	)
	(gr_line
		(start 420.271702 -132.66547)
		(end 420.284148 -132.655818)
		(stroke
			(width 0.05715)
			(type default)
		)
		(layer "In4.Cu")
	)
	(gr_line
		(start 420.747952 -133.123686)
		(end 420.756334 -133.110732)
		(stroke
			(width 0.05715)
			(type default)
		)
		(layer "In4.Cu")
	)
	(gr_line
		(start 420.756334 -133.110732)
		(end 420.76878 -133.10108)
		(stroke
			(width 0.05715)
			(type default)
		)
		(layer "In4.Cu")
	)
	(gr_line
		(start 421.2336 -133.56717)
		(end 421.240712 -133.55574)
		(stroke
			(width 0.05715)
			(type default)
		)
		(layer "In4.Cu")
	)
	(gr_line
		(start 421.240712 -133.55574)
		(end 421.251634 -133.547358)
		(stroke
			(width 0.05715)
			(type default)
		)
		(layer "In4.Cu")
	)
	(gr_line
		(start 421.719502 -134.00913)
		(end 421.727884 -133.996176)
		(stroke
			(width 0.05715)
			(type default)
		)
		(layer "In4.Cu")
	)
	(gr_line
		(start 421.727884 -133.996176)
		(end 421.74033 -133.986524)
		(stroke
			(width 0.05715)
			(type default)
		)
		(layer "In4.Cu")
	)
	(gr_line
		(start 421.90416 -128.8161)
		(end 421.908478 -128.81737)
		(stroke
			(width 0.05715)
			(type default)
		)
		(layer "In4.Cu")
	)
	(gr_line
		(start 422.453054 -130.998214)
		(end 422.465754 -130.988562)
		(stroke
			(width 0.05715)
			(type default)
		)
		(layer "In4.Cu")
	)
	(gr_line
		(start 422.465754 -130.988562)
		(end 422.481248 -130.98399)
		(stroke
			(width 0.05715)
			(type default)
		)
		(layer "In4.Cu")
	)
	(gr_line
		(start 422.750488 -131.58597)
		(end 422.763188 -131.576318)
		(stroke
			(width 0.05715)
			(type default)
		)
		(layer "In4.Cu")
	)
	(gr_line
		(start 422.763188 -131.576318)
		(end 422.778682 -131.571746)
		(stroke
			(width 0.05715)
			(type default)
		)
		(layer "In4.Cu")
	)
	(gr_line
		(start 423.047414 -132.17398)
		(end 423.060368 -132.164074)
		(stroke
			(width 0.05715)
			(type default)
		)
		(layer "In4.Cu")
	)
	(gr_line
		(start 423.060368 -132.164074)
		(end 423.076624 -132.159248)
		(stroke
			(width 0.05715)
			(type default)
		)
		(layer "In4.Cu")
	)
	(gr_line
		(start 423.341292 -132.762752)
		(end 423.353992 -132.7531)
		(stroke
			(width 0.05715)
			(type default)
		)
		(layer "In4.Cu")
	)
	(gr_line
		(start 423.353992 -132.7531)
		(end 423.369486 -132.748528)
		(stroke
			(width 0.05715)
			(type default)
		)
		(layer "In4.Cu")
	)
	(gr_line
		(start 424.382692 -129.86131)
		(end 424.422062 -129.872994)
		(stroke
			(width 0.05715)
			(type default)
		)
		(layer "In4.Cu")
	)
	(gr_line
		(start 424.422062 -129.872994)
		(end 424.461686 -129.863342)
		(stroke
			(width 0.05715)
			(type default)
		)
		(layer "In4.Cu")
	)
	(gr_line
		(start 424.495468 -129.168652)
		(end 424.534838 -129.180336)
		(stroke
			(width 0.05715)
			(type default)
		)
		(layer "In4.Cu")
	)
	(gr_line
		(start 424.51401 -128.497838)
		(end 424.55338 -128.509522)
		(stroke
			(width 0.05715)
			(type default)
		)
		(layer "In4.Cu")
	)
	(gr_line
		(start 424.532552 -127.827532)
		(end 424.571922 -127.839216)
		(stroke
			(width 0.05715)
			(type default)
		)
		(layer "In4.Cu")
	)
	(gr_line
		(start 424.534838 -129.180336)
		(end 424.574462 -129.170684)
		(stroke
			(width 0.05715)
			(type default)
		)
		(layer "In4.Cu")
	)
	(gr_line
		(start 424.55338 -128.509522)
		(end 424.593004 -128.49987)
		(stroke
			(width 0.05715)
			(type default)
		)
		(layer "In4.Cu")
	)
	(gr_line
		(start 424.571922 -127.839216)
		(end 424.611546 -127.829564)
		(stroke
			(width 0.05715)
			(type default)
		)
		(layer "In4.Cu")
	)
	(gr_line
		(start 425.211494 -127.686308)
		(end 425.29379 -127.666496)
		(stroke
			(width 0.05715)
			(type default)
		)
		(layer "In4.Cu")
	)
	(gr_line
		(start 425.29379 -127.666496)
		(end 425.337224 -127.595122)
		(stroke
			(width 0.05715)
			(type default)
		)
		(layer "In4.Cu")
	)
	(gr_line
		(start 425.59351 -131.422902)
		(end 425.627038 -131.412996)
		(stroke
			(width 0.05715)
			(type default)
		)
		(layer "In4.Cu")
	)
	(gr_line
		(start 425.600114 -130.071622)
		(end 425.633642 -130.061716)
		(stroke
			(width 0.05715)
			(type default)
		)
		(layer "In4.Cu")
	)
	(gr_line
		(start 425.604178 -130.74523)
		(end 425.637706 -130.735324)
		(stroke
			(width 0.05715)
			(type default)
		)
		(layer "In4.Cu")
	)
	(gr_line
		(start 425.627038 -131.412996)
		(end 425.661328 -131.420108)
		(stroke
			(width 0.05715)
			(type default)
		)
		(layer "In4.Cu")
	)
	(gr_line
		(start 425.627038 -128.252982)
		(end 425.707556 -128.233678)
		(stroke
			(width 0.05715)
			(type default)
		)
		(layer "In4.Cu")
	)
	(gr_line
		(start 425.633642 -130.061716)
		(end 425.667932 -130.068828)
		(stroke
			(width 0.05715)
			(type default)
		)
		(layer "In4.Cu")
	)
	(gr_line
		(start 425.637706 -130.735324)
		(end 425.67225 -130.742436)
		(stroke
			(width 0.05715)
			(type default)
		)
		(layer "In4.Cu")
	)
	(gr_line
		(start 425.6405 -132.084064)
		(end 425.67606 -132.07365)
		(stroke
			(width 0.05715)
			(type default)
		)
		(layer "In4.Cu")
	)
	(gr_line
		(start 425.67606 -132.07365)
		(end 425.712128 -132.08127)
		(stroke
			(width 0.05715)
			(type default)
		)
		(layer "In4.Cu")
	)
	(gr_line
		(start 425.707556 -128.233678)
		(end 425.750482 -128.162812)
		(stroke
			(width 0.05715)
			(type default)
		)
		(layer "In4.Cu")
	)
	(gr_line
		(start 426.039026 -128.820418)
		(end 426.120306 -128.80086)
		(stroke
			(width 0.05715)
			(type default)
		)
		(layer "In4.Cu")
	)
	(gr_line
		(start 426.120306 -128.80086)
		(end 426.163232 -128.729994)
		(stroke
			(width 0.05715)
			(type default)
		)
		(layer "In4.Cu")
	)
	(gr_line
		(start 426.453046 -129.387092)
		(end 426.53331 -129.368042)
		(stroke
			(width 0.05715)
			(type default)
		)
		(layer "In4.Cu")
	)
	(gr_line
		(start 426.53331 -129.368042)
		(end 426.576236 -129.297176)
		(stroke
			(width 0.05715)
			(type default)
		)
		(layer "In4.Cu")
	)
	(gr_line
		(start 426.902118 -125.706632)
		(end 426.917104 -125.681994)
		(stroke
			(width 0.05715)
			(type default)
		)
		(layer "In4.Cu")
	)
	(gr_line
		(start 426.917104 -125.681994)
		(end 426.941234 -125.665992)
		(stroke
			(width 0.05715)
			(type default)
		)
		(layer "In4.Cu")
	)
	(gr_line
		(start 427.067472 -47.647098)
		(end 427.067472 -47.877222)
		(stroke
			(width 0.05715)
			(type default)
		)
		(layer "In4.Cu")
	)
	(gr_line
		(start 427.067472 -47.647098)
		(end 427.309788 -47.404782)
		(stroke
			(width 0.05715)
			(type default)
		)
		(layer "In4.Cu")
	)
	(gr_line
		(start 427.228508 -130.695954)
		(end 427.282356 -130.707384)
		(stroke
			(width 0.05715)
			(type default)
		)
		(layer "In4.Cu")
	)
	(gr_line
		(start 427.277784 -131.379468)
		(end 427.331632 -131.390898)
		(stroke
			(width 0.05715)
			(type default)
		)
		(layer "In4.Cu")
	)
	(gr_line
		(start 427.282356 -130.707384)
		(end 427.332902 -130.685794)
		(stroke
			(width 0.05715)
			(type default)
		)
		(layer "In4.Cu")
	)
	(gr_line
		(start 427.309788 -47.404782)
		(end 427.539912 -47.404782)
		(stroke
			(width 0.05715)
			(type default)
		)
		(layer "In4.Cu")
	)
	(gr_line
		(start 427.318424 -132.067046)
		(end 427.370748 -132.077968)
		(stroke
			(width 0.05715)
			(type default)
		)
		(layer "In4.Cu")
	)
	(gr_line
		(start 427.331632 -131.390898)
		(end 427.382178 -131.369308)
		(stroke
			(width 0.05715)
			(type default)
		)
		(layer "In4.Cu")
	)
	(gr_line
		(start 427.370748 -132.077968)
		(end 427.419516 -132.05714)
		(stroke
			(width 0.05715)
			(type default)
		)
		(layer "In4.Cu")
	)
	(gr_line
		(start 427.37151 -126.180596)
		(end 427.386496 -126.155958)
		(stroke
			(width 0.05715)
			(type default)
		)
		(layer "In4.Cu")
	)
	(gr_line
		(start 427.386496 -126.155958)
		(end 427.410626 -126.139956)
		(stroke
			(width 0.05715)
			(type default)
		)
		(layer "In4.Cu")
	)
	(gr_line
		(start 427.40072 -132.736082)
		(end 427.454568 -132.747512)
		(stroke
			(width 0.05715)
			(type default)
		)
		(layer "In4.Cu")
	)
	(gr_line
		(start 427.454568 -132.747512)
		(end 427.505114 -132.725922)
		(stroke
			(width 0.05715)
			(type default)
		)
		(layer "In4.Cu")
	)
	(gr_line
		(start 427.482508 -47.878746)
		(end 427.541436 -47.819818)
		(stroke
			(width 0.05715)
			(type default)
		)
		(layer "In4.Cu")
	)
	(gr_line
		(start 427.574456 -122.587004)
		(end 427.598586 -122.525536)
		(stroke
			(width 0.05715)
			(type default)
		)
		(layer "In4.Cu")
	)
	(gr_line
		(start 427.598586 -122.525536)
		(end 427.655736 -122.493278)
		(stroke
			(width 0.05715)
			(type default)
		)
		(layer "In4.Cu")
	)
	(gr_line
		(start 427.735492 -125.142752)
		(end 427.745144 -125.136402)
		(stroke
			(width 0.05715)
			(type default)
		)
		(layer "In4.Cu")
	)
	(gr_line
		(start 427.745144 -125.136402)
		(end 427.75632 -125.133354)
		(stroke
			(width 0.05715)
			(type default)
		)
		(layer "In4.Cu")
	)
	(gr_line
		(start 427.839378 -126.657862)
		(end 427.854364 -126.633224)
		(stroke
			(width 0.05715)
			(type default)
		)
		(layer "In4.Cu")
	)
	(gr_line
		(start 427.854364 -126.633224)
		(end 427.878494 -126.617222)
		(stroke
			(width 0.05715)
			(type default)
		)
		(layer "In4.Cu")
	)
	(gr_line
		(start 428.046388 -125.721618)
		(end 428.055278 -125.715776)
		(stroke
			(width 0.05715)
			(type default)
		)
		(layer "In4.Cu")
	)
	(gr_line
		(start 428.055278 -125.715776)
		(end 428.065692 -125.712982)
		(stroke
			(width 0.05715)
			(type default)
		)
		(layer "In4.Cu")
	)
	(gr_line
		(start 428.09795 -130.359404)
		(end 428.139098 -130.341878)
		(stroke
			(width 0.05715)
			(type default)
		)
		(layer "In4.Cu")
	)
	(gr_line
		(start 428.139098 -130.341878)
		(end 428.16526 -130.305302)
		(stroke
			(width 0.05715)
			(type default)
		)
		(layer "In4.Cu")
	)
	(gr_line
		(start 428.342552 -126.31166)
		(end 428.351696 -126.305818)
		(stroke
			(width 0.05715)
			(type default)
		)
		(layer "In4.Cu")
	)
	(gr_line
		(start 428.351696 -126.305818)
		(end 428.36211 -126.303024)
		(stroke
			(width 0.05715)
			(type default)
		)
		(layer "In4.Cu")
	)
	(gr_line
		(start 428.518574 -130.884422)
		(end 428.559722 -130.866896)
		(stroke
			(width 0.05715)
			(type default)
		)
		(layer "In4.Cu")
	)
	(gr_line
		(start 428.559722 -130.866896)
		(end 428.585884 -130.83032)
		(stroke
			(width 0.05715)
			(type default)
		)
		(layer "In4.Cu")
	)
	(gr_line
		(start 428.65167 -129.128012)
		(end 428.670466 -129.102104)
		(stroke
			(width 0.05715)
			(type default)
		)
		(layer "In4.Cu")
	)
	(gr_line
		(start 428.670466 -129.102104)
		(end 428.69866 -129.087118)
		(stroke
			(width 0.05715)
			(type default)
		)
		(layer "In4.Cu")
	)
	(gr_line
		(start 428.752508 -121.870978)
		(end 428.813976 -121.835926)
		(stroke
			(width 0.05715)
			(type default)
		)
		(layer "In4.Cu")
	)
	(gr_line
		(start 428.813976 -121.835926)
		(end 428.883064 -121.849896)
		(stroke
			(width 0.05715)
			(type default)
		)
		(layer "In4.Cu")
	)
	(gr_line
		(start 428.938436 -131.409694)
		(end 428.980092 -131.391914)
		(stroke
			(width 0.05715)
			(type default)
		)
		(layer "In4.Cu")
	)
	(gr_line
		(start 428.980092 -131.391914)
		(end 429.006254 -131.355338)
		(stroke
			(width 0.05715)
			(type default)
		)
		(layer "In4.Cu")
	)
	(gr_line
		(start 429.089566 -129.6289)
		(end 429.108362 -129.602992)
		(stroke
			(width 0.05715)
			(type default)
		)
		(layer "In4.Cu")
	)
	(gr_line
		(start 429.108362 -129.602992)
		(end 429.136556 -129.588006)
		(stroke
			(width 0.05715)
			(type default)
		)
		(layer "In4.Cu")
	)
	(gr_line
		(start 429.518318 -125.998478)
		(end 429.549052 -125.99035)
		(stroke
			(width 0.05715)
			(type default)
		)
		(layer "In4.Cu")
	)
	(gr_line
		(start 429.527208 -130.129788)
		(end 429.546004 -130.10388)
		(stroke
			(width 0.05715)
			(type default)
		)
		(layer "In4.Cu")
	)
	(gr_line
		(start 429.546004 -130.10388)
		(end 429.574198 -130.088894)
		(stroke
			(width 0.05715)
			(type default)
		)
		(layer "In4.Cu")
	)
	(gr_line
		(start 429.549052 -125.99035)
		(end 429.580802 -125.997208)
		(stroke
			(width 0.05715)
			(type default)
		)
		(layer "In4.Cu")
	)
	(gr_line
		(start 429.56353 -125.31852)
		(end 429.594264 -125.310392)
		(stroke
			(width 0.05715)
			(type default)
		)
		(layer "In4.Cu")
	)
	(gr_line
		(start 429.56988 -124.656342)
		(end 429.600614 -124.648214)
		(stroke
			(width 0.05715)
			(type default)
		)
		(layer "In4.Cu")
	)
	(gr_line
		(start 429.594264 -125.310392)
		(end 429.626014 -125.31725)
		(stroke
			(width 0.05715)
			(type default)
		)
		(layer "In4.Cu")
	)
	(gr_line
		(start 429.600614 -124.648214)
		(end 429.632364 -124.655072)
		(stroke
			(width 0.05715)
			(type default)
		)
		(layer "In4.Cu")
	)
	(gr_line
		(start 430.26711 -122.423682)
		(end 430.301908 -122.430794)
		(stroke
			(width 0.05715)
			(type default)
		)
		(layer "In4.Cu")
	)
	(gr_line
		(start 430.301908 -122.430794)
		(end 430.335944 -122.42038)
		(stroke
			(width 0.05715)
			(type default)
		)
		(layer "In4.Cu")
	)
	(gr_line
		(start 430.504092 -131.128262)
		(end 430.552352 -131.107688)
		(stroke
			(width 0.05715)
			(type default)
		)
		(layer "In4.Cu")
	)
	(gr_line
		(start 430.537112 -126.505462)
		(end 430.567592 -126.512066)
		(stroke
			(width 0.05715)
			(type default)
		)
		(layer "In4.Cu")
	)
	(gr_line
		(start 430.552352 -131.107688)
		(end 430.603914 -131.118102)
		(stroke
			(width 0.05715)
			(type default)
		)
		(layer "In4.Cu")
	)
	(gr_line
		(start 430.567592 -126.512066)
		(end 430.59731 -126.504446)
		(stroke
			(width 0.05715)
			(type default)
		)
		(layer "In4.Cu")
	)
	(gr_line
		(start 430.591468 -125.164342)
		(end 430.621694 -125.170946)
		(stroke
			(width 0.05715)
			(type default)
		)
		(layer "In4.Cu")
	)
	(gr_line
		(start 430.59985 -125.829822)
		(end 430.63033 -125.836426)
		(stroke
			(width 0.05715)
			(type default)
		)
		(layer "In4.Cu")
	)
	(gr_line
		(start 430.621694 -125.170946)
		(end 430.65192 -125.163326)
		(stroke
			(width 0.05715)
			(type default)
		)
		(layer "In4.Cu")
	)
	(gr_line
		(start 430.63033 -125.836426)
		(end 430.65954 -125.828806)
		(stroke
			(width 0.05715)
			(type default)
		)
		(layer "In4.Cu")
	)
	(gr_line
		(start 431.228246 -55.776114)
		(end 431.390806 -55.613554)
		(stroke
			(width 0.05715)
			(type default)
		)
		(layer "In4.Cu")
	)
	(gr_line
		(start 431.390806 -55.613554)
		(end 431.733706 -55.613554)
		(stroke
			(width 0.05715)
			(type default)
		)
		(layer "In4.Cu")
	)
	(gr_line
		(start 431.461926 -127.996188)
		(end 431.49139 -127.988568)
		(stroke
			(width 0.05715)
			(type default)
		)
		(layer "In4.Cu")
	)
	(gr_line
		(start 431.49139 -127.988568)
		(end 431.521108 -127.994664)
		(stroke
			(width 0.05715)
			(type default)
		)
		(layer "In4.Cu")
	)
	(gr_line
		(start 431.498248 -128.656334)
		(end 431.527712 -128.648714)
		(stroke
			(width 0.05715)
			(type default)
		)
		(layer "In4.Cu")
	)
	(gr_line
		(start 431.519838 -129.320798)
		(end 431.549048 -129.313178)
		(stroke
			(width 0.05715)
			(type default)
		)
		(layer "In4.Cu")
	)
	(gr_line
		(start 431.520346 -56.070754)
		(end 431.604166 -56.070754)
		(stroke
			(width 0.05715)
			(type default)
		)
		(layer "In4.Cu")
	)
	(gr_line
		(start 431.527712 -128.648714)
		(end 431.55743 -128.65481)
		(stroke
			(width 0.05715)
			(type default)
		)
		(layer "In4.Cu")
	)
	(gr_line
		(start 431.549048 -129.313178)
		(end 431.57902 -129.319274)
		(stroke
			(width 0.05715)
			(type default)
		)
		(layer "In4.Cu")
	)
	(gr_line
		(start 431.681382 -140.51915)
		(end 431.833782 -140.36675)
		(stroke
			(width 0.05715)
			(type default)
		)
		(layer "In4.Cu")
	)
	(gr_line
		(start 431.733706 -55.613554)
		(end 431.896266 -55.776114)
		(stroke
			(width 0.05715)
			(type default)
		)
		(layer "In4.Cu")
	)
	(gr_line
		(start 431.833782 -140.36675)
		(end 432.176682 -140.36675)
		(stroke
			(width 0.05715)
			(type default)
		)
		(layer "In4.Cu")
	)
	(gr_line
		(start 431.973482 -140.82395)
		(end 432.036982 -140.82395)
		(stroke
			(width 0.05715)
			(type default)
		)
		(layer "In4.Cu")
	)
	(gr_line
		(start 432.048412 -121.589038)
		(end 432.089052 -121.576592)
		(stroke
			(width 0.05715)
			(type default)
		)
		(layer "In4.Cu")
	)
	(gr_line
		(start 432.089052 -121.576592)
		(end 432.130708 -121.586752)
		(stroke
			(width 0.05715)
			(type default)
		)
		(layer "In4.Cu")
	)
	(gr_line
		(start 432.152298 -124.779278)
		(end 432.15687 -124.778008)
		(stroke
			(width 0.05715)
			(type default)
		)
		(layer "In4.Cu")
	)
	(gr_line
		(start 432.15687 -124.778008)
		(end 432.160426 -124.775722)
		(stroke
			(width 0.05715)
			(type default)
		)
		(layer "In4.Cu")
	)
	(gr_line
		(start 432.176682 -140.36675)
		(end 432.329082 -140.51915)
		(stroke
			(width 0.05715)
			(type default)
		)
		(layer "In4.Cu")
	)
	(gr_line
		(start 432.244246 -55.776114)
		(end 432.406806 -55.613554)
		(stroke
			(width 0.05715)
			(type default)
		)
		(layer "In4.Cu")
	)
	(gr_line
		(start 432.406806 -55.613554)
		(end 432.749706 -55.613554)
		(stroke
			(width 0.05715)
			(type default)
		)
		(layer "In4.Cu")
	)
	(gr_line
		(start 432.407822 -125.38202)
		(end 432.412394 -125.38075)
		(stroke
			(width 0.05715)
			(type default)
		)
		(layer "In4.Cu")
	)
	(gr_line
		(start 432.412394 -125.38075)
		(end 432.41595 -125.378464)
		(stroke
			(width 0.05715)
			(type default)
		)
		(layer "In4.Cu")
	)
	(gr_line
		(start 432.518058 -128.498346)
		(end 432.544474 -128.50368)
		(stroke
			(width 0.05715)
			(type default)
		)
		(layer "In4.Cu")
	)
	(gr_line
		(start 432.536346 -56.070754)
		(end 432.620166 -56.070754)
		(stroke
			(width 0.05715)
			(type default)
		)
		(layer "In4.Cu")
	)
	(gr_line
		(start 432.544474 -128.50368)
		(end 432.57089 -128.497584)
		(stroke
			(width 0.05715)
			(type default)
		)
		(layer "In4.Cu")
	)
	(gr_line
		(start 432.57343 -121.996708)
		(end 432.597306 -122.00255)
		(stroke
			(width 0.05715)
			(type default)
		)
		(layer "In4.Cu")
	)
	(gr_line
		(start 432.597306 -122.00255)
		(end 432.620674 -121.998232)
		(stroke
			(width 0.05715)
			(type default)
		)
		(layer "In4.Cu")
	)
	(gr_line
		(start 432.637184 -129.17551)
		(end 432.6636 -129.180844)
		(stroke
			(width 0.05715)
			(type default)
		)
		(layer "In4.Cu")
	)
	(gr_line
		(start 432.648868 -129.837688)
		(end 432.675284 -129.843022)
		(stroke
			(width 0.05715)
			(type default)
		)
		(layer "In4.Cu")
	)
	(gr_line
		(start 432.6636 -129.180844)
		(end 432.690016 -129.174748)
		(stroke
			(width 0.05715)
			(type default)
		)
		(layer "In4.Cu")
	)
	(gr_line
		(start 432.675284 -129.843022)
		(end 432.7017 -129.836926)
		(stroke
			(width 0.05715)
			(type default)
		)
		(layer "In4.Cu")
	)
	(gr_line
		(start 432.697382 -140.51915)
		(end 432.849782 -140.36675)
		(stroke
			(width 0.05715)
			(type default)
		)
		(layer "In4.Cu")
	)
	(gr_line
		(start 432.749706 -55.613554)
		(end 432.912266 -55.776114)
		(stroke
			(width 0.05715)
			(type default)
		)
		(layer "In4.Cu")
	)
	(gr_line
		(start 432.75123 -125.954282)
		(end 432.755802 -125.953012)
		(stroke
			(width 0.05715)
			(type default)
		)
		(layer "In4.Cu")
	)
	(gr_line
		(start 432.755802 -125.953012)
		(end 432.759358 -125.950726)
		(stroke
			(width 0.05715)
			(type default)
		)
		(layer "In4.Cu")
	)
	(gr_line
		(start 432.849782 -140.36675)
		(end 433.192682 -140.36675)
		(stroke
			(width 0.05715)
			(type default)
		)
		(layer "In4.Cu")
	)
	(gr_line
		(start 432.857402 -131.867402)
		(end 432.895756 -131.875276)
		(stroke
			(width 0.05715)
			(type default)
		)
		(layer "In4.Cu")
	)
	(gr_line
		(start 432.895756 -131.875276)
		(end 432.93284 -131.86283)
		(stroke
			(width 0.05715)
			(type default)
		)
		(layer "In4.Cu")
	)
	(gr_line
		(start 432.933856 -125.507496)
		(end 433.449476 -125.20168)
		(stroke
			(width 0.05715)
			(type default)
		)
		(layer "In4.Cu")
	)
	(gr_line
		(start 432.989482 -140.82395)
		(end 433.052982 -140.82395)
		(stroke
			(width 0.05715)
			(type default)
		)
		(layer "In4.Cu")
	)
	(gr_line
		(start 433.053998 -125.778768)
		(end 433.27701 -125.835918)
		(stroke
			(width 0.05715)
			(type default)
		)
		(layer "In4.Cu")
	)
	(gr_line
		(start 433.192682 -140.36675)
		(end 433.345082 -140.51915)
		(stroke
			(width 0.05715)
			(type default)
		)
		(layer "In4.Cu")
	)
	(gr_line
		(start 433.27701 -125.835918)
		(end 433.571904 -125.661166)
		(stroke
			(width 0.05715)
			(type default)
		)
		(layer "In4.Cu")
	)
	(gr_line
		(start 433.413916 -128.302004)
		(end 433.438046 -128.296416)
		(stroke
			(width 0.05715)
			(type default)
		)
		(layer "In4.Cu")
	)
	(gr_line
		(start 433.438046 -128.296416)
		(end 433.457858 -128.28143)
		(stroke
			(width 0.05715)
			(type default)
		)
		(layer "In4.Cu")
	)
	(gr_line
		(start 433.470558 -121.544334)
		(end 433.492148 -121.54027)
		(stroke
			(width 0.05715)
			(type default)
		)
		(layer "In4.Cu")
	)
	(gr_line
		(start 433.492148 -121.54027)
		(end 433.513484 -121.545096)
		(stroke
			(width 0.05715)
			(type default)
		)
		(layer "In4.Cu")
	)
	(gr_line
		(start 433.571904 -125.661166)
		(end 433.629054 -125.4379)
		(stroke
			(width 0.05715)
			(type default)
		)
		(layer "In4.Cu")
	)
	(gr_line
		(start 433.72278 -128.935226)
		(end 433.74691 -128.929638)
		(stroke
			(width 0.05715)
			(type default)
		)
		(layer "In4.Cu")
	)
	(gr_line
		(start 433.74691 -128.929638)
		(end 433.766722 -128.914652)
		(stroke
			(width 0.05715)
			(type default)
		)
		(layer "In4.Cu")
	)
	(gr_line
		(start 433.807362 -124.98959)
		(end 434.323998 -124.683266)
		(stroke
			(width 0.05715)
			(type default)
		)
		(layer "In4.Cu")
	)
	(gr_line
		(start 433.928012 -125.260608)
		(end 434.151024 -125.317758)
		(stroke
			(width 0.05715)
			(type default)
		)
		(layer "In4.Cu")
	)
	(gr_line
		(start 434.033676 -127.843534)
		(end 434.066696 -127.818388)
		(stroke
			(width 0.05715)
			(type default)
		)
		(layer "In4.Cu")
	)
	(gr_line
		(start 434.066696 -127.818388)
		(end 434.082444 -127.780288)
		(stroke
			(width 0.05715)
			(type default)
		)
		(layer "In4.Cu")
	)
	(gr_line
		(start 434.098192 -129.513076)
		(end 434.122322 -129.507488)
		(stroke
			(width 0.05715)
			(type default)
		)
		(layer "In4.Cu")
	)
	(gr_line
		(start 434.122322 -129.507488)
		(end 434.142134 -129.492502)
		(stroke
			(width 0.05715)
			(type default)
		)
		(layer "In4.Cu")
	)
	(gr_line
		(start 434.151024 -125.317758)
		(end 434.445918 -125.142752)
		(stroke
			(width 0.05715)
			(type default)
		)
		(layer "In4.Cu")
	)
	(gr_line
		(start 434.173122 -57.11444)
		(end 434.23205 -57.173368)
		(stroke
			(width 0.05715)
			(type default)
		)
		(layer "In4.Cu")
	)
	(gr_line
		(start 434.174646 -56.699404)
		(end 434.40477 -56.699404)
		(stroke
			(width 0.05715)
			(type default)
		)
		(layer "In4.Cu")
	)
	(gr_line
		(start 434.335936 -122.027442)
		(end 434.37048 -122.035062)
		(stroke
			(width 0.05715)
			(type default)
		)
		(layer "In4.Cu")
	)
	(gr_line
		(start 434.37048 -122.035062)
		(end 434.40477 -122.02541)
		(stroke
			(width 0.05715)
			(type default)
		)
		(layer "In4.Cu")
	)
	(gr_line
		(start 434.40477 -56.699404)
		(end 434.647086 -56.94172)
		(stroke
			(width 0.05715)
			(type default)
		)
		(layer "In4.Cu")
	)
	(gr_line
		(start 434.445918 -125.142752)
		(end 434.503068 -124.91974)
		(stroke
			(width 0.05715)
			(type default)
		)
		(layer "In4.Cu")
	)
	(gr_line
		(start 434.532024 -128.332992)
		(end 434.565044 -128.307846)
		(stroke
			(width 0.05715)
			(type default)
		)
		(layer "In4.Cu")
	)
	(gr_line
		(start 434.565044 -128.307846)
		(end 434.580792 -128.269746)
		(stroke
			(width 0.05715)
			(type default)
		)
		(layer "In4.Cu")
	)
	(gr_line
		(start 434.647086 -56.94172)
		(end 434.647086 -57.171844)
		(stroke
			(width 0.05715)
			(type default)
		)
		(layer "In4.Cu")
	)
	(gr_line
		(start 434.682646 -130.971544)
		(end 434.716936 -130.960114)
		(stroke
			(width 0.05715)
			(type default)
		)
		(layer "In4.Cu")
	)
	(gr_line
		(start 434.716936 -130.960114)
		(end 434.752496 -130.96621)
		(stroke
			(width 0.05715)
			(type default)
		)
		(layer "In4.Cu")
	)
	(gr_line
		(start 434.891434 -57.832752)
		(end 434.950362 -57.89168)
		(stroke
			(width 0.05715)
			(type default)
		)
		(layer "In4.Cu")
	)
	(gr_line
		(start 434.892958 -57.417716)
		(end 435.123082 -57.417716)
		(stroke
			(width 0.05715)
			(type default)
		)
		(layer "In4.Cu")
	)
	(gr_line
		(start 435.03342 -128.815084)
		(end 435.06644 -128.789938)
		(stroke
			(width 0.05715)
			(type default)
		)
		(layer "In4.Cu")
	)
	(gr_line
		(start 435.042056 -131.312666)
		(end 435.629558 -131.413758)
		(stroke
			(width 0.05715)
			(type default)
		)
		(layer "In4.Cu")
	)
	(gr_line
		(start 435.05755 -131.016248)
		(end 435.24551 -130.88366)
		(stroke
			(width 0.05715)
			(type default)
		)
		(layer "In4.Cu")
	)
	(gr_line
		(start 435.06644 -128.789938)
		(end 435.082188 -128.751838)
		(stroke
			(width 0.05715)
			(type default)
		)
		(layer "In4.Cu")
	)
	(gr_line
		(start 435.123082 -57.417716)
		(end 435.365398 -57.660032)
		(stroke
			(width 0.05715)
			(type default)
		)
		(layer "In4.Cu")
	)
	(gr_line
		(start 435.24551 -130.88366)
		(end 435.583584 -130.94208)
		(stroke
			(width 0.05715)
			(type default)
		)
		(layer "In4.Cu")
	)
	(gr_line
		(start 435.364128 -121.752868)
		(end 435.364382 -121.752868)
		(stroke
			(width 0.05715)
			(type default)
		)
		(layer "In4.Cu")
	)
	(gr_line
		(start 435.364382 -121.752868)
		(end 435.36489 -121.752614)
		(stroke
			(width 0.05715)
			(type default)
		)
		(layer "In4.Cu")
	)
	(gr_line
		(start 435.365398 -57.660032)
		(end 435.365398 -57.890156)
		(stroke
			(width 0.05715)
			(type default)
		)
		(layer "In4.Cu")
	)
	(gr_line
		(start 435.502304 -124.832618)
		(end 435.529228 -124.79528)
		(stroke
			(width 0.05715)
			(type default)
		)
		(layer "In4.Cu")
	)
	(gr_line
		(start 435.529228 -124.79528)
		(end 435.572154 -124.7775)
		(stroke
			(width 0.05715)
			(type default)
		)
		(layer "In4.Cu")
	)
	(gr_line
		(start 435.583584 -130.94208)
		(end 435.716172 -131.13004)
		(stroke
			(width 0.05715)
			(type default)
		)
		(layer "In4.Cu")
	)
	(gr_line
		(start 435.766464 -53.05171)
		(end 435.825392 -53.110638)
		(stroke
			(width 0.05715)
			(type default)
		)
		(layer "In4.Cu")
	)
	(gr_line
		(start 435.914546 -125.36932)
		(end 435.94147 -125.331982)
		(stroke
			(width 0.05715)
			(type default)
		)
		(layer "In4.Cu")
	)
	(gr_line
		(start 435.94147 -125.331982)
		(end 435.984396 -125.314202)
		(stroke
			(width 0.05715)
			(type default)
		)
		(layer "In4.Cu")
	)
	(gr_line
		(start 436.09514 -46.31436)
		(end 436.2577 -46.1518)
		(stroke
			(width 0.05715)
			(type default)
		)
		(layer "In4.Cu")
	)
	(gr_line
		(start 436.253382 -53.951886)
		(end 436.676546 -54.375304)
		(stroke
			(width 0.05715)
			(type default)
		)
		(layer "In4.Cu")
	)
	(gr_line
		(start 436.2577 -46.1518)
		(end 436.6006 -46.1518)
		(stroke
			(width 0.05715)
			(type default)
		)
		(layer "In4.Cu")
	)
	(gr_line
		(start 436.27167 -51.5366)
		(end 436.380636 -51.5366)
		(stroke
			(width 0.05715)
			(type default)
		)
		(layer "In4.Cu")
	)
	(gr_line
		(start 436.275988 -125.97511)
		(end 436.302912 -125.937772)
		(stroke
			(width 0.05715)
			(type default)
		)
		(layer "In4.Cu")
	)
	(gr_line
		(start 436.302912 -125.937772)
		(end 436.346092 -125.919992)
		(stroke
			(width 0.05715)
			(type default)
		)
		(layer "In4.Cu")
	)
	(gr_line
		(start 436.38724 -46.609)
		(end 436.47106 -46.609)
		(stroke
			(width 0.05715)
			(type default)
		)
		(layer "In4.Cu")
	)
	(gr_line
		(start 436.43677 -53.718714)
		(end 436.666894 -53.718714)
		(stroke
			(width 0.05715)
			(type default)
		)
		(layer "In4.Cu")
	)
	(gr_line
		(start 436.56123 -51.769264)
		(end 436.573422 -51.769264)
		(stroke
			(width 0.05715)
			(type default)
		)
		(layer "In4.Cu")
	)
	(gr_line
		(start 436.6006 -46.1518)
		(end 436.76316 -46.31436)
		(stroke
			(width 0.05715)
			(type default)
		)
		(layer "In4.Cu")
	)
	(gr_line
		(start 436.621174 -120.668288)
		(end 436.631588 -120.662192)
		(stroke
			(width 0.05715)
			(type default)
		)
		(layer "In4.Cu")
	)
	(gr_line
		(start 436.631588 -120.662192)
		(end 436.644034 -120.659652)
		(stroke
			(width 0.05715)
			(type default)
		)
		(layer "In4.Cu")
	)
	(gr_line
		(start 436.666894 -53.718714)
		(end 436.909464 -53.96103)
		(stroke
			(width 0.05715)
			(type default)
		)
		(layer "In4.Cu")
	)
	(gr_line
		(start 436.909464 -53.96103)
		(end 436.909464 -54.191408)
		(stroke
			(width 0.05715)
			(type default)
		)
		(layer "In4.Cu")
	)
	(gr_line
		(start 436.93969 -131.639818)
		(end 436.97652 -131.646168)
		(stroke
			(width 0.05715)
			(type default)
		)
		(layer "In4.Cu")
	)
	(gr_line
		(start 436.97652 -131.646168)
		(end 437.011826 -131.633976)
		(stroke
			(width 0.05715)
			(type default)
		)
		(layer "In4.Cu")
	)
	(gr_line
		(start 437.11114 -46.31436)
		(end 437.2737 -46.1518)
		(stroke
			(width 0.05715)
			(type default)
		)
		(layer "In4.Cu")
	)
	(gr_line
		(start 437.2737 -46.1518)
		(end 437.6166 -46.1518)
		(stroke
			(width 0.05715)
			(type default)
		)
		(layer "In4.Cu")
	)
	(gr_line
		(start 437.323992 -122.128788)
		(end 437.334406 -122.122692)
		(stroke
			(width 0.05715)
			(type default)
		)
		(layer "In4.Cu")
	)
	(gr_line
		(start 437.334406 -122.122692)
		(end 437.33466 -122.122438)
		(stroke
			(width 0.05715)
			(type default)
		)
		(layer "In4.Cu")
	)
	(gr_line
		(start 437.33466 -122.122692)
		(end 437.345836 -122.120406)
		(stroke
			(width 0.05715)
			(type default)
		)
		(layer "In4.Cu")
	)
	(gr_line
		(start 437.33466 -122.122438)
		(end 437.33466 -122.122692)
		(stroke
			(width 0.05715)
			(type default)
		)
		(layer "In4.Cu")
	)
	(gr_line
		(start 437.40324 -46.609)
		(end 437.48706 -46.609)
		(stroke
			(width 0.05715)
			(type default)
		)
		(layer "In4.Cu")
	)
	(gr_line
		(start 437.52643 -122.784616)
		(end 437.536844 -122.77852)
		(stroke
			(width 0.05715)
			(type default)
		)
		(layer "In4.Cu")
	)
	(gr_line
		(start 437.536844 -122.77852)
		(end 437.54802 -122.776488)
		(stroke
			(width 0.05715)
			(type default)
		)
		(layer "In4.Cu")
	)
	(gr_line
		(start 437.573166 -121.227342)
		(end 437.582818 -121.2215)
		(stroke
			(width 0.05715)
			(type default)
		)
		(layer "In4.Cu")
	)
	(gr_line
		(start 437.582818 -121.2215)
		(end 437.593994 -121.219214)
		(stroke
			(width 0.05715)
			(type default)
		)
		(layer "In4.Cu")
	)
	(gr_line
		(start 437.6166 -46.1518)
		(end 437.77916 -46.31436)
		(stroke
			(width 0.05715)
			(type default)
		)
		(layer "In4.Cu")
	)
	(gr_line
		(start 437.924956 -123.80214)
		(end 438.48147 -123.571508)
		(stroke
			(width 0.05715)
			(type default)
		)
		(layer "In4.Cu")
	)
	(gr_line
		(start 437.980836 -122.690382)
		(end 438.564274 -122.574304)
		(stroke
			(width 0.05715)
			(type default)
		)
		(layer "In4.Cu")
	)
	(gr_line
		(start 438.001918 -122.986292)
		(end 438.19318 -123.114308)
		(stroke
			(width 0.05715)
			(type default)
		)
		(layer "In4.Cu")
	)
	(gr_line
		(start 438.007506 -124.086874)
		(end 438.220358 -124.175012)
		(stroke
			(width 0.05715)
			(type default)
		)
		(layer "In4.Cu")
	)
	(gr_line
		(start 438.19318 -123.114308)
		(end 438.529476 -123.047252)
		(stroke
			(width 0.05715)
			(type default)
		)
		(layer "In4.Cu")
	)
	(gr_line
		(start 438.220358 -124.175012)
		(end 438.537096 -124.043694)
		(stroke
			(width 0.05715)
			(type default)
		)
		(layer "In4.Cu")
	)
	(gr_line
		(start 438.35574 -54.53126)
		(end 438.5183 -54.3687)
		(stroke
			(width 0.05715)
			(type default)
		)
		(layer "In4.Cu")
	)
	(gr_line
		(start 438.5183 -54.3687)
		(end 438.8612 -54.3687)
		(stroke
			(width 0.05715)
			(type default)
		)
		(layer "In4.Cu")
	)
	(gr_line
		(start 438.529476 -123.047252)
		(end 438.657492 -122.85599)
		(stroke
			(width 0.05715)
			(type default)
		)
		(layer "In4.Cu")
	)
	(gr_line
		(start 438.537096 -124.043694)
		(end 438.625234 -123.830842)
		(stroke
			(width 0.05715)
			(type default)
		)
		(layer "In4.Cu")
	)
	(gr_line
		(start 438.55132 -130.269996)
		(end 438.639204 -130.482848)
		(stroke
			(width 0.05715)
			(type default)
		)
		(layer "In4.Cu")
	)
	(gr_line
		(start 438.55132 -130.269996)
		(end 438.682638 -129.953258)
		(stroke
			(width 0.05715)
			(type default)
		)
		(layer "In4.Cu")
	)
	(gr_line
		(start 438.640728 -131.066032)
		(end 438.72912 -131.035298)
		(stroke
			(width 0.05715)
			(type default)
		)
		(layer "In4.Cu")
	)
	(gr_line
		(start 438.64784 -54.8259)
		(end 438.73166 -54.8259)
		(stroke
			(width 0.05715)
			(type default)
		)
		(layer "In4.Cu")
	)
	(gr_line
		(start 438.682638 -129.953258)
		(end 438.89549 -129.86512)
		(stroke
			(width 0.05715)
			(type default)
		)
		(layer "In4.Cu")
	)
	(gr_line
		(start 438.707022 -44.83735)
		(end 439.081672 -44.83735)
		(stroke
			(width 0.05715)
			(type default)
		)
		(layer "In4.Cu")
	)
	(gr_line
		(start 438.72912 -131.035298)
		(end 438.765442 -130.947922)
		(stroke
			(width 0.05715)
			(type default)
		)
		(layer "In4.Cu")
	)
	(gr_line
		(start 438.8612 -54.3687)
		(end 439.02376 -54.53126)
		(stroke
			(width 0.05715)
			(type default)
		)
		(layer "In4.Cu")
	)
	(gr_line
		(start 438.863994 -123.413012)
		(end 439.419492 -123.182634)
		(stroke
			(width 0.05715)
			(type default)
		)
		(layer "In4.Cu")
	)
	(gr_line
		(start 438.924446 -130.563874)
		(end 439.1533 -130.012186)
		(stroke
			(width 0.05715)
			(type default)
		)
		(layer "In4.Cu")
	)
	(gr_line
		(start 438.940702 -129.331466)
		(end 439.028586 -129.544064)
		(stroke
			(width 0.05715)
			(type default)
		)
		(layer "In4.Cu")
	)
	(gr_line
		(start 438.940702 -129.331466)
		(end 439.07202 -129.014728)
		(stroke
			(width 0.05715)
			(type default)
		)
		(layer "In4.Cu")
	)
	(gr_line
		(start 438.946036 -123.698)
		(end 439.158888 -123.785884)
		(stroke
			(width 0.05715)
			(type default)
		)
		(layer "In4.Cu")
	)
	(gr_line
		(start 439.07202 -129.014728)
		(end 439.284618 -128.92659)
		(stroke
			(width 0.05715)
			(type default)
		)
		(layer "In4.Cu")
	)
	(gr_line
		(start 439.074306 -127.02159)
		(end 439.26379 -127.02159)
		(stroke
			(width 0.05715)
			(type default)
		)
		(layer "In4.Cu")
	)
	(gr_line
		(start 439.081672 -44.83735)
		(end 439.141108 -44.896786)
		(stroke
			(width 0.05715)
			(type default)
		)
		(layer "In4.Cu")
	)
	(gr_line
		(start 439.099706 -120.919748)
		(end 439.688224 -120.802654)
		(stroke
			(width 0.05715)
			(type default)
		)
		(layer "In4.Cu")
	)
	(gr_line
		(start 439.123836 -121.215404)
		(end 439.315098 -121.343166)
		(stroke
			(width 0.05715)
			(type default)
		)
		(layer "In4.Cu")
	)
	(gr_line
		(start 439.158888 -123.785884)
		(end 439.475626 -123.654566)
		(stroke
			(width 0.05715)
			(type default)
		)
		(layer "In4.Cu")
	)
	(gr_line
		(start 439.26379 -127.02159)
		(end 439.51017 -127.26797)
		(stroke
			(width 0.05715)
			(type default)
		)
		(layer "In4.Cu")
	)
	(gr_line
		(start 439.31459 -129.623058)
		(end 439.54319 -129.072132)
		(stroke
			(width 0.05715)
			(type default)
		)
		(layer "In4.Cu")
	)
	(gr_line
		(start 439.315098 -121.343166)
		(end 439.651394 -121.276364)
		(stroke
			(width 0.05715)
			(type default)
		)
		(layer "In4.Cu")
	)
	(gr_line
		(start 439.37174 -54.53126)
		(end 439.5343 -54.3687)
		(stroke
			(width 0.05715)
			(type default)
		)
		(layer "In4.Cu")
	)
	(gr_line
		(start 439.458608 -47.90313)
		(end 439.621168 -47.74057)
		(stroke
			(width 0.05715)
			(type default)
		)
		(layer "In4.Cu")
	)
	(gr_line
		(start 439.475626 -123.654566)
		(end 439.563764 -123.441714)
		(stroke
			(width 0.05715)
			(type default)
		)
		(layer "In4.Cu")
	)
	(gr_line
		(start 439.5343 -54.3687)
		(end 439.8772 -54.3687)
		(stroke
			(width 0.05715)
			(type default)
		)
		(layer "In4.Cu")
	)
	(gr_line
		(start 439.557414 -48.714914)
		(end 439.719974 -48.552354)
		(stroke
			(width 0.05715)
			(type default)
		)
		(layer "In4.Cu")
	)
	(gr_line
		(start 439.557668 -44.896786)
		(end 439.617104 -44.83735)
		(stroke
			(width 0.05715)
			(type default)
		)
		(layer "In4.Cu")
	)
	(gr_line
		(start 439.617104 -44.83735)
		(end 439.977022 -44.83735)
		(stroke
			(width 0.05715)
			(type default)
		)
		(layer "In4.Cu")
	)
	(gr_line
		(start 439.621168 -47.74057)
		(end 439.964068 -47.74057)
		(stroke
			(width 0.05715)
			(type default)
		)
		(layer "In4.Cu")
	)
	(gr_line
		(start 439.651394 -121.276364)
		(end 439.77941 -121.085102)
		(stroke
			(width 0.05715)
			(type default)
		)
		(layer "In4.Cu")
	)
	(gr_line
		(start 439.66384 -54.8259)
		(end 439.74766 -54.8259)
		(stroke
			(width 0.05715)
			(type default)
		)
		(layer "In4.Cu")
	)
	(gr_line
		(start 439.719974 -48.552354)
		(end 440.062874 -48.552354)
		(stroke
			(width 0.05715)
			(type default)
		)
		(layer "In4.Cu")
	)
	(gr_line
		(start 439.750708 -48.19777)
		(end 439.834528 -48.19777)
		(stroke
			(width 0.05715)
			(type default)
		)
		(layer "In4.Cu")
	)
	(gr_line
		(start 439.849514 -49.009554)
		(end 439.933334 -49.009554)
		(stroke
			(width 0.05715)
			(type default)
		)
		(layer "In4.Cu")
	)
	(gr_line
		(start 439.85688 -128.315974)
		(end 439.8645 -128.297432)
		(stroke
			(width 0.05715)
			(type default)
		)
		(layer "In4.Cu")
	)
	(gr_line
		(start 439.8772 -54.3687)
		(end 440.03976 -54.53126)
		(stroke
			(width 0.05715)
			(type default)
		)
		(layer "In4.Cu")
	)
	(gr_line
		(start 439.92673 -127.26797)
		(end 440.17311 -127.02159)
		(stroke
			(width 0.05715)
			(type default)
		)
		(layer "In4.Cu")
	)
	(gr_line
		(start 439.964068 -47.74057)
		(end 440.126628 -47.90313)
		(stroke
			(width 0.05715)
			(type default)
		)
		(layer "In4.Cu")
	)
	(gr_line
		(start 440.062874 -48.552354)
		(end 440.225434 -48.714914)
		(stroke
			(width 0.05715)
			(type default)
		)
		(layer "In4.Cu")
	)
	(gr_line
		(start 440.095894 -120.721628)
		(end 440.684666 -120.604534)
		(stroke
			(width 0.05715)
			(type default)
		)
		(layer "In4.Cu")
	)
	(gr_line
		(start 440.120278 -121.017284)
		(end 440.31154 -121.145046)
		(stroke
			(width 0.05715)
			(type default)
		)
		(layer "In4.Cu")
	)
	(gr_line
		(start 440.124088 -55.45836)
		(end 440.286648 -55.2958)
		(stroke
			(width 0.05715)
			(type default)
		)
		(layer "In4.Cu")
	)
	(gr_line
		(start 440.17311 -127.02159)
		(end 440.344306 -127.02159)
		(stroke
			(width 0.05715)
			(type default)
		)
		(layer "In4.Cu")
	)
	(gr_line
		(start 440.286648 -55.2958)
		(end 440.629548 -55.2958)
		(stroke
			(width 0.05715)
			(type default)
		)
		(layer "In4.Cu")
	)
	(gr_line
		(start 440.304936 -53.754274)
		(end 440.520074 -53.754274)
		(stroke
			(width 0.05715)
			(type default)
		)
		(layer "In4.Cu")
	)
	(gr_line
		(start 440.31154 -121.145046)
		(end 440.647836 -121.078244)
		(stroke
			(width 0.05715)
			(type default)
		)
		(layer "In4.Cu")
	)
	(gr_line
		(start 440.416188 -55.753)
		(end 440.500008 -55.753)
		(stroke
			(width 0.05715)
			(type default)
		)
		(layer "In4.Cu")
	)
	(gr_line
		(start 440.474608 -47.90313)
		(end 440.637168 -47.74057)
		(stroke
			(width 0.05715)
			(type default)
		)
		(layer "In4.Cu")
	)
	(gr_line
		(start 440.520074 -53.754274)
		(end 440.70397 -53.93817)
		(stroke
			(width 0.05715)
			(type default)
		)
		(layer "In4.Cu")
	)
	(gr_line
		(start 440.573414 -48.714914)
		(end 440.735974 -48.552354)
		(stroke
			(width 0.05715)
			(type default)
		)
		(layer "In4.Cu")
	)
	(gr_line
		(start 440.629548 -55.2958)
		(end 440.792108 -55.45836)
		(stroke
			(width 0.05715)
			(type default)
		)
		(layer "In4.Cu")
	)
	(gr_line
		(start 440.637168 -47.74057)
		(end 440.980068 -47.74057)
		(stroke
			(width 0.05715)
			(type default)
		)
		(layer "In4.Cu")
	)
	(gr_line
		(start 440.647836 -121.078244)
		(end 440.775852 -120.886982)
		(stroke
			(width 0.05715)
			(type default)
		)
		(layer "In4.Cu")
	)
	(gr_line
		(start 440.735974 -48.552354)
		(end 441.078874 -48.552354)
		(stroke
			(width 0.05715)
			(type default)
		)
		(layer "In4.Cu")
	)
	(gr_line
		(start 440.766708 -48.19777)
		(end 440.850528 -48.19777)
		(stroke
			(width 0.05715)
			(type default)
		)
		(layer "In4.Cu")
	)
	(gr_line
		(start 440.865514 -49.009554)
		(end 440.949334 -49.009554)
		(stroke
			(width 0.05715)
			(type default)
		)
		(layer "In4.Cu")
	)
	(gr_line
		(start 440.980068 -47.74057)
		(end 441.142628 -47.90313)
		(stroke
			(width 0.05715)
			(type default)
		)
		(layer "In4.Cu")
	)
	(gr_line
		(start 441.078874 -48.552354)
		(end 441.241434 -48.714914)
		(stroke
			(width 0.05715)
			(type default)
		)
		(layer "In4.Cu")
	)
	(gr_line
		(start 441.094368 -120.523254)
		(end 441.680346 -120.406668)
		(stroke
			(width 0.05715)
			(type default)
		)
		(layer "In4.Cu")
	)
	(gr_line
		(start 441.116974 -120.819164)
		(end 441.308236 -120.946926)
		(stroke
			(width 0.05715)
			(type default)
		)
		(layer "In4.Cu")
	)
	(gr_line
		(start 441.12053 -53.93817)
		(end 441.304426 -53.754274)
		(stroke
			(width 0.05715)
			(type default)
		)
		(layer "In4.Cu")
	)
	(gr_line
		(start 441.140088 -55.45836)
		(end 441.302648 -55.2958)
		(stroke
			(width 0.05715)
			(type default)
		)
		(layer "In4.Cu")
	)
	(gr_line
		(start 441.17641 -43.4975)
		(end 441.33897 -43.66006)
		(stroke
			(width 0.05715)
			(type default)
		)
		(layer "In4.Cu")
	)
	(gr_line
		(start 441.302648 -55.2958)
		(end 441.645548 -55.2958)
		(stroke
			(width 0.05715)
			(type default)
		)
		(layer "In4.Cu")
	)
	(gr_line
		(start 441.304426 -53.754274)
		(end 441.574936 -53.754274)
		(stroke
			(width 0.05715)
			(type default)
		)
		(layer "In4.Cu")
	)
	(gr_line
		(start 441.308236 -120.946926)
		(end 441.644532 -120.880124)
		(stroke
			(width 0.05715)
			(type default)
		)
		(layer "In4.Cu")
	)
	(gr_line
		(start 441.33897 -43.66006)
		(end 441.68187 -43.66006)
		(stroke
			(width 0.05715)
			(type default)
		)
		(layer "In4.Cu")
	)
	(gr_line
		(start 441.432188 -55.753)
		(end 441.516008 -55.753)
		(stroke
			(width 0.05715)
			(type default)
		)
		(layer "In4.Cu")
	)
	(gr_line
		(start 441.46851 -43.20286)
		(end 441.55233 -43.20286)
		(stroke
			(width 0.05715)
			(type default)
		)
		(layer "In4.Cu")
	)
	(gr_line
		(start 441.470034 -137.79627)
		(end 441.622434 -137.64387)
		(stroke
			(width 0.05715)
			(type default)
		)
		(layer "In4.Cu")
	)
	(gr_line
		(start 441.490608 -47.90313)
		(end 441.653168 -47.74057)
		(stroke
			(width 0.05715)
			(type default)
		)
		(layer "In4.Cu")
	)
	(gr_line
		(start 441.589414 -48.714914)
		(end 441.751974 -48.552354)
		(stroke
			(width 0.05715)
			(type default)
		)
		(layer "In4.Cu")
	)
	(gr_line
		(start 441.622434 -137.64387)
		(end 441.965334 -137.64387)
		(stroke
			(width 0.05715)
			(type default)
		)
		(layer "In4.Cu")
	)
	(gr_line
		(start 441.644532 -120.880124)
		(end 441.772294 -120.688862)
		(stroke
			(width 0.05715)
			(type default)
		)
		(layer "In4.Cu")
	)
	(gr_line
		(start 441.645548 -55.2958)
		(end 441.808108 -55.45836)
		(stroke
			(width 0.05715)
			(type default)
		)
		(layer "In4.Cu")
	)
	(gr_line
		(start 441.653168 -47.74057)
		(end 441.996068 -47.74057)
		(stroke
			(width 0.05715)
			(type default)
		)
		(layer "In4.Cu")
	)
	(gr_line
		(start 441.68187 -43.66006)
		(end 441.84443 -43.4975)
		(stroke
			(width 0.05715)
			(type default)
		)
		(layer "In4.Cu")
	)
	(gr_line
		(start 441.751974 -48.552354)
		(end 442.094874 -48.552354)
		(stroke
			(width 0.05715)
			(type default)
		)
		(layer "In4.Cu")
	)
	(gr_line
		(start 441.762134 -138.10107)
		(end 441.825634 -138.10107)
		(stroke
			(width 0.05715)
			(type default)
		)
		(layer "In4.Cu")
	)
	(gr_line
		(start 441.782708 -48.19777)
		(end 441.866528 -48.19777)
		(stroke
			(width 0.05715)
			(type default)
		)
		(layer "In4.Cu")
	)
	(gr_line
		(start 441.881514 -49.009554)
		(end 441.965334 -49.009554)
		(stroke
			(width 0.05715)
			(type default)
		)
		(layer "In4.Cu")
	)
	(gr_line
		(start 441.907168 -44.83735)
		(end 442.281818 -44.83735)
		(stroke
			(width 0.05715)
			(type default)
		)
		(layer "In4.Cu")
	)
	(gr_line
		(start 441.965334 -137.64387)
		(end 442.117734 -137.79627)
		(stroke
			(width 0.05715)
			(type default)
		)
		(layer "In4.Cu")
	)
	(gr_line
		(start 441.996068 -47.74057)
		(end 442.158628 -47.90313)
		(stroke
			(width 0.05715)
			(type default)
		)
		(layer "In4.Cu")
	)
	(gr_line
		(start 442.094874 -48.552354)
		(end 442.257434 -48.714914)
		(stroke
			(width 0.05715)
			(type default)
		)
		(layer "In4.Cu")
	)
	(gr_line
		(start 442.156088 -55.45836)
		(end 442.318648 -55.2958)
		(stroke
			(width 0.05715)
			(type default)
		)
		(layer "In4.Cu")
	)
	(gr_line
		(start 442.19241 -43.4975)
		(end 442.35497 -43.66006)
		(stroke
			(width 0.05715)
			(type default)
		)
		(layer "In4.Cu")
	)
	(gr_line
		(start 442.281818 -44.83735)
		(end 442.333888 -44.88942)
		(stroke
			(width 0.05715)
			(type default)
		)
		(layer "In4.Cu")
	)
	(gr_line
		(start 442.318648 -55.2958)
		(end 442.661548 -55.2958)
		(stroke
			(width 0.05715)
			(type default)
		)
		(layer "In4.Cu")
	)
	(gr_line
		(start 442.35497 -43.66006)
		(end 442.69787 -43.66006)
		(stroke
			(width 0.05715)
			(type default)
		)
		(layer "In4.Cu")
	)
	(gr_line
		(start 442.448188 -55.753)
		(end 442.532008 -55.753)
		(stroke
			(width 0.05715)
			(type default)
		)
		(layer "In4.Cu")
	)
	(gr_line
		(start 442.48451 -43.20286)
		(end 442.56833 -43.20286)
		(stroke
			(width 0.05715)
			(type default)
		)
		(layer "In4.Cu")
	)
	(gr_line
		(start 442.486034 -137.79627)
		(end 442.638434 -137.64387)
		(stroke
			(width 0.05715)
			(type default)
		)
		(layer "In4.Cu")
	)
	(gr_line
		(start 442.605414 -48.714914)
		(end 442.767974 -48.552354)
		(stroke
			(width 0.05715)
			(type default)
		)
		(layer "In4.Cu")
	)
	(gr_line
		(start 442.638434 -137.64387)
		(end 442.981334 -137.64387)
		(stroke
			(width 0.05715)
			(type default)
		)
		(layer "In4.Cu")
	)
	(gr_line
		(start 442.661548 -55.2958)
		(end 442.824108 -55.45836)
		(stroke
			(width 0.05715)
			(type default)
		)
		(layer "In4.Cu")
	)
	(gr_line
		(start 442.69787 -43.66006)
		(end 442.86043 -43.4975)
		(stroke
			(width 0.05715)
			(type default)
		)
		(layer "In4.Cu")
	)
	(gr_line
		(start 442.750702 -44.88942)
		(end 442.802772 -44.83735)
		(stroke
			(width 0.05715)
			(type default)
		)
		(layer "In4.Cu")
	)
	(gr_line
		(start 442.75375 -126.0856)
		(end 443.1792 -126.0856)
		(stroke
			(width 0.05715)
			(type default)
		)
		(layer "In4.Cu")
	)
	(gr_line
		(start 442.765434 -47.072042)
		(end 442.927994 -46.909482)
		(stroke
			(width 0.05715)
			(type default)
		)
		(layer "In4.Cu")
	)
	(gr_line
		(start 442.767974 -48.552354)
		(end 443.110874 -48.552354)
		(stroke
			(width 0.05715)
			(type default)
		)
		(layer "In4.Cu")
	)
	(gr_line
		(start 442.778134 -138.10107)
		(end 442.841634 -138.10107)
		(stroke
			(width 0.05715)
			(type default)
		)
		(layer "In4.Cu")
	)
	(gr_line
		(start 442.802772 -44.83735)
		(end 443.177168 -44.83735)
		(stroke
			(width 0.05715)
			(type default)
		)
		(layer "In4.Cu")
	)
	(gr_line
		(start 442.897514 -49.009554)
		(end 442.981334 -49.009554)
		(stroke
			(width 0.05715)
			(type default)
		)
		(layer "In4.Cu")
	)
	(gr_line
		(start 442.927994 -46.909482)
		(end 443.270894 -46.909482)
		(stroke
			(width 0.05715)
			(type default)
		)
		(layer "In4.Cu")
	)
	(gr_line
		(start 442.981334 -137.64387)
		(end 443.133734 -137.79627)
		(stroke
			(width 0.05715)
			(type default)
		)
		(layer "In4.Cu")
	)
	(gr_line
		(start 443.057534 -47.366682)
		(end 443.141354 -47.366682)
		(stroke
			(width 0.05715)
			(type default)
		)
		(layer "In4.Cu")
	)
	(gr_line
		(start 443.110874 -48.552354)
		(end 443.273434 -48.714914)
		(stroke
			(width 0.05715)
			(type default)
		)
		(layer "In4.Cu")
	)
	(gr_line
		(start 443.1792 -126.0856)
		(end 443.26302 -126.00178)
		(stroke
			(width 0.05715)
			(type default)
		)
		(layer "In4.Cu")
	)
	(gr_line
		(start 443.20841 -43.4975)
		(end 443.37097 -43.66006)
		(stroke
			(width 0.05715)
			(type default)
		)
		(layer "In4.Cu")
	)
	(gr_line
		(start 443.270894 -46.909482)
		(end 443.433454 -47.072042)
		(stroke
			(width 0.05715)
			(type default)
		)
		(layer "In4.Cu")
	)
	(gr_line
		(start 443.37097 -43.66006)
		(end 443.71387 -43.66006)
		(stroke
			(width 0.05715)
			(type default)
		)
		(layer "In4.Cu")
	)
	(gr_line
		(start 443.415928 -56.11876)
		(end 443.578488 -55.9562)
		(stroke
			(width 0.05715)
			(type default)
		)
		(layer "In4.Cu")
	)
	(gr_line
		(start 443.50051 -43.20286)
		(end 443.58433 -43.20286)
		(stroke
			(width 0.05715)
			(type default)
		)
		(layer "In4.Cu")
	)
	(gr_line
		(start 443.51575 -53.754274)
		(end 443.8904 -53.754274)
		(stroke
			(width 0.05715)
			(type default)
		)
		(layer "In4.Cu")
	)
	(gr_line
		(start 443.578488 -55.9562)
		(end 443.921388 -55.9562)
		(stroke
			(width 0.05715)
			(type default)
		)
		(layer "In4.Cu")
	)
	(gr_line
		(start 443.67958 -126.00178)
		(end 443.7634 -126.0856)
		(stroke
			(width 0.05715)
			(type default)
		)
		(layer "In4.Cu")
	)
	(gr_line
		(start 443.708028 -56.4134)
		(end 443.791848 -56.4134)
		(stroke
			(width 0.05715)
			(type default)
		)
		(layer "In4.Cu")
	)
	(gr_line
		(start 443.71387 -43.66006)
		(end 443.87643 -43.4975)
		(stroke
			(width 0.05715)
			(type default)
		)
		(layer "In4.Cu")
	)
	(gr_line
		(start 443.7634 -126.0856)
		(end 444.02375 -126.0856)
		(stroke
			(width 0.05715)
			(type default)
		)
		(layer "In4.Cu")
	)
	(gr_line
		(start 443.781434 -47.072042)
		(end 443.943994 -46.909482)
		(stroke
			(width 0.05715)
			(type default)
		)
		(layer "In4.Cu")
	)
	(gr_line
		(start 443.8904 -53.754274)
		(end 443.94247 -53.806344)
		(stroke
			(width 0.05715)
			(type default)
		)
		(layer "In4.Cu")
	)
	(gr_line
		(start 443.921388 -55.9562)
		(end 444.083948 -56.11876)
		(stroke
			(width 0.05715)
			(type default)
		)
		(layer "In4.Cu")
	)
	(gr_line
		(start 443.943994 -46.909482)
		(end 444.286894 -46.909482)
		(stroke
			(width 0.05715)
			(type default)
		)
		(layer "In4.Cu")
	)
	(gr_line
		(start 444.073534 -47.366682)
		(end 444.157354 -47.366682)
		(stroke
			(width 0.05715)
			(type default)
		)
		(layer "In4.Cu")
	)
	(gr_line
		(start 444.22441 -43.4975)
		(end 444.38697 -43.66006)
		(stroke
			(width 0.05715)
			(type default)
		)
		(layer "In4.Cu")
	)
	(gr_line
		(start 444.286894 -46.909482)
		(end 444.449454 -47.072042)
		(stroke
			(width 0.05715)
			(type default)
		)
		(layer "In4.Cu")
	)
	(gr_line
		(start 444.35903 -53.806344)
		(end 444.4111 -53.754274)
		(stroke
			(width 0.05715)
			(type default)
		)
		(layer "In4.Cu")
	)
	(gr_line
		(start 444.38697 -43.66006)
		(end 444.72987 -43.66006)
		(stroke
			(width 0.05715)
			(type default)
		)
		(layer "In4.Cu")
	)
	(gr_line
		(start 444.4111 -53.754274)
		(end 444.78575 -53.754274)
		(stroke
			(width 0.05715)
			(type default)
		)
		(layer "In4.Cu")
	)
	(gr_line
		(start 444.431928 -56.11876)
		(end 444.594488 -55.9562)
		(stroke
			(width 0.05715)
			(type default)
		)
		(layer "In4.Cu")
	)
	(gr_line
		(start 444.4619 -119.402606)
		(end 444.5127 -119.3927)
		(stroke
			(width 0.05715)
			(type default)
		)
		(layer "In4.Cu")
	)
	(gr_line
		(start 444.51651 -43.20286)
		(end 444.60033 -43.20286)
		(stroke
			(width 0.05715)
			(type default)
		)
		(layer "In4.Cu")
	)
	(gr_line
		(start 444.594488 -55.9562)
		(end 444.937388 -55.9562)
		(stroke
			(width 0.05715)
			(type default)
		)
		(layer "In4.Cu")
	)
	(gr_line
		(start 444.724028 -56.4134)
		(end 444.807848 -56.4134)
		(stroke
			(width 0.05715)
			(type default)
		)
		(layer "In4.Cu")
	)
	(gr_line
		(start 444.72987 -43.66006)
		(end 444.89243 -43.4975)
		(stroke
			(width 0.05715)
			(type default)
		)
		(layer "In4.Cu")
	)
	(gr_line
		(start 444.797434 -47.072042)
		(end 444.959994 -46.909482)
		(stroke
			(width 0.05715)
			(type default)
		)
		(layer "In4.Cu")
	)
	(gr_line
		(start 444.937388 -55.9562)
		(end 445.099948 -56.11876)
		(stroke
			(width 0.05715)
			(type default)
		)
		(layer "In4.Cu")
	)
	(gr_line
		(start 444.959994 -46.909482)
		(end 445.302894 -46.909482)
		(stroke
			(width 0.05715)
			(type default)
		)
		(layer "In4.Cu")
	)
	(gr_line
		(start 445.089534 -47.366682)
		(end 445.173354 -47.366682)
		(stroke
			(width 0.05715)
			(type default)
		)
		(layer "In4.Cu")
	)
	(gr_line
		(start 445.10706 -44.83735)
		(end 445.48171 -44.83735)
		(stroke
			(width 0.05715)
			(type default)
		)
		(layer "In4.Cu")
	)
	(gr_line
		(start 445.302894 -46.909482)
		(end 445.465454 -47.072042)
		(stroke
			(width 0.05715)
			(type default)
		)
		(layer "In4.Cu")
	)
	(gr_line
		(start 445.40805 -126.087124)
		(end 445.7827 -126.087124)
		(stroke
			(width 0.05715)
			(type default)
		)
		(layer "In4.Cu")
	)
	(gr_line
		(start 445.48171 -44.83735)
		(end 445.53378 -44.78528)
		(stroke
			(width 0.05715)
			(type default)
		)
		(layer "In4.Cu")
	)
	(gr_line
		(start 445.732916 -55.600346)
		(end 445.732916 -55.83047)
		(stroke
			(width 0.05715)
			(type default)
		)
		(layer "In4.Cu")
	)
	(gr_line
		(start 445.732916 -55.600346)
		(end 445.975486 -55.357776)
		(stroke
			(width 0.05715)
			(type default)
		)
		(layer "In4.Cu")
	)
	(gr_line
		(start 445.7827 -126.087124)
		(end 445.83477 -126.035054)
		(stroke
			(width 0.05715)
			(type default)
		)
		(layer "In4.Cu")
	)
	(gr_line
		(start 445.950594 -44.78528)
		(end 446.002664 -44.83735)
		(stroke
			(width 0.05715)
			(type default)
		)
		(layer "In4.Cu")
	)
	(gr_line
		(start 445.975486 -55.357776)
		(end 446.20561 -55.357776)
		(stroke
			(width 0.05715)
			(type default)
		)
		(layer "In4.Cu")
	)
	(gr_line
		(start 445.980058 -122.3518)
		(end 446.038986 -122.410728)
		(stroke
			(width 0.05715)
			(type default)
		)
		(layer "In4.Cu")
	)
	(gr_line
		(start 445.98844 -56.75376)
		(end 446.151 -56.5912)
		(stroke
			(width 0.05715)
			(type default)
		)
		(layer "In4.Cu")
	)
	(gr_line
		(start 446.002664 -44.83735)
		(end 446.37706 -44.83735)
		(stroke
			(width 0.05715)
			(type default)
		)
		(layer "In4.Cu")
	)
	(gr_line
		(start 446.147952 -55.831994)
		(end 446.207134 -55.772812)
		(stroke
			(width 0.05715)
			(type default)
		)
		(layer "In4.Cu")
	)
	(gr_line
		(start 446.151 -56.5912)
		(end 446.4939 -56.5912)
		(stroke
			(width 0.05715)
			(type default)
		)
		(layer "In4.Cu")
	)
	(gr_line
		(start 446.234312 -121.539)
		(end 446.29324 -121.597928)
		(stroke
			(width 0.05715)
			(type default)
		)
		(layer "In4.Cu")
	)
	(gr_line
		(start 446.25133 -126.035054)
		(end 446.3034 -126.087124)
		(stroke
			(width 0.05715)
			(type default)
		)
		(layer "In4.Cu")
	)
	(gr_line
		(start 446.28054 -57.0484)
		(end 446.36436 -57.0484)
		(stroke
			(width 0.05715)
			(type default)
		)
		(layer "In4.Cu")
	)
	(gr_line
		(start 446.3034 -126.087124)
		(end 446.67805 -126.087124)
		(stroke
			(width 0.05715)
			(type default)
		)
		(layer "In4.Cu")
	)
	(gr_line
		(start 446.451482 -54.88178)
		(end 446.451482 -55.111904)
		(stroke
			(width 0.05715)
			(type default)
		)
		(layer "In4.Cu")
	)
	(gr_line
		(start 446.451482 -54.88178)
		(end 446.693798 -54.639464)
		(stroke
			(width 0.05715)
			(type default)
		)
		(layer "In4.Cu")
	)
	(gr_line
		(start 446.4939 -56.5912)
		(end 446.65646 -56.75376)
		(stroke
			(width 0.05715)
			(type default)
		)
		(layer "In4.Cu")
	)
	(gr_line
		(start 446.6844 -123.056142)
		(end 446.699894 -123.071636)
		(stroke
			(width 0.05715)
			(type default)
		)
		(layer "In4.Cu")
	)
	(gr_line
		(start 446.693798 -54.639464)
		(end 446.923922 -54.639464)
		(stroke
			(width 0.05715)
			(type default)
		)
		(layer "In4.Cu")
	)
	(gr_line
		(start 446.699894 -123.071636)
		(end 446.708276 -123.091702)
		(stroke
			(width 0.05715)
			(type default)
		)
		(layer "In4.Cu")
	)
	(gr_line
		(start 446.703196 -122.421396)
		(end 446.719198 -122.437398)
		(stroke
			(width 0.05715)
			(type default)
		)
		(layer "In4.Cu")
	)
	(gr_line
		(start 446.71615 -53.754274)
		(end 447.0908 -53.754274)
		(stroke
			(width 0.05715)
			(type default)
		)
		(layer "In4.Cu")
	)
	(gr_line
		(start 446.719198 -122.437398)
		(end 446.741042 -122.446542)
		(stroke
			(width 0.05715)
			(type default)
		)
		(layer "In4.Cu")
	)
	(gr_line
		(start 446.866518 -55.113428)
		(end 446.925446 -55.0545)
		(stroke
			(width 0.05715)
			(type default)
		)
		(layer "In4.Cu")
	)
	(gr_line
		(start 446.892426 -124.300488)
		(end 446.900808 -124.320808)
		(stroke
			(width 0.05715)
			(type default)
		)
		(layer "In4.Cu")
	)
	(gr_line
		(start 446.90792 -121.58472)
		(end 446.923414 -121.600214)
		(stroke
			(width 0.05715)
			(type default)
		)
		(layer "In4.Cu")
	)
	(gr_line
		(start 446.923414 -121.600214)
		(end 446.94348 -121.608596)
		(stroke
			(width 0.05715)
			(type default)
		)
		(layer "In4.Cu")
	)
	(gr_line
		(start 447.00444 -56.75376)
		(end 447.167 -56.5912)
		(stroke
			(width 0.05715)
			(type default)
		)
		(layer "In4.Cu")
	)
	(gr_line
		(start 447.0908 -53.754274)
		(end 447.14287 -53.806344)
		(stroke
			(width 0.05715)
			(type default)
		)
		(layer "In4.Cu")
	)
	(gr_line
		(start 447.167 -56.5912)
		(end 447.5099 -56.5912)
		(stroke
			(width 0.05715)
			(type default)
		)
		(layer "In4.Cu")
	)
	(gr_line
		(start 447.29654 -57.0484)
		(end 447.38036 -57.0484)
		(stroke
			(width 0.05715)
			(type default)
		)
		(layer "In4.Cu")
	)
	(gr_line
		(start 447.5099 -56.5912)
		(end 447.67246 -56.75376)
		(stroke
			(width 0.05715)
			(type default)
		)
		(layer "In4.Cu")
	)
	(gr_line
		(start 447.519298 -124.939044)
		(end 447.538094 -124.946918)
		(stroke
			(width 0.05715)
			(type default)
		)
		(layer "In4.Cu")
	)
	(gr_line
		(start 447.55943 -53.806344)
		(end 447.6115 -53.754274)
		(stroke
			(width 0.05715)
			(type default)
		)
		(layer "In4.Cu")
	)
	(gr_line
		(start 447.6115 -53.754274)
		(end 447.98615 -53.754274)
		(stroke
			(width 0.05715)
			(type default)
		)
		(layer "In4.Cu")
	)
	(gr_line
		(start 447.949574 -137.510774)
		(end 447.949574 -137.72642)
		(stroke
			(width 0.05715)
			(type default)
		)
		(layer "In4.Cu")
	)
	(gr_line
		(start 447.949574 -137.510774)
		(end 448.19189 -137.268458)
		(stroke
			(width 0.05715)
			(type default)
		)
		(layer "In4.Cu")
	)
	(gr_line
		(start 448.02044 -56.75376)
		(end 448.183 -56.5912)
		(stroke
			(width 0.05715)
			(type default)
		)
		(layer "In4.Cu")
	)
	(gr_line
		(start 448.062604 -122.071892)
		(end 448.067176 -122.07367)
		(stroke
			(width 0.05715)
			(type default)
		)
		(layer "In4.Cu")
	)
	(gr_line
		(start 448.067176 -122.07367)
		(end 448.072256 -122.074178)
		(stroke
			(width 0.05715)
			(type default)
		)
		(layer "In4.Cu")
	)
	(gr_line
		(start 448.183 -56.5912)
		(end 448.5259 -56.5912)
		(stroke
			(width 0.05715)
			(type default)
		)
		(layer "In4.Cu")
	)
	(gr_line
		(start 448.19189 -137.268458)
		(end 448.407536 -137.268458)
		(stroke
			(width 0.05715)
			(type default)
		)
		(layer "In4.Cu")
	)
	(gr_line
		(start 448.306952 -44.83735)
		(end 448.65925 -44.83735)
		(stroke
			(width 0.05715)
			(type default)
		)
		(layer "In4.Cu")
	)
	(gr_line
		(start 448.31254 -57.0484)
		(end 448.39636 -57.0484)
		(stroke
			(width 0.05715)
			(type default)
		)
		(layer "In4.Cu")
	)
	(gr_line
		(start 448.36842 -125.290834)
		(end 448.385692 -125.2982)
		(stroke
			(width 0.05715)
			(type default)
		)
		(layer "In4.Cu")
	)
	(gr_line
		(start 448.371722 -137.73531)
		(end 448.416426 -137.690606)
		(stroke
			(width 0.05715)
			(type default)
		)
		(layer "In4.Cu")
	)
	(gr_line
		(start 448.39255 -123.78817)
		(end 448.7672 -123.78817)
		(stroke
			(width 0.05715)
			(type default)
		)
		(layer "In4.Cu")
	)
	(gr_line
		(start 448.5259 -56.5912)
		(end 448.68846 -56.75376)
		(stroke
			(width 0.05715)
			(type default)
		)
		(layer "In4.Cu")
	)
	(gr_line
		(start 448.65925 -44.83735)
		(end 448.722496 -44.900596)
		(stroke
			(width 0.05715)
			(type default)
		)
		(layer "In4.Cu")
	)
	(gr_line
		(start 448.667886 -136.792462)
		(end 448.667886 -137.008108)
		(stroke
			(width 0.05715)
			(type default)
		)
		(layer "In4.Cu")
	)
	(gr_line
		(start 448.667886 -136.792462)
		(end 448.910202 -136.550146)
		(stroke
			(width 0.05715)
			(type default)
		)
		(layer "In4.Cu")
	)
	(gr_line
		(start 448.7672 -123.78817)
		(end 448.81927 -123.7361)
		(stroke
			(width 0.05715)
			(type default)
		)
		(layer "In4.Cu")
	)
	(gr_line
		(start 448.891152 -123.020582)
		(end 448.911218 -123.028964)
		(stroke
			(width 0.05715)
			(type default)
		)
		(layer "In4.Cu")
	)
	(gr_line
		(start 448.910202 -136.550146)
		(end 449.125848 -136.550146)
		(stroke
			(width 0.05715)
			(type default)
		)
		(layer "In4.Cu")
	)
	(gr_line
		(start 449.090034 -137.016998)
		(end 449.134738 -136.972294)
		(stroke
			(width 0.05715)
			(type default)
		)
		(layer "In4.Cu")
	)
	(gr_line
		(start 449.114672 -123.232672)
		(end 449.1736 -123.2916)
		(stroke
			(width 0.05715)
			(type default)
		)
		(layer "In4.Cu")
	)
	(gr_line
		(start 449.13931 -44.900596)
		(end 449.202556 -44.83735)
		(stroke
			(width 0.05715)
			(type default)
		)
		(layer "In4.Cu")
	)
	(gr_line
		(start 449.202556 -44.83735)
		(end 449.576952 -44.83735)
		(stroke
			(width 0.05715)
			(type default)
		)
		(layer "In4.Cu")
	)
	(gr_line
		(start 449.23583 -123.7361)
		(end 449.2879 -123.78817)
		(stroke
			(width 0.05715)
			(type default)
		)
		(layer "In4.Cu")
	)
	(gr_line
		(start 449.27647 -56.280304)
		(end 449.27647 -56.510428)
		(stroke
			(width 0.05715)
			(type default)
		)
		(layer "In4.Cu")
	)
	(gr_line
		(start 449.27647 -56.280304)
		(end 449.518786 -56.037988)
		(stroke
			(width 0.05715)
			(type default)
		)
		(layer "In4.Cu")
	)
	(gr_line
		(start 449.2879 -123.78817)
		(end 449.66255 -123.78817)
		(stroke
			(width 0.05715)
			(type default)
		)
		(layer "In4.Cu")
	)
	(gr_line
		(start 449.518786 -56.037988)
		(end 449.74891 -56.037988)
		(stroke
			(width 0.05715)
			(type default)
		)
		(layer "In4.Cu")
	)
	(gr_line
		(start 449.658994 -125.2982)
		(end 449.677536 -125.29058)
		(stroke
			(width 0.05715)
			(type default)
		)
		(layer "In4.Cu")
	)
	(gr_line
		(start 449.691506 -56.511952)
		(end 449.750434 -56.453024)
		(stroke
			(width 0.05715)
			(type default)
		)
		(layer "In4.Cu")
	)
	(gr_line
		(start 449.91655 -53.754274)
		(end 450.2912 -53.754274)
		(stroke
			(width 0.05715)
			(type default)
		)
		(layer "In4.Cu")
	)
	(gr_line
		(start 450.287644 -124.721366)
		(end 450.838316 -124.493274)
		(stroke
			(width 0.05715)
			(type default)
		)
		(layer "In4.Cu")
	)
	(gr_line
		(start 450.2912 -53.754274)
		(end 450.34327 -53.806344)
		(stroke
			(width 0.05715)
			(type default)
		)
		(layer "In4.Cu")
	)
	(gr_line
		(start 450.366892 -125.00737)
		(end 450.579236 -125.095508)
		(stroke
			(width 0.05715)
			(type default)
		)
		(layer "In4.Cu")
	)
	(gr_line
		(start 450.579236 -125.095508)
		(end 450.895974 -124.96419)
		(stroke
			(width 0.05715)
			(type default)
		)
		(layer "In4.Cu")
	)
	(gr_line
		(start 450.760084 -53.806344)
		(end 450.812154 -53.754274)
		(stroke
			(width 0.05715)
			(type default)
		)
		(layer "In4.Cu")
	)
	(gr_line
		(start 450.812154 -53.754274)
		(end 451.18655 -53.754274)
		(stroke
			(width 0.05715)
			(type default)
		)
		(layer "In4.Cu")
	)
	(gr_line
		(start 450.895974 -124.96419)
		(end 450.984112 -124.751592)
		(stroke
			(width 0.05715)
			(type default)
		)
		(layer "In4.Cu")
	)
	(gr_line
		(start 451.283324 -124.6251)
		(end 451.30212 -124.617226)
		(stroke
			(width 0.05715)
			(type default)
		)
		(layer "In4.Cu")
	)
	(gr_line
		(start 451.359524 -56.915304)
		(end 451.359524 -57.145428)
		(stroke
			(width 0.05715)
			(type default)
		)
		(layer "In4.Cu")
	)
	(gr_line
		(start 451.359524 -56.915304)
		(end 451.60184 -56.672988)
		(stroke
			(width 0.05715)
			(type default)
		)
		(layer "In4.Cu")
	)
	(gr_line
		(start 451.507098 -44.83735)
		(end 451.881748 -44.83735)
		(stroke
			(width 0.05715)
			(type default)
		)
		(layer "In4.Cu")
	)
	(gr_line
		(start 451.60184 -56.672988)
		(end 451.831964 -56.672988)
		(stroke
			(width 0.05715)
			(type default)
		)
		(layer "In4.Cu")
	)
	(gr_line
		(start 451.77456 -57.146952)
		(end 451.833488 -57.088024)
		(stroke
			(width 0.05715)
			(type default)
		)
		(layer "In4.Cu")
	)
	(gr_line
		(start 451.788022 -123.718066)
		(end 451.804532 -123.701556)
		(stroke
			(width 0.05715)
			(type default)
		)
		(layer "In4.Cu")
	)
	(gr_line
		(start 451.804532 -123.701556)
		(end 451.825614 -123.692666)
		(stroke
			(width 0.05715)
			(type default)
		)
		(layer "In4.Cu")
	)
	(gr_line
		(start 451.881748 -44.83735)
		(end 451.933818 -44.88942)
		(stroke
			(width 0.05715)
			(type default)
		)
		(layer "In4.Cu")
	)
	(gr_line
		(start 452.077836 -56.196992)
		(end 452.077836 -56.427116)
		(stroke
			(width 0.05715)
			(type default)
		)
		(layer "In4.Cu")
	)
	(gr_line
		(start 452.077836 -56.196992)
		(end 452.320152 -55.954676)
		(stroke
			(width 0.05715)
			(type default)
		)
		(layer "In4.Cu")
	)
	(gr_line
		(start 452.320152 -55.954676)
		(end 452.550276 -55.954676)
		(stroke
			(width 0.05715)
			(type default)
		)
		(layer "In4.Cu")
	)
	(gr_line
		(start 452.350632 -44.88942)
		(end 452.402702 -44.83735)
		(stroke
			(width 0.05715)
			(type default)
		)
		(layer "In4.Cu")
	)
	(gr_line
		(start 452.402702 -44.83735)
		(end 452.777098 -44.83735)
		(stroke
			(width 0.05715)
			(type default)
		)
		(layer "In4.Cu")
	)
	(gr_line
		(start 452.492872 -56.42864)
		(end 452.5518 -56.369712)
		(stroke
			(width 0.05715)
			(type default)
		)
		(layer "In4.Cu")
	)
	(gr_line
		(start 452.67372 -123.341892)
		(end 452.690992 -123.334526)
		(stroke
			(width 0.05715)
			(type default)
		)
		(layer "In4.Cu")
	)
	(gr_line
		(start 452.773034 -60.941966)
		(end 452.935594 -60.779406)
		(stroke
			(width 0.05715)
			(type default)
		)
		(layer "In4.Cu")
	)
	(gr_line
		(start 452.935594 -60.779406)
		(end 453.291194 -60.779406)
		(stroke
			(width 0.05715)
			(type default)
		)
		(layer "In4.Cu")
	)
	(gr_line
		(start 453.065134 -61.236606)
		(end 453.161654 -61.236606)
		(stroke
			(width 0.05715)
			(type default)
		)
		(layer "In4.Cu")
	)
	(gr_line
		(start 453.11695 -53.754274)
		(end 453.4916 -53.754274)
		(stroke
			(width 0.05715)
			(type default)
		)
		(layer "In4.Cu")
	)
	(gr_line
		(start 453.26935 -124.18822)
		(end 453.644 -124.18822)
		(stroke
			(width 0.05715)
			(type default)
		)
		(layer "In4.Cu")
	)
	(gr_line
		(start 453.291194 -60.779406)
		(end 453.453754 -60.941966)
		(stroke
			(width 0.05715)
			(type default)
		)
		(layer "In4.Cu")
	)
	(gr_line
		(start 453.314562 -119.893842)
		(end 453.322944 -119.913908)
		(stroke
			(width 0.05715)
			(type default)
		)
		(layer "In4.Cu")
	)
	(gr_line
		(start 453.467724 -117.8687)
		(end 453.484996 -117.876066)
		(stroke
			(width 0.05715)
			(type default)
		)
		(layer "In4.Cu")
	)
	(gr_line
		(start 453.4916 -53.754274)
		(end 453.54367 -53.806344)
		(stroke
			(width 0.05715)
			(type default)
		)
		(layer "In4.Cu")
	)
	(gr_line
		(start 453.541892 -123.334526)
		(end 453.601074 -123.393454)
		(stroke
			(width 0.05715)
			(type default)
		)
		(layer "In4.Cu")
	)
	(gr_line
		(start 453.644 -124.18822)
		(end 453.69607 -124.13615)
		(stroke
			(width 0.05715)
			(type default)
		)
		(layer "In4.Cu")
	)
	(gr_line
		(start 453.673972 -122.579384)
		(end 453.69353 -122.587512)
		(stroke
			(width 0.05715)
			(type default)
		)
		(layer "In4.Cu")
	)
	(gr_line
		(start 453.69353 -122.587512)
		(end 453.70877 -122.602752)
		(stroke
			(width 0.05715)
			(type default)
		)
		(layer "In4.Cu")
	)
	(gr_line
		(start 453.69607 -57.651904)
		(end 453.69607 -57.882028)
		(stroke
			(width 0.05715)
			(type default)
		)
		(layer "In4.Cu")
	)
	(gr_line
		(start 453.69607 -57.651904)
		(end 453.938386 -57.409588)
		(stroke
			(width 0.05715)
			(type default)
		)
		(layer "In4.Cu")
	)
	(gr_line
		(start 453.814434 -60.941966)
		(end 453.976994 -60.779406)
		(stroke
			(width 0.05715)
			(type default)
		)
		(layer "In4.Cu")
	)
	(gr_line
		(start 453.938386 -57.409588)
		(end 454.16851 -57.409588)
		(stroke
			(width 0.05715)
			(type default)
		)
		(layer "In4.Cu")
	)
	(gr_line
		(start 453.96023 -53.806344)
		(end 454.0123 -53.754274)
		(stroke
			(width 0.05715)
			(type default)
		)
		(layer "In4.Cu")
	)
	(gr_line
		(start 453.976994 -60.779406)
		(end 454.332594 -60.779406)
		(stroke
			(width 0.05715)
			(type default)
		)
		(layer "In4.Cu")
	)
	(gr_line
		(start 453.992488 -123.784868)
		(end 454.0504 -123.842526)
		(stroke
			(width 0.05715)
			(type default)
		)
		(layer "In4.Cu")
	)
	(gr_line
		(start 454.004934 -121.560844)
		(end 454.0123 -121.578116)
		(stroke
			(width 0.05715)
			(type default)
		)
		(layer "In4.Cu")
	)
	(gr_line
		(start 454.0123 -53.754274)
		(end 454.38695 -53.754274)
		(stroke
			(width 0.05715)
			(type default)
		)
		(layer "In4.Cu")
	)
	(gr_line
		(start 454.085452 -123.392692)
		(end 454.14438 -123.45162)
		(stroke
			(width 0.05715)
			(type default)
		)
		(layer "In4.Cu")
	)
	(gr_line
		(start 454.106534 -61.236606)
		(end 454.203054 -61.236606)
		(stroke
			(width 0.05715)
			(type default)
		)
		(layer "In4.Cu")
	)
	(gr_line
		(start 454.111106 -57.883552)
		(end 454.170034 -57.824624)
		(stroke
			(width 0.05715)
			(type default)
		)
		(layer "In4.Cu")
	)
	(gr_line
		(start 454.11263 -124.13615)
		(end 454.1647 -124.18822)
		(stroke
			(width 0.05715)
			(type default)
		)
		(layer "In4.Cu")
	)
	(gr_line
		(start 454.1647 -124.18822)
		(end 454.53935 -124.18822)
		(stroke
			(width 0.05715)
			(type default)
		)
		(layer "In4.Cu")
	)
	(gr_line
		(start 454.332594 -60.779406)
		(end 454.495154 -60.941966)
		(stroke
			(width 0.05715)
			(type default)
		)
		(layer "In4.Cu")
	)
	(gr_line
		(start 454.414382 -56.933592)
		(end 454.414382 -57.163716)
		(stroke
			(width 0.05715)
			(type default)
		)
		(layer "In4.Cu")
	)
	(gr_line
		(start 454.414382 -56.933592)
		(end 454.656952 -56.691022)
		(stroke
			(width 0.05715)
			(type default)
		)
		(layer "In4.Cu")
	)
	(gr_line
		(start 454.471278 -118.284244)
		(end 454.491344 -118.292626)
		(stroke
			(width 0.05715)
			(type default)
		)
		(layer "In4.Cu")
	)
	(gr_line
		(start 454.574656 -119.02313)
		(end 454.817226 -119.265446)
		(stroke
			(width 0.05715)
			(type default)
		)
		(layer "In4.Cu")
	)
	(gr_line
		(start 454.574656 -118.792498)
		(end 454.574656 -119.02313)
		(stroke
			(width 0.05715)
			(type default)
		)
		(layer "In4.Cu")
	)
	(gr_line
		(start 454.656952 -56.691022)
		(end 454.887076 -56.691022)
		(stroke
			(width 0.05715)
			(type default)
		)
		(layer "In4.Cu")
	)
	(gr_line
		(start 454.70699 -44.83735)
		(end 455.08164 -44.83735)
		(stroke
			(width 0.05715)
			(type default)
		)
		(layer "In4.Cu")
	)
	(gr_line
		(start 454.817226 -119.265446)
		(end 455.047604 -119.265446)
		(stroke
			(width 0.05715)
			(type default)
		)
		(layer "In4.Cu")
	)
	(gr_line
		(start 454.829418 -57.16524)
		(end 454.8886 -57.106058)
		(stroke
			(width 0.05715)
			(type default)
		)
		(layer "In4.Cu")
	)
	(gr_line
		(start 454.989692 -118.790974)
		(end 455.049128 -118.85041)
		(stroke
			(width 0.05715)
			(type default)
		)
		(layer "In4.Cu")
	)
	(gr_line
		(start 455.08164 -44.83735)
		(end 455.13371 -44.88942)
		(stroke
			(width 0.05715)
			(type default)
		)
		(layer "In4.Cu")
	)
	(gr_line
		(start 455.293222 -119.741442)
		(end 455.535538 -119.984012)
		(stroke
			(width 0.05715)
			(type default)
		)
		(layer "In4.Cu")
	)
	(gr_line
		(start 455.293222 -119.511064)
		(end 455.293222 -119.741442)
		(stroke
			(width 0.05715)
			(type default)
		)
		(layer "In4.Cu")
	)
	(gr_line
		(start 455.535538 -119.984012)
		(end 455.76617 -119.984012)
		(stroke
			(width 0.05715)
			(type default)
		)
		(layer "In4.Cu")
	)
	(gr_line
		(start 455.550524 -44.88942)
		(end 455.602594 -44.83735)
		(stroke
			(width 0.05715)
			(type default)
		)
		(layer "In4.Cu")
	)
	(gr_line
		(start 455.602594 -44.83735)
		(end 455.97699 -44.83735)
		(stroke
			(width 0.05715)
			(type default)
		)
		(layer "In4.Cu")
	)
	(gr_line
		(start 455.708258 -119.50954)
		(end 455.767694 -119.568976)
		(stroke
			(width 0.05715)
			(type default)
		)
		(layer "In4.Cu")
	)
	(gr_line
		(start 456.112626 -123.15952)
		(end 456.131168 -123.16714)
		(stroke
			(width 0.05715)
			(type default)
		)
		(layer "In4.Cu")
	)
	(gr_line
		(start 456.21575 -124.18822)
		(end 456.5904 -124.18822)
		(stroke
			(width 0.05715)
			(type default)
		)
		(layer "In4.Cu")
	)
	(gr_line
		(start 456.311 -140.8938)
		(end 456.4634 -140.7414)
		(stroke
			(width 0.05715)
			(type default)
		)
		(layer "In4.Cu")
	)
	(gr_line
		(start 456.317604 -53.906674)
		(end 456.577954 -53.906674)
		(stroke
			(width 0.05715)
			(type default)
		)
		(layer "In4.Cu")
	)
	(gr_line
		(start 456.4634 -140.7414)
		(end 456.8063 -140.7414)
		(stroke
			(width 0.05715)
			(type default)
		)
		(layer "In4.Cu")
	)
	(gr_line
		(start 456.577954 -53.906674)
		(end 456.687174 -54.015894)
		(stroke
			(width 0.05715)
			(type default)
		)
		(layer "In4.Cu")
	)
	(gr_line
		(start 456.5904 -124.18822)
		(end 456.64247 -124.13615)
		(stroke
			(width 0.05715)
			(type default)
		)
		(layer "In4.Cu")
	)
	(gr_line
		(start 456.6031 -141.1986)
		(end 456.6666 -141.1986)
		(stroke
			(width 0.05715)
			(type default)
		)
		(layer "In4.Cu")
	)
	(gr_line
		(start 456.683618 -123.396248)
		(end 456.702414 -123.404122)
		(stroke
			(width 0.05715)
			(type default)
		)
		(layer "In4.Cu")
	)
	(gr_line
		(start 456.8063 -140.7414)
		(end 456.9587 -140.8938)
		(stroke
			(width 0.05715)
			(type default)
		)
		(layer "In4.Cu")
	)
	(gr_line
		(start 457.05903 -124.13615)
		(end 457.1111 -124.18822)
		(stroke
			(width 0.05715)
			(type default)
		)
		(layer "In4.Cu")
	)
	(gr_line
		(start 457.103988 -54.015894)
		(end 457.213208 -53.906674)
		(stroke
			(width 0.05715)
			(type default)
		)
		(layer "In4.Cu")
	)
	(gr_line
		(start 457.1111 -124.18822)
		(end 457.48575 -124.18822)
		(stroke
			(width 0.05715)
			(type default)
		)
		(layer "In4.Cu")
	)
	(gr_line
		(start 457.113894 -121.562114)
		(end 457.35621 -121.80443)
		(stroke
			(width 0.05715)
			(type default)
		)
		(layer "In4.Cu")
	)
	(gr_line
		(start 457.113894 -121.331736)
		(end 457.113894 -121.562114)
		(stroke
			(width 0.05715)
			(type default)
		)
		(layer "In4.Cu")
	)
	(gr_line
		(start 457.213208 -53.906674)
		(end 457.587604 -53.906674)
		(stroke
			(width 0.05715)
			(type default)
		)
		(layer "In4.Cu")
	)
	(gr_line
		(start 457.35621 -121.80443)
		(end 457.586588 -121.80443)
		(stroke
			(width 0.05715)
			(type default)
		)
		(layer "In4.Cu")
	)
	(gr_line
		(start 457.52893 -121.330212)
		(end 457.588112 -121.389394)
		(stroke
			(width 0.05715)
			(type default)
		)
		(layer "In4.Cu")
	)
	(gr_line
		(start 457.832206 -122.047)
		(end 457.852272 -122.055382)
		(stroke
			(width 0.05715)
			(type default)
		)
		(layer "In4.Cu")
	)
	(gr_line
		(start 457.907136 -44.83735)
		(end 458.281786 -44.83735)
		(stroke
			(width 0.05715)
			(type default)
		)
		(layer "In4.Cu")
	)
	(gr_line
		(start 457.963778 -141.969236)
		(end 458.008482 -142.01394)
		(stroke
			(width 0.05715)
			(type default)
		)
		(layer "In4.Cu")
	)
	(gr_line
		(start 457.972668 -141.547088)
		(end 458.188314 -141.547088)
		(stroke
			(width 0.05715)
			(type default)
		)
		(layer "In4.Cu")
	)
	(gr_line
		(start 458.188314 -141.547088)
		(end 458.43063 -141.789404)
		(stroke
			(width 0.05715)
			(type default)
		)
		(layer "In4.Cu")
	)
	(gr_line
		(start 458.281786 -44.83735)
		(end 458.333856 -44.88942)
		(stroke
			(width 0.05715)
			(type default)
		)
		(layer "In4.Cu")
	)
	(gr_line
		(start 458.3811 -144.2212)
		(end 458.3811 -144.2847)
		(stroke
			(width 0.05715)
			(type default)
		)
		(layer "In4.Cu")
	)
	(gr_line
		(start 458.3811 -142.9131)
		(end 458.3811 -142.9766)
		(stroke
			(width 0.05715)
			(type default)
		)
		(layer "In4.Cu")
	)
	(gr_line
		(start 458.43063 -141.789404)
		(end 458.43063 -142.00505)
		(stroke
			(width 0.05715)
			(type default)
		)
		(layer "In4.Cu")
	)
	(gr_line
		(start 458.6859 -144.5768)
		(end 458.8383 -144.4244)
		(stroke
			(width 0.05715)
			(type default)
		)
		(layer "In4.Cu")
	)
	(gr_line
		(start 458.6859 -143.9291)
		(end 458.8383 -144.0815)
		(stroke
			(width 0.05715)
			(type default)
		)
		(layer "In4.Cu")
	)
	(gr_line
		(start 458.6859 -143.2687)
		(end 458.8383 -143.1163)
		(stroke
			(width 0.05715)
			(type default)
		)
		(layer "In4.Cu")
	)
	(gr_line
		(start 458.6859 -142.621)
		(end 458.8383 -142.7734)
		(stroke
			(width 0.05715)
			(type default)
		)
		(layer "In4.Cu")
	)
	(gr_line
		(start 458.75067 -44.88942)
		(end 458.80274 -44.83735)
		(stroke
			(width 0.05715)
			(type default)
		)
		(layer "In4.Cu")
	)
	(gr_line
		(start 458.80274 -44.83735)
		(end 459.177136 -44.83735)
		(stroke
			(width 0.05715)
			(type default)
		)
		(layer "In4.Cu")
	)
	(gr_line
		(start 458.8383 -144.0815)
		(end 458.8383 -144.4244)
		(stroke
			(width 0.05715)
			(type default)
		)
		(layer "In4.Cu")
	)
	(gr_line
		(start 458.8383 -142.7734)
		(end 458.8383 -143.1163)
		(stroke
			(width 0.05715)
			(type default)
		)
		(layer "In4.Cu")
	)
	(gr_line
		(start 458.931772 -122.90552)
		(end 458.982572 -122.915426)
		(stroke
			(width 0.05715)
			(type default)
		)
		(layer "In4.Cu")
	)
	(gr_line
		(start 458.97165 -124.13742)
		(end 459.3463 -124.13742)
		(stroke
			(width 0.05715)
			(type default)
		)
		(layer "In4.Cu")
	)
	(gr_line
		(start 458.982572 -122.915426)
		(end 459.019656 -122.95251)
		(stroke
			(width 0.05715)
			(type default)
		)
		(layer "In4.Cu")
	)
	(gr_line
		(start 459.081124 -144.977104)
		(end 459.246478 -144.81175)
		(stroke
			(width 0.05715)
			(type default)
		)
		(layer "In4.Cu")
	)
	(gr_line
		(start 459.3463 -124.13742)
		(end 459.39837 -124.08535)
		(stroke
			(width 0.05715)
			(type default)
		)
		(layer "In4.Cu")
	)
	(gr_line
		(start 459.51775 -53.906674)
		(end 459.8924 -53.906674)
		(stroke
			(width 0.05715)
			(type default)
		)
		(layer "In4.Cu")
	)
	(gr_line
		(start 459.693772 -123.626626)
		(end 459.7527 -123.685554)
		(stroke
			(width 0.05715)
			(type default)
		)
		(layer "In4.Cu")
	)
	(gr_line
		(start 459.81493 -124.08535)
		(end 459.867 -124.13742)
		(stroke
			(width 0.05715)
			(type default)
		)
		(layer "In4.Cu")
	)
	(gr_line
		(start 459.867 -124.13742)
		(end 460.24165 -124.13742)
		(stroke
			(width 0.05715)
			(type default)
		)
		(layer "In4.Cu")
	)
	(gr_line
		(start 459.8924 -53.906674)
		(end 459.94447 -53.958744)
		(stroke
			(width 0.05715)
			(type default)
		)
		(layer "In4.Cu")
	)
	(gr_line
		(start 460.328772 -123.081034)
		(end 460.346044 -123.0884)
		(stroke
			(width 0.05715)
			(type default)
		)
		(layer "In4.Cu")
	)
	(gr_line
		(start 460.361284 -53.958744)
		(end 460.413354 -53.906674)
		(stroke
			(width 0.05715)
			(type default)
		)
		(layer "In4.Cu")
	)
	(gr_line
		(start 460.413354 -53.906674)
		(end 460.78775 -53.906674)
		(stroke
			(width 0.05715)
			(type default)
		)
		(layer "In4.Cu")
	)
	(gr_line
		(start 460.815182 -51.91506)
		(end 460.977742 -51.7525)
		(stroke
			(width 0.05715)
			(type default)
		)
		(layer "In4.Cu")
	)
	(gr_line
		(start 460.977742 -51.7525)
		(end 461.320642 -51.7525)
		(stroke
			(width 0.05715)
			(type default)
		)
		(layer "In4.Cu")
	)
	(gr_line
		(start 460.99857 -58.174128)
		(end 460.99857 -58.41873)
		(stroke
			(width 0.05715)
			(type default)
		)
		(layer "In4.Cu")
	)
	(gr_line
		(start 460.99857 -58.174128)
		(end 461.24114 -57.931812)
		(stroke
			(width 0.05715)
			(type default)
		)
		(layer "In4.Cu")
	)
	(gr_line
		(start 461.107028 -44.83735)
		(end 461.481678 -44.83735)
		(stroke
			(width 0.05715)
			(type default)
		)
		(layer "In4.Cu")
	)
	(gr_line
		(start 461.107282 -52.2097)
		(end 461.191102 -52.2097)
		(stroke
			(width 0.05715)
			(type default)
		)
		(layer "In4.Cu")
	)
	(gr_line
		(start 461.24114 -57.931812)
		(end 461.485488 -57.931812)
		(stroke
			(width 0.05715)
			(type default)
		)
		(layer "In4.Cu")
	)
	(gr_line
		(start 461.320642 -51.7525)
		(end 461.483202 -51.91506)
		(stroke
			(width 0.05715)
			(type default)
		)
		(layer "In4.Cu")
	)
	(gr_line
		(start 461.341724 -122.7963)
		(end 461.358996 -122.803666)
		(stroke
			(width 0.05715)
			(type default)
		)
		(layer "In4.Cu")
	)
	(gr_line
		(start 461.413606 -58.420254)
		(end 461.487012 -58.346848)
		(stroke
			(width 0.05715)
			(type default)
		)
		(layer "In4.Cu")
	)
	(gr_line
		(start 461.481678 -44.83735)
		(end 461.533748 -44.88942)
		(stroke
			(width 0.05715)
			(type default)
		)
		(layer "In4.Cu")
	)
	(gr_line
		(start 461.73136 -57.441338)
		(end 461.73136 -57.68594)
		(stroke
			(width 0.05715)
			(type default)
		)
		(layer "In4.Cu")
	)
	(gr_line
		(start 461.73136 -57.441338)
		(end 461.97393 -57.199022)
		(stroke
			(width 0.05715)
			(type default)
		)
		(layer "In4.Cu")
	)
	(gr_line
		(start 461.831182 -51.91506)
		(end 461.993742 -51.7525)
		(stroke
			(width 0.05715)
			(type default)
		)
		(layer "In4.Cu")
	)
	(gr_line
		(start 461.950308 -44.88942)
		(end 462.002378 -44.83735)
		(stroke
			(width 0.05715)
			(type default)
		)
		(layer "In4.Cu")
	)
	(gr_line
		(start 461.97393 -57.199022)
		(end 462.218278 -57.199022)
		(stroke
			(width 0.05715)
			(type default)
		)
		(layer "In4.Cu")
	)
	(gr_line
		(start 461.993742 -51.7525)
		(end 462.336642 -51.7525)
		(stroke
			(width 0.05715)
			(type default)
		)
		(layer "In4.Cu")
	)
	(gr_line
		(start 462.002378 -44.83735)
		(end 462.377028 -44.83735)
		(stroke
			(width 0.05715)
			(type default)
		)
		(layer "In4.Cu")
	)
	(gr_line
		(start 462.05775 -124.18822)
		(end 462.4324 -124.18822)
		(stroke
			(width 0.05715)
			(type default)
		)
		(layer "In4.Cu")
	)
	(gr_line
		(start 462.123282 -52.2097)
		(end 462.207102 -52.2097)
		(stroke
			(width 0.05715)
			(type default)
		)
		(layer "In4.Cu")
	)
	(gr_line
		(start 462.146396 -57.687464)
		(end 462.219802 -57.614058)
		(stroke
			(width 0.05715)
			(type default)
		)
		(layer "In4.Cu")
	)
	(gr_line
		(start 462.336642 -51.7525)
		(end 462.499202 -51.91506)
		(stroke
			(width 0.05715)
			(type default)
		)
		(layer "In4.Cu")
	)
	(gr_line
		(start 462.4324 -124.18822)
		(end 462.50733 -124.11329)
		(stroke
			(width 0.05715)
			(type default)
		)
		(layer "In4.Cu")
	)
	(gr_line
		(start 462.46415 -56.708548)
		(end 462.46415 -56.95315)
		(stroke
			(width 0.05715)
			(type default)
		)
		(layer "In4.Cu")
	)
	(gr_line
		(start 462.46415 -56.708548)
		(end 462.70672 -56.466232)
		(stroke
			(width 0.05715)
			(type default)
		)
		(layer "In4.Cu")
	)
	(gr_line
		(start 462.47939 -123.26747)
		(end 462.499456 -123.275852)
		(stroke
			(width 0.05715)
			(type default)
		)
		(layer "In4.Cu")
	)
	(gr_line
		(start 462.499456 -123.275852)
		(end 462.51495 -123.291346)
		(stroke
			(width 0.05715)
			(type default)
		)
		(layer "In4.Cu")
	)
	(gr_line
		(start 462.70672 -56.466232)
		(end 462.951068 -56.466232)
		(stroke
			(width 0.05715)
			(type default)
		)
		(layer "In4.Cu")
	)
	(gr_line
		(start 462.70799 -53.888894)
		(end 463.08264 -53.888894)
		(stroke
			(width 0.05715)
			(type default)
		)
		(layer "In4.Cu")
	)
	(gr_line
		(start 462.780126 -123.556268)
		(end 462.8388 -123.614942)
		(stroke
			(width 0.05715)
			(type default)
		)
		(layer "In4.Cu")
	)
	(gr_line
		(start 462.847182 -51.91506)
		(end 463.009742 -51.7525)
		(stroke
			(width 0.05715)
			(type default)
		)
		(layer "In4.Cu")
	)
	(gr_line
		(start 462.879186 -56.954674)
		(end 462.952592 -56.881268)
		(stroke
			(width 0.05715)
			(type default)
		)
		(layer "In4.Cu")
	)
	(gr_line
		(start 462.92389 -124.11329)
		(end 462.99882 -124.18822)
		(stroke
			(width 0.05715)
			(type default)
		)
		(layer "In4.Cu")
	)
	(gr_line
		(start 462.99882 -124.18822)
		(end 463.32775 -124.18822)
		(stroke
			(width 0.05715)
			(type default)
		)
		(layer "In4.Cu")
	)
	(gr_line
		(start 463.009742 -51.7525)
		(end 463.352642 -51.7525)
		(stroke
			(width 0.05715)
			(type default)
		)
		(layer "In4.Cu")
	)
	(gr_line
		(start 463.08264 -53.888894)
		(end 463.13471 -53.940964)
		(stroke
			(width 0.05715)
			(type default)
		)
		(layer "In4.Cu")
	)
	(gr_line
		(start 463.139282 -52.2097)
		(end 463.223102 -52.2097)
		(stroke
			(width 0.05715)
			(type default)
		)
		(layer "In4.Cu")
	)
	(gr_line
		(start 463.352642 -51.7525)
		(end 463.515202 -51.91506)
		(stroke
			(width 0.05715)
			(type default)
		)
		(layer "In4.Cu")
	)
	(gr_line
		(start 463.55127 -53.940964)
		(end 463.60334 -53.888894)
		(stroke
			(width 0.05715)
			(type default)
		)
		(layer "In4.Cu")
	)
	(gr_line
		(start 463.60334 -53.888894)
		(end 463.97799 -53.888894)
		(stroke
			(width 0.05715)
			(type default)
		)
		(layer "In4.Cu")
	)
	(gr_line
		(start 463.863182 -51.91506)
		(end 464.025742 -51.7525)
		(stroke
			(width 0.05715)
			(type default)
		)
		(layer "In4.Cu")
	)
	(gr_line
		(start 464.025742 -51.7525)
		(end 464.368642 -51.7525)
		(stroke
			(width 0.05715)
			(type default)
		)
		(layer "In4.Cu")
	)
	(gr_line
		(start 464.155282 -52.2097)
		(end 464.239102 -52.2097)
		(stroke
			(width 0.05715)
			(type default)
		)
		(layer "In4.Cu")
	)
	(gr_line
		(start 464.368642 -51.7525)
		(end 464.531202 -51.91506)
		(stroke
			(width 0.05715)
			(type default)
		)
		(layer "In4.Cu")
	)
	(gr_line
		(start 475.525846 -64.247776)
		(end 475.525846 -64.4779)
		(stroke
			(width 0.05715)
			(type default)
		)
		(layer "In4.Cu")
	)
	(gr_line
		(start 475.525846 -64.247776)
		(end 475.768416 -64.005206)
		(stroke
			(width 0.05715)
			(type default)
		)
		(layer "In4.Cu")
	)
	(gr_line
		(start 475.574868 -65.563496)
		(end 475.574868 -65.79362)
		(stroke
			(width 0.05715)
			(type default)
		)
		(layer "In4.Cu")
	)
	(gr_line
		(start 475.574868 -65.563496)
		(end 475.817184 -65.320926)
		(stroke
			(width 0.05715)
			(type default)
		)
		(layer "In4.Cu")
	)
	(gr_line
		(start 475.768416 -64.005206)
		(end 475.99854 -64.005206)
		(stroke
			(width 0.05715)
			(type default)
		)
		(layer "In4.Cu")
	)
	(gr_line
		(start 475.817184 -65.320926)
		(end 476.047562 -65.320926)
		(stroke
			(width 0.05715)
			(type default)
		)
		(layer "In4.Cu")
	)
	(gr_line
		(start 475.940882 -64.479424)
		(end 476.000064 -64.420242)
		(stroke
			(width 0.05715)
			(type default)
		)
		(layer "In4.Cu")
	)
	(gr_line
		(start 475.989904 -65.795144)
		(end 476.049086 -65.735962)
		(stroke
			(width 0.05715)
			(type default)
		)
		(layer "In4.Cu")
	)
	(gr_line
		(start 476.244412 -63.52921)
		(end 476.244412 -63.759334)
		(stroke
			(width 0.05715)
			(type default)
		)
		(layer "In4.Cu")
	)
	(gr_line
		(start 476.244412 -63.52921)
		(end 476.486728 -63.286894)
		(stroke
			(width 0.05715)
			(type default)
		)
		(layer "In4.Cu")
	)
	(gr_line
		(start 476.29318 -64.84493)
		(end 476.29318 -65.075308)
		(stroke
			(width 0.05715)
			(type default)
		)
		(layer "In4.Cu")
	)
	(gr_line
		(start 476.29318 -64.84493)
		(end 476.53575 -64.602614)
		(stroke
			(width 0.05715)
			(type default)
		)
		(layer "In4.Cu")
	)
	(gr_line
		(start 476.486728 -63.286894)
		(end 476.716852 -63.286894)
		(stroke
			(width 0.05715)
			(type default)
		)
		(layer "In4.Cu")
	)
	(gr_line
		(start 476.53575 -64.602614)
		(end 476.765874 -64.602614)
		(stroke
			(width 0.05715)
			(type default)
		)
		(layer "In4.Cu")
	)
	(gr_line
		(start 476.659448 -63.760858)
		(end 476.718376 -63.70193)
		(stroke
			(width 0.05715)
			(type default)
		)
		(layer "In4.Cu")
	)
	(gr_line
		(start 476.708216 -65.076832)
		(end 476.767398 -65.01765)
		(stroke
			(width 0.05715)
			(type default)
		)
		(layer "In4.Cu")
	)
	(gr_line
		(start 476.962724 -62.810898)
		(end 476.962724 -63.041022)
		(stroke
			(width 0.05715)
			(type default)
		)
		(layer "In4.Cu")
	)
	(gr_line
		(start 476.962724 -62.810898)
		(end 477.205294 -62.568328)
		(stroke
			(width 0.05715)
			(type default)
		)
		(layer "In4.Cu")
	)
	(gr_line
		(start 477.011746 -64.126618)
		(end 477.011746 -64.356742)
		(stroke
			(width 0.05715)
			(type default)
		)
		(layer "In4.Cu")
	)
	(gr_line
		(start 477.011746 -64.126618)
		(end 477.254062 -63.884302)
		(stroke
			(width 0.05715)
			(type default)
		)
		(layer "In4.Cu")
	)
	(gr_line
		(start 477.205294 -62.568328)
		(end 477.435418 -62.568328)
		(stroke
			(width 0.05715)
			(type default)
		)
		(layer "In4.Cu")
	)
	(gr_line
		(start 477.254062 -63.884302)
		(end 477.484186 -63.884302)
		(stroke
			(width 0.05715)
			(type default)
		)
		(layer "In4.Cu")
	)
	(gr_line
		(start 477.37776 -63.042546)
		(end 477.436942 -62.983364)
		(stroke
			(width 0.05715)
			(type default)
		)
		(layer "In4.Cu")
	)
	(gr_line
		(start 477.426782 -64.358266)
		(end 477.48571 -64.299338)
		(stroke
			(width 0.05715)
			(type default)
		)
		(layer "In4.Cu")
	)
	(gr_line
		(start 477.681036 -62.092332)
		(end 477.681036 -62.32271)
		(stroke
			(width 0.05715)
			(type default)
		)
		(layer "In4.Cu")
	)
	(gr_line
		(start 477.681036 -62.092332)
		(end 477.923606 -61.850016)
		(stroke
			(width 0.05715)
			(type default)
		)
		(layer "In4.Cu")
	)
	(gr_line
		(start 477.730058 -63.408306)
		(end 477.730058 -63.63843)
		(stroke
			(width 0.05715)
			(type default)
		)
		(layer "In4.Cu")
	)
	(gr_line
		(start 477.730058 -63.408306)
		(end 477.972628 -63.165736)
		(stroke
			(width 0.05715)
			(type default)
		)
		(layer "In4.Cu")
	)
	(gr_line
		(start 477.923606 -61.850016)
		(end 478.15373 -61.850016)
		(stroke
			(width 0.05715)
			(type default)
		)
		(layer "In4.Cu")
	)
	(gr_line
		(start 477.972628 -63.165736)
		(end 478.202752 -63.165736)
		(stroke
			(width 0.05715)
			(type default)
		)
		(layer "In4.Cu")
	)
	(gr_line
		(start 478.096072 -62.324234)
		(end 478.155254 -62.265052)
		(stroke
			(width 0.05715)
			(type default)
		)
		(layer "In4.Cu")
	)
	(gr_line
		(start 478.145094 -63.639954)
		(end 478.204276 -63.580772)
		(stroke
			(width 0.05715)
			(type default)
		)
		(layer "In4.Cu")
	)
	(gr_line
		(start 483.594918 -51.173888)
		(end 483.82301 -51.40198)
		(stroke
			(width 0.05715)
			(type default)
		)
		(layer "In4.Cu")
	)
	(gr_line
		(start 483.626668 -52.04333)
		(end 483.871778 -51.79822)
		(stroke
			(width 0.05715)
			(type default)
		)
		(layer "In4.Cu")
	)
	(gr_line
		(start 483.82301 -51.40198)
		(end 483.892352 -51.40198)
		(stroke
			(width 0.05715)
			(type default)
		)
		(layer "In4.Cu")
	)
	(gr_line
		(start 483.892352 -51.40198)
		(end 483.957122 -51.46675)
		(stroke
			(width 0.05715)
			(type default)
		)
		(layer "In4.Cu")
	)
	(gr_line
		(start 484.992934 -53.03647)
		(end 484.994204 -52.742846)
		(stroke
			(width 0.05715)
			(type default)
		)
		(layer "In4.Cu")
	)
	(gr_line
		(start 484.994204 -52.742846)
		(end 485.107234 -52.630578)
		(stroke
			(width 0.05715)
			(type default)
		)
		(layer "In4.Cu")
	)
	(gr_line
		(start 484.995728 -52.205128)
		(end 485.124252 -52.33416)
		(stroke
			(width 0.05715)
			(type default)
		)
		(layer "In4.Cu")
	)
	(gr_line
		(start 484.995728 -52.20208)
		(end 484.995728 -52.205128)
		(stroke
			(width 0.05715)
			(type default)
		)
		(layer "In4.Cu")
	)
	(gr_line
		(start 484.995728 -52.20208)
		(end 484.997252 -51.893978)
		(stroke
			(width 0.05715)
			(type default)
		)
		(layer "In4.Cu")
	)
	(gr_line
		(start 1.1684 -67.0052)
		(end 2.8702 -68.707)
		(stroke
			(width 1.27)
			(type default)
		)
		(layer "In5.Cu")
	)
	(gr_line
		(start 1.1684 -60.1218)
		(end 1.1684 -67.0052)
		(stroke
			(width 1.27)
			(type default)
		)
		(layer "In5.Cu")
	)
	(gr_line
		(start 2.4384 -58.8518)
		(end 1.1684 -60.1218)
		(stroke
			(width 1.27)
			(type default)
		)
		(layer "In5.Cu")
	)
	(gr_line
		(start 2.4384 -50.0634)
		(end 2.4384 -58.8518)
		(stroke
			(width 1.27)
			(type default)
		)
		(layer "In5.Cu")
	)
	(gr_line
		(start 2.8702 -85.8266)
		(end 3.8608 -86.8172)
		(stroke
			(width 1.27)
			(type default)
		)
		(layer "In5.Cu")
	)
	(gr_line
		(start 2.8702 -68.707)
		(end 2.8702 -85.8266)
		(stroke
			(width 1.27)
			(type default)
		)
		(layer "In5.Cu")
	)
	(gr_line
		(start 3.0988 -49.403)
		(end 2.4384 -50.0634)
		(stroke
			(width 1.27)
			(type default)
		)
		(layer "In5.Cu")
	)
	(gr_line
		(start 3.8608 -86.8172)
		(end 10.107422 -86.8172)
		(stroke
			(width 1.27)
			(type default)
		)
		(layer "In5.Cu")
	)
	(gr_line
		(start 9.72185 -49.403)
		(end 3.0988 -49.403)
		(stroke
			(width 1.27)
			(type default)
		)
		(layer "In5.Cu")
	)
	(gr_line
		(start 10.107422 -86.8172)
		(end 10.727436 -86.197186)
		(stroke
			(width 1.27)
			(type default)
		)
		(layer "In5.Cu")
	)
	(gr_line
		(start 10.727436 -86.197186)
		(end 10.727436 -50.408586)
		(stroke
			(width 1.27)
			(type default)
		)
		(layer "In5.Cu")
	)
	(gr_line
		(start 10.727436 -50.408586)
		(end 9.72185 -49.403)
		(stroke
			(width 1.27)
			(type default)
		)
		(layer "In5.Cu")
	)
	(gr_line
		(start 429.82007 -137.109454)
		(end 431.09007 -137.109454)
		(stroke
			(width 0.2)
			(type default)
		)
		(layer "In5.Cu")
	)
	(gr_arc
		(start 429.82007 -135.580374)
		(mid 429.05553 -136.344914)
		(end 429.82007 -137.109454)
		(stroke
			(width 0.2)
			(type default)
		)
		(layer "In5.Cu")
	)
	(gr_arc
		(start 431.09007 -137.109454)
		(mid 431.629783 -136.886423)
		(end 431.85461 -136.347454)
		(stroke
			(width 0.2)
			(type default)
		)
		(layer "In5.Cu")
	)
	(gr_line
		(start 431.09007 -135.580374)
		(end 429.82007 -135.580374)
		(stroke
			(width 0.2)
			(type default)
		)
		(layer "In5.Cu")
	)
	(gr_line
		(start 431.666142 -136.347454)
		(end 431.666142 -136.344914)
		(stroke
			(width 0.2)
			(type default)
		)
		(layer "In5.Cu")
	)
	(gr_line
		(start 431.666142 -136.344914)
		(end 431.85461 -136.344914)
		(stroke
			(width 0.2)
			(type default)
		)
		(layer "In5.Cu")
	)
	(gr_line
		(start 431.85461 -136.347454)
		(end 431.666142 -136.347454)
		(stroke
			(width 0.2)
			(type default)
		)
		(layer "In5.Cu")
	)
	(gr_arc
		(start 431.85461 -136.344914)
		(mid 431.630681 -135.804303)
		(end 431.09007 -135.580374)
		(stroke
			(width 0.2)
			(type default)
		)
		(layer "In5.Cu")
	)
	(gr_line
		(start 433.63007 -137.109454)
		(end 434.90007 -137.109454)
		(stroke
			(width 0.2)
			(type default)
		)
		(layer "In5.Cu")
	)
	(gr_arc
		(start 433.63007 -135.580374)
		(mid 432.86553 -136.344914)
		(end 433.63007 -137.109454)
		(stroke
			(width 0.2)
			(type default)
		)
		(layer "In5.Cu")
	)
	(gr_arc
		(start 434.90007 -137.109454)
		(mid 435.439783 -136.886423)
		(end 435.66461 -136.347454)
		(stroke
			(width 0.2)
			(type default)
		)
		(layer "In5.Cu")
	)
	(gr_line
		(start 434.90007 -135.580374)
		(end 433.63007 -135.580374)
		(stroke
			(width 0.2)
			(type default)
		)
		(layer "In5.Cu")
	)
	(gr_line
		(start 435.473856 -136.347454)
		(end 435.473856 -136.344914)
		(stroke
			(width 0.2)
			(type default)
		)
		(layer "In5.Cu")
	)
	(gr_line
		(start 435.473856 -136.344914)
		(end 435.66461 -136.344914)
		(stroke
			(width 0.2)
			(type default)
		)
		(layer "In5.Cu")
	)
	(gr_line
		(start 435.66461 -136.347454)
		(end 435.473856 -136.347454)
		(stroke
			(width 0.2)
			(type default)
		)
		(layer "In5.Cu")
	)
	(gr_arc
		(start 435.66461 -136.344914)
		(mid 435.440681 -135.804303)
		(end 434.90007 -135.580374)
		(stroke
			(width 0.2)
			(type default)
		)
		(layer "In5.Cu")
	)
	(gr_line
		(start 429.82007 -137.109454)
		(end 431.09007 -137.109454)
		(stroke
			(width 0.2)
			(type default)
		)
		(layer "In6.Cu")
	)
	(gr_arc
		(start 429.82007 -135.580374)
		(mid 429.05553 -136.344914)
		(end 429.82007 -137.109454)
		(stroke
			(width 0.2)
			(type default)
		)
		(layer "In6.Cu")
	)
	(gr_arc
		(start 431.09007 -137.109454)
		(mid 431.629783 -136.886423)
		(end 431.85461 -136.347454)
		(stroke
			(width 0.2)
			(type default)
		)
		(layer "In6.Cu")
	)
	(gr_line
		(start 431.09007 -135.580374)
		(end 429.82007 -135.580374)
		(stroke
			(width 0.2)
			(type default)
		)
		(layer "In6.Cu")
	)
	(gr_line
		(start 431.666142 -136.347454)
		(end 431.666142 -136.344914)
		(stroke
			(width 0.2)
			(type default)
		)
		(layer "In6.Cu")
	)
	(gr_line
		(start 431.666142 -136.344914)
		(end 431.85461 -136.344914)
		(stroke
			(width 0.2)
			(type default)
		)
		(layer "In6.Cu")
	)
	(gr_line
		(start 431.85461 -136.347454)
		(end 431.666142 -136.347454)
		(stroke
			(width 0.2)
			(type default)
		)
		(layer "In6.Cu")
	)
	(gr_arc
		(start 431.85461 -136.344914)
		(mid 431.630681 -135.804303)
		(end 431.09007 -135.580374)
		(stroke
			(width 0.2)
			(type default)
		)
		(layer "In6.Cu")
	)
	(gr_line
		(start 433.63007 -137.109454)
		(end 434.90007 -137.109454)
		(stroke
			(width 0.2)
			(type default)
		)
		(layer "In6.Cu")
	)
	(gr_arc
		(start 433.63007 -135.580374)
		(mid 432.86553 -136.344914)
		(end 433.63007 -137.109454)
		(stroke
			(width 0.2)
			(type default)
		)
		(layer "In6.Cu")
	)
	(gr_arc
		(start 434.90007 -137.109454)
		(mid 435.439783 -136.886423)
		(end 435.66461 -136.347454)
		(stroke
			(width 0.2)
			(type default)
		)
		(layer "In6.Cu")
	)
	(gr_line
		(start 434.90007 -135.580374)
		(end 433.63007 -135.580374)
		(stroke
			(width 0.2)
			(type default)
		)
		(layer "In6.Cu")
	)
	(gr_line
		(start 435.473856 -136.347454)
		(end 435.473856 -136.344914)
		(stroke
			(width 0.2)
			(type default)
		)
		(layer "In6.Cu")
	)
	(gr_line
		(start 435.473856 -136.344914)
		(end 435.66461 -136.344914)
		(stroke
			(width 0.2)
			(type default)
		)
		(layer "In6.Cu")
	)
	(gr_line
		(start 435.66461 -136.347454)
		(end 435.473856 -136.347454)
		(stroke
			(width 0.2)
			(type default)
		)
		(layer "In6.Cu")
	)
	(gr_arc
		(start 435.66461 -136.344914)
		(mid 435.440681 -135.804303)
		(end 434.90007 -135.580374)
		(stroke
			(width 0.2)
			(type default)
		)
		(layer "In6.Cu")
	)
	(gr_line
		(start 429.82007 -137.109454)
		(end 431.09007 -137.109454)
		(stroke
			(width 0.2)
			(type default)
		)
		(layer "In7.Cu")
	)
	(gr_arc
		(start 429.82007 -135.580374)
		(mid 429.05553 -136.344914)
		(end 429.82007 -137.109454)
		(stroke
			(width 0.2)
			(type default)
		)
		(layer "In7.Cu")
	)
	(gr_arc
		(start 431.09007 -137.109454)
		(mid 431.629783 -136.886423)
		(end 431.85461 -136.347454)
		(stroke
			(width 0.2)
			(type default)
		)
		(layer "In7.Cu")
	)
	(gr_line
		(start 431.09007 -135.580374)
		(end 429.82007 -135.580374)
		(stroke
			(width 0.2)
			(type default)
		)
		(layer "In7.Cu")
	)
	(gr_line
		(start 431.666142 -136.347454)
		(end 431.666142 -136.344914)
		(stroke
			(width 0.2)
			(type default)
		)
		(layer "In7.Cu")
	)
	(gr_line
		(start 431.666142 -136.344914)
		(end 431.85461 -136.344914)
		(stroke
			(width 0.2)
			(type default)
		)
		(layer "In7.Cu")
	)
	(gr_line
		(start 431.85461 -136.347454)
		(end 431.666142 -136.347454)
		(stroke
			(width 0.2)
			(type default)
		)
		(layer "In7.Cu")
	)
	(gr_arc
		(start 431.85461 -136.344914)
		(mid 431.630681 -135.804303)
		(end 431.09007 -135.580374)
		(stroke
			(width 0.2)
			(type default)
		)
		(layer "In7.Cu")
	)
	(gr_line
		(start 433.63007 -137.109454)
		(end 434.90007 -137.109454)
		(stroke
			(width 0.2)
			(type default)
		)
		(layer "In7.Cu")
	)
	(gr_arc
		(start 433.63007 -135.580374)
		(mid 432.86553 -136.344914)
		(end 433.63007 -137.109454)
		(stroke
			(width 0.2)
			(type default)
		)
		(layer "In7.Cu")
	)
	(gr_arc
		(start 434.90007 -137.109454)
		(mid 435.439783 -136.886423)
		(end 435.66461 -136.347454)
		(stroke
			(width 0.2)
			(type default)
		)
		(layer "In7.Cu")
	)
	(gr_line
		(start 434.90007 -135.580374)
		(end 433.63007 -135.580374)
		(stroke
			(width 0.2)
			(type default)
		)
		(layer "In7.Cu")
	)
	(gr_line
		(start 435.473856 -136.347454)
		(end 435.473856 -136.344914)
		(stroke
			(width 0.2)
			(type default)
		)
		(layer "In7.Cu")
	)
	(gr_line
		(start 435.473856 -136.344914)
		(end 435.66461 -136.344914)
		(stroke
			(width 0.2)
			(type default)
		)
		(layer "In7.Cu")
	)
	(gr_line
		(start 435.66461 -136.347454)
		(end 435.473856 -136.347454)
		(stroke
			(width 0.2)
			(type default)
		)
		(layer "In7.Cu")
	)
	(gr_arc
		(start 435.66461 -136.344914)
		(mid 435.440681 -135.804303)
		(end 434.90007 -135.580374)
		(stroke
			(width 0.2)
			(type default)
		)
		(layer "In7.Cu")
	)
	(gr_line
		(start 1.651 -67.4878)
		(end 1.651 -59.6138)
		(stroke
			(width 1.27)
			(type default)
		)
		(layer "In8.Cu")
	)
	(gr_line
		(start 1.651 -59.6138)
		(end 2.4384 -58.8264)
		(stroke
			(width 1.27)
			(type default)
		)
		(layer "In8.Cu")
	)
	(gr_line
		(start 2.4384 -58.8264)
		(end 2.4384 -50.0634)
		(stroke
			(width 1.27)
			(type default)
		)
		(layer "In8.Cu")
	)
	(gr_line
		(start 2.4384 -50.0634)
		(end 3.0988 -49.403)
		(stroke
			(width 1.27)
			(type default)
		)
		(layer "In8.Cu")
	)
	(gr_line
		(start 2.8702 -85.8266)
		(end 2.8702 -68.707)
		(stroke
			(width 1.27)
			(type default)
		)
		(layer "In8.Cu")
	)
	(gr_line
		(start 2.8702 -68.707)
		(end 1.651 -67.4878)
		(stroke
			(width 1.27)
			(type default)
		)
		(layer "In8.Cu")
	)
	(gr_line
		(start 3.0988 -49.403)
		(end 9.72185 -49.403)
		(stroke
			(width 1.27)
			(type default)
		)
		(layer "In8.Cu")
	)
	(gr_line
		(start 3.8608 -86.8172)
		(end 2.8702 -85.8266)
		(stroke
			(width 1.27)
			(type default)
		)
		(layer "In8.Cu")
	)
	(gr_line
		(start 9.72185 -49.403)
		(end 10.727436 -50.408586)
		(stroke
			(width 1.27)
			(type default)
		)
		(layer "In8.Cu")
	)
	(gr_line
		(start 10.107422 -86.8172)
		(end 3.8608 -86.8172)
		(stroke
			(width 1.27)
			(type default)
		)
		(layer "In8.Cu")
	)
	(gr_line
		(start 10.727436 -86.197186)
		(end 10.107422 -86.8172)
		(stroke
			(width 1.27)
			(type default)
		)
		(layer "In8.Cu")
	)
	(gr_line
		(start 10.727436 -50.408586)
		(end 10.727436 -86.197186)
		(stroke
			(width 1.27)
			(type default)
		)
		(layer "In8.Cu")
	)
	(gr_line
		(start 12.5222 -66.04)
		(end 12.5222 -56.769)
		(stroke
			(width 1.27)
			(type default)
		)
		(layer "In8.Cu")
	)
	(gr_line
		(start 12.5222 -56.769)
		(end 13.208 -56.0832)
		(stroke
			(width 1.27)
			(type default)
		)
		(layer "In8.Cu")
	)
	(gr_line
		(start 13.208 -56.0832)
		(end 18.9738 -56.0832)
		(stroke
			(width 1.27)
			(type default)
		)
		(layer "In8.Cu")
	)
	(gr_line
		(start 14.9606 -68.4784)
		(end 12.5222 -66.04)
		(stroke
			(width 1.27)
			(type default)
		)
		(layer "In8.Cu")
	)
	(gr_line
		(start 18.7706 -68.4784)
		(end 14.9606 -68.4784)
		(stroke
			(width 1.27)
			(type default)
		)
		(layer "In8.Cu")
	)
	(gr_line
		(start 18.9738 -56.0832)
		(end 19.685 -56.7944)
		(stroke
			(width 1.27)
			(type default)
		)
		(layer "In8.Cu")
	)
	(gr_line
		(start 19.685 -67.564)
		(end 18.7706 -68.4784)
		(stroke
			(width 1.27)
			(type default)
		)
		(layer "In8.Cu")
	)
	(gr_line
		(start 19.685 -64.008)
		(end 19.685 -67.564)
		(stroke
			(width 1.27)
			(type default)
		)
		(layer "In8.Cu")
	)
	(gr_line
		(start 19.685 -56.7944)
		(end 19.685 -64.008)
		(stroke
			(width 1.27)
			(type default)
		)
		(layer "In8.Cu")
	)
	(gr_line
		(start 80.07096 -23.06828)
		(end 81.19618 -24.1935)
		(stroke
			(width 0.381)
			(type default)
		)
		(layer "In8.Cu")
	)
	(gr_line
		(start 80.07096 -16.68272)
		(end 80.07096 -23.06828)
		(stroke
			(width 0.381)
			(type default)
		)
		(layer "In8.Cu")
	)
	(gr_circle
		(center 80.071214 -16.68272)
		(end 80.071468 -16.68272)
		(stroke
			(width 0.381)
			(type default)
		)
		(fill no)
		(layer "In8.Cu")
	)
	(gr_line
		(start 80.283304 -135.610854)
		(end 81.84515 -137.1727)
		(stroke
			(width 0.381)
			(type default)
		)
		(layer "In8.Cu")
	)
	(gr_line
		(start 80.283304 -130.489706)
		(end 80.283304 -135.610854)
		(stroke
			(width 0.381)
			(type default)
		)
		(layer "In8.Cu")
	)
	(gr_circle
		(center 80.283558 -130.489706)
		(end 80.283812 -130.489706)
		(stroke
			(width 0.381)
			(type default)
		)
		(fill no)
		(layer "In8.Cu")
	)
	(gr_line
		(start 80.56372 -16.18996)
		(end 80.07096 -16.68272)
		(stroke
			(width 0.381)
			(type default)
		)
		(layer "In8.Cu")
	)
	(gr_line
		(start 81.19618 -24.1935)
		(end 91.01074 -24.1935)
		(stroke
			(width 0.381)
			(type default)
		)
		(layer "In8.Cu")
	)
	(gr_circle
		(center 81.19618 -24.193246)
		(end 81.196434 -24.193246)
		(stroke
			(width 0.381)
			(type default)
		)
		(fill no)
		(layer "In8.Cu")
	)
	(gr_line
		(start 81.820766 -128.952244)
		(end 80.283304 -130.489706)
		(stroke
			(width 0.381)
			(type default)
		)
		(layer "In8.Cu")
	)
	(gr_line
		(start 81.84515 -137.1727)
		(end 90.81516 -137.1727)
		(stroke
			(width 0.381)
			(type default)
		)
		(layer "In8.Cu")
	)
	(gr_circle
		(center 81.84515 -137.172446)
		(end 81.845404 -137.172446)
		(stroke
			(width 0.381)
			(type default)
		)
		(fill no)
		(layer "In8.Cu")
	)
	(gr_line
		(start 90.81516 -137.1727)
		(end 91.613736 -136.374124)
		(stroke
			(width 0.381)
			(type default)
		)
		(layer "In8.Cu")
	)
	(gr_line
		(start 91.01074 -24.1935)
		(end 91.6178 -23.58644)
		(stroke
			(width 0.381)
			(type default)
		)
		(layer "In8.Cu")
	)
	(gr_circle
		(center 91.155774 -128.952498)
		(end 91.156028 -128.952498)
		(stroke
			(width 0.381)
			(type default)
		)
		(fill no)
		(layer "In8.Cu")
	)
	(gr_line
		(start 91.155774 -128.952244)
		(end 81.820766 -128.952244)
		(stroke
			(width 0.381)
			(type default)
		)
		(layer "In8.Cu")
	)
	(gr_circle
		(center 91.26474 -16.190214)
		(end 91.264994 -16.190214)
		(stroke
			(width 0.381)
			(type default)
		)
		(fill no)
		(layer "In8.Cu")
	)
	(gr_line
		(start 91.26474 -16.18996)
		(end 80.56372 -16.18996)
		(stroke
			(width 0.381)
			(type default)
		)
		(layer "In8.Cu")
	)
	(gr_circle
		(center 91.613482 -136.374124)
		(end 91.613736 -136.374124)
		(stroke
			(width 0.381)
			(type default)
		)
		(fill no)
		(layer "In8.Cu")
	)
	(gr_line
		(start 91.613736 -136.374124)
		(end 91.613736 -129.410206)
		(stroke
			(width 0.381)
			(type default)
		)
		(layer "In8.Cu")
	)
	(gr_line
		(start 91.613736 -129.410206)
		(end 91.155774 -128.952244)
		(stroke
			(width 0.381)
			(type default)
		)
		(layer "In8.Cu")
	)
	(gr_circle
		(center 91.617546 -23.58644)
		(end 91.6178 -23.58644)
		(stroke
			(width 0.381)
			(type default)
		)
		(fill no)
		(layer "In8.Cu")
	)
	(gr_line
		(start 91.6178 -23.58644)
		(end 91.6178 -16.54302)
		(stroke
			(width 0.381)
			(type default)
		)
		(layer "In8.Cu")
	)
	(gr_line
		(start 91.6178 -16.54302)
		(end 91.26474 -16.18996)
		(stroke
			(width 0.381)
			(type default)
		)
		(layer "In8.Cu")
	)
	(gr_line
		(start 99.24796 -25.10282)
		(end 101.64318 -27.49804)
		(stroke
			(width 0.381)
			(type default)
		)
		(layer "In8.Cu")
	)
	(gr_line
		(start 99.24796 -17.31772)
		(end 99.24796 -25.10282)
		(stroke
			(width 0.381)
			(type default)
		)
		(layer "In8.Cu")
	)
	(gr_circle
		(center 99.248214 -17.31772)
		(end 99.248468 -17.31772)
		(stroke
			(width 0.381)
			(type default)
		)
		(fill no)
		(layer "In8.Cu")
	)
	(gr_line
		(start 99.550982 -136.698482)
		(end 99.92614 -137.07364)
		(stroke
			(width 0.381)
			(type default)
		)
		(layer "In8.Cu")
	)
	(gr_line
		(start 99.550982 -129.179574)
		(end 99.550982 -136.698482)
		(stroke
			(width 0.381)
			(type default)
		)
		(layer "In8.Cu")
	)
	(gr_circle
		(center 99.551236 -129.179574)
		(end 99.55149 -129.179574)
		(stroke
			(width 0.381)
			(type default)
		)
		(fill no)
		(layer "In8.Cu")
	)
	(gr_line
		(start 99.889564 -128.8415)
		(end 99.550982 -129.179574)
		(stroke
			(width 0.381)
			(type default)
		)
		(layer "In8.Cu")
	)
	(gr_line
		(start 99.92614 -137.07364)
		(end 113.356136 -137.07364)
		(stroke
			(width 0.381)
			(type default)
		)
		(layer "In8.Cu")
	)
	(gr_circle
		(center 99.92614 -137.073386)
		(end 99.926394 -137.073386)
		(stroke
			(width 0.381)
			(type default)
		)
		(fill no)
		(layer "In8.Cu")
	)
	(gr_circle
		(center 100.62718 -15.938754)
		(end 100.627434 -15.938754)
		(stroke
			(width 0.381)
			(type default)
		)
		(fill no)
		(layer "In8.Cu")
	)
	(gr_line
		(start 100.62718 -15.9385)
		(end 99.24796 -17.31772)
		(stroke
			(width 0.381)
			(type default)
		)
		(layer "In8.Cu")
	)
	(gr_line
		(start 101.64318 -27.49804)
		(end 109.17174 -27.49804)
		(stroke
			(width 0.381)
			(type default)
		)
		(layer "In8.Cu")
	)
	(gr_circle
		(center 101.64318 -27.497786)
		(end 101.643434 -27.497786)
		(stroke
			(width 0.381)
			(type default)
		)
		(fill no)
		(layer "In8.Cu")
	)
	(gr_line
		(start 106.794808 -128.8415)
		(end 99.889564 -128.8415)
		(stroke
			(width 0.381)
			(type default)
		)
		(layer "In8.Cu")
	)
	(gr_circle
		(center 106.794808 -128.841246)
		(end 106.795062 -128.841246)
		(stroke
			(width 0.381)
			(type default)
		)
		(fill no)
		(layer "In8.Cu")
	)
	(gr_line
		(start 109.17174 -27.49804)
		(end 113.9825 -22.68728)
		(stroke
			(width 0.381)
			(type default)
		)
		(layer "In8.Cu")
	)
	(gr_line
		(start 109.653324 -125.98654)
		(end 106.794808 -128.8415)
		(stroke
			(width 0.381)
			(type default)
		)
		(layer "In8.Cu")
	)
	(gr_circle
		(center 110.357666 -125.986794)
		(end 110.35792 -125.986794)
		(stroke
			(width 0.381)
			(type default)
		)
		(fill no)
		(layer "In8.Cu")
	)
	(gr_line
		(start 110.357666 -125.98654)
		(end 109.653324 -125.98654)
		(stroke
			(width 0.381)
			(type default)
		)
		(layer "In8.Cu")
	)
	(gr_circle
		(center 113.23574 -15.938754)
		(end 113.235994 -15.938754)
		(stroke
			(width 0.381)
			(type default)
		)
		(fill no)
		(layer "In8.Cu")
	)
	(gr_line
		(start 113.23574 -15.9385)
		(end 100.62718 -15.9385)
		(stroke
			(width 0.381)
			(type default)
		)
		(layer "In8.Cu")
	)
	(gr_line
		(start 113.356136 -137.07364)
		(end 113.55578 -136.87425)
		(stroke
			(width 0.381)
			(type default)
		)
		(layer "In8.Cu")
	)
	(gr_circle
		(center 113.555526 -136.87425)
		(end 113.55578 -136.87425)
		(stroke
			(width 0.381)
			(type default)
		)
		(fill no)
		(layer "In8.Cu")
	)
	(gr_line
		(start 113.55578 -136.87425)
		(end 113.55578 -129.188464)
		(stroke
			(width 0.381)
			(type default)
		)
		(layer "In8.Cu")
	)
	(gr_line
		(start 113.55578 -129.188464)
		(end 110.357666 -125.98654)
		(stroke
			(width 0.381)
			(type default)
		)
		(layer "In8.Cu")
	)
	(gr_circle
		(center 113.982246 -22.68728)
		(end 113.9825 -22.68728)
		(stroke
			(width 0.381)
			(type default)
		)
		(fill no)
		(layer "In8.Cu")
	)
	(gr_line
		(start 113.9825 -22.68728)
		(end 113.9825 -16.68526)
		(stroke
			(width 0.381)
			(type default)
		)
		(layer "In8.Cu")
	)
	(gr_line
		(start 113.9825 -16.68526)
		(end 113.23574 -15.9385)
		(stroke
			(width 0.381)
			(type default)
		)
		(layer "In8.Cu")
	)
	(gr_line
		(start 245.284244 -135.610854)
		(end 245.284244 -130.489706)
		(stroke
			(width 0.381)
			(type default)
		)
		(layer "In8.Cu")
	)
	(gr_line
		(start 245.284244 -130.489706)
		(end 246.821706 -128.952244)
		(stroke
			(width 0.381)
			(type default)
		)
		(layer "In8.Cu")
	)
	(gr_circle
		(center 245.284498 -130.489706)
		(end 245.284752 -130.489706)
		(stroke
			(width 0.381)
			(type default)
		)
		(fill no)
		(layer "In8.Cu")
	)
	(gr_line
		(start 245.42496 -22.658324)
		(end 245.42496 -17.3228)
		(stroke
			(width 0.381)
			(type default)
		)
		(layer "In8.Cu")
	)
	(gr_line
		(start 245.42496 -17.3228)
		(end 246.4308 -16.31696)
		(stroke
			(width 0.381)
			(type default)
		)
		(layer "In8.Cu")
	)
	(gr_circle
		(center 245.425214 -22.658324)
		(end 245.425468 -22.658324)
		(stroke
			(width 0.381)
			(type default)
		)
		(fill no)
		(layer "In8.Cu")
	)
	(gr_circle
		(center 246.4308 -16.317214)
		(end 246.431054 -16.317214)
		(stroke
			(width 0.381)
			(type default)
		)
		(fill no)
		(layer "In8.Cu")
	)
	(gr_line
		(start 246.4308 -16.31696)
		(end 256.36474 -16.31696)
		(stroke
			(width 0.381)
			(type default)
		)
		(layer "In8.Cu")
	)
	(gr_line
		(start 246.58066 -23.815294)
		(end 245.42496 -22.658324)
		(stroke
			(width 0.381)
			(type default)
		)
		(layer "In8.Cu")
	)
	(gr_circle
		(center 246.58066 -23.81504)
		(end 246.580914 -23.81504)
		(stroke
			(width 0.381)
			(type default)
		)
		(fill no)
		(layer "In8.Cu")
	)
	(gr_line
		(start 246.59971 -136.92632)
		(end 245.284244 -135.610854)
		(stroke
			(width 0.381)
			(type default)
		)
		(layer "In8.Cu")
	)
	(gr_circle
		(center 246.59971 -136.926066)
		(end 246.599964 -136.926066)
		(stroke
			(width 0.381)
			(type default)
		)
		(fill no)
		(layer "In8.Cu")
	)
	(gr_line
		(start 246.821706 -128.952244)
		(end 254.506984 -128.952244)
		(stroke
			(width 0.381)
			(type default)
		)
		(layer "In8.Cu")
	)
	(gr_circle
		(center 254.506984 -128.952498)
		(end 254.507238 -128.952498)
		(stroke
			(width 0.381)
			(type default)
		)
		(fill no)
		(layer "In8.Cu")
	)
	(gr_line
		(start 254.506984 -128.952244)
		(end 255.7018 -130.14706)
		(stroke
			(width 0.381)
			(type default)
		)
		(layer "In8.Cu")
	)
	(gr_line
		(start 255.7018 -130.14706)
		(end 256.11836 -130.14706)
		(stroke
			(width 0.381)
			(type default)
		)
		(layer "In8.Cu")
	)
	(gr_line
		(start 255.734566 -23.815294)
		(end 246.58066 -23.815294)
		(stroke
			(width 0.381)
			(type default)
		)
		(layer "In8.Cu")
	)
	(gr_circle
		(center 255.734566 -23.81504)
		(end 255.73482 -23.81504)
		(stroke
			(width 0.381)
			(type default)
		)
		(fill no)
		(layer "In8.Cu")
	)
	(gr_line
		(start 256.06248 -136.92632)
		(end 246.59971 -136.92632)
		(stroke
			(width 0.381)
			(type default)
		)
		(layer "In8.Cu")
	)
	(gr_circle
		(center 256.06248 -136.926066)
		(end 256.062734 -136.926066)
		(stroke
			(width 0.381)
			(type default)
		)
		(fill no)
		(layer "In8.Cu")
	)
	(gr_line
		(start 256.11836 -130.14706)
		(end 256.614676 -130.643376)
		(stroke
			(width 0.381)
			(type default)
		)
		(layer "In8.Cu")
	)
	(gr_line
		(start 256.36474 -16.31696)
		(end 256.60858 -16.5608)
		(stroke
			(width 0.381)
			(type default)
		)
		(layer "In8.Cu")
	)
	(gr_circle
		(center 256.608326 -16.5608)
		(end 256.60858 -16.5608)
		(stroke
			(width 0.381)
			(type default)
		)
		(fill no)
		(layer "In8.Cu")
	)
	(gr_line
		(start 256.60858 -22.94128)
		(end 255.734566 -23.815294)
		(stroke
			(width 0.381)
			(type default)
		)
		(layer "In8.Cu")
	)
	(gr_line
		(start 256.60858 -16.5608)
		(end 256.60858 -22.94128)
		(stroke
			(width 0.381)
			(type default)
		)
		(layer "In8.Cu")
	)
	(gr_circle
		(center 256.614422 -136.374124)
		(end 256.614676 -136.374124)
		(stroke
			(width 0.381)
			(type default)
		)
		(fill no)
		(layer "In8.Cu")
	)
	(gr_circle
		(center 256.614422 -130.643376)
		(end 256.614676 -130.643376)
		(stroke
			(width 0.381)
			(type default)
		)
		(fill no)
		(layer "In8.Cu")
	)
	(gr_line
		(start 256.614676 -136.374124)
		(end 256.06248 -136.92632)
		(stroke
			(width 0.381)
			(type default)
		)
		(layer "In8.Cu")
	)
	(gr_line
		(start 256.614676 -130.643376)
		(end 256.614676 -136.374124)
		(stroke
			(width 0.381)
			(type default)
		)
		(layer "In8.Cu")
	)
	(gr_line
		(start 264.551922 -136.533382)
		(end 264.551922 -129.179574)
		(stroke
			(width 0.381)
			(type default)
		)
		(layer "In8.Cu")
	)
	(gr_line
		(start 264.551922 -129.179574)
		(end 264.890504 -128.8415)
		(stroke
			(width 0.381)
			(type default)
		)
		(layer "In8.Cu")
	)
	(gr_circle
		(center 264.552176 -136.533382)
		(end 264.55243 -136.533382)
		(stroke
			(width 0.381)
			(type default)
		)
		(fill no)
		(layer "In8.Cu")
	)
	(gr_circle
		(center 264.552176 -129.179574)
		(end 264.55243 -129.179574)
		(stroke
			(width 0.381)
			(type default)
		)
		(fill no)
		(layer "In8.Cu")
	)
	(gr_line
		(start 264.890504 -128.8415)
		(end 271.795748 -128.8415)
		(stroke
			(width 0.381)
			(type default)
		)
		(layer "In8.Cu")
	)
	(gr_line
		(start 264.96772 -136.94918)
		(end 264.551922 -136.533382)
		(stroke
			(width 0.381)
			(type default)
		)
		(layer "In8.Cu")
	)
	(gr_circle
		(center 264.96772 -136.948926)
		(end 264.967974 -136.948926)
		(stroke
			(width 0.381)
			(type default)
		)
		(fill no)
		(layer "In8.Cu")
	)
	(gr_line
		(start 265.35888 -23.19274)
		(end 265.86942 -23.70328)
		(stroke
			(width 0.381)
			(type default)
		)
		(layer "In8.Cu")
	)
	(gr_line
		(start 265.35888 -19.35226)
		(end 265.35888 -23.19274)
		(stroke
			(width 0.381)
			(type default)
		)
		(layer "In8.Cu")
	)
	(gr_circle
		(center 265.359134 -19.35226)
		(end 265.359388 -19.35226)
		(stroke
			(width 0.381)
			(type default)
		)
		(fill no)
		(layer "In8.Cu")
	)
	(gr_line
		(start 265.73734 -18.9738)
		(end 265.35888 -19.35226)
		(stroke
			(width 0.381)
			(type default)
		)
		(layer "In8.Cu")
	)
	(gr_line
		(start 265.73734 -18.38452)
		(end 265.73734 -18.9738)
		(stroke
			(width 0.381)
			(type default)
		)
		(layer "In8.Cu")
	)
	(gr_circle
		(center 265.737594 -18.38452)
		(end 265.737848 -18.38452)
		(stroke
			(width 0.381)
			(type default)
		)
		(fill no)
		(layer "In8.Cu")
	)
	(gr_circle
		(center 265.869166 -23.70328)
		(end 265.86942 -23.70328)
		(stroke
			(width 0.381)
			(type default)
		)
		(fill no)
		(layer "In8.Cu")
	)
	(gr_line
		(start 265.86942 -26.24201)
		(end 266.870688 -27.24404)
		(stroke
			(width 0.381)
			(type default)
		)
		(layer "In8.Cu")
	)
	(gr_line
		(start 265.86942 -23.70328)
		(end 265.86942 -26.24201)
		(stroke
			(width 0.381)
			(type default)
		)
		(layer "In8.Cu")
	)
	(gr_line
		(start 265.9253 -18.19656)
		(end 265.73734 -18.38452)
		(stroke
			(width 0.381)
			(type default)
		)
		(layer "In8.Cu")
	)
	(gr_line
		(start 265.9253 -16.957802)
		(end 265.9253 -18.19656)
		(stroke
			(width 0.381)
			(type default)
		)
		(layer "In8.Cu")
	)
	(gr_circle
		(center 265.925554 -16.957802)
		(end 265.925808 -16.957802)
		(stroke
			(width 0.381)
			(type default)
		)
		(fill no)
		(layer "In8.Cu")
	)
	(gr_line
		(start 266.43965 -16.44396)
		(end 265.9253 -16.957802)
		(stroke
			(width 0.381)
			(type default)
		)
		(layer "In8.Cu")
	)
	(gr_line
		(start 266.870688 -27.24404)
		(end 273.88947 -27.24404)
		(stroke
			(width 0.381)
			(type default)
		)
		(layer "In8.Cu")
	)
	(gr_circle
		(center 266.870688 -27.243786)
		(end 266.870942 -27.243786)
		(stroke
			(width 0.381)
			(type default)
		)
		(fill no)
		(layer "In8.Cu")
	)
	(gr_line
		(start 271.795748 -128.8415)
		(end 274.654264 -125.98654)
		(stroke
			(width 0.381)
			(type default)
		)
		(layer "In8.Cu")
	)
	(gr_circle
		(center 271.795748 -128.841246)
		(end 271.796002 -128.841246)
		(stroke
			(width 0.381)
			(type default)
		)
		(fill no)
		(layer "In8.Cu")
	)
	(gr_line
		(start 273.88947 -27.24404)
		(end 278.83104 -22.306534)
		(stroke
			(width 0.381)
			(type default)
		)
		(layer "In8.Cu")
	)
	(gr_line
		(start 274.654264 -125.98654)
		(end 275.358606 -125.98654)
		(stroke
			(width 0.381)
			(type default)
		)
		(layer "In8.Cu")
	)
	(gr_circle
		(center 275.358606 -125.986794)
		(end 275.35886 -125.986794)
		(stroke
			(width 0.381)
			(type default)
		)
		(fill no)
		(layer "In8.Cu")
	)
	(gr_line
		(start 275.358606 -125.98654)
		(end 278.55672 -129.188464)
		(stroke
			(width 0.381)
			(type default)
		)
		(layer "In8.Cu")
	)
	(gr_line
		(start 278.212296 -136.94918)
		(end 264.96772 -136.94918)
		(stroke
			(width 0.381)
			(type default)
		)
		(layer "In8.Cu")
	)
	(gr_circle
		(center 278.212296 -136.948926)
		(end 278.21255 -136.948926)
		(stroke
			(width 0.381)
			(type default)
		)
		(fill no)
		(layer "In8.Cu")
	)
	(gr_circle
		(center 278.337518 -16.444214)
		(end 278.337772 -16.444214)
		(stroke
			(width 0.381)
			(type default)
		)
		(fill no)
		(layer "In8.Cu")
	)
	(gr_line
		(start 278.337518 -16.44396)
		(end 266.43965 -16.44396)
		(stroke
			(width 0.381)
			(type default)
		)
		(layer "In8.Cu")
	)
	(gr_circle
		(center 278.437086 -136.72439)
		(end 278.43734 -136.72439)
		(stroke
			(width 0.381)
			(type default)
		)
		(fill no)
		(layer "In8.Cu")
	)
	(gr_circle
		(center 278.556466 -136.605264)
		(end 278.55672 -136.605264)
		(stroke
			(width 0.381)
			(type default)
		)
		(fill no)
		(layer "In8.Cu")
	)
	(gr_line
		(start 278.55672 -136.605264)
		(end 278.212296 -136.94918)
		(stroke
			(width 0.381)
			(type default)
		)
		(layer "In8.Cu")
	)
	(gr_line
		(start 278.55672 -129.188464)
		(end 278.55672 -136.605264)
		(stroke
			(width 0.381)
			(type default)
		)
		(layer "In8.Cu")
	)
	(gr_circle
		(center 278.830786 -22.306534)
		(end 278.83104 -22.306534)
		(stroke
			(width 0.381)
			(type default)
		)
		(fill no)
		(layer "In8.Cu")
	)
	(gr_line
		(start 278.83104 -22.306534)
		(end 278.83104 -16.93799)
		(stroke
			(width 0.381)
			(type default)
		)
		(layer "In8.Cu")
	)
	(gr_line
		(start 278.83104 -16.93799)
		(end 278.337518 -16.44396)
		(stroke
			(width 0.381)
			(type default)
		)
		(layer "In8.Cu")
	)
	(gr_line
		(start 429.82007 -137.109454)
		(end 431.09007 -137.109454)
		(stroke
			(width 0.2)
			(type default)
		)
		(layer "In8.Cu")
	)
	(gr_arc
		(start 429.82007 -135.580374)
		(mid 429.05553 -136.344914)
		(end 429.82007 -137.109454)
		(stroke
			(width 0.2)
			(type default)
		)
		(layer "In8.Cu")
	)
	(gr_arc
		(start 431.09007 -137.109454)
		(mid 431.629783 -136.886423)
		(end 431.85461 -136.347454)
		(stroke
			(width 0.2)
			(type default)
		)
		(layer "In8.Cu")
	)
	(gr_line
		(start 431.09007 -135.580374)
		(end 429.82007 -135.580374)
		(stroke
			(width 0.2)
			(type default)
		)
		(layer "In8.Cu")
	)
	(gr_line
		(start 431.666142 -136.347454)
		(end 431.666142 -136.344914)
		(stroke
			(width 0.2)
			(type default)
		)
		(layer "In8.Cu")
	)
	(gr_line
		(start 431.666142 -136.344914)
		(end 431.85461 -136.344914)
		(stroke
			(width 0.2)
			(type default)
		)
		(layer "In8.Cu")
	)
	(gr_line
		(start 431.85461 -136.347454)
		(end 431.666142 -136.347454)
		(stroke
			(width 0.2)
			(type default)
		)
		(layer "In8.Cu")
	)
	(gr_arc
		(start 431.85461 -136.344914)
		(mid 431.630681 -135.804303)
		(end 431.09007 -135.580374)
		(stroke
			(width 0.2)
			(type default)
		)
		(layer "In8.Cu")
	)
	(gr_line
		(start 433.63007 -137.109454)
		(end 434.90007 -137.109454)
		(stroke
			(width 0.2)
			(type default)
		)
		(layer "In8.Cu")
	)
	(gr_arc
		(start 433.63007 -135.580374)
		(mid 432.86553 -136.344914)
		(end 433.63007 -137.109454)
		(stroke
			(width 0.2)
			(type default)
		)
		(layer "In8.Cu")
	)
	(gr_arc
		(start 434.90007 -137.109454)
		(mid 435.439783 -136.886423)
		(end 435.66461 -136.347454)
		(stroke
			(width 0.2)
			(type default)
		)
		(layer "In8.Cu")
	)
	(gr_line
		(start 434.90007 -135.580374)
		(end 433.63007 -135.580374)
		(stroke
			(width 0.2)
			(type default)
		)
		(layer "In8.Cu")
	)
	(gr_line
		(start 435.473856 -136.347454)
		(end 435.473856 -136.344914)
		(stroke
			(width 0.2)
			(type default)
		)
		(layer "In8.Cu")
	)
	(gr_line
		(start 435.473856 -136.344914)
		(end 435.66461 -136.344914)
		(stroke
			(width 0.2)
			(type default)
		)
		(layer "In8.Cu")
	)
	(gr_line
		(start 435.66461 -136.347454)
		(end 435.473856 -136.347454)
		(stroke
			(width 0.2)
			(type default)
		)
		(layer "In8.Cu")
	)
	(gr_arc
		(start 435.66461 -136.344914)
		(mid 435.440681 -135.804303)
		(end 434.90007 -135.580374)
		(stroke
			(width 0.2)
			(type default)
		)
		(layer "In8.Cu")
	)
	(gr_line
		(start -3.899916 -39.710106)
		(end -3.899662 -39.710106)
		(stroke
			(width 0.05715)
			(type default)
		)
		(layer "In9.Cu")
	)
	(gr_line
		(start -3.899916 -31.710122)
		(end -3.899662 -31.710122)
		(stroke
			(width 0.050546)
			(type default)
		)
		(layer "In9.Cu")
	)
	(gr_line
		(start -3.899662 -39.710106)
		(end -3.408172 -40.201596)
		(stroke
			(width 0.05715)
			(type default)
		)
		(layer "In9.Cu")
	)
	(gr_line
		(start -3.899662 -31.710122)
		(end -3.42646 -31.23692)
		(stroke
			(width 0.050546)
			(type default)
		)
		(layer "In9.Cu")
	)
	(gr_line
		(start -2.991612 -40.201596)
		(end -2.500122 -39.710106)
		(stroke
			(width 0.05715)
			(type default)
		)
		(layer "In9.Cu")
	)
	(gr_line
		(start -2.901442 -31.308802)
		(end -2.500122 -31.710122)
		(stroke
			(width 0.050546)
			(type default)
		)
		(layer "In9.Cu")
	)
	(gr_line
		(start -2.599944 -37.71011)
		(end -2.142744 -37.71011)
		(stroke
			(width 0.05715)
			(type default)
		)
		(layer "In9.Cu")
	)
	(gr_line
		(start -2.142744 -37.71011)
		(end -2.076958 -37.775896)
		(stroke
			(width 0.05715)
			(type default)
		)
		(layer "In9.Cu")
	)
	(gr_line
		(start -1.660144 -37.775896)
		(end -1.594358 -37.71011)
		(stroke
			(width 0.05715)
			(type default)
		)
		(layer "In9.Cu")
	)
	(gr_line
		(start -1.594358 -37.71011)
		(end -1.20015 -37.71011)
		(stroke
			(width 0.05715)
			(type default)
		)
		(layer "In9.Cu")
	)
	(gr_poly
		(pts
			(xy 475.5134 -40.0558) (xy 472.8718 -40.0558) (xy 472.8718 -43.307) (xy 475.5134 -43.307)
		)
		(stroke
			(width 0)
			(type solid)
		)
		(fill yes)
		(layer "In9.Cu")
		(net "GND")
	)
	(gr_poly
		(pts
			(xy 367.6269 -105.9434) (xy 364.998 -105.9434) (xy 364.998 -109.038644) (xy 365.103156 -109.1438)
			(xy 367.6269 -109.1438)
		)
		(stroke
			(width 0)
			(type solid)
		)
		(fill yes)
		(layer "In9.Cu")
		(net "GND")
	)
	(gr_poly
		(pts
			(xy 408.83078 -100.708206) (xy 408.83078 -98.287078) (xy 405.741124 -98.287078) (xy 405.741124 -100.708714)
			(xy 408.827732 -100.708714)
		)
		(stroke
			(width 0)
			(type solid)
		)
		(fill yes)
		(layer "In9.Cu")
		(net "GND")
	)
	(gr_poly
		(pts
			(xy 368.1222 -100.787962) (xy 368.121184 -100.7872) (xy 368.121184 -96.2406) (xy 366.6998 -96.2406)
			(xy 366.6998 -100.9142) (xy 368.1222 -100.9142)
		)
		(stroke
			(width 0)
			(type solid)
		)
		(fill yes)
		(layer "In9.Cu")
		(net "GND")
	)
	(gr_line
		(start 0.299974 -39.710106)
		(end 0.300228 -39.710106)
		(stroke
			(width 0.05715)
			(type default)
		)
		(layer "In9.Cu")
	)
	(gr_line
		(start 0.299974 -35.710114)
		(end 0.487934 -35.710114)
		(stroke
			(width 0.05715)
			(type default)
		)
		(layer "In9.Cu")
	)
	(gr_line
		(start 0.299974 -31.710122)
		(end 0.300228 -31.710122)
		(stroke
			(width 0.050546)
			(type default)
		)
		(layer "In9.Cu")
	)
	(gr_line
		(start 0.300228 -39.710106)
		(end 0.791718 -40.201596)
		(stroke
			(width 0.05715)
			(type default)
		)
		(layer "In9.Cu")
	)
	(gr_line
		(start 0.300228 -31.710122)
		(end 0.701802 -32.111696)
		(stroke
			(width 0.050546)
			(type default)
		)
		(layer "In9.Cu")
	)
	(gr_line
		(start 0.487934 -35.710114)
		(end 0.790194 -35.407854)
		(stroke
			(width 0.05715)
			(type default)
		)
		(layer "In9.Cu")
	)
	(gr_line
		(start 0.8001 -40.95369)
		(end 0.859028 -41.012618)
		(stroke
			(width 0.05715)
			(type default)
		)
		(layer "In9.Cu")
	)
	(gr_line
		(start 1.206754 -35.407854)
		(end 1.509014 -35.710114)
		(stroke
			(width 0.05715)
			(type default)
		)
		(layer "In9.Cu")
	)
	(gr_line
		(start 1.208532 -40.201596)
		(end 1.700022 -39.710106)
		(stroke
			(width 0.05715)
			(type default)
		)
		(layer "In9.Cu")
	)
	(gr_line
		(start 1.298448 -32.111696)
		(end 1.700022 -31.710122)
		(stroke
			(width 0.050546)
			(type default)
		)
		(layer "In9.Cu")
	)
	(gr_line
		(start 1.416812 -41.570402)
		(end 1.42113 -41.57472)
		(stroke
			(width 0.05715)
			(type default)
		)
		(layer "In9.Cu")
	)
	(gr_line
		(start 1.42113 -41.57472)
		(end 1.425956 -41.57726)
		(stroke
			(width 0.05715)
			(type default)
		)
		(layer "In9.Cu")
	)
	(gr_line
		(start 1.509014 -35.710114)
		(end 1.700022 -35.710114)
		(stroke
			(width 0.05715)
			(type default)
		)
		(layer "In9.Cu")
	)
	(gr_line
		(start 1.599946 -37.71011)
		(end 1.62687 -37.71011)
		(stroke
			(width 0.05715)
			(type default)
		)
		(layer "In9.Cu")
	)
	(gr_line
		(start 1.62687 -37.71011)
		(end 2.02184 -37.31514)
		(stroke
			(width 0.05715)
			(type default)
		)
		(layer "In9.Cu")
	)
	(gr_line
		(start 1.87071 -41.818814)
		(end 1.901698 -41.835578)
		(stroke
			(width 0.05715)
			(type default)
		)
		(layer "In9.Cu")
	)
	(gr_line
		(start 2.438654 -37.31514)
		(end 2.833624 -37.71011)
		(stroke
			(width 0.05715)
			(type default)
		)
		(layer "In9.Cu")
	)
	(gr_line
		(start 2.824988 -41.540938)
		(end 2.939796 -41.42613)
		(stroke
			(width 0.05715)
			(type default)
		)
		(layer "In9.Cu")
	)
	(gr_line
		(start 2.833624 -37.71011)
		(end 2.999994 -37.71011)
		(stroke
			(width 0.05715)
			(type default)
		)
		(layer "In9.Cu")
	)
	(gr_line
		(start 2.939796 -41.42613)
		(end 3.282696 -41.42613)
		(stroke
			(width 0.05715)
			(type default)
		)
		(layer "In9.Cu")
	)
	(gr_line
		(start 3.282696 -41.42613)
		(end 3.397504 -41.540938)
		(stroke
			(width 0.05715)
			(type default)
		)
		(layer "In9.Cu")
	)
	(gr_line
		(start 4.499864 -39.710106)
		(end 4.500118 -39.710106)
		(stroke
			(width 0.05715)
			(type default)
		)
		(layer "In9.Cu")
	)
	(gr_line
		(start 4.500118 -39.710106)
		(end 4.910074 -40.120062)
		(stroke
			(width 0.05715)
			(type default)
		)
		(layer "In9.Cu")
	)
	(gr_line
		(start 4.9911 -40.496998)
		(end 5.050028 -40.555672)
		(stroke
			(width 0.05715)
			(type default)
		)
		(layer "In9.Cu")
	)
	(gr_line
		(start 5.055616 -64.557148)
		(end 5.235956 -64.737488)
		(stroke
			(width 0.1905)
			(type default)
		)
		(layer "In9.Cu")
	)
	(gr_line
		(start 5.235956 -64.737488)
		(end 7.456678 -64.737488)
		(stroke
			(width 0.1905)
			(type default)
		)
		(layer "In9.Cu")
	)
	(gr_line
		(start 5.326634 -40.120062)
		(end 5.73659 -39.710106)
		(stroke
			(width 0.05715)
			(type default)
		)
		(layer "In9.Cu")
	)
	(gr_line
		(start 5.427726 -40.9321)
		(end 5.439664 -40.944038)
		(stroke
			(width 0.05715)
			(type default)
		)
		(layer "In9.Cu")
	)
	(gr_line
		(start 5.439664 -40.944038)
		(end 5.455412 -40.950896)
		(stroke
			(width 0.05715)
			(type default)
		)
		(layer "In9.Cu")
	)
	(gr_line
		(start 5.73659 -39.710106)
		(end 5.899912 -39.710106)
		(stroke
			(width 0.05715)
			(type default)
		)
		(layer "In9.Cu")
	)
	(gr_line
		(start 7.134098 -34.564066)
		(end 7.15137 -34.571432)
		(stroke
			(width 0.05715)
			(type default)
		)
		(layer "In9.Cu")
	)
	(gr_line
		(start 7.17042 -38.564058)
		(end 7.182612 -38.56863)
		(stroke
			(width 0.05715)
			(type default)
		)
		(layer "In9.Cu")
	)
	(gr_line
		(start 7.456678 -64.737488)
		(end 9.398 -66.67881)
		(stroke
			(width 0.1905)
			(type default)
		)
		(layer "In9.Cu")
	)
	(gr_line
		(start 8.22325 -38.948614)
		(end 8.24103 -38.954964)
		(stroke
			(width 0.05715)
			(type default)
		)
		(layer "In9.Cu")
	)
	(gr_line
		(start 8.24103 -38.954964)
		(end 8.255508 -38.967918)
		(stroke
			(width 0.05715)
			(type default)
		)
		(layer "In9.Cu")
	)
	(gr_line
		(start 8.30326 -35.514534)
		(end 8.797036 -35.844734)
		(stroke
			(width 0.05715)
			(type default)
		)
		(layer "In9.Cu")
	)
	(gr_line
		(start 8.436102 -35.249104)
		(end 8.6614 -35.2044)
		(stroke
			(width 0.05715)
			(type default)
		)
		(layer "In9.Cu")
	)
	(gr_line
		(start 8.552942 -36.564062)
		(end 8.595868 -36.59378)
		(stroke
			(width 0.05715)
			(type default)
		)
		(layer "In9.Cu")
	)
	(gr_line
		(start 8.6614 -35.2044)
		(end 8.946642 -35.394646)
		(stroke
			(width 0.05715)
			(type default)
		)
		(layer "In9.Cu")
	)
	(gr_line
		(start 8.667496 -39.729664)
		(end 8.671814 -39.733474)
		(stroke
			(width 0.05715)
			(type default)
		)
		(layer "In9.Cu")
	)
	(gr_line
		(start 8.671814 -39.733474)
		(end 8.676894 -39.736014)
		(stroke
			(width 0.05715)
			(type default)
		)
		(layer "In9.Cu")
	)
	(gr_line
		(start 8.946642 -35.394646)
		(end 8.991346 -35.620452)
		(stroke
			(width 0.05715)
			(type default)
		)
		(layer "In9.Cu")
	)
	(gr_line
		(start 9.146794 -36.078414)
		(end 9.643364 -36.410392)
		(stroke
			(width 0.05715)
			(type default)
		)
		(layer "In9.Cu")
	)
	(gr_line
		(start 9.280652 -35.813492)
		(end 9.506458 -35.768788)
		(stroke
			(width 0.05715)
			(type default)
		)
		(layer "In9.Cu")
	)
	(gr_line
		(start 9.398 -66.67881)
		(end 9.398 -67.3989)
		(stroke
			(width 0.1905)
			(type default)
		)
		(layer "In9.Cu")
	)
	(gr_line
		(start 9.506458 -35.768788)
		(end 9.791446 -35.959034)
		(stroke
			(width 0.05715)
			(type default)
		)
		(layer "In9.Cu")
	)
	(gr_line
		(start 9.739122 -37.940234)
		(end 10.136886 -38.38575)
		(stroke
			(width 0.05715)
			(type default)
		)
		(layer "In9.Cu")
	)
	(gr_line
		(start 9.791446 -35.959034)
		(end 9.83615 -36.18484)
		(stroke
			(width 0.05715)
			(type default)
		)
		(layer "In9.Cu")
	)
	(gr_line
		(start 9.934702 -37.716968)
		(end 10.164318 -37.729922)
		(stroke
			(width 0.05715)
			(type default)
		)
		(layer "In9.Cu")
	)
	(gr_line
		(start 10.164318 -37.729922)
		(end 10.392664 -37.985446)
		(stroke
			(width 0.05715)
			(type default)
		)
		(layer "In9.Cu")
	)
	(gr_line
		(start 10.379964 -38.215316)
		(end 10.392664 -37.985446)
		(stroke
			(width 0.05715)
			(type default)
		)
		(layer "In9.Cu")
	)
	(gr_line
		(start 10.414 -66.728594)
		(end 10.414 -67.3989)
		(stroke
			(width 0.1905)
			(type default)
		)
		(layer "In9.Cu")
	)
	(gr_line
		(start 10.414 -66.728594)
		(end 12.5095 -64.633094)
		(stroke
			(width 0.1905)
			(type default)
		)
		(layer "In9.Cu")
	)
	(gr_line
		(start 10.416032 -41.84904)
		(end 10.434828 -41.852088)
		(stroke
			(width 0.05715)
			(type default)
		)
		(layer "In9.Cu")
	)
	(gr_line
		(start 10.434828 -41.852088)
		(end 10.453878 -41.847516)
		(stroke
			(width 0.05715)
			(type default)
		)
		(layer "In9.Cu")
	)
	(gr_line
		(start 10.486898 -42.528236)
		(end 10.505694 -42.531538)
		(stroke
			(width 0.05715)
			(type default)
		)
		(layer "In9.Cu")
	)
	(gr_line
		(start 10.505694 -42.531538)
		(end 10.52449 -42.526966)
		(stroke
			(width 0.05715)
			(type default)
		)
		(layer "In9.Cu")
	)
	(gr_line
		(start 10.59688 -38.46195)
		(end 10.608056 -38.474396)
		(stroke
			(width 0.05715)
			(type default)
		)
		(layer "In9.Cu")
	)
	(gr_line
		(start 10.608056 -38.474396)
		(end 10.614152 -38.490652)
		(stroke
			(width 0.05715)
			(type default)
		)
		(layer "In9.Cu")
	)
	(gr_line
		(start 10.684002 -39.520622)
		(end 10.689082 -39.534084)
		(stroke
			(width 0.05715)
			(type default)
		)
		(layer "In9.Cu")
	)
	(gr_line
		(start 10.689082 -39.534084)
		(end 10.69848 -39.544752)
		(stroke
			(width 0.05715)
			(type default)
		)
		(layer "In9.Cu")
	)
	(gr_line
		(start 10.730738 -41.482772)
		(end 10.749026 -41.478454)
		(stroke
			(width 0.05715)
			(type default)
		)
		(layer "In9.Cu")
	)
	(gr_line
		(start 10.749026 -41.478454)
		(end 10.767822 -41.481756)
		(stroke
			(width 0.05715)
			(type default)
		)
		(layer "In9.Cu")
	)
	(gr_line
		(start 10.801604 -42.162476)
		(end 10.820654 -42.157904)
		(stroke
			(width 0.05715)
			(type default)
		)
		(layer "In9.Cu")
	)
	(gr_line
		(start 10.808716 -37.478716)
		(end 10.843514 -37.513514)
		(stroke
			(width 0.05715)
			(type default)
		)
		(layer "In9.Cu")
	)
	(gr_line
		(start 10.820654 -42.157904)
		(end 10.83945 -42.160952)
		(stroke
			(width 0.05715)
			(type default)
		)
		(layer "In9.Cu")
	)
	(gr_line
		(start 10.843514 -37.513514)
		(end 10.89152 -37.523674)
		(stroke
			(width 0.05715)
			(type default)
		)
		(layer "In9.Cu")
	)
	(gr_line
		(start 10.897362 -39.7764)
		(end 10.906252 -39.78656)
		(stroke
			(width 0.05715)
			(type default)
		)
		(layer "In9.Cu")
	)
	(gr_line
		(start 10.906252 -39.78656)
		(end 10.918444 -39.793418)
		(stroke
			(width 0.05715)
			(type default)
		)
		(layer "In9.Cu")
	)
	(gr_line
		(start 11.895328 -41.277032)
		(end 11.899392 -41.279064)
		(stroke
			(width 0.05715)
			(type default)
		)
		(layer "In9.Cu")
	)
	(gr_line
		(start 11.899392 -41.279064)
		(end 11.903964 -41.279826)
		(stroke
			(width 0.05715)
			(type default)
		)
		(layer "In9.Cu")
	)
	(gr_line
		(start 12.016486 -39.206424)
		(end 12.264136 -39.206424)
		(stroke
			(width 0.05715)
			(type default)
		)
		(layer "In9.Cu")
	)
	(gr_line
		(start 12.264136 -39.206424)
		(end 12.303506 -39.245794)
		(stroke
			(width 0.05715)
			(type default)
		)
		(layer "In9.Cu")
	)
	(gr_line
		(start 12.378436 -39.60114)
		(end 12.420854 -39.652956)
		(stroke
			(width 0.05715)
			(type default)
		)
		(layer "In9.Cu")
	)
	(gr_line
		(start 12.5095 -64.633094)
		(end 14.513306 -64.633094)
		(stroke
			(width 0.1905)
			(type default)
		)
		(layer "In9.Cu")
	)
	(gr_line
		(start 12.554966 -40.711628)
		(end 12.56792 -40.718994)
		(stroke
			(width 0.05715)
			(type default)
		)
		(layer "In9.Cu")
	)
	(gr_line
		(start 12.56792 -40.718994)
		(end 12.582906 -40.721534)
		(stroke
			(width 0.05715)
			(type default)
		)
		(layer "In9.Cu")
	)
	(gr_line
		(start 12.657074 -39.941246)
		(end 12.683744 -39.973758)
		(stroke
			(width 0.05715)
			(type default)
		)
		(layer "In9.Cu")
	)
	(gr_line
		(start 12.683744 -39.973758)
		(end 12.722606 -39.98849)
		(stroke
			(width 0.05715)
			(type default)
		)
		(layer "In9.Cu")
	)
	(gr_line
		(start 12.68984 -37.4142)
		(end 12.707112 -37.421566)
		(stroke
			(width 0.05715)
			(type default)
		)
		(layer "In9.Cu")
	)
	(gr_line
		(start 12.720066 -39.245794)
		(end 12.759436 -39.206424)
		(stroke
			(width 0.05715)
			(type default)
		)
		(layer "In9.Cu")
	)
	(gr_line
		(start 12.759436 -39.206424)
		(end 13.032486 -39.206424)
		(stroke
			(width 0.05715)
			(type default)
		)
		(layer "In9.Cu")
	)
	(gr_line
		(start 14.303248 -38.08222)
		(end 14.323314 -38.090602)
		(stroke
			(width 0.05715)
			(type default)
		)
		(layer "In9.Cu")
	)
	(gr_line
		(start 14.513306 -64.633094)
		(end 14.605 -64.5414)
		(stroke
			(width 0.1905)
			(type default)
		)
		(layer "In9.Cu")
	)
	(gr_line
		(start 15.066264 -39.247064)
		(end 15.08633 -39.255446)
		(stroke
			(width 0.05715)
			(type default)
		)
		(layer "In9.Cu")
	)
	(gr_line
		(start 15.4178 -29.27985)
		(end 15.4178 -29.6545)
		(stroke
			(width 0.05715)
			(type default)
		)
		(layer "In9.Cu")
	)
	(gr_line
		(start 15.4178 -29.27985)
		(end 15.475966 -29.221684)
		(stroke
			(width 0.05715)
			(type default)
		)
		(layer "In9.Cu")
	)
	(gr_line
		(start 15.4178 -28.746704)
		(end 15.475966 -28.80487)
		(stroke
			(width 0.05715)
			(type default)
		)
		(layer "In9.Cu")
	)
	(gr_line
		(start 15.4178 -28.3845)
		(end 15.4178 -28.746704)
		(stroke
			(width 0.05715)
			(type default)
		)
		(layer "In9.Cu")
	)
	(gr_line
		(start 15.443454 -26.0985)
		(end 15.451074 -25.72385)
		(stroke
			(width 0.05715)
			(type default)
		)
		(layer "In9.Cu")
	)
	(gr_line
		(start 15.443454 -24.8285)
		(end 15.450566 -25.181306)
		(stroke
			(width 0.05715)
			(type default)
		)
		(layer "In9.Cu")
	)
	(gr_line
		(start 15.450566 -25.181306)
		(end 15.564612 -25.293066)
		(stroke
			(width 0.05715)
			(type default)
		)
		(layer "In9.Cu")
	)
	(gr_line
		(start 15.451074 -36.406328)
		(end 15.451074 -36.7665)
		(stroke
			(width 0.05715)
			(type default)
		)
		(layer "In9.Cu")
	)
	(gr_line
		(start 15.451074 -36.406328)
		(end 15.510256 -36.347146)
		(stroke
			(width 0.05715)
			(type default)
		)
		(layer "In9.Cu")
	)
	(gr_line
		(start 15.451074 -35.87115)
		(end 15.510256 -35.930332)
		(stroke
			(width 0.05715)
			(type default)
		)
		(layer "In9.Cu")
	)
	(gr_line
		(start 15.451074 -35.4965)
		(end 15.451074 -35.87115)
		(stroke
			(width 0.05715)
			(type default)
		)
		(layer "In9.Cu")
	)
	(gr_line
		(start 15.451074 -32.83585)
		(end 15.451074 -33.2105)
		(stroke
			(width 0.05715)
			(type default)
		)
		(layer "In9.Cu")
	)
	(gr_line
		(start 15.451074 -32.83585)
		(end 15.503144 -32.78378)
		(stroke
			(width 0.05715)
			(type default)
		)
		(layer "In9.Cu")
	)
	(gr_line
		(start 15.451074 -32.31515)
		(end 15.503144 -32.36722)
		(stroke
			(width 0.05715)
			(type default)
		)
		(layer "In9.Cu")
	)
	(gr_line
		(start 15.451074 -31.9405)
		(end 15.451074 -32.31515)
		(stroke
			(width 0.05715)
			(type default)
		)
		(layer "In9.Cu")
	)
	(gr_line
		(start 15.451074 -25.72385)
		(end 15.585694 -25.58923)
		(stroke
			(width 0.05715)
			(type default)
		)
		(layer "In9.Cu")
	)
	(gr_line
		(start 16.026892 -38.474142)
		(end 16.426942 -38.474142)
		(stroke
			(width 0.05715)
			(type default)
		)
		(layer "In9.Cu")
	)
	(gr_line
		(start 16.18615 -23.0886)
		(end 16.5608 -23.0886)
		(stroke
			(width 0.05715)
			(type default)
		)
		(layer "In9.Cu")
	)
	(gr_line
		(start 16.398494 -36.283392)
		(end 16.415766 -36.276026)
		(stroke
			(width 0.05715)
			(type default)
		)
		(layer "In9.Cu")
	)
	(gr_line
		(start 16.426942 -38.474142)
		(end 16.453612 -38.500812)
		(stroke
			(width 0.05715)
			(type default)
		)
		(layer "In9.Cu")
	)
	(gr_line
		(start 16.5608 -23.0886)
		(end 16.61287 -23.14067)
		(stroke
			(width 0.05715)
			(type default)
		)
		(layer "In9.Cu")
	)
	(gr_line
		(start 16.607536 -27.50185)
		(end 16.607536 -27.8765)
		(stroke
			(width 0.05715)
			(type default)
		)
		(layer "In9.Cu")
	)
	(gr_line
		(start 16.607536 -27.50185)
		(end 16.659606 -27.44978)
		(stroke
			(width 0.05715)
			(type default)
		)
		(layer "In9.Cu")
	)
	(gr_line
		(start 16.607536 -26.98115)
		(end 16.659606 -27.03322)
		(stroke
			(width 0.05715)
			(type default)
		)
		(layer "In9.Cu")
	)
	(gr_line
		(start 16.607536 -26.6065)
		(end 16.607536 -26.98115)
		(stroke
			(width 0.05715)
			(type default)
		)
		(layer "In9.Cu")
	)
	(gr_line
		(start 16.61287 -31.05277)
		(end 16.61287 -31.42742)
		(stroke
			(width 0.05715)
			(type default)
		)
		(layer "In9.Cu")
	)
	(gr_line
		(start 16.61287 -31.05277)
		(end 16.66494 -31.0007)
		(stroke
			(width 0.05715)
			(type default)
		)
		(layer "In9.Cu")
	)
	(gr_line
		(start 16.61287 -30.53207)
		(end 16.66494 -30.58414)
		(stroke
			(width 0.05715)
			(type default)
		)
		(layer "In9.Cu")
	)
	(gr_line
		(start 16.61287 -30.15742)
		(end 16.61287 -30.53207)
		(stroke
			(width 0.05715)
			(type default)
		)
		(layer "In9.Cu")
	)
	(gr_line
		(start 16.684498 -34.61385)
		(end 16.684498 -34.9885)
		(stroke
			(width 0.05715)
			(type default)
		)
		(layer "In9.Cu")
	)
	(gr_line
		(start 16.684498 -34.61385)
		(end 16.736568 -34.56178)
		(stroke
			(width 0.05715)
			(type default)
		)
		(layer "In9.Cu")
	)
	(gr_line
		(start 16.684498 -34.09315)
		(end 16.736568 -34.14522)
		(stroke
			(width 0.05715)
			(type default)
		)
		(layer "In9.Cu")
	)
	(gr_line
		(start 16.684498 -33.7185)
		(end 16.684498 -34.09315)
		(stroke
			(width 0.05715)
			(type default)
		)
		(layer "In9.Cu")
	)
	(gr_line
		(start 16.870172 -38.500812)
		(end 16.896842 -38.474142)
		(stroke
			(width 0.05715)
			(type default)
		)
		(layer "In9.Cu")
	)
	(gr_line
		(start 16.896842 -38.474142)
		(end 17.296892 -38.474142)
		(stroke
			(width 0.05715)
			(type default)
		)
		(layer "In9.Cu")
	)
	(gr_line
		(start 16.992346 -39.337488)
		(end 17.041622 -39.34714)
		(stroke
			(width 0.05715)
			(type default)
		)
		(layer "In9.Cu")
	)
	(gr_line
		(start 17.02943 -23.14067)
		(end 17.0815 -23.0886)
		(stroke
			(width 0.05715)
			(type default)
		)
		(layer "In9.Cu")
	)
	(gr_line
		(start 17.0815 -23.0886)
		(end 17.45615 -23.0886)
		(stroke
			(width 0.05715)
			(type default)
		)
		(layer "In9.Cu")
	)
	(gr_line
		(start 17.127728 -27.09545)
		(end 17.145508 -27.102816)
		(stroke
			(width 0.05715)
			(type default)
		)
		(layer "In9.Cu")
	)
	(gr_line
		(start 17.135094 -32.72155)
		(end 17.152366 -32.714184)
		(stroke
			(width 0.05715)
			(type default)
		)
		(layer "In9.Cu")
	)
	(gr_line
		(start 17.135348 -23.946104)
		(end 17.184878 -23.95601)
		(stroke
			(width 0.05715)
			(type default)
		)
		(layer "In9.Cu")
	)
	(gr_line
		(start 17.447768 -30.94355)
		(end 17.466564 -30.93593)
		(stroke
			(width 0.05715)
			(type default)
		)
		(layer "In9.Cu")
	)
	(gr_line
		(start 17.50568 -35.508946)
		(end 17.522952 -35.50158)
		(stroke
			(width 0.05715)
			(type default)
		)
		(layer "In9.Cu")
	)
	(gr_line
		(start 17.527524 -27.260804)
		(end 17.545812 -27.268424)
		(stroke
			(width 0.05715)
			(type default)
		)
		(layer "In9.Cu")
	)
	(gr_line
		(start 17.545812 -27.268424)
		(end 17.560036 -27.282648)
		(stroke
			(width 0.05715)
			(type default)
		)
		(layer "In9.Cu")
	)
	(gr_line
		(start 17.772888 -27.90952)
		(end 17.831308 -27.96794)
		(stroke
			(width 0.05715)
			(type default)
		)
		(layer "In9.Cu")
	)
	(gr_line
		(start 18.00352 -28.861004)
		(end 18.020792 -28.86837)
		(stroke
			(width 0.05715)
			(type default)
		)
		(layer "In9.Cu")
	)
	(gr_line
		(start 18.600674 -29.424376)
		(end 18.617946 -29.431742)
		(stroke
			(width 0.05715)
			(type default)
		)
		(layer "In9.Cu")
	)
	(gr_line
		(start 18.95221 -35.79368)
		(end 18.969228 -35.786822)
		(stroke
			(width 0.05715)
			(type default)
		)
		(layer "In9.Cu")
	)
	(gr_line
		(start 19.343878 -31.490666)
		(end 19.36115 -31.4833)
		(stroke
			(width 0.05715)
			(type default)
		)
		(layer "In9.Cu")
	)
	(gr_line
		(start 19.42084 -29.809694)
		(end 19.439382 -29.802074)
		(stroke
			(width 0.05715)
			(type default)
		)
		(layer "In9.Cu")
	)
	(gr_line
		(start 19.439382 -29.802074)
		(end 19.459194 -29.802074)
		(stroke
			(width 0.05715)
			(type default)
		)
		(layer "In9.Cu")
	)
	(gr_line
		(start 20.191222 -34.5821)
		(end 20.208494 -34.574734)
		(stroke
			(width 0.05715)
			(type default)
		)
		(layer "In9.Cu")
	)
	(gr_line
		(start 20.957286 -24.64054)
		(end 21.119846 -24.8031)
		(stroke
			(width 0.05715)
			(type default)
		)
		(layer "In9.Cu")
	)
	(gr_line
		(start 20.997926 -40.13835)
		(end 21.040598 -40.146986)
		(stroke
			(width 0.05715)
			(type default)
		)
		(layer "In9.Cu")
	)
	(gr_line
		(start 21.040598 -40.146986)
		(end 21.081746 -40.132254)
		(stroke
			(width 0.05715)
			(type default)
		)
		(layer "In9.Cu")
	)
	(gr_line
		(start 21.119846 -24.8031)
		(end 21.462746 -24.8031)
		(stroke
			(width 0.05715)
			(type default)
		)
		(layer "In9.Cu")
	)
	(gr_line
		(start 21.249386 -24.3459)
		(end 21.333206 -24.3459)
		(stroke
			(width 0.05715)
			(type default)
		)
		(layer "In9.Cu")
	)
	(gr_line
		(start 21.462746 -24.8031)
		(end 21.625306 -24.64054)
		(stroke
			(width 0.05715)
			(type default)
		)
		(layer "In9.Cu")
	)
	(gr_line
		(start 21.973286 -24.64054)
		(end 22.135846 -24.8031)
		(stroke
			(width 0.05715)
			(type default)
		)
		(layer "In9.Cu")
	)
	(gr_line
		(start 22.135846 -24.8031)
		(end 22.478746 -24.8031)
		(stroke
			(width 0.05715)
			(type default)
		)
		(layer "In9.Cu")
	)
	(gr_line
		(start 22.265386 -24.3459)
		(end 22.349206 -24.3459)
		(stroke
			(width 0.05715)
			(type default)
		)
		(layer "In9.Cu")
	)
	(gr_line
		(start 22.478746 -24.8031)
		(end 22.641306 -24.64054)
		(stroke
			(width 0.05715)
			(type default)
		)
		(layer "In9.Cu")
	)
	(gr_line
		(start 22.892258 -41.1099)
		(end 22.90572 -41.112186)
		(stroke
			(width 0.05715)
			(type default)
		)
		(layer "In9.Cu")
	)
	(gr_line
		(start 22.90572 -41.112186)
		(end 22.919182 -41.1099)
		(stroke
			(width 0.05715)
			(type default)
		)
		(layer "In9.Cu")
	)
	(gr_line
		(start 22.989286 -24.64054)
		(end 23.151846 -24.8031)
		(stroke
			(width 0.05715)
			(type default)
		)
		(layer "In9.Cu")
	)
	(gr_line
		(start 23.151846 -24.8031)
		(end 23.494746 -24.8031)
		(stroke
			(width 0.05715)
			(type default)
		)
		(layer "In9.Cu")
	)
	(gr_line
		(start 23.281386 -24.3459)
		(end 23.365206 -24.3459)
		(stroke
			(width 0.05715)
			(type default)
		)
		(layer "In9.Cu")
	)
	(gr_line
		(start 23.299166 -41.04259)
		(end 23.311866 -41.040304)
		(stroke
			(width 0.05715)
			(type default)
		)
		(layer "In9.Cu")
	)
	(gr_line
		(start 23.311866 -41.040304)
		(end 23.323042 -41.033954)
		(stroke
			(width 0.05715)
			(type default)
		)
		(layer "In9.Cu")
	)
	(gr_line
		(start 23.38197 -38.993318)
		(end 23.394162 -38.989)
		(stroke
			(width 0.05715)
			(type default)
		)
		(layer "In9.Cu")
	)
	(gr_line
		(start 23.494746 -24.8031)
		(end 23.657306 -24.64054)
		(stroke
			(width 0.05715)
			(type default)
		)
		(layer "In9.Cu")
	)
	(gr_line
		(start 23.607268 -42.07383)
		(end 23.63089 -42.078656)
		(stroke
			(width 0.05715)
			(type default)
		)
		(layer "In9.Cu")
	)
	(gr_line
		(start 23.63089 -42.078656)
		(end 23.654766 -42.073322)
		(stroke
			(width 0.05715)
			(type default)
		)
		(layer "In9.Cu")
	)
	(gr_line
		(start 24.005286 -24.64054)
		(end 24.167846 -24.8031)
		(stroke
			(width 0.05715)
			(type default)
		)
		(layer "In9.Cu")
	)
	(gr_line
		(start 24.167846 -24.8031)
		(end 24.510746 -24.8031)
		(stroke
			(width 0.05715)
			(type default)
		)
		(layer "In9.Cu")
	)
	(gr_line
		(start 24.297386 -24.3459)
		(end 24.381206 -24.3459)
		(stroke
			(width 0.05715)
			(type default)
		)
		(layer "In9.Cu")
	)
	(gr_line
		(start 24.311864 -32.559498)
		(end 24.329136 -32.552132)
		(stroke
			(width 0.05715)
			(type default)
		)
		(layer "In9.Cu")
	)
	(gr_line
		(start 24.445468 -33.262316)
		(end 24.462486 -33.255458)
		(stroke
			(width 0.05715)
			(type default)
		)
		(layer "In9.Cu")
	)
	(gr_line
		(start 24.484584 -42.921174)
		(end 25.054814 -43.03522)
		(stroke
			(width 0.05715)
			(type default)
		)
		(layer "In9.Cu")
	)
	(gr_line
		(start 24.508968 -42.625518)
		(end 24.687784 -42.505884)
		(stroke
			(width 0.05715)
			(type default)
		)
		(layer "In9.Cu")
	)
	(gr_line
		(start 24.510746 -24.8031)
		(end 24.673306 -24.64054)
		(stroke
			(width 0.05715)
			(type default)
		)
		(layer "In9.Cu")
	)
	(gr_line
		(start 24.687784 -42.505884)
		(end 25.024588 -42.573448)
		(stroke
			(width 0.05715)
			(type default)
		)
		(layer "In9.Cu")
	)
	(gr_line
		(start 24.882094 -39.808404)
		(end 24.915622 -39.7891)
		(stroke
			(width 0.05715)
			(type default)
		)
		(layer "In9.Cu")
	)
	(gr_line
		(start 25.024588 -42.573448)
		(end 25.143968 -42.752518)
		(stroke
			(width 0.05715)
			(type default)
		)
		(layer "In9.Cu")
	)
	(gr_line
		(start 25.194768 -33.255458)
		(end 25.214072 -33.263586)
		(stroke
			(width 0.05715)
			(type default)
		)
		(layer "In9.Cu")
	)
	(gr_line
		(start 25.33015 -32.552132)
		(end 25.347422 -32.559498)
		(stroke
			(width 0.05715)
			(type default)
		)
		(layer "In9.Cu")
	)
	(gr_line
		(start 25.642316 -45.306488)
		(end 25.661366 -45.310298)
		(stroke
			(width 0.05715)
			(type default)
		)
		(layer "In9.Cu")
	)
	(gr_line
		(start 25.661366 -45.310298)
		(end 25.680416 -45.306488)
		(stroke
			(width 0.05715)
			(type default)
		)
		(layer "In9.Cu")
	)
	(gr_line
		(start 25.70099 -44.647104)
		(end 25.72004 -44.650914)
		(stroke
			(width 0.05715)
			(type default)
		)
		(layer "In9.Cu")
	)
	(gr_line
		(start 25.714706 -43.167046)
		(end 25.715976 -43.1673)
		(stroke
			(width 0.05715)
			(type default)
		)
		(layer "In9.Cu")
	)
	(gr_line
		(start 25.715976 -43.1673)
		(end 25.717246 -43.1673)
		(stroke
			(width 0.05715)
			(type default)
		)
		(layer "In9.Cu")
	)
	(gr_line
		(start 25.72004 -44.650914)
		(end 25.73909 -44.647104)
		(stroke
			(width 0.05715)
			(type default)
		)
		(layer "In9.Cu")
	)
	(gr_line
		(start 25.837134 -41.242996)
		(end 26.403808 -41.042844)
		(stroke
			(width 0.05715)
			(type default)
		)
		(layer "In9.Cu")
	)
	(gr_line
		(start 25.894284 -40.08374)
		(end 26.056844 -40.2463)
		(stroke
			(width 0.05715)
			(type default)
		)
		(layer "In9.Cu")
	)
	(gr_line
		(start 25.903174 -41.532048)
		(end 26.110946 -41.631362)
		(stroke
			(width 0.05715)
			(type default)
		)
		(layer "In9.Cu")
	)
	(gr_line
		(start 25.921208 -46.010322)
		(end 25.940766 -46.014386)
		(stroke
			(width 0.05715)
			(type default)
		)
		(layer "In9.Cu")
	)
	(gr_line
		(start 25.940766 -46.014386)
		(end 25.94102 -46.014386)
		(stroke
			(width 0.05715)
			(type default)
		)
		(layer "In9.Cu")
	)
	(gr_line
		(start 25.94102 -46.014386)
		(end 25.962356 -46.010068)
		(stroke
			(width 0.05715)
			(type default)
		)
		(layer "In9.Cu")
	)
	(gr_line
		(start 26.056844 -40.2463)
		(end 26.399744 -40.2463)
		(stroke
			(width 0.05715)
			(type default)
		)
		(layer "In9.Cu")
	)
	(gr_line
		(start 26.110946 -41.631362)
		(end 26.434288 -41.517316)
		(stroke
			(width 0.05715)
			(type default)
		)
		(layer "In9.Cu")
	)
	(gr_line
		(start 26.119074 -43.915838)
		(end 26.138124 -43.919648)
		(stroke
			(width 0.05715)
			(type default)
		)
		(layer "In9.Cu")
	)
	(gr_line
		(start 26.138124 -43.919648)
		(end 26.157174 -43.915838)
		(stroke
			(width 0.05715)
			(type default)
		)
		(layer "In9.Cu")
	)
	(gr_line
		(start 26.186384 -39.7891)
		(end 26.270204 -39.7891)
		(stroke
			(width 0.05715)
			(type default)
		)
		(layer "In9.Cu")
	)
	(gr_line
		(start 26.399744 -40.2463)
		(end 26.562304 -40.08374)
		(stroke
			(width 0.05715)
			(type default)
		)
		(layer "In9.Cu")
	)
	(gr_line
		(start 26.434288 -41.517316)
		(end 26.533856 -41.309544)
		(stroke
			(width 0.05715)
			(type default)
		)
		(layer "In9.Cu")
	)
	(gr_line
		(start 26.65349 -43.10888)
		(end 26.668476 -43.107864)
		(stroke
			(width 0.05715)
			(type default)
		)
		(layer "In9.Cu")
	)
	(gr_line
		(start 26.668476 -43.107864)
		(end 26.681684 -43.102022)
		(stroke
			(width 0.05715)
			(type default)
		)
		(layer "In9.Cu")
	)
	(gr_line
		(start 26.72334 -45.553122)
		(end 26.763472 -45.54474)
		(stroke
			(width 0.05715)
			(type default)
		)
		(layer "In9.Cu")
	)
	(gr_line
		(start 26.763472 -45.54474)
		(end 26.802334 -45.557948)
		(stroke
			(width 0.05715)
			(type default)
		)
		(layer "In9.Cu")
	)
	(gr_line
		(start 27.132788 -29.783532)
		(end 27.183334 -29.783532)
		(stroke
			(width 0.05715)
			(type default)
		)
		(layer "In9.Cu")
	)
	(gr_line
		(start 27.183334 -29.783532)
		(end 27.225498 -29.811472)
		(stroke
			(width 0.05715)
			(type default)
		)
		(layer "In9.Cu")
	)
	(gr_line
		(start 27.560016 -45.810424)
		(end 27.651964 -45.841158)
		(stroke
			(width 0.05715)
			(type default)
		)
		(layer "In9.Cu")
	)
	(gr_line
		(start 27.645868 -25.657048)
		(end 27.773376 -25.84831)
		(stroke
			(width 0.05715)
			(type default)
		)
		(layer "In9.Cu")
	)
	(gr_line
		(start 27.651964 -45.841158)
		(end 27.688286 -45.930566)
		(stroke
			(width 0.05715)
			(type default)
		)
		(layer "In9.Cu")
	)
	(gr_line
		(start 27.69997 -46.73346)
		(end 27.70886 -46.755304)
		(stroke
			(width 0.05715)
			(type default)
		)
		(layer "In9.Cu")
	)
	(gr_line
		(start 27.70886 -46.755304)
		(end 27.725624 -46.772068)
		(stroke
			(width 0.05715)
			(type default)
		)
		(layer "In9.Cu")
	)
	(gr_line
		(start 27.738832 -25.375108)
		(end 28.323032 -25.491948)
		(stroke
			(width 0.05715)
			(type default)
		)
		(layer "In9.Cu")
	)
	(gr_line
		(start 27.773376 -25.84831)
		(end 28.109418 -25.91562)
		(stroke
			(width 0.05715)
			(type default)
		)
		(layer "In9.Cu")
	)
	(gr_line
		(start 27.805634 -40.548052)
		(end 28.370276 -40.348662)
		(stroke
			(width 0.05715)
			(type default)
		)
		(layer "In9.Cu")
	)
	(gr_line
		(start 27.822144 -30.560772)
		(end 27.8384 -30.57144)
		(stroke
			(width 0.05715)
			(type default)
		)
		(layer "In9.Cu")
	)
	(gr_line
		(start 27.8384 -30.57144)
		(end 27.85745 -30.57525)
		(stroke
			(width 0.05715)
			(type default)
		)
		(layer "In9.Cu")
	)
	(gr_line
		(start 27.871166 -40.837612)
		(end 28.078684 -40.936926)
		(stroke
			(width 0.05715)
			(type default)
		)
		(layer "In9.Cu")
	)
	(gr_line
		(start 27.923744 -40.0812)
		(end 27.972004 -40.044116)
		(stroke
			(width 0.05715)
			(type default)
		)
		(layer "In9.Cu")
	)
	(gr_line
		(start 28.04287 -27.38755)
		(end 28.060142 -27.394916)
		(stroke
			(width 0.05715)
			(type default)
		)
		(layer "In9.Cu")
	)
	(gr_line
		(start 28.078684 -40.936926)
		(end 28.402026 -40.82288)
		(stroke
			(width 0.05715)
			(type default)
		)
		(layer "In9.Cu")
	)
	(gr_line
		(start 28.109418 -25.91562)
		(end 28.30068 -25.788112)
		(stroke
			(width 0.05715)
			(type default)
		)
		(layer "In9.Cu")
	)
	(gr_line
		(start 28.206954 -47.247302)
		(end 28.242514 -47.282608)
		(stroke
			(width 0.05715)
			(type default)
		)
		(layer "In9.Cu")
	)
	(gr_line
		(start 28.242514 -47.282608)
		(end 28.292044 -47.292514)
		(stroke
			(width 0.05715)
			(type default)
		)
		(layer "In9.Cu")
	)
	(gr_line
		(start 28.402026 -40.82288)
		(end 28.501086 -40.615108)
		(stroke
			(width 0.05715)
			(type default)
		)
		(layer "In9.Cu")
	)
	(gr_line
		(start 28.576524 -31.4833)
		(end 28.593796 -31.490666)
		(stroke
			(width 0.05715)
			(type default)
		)
		(layer "In9.Cu")
	)
	(gr_line
		(start 28.642056 -25.856438)
		(end 28.769564 -26.0477)
		(stroke
			(width 0.05715)
			(type default)
		)
		(layer "In9.Cu")
	)
	(gr_line
		(start 28.65374 -42.218102)
		(end 28.668472 -42.211498)
		(stroke
			(width 0.05715)
			(type default)
		)
		(layer "In9.Cu")
	)
	(gr_line
		(start 28.668472 -42.211498)
		(end 28.680156 -42.200068)
		(stroke
			(width 0.05715)
			(type default)
		)
		(layer "In9.Cu")
	)
	(gr_line
		(start 28.73502 -25.574498)
		(end 29.318966 -25.691338)
		(stroke
			(width 0.05715)
			(type default)
		)
		(layer "In9.Cu")
	)
	(gr_line
		(start 28.769564 -26.0477)
		(end 29.10586 -26.11501)
		(stroke
			(width 0.05715)
			(type default)
		)
		(layer "In9.Cu")
	)
	(gr_line
		(start 28.888944 -38.10762)
		(end 28.909518 -38.1)
		(stroke
			(width 0.05715)
			(type default)
		)
		(layer "In9.Cu")
	)
	(gr_line
		(start 29.032454 -38.860984)
		(end 29.080714 -38.8239)
		(stroke
			(width 0.05715)
			(type default)
		)
		(layer "In9.Cu")
	)
	(gr_line
		(start 29.104336 -47.454312)
		(end 29.123894 -47.458376)
		(stroke
			(width 0.05715)
			(type default)
		)
		(layer "In9.Cu")
	)
	(gr_line
		(start 29.10586 -26.11501)
		(end 29.296868 -25.987502)
		(stroke
			(width 0.05715)
			(type default)
		)
		(layer "In9.Cu")
	)
	(gr_line
		(start 29.123894 -47.458376)
		(end 29.142944 -47.454566)
		(stroke
			(width 0.05715)
			(type default)
		)
		(layer "In9.Cu")
	)
	(gr_line
		(start 29.334206 -29.139642)
		(end 29.351478 -29.147008)
		(stroke
			(width 0.05715)
			(type default)
		)
		(layer "In9.Cu")
	)
	(gr_line
		(start 29.638244 -26.055574)
		(end 29.765752 -26.24709)
		(stroke
			(width 0.05715)
			(type default)
		)
		(layer "In9.Cu")
	)
	(gr_line
		(start 29.674566 -40.807386)
		(end 29.680662 -40.801544)
		(stroke
			(width 0.05715)
			(type default)
		)
		(layer "In9.Cu")
	)
	(gr_line
		(start 29.680662 -40.801544)
		(end 29.688028 -40.797734)
		(stroke
			(width 0.05715)
			(type default)
		)
		(layer "In9.Cu")
	)
	(gr_line
		(start 29.731208 -25.773888)
		(end 30.315154 -25.890728)
		(stroke
			(width 0.05715)
			(type default)
		)
		(layer "In9.Cu")
	)
	(gr_line
		(start 29.765752 -26.24709)
		(end 30.102048 -26.3144)
		(stroke
			(width 0.05715)
			(type default)
		)
		(layer "In9.Cu")
	)
	(gr_line
		(start 29.850334 -47.315882)
		(end 29.932884 -47.308516)
		(stroke
			(width 0.05715)
			(type default)
		)
		(layer "In9.Cu")
	)
	(gr_line
		(start 29.932884 -47.308516)
		(end 29.987748 -47.244254)
		(stroke
			(width 0.05715)
			(type default)
		)
		(layer "In9.Cu")
	)
	(gr_line
		(start 30.003496 -31.00705)
		(end 30.131258 -31.198566)
		(stroke
			(width 0.05715)
			(type default)
		)
		(layer "In9.Cu")
	)
	(gr_line
		(start 30.063948 -32.415734)
		(end 30.08122 -32.4231)
		(stroke
			(width 0.05715)
			(type default)
		)
		(layer "In9.Cu")
	)
	(gr_line
		(start 30.09646 -30.725364)
		(end 30.682946 -30.842458)
		(stroke
			(width 0.05715)
			(type default)
		)
		(layer "In9.Cu")
	)
	(gr_line
		(start 30.102048 -26.3144)
		(end 30.29331 -26.186892)
		(stroke
			(width 0.05715)
			(type default)
		)
		(layer "In9.Cu")
	)
	(gr_line
		(start 30.131258 -31.198566)
		(end 30.467554 -31.265622)
		(stroke
			(width 0.05715)
			(type default)
		)
		(layer "In9.Cu")
	)
	(gr_line
		(start 30.348682 -39.49827)
		(end 30.376622 -39.4843)
		(stroke
			(width 0.05715)
			(type default)
		)
		(layer "In9.Cu")
	)
	(gr_line
		(start 30.457902 -34.833306)
		(end 30.506416 -34.853372)
		(stroke
			(width 0.05715)
			(type default)
		)
		(layer "In9.Cu")
	)
	(gr_line
		(start 30.467554 -31.265622)
		(end 30.65907 -31.138114)
		(stroke
			(width 0.05715)
			(type default)
		)
		(layer "In9.Cu")
	)
	(gr_line
		(start 30.506416 -34.853372)
		(end 30.557978 -34.842958)
		(stroke
			(width 0.05715)
			(type default)
		)
		(layer "In9.Cu")
	)
	(gr_line
		(start 30.634432 -26.254964)
		(end 30.76194 -26.44648)
		(stroke
			(width 0.05715)
			(type default)
		)
		(layer "In9.Cu")
	)
	(gr_line
		(start 30.726888 -25.973024)
		(end 31.31185 -26.090118)
		(stroke
			(width 0.05715)
			(type default)
		)
		(layer "In9.Cu")
	)
	(gr_line
		(start 30.76194 -26.44648)
		(end 31.098236 -26.51379)
		(stroke
			(width 0.05715)
			(type default)
		)
		(layer "In9.Cu")
	)
	(gr_line
		(start 30.947614 -30.124146)
		(end 31.500318 -30.353)
		(stroke
			(width 0.05715)
			(type default)
		)
		(layer "In9.Cu")
	)
	(gr_line
		(start 30.959806 -32.131)
		(end 30.977078 -32.138366)
		(stroke
			(width 0.05715)
			(type default)
		)
		(layer "In9.Cu")
	)
	(gr_line
		(start 30.988 -40.133778)
		(end 31.016448 -40.1193)
		(stroke
			(width 0.05715)
			(type default)
		)
		(layer "In9.Cu")
	)
	(gr_line
		(start 31.000192 -31.20644)
		(end 31.1277 -31.397702)
		(stroke
			(width 0.05715)
			(type default)
		)
		(layer "In9.Cu")
	)
	(gr_line
		(start 31.027624 -29.838396)
		(end 31.240222 -29.750512)
		(stroke
			(width 0.05715)
			(type default)
		)
		(layer "In9.Cu")
	)
	(gr_line
		(start 31.093918 -30.924754)
		(end 31.676848 -31.04134)
		(stroke
			(width 0.05715)
			(type default)
		)
		(layer "In9.Cu")
	)
	(gr_line
		(start 31.098236 -26.51379)
		(end 31.289498 -26.386282)
		(stroke
			(width 0.05715)
			(type default)
		)
		(layer "In9.Cu")
	)
	(gr_line
		(start 31.1277 -31.397702)
		(end 31.463742 -31.465012)
		(stroke
			(width 0.05715)
			(type default)
		)
		(layer "In9.Cu")
	)
	(gr_line
		(start 31.240222 -29.750512)
		(end 31.557214 -29.881576)
		(stroke
			(width 0.05715)
			(type default)
		)
		(layer "In9.Cu")
	)
	(gr_line
		(start 31.46044 -42.855388)
		(end 31.461456 -42.855134)
		(stroke
			(width 0.05715)
			(type default)
		)
		(layer "In9.Cu")
	)
	(gr_line
		(start 31.461456 -42.855134)
		(end 31.462472 -42.854626)
		(stroke
			(width 0.05715)
			(type default)
		)
		(layer "In9.Cu")
	)
	(gr_line
		(start 31.463742 -31.465012)
		(end 31.655258 -31.337504)
		(stroke
			(width 0.05715)
			(type default)
		)
		(layer "In9.Cu")
	)
	(gr_line
		(start 31.557214 -29.881576)
		(end 31.645352 -30.094174)
		(stroke
			(width 0.05715)
			(type default)
		)
		(layer "In9.Cu")
	)
	(gr_line
		(start 31.792926 -43.436794)
		(end 31.795212 -43.436286)
		(stroke
			(width 0.05715)
			(type default)
		)
		(layer "In9.Cu")
	)
	(gr_line
		(start 31.795212 -43.436286)
		(end 31.797498 -43.43527)
		(stroke
			(width 0.05715)
			(type default)
		)
		(layer "In9.Cu")
	)
	(gr_line
		(start 31.886398 -30.51302)
		(end 32.437832 -30.741366)
		(stroke
			(width 0.05715)
			(type default)
		)
		(layer "In9.Cu")
	)
	(gr_line
		(start 31.966408 -30.22727)
		(end 32.179006 -30.139132)
		(stroke
			(width 0.05715)
			(type default)
		)
		(layer "In9.Cu")
	)
	(gr_line
		(start 31.996126 -44.438062)
		(end 32.01289 -44.418504)
		(stroke
			(width 0.05715)
			(type default)
		)
		(layer "In9.Cu")
	)
	(gr_line
		(start 32.01289 -44.418504)
		(end 32.036004 -44.407582)
		(stroke
			(width 0.05715)
			(type default)
		)
		(layer "In9.Cu")
	)
	(gr_line
		(start 32.08401 -29.377894)
		(end 32.634936 -29.605986)
		(stroke
			(width 0.05715)
			(type default)
		)
		(layer "In9.Cu")
	)
	(gr_line
		(start 32.163512 -29.09189)
		(end 32.375856 -29.003752)
		(stroke
			(width 0.05715)
			(type default)
		)
		(layer "In9.Cu")
	)
	(gr_line
		(start 32.179006 -30.139132)
		(end 32.495744 -30.27045)
		(stroke
			(width 0.05715)
			(type default)
		)
		(layer "In9.Cu")
	)
	(gr_line
		(start 32.375856 -29.003752)
		(end 32.692594 -29.134816)
		(stroke
			(width 0.05715)
			(type default)
		)
		(layer "In9.Cu")
	)
	(gr_line
		(start 32.471614 -26.322274)
		(end 32.490664 -26.326084)
		(stroke
			(width 0.05715)
			(type default)
		)
		(layer "In9.Cu")
	)
	(gr_line
		(start 32.490664 -26.326084)
		(end 32.506666 -26.336752)
		(stroke
			(width 0.05715)
			(type default)
		)
		(layer "In9.Cu")
	)
	(gr_line
		(start 32.495744 -30.27045)
		(end 32.583882 -30.483048)
		(stroke
			(width 0.05715)
			(type default)
		)
		(layer "In9.Cu")
	)
	(gr_line
		(start 32.692594 -29.134816)
		(end 32.780732 -29.347414)
		(stroke
			(width 0.05715)
			(type default)
		)
		(layer "In9.Cu")
	)
	(gr_line
		(start 32.738822 -34.10077)
		(end 32.790638 -34.090356)
		(stroke
			(width 0.05715)
			(type default)
		)
		(layer "In9.Cu")
	)
	(gr_line
		(start 32.756094 -36.279836)
		(end 32.857694 -36.486084)
		(stroke
			(width 0.05715)
			(type default)
		)
		(layer "In9.Cu")
	)
	(gr_line
		(start 32.790638 -34.090356)
		(end 32.839152 -34.110422)
		(stroke
			(width 0.05715)
			(type default)
		)
		(layer "In9.Cu")
	)
	(gr_line
		(start 32.857694 -36.486084)
		(end 33.182306 -36.596066)
		(stroke
			(width 0.05715)
			(type default)
		)
		(layer "In9.Cu")
	)
	(gr_line
		(start 32.885634 -36.012628)
		(end 33.448752 -36.203636)
		(stroke
			(width 0.05715)
			(type default)
		)
		(layer "In9.Cu")
	)
	(gr_line
		(start 32.930338 -25.76322)
		(end 32.949388 -25.76703)
		(stroke
			(width 0.05715)
			(type default)
		)
		(layer "In9.Cu")
	)
	(gr_line
		(start 32.949388 -25.76703)
		(end 32.965644 -25.777698)
		(stroke
			(width 0.05715)
			(type default)
		)
		(layer "In9.Cu")
	)
	(gr_line
		(start 33.020508 -29.765752)
		(end 33.573212 -29.99486)
		(stroke
			(width 0.05715)
			(type default)
		)
		(layer "In9.Cu")
	)
	(gr_line
		(start 33.101788 -29.48051)
		(end 33.314386 -29.392626)
		(stroke
			(width 0.05715)
			(type default)
		)
		(layer "In9.Cu")
	)
	(gr_line
		(start 33.182306 -36.596066)
		(end 33.388554 -36.494212)
		(stroke
			(width 0.05715)
			(type default)
		)
		(layer "In9.Cu")
	)
	(gr_line
		(start 33.314386 -29.392626)
		(end 33.631378 -29.52369)
		(stroke
			(width 0.05715)
			(type default)
		)
		(layer "In9.Cu")
	)
	(gr_line
		(start 33.631378 -29.52369)
		(end 33.719262 -29.736288)
		(stroke
			(width 0.05715)
			(type default)
		)
		(layer "In9.Cu")
	)
	(gr_line
		(start 33.717992 -36.605972)
		(end 33.819846 -36.811966)
		(stroke
			(width 0.05715)
			(type default)
		)
		(layer "In9.Cu")
	)
	(gr_line
		(start 33.819846 -36.811966)
		(end 34.144458 -36.922202)
		(stroke
			(width 0.05715)
			(type default)
		)
		(layer "In9.Cu")
	)
	(gr_line
		(start 33.843214 -41.342564)
		(end 33.870392 -41.329102)
		(stroke
			(width 0.05715)
			(type default)
		)
		(layer "In9.Cu")
	)
	(gr_line
		(start 33.84804 -36.339018)
		(end 34.41065 -36.529772)
		(stroke
			(width 0.05715)
			(type default)
		)
		(layer "In9.Cu")
	)
	(gr_line
		(start 33.959292 -30.154626)
		(end 34.513266 -30.384242)
		(stroke
			(width 0.05715)
			(type default)
		)
		(layer "In9.Cu")
	)
	(gr_line
		(start 34.007806 -41.97858)
		(end 34.036254 -41.964102)
		(stroke
			(width 0.05715)
			(type default)
		)
		(layer "In9.Cu")
	)
	(gr_line
		(start 34.040572 -29.869384)
		(end 34.25317 -29.781246)
		(stroke
			(width 0.05715)
			(type default)
		)
		(layer "In9.Cu")
	)
	(gr_line
		(start 34.144458 -36.922202)
		(end 34.35096 -36.820348)
		(stroke
			(width 0.05715)
			(type default)
		)
		(layer "In9.Cu")
	)
	(gr_line
		(start 34.224468 -40.1193)
		(end 34.228278 -40.12057)
		(stroke
			(width 0.05715)
			(type default)
		)
		(layer "In9.Cu")
	)
	(gr_line
		(start 34.25317 -29.781246)
		(end 34.569908 -29.912564)
		(stroke
			(width 0.05715)
			(type default)
		)
		(layer "In9.Cu")
	)
	(gr_line
		(start 34.319464 -39.4843)
		(end 34.323274 -39.48557)
		(stroke
			(width 0.05715)
			(type default)
		)
		(layer "In9.Cu")
	)
	(gr_line
		(start 34.338006 -42.624248)
		(end 34.36239 -42.612818)
		(stroke
			(width 0.05715)
			(type default)
		)
		(layer "In9.Cu")
	)
	(gr_line
		(start 34.39033 -43.30192)
		(end 34.414714 -43.29049)
		(stroke
			(width 0.05715)
			(type default)
		)
		(layer "In9.Cu")
	)
	(gr_line
		(start 34.569908 -29.912564)
		(end 34.658046 -30.125162)
		(stroke
			(width 0.05715)
			(type default)
		)
		(layer "In9.Cu")
	)
	(gr_line
		(start 34.613596 -31.642558)
		(end 35.16503 -31.870904)
		(stroke
			(width 0.05715)
			(type default)
		)
		(layer "In9.Cu")
	)
	(gr_line
		(start 34.636964 -38.1)
		(end 34.640012 -38.101016)
		(stroke
			(width 0.05715)
			(type default)
		)
		(layer "In9.Cu")
	)
	(gr_line
		(start 34.693606 -31.356808)
		(end 34.906204 -31.26867)
		(stroke
			(width 0.05715)
			(type default)
		)
		(layer "In9.Cu")
	)
	(gr_line
		(start 34.810954 -38.8239)
		(end 34.815526 -38.825424)
		(stroke
			(width 0.05715)
			(type default)
		)
		(layer "In9.Cu")
	)
	(gr_line
		(start 34.87928 -32.599884)
		(end 34.967418 -32.812482)
		(stroke
			(width 0.05715)
			(type default)
		)
		(layer "In9.Cu")
	)
	(gr_line
		(start 34.906204 -31.26867)
		(end 35.222942 -31.399988)
		(stroke
			(width 0.05715)
			(type default)
		)
		(layer "In9.Cu")
	)
	(gr_line
		(start 34.967418 -32.812482)
		(end 35.284156 -32.943546)
		(stroke
			(width 0.05715)
			(type default)
		)
		(layer "In9.Cu")
	)
	(gr_line
		(start 35.0266 -32.342074)
		(end 35.575748 -32.569404)
		(stroke
			(width 0.05715)
			(type default)
		)
		(layer "In9.Cu")
	)
	(gr_line
		(start 35.222942 -31.399988)
		(end 35.31108 -31.612586)
		(stroke
			(width 0.05715)
			(type default)
		)
		(layer "In9.Cu")
	)
	(gr_line
		(start 35.284156 -32.943546)
		(end 35.496754 -32.855408)
		(stroke
			(width 0.05715)
			(type default)
		)
		(layer "In9.Cu")
	)
	(gr_line
		(start 35.554158 -32.03194)
		(end 36.10229 -32.259016)
		(stroke
			(width 0.05715)
			(type default)
		)
		(layer "In9.Cu")
	)
	(gr_line
		(start 35.63239 -31.745682)
		(end 35.844734 -31.657544)
		(stroke
			(width 0.05715)
			(type default)
		)
		(layer "In9.Cu")
	)
	(gr_line
		(start 35.712654 -35.619944)
		(end 35.800792 -35.832542)
		(stroke
			(width 0.05715)
			(type default)
		)
		(layer "In9.Cu")
	)
	(gr_line
		(start 35.745928 -34.432748)
		(end 35.834066 -34.645346)
		(stroke
			(width 0.05715)
			(type default)
		)
		(layer "In9.Cu")
	)
	(gr_line
		(start 35.800792 -35.832542)
		(end 36.11753 -35.96386)
		(stroke
			(width 0.05715)
			(type default)
		)
		(layer "In9.Cu")
	)
	(gr_line
		(start 35.818064 -32.988504)
		(end 35.906202 -33.201102)
		(stroke
			(width 0.05715)
			(type default)
		)
		(layer "In9.Cu")
	)
	(gr_line
		(start 35.825684 -43.29049)
		(end 35.82924 -43.291506)
		(stroke
			(width 0.05715)
			(type default)
		)
		(layer "In9.Cu")
	)
	(gr_line
		(start 35.834066 -34.645346)
		(end 36.150804 -34.776664)
		(stroke
			(width 0.05715)
			(type default)
		)
		(layer "In9.Cu")
	)
	(gr_line
		(start 35.844734 -31.657544)
		(end 36.161726 -31.788608)
		(stroke
			(width 0.05715)
			(type default)
		)
		(layer "In9.Cu")
	)
	(gr_line
		(start 35.855148 -35.359594)
		(end 36.412932 -35.590734)
		(stroke
			(width 0.05715)
			(type default)
		)
		(layer "In9.Cu")
	)
	(gr_line
		(start 35.886644 -42.612818)
		(end 35.890454 -42.614088)
		(stroke
			(width 0.05715)
			(type default)
		)
		(layer "In9.Cu")
	)
	(gr_line
		(start 35.889946 -34.173414)
		(end 36.44392 -34.402776)
		(stroke
			(width 0.05715)
			(type default)
		)
		(layer "In9.Cu")
	)
	(gr_line
		(start 35.906202 -33.201102)
		(end 36.22294 -33.332166)
		(stroke
			(width 0.05715)
			(type default)
		)
		(layer "In9.Cu")
	)
	(gr_line
		(start 35.936428 -41.964102)
		(end 35.940238 -41.965372)
		(stroke
			(width 0.05715)
			(type default)
		)
		(layer "In9.Cu")
	)
	(gr_line
		(start 35.963098 -32.729678)
		(end 36.514532 -32.958024)
		(stroke
			(width 0.05715)
			(type default)
		)
		(layer "In9.Cu")
	)
	(gr_line
		(start 36.030662 -41.329102)
		(end 36.034472 -41.330372)
		(stroke
			(width 0.05715)
			(type default)
		)
		(layer "In9.Cu")
	)
	(gr_line
		(start 36.11753 -35.96386)
		(end 36.330382 -35.875722)
		(stroke
			(width 0.05715)
			(type default)
		)
		(layer "In9.Cu")
	)
	(gr_line
		(start 36.150804 -34.776664)
		(end 36.363402 -34.688526)
		(stroke
			(width 0.05715)
			(type default)
		)
		(layer "In9.Cu")
	)
	(gr_line
		(start 36.161726 -31.788608)
		(end 36.24961 -32.001206)
		(stroke
			(width 0.05715)
			(type default)
		)
		(layer "In9.Cu")
	)
	(gr_line
		(start 36.22294 -33.332166)
		(end 36.435538 -33.244028)
		(stroke
			(width 0.05715)
			(type default)
		)
		(layer "In9.Cu")
	)
	(gr_line
		(start 36.491926 -32.420306)
		(end 37.042598 -32.648398)
		(stroke
			(width 0.05715)
			(type default)
		)
		(layer "In9.Cu")
	)
	(gr_line
		(start 36.57092 -32.134302)
		(end 36.783518 -32.046164)
		(stroke
			(width 0.05715)
			(type default)
		)
		(layer "In9.Cu")
	)
	(gr_line
		(start 36.651438 -36.008818)
		(end 36.739322 -36.221416)
		(stroke
			(width 0.05715)
			(type default)
		)
		(layer "In9.Cu")
	)
	(gr_line
		(start 36.684712 -34.821622)
		(end 36.772596 -35.03422)
		(stroke
			(width 0.05715)
			(type default)
		)
		(layer "In9.Cu")
	)
	(gr_line
		(start 36.739322 -36.221416)
		(end 37.056314 -36.352734)
		(stroke
			(width 0.05715)
			(type default)
		)
		(layer "In9.Cu")
	)
	(gr_line
		(start 36.756594 -33.37687)
		(end 36.844732 -33.589722)
		(stroke
			(width 0.05715)
			(type default)
		)
		(layer "In9.Cu")
	)
	(gr_line
		(start 36.772596 -35.03422)
		(end 37.089588 -35.165538)
		(stroke
			(width 0.05715)
			(type default)
		)
		(layer "In9.Cu")
	)
	(gr_line
		(start 36.783518 -32.046164)
		(end 37.100256 -32.177482)
		(stroke
			(width 0.05715)
			(type default)
		)
		(layer "In9.Cu")
	)
	(gr_line
		(start 36.793678 -35.748468)
		(end 37.35197 -35.979608)
		(stroke
			(width 0.05715)
			(type default)
		)
		(layer "In9.Cu")
	)
	(gr_line
		(start 36.830254 -34.56305)
		(end 37.382196 -34.79165)
		(stroke
			(width 0.05715)
			(type default)
		)
		(layer "In9.Cu")
	)
	(gr_line
		(start 36.844732 -33.589722)
		(end 37.161724 -33.720786)
		(stroke
			(width 0.05715)
			(type default)
		)
		(layer "In9.Cu")
	)
	(gr_line
		(start 36.902136 -33.118552)
		(end 37.455602 -33.34766)
		(stroke
			(width 0.05715)
			(type default)
		)
		(layer "In9.Cu")
	)
	(gr_line
		(start 37.056314 -36.352734)
		(end 37.268912 -36.264596)
		(stroke
			(width 0.05715)
			(type default)
		)
		(layer "In9.Cu")
	)
	(gr_line
		(start 37.089588 -35.165538)
		(end 37.302186 -35.0774)
		(stroke
			(width 0.05715)
			(type default)
		)
		(layer "In9.Cu")
	)
	(gr_line
		(start 37.100256 -32.177482)
		(end 37.188394 -32.39008)
		(stroke
			(width 0.05715)
			(type default)
		)
		(layer "In9.Cu")
	)
	(gr_line
		(start 37.161724 -33.720786)
		(end 37.374576 -33.632902)
		(stroke
			(width 0.05715)
			(type default)
		)
		(layer "In9.Cu")
	)
	(gr_line
		(start 37.429694 -32.808926)
		(end 37.981636 -33.037526)
		(stroke
			(width 0.05715)
			(type default)
		)
		(layer "In9.Cu")
	)
	(gr_line
		(start 37.486082 -37.88283)
		(end 37.587936 -38.089078)
		(stroke
			(width 0.05715)
			(type default)
		)
		(layer "In9.Cu")
	)
	(gr_line
		(start 37.50945 -32.523176)
		(end 37.722302 -32.435038)
		(stroke
			(width 0.05715)
			(type default)
		)
		(layer "In9.Cu")
	)
	(gr_line
		(start 37.587936 -38.089078)
		(end 37.912548 -38.19906)
		(stroke
			(width 0.05715)
			(type default)
		)
		(layer "In9.Cu")
	)
	(gr_line
		(start 37.589968 -36.397692)
		(end 37.678106 -36.61029)
		(stroke
			(width 0.05715)
			(type default)
		)
		(layer "In9.Cu")
	)
	(gr_line
		(start 37.61613 -37.61613)
		(end 38.178486 -37.80663)
		(stroke
			(width 0.05715)
			(type default)
		)
		(layer "In9.Cu")
	)
	(gr_line
		(start 37.623242 -35.210496)
		(end 37.71138 -35.423094)
		(stroke
			(width 0.05715)
			(type default)
		)
		(layer "In9.Cu")
	)
	(gr_line
		(start 37.678106 -36.61029)
		(end 37.994844 -36.741608)
		(stroke
			(width 0.05715)
			(type default)
		)
		(layer "In9.Cu")
	)
	(gr_line
		(start 37.695378 -33.765744)
		(end 37.783516 -33.978342)
		(stroke
			(width 0.05715)
			(type default)
		)
		(layer "In9.Cu")
	)
	(gr_line
		(start 37.71138 -35.423094)
		(end 38.028118 -35.554412)
		(stroke
			(width 0.05715)
			(type default)
		)
		(layer "In9.Cu")
	)
	(gr_line
		(start 37.722302 -32.435038)
		(end 38.03904 -32.566356)
		(stroke
			(width 0.05715)
			(type default)
		)
		(layer "In9.Cu")
	)
	(gr_line
		(start 37.732462 -36.137342)
		(end 38.290246 -36.368482)
		(stroke
			(width 0.05715)
			(type default)
		)
		(layer "In9.Cu")
	)
	(gr_line
		(start 37.76853 -34.951924)
		(end 38.321488 -35.180778)
		(stroke
			(width 0.05715)
			(type default)
		)
		(layer "In9.Cu")
	)
	(gr_line
		(start 37.783516 -33.978342)
		(end 38.100254 -34.10966)
		(stroke
			(width 0.05715)
			(type default)
		)
		(layer "In9.Cu")
	)
	(gr_line
		(start 37.839904 -33.506664)
		(end 38.393878 -33.736026)
		(stroke
			(width 0.05715)
			(type default)
		)
		(layer "In9.Cu")
	)
	(gr_line
		(start 37.912548 -38.19906)
		(end 38.118542 -38.097206)
		(stroke
			(width 0.05715)
			(type default)
		)
		(layer "In9.Cu")
	)
	(gr_line
		(start 37.994844 -36.741608)
		(end 38.207442 -36.65347)
		(stroke
			(width 0.05715)
			(type default)
		)
		(layer "In9.Cu")
	)
	(gr_line
		(start 38.028118 -35.554412)
		(end 38.240716 -35.466274)
		(stroke
			(width 0.05715)
			(type default)
		)
		(layer "In9.Cu")
	)
	(gr_line
		(start 38.03904 -32.566356)
		(end 38.127178 -32.778954)
		(stroke
			(width 0.05715)
			(type default)
		)
		(layer "In9.Cu")
	)
	(gr_line
		(start 38.100254 -34.10966)
		(end 38.31336 -34.021522)
		(stroke
			(width 0.05715)
			(type default)
		)
		(layer "In9.Cu")
	)
	(gr_line
		(start 38.448234 -38.208966)
		(end 38.550088 -38.415214)
		(stroke
			(width 0.05715)
			(type default)
		)
		(layer "In9.Cu")
	)
	(gr_line
		(start 38.528752 -36.786566)
		(end 38.616636 -36.999164)
		(stroke
			(width 0.05715)
			(type default)
		)
		(layer "In9.Cu")
	)
	(gr_line
		(start 38.550088 -38.415214)
		(end 38.8747 -38.525196)
		(stroke
			(width 0.05715)
			(type default)
		)
		(layer "In9.Cu")
	)
	(gr_line
		(start 38.550088 -31.73984)
		(end 38.55593 -31.74238)
		(stroke
			(width 0.05715)
			(type default)
		)
		(layer "In9.Cu")
	)
	(gr_line
		(start 38.55593 -31.74238)
		(end 38.56101 -31.746444)
		(stroke
			(width 0.05715)
			(type default)
		)
		(layer "In9.Cu")
	)
	(gr_line
		(start 38.578282 -37.942012)
		(end 39.140384 -38.132512)
		(stroke
			(width 0.05715)
			(type default)
		)
		(layer "In9.Cu")
	)
	(gr_line
		(start 38.616636 -36.999164)
		(end 38.933628 -37.130482)
		(stroke
			(width 0.05715)
			(type default)
		)
		(layer "In9.Cu")
	)
	(gr_line
		(start 38.672516 -36.526978)
		(end 39.227252 -36.756848)
		(stroke
			(width 0.05715)
			(type default)
		)
		(layer "In9.Cu")
	)
	(gr_line
		(start 38.790626 -33.90011)
		(end 38.810692 -33.908492)
		(stroke
			(width 0.05715)
			(type default)
		)
		(layer "In9.Cu")
	)
	(gr_line
		(start 38.810692 -33.908492)
		(end 38.826186 -33.923986)
		(stroke
			(width 0.05715)
			(type default)
		)
		(layer "In9.Cu")
	)
	(gr_line
		(start 38.8747 -38.525196)
		(end 39.080948 -38.423342)
		(stroke
			(width 0.05715)
			(type default)
		)
		(layer "In9.Cu")
	)
	(gr_line
		(start 38.933628 -37.130482)
		(end 39.146226 -37.042344)
		(stroke
			(width 0.05715)
			(type default)
		)
		(layer "In9.Cu")
	)
	(gr_line
		(start 39.14013 -35.519868)
		(end 39.160196 -35.52825)
		(stroke
			(width 0.05715)
			(type default)
		)
		(layer "In9.Cu")
	)
	(gr_line
		(start 39.160196 -35.52825)
		(end 39.17569 -35.543744)
		(stroke
			(width 0.05715)
			(type default)
		)
		(layer "In9.Cu")
	)
	(gr_line
		(start 39.338758 -32.762444)
		(end 39.802562 -33.142682)
		(stroke
			(width 0.05715)
			(type default)
		)
		(layer "In9.Cu")
	)
	(gr_line
		(start 39.410386 -38.535102)
		(end 39.51224 -38.74135)
		(stroke
			(width 0.05715)
			(type default)
		)
		(layer "In9.Cu")
	)
	(gr_line
		(start 39.431214 -33.321498)
		(end 39.45128 -33.32988)
		(stroke
			(width 0.05715)
			(type default)
		)
		(layer "In9.Cu")
	)
	(gr_line
		(start 39.45128 -33.32988)
		(end 39.466774 -33.345374)
		(stroke
			(width 0.05715)
			(type default)
		)
		(layer "In9.Cu")
	)
	(gr_line
		(start 39.499032 -32.512762)
		(end 39.72814 -32.489902)
		(stroke
			(width 0.05715)
			(type default)
		)
		(layer "In9.Cu")
	)
	(gr_line
		(start 39.51224 -38.74135)
		(end 39.837106 -38.851332)
		(stroke
			(width 0.05715)
			(type default)
		)
		(layer "In9.Cu")
	)
	(gr_line
		(start 39.512748 -44.3738)
		(end 39.519606 -44.375578)
		(stroke
			(width 0.05715)
			(type default)
		)
		(layer "In9.Cu")
	)
	(gr_line
		(start 39.519606 -44.375578)
		(end 39.51986 -44.375832)
		(stroke
			(width 0.05715)
			(type default)
		)
		(layer "In9.Cu")
	)
	(gr_line
		(start 39.51986 -44.375832)
		(end 39.525194 -44.379642)
		(stroke
			(width 0.05715)
			(type default)
		)
		(layer "In9.Cu")
	)
	(gr_line
		(start 39.540434 -38.268148)
		(end 40.103552 -38.458902)
		(stroke
			(width 0.05715)
			(type default)
		)
		(layer "In9.Cu")
	)
	(gr_line
		(start 39.72814 -32.489902)
		(end 39.993316 -32.707326)
		(stroke
			(width 0.05715)
			(type default)
		)
		(layer "In9.Cu")
	)
	(gr_line
		(start 39.837106 -38.851332)
		(end 40.043354 -38.749478)
		(stroke
			(width 0.05715)
			(type default)
		)
		(layer "In9.Cu")
	)
	(gr_line
		(start 39.973504 -43.849036)
		(end 39.978838 -43.85056)
		(stroke
			(width 0.05715)
			(type default)
		)
		(layer "In9.Cu")
	)
	(gr_line
		(start 39.978838 -43.85056)
		(end 39.984172 -43.854116)
		(stroke
			(width 0.05715)
			(type default)
		)
		(layer "In9.Cu")
	)
	(gr_line
		(start 39.993316 -32.707326)
		(end 40.015922 -32.936434)
		(stroke
			(width 0.05715)
			(type default)
		)
		(layer "In9.Cu")
	)
	(gr_line
		(start 40.12438 -33.406588)
		(end 40.588184 -33.786826)
		(stroke
			(width 0.05715)
			(type default)
		)
		(layer "In9.Cu")
	)
	(gr_line
		(start 40.271446 -43.27525)
		(end 40.27678 -43.276774)
		(stroke
			(width 0.05715)
			(type default)
		)
		(layer "In9.Cu")
	)
	(gr_line
		(start 40.27678 -43.276774)
		(end 40.282114 -43.28033)
		(stroke
			(width 0.05715)
			(type default)
		)
		(layer "In9.Cu")
	)
	(gr_line
		(start 40.284654 -33.156906)
		(end 40.513762 -33.1343)
		(stroke
			(width 0.05715)
			(type default)
		)
		(layer "In9.Cu")
	)
	(gr_line
		(start 40.372792 -38.861238)
		(end 40.474646 -39.067232)
		(stroke
			(width 0.05715)
			(type default)
		)
		(layer "In9.Cu")
	)
	(gr_line
		(start 40.474646 -39.067232)
		(end 40.799258 -39.177468)
		(stroke
			(width 0.05715)
			(type default)
		)
		(layer "In9.Cu")
	)
	(gr_line
		(start 40.502332 -38.59403)
		(end 41.066974 -38.785292)
		(stroke
			(width 0.05715)
			(type default)
		)
		(layer "In9.Cu")
	)
	(gr_line
		(start 40.513762 -33.1343)
		(end 40.778938 -33.351724)
		(stroke
			(width 0.05715)
			(type default)
		)
		(layer "In9.Cu")
	)
	(gr_line
		(start 40.73779 -42.752518)
		(end 40.742616 -42.753788)
		(stroke
			(width 0.05715)
			(type default)
		)
		(layer "In9.Cu")
	)
	(gr_line
		(start 40.742616 -42.753788)
		(end 40.747442 -42.756836)
		(stroke
			(width 0.05715)
			(type default)
		)
		(layer "In9.Cu")
	)
	(gr_line
		(start 40.778938 -33.351724)
		(end 40.801544 -33.580578)
		(stroke
			(width 0.05715)
			(type default)
		)
		(layer "In9.Cu")
	)
	(gr_line
		(start 40.799258 -39.177468)
		(end 41.005506 -39.075614)
		(stroke
			(width 0.05715)
			(type default)
		)
		(layer "In9.Cu")
	)
	(gr_line
		(start 40.910764 -34.05124)
		(end 41.373806 -34.43097)
		(stroke
			(width 0.05715)
			(type default)
		)
		(layer "In9.Cu")
	)
	(gr_line
		(start 41.070276 -33.80105)
		(end 41.299384 -33.778444)
		(stroke
			(width 0.05715)
			(type default)
		)
		(layer "In9.Cu")
	)
	(gr_line
		(start 41.077134 -42.191178)
		(end 41.08196 -42.192448)
		(stroke
			(width 0.05715)
			(type default)
		)
		(layer "In9.Cu")
	)
	(gr_line
		(start 41.08196 -42.192448)
		(end 41.086786 -42.195496)
		(stroke
			(width 0.05715)
			(type default)
		)
		(layer "In9.Cu")
	)
	(gr_line
		(start 41.299384 -33.778444)
		(end 41.56456 -33.995868)
		(stroke
			(width 0.05715)
			(type default)
		)
		(layer "In9.Cu")
	)
	(gr_line
		(start 41.463468 -38.919658)
		(end 41.463722 -38.919658)
		(stroke
			(width 0.05715)
			(type default)
		)
		(layer "In9.Cu")
	)
	(gr_line
		(start 41.532048 -41.66489)
		(end 41.536874 -41.66616)
		(stroke
			(width 0.05715)
			(type default)
		)
		(layer "In9.Cu")
	)
	(gr_line
		(start 41.536874 -41.66616)
		(end 41.5417 -41.669208)
		(stroke
			(width 0.05715)
			(type default)
		)
		(layer "In9.Cu")
	)
	(gr_line
		(start 41.56456 -33.995868)
		(end 41.58742 -34.224976)
		(stroke
			(width 0.05715)
			(type default)
		)
		(layer "In9.Cu")
	)
	(gr_line
		(start 41.717976 -40.96004)
		(end 41.72331 -40.961818)
		(stroke
			(width 0.05715)
			(type default)
		)
		(layer "In9.Cu")
	)
	(gr_line
		(start 41.72331 -40.961818)
		(end 41.727882 -40.964866)
		(stroke
			(width 0.05715)
			(type default)
		)
		(layer "In9.Cu")
	)
	(gr_line
		(start 42.266362 -40.4495)
		(end 42.266616 -40.4495)
		(stroke
			(width 0.05715)
			(type default)
		)
		(layer "In9.Cu")
	)
	(gr_line
		(start 44.39793 -34.27222)
		(end 44.416218 -34.284412)
		(stroke
			(width 0.05715)
			(type default)
		)
		(layer "In9.Cu")
	)
	(gr_line
		(start 44.416218 -34.284412)
		(end 44.42841 -34.3027)
		(stroke
			(width 0.05715)
			(type default)
		)
		(layer "In9.Cu")
	)
	(gr_line
		(start 44.838874 -33.695132)
		(end 44.857162 -33.707324)
		(stroke
			(width 0.05715)
			(type default)
		)
		(layer "In9.Cu")
	)
	(gr_line
		(start 44.857162 -33.707324)
		(end 44.869354 -33.725612)
		(stroke
			(width 0.05715)
			(type default)
		)
		(layer "In9.Cu")
	)
	(gr_line
		(start 45.780452 -36.857686)
		(end 45.792644 -36.875974)
		(stroke
			(width 0.05715)
			(type default)
		)
		(layer "In9.Cu")
	)
	(gr_line
		(start 45.792644 -36.875974)
		(end 45.810932 -36.888166)
		(stroke
			(width 0.05715)
			(type default)
		)
		(layer "In9.Cu")
	)
	(gr_line
		(start 46.330616 -36.444428)
		(end 46.343824 -36.46424)
		(stroke
			(width 0.05715)
			(type default)
		)
		(layer "In9.Cu")
	)
	(gr_line
		(start 46.343824 -36.46424)
		(end 46.36389 -36.477448)
		(stroke
			(width 0.05715)
			(type default)
		)
		(layer "In9.Cu")
	)
	(gr_line
		(start 50.243994 -51.52517)
		(end 50.262282 -51.537362)
		(stroke
			(width 0.05715)
			(type default)
		)
		(layer "In9.Cu")
	)
	(gr_line
		(start 50.262282 -51.537362)
		(end 50.274474 -51.55565)
		(stroke
			(width 0.05715)
			(type default)
		)
		(layer "In9.Cu")
	)
	(gr_line
		(start 50.729896 -51.017424)
		(end 50.748184 -51.029616)
		(stroke
			(width 0.05715)
			(type default)
		)
		(layer "In9.Cu")
	)
	(gr_line
		(start 50.748184 -51.029616)
		(end 50.760376 -51.047904)
		(stroke
			(width 0.05715)
			(type default)
		)
		(layer "In9.Cu")
	)
	(gr_line
		(start 51.293268 -79.194152)
		(end 51.297332 -79.214218)
		(stroke
			(width 0.05715)
			(type default)
		)
		(layer "In9.Cu")
	)
	(gr_line
		(start 51.293268 -79.194152)
		(end 51.297332 -79.174594)
		(stroke
			(width 0.05715)
			(type default)
		)
		(layer "In9.Cu")
	)
	(gr_line
		(start 51.348132 -50.658268)
		(end 51.364388 -50.668936)
		(stroke
			(width 0.05715)
			(type default)
		)
		(layer "In9.Cu")
	)
	(gr_line
		(start 51.364388 -50.668936)
		(end 51.375818 -50.685954)
		(stroke
			(width 0.05715)
			(type default)
		)
		(layer "In9.Cu")
	)
	(gr_line
		(start 51.874928 -50.174398)
		(end 51.893216 -50.18659)
		(stroke
			(width 0.05715)
			(type default)
		)
		(layer "In9.Cu")
	)
	(gr_line
		(start 51.893216 -50.18659)
		(end 51.905408 -50.204878)
		(stroke
			(width 0.05715)
			(type default)
		)
		(layer "In9.Cu")
	)
	(gr_line
		(start 52.033932 -79.204058)
		(end 52.037742 -79.185008)
		(stroke
			(width 0.05715)
			(type default)
		)
		(layer "In9.Cu")
	)
	(gr_line
		(start 52.033932 -79.204058)
		(end 52.037996 -79.223616)
		(stroke
			(width 0.05715)
			(type default)
		)
		(layer "In9.Cu")
	)
	(gr_line
		(start 52.275486 -80.412082)
		(end 52.291996 -80.494378)
		(stroke
			(width 0.05715)
			(type default)
		)
		(layer "In9.Cu")
	)
	(gr_line
		(start 52.291996 -80.494378)
		(end 52.361846 -80.54086)
		(stroke
			(width 0.05715)
			(type default)
		)
		(layer "In9.Cu")
	)
	(gr_line
		(start 52.437792 -49.951894)
		(end 58.083196 -58.420254)
		(stroke
			(width 0.1778)
			(type default)
		)
		(layer "In9.Cu")
	)
	(gr_line
		(start 52.501038 -81.539588)
		(end 52.517548 -81.622392)
		(stroke
			(width 0.05715)
			(type default)
		)
		(layer "In9.Cu")
	)
	(gr_line
		(start 52.501038 -81.539588)
		(end 52.547774 -81.469484)
		(stroke
			(width 0.05715)
			(type default)
		)
		(layer "In9.Cu")
	)
	(gr_line
		(start 52.508658 -49.809908)
		(end 52.526946 -49.8221)
		(stroke
			(width 0.05715)
			(type default)
		)
		(layer "In9.Cu")
	)
	(gr_line
		(start 52.526946 -49.8221)
		(end 52.539138 -49.840388)
		(stroke
			(width 0.05715)
			(type default)
		)
		(layer "In9.Cu")
	)
	(gr_line
		(start 52.558188 -80.672178)
		(end 52.62753 -80.718406)
		(stroke
			(width 0.05715)
			(type default)
		)
		(layer "In9.Cu")
	)
	(gr_line
		(start 52.584604 -81.957418)
		(end 52.601114 -82.039714)
		(stroke
			(width 0.05715)
			(type default)
		)
		(layer "In9.Cu")
	)
	(gr_line
		(start 52.601114 -82.039714)
		(end 52.670964 -82.086196)
		(stroke
			(width 0.05715)
			(type default)
		)
		(layer "In9.Cu")
	)
	(gr_line
		(start 52.62753 -80.718406)
		(end 52.709572 -80.701896)
		(stroke
			(width 0.05715)
			(type default)
		)
		(layer "In9.Cu")
	)
	(gr_line
		(start 52.67833 -81.274158)
		(end 52.724812 -81.204308)
		(stroke
			(width 0.05715)
			(type default)
		)
		(layer "In9.Cu")
	)
	(gr_line
		(start 52.724812 -81.204308)
		(end 52.807108 -81.187798)
		(stroke
			(width 0.05715)
			(type default)
		)
		(layer "In9.Cu")
	)
	(gr_line
		(start 52.810156 -83.084924)
		(end 52.826666 -83.167474)
		(stroke
			(width 0.05715)
			(type default)
		)
		(layer "In9.Cu")
	)
	(gr_line
		(start 52.810156 -83.084924)
		(end 52.856892 -83.01482)
		(stroke
			(width 0.05715)
			(type default)
		)
		(layer "In9.Cu")
	)
	(gr_line
		(start 52.86121 -80.373474)
		(end 52.94376 -80.356964)
		(stroke
			(width 0.05715)
			(type default)
		)
		(layer "In9.Cu")
	)
	(gr_line
		(start 52.867306 -82.217514)
		(end 52.936648 -82.263742)
		(stroke
			(width 0.05715)
			(type default)
		)
		(layer "In9.Cu")
	)
	(gr_line
		(start 52.936648 -82.263742)
		(end 53.01869 -82.247232)
		(stroke
			(width 0.05715)
			(type default)
		)
		(layer "In9.Cu")
	)
	(gr_line
		(start 52.94376 -80.356964)
		(end 53.01361 -80.403446)
		(stroke
			(width 0.05715)
			(type default)
		)
		(layer "In9.Cu")
	)
	(gr_line
		(start 52.987448 -82.819494)
		(end 53.03393 -82.749644)
		(stroke
			(width 0.05715)
			(type default)
		)
		(layer "In9.Cu")
	)
	(gr_line
		(start 53.03393 -82.749644)
		(end 53.116226 -82.733134)
		(stroke
			(width 0.05715)
			(type default)
		)
		(layer "In9.Cu")
	)
	(gr_line
		(start 53.036978 -77.596238)
		(end 53.040788 -77.577188)
		(stroke
			(width 0.05715)
			(type default)
		)
		(layer "In9.Cu")
	)
	(gr_line
		(start 53.036978 -77.596238)
		(end 53.041042 -77.616304)
		(stroke
			(width 0.05715)
			(type default)
		)
		(layer "In9.Cu")
	)
	(gr_line
		(start 53.0733 -81.432654)
		(end 53.155596 -81.416144)
		(stroke
			(width 0.05715)
			(type default)
		)
		(layer "In9.Cu")
	)
	(gr_line
		(start 53.155596 -81.416144)
		(end 53.202078 -81.346294)
		(stroke
			(width 0.05715)
			(type default)
		)
		(layer "In9.Cu")
	)
	(gr_line
		(start 53.170328 -81.91881)
		(end 53.252878 -81.9023)
		(stroke
			(width 0.05715)
			(type default)
		)
		(layer "In9.Cu")
	)
	(gr_line
		(start 53.21046 -80.535018)
		(end 53.279294 -80.580992)
		(stroke
			(width 0.05715)
			(type default)
		)
		(layer "In9.Cu")
	)
	(gr_line
		(start 53.212238 -49.449482)
		(end 53.230526 -49.461674)
		(stroke
			(width 0.05715)
			(type default)
		)
		(layer "In9.Cu")
	)
	(gr_line
		(start 53.230526 -49.461674)
		(end 53.242718 -49.479962)
		(stroke
			(width 0.05715)
			(type default)
		)
		(layer "In9.Cu")
	)
	(gr_line
		(start 53.252878 -81.9023)
		(end 53.322728 -81.948782)
		(stroke
			(width 0.05715)
			(type default)
		)
		(layer "In9.Cu")
	)
	(gr_line
		(start 53.279294 -80.580992)
		(end 53.29555 -80.662018)
		(stroke
			(width 0.05715)
			(type default)
		)
		(layer "In9.Cu")
	)
	(gr_line
		(start 53.332634 -81.150968)
		(end 53.379624 -81.080356)
		(stroke
			(width 0.05715)
			(type default)
		)
		(layer "In9.Cu")
	)
	(gr_line
		(start 53.363114 -80.999076)
		(end 53.379624 -81.080356)
		(stroke
			(width 0.05715)
			(type default)
		)
		(layer "In9.Cu")
	)
	(gr_line
		(start 53.382418 -82.97799)
		(end 53.464714 -82.96148)
		(stroke
			(width 0.05715)
			(type default)
		)
		(layer "In9.Cu")
	)
	(gr_line
		(start 53.464714 -82.96148)
		(end 53.511196 -82.89163)
		(stroke
			(width 0.05715)
			(type default)
		)
		(layer "In9.Cu")
	)
	(gr_line
		(start 53.519578 -82.080354)
		(end 53.588412 -82.126328)
		(stroke
			(width 0.05715)
			(type default)
		)
		(layer "In9.Cu")
	)
	(gr_line
		(start 53.588412 -82.126328)
		(end 53.604668 -82.207354)
		(stroke
			(width 0.05715)
			(type default)
		)
		(layer "In9.Cu")
	)
	(gr_line
		(start 53.641752 -82.696304)
		(end 53.688742 -82.625692)
		(stroke
			(width 0.05715)
			(type default)
		)
		(layer "In9.Cu")
	)
	(gr_line
		(start 53.672232 -82.544412)
		(end 53.688742 -82.625692)
		(stroke
			(width 0.05715)
			(type default)
		)
		(layer "In9.Cu")
	)
	(gr_line
		(start 53.727604 -48.964088)
		(end 53.745892 -48.97628)
		(stroke
			(width 0.05715)
			(type default)
		)
		(layer "In9.Cu")
	)
	(gr_line
		(start 53.745892 -48.97628)
		(end 53.758084 -48.994568)
		(stroke
			(width 0.05715)
			(type default)
		)
		(layer "In9.Cu")
	)
	(gr_line
		(start 53.789072 -77.199236)
		(end 53.792882 -77.180186)
		(stroke
			(width 0.05715)
			(type default)
		)
		(layer "In9.Cu")
	)
	(gr_line
		(start 53.789072 -77.199236)
		(end 53.793136 -77.219048)
		(stroke
			(width 0.05715)
			(type default)
		)
		(layer "In9.Cu")
	)
	(gr_line
		(start 54.356254 -48.51019)
		(end 54.374542 -48.522382)
		(stroke
			(width 0.05715)
			(type default)
		)
		(layer "In9.Cu")
	)
	(gr_line
		(start 54.374542 -48.522382)
		(end 54.386734 -48.54067)
		(stroke
			(width 0.05715)
			(type default)
		)
		(layer "In9.Cu")
	)
	(gr_line
		(start 54.687724 -85.845904)
		(end 54.691026 -85.862922)
		(stroke
			(width 0.05715)
			(type default)
		)
		(layer "In9.Cu")
	)
	(gr_line
		(start 54.691026 -85.862922)
		(end 54.70144 -85.879178)
		(stroke
			(width 0.05715)
			(type default)
		)
		(layer "In9.Cu")
	)
	(gr_line
		(start 54.73192 -58.24093)
		(end 54.778656 -58.311034)
		(stroke
			(width 0.05715)
			(type default)
		)
		(layer "In9.Cu")
	)
	(gr_line
		(start 54.762146 -58.393838)
		(end 54.778656 -58.311034)
		(stroke
			(width 0.05715)
			(type default)
		)
		(layer "In9.Cu")
	)
	(gr_line
		(start 54.93512 -47.907194)
		(end 54.953408 -47.919386)
		(stroke
			(width 0.05715)
			(type default)
		)
		(layer "In9.Cu")
	)
	(gr_line
		(start 54.953408 -47.919386)
		(end 54.9656 -47.937674)
		(stroke
			(width 0.05715)
			(type default)
		)
		(layer "In9.Cu")
	)
	(gr_line
		(start 55.489602 -58.141616)
		(end 55.536338 -58.211974)
		(stroke
			(width 0.05715)
			(type default)
		)
		(layer "In9.Cu")
	)
	(gr_line
		(start 55.519828 -58.294778)
		(end 55.536338 -58.211974)
		(stroke
			(width 0.05715)
			(type default)
		)
		(layer "In9.Cu")
	)
	(gr_line
		(start 55.550816 -86.63305)
		(end 55.561738 -86.64956)
		(stroke
			(width 0.05715)
			(type default)
		)
		(layer "In9.Cu")
	)
	(gr_line
		(start 55.561738 -86.64956)
		(end 55.565802 -86.669118)
		(stroke
			(width 0.05715)
			(type default)
		)
		(layer "In9.Cu")
	)
	(gr_line
		(start 55.635144 -90.582496)
		(end 55.635398 -90.58275)
		(stroke
			(width 0.05715)
			(type default)
		)
		(layer "In9.Cu")
	)
	(gr_line
		(start 55.635144 -90.582496)
		(end 55.639462 -90.560906)
		(stroke
			(width 0.05715)
			(type default)
		)
		(layer "In9.Cu")
	)
	(gr_line
		(start 55.635398 -90.58275)
		(end 55.639462 -90.602562)
		(stroke
			(width 0.05715)
			(type default)
		)
		(layer "In9.Cu")
	)
	(gr_line
		(start 55.712106 -47.65802)
		(end 55.730394 -47.670212)
		(stroke
			(width 0.05715)
			(type default)
		)
		(layer "In9.Cu")
	)
	(gr_line
		(start 55.730394 -47.670212)
		(end 55.742586 -47.6885)
		(stroke
			(width 0.05715)
			(type default)
		)
		(layer "In9.Cu")
	)
	(gr_line
		(start 56.02859 -102.974648)
		(end 56.032654 -102.994968)
		(stroke
			(width 0.05715)
			(type default)
		)
		(layer "In9.Cu")
	)
	(gr_line
		(start 56.032654 -102.994968)
		(end 56.044338 -103.012494)
		(stroke
			(width 0.05715)
			(type default)
		)
		(layer "In9.Cu")
	)
	(gr_line
		(start 56.048402 -46.989238)
		(end 56.06669 -47.00143)
		(stroke
			(width 0.05715)
			(type default)
		)
		(layer "In9.Cu")
	)
	(gr_line
		(start 56.06669 -47.00143)
		(end 56.078882 -47.019718)
		(stroke
			(width 0.05715)
			(type default)
		)
		(layer "In9.Cu")
	)
	(gr_line
		(start 56.143398 -89.551002)
		(end 56.147716 -89.529666)
		(stroke
			(width 0.05715)
			(type default)
		)
		(layer "In9.Cu")
	)
	(gr_line
		(start 56.143398 -89.50833)
		(end 56.147716 -89.529666)
		(stroke
			(width 0.05715)
			(type default)
		)
		(layer "In9.Cu")
	)
	(gr_line
		(start 56.268112 -58.02376)
		(end 56.314848 -58.093864)
		(stroke
			(width 0.05715)
			(type default)
		)
		(layer "In9.Cu")
	)
	(gr_line
		(start 56.298338 -58.176414)
		(end 56.314848 -58.093864)
		(stroke
			(width 0.05715)
			(type default)
		)
		(layer "In9.Cu")
	)
	(gr_line
		(start 56.498998 -90.572336)
		(end 56.503062 -90.592148)
		(stroke
			(width 0.05715)
			(type default)
		)
		(layer "In9.Cu")
	)
	(gr_line
		(start 56.599582 -46.492414)
		(end 56.61787 -46.504606)
		(stroke
			(width 0.05715)
			(type default)
		)
		(layer "In9.Cu")
	)
	(gr_line
		(start 56.61787 -46.504606)
		(end 56.630062 -46.522894)
		(stroke
			(width 0.05715)
			(type default)
		)
		(layer "In9.Cu")
	)
	(gr_line
		(start 56.70042 -102.547166)
		(end 56.704738 -102.568502)
		(stroke
			(width 0.05715)
			(type default)
		)
		(layer "In9.Cu")
	)
	(gr_line
		(start 56.704738 -102.568502)
		(end 56.71693 -102.58679)
		(stroke
			(width 0.05715)
			(type default)
		)
		(layer "In9.Cu")
	)
	(gr_line
		(start 56.889396 -45.728382)
		(end 56.907684 -45.740574)
		(stroke
			(width 0.05715)
			(type default)
		)
		(layer "In9.Cu")
	)
	(gr_line
		(start 56.907684 -45.740574)
		(end 56.919876 -45.758862)
		(stroke
			(width 0.05715)
			(type default)
		)
		(layer "In9.Cu")
	)
	(gr_line
		(start 56.99252 -70.230492)
		(end 57.010046 -70.263512)
		(stroke
			(width 0.05715)
			(type default)
		)
		(layer "In9.Cu")
	)
	(gr_line
		(start 56.99252 -67.258946)
		(end 56.999886 -67.241674)
		(stroke
			(width 0.05715)
			(type default)
		)
		(layer "In9.Cu")
	)
	(gr_line
		(start 56.99506 -103.00335)
		(end 57.330594 -103.506016)
		(stroke
			(width 0.05715)
			(type default)
		)
		(layer "In9.Cu")
	)
	(gr_line
		(start 57.13857 -70.156324)
		(end 57.155588 -70.225158)
		(stroke
			(width 0.1778)
			(type default)
		)
		(layer "In9.Cu")
	)
	(gr_line
		(start 57.13857 -67.317112)
		(end 57.13857 -70.156324)
		(stroke
			(width 0.1778)
			(type default)
		)
		(layer "In9.Cu")
	)
	(gr_line
		(start 57.149492 -67.261232)
		(end 57.13857 -67.317112)
		(stroke
			(width 0.1778)
			(type default)
		)
		(layer "In9.Cu")
	)
	(gr_line
		(start 57.155588 -70.225158)
		(end 59.873388 -75.307952)
		(stroke
			(width 0.1778)
			(type default)
		)
		(layer "In9.Cu")
	)
	(gr_line
		(start 57.161938 -88.746838)
		(end 57.166002 -88.727026)
		(stroke
			(width 0.05715)
			(type default)
		)
		(layer "In9.Cu")
	)
	(gr_line
		(start 57.162192 -88.707976)
		(end 57.166002 -88.727026)
		(stroke
			(width 0.05715)
			(type default)
		)
		(layer "In9.Cu")
	)
	(gr_line
		(start 57.221882 -102.812088)
		(end 57.447688 -102.857046)
		(stroke
			(width 0.05715)
			(type default)
		)
		(layer "In9.Cu")
	)
	(gr_line
		(start 57.23255 -82.009234)
		(end 57.24906 -81.978246)
		(stroke
			(width 0.05715)
			(type default)
		)
		(layer "In9.Cu")
	)
	(gr_line
		(start 57.352692 -58.37555)
		(end 57.364376 -58.393076)
		(stroke
			(width 0.05715)
			(type default)
		)
		(layer "In9.Cu")
	)
	(gr_line
		(start 57.364376 -58.393076)
		(end 57.368186 -58.413142)
		(stroke
			(width 0.05715)
			(type default)
		)
		(layer "In9.Cu")
	)
	(gr_line
		(start 57.375044 -63.873634)
		(end 57.378854 -63.854584)
		(stroke
			(width 0.05715)
			(type default)
		)
		(layer "In9.Cu")
	)
	(gr_line
		(start 57.375044 -63.873634)
		(end 57.379108 -63.893446)
		(stroke
			(width 0.05715)
			(type default)
		)
		(layer "In9.Cu")
	)
	(gr_line
		(start 57.3786 -82.08264)
		(end 57.3786 -83.054952)
		(stroke
			(width 0.1778)
			(type default)
		)
		(layer "In9.Cu")
	)
	(gr_line
		(start 57.395618 -82.013806)
		(end 57.3786 -82.08264)
		(stroke
			(width 0.1778)
			(type default)
		)
		(layer "In9.Cu")
	)
	(gr_line
		(start 57.42432 -89.306146)
		(end 57.42813 -89.287096)
		(stroke
			(width 0.05715)
			(type default)
		)
		(layer "In9.Cu")
	)
	(gr_line
		(start 57.42432 -89.306146)
		(end 57.428384 -89.325958)
		(stroke
			(width 0.05715)
			(type default)
		)
		(layer "In9.Cu")
	)
	(gr_line
		(start 57.436766 -45.263816)
		(end 57.455054 -45.276008)
		(stroke
			(width 0.05715)
			(type default)
		)
		(layer "In9.Cu")
	)
	(gr_line
		(start 57.447688 -102.857046)
		(end 57.638188 -103.142288)
		(stroke
			(width 0.05715)
			(type default)
		)
		(layer "In9.Cu")
	)
	(gr_line
		(start 57.455054 -45.276008)
		(end 57.467246 -45.294296)
		(stroke
			(width 0.05715)
			(type default)
		)
		(layer "In9.Cu")
	)
	(gr_line
		(start 57.52973 -63.902336)
		(end 57.674256 -64.624966)
		(stroke
			(width 0.1778)
			(type default)
		)
		(layer "In9.Cu")
	)
	(gr_line
		(start 57.52973 -63.844932)
		(end 57.52973 -63.902336)
		(stroke
			(width 0.1778)
			(type default)
		)
		(layer "In9.Cu")
	)
	(gr_line
		(start 57.579006 -89.334848)
		(end 60.459874 -103.741728)
		(stroke
			(width 0.1778)
			(type default)
		)
		(layer "In9.Cu")
	)
	(gr_line
		(start 57.579006 -89.277444)
		(end 57.579006 -89.334848)
		(stroke
			(width 0.1778)
			(type default)
		)
		(layer "In9.Cu")
	)
	(gr_line
		(start 57.59323 -103.368348)
		(end 57.638188 -103.142288)
		(stroke
			(width 0.05715)
			(type default)
		)
		(layer "In9.Cu")
	)
	(gr_line
		(start 57.601866 -59.62396)
		(end 57.60593 -59.604148)
		(stroke
			(width 0.05715)
			(type default)
		)
		(layer "In9.Cu")
	)
	(gr_line
		(start 57.601866 -59.58459)
		(end 57.60593 -59.604148)
		(stroke
			(width 0.05715)
			(type default)
		)
		(layer "In9.Cu")
	)
	(gr_line
		(start 57.665874 -66.0146)
		(end 57.149492 -67.261232)
		(stroke
			(width 0.1778)
			(type default)
		)
		(layer "In9.Cu")
	)
	(gr_line
		(start 57.674256 -64.624966)
		(end 57.67705 -64.653668)
		(stroke
			(width 0.1778)
			(type default)
		)
		(layer "In9.Cu")
	)
	(gr_line
		(start 57.67705 -65.95872)
		(end 57.665874 -66.0146)
		(stroke
			(width 0.1778)
			(type default)
		)
		(layer "In9.Cu")
	)
	(gr_line
		(start 57.67705 -64.653668)
		(end 57.67705 -65.95872)
		(stroke
			(width 0.1778)
			(type default)
		)
		(layer "In9.Cu")
	)
	(gr_line
		(start 57.766966 -44.508166)
		(end 57.785254 -44.520358)
		(stroke
			(width 0.05715)
			(type default)
		)
		(layer "In9.Cu")
	)
	(gr_line
		(start 57.76722 -70.330568)
		(end 57.78373 -70.361556)
		(stroke
			(width 0.05715)
			(type default)
		)
		(layer "In9.Cu")
	)
	(gr_line
		(start 57.76722 -67.468242)
		(end 57.76849 -67.464432)
		(stroke
			(width 0.05715)
			(type default)
		)
		(layer "In9.Cu")
	)
	(gr_line
		(start 57.785254 -44.520358)
		(end 57.797446 -44.538646)
		(stroke
			(width 0.05715)
			(type default)
		)
		(layer "In9.Cu")
	)
	(gr_line
		(start 57.815734 -66.034158)
		(end 57.8231 -66.016886)
		(stroke
			(width 0.05715)
			(type default)
		)
		(layer "In9.Cu")
	)
	(gr_line
		(start 57.96407 -80.950562)
		(end 57.395618 -82.013806)
		(stroke
			(width 0.1778)
			(type default)
		)
		(layer "In9.Cu")
	)
	(gr_line
		(start 57.971436 -80.938116)
		(end 57.96407 -80.950562)
		(stroke
			(width 0.1778)
			(type default)
		)
		(layer "In9.Cu")
	)
	(gr_line
		(start 58.064146 -86.851998)
		(end 57.579006 -89.277444)
		(stroke
			(width 0.1778)
			(type default)
		)
		(layer "In9.Cu")
	)
	(gr_line
		(start 58.06694 -86.823296)
		(end 58.064146 -86.851998)
		(stroke
			(width 0.1778)
			(type default)
		)
		(layer "In9.Cu")
	)
	(gr_line
		(start 58.06694 -83.86445)
		(end 58.06694 -86.823296)
		(stroke
			(width 0.1778)
			(type default)
		)
		(layer "In9.Cu")
	)
	(gr_line
		(start 58.075576 -43.779186)
		(end 58.095642 -43.792394)
		(stroke
			(width 0.05715)
			(type default)
		)
		(layer "In9.Cu")
	)
	(gr_line
		(start 58.083196 -58.420254)
		(end 58.349134 -59.749436)
		(stroke
			(width 0.1778)
			(type default)
		)
		(layer "In9.Cu")
	)
	(gr_line
		(start 58.083704 -64.013334)
		(end 58.087514 -63.994284)
		(stroke
			(width 0.05715)
			(type default)
		)
		(layer "In9.Cu")
	)
	(gr_line
		(start 58.083704 -64.013334)
		(end 58.087768 -64.0334)
		(stroke
			(width 0.05715)
			(type default)
		)
		(layer "In9.Cu")
	)
	(gr_line
		(start 58.095642 -43.792394)
		(end 58.10885 -43.812206)
		(stroke
			(width 0.05715)
			(type default)
		)
		(layer "In9.Cu")
	)
	(gr_line
		(start 58.12028 -89.4334)
		(end 58.124598 -89.45499)
		(stroke
			(width 0.05715)
			(type default)
		)
		(layer "In9.Cu")
	)
	(gr_line
		(start 58.12028 -89.4334)
		(end 58.124598 -89.411302)
		(stroke
			(width 0.05715)
			(type default)
		)
		(layer "In9.Cu")
	)
	(gr_line
		(start 58.226198 -58.370978)
		(end 58.236866 -58.387234)
		(stroke
			(width 0.05715)
			(type default)
		)
		(layer "In9.Cu")
	)
	(gr_line
		(start 58.231532 -103.558086)
		(end 58.235342 -103.577136)
		(stroke
			(width 0.05715)
			(type default)
		)
		(layer "In9.Cu")
	)
	(gr_line
		(start 58.235342 -103.577136)
		(end 58.24601 -103.593392)
		(stroke
			(width 0.05715)
			(type default)
		)
		(layer "In9.Cu")
	)
	(gr_line
		(start 58.236866 -58.387234)
		(end 58.23712 -58.387234)
		(stroke
			(width 0.05715)
			(type default)
		)
		(layer "In9.Cu")
	)
	(gr_line
		(start 58.23712 -58.387234)
		(end 58.24093 -58.4073)
		(stroke
			(width 0.05715)
			(type default)
		)
		(layer "In9.Cu")
	)
	(gr_line
		(start 58.349134 -59.749436)
		(end 57.52973 -63.844932)
		(stroke
			(width 0.1778)
			(type default)
		)
		(layer "In9.Cu")
	)
	(gr_line
		(start 58.47715 -81.061814)
		(end 58.50509 -81.019904)
		(stroke
			(width 0.05715)
			(type default)
		)
		(layer "In9.Cu")
	)
	(gr_line
		(start 58.499756 -59.740292)
		(end 58.50382 -59.720734)
		(stroke
			(width 0.05715)
			(type default)
		)
		(layer "In9.Cu")
	)
	(gr_line
		(start 58.499756 -59.700922)
		(end 58.50382 -59.720734)
		(stroke
			(width 0.05715)
			(type default)
		)
		(layer "In9.Cu")
	)
	(gr_line
		(start 58.54192 -70.372224)
		(end 58.55843 -70.403212)
		(stroke
			(width 0.05715)
			(type default)
		)
		(layer "In9.Cu")
	)
	(gr_line
		(start 58.664094 -65.51168)
		(end 58.674508 -65.477644)
		(stroke
			(width 0.05715)
			(type default)
		)
		(layer "In9.Cu")
	)
	(gr_line
		(start 58.667396 -65.442084)
		(end 58.674508 -65.477644)
		(stroke
			(width 0.05715)
			(type default)
		)
		(layer "In9.Cu")
	)
	(gr_line
		(start 58.68797 -70.298818)
		(end 58.705242 -70.367652)
		(stroke
			(width 0.1778)
			(type default)
		)
		(layer "In9.Cu")
	)
	(gr_line
		(start 58.68797 -68.475098)
		(end 58.68797 -70.298818)
		(stroke
			(width 0.1778)
			(type default)
		)
		(layer "In9.Cu")
	)
	(gr_line
		(start 58.705242 -70.367652)
		(end 61.062362 -74.772012)
		(stroke
			(width 0.1778)
			(type default)
		)
		(layer "In9.Cu")
	)
	(gr_line
		(start 58.730642 -68.37172)
		(end 58.68797 -68.475098)
		(stroke
			(width 0.1778)
			(type default)
		)
		(layer "In9.Cu")
	)
	(gr_line
		(start 58.80227 -64.180974)
		(end 58.80608 -64.161924)
		(stroke
			(width 0.05715)
			(type default)
		)
		(layer "In9.Cu")
	)
	(gr_line
		(start 58.80227 -64.180974)
		(end 58.806334 -64.20104)
		(stroke
			(width 0.05715)
			(type default)
		)
		(layer "In9.Cu")
	)
	(gr_line
		(start 58.85053 -89.286588)
		(end 58.85434 -89.267538)
		(stroke
			(width 0.05715)
			(type default)
		)
		(layer "In9.Cu")
	)
	(gr_line
		(start 58.85053 -89.286588)
		(end 58.854594 -89.3064)
		(stroke
			(width 0.05715)
			(type default)
		)
		(layer "In9.Cu")
	)
	(gr_line
		(start 58.85815 -83.263232)
		(end 58.85815 -83.280504)
		(stroke
			(width 0.05715)
			(type default)
		)
		(layer "In9.Cu")
	)
	(gr_line
		(start 58.956956 -64.209422)
		(end 59.557412 -67.214242)
		(stroke
			(width 0.1778)
			(type default)
		)
		(layer "In9.Cu")
	)
	(gr_line
		(start 58.956956 -64.152272)
		(end 58.956956 -64.209422)
		(stroke
			(width 0.1778)
			(type default)
		)
		(layer "In9.Cu")
	)
	(gr_line
		(start 58.984134 -58.091578)
		(end 58.994802 -58.107834)
		(stroke
			(width 0.05715)
			(type default)
		)
		(layer "In9.Cu")
	)
	(gr_line
		(start 58.99912 -83.552792)
		(end 58.99912 -83.570064)
		(stroke
			(width 0.05715)
			(type default)
		)
		(layer "In9.Cu")
	)
	(gr_line
		(start 59.005216 -89.31529)
		(end 61.812932 -103.35387)
		(stroke
			(width 0.1778)
			(type default)
		)
		(layer "In9.Cu")
	)
	(gr_line
		(start 59.005216 -89.257886)
		(end 59.005216 -89.31529)
		(stroke
			(width 0.1778)
			(type default)
		)
		(layer "In9.Cu")
	)
	(gr_line
		(start 59.099196 -103.573326)
		(end 59.103006 -103.592376)
		(stroke
			(width 0.05715)
			(type default)
		)
		(layer "In9.Cu")
	)
	(gr_line
		(start 59.103006 -103.592376)
		(end 59.113674 -103.608632)
		(stroke
			(width 0.05715)
			(type default)
		)
		(layer "In9.Cu")
	)
	(gr_line
		(start 59.27471 -59.547252)
		(end 59.278774 -59.52744)
		(stroke
			(width 0.05715)
			(type default)
		)
		(layer "In9.Cu")
	)
	(gr_line
		(start 59.274964 -59.50839)
		(end 59.278774 -59.52744)
		(stroke
			(width 0.05715)
			(type default)
		)
		(layer "In9.Cu")
	)
	(gr_line
		(start 59.487308 -57.872376)
		(end 59.844178 -59.65571)
		(stroke
			(width 0.1778)
			(type default)
		)
		(layer "In9.Cu")
	)
	(gr_line
		(start 59.517534 -67.585082)
		(end 58.730642 -68.37172)
		(stroke
			(width 0.1778)
			(type default)
		)
		(layer "In9.Cu")
	)
	(gr_line
		(start 59.525154 -89.421462)
		(end 59.528964 -89.402412)
		(stroke
			(width 0.05715)
			(type default)
		)
		(layer "In9.Cu")
	)
	(gr_line
		(start 59.525154 -89.421462)
		(end 59.529218 -89.441274)
		(stroke
			(width 0.05715)
			(type default)
		)
		(layer "In9.Cu")
	)
	(gr_line
		(start 59.53252 -64.387984)
		(end 59.53633 -64.368934)
		(stroke
			(width 0.05715)
			(type default)
		)
		(layer "In9.Cu")
	)
	(gr_line
		(start 59.53252 -64.387984)
		(end 59.536584 -64.407796)
		(stroke
			(width 0.05715)
			(type default)
		)
		(layer "In9.Cu")
	)
	(gr_line
		(start 59.557412 -67.214242)
		(end 59.560206 -67.242944)
		(stroke
			(width 0.1778)
			(type default)
		)
		(layer "In9.Cu")
	)
	(gr_line
		(start 59.560206 -67.481704)
		(end 59.517534 -67.585082)
		(stroke
			(width 0.1778)
			(type default)
		)
		(layer "In9.Cu")
	)
	(gr_line
		(start 59.560206 -67.242944)
		(end 59.560206 -67.481704)
		(stroke
			(width 0.1778)
			(type default)
		)
		(layer "In9.Cu")
	)
	(gr_line
		(start 59.608466 -57.770776)
		(end 59.619134 -57.787032)
		(stroke
			(width 0.05715)
			(type default)
		)
		(layer "In9.Cu")
	)
	(gr_line
		(start 59.619134 -57.787032)
		(end 59.622944 -57.806082)
		(stroke
			(width 0.05715)
			(type default)
		)
		(layer "In9.Cu")
	)
	(gr_line
		(start 59.844178 -59.71286)
		(end 58.956956 -64.152272)
		(stroke
			(width 0.1778)
			(type default)
		)
		(layer "In9.Cu")
	)
	(gr_line
		(start 59.844178 -59.65571)
		(end 59.844178 -59.71286)
		(stroke
			(width 0.1778)
			(type default)
		)
		(layer "In9.Cu")
	)
	(gr_line
		(start 59.873388 -75.307952)
		(end 59.887866 -75.348338)
		(stroke
			(width 0.1778)
			(type default)
		)
		(layer "In9.Cu")
	)
	(gr_line
		(start 59.887866 -75.348338)
		(end 60.18403 -76.826618)
		(stroke
			(width 0.1778)
			(type default)
		)
		(layer "In9.Cu")
	)
	(gr_line
		(start 59.9567 -77.964538)
		(end 57.971436 -80.938116)
		(stroke
			(width 0.1778)
			(type default)
		)
		(layer "In9.Cu")
	)
	(gr_line
		(start 59.96432 -70.562724)
		(end 60.12688 -70.725284)
		(stroke
			(width 0.05715)
			(type default)
		)
		(layer "In9.Cu")
	)
	(gr_line
		(start 59.96432 -70.219824)
		(end 59.96432 -70.562724)
		(stroke
			(width 0.05715)
			(type default)
		)
		(layer "In9.Cu")
	)
	(gr_line
		(start 59.96432 -70.219824)
		(end 60.12688 -70.057264)
		(stroke
			(width 0.05715)
			(type default)
		)
		(layer "In9.Cu")
	)
	(gr_line
		(start 59.978544 -77.91196)
		(end 59.9567 -77.964538)
		(stroke
			(width 0.1778)
			(type default)
		)
		(layer "In9.Cu")
	)
	(gr_line
		(start 59.9948 -59.704478)
		(end 59.998864 -59.684412)
		(stroke
			(width 0.05715)
			(type default)
		)
		(layer "In9.Cu")
	)
	(gr_line
		(start 59.995054 -59.665362)
		(end 59.998864 -59.684412)
		(stroke
			(width 0.05715)
			(type default)
		)
		(layer "In9.Cu")
	)
	(gr_line
		(start 60.019946 -75.271884)
		(end 60.02274 -75.277218)
		(stroke
			(width 0.05715)
			(type default)
		)
		(layer "In9.Cu")
	)
	(gr_line
		(start 60.02274 -75.277218)
		(end 60.02401 -75.283314)
		(stroke
			(width 0.05715)
			(type default)
		)
		(layer "In9.Cu")
	)
	(gr_line
		(start 60.041536 -109.00791)
		(end 60.053728 -109.026198)
		(stroke
			(width 0.05715)
			(type default)
		)
		(layer "In9.Cu")
	)
	(gr_line
		(start 60.053728 -109.026198)
		(end 60.072016 -109.03839)
		(stroke
			(width 0.05715)
			(type default)
		)
		(layer "In9.Cu")
	)
	(gr_line
		(start 60.099702 -78.01356)
		(end 60.11037 -77.997558)
		(stroke
			(width 0.05715)
			(type default)
		)
		(layer "In9.Cu")
	)
	(gr_line
		(start 60.11037 -77.997558)
		(end 60.11418 -77.978508)
		(stroke
			(width 0.05715)
			(type default)
		)
		(layer "In9.Cu")
	)
	(gr_line
		(start 60.12942 -71.860156)
		(end 60.14593 -71.891144)
		(stroke
			(width 0.05715)
			(type default)
		)
		(layer "In9.Cu")
	)
	(gr_line
		(start 60.18403 -76.883768)
		(end 59.978544 -77.91196)
		(stroke
			(width 0.1778)
			(type default)
		)
		(layer "In9.Cu")
	)
	(gr_line
		(start 60.18403 -76.826618)
		(end 60.18403 -76.883768)
		(stroke
			(width 0.1778)
			(type default)
		)
		(layer "In9.Cu")
	)
	(gr_line
		(start 60.272422 -57.36971)
		(end 60.284106 -57.38749)
		(stroke
			(width 0.05715)
			(type default)
		)
		(layer "In9.Cu")
	)
	(gr_line
		(start 60.284106 -57.38749)
		(end 60.28436 -57.388506)
		(stroke
			(width 0.05715)
			(type default)
		)
		(layer "In9.Cu")
	)
	(gr_line
		(start 60.28436 -57.388506)
		(end 60.28817 -57.407556)
		(stroke
			(width 0.05715)
			(type default)
		)
		(layer "In9.Cu")
	)
	(gr_line
		(start 60.324238 -103.808022)
		(end 60.328048 -103.827072)
		(stroke
			(width 0.05715)
			(type default)
		)
		(layer "In9.Cu")
	)
	(gr_line
		(start 60.328048 -103.827072)
		(end 60.338716 -103.843328)
		(stroke
			(width 0.05715)
			(type default)
		)
		(layer "In9.Cu")
	)
	(gr_line
		(start 60.334652 -76.875132)
		(end 60.338716 -76.85532)
		(stroke
			(width 0.05715)
			(type default)
		)
		(layer "In9.Cu")
	)
	(gr_line
		(start 60.334906 -76.83627)
		(end 60.338716 -76.85532)
		(stroke
			(width 0.05715)
			(type default)
		)
		(layer "In9.Cu")
	)
	(gr_line
		(start 60.350908 -64.358774)
		(end 60.354718 -64.377824)
		(stroke
			(width 0.05715)
			(type default)
		)
		(layer "In9.Cu")
	)
	(gr_line
		(start 60.350908 -64.358774)
		(end 60.354972 -64.338962)
		(stroke
			(width 0.05715)
			(type default)
		)
		(layer "In9.Cu")
	)
	(gr_line
		(start 60.409582 -89.782142)
		(end 60.413392 -89.801192)
		(stroke
			(width 0.05715)
			(type default)
		)
		(layer "In9.Cu")
	)
	(gr_line
		(start 60.409582 -89.782142)
		(end 60.413646 -89.76233)
		(stroke
			(width 0.05715)
			(type default)
		)
		(layer "In9.Cu")
	)
	(gr_line
		(start 60.42152 -70.349364)
		(end 60.42152 -70.433184)
		(stroke
			(width 0.05715)
			(type default)
		)
		(layer "In9.Cu")
	)
	(gr_line
		(start 60.459874 -103.741728)
		(end 60.481464 -103.794052)
		(stroke
			(width 0.1778)
			(type default)
		)
		(layer "In9.Cu")
	)
	(gr_line
		(start 60.481464 -103.794052)
		(end 62.84595 -107.340146)
		(stroke
			(width 0.1778)
			(type default)
		)
		(layer "In9.Cu")
	)
	(gr_line
		(start 60.623196 -75.047856)
		(end 60.62599 -75.05319)
		(stroke
			(width 0.05715)
			(type default)
		)
		(layer "In9.Cu")
	)
	(gr_line
		(start 60.62599 -75.05319)
		(end 60.62726 -75.059286)
		(stroke
			(width 0.05715)
			(type default)
		)
		(layer "In9.Cu")
	)
	(gr_line
		(start 60.698126 -78.261464)
		(end 60.708794 -78.245462)
		(stroke
			(width 0.05715)
			(type default)
		)
		(layer "In9.Cu")
	)
	(gr_line
		(start 60.708794 -78.245462)
		(end 60.712604 -78.226412)
		(stroke
			(width 0.05715)
			(type default)
		)
		(layer "In9.Cu")
	)
	(gr_line
		(start 60.753752 -59.77255)
		(end 60.757816 -59.752738)
		(stroke
			(width 0.05715)
			(type default)
		)
		(layer "In9.Cu")
	)
	(gr_line
		(start 60.754006 -59.733688)
		(end 60.757816 -59.752738)
		(stroke
			(width 0.05715)
			(type default)
		)
		(layer "In9.Cu")
	)
	(gr_line
		(start 60.804552 -108.707174)
		(end 60.816744 -108.725462)
		(stroke
			(width 0.05715)
			(type default)
		)
		(layer "In9.Cu")
	)
	(gr_line
		(start 60.816744 -108.725462)
		(end 60.816998 -108.725462)
		(stroke
			(width 0.05715)
			(type default)
		)
		(layer "In9.Cu")
	)
	(gr_line
		(start 60.816998 -108.725462)
		(end 60.834016 -108.736892)
		(stroke
			(width 0.05715)
			(type default)
		)
		(layer "In9.Cu")
	)
	(gr_line
		(start 60.95111 -103.589074)
		(end 60.95492 -103.608124)
		(stroke
			(width 0.05715)
			(type default)
		)
		(layer "In9.Cu")
	)
	(gr_line
		(start 60.95492 -103.608124)
		(end 60.965588 -103.62438)
		(stroke
			(width 0.05715)
			(type default)
		)
		(layer "In9.Cu")
	)
	(gr_line
		(start 60.982606 -76.875386)
		(end 60.98667 -76.855574)
		(stroke
			(width 0.05715)
			(type default)
		)
		(layer "In9.Cu")
	)
	(gr_line
		(start 60.98286 -76.836524)
		(end 60.98667 -76.855574)
		(stroke
			(width 0.05715)
			(type default)
		)
		(layer "In9.Cu")
	)
	(gr_line
		(start 61.027818 -57.029604)
		(end 61.038486 -57.04586)
		(stroke
			(width 0.05715)
			(type default)
		)
		(layer "In9.Cu")
	)
	(gr_line
		(start 61.038486 -57.04586)
		(end 61.042296 -57.06491)
		(stroke
			(width 0.05715)
			(type default)
		)
		(layer "In9.Cu")
	)
	(gr_line
		(start 61.062362 -74.772012)
		(end 61.07684 -74.812398)
		(stroke
			(width 0.1778)
			(type default)
		)
		(layer "In9.Cu")
	)
	(gr_line
		(start 61.07684 -74.812398)
		(end 61.479938 -76.82738)
		(stroke
			(width 0.1778)
			(type default)
		)
		(layer "In9.Cu")
	)
	(gr_line
		(start 61.11113 -64.37122)
		(end 61.11494 -64.39027)
		(stroke
			(width 0.05715)
			(type default)
		)
		(layer "In9.Cu")
	)
	(gr_line
		(start 61.11113 -64.37122)
		(end 61.115194 -64.351408)
		(stroke
			(width 0.05715)
			(type default)
		)
		(layer "In9.Cu")
	)
	(gr_line
		(start 61.127386 -89.546938)
		(end 61.131196 -89.565988)
		(stroke
			(width 0.05715)
			(type default)
		)
		(layer "In9.Cu")
	)
	(gr_line
		(start 61.127386 -89.546938)
		(end 61.13145 -89.527126)
		(stroke
			(width 0.05715)
			(type default)
		)
		(layer "In9.Cu")
	)
	(gr_line
		(start 61.20892 -74.735944)
		(end 61.211714 -74.741278)
		(stroke
			(width 0.05715)
			(type default)
		)
		(layer "In9.Cu")
	)
	(gr_line
		(start 61.211714 -74.741278)
		(end 61.212984 -74.747374)
		(stroke
			(width 0.05715)
			(type default)
		)
		(layer "In9.Cu")
	)
	(gr_line
		(start 61.412374 -108.343192)
		(end 61.424566 -108.36148)
		(stroke
			(width 0.05715)
			(type default)
		)
		(layer "In9.Cu")
	)
	(gr_line
		(start 61.424566 -108.36148)
		(end 61.442854 -108.373672)
		(stroke
			(width 0.05715)
			(type default)
		)
		(layer "In9.Cu")
	)
	(gr_line
		(start 61.479938 -76.884784)
		(end 59.005216 -89.257886)
		(stroke
			(width 0.1778)
			(type default)
		)
		(layer "In9.Cu")
	)
	(gr_line
		(start 61.479938 -76.82738)
		(end 61.479938 -76.884784)
		(stroke
			(width 0.1778)
			(type default)
		)
		(layer "In9.Cu")
	)
	(gr_line
		(start 61.571632 -59.74588)
		(end 61.575696 -59.726068)
		(stroke
			(width 0.05715)
			(type default)
		)
		(layer "In9.Cu")
	)
	(gr_line
		(start 61.571886 -59.707272)
		(end 61.575696 -59.726068)
		(stroke
			(width 0.05715)
			(type default)
		)
		(layer "In9.Cu")
	)
	(gr_line
		(start 61.63056 -76.875894)
		(end 61.634624 -76.856082)
		(stroke
			(width 0.05715)
			(type default)
		)
		(layer "In9.Cu")
	)
	(gr_line
		(start 61.630814 -76.837032)
		(end 61.634624 -76.856082)
		(stroke
			(width 0.05715)
			(type default)
		)
		(layer "In9.Cu")
	)
	(gr_line
		(start 61.676788 -103.418894)
		(end 61.680852 -103.43896)
		(stroke
			(width 0.05715)
			(type default)
		)
		(layer "In9.Cu")
	)
	(gr_line
		(start 61.680852 -103.43896)
		(end 61.691774 -103.45547)
		(stroke
			(width 0.05715)
			(type default)
		)
		(layer "In9.Cu")
	)
	(gr_line
		(start 61.683138 -56.597804)
		(end 61.693806 -56.61406)
		(stroke
			(width 0.05715)
			(type default)
		)
		(layer "In9.Cu")
	)
	(gr_line
		(start 61.693806 -56.61406)
		(end 61.697616 -56.63311)
		(stroke
			(width 0.05715)
			(type default)
		)
		(layer "In9.Cu")
	)
	(gr_line
		(start 61.728858 -103.515668)
		(end 61.732922 -103.53421)
		(stroke
			(width 0.05715)
			(type default)
		)
		(layer "In9.Cu")
	)
	(gr_line
		(start 61.732922 -103.53421)
		(end 61.743082 -103.549704)
		(stroke
			(width 0.05715)
			(type default)
		)
		(layer "In9.Cu")
	)
	(gr_line
		(start 61.805312 -89.509346)
		(end 61.809122 -89.528396)
		(stroke
			(width 0.05715)
			(type default)
		)
		(layer "In9.Cu")
	)
	(gr_line
		(start 61.805312 -89.509346)
		(end 61.809376 -89.489534)
		(stroke
			(width 0.05715)
			(type default)
		)
		(layer "In9.Cu")
	)
	(gr_line
		(start 61.832744 -64.424052)
		(end 61.836554 -64.443102)
		(stroke
			(width 0.05715)
			(type default)
		)
		(layer "In9.Cu")
	)
	(gr_line
		(start 61.832744 -64.424052)
		(end 61.836808 -64.40424)
		(stroke
			(width 0.05715)
			(type default)
		)
		(layer "In9.Cu")
	)
	(gr_line
		(start 61.837316 -74.431906)
		(end 61.84011 -74.43724)
		(stroke
			(width 0.05715)
			(type default)
		)
		(layer "In9.Cu")
	)
	(gr_line
		(start 61.84011 -74.43724)
		(end 61.84138 -74.443336)
		(stroke
			(width 0.05715)
			(type default)
		)
		(layer "In9.Cu")
	)
	(gr_line
		(start 61.992002 -103.379016)
		(end 62.002416 -103.394764)
		(stroke
			(width 0.05715)
			(type default)
		)
		(layer "In9.Cu")
	)
	(gr_line
		(start 62.002416 -103.394764)
		(end 62.006226 -103.413052)
		(stroke
			(width 0.05715)
			(type default)
		)
		(layer "In9.Cu")
	)
	(gr_line
		(start 62.011814 -107.95508)
		(end 62.024006 -107.973368)
		(stroke
			(width 0.05715)
			(type default)
		)
		(layer "In9.Cu")
	)
	(gr_line
		(start 62.024006 -107.973368)
		(end 62.042294 -107.98556)
		(stroke
			(width 0.05715)
			(type default)
		)
		(layer "In9.Cu")
	)
	(gr_line
		(start 62.275466 -103.17226)
		(end 62.279276 -103.19131)
		(stroke
			(width 0.05715)
			(type default)
		)
		(layer "In9.Cu")
	)
	(gr_line
		(start 62.279276 -103.19131)
		(end 62.289944 -103.207566)
		(stroke
			(width 0.05715)
			(type default)
		)
		(layer "In9.Cu")
	)
	(gr_line
		(start 62.305692 -56.358536)
		(end 62.31636 -56.374792)
		(stroke
			(width 0.05715)
			(type default)
		)
		(layer "In9.Cu")
	)
	(gr_line
		(start 62.31636 -56.374792)
		(end 62.319916 -56.39308)
		(stroke
			(width 0.05715)
			(type default)
		)
		(layer "In9.Cu")
	)
	(gr_line
		(start 62.323726 -59.756802)
		(end 62.32779 -59.776614)
		(stroke
			(width 0.05715)
			(type default)
		)
		(layer "In9.Cu")
	)
	(gr_line
		(start 62.32398 -59.795664)
		(end 62.32779 -59.776614)
		(stroke
			(width 0.05715)
			(type default)
		)
		(layer "In9.Cu")
	)
	(gr_line
		(start 62.325758 -76.906374)
		(end 62.329822 -76.886562)
		(stroke
			(width 0.05715)
			(type default)
		)
		(layer "In9.Cu")
	)
	(gr_line
		(start 62.326012 -76.867512)
		(end 62.329822 -76.886562)
		(stroke
			(width 0.05715)
			(type default)
		)
		(layer "In9.Cu")
	)
	(gr_line
		(start 62.488572 -89.4207)
		(end 62.492382 -89.43975)
		(stroke
			(width 0.05715)
			(type default)
		)
		(layer "In9.Cu")
	)
	(gr_line
		(start 62.488572 -89.4207)
		(end 62.492636 -89.400888)
		(stroke
			(width 0.05715)
			(type default)
		)
		(layer "In9.Cu")
	)
	(gr_line
		(start 62.534546 -64.68237)
		(end 62.538356 -64.70142)
		(stroke
			(width 0.05715)
			(type default)
		)
		(layer "In9.Cu")
	)
	(gr_line
		(start 62.534546 -64.68237)
		(end 62.53861 -64.662558)
		(stroke
			(width 0.05715)
			(type default)
		)
		(layer "In9.Cu")
	)
	(gr_line
		(start 62.744604 -107.451652)
		(end 62.756796 -107.46994)
		(stroke
			(width 0.05715)
			(type default)
		)
		(layer "In9.Cu")
	)
	(gr_line
		(start 62.756796 -107.46994)
		(end 62.775084 -107.482132)
		(stroke
			(width 0.05715)
			(type default)
		)
		(layer "In9.Cu")
	)
	(gr_line
		(start 62.900306 -55.92699)
		(end 62.910974 -55.943246)
		(stroke
			(width 0.05715)
			(type default)
		)
		(layer "In9.Cu")
	)
	(gr_line
		(start 62.910974 -55.943246)
		(end 62.91453 -55.961534)
		(stroke
			(width 0.05715)
			(type default)
		)
		(layer "In9.Cu")
	)
	(gr_line
		(start 63.010288 -102.800404)
		(end 63.014098 -102.82047)
		(stroke
			(width 0.05715)
			(type default)
		)
		(layer "In9.Cu")
	)
	(gr_line
		(start 63.014098 -102.82047)
		(end 63.025782 -102.83825)
		(stroke
			(width 0.05715)
			(type default)
		)
		(layer "In9.Cu")
	)
	(gr_line
		(start 63.024766 -59.912758)
		(end 63.02883 -59.93257)
		(stroke
			(width 0.05715)
			(type default)
		)
		(layer "In9.Cu")
	)
	(gr_line
		(start 63.02502 -59.95162)
		(end 63.02883 -59.93257)
		(stroke
			(width 0.05715)
			(type default)
		)
		(layer "In9.Cu")
	)
	(gr_line
		(start 63.03518 -106.729022)
		(end 63.047372 -106.74731)
		(stroke
			(width 0.05715)
			(type default)
		)
		(layer "In9.Cu")
	)
	(gr_line
		(start 63.047372 -106.74731)
		(end 63.065406 -106.759502)
		(stroke
			(width 0.05715)
			(type default)
		)
		(layer "In9.Cu")
	)
	(gr_line
		(start 63.146432 -89.433146)
		(end 63.150242 -89.452196)
		(stroke
			(width 0.05715)
			(type default)
		)
		(layer "In9.Cu")
	)
	(gr_line
		(start 63.146432 -89.433146)
		(end 63.150496 -89.413334)
		(stroke
			(width 0.05715)
			(type default)
		)
		(layer "In9.Cu")
	)
	(gr_line
		(start 63.205868 -64.687704)
		(end 63.209678 -64.706754)
		(stroke
			(width 0.05715)
			(type default)
		)
		(layer "In9.Cu")
	)
	(gr_line
		(start 63.205868 -64.687704)
		(end 63.209932 -64.667892)
		(stroke
			(width 0.05715)
			(type default)
		)
		(layer "In9.Cu")
	)
	(gr_line
		(start 63.216536 -77.196188)
		(end 63.2206 -77.216)
		(stroke
			(width 0.05715)
			(type default)
		)
		(layer "In9.Cu")
	)
	(gr_line
		(start 63.21679 -77.23505)
		(end 63.2206 -77.216)
		(stroke
			(width 0.05715)
			(type default)
		)
		(layer "In9.Cu")
	)
	(gr_line
		(start 63.292228 -105.87355)
		(end 63.30442 -105.891838)
		(stroke
			(width 0.05715)
			(type default)
		)
		(layer "In9.Cu")
	)
	(gr_line
		(start 63.30442 -105.891838)
		(end 63.322708 -105.90403)
		(stroke
			(width 0.05715)
			(type default)
		)
		(layer "In9.Cu")
	)
	(gr_line
		(start 63.573914 -55.739538)
		(end 63.584582 -55.755794)
		(stroke
			(width 0.05715)
			(type default)
		)
		(layer "In9.Cu")
	)
	(gr_line
		(start 63.584582 -55.755794)
		(end 63.588392 -55.774844)
		(stroke
			(width 0.05715)
			(type default)
		)
		(layer "In9.Cu")
	)
	(gr_line
		(start 63.654432 -105.254552)
		(end 63.666624 -105.27284)
		(stroke
			(width 0.05715)
			(type default)
		)
		(layer "In9.Cu")
	)
	(gr_line
		(start 63.666624 -105.27284)
		(end 63.684658 -105.285032)
		(stroke
			(width 0.05715)
			(type default)
		)
		(layer "In9.Cu")
	)
	(gr_line
		(start 63.742062 -60.1345)
		(end 63.746126 -60.114688)
		(stroke
			(width 0.05715)
			(type default)
		)
		(layer "In9.Cu")
	)
	(gr_line
		(start 63.742062 -60.09513)
		(end 63.746126 -60.114688)
		(stroke
			(width 0.05715)
			(type default)
		)
		(layer "In9.Cu")
	)
	(gr_line
		(start 63.761366 -102.72776)
		(end 63.764922 -102.746556)
		(stroke
			(width 0.05715)
			(type default)
		)
		(layer "In9.Cu")
	)
	(gr_line
		(start 63.764922 -102.746556)
		(end 63.77559 -102.762304)
		(stroke
			(width 0.05715)
			(type default)
		)
		(layer "In9.Cu")
	)
	(gr_line
		(start 63.819532 -89.319608)
		(end 63.823342 -89.338658)
		(stroke
			(width 0.05715)
			(type default)
		)
		(layer "In9.Cu")
	)
	(gr_line
		(start 63.819532 -89.319608)
		(end 63.823596 -89.299796)
		(stroke
			(width 0.05715)
			(type default)
		)
		(layer "In9.Cu")
	)
	(gr_line
		(start 63.874396 -64.778128)
		(end 63.878206 -64.797178)
		(stroke
			(width 0.05715)
			(type default)
		)
		(layer "In9.Cu")
	)
	(gr_line
		(start 63.874396 -64.778128)
		(end 63.87846 -64.758316)
		(stroke
			(width 0.05715)
			(type default)
		)
		(layer "In9.Cu")
	)
	(gr_line
		(start 63.930276 -76.980288)
		(end 63.93434 -77.0001)
		(stroke
			(width 0.05715)
			(type default)
		)
		(layer "In9.Cu")
	)
	(gr_line
		(start 63.93053 -77.01915)
		(end 63.93434 -77.0001)
		(stroke
			(width 0.05715)
			(type default)
		)
		(layer "In9.Cu")
	)
	(gr_line
		(start 64.215518 -55.415688)
		(end 64.226186 -55.431944)
		(stroke
			(width 0.05715)
			(type default)
		)
		(layer "In9.Cu")
	)
	(gr_line
		(start 64.226186 -55.431944)
		(end 64.229996 -55.450994)
		(stroke
			(width 0.05715)
			(type default)
		)
		(layer "In9.Cu")
	)
	(gr_line
		(start 64.232028 -104.648254)
		(end 64.24422 -104.666288)
		(stroke
			(width 0.05715)
			(type default)
		)
		(layer "In9.Cu")
	)
	(gr_line
		(start 64.24422 -104.666288)
		(end 64.262254 -104.67848)
		(stroke
			(width 0.05715)
			(type default)
		)
		(layer "In9.Cu")
	)
	(gr_line
		(start 64.333374 -102.15626)
		(end 64.337184 -102.176326)
		(stroke
			(width 0.05715)
			(type default)
		)
		(layer "In9.Cu")
	)
	(gr_line
		(start 64.337184 -102.176326)
		(end 64.348868 -102.194106)
		(stroke
			(width 0.05715)
			(type default)
		)
		(layer "In9.Cu")
	)
	(gr_line
		(start 64.433704 -60.037472)
		(end 64.437768 -60.01766)
		(stroke
			(width 0.05715)
			(type default)
		)
		(layer "In9.Cu")
	)
	(gr_line
		(start 64.433704 -59.998102)
		(end 64.437768 -60.01766)
		(stroke
			(width 0.05715)
			(type default)
		)
		(layer "In9.Cu")
	)
	(gr_line
		(start 64.482218 -89.281762)
		(end 64.486028 -89.300812)
		(stroke
			(width 0.05715)
			(type default)
		)
		(layer "In9.Cu")
	)
	(gr_line
		(start 64.482218 -89.281762)
		(end 64.486282 -89.26195)
		(stroke
			(width 0.05715)
			(type default)
		)
		(layer "In9.Cu")
	)
	(gr_line
		(start 64.523366 -64.771524)
		(end 64.527176 -64.790574)
		(stroke
			(width 0.05715)
			(type default)
		)
		(layer "In9.Cu")
	)
	(gr_line
		(start 64.523366 -64.771524)
		(end 64.52743 -64.751712)
		(stroke
			(width 0.05715)
			(type default)
		)
		(layer "In9.Cu")
	)
	(gr_line
		(start 64.621156 -76.879196)
		(end 64.62522 -76.899008)
		(stroke
			(width 0.05715)
			(type default)
		)
		(layer "In9.Cu")
	)
	(gr_line
		(start 64.62141 -76.918058)
		(end 64.62522 -76.899008)
		(stroke
			(width 0.05715)
			(type default)
		)
		(layer "In9.Cu")
	)
	(gr_line
		(start 64.737996 -104.207056)
		(end 64.750188 -104.22509)
		(stroke
			(width 0.05715)
			(type default)
		)
		(layer "In9.Cu")
	)
	(gr_line
		(start 64.750188 -104.22509)
		(end 64.768222 -104.237282)
		(stroke
			(width 0.05715)
			(type default)
		)
		(layer "In9.Cu")
	)
	(gr_line
		(start 64.822578 -55.075328)
		(end 64.833246 -55.091584)
		(stroke
			(width 0.05715)
			(type default)
		)
		(layer "In9.Cu")
	)
	(gr_line
		(start 64.833246 -55.091584)
		(end 64.837056 -55.110634)
		(stroke
			(width 0.05715)
			(type default)
		)
		(layer "In9.Cu")
	)
	(gr_line
		(start 64.97574 -101.863144)
		(end 64.97955 -101.882194)
		(stroke
			(width 0.05715)
			(type default)
		)
		(layer "In9.Cu")
	)
	(gr_line
		(start 64.97955 -101.882194)
		(end 64.990218 -101.89845)
		(stroke
			(width 0.05715)
			(type default)
		)
		(layer "In9.Cu")
	)
	(gr_line
		(start 65.129918 -59.949588)
		(end 65.133982 -59.9694)
		(stroke
			(width 0.05715)
			(type default)
		)
		(layer "In9.Cu")
	)
	(gr_line
		(start 65.130172 -59.98845)
		(end 65.133982 -59.9694)
		(stroke
			(width 0.05715)
			(type default)
		)
		(layer "In9.Cu")
	)
	(gr_line
		(start 65.175892 -89.142316)
		(end 65.179702 -89.161366)
		(stroke
			(width 0.05715)
			(type default)
		)
		(layer "In9.Cu")
	)
	(gr_line
		(start 65.175892 -89.142316)
		(end 65.179956 -89.122504)
		(stroke
			(width 0.05715)
			(type default)
		)
		(layer "In9.Cu")
	)
	(gr_line
		(start 65.256918 -65.0621)
		(end 65.260728 -65.08115)
		(stroke
			(width 0.05715)
			(type default)
		)
		(layer "In9.Cu")
	)
	(gr_line
		(start 65.256918 -65.0621)
		(end 65.260982 -65.042288)
		(stroke
			(width 0.05715)
			(type default)
		)
		(layer "In9.Cu")
	)
	(gr_line
		(start 65.279016 -76.917042)
		(end 65.28308 -76.936854)
		(stroke
			(width 0.05715)
			(type default)
		)
		(layer "In9.Cu")
	)
	(gr_line
		(start 65.27927 -76.955904)
		(end 65.28308 -76.936854)
		(stroke
			(width 0.05715)
			(type default)
		)
		(layer "In9.Cu")
	)
	(gr_line
		(start 65.48628 -103.90124)
		(end 65.498472 -103.919274)
		(stroke
			(width 0.05715)
			(type default)
		)
		(layer "In9.Cu")
	)
	(gr_line
		(start 65.498472 -103.919274)
		(end 65.516506 -103.931466)
		(stroke
			(width 0.05715)
			(type default)
		)
		(layer "In9.Cu")
	)
	(gr_line
		(start 65.52692 -54.93893)
		(end 65.537588 -54.955186)
		(stroke
			(width 0.05715)
			(type default)
		)
		(layer "In9.Cu")
	)
	(gr_line
		(start 65.537588 -54.955186)
		(end 65.541398 -54.974236)
		(stroke
			(width 0.05715)
			(type default)
		)
		(layer "In9.Cu")
	)
	(gr_line
		(start 65.539366 -101.399848)
		(end 65.543176 -101.419914)
		(stroke
			(width 0.05715)
			(type default)
		)
		(layer "In9.Cu")
	)
	(gr_line
		(start 65.543176 -101.419914)
		(end 65.55486 -101.437694)
		(stroke
			(width 0.05715)
			(type default)
		)
		(layer "In9.Cu")
	)
	(gr_line
		(start 65.791334 -59.88177)
		(end 65.795398 -59.901582)
		(stroke
			(width 0.05715)
			(type default)
		)
		(layer "In9.Cu")
	)
	(gr_line
		(start 65.791588 -59.920632)
		(end 65.795398 -59.901582)
		(stroke
			(width 0.05715)
			(type default)
		)
		(layer "In9.Cu")
	)
	(gr_line
		(start 65.944242 -76.892658)
		(end 65.948306 -76.91247)
		(stroke
			(width 0.05715)
			(type default)
		)
		(layer "In9.Cu")
	)
	(gr_line
		(start 65.944496 -76.93152)
		(end 65.948306 -76.91247)
		(stroke
			(width 0.05715)
			(type default)
		)
		(layer "In9.Cu")
	)
	(gr_line
		(start 66.011298 -103.429816)
		(end 66.02349 -103.448104)
		(stroke
			(width 0.05715)
			(type default)
		)
		(layer "In9.Cu")
	)
	(gr_line
		(start 66.02349 -103.448104)
		(end 66.041524 -103.460296)
		(stroke
			(width 0.05715)
			(type default)
		)
		(layer "In9.Cu")
	)
	(gr_line
		(start 66.190114 -101.174804)
		(end 66.19367 -101.1936)
		(stroke
			(width 0.05715)
			(type default)
		)
		(layer "In9.Cu")
	)
	(gr_line
		(start 66.19367 -101.1936)
		(end 66.204338 -101.209348)
		(stroke
			(width 0.05715)
			(type default)
		)
		(layer "In9.Cu")
	)
	(gr_line
		(start 66.552826 -60.032392)
		(end 66.55689 -60.052204)
		(stroke
			(width 0.05715)
			(type default)
		)
		(layer "In9.Cu")
	)
	(gr_line
		(start 66.55308 -60.071254)
		(end 66.55689 -60.052204)
		(stroke
			(width 0.05715)
			(type default)
		)
		(layer "In9.Cu")
	)
	(gr_line
		(start 66.594736 -76.891896)
		(end 66.5988 -76.911708)
		(stroke
			(width 0.05715)
			(type default)
		)
		(layer "In9.Cu")
	)
	(gr_line
		(start 66.59499 -76.930758)
		(end 66.5988 -76.911708)
		(stroke
			(width 0.05715)
			(type default)
		)
		(layer "In9.Cu")
	)
	(gr_line
		(start 66.60388 -103.01224)
		(end 66.616072 -103.030274)
		(stroke
			(width 0.05715)
			(type default)
		)
		(layer "In9.Cu")
	)
	(gr_line
		(start 66.616072 -103.030274)
		(end 66.634106 -103.042466)
		(stroke
			(width 0.05715)
			(type default)
		)
		(layer "In9.Cu")
	)
	(gr_line
		(start 66.81724 -100.954586)
		(end 66.820796 -100.973382)
		(stroke
			(width 0.05715)
			(type default)
		)
		(layer "In9.Cu")
	)
	(gr_line
		(start 66.820796 -100.973382)
		(end 66.831464 -100.98913)
		(stroke
			(width 0.05715)
			(type default)
		)
		(layer "In9.Cu")
	)
	(gr_line
		(start 67.031108 -102.4509)
		(end 67.0433 -102.468934)
		(stroke
			(width 0.05715)
			(type default)
		)
		(layer "In9.Cu")
	)
	(gr_line
		(start 67.0433 -102.468934)
		(end 67.061334 -102.481126)
		(stroke
			(width 0.05715)
			(type default)
		)
		(layer "In9.Cu")
	)
	(gr_line
		(start 67.247516 -76.94422)
		(end 67.25158 -76.924408)
		(stroke
			(width 0.05715)
			(type default)
		)
		(layer "In9.Cu")
	)
	(gr_line
		(start 67.247516 -76.90485)
		(end 67.25158 -76.924408)
		(stroke
			(width 0.05715)
			(type default)
		)
		(layer "In9.Cu")
	)
	(gr_line
		(start 67.411346 -101.860096)
		(end 67.423538 -101.87813)
		(stroke
			(width 0.05715)
			(type default)
		)
		(layer "In9.Cu")
	)
	(gr_line
		(start 67.423538 -101.87813)
		(end 67.441572 -101.890322)
		(stroke
			(width 0.05715)
			(type default)
		)
		(layer "In9.Cu")
	)
	(gr_line
		(start 67.510152 -100.812854)
		(end 67.513962 -100.83292)
		(stroke
			(width 0.05715)
			(type default)
		)
		(layer "In9.Cu")
	)
	(gr_line
		(start 67.513962 -100.83292)
		(end 67.525646 -100.8507)
		(stroke
			(width 0.05715)
			(type default)
		)
		(layer "In9.Cu")
	)
	(gr_line
		(start 67.835272 -101.31552)
		(end 67.846702 -101.332538)
		(stroke
			(width 0.05715)
			(type default)
		)
		(layer "In9.Cu")
	)
	(gr_line
		(start 67.846702 -101.332538)
		(end 67.862958 -101.343206)
		(stroke
			(width 0.05715)
			(type default)
		)
		(layer "In9.Cu")
	)
	(gr_line
		(start 67.917822 -76.879958)
		(end 67.921886 -76.89977)
		(stroke
			(width 0.05715)
			(type default)
		)
		(layer "In9.Cu")
	)
	(gr_line
		(start 67.918076 -76.91882)
		(end 67.921886 -76.89977)
		(stroke
			(width 0.05715)
			(type default)
		)
		(layer "In9.Cu")
	)
	(gr_line
		(start 68.221098 -112.104932)
		(end 68.600828 -112.357916)
		(stroke
			(width 0.05715)
			(type default)
		)
		(layer "In9.Cu")
	)
	(gr_line
		(start 68.357242 -111.841534)
		(end 68.48221 -111.816388)
		(stroke
			(width 0.05715)
			(type default)
		)
		(layer "In9.Cu")
	)
	(gr_line
		(start 68.48221 -111.816388)
		(end 68.768214 -112.006888)
		(stroke
			(width 0.05715)
			(type default)
		)
		(layer "In9.Cu")
	)
	(gr_line
		(start 68.540884 -108.5215)
		(end 68.55714 -108.532168)
		(stroke
			(width 0.05715)
			(type default)
		)
		(layer "In9.Cu")
	)
	(gr_line
		(start 68.55714 -108.532168)
		(end 68.57619 -108.535978)
		(stroke
			(width 0.05715)
			(type default)
		)
		(layer "In9.Cu")
	)
	(gr_line
		(start 68.580254 -109.408468)
		(end 68.59651 -109.419136)
		(stroke
			(width 0.05715)
			(type default)
		)
		(layer "In9.Cu")
	)
	(gr_line
		(start 68.59651 -109.419136)
		(end 68.61556 -109.422946)
		(stroke
			(width 0.05715)
			(type default)
		)
		(layer "In9.Cu")
	)
	(gr_line
		(start 68.625974 -107.586526)
		(end 68.642992 -107.597702)
		(stroke
			(width 0.05715)
			(type default)
		)
		(layer "In9.Cu")
	)
	(gr_line
		(start 68.642992 -107.597702)
		(end 68.66128 -107.601258)
		(stroke
			(width 0.05715)
			(type default)
		)
		(layer "In9.Cu")
	)
	(gr_line
		(start 68.768214 -112.006888)
		(end 68.792852 -112.131856)
		(stroke
			(width 0.05715)
			(type default)
		)
		(layer "In9.Cu")
	)
	(gr_line
		(start 68.856606 -106.961686)
		(end 68.874386 -106.97337)
		(stroke
			(width 0.05715)
			(type default)
		)
		(layer "In9.Cu")
	)
	(gr_line
		(start 68.874386 -106.97337)
		(end 68.894452 -106.97718)
		(stroke
			(width 0.05715)
			(type default)
		)
		(layer "In9.Cu")
	)
	(gr_line
		(start 68.956428 -112.595152)
		(end 69.380354 -112.877854)
		(stroke
			(width 0.05715)
			(type default)
		)
		(layer "In9.Cu")
	)
	(gr_line
		(start 69.093334 -112.332262)
		(end 69.25437 -112.29975)
		(stroke
			(width 0.05715)
			(type default)
		)
		(layer "In9.Cu")
	)
	(gr_line
		(start 69.186298 -106.376978)
		(end 69.204078 -106.388662)
		(stroke
			(width 0.05715)
			(type default)
		)
		(layer "In9.Cu")
	)
	(gr_line
		(start 69.204078 -106.388662)
		(end 69.224144 -106.392472)
		(stroke
			(width 0.05715)
			(type default)
		)
		(layer "In9.Cu")
	)
	(gr_line
		(start 69.25437 -112.29975)
		(end 69.540374 -112.49025)
		(stroke
			(width 0.05715)
			(type default)
		)
		(layer "In9.Cu")
	)
	(gr_line
		(start 69.494654 -105.761282)
		(end 69.512434 -105.772966)
		(stroke
			(width 0.05715)
			(type default)
		)
		(layer "In9.Cu")
	)
	(gr_line
		(start 69.512434 -105.772966)
		(end 69.5325 -105.776776)
		(stroke
			(width 0.05715)
			(type default)
		)
		(layer "In9.Cu")
	)
	(gr_line
		(start 69.540374 -112.49025)
		(end 69.572124 -112.651286)
		(stroke
			(width 0.05715)
			(type default)
		)
		(layer "In9.Cu")
	)
	(gr_line
		(start 69.605144 -115.394232)
		(end 69.6214 -115.4049)
		(stroke
			(width 0.05715)
			(type default)
		)
		(layer "In9.Cu")
	)
	(gr_line
		(start 69.6214 -115.4049)
		(end 69.64045 -115.40871)
		(stroke
			(width 0.05715)
			(type default)
		)
		(layer "In9.Cu")
	)
	(gr_line
		(start 69.64807 -104.20477)
		(end 69.66585 -104.216454)
		(stroke
			(width 0.05715)
			(type default)
		)
		(layer "In9.Cu")
	)
	(gr_line
		(start 69.66585 -104.216454)
		(end 69.685916 -104.220264)
		(stroke
			(width 0.05715)
			(type default)
		)
		(layer "In9.Cu")
	)
	(gr_line
		(start 69.769736 -114.695478)
		(end 69.785992 -114.706146)
		(stroke
			(width 0.05715)
			(type default)
		)
		(layer "In9.Cu")
	)
	(gr_line
		(start 69.785992 -114.706146)
		(end 69.805042 -114.709956)
		(stroke
			(width 0.05715)
			(type default)
		)
		(layer "In9.Cu")
	)
	(gr_line
		(start 69.836538 -105.175812)
		(end 69.854318 -105.187496)
		(stroke
			(width 0.05715)
			(type default)
		)
		(layer "In9.Cu")
	)
	(gr_line
		(start 69.854318 -105.187496)
		(end 69.874384 -105.191306)
		(stroke
			(width 0.05715)
			(type default)
		)
		(layer "In9.Cu")
	)
	(gr_line
		(start 69.905118 -103.532178)
		(end 69.921374 -103.542846)
		(stroke
			(width 0.05715)
			(type default)
		)
		(layer "In9.Cu")
	)
	(gr_line
		(start 69.921374 -103.542846)
		(end 69.940424 -103.546656)
		(stroke
			(width 0.05715)
			(type default)
		)
		(layer "In9.Cu")
	)
	(gr_line
		(start 69.94144 -114.039142)
		(end 69.957696 -114.04981)
		(stroke
			(width 0.05715)
			(type default)
		)
		(layer "In9.Cu")
	)
	(gr_line
		(start 69.947028 -102.732332)
		(end 69.964808 -102.744016)
		(stroke
			(width 0.05715)
			(type default)
		)
		(layer "In9.Cu")
	)
	(gr_line
		(start 69.957696 -114.04981)
		(end 69.976746 -114.05362)
		(stroke
			(width 0.05715)
			(type default)
		)
		(layer "In9.Cu")
	)
	(gr_line
		(start 69.964808 -102.744016)
		(end 69.984874 -102.747826)
		(stroke
			(width 0.05715)
			(type default)
		)
		(layer "In9.Cu")
	)
	(gr_line
		(start 70.169024 -113.403634)
		(end 70.18528 -113.414302)
		(stroke
			(width 0.05715)
			(type default)
		)
		(layer "In9.Cu")
	)
	(gr_line
		(start 70.18528 -113.414302)
		(end 70.20433 -113.418112)
		(stroke
			(width 0.05715)
			(type default)
		)
		(layer "In9.Cu")
	)
	(gr_line
		(start 70.891146 -112.893094)
		(end 70.907402 -112.903762)
		(stroke
			(width 0.05715)
			(type default)
		)
		(layer "In9.Cu")
	)
	(gr_line
		(start 70.907402 -112.903762)
		(end 70.926452 -112.907572)
		(stroke
			(width 0.05715)
			(type default)
		)
		(layer "In9.Cu")
	)
	(gr_line
		(start 71.412608 -112.321848)
		(end 71.428864 -112.332516)
		(stroke
			(width 0.05715)
			(type default)
		)
		(layer "In9.Cu")
	)
	(gr_line
		(start 71.428864 -112.332516)
		(end 71.447914 -112.336326)
		(stroke
			(width 0.05715)
			(type default)
		)
		(layer "In9.Cu")
	)
	(gr_line
		(start 74.306176 -110.561374)
		(end 74.325226 -110.565184)
		(stroke
			(width 0.05715)
			(type default)
		)
		(layer "In9.Cu")
	)
	(gr_line
		(start 74.325226 -110.565184)
		(end 74.344276 -110.561374)
		(stroke
			(width 0.05715)
			(type default)
		)
		(layer "In9.Cu")
	)
	(gr_line
		(start 74.724514 -109.766354)
		(end 74.743564 -109.770164)
		(stroke
			(width 0.05715)
			(type default)
		)
		(layer "In9.Cu")
	)
	(gr_line
		(start 74.743564 -109.770164)
		(end 74.762614 -109.766354)
		(stroke
			(width 0.05715)
			(type default)
		)
		(layer "In9.Cu")
	)
	(gr_line
		(start 75.094084 -108.886244)
		(end 75.113134 -108.890054)
		(stroke
			(width 0.05715)
			(type default)
		)
		(layer "In9.Cu")
	)
	(gr_line
		(start 75.113134 -108.890054)
		(end 75.132184 -108.886244)
		(stroke
			(width 0.05715)
			(type default)
		)
		(layer "In9.Cu")
	)
	(gr_line
		(start 75.148186 -108.227114)
		(end 75.167236 -108.230924)
		(stroke
			(width 0.05715)
			(type default)
		)
		(layer "In9.Cu")
	)
	(gr_line
		(start 75.148694 -107.576874)
		(end 75.167744 -107.580684)
		(stroke
			(width 0.05715)
			(type default)
		)
		(layer "In9.Cu")
	)
	(gr_line
		(start 75.167236 -108.230924)
		(end 75.186286 -108.227114)
		(stroke
			(width 0.05715)
			(type default)
		)
		(layer "In9.Cu")
	)
	(gr_line
		(start 75.167744 -107.580684)
		(end 75.186794 -107.576874)
		(stroke
			(width 0.05715)
			(type default)
		)
		(layer "In9.Cu")
	)
	(gr_line
		(start 75.222354 -106.914188)
		(end 75.241404 -106.917998)
		(stroke
			(width 0.05715)
			(type default)
		)
		(layer "In9.Cu")
	)
	(gr_line
		(start 75.234038 -106.26344)
		(end 75.253088 -106.26725)
		(stroke
			(width 0.05715)
			(type default)
		)
		(layer "In9.Cu")
	)
	(gr_line
		(start 75.253088 -106.26725)
		(end 75.272138 -106.26344)
		(stroke
			(width 0.05715)
			(type default)
		)
		(layer "In9.Cu")
	)
	(gr_line
		(start 75.943968 -105.471722)
		(end 75.963018 -105.475532)
		(stroke
			(width 0.05715)
			(type default)
		)
		(layer "In9.Cu")
	)
	(gr_line
		(start 75.963018 -105.475532)
		(end 75.982068 -105.471722)
		(stroke
			(width 0.05715)
			(type default)
		)
		(layer "In9.Cu")
	)
	(gr_line
		(start 76.133198 -104.78516)
		(end 76.152248 -104.78897)
		(stroke
			(width 0.05715)
			(type default)
		)
		(layer "In9.Cu")
	)
	(gr_line
		(start 76.152248 -104.78897)
		(end 76.171298 -104.78516)
		(stroke
			(width 0.05715)
			(type default)
		)
		(layer "In9.Cu")
	)
	(gr_line
		(start 76.159868 -103.982774)
		(end 76.178918 -103.986584)
		(stroke
			(width 0.05715)
			(type default)
		)
		(layer "In9.Cu")
	)
	(gr_line
		(start 76.178918 -103.986584)
		(end 76.197968 -103.982774)
		(stroke
			(width 0.05715)
			(type default)
		)
		(layer "In9.Cu")
	)
	(gr_line
		(start 82.945732 -118.069614)
		(end 82.964782 -118.073424)
		(stroke
			(width 0.05715)
			(type default)
		)
		(layer "In9.Cu")
	)
	(gr_line
		(start 82.964782 -118.073424)
		(end 82.983832 -118.069614)
		(stroke
			(width 0.05715)
			(type default)
		)
		(layer "In9.Cu")
	)
	(gr_line
		(start 83.02244 -115.326922)
		(end 83.04149 -115.330732)
		(stroke
			(width 0.05715)
			(type default)
		)
		(layer "In9.Cu")
	)
	(gr_line
		(start 83.04149 -115.330732)
		(end 83.06054 -115.326922)
		(stroke
			(width 0.05715)
			(type default)
		)
		(layer "In9.Cu")
	)
	(gr_line
		(start 83.05927 -114.659156)
		(end 83.07832 -114.662966)
		(stroke
			(width 0.05715)
			(type default)
		)
		(layer "In9.Cu")
	)
	(gr_line
		(start 83.07832 -114.662966)
		(end 83.09737 -114.659156)
		(stroke
			(width 0.05715)
			(type default)
		)
		(layer "In9.Cu")
	)
	(gr_line
		(start 83.123024 -116.002308)
		(end 83.142074 -116.006118)
		(stroke
			(width 0.05715)
			(type default)
		)
		(layer "In9.Cu")
	)
	(gr_line
		(start 83.136232 -117.376448)
		(end 83.155282 -117.380258)
		(stroke
			(width 0.05715)
			(type default)
		)
		(layer "In9.Cu")
	)
	(gr_line
		(start 83.142074 -116.006118)
		(end 83.161124 -116.002308)
		(stroke
			(width 0.05715)
			(type default)
		)
		(layer "In9.Cu")
	)
	(gr_line
		(start 83.155282 -117.380258)
		(end 83.174332 -117.376448)
		(stroke
			(width 0.05715)
			(type default)
		)
		(layer "In9.Cu")
	)
	(gr_line
		(start 83.19135 -107.782614)
		(end 83.2104 -107.778804)
		(stroke
			(width 0.05715)
			(type default)
		)
		(layer "In9.Cu")
	)
	(gr_line
		(start 83.2104 -107.778804)
		(end 83.22945 -107.782614)
		(stroke
			(width 0.05715)
			(type default)
		)
		(layer "In9.Cu")
	)
	(gr_line
		(start 83.224624 -116.703094)
		(end 83.243674 -116.706904)
		(stroke
			(width 0.05715)
			(type default)
		)
		(layer "In9.Cu")
	)
	(gr_line
		(start 83.243674 -116.706904)
		(end 83.262724 -116.703094)
		(stroke
			(width 0.05715)
			(type default)
		)
		(layer "In9.Cu")
	)
	(gr_line
		(start 83.281012 -108.476288)
		(end 83.300062 -108.472478)
		(stroke
			(width 0.05715)
			(type default)
		)
		(layer "In9.Cu")
	)
	(gr_line
		(start 83.300062 -108.472478)
		(end 83.319112 -108.476288)
		(stroke
			(width 0.05715)
			(type default)
		)
		(layer "In9.Cu")
	)
	(gr_line
		(start 83.3247 -106.30154)
		(end 83.34375 -106.29773)
		(stroke
			(width 0.05715)
			(type default)
		)
		(layer "In9.Cu")
	)
	(gr_line
		(start 83.326732 -106.949748)
		(end 83.345782 -106.945938)
		(stroke
			(width 0.05715)
			(type default)
		)
		(layer "In9.Cu")
	)
	(gr_line
		(start 83.345782 -106.945938)
		(end 83.364832 -106.949748)
		(stroke
			(width 0.05715)
			(type default)
		)
		(layer "In9.Cu")
	)
	(gr_line
		(start 83.520534 -105.61193)
		(end 83.539584 -105.60812)
		(stroke
			(width 0.05715)
			(type default)
		)
		(layer "In9.Cu")
	)
	(gr_line
		(start 83.539584 -105.60812)
		(end 83.558634 -105.61193)
		(stroke
			(width 0.05715)
			(type default)
		)
		(layer "In9.Cu")
	)
	(gr_line
		(start 83.580224 -104.952292)
		(end 83.599274 -104.948482)
		(stroke
			(width 0.05715)
			(type default)
		)
		(layer "In9.Cu")
	)
	(gr_line
		(start 83.599274 -104.948482)
		(end 83.618324 -104.952292)
		(stroke
			(width 0.05715)
			(type default)
		)
		(layer "In9.Cu")
	)
	(gr_line
		(start 83.63966 -104.291892)
		(end 83.65871 -104.288082)
		(stroke
			(width 0.05715)
			(type default)
		)
		(layer "In9.Cu")
	)
	(gr_line
		(start 83.65871 -104.288082)
		(end 83.67776 -104.291892)
		(stroke
			(width 0.05715)
			(type default)
		)
		(layer "In9.Cu")
	)
	(gr_line
		(start 83.729576 -102.975664)
		(end 83.748626 -102.971854)
		(stroke
			(width 0.05715)
			(type default)
		)
		(layer "In9.Cu")
	)
	(gr_line
		(start 83.732116 -103.623872)
		(end 83.751166 -103.620062)
		(stroke
			(width 0.05715)
			(type default)
		)
		(layer "In9.Cu")
	)
	(gr_line
		(start 84.253832 -102.07371)
		(end 84.272882 -102.0699)
		(stroke
			(width 0.05715)
			(type default)
		)
		(layer "In9.Cu")
	)
	(gr_line
		(start 84.272882 -102.0699)
		(end 84.291932 -102.07371)
		(stroke
			(width 0.05715)
			(type default)
		)
		(layer "In9.Cu")
	)
	(gr_line
		(start 90.939874 -116.18087)
		(end 90.958924 -116.17706)
		(stroke
			(width 0.05715)
			(type default)
		)
		(layer "In9.Cu")
	)
	(gr_line
		(start 90.958924 -116.17706)
		(end 90.977974 -116.18087)
		(stroke
			(width 0.05715)
			(type default)
		)
		(layer "In9.Cu")
	)
	(gr_line
		(start 92.260166 -115.261136)
		(end 92.279216 -115.257326)
		(stroke
			(width 0.05715)
			(type default)
		)
		(layer "In9.Cu")
	)
	(gr_line
		(start 92.279216 -115.257326)
		(end 92.298266 -115.261136)
		(stroke
			(width 0.05715)
			(type default)
		)
		(layer "In9.Cu")
	)
	(gr_line
		(start 92.337636 -105.635298)
		(end 92.356686 -105.639108)
		(stroke
			(width 0.05715)
			(type default)
		)
		(layer "In9.Cu")
	)
	(gr_line
		(start 92.337636 -104.987598)
		(end 92.356686 -104.991408)
		(stroke
			(width 0.05715)
			(type default)
		)
		(layer "In9.Cu")
	)
	(gr_line
		(start 92.356686 -105.639108)
		(end 92.375736 -105.635298)
		(stroke
			(width 0.05715)
			(type default)
		)
		(layer "In9.Cu")
	)
	(gr_line
		(start 92.461842 -107.01909)
		(end 92.480892 -107.0229)
		(stroke
			(width 0.05715)
			(type default)
		)
		(layer "In9.Cu")
	)
	(gr_line
		(start 92.461842 -106.346752)
		(end 92.480892 -106.350562)
		(stroke
			(width 0.05715)
			(type default)
		)
		(layer "In9.Cu")
	)
	(gr_line
		(start 92.480892 -107.0229)
		(end 92.499942 -107.01909)
		(stroke
			(width 0.05715)
			(type default)
		)
		(layer "In9.Cu")
	)
	(gr_line
		(start 92.480892 -106.350562)
		(end 92.499942 -106.346752)
		(stroke
			(width 0.05715)
			(type default)
		)
		(layer "In9.Cu")
	)
	(gr_line
		(start 92.55633 -104.024684)
		(end 92.57538 -104.028494)
		(stroke
			(width 0.05715)
			(type default)
		)
		(layer "In9.Cu")
	)
	(gr_line
		(start 92.57538 -104.028494)
		(end 92.59443 -104.024684)
		(stroke
			(width 0.05715)
			(type default)
		)
		(layer "In9.Cu")
	)
	(gr_line
		(start 92.628466 -109.96041)
		(end 92.647516 -109.96422)
		(stroke
			(width 0.05715)
			(type default)
		)
		(layer "In9.Cu")
	)
	(gr_line
		(start 92.647516 -109.96422)
		(end 92.666566 -109.96041)
		(stroke
			(width 0.05715)
			(type default)
		)
		(layer "In9.Cu")
	)
	(gr_line
		(start 92.667328 -107.73156)
		(end 92.686378 -107.73537)
		(stroke
			(width 0.05715)
			(type default)
		)
		(layer "In9.Cu")
	)
	(gr_line
		(start 92.686378 -107.73537)
		(end 92.705428 -107.73156)
		(stroke
			(width 0.05715)
			(type default)
		)
		(layer "In9.Cu")
	)
	(gr_line
		(start 92.68841 -108.464604)
		(end 92.70746 -108.468414)
		(stroke
			(width 0.05715)
			(type default)
		)
		(layer "In9.Cu")
	)
	(gr_line
		(start 92.70746 -108.468414)
		(end 92.72651 -108.464604)
		(stroke
			(width 0.05715)
			(type default)
		)
		(layer "In9.Cu")
	)
	(gr_line
		(start 92.745814 -109.123988)
		(end 92.764864 -109.127798)
		(stroke
			(width 0.05715)
			(type default)
		)
		(layer "In9.Cu")
	)
	(gr_line
		(start 92.764102 -110.662974)
		(end 92.783152 -110.666784)
		(stroke
			(width 0.05715)
			(type default)
		)
		(layer "In9.Cu")
	)
	(gr_line
		(start 92.764864 -109.127798)
		(end 92.783914 -109.123988)
		(stroke
			(width 0.05715)
			(type default)
		)
		(layer "In9.Cu")
	)
	(gr_line
		(start 92.783152 -110.666784)
		(end 92.802202 -110.662974)
		(stroke
			(width 0.05715)
			(type default)
		)
		(layer "In9.Cu")
	)
	(gr_line
		(start 93.366844 -114.384582)
		(end 93.385894 -114.380772)
		(stroke
			(width 0.05715)
			(type default)
		)
		(layer "In9.Cu")
	)
	(gr_line
		(start 93.385894 -114.380772)
		(end 93.404944 -114.384582)
		(stroke
			(width 0.05715)
			(type default)
		)
		(layer "In9.Cu")
	)
	(gr_line
		(start 94.331028 -113.470436)
		(end 94.350078 -113.466626)
		(stroke
			(width 0.05715)
			(type default)
		)
		(layer "In9.Cu")
	)
	(gr_line
		(start 94.350078 -113.466626)
		(end 94.369128 -113.470436)
		(stroke
			(width 0.05715)
			(type default)
		)
		(layer "In9.Cu")
	)
	(gr_line
		(start 95.553784 -112.529874)
		(end 95.572834 -112.526064)
		(stroke
			(width 0.05715)
			(type default)
		)
		(layer "In9.Cu")
	)
	(gr_line
		(start 95.572834 -112.526064)
		(end 95.591884 -112.529874)
		(stroke
			(width 0.05715)
			(type default)
		)
		(layer "In9.Cu")
	)
	(gr_line
		(start 96.452944 -109.634782)
		(end 96.472502 -109.630718)
		(stroke
			(width 0.05715)
			(type default)
		)
		(layer "In9.Cu")
	)
	(gr_line
		(start 96.472502 -109.630718)
		(end 96.491552 -109.634528)
		(stroke
			(width 0.05715)
			(type default)
		)
		(layer "In9.Cu")
	)
	(gr_line
		(start 96.900746 -108.815632)
		(end 96.919796 -108.819442)
		(stroke
			(width 0.05715)
			(type default)
		)
		(layer "In9.Cu")
	)
	(gr_line
		(start 97.091754 -111.562134)
		(end 97.110804 -111.558324)
		(stroke
			(width 0.05715)
			(type default)
		)
		(layer "In9.Cu")
	)
	(gr_line
		(start 97.110804 -111.558324)
		(end 97.129854 -111.562134)
		(stroke
			(width 0.05715)
			(type default)
		)
		(layer "In9.Cu")
	)
	(gr_line
		(start 97.14865 -113.140236)
		(end 97.733358 -113.257584)
		(stroke
			(width 0.05715)
			(type default)
		)
		(layer "In9.Cu")
	)
	(gr_line
		(start 97.170748 -112.844072)
		(end 97.362264 -112.716818)
		(stroke
			(width 0.05715)
			(type default)
		)
		(layer "In9.Cu")
	)
	(gr_line
		(start 97.262442 -5.799582)
		(end 97.304606 -5.799582)
		(stroke
			(width 0.050546)
			(type default)
		)
		(layer "In9.Cu")
	)
	(gr_line
		(start 97.362264 -112.716818)
		(end 97.698306 -112.784128)
		(stroke
			(width 0.05715)
			(type default)
		)
		(layer "In9.Cu")
	)
	(gr_line
		(start 97.519744 -102.74173)
		(end 97.538794 -102.73792)
		(stroke
			(width 0.05715)
			(type default)
		)
		(layer "In9.Cu")
	)
	(gr_line
		(start 97.538794 -102.73792)
		(end 97.557844 -102.74173)
		(stroke
			(width 0.05715)
			(type default)
		)
		(layer "In9.Cu")
	)
	(gr_line
		(start 97.679256 -5.581142)
		(end 97.72142 -5.581142)
		(stroke
			(width 0.050546)
			(type default)
		)
		(layer "In9.Cu")
	)
	(gr_line
		(start 97.698306 -112.784128)
		(end 97.826068 -112.975644)
		(stroke
			(width 0.05715)
			(type default)
		)
		(layer "In9.Cu")
	)
	(gr_line
		(start 97.90049 -104.232456)
		(end 97.91954 -104.228646)
		(stroke
			(width 0.05715)
			(type default)
		)
		(layer "In9.Cu")
	)
	(gr_line
		(start 97.91954 -104.228646)
		(end 97.93859 -104.232456)
		(stroke
			(width 0.05715)
			(type default)
		)
		(layer "In9.Cu")
	)
	(gr_line
		(start 97.962212 -107.790488)
		(end 97.981262 -107.786678)
		(stroke
			(width 0.05715)
			(type default)
		)
		(layer "In9.Cu")
	)
	(gr_line
		(start 97.981262 -107.786678)
		(end 98.000312 -107.790488)
		(stroke
			(width 0.05715)
			(type default)
		)
		(layer "In9.Cu")
	)
	(gr_line
		(start 98.024696 -106.369866)
		(end 98.043746 -106.366056)
		(stroke
			(width 0.05715)
			(type default)
		)
		(layer "In9.Cu")
	)
	(gr_line
		(start 98.02495 -105.616248)
		(end 98.044 -105.612438)
		(stroke
			(width 0.05715)
			(type default)
		)
		(layer "In9.Cu")
	)
	(gr_line
		(start 98.02495 -104.94391)
		(end 98.044 -104.9401)
		(stroke
			(width 0.05715)
			(type default)
		)
		(layer "In9.Cu")
	)
	(gr_line
		(start 98.043746 -106.366056)
		(end 98.062796 -106.369866)
		(stroke
			(width 0.05715)
			(type default)
		)
		(layer "In9.Cu")
	)
	(gr_line
		(start 98.044 -105.612438)
		(end 98.06305 -105.616248)
		(stroke
			(width 0.05715)
			(type default)
		)
		(layer "In9.Cu")
	)
	(gr_line
		(start 98.044 -104.9401)
		(end 98.06305 -104.94391)
		(stroke
			(width 0.05715)
			(type default)
		)
		(layer "In9.Cu")
	)
	(gr_line
		(start 98.076512 -107.096814)
		(end 98.095562 -107.093004)
		(stroke
			(width 0.05715)
			(type default)
		)
		(layer "In9.Cu")
	)
	(gr_line
		(start 98.095562 -107.093004)
		(end 98.114612 -107.096814)
		(stroke
			(width 0.05715)
			(type default)
		)
		(layer "In9.Cu")
	)
	(gr_line
		(start 98.154236 -103.533956)
		(end 98.173286 -103.530146)
		(stroke
			(width 0.05715)
			(type default)
		)
		(layer "In9.Cu")
	)
	(gr_line
		(start 98.173286 -103.530146)
		(end 98.192336 -103.533956)
		(stroke
			(width 0.05715)
			(type default)
		)
		(layer "In9.Cu")
	)
	(gr_line
		(start 98.381058 -117.95887)
		(end 98.400108 -117.96268)
		(stroke
			(width 0.05715)
			(type default)
		)
		(layer "In9.Cu")
	)
	(gr_line
		(start 98.392996 -115.68049)
		(end 98.412046 -115.6843)
		(stroke
			(width 0.05715)
			(type default)
		)
		(layer "In9.Cu")
	)
	(gr_line
		(start 98.400108 -117.96268)
		(end 98.419158 -117.95887)
		(stroke
			(width 0.05715)
			(type default)
		)
		(layer "In9.Cu")
	)
	(gr_line
		(start 98.412046 -115.6843)
		(end 98.431096 -115.68049)
		(stroke
			(width 0.05715)
			(type default)
		)
		(layer "In9.Cu")
	)
	(gr_line
		(start 98.417888 -116.78285)
		(end 98.436938 -116.78666)
		(stroke
			(width 0.05715)
			(type default)
		)
		(layer "In9.Cu")
	)
	(gr_line
		(start 98.436938 -116.78666)
		(end 98.455988 -116.78285)
		(stroke
			(width 0.05715)
			(type default)
		)
		(layer "In9.Cu")
	)
	(gr_line
		(start 98.660204 -114.62639)
		(end 98.679254 -114.6302)
		(stroke
			(width 0.05715)
			(type default)
		)
		(layer "In9.Cu")
	)
	(gr_line
		(start 98.679254 -114.6302)
		(end 98.698304 -114.62639)
		(stroke
			(width 0.05715)
			(type default)
		)
		(layer "In9.Cu")
	)
	(gr_line
		(start 99.141026 -113.540032)
		(end 99.160076 -113.543842)
		(stroke
			(width 0.05715)
			(type default)
		)
		(layer "In9.Cu")
	)
	(gr_line
		(start 99.160076 -113.543842)
		(end 99.179126 -113.540032)
		(stroke
			(width 0.05715)
			(type default)
		)
		(layer "In9.Cu")
	)
	(gr_line
		(start 99.31781 -5.581142)
		(end 99.362768 -5.581142)
		(stroke
			(width 0.050546)
			(type default)
		)
		(layer "In9.Cu")
	)
	(gr_line
		(start 99.734624 -5.802376)
		(end 99.779582 -5.802376)
		(stroke
			(width 0.050546)
			(type default)
		)
		(layer "In9.Cu")
	)
	(gr_line
		(start 100.391722 -112.512348)
		(end 100.410772 -112.516158)
		(stroke
			(width 0.05715)
			(type default)
		)
		(layer "In9.Cu")
	)
	(gr_line
		(start 100.410772 -112.516158)
		(end 100.429822 -112.512348)
		(stroke
			(width 0.05715)
			(type default)
		)
		(layer "In9.Cu")
	)
	(gr_line
		(start 101.636576 -114.739166)
		(end 101.764084 -114.547904)
		(stroke
			(width 0.05715)
			(type default)
		)
		(layer "In9.Cu")
	)
	(gr_line
		(start 101.72954 -115.021106)
		(end 102.31501 -114.904012)
		(stroke
			(width 0.05715)
			(type default)
		)
		(layer "In9.Cu")
	)
	(gr_line
		(start 101.764084 -114.547904)
		(end 102.10038 -114.480594)
		(stroke
			(width 0.05715)
			(type default)
		)
		(layer "In9.Cu")
	)
	(gr_line
		(start 102.10038 -114.480594)
		(end 102.291642 -114.608356)
		(stroke
			(width 0.05715)
			(type default)
		)
		(layer "In9.Cu")
	)
	(gr_line
		(start 102.632764 -114.54003)
		(end 102.760272 -114.348768)
		(stroke
			(width 0.05715)
			(type default)
		)
		(layer "In9.Cu")
	)
	(gr_line
		(start 102.72522 -114.822224)
		(end 103.312214 -114.704876)
		(stroke
			(width 0.05715)
			(type default)
		)
		(layer "In9.Cu")
	)
	(gr_line
		(start 102.760272 -114.348768)
		(end 103.096568 -114.281458)
		(stroke
			(width 0.05715)
			(type default)
		)
		(layer "In9.Cu")
	)
	(gr_line
		(start 103.029004 -111.694468)
		(end 103.048054 -111.690658)
		(stroke
			(width 0.05715)
			(type default)
		)
		(layer "In9.Cu")
	)
	(gr_line
		(start 103.048054 -111.690658)
		(end 103.067104 -111.694468)
		(stroke
			(width 0.05715)
			(type default)
		)
		(layer "In9.Cu")
	)
	(gr_line
		(start 103.096568 -114.281458)
		(end 103.288084 -114.40922)
		(stroke
			(width 0.05715)
			(type default)
		)
		(layer "In9.Cu")
	)
	(gr_line
		(start 103.21417 -112.435132)
		(end 103.23322 -112.431322)
		(stroke
			(width 0.05715)
			(type default)
		)
		(layer "In9.Cu")
	)
	(gr_line
		(start 103.23322 -112.431322)
		(end 103.25227 -112.435132)
		(stroke
			(width 0.05715)
			(type default)
		)
		(layer "In9.Cu")
	)
	(gr_line
		(start 103.629206 -114.340894)
		(end 103.756714 -114.149632)
		(stroke
			(width 0.05715)
			(type default)
		)
		(layer "In9.Cu")
	)
	(gr_line
		(start 103.72217 -114.622834)
		(end 104.307386 -114.50574)
		(stroke
			(width 0.05715)
			(type default)
		)
		(layer "In9.Cu")
	)
	(gr_line
		(start 103.756714 -114.149632)
		(end 104.092756 -114.082322)
		(stroke
			(width 0.05715)
			(type default)
		)
		(layer "In9.Cu")
	)
	(gr_line
		(start 103.976932 -113.273078)
		(end 103.995982 -113.269268)
		(stroke
			(width 0.05715)
			(type default)
		)
		(layer "In9.Cu")
	)
	(gr_line
		(start 103.995982 -113.269268)
		(end 104.015032 -113.273078)
		(stroke
			(width 0.05715)
			(type default)
		)
		(layer "In9.Cu")
	)
	(gr_line
		(start 104.092756 -114.082322)
		(end 104.284272 -114.210084)
		(stroke
			(width 0.05715)
			(type default)
		)
		(layer "In9.Cu")
	)
	(gr_line
		(start 104.255062 -116.489988)
		(end 104.382824 -116.298472)
		(stroke
			(width 0.05715)
			(type default)
		)
		(layer "In9.Cu")
	)
	(gr_line
		(start 104.348026 -116.771674)
		(end 104.93248 -116.654834)
		(stroke
			(width 0.05715)
			(type default)
		)
		(layer "In9.Cu")
	)
	(gr_line
		(start 104.382824 -116.298472)
		(end 104.718866 -116.231162)
		(stroke
			(width 0.05715)
			(type default)
		)
		(layer "In9.Cu")
	)
	(gr_line
		(start 104.718866 -116.231162)
		(end 104.910382 -116.358924)
		(stroke
			(width 0.05715)
			(type default)
		)
		(layer "In9.Cu")
	)
	(gr_line
		(start 104.827578 -114.103912)
		(end 104.846628 -114.100102)
		(stroke
			(width 0.05715)
			(type default)
		)
		(layer "In9.Cu")
	)
	(gr_line
		(start 104.846628 -114.100102)
		(end 104.865678 -114.103912)
		(stroke
			(width 0.05715)
			(type default)
		)
		(layer "In9.Cu")
	)
	(gr_line
		(start 105.25125 -116.290598)
		(end 105.378758 -116.099082)
		(stroke
			(width 0.05715)
			(type default)
		)
		(layer "In9.Cu")
	)
	(gr_line
		(start 105.344976 -116.57203)
		(end 105.92816 -116.455444)
		(stroke
			(width 0.05715)
			(type default)
		)
		(layer "In9.Cu")
	)
	(gr_line
		(start 105.378758 -116.099082)
		(end 105.715054 -116.031772)
		(stroke
			(width 0.05715)
			(type default)
		)
		(layer "In9.Cu")
	)
	(gr_line
		(start 105.715054 -116.031772)
		(end 105.90657 -116.15928)
		(stroke
			(width 0.05715)
			(type default)
		)
		(layer "In9.Cu")
	)
	(gr_line
		(start 105.946448 -114.988086)
		(end 105.965498 -114.984276)
		(stroke
			(width 0.05715)
			(type default)
		)
		(layer "In9.Cu")
	)
	(gr_line
		(start 105.965498 -114.984276)
		(end 105.984548 -114.988086)
		(stroke
			(width 0.05715)
			(type default)
		)
		(layer "In9.Cu")
	)
	(gr_line
		(start 106.247692 -116.091208)
		(end 106.3752 -115.899692)
		(stroke
			(width 0.05715)
			(type default)
		)
		(layer "In9.Cu")
	)
	(gr_line
		(start 106.341926 -116.372386)
		(end 106.924602 -116.256054)
		(stroke
			(width 0.05715)
			(type default)
		)
		(layer "In9.Cu")
	)
	(gr_line
		(start 106.3752 -115.899692)
		(end 106.711242 -115.832382)
		(stroke
			(width 0.05715)
			(type default)
		)
		(layer "In9.Cu")
	)
	(gr_line
		(start 106.381296 -111.00943)
		(end 106.400346 -111.01324)
		(stroke
			(width 0.05715)
			(type default)
		)
		(layer "In9.Cu")
	)
	(gr_line
		(start 106.400346 -111.01324)
		(end 106.419396 -111.00943)
		(stroke
			(width 0.05715)
			(type default)
		)
		(layer "In9.Cu")
	)
	(gr_line
		(start 106.67365 -109.82325)
		(end 106.6927 -109.82706)
		(stroke
			(width 0.05715)
			(type default)
		)
		(layer "In9.Cu")
	)
	(gr_line
		(start 106.6927 -109.82706)
		(end 106.71175 -109.82325)
		(stroke
			(width 0.05715)
			(type default)
		)
		(layer "In9.Cu")
	)
	(gr_line
		(start 106.711242 -115.832382)
		(end 106.902758 -115.95989)
		(stroke
			(width 0.05715)
			(type default)
		)
		(layer "In9.Cu")
	)
	(gr_line
		(start 106.72318 -106.287824)
		(end 106.74223 -106.291634)
		(stroke
			(width 0.05715)
			(type default)
		)
		(layer "In9.Cu")
	)
	(gr_line
		(start 106.723434 -108.400342)
		(end 106.742484 -108.404152)
		(stroke
			(width 0.05715)
			(type default)
		)
		(layer "In9.Cu")
	)
	(gr_line
		(start 106.723434 -107.646724)
		(end 106.742484 -107.650534)
		(stroke
			(width 0.05715)
			(type default)
		)
		(layer "In9.Cu")
	)
	(gr_line
		(start 106.723434 -106.974386)
		(end 106.742484 -106.978196)
		(stroke
			(width 0.05715)
			(type default)
		)
		(layer "In9.Cu")
	)
	(gr_line
		(start 106.74223 -106.291634)
		(end 106.76128 -106.287824)
		(stroke
			(width 0.05715)
			(type default)
		)
		(layer "In9.Cu")
	)
	(gr_line
		(start 106.742484 -108.404152)
		(end 106.761534 -108.400342)
		(stroke
			(width 0.05715)
			(type default)
		)
		(layer "In9.Cu")
	)
	(gr_line
		(start 106.742484 -107.650534)
		(end 106.761534 -107.646724)
		(stroke
			(width 0.05715)
			(type default)
		)
		(layer "In9.Cu")
	)
	(gr_line
		(start 106.742484 -106.978196)
		(end 106.761534 -106.974386)
		(stroke
			(width 0.05715)
			(type default)
		)
		(layer "In9.Cu")
	)
	(gr_line
		(start 106.838242 -109.13999)
		(end 106.857292 -109.1438)
		(stroke
			(width 0.05715)
			(type default)
		)
		(layer "In9.Cu")
	)
	(gr_line
		(start 106.857292 -109.1438)
		(end 106.876342 -109.13999)
		(stroke
			(width 0.05715)
			(type default)
		)
		(layer "In9.Cu")
	)
	(gr_line
		(start 106.857546 -104.900222)
		(end 106.876596 -104.904032)
		(stroke
			(width 0.05715)
			(type default)
		)
		(layer "In9.Cu")
	)
	(gr_line
		(start 106.876596 -104.904032)
		(end 106.895646 -104.900222)
		(stroke
			(width 0.05715)
			(type default)
		)
		(layer "In9.Cu")
	)
	(gr_line
		(start 106.975656 -105.58907)
		(end 106.994706 -105.59288)
		(stroke
			(width 0.05715)
			(type default)
		)
		(layer "In9.Cu")
	)
	(gr_line
		(start 106.994706 -105.59288)
		(end 107.013756 -105.58907)
		(stroke
			(width 0.05715)
			(type default)
		)
		(layer "In9.Cu")
	)
	(gr_line
		(start 107.03052 -110.589314)
		(end 107.61472 -110.472728)
		(stroke
			(width 0.05715)
			(type default)
		)
		(layer "In9.Cu")
	)
	(gr_line
		(start 107.052618 -110.885478)
		(end 107.243626 -111.012986)
		(stroke
			(width 0.05715)
			(type default)
		)
		(layer "In9.Cu")
	)
	(gr_line
		(start 107.222798 -115.898422)
		(end 107.241848 -115.894612)
		(stroke
			(width 0.05715)
			(type default)
		)
		(layer "In9.Cu")
	)
	(gr_line
		(start 107.241848 -115.894612)
		(end 107.260898 -115.898422)
		(stroke
			(width 0.05715)
			(type default)
		)
		(layer "In9.Cu")
	)
	(gr_line
		(start 107.243626 -111.012986)
		(end 107.579922 -110.94593)
		(stroke
			(width 0.05715)
			(type default)
		)
		(layer "In9.Cu")
	)
	(gr_line
		(start 107.579922 -110.94593)
		(end 107.707684 -110.754414)
		(stroke
			(width 0.05715)
			(type default)
		)
		(layer "In9.Cu")
	)
	(gr_line
		(start 108.026962 -110.390178)
		(end 108.611162 -110.273592)
		(stroke
			(width 0.05715)
			(type default)
		)
		(layer "In9.Cu")
	)
	(gr_line
		(start 108.048806 -110.686342)
		(end 108.240068 -110.81385)
		(stroke
			(width 0.05715)
			(type default)
		)
		(layer "In9.Cu")
	)
	(gr_line
		(start 108.240068 -110.81385)
		(end 108.576364 -110.74654)
		(stroke
			(width 0.05715)
			(type default)
		)
		(layer "In9.Cu")
	)
	(gr_line
		(start 108.576364 -110.74654)
		(end 108.704126 -110.555278)
		(stroke
			(width 0.05715)
			(type default)
		)
		(layer "In9.Cu")
	)
	(gr_line
		(start 109.714538 -108.924344)
		(end 109.733588 -108.920534)
		(stroke
			(width 0.05715)
			(type default)
		)
		(layer "In9.Cu")
	)
	(gr_line
		(start 109.733588 -108.920534)
		(end 109.752638 -108.924344)
		(stroke
			(width 0.05715)
			(type default)
		)
		(layer "In9.Cu")
	)
	(gr_line
		(start 110.052866 -108.20654)
		(end 110.071916 -108.20273)
		(stroke
			(width 0.05715)
			(type default)
		)
		(layer "In9.Cu")
	)
	(gr_line
		(start 110.071916 -108.20273)
		(end 110.090966 -108.20654)
		(stroke
			(width 0.05715)
			(type default)
		)
		(layer "In9.Cu")
	)
	(gr_line
		(start 110.240572 -107.40644)
		(end 110.259622 -107.40263)
		(stroke
			(width 0.05715)
			(type default)
		)
		(layer "In9.Cu")
	)
	(gr_line
		(start 110.258098 -106.649266)
		(end 110.277148 -106.645456)
		(stroke
			(width 0.05715)
			(type default)
		)
		(layer "In9.Cu")
	)
	(gr_line
		(start 110.259622 -107.40263)
		(end 110.278672 -107.40644)
		(stroke
			(width 0.05715)
			(type default)
		)
		(layer "In9.Cu")
	)
	(gr_line
		(start 110.277148 -106.645456)
		(end 110.296198 -106.649266)
		(stroke
			(width 0.05715)
			(type default)
		)
		(layer "In9.Cu")
	)
	(gr_line
		(start 110.399068 -109.91596)
		(end 110.418118 -109.91215)
		(stroke
			(width 0.05715)
			(type default)
		)
		(layer "In9.Cu")
	)
	(gr_line
		(start 110.418118 -109.91215)
		(end 110.437168 -109.91596)
		(stroke
			(width 0.05715)
			(type default)
		)
		(layer "In9.Cu")
	)
	(gr_line
		(start 110.534958 -105.92181)
		(end 110.554008 -105.918)
		(stroke
			(width 0.05715)
			(type default)
		)
		(layer "In9.Cu")
	)
	(gr_line
		(start 110.554008 -105.918)
		(end 110.573058 -105.92181)
		(stroke
			(width 0.05715)
			(type default)
		)
		(layer "In9.Cu")
	)
	(gr_line
		(start 110.92307 -105.15727)
		(end 110.94212 -105.15346)
		(stroke
			(width 0.05715)
			(type default)
		)
		(layer "In9.Cu")
	)
	(gr_line
		(start 110.94212 -105.15346)
		(end 110.96117 -105.15727)
		(stroke
			(width 0.05715)
			(type default)
		)
		(layer "In9.Cu")
	)
	(gr_line
		(start 111.32312 -104.429306)
		(end 111.34217 -104.425496)
		(stroke
			(width 0.05715)
			(type default)
		)
		(layer "In9.Cu")
	)
	(gr_line
		(start 111.64443 -103.652574)
		(end 111.66348 -103.648764)
		(stroke
			(width 0.05715)
			(type default)
		)
		(layer "In9.Cu")
	)
	(gr_line
		(start 111.66348 -103.648764)
		(end 111.68253 -103.652574)
		(stroke
			(width 0.05715)
			(type default)
		)
		(layer "In9.Cu")
	)
	(gr_line
		(start 114.703606 -110.212632)
		(end 114.722656 -110.216442)
		(stroke
			(width 0.05715)
			(type default)
		)
		(layer "In9.Cu")
	)
	(gr_line
		(start 114.722656 -110.216442)
		(end 114.741706 -110.212632)
		(stroke
			(width 0.05715)
			(type default)
		)
		(layer "In9.Cu")
	)
	(gr_line
		(start 114.815112 -111.089694)
		(end 114.836702 -111.094012)
		(stroke
			(width 0.05715)
			(type default)
		)
		(layer "In9.Cu")
	)
	(gr_line
		(start 114.836702 -111.094012)
		(end 114.837464 -111.093758)
		(stroke
			(width 0.05715)
			(type default)
		)
		(layer "In9.Cu")
	)
	(gr_line
		(start 114.837464 -111.093758)
		(end 114.856514 -111.089948)
		(stroke
			(width 0.05715)
			(type default)
		)
		(layer "In9.Cu")
	)
	(gr_line
		(start 115.02644 -109.49178)
		(end 115.04549 -109.49559)
		(stroke
			(width 0.05715)
			(type default)
		)
		(layer "In9.Cu")
	)
	(gr_line
		(start 115.04549 -109.49559)
		(end 115.06454 -109.49178)
		(stroke
			(width 0.05715)
			(type default)
		)
		(layer "In9.Cu")
	)
	(gr_line
		(start 115.15471 -110.732316)
		(end 115.739926 -110.615222)
		(stroke
			(width 0.05715)
			(type default)
		)
		(layer "In9.Cu")
	)
	(gr_line
		(start 115.176808 -111.02848)
		(end 115.36807 -111.155988)
		(stroke
			(width 0.05715)
			(type default)
		)
		(layer "In9.Cu")
	)
	(gr_line
		(start 115.36807 -111.155988)
		(end 115.704112 -111.088678)
		(stroke
			(width 0.05715)
			(type default)
		)
		(layer "In9.Cu")
	)
	(gr_line
		(start 115.4938 -108.747814)
		(end 115.51285 -108.751624)
		(stroke
			(width 0.05715)
			(type default)
		)
		(layer "In9.Cu")
	)
	(gr_line
		(start 115.51285 -108.751624)
		(end 115.5319 -108.747814)
		(stroke
			(width 0.05715)
			(type default)
		)
		(layer "In9.Cu")
	)
	(gr_line
		(start 115.704112 -111.088678)
		(end 115.831874 -110.897416)
		(stroke
			(width 0.05715)
			(type default)
		)
		(layer "In9.Cu")
	)
	(gr_line
		(start 115.764818 -108.041186)
		(end 115.783868 -108.044996)
		(stroke
			(width 0.05715)
			(type default)
		)
		(layer "In9.Cu")
	)
	(gr_line
		(start 115.783868 -108.044996)
		(end 115.802918 -108.041186)
		(stroke
			(width 0.05715)
			(type default)
		)
		(layer "In9.Cu")
	)
	(gr_line
		(start 116.000022 -107.305602)
		(end 116.019072 -107.309412)
		(stroke
			(width 0.05715)
			(type default)
		)
		(layer "In9.Cu")
	)
	(gr_line
		(start 116.019072 -107.309412)
		(end 116.038122 -107.305602)
		(stroke
			(width 0.05715)
			(type default)
		)
		(layer "In9.Cu")
	)
	(gr_line
		(start 116.360702 -106.53522)
		(end 116.379752 -106.53903)
		(stroke
			(width 0.05715)
			(type default)
		)
		(layer "In9.Cu")
	)
	(gr_line
		(start 116.379752 -106.53903)
		(end 116.398802 -106.53522)
		(stroke
			(width 0.05715)
			(type default)
		)
		(layer "In9.Cu")
	)
	(gr_line
		(start 116.549678 -113.921794)
		(end 117.134132 -114.038126)
		(stroke
			(width 0.05715)
			(type default)
		)
		(layer "In9.Cu")
	)
	(gr_line
		(start 116.57203 -113.626138)
		(end 116.763292 -113.498376)
		(stroke
			(width 0.05715)
			(type default)
		)
		(layer "In9.Cu")
	)
	(gr_line
		(start 116.68633 -105.79227)
		(end 116.70538 -105.79608)
		(stroke
			(width 0.05715)
			(type default)
		)
		(layer "In9.Cu")
	)
	(gr_line
		(start 116.70538 -105.79608)
		(end 116.72443 -105.79227)
		(stroke
			(width 0.05715)
			(type default)
		)
		(layer "In9.Cu")
	)
	(gr_line
		(start 116.763292 -113.498376)
		(end 117.099588 -113.565178)
		(stroke
			(width 0.05715)
			(type default)
		)
		(layer "In9.Cu")
	)
	(gr_line
		(start 117.099588 -113.565178)
		(end 117.22735 -113.75644)
		(stroke
			(width 0.05715)
			(type default)
		)
		(layer "In9.Cu")
	)
	(gr_line
		(start 117.12575 -105.039414)
		(end 117.1448 -105.043224)
		(stroke
			(width 0.05715)
			(type default)
		)
		(layer "In9.Cu")
	)
	(gr_line
		(start 117.1448 -105.043224)
		(end 117.16385 -105.039414)
		(stroke
			(width 0.05715)
			(type default)
		)
		(layer "In9.Cu")
	)
	(gr_line
		(start 122.835162 -115.945666)
		(end 122.854212 -115.949476)
		(stroke
			(width 0.05715)
			(type default)
		)
		(layer "In9.Cu")
	)
	(gr_line
		(start 122.854212 -115.949476)
		(end 122.873262 -115.945666)
		(stroke
			(width 0.05715)
			(type default)
		)
		(layer "In9.Cu")
	)
	(gr_line
		(start 122.882914 -115.79479)
		(end 131.341876 -114.100102)
		(stroke
			(width 0.1778)
			(type default)
		)
		(layer "In9.Cu")
	)
	(gr_line
		(start 122.941842 -116.670836)
		(end 122.960892 -116.674646)
		(stroke
			(width 0.05715)
			(type default)
		)
		(layer "In9.Cu")
	)
	(gr_line
		(start 122.960892 -116.674646)
		(end 122.979942 -116.670836)
		(stroke
			(width 0.05715)
			(type default)
		)
		(layer "In9.Cu")
	)
	(gr_line
		(start 122.979942 -117.364256)
		(end 122.998992 -117.368066)
		(stroke
			(width 0.05715)
			(type default)
		)
		(layer "In9.Cu")
	)
	(gr_line
		(start 122.998992 -117.368066)
		(end 123.018042 -117.364256)
		(stroke
			(width 0.05715)
			(type default)
		)
		(layer "In9.Cu")
	)
	(gr_line
		(start 123.006104 -118.028974)
		(end 123.025154 -118.032784)
		(stroke
			(width 0.05715)
			(type default)
		)
		(layer "In9.Cu")
	)
	(gr_line
		(start 123.025154 -118.032784)
		(end 123.044204 -118.028974)
		(stroke
			(width 0.05715)
			(type default)
		)
		(layer "In9.Cu")
	)
	(gr_line
		(start 123.028456 -118.6942)
		(end 123.047506 -118.69801)
		(stroke
			(width 0.05715)
			(type default)
		)
		(layer "In9.Cu")
	)
	(gr_line
		(start 123.047506 -118.69801)
		(end 123.066556 -118.6942)
		(stroke
			(width 0.05715)
			(type default)
		)
		(layer "In9.Cu")
	)
	(gr_line
		(start 123.080272 -115.22075)
		(end 123.09983 -115.224814)
		(stroke
			(width 0.05715)
			(type default)
		)
		(layer "In9.Cu")
	)
	(gr_line
		(start 123.09983 -115.224814)
		(end 123.119388 -115.22075)
		(stroke
			(width 0.05715)
			(type default)
		)
		(layer "In9.Cu")
	)
	(gr_line
		(start 123.128532 -119.36984)
		(end 123.147582 -119.37365)
		(stroke
			(width 0.05715)
			(type default)
		)
		(layer "In9.Cu")
	)
	(gr_line
		(start 123.147582 -119.37365)
		(end 123.166632 -119.36984)
		(stroke
			(width 0.05715)
			(type default)
		)
		(layer "In9.Cu")
	)
	(gr_line
		(start 125.139958 -94.242636)
		(end 125.144784 -94.234)
		(stroke
			(width 0.04445)
			(type default)
		)
		(layer "In9.Cu")
	)
	(gr_line
		(start 125.300232 -95.337122)
		(end 125.305058 -95.328486)
		(stroke
			(width 0.04445)
			(type default)
		)
		(layer "In9.Cu")
	)
	(gr_line
		(start 125.998478 -95.328486)
		(end 126.003304 -95.337122)
		(stroke
			(width 0.04445)
			(type default)
		)
		(layer "In9.Cu")
	)
	(gr_line
		(start 126.158752 -94.234)
		(end 126.163578 -94.242636)
		(stroke
			(width 0.04445)
			(type default)
		)
		(layer "In9.Cu")
	)
	(gr_line
		(start 127.017272 -95.337122)
		(end 127.022098 -95.328486)
		(stroke
			(width 0.04445)
			(type default)
		)
		(layer "In9.Cu")
	)
	(gr_arc
		(start 127.34671 -100.081334)
		(mid 127.790464 -100.065772)
		(end 128.227328 -99.986338)
		(stroke
			(width 0.04445)
			(type default)
		)
		(layer "In9.Cu")
	)
	(gr_line
		(start 127.353822 -99.890834)
		(end 127.383794 -99.890834)
		(stroke
			(width 0.04445)
			(type default)
		)
		(layer "In9.Cu")
	)
	(gr_line
		(start 127.368808 -98.500184)
		(end 127.661924 -98.331274)
		(stroke
			(width 0.04445)
			(type default)
		)
		(layer "In9.Cu")
	)
	(gr_arc
		(start 127.383794 -99.890834)
		(mid 127.707656 -99.826387)
		(end 127.982218 -99.64293)
		(stroke
			(width 0.04445)
			(type default)
		)
		(layer "In9.Cu")
	)
	(gr_line
		(start 127.655828 -107.33151)
		(end 127.674878 -107.3277)
		(stroke
			(width 0.05715)
			(type default)
		)
		(layer "In9.Cu")
	)
	(gr_line
		(start 127.661924 -98.331274)
		(end 127.685292 -98.243898)
		(stroke
			(width 0.04445)
			(type default)
		)
		(layer "In9.Cu")
	)
	(gr_line
		(start 127.674878 -107.3277)
		(end 127.693928 -107.33151)
		(stroke
			(width 0.05715)
			(type default)
		)
		(layer "In9.Cu")
	)
	(gr_line
		(start 127.709168 -94.748604)
		(end 127.715518 -94.737936)
		(stroke
			(width 0.04445)
			(type default)
		)
		(layer "In9.Cu")
	)
	(gr_line
		(start 127.715518 -95.328486)
		(end 127.720344 -95.337122)
		(stroke
			(width 0.04445)
			(type default)
		)
		(layer "In9.Cu")
	)
	(gr_line
		(start 127.756158 -106.655616)
		(end 127.775208 -106.651806)
		(stroke
			(width 0.05715)
			(type default)
		)
		(layer "In9.Cu")
	)
	(gr_line
		(start 127.775208 -106.651806)
		(end 127.794258 -106.655616)
		(stroke
			(width 0.05715)
			(type default)
		)
		(layer "In9.Cu")
	)
	(gr_line
		(start 127.793496 -108.204508)
		(end 127.812546 -108.200698)
		(stroke
			(width 0.05715)
			(type default)
		)
		(layer "In9.Cu")
	)
	(gr_line
		(start 127.812546 -108.200698)
		(end 127.831596 -108.204508)
		(stroke
			(width 0.05715)
			(type default)
		)
		(layer "In9.Cu")
	)
	(gr_line
		(start 127.821182 -105.992168)
		(end 127.840232 -105.988358)
		(stroke
			(width 0.05715)
			(type default)
		)
		(layer "In9.Cu")
	)
	(gr_line
		(start 127.840232 -105.988358)
		(end 127.859282 -105.992168)
		(stroke
			(width 0.05715)
			(type default)
		)
		(layer "In9.Cu")
	)
	(gr_line
		(start 127.841248 -108.355384)
		(end 130.403346 -108.867956)
		(stroke
			(width 0.1778)
			(type default)
		)
		(layer "In9.Cu")
	)
	(gr_line
		(start 127.856996 -98.15322)
		(end 127.934212 -98.174048)
		(stroke
			(width 0.04445)
			(type default)
		)
		(layer "In9.Cu")
	)
	(gr_line
		(start 127.934212 -98.174048)
		(end 128.227328 -98.005138)
		(stroke
			(width 0.04445)
			(type default)
		)
		(layer "In9.Cu")
	)
	(gr_line
		(start 127.982218 -99.64293)
		(end 128.160272 -99.464876)
		(stroke
			(width 0.04445)
			(type default)
		)
		(layer "In9.Cu")
	)
	(gr_line
		(start 128.011936 -103.236522)
		(end 128.030986 -103.232712)
		(stroke
			(width 0.05715)
			(type default)
		)
		(layer "In9.Cu")
	)
	(gr_line
		(start 128.030986 -103.232712)
		(end 128.050036 -103.236522)
		(stroke
			(width 0.05715)
			(type default)
		)
		(layer "In9.Cu")
	)
	(gr_line
		(start 128.045718 -103.907844)
		(end 128.067308 -103.903526)
		(stroke
			(width 0.05715)
			(type default)
		)
		(layer "In9.Cu")
	)
	(gr_line
		(start 128.067308 -103.903526)
		(end 128.088898 -103.907844)
		(stroke
			(width 0.05715)
			(type default)
		)
		(layer "In9.Cu")
	)
	(gr_line
		(start 128.080262 -105.287826)
		(end 128.099312 -105.284016)
		(stroke
			(width 0.05715)
			(type default)
		)
		(layer "In9.Cu")
	)
	(gr_line
		(start 128.099312 -105.284016)
		(end 128.118362 -105.287826)
		(stroke
			(width 0.05715)
			(type default)
		)
		(layer "In9.Cu")
	)
	(gr_line
		(start 128.135634 -104.588056)
		(end 128.154684 -104.584246)
		(stroke
			(width 0.05715)
			(type default)
		)
		(layer "In9.Cu")
	)
	(gr_line
		(start 128.154684 -104.584246)
		(end 128.173734 -104.588056)
		(stroke
			(width 0.05715)
			(type default)
		)
		(layer "In9.Cu")
	)
	(gr_arc
		(start 128.160272 -99.464876)
		(mid 128.209914 -99.390654)
		(end 128.227328 -99.303078)
		(stroke
			(width 0.04445)
			(type default)
		)
		(layer "In9.Cu")
	)
	(gr_line
		(start 128.227328 -100.976684)
		(end 128.520444 -100.807774)
		(stroke
			(width 0.04445)
			(type default)
		)
		(layer "In9.Cu")
	)
	(gr_line
		(start 128.227328 -98.995738)
		(end 128.227328 -99.303078)
		(stroke
			(width 0.04445)
			(type default)
		)
		(layer "In9.Cu")
	)
	(gr_line
		(start 128.520444 -100.807774)
		(end 128.541018 -100.730812)
		(stroke
			(width 0.04445)
			(type default)
		)
		(layer "In9.Cu")
	)
	(gr_line
		(start 128.689862 -102.733602)
		(end 128.739138 -102.72395)
		(stroke
			(width 0.05715)
			(type default)
		)
		(layer "In9.Cu")
	)
	(gr_line
		(start 128.705356 -100.626926)
		(end 128.792732 -100.650548)
		(stroke
			(width 0.04445)
			(type default)
		)
		(layer "In9.Cu")
	)
	(gr_line
		(start 128.792732 -100.650548)
		(end 129.085848 -100.481638)
		(stroke
			(width 0.04445)
			(type default)
		)
		(layer "In9.Cu")
	)
	(gr_line
		(start 129.085848 -99.490784)
		(end 129.378964 -99.659948)
		(stroke
			(width 0.04445)
			(type default)
		)
		(layer "In9.Cu")
	)
	(gr_line
		(start 129.308606 -102.608888)
		(end 129.330704 -102.608888)
		(stroke
			(width 0.04445)
			(type default)
		)
		(layer "In9.Cu")
	)
	(gr_line
		(start 129.308606 -102.316788)
		(end 129.330704 -102.316788)
		(stroke
			(width 0.04445)
			(type default)
		)
		(layer "In9.Cu")
	)
	(gr_line
		(start 129.330704 -102.608888)
		(end 129.340356 -102.599236)
		(stroke
			(width 0.04445)
			(type default)
		)
		(layer "In9.Cu")
	)
	(gr_line
		(start 129.330704 -102.316788)
		(end 129.340356 -102.32644)
		(stroke
			(width 0.04445)
			(type default)
		)
		(layer "In9.Cu")
	)
	(gr_line
		(start 129.342134 -102.597458)
		(end 129.381504 -102.558088)
		(stroke
			(width 0.04445)
			(type default)
		)
		(layer "In9.Cu")
	)
	(gr_line
		(start 129.342134 -102.328218)
		(end 129.381504 -102.367588)
		(stroke
			(width 0.04445)
			(type default)
		)
		(layer "In9.Cu")
	)
	(gr_line
		(start 129.378964 -99.659948)
		(end 129.455926 -99.63912)
		(stroke
			(width 0.04445)
			(type default)
		)
		(layer "In9.Cu")
	)
	(gr_line
		(start 129.627884 -99.729798)
		(end 129.651252 -99.817174)
		(stroke
			(width 0.04445)
			(type default)
		)
		(layer "In9.Cu")
	)
	(gr_line
		(start 129.651252 -99.817174)
		(end 129.944368 -99.986338)
		(stroke
			(width 0.04445)
			(type default)
		)
		(layer "In9.Cu")
	)
	(gr_line
		(start 129.944368 -97.667064)
		(end 129.944368 -98.005138)
		(stroke
			(width 0.04445)
			(type default)
		)
		(layer "In9.Cu")
	)
	(gr_line
		(start 129.944368 -97.667064)
		(end 129.965196 -97.646236)
		(stroke
			(width 0.04445)
			(type default)
		)
		(layer "In9.Cu")
	)
	(gr_line
		(start 129.944368 -97.352612)
		(end 129.965196 -97.37344)
		(stroke
			(width 0.04445)
			(type default)
		)
		(layer "In9.Cu")
	)
	(gr_line
		(start 129.944368 -97.014538)
		(end 129.944368 -97.352612)
		(stroke
			(width 0.04445)
			(type default)
		)
		(layer "In9.Cu")
	)
	(gr_line
		(start 129.966974 -97.644458)
		(end 130.009646 -97.601786)
		(stroke
			(width 0.04445)
			(type default)
		)
		(layer "In9.Cu")
	)
	(gr_line
		(start 129.966974 -97.375218)
		(end 130.00228 -97.410524)
		(stroke
			(width 0.04445)
			(type default)
		)
		(layer "In9.Cu")
	)
	(gr_line
		(start 130.10642 -104.560624)
		(end 130.128518 -104.560624)
		(stroke
			(width 0.04445)
			(type default)
		)
		(layer "In9.Cu")
	)
	(gr_line
		(start 130.10642 -104.268524)
		(end 130.128518 -104.268524)
		(stroke
			(width 0.04445)
			(type default)
		)
		(layer "In9.Cu")
	)
	(gr_line
		(start 130.128518 -104.560624)
		(end 130.13817 -104.550972)
		(stroke
			(width 0.04445)
			(type default)
		)
		(layer "In9.Cu")
	)
	(gr_line
		(start 130.128518 -104.268524)
		(end 130.13817 -104.278176)
		(stroke
			(width 0.04445)
			(type default)
		)
		(layer "In9.Cu")
	)
	(gr_line
		(start 130.139948 -104.549194)
		(end 130.179318 -104.509824)
		(stroke
			(width 0.04445)
			(type default)
		)
		(layer "In9.Cu")
	)
	(gr_line
		(start 130.139948 -104.279954)
		(end 130.179318 -104.319324)
		(stroke
			(width 0.04445)
			(type default)
		)
		(layer "In9.Cu")
	)
	(gr_line
		(start 130.168904 -105.28681)
		(end 130.171444 -105.28935)
		(stroke
			(width 0.05715)
			(type default)
		)
		(layer "In9.Cu")
	)
	(gr_line
		(start 130.325368 -103.900478)
		(end 130.347466 -103.900478)
		(stroke
			(width 0.04445)
			(type default)
		)
		(layer "In9.Cu")
	)
	(gr_line
		(start 130.325368 -103.608378)
		(end 130.347466 -103.608378)
		(stroke
			(width 0.04445)
			(type default)
		)
		(layer "In9.Cu")
	)
	(gr_line
		(start 130.347466 -103.900478)
		(end 130.357118 -103.890826)
		(stroke
			(width 0.04445)
			(type default)
		)
		(layer "In9.Cu")
	)
	(gr_line
		(start 130.347466 -103.608378)
		(end 130.357118 -103.61803)
		(stroke
			(width 0.04445)
			(type default)
		)
		(layer "In9.Cu")
	)
	(gr_line
		(start 130.358896 -103.889048)
		(end 130.398266 -103.849678)
		(stroke
			(width 0.04445)
			(type default)
		)
		(layer "In9.Cu")
	)
	(gr_line
		(start 130.358896 -103.619808)
		(end 130.398266 -103.659178)
		(stroke
			(width 0.04445)
			(type default)
		)
		(layer "In9.Cu")
	)
	(gr_line
		(start 130.403346 -108.867956)
		(end 130.432048 -108.87075)
		(stroke
			(width 0.1778)
			(type default)
		)
		(layer "In9.Cu")
	)
	(gr_line
		(start 130.432048 -108.87075)
		(end 133.613906 -108.87075)
		(stroke
			(width 0.1778)
			(type default)
		)
		(layer "In9.Cu")
	)
	(gr_line
		(start 130.451352 -95.337122)
		(end 130.456178 -95.328486)
		(stroke
			(width 0.04445)
			(type default)
		)
		(layer "In9.Cu")
	)
	(gr_line
		(start 130.491992 -104.316784)
		(end 130.559302 -104.249474)
		(stroke
			(width 0.04445)
			(type default)
		)
		(layer "In9.Cu")
	)
	(gr_line
		(start 130.559302 -104.249474)
		(end 130.737102 -104.249474)
		(stroke
			(width 0.04445)
			(type default)
		)
		(layer "In9.Cu")
	)
	(gr_line
		(start 130.637534 -113.72469)
		(end 130.687064 -113.714784)
		(stroke
			(width 0.05715)
			(type default)
		)
		(layer "In9.Cu")
	)
	(gr_line
		(start 130.737102 -104.249474)
		(end 130.804412 -104.316784)
		(stroke
			(width 0.04445)
			(type default)
		)
		(layer "In9.Cu")
	)
	(gr_line
		(start 130.802888 -97.509584)
		(end 131.096004 -97.678748)
		(stroke
			(width 0.04445)
			(type default)
		)
		(layer "In9.Cu")
	)
	(gr_line
		(start 130.894582 -103.656638)
		(end 130.978402 -103.572818)
		(stroke
			(width 0.04445)
			(type default)
		)
		(layer "In9.Cu")
	)
	(gr_line
		(start 130.978402 -103.572818)
		(end 131.156202 -103.572818)
		(stroke
			(width 0.04445)
			(type default)
		)
		(layer "In9.Cu")
	)
	(gr_line
		(start 131.003802 -104.316784)
		(end 131.087622 -104.232964)
		(stroke
			(width 0.04445)
			(type default)
		)
		(layer "In9.Cu")
	)
	(gr_line
		(start 131.087622 -104.232964)
		(end 131.265422 -104.232964)
		(stroke
			(width 0.04445)
			(type default)
		)
		(layer "In9.Cu")
	)
	(gr_line
		(start 131.096004 -97.678748)
		(end 131.172966 -97.65792)
		(stroke
			(width 0.04445)
			(type default)
		)
		(layer "In9.Cu")
	)
	(gr_line
		(start 131.143248 -94.748604)
		(end 131.149598 -94.737936)
		(stroke
			(width 0.04445)
			(type default)
		)
		(layer "In9.Cu")
	)
	(gr_line
		(start 131.149598 -95.328486)
		(end 131.154424 -95.337122)
		(stroke
			(width 0.04445)
			(type default)
		)
		(layer "In9.Cu")
	)
	(gr_line
		(start 131.156202 -103.572818)
		(end 131.240022 -103.656638)
		(stroke
			(width 0.04445)
			(type default)
		)
		(layer "In9.Cu")
	)
	(gr_line
		(start 131.265422 -104.232964)
		(end 131.349242 -104.316784)
		(stroke
			(width 0.04445)
			(type default)
		)
		(layer "In9.Cu")
	)
	(gr_line
		(start 131.341876 -114.100102)
		(end 131.34213 -114.100102)
		(stroke
			(width 0.1778)
			(type default)
		)
		(layer "In9.Cu")
	)
	(gr_line
		(start 131.34213 -114.100102)
		(end 131.416806 -114.060224)
		(stroke
			(width 0.1778)
			(type default)
		)
		(layer "In9.Cu")
	)
	(gr_line
		(start 131.344924 -97.748598)
		(end 131.368292 -97.835974)
		(stroke
			(width 0.04445)
			(type default)
		)
		(layer "In9.Cu")
	)
	(gr_line
		(start 131.368292 -97.835974)
		(end 131.661408 -98.005138)
		(stroke
			(width 0.04445)
			(type default)
		)
		(layer "In9.Cu")
	)
	(gr_line
		(start 131.407408 -114.235992)
		(end 131.4577 -114.226086)
		(stroke
			(width 0.05715)
			(type default)
		)
		(layer "In9.Cu")
	)
	(gr_line
		(start 131.416806 -114.060224)
		(end 139.325858 -106.151172)
		(stroke
			(width 0.1778)
			(type default)
		)
		(layer "In9.Cu")
	)
	(gr_line
		(start 131.422902 -103.656638)
		(end 131.506722 -103.572818)
		(stroke
			(width 0.04445)
			(type default)
		)
		(layer "In9.Cu")
	)
	(gr_line
		(start 131.506722 -103.572818)
		(end 131.684522 -103.572818)
		(stroke
			(width 0.04445)
			(type default)
		)
		(layer "In9.Cu")
	)
	(gr_line
		(start 131.532122 -104.316784)
		(end 131.615942 -104.232964)
		(stroke
			(width 0.04445)
			(type default)
		)
		(layer "In9.Cu")
	)
	(gr_line
		(start 131.59613 -102.554786)
		(end 131.638802 -102.597458)
		(stroke
			(width 0.04445)
			(type default)
		)
		(layer "In9.Cu")
	)
	(gr_line
		(start 131.603496 -102.363524)
		(end 131.638802 -102.328218)
		(stroke
			(width 0.04445)
			(type default)
		)
		(layer "In9.Cu")
	)
	(gr_line
		(start 131.615942 -104.232964)
		(end 131.793742 -104.232964)
		(stroke
			(width 0.04445)
			(type default)
		)
		(layer "In9.Cu")
	)
	(gr_line
		(start 131.64058 -102.599236)
		(end 131.661408 -102.620064)
		(stroke
			(width 0.04445)
			(type default)
		)
		(layer "In9.Cu")
	)
	(gr_line
		(start 131.64058 -102.32644)
		(end 131.661408 -102.305612)
		(stroke
			(width 0.04445)
			(type default)
		)
		(layer "In9.Cu")
	)
	(gr_line
		(start 131.661408 -102.620064)
		(end 131.661408 -102.958138)
		(stroke
			(width 0.04445)
			(type default)
		)
		(layer "In9.Cu")
	)
	(gr_line
		(start 131.661408 -101.967538)
		(end 131.661408 -102.305612)
		(stroke
			(width 0.04445)
			(type default)
		)
		(layer "In9.Cu")
	)
	(gr_line
		(start 131.661408 -97.014538)
		(end 131.95427 -96.845628)
		(stroke
			(width 0.04445)
			(type default)
		)
		(layer "In9.Cu")
	)
	(gr_line
		(start 131.661408 -95.685864)
		(end 131.661408 -96.023938)
		(stroke
			(width 0.04445)
			(type default)
		)
		(layer "In9.Cu")
	)
	(gr_line
		(start 131.661408 -95.685864)
		(end 131.682236 -95.665036)
		(stroke
			(width 0.04445)
			(type default)
		)
		(layer "In9.Cu")
	)
	(gr_line
		(start 131.661408 -95.371158)
		(end 131.682236 -95.391986)
		(stroke
			(width 0.04445)
			(type default)
		)
		(layer "In9.Cu")
	)
	(gr_line
		(start 131.661408 -95.033084)
		(end 131.661408 -95.371158)
		(stroke
			(width 0.04445)
			(type default)
		)
		(layer "In9.Cu")
	)
	(gr_line
		(start 131.684014 -95.663258)
		(end 131.719066 -95.628206)
		(stroke
			(width 0.04445)
			(type default)
		)
		(layer "In9.Cu")
	)
	(gr_line
		(start 131.684014 -95.393764)
		(end 131.726686 -95.436436)
		(stroke
			(width 0.04445)
			(type default)
		)
		(layer "In9.Cu")
	)
	(gr_line
		(start 131.684522 -103.572818)
		(end 131.768342 -103.656638)
		(stroke
			(width 0.04445)
			(type default)
		)
		(layer "In9.Cu")
	)
	(gr_line
		(start 131.793742 -104.232964)
		(end 131.877562 -104.316784)
		(stroke
			(width 0.04445)
			(type default)
		)
		(layer "In9.Cu")
	)
	(gr_line
		(start 131.95427 -96.845628)
		(end 132.042408 -96.869504)
		(stroke
			(width 0.04445)
			(type default)
		)
		(layer "In9.Cu")
	)
	(gr_line
		(start 132.004562 -93.836998)
		(end 132.007864 -93.84284)
		(stroke
			(width 0.04445)
			(type default)
		)
		(layer "In9.Cu")
	)
	(gr_line
		(start 132.047234 -105.28935)
		(end 132.069332 -105.28935)
		(stroke
			(width 0.04445)
			(type default)
		)
		(layer "In9.Cu")
	)
	(gr_line
		(start 132.047234 -104.99725)
		(end 132.069332 -104.99725)
		(stroke
			(width 0.04445)
			(type default)
		)
		(layer "In9.Cu")
	)
	(gr_line
		(start 132.060442 -104.316784)
		(end 132.144262 -104.232964)
		(stroke
			(width 0.04445)
			(type default)
		)
		(layer "In9.Cu")
	)
	(gr_line
		(start 132.069332 -105.28935)
		(end 132.078984 -105.279698)
		(stroke
			(width 0.04445)
			(type default)
		)
		(layer "In9.Cu")
	)
	(gr_line
		(start 132.069332 -104.99725)
		(end 132.078984 -105.006902)
		(stroke
			(width 0.04445)
			(type default)
		)
		(layer "In9.Cu")
	)
	(gr_line
		(start 132.074412 -103.411274)
		(end 132.074412 -103.529892)
		(stroke
			(width 0.04445)
			(type default)
		)
		(layer "In9.Cu")
	)
	(gr_line
		(start 132.074412 -103.411274)
		(end 132.200142 -103.285544)
		(stroke
			(width 0.04445)
			(type default)
		)
		(layer "In9.Cu")
	)
	(gr_line
		(start 132.080762 -105.27792)
		(end 132.120132 -105.23855)
		(stroke
			(width 0.04445)
			(type default)
		)
		(layer "In9.Cu")
	)
	(gr_line
		(start 132.080762 -105.00868)
		(end 132.120132 -105.04805)
		(stroke
			(width 0.04445)
			(type default)
		)
		(layer "In9.Cu")
	)
	(gr_line
		(start 132.103622 -114.846354)
		(end 132.152898 -114.836702)
		(stroke
			(width 0.05715)
			(type default)
		)
		(layer "In9.Cu")
	)
	(gr_line
		(start 132.144262 -104.232964)
		(end 132.322062 -104.232964)
		(stroke
			(width 0.04445)
			(type default)
		)
		(layer "In9.Cu")
	)
	(gr_line
		(start 132.200142 -103.285544)
		(end 132.319014 -103.285544)
		(stroke
			(width 0.04445)
			(type default)
		)
		(layer "In9.Cu")
	)
	(gr_line
		(start 132.205984 -96.765364)
		(end 132.226812 -96.687894)
		(stroke
			(width 0.04445)
			(type default)
		)
		(layer "In9.Cu")
	)
	(gr_line
		(start 132.226812 -96.687894)
		(end 132.519674 -96.518984)
		(stroke
			(width 0.04445)
			(type default)
		)
		(layer "In9.Cu")
	)
	(gr_line
		(start 132.29844 -106.009186)
		(end 132.320538 -106.009186)
		(stroke
			(width 0.04445)
			(type default)
		)
		(layer "In9.Cu")
	)
	(gr_line
		(start 132.29844 -105.717086)
		(end 132.320538 -105.717086)
		(stroke
			(width 0.04445)
			(type default)
		)
		(layer "In9.Cu")
	)
	(gr_line
		(start 132.320538 -106.009186)
		(end 132.33019 -105.999534)
		(stroke
			(width 0.04445)
			(type default)
		)
		(layer "In9.Cu")
	)
	(gr_line
		(start 132.320538 -105.717086)
		(end 132.33019 -105.726738)
		(stroke
			(width 0.04445)
			(type default)
		)
		(layer "In9.Cu")
	)
	(gr_line
		(start 132.322062 -104.232964)
		(end 132.405882 -104.316784)
		(stroke
			(width 0.04445)
			(type default)
		)
		(layer "In9.Cu")
	)
	(gr_line
		(start 132.331968 -105.997756)
		(end 132.371338 -105.958386)
		(stroke
			(width 0.04445)
			(type default)
		)
		(layer "In9.Cu")
	)
	(gr_line
		(start 132.331968 -105.728516)
		(end 132.371338 -105.767886)
		(stroke
			(width 0.04445)
			(type default)
		)
		(layer "In9.Cu")
	)
	(gr_line
		(start 132.345684 -103.53167)
		(end 132.435346 -103.442008)
		(stroke
			(width 0.04445)
			(type default)
		)
		(layer "In9.Cu")
	)
	(gr_line
		(start 132.501894 -94.137988)
		(end 132.532628 -94.137988)
		(stroke
			(width 0.04445)
			(type default)
		)
		(layer "In9.Cu")
	)
	(gr_line
		(start 132.502656 -106.703368)
		(end 132.524754 -106.703368)
		(stroke
			(width 0.04445)
			(type default)
		)
		(layer "In9.Cu")
	)
	(gr_line
		(start 132.502656 -106.411268)
		(end 132.524754 -106.411268)
		(stroke
			(width 0.04445)
			(type default)
		)
		(layer "In9.Cu")
	)
	(gr_line
		(start 132.519674 -102.462584)
		(end 132.789422 -102.61854)
		(stroke
			(width 0.04445)
			(type default)
		)
		(layer "In9.Cu")
	)
	(gr_line
		(start 132.524754 -106.703368)
		(end 132.534406 -106.693716)
		(stroke
			(width 0.04445)
			(type default)
		)
		(layer "In9.Cu")
	)
	(gr_line
		(start 132.524754 -106.411268)
		(end 132.534406 -106.42092)
		(stroke
			(width 0.04445)
			(type default)
		)
		(layer "In9.Cu")
	)
	(gr_line
		(start 132.536184 -106.691938)
		(end 132.575554 -106.652568)
		(stroke
			(width 0.04445)
			(type default)
		)
		(layer "In9.Cu")
	)
	(gr_line
		(start 132.536184 -106.422698)
		(end 132.575554 -106.462068)
		(stroke
			(width 0.04445)
			(type default)
		)
		(layer "In9.Cu")
	)
	(gr_line
		(start 132.537708 -97.01403)
		(end 132.124704 -96.818196)
		(stroke
			(width 0.1778)
			(type default)
		)
		(layer "In9.Cu")
	)
	(gr_line
		(start 132.70357 -115.427252)
		(end 132.752846 -115.4176)
		(stroke
			(width 0.05715)
			(type default)
		)
		(layer "In9.Cu")
	)
	(gr_line
		(start 132.714746 -104.06888)
		(end 132.714746 -104.187244)
		(stroke
			(width 0.04445)
			(type default)
		)
		(layer "In9.Cu")
	)
	(gr_line
		(start 132.714746 -104.06888)
		(end 132.84073 -103.942896)
		(stroke
			(width 0.04445)
			(type default)
		)
		(layer "In9.Cu")
	)
	(gr_line
		(start 132.789422 -102.61854)
		(end 132.820918 -102.73665)
		(stroke
			(width 0.04445)
			(type default)
		)
		(layer "In9.Cu")
	)
	(gr_line
		(start 132.84073 -103.942896)
		(end 132.959094 -103.942896)
		(stroke
			(width 0.04445)
			(type default)
		)
		(layer "In9.Cu")
	)
	(gr_line
		(start 132.871972 -107.542584)
		(end 132.89407 -107.542584)
		(stroke
			(width 0.04445)
			(type default)
		)
		(layer "In9.Cu")
	)
	(gr_line
		(start 132.871972 -107.250484)
		(end 132.89407 -107.250484)
		(stroke
			(width 0.04445)
			(type default)
		)
		(layer "In9.Cu")
	)
	(gr_line
		(start 132.89407 -107.542584)
		(end 132.903722 -107.532932)
		(stroke
			(width 0.04445)
			(type default)
		)
		(layer "In9.Cu")
	)
	(gr_line
		(start 132.89407 -107.250484)
		(end 132.903722 -107.260136)
		(stroke
			(width 0.04445)
			(type default)
		)
		(layer "In9.Cu")
	)
	(gr_line
		(start 132.9055 -107.531154)
		(end 132.94487 -107.491784)
		(stroke
			(width 0.04445)
			(type default)
		)
		(layer "In9.Cu")
	)
	(gr_line
		(start 132.9055 -107.261914)
		(end 132.94487 -107.301284)
		(stroke
			(width 0.04445)
			(type default)
		)
		(layer "In9.Cu")
	)
	(gr_line
		(start 132.90931 -96.79051)
		(end 132.537708 -97.01403)
		(stroke
			(width 0.1778)
			(type default)
		)
		(layer "In9.Cu")
	)
	(gr_line
		(start 132.948934 -96.766634)
		(end 132.90931 -96.79051)
		(stroke
			(width 0.1778)
			(type default)
		)
		(layer "In9.Cu")
	)
	(gr_line
		(start 132.989066 -102.835964)
		(end 133.110224 -102.802944)
		(stroke
			(width 0.04445)
			(type default)
		)
		(layer "In9.Cu")
	)
	(gr_line
		(start 133.088126 -103.695246)
		(end 133.088126 -103.813864)
		(stroke
			(width 0.04445)
			(type default)
		)
		(layer "In9.Cu")
	)
	(gr_line
		(start 133.088126 -103.695246)
		(end 133.21411 -103.569262)
		(stroke
			(width 0.04445)
			(type default)
		)
		(layer "In9.Cu")
	)
	(gr_line
		(start 133.110224 -102.802944)
		(end 133.378194 -102.958138)
		(stroke
			(width 0.04445)
			(type default)
		)
		(layer "In9.Cu")
	)
	(gr_line
		(start 133.112002 -108.221018)
		(end 133.1341 -108.221018)
		(stroke
			(width 0.04445)
			(type default)
		)
		(layer "In9.Cu")
	)
	(gr_line
		(start 133.112002 -107.928918)
		(end 133.1341 -107.928918)
		(stroke
			(width 0.04445)
			(type default)
		)
		(layer "In9.Cu")
	)
	(gr_line
		(start 133.1341 -108.221018)
		(end 133.143752 -108.211366)
		(stroke
			(width 0.04445)
			(type default)
		)
		(layer "In9.Cu")
	)
	(gr_line
		(start 133.1341 -107.928918)
		(end 133.143752 -107.93857)
		(stroke
			(width 0.04445)
			(type default)
		)
		(layer "In9.Cu")
	)
	(gr_line
		(start 133.14553 -108.209588)
		(end 133.1849 -108.170218)
		(stroke
			(width 0.04445)
			(type default)
		)
		(layer "In9.Cu")
	)
	(gr_line
		(start 133.14553 -107.940348)
		(end 133.1849 -107.979718)
		(stroke
			(width 0.04445)
			(type default)
		)
		(layer "In9.Cu")
	)
	(gr_line
		(start 133.21411 -103.569262)
		(end 133.332728 -103.569262)
		(stroke
			(width 0.04445)
			(type default)
		)
		(layer "In9.Cu")
	)
	(gr_line
		(start 133.255258 -115.987576)
		(end 133.304534 -115.977924)
		(stroke
			(width 0.05715)
			(type default)
		)
		(layer "In9.Cu")
	)
	(gr_line
		(start 133.28777 -104.42194)
		(end 133.28777 -104.532176)
		(stroke
			(width 0.04445)
			(type default)
		)
		(layer "In9.Cu")
	)
	(gr_line
		(start 133.28777 -104.42194)
		(end 133.413754 -104.295956)
		(stroke
			(width 0.04445)
			(type default)
		)
		(layer "In9.Cu")
	)
	(gr_line
		(start 133.363208 -95.623888)
		(end 133.39318 -95.623888)
		(stroke
			(width 0.04445)
			(type default)
		)
		(layer "In9.Cu")
	)
	(gr_line
		(start 133.378194 -101.967538)
		(end 133.5024 -101.89591)
		(stroke
			(width 0.04445)
			(type default)
		)
		(layer "In9.Cu")
	)
	(gr_line
		(start 133.396482 -96.519238)
		(end 133.359906 -96.519238)
		(stroke
			(width 0.1778)
			(type default)
		)
		(layer "In9.Cu")
	)
	(gr_line
		(start 133.413754 -104.295956)
		(end 133.52399 -104.295956)
		(stroke
			(width 0.04445)
			(type default)
		)
		(layer "In9.Cu")
	)
	(gr_line
		(start 133.5024 -101.89591)
		(end 133.67131 -101.798374)
		(stroke
			(width 0.04445)
			(type default)
		)
		(layer "In9.Cu")
	)
	(gr_line
		(start 133.613906 -109.0168)
		(end 133.636004 -109.0168)
		(stroke
			(width 0.04445)
			(type default)
		)
		(layer "In9.Cu")
	)
	(gr_line
		(start 133.613906 -108.87075)
		(end 133.636004 -108.87075)
		(stroke
			(width 0.1778)
			(type default)
		)
		(layer "In9.Cu")
	)
	(gr_line
		(start 133.613906 -108.7247)
		(end 133.636004 -108.7247)
		(stroke
			(width 0.04445)
			(type default)
		)
		(layer "In9.Cu")
	)
	(gr_line
		(start 133.636004 -109.0168)
		(end 133.645656 -109.007148)
		(stroke
			(width 0.04445)
			(type default)
		)
		(layer "In9.Cu")
	)
	(gr_line
		(start 133.636004 -108.7247)
		(end 133.645656 -108.734352)
		(stroke
			(width 0.04445)
			(type default)
		)
		(layer "In9.Cu")
	)
	(gr_line
		(start 133.647434 -109.00537)
		(end 133.686804 -108.966)
		(stroke
			(width 0.04445)
			(type default)
		)
		(layer "In9.Cu")
	)
	(gr_line
		(start 133.647434 -108.73613)
		(end 133.686804 -108.7755)
		(stroke
			(width 0.04445)
			(type default)
		)
		(layer "In9.Cu")
	)
	(gr_line
		(start 133.657086 -104.044242)
		(end 133.657086 -104.16286)
		(stroke
			(width 0.04445)
			(type default)
		)
		(layer "In9.Cu")
	)
	(gr_line
		(start 133.657086 -104.044242)
		(end 133.78307 -103.918258)
		(stroke
			(width 0.04445)
			(type default)
		)
		(layer "In9.Cu")
	)
	(gr_line
		(start 133.67131 -101.798374)
		(end 133.748272 -101.819202)
		(stroke
			(width 0.04445)
			(type default)
		)
		(layer "In9.Cu")
	)
	(gr_line
		(start 133.686804 -108.87075)
		(end 134.110984 -108.87075)
		(stroke
			(width 0.1778)
			(type default)
		)
		(layer "In9.Cu")
	)
	(gr_line
		(start 133.76783 -96.743012)
		(end 133.396482 -96.519238)
		(stroke
			(width 0.1778)
			(type default)
		)
		(layer "In9.Cu")
	)
	(gr_line
		(start 133.78307 -103.918258)
		(end 133.901688 -103.918258)
		(stroke
			(width 0.04445)
			(type default)
		)
		(layer "In9.Cu")
	)
	(gr_line
		(start 133.807454 -96.766634)
		(end 133.76783 -96.743012)
		(stroke
			(width 0.1778)
			(type default)
		)
		(layer "In9.Cu")
	)
	(gr_line
		(start 133.90499 -116.526818)
		(end 133.954266 -116.517166)
		(stroke
			(width 0.05715)
			(type default)
		)
		(layer "In9.Cu")
	)
	(gr_line
		(start 133.92023 -101.728524)
		(end 133.943598 -101.641148)
		(stroke
			(width 0.04445)
			(type default)
		)
		(layer "In9.Cu")
	)
	(gr_line
		(start 133.943598 -101.641148)
		(end 134.236714 -101.471984)
		(stroke
			(width 0.04445)
			(type default)
		)
		(layer "In9.Cu")
	)
	(gr_line
		(start 133.96214 -102.787704)
		(end 133.9723 -102.805484)
		(stroke
			(width 0.04445)
			(type default)
		)
		(layer "In9.Cu")
	)
	(gr_line
		(start 134.03072 -103.670608)
		(end 134.03072 -103.789226)
		(stroke
			(width 0.04445)
			(type default)
		)
		(layer "In9.Cu")
	)
	(gr_line
		(start 134.03072 -103.670608)
		(end 134.156704 -103.544624)
		(stroke
			(width 0.04445)
			(type default)
		)
		(layer "In9.Cu")
	)
	(gr_line
		(start 134.091934 -105.470706)
		(end 134.091934 -105.610406)
		(stroke
			(width 0.04445)
			(type default)
		)
		(layer "In9.Cu")
	)
	(gr_line
		(start 134.091934 -105.470706)
		(end 134.217664 -105.344976)
		(stroke
			(width 0.04445)
			(type default)
		)
		(layer "In9.Cu")
	)
	(gr_line
		(start 134.110984 -108.87075)
		(end 134.178294 -108.84281)
		(stroke
			(width 0.1778)
			(type default)
		)
		(layer "In9.Cu")
	)
	(gr_line
		(start 134.156704 -103.544624)
		(end 134.275322 -103.544624)
		(stroke
			(width 0.04445)
			(type default)
		)
		(layer "In9.Cu")
	)
	(gr_line
		(start 134.178294 -108.84281)
		(end 137.556748 -105.464356)
		(stroke
			(width 0.1778)
			(type default)
		)
		(layer "In9.Cu")
	)
	(gr_line
		(start 134.217664 -105.344976)
		(end 134.357364 -105.344976)
		(stroke
			(width 0.04445)
			(type default)
		)
		(layer "In9.Cu")
	)
	(gr_line
		(start 134.236714 -100.481638)
		(end 134.52983 -100.650548)
		(stroke
			(width 0.04445)
			(type default)
		)
		(layer "In9.Cu")
	)
	(gr_line
		(start 134.251192 -97.014284)
		(end 134.218426 -97.014284)
		(stroke
			(width 0.1778)
			(type default)
		)
		(layer "In9.Cu")
	)
	(gr_line
		(start 134.42188 -102.942136)
		(end 134.43204 -102.924356)
		(stroke
			(width 0.04445)
			(type default)
		)
		(layer "In9.Cu")
	)
	(gr_line
		(start 134.486396 -105.076244)
		(end 134.486396 -105.215944)
		(stroke
			(width 0.04445)
			(type default)
		)
		(layer "In9.Cu")
	)
	(gr_line
		(start 134.486396 -105.076244)
		(end 134.612126 -104.950514)
		(stroke
			(width 0.04445)
			(type default)
		)
		(layer "In9.Cu")
	)
	(gr_line
		(start 134.52983 -100.650548)
		(end 134.553198 -100.737924)
		(stroke
			(width 0.04445)
			(type default)
		)
		(layer "In9.Cu")
	)
	(gr_line
		(start 134.583424 -101.272086)
		(end 134.58825 -101.280722)
		(stroke
			(width 0.04445)
			(type default)
		)
		(layer "In9.Cu")
	)
	(gr_line
		(start 134.612126 -104.950514)
		(end 134.751826 -104.950514)
		(stroke
			(width 0.04445)
			(type default)
		)
		(layer "In9.Cu")
	)
	(gr_line
		(start 134.626096 -97.238058)
		(end 134.251192 -97.014284)
		(stroke
			(width 0.1778)
			(type default)
		)
		(layer "In9.Cu")
	)
	(gr_line
		(start 134.665974 -97.261934)
		(end 134.626096 -97.238058)
		(stroke
			(width 0.1778)
			(type default)
		)
		(layer "In9.Cu")
	)
	(gr_line
		(start 134.715504 -117.060218)
		(end 134.76478 -117.050566)
		(stroke
			(width 0.05715)
			(type default)
		)
		(layer "In9.Cu")
	)
	(gr_line
		(start 134.724902 -100.828602)
		(end 134.802118 -100.807774)
		(stroke
			(width 0.04445)
			(type default)
		)
		(layer "In9.Cu")
	)
	(gr_line
		(start 134.802118 -100.807774)
		(end 135.095234 -100.976684)
		(stroke
			(width 0.04445)
			(type default)
		)
		(layer "In9.Cu")
	)
	(gr_line
		(start 134.880858 -104.681782)
		(end 134.880858 -104.821482)
		(stroke
			(width 0.04445)
			(type default)
		)
		(layer "In9.Cu")
	)
	(gr_line
		(start 134.880858 -104.681782)
		(end 135.006588 -104.556052)
		(stroke
			(width 0.04445)
			(type default)
		)
		(layer "In9.Cu")
	)
	(gr_line
		(start 135.006588 -104.556052)
		(end 135.146288 -104.556052)
		(stroke
			(width 0.04445)
			(type default)
		)
		(layer "In9.Cu")
	)
	(gr_line
		(start 135.095234 -99.986338)
		(end 135.38835 -99.817174)
		(stroke
			(width 0.04445)
			(type default)
		)
		(layer "In9.Cu")
	)
	(gr_line
		(start 135.113522 -97.509838)
		(end 135.080756 -97.509838)
		(stroke
			(width 0.1778)
			(type default)
		)
		(layer "In9.Cu")
	)
	(gr_line
		(start 135.27532 -104.28732)
		(end 135.27532 -104.42702)
		(stroke
			(width 0.04445)
			(type default)
		)
		(layer "In9.Cu")
	)
	(gr_line
		(start 135.27532 -104.28732)
		(end 135.40105 -104.16159)
		(stroke
			(width 0.04445)
			(type default)
		)
		(layer "In9.Cu")
	)
	(gr_line
		(start 135.38835 -99.817174)
		(end 135.475726 -99.840796)
		(stroke
			(width 0.04445)
			(type default)
		)
		(layer "In9.Cu")
	)
	(gr_line
		(start 135.40105 -104.16159)
		(end 135.54075 -104.16159)
		(stroke
			(width 0.04445)
			(type default)
		)
		(layer "In9.Cu")
	)
	(gr_line
		(start 135.481822 -102.827074)
		(end 135.48233 -102.827836)
		(stroke
			(width 0.04445)
			(type default)
		)
		(layer "In9.Cu")
	)
	(gr_line
		(start 135.48487 -97.733612)
		(end 135.113522 -97.509838)
		(stroke
			(width 0.1778)
			(type default)
		)
		(layer "In9.Cu")
	)
	(gr_line
		(start 135.640064 -99.73691)
		(end 135.660638 -99.659948)
		(stroke
			(width 0.04445)
			(type default)
		)
		(layer "In9.Cu")
	)
	(gr_line
		(start 135.646922 -102.731824)
		(end 135.64743 -102.732586)
		(stroke
			(width 0.04445)
			(type default)
		)
		(layer "In9.Cu")
	)
	(gr_line
		(start 135.660638 -99.659948)
		(end 135.953754 -99.490784)
		(stroke
			(width 0.04445)
			(type default)
		)
		(layer "In9.Cu")
	)
	(gr_line
		(start 135.669782 -103.892858)
		(end 135.669782 -104.032558)
		(stroke
			(width 0.04445)
			(type default)
		)
		(layer "In9.Cu")
	)
	(gr_line
		(start 135.669782 -103.892858)
		(end 135.795512 -103.767128)
		(stroke
			(width 0.04445)
			(type default)
		)
		(layer "In9.Cu")
	)
	(gr_line
		(start 135.702548 -102.828344)
		(end 135.712454 -102.845616)
		(stroke
			(width 0.04445)
			(type default)
		)
		(layer "In9.Cu")
	)
	(gr_line
		(start 135.795512 -103.767128)
		(end 135.935212 -103.767128)
		(stroke
			(width 0.04445)
			(type default)
		)
		(layer "In9.Cu")
	)
	(gr_arc
		(start 135.888984 -100.884482)
		(mid 135.878559 -100.885661)
		(end 135.868156 -100.887022)
		(stroke
			(width 0.04445)
			(type default)
		)
		(layer "In9.Cu")
	)
	(gr_line
		(start 135.888984 -100.884482)
		(end 135.931402 -100.842064)
		(stroke
			(width 0.04445)
			(type default)
		)
		(layer "In9.Cu")
	)
	(gr_line
		(start 135.895842 -101.075998)
		(end 135.931402 -101.111558)
		(stroke
			(width 0.04445)
			(type default)
		)
		(layer "In9.Cu")
	)
	(gr_line
		(start 135.93318 -101.113336)
		(end 135.953754 -101.13391)
		(stroke
			(width 0.04445)
			(type default)
		)
		(layer "In9.Cu")
	)
	(gr_line
		(start 135.93318 -100.840286)
		(end 135.953754 -100.819712)
		(stroke
			(width 0.04445)
			(type default)
		)
		(layer "In9.Cu")
	)
	(gr_line
		(start 135.953754 -101.13391)
		(end 135.953754 -101.471984)
		(stroke
			(width 0.04445)
			(type default)
		)
		(layer "In9.Cu")
	)
	(gr_line
		(start 135.953754 -100.481638)
		(end 135.953754 -100.819712)
		(stroke
			(width 0.04445)
			(type default)
		)
		(layer "In9.Cu")
	)
	(gr_line
		(start 135.953754 -98.500184)
		(end 136.24687 -98.669348)
		(stroke
			(width 0.04445)
			(type default)
		)
		(layer "In9.Cu")
	)
	(gr_line
		(start 136.24687 -98.669348)
		(end 136.270238 -98.756724)
		(stroke
			(width 0.04445)
			(type default)
		)
		(layer "In9.Cu")
	)
	(gr_line
		(start 136.264396 -104.20223)
		(end 136.264396 -104.320594)
		(stroke
			(width 0.04445)
			(type default)
		)
		(layer "In9.Cu")
	)
	(gr_line
		(start 136.264396 -104.20223)
		(end 136.39038 -104.076246)
		(stroke
			(width 0.04445)
			(type default)
		)
		(layer "In9.Cu")
	)
	(gr_line
		(start 136.306814 -101.66096)
		(end 136.307068 -101.66096)
		(stroke
			(width 0.04445)
			(type default)
		)
		(layer "In9.Cu")
	)
	(gr_line
		(start 136.39038 -104.076246)
		(end 136.508744 -104.076246)
		(stroke
			(width 0.04445)
			(type default)
		)
		(layer "In9.Cu")
	)
	(gr_line
		(start 136.442196 -98.847402)
		(end 136.519158 -98.826574)
		(stroke
			(width 0.04445)
			(type default)
		)
		(layer "In9.Cu")
	)
	(gr_line
		(start 136.519158 -98.826574)
		(end 136.812274 -98.995738)
		(stroke
			(width 0.04445)
			(type default)
		)
		(layer "In9.Cu")
	)
	(gr_line
		(start 136.568688 -102.356666)
		(end 136.577324 -102.372922)
		(stroke
			(width 0.04445)
			(type default)
		)
		(layer "In9.Cu")
	)
	(gr_line
		(start 136.671558 -103.795068)
		(end 136.671558 -103.913432)
		(stroke
			(width 0.04445)
			(type default)
		)
		(layer "In9.Cu")
	)
	(gr_line
		(start 136.671558 -103.795068)
		(end 136.797542 -103.669084)
		(stroke
			(width 0.04445)
			(type default)
		)
		(layer "In9.Cu")
	)
	(gr_line
		(start 136.797542 -103.669084)
		(end 136.915906 -103.669084)
		(stroke
			(width 0.04445)
			(type default)
		)
		(layer "In9.Cu")
	)
	(gr_line
		(start 136.812274 -98.005138)
		(end 137.10539 -97.835974)
		(stroke
			(width 0.04445)
			(type default)
		)
		(layer "In9.Cu")
	)
	(gr_line
		(start 136.824974 -104.787954)
		(end 136.824974 -104.89438)
		(stroke
			(width 0.04445)
			(type default)
		)
		(layer "In9.Cu")
	)
	(gr_line
		(start 136.824974 -104.787954)
		(end 136.950958 -104.66197)
		(stroke
			(width 0.04445)
			(type default)
		)
		(layer "In9.Cu")
	)
	(gr_line
		(start 136.950958 -104.66197)
		(end 137.057384 -104.66197)
		(stroke
			(width 0.04445)
			(type default)
		)
		(layer "In9.Cu")
	)
	(gr_line
		(start 137.10539 -97.835974)
		(end 137.182352 -97.856802)
		(stroke
			(width 0.04445)
			(type default)
		)
		(layer "In9.Cu")
	)
	(gr_arc
		(start 137.157968 -100.776532)
		(mid 137.155555 -100.771263)
		(end 137.152888 -100.766118)
		(stroke
			(width 0.04445)
			(type default)
		)
		(layer "In9.Cu")
	)
	(gr_line
		(start 137.163048 -102.585012)
		(end 137.23874 -102.660704)
		(stroke
			(width 0.04445)
			(type default)
		)
		(layer "In9.Cu")
	)
	(gr_line
		(start 137.163048 -102.407212)
		(end 137.163048 -102.585012)
		(stroke
			(width 0.04445)
			(type default)
		)
		(layer "In9.Cu")
	)
	(gr_line
		(start 137.163048 -102.407212)
		(end 137.23874 -102.33152)
		(stroke
			(width 0.04445)
			(type default)
		)
		(layer "In9.Cu")
	)
	(gr_line
		(start 137.19048 -104.410256)
		(end 137.19048 -104.528874)
		(stroke
			(width 0.04445)
			(type default)
		)
		(layer "In9.Cu")
	)
	(gr_line
		(start 137.19048 -104.410256)
		(end 137.316464 -104.284272)
		(stroke
			(width 0.04445)
			(type default)
		)
		(layer "In9.Cu")
	)
	(gr_line
		(start 137.316464 -104.284272)
		(end 137.435082 -104.284272)
		(stroke
			(width 0.04445)
			(type default)
		)
		(layer "In9.Cu")
	)
	(gr_arc
		(start 137.329418 -100.69195)
		(mid 137.327057 -100.686656)
		(end 137.324338 -100.681536)
		(stroke
			(width 0.04445)
			(type default)
		)
		(layer "In9.Cu")
	)
	(gr_line
		(start 137.35431 -97.766124)
		(end 137.377678 -97.678748)
		(stroke
			(width 0.04445)
			(type default)
		)
		(layer "In9.Cu")
	)
	(gr_line
		(start 137.377678 -97.678748)
		(end 137.670794 -97.509584)
		(stroke
			(width 0.04445)
			(type default)
		)
		(layer "In9.Cu")
	)
	(gr_line
		(start 137.489438 -105.274872)
		(end 137.489438 -105.39349)
		(stroke
			(width 0.04445)
			(type default)
		)
		(layer "In9.Cu")
	)
	(gr_line
		(start 137.489438 -105.274872)
		(end 137.615422 -105.148888)
		(stroke
			(width 0.04445)
			(type default)
		)
		(layer "In9.Cu")
	)
	(gr_line
		(start 137.556748 -105.464356)
		(end 137.804906 -105.216198)
		(stroke
			(width 0.1778)
			(type default)
		)
		(layer "In9.Cu")
	)
	(gr_line
		(start 137.564114 -104.036622)
		(end 137.564114 -104.15524)
		(stroke
			(width 0.04445)
			(type default)
		)
		(layer "In9.Cu")
	)
	(gr_line
		(start 137.564114 -104.036622)
		(end 137.690098 -103.910638)
		(stroke
			(width 0.04445)
			(type default)
		)
		(layer "In9.Cu")
	)
	(gr_line
		(start 137.615422 -105.148888)
		(end 137.73404 -105.148888)
		(stroke
			(width 0.04445)
			(type default)
		)
		(layer "In9.Cu")
	)
	(gr_line
		(start 137.653014 -90.975434)
		(end 137.688574 -90.975434)
		(stroke
			(width 0.04445)
			(type default)
		)
		(layer "In9.Cu")
	)
	(gr_line
		(start 137.653014 -89.984834)
		(end 137.688574 -89.984834)
		(stroke
			(width 0.04445)
			(type default)
		)
		(layer "In9.Cu")
	)
	(gr_line
		(start 137.690098 -103.910638)
		(end 137.808716 -103.910638)
		(stroke
			(width 0.04445)
			(type default)
		)
		(layer "In9.Cu")
	)
	(gr_line
		(start 137.804906 -105.216198)
		(end 137.930382 -105.090722)
		(stroke
			(width 0.1778)
			(type default)
		)
		(layer "In9.Cu")
	)
	(gr_line
		(start 137.851388 -102.957376)
		(end 137.935208 -103.041196)
		(stroke
			(width 0.04445)
			(type default)
		)
		(layer "In9.Cu")
	)
	(gr_line
		(start 137.851388 -102.779576)
		(end 137.851388 -102.957376)
		(stroke
			(width 0.04445)
			(type default)
		)
		(layer "In9.Cu")
	)
	(gr_line
		(start 137.851388 -102.779576)
		(end 137.935208 -102.695756)
		(stroke
			(width 0.04445)
			(type default)
		)
		(layer "In9.Cu")
	)
	(gr_line
		(start 137.851388 -102.429056)
		(end 137.935208 -102.512876)
		(stroke
			(width 0.04445)
			(type default)
		)
		(layer "In9.Cu")
	)
	(gr_line
		(start 137.851388 -102.251256)
		(end 137.851388 -102.429056)
		(stroke
			(width 0.04445)
			(type default)
		)
		(layer "In9.Cu")
	)
	(gr_line
		(start 137.851388 -102.251256)
		(end 137.935208 -102.167436)
		(stroke
			(width 0.04445)
			(type default)
		)
		(layer "In9.Cu")
	)
	(gr_line
		(start 137.863072 -104.901238)
		(end 137.863072 -105.019856)
		(stroke
			(width 0.04445)
			(type default)
		)
		(layer "In9.Cu")
	)
	(gr_line
		(start 137.863072 -104.901238)
		(end 137.989056 -104.775254)
		(stroke
			(width 0.04445)
			(type default)
		)
		(layer "In9.Cu")
	)
	(gr_line
		(start 137.871962 -103.48976)
		(end 137.935208 -103.553006)
		(stroke
			(width 0.04445)
			(type default)
		)
		(layer "In9.Cu")
	)
	(gr_line
		(start 137.871962 -103.31196)
		(end 137.871962 -103.48976)
		(stroke
			(width 0.04445)
			(type default)
		)
		(layer "In9.Cu")
	)
	(gr_line
		(start 137.871962 -103.31196)
		(end 137.935208 -103.248714)
		(stroke
			(width 0.04445)
			(type default)
		)
		(layer "In9.Cu")
	)
	(gr_line
		(start 137.930382 -105.090722)
		(end 138.17854 -104.842564)
		(stroke
			(width 0.1778)
			(type default)
		)
		(layer "In9.Cu")
	)
	(gr_line
		(start 137.989056 -104.775254)
		(end 138.107674 -104.775254)
		(stroke
			(width 0.04445)
			(type default)
		)
		(layer "In9.Cu")
	)
	(gr_line
		(start 138.017504 -99.290886)
		(end 138.02233 -99.299522)
		(stroke
			(width 0.04445)
			(type default)
		)
		(layer "In9.Cu")
	)
	(gr_line
		(start 138.177778 -100.1776)
		(end 138.182604 -100.186236)
		(stroke
			(width 0.04445)
			(type default)
		)
		(layer "In9.Cu")
	)
	(gr_line
		(start 138.17854 -104.842564)
		(end 138.304016 -104.717088)
		(stroke
			(width 0.1778)
			(type default)
		)
		(layer "In9.Cu")
	)
	(gr_line
		(start 138.199876 -105.78846)
		(end 138.199876 -105.788714)
		(stroke
			(width 0.04445)
			(type default)
		)
		(layer "In9.Cu")
	)
	(gr_line
		(start 138.199876 -105.78846)
		(end 138.21537 -105.772966)
		(stroke
			(width 0.04445)
			(type default)
		)
		(layer "In9.Cu")
	)
	(gr_line
		(start 138.21537 -105.772966)
		(end 138.229086 -105.772966)
		(stroke
			(width 0.04445)
			(type default)
		)
		(layer "In9.Cu")
	)
	(gr_line
		(start 138.231626 -105.772966)
		(end 138.287506 -105.772966)
		(stroke
			(width 0.04445)
			(type default)
		)
		(layer "In9.Cu")
	)
	(gr_line
		(start 138.236706 -104.527604)
		(end 138.236706 -104.646222)
		(stroke
			(width 0.04445)
			(type default)
		)
		(layer "In9.Cu")
	)
	(gr_line
		(start 138.236706 -104.527604)
		(end 138.36269 -104.40162)
		(stroke
			(width 0.04445)
			(type default)
		)
		(layer "In9.Cu")
	)
	(gr_line
		(start 138.304016 -104.717088)
		(end 138.552174 -104.46893)
		(stroke
			(width 0.1778)
			(type default)
		)
		(layer "In9.Cu")
	)
	(gr_line
		(start 138.313668 -111.510826)
		(end 138.313668 -111.741204)
		(stroke
			(width 0.05715)
			(type default)
		)
		(layer "In9.Cu")
	)
	(gr_line
		(start 138.313668 -111.510826)
		(end 138.556238 -111.26851)
		(stroke
			(width 0.05715)
			(type default)
		)
		(layer "In9.Cu")
	)
	(gr_line
		(start 138.36269 -104.40162)
		(end 138.481308 -104.40162)
		(stroke
			(width 0.04445)
			(type default)
		)
		(layer "In9.Cu")
	)
	(gr_line
		(start 138.406632 -105.995216)
		(end 138.422126 -105.979722)
		(stroke
			(width 0.04445)
			(type default)
		)
		(layer "In9.Cu")
	)
	(gr_line
		(start 138.422126 -105.966006)
		(end 138.422126 -105.979722)
		(stroke
			(width 0.04445)
			(type default)
		)
		(layer "In9.Cu")
	)
	(gr_line
		(start 138.422126 -105.908094)
		(end 138.422126 -105.963466)
		(stroke
			(width 0.04445)
			(type default)
		)
		(layer "In9.Cu")
	)
	(gr_line
		(start 138.552174 -104.46893)
		(end 138.67765 -104.343454)
		(stroke
			(width 0.1778)
			(type default)
		)
		(layer "In9.Cu")
	)
	(gr_line
		(start 138.556238 -111.26851)
		(end 138.786362 -111.26851)
		(stroke
			(width 0.05715)
			(type default)
		)
		(layer "In9.Cu")
	)
	(gr_line
		(start 138.61034 -104.15397)
		(end 138.61034 -104.272588)
		(stroke
			(width 0.04445)
			(type default)
		)
		(layer "In9.Cu")
	)
	(gr_line
		(start 138.61034 -104.15397)
		(end 138.736324 -104.027986)
		(stroke
			(width 0.04445)
			(type default)
		)
		(layer "In9.Cu")
	)
	(gr_line
		(start 138.67765 -104.343454)
		(end 138.925808 -104.095296)
		(stroke
			(width 0.1778)
			(type default)
		)
		(layer "In9.Cu")
	)
	(gr_line
		(start 138.721846 -105.216452)
		(end 138.721846 -105.335324)
		(stroke
			(width 0.04445)
			(type default)
		)
		(layer "In9.Cu")
	)
	(gr_line
		(start 138.721846 -105.216452)
		(end 138.84783 -105.090468)
		(stroke
			(width 0.04445)
			(type default)
		)
		(layer "In9.Cu")
	)
	(gr_line
		(start 138.728704 -111.742728)
		(end 138.787886 -111.683546)
		(stroke
			(width 0.05715)
			(type default)
		)
		(layer "In9.Cu")
	)
	(gr_line
		(start 138.736324 -104.027986)
		(end 138.854942 -104.027986)
		(stroke
			(width 0.04445)
			(type default)
		)
		(layer "In9.Cu")
	)
	(gr_line
		(start 138.84783 -105.090468)
		(end 138.966702 -105.090468)
		(stroke
			(width 0.04445)
			(type default)
		)
		(layer "In9.Cu")
	)
	(gr_line
		(start 138.87323 -101.670358)
		(end 138.944604 -101.741732)
		(stroke
			(width 0.04445)
			(type default)
		)
		(layer "In9.Cu")
	)
	(gr_line
		(start 138.87323 -101.492558)
		(end 138.87323 -101.670358)
		(stroke
			(width 0.04445)
			(type default)
		)
		(layer "In9.Cu")
	)
	(gr_line
		(start 138.87323 -101.492558)
		(end 138.944604 -101.421184)
		(stroke
			(width 0.04445)
			(type default)
		)
		(layer "In9.Cu")
	)
	(gr_line
		(start 138.87831 -105.451656)
		(end 138.968226 -105.36174)
		(stroke
			(width 0.04445)
			(type default)
		)
		(layer "In9.Cu")
	)
	(gr_line
		(start 138.918188 -103.518208)
		(end 138.981434 -103.581454)
		(stroke
			(width 0.04445)
			(type default)
		)
		(layer "In9.Cu")
	)
	(gr_line
		(start 138.918188 -103.340408)
		(end 138.918188 -103.518208)
		(stroke
			(width 0.04445)
			(type default)
		)
		(layer "In9.Cu")
	)
	(gr_line
		(start 138.918188 -103.340408)
		(end 138.981434 -103.277162)
		(stroke
			(width 0.04445)
			(type default)
		)
		(layer "In9.Cu")
	)
	(gr_line
		(start 138.925808 -104.095296)
		(end 139.051284 -103.96982)
		(stroke
			(width 0.1778)
			(type default)
		)
		(layer "In9.Cu")
	)
	(gr_line
		(start 139.032234 -110.792514)
		(end 139.032234 -111.022638)
		(stroke
			(width 0.05715)
			(type default)
		)
		(layer "In9.Cu")
	)
	(gr_line
		(start 139.032234 -110.792514)
		(end 139.27455 -110.549944)
		(stroke
			(width 0.05715)
			(type default)
		)
		(layer "In9.Cu")
	)
	(gr_line
		(start 139.036044 -101.016816)
		(end 138.958828 -100.729034)
		(stroke
			(width 0.1778)
			(type default)
		)
		(layer "In9.Cu")
	)
	(gr_line
		(start 139.042394 -102.166928)
		(end 139.042394 -101.744272)
		(stroke
			(width 0.1778)
			(type default)
		)
		(layer "In9.Cu")
	)
	(gr_line
		(start 139.042394 -101.744272)
		(end 139.042394 -101.418644)
		(stroke
			(width 0.1778)
			(type default)
		)
		(layer "In9.Cu")
	)
	(gr_line
		(start 139.042394 -101.418644)
		(end 139.042394 -101.040692)
		(stroke
			(width 0.1778)
			(type default)
		)
		(layer "In9.Cu")
	)
	(gr_line
		(start 139.042394 -101.040692)
		(end 139.036044 -101.016816)
		(stroke
			(width 0.1778)
			(type default)
		)
		(layer "In9.Cu")
	)
	(gr_line
		(start 139.051284 -103.96982)
		(end 139.079224 -103.90251)
		(stroke
			(width 0.1778)
			(type default)
		)
		(layer "In9.Cu")
	)
	(gr_line
		(start 139.07643 -107.266232)
		(end 139.07643 -107.49661)
		(stroke
			(width 0.05715)
			(type default)
		)
		(layer "In9.Cu")
	)
	(gr_line
		(start 139.07643 -107.266232)
		(end 139.319 -107.023916)
		(stroke
			(width 0.05715)
			(type default)
		)
		(layer "In9.Cu")
	)
	(gr_line
		(start 139.079224 -103.90251)
		(end 139.079224 -103.583994)
		(stroke
			(width 0.1778)
			(type default)
		)
		(layer "In9.Cu")
	)
	(gr_line
		(start 139.079224 -103.583994)
		(end 139.079224 -103.274622)
		(stroke
			(width 0.1778)
			(type default)
		)
		(layer "In9.Cu")
	)
	(gr_line
		(start 139.079224 -103.274622)
		(end 139.079224 -103.076248)
		(stroke
			(width 0.1778)
			(type default)
		)
		(layer "In9.Cu")
	)
	(gr_line
		(start 139.079224 -103.076248)
		(end 139.042394 -102.166928)
		(stroke
			(width 0.1778)
			(type default)
		)
		(layer "In9.Cu")
	)
	(gr_line
		(start 139.09548 -104.842818)
		(end 139.09548 -104.96169)
		(stroke
			(width 0.04445)
			(type default)
		)
		(layer "In9.Cu")
	)
	(gr_line
		(start 139.09548 -104.842818)
		(end 139.221464 -104.716834)
		(stroke
			(width 0.04445)
			(type default)
		)
		(layer "In9.Cu")
	)
	(gr_line
		(start 139.221464 -104.716834)
		(end 139.340336 -104.716834)
		(stroke
			(width 0.04445)
			(type default)
		)
		(layer "In9.Cu")
	)
	(gr_line
		(start 139.22248 -106.047794)
		(end 139.237974 -106.0323)
		(stroke
			(width 0.04445)
			(type default)
		)
		(layer "In9.Cu")
	)
	(gr_line
		(start 139.237974 -106.0323)
		(end 139.25169 -106.0323)
		(stroke
			(width 0.04445)
			(type default)
		)
		(layer "In9.Cu")
	)
	(gr_line
		(start 139.25423 -106.0323)
		(end 139.309602 -106.0323)
		(stroke
			(width 0.04445)
			(type default)
		)
		(layer "In9.Cu")
	)
	(gr_line
		(start 139.27455 -110.549944)
		(end 139.504928 -110.549944)
		(stroke
			(width 0.05715)
			(type default)
		)
		(layer "In9.Cu")
	)
	(gr_line
		(start 139.319 -107.023916)
		(end 139.549124 -107.023916)
		(stroke
			(width 0.05715)
			(type default)
		)
		(layer "In9.Cu")
	)
	(gr_line
		(start 139.325858 -106.151172)
		(end 139.341352 -106.135678)
		(stroke
			(width 0.1778)
			(type default)
		)
		(layer "In9.Cu")
	)
	(gr_line
		(start 139.340844 -108.2548)
		(end 139.340844 -108.413042)
		(stroke
			(width 0.05715)
			(type default)
		)
		(layer "In9.Cu")
	)
	(gr_line
		(start 139.340844 -108.2548)
		(end 139.583668 -108.011976)
		(stroke
			(width 0.05715)
			(type default)
		)
		(layer "In9.Cu")
	)
	(gr_line
		(start 139.377166 -106.09961)
		(end 139.584176 -105.892346)
		(stroke
			(width 0.1778)
			(type default)
		)
		(layer "In9.Cu")
	)
	(gr_line
		(start 139.429236 -106.25455)
		(end 139.44473 -106.239056)
		(stroke
			(width 0.04445)
			(type default)
		)
		(layer "In9.Cu")
	)
	(gr_line
		(start 139.44473 -106.22534)
		(end 139.44473 -106.239056)
		(stroke
			(width 0.04445)
			(type default)
		)
		(layer "In9.Cu")
	)
	(gr_line
		(start 139.44473 -106.16692)
		(end 139.44473 -106.2228)
		(stroke
			(width 0.04445)
			(type default)
		)
		(layer "In9.Cu")
	)
	(gr_line
		(start 139.44727 -111.024162)
		(end 139.506452 -110.96498)
		(stroke
			(width 0.05715)
			(type default)
		)
		(layer "In9.Cu")
	)
	(gr_line
		(start 139.469114 -104.469184)
		(end 139.469114 -104.587802)
		(stroke
			(width 0.04445)
			(type default)
		)
		(layer "In9.Cu")
	)
	(gr_line
		(start 139.469114 -104.469184)
		(end 139.595098 -104.3432)
		(stroke
			(width 0.04445)
			(type default)
		)
		(layer "In9.Cu")
	)
	(gr_line
		(start 139.491466 -107.498134)
		(end 139.550648 -107.438952)
		(stroke
			(width 0.05715)
			(type default)
		)
		(layer "In9.Cu")
	)
	(gr_line
		(start 139.516866 -105.68178)
		(end 139.516866 -105.821734)
		(stroke
			(width 0.04445)
			(type default)
		)
		(layer "In9.Cu")
	)
	(gr_line
		(start 139.516866 -105.68178)
		(end 139.642596 -105.55605)
		(stroke
			(width 0.04445)
			(type default)
		)
		(layer "In9.Cu")
	)
	(gr_line
		(start 139.583668 -108.011976)
		(end 139.74191 -108.011976)
		(stroke
			(width 0.05715)
			(type default)
		)
		(layer "In9.Cu")
	)
	(gr_line
		(start 139.584176 -105.892346)
		(end 139.853162 -105.62336)
		(stroke
			(width 0.1778)
			(type default)
		)
		(layer "In9.Cu")
	)
	(gr_line
		(start 139.595098 -104.3432)
		(end 139.713716 -104.3432)
		(stroke
			(width 0.04445)
			(type default)
		)
		(layer "In9.Cu")
	)
	(gr_line
		(start 139.601702 -101.281738)
		(end 139.694158 -101.374194)
		(stroke
			(width 0.04445)
			(type default)
		)
		(layer "In9.Cu")
	)
	(gr_line
		(start 139.601702 -101.103938)
		(end 139.601702 -101.281738)
		(stroke
			(width 0.04445)
			(type default)
		)
		(layer "In9.Cu")
	)
	(gr_line
		(start 139.601702 -101.103938)
		(end 139.694158 -101.011482)
		(stroke
			(width 0.04445)
			(type default)
		)
		(layer "In9.Cu")
	)
	(gr_line
		(start 139.642596 -105.55605)
		(end 139.78255 -105.55605)
		(stroke
			(width 0.04445)
			(type default)
		)
		(layer "In9.Cu")
	)
	(gr_line
		(start 139.741656 -103.640128)
		(end 139.840208 -103.73868)
		(stroke
			(width 0.04445)
			(type default)
		)
		(layer "In9.Cu")
	)
	(gr_line
		(start 139.741656 -103.462328)
		(end 139.741656 -103.640128)
		(stroke
			(width 0.04445)
			(type default)
		)
		(layer "In9.Cu")
	)
	(gr_line
		(start 139.741656 -103.462328)
		(end 139.840208 -103.363776)
		(stroke
			(width 0.04445)
			(type default)
		)
		(layer "In9.Cu")
	)
	(gr_line
		(start 139.741656 -103.082344)
		(end 139.840208 -103.180896)
		(stroke
			(width 0.04445)
			(type default)
		)
		(layer "In9.Cu")
	)
	(gr_line
		(start 139.741656 -102.904544)
		(end 139.741656 -103.082344)
		(stroke
			(width 0.04445)
			(type default)
		)
		(layer "In9.Cu")
	)
	(gr_line
		(start 139.741656 -102.904544)
		(end 139.840208 -102.805992)
		(stroke
			(width 0.04445)
			(type default)
		)
		(layer "In9.Cu")
	)
	(gr_line
		(start 139.853162 -105.62336)
		(end 139.978638 -105.497884)
		(stroke
			(width 0.1778)
			(type default)
		)
		(layer "In9.Cu")
	)
	(gr_line
		(start 139.896342 -98.804476)
		(end 139.901168 -98.79584)
		(stroke
			(width 0.04445)
			(type default)
		)
		(layer "In9.Cu")
	)
	(gr_line
		(start 139.911328 -105.287318)
		(end 139.911328 -105.427272)
		(stroke
			(width 0.04445)
			(type default)
		)
		(layer "In9.Cu")
	)
	(gr_line
		(start 139.911328 -105.287318)
		(end 140.037058 -105.161588)
		(stroke
			(width 0.04445)
			(type default)
		)
		(layer "In9.Cu")
	)
	(gr_line
		(start 139.978638 -105.497884)
		(end 140.247624 -105.228898)
		(stroke
			(width 0.1778)
			(type default)
		)
		(layer "In9.Cu")
	)
	(gr_line
		(start 140.037058 -105.161588)
		(end 140.177012 -105.161588)
		(stroke
			(width 0.04445)
			(type default)
		)
		(layer "In9.Cu")
	)
	(gr_line
		(start 140.247624 -105.228898)
		(end 140.3731 -105.103422)
		(stroke
			(width 0.1778)
			(type default)
		)
		(layer "In9.Cu")
	)
	(gr_line
		(start 140.30579 -104.892856)
		(end 140.30579 -105.03281)
		(stroke
			(width 0.04445)
			(type default)
		)
		(layer "In9.Cu")
	)
	(gr_line
		(start 140.30579 -104.892856)
		(end 140.43152 -104.767126)
		(stroke
			(width 0.04445)
			(type default)
		)
		(layer "In9.Cu")
	)
	(gr_line
		(start 140.43152 -104.767126)
		(end 140.571474 -104.767126)
		(stroke
			(width 0.04445)
			(type default)
		)
		(layer "In9.Cu")
	)
	(gr_line
		(start 140.438378 -100.97643)
		(end 140.512546 -101.050598)
		(stroke
			(width 0.04445)
			(type default)
		)
		(layer "In9.Cu")
	)
	(gr_line
		(start 140.438378 -100.79863)
		(end 140.438378 -100.97643)
		(stroke
			(width 0.04445)
			(type default)
		)
		(layer "In9.Cu")
	)
	(gr_line
		(start 140.438378 -100.79863)
		(end 140.512546 -100.724462)
		(stroke
			(width 0.04445)
			(type default)
		)
		(layer "In9.Cu")
	)
	(gr_line
		(start 140.515086 -100.515674)
		(end 140.515086 -100.696014)
		(stroke
			(width 0.04445)
			(type default)
		)
		(layer "In9.Cu")
	)
	(gr_line
		(start 140.569188 -90.673428)
		(end 140.66774 -90.77198)
		(stroke
			(width 0.04445)
			(type default)
		)
		(layer "In9.Cu")
	)
	(gr_line
		(start 140.59916 -104.215438)
		(end 140.697712 -104.31399)
		(stroke
			(width 0.04445)
			(type default)
		)
		(layer "In9.Cu")
	)
	(gr_line
		(start 140.59916 -104.037638)
		(end 140.59916 -104.215438)
		(stroke
			(width 0.04445)
			(type default)
		)
		(layer "In9.Cu")
	)
	(gr_line
		(start 140.59916 -104.037638)
		(end 140.697712 -103.939086)
		(stroke
			(width 0.04445)
			(type default)
		)
		(layer "In9.Cu")
	)
	(gr_line
		(start 140.59916 -103.657654)
		(end 140.697712 -103.756206)
		(stroke
			(width 0.04445)
			(type default)
		)
		(layer "In9.Cu")
	)
	(gr_line
		(start 140.59916 -103.479854)
		(end 140.59916 -103.657654)
		(stroke
			(width 0.04445)
			(type default)
		)
		(layer "In9.Cu")
	)
	(gr_line
		(start 140.59916 -103.479854)
		(end 140.697712 -103.381302)
		(stroke
			(width 0.04445)
			(type default)
		)
		(layer "In9.Cu")
	)
	(gr_line
		(start 140.59916 -103.09987)
		(end 140.697712 -103.198422)
		(stroke
			(width 0.04445)
			(type default)
		)
		(layer "In9.Cu")
	)
	(gr_line
		(start 140.59916 -102.92207)
		(end 140.59916 -103.09987)
		(stroke
			(width 0.04445)
			(type default)
		)
		(layer "In9.Cu")
	)
	(gr_line
		(start 140.59916 -102.92207)
		(end 140.697712 -102.823518)
		(stroke
			(width 0.04445)
			(type default)
		)
		(layer "In9.Cu")
	)
	(gr_line
		(start 140.611606 -102.542086)
		(end 140.697712 -102.628192)
		(stroke
			(width 0.04445)
			(type default)
		)
		(layer "In9.Cu")
	)
	(gr_line
		(start 140.611606 -102.364286)
		(end 140.611606 -102.542086)
		(stroke
			(width 0.04445)
			(type default)
		)
		(layer "In9.Cu")
	)
	(gr_line
		(start 140.611606 -102.364286)
		(end 140.697712 -102.27818)
		(stroke
			(width 0.04445)
			(type default)
		)
		(layer "In9.Cu")
	)
	(gr_line
		(start 140.66774 -90.77198)
		(end 140.84554 -90.77198)
		(stroke
			(width 0.04445)
			(type default)
		)
		(layer "In9.Cu")
	)
	(gr_line
		(start 140.705332 -100.505514)
		(end 140.705586 -100.505514)
		(stroke
			(width 0.04445)
			(type default)
		)
		(layer "In9.Cu")
	)
	(gr_line
		(start 140.753592 -98.308922)
		(end 140.758418 -98.300286)
		(stroke
			(width 0.04445)
			(type default)
		)
		(layer "In9.Cu")
	)
	(gr_line
		(start 140.769848 -95.138494)
		(end 140.787628 -95.168974)
		(stroke
			(width 0.04445)
			(type default)
		)
		(layer "In9.Cu")
	)
	(gr_line
		(start 140.787628 -95.168974)
		(end 140.819632 -95.182182)
		(stroke
			(width 0.04445)
			(type default)
		)
		(layer "In9.Cu")
	)
	(gr_line
		(start 140.84554 -90.77198)
		(end 140.944092 -90.673428)
		(stroke
			(width 0.04445)
			(type default)
		)
		(layer "In9.Cu")
	)
	(gr_line
		(start 140.862812 -92.899484)
		(end 140.988796 -93.025468)
		(stroke
			(width 0.04445)
			(type default)
		)
		(layer "In9.Cu")
	)
	(gr_line
		(start 140.862812 -92.780866)
		(end 140.862812 -92.899484)
		(stroke
			(width 0.04445)
			(type default)
		)
		(layer "In9.Cu")
	)
	(gr_line
		(start 140.988796 -93.025468)
		(end 141.107414 -93.025468)
		(stroke
			(width 0.04445)
			(type default)
		)
		(layer "In9.Cu")
	)
	(gr_line
		(start 141.004544 -95.26143)
		(end 141.039596 -95.346012)
		(stroke
			(width 0.04445)
			(type default)
		)
		(layer "In9.Cu")
	)
	(gr_line
		(start 141.039596 -95.346012)
		(end 141.204188 -95.414084)
		(stroke
			(width 0.04445)
			(type default)
		)
		(layer "In9.Cu")
	)
	(gr_line
		(start 141.103858 -96.11868)
		(end 141.105636 -96.11868)
		(stroke
			(width 0.04445)
			(type default)
		)
		(layer "In9.Cu")
	)
	(gr_line
		(start 141.105128 -95.094044)
		(end 141.338046 -95.190564)
		(stroke
			(width 0.04445)
			(type default)
		)
		(layer "In9.Cu")
	)
	(gr_line
		(start 141.12367 -95.928434)
		(end 141.126464 -95.928434)
		(stroke
			(width 0.04445)
			(type default)
		)
		(layer "In9.Cu")
	)
	(gr_line
		(start 141.183106 -95.93326)
		(end 141.183614 -95.93326)
		(stroke
			(width 0.04445)
			(type default)
		)
		(layer "In9.Cu")
	)
	(gr_line
		(start 141.204188 -95.414084)
		(end 141.28877 -95.379032)
		(stroke
			(width 0.04445)
			(type default)
		)
		(layer "In9.Cu")
	)
	(gr_line
		(start 141.236446 -93.273118)
		(end 141.36243 -93.399102)
		(stroke
			(width 0.04445)
			(type default)
		)
		(layer "In9.Cu")
	)
	(gr_line
		(start 141.236446 -93.1545)
		(end 141.236446 -93.273118)
		(stroke
			(width 0.04445)
			(type default)
		)
		(layer "In9.Cu")
	)
	(gr_line
		(start 141.299184 -100.671376)
		(end 141.397736 -100.769928)
		(stroke
			(width 0.04445)
			(type default)
		)
		(layer "In9.Cu")
	)
	(gr_line
		(start 141.299184 -100.493576)
		(end 141.299184 -100.671376)
		(stroke
			(width 0.04445)
			(type default)
		)
		(layer "In9.Cu")
	)
	(gr_line
		(start 141.299184 -100.493576)
		(end 141.397736 -100.395024)
		(stroke
			(width 0.04445)
			(type default)
		)
		(layer "In9.Cu")
	)
	(gr_line
		(start 141.299184 -100.07092)
		(end 141.397736 -100.169472)
		(stroke
			(width 0.04445)
			(type default)
		)
		(layer "In9.Cu")
	)
	(gr_line
		(start 141.299184 -99.89312)
		(end 141.299184 -100.07092)
		(stroke
			(width 0.04445)
			(type default)
		)
		(layer "In9.Cu")
	)
	(gr_line
		(start 141.299184 -99.89312)
		(end 141.397736 -99.794568)
		(stroke
			(width 0.04445)
			(type default)
		)
		(layer "In9.Cu")
	)
	(gr_line
		(start 141.326108 -90.93962)
		(end 141.451838 -91.06535)
		(stroke
			(width 0.04445)
			(type default)
		)
		(layer "In9.Cu")
	)
	(gr_line
		(start 141.326108 -90.79992)
		(end 141.326108 -90.93962)
		(stroke
			(width 0.04445)
			(type default)
		)
		(layer "In9.Cu")
	)
	(gr_line
		(start 141.327886 -99.513136)
		(end 141.397736 -99.582986)
		(stroke
			(width 0.04445)
			(type default)
		)
		(layer "In9.Cu")
	)
	(gr_line
		(start 141.327886 -99.335336)
		(end 141.327886 -99.513136)
		(stroke
			(width 0.04445)
			(type default)
		)
		(layer "In9.Cu")
	)
	(gr_line
		(start 141.327886 -99.335336)
		(end 141.397736 -99.265486)
		(stroke
			(width 0.04445)
			(type default)
		)
		(layer "In9.Cu")
	)
	(gr_line
		(start 141.36243 -93.399102)
		(end 141.481048 -93.399102)
		(stroke
			(width 0.04445)
			(type default)
		)
		(layer "In9.Cu")
	)
	(gr_line
		(start 141.451838 -91.06535)
		(end 141.591538 -91.06535)
		(stroke
			(width 0.04445)
			(type default)
		)
		(layer "In9.Cu")
	)
	(gr_line
		(start 141.472666 -95.455232)
		(end 141.509242 -95.544132)
		(stroke
			(width 0.04445)
			(type default)
		)
		(layer "In9.Cu")
	)
	(gr_line
		(start 141.482318 -98.28657)
		(end 141.48816 -98.297492)
		(stroke
			(width 0.04445)
			(type default)
		)
		(layer "In9.Cu")
	)
	(gr_line
		(start 141.509242 -95.544132)
		(end 141.673834 -95.61195)
		(stroke
			(width 0.04445)
			(type default)
		)
		(layer "In9.Cu")
	)
	(gr_line
		(start 141.513052 -102.095808)
		(end 141.584426 -102.167182)
		(stroke
			(width 0.04445)
			(type default)
		)
		(layer "In9.Cu")
	)
	(gr_line
		(start 141.513052 -101.918008)
		(end 141.513052 -102.095808)
		(stroke
			(width 0.04445)
			(type default)
		)
		(layer "In9.Cu")
	)
	(gr_line
		(start 141.513052 -101.918008)
		(end 141.584426 -101.846634)
		(stroke
			(width 0.04445)
			(type default)
		)
		(layer "In9.Cu")
	)
	(gr_line
		(start 141.536166 -102.466648)
		(end 141.536166 -102.488746)
		(stroke
			(width 0.04445)
			(type default)
		)
		(layer "In9.Cu")
	)
	(gr_line
		(start 141.536166 -102.466648)
		(end 141.545818 -102.456996)
		(stroke
			(width 0.04445)
			(type default)
		)
		(layer "In9.Cu")
	)
	(gr_line
		(start 141.547596 -102.455218)
		(end 141.586966 -102.415848)
		(stroke
			(width 0.04445)
			(type default)
		)
		(layer "In9.Cu")
	)
	(gr_line
		(start 141.572742 -95.287846)
		(end 141.810486 -95.386398)
		(stroke
			(width 0.04445)
			(type default)
		)
		(layer "In9.Cu")
	)
	(gr_arc
		(start 141.656562 -96.811592)
		(mid 141.661374 -96.801412)
		(end 141.665706 -96.791018)
		(stroke
			(width 0.04445)
			(type default)
		)
		(layer "In9.Cu")
	)
	(gr_line
		(start 141.673834 -95.61195)
		(end 141.762226 -95.575374)
		(stroke
			(width 0.04445)
			(type default)
		)
		(layer "In9.Cu")
	)
	(gr_line
		(start 141.72057 -91.334082)
		(end 141.8463 -91.459812)
		(stroke
			(width 0.04445)
			(type default)
		)
		(layer "In9.Cu")
	)
	(gr_line
		(start 141.72057 -91.194382)
		(end 141.72057 -91.334082)
		(stroke
			(width 0.04445)
			(type default)
		)
		(layer "In9.Cu")
	)
	(gr_line
		(start 141.777466 -102.415848)
		(end 141.816836 -102.455218)
		(stroke
			(width 0.04445)
			(type default)
		)
		(layer "In9.Cu")
	)
	(gr_line
		(start 141.818614 -102.456996)
		(end 141.828266 -102.466648)
		(stroke
			(width 0.04445)
			(type default)
		)
		(layer "In9.Cu")
	)
	(gr_line
		(start 141.828266 -102.466648)
		(end 141.828266 -102.488746)
		(stroke
			(width 0.04445)
			(type default)
		)
		(layer "In9.Cu")
	)
	(gr_line
		(start 141.8463 -91.459812)
		(end 141.986 -91.459812)
		(stroke
			(width 0.04445)
			(type default)
		)
		(layer "In9.Cu")
	)
	(gr_line
		(start 141.94282 -95.65005)
		(end 141.979142 -95.737934)
		(stroke
			(width 0.04445)
			(type default)
		)
		(layer "In9.Cu")
	)
	(gr_line
		(start 141.979142 -95.737934)
		(end 142.143734 -95.806006)
		(stroke
			(width 0.04445)
			(type default)
		)
		(layer "In9.Cu")
	)
	(gr_line
		(start 142.042388 -95.48241)
		(end 142.279624 -95.580708)
		(stroke
			(width 0.04445)
			(type default)
		)
		(layer "In9.Cu")
	)
	(gr_line
		(start 142.115032 -91.728544)
		(end 142.240762 -91.854274)
		(stroke
			(width 0.04445)
			(type default)
		)
		(layer "In9.Cu")
	)
	(gr_line
		(start 142.115032 -91.588844)
		(end 142.115032 -91.728544)
		(stroke
			(width 0.04445)
			(type default)
		)
		(layer "In9.Cu")
	)
	(gr_line
		(start 142.143734 -95.806006)
		(end 142.231364 -95.769684)
		(stroke
			(width 0.04445)
			(type default)
		)
		(layer "In9.Cu")
	)
	(gr_line
		(start 142.240762 -91.854274)
		(end 142.380462 -91.854274)
		(stroke
			(width 0.04445)
			(type default)
		)
		(layer "In9.Cu")
	)
	(gr_line
		(start 142.321026 -93.64472)
		(end 142.386304 -93.709998)
		(stroke
			(width 0.04445)
			(type default)
		)
		(layer "In9.Cu")
	)
	(gr_line
		(start 142.386304 -93.709998)
		(end 142.564104 -93.709998)
		(stroke
			(width 0.04445)
			(type default)
		)
		(layer "In9.Cu")
	)
	(gr_line
		(start 142.464028 -98.10496)
		(end 142.56258 -98.203512)
		(stroke
			(width 0.04445)
			(type default)
		)
		(layer "In9.Cu")
	)
	(gr_line
		(start 142.464028 -97.92716)
		(end 142.464028 -98.10496)
		(stroke
			(width 0.04445)
			(type default)
		)
		(layer "In9.Cu")
	)
	(gr_line
		(start 142.464028 -97.92716)
		(end 142.56258 -97.828608)
		(stroke
			(width 0.04445)
			(type default)
		)
		(layer "In9.Cu")
	)
	(gr_line
		(start 142.464028 -97.547176)
		(end 142.56258 -97.645728)
		(stroke
			(width 0.04445)
			(type default)
		)
		(layer "In9.Cu")
	)
	(gr_line
		(start 142.464028 -97.369376)
		(end 142.464028 -97.547176)
		(stroke
			(width 0.04445)
			(type default)
		)
		(layer "In9.Cu")
	)
	(gr_line
		(start 142.464028 -97.369376)
		(end 142.56258 -97.270824)
		(stroke
			(width 0.04445)
			(type default)
		)
		(layer "In9.Cu")
	)
	(gr_line
		(start 142.464028 -96.989392)
		(end 142.56258 -97.087944)
		(stroke
			(width 0.04445)
			(type default)
		)
		(layer "In9.Cu")
	)
	(gr_line
		(start 142.464028 -96.811592)
		(end 142.464028 -96.989392)
		(stroke
			(width 0.04445)
			(type default)
		)
		(layer "In9.Cu")
	)
	(gr_line
		(start 142.464028 -96.811592)
		(end 142.56258 -96.71304)
		(stroke
			(width 0.04445)
			(type default)
		)
		(layer "In9.Cu")
	)
	(gr_line
		(start 142.478506 -96.435672)
		(end 142.56258 -96.519746)
		(stroke
			(width 0.04445)
			(type default)
		)
		(layer "In9.Cu")
	)
	(gr_line
		(start 142.478506 -96.257872)
		(end 142.478506 -96.435672)
		(stroke
			(width 0.04445)
			(type default)
		)
		(layer "In9.Cu")
	)
	(gr_line
		(start 142.478506 -96.257872)
		(end 142.56258 -96.173798)
		(stroke
			(width 0.04445)
			(type default)
		)
		(layer "In9.Cu")
	)
	(gr_line
		(start 142.47876 -99.176332)
		(end 142.56258 -99.260152)
		(stroke
			(width 0.04445)
			(type default)
		)
		(layer "In9.Cu")
	)
	(gr_line
		(start 142.47876 -98.998532)
		(end 142.47876 -99.176332)
		(stroke
			(width 0.04445)
			(type default)
		)
		(layer "In9.Cu")
	)
	(gr_line
		(start 142.47876 -98.998532)
		(end 142.56258 -98.914712)
		(stroke
			(width 0.04445)
			(type default)
		)
		(layer "In9.Cu")
	)
	(gr_line
		(start 142.47876 -98.648012)
		(end 142.56258 -98.731832)
		(stroke
			(width 0.04445)
			(type default)
		)
		(layer "In9.Cu")
	)
	(gr_line
		(start 142.47876 -98.470212)
		(end 142.47876 -98.648012)
		(stroke
			(width 0.04445)
			(type default)
		)
		(layer "In9.Cu")
	)
	(gr_line
		(start 142.47876 -98.470212)
		(end 142.56258 -98.386392)
		(stroke
			(width 0.04445)
			(type default)
		)
		(layer "In9.Cu")
	)
	(gr_line
		(start 142.491206 -99.704652)
		(end 142.56258 -99.776026)
		(stroke
			(width 0.04445)
			(type default)
		)
		(layer "In9.Cu")
	)
	(gr_line
		(start 142.491206 -99.526852)
		(end 142.491206 -99.704652)
		(stroke
			(width 0.04445)
			(type default)
		)
		(layer "In9.Cu")
	)
	(gr_line
		(start 142.491206 -99.526852)
		(end 142.56258 -99.455478)
		(stroke
			(width 0.04445)
			(type default)
		)
		(layer "In9.Cu")
	)
	(gr_line
		(start 142.509494 -92.123006)
		(end 142.635224 -92.248736)
		(stroke
			(width 0.04445)
			(type default)
		)
		(layer "In9.Cu")
	)
	(gr_line
		(start 142.509494 -91.983306)
		(end 142.509494 -92.123006)
		(stroke
			(width 0.04445)
			(type default)
		)
		(layer "In9.Cu")
	)
	(gr_line
		(start 142.512034 -94.898972)
		(end 142.638018 -95.024956)
		(stroke
			(width 0.04445)
			(type default)
		)
		(layer "In9.Cu")
	)
	(gr_line
		(start 142.512034 -94.761812)
		(end 142.512034 -94.898972)
		(stroke
			(width 0.04445)
			(type default)
		)
		(layer "In9.Cu")
	)
	(gr_line
		(start 142.51432 -100.144834)
		(end 142.51432 -100.166932)
		(stroke
			(width 0.04445)
			(type default)
		)
		(layer "In9.Cu")
	)
	(gr_line
		(start 142.51432 -100.144834)
		(end 142.523972 -100.135182)
		(stroke
			(width 0.04445)
			(type default)
		)
		(layer "In9.Cu")
	)
	(gr_line
		(start 142.52575 -100.133404)
		(end 142.56512 -100.094034)
		(stroke
			(width 0.04445)
			(type default)
		)
		(layer "In9.Cu")
	)
	(gr_line
		(start 142.547594 -95.691706)
		(end 142.554198 -95.6945)
		(stroke
			(width 0.04445)
			(type default)
		)
		(layer "In9.Cu")
	)
	(gr_line
		(start 142.564104 -93.709998)
		(end 142.629382 -93.64472)
		(stroke
			(width 0.04445)
			(type default)
		)
		(layer "In9.Cu")
	)
	(gr_line
		(start 142.635224 -92.248736)
		(end 142.774924 -92.248736)
		(stroke
			(width 0.04445)
			(type default)
		)
		(layer "In9.Cu")
	)
	(gr_line
		(start 142.638018 -95.024956)
		(end 142.775178 -95.024956)
		(stroke
			(width 0.04445)
			(type default)
		)
		(layer "In9.Cu")
	)
	(gr_line
		(start 142.75562 -100.094034)
		(end 142.79499 -100.133404)
		(stroke
			(width 0.04445)
			(type default)
		)
		(layer "In9.Cu")
	)
	(gr_line
		(start 142.796768 -100.135182)
		(end 142.80642 -100.144834)
		(stroke
			(width 0.04445)
			(type default)
		)
		(layer "In9.Cu")
	)
	(gr_line
		(start 142.80642 -100.144834)
		(end 142.80642 -100.166932)
		(stroke
			(width 0.04445)
			(type default)
		)
		(layer "In9.Cu")
	)
	(gr_line
		(start 142.903956 -92.517468)
		(end 143.029686 -92.643198)
		(stroke
			(width 0.04445)
			(type default)
		)
		(layer "In9.Cu")
	)
	(gr_line
		(start 142.903956 -92.377768)
		(end 142.903956 -92.517468)
		(stroke
			(width 0.04445)
			(type default)
		)
		(layer "In9.Cu")
	)
	(gr_line
		(start 142.906242 -95.289116)
		(end 143.032226 -95.4151)
		(stroke
			(width 0.04445)
			(type default)
		)
		(layer "In9.Cu")
	)
	(gr_line
		(start 142.906242 -95.15602)
		(end 142.906242 -95.289116)
		(stroke
			(width 0.04445)
			(type default)
		)
		(layer "In9.Cu")
	)
	(gr_line
		(start 143.029686 -92.643198)
		(end 143.169386 -92.643198)
		(stroke
			(width 0.04445)
			(type default)
		)
		(layer "In9.Cu")
	)
	(gr_line
		(start 143.032226 -95.4151)
		(end 143.165322 -95.4151)
		(stroke
			(width 0.04445)
			(type default)
		)
		(layer "In9.Cu")
	)
	(gr_line
		(start 143.158972 -94.007432)
		(end 143.174466 -94.022926)
		(stroke
			(width 0.04445)
			(type default)
		)
		(layer "In9.Cu")
	)
	(gr_line
		(start 143.158972 -93.993716)
		(end 143.158972 -94.007432)
		(stroke
			(width 0.04445)
			(type default)
		)
		(layer "In9.Cu")
	)
	(gr_line
		(start 143.158972 -93.935296)
		(end 143.158972 -93.991176)
		(stroke
			(width 0.04445)
			(type default)
		)
		(layer "In9.Cu")
	)
	(gr_line
		(start 143.187928 -97.665286)
		(end 143.28648 -97.763838)
		(stroke
			(width 0.04445)
			(type default)
		)
		(layer "In9.Cu")
	)
	(gr_line
		(start 143.187928 -97.487486)
		(end 143.187928 -97.665286)
		(stroke
			(width 0.04445)
			(type default)
		)
		(layer "In9.Cu")
	)
	(gr_line
		(start 143.187928 -97.487486)
		(end 143.28648 -97.388934)
		(stroke
			(width 0.04445)
			(type default)
		)
		(layer "In9.Cu")
	)
	(gr_line
		(start 143.187928 -97.107502)
		(end 143.28648 -97.206054)
		(stroke
			(width 0.04445)
			(type default)
		)
		(layer "In9.Cu")
	)
	(gr_line
		(start 143.187928 -96.929702)
		(end 143.187928 -97.107502)
		(stroke
			(width 0.04445)
			(type default)
		)
		(layer "In9.Cu")
	)
	(gr_line
		(start 143.187928 -96.929702)
		(end 143.28648 -96.83115)
		(stroke
			(width 0.04445)
			(type default)
		)
		(layer "In9.Cu")
	)
	(gr_line
		(start 143.187928 -96.549718)
		(end 143.28648 -96.64827)
		(stroke
			(width 0.04445)
			(type default)
		)
		(layer "In9.Cu")
	)
	(gr_line
		(start 143.187928 -96.371918)
		(end 143.187928 -96.549718)
		(stroke
			(width 0.04445)
			(type default)
		)
		(layer "In9.Cu")
	)
	(gr_line
		(start 143.187928 -96.371918)
		(end 143.28648 -96.273366)
		(stroke
			(width 0.04445)
			(type default)
		)
		(layer "In9.Cu")
	)
	(gr_line
		(start 143.187928 -95.991934)
		(end 143.28648 -96.090486)
		(stroke
			(width 0.04445)
			(type default)
		)
		(layer "In9.Cu")
	)
	(gr_line
		(start 143.187928 -95.814134)
		(end 143.187928 -95.991934)
		(stroke
			(width 0.04445)
			(type default)
		)
		(layer "In9.Cu")
	)
	(gr_line
		(start 143.187928 -95.814134)
		(end 143.28648 -95.715582)
		(stroke
			(width 0.04445)
			(type default)
		)
		(layer "In9.Cu")
	)
	(gr_line
		(start 143.23822 -98.165158)
		(end 143.23822 -98.187256)
		(stroke
			(width 0.04445)
			(type default)
		)
		(layer "In9.Cu")
	)
	(gr_line
		(start 143.23822 -98.165158)
		(end 143.247872 -98.155506)
		(stroke
			(width 0.04445)
			(type default)
		)
		(layer "In9.Cu")
	)
	(gr_line
		(start 143.24965 -98.153728)
		(end 143.28902 -98.114358)
		(stroke
			(width 0.04445)
			(type default)
		)
		(layer "In9.Cu")
	)
	(gr_line
		(start 143.2941 -93.800676)
		(end 143.349472 -93.800676)
		(stroke
			(width 0.04445)
			(type default)
		)
		(layer "In9.Cu")
	)
	(gr_line
		(start 143.352012 -93.800676)
		(end 143.365474 -93.800676)
		(stroke
			(width 0.04445)
			(type default)
		)
		(layer "In9.Cu")
	)
	(gr_line
		(start 143.365474 -93.800676)
		(end 143.380968 -93.81617)
		(stroke
			(width 0.04445)
			(type default)
		)
		(layer "In9.Cu")
	)
	(gr_line
		(start 143.47952 -98.114358)
		(end 143.51889 -98.153728)
		(stroke
			(width 0.04445)
			(type default)
		)
		(layer "In9.Cu")
	)
	(gr_line
		(start 143.520668 -98.155506)
		(end 143.53032 -98.165158)
		(stroke
			(width 0.04445)
			(type default)
		)
		(layer "In9.Cu")
	)
	(gr_line
		(start 143.53032 -98.165158)
		(end 143.53032 -98.187256)
		(stroke
			(width 0.04445)
			(type default)
		)
		(layer "In9.Cu")
	)
	(gr_line
		(start 143.765524 -93.307916)
		(end 143.781018 -93.32341)
		(stroke
			(width 0.04445)
			(type default)
		)
		(layer "In9.Cu")
	)
	(gr_line
		(start 143.765524 -93.2942)
		(end 143.765524 -93.307916)
		(stroke
			(width 0.04445)
			(type default)
		)
		(layer "In9.Cu")
	)
	(gr_line
		(start 143.765524 -93.23578)
		(end 143.765524 -93.29166)
		(stroke
			(width 0.04445)
			(type default)
		)
		(layer "In9.Cu")
	)
	(gr_line
		(start 143.781018 -93.323156)
		(end 143.781018 -93.32341)
		(stroke
			(width 0.04445)
			(type default)
		)
		(layer "In9.Cu")
	)
	(gr_line
		(start 143.900398 -93.10116)
		(end 143.956024 -93.10116)
		(stroke
			(width 0.04445)
			(type default)
		)
		(layer "In9.Cu")
	)
	(gr_line
		(start 143.958564 -93.10116)
		(end 143.97228 -93.10116)
		(stroke
			(width 0.04445)
			(type default)
		)
		(layer "In9.Cu")
	)
	(gr_line
		(start 143.97228 -93.10116)
		(end 143.987774 -93.116654)
		(stroke
			(width 0.04445)
			(type default)
		)
		(layer "In9.Cu")
	)
	(gr_line
		(start 169.975276 -89.206324)
		(end 170.18254 -89.206324)
		(stroke
			(width 0.05715)
			(type default)
		)
		(layer "In9.Cu")
	)
	(gr_line
		(start 170.18254 -89.206324)
		(end 170.335702 -89.053162)
		(stroke
			(width 0.05715)
			(type default)
		)
		(layer "In9.Cu")
	)
	(gr_line
		(start 170.752262 -89.053162)
		(end 170.905424 -89.206324)
		(stroke
			(width 0.05715)
			(type default)
		)
		(layer "In9.Cu")
	)
	(gr_line
		(start 170.905424 -89.206324)
		(end 171.245276 -89.206324)
		(stroke
			(width 0.05715)
			(type default)
		)
		(layer "In9.Cu")
	)
	(gr_line
		(start 176.64176 -77.131926)
		(end 177.06848 -77.558646)
		(stroke
			(width 0.05715)
			(type default)
		)
		(layer "In9.Cu")
	)
	(gr_line
		(start 176.64176 -76.715366)
		(end 177.06848 -76.288646)
		(stroke
			(width 0.05715)
			(type default)
		)
		(layer "In9.Cu")
	)
	(gr_line
		(start 176.83099 -65.42786)
		(end 176.83099 -65.51168)
		(stroke
			(width 0.05715)
			(type default)
		)
		(layer "In9.Cu")
	)
	(gr_line
		(start 176.83099 -64.41186)
		(end 176.83099 -64.49568)
		(stroke
			(width 0.05715)
			(type default)
		)
		(layer "In9.Cu")
	)
	(gr_line
		(start 176.83099 -63.39586)
		(end 176.83099 -63.47968)
		(stroke
			(width 0.05715)
			(type default)
		)
		(layer "In9.Cu")
	)
	(gr_line
		(start 176.83099 -62.37986)
		(end 176.83099 -62.46368)
		(stroke
			(width 0.05715)
			(type default)
		)
		(layer "In9.Cu")
	)
	(gr_line
		(start 177.12563 -65.80378)
		(end 177.28819 -65.64122)
		(stroke
			(width 0.05715)
			(type default)
		)
		(layer "In9.Cu")
	)
	(gr_line
		(start 177.12563 -65.13576)
		(end 177.28819 -65.29832)
		(stroke
			(width 0.05715)
			(type default)
		)
		(layer "In9.Cu")
	)
	(gr_line
		(start 177.12563 -64.78778)
		(end 177.28819 -64.62522)
		(stroke
			(width 0.05715)
			(type default)
		)
		(layer "In9.Cu")
	)
	(gr_line
		(start 177.12563 -64.11976)
		(end 177.28819 -64.28232)
		(stroke
			(width 0.05715)
			(type default)
		)
		(layer "In9.Cu")
	)
	(gr_line
		(start 177.12563 -63.77178)
		(end 177.28819 -63.60922)
		(stroke
			(width 0.05715)
			(type default)
		)
		(layer "In9.Cu")
	)
	(gr_line
		(start 177.12563 -63.10376)
		(end 177.28819 -63.26632)
		(stroke
			(width 0.05715)
			(type default)
		)
		(layer "In9.Cu")
	)
	(gr_line
		(start 177.12563 -62.75578)
		(end 177.28819 -62.59322)
		(stroke
			(width 0.05715)
			(type default)
		)
		(layer "In9.Cu")
	)
	(gr_line
		(start 177.12563 -62.08776)
		(end 177.28819 -62.25032)
		(stroke
			(width 0.05715)
			(type default)
		)
		(layer "In9.Cu")
	)
	(gr_line
		(start 177.170334 -82.289904)
		(end 177.170334 -82.677)
		(stroke
			(width 0.05715)
			(type default)
		)
		(layer "In9.Cu")
	)
	(gr_line
		(start 177.170334 -82.289904)
		(end 177.222404 -82.237834)
		(stroke
			(width 0.05715)
			(type default)
		)
		(layer "In9.Cu")
	)
	(gr_line
		(start 177.170334 -81.76895)
		(end 177.222404 -81.82102)
		(stroke
			(width 0.05715)
			(type default)
		)
		(layer "In9.Cu")
	)
	(gr_line
		(start 177.170334 -81.407)
		(end 177.170334 -81.76895)
		(stroke
			(width 0.05715)
			(type default)
		)
		(layer "In9.Cu")
	)
	(gr_line
		(start 177.28819 -65.29832)
		(end 177.28819 -65.64122)
		(stroke
			(width 0.05715)
			(type default)
		)
		(layer "In9.Cu")
	)
	(gr_line
		(start 177.28819 -64.28232)
		(end 177.28819 -64.62522)
		(stroke
			(width 0.05715)
			(type default)
		)
		(layer "In9.Cu")
	)
	(gr_line
		(start 177.28819 -63.26632)
		(end 177.28819 -63.60922)
		(stroke
			(width 0.05715)
			(type default)
		)
		(layer "In9.Cu")
	)
	(gr_line
		(start 177.28819 -62.25032)
		(end 177.28819 -62.59322)
		(stroke
			(width 0.05715)
			(type default)
		)
		(layer "In9.Cu")
	)
	(gr_line
		(start 178.918616 -80.23225)
		(end 179.345336 -79.80553)
		(stroke
			(width 0.05715)
			(type default)
		)
		(layer "In9.Cu")
	)
	(gr_line
		(start 178.918616 -78.96225)
		(end 179.345336 -79.38897)
		(stroke
			(width 0.05715)
			(type default)
		)
		(layer "In9.Cu")
	)
	(gr_line
		(start 182.271162 -59.774328)
		(end 182.330344 -59.715146)
		(stroke
			(width 0.05715)
			(type default)
		)
		(layer "In9.Cu")
	)
	(gr_line
		(start 182.272686 -60.189364)
		(end 182.503064 -60.189364)
		(stroke
			(width 0.05715)
			(type default)
		)
		(layer "In9.Cu")
	)
	(gr_line
		(start 182.503064 -60.189364)
		(end 182.74538 -59.947048)
		(stroke
			(width 0.05715)
			(type default)
		)
		(layer "In9.Cu")
	)
	(gr_line
		(start 182.74538 -59.71667)
		(end 182.74538 -59.947048)
		(stroke
			(width 0.05715)
			(type default)
		)
		(layer "In9.Cu")
	)
	(gr_line
		(start 182.989474 -59.056016)
		(end 183.048656 -58.996834)
		(stroke
			(width 0.05715)
			(type default)
		)
		(layer "In9.Cu")
	)
	(gr_line
		(start 182.990998 -59.471052)
		(end 183.221122 -59.471052)
		(stroke
			(width 0.05715)
			(type default)
		)
		(layer "In9.Cu")
	)
	(gr_line
		(start 183.221122 -59.471052)
		(end 183.463692 -59.228482)
		(stroke
			(width 0.05715)
			(type default)
		)
		(layer "In9.Cu")
	)
	(gr_line
		(start 183.463692 -58.998358)
		(end 183.463692 -59.228482)
		(stroke
			(width 0.05715)
			(type default)
		)
		(layer "In9.Cu")
	)
	(gr_line
		(start 225.705416 -101.880924)
		(end 225.75012 -101.870002)
		(stroke
			(width 0.05715)
			(type default)
		)
		(layer "In9.Cu")
	)
	(gr_line
		(start 225.75012 -101.870002)
		(end 225.782632 -101.83749)
		(stroke
			(width 0.05715)
			(type default)
		)
		(layer "In9.Cu")
	)
	(gr_line
		(start 226.332796 -102.764082)
		(end 226.379278 -102.753414)
		(stroke
			(width 0.05715)
			(type default)
		)
		(layer "In9.Cu")
	)
	(gr_line
		(start 226.379278 -102.753414)
		(end 226.41306 -102.719632)
		(stroke
			(width 0.05715)
			(type default)
		)
		(layer "In9.Cu")
	)
	(gr_line
		(start 227.279454 -101.43998)
		(end 227.339144 -101.38029)
		(stroke
			(width 0.05715)
			(type default)
		)
		(layer "In9.Cu")
	)
	(gr_line
		(start 228.294692 -98.912172)
		(end 228.35362 -98.853244)
		(stroke
			(width 0.05715)
			(type default)
		)
		(layer "In9.Cu")
	)
	(gr_line
		(start 239.940846 -102.507796)
		(end 239.958626 -102.50043)
		(stroke
			(width 0.05715)
			(type default)
		)
		(layer "In9.Cu")
	)
	(gr_line
		(start 242.221258 -103.29799)
		(end 242.23853 -103.290624)
		(stroke
			(width 0.05715)
			(type default)
		)
		(layer "In9.Cu")
	)
	(gr_line
		(start 243.689378 -100.642166)
		(end 243.707158 -100.6348)
		(stroke
			(width 0.05715)
			(type default)
		)
		(layer "In9.Cu")
	)
	(gr_line
		(start 247.107202 -101.27488)
		(end 247.125744 -101.26726)
		(stroke
			(width 0.05715)
			(type default)
		)
		(layer "In9.Cu")
	)
	(gr_line
		(start 247.125744 -101.26726)
		(end 247.140476 -101.252528)
		(stroke
			(width 0.05715)
			(type default)
		)
		(layer "In9.Cu")
	)
	(gr_line
		(start 247.260872 -100.719128)
		(end 247.3198 -100.6602)
		(stroke
			(width 0.05715)
			(type default)
		)
		(layer "In9.Cu")
	)
	(gr_line
		(start 253.287784 -50.15484)
		(end 253.450344 -50.3174)
		(stroke
			(width 0.05715)
			(type default)
		)
		(layer "In9.Cu")
	)
	(gr_line
		(start 253.450344 -50.3174)
		(end 253.793244 -50.3174)
		(stroke
			(width 0.05715)
			(type default)
		)
		(layer "In9.Cu")
	)
	(gr_line
		(start 253.579884 -49.8602)
		(end 253.663704 -49.8602)
		(stroke
			(width 0.05715)
			(type default)
		)
		(layer "In9.Cu")
	)
	(gr_line
		(start 253.793244 -50.3174)
		(end 253.955804 -50.15484)
		(stroke
			(width 0.05715)
			(type default)
		)
		(layer "In9.Cu")
	)
	(gr_line
		(start 254.303784 -50.15484)
		(end 254.466344 -50.3174)
		(stroke
			(width 0.05715)
			(type default)
		)
		(layer "In9.Cu")
	)
	(gr_line
		(start 254.466344 -50.3174)
		(end 254.809244 -50.3174)
		(stroke
			(width 0.05715)
			(type default)
		)
		(layer "In9.Cu")
	)
	(gr_line
		(start 254.595884 -49.8602)
		(end 254.679704 -49.8602)
		(stroke
			(width 0.05715)
			(type default)
		)
		(layer "In9.Cu")
	)
	(gr_line
		(start 254.809244 -50.3174)
		(end 254.971804 -50.15484)
		(stroke
			(width 0.05715)
			(type default)
		)
		(layer "In9.Cu")
	)
	(gr_line
		(start 255.319784 -50.15484)
		(end 255.482344 -50.3174)
		(stroke
			(width 0.05715)
			(type default)
		)
		(layer "In9.Cu")
	)
	(gr_line
		(start 255.482344 -50.3174)
		(end 255.825244 -50.3174)
		(stroke
			(width 0.05715)
			(type default)
		)
		(layer "In9.Cu")
	)
	(gr_line
		(start 255.611884 -49.8602)
		(end 255.695704 -49.8602)
		(stroke
			(width 0.05715)
			(type default)
		)
		(layer "In9.Cu")
	)
	(gr_line
		(start 255.767078 -48.50003)
		(end 255.929638 -48.66259)
		(stroke
			(width 0.05715)
			(type default)
		)
		(layer "In9.Cu")
	)
	(gr_line
		(start 255.825244 -50.3174)
		(end 255.987804 -50.15484)
		(stroke
			(width 0.05715)
			(type default)
		)
		(layer "In9.Cu")
	)
	(gr_line
		(start 255.929638 -48.66259)
		(end 256.272538 -48.66259)
		(stroke
			(width 0.05715)
			(type default)
		)
		(layer "In9.Cu")
	)
	(gr_line
		(start 256.059178 -48.20539)
		(end 256.142998 -48.20539)
		(stroke
			(width 0.05715)
			(type default)
		)
		(layer "In9.Cu")
	)
	(gr_line
		(start 256.272538 -48.66259)
		(end 256.435098 -48.50003)
		(stroke
			(width 0.05715)
			(type default)
		)
		(layer "In9.Cu")
	)
	(gr_line
		(start 256.335784 -50.15484)
		(end 256.498344 -50.3174)
		(stroke
			(width 0.05715)
			(type default)
		)
		(layer "In9.Cu")
	)
	(gr_line
		(start 256.498344 -50.3174)
		(end 256.841244 -50.3174)
		(stroke
			(width 0.05715)
			(type default)
		)
		(layer "In9.Cu")
	)
	(gr_line
		(start 256.627884 -49.8602)
		(end 256.711704 -49.8602)
		(stroke
			(width 0.05715)
			(type default)
		)
		(layer "In9.Cu")
	)
	(gr_line
		(start 256.783078 -48.50003)
		(end 256.945638 -48.66259)
		(stroke
			(width 0.05715)
			(type default)
		)
		(layer "In9.Cu")
	)
	(gr_line
		(start 256.841244 -50.3174)
		(end 257.003804 -50.15484)
		(stroke
			(width 0.05715)
			(type default)
		)
		(layer "In9.Cu")
	)
	(gr_line
		(start 256.945638 -48.66259)
		(end 257.288538 -48.66259)
		(stroke
			(width 0.05715)
			(type default)
		)
		(layer "In9.Cu")
	)
	(gr_line
		(start 257.075178 -48.20539)
		(end 257.158998 -48.20539)
		(stroke
			(width 0.05715)
			(type default)
		)
		(layer "In9.Cu")
	)
	(gr_line
		(start 257.288538 -48.66259)
		(end 257.451098 -48.50003)
		(stroke
			(width 0.05715)
			(type default)
		)
		(layer "In9.Cu")
	)
	(gr_line
		(start 257.799078 -48.50003)
		(end 257.961638 -48.66259)
		(stroke
			(width 0.05715)
			(type default)
		)
		(layer "In9.Cu")
	)
	(gr_line
		(start 257.961638 -48.66259)
		(end 258.304538 -48.66259)
		(stroke
			(width 0.05715)
			(type default)
		)
		(layer "In9.Cu")
	)
	(gr_line
		(start 258.091178 -48.20539)
		(end 258.174998 -48.20539)
		(stroke
			(width 0.05715)
			(type default)
		)
		(layer "In9.Cu")
	)
	(gr_line
		(start 258.304538 -48.66259)
		(end 258.467098 -48.50003)
		(stroke
			(width 0.05715)
			(type default)
		)
		(layer "In9.Cu")
	)
	(gr_line
		(start 260.446012 -50.3047)
		(end 260.457188 -50.324004)
		(stroke
			(width 0.04445)
			(type default)
		)
		(layer "In9.Cu")
	)
	(gr_line
		(start 260.457188 -50.324004)
		(end 260.522974 -50.34153)
		(stroke
			(width 0.04445)
			(type default)
		)
		(layer "In9.Cu")
	)
	(gr_line
		(start 260.556502 -49.913032)
		(end 260.558026 -49.914556)
		(stroke
			(width 0.05715)
			(type default)
		)
		(layer "In9.Cu")
	)
	(gr_line
		(start 260.558026 -49.914556)
		(end 260.559042 -49.916334)
		(stroke
			(width 0.05715)
			(type default)
		)
		(layer "In9.Cu")
	)
	(gr_line
		(start 260.68274 -51.278282)
		(end 260.729476 -51.313588)
		(stroke
			(width 0.05715)
			(type default)
		)
		(layer "In9.Cu")
	)
	(gr_line
		(start 260.692392 -50.24374)
		(end 260.710172 -50.177954)
		(stroke
			(width 0.04445)
			(type default)
		)
		(layer "In9.Cu")
	)
	(gr_line
		(start 260.698996 -50.15865)
		(end 260.710172 -50.177954)
		(stroke
			(width 0.04445)
			(type default)
		)
		(layer "In9.Cu")
	)
	(gr_line
		(start 261.027164 -51.90236)
		(end 261.044436 -51.915314)
		(stroke
			(width 0.04445)
			(type default)
		)
		(layer "In9.Cu")
	)
	(gr_line
		(start 261.044436 -51.915314)
		(end 261.112254 -51.905662)
		(stroke
			(width 0.04445)
			(type default)
		)
		(layer "In9.Cu")
	)
	(gr_line
		(start 261.202678 -51.66868)
		(end 261.220204 -51.681888)
		(stroke
			(width 0.04445)
			(type default)
		)
		(layer "In9.Cu")
	)
	(gr_line
		(start 261.220204 -51.681888)
		(end 261.229348 -51.748944)
		(stroke
			(width 0.04445)
			(type default)
		)
		(layer "In9.Cu")
	)
	(gr_line
		(start 261.788402 -52.172108)
		(end 261.794498 -52.17668)
		(stroke
			(width 0.04445)
			(type default)
		)
		(layer "In9.Cu")
	)
	(gr_line
		(start 261.794498 -52.17668)
		(end 261.798308 -52.183538)
		(stroke
			(width 0.04445)
			(type default)
		)
		(layer "In9.Cu")
	)
	(gr_line
		(start 264.347198 -5.093716)
		(end 264.426192 -5.093716)
		(stroke
			(width 0.050546)
			(type default)
		)
		(layer "In9.Cu")
	)
	(gr_line
		(start 264.764012 -5.348986)
		(end 264.843006 -5.348986)
		(stroke
			(width 0.050546)
			(type default)
		)
		(layer "In9.Cu")
	)
	(gr_line
		(start 267.331952 -55.750968)
		(end 267.373354 -55.79237)
		(stroke
			(width 0.04445)
			(type default)
		)
		(layer "In9.Cu")
	)
	(gr_line
		(start 267.33373 -55.479696)
		(end 267.455904 -55.479696)
		(stroke
			(width 0.04445)
			(type default)
		)
		(layer "In9.Cu")
	)
	(gr_line
		(start 267.455904 -55.479696)
		(end 267.644626 -55.668418)
		(stroke
			(width 0.04445)
			(type default)
		)
		(layer "In9.Cu")
	)
	(gr_line
		(start 267.60805 -54.390544)
		(end 267.977112 -54.488334)
		(stroke
			(width 0.04445)
			(type default)
		)
		(layer "In9.Cu")
	)
	(gr_line
		(start 267.630148 -54.196742)
		(end 267.735812 -54.135274)
		(stroke
			(width 0.04445)
			(type default)
		)
		(layer "In9.Cu")
	)
	(gr_line
		(start 267.644626 -55.668418)
		(end 267.644626 -55.790592)
		(stroke
			(width 0.04445)
			(type default)
		)
		(layer "In9.Cu")
	)
	(gr_line
		(start 267.735812 -54.135274)
		(end 267.993622 -54.203854)
		(stroke
			(width 0.04445)
			(type default)
		)
		(layer "In9.Cu")
	)
	(gr_line
		(start 267.834872 -56.253888)
		(end 267.876274 -56.29529)
		(stroke
			(width 0.04445)
			(type default)
		)
		(layer "In9.Cu")
	)
	(gr_line
		(start 267.83665 -55.982616)
		(end 267.958824 -55.982616)
		(stroke
			(width 0.04445)
			(type default)
		)
		(layer "In9.Cu")
	)
	(gr_line
		(start 267.958824 -55.982616)
		(end 268.147546 -56.171338)
		(stroke
			(width 0.04445)
			(type default)
		)
		(layer "In9.Cu")
	)
	(gr_line
		(start 267.993622 -54.203854)
		(end 268.054836 -54.309518)
		(stroke
			(width 0.04445)
			(type default)
		)
		(layer "In9.Cu")
	)
	(gr_line
		(start 268.147546 -56.171338)
		(end 268.147546 -56.293512)
		(stroke
			(width 0.04445)
			(type default)
		)
		(layer "In9.Cu")
	)
	(gr_line
		(start 268.295374 -54.572916)
		(end 268.664944 -54.67096)
		(stroke
			(width 0.04445)
			(type default)
		)
		(layer "In9.Cu")
	)
	(gr_line
		(start 268.317218 -54.379114)
		(end 268.423136 -54.317646)
		(stroke
			(width 0.04445)
			(type default)
		)
		(layer "In9.Cu")
	)
	(gr_line
		(start 268.423136 -54.317646)
		(end 268.680946 -54.386226)
		(stroke
			(width 0.04445)
			(type default)
		)
		(layer "In9.Cu")
	)
	(gr_line
		(start 268.680946 -54.386226)
		(end 268.74216 -54.492144)
		(stroke
			(width 0.04445)
			(type default)
		)
		(layer "In9.Cu")
	)
	(gr_line
		(start 268.730984 -56.485536)
		(end 268.741906 -56.49087)
		(stroke
			(width 0.04445)
			(type default)
		)
		(layer "In9.Cu")
	)
	(gr_line
		(start 268.955012 -54.550818)
		(end 269.001748 -54.563264)
		(stroke
			(width 0.04445)
			(type default)
		)
		(layer "In9.Cu")
	)
	(gr_line
		(start 269.001748 -54.563264)
		(end 269.026132 -54.604412)
		(stroke
			(width 0.04445)
			(type default)
		)
		(layer "In9.Cu")
	)
	(gr_line
		(start 269.107412 -55.117238)
		(end 269.3035 -55.448962)
		(stroke
			(width 0.04445)
			(type default)
		)
		(layer "In9.Cu")
	)
	(gr_line
		(start 269.259812 -54.995572)
		(end 269.37843 -55.026306)
		(stroke
			(width 0.04445)
			(type default)
		)
		(layer "In9.Cu")
	)
	(gr_line
		(start 269.37843 -55.026306)
		(end 269.514066 -55.255922)
		(stroke
			(width 0.04445)
			(type default)
		)
		(layer "In9.Cu")
	)
	(gr_line
		(start 269.483586 -55.37454)
		(end 269.514066 -55.255922)
		(stroke
			(width 0.04445)
			(type default)
		)
		(layer "In9.Cu")
	)
	(gr_line
		(start 270.078708 -56.45023)
		(end 270.1163 -56.494934)
		(stroke
			(width 0.04445)
			(type default)
		)
		(layer "In9.Cu")
	)
	(gr_line
		(start 270.357854 -57.4802)
		(end 270.368776 -57.485534)
		(stroke
			(width 0.04445)
			(type default)
		)
		(layer "In9.Cu")
	)
	(gr_line
		(start 270.942308 -57.683654)
		(end 270.942562 -57.683654)
		(stroke
			(width 0.04445)
			(type default)
		)
		(layer "In9.Cu")
	)
	(gr_line
		(start 273.348704 -102.67696)
		(end 273.511264 -102.5144)
		(stroke
			(width 0.05715)
			(type default)
		)
		(layer "In9.Cu")
	)
	(gr_line
		(start 273.511264 -102.5144)
		(end 273.866864 -102.5144)
		(stroke
			(width 0.05715)
			(type default)
		)
		(layer "In9.Cu")
	)
	(gr_line
		(start 273.640804 -102.9716)
		(end 273.737324 -102.9716)
		(stroke
			(width 0.05715)
			(type default)
		)
		(layer "In9.Cu")
	)
	(gr_line
		(start 273.866864 -102.5144)
		(end 274.029424 -102.67696)
		(stroke
			(width 0.05715)
			(type default)
		)
		(layer "In9.Cu")
	)
	(gr_line
		(start 274.390104 -102.67696)
		(end 274.552664 -102.5144)
		(stroke
			(width 0.05715)
			(type default)
		)
		(layer "In9.Cu")
	)
	(gr_line
		(start 274.399502 -58.670698)
		(end 274.402804 -58.67654)
		(stroke
			(width 0.04445)
			(type default)
		)
		(layer "In9.Cu")
	)
	(gr_line
		(start 274.552664 -102.5144)
		(end 274.908264 -102.5144)
		(stroke
			(width 0.05715)
			(type default)
		)
		(layer "In9.Cu")
	)
	(gr_line
		(start 274.568158 -59.571382)
		(end 274.57146 -59.577224)
		(stroke
			(width 0.04445)
			(type default)
		)
		(layer "In9.Cu")
	)
	(gr_line
		(start 274.682204 -102.9716)
		(end 274.778724 -102.9716)
		(stroke
			(width 0.05715)
			(type default)
		)
		(layer "In9.Cu")
	)
	(gr_line
		(start 274.908264 -102.5144)
		(end 275.070824 -102.67696)
		(stroke
			(width 0.05715)
			(type default)
		)
		(layer "In9.Cu")
	)
	(gr_line
		(start 275.420328 -104.03586)
		(end 275.582888 -103.8733)
		(stroke
			(width 0.05715)
			(type default)
		)
		(layer "In9.Cu")
	)
	(gr_line
		(start 275.582888 -103.8733)
		(end 275.925788 -103.8733)
		(stroke
			(width 0.05715)
			(type default)
		)
		(layer "In9.Cu")
	)
	(gr_line
		(start 275.712428 -104.3305)
		(end 275.796248 -104.3305)
		(stroke
			(width 0.05715)
			(type default)
		)
		(layer "In9.Cu")
	)
	(gr_line
		(start 275.925788 -103.8733)
		(end 276.088348 -104.03586)
		(stroke
			(width 0.05715)
			(type default)
		)
		(layer "In9.Cu")
	)
	(gr_line
		(start 276.352508 -101.755956)
		(end 276.368002 -101.740462)
		(stroke
			(width 0.04445)
			(type default)
		)
		(layer "In9.Cu")
	)
	(gr_line
		(start 276.368002 -101.740462)
		(end 276.381464 -101.740462)
		(stroke
			(width 0.04445)
			(type default)
		)
		(layer "In9.Cu")
	)
	(gr_line
		(start 276.384004 -101.740462)
		(end 276.440138 -101.740462)
		(stroke
			(width 0.04445)
			(type default)
		)
		(layer "In9.Cu")
	)
	(gr_line
		(start 276.436328 -104.03586)
		(end 276.598888 -103.8733)
		(stroke
			(width 0.05715)
			(type default)
		)
		(layer "In9.Cu")
	)
	(gr_line
		(start 276.55901 -101.962966)
		(end 276.574504 -101.947472)
		(stroke
			(width 0.04445)
			(type default)
		)
		(layer "In9.Cu")
	)
	(gr_line
		(start 276.574504 -101.933502)
		(end 276.574504 -101.947472)
		(stroke
			(width 0.04445)
			(type default)
		)
		(layer "In9.Cu")
	)
	(gr_line
		(start 276.574504 -101.87559)
		(end 276.574504 -101.930962)
		(stroke
			(width 0.04445)
			(type default)
		)
		(layer "In9.Cu")
	)
	(gr_line
		(start 276.598888 -103.8733)
		(end 276.941788 -103.8733)
		(stroke
			(width 0.05715)
			(type default)
		)
		(layer "In9.Cu")
	)
	(gr_line
		(start 276.728428 -104.3305)
		(end 276.812248 -104.3305)
		(stroke
			(width 0.05715)
			(type default)
		)
		(layer "In9.Cu")
	)
	(gr_line
		(start 276.941788 -103.8733)
		(end 277.104348 -104.03586)
		(stroke
			(width 0.05715)
			(type default)
		)
		(layer "In9.Cu")
	)
	(gr_line
		(start 279.189688 -104.3305)
		(end 279.248616 -104.271572)
		(stroke
			(width 0.05715)
			(type default)
		)
		(layer "In9.Cu")
	)
	(gr_line
		(start 280.311606 -102.79507)
		(end 280.3271 -102.779576)
		(stroke
			(width 0.04445)
			(type default)
		)
		(layer "In9.Cu")
	)
	(gr_line
		(start 280.3271 -102.779576)
		(end 280.340816 -102.779576)
		(stroke
			(width 0.04445)
			(type default)
		)
		(layer "In9.Cu")
	)
	(gr_line
		(start 280.343356 -102.779576)
		(end 280.398728 -102.779576)
		(stroke
			(width 0.04445)
			(type default)
		)
		(layer "In9.Cu")
	)
	(gr_line
		(start 280.518362 -103.001826)
		(end 280.533856 -102.986332)
		(stroke
			(width 0.04445)
			(type default)
		)
		(layer "In9.Cu")
	)
	(gr_line
		(start 280.533856 -102.972616)
		(end 280.533856 -102.986332)
		(stroke
			(width 0.04445)
			(type default)
		)
		(layer "In9.Cu")
	)
	(gr_line
		(start 280.533856 -102.914196)
		(end 280.533856 -102.970076)
		(stroke
			(width 0.04445)
			(type default)
		)
		(layer "In9.Cu")
	)
	(gr_line
		(start 280.792428 -102.260146)
		(end 280.792428 -102.382574)
		(stroke
			(width 0.04445)
			(type default)
		)
		(layer "In9.Cu")
	)
	(gr_line
		(start 280.792428 -102.260146)
		(end 280.98115 -102.071424)
		(stroke
			(width 0.04445)
			(type default)
		)
		(layer "In9.Cu")
	)
	(gr_line
		(start 280.98115 -102.071424)
		(end 281.103578 -102.071424)
		(stroke
			(width 0.04445)
			(type default)
		)
		(layer "In9.Cu")
	)
	(gr_line
		(start 281.0637 -102.384352)
		(end 281.105356 -102.342696)
		(stroke
			(width 0.04445)
			(type default)
		)
		(layer "In9.Cu")
	)
	(gr_line
		(start 281.295348 -101.757226)
		(end 281.295348 -101.879654)
		(stroke
			(width 0.04445)
			(type default)
		)
		(layer "In9.Cu")
	)
	(gr_line
		(start 281.295348 -101.757226)
		(end 281.48407 -101.568504)
		(stroke
			(width 0.04445)
			(type default)
		)
		(layer "In9.Cu")
	)
	(gr_line
		(start 281.48407 -101.568504)
		(end 281.606498 -101.568504)
		(stroke
			(width 0.04445)
			(type default)
		)
		(layer "In9.Cu")
	)
	(gr_line
		(start 281.56662 -101.881432)
		(end 281.608276 -101.839776)
		(stroke
			(width 0.04445)
			(type default)
		)
		(layer "In9.Cu")
	)
	(gr_line
		(start 281.798268 -101.254306)
		(end 281.798268 -101.376734)
		(stroke
			(width 0.04445)
			(type default)
		)
		(layer "In9.Cu")
	)
	(gr_line
		(start 281.798268 -101.254306)
		(end 281.98699 -101.065584)
		(stroke
			(width 0.04445)
			(type default)
		)
		(layer "In9.Cu")
	)
	(gr_line
		(start 281.98699 -101.065584)
		(end 282.109418 -101.065584)
		(stroke
			(width 0.04445)
			(type default)
		)
		(layer "In9.Cu")
	)
	(gr_line
		(start 282.06954 -101.378512)
		(end 282.111196 -101.336856)
		(stroke
			(width 0.04445)
			(type default)
		)
		(layer "In9.Cu")
	)
	(gr_line
		(start 285.501334 -87.603584)
		(end 285.794196 -87.772494)
		(stroke
			(width 0.04445)
			(type default)
		)
		(layer "In9.Cu")
	)
	(gr_line
		(start 285.794196 -87.772494)
		(end 285.817818 -87.860632)
		(stroke
			(width 0.04445)
			(type default)
		)
		(layer "In9.Cu")
	)
	(gr_line
		(start 285.84144 -94.327472)
		(end 285.84779 -94.33814)
		(stroke
			(width 0.04445)
			(type default)
		)
		(layer "In9.Cu")
	)
	(gr_line
		(start 285.989268 -87.95131)
		(end 286.066738 -87.930228)
		(stroke
			(width 0.04445)
			(type default)
		)
		(layer "In9.Cu")
	)
	(gr_line
		(start 286.013144 -95.232982)
		(end 286.019494 -95.24365)
		(stroke
			(width 0.04445)
			(type default)
		)
		(layer "In9.Cu")
	)
	(gr_line
		(start 286.066738 -87.930228)
		(end 286.3596 -88.099138)
		(stroke
			(width 0.04445)
			(type default)
		)
		(layer "In9.Cu")
	)
	(gr_line
		(start 286.3596 -89.089738)
		(end 286.652716 -88.920574)
		(stroke
			(width 0.04445)
			(type default)
		)
		(layer "In9.Cu")
	)
	(gr_line
		(start 286.652716 -88.920574)
		(end 286.729678 -88.941402)
		(stroke
			(width 0.04445)
			(type default)
		)
		(layer "In9.Cu")
	)
	(gr_line
		(start 286.70631 -94.242636)
		(end 286.711136 -94.234)
		(stroke
			(width 0.04445)
			(type default)
		)
		(layer "In9.Cu")
	)
	(gr_line
		(start 286.866584 -95.337122)
		(end 286.87141 -95.328486)
		(stroke
			(width 0.04445)
			(type default)
		)
		(layer "In9.Cu")
	)
	(gr_line
		(start 286.866584 -70.572122)
		(end 286.87141 -70.563486)
		(stroke
			(width 0.04445)
			(type default)
		)
		(layer "In9.Cu")
	)
	(gr_line
		(start 286.901636 -88.850724)
		(end 286.925004 -88.763348)
		(stroke
			(width 0.04445)
			(type default)
		)
		(layer "In9.Cu")
	)
	(gr_line
		(start 286.925004 -88.763348)
		(end 287.21812 -88.594184)
		(stroke
			(width 0.04445)
			(type default)
		)
		(layer "In9.Cu")
	)
	(gr_line
		(start 287.153096 -72.341486)
		(end 287.195514 -72.383904)
		(stroke
			(width 0.04445)
			(type default)
		)
		(layer "In9.Cu")
	)
	(gr_line
		(start 287.160208 -72.14997)
		(end 287.195514 -72.114664)
		(stroke
			(width 0.04445)
			(type default)
		)
		(layer "In9.Cu")
	)
	(gr_line
		(start 287.197292 -72.385682)
		(end 287.21812 -72.40651)
		(stroke
			(width 0.04445)
			(type default)
		)
		(layer "In9.Cu")
	)
	(gr_line
		(start 287.197292 -72.112886)
		(end 287.21812 -72.092058)
		(stroke
			(width 0.04445)
			(type default)
		)
		(layer "In9.Cu")
	)
	(gr_line
		(start 287.21812 -72.40651)
		(end 287.21812 -72.744584)
		(stroke
			(width 0.04445)
			(type default)
		)
		(layer "In9.Cu")
	)
	(gr_line
		(start 287.21812 -71.753984)
		(end 287.21812 -72.092058)
		(stroke
			(width 0.04445)
			(type default)
		)
		(layer "In9.Cu")
	)
	(gr_line
		(start 288.011616 -69.864986)
		(end 288.054288 -69.907658)
		(stroke
			(width 0.04445)
			(type default)
		)
		(layer "In9.Cu")
	)
	(gr_line
		(start 288.018728 -69.673724)
		(end 288.054288 -69.638164)
		(stroke
			(width 0.04445)
			(type default)
		)
		(layer "In9.Cu")
	)
	(gr_line
		(start 288.056066 -69.909436)
		(end 288.07664 -69.93001)
		(stroke
			(width 0.04445)
			(type default)
		)
		(layer "In9.Cu")
	)
	(gr_line
		(start 288.056066 -69.636386)
		(end 288.07664 -69.615812)
		(stroke
			(width 0.04445)
			(type default)
		)
		(layer "In9.Cu")
	)
	(gr_line
		(start 288.07664 -69.93001)
		(end 288.07664 -70.268084)
		(stroke
			(width 0.04445)
			(type default)
		)
		(layer "In9.Cu")
	)
	(gr_line
		(start 288.07664 -69.277738)
		(end 288.07664 -69.615812)
		(stroke
			(width 0.04445)
			(type default)
		)
		(layer "In9.Cu")
	)
	(gr_line
		(start 315.329062 -120.796304)
		(end 315.358272 -120.838976)
		(stroke
			(width 0.05715)
			(type default)
		)
		(layer "In9.Cu")
	)
	(gr_line
		(start 315.329062 -118.589806)
		(end 315.329062 -118.673626)
		(stroke
			(width 0.05715)
			(type default)
		)
		(layer "In9.Cu")
	)
	(gr_line
		(start 315.329062 -117.573806)
		(end 315.329062 -117.657626)
		(stroke
			(width 0.05715)
			(type default)
		)
		(layer "In9.Cu")
	)
	(gr_line
		(start 315.329062 -116.557806)
		(end 315.329062 -116.641626)
		(stroke
			(width 0.05715)
			(type default)
		)
		(layer "In9.Cu")
	)
	(gr_line
		(start 315.329062 -115.541806)
		(end 315.329062 -115.625626)
		(stroke
			(width 0.05715)
			(type default)
		)
		(layer "In9.Cu")
	)
	(gr_line
		(start 315.329062 -114.834924)
		(end 315.342778 -114.807746)
		(stroke
			(width 0.05715)
			(type default)
		)
		(layer "In9.Cu")
	)
	(gr_line
		(start 315.595508 -121.185432)
		(end 315.932312 -121.677684)
		(stroke
			(width 0.05715)
			(type default)
		)
		(layer "In9.Cu")
	)
	(gr_line
		(start 315.623702 -118.965726)
		(end 315.786262 -118.803166)
		(stroke
			(width 0.05715)
			(type default)
		)
		(layer "In9.Cu")
	)
	(gr_line
		(start 315.623702 -118.297706)
		(end 315.786262 -118.460266)
		(stroke
			(width 0.05715)
			(type default)
		)
		(layer "In9.Cu")
	)
	(gr_line
		(start 315.623702 -117.949726)
		(end 315.786262 -117.787166)
		(stroke
			(width 0.05715)
			(type default)
		)
		(layer "In9.Cu")
	)
	(gr_line
		(start 315.623702 -117.281706)
		(end 315.786262 -117.444266)
		(stroke
			(width 0.05715)
			(type default)
		)
		(layer "In9.Cu")
	)
	(gr_line
		(start 315.623702 -116.933726)
		(end 315.786262 -116.771166)
		(stroke
			(width 0.05715)
			(type default)
		)
		(layer "In9.Cu")
	)
	(gr_line
		(start 315.623702 -116.265706)
		(end 315.786262 -116.428266)
		(stroke
			(width 0.05715)
			(type default)
		)
		(layer "In9.Cu")
	)
	(gr_line
		(start 315.623702 -115.917726)
		(end 315.786262 -115.755166)
		(stroke
			(width 0.05715)
			(type default)
		)
		(layer "In9.Cu")
	)
	(gr_line
		(start 315.623702 -115.249706)
		(end 315.786262 -115.412266)
		(stroke
			(width 0.05715)
			(type default)
		)
		(layer "In9.Cu")
	)
	(gr_line
		(start 315.786262 -118.460266)
		(end 315.786262 -118.803166)
		(stroke
			(width 0.05715)
			(type default)
		)
		(layer "In9.Cu")
	)
	(gr_line
		(start 315.786262 -117.444266)
		(end 315.786262 -117.787166)
		(stroke
			(width 0.05715)
			(type default)
		)
		(layer "In9.Cu")
	)
	(gr_line
		(start 315.786262 -116.428266)
		(end 315.786262 -116.771166)
		(stroke
			(width 0.05715)
			(type default)
		)
		(layer "In9.Cu")
	)
	(gr_line
		(start 315.786262 -115.412266)
		(end 315.786262 -115.755166)
		(stroke
			(width 0.05715)
			(type default)
		)
		(layer "In9.Cu")
	)
	(gr_line
		(start 315.818266 -120.989598)
		(end 316.044326 -121.031762)
		(stroke
			(width 0.05715)
			(type default)
		)
		(layer "In9.Cu")
	)
	(gr_line
		(start 316.044326 -121.031762)
		(end 316.238128 -121.314718)
		(stroke
			(width 0.05715)
			(type default)
		)
		(layer "In9.Cu")
	)
	(gr_line
		(start 316.054232 -114.891312)
		(end 316.054486 -114.891312)
		(stroke
			(width 0.05715)
			(type default)
		)
		(layer "In9.Cu")
	)
	(gr_line
		(start 316.054232 -114.891312)
		(end 316.091316 -114.817652)
		(stroke
			(width 0.05715)
			(type default)
		)
		(layer "In9.Cu")
	)
	(gr_line
		(start 316.054486 -114.891312)
		(end 316.079378 -114.96929)
		(stroke
			(width 0.05715)
			(type default)
		)
		(layer "In9.Cu")
	)
	(gr_line
		(start 316.091316 -114.817144)
		(end 316.091316 -114.817398)
		(stroke
			(width 0.05715)
			(type default)
		)
		(layer "In9.Cu")
	)
	(gr_line
		(start 316.169548 -122.023886)
		(end 316.506098 -122.51563)
		(stroke
			(width 0.05715)
			(type default)
		)
		(layer "In9.Cu")
	)
	(gr_line
		(start 316.187074 -119.511318)
		(end 316.2046 -119.448072)
		(stroke
			(width 0.05715)
			(type default)
		)
		(layer "In9.Cu")
	)
	(gr_line
		(start 316.187074 -119.511318)
		(end 316.213744 -119.57177)
		(stroke
			(width 0.05715)
			(type default)
		)
		(layer "In9.Cu")
	)
	(gr_line
		(start 316.195964 -121.540778)
		(end 316.238128 -121.314718)
		(stroke
			(width 0.05715)
			(type default)
		)
		(layer "In9.Cu")
	)
	(gr_line
		(start 316.2046 -119.447564)
		(end 316.2046 -119.447818)
		(stroke
			(width 0.05715)
			(type default)
		)
		(layer "In9.Cu")
	)
	(gr_line
		(start 316.392306 -121.827798)
		(end 316.618366 -121.870216)
		(stroke
			(width 0.05715)
			(type default)
		)
		(layer "In9.Cu")
	)
	(gr_line
		(start 316.618366 -121.870216)
		(end 316.812168 -122.153172)
		(stroke
			(width 0.05715)
			(type default)
		)
		(layer "In9.Cu")
	)
	(gr_line
		(start 316.762638 -114.980212)
		(end 316.7634 -114.978688)
		(stroke
			(width 0.05715)
			(type default)
		)
		(layer "In9.Cu")
	)
	(gr_line
		(start 316.762638 -114.980212)
		(end 316.78753 -115.057682)
		(stroke
			(width 0.05715)
			(type default)
		)
		(layer "In9.Cu")
	)
	(gr_line
		(start 316.7634 -114.978688)
		(end 316.799468 -114.906806)
		(stroke
			(width 0.05715)
			(type default)
		)
		(layer "In9.Cu")
	)
	(gr_line
		(start 316.770004 -122.379486)
		(end 316.812168 -122.153172)
		(stroke
			(width 0.05715)
			(type default)
		)
		(layer "In9.Cu")
	)
	(gr_line
		(start 316.775338 -111.95431)
		(end 316.781942 -111.941356)
		(stroke
			(width 0.05715)
			(type default)
		)
		(layer "In9.Cu")
	)
	(gr_line
		(start 316.781942 -111.941356)
		(end 316.792864 -111.931196)
		(stroke
			(width 0.05715)
			(type default)
		)
		(layer "In9.Cu")
	)
	(gr_line
		(start 316.873128 -119.461026)
		(end 316.890654 -119.39778)
		(stroke
			(width 0.05715)
			(type default)
		)
		(layer "In9.Cu")
	)
	(gr_line
		(start 316.873128 -119.461026)
		(end 316.899798 -119.521478)
		(stroke
			(width 0.05715)
			(type default)
		)
		(layer "In9.Cu")
	)
	(gr_line
		(start 316.890654 -119.397272)
		(end 316.890654 -119.397526)
		(stroke
			(width 0.05715)
			(type default)
		)
		(layer "In9.Cu")
	)
	(gr_line
		(start 316.97549 -121.293382)
		(end 316.990222 -121.326656)
		(stroke
			(width 0.05715)
			(type default)
		)
		(layer "In9.Cu")
	)
	(gr_line
		(start 316.990222 -121.326656)
		(end 317.018416 -121.3485)
		(stroke
			(width 0.05715)
			(type default)
		)
		(layer "In9.Cu")
	)
	(gr_line
		(start 317.101728 -117.19687)
		(end 317.116714 -117.243352)
		(stroke
			(width 0.05715)
			(type default)
		)
		(layer "In9.Cu")
	)
	(gr_line
		(start 317.10376 -117.290342)
		(end 317.116714 -117.243352)
		(stroke
			(width 0.05715)
			(type default)
		)
		(layer "In9.Cu")
	)
	(gr_line
		(start 317.21933 -123.557538)
		(end 317.22822 -123.570492)
		(stroke
			(width 0.05715)
			(type default)
		)
		(layer "In9.Cu")
	)
	(gr_line
		(start 317.22822 -123.570492)
		(end 317.24092 -123.579382)
		(stroke
			(width 0.05715)
			(type default)
		)
		(layer "In9.Cu")
	)
	(gr_line
		(start 317.361316 -112.287304)
		(end 317.36792 -112.27435)
		(stroke
			(width 0.05715)
			(type default)
		)
		(layer "In9.Cu")
	)
	(gr_line
		(start 317.36792 -112.27435)
		(end 317.378842 -112.26419)
		(stroke
			(width 0.05715)
			(type default)
		)
		(layer "In9.Cu")
	)
	(gr_line
		(start 317.471298 -115.068604)
		(end 317.49619 -115.145566)
		(stroke
			(width 0.05715)
			(type default)
		)
		(layer "In9.Cu")
	)
	(gr_line
		(start 317.471298 -115.068604)
		(end 317.507874 -114.99596)
		(stroke
			(width 0.05715)
			(type default)
		)
		(layer "In9.Cu")
	)
	(gr_line
		(start 317.482474 -120.837706)
		(end 317.497206 -120.87098)
		(stroke
			(width 0.05715)
			(type default)
		)
		(layer "In9.Cu")
	)
	(gr_line
		(start 317.497206 -120.87098)
		(end 317.525908 -120.893586)
		(stroke
			(width 0.05715)
			(type default)
		)
		(layer "In9.Cu")
	)
	(gr_line
		(start 317.763652 -121.931938)
		(end 317.779654 -121.944384)
		(stroke
			(width 0.05715)
			(type default)
		)
		(layer "In9.Cu")
	)
	(gr_line
		(start 317.777368 -117.181122)
		(end 317.792862 -117.229382)
		(stroke
			(width 0.05715)
			(type default)
		)
		(layer "In9.Cu")
	)
	(gr_line
		(start 317.7794 -117.27815)
		(end 317.792862 -117.229382)
		(stroke
			(width 0.05715)
			(type default)
		)
		(layer "In9.Cu")
	)
	(gr_line
		(start 317.779654 -121.944384)
		(end 317.799212 -121.949972)
		(stroke
			(width 0.05715)
			(type default)
		)
		(layer "In9.Cu")
	)
	(gr_line
		(start 317.8175 -118.474744)
		(end 317.817754 -118.473728)
		(stroke
			(width 0.05715)
			(type default)
		)
		(layer "In9.Cu")
	)
	(gr_line
		(start 317.89878 -112.710976)
		(end 317.901066 -112.658652)
		(stroke
			(width 0.05715)
			(type default)
		)
		(layer "In9.Cu")
	)
	(gr_line
		(start 317.901066 -112.658652)
		(end 317.962026 -112.602518)
		(stroke
			(width 0.05715)
			(type default)
		)
		(layer "In9.Cu")
	)
	(gr_line
		(start 318.105536 -121.34723)
		(end 318.13246 -121.368312)
		(stroke
			(width 0.05715)
			(type default)
		)
		(layer "In9.Cu")
	)
	(gr_line
		(start 318.108076 -124.178822)
		(end 318.150748 -124.20854)
		(stroke
			(width 0.05715)
			(type default)
		)
		(layer "In9.Cu")
	)
	(gr_line
		(start 318.13246 -121.368312)
		(end 318.166496 -121.374408)
		(stroke
			(width 0.05715)
			(type default)
		)
		(layer "In9.Cu")
	)
	(gr_line
		(start 318.176656 -112.8141)
		(end 318.185038 -112.797336)
		(stroke
			(width 0.05715)
			(type default)
		)
		(layer "In9.Cu")
	)
	(gr_line
		(start 318.453262 -117.167152)
		(end 318.468756 -117.215412)
		(stroke
			(width 0.05715)
			(type default)
		)
		(layer "In9.Cu")
	)
	(gr_line
		(start 318.455548 -117.262402)
		(end 318.455548 -117.262656)
		(stroke
			(width 0.05715)
			(type default)
		)
		(layer "In9.Cu")
	)
	(gr_line
		(start 318.455548 -117.262402)
		(end 318.468502 -117.215412)
		(stroke
			(width 0.05715)
			(type default)
		)
		(layer "In9.Cu")
	)
	(gr_line
		(start 318.468502 -117.215412)
		(end 318.468756 -117.215412)
		(stroke
			(width 0.05715)
			(type default)
		)
		(layer "In9.Cu")
	)
	(gr_line
		(start 318.495172 -113.028476)
		(end 318.501776 -113.015522)
		(stroke
			(width 0.05715)
			(type default)
		)
		(layer "In9.Cu")
	)
	(gr_line
		(start 318.501776 -113.015522)
		(end 318.512698 -113.005362)
		(stroke
			(width 0.05715)
			(type default)
		)
		(layer "In9.Cu")
	)
	(gr_line
		(start 318.9478 -124.333)
		(end 319.10528 -124.49048)
		(stroke
			(width 0.05715)
			(type default)
		)
		(layer "In9.Cu")
	)
	(gr_line
		(start 318.9478 -123.91644)
		(end 319.1129 -123.75134)
		(stroke
			(width 0.05715)
			(type default)
		)
		(layer "In9.Cu")
	)
	(gr_line
		(start 319.10528 -124.49048)
		(end 319.10528 -124.62764)
		(stroke
			(width 0.05715)
			(type default)
		)
		(layer "In9.Cu")
	)
	(gr_line
		(start 319.1129 -123.46432)
		(end 319.1129 -123.75134)
		(stroke
			(width 0.05715)
			(type default)
		)
		(layer "In9.Cu")
	)
	(gr_line
		(start 319.39357 -120.08231)
		(end 319.56756 -120.2563)
		(stroke
			(width 0.05715)
			(type default)
		)
		(layer "In9.Cu")
	)
	(gr_line
		(start 319.39357 -119.66575)
		(end 319.564004 -119.495316)
		(stroke
			(width 0.05715)
			(type default)
		)
		(layer "In9.Cu")
	)
	(gr_line
		(start 319.564004 -119.26316)
		(end 319.564004 -119.495316)
		(stroke
			(width 0.05715)
			(type default)
		)
		(layer "In9.Cu")
	)
	(gr_line
		(start 319.56756 -120.2563)
		(end 319.56756 -120.53316)
		(stroke
			(width 0.05715)
			(type default)
		)
		(layer "In9.Cu")
	)
	(gr_line
		(start 320.134996 -121.725436)
		(end 320.163952 -121.730516)
		(stroke
			(width 0.05715)
			(type default)
		)
		(layer "In9.Cu")
	)
	(gr_line
		(start 320.163952 -121.730516)
		(end 320.191384 -121.722642)
		(stroke
			(width 0.05715)
			(type default)
		)
		(layer "In9.Cu")
	)
	(gr_line
		(start 320.7258 -117.636798)
		(end 320.80327 -117.714268)
		(stroke
			(width 0.05715)
			(type default)
		)
		(layer "In9.Cu")
	)
	(gr_line
		(start 320.7258 -117.298216)
		(end 320.7258 -117.636798)
		(stroke
			(width 0.05715)
			(type default)
		)
		(layer "In9.Cu")
	)
	(gr_line
		(start 320.7766 -118.157498)
		(end 320.7766 -118.492016)
		(stroke
			(width 0.05715)
			(type default)
		)
		(layer "In9.Cu")
	)
	(gr_line
		(start 320.7766 -118.157498)
		(end 320.80327 -118.130828)
		(stroke
			(width 0.05715)
			(type default)
		)
		(layer "In9.Cu")
	)
	(gr_line
		(start 321.494912 -123.00585)
		(end 321.497198 -123.006612)
		(stroke
			(width 0.05715)
			(type default)
		)
		(layer "In9.Cu")
	)
	(gr_line
		(start 321.955668 -120.917716)
		(end 321.957954 -120.917208)
		(stroke
			(width 0.05715)
			(type default)
		)
		(layer "In9.Cu")
	)
	(gr_line
		(start 322.21043 -110.963456)
		(end 322.224146 -110.936278)
		(stroke
			(width 0.05715)
			(type default)
		)
		(layer "In9.Cu")
	)
	(gr_line
		(start 322.614544 -121.30151)
		(end 322.979034 -121.666)
		(stroke
			(width 0.05715)
			(type default)
		)
		(layer "In9.Cu")
	)
	(gr_line
		(start 322.614544 -120.884696)
		(end 322.99656 -120.50268)
		(stroke
			(width 0.05715)
			(type default)
		)
		(layer "In9.Cu")
	)
	(gr_line
		(start 322.662042 -123.276614)
		(end 323.002148 -123.61672)
		(stroke
			(width 0.05715)
			(type default)
		)
		(layer "In9.Cu")
	)
	(gr_line
		(start 322.6689 -110.050072)
		(end 322.675504 -110.037118)
		(stroke
			(width 0.05715)
			(type default)
		)
		(layer "In9.Cu")
	)
	(gr_line
		(start 322.675504 -110.037118)
		(end 322.686426 -110.026958)
		(stroke
			(width 0.05715)
			(type default)
		)
		(layer "In9.Cu")
	)
	(gr_line
		(start 322.74637 -122.884692)
		(end 322.790566 -122.884438)
		(stroke
			(width 0.05715)
			(type default)
		)
		(layer "In9.Cu")
	)
	(gr_line
		(start 322.85686 -122.884438)
		(end 322.90512 -122.884438)
		(stroke
			(width 0.05715)
			(type default)
		)
		(layer "In9.Cu")
	)
	(gr_line
		(start 322.90512 -122.884438)
		(end 322.998338 -122.79122)
		(stroke
			(width 0.05715)
			(type default)
		)
		(layer "In9.Cu")
	)
	(gr_line
		(start 322.998338 -122.555)
		(end 322.998338 -122.79122)
		(stroke
			(width 0.05715)
			(type default)
		)
		(layer "In9.Cu")
	)
	(gr_line
		(start 323.002148 -123.61672)
		(end 323.002148 -123.780804)
		(stroke
			(width 0.05715)
			(type default)
		)
		(layer "In9.Cu")
	)
	(gr_line
		(start 323.199506 -116.575332)
		(end 323.199506 -116.659152)
		(stroke
			(width 0.05715)
			(type default)
		)
		(layer "In9.Cu")
	)
	(gr_line
		(start 323.199506 -115.559332)
		(end 323.199506 -115.643152)
		(stroke
			(width 0.05715)
			(type default)
		)
		(layer "In9.Cu")
	)
	(gr_line
		(start 323.199506 -110.468664)
		(end 323.265546 -110.407704)
		(stroke
			(width 0.05715)
			(type default)
		)
		(layer "In9.Cu")
	)
	(gr_line
		(start 323.494146 -116.951252)
		(end 323.656706 -116.788692)
		(stroke
			(width 0.05715)
			(type default)
		)
		(layer "In9.Cu")
	)
	(gr_line
		(start 323.494146 -116.283232)
		(end 323.656706 -116.445792)
		(stroke
			(width 0.05715)
			(type default)
		)
		(layer "In9.Cu")
	)
	(gr_line
		(start 323.494146 -115.935252)
		(end 323.656706 -115.772692)
		(stroke
			(width 0.05715)
			(type default)
		)
		(layer "In9.Cu")
	)
	(gr_line
		(start 323.494146 -115.267232)
		(end 323.656706 -115.429792)
		(stroke
			(width 0.05715)
			(type default)
		)
		(layer "In9.Cu")
	)
	(gr_line
		(start 323.656706 -116.445792)
		(end 323.656706 -116.788692)
		(stroke
			(width 0.05715)
			(type default)
		)
		(layer "In9.Cu")
	)
	(gr_line
		(start 323.656706 -115.429792)
		(end 323.656706 -115.772692)
		(stroke
			(width 0.05715)
			(type default)
		)
		(layer "In9.Cu")
	)
	(gr_line
		(start 324.125336 -74.522838)
		(end 324.130416 -74.546206)
		(stroke
			(width 0.05715)
			(type default)
		)
		(layer "In9.Cu")
	)
	(gr_line
		(start 324.125336 -74.522838)
		(end 324.130416 -74.499724)
		(stroke
			(width 0.05715)
			(type default)
		)
		(layer "In9.Cu")
	)
	(gr_line
		(start 324.13448 -77.480922)
		(end 324.13956 -77.50429)
		(stroke
			(width 0.05715)
			(type default)
		)
		(layer "In9.Cu")
	)
	(gr_line
		(start 324.13448 -77.480922)
		(end 324.13956 -77.457808)
		(stroke
			(width 0.05715)
			(type default)
		)
		(layer "In9.Cu")
	)
	(gr_line
		(start 324.139306 -69.386704)
		(end 324.143878 -69.364098)
		(stroke
			(width 0.05715)
			(type default)
		)
		(layer "In9.Cu")
	)
	(gr_line
		(start 324.139306 -69.386704)
		(end 324.144132 -69.409056)
		(stroke
			(width 0.05715)
			(type default)
		)
		(layer "In9.Cu")
	)
	(gr_line
		(start 324.194678 -83.527646)
		(end 324.200774 -83.556348)
		(stroke
			(width 0.05715)
			(type default)
		)
		(layer "In9.Cu")
	)
	(gr_line
		(start 324.194678 -83.527646)
		(end 324.201536 -83.499452)
		(stroke
			(width 0.05715)
			(type default)
		)
		(layer "In9.Cu")
	)
	(gr_line
		(start 324.266814 -118.920006)
		(end 324.325742 -118.978934)
		(stroke
			(width 0.05715)
			(type default)
		)
		(layer "In9.Cu")
	)
	(gr_line
		(start 324.268338 -118.50497)
		(end 324.498462 -118.50497)
		(stroke
			(width 0.05715)
			(type default)
		)
		(layer "In9.Cu")
	)
	(gr_line
		(start 324.498462 -118.50497)
		(end 324.740778 -118.747286)
		(stroke
			(width 0.05715)
			(type default)
		)
		(layer "In9.Cu")
	)
	(gr_line
		(start 324.59295 -110.145576)
		(end 324.65899 -110.084362)
		(stroke
			(width 0.05715)
			(type default)
		)
		(layer "In9.Cu")
	)
	(gr_line
		(start 324.737476 -76.047092)
		(end 324.742556 -76.023978)
		(stroke
			(width 0.05715)
			(type default)
		)
		(layer "In9.Cu")
	)
	(gr_line
		(start 324.737476 -76.00061)
		(end 324.742556 -76.023978)
		(stroke
			(width 0.05715)
			(type default)
		)
		(layer "In9.Cu")
	)
	(gr_line
		(start 324.740778 -118.747286)
		(end 324.740778 -118.97741)
		(stroke
			(width 0.05715)
			(type default)
		)
		(layer "In9.Cu")
	)
	(gr_line
		(start 324.7771 -74.522838)
		(end 324.78218 -74.545952)
		(stroke
			(width 0.05715)
			(type default)
		)
		(layer "In9.Cu")
	)
	(gr_line
		(start 324.7771 -74.522838)
		(end 324.78218 -74.49947)
		(stroke
			(width 0.05715)
			(type default)
		)
		(layer "In9.Cu")
	)
	(gr_line
		(start 324.786244 -77.480922)
		(end 324.791324 -77.504036)
		(stroke
			(width 0.05715)
			(type default)
		)
		(layer "In9.Cu")
	)
	(gr_line
		(start 324.786244 -77.480922)
		(end 324.791324 -77.457554)
		(stroke
			(width 0.05715)
			(type default)
		)
		(layer "In9.Cu")
	)
	(gr_line
		(start 324.799706 -69.427852)
		(end 324.804278 -69.405246)
		(stroke
			(width 0.05715)
			(type default)
		)
		(layer "In9.Cu")
	)
	(gr_line
		(start 324.799706 -69.427852)
		(end 324.804532 -69.449696)
		(stroke
			(width 0.05715)
			(type default)
		)
		(layer "In9.Cu")
	)
	(gr_line
		(start 324.866508 -83.457288)
		(end 324.866762 -83.457288)
		(stroke
			(width 0.05715)
			(type default)
		)
		(layer "In9.Cu")
	)
	(gr_line
		(start 324.866508 -83.457288)
		(end 324.87235 -83.48472)
		(stroke
			(width 0.05715)
			(type default)
		)
		(layer "In9.Cu")
	)
	(gr_line
		(start 324.866762 -83.457288)
		(end 324.873366 -83.430364)
		(stroke
			(width 0.05715)
			(type default)
		)
		(layer "In9.Cu")
	)
	(gr_line
		(start 324.904608 -104.834944)
		(end 324.91172 -104.82834)
		(stroke
			(width 0.05715)
			(type default)
		)
		(layer "In9.Cu")
	)
	(gr_line
		(start 324.91172 -104.82834)
		(end 324.916292 -104.820212)
		(stroke
			(width 0.05715)
			(type default)
		)
		(layer "In9.Cu")
	)
	(gr_line
		(start 324.97141 -71.945754)
		(end 324.97649 -71.92264)
		(stroke
			(width 0.05715)
			(type default)
		)
		(layer "In9.Cu")
	)
	(gr_line
		(start 324.97141 -71.899272)
		(end 324.97649 -71.92264)
		(stroke
			(width 0.05715)
			(type default)
		)
		(layer "In9.Cu")
	)
	(gr_line
		(start 324.985126 -119.638318)
		(end 325.044054 -119.697246)
		(stroke
			(width 0.05715)
			(type default)
		)
		(layer "In9.Cu")
	)
	(gr_line
		(start 324.98665 -119.223282)
		(end 325.216774 -119.223282)
		(stroke
			(width 0.05715)
			(type default)
		)
		(layer "In9.Cu")
	)
	(gr_line
		(start 325.060564 -56.674512)
		(end 325.063612 -56.698134)
		(stroke
			(width 0.05715)
			(type default)
		)
		(layer "In9.Cu")
	)
	(gr_line
		(start 325.060564 -56.674512)
		(end 325.067168 -56.651652)
		(stroke
			(width 0.05715)
			(type default)
		)
		(layer "In9.Cu")
	)
	(gr_line
		(start 325.114412 -57.090818)
		(end 325.118476 -57.122314)
		(stroke
			(width 0.05715)
			(type default)
		)
		(layer "In9.Cu")
	)
	(gr_line
		(start 325.14286 -80.880966)
		(end 325.149718 -80.852772)
		(stroke
			(width 0.05715)
			(type default)
		)
		(layer "In9.Cu")
	)
	(gr_line
		(start 325.143622 -80.82407)
		(end 325.149718 -80.852772)
		(stroke
			(width 0.05715)
			(type default)
		)
		(layer "In9.Cu")
	)
	(gr_line
		(start 325.216774 -119.223282)
		(end 325.45909 -119.465598)
		(stroke
			(width 0.05715)
			(type default)
		)
		(layer "In9.Cu")
	)
	(gr_line
		(start 325.34225 -63.474346)
		(end 325.34606 -63.45555)
		(stroke
			(width 0.05715)
			(type default)
		)
		(layer "In9.Cu")
	)
	(gr_line
		(start 325.34606 -63.45555)
		(end 325.356474 -63.440056)
		(stroke
			(width 0.05715)
			(type default)
		)
		(layer "In9.Cu")
	)
	(gr_line
		(start 325.38924 -76.047092)
		(end 325.39432 -76.023978)
		(stroke
			(width 0.05715)
			(type default)
		)
		(layer "In9.Cu")
	)
	(gr_line
		(start 325.38924 -76.00061)
		(end 325.39432 -76.023978)
		(stroke
			(width 0.05715)
			(type default)
		)
		(layer "In9.Cu")
	)
	(gr_line
		(start 325.428864 -74.523092)
		(end 325.433944 -74.546206)
		(stroke
			(width 0.05715)
			(type default)
		)
		(layer "In9.Cu")
	)
	(gr_line
		(start 325.428864 -74.523092)
		(end 325.433944 -74.499724)
		(stroke
			(width 0.05715)
			(type default)
		)
		(layer "In9.Cu")
	)
	(gr_line
		(start 325.438262 -77.480922)
		(end 325.443342 -77.504036)
		(stroke
			(width 0.05715)
			(type default)
		)
		(layer "In9.Cu")
	)
	(gr_line
		(start 325.438262 -77.480922)
		(end 325.443342 -77.457554)
		(stroke
			(width 0.05715)
			(type default)
		)
		(layer "In9.Cu")
	)
	(gr_line
		(start 325.452486 -59.846718)
		(end 325.456296 -59.827668)
		(stroke
			(width 0.05715)
			(type default)
		)
		(layer "In9.Cu")
	)
	(gr_line
		(start 325.452486 -59.846718)
		(end 325.45655 -59.86653)
		(stroke
			(width 0.05715)
			(type default)
		)
		(layer "In9.Cu")
	)
	(gr_line
		(start 325.45909 -119.465598)
		(end 325.45909 -119.695722)
		(stroke
			(width 0.05715)
			(type default)
		)
		(layer "In9.Cu")
	)
	(gr_line
		(start 325.468234 -55.284878)
		(end 325.47052 -55.277004)
		(stroke
			(width 0.05715)
			(type default)
		)
		(layer "In9.Cu")
	)
	(gr_line
		(start 325.47052 -55.277004)
		(end 325.475092 -55.270146)
		(stroke
			(width 0.05715)
			(type default)
		)
		(layer "In9.Cu")
	)
	(gr_line
		(start 325.477632 -69.550788)
		(end 325.482204 -69.528182)
		(stroke
			(width 0.05715)
			(type default)
		)
		(layer "In9.Cu")
	)
	(gr_line
		(start 325.477632 -69.550788)
		(end 325.482458 -69.572632)
		(stroke
			(width 0.05715)
			(type default)
		)
		(layer "In9.Cu")
	)
	(gr_line
		(start 325.486522 -105.172002)
		(end 325.493634 -105.165398)
		(stroke
			(width 0.05715)
			(type default)
		)
		(layer "In9.Cu")
	)
	(gr_line
		(start 325.493634 -105.165398)
		(end 325.498206 -105.15727)
		(stroke
			(width 0.05715)
			(type default)
		)
		(layer "In9.Cu")
	)
	(gr_line
		(start 325.524368 -83.48472)
		(end 325.530464 -83.512914)
		(stroke
			(width 0.05715)
			(type default)
		)
		(layer "In9.Cu")
	)
	(gr_line
		(start 325.524368 -83.48472)
		(end 325.531226 -83.45678)
		(stroke
			(width 0.05715)
			(type default)
		)
		(layer "In9.Cu")
	)
	(gr_line
		(start 325.531226 -83.456272)
		(end 325.531226 -83.456526)
		(stroke
			(width 0.05715)
			(type default)
		)
		(layer "In9.Cu")
	)
	(gr_line
		(start 325.623174 -71.945754)
		(end 325.628254 -71.92264)
		(stroke
			(width 0.05715)
			(type default)
		)
		(layer "In9.Cu")
	)
	(gr_line
		(start 325.623174 -71.899272)
		(end 325.628254 -71.92264)
		(stroke
			(width 0.05715)
			(type default)
		)
		(layer "In9.Cu")
	)
	(gr_line
		(start 325.706232 -54.923944)
		(end 326.038464 -54.425342)
		(stroke
			(width 0.05715)
			(type default)
		)
		(layer "In9.Cu")
	)
	(gr_line
		(start 325.795894 -80.88757)
		(end 325.802752 -80.859376)
		(stroke
			(width 0.05715)
			(type default)
		)
		(layer "In9.Cu")
	)
	(gr_line
		(start 325.796656 -80.830674)
		(end 325.802752 -80.859376)
		(stroke
			(width 0.05715)
			(type default)
		)
		(layer "In9.Cu")
	)
	(gr_line
		(start 325.900542 -57.767982)
		(end 325.91121 -57.784238)
		(stroke
			(width 0.05715)
			(type default)
		)
		(layer "In9.Cu")
	)
	(gr_line
		(start 325.91121 -57.784238)
		(end 325.91502 -57.803288)
		(stroke
			(width 0.05715)
			(type default)
		)
		(layer "In9.Cu")
	)
	(gr_line
		(start 325.931784 -55.116476)
		(end 326.15759 -55.071264)
		(stroke
			(width 0.05715)
			(type default)
		)
		(layer "In9.Cu")
	)
	(gr_line
		(start 325.958962 -63.728346)
		(end 325.963026 -63.709042)
		(stroke
			(width 0.05715)
			(type default)
		)
		(layer "In9.Cu")
	)
	(gr_line
		(start 325.963026 -63.709042)
		(end 325.973948 -63.692532)
		(stroke
			(width 0.05715)
			(type default)
		)
		(layer "In9.Cu")
	)
	(gr_line
		(start 326.033384 -58.391552)
		(end 326.037448 -58.411364)
		(stroke
			(width 0.05715)
			(type default)
		)
		(layer "In9.Cu")
	)
	(gr_line
		(start 326.033638 -58.430414)
		(end 326.037448 -58.411364)
		(stroke
			(width 0.05715)
			(type default)
		)
		(layer "In9.Cu")
	)
	(gr_line
		(start 326.041004 -76.047346)
		(end 326.046084 -76.023978)
		(stroke
			(width 0.05715)
			(type default)
		)
		(layer "In9.Cu")
	)
	(gr_line
		(start 326.041004 -76.000864)
		(end 326.046084 -76.023978)
		(stroke
			(width 0.05715)
			(type default)
		)
		(layer "In9.Cu")
	)
	(gr_line
		(start 326.079612 -74.52868)
		(end 326.084946 -74.503788)
		(stroke
			(width 0.05715)
			(type default)
		)
		(layer "In9.Cu")
	)
	(gr_line
		(start 326.079612 -74.52868)
		(end 326.085962 -74.558906)
		(stroke
			(width 0.05715)
			(type default)
		)
		(layer "In9.Cu")
	)
	(gr_line
		(start 326.090026 -77.491336)
		(end 326.091042 -77.486002)
		(stroke
			(width 0.05715)
			(type default)
		)
		(layer "In9.Cu")
	)
	(gr_line
		(start 326.090026 -77.491336)
		(end 326.095106 -77.515466)
		(stroke
			(width 0.05715)
			(type default)
		)
		(layer "In9.Cu")
	)
	(gr_line
		(start 326.090026 -77.48143)
		(end 326.091042 -77.486002)
		(stroke
			(width 0.05715)
			(type default)
		)
		(layer "In9.Cu")
	)
	(gr_line
		(start 326.090026 -77.481176)
		(end 326.090026 -77.48143)
		(stroke
			(width 0.05715)
			(type default)
		)
		(layer "In9.Cu")
	)
	(gr_line
		(start 326.090026 -77.481176)
		(end 326.095106 -77.456538)
		(stroke
			(width 0.05715)
			(type default)
		)
		(layer "In9.Cu")
	)
	(gr_line
		(start 326.127618 -69.542914)
		(end 326.132698 -69.566282)
		(stroke
			(width 0.05715)
			(type default)
		)
		(layer "In9.Cu")
	)
	(gr_line
		(start 326.127618 -69.542914)
		(end 326.132698 -69.518022)
		(stroke
			(width 0.05715)
			(type default)
		)
		(layer "In9.Cu")
	)
	(gr_line
		(start 326.132698 -69.517514)
		(end 326.132698 -69.517768)
		(stroke
			(width 0.05715)
			(type default)
		)
		(layer "In9.Cu")
	)
	(gr_line
		(start 326.137778 -62.787276)
		(end 326.148192 -62.771782)
		(stroke
			(width 0.05715)
			(type default)
		)
		(layer "In9.Cu")
	)
	(gr_line
		(start 326.148192 -62.771782)
		(end 326.152002 -62.752986)
		(stroke
			(width 0.05715)
			(type default)
		)
		(layer "In9.Cu")
	)
	(gr_line
		(start 326.15251 -105.433622)
		(end 326.159622 -105.427018)
		(stroke
			(width 0.05715)
			(type default)
		)
		(layer "In9.Cu")
	)
	(gr_line
		(start 326.15759 -55.071264)
		(end 326.347836 -54.785768)
		(stroke
			(width 0.05715)
			(type default)
		)
		(layer "In9.Cu")
	)
	(gr_line
		(start 326.159368 -59.912504)
		(end 326.163178 -59.931554)
		(stroke
			(width 0.05715)
			(type default)
		)
		(layer "In9.Cu")
	)
	(gr_line
		(start 326.159368 -59.912504)
		(end 326.163432 -59.892438)
		(stroke
			(width 0.05715)
			(type default)
		)
		(layer "In9.Cu")
	)
	(gr_line
		(start 326.159622 -105.427018)
		(end 326.164194 -105.41889)
		(stroke
			(width 0.05715)
			(type default)
		)
		(layer "In9.Cu")
	)
	(gr_line
		(start 326.238362 -62.329822)
		(end 326.24268 -62.308232)
		(stroke
			(width 0.05715)
			(type default)
		)
		(layer "In9.Cu")
	)
	(gr_line
		(start 326.238362 -62.286642)
		(end 326.24268 -62.308232)
		(stroke
			(width 0.05715)
			(type default)
		)
		(layer "In9.Cu")
	)
	(gr_line
		(start 326.244458 -83.645248)
		(end 326.251316 -83.677506)
		(stroke
			(width 0.05715)
			(type default)
		)
		(layer "In9.Cu")
	)
	(gr_line
		(start 326.244458 -83.645248)
		(end 326.252332 -83.613244)
		(stroke
			(width 0.05715)
			(type default)
		)
		(layer "In9.Cu")
	)
	(gr_line
		(start 326.274938 -71.946008)
		(end 326.280018 -71.92264)
		(stroke
			(width 0.05715)
			(type default)
		)
		(layer "In9.Cu")
	)
	(gr_line
		(start 326.274938 -71.899526)
		(end 326.280018 -71.92264)
		(stroke
			(width 0.05715)
			(type default)
		)
		(layer "In9.Cu")
	)
	(gr_line
		(start 326.280018 -95.250508)
		(end 326.284844 -95.227648)
		(stroke
			(width 0.05715)
			(type default)
		)
		(layer "In9.Cu")
	)
	(gr_line
		(start 326.280018 -95.250508)
		(end 326.285098 -95.273876)
		(stroke
			(width 0.05715)
			(type default)
		)
		(layer "In9.Cu")
	)
	(gr_line
		(start 326.302878 -54.560216)
		(end 326.347836 -54.785768)
		(stroke
			(width 0.05715)
			(type default)
		)
		(layer "In9.Cu")
	)
	(gr_line
		(start 326.375776 -58.829956)
		(end 326.492362 -58.246518)
		(stroke
			(width 0.05715)
			(type default)
		)
		(layer "In9.Cu")
	)
	(gr_line
		(start 326.386444 -53.903626)
		(end 326.60209 -53.580284)
		(stroke
			(width 0.05715)
			(type default)
		)
		(layer "In9.Cu")
	)
	(gr_line
		(start 326.441562 -61.323728)
		(end 326.559164 -61.911484)
		(stroke
			(width 0.05715)
			(type default)
		)
		(layer "In9.Cu")
	)
	(gr_line
		(start 326.451214 -57.33669)
		(end 326.460358 -57.38241)
		(stroke
			(width 0.05715)
			(type default)
		)
		(layer "In9.Cu")
	)
	(gr_line
		(start 326.451214 -57.33669)
		(end 326.467724 -57.292748)
		(stroke
			(width 0.05715)
			(type default)
		)
		(layer "In9.Cu")
	)
	(gr_line
		(start 326.453754 -80.915002)
		(end 326.453754 -80.915256)
		(stroke
			(width 0.05715)
			(type default)
		)
		(layer "In9.Cu")
	)
	(gr_line
		(start 326.453754 -80.914748)
		(end 326.460612 -80.886808)
		(stroke
			(width 0.05715)
			(type default)
		)
		(layer "In9.Cu")
	)
	(gr_line
		(start 326.454516 -80.858614)
		(end 326.460612 -80.886808)
		(stroke
			(width 0.05715)
			(type default)
		)
		(layer "In9.Cu")
	)
	(gr_line
		(start 326.46747 -57.293002)
		(end 326.467724 -57.29224)
		(stroke
			(width 0.05715)
			(type default)
		)
		(layer "In9.Cu")
	)
	(gr_line
		(start 326.495664 -54.27091)
		(end 326.63892 -54.242462)
		(stroke
			(width 0.05715)
			(type default)
		)
		(layer "In9.Cu")
	)
	(gr_line
		(start 326.615806 -63.953644)
		(end 326.61987 -63.93434)
		(stroke
			(width 0.05715)
			(type default)
		)
		(layer "In9.Cu")
	)
	(gr_line
		(start 326.61987 -63.93434)
		(end 326.630792 -63.91783)
		(stroke
			(width 0.05715)
			(type default)
		)
		(layer "In9.Cu")
	)
	(gr_line
		(start 326.63892 -54.242462)
		(end 326.721216 -54.225952)
		(stroke
			(width 0.05715)
			(type default)
		)
		(layer "In9.Cu")
	)
	(gr_line
		(start 326.657462 -58.923174)
		(end 326.848724 -58.795666)
		(stroke
			(width 0.05715)
			(type default)
		)
		(layer "In9.Cu")
	)
	(gr_line
		(start 326.681338 -105.856532)
		(end 326.688196 -105.850182)
		(stroke
			(width 0.05715)
			(type default)
		)
		(layer "In9.Cu")
	)
	(gr_line
		(start 326.688196 -105.850182)
		(end 326.692768 -105.842054)
		(stroke
			(width 0.05715)
			(type default)
		)
		(layer "In9.Cu")
	)
	(gr_line
		(start 326.693784 -76.053442)
		(end 326.697848 -76.034646)
		(stroke
			(width 0.05715)
			(type default)
		)
		(layer "In9.Cu")
	)
	(gr_line
		(start 326.693784 -76.005944)
		(end 326.696578 -76.018644)
		(stroke
			(width 0.05715)
			(type default)
		)
		(layer "In9.Cu")
	)
	(gr_line
		(start 326.696578 -76.018644)
		(end 326.696832 -76.019914)
		(stroke
			(width 0.05715)
			(type default)
		)
		(layer "In9.Cu")
	)
	(gr_line
		(start 326.696832 -76.019914)
		(end 326.698864 -76.029566)
		(stroke
			(width 0.05715)
			(type default)
		)
		(layer "In9.Cu")
	)
	(gr_line
		(start 326.697848 -76.034646)
		(end 326.698864 -76.029566)
		(stroke
			(width 0.05715)
			(type default)
		)
		(layer "In9.Cu")
	)
	(gr_line
		(start 326.721216 -54.225952)
		(end 326.911462 -53.940456)
		(stroke
			(width 0.05715)
			(type default)
		)
		(layer "In9.Cu")
	)
	(gr_line
		(start 326.723756 -61.23178)
		(end 326.915272 -61.359542)
		(stroke
			(width 0.05715)
			(type default)
		)
		(layer "In9.Cu")
	)
	(gr_line
		(start 326.732392 -74.523092)
		(end 326.737472 -74.54646)
		(stroke
			(width 0.05715)
			(type default)
		)
		(layer "In9.Cu")
	)
	(gr_line
		(start 326.732392 -74.523092)
		(end 326.737472 -74.499978)
		(stroke
			(width 0.05715)
			(type default)
		)
		(layer "In9.Cu")
	)
	(gr_line
		(start 326.741536 -77.480668)
		(end 326.746616 -77.504036)
		(stroke
			(width 0.05715)
			(type default)
		)
		(layer "In9.Cu")
	)
	(gr_line
		(start 326.741536 -77.480668)
		(end 326.746616 -77.457554)
		(stroke
			(width 0.05715)
			(type default)
		)
		(layer "In9.Cu")
	)
	(gr_line
		(start 326.74306 -63.060326)
		(end 326.753982 -63.043816)
		(stroke
			(width 0.05715)
			(type default)
		)
		(layer "In9.Cu")
	)
	(gr_line
		(start 326.753982 -63.043816)
		(end 326.758046 -63.024258)
		(stroke
			(width 0.05715)
			(type default)
		)
		(layer "In9.Cu")
	)
	(gr_line
		(start 326.75957 -86.071456)
		(end 326.883268 -86.653878)
		(stroke
			(width 0.05715)
			(type default)
		)
		(layer "In9.Cu")
	)
	(gr_line
		(start 326.775572 -94.32417)
		(end 326.780652 -94.300802)
		(stroke
			(width 0.05715)
			(type default)
		)
		(layer "In9.Cu")
	)
	(gr_line
		(start 326.775572 -94.27718)
		(end 326.780652 -94.300802)
		(stroke
			(width 0.05715)
			(type default)
		)
		(layer "In9.Cu")
	)
	(gr_line
		(start 326.788526 -58.268108)
		(end 326.916034 -58.459624)
		(stroke
			(width 0.05715)
			(type default)
		)
		(layer "In9.Cu")
	)
	(gr_line
		(start 326.8091 -66.192654)
		(end 326.928226 -65.606676)
		(stroke
			(width 0.05715)
			(type default)
		)
		(layer "In9.Cu")
	)
	(gr_line
		(start 326.8345 -53.23205)
		(end 327.1647 -52.73675)
		(stroke
			(width 0.05715)
			(type default)
		)
		(layer "In9.Cu")
	)
	(gr_line
		(start 326.848724 -58.795666)
		(end 326.916034 -58.459624)
		(stroke
			(width 0.05715)
			(type default)
		)
		(layer "In9.Cu")
	)
	(gr_line
		(start 326.85482 -61.8871)
		(end 326.982582 -61.695584)
		(stroke
			(width 0.05715)
			(type default)
		)
		(layer "In9.Cu")
	)
	(gr_line
		(start 326.856598 -57.874154)
		(end 326.860662 -57.89422)
		(stroke
			(width 0.05715)
			(type default)
		)
		(layer "In9.Cu")
	)
	(gr_line
		(start 326.856852 -57.91327)
		(end 326.860662 -57.89422)
		(stroke
			(width 0.05715)
			(type default)
		)
		(layer "In9.Cu")
	)
	(gr_line
		(start 326.866504 -53.715158)
		(end 326.911462 -53.940456)
		(stroke
			(width 0.05715)
			(type default)
		)
		(layer "In9.Cu")
	)
	(gr_line
		(start 326.89292 -101.227128)
		(end 326.905112 -101.205284)
		(stroke
			(width 0.05715)
			(type default)
		)
		(layer "In9.Cu")
	)
	(gr_line
		(start 326.905112 -101.205284)
		(end 326.907144 -101.180138)
		(stroke
			(width 0.05715)
			(type default)
		)
		(layer "In9.Cu")
	)
	(gr_line
		(start 326.915272 -61.359542)
		(end 326.982582 -61.695584)
		(stroke
			(width 0.05715)
			(type default)
		)
		(layer "In9.Cu")
	)
	(gr_line
		(start 326.916034 -62.24778)
		(end 326.920352 -62.22619)
		(stroke
			(width 0.05715)
			(type default)
		)
		(layer "In9.Cu")
	)
	(gr_line
		(start 326.916034 -62.2046)
		(end 326.920352 -62.22619)
		(stroke
			(width 0.05715)
			(type default)
		)
		(layer "In9.Cu")
	)
	(gr_line
		(start 326.926702 -71.946008)
		(end 326.931782 -71.92264)
		(stroke
			(width 0.05715)
			(type default)
		)
		(layer "In9.Cu")
	)
	(gr_line
		(start 326.926702 -71.899526)
		(end 326.931782 -71.92264)
		(stroke
			(width 0.05715)
			(type default)
		)
		(layer "In9.Cu")
	)
	(gr_line
		(start 326.964294 -95.403416)
		(end 326.969374 -95.42653)
		(stroke
			(width 0.05715)
			(type default)
		)
		(layer "In9.Cu")
	)
	(gr_line
		(start 326.964294 -95.403416)
		(end 326.969374 -95.380048)
		(stroke
			(width 0.05715)
			(type default)
		)
		(layer "In9.Cu")
	)
	(gr_line
		(start 326.970644 -87.065358)
		(end 327.094342 -87.64778)
		(stroke
			(width 0.05715)
			(type default)
		)
		(layer "In9.Cu")
	)
	(gr_line
		(start 326.973438 -70.457314)
		(end 326.97801 -70.434708)
		(stroke
			(width 0.05715)
			(type default)
		)
		(layer "In9.Cu")
	)
	(gr_line
		(start 326.973438 -70.457314)
		(end 326.978264 -70.479666)
		(stroke
			(width 0.05715)
			(type default)
		)
		(layer "In9.Cu")
	)
	(gr_line
		(start 327.011284 -83.34502)
		(end 327.01738 -83.373722)
		(stroke
			(width 0.05715)
			(type default)
		)
		(layer "In9.Cu")
	)
	(gr_line
		(start 327.011284 -83.34502)
		(end 327.018142 -83.316826)
		(stroke
			(width 0.05715)
			(type default)
		)
		(layer "In9.Cu")
	)
	(gr_line
		(start 327.011792 -65.196212)
		(end 327.130664 -64.610996)
		(stroke
			(width 0.05715)
			(type default)
		)
		(layer "In9.Cu")
	)
	(gr_line
		(start 327.04024 -85.974936)
		(end 327.23328 -86.100412)
		(stroke
			(width 0.05715)
			(type default)
		)
		(layer "In9.Cu")
	)
	(gr_line
		(start 327.05929 -53.425598)
		(end 327.284842 -53.38064)
		(stroke
			(width 0.05715)
			(type default)
		)
		(layer "In9.Cu")
	)
	(gr_line
		(start 327.090786 -66.285618)
		(end 327.28281 -66.158364)
		(stroke
			(width 0.05715)
			(type default)
		)
		(layer "In9.Cu")
	)
	(gr_line
		(start 327.151492 -97.94748)
		(end 327.152508 -97.952306)
		(stroke
			(width 0.05715)
			(type default)
		)
		(layer "In9.Cu")
	)
	(gr_line
		(start 327.152254 -97.957132)
		(end 327.152508 -97.952306)
		(stroke
			(width 0.05715)
			(type default)
		)
		(layer "In9.Cu")
	)
	(gr_line
		(start 327.155048 -81.153)
		(end 327.162414 -81.123028)
		(stroke
			(width 0.05715)
			(type default)
		)
		(layer "In9.Cu")
	)
	(gr_line
		(start 327.15581 -81.092802)
		(end 327.162414 -81.123028)
		(stroke
			(width 0.05715)
			(type default)
		)
		(layer "In9.Cu")
	)
	(gr_line
		(start 327.179178 -86.628478)
		(end 327.3044 -86.435692)
		(stroke
			(width 0.05715)
			(type default)
		)
		(layer "In9.Cu")
	)
	(gr_line
		(start 327.213722 -64.201294)
		(end 327.217786 -64.18199)
		(stroke
			(width 0.05715)
			(type default)
		)
		(layer "In9.Cu")
	)
	(gr_line
		(start 327.217786 -64.18199)
		(end 327.228708 -64.16548)
		(stroke
			(width 0.05715)
			(type default)
		)
		(layer "In9.Cu")
	)
	(gr_line
		(start 327.223882 -65.630552)
		(end 327.351136 -65.822322)
		(stroke
			(width 0.05715)
			(type default)
		)
		(layer "In9.Cu")
	)
	(gr_line
		(start 327.23328 -86.100412)
		(end 327.3044 -86.435692)
		(stroke
			(width 0.05715)
			(type default)
		)
		(layer "In9.Cu")
	)
	(gr_line
		(start 327.251314 -86.968838)
		(end 327.444354 -87.094314)
		(stroke
			(width 0.05715)
			(type default)
		)
		(layer "In9.Cu")
	)
	(gr_line
		(start 327.28281 -66.158364)
		(end 327.351136 -65.822322)
		(stroke
			(width 0.05715)
			(type default)
		)
		(layer "In9.Cu")
	)
	(gr_line
		(start 327.284842 -53.38064)
		(end 327.475088 -53.095398)
		(stroke
			(width 0.05715)
			(type default)
		)
		(layer "In9.Cu")
	)
	(gr_line
		(start 327.293224 -65.289938)
		(end 327.485248 -65.162684)
		(stroke
			(width 0.05715)
			(type default)
		)
		(layer "In9.Cu")
	)
	(gr_line
		(start 327.323704 -106.140758)
		(end 327.330816 -106.134154)
		(stroke
			(width 0.05715)
			(type default)
		)
		(layer "In9.Cu")
	)
	(gr_line
		(start 327.330816 -106.134154)
		(end 327.335134 -106.12628)
		(stroke
			(width 0.05715)
			(type default)
		)
		(layer "In9.Cu")
	)
	(gr_line
		(start 327.344532 -76.047346)
		(end 327.349612 -76.024232)
		(stroke
			(width 0.05715)
			(type default)
		)
		(layer "In9.Cu")
	)
	(gr_line
		(start 327.344532 -76.000864)
		(end 327.349612 -76.024232)
		(stroke
			(width 0.05715)
			(type default)
		)
		(layer "In9.Cu")
	)
	(gr_line
		(start 327.34631 -56.793638)
		(end 327.355454 -56.839358)
		(stroke
			(width 0.05715)
			(type default)
		)
		(layer "In9.Cu")
	)
	(gr_line
		(start 327.34631 -56.793638)
		(end 327.36282 -56.749696)
		(stroke
			(width 0.05715)
			(type default)
		)
		(layer "In9.Cu")
	)
	(gr_line
		(start 327.362566 -56.74995)
		(end 327.36282 -56.749188)
		(stroke
			(width 0.05715)
			(type default)
		)
		(layer "In9.Cu")
	)
	(gr_line
		(start 327.380346 -63.315088)
		(end 327.391268 -63.298324)
		(stroke
			(width 0.05715)
			(type default)
		)
		(layer "In9.Cu")
	)
	(gr_line
		(start 327.384156 -74.523346)
		(end 327.389236 -74.546714)
		(stroke
			(width 0.05715)
			(type default)
		)
		(layer "In9.Cu")
	)
	(gr_line
		(start 327.384156 -74.523346)
		(end 327.389236 -74.500232)
		(stroke
			(width 0.05715)
			(type default)
		)
		(layer "In9.Cu")
	)
	(gr_line
		(start 327.390252 -87.62238)
		(end 327.515474 -87.429594)
		(stroke
			(width 0.05715)
			(type default)
		)
		(layer "In9.Cu")
	)
	(gr_line
		(start 327.391268 -63.298324)
		(end 327.395078 -63.27902)
		(stroke
			(width 0.05715)
			(type default)
		)
		(layer "In9.Cu")
	)
	(gr_line
		(start 327.3933 -77.480668)
		(end 327.39838 -77.504036)
		(stroke
			(width 0.05715)
			(type default)
		)
		(layer "In9.Cu")
	)
	(gr_line
		(start 327.3933 -77.480668)
		(end 327.39838 -77.457554)
		(stroke
			(width 0.05715)
			(type default)
		)
		(layer "In9.Cu")
	)
	(gr_line
		(start 327.42632 -64.634872)
		(end 327.553574 -64.826642)
		(stroke
			(width 0.05715)
			(type default)
		)
		(layer "In9.Cu")
	)
	(gr_line
		(start 327.43013 -52.869846)
		(end 327.475088 -53.095398)
		(stroke
			(width 0.05715)
			(type default)
		)
		(layer "In9.Cu")
	)
	(gr_line
		(start 327.444354 -87.094314)
		(end 327.515474 -87.429594)
		(stroke
			(width 0.05715)
			(type default)
		)
		(layer "In9.Cu")
	)
	(gr_line
		(start 327.477374 -94.393004)
		(end 327.482454 -94.36989)
		(stroke
			(width 0.05715)
			(type default)
		)
		(layer "In9.Cu")
	)
	(gr_line
		(start 327.477374 -94.346522)
		(end 327.482454 -94.36989)
		(stroke
			(width 0.05715)
			(type default)
		)
		(layer "In9.Cu")
	)
	(gr_line
		(start 327.485248 -65.162684)
		(end 327.553574 -64.826642)
		(stroke
			(width 0.05715)
			(type default)
		)
		(layer "In9.Cu")
	)
	(gr_line
		(start 327.559416 -101.4095)
		(end 327.572116 -101.38664)
		(stroke
			(width 0.05715)
			(type default)
		)
		(layer "In9.Cu")
	)
	(gr_line
		(start 327.572116 -101.38664)
		(end 327.574148 -101.360478)
		(stroke
			(width 0.05715)
			(type default)
		)
		(layer "In9.Cu")
	)
	(gr_line
		(start 327.578466 -71.945754)
		(end 327.583546 -71.92264)
		(stroke
			(width 0.05715)
			(type default)
		)
		(layer "In9.Cu")
	)
	(gr_line
		(start 327.578466 -71.899272)
		(end 327.583546 -71.92264)
		(stroke
			(width 0.05715)
			(type default)
		)
		(layer "In9.Cu")
	)
	(gr_line
		(start 327.624694 -95.444056)
		(end 327.629774 -95.46717)
		(stroke
			(width 0.05715)
			(type default)
		)
		(layer "In9.Cu")
	)
	(gr_line
		(start 327.624694 -95.444056)
		(end 327.629774 -95.420688)
		(stroke
			(width 0.05715)
			(type default)
		)
		(layer "In9.Cu")
	)
	(gr_line
		(start 327.63206 -70.489064)
		(end 327.636632 -70.466458)
		(stroke
			(width 0.05715)
			(type default)
		)
		(layer "In9.Cu")
	)
	(gr_line
		(start 327.63206 -70.489064)
		(end 327.636886 -70.511416)
		(stroke
			(width 0.05715)
			(type default)
		)
		(layer "In9.Cu")
	)
	(gr_line
		(start 327.68286 -83.43265)
		(end 327.688956 -83.461352)
		(stroke
			(width 0.05715)
			(type default)
		)
		(layer "In9.Cu")
	)
	(gr_line
		(start 327.68286 -83.43265)
		(end 327.689718 -83.404456)
		(stroke
			(width 0.05715)
			(type default)
		)
		(layer "In9.Cu")
	)
	(gr_line
		(start 327.712578 -90.560144)
		(end 327.837038 -91.145868)
		(stroke
			(width 0.05715)
			(type default)
		)
		(layer "In9.Cu")
	)
	(gr_line
		(start 327.825354 -98.048826)
		(end 327.82637 -98.053652)
		(stroke
			(width 0.05715)
			(type default)
		)
		(layer "In9.Cu")
	)
	(gr_line
		(start 327.826116 -98.058478)
		(end 327.82637 -98.053652)
		(stroke
			(width 0.05715)
			(type default)
		)
		(layer "In9.Cu")
	)
	(gr_line
		(start 327.826624 -81.241138)
		(end 327.833482 -81.212944)
		(stroke
			(width 0.05715)
			(type default)
		)
		(layer "In9.Cu")
	)
	(gr_line
		(start 327.827386 -81.184242)
		(end 327.833482 -81.212944)
		(stroke
			(width 0.05715)
			(type default)
		)
		(layer "In9.Cu")
	)
	(gr_line
		(start 327.836784 -106.581956)
		(end 327.843896 -106.575352)
		(stroke
			(width 0.05715)
			(type default)
		)
		(layer "In9.Cu")
	)
	(gr_line
		(start 327.843896 -106.575352)
		(end 327.848468 -106.567224)
		(stroke
			(width 0.05715)
			(type default)
		)
		(layer "In9.Cu")
	)
	(gr_line
		(start 327.846436 -55.457852)
		(end 328.05751 -54.894734)
		(stroke
			(width 0.05715)
			(type default)
		)
		(layer "In9.Cu")
	)
	(gr_line
		(start 327.91781 -51.60772)
		(end 327.92543 -51.596036)
		(stroke
			(width 0.05715)
			(type default)
		)
		(layer "In9.Cu")
	)
	(gr_line
		(start 327.923652 -91.553792)
		(end 328.047604 -92.137484)
		(stroke
			(width 0.05715)
			(type default)
		)
		(layer "In9.Cu")
	)
	(gr_line
		(start 327.92543 -51.596036)
		(end 327.93686 -51.587908)
		(stroke
			(width 0.05715)
			(type default)
		)
		(layer "In9.Cu")
	)
	(gr_line
		(start 327.979532 -63.560706)
		(end 327.990454 -63.543942)
		(stroke
			(width 0.05715)
			(type default)
		)
		(layer "In9.Cu")
	)
	(gr_line
		(start 327.990454 -63.543942)
		(end 327.994264 -63.524638)
		(stroke
			(width 0.05715)
			(type default)
		)
		(layer "In9.Cu")
	)
	(gr_line
		(start 327.993502 -90.464386)
		(end 328.186542 -90.589862)
		(stroke
			(width 0.05715)
			(type default)
		)
		(layer "In9.Cu")
	)
	(gr_line
		(start 327.996296 -76.0476)
		(end 328.001376 -76.024232)
		(stroke
			(width 0.05715)
			(type default)
		)
		(layer "In9.Cu")
	)
	(gr_line
		(start 327.996296 -76.001118)
		(end 328.001376 -76.024232)
		(stroke
			(width 0.05715)
			(type default)
		)
		(layer "In9.Cu")
	)
	(gr_line
		(start 328.03592 -74.523346)
		(end 328.041 -74.54646)
		(stroke
			(width 0.05715)
			(type default)
		)
		(layer "In9.Cu")
	)
	(gr_line
		(start 328.03592 -74.523346)
		(end 328.041 -74.499978)
		(stroke
			(width 0.05715)
			(type default)
		)
		(layer "In9.Cu")
	)
	(gr_line
		(start 328.045064 -77.480668)
		(end 328.050144 -77.503782)
		(stroke
			(width 0.05715)
			(type default)
		)
		(layer "In9.Cu")
	)
	(gr_line
		(start 328.045064 -77.480668)
		(end 328.050144 -77.4573)
		(stroke
			(width 0.05715)
			(type default)
		)
		(layer "In9.Cu")
	)
	(gr_line
		(start 328.083926 -57.152286)
		(end 328.100182 -57.109106)
		(stroke
			(width 0.05715)
			(type default)
		)
		(layer "In9.Cu")
	)
	(gr_line
		(start 328.110596 -55.593234)
		(end 328.320146 -55.49773)
		(stroke
			(width 0.05715)
			(type default)
		)
		(layer "In9.Cu")
	)
	(gr_line
		(start 328.13244 -91.118436)
		(end 328.257662 -90.925142)
		(stroke
			(width 0.05715)
			(type default)
		)
		(layer "In9.Cu")
	)
	(gr_line
		(start 328.134472 -92.546932)
		(end 328.258932 -93.132656)
		(stroke
			(width 0.05715)
			(type default)
		)
		(layer "In9.Cu")
	)
	(gr_line
		(start 328.138282 -94.432374)
		(end 328.143362 -94.409006)
		(stroke
			(width 0.05715)
			(type default)
		)
		(layer "In9.Cu")
	)
	(gr_line
		(start 328.138282 -94.385892)
		(end 328.143362 -94.409006)
		(stroke
			(width 0.05715)
			(type default)
		)
		(layer "In9.Cu")
	)
	(gr_line
		(start 328.15657 -59.393582)
		(end 328.156824 -59.39282)
		(stroke
			(width 0.05715)
			(type default)
		)
		(layer "In9.Cu")
	)
	(gr_line
		(start 328.15657 -59.352434)
		(end 328.160634 -59.372754)
		(stroke
			(width 0.05715)
			(type default)
		)
		(layer "In9.Cu")
	)
	(gr_line
		(start 328.156824 -59.392566)
		(end 328.160634 -59.372754)
		(stroke
			(width 0.05715)
			(type default)
		)
		(layer "In9.Cu")
	)
	(gr_line
		(start 328.186542 -90.589862)
		(end 328.257662 -90.925142)
		(stroke
			(width 0.05715)
			(type default)
		)
		(layer "In9.Cu")
	)
	(gr_line
		(start 328.202544 -54.506876)
		(end 328.41311 -53.94452)
		(stroke
			(width 0.05715)
			(type default)
		)
		(layer "In9.Cu")
	)
	(gr_line
		(start 328.204576 -91.458288)
		(end 328.397616 -91.58351)
		(stroke
			(width 0.05715)
			(type default)
		)
		(layer "In9.Cu")
	)
	(gr_line
		(start 328.211688 -101.696266)
		(end 328.223372 -101.675184)
		(stroke
			(width 0.05715)
			(type default)
		)
		(layer "In9.Cu")
	)
	(gr_line
		(start 328.223372 -101.675184)
		(end 328.22515 -101.651308)
		(stroke
			(width 0.05715)
			(type default)
		)
		(layer "In9.Cu")
	)
	(gr_line
		(start 328.23023 -71.946008)
		(end 328.23531 -71.92264)
		(stroke
			(width 0.05715)
			(type default)
		)
		(layer "In9.Cu")
	)
	(gr_line
		(start 328.23023 -71.899526)
		(end 328.23531 -71.92264)
		(stroke
			(width 0.05715)
			(type default)
		)
		(layer "In9.Cu")
	)
	(gr_line
		(start 328.296016 -70.546722)
		(end 328.300588 -70.524116)
		(stroke
			(width 0.05715)
			(type default)
		)
		(layer "In9.Cu")
	)
	(gr_line
		(start 328.296016 -70.546722)
		(end 328.300842 -70.568566)
		(stroke
			(width 0.05715)
			(type default)
		)
		(layer "In9.Cu")
	)
	(gr_line
		(start 328.299318 -95.55226)
		(end 328.304398 -95.575374)
		(stroke
			(width 0.05715)
			(type default)
		)
		(layer "In9.Cu")
	)
	(gr_line
		(start 328.299318 -95.55226)
		(end 328.304398 -95.528892)
		(stroke
			(width 0.05715)
			(type default)
		)
		(layer "In9.Cu")
	)
	(gr_line
		(start 328.320146 -55.49773)
		(end 328.440288 -55.176674)
		(stroke
			(width 0.05715)
			(type default)
		)
		(layer "In9.Cu")
	)
	(gr_line
		(start 328.332084 -107.090718)
		(end 328.339958 -107.083352)
		(stroke
			(width 0.05715)
			(type default)
		)
		(layer "In9.Cu")
	)
	(gr_line
		(start 328.339958 -107.083352)
		(end 328.344784 -107.074462)
		(stroke
			(width 0.05715)
			(type default)
		)
		(layer "In9.Cu")
	)
	(gr_line
		(start 328.34326 -92.112084)
		(end 328.468736 -91.919044)
		(stroke
			(width 0.05715)
			(type default)
		)
		(layer "In9.Cu")
	)
	(gr_line
		(start 328.345038 -54.96687)
		(end 328.440288 -55.176674)
		(stroke
			(width 0.05715)
			(type default)
		)
		(layer "In9.Cu")
	)
	(gr_line
		(start 328.345546 -93.541596)
		(end 328.470006 -94.12732)
		(stroke
			(width 0.05715)
			(type default)
		)
		(layer "In9.Cu")
	)
	(gr_line
		(start 328.357484 -83.507326)
		(end 328.36358 -83.535012)
		(stroke
			(width 0.05715)
			(type default)
		)
		(layer "In9.Cu")
	)
	(gr_line
		(start 328.357484 -83.507326)
		(end 328.364342 -83.480148)
		(stroke
			(width 0.05715)
			(type default)
		)
		(layer "In9.Cu")
	)
	(gr_line
		(start 328.392282 -52.154074)
		(end 328.410062 -52.106576)
		(stroke
			(width 0.05715)
			(type default)
		)
		(layer "In9.Cu")
	)
	(gr_line
		(start 328.397616 -91.58351)
		(end 328.468736 -91.919044)
		(stroke
			(width 0.05715)
			(type default)
		)
		(layer "In9.Cu")
	)
	(gr_line
		(start 328.410062 -52.106576)
		(end 328.450448 -52.07762)
		(stroke
			(width 0.05715)
			(type default)
		)
		(layer "In9.Cu")
	)
	(gr_line
		(start 328.41565 -92.451936)
		(end 328.608436 -92.577412)
		(stroke
			(width 0.05715)
			(type default)
		)
		(layer "In9.Cu")
	)
	(gr_line
		(start 328.466958 -54.64175)
		(end 328.676254 -54.546246)
		(stroke
			(width 0.05715)
			(type default)
		)
		(layer "In9.Cu")
	)
	(gr_line
		(start 328.492612 -98.121724)
		(end 328.493628 -98.12655)
		(stroke
			(width 0.05715)
			(type default)
		)
		(layer "In9.Cu")
	)
	(gr_line
		(start 328.493374 -98.131376)
		(end 328.493374 -98.132392)
		(stroke
			(width 0.05715)
			(type default)
		)
		(layer "In9.Cu")
	)
	(gr_line
		(start 328.493374 -98.131376)
		(end 328.493628 -98.12655)
		(stroke
			(width 0.05715)
			(type default)
		)
		(layer "In9.Cu")
	)
	(gr_line
		(start 328.497438 -81.331054)
		(end 328.497438 -81.331308)
		(stroke
			(width 0.05715)
			(type default)
		)
		(layer "In9.Cu")
	)
	(gr_line
		(start 328.497438 -81.3308)
		(end 328.504296 -81.30286)
		(stroke
			(width 0.05715)
			(type default)
		)
		(layer "In9.Cu")
	)
	(gr_line
		(start 328.4982 -81.274666)
		(end 328.504296 -81.30286)
		(stroke
			(width 0.05715)
			(type default)
		)
		(layer "In9.Cu")
	)
	(gr_line
		(start 328.554334 -93.105986)
		(end 328.67981 -92.912946)
		(stroke
			(width 0.05715)
			(type default)
		)
		(layer "In9.Cu")
	)
	(gr_line
		(start 328.559414 -53.553868)
		(end 328.769218 -52.994306)
		(stroke
			(width 0.05715)
			(type default)
		)
		(layer "In9.Cu")
	)
	(gr_line
		(start 328.608436 -92.577412)
		(end 328.67981 -92.912946)
		(stroke
			(width 0.05715)
			(type default)
		)
		(layer "In9.Cu")
	)
	(gr_line
		(start 328.62647 -93.445838)
		(end 328.81951 -93.571314)
		(stroke
			(width 0.05715)
			(type default)
		)
		(layer "In9.Cu")
	)
	(gr_line
		(start 328.632312 -107.954318)
		(end 328.63409 -107.95127)
		(stroke
			(width 0.05715)
			(type default)
		)
		(layer "In9.Cu")
	)
	(gr_line
		(start 328.64806 -76.047346)
		(end 328.65314 -76.024232)
		(stroke
			(width 0.05715)
			(type default)
		)
		(layer "In9.Cu")
	)
	(gr_line
		(start 328.64806 -76.000864)
		(end 328.65314 -76.024232)
		(stroke
			(width 0.05715)
			(type default)
		)
		(layer "In9.Cu")
	)
	(gr_line
		(start 328.676254 -54.546246)
		(end 328.79665 -54.22519)
		(stroke
			(width 0.05715)
			(type default)
		)
		(layer "In9.Cu")
	)
	(gr_line
		(start 328.687684 -74.523346)
		(end 328.692764 -74.547222)
		(stroke
			(width 0.05715)
			(type default)
		)
		(layer "In9.Cu")
	)
	(gr_line
		(start 328.687684 -74.523346)
		(end 328.692764 -74.500232)
		(stroke
			(width 0.05715)
			(type default)
		)
		(layer "In9.Cu")
	)
	(gr_line
		(start 328.696828 -77.480668)
		(end 328.701908 -77.504036)
		(stroke
			(width 0.05715)
			(type default)
		)
		(layer "In9.Cu")
	)
	(gr_line
		(start 328.696828 -77.480668)
		(end 328.701908 -77.457554)
		(stroke
			(width 0.05715)
			(type default)
		)
		(layer "In9.Cu")
	)
	(gr_line
		(start 328.7014 -54.01564)
		(end 328.79665 -54.22519)
		(stroke
			(width 0.05715)
			(type default)
		)
		(layer "In9.Cu")
	)
	(gr_line
		(start 328.765408 -94.099634)
		(end 328.89063 -93.906848)
		(stroke
			(width 0.05715)
			(type default)
		)
		(layer "In9.Cu")
	)
	(gr_line
		(start 328.789284 -77.91577)
		(end 328.912728 -78.496922)
		(stroke
			(width 0.05715)
			(type default)
		)
		(layer "In9.Cu")
	)
	(gr_line
		(start 328.812906 -59.3471)
		(end 328.81697 -59.327034)
		(stroke
			(width 0.05715)
			(type default)
		)
		(layer "In9.Cu")
	)
	(gr_line
		(start 328.812906 -59.307222)
		(end 328.81697 -59.327034)
		(stroke
			(width 0.05715)
			(type default)
		)
		(layer "In9.Cu")
	)
	(gr_line
		(start 328.81951 -93.571314)
		(end 328.89063 -93.906848)
		(stroke
			(width 0.05715)
			(type default)
		)
		(layer "In9.Cu")
	)
	(gr_line
		(start 328.82078 -57.512204)
		(end 328.837544 -57.429908)
		(stroke
			(width 0.05715)
			(type default)
		)
		(layer "In9.Cu")
	)
	(gr_line
		(start 328.82078 -57.512204)
		(end 328.867516 -57.58307)
		(stroke
			(width 0.05715)
			(type default)
		)
		(layer "In9.Cu")
	)
	(gr_line
		(start 328.82332 -53.690012)
		(end 329.032616 -53.594762)
		(stroke
			(width 0.05715)
			(type default)
		)
		(layer "In9.Cu")
	)
	(gr_line
		(start 328.829924 -94.459806)
		(end 328.83475 -94.437962)
		(stroke
			(width 0.05715)
			(type default)
		)
		(layer "In9.Cu")
	)
	(gr_line
		(start 328.830432 -94.417896)
		(end 328.83475 -94.437962)
		(stroke
			(width 0.05715)
			(type default)
		)
		(layer "In9.Cu")
	)
	(gr_line
		(start 328.877168 -101.871272)
		(end 328.88936 -101.849428)
		(stroke
			(width 0.05715)
			(type default)
		)
		(layer "In9.Cu")
	)
	(gr_line
		(start 328.881994 -71.945754)
		(end 328.887074 -71.92264)
		(stroke
			(width 0.05715)
			(type default)
		)
		(layer "In9.Cu")
	)
	(gr_line
		(start 328.881994 -71.899272)
		(end 328.887074 -71.92264)
		(stroke
			(width 0.05715)
			(type default)
		)
		(layer "In9.Cu")
	)
	(gr_line
		(start 328.88936 -101.849428)
		(end 328.891392 -101.824282)
		(stroke
			(width 0.05715)
			(type default)
		)
		(layer "In9.Cu")
	)
	(gr_line
		(start 328.906378 -57.09412)
		(end 328.922634 -57.013602)
		(stroke
			(width 0.05715)
			(type default)
		)
		(layer "In9.Cu")
	)
	(gr_line
		(start 328.922634 -57.013602)
		(end 328.991722 -56.967628)
		(stroke
			(width 0.05715)
			(type default)
		)
		(layer "In9.Cu")
	)
	(gr_line
		(start 328.92619 -52.574952)
		(end 328.943716 -52.528216)
		(stroke
			(width 0.05715)
			(type default)
		)
		(layer "In9.Cu")
	)
	(gr_line
		(start 328.943716 -52.528216)
		(end 328.984102 -52.49926)
		(stroke
			(width 0.05715)
			(type default)
		)
		(layer "In9.Cu")
	)
	(gr_line
		(start 328.952098 -70.566534)
		(end 328.95667 -70.543928)
		(stroke
			(width 0.05715)
			(type default)
		)
		(layer "In9.Cu")
	)
	(gr_line
		(start 328.952098 -70.566534)
		(end 328.956924 -70.588886)
		(stroke
			(width 0.05715)
			(type default)
		)
		(layer "In9.Cu")
	)
	(gr_line
		(start 328.958956 -95.588328)
		(end 328.964036 -95.611696)
		(stroke
			(width 0.05715)
			(type default)
		)
		(layer "In9.Cu")
	)
	(gr_line
		(start 328.958956 -95.588328)
		(end 328.964036 -95.565214)
		(stroke
			(width 0.05715)
			(type default)
		)
		(layer "In9.Cu")
	)
	(gr_line
		(start 328.997056 -57.778396)
		(end 329.043538 -57.8485)
		(stroke
			(width 0.05715)
			(type default)
		)
		(layer "In9.Cu")
	)
	(gr_line
		(start 329.000104 -78.90891)
		(end 329.124056 -79.491586)
		(stroke
			(width 0.05715)
			(type default)
		)
		(layer "In9.Cu")
	)
	(gr_line
		(start 329.032616 -53.594762)
		(end 329.152758 -53.273706)
		(stroke
			(width 0.05715)
			(type default)
		)
		(layer "In9.Cu")
	)
	(gr_line
		(start 329.043538 -57.8485)
		(end 329.12558 -57.865264)
		(stroke
			(width 0.05715)
			(type default)
		)
		(layer "In9.Cu")
	)
	(gr_line
		(start 329.057762 -53.064156)
		(end 329.152758 -53.273706)
		(stroke
			(width 0.05715)
			(type default)
		)
		(layer "In9.Cu")
	)
	(gr_line
		(start 329.0697 -77.818234)
		(end 329.262486 -77.943202)
		(stroke
			(width 0.05715)
			(type default)
		)
		(layer "In9.Cu")
	)
	(gr_line
		(start 329.125834 -83.198716)
		(end 329.132438 -83.22945)
		(stroke
			(width 0.05715)
			(type default)
		)
		(layer "In9.Cu")
	)
	(gr_line
		(start 329.125834 -83.198716)
		(end 329.1332 -83.169252)
		(stroke
			(width 0.05715)
			(type default)
		)
		(layer "In9.Cu")
	)
	(gr_line
		(start 329.164442 -98.216212)
		(end 329.165458 -98.221038)
		(stroke
			(width 0.05715)
			(type default)
		)
		(layer "In9.Cu")
	)
	(gr_line
		(start 329.165204 -98.225864)
		(end 329.165204 -98.22688)
		(stroke
			(width 0.05715)
			(type default)
		)
		(layer "In9.Cu")
	)
	(gr_line
		(start 329.165204 -98.225864)
		(end 329.165458 -98.221038)
		(stroke
			(width 0.05715)
			(type default)
		)
		(layer "In9.Cu")
	)
	(gr_line
		(start 329.168506 -81.421224)
		(end 329.175364 -81.39303)
		(stroke
			(width 0.05715)
			(type default)
		)
		(layer "In9.Cu")
	)
	(gr_line
		(start 329.169268 -81.364836)
		(end 329.175364 -81.39303)
		(stroke
			(width 0.05715)
			(type default)
		)
		(layer "In9.Cu")
	)
	(gr_line
		(start 329.18908 -56.836818)
		(end 329.259184 -56.790336)
		(stroke
			(width 0.05715)
			(type default)
		)
		(layer "In9.Cu")
	)
	(gr_line
		(start 329.208638 -78.471522)
		(end 329.33386 -78.278736)
		(stroke
			(width 0.05715)
			(type default)
		)
		(layer "In9.Cu")
	)
	(gr_line
		(start 329.210924 -79.901542)
		(end 329.334876 -80.48498)
		(stroke
			(width 0.05715)
			(type default)
		)
		(layer "In9.Cu")
	)
	(gr_line
		(start 329.259184 -56.790336)
		(end 329.342242 -56.8071)
		(stroke
			(width 0.05715)
			(type default)
		)
		(layer "In9.Cu")
	)
	(gr_line
		(start 329.262486 -77.943202)
		(end 329.33386 -78.278736)
		(stroke
			(width 0.05715)
			(type default)
		)
		(layer "In9.Cu")
	)
	(gr_line
		(start 329.280774 -78.812136)
		(end 329.47356 -78.937104)
		(stroke
			(width 0.05715)
			(type default)
		)
		(layer "In9.Cu")
	)
	(gr_line
		(start 329.29957 -76.047346)
		(end 329.30465 -76.024232)
		(stroke
			(width 0.05715)
			(type default)
		)
		(layer "In9.Cu")
	)
	(gr_line
		(start 329.29957 -76.000356)
		(end 329.30465 -76.024232)
		(stroke
			(width 0.05715)
			(type default)
		)
		(layer "In9.Cu")
	)
	(gr_line
		(start 329.38593 -105.97769)
		(end 329.675744 -105.451148)
		(stroke
			(width 0.05715)
			(type default)
		)
		(layer "In9.Cu")
	)
	(gr_line
		(start 329.419712 -79.465424)
		(end 329.544934 -79.272638)
		(stroke
			(width 0.05715)
			(type default)
		)
		(layer "In9.Cu")
	)
	(gr_line
		(start 329.472544 -57.638188)
		(end 329.552808 -57.654444)
		(stroke
			(width 0.05715)
			(type default)
		)
		(layer "In9.Cu")
	)
	(gr_line
		(start 329.47356 -78.937104)
		(end 329.544934 -79.272638)
		(stroke
			(width 0.05715)
			(type default)
		)
		(layer "In9.Cu")
	)
	(gr_line
		(start 329.491848 -79.805784)
		(end 329.684634 -79.931006)
		(stroke
			(width 0.05715)
			(type default)
		)
		(layer "In9.Cu")
	)
	(gr_line
		(start 329.518772 -102.157276)
		(end 329.530964 -102.135432)
		(stroke
			(width 0.05715)
			(type default)
		)
		(layer "In9.Cu")
	)
	(gr_line
		(start 329.530964 -102.135432)
		(end 329.532996 -102.110286)
		(stroke
			(width 0.05715)
			(type default)
		)
		(layer "In9.Cu")
	)
	(gr_line
		(start 329.533758 -71.945754)
		(end 329.538838 -71.92264)
		(stroke
			(width 0.05715)
			(type default)
		)
		(layer "In9.Cu")
	)
	(gr_line
		(start 329.533758 -71.899272)
		(end 329.538838 -71.92264)
		(stroke
			(width 0.05715)
			(type default)
		)
		(layer "In9.Cu")
	)
	(gr_line
		(start 329.552808 -57.654444)
		(end 329.59802 -57.72277)
		(stroke
			(width 0.05715)
			(type default)
		)
		(layer "In9.Cu")
	)
	(gr_line
		(start 329.578716 -94.077028)
		(end 329.583796 -94.053914)
		(stroke
			(width 0.05715)
			(type default)
		)
		(layer "In9.Cu")
	)
	(gr_line
		(start 329.578716 -94.030546)
		(end 329.583796 -94.053914)
		(stroke
			(width 0.05715)
			(type default)
		)
		(layer "In9.Cu")
	)
	(gr_line
		(start 329.599544 -57.158128)
		(end 329.682602 -57.174892)
		(stroke
			(width 0.05715)
			(type default)
		)
		(layer "In9.Cu")
	)
	(gr_line
		(start 329.628246 -106.148886)
		(end 329.84948 -106.084624)
		(stroke
			(width 0.05715)
			(type default)
		)
		(layer "In9.Cu")
	)
	(gr_line
		(start 329.628754 -95.671894)
		(end 329.633834 -95.695262)
		(stroke
			(width 0.05715)
			(type default)
		)
		(layer "In9.Cu")
	)
	(gr_line
		(start 329.628754 -95.671894)
		(end 329.633834 -95.64878)
		(stroke
			(width 0.05715)
			(type default)
		)
		(layer "In9.Cu")
	)
	(gr_line
		(start 329.630786 -80.459326)
		(end 329.756008 -80.26654)
		(stroke
			(width 0.05715)
			(type default)
		)
		(layer "In9.Cu")
	)
	(gr_line
		(start 329.653138 -54.87416)
		(end 329.677268 -54.95544)
		(stroke
			(width 0.05715)
			(type default)
		)
		(layer "In9.Cu")
	)
	(gr_line
		(start 329.653138 -54.87416)
		(end 329.693016 -54.800754)
		(stroke
			(width 0.05715)
			(type default)
		)
		(layer "In9.Cu")
	)
	(gr_line
		(start 329.682602 -57.174892)
		(end 329.75296 -57.12841)
		(stroke
			(width 0.05715)
			(type default)
		)
		(layer "In9.Cu")
	)
	(gr_line
		(start 329.684634 -79.931006)
		(end 329.756008 -80.26654)
		(stroke
			(width 0.05715)
			(type default)
		)
		(layer "In9.Cu")
	)
	(gr_line
		(start 329.698604 -52.853844)
		(end 329.716892 -52.80533)
		(stroke
			(width 0.05715)
			(type default)
		)
		(layer "In9.Cu")
	)
	(gr_line
		(start 329.716892 -52.80533)
		(end 329.759056 -52.775104)
		(stroke
			(width 0.05715)
			(type default)
		)
		(layer "In9.Cu")
	)
	(gr_line
		(start 329.738228 -90.00998)
		(end 329.861672 -90.591386)
		(stroke
			(width 0.05715)
			(type default)
		)
		(layer "In9.Cu")
	)
	(gr_line
		(start 329.744324 -55.180992)
		(end 329.7682 -55.260748)
		(stroke
			(width 0.05715)
			(type default)
		)
		(layer "In9.Cu")
	)
	(gr_line
		(start 329.753722 -57.955942)
		(end 329.75423 -57.956958)
		(stroke
			(width 0.05715)
			(type default)
		)
		(layer "In9.Cu")
	)
	(gr_line
		(start 329.75423 -57.957212)
		(end 329.800712 -58.027062)
		(stroke
			(width 0.05715)
			(type default)
		)
		(layer "In9.Cu")
	)
	(gr_line
		(start 329.7682 -55.260748)
		(end 329.841098 -55.300372)
		(stroke
			(width 0.05715)
			(type default)
		)
		(layer "In9.Cu")
	)
	(gr_line
		(start 329.783948 -58.109612)
		(end 329.800712 -58.027062)
		(stroke
			(width 0.05715)
			(type default)
		)
		(layer "In9.Cu")
	)
	(gr_line
		(start 329.824588 -98.255836)
		(end 329.825604 -98.260662)
		(stroke
			(width 0.05715)
			(type default)
		)
		(layer "In9.Cu")
	)
	(gr_line
		(start 329.82535 -98.265488)
		(end 329.825604 -98.260662)
		(stroke
			(width 0.05715)
			(type default)
		)
		(layer "In9.Cu")
	)
	(gr_line
		(start 329.838812 -81.511902)
		(end 329.84567 -81.483454)
		(stroke
			(width 0.05715)
			(type default)
		)
		(layer "In9.Cu")
	)
	(gr_line
		(start 329.839574 -81.454498)
		(end 329.84567 -81.4832)
		(stroke
			(width 0.05715)
			(type default)
		)
		(layer "In9.Cu")
	)
	(gr_line
		(start 329.842368 -56.352948)
		(end 329.843384 -56.347868)
		(stroke
			(width 0.05715)
			(type default)
		)
		(layer "In9.Cu")
	)
	(gr_line
		(start 329.843384 -56.347868)
		(end 329.845924 -56.343296)
		(stroke
			(width 0.05715)
			(type default)
		)
		(layer "In9.Cu")
	)
	(gr_line
		(start 329.84567 -81.4832)
		(end 329.84567 -81.483454)
		(stroke
			(width 0.05715)
			(type default)
		)
		(layer "In9.Cu")
	)
	(gr_line
		(start 329.84948 -106.084624)
		(end 330.01458 -105.784396)
		(stroke
			(width 0.05715)
			(type default)
		)
		(layer "In9.Cu")
	)
	(gr_line
		(start 329.855576 -54.500272)
		(end 329.895708 -54.426358)
		(stroke
			(width 0.05715)
			(type default)
		)
		(layer "In9.Cu")
	)
	(gr_line
		(start 329.876404 -105.086658)
		(end 330.165202 -104.56164)
		(stroke
			(width 0.05715)
			(type default)
		)
		(layer "In9.Cu")
	)
	(gr_line
		(start 329.895708 -54.426358)
		(end 329.975718 -54.402482)
		(stroke
			(width 0.05715)
			(type default)
		)
		(layer "In9.Cu")
	)
	(gr_line
		(start 329.948794 -56.99887)
		(end 330.018898 -56.952642)
		(stroke
			(width 0.05715)
			(type default)
		)
		(layer "In9.Cu")
	)
	(gr_line
		(start 329.949048 -91.00312)
		(end 330.072746 -91.585542)
		(stroke
			(width 0.05715)
			(type default)
		)
		(layer "In9.Cu")
	)
	(gr_line
		(start 329.950572 -105.563416)
		(end 330.01458 -105.784396)
		(stroke
			(width 0.05715)
			(type default)
		)
		(layer "In9.Cu")
	)
	(gr_line
		(start 330.018644 -89.912952)
		(end 330.211684 -90.038428)
		(stroke
			(width 0.05715)
			(type default)
		)
		(layer "In9.Cu")
	)
	(gr_line
		(start 330.018898 -56.952642)
		(end 330.035662 -56.870092)
		(stroke
			(width 0.05715)
			(type default)
		)
		(layer "In9.Cu")
	)
	(gr_line
		(start 330.117958 -105.258616)
		(end 330.24953 -105.220516)
		(stroke
			(width 0.05715)
			(type default)
		)
		(layer "In9.Cu")
	)
	(gr_line
		(start 330.157582 -90.566494)
		(end 330.282804 -90.373962)
		(stroke
			(width 0.05715)
			(type default)
		)
		(layer "In9.Cu")
	)
	(gr_line
		(start 330.160122 -91.997276)
		(end 330.28382 -92.579698)
		(stroke
			(width 0.05715)
			(type default)
		)
		(layer "In9.Cu")
	)
	(gr_line
		(start 330.202032 -54.335172)
		(end 330.28255 -54.311296)
		(stroke
			(width 0.05715)
			(type default)
		)
		(layer "In9.Cu")
	)
	(gr_line
		(start 330.208128 -102.277418)
		(end 330.22032 -102.255574)
		(stroke
			(width 0.05715)
			(type default)
		)
		(layer "In9.Cu")
	)
	(gr_line
		(start 330.211684 -90.038428)
		(end 330.282804 -90.373962)
		(stroke
			(width 0.05715)
			(type default)
		)
		(layer "In9.Cu")
	)
	(gr_line
		(start 330.22032 -102.255574)
		(end 330.222352 -102.230428)
		(stroke
			(width 0.05715)
			(type default)
		)
		(layer "In9.Cu")
	)
	(gr_line
		(start 330.229718 -90.906854)
		(end 330.422758 -91.03233)
		(stroke
			(width 0.05715)
			(type default)
		)
		(layer "In9.Cu")
	)
	(gr_line
		(start 330.248514 -94.158054)
		(end 330.253594 -94.134686)
		(stroke
			(width 0.05715)
			(type default)
		)
		(layer "In9.Cu")
	)
	(gr_line
		(start 330.248514 -94.111572)
		(end 330.253594 -94.134686)
		(stroke
			(width 0.05715)
			(type default)
		)
		(layer "In9.Cu")
	)
	(gr_line
		(start 330.24953 -105.220516)
		(end 330.339192 -105.194354)
		(stroke
			(width 0.05715)
			(type default)
		)
		(layer "In9.Cu")
	)
	(gr_line
		(start 330.28255 -54.311296)
		(end 330.355956 -54.351174)
		(stroke
			(width 0.05715)
			(type default)
		)
		(layer "In9.Cu")
	)
	(gr_line
		(start 330.286868 -95.703136)
		(end 330.291948 -95.72625)
		(stroke
			(width 0.05715)
			(type default)
		)
		(layer "In9.Cu")
	)
	(gr_line
		(start 330.286868 -95.703136)
		(end 330.291948 -95.679514)
		(stroke
			(width 0.05715)
			(type default)
		)
		(layer "In9.Cu")
	)
	(gr_line
		(start 330.339192 -105.194354)
		(end 330.504292 -104.894126)
		(stroke
			(width 0.05715)
			(type default)
		)
		(layer "In9.Cu")
	)
	(gr_line
		(start 330.356718 -55.24754)
		(end 330.430886 -55.287672)
		(stroke
			(width 0.05715)
			(type default)
		)
		(layer "In9.Cu")
	)
	(gr_line
		(start 330.362306 -53.408326)
		(end 330.386436 -53.489606)
		(stroke
			(width 0.05715)
			(type default)
		)
		(layer "In9.Cu")
	)
	(gr_line
		(start 330.362306 -53.408326)
		(end 330.402184 -53.33492)
		(stroke
			(width 0.05715)
			(type default)
		)
		(layer "In9.Cu")
	)
	(gr_line
		(start 330.366116 -104.196388)
		(end 330.65466 -103.671878)
		(stroke
			(width 0.05715)
			(type default)
		)
		(layer "In9.Cu")
	)
	(gr_line
		(start 330.368656 -91.560396)
		(end 330.493878 -91.36761)
		(stroke
			(width 0.05715)
			(type default)
		)
		(layer "In9.Cu")
	)
	(gr_line
		(start 330.37145 -92.992448)
		(end 330.495148 -93.57487)
		(stroke
			(width 0.05715)
			(type default)
		)
		(layer "In9.Cu")
	)
	(gr_line
		(start 330.422758 -91.03233)
		(end 330.493878 -91.36761)
		(stroke
			(width 0.05715)
			(type default)
		)
		(layer "In9.Cu")
	)
	(gr_line
		(start 330.430886 -55.287672)
		(end 330.455016 -55.369206)
		(stroke
			(width 0.05715)
			(type default)
		)
		(layer "In9.Cu")
	)
	(gr_line
		(start 330.440284 -104.673146)
		(end 330.504292 -104.894126)
		(stroke
			(width 0.05715)
			(type default)
		)
		(layer "In9.Cu")
	)
	(gr_line
		(start 330.440792 -91.900756)
		(end 330.633578 -92.026232)
		(stroke
			(width 0.05715)
			(type default)
		)
		(layer "In9.Cu")
	)
	(gr_line
		(start 330.44511 -56.661812)
		(end 330.446126 -56.656732)
		(stroke
			(width 0.05715)
			(type default)
		)
		(layer "In9.Cu")
	)
	(gr_line
		(start 330.446126 -56.656732)
		(end 330.448412 -56.652414)
		(stroke
			(width 0.05715)
			(type default)
		)
		(layer "In9.Cu")
	)
	(gr_line
		(start 330.453492 -53.715158)
		(end 330.477368 -53.794914)
		(stroke
			(width 0.05715)
			(type default)
		)
		(layer "In9.Cu")
	)
	(gr_line
		(start 330.477368 -53.794914)
		(end 330.550266 -53.834538)
		(stroke
			(width 0.05715)
			(type default)
		)
		(layer "In9.Cu")
	)
	(gr_line
		(start 330.504546 -55.748682)
		(end 330.544932 -55.674768)
		(stroke
			(width 0.05715)
			(type default)
		)
		(layer "In9.Cu")
	)
	(gr_line
		(start 330.510388 -98.417888)
		(end 330.511404 -98.422714)
		(stroke
			(width 0.05715)
			(type default)
		)
		(layer "In9.Cu")
	)
	(gr_line
		(start 330.51115 -98.42754)
		(end 330.51115 -98.428556)
		(stroke
			(width 0.05715)
			(type default)
		)
		(layer "In9.Cu")
	)
	(gr_line
		(start 330.51115 -98.42754)
		(end 330.511404 -98.422714)
		(stroke
			(width 0.05715)
			(type default)
		)
		(layer "In9.Cu")
	)
	(gr_line
		(start 330.521056 -55.593742)
		(end 330.544932 -55.674768)
		(stroke
			(width 0.05715)
			(type default)
		)
		(layer "In9.Cu")
	)
	(gr_line
		(start 330.564744 -53.034438)
		(end 330.604876 -52.960524)
		(stroke
			(width 0.05715)
			(type default)
		)
		(layer "In9.Cu")
	)
	(gr_line
		(start 330.577952 -54.803802)
		(end 330.651612 -54.84368)
		(stroke
			(width 0.05715)
			(type default)
		)
		(layer "In9.Cu")
	)
	(gr_line
		(start 330.579476 -92.554552)
		(end 330.704952 -92.361512)
		(stroke
			(width 0.05715)
			(type default)
		)
		(layer "In9.Cu")
	)
	(gr_line
		(start 330.604876 -52.960524)
		(end 330.684886 -52.936648)
		(stroke
			(width 0.05715)
			(type default)
		)
		(layer "In9.Cu")
	)
	(gr_line
		(start 330.607924 -104.368346)
		(end 330.828904 -104.304084)
		(stroke
			(width 0.05715)
			(type default)
		)
		(layer "In9.Cu")
	)
	(gr_line
		(start 330.62037 -102.332282)
		(end 330.635102 -102.305866)
		(stroke
			(width 0.05715)
			(type default)
		)
		(layer "In9.Cu")
	)
	(gr_line
		(start 330.633578 -92.026232)
		(end 330.704952 -92.361512)
		(stroke
			(width 0.05715)
			(type default)
		)
		(layer "In9.Cu")
	)
	(gr_line
		(start 330.651612 -54.84368)
		(end 330.73213 -54.819804)
		(stroke
			(width 0.05715)
			(type default)
		)
		(layer "In9.Cu")
	)
	(gr_line
		(start 330.651866 -92.894912)
		(end 330.844652 -93.01988)
		(stroke
			(width 0.05715)
			(type default)
		)
		(layer "In9.Cu")
	)
	(gr_line
		(start 330.78928 -91.033854)
		(end 330.91374 -91.620594)
		(stroke
			(width 0.05715)
			(type default)
		)
		(layer "In9.Cu")
	)
	(gr_line
		(start 330.79055 -93.548454)
		(end 330.916026 -93.355414)
		(stroke
			(width 0.05715)
			(type default)
		)
		(layer "In9.Cu")
	)
	(gr_line
		(start 330.828904 -104.304084)
		(end 330.994004 -104.003856)
		(stroke
			(width 0.05715)
			(type default)
		)
		(layer "In9.Cu")
	)
	(gr_line
		(start 330.844652 -93.01988)
		(end 330.916026 -93.355414)
		(stroke
			(width 0.05715)
			(type default)
		)
		(layer "In9.Cu")
	)
	(gr_line
		(start 330.85659 -103.304848)
		(end 331.143864 -102.782878)
		(stroke
			(width 0.05715)
			(type default)
		)
		(layer "In9.Cu")
	)
	(gr_line
		(start 330.859892 -57.94756)
		(end 330.860908 -57.94248)
		(stroke
			(width 0.05715)
			(type default)
		)
		(layer "In9.Cu")
	)
	(gr_line
		(start 330.860908 -57.94248)
		(end 330.863194 -57.938162)
		(stroke
			(width 0.05715)
			(type default)
		)
		(layer "In9.Cu")
	)
	(gr_line
		(start 330.864718 -102.499668)
		(end 330.92009 -102.444296)
		(stroke
			(width 0.05715)
			(type default)
		)
		(layer "In9.Cu")
	)
	(gr_line
		(start 330.905358 -55.809642)
		(end 331.190092 -55.283862)
		(stroke
			(width 0.05715)
			(type default)
		)
		(layer "In9.Cu")
	)
	(gr_line
		(start 330.910692 -94.126304)
		(end 330.915772 -94.149672)
		(stroke
			(width 0.05715)
			(type default)
		)
		(layer "In9.Cu")
	)
	(gr_line
		(start 330.910946 -94.172278)
		(end 330.915518 -94.150688)
		(stroke
			(width 0.05715)
			(type default)
		)
		(layer "In9.Cu")
	)
	(gr_line
		(start 330.9112 -52.869338)
		(end 330.991718 -52.845462)
		(stroke
			(width 0.05715)
			(type default)
		)
		(layer "In9.Cu")
	)
	(gr_line
		(start 330.915518 -94.150942)
		(end 330.915772 -94.149672)
		(stroke
			(width 0.05715)
			(type default)
		)
		(layer "In9.Cu")
	)
	(gr_line
		(start 330.915518 -94.150688)
		(end 330.915518 -94.150942)
		(stroke
			(width 0.05715)
			(type default)
		)
		(layer "In9.Cu")
	)
	(gr_line
		(start 330.92009 -102.444296)
		(end 330.92644 -102.361238)
		(stroke
			(width 0.05715)
			(type default)
		)
		(layer "In9.Cu")
	)
	(gr_line
		(start 330.929996 -103.782876)
		(end 330.994004 -104.003856)
		(stroke
			(width 0.05715)
			(type default)
		)
		(layer "In9.Cu")
	)
	(gr_line
		(start 330.976224 -54.746906)
		(end 331.055218 -54.723538)
		(stroke
			(width 0.05715)
			(type default)
		)
		(layer "In9.Cu")
	)
	(gr_line
		(start 330.976986 -95.53575)
		(end 330.982066 -95.559118)
		(stroke
			(width 0.05715)
			(type default)
		)
		(layer "In9.Cu")
	)
	(gr_line
		(start 330.976986 -95.53575)
		(end 330.982066 -95.512636)
		(stroke
			(width 0.05715)
			(type default)
		)
		(layer "In9.Cu")
	)
	(gr_line
		(start 330.991718 -52.845462)
		(end 331.065886 -52.885594)
		(stroke
			(width 0.05715)
			(type default)
		)
		(layer "In9.Cu")
	)
	(gr_line
		(start 331.0001 -92.026994)
		(end 331.12456 -92.612972)
		(stroke
			(width 0.05715)
			(type default)
		)
		(layer "In9.Cu")
	)
	(gr_line
		(start 331.055218 -54.723538)
		(end 331.094588 -54.650894)
		(stroke
			(width 0.05715)
			(type default)
		)
		(layer "In9.Cu")
	)
	(gr_line
		(start 331.070204 -90.938096)
		(end 331.263244 -91.063572)
		(stroke
			(width 0.05715)
			(type default)
		)
		(layer "In9.Cu")
	)
	(gr_line
		(start 331.09408 -53.796946)
		(end 331.167994 -53.837078)
		(stroke
			(width 0.05715)
			(type default)
		)
		(layer "In9.Cu")
	)
	(gr_line
		(start 331.097636 -103.478076)
		(end 331.318616 -103.413814)
		(stroke
			(width 0.05715)
			(type default)
		)
		(layer "In9.Cu")
	)
	(gr_line
		(start 331.14742 -55.981092)
		(end 331.367892 -55.91556)
		(stroke
			(width 0.05715)
			(type default)
		)
		(layer "In9.Cu")
	)
	(gr_line
		(start 331.167994 -53.837078)
		(end 331.19187 -53.917596)
		(stroke
			(width 0.05715)
			(type default)
		)
		(layer "In9.Cu")
	)
	(gr_line
		(start 331.207872 -98.632264)
		(end 331.208888 -98.63709)
		(stroke
			(width 0.05715)
			(type default)
		)
		(layer "In9.Cu")
	)
	(gr_line
		(start 331.208634 -98.641916)
		(end 331.208888 -98.63709)
		(stroke
			(width 0.05715)
			(type default)
		)
		(layer "In9.Cu")
	)
	(gr_line
		(start 331.209142 -91.592146)
		(end 331.334618 -91.399106)
		(stroke
			(width 0.05715)
			(type default)
		)
		(layer "In9.Cu")
	)
	(gr_line
		(start 331.22743 -118.09349)
		(end 331.2668 -118.13286)
		(stroke
			(width 0.05715)
			(type default)
		)
		(layer "In9.Cu")
	)
	(gr_line
		(start 331.22743 -117.67693)
		(end 331.2668 -117.63756)
		(stroke
			(width 0.05715)
			(type default)
		)
		(layer "In9.Cu")
	)
	(gr_line
		(start 331.258926 -54.347872)
		(end 331.29855 -54.27472)
		(stroke
			(width 0.05715)
			(type default)
		)
		(layer "In9.Cu")
	)
	(gr_line
		(start 331.263244 -91.063572)
		(end 331.334618 -91.399106)
		(stroke
			(width 0.05715)
			(type default)
		)
		(layer "In9.Cu")
	)
	(gr_line
		(start 331.2668 -118.13286)
		(end 331.2668 -118.5164)
		(stroke
			(width 0.05715)
			(type default)
		)
		(layer "In9.Cu")
	)
	(gr_line
		(start 331.2668 -117.35562)
		(end 331.2668 -117.63756)
		(stroke
			(width 0.05715)
			(type default)
		)
		(layer "In9.Cu")
	)
	(gr_line
		(start 331.27442 -54.193186)
		(end 331.29855 -54.27472)
		(stroke
			(width 0.05715)
			(type default)
		)
		(layer "In9.Cu")
	)
	(gr_line
		(start 331.281278 -91.931998)
		(end 331.474318 -92.057474)
		(stroke
			(width 0.05715)
			(type default)
		)
		(layer "In9.Cu")
	)
	(gr_line
		(start 331.318616 -103.413814)
		(end 331.483716 -103.113586)
		(stroke
			(width 0.05715)
			(type default)
		)
		(layer "In9.Cu")
	)
	(gr_line
		(start 331.364082 -58.71337)
		(end 331.365098 -58.70829)
		(stroke
			(width 0.05715)
			(type default)
		)
		(layer "In9.Cu")
	)
	(gr_line
		(start 331.36459 -53.379878)
		(end 331.437234 -53.419248)
		(stroke
			(width 0.05715)
			(type default)
		)
		(layer "In9.Cu")
	)
	(gr_line
		(start 331.365098 -58.70829)
		(end 331.367384 -58.703972)
		(stroke
			(width 0.05715)
			(type default)
		)
		(layer "In9.Cu")
	)
	(gr_line
		(start 331.367892 -55.91556)
		(end 331.531214 -55.614062)
		(stroke
			(width 0.05715)
			(type default)
		)
		(layer "In9.Cu")
	)
	(gr_line
		(start 331.389736 -54.915816)
		(end 331.673708 -54.391814)
		(stroke
			(width 0.05715)
			(type default)
		)
		(layer "In9.Cu")
	)
	(gr_line
		(start 331.419708 -102.892606)
		(end 331.483716 -103.113586)
		(stroke
			(width 0.05715)
			(type default)
		)
		(layer "In9.Cu")
	)
	(gr_line
		(start 331.419962 -92.585794)
		(end 331.545438 -92.392754)
		(stroke
			(width 0.05715)
			(type default)
		)
		(layer "In9.Cu")
	)
	(gr_line
		(start 331.437234 -53.419248)
		(end 331.515974 -53.39588)
		(stroke
			(width 0.05715)
			(type default)
		)
		(layer "In9.Cu")
	)
	(gr_line
		(start 331.465936 -55.39359)
		(end 331.531214 -55.614062)
		(stroke
			(width 0.05715)
			(type default)
		)
		(layer "In9.Cu")
	)
	(gr_line
		(start 331.474318 -92.057474)
		(end 331.545438 -92.392754)
		(stroke
			(width 0.05715)
			(type default)
		)
		(layer "In9.Cu")
	)
	(gr_line
		(start 331.568044 -58.333894)
		(end 331.851508 -57.810654)
		(stroke
			(width 0.05715)
			(type default)
		)
		(layer "In9.Cu")
	)
	(gr_line
		(start 331.571854 -102.610666)
		(end 331.584046 -102.588822)
		(stroke
			(width 0.05715)
			(type default)
		)
		(layer "In9.Cu")
	)
	(gr_line
		(start 331.584046 -102.588822)
		(end 331.586078 -102.563676)
		(stroke
			(width 0.05715)
			(type default)
		)
		(layer "In9.Cu")
	)
	(gr_line
		(start 331.631544 -55.087774)
		(end 331.852016 -55.022242)
		(stroke
			(width 0.05715)
			(type default)
		)
		(layer "In9.Cu")
	)
	(gr_line
		(start 331.654912 -93.750638)
		(end 331.659992 -93.727524)
		(stroke
			(width 0.05715)
			(type default)
		)
		(layer "In9.Cu")
	)
	(gr_line
		(start 331.654912 -93.704156)
		(end 331.659992 -93.727524)
		(stroke
			(width 0.05715)
			(type default)
		)
		(layer "In9.Cu")
	)
	(gr_line
		(start 331.743558 -53.328824)
		(end 331.823822 -53.304948)
		(stroke
			(width 0.05715)
			(type default)
		)
		(layer "In9.Cu")
	)
	(gr_line
		(start 331.809598 -58.506614)
		(end 332.029816 -58.441082)
		(stroke
			(width 0.05715)
			(type default)
		)
		(layer "In9.Cu")
	)
	(gr_line
		(start 331.823822 -53.304948)
		(end 331.863446 -53.231542)
		(stroke
			(width 0.05715)
			(type default)
		)
		(layer "In9.Cu")
	)
	(gr_line
		(start 331.852016 -55.022242)
		(end 332.015338 -54.720744)
		(stroke
			(width 0.05715)
			(type default)
		)
		(layer "In9.Cu")
	)
	(gr_line
		(start 331.874368 -54.021736)
		(end 332.15834 -53.497734)
		(stroke
			(width 0.05715)
			(type default)
		)
		(layer "In9.Cu")
	)
	(gr_line
		(start 331.89672 -98.459544)
		(end 331.897736 -98.46437)
		(stroke
			(width 0.05715)
			(type default)
		)
		(layer "In9.Cu")
	)
	(gr_line
		(start 331.897482 -98.46945)
		(end 331.897736 -98.464624)
		(stroke
			(width 0.05715)
			(type default)
		)
		(layer "In9.Cu")
	)
	(gr_line
		(start 331.897736 -98.46437)
		(end 331.897736 -98.464624)
		(stroke
			(width 0.05715)
			(type default)
		)
		(layer "In9.Cu")
	)
	(gr_line
		(start 331.95006 -54.500272)
		(end 332.015338 -54.720744)
		(stroke
			(width 0.05715)
			(type default)
		)
		(layer "In9.Cu")
	)
	(gr_line
		(start 332.029816 -58.441082)
		(end 332.193392 -58.139584)
		(stroke
			(width 0.05715)
			(type default)
		)
		(layer "In9.Cu")
	)
	(gr_line
		(start 332.05166 -57.441084)
		(end 332.335632 -56.917336)
		(stroke
			(width 0.05715)
			(type default)
		)
		(layer "In9.Cu")
	)
	(gr_line
		(start 332.115668 -54.194456)
		(end 332.33614 -54.129178)
		(stroke
			(width 0.05715)
			(type default)
		)
		(layer "In9.Cu")
	)
	(gr_line
		(start 332.12786 -57.919112)
		(end 332.193392 -58.139584)
		(stroke
			(width 0.05715)
			(type default)
		)
		(layer "In9.Cu")
	)
	(gr_line
		(start 332.293722 -57.613296)
		(end 332.51394 -57.547764)
		(stroke
			(width 0.05715)
			(type default)
		)
		(layer "In9.Cu")
	)
	(gr_line
		(start 332.316836 -51.78171)
		(end 332.33106 -51.755548)
		(stroke
			(width 0.05715)
			(type default)
		)
		(layer "In9.Cu")
	)
	(gr_line
		(start 332.33106 -51.755548)
		(end 332.354936 -51.738276)
		(stroke
			(width 0.05715)
			(type default)
		)
		(layer "In9.Cu")
	)
	(gr_line
		(start 332.33614 -54.129178)
		(end 332.499462 -53.82768)
		(stroke
			(width 0.05715)
			(type default)
		)
		(layer "In9.Cu")
	)
	(gr_line
		(start 332.357476 -53.129942)
		(end 332.642972 -52.6034)
		(stroke
			(width 0.05715)
			(type default)
		)
		(layer "In9.Cu")
	)
	(gr_line
		(start 332.434184 -53.606954)
		(end 332.499462 -53.82768)
		(stroke
			(width 0.05715)
			(type default)
		)
		(layer "In9.Cu")
	)
	(gr_line
		(start 332.47203 -54.969918)
		(end 332.755748 -54.44617)
		(stroke
			(width 0.05715)
			(type default)
		)
		(layer "In9.Cu")
	)
	(gr_line
		(start 332.51394 -57.547764)
		(end 332.677516 -57.246266)
		(stroke
			(width 0.05715)
			(type default)
		)
		(layer "In9.Cu")
	)
	(gr_line
		(start 332.599792 -53.301392)
		(end 332.820264 -53.23586)
		(stroke
			(width 0.05715)
			(type default)
		)
		(layer "In9.Cu")
	)
	(gr_line
		(start 332.611984 -57.025794)
		(end 332.677516 -57.246266)
		(stroke
			(width 0.05715)
			(type default)
		)
		(layer "In9.Cu")
	)
	(gr_line
		(start 332.713584 -55.14213)
		(end 332.934056 -55.076598)
		(stroke
			(width 0.05715)
			(type default)
		)
		(layer "In9.Cu")
	)
	(gr_line
		(start 332.820264 -53.23586)
		(end 332.983586 -52.934362)
		(stroke
			(width 0.05715)
			(type default)
		)
		(layer "In9.Cu")
	)
	(gr_line
		(start 332.841854 -52.236624)
		(end 332.85557 -52.21097)
		(stroke
			(width 0.05715)
			(type default)
		)
		(layer "In9.Cu")
	)
	(gr_line
		(start 332.85557 -52.21097)
		(end 332.879446 -52.193698)
		(stroke
			(width 0.05715)
			(type default)
		)
		(layer "In9.Cu")
	)
	(gr_line
		(start 332.918308 -52.713636)
		(end 332.983586 -52.934362)
		(stroke
			(width 0.05715)
			(type default)
		)
		(layer "In9.Cu")
	)
	(gr_line
		(start 332.934056 -55.076598)
		(end 333.097632 -54.7751)
		(stroke
			(width 0.05715)
			(type default)
		)
		(layer "In9.Cu")
	)
	(gr_line
		(start 332.956408 -54.076092)
		(end 333.240126 -53.552344)
		(stroke
			(width 0.05715)
			(type default)
		)
		(layer "In9.Cu")
	)
	(gr_line
		(start 333.0321 -54.554628)
		(end 333.097632 -54.7751)
		(stroke
			(width 0.05715)
			(type default)
		)
		(layer "In9.Cu")
	)
	(gr_line
		(start 333.197708 -54.248812)
		(end 333.41818 -54.18328)
		(stroke
			(width 0.05715)
			(type default)
		)
		(layer "In9.Cu")
	)
	(gr_line
		(start 333.344266 -47.697898)
		(end 333.364078 -47.683674)
		(stroke
			(width 0.05715)
			(type default)
		)
		(layer "In9.Cu")
	)
	(gr_line
		(start 333.364078 -47.683674)
		(end 333.387446 -47.679102)
		(stroke
			(width 0.05715)
			(type default)
		)
		(layer "In9.Cu")
	)
	(gr_line
		(start 333.41818 -54.18328)
		(end 333.581502 -53.881782)
		(stroke
			(width 0.05715)
			(type default)
		)
		(layer "In9.Cu")
	)
	(gr_line
		(start 333.43977 -53.18379)
		(end 333.724504 -52.658518)
		(stroke
			(width 0.05715)
			(type default)
		)
		(layer "In9.Cu")
	)
	(gr_line
		(start 333.516224 -53.66131)
		(end 333.581502 -53.881782)
		(stroke
			(width 0.05715)
			(type default)
		)
		(layer "In9.Cu")
	)
	(gr_line
		(start 333.677514 -48.316642)
		(end 333.697326 -48.302418)
		(stroke
			(width 0.05715)
			(type default)
		)
		(layer "In9.Cu")
	)
	(gr_line
		(start 333.681832 -53.355494)
		(end 333.902304 -53.289962)
		(stroke
			(width 0.05715)
			(type default)
		)
		(layer "In9.Cu")
	)
	(gr_line
		(start 333.697326 -48.302418)
		(end 333.720694 -48.297846)
		(stroke
			(width 0.05715)
			(type default)
		)
		(layer "In9.Cu")
	)
	(gr_line
		(start 333.902304 -53.289962)
		(end 334.065626 -52.988464)
		(stroke
			(width 0.05715)
			(type default)
		)
		(layer "In9.Cu")
	)
	(gr_line
		(start 333.908146 -48.95723)
		(end 333.927958 -48.943006)
		(stroke
			(width 0.05715)
			(type default)
		)
		(layer "In9.Cu")
	)
	(gr_line
		(start 333.923894 -52.290726)
		(end 333.93761 -52.265072)
		(stroke
			(width 0.05715)
			(type default)
		)
		(layer "In9.Cu")
	)
	(gr_line
		(start 333.927958 -48.943006)
		(end 333.951326 -48.938434)
		(stroke
			(width 0.05715)
			(type default)
		)
		(layer "In9.Cu")
	)
	(gr_line
		(start 333.93761 -52.265072)
		(end 333.961486 -52.2478)
		(stroke
			(width 0.05715)
			(type default)
		)
		(layer "In9.Cu")
	)
	(gr_line
		(start 334.000348 -52.767738)
		(end 334.065626 -52.988464)
		(stroke
			(width 0.05715)
			(type default)
		)
		(layer "In9.Cu")
	)
	(gr_line
		(start 334.189578 -49.586896)
		(end 334.257142 -49.538128)
		(stroke
			(width 0.05715)
			(type default)
		)
		(layer "In9.Cu")
	)
	(gr_line
		(start 334.257142 -49.538128)
		(end 334.317086 -49.54778)
		(stroke
			(width 0.05715)
			(type default)
		)
		(layer "In9.Cu")
	)
	(gr_line
		(start 334.335628 -49.844706)
		(end 334.34528 -49.842674)
		(stroke
			(width 0.05715)
			(type default)
		)
		(layer "In9.Cu")
	)
	(gr_line
		(start 334.472026 -50.2158)
		(end 334.491838 -50.201576)
		(stroke
			(width 0.05715)
			(type default)
		)
		(layer "In9.Cu")
	)
	(gr_line
		(start 334.491838 -50.201576)
		(end 334.515206 -50.197004)
		(stroke
			(width 0.05715)
			(type default)
		)
		(layer "In9.Cu")
	)
	(gr_line
		(start 334.691228 -52.570888)
		(end 334.704944 -52.545234)
		(stroke
			(width 0.05715)
			(type default)
		)
		(layer "In9.Cu")
	)
	(gr_line
		(start 334.704944 -52.545234)
		(end 334.72882 -52.527962)
		(stroke
			(width 0.05715)
			(type default)
		)
		(layer "In9.Cu")
	)
	(gr_line
		(start 334.753712 -50.84572)
		(end 334.773524 -50.831496)
		(stroke
			(width 0.05715)
			(type default)
		)
		(layer "In9.Cu")
	)
	(gr_line
		(start 334.773524 -50.831496)
		(end 334.796892 -50.826924)
		(stroke
			(width 0.05715)
			(type default)
		)
		(layer "In9.Cu")
	)
	(gr_line
		(start 335.036414 -51.474624)
		(end 335.056226 -51.4604)
		(stroke
			(width 0.05715)
			(type default)
		)
		(layer "In9.Cu")
	)
	(gr_line
		(start 335.056226 -51.4604)
		(end 335.079594 -51.455828)
		(stroke
			(width 0.05715)
			(type default)
		)
		(layer "In9.Cu")
	)
	(gr_line
		(start 335.101438 -75.407012)
		(end 335.559908 -75.865482)
		(stroke
			(width 0.0635)
			(type default)
		)
		(layer "In9.Cu")
	)
	(gr_line
		(start 335.10474 -76.40193)
		(end 335.371948 -76.134722)
		(stroke
			(width 0.0635)
			(type default)
		)
		(layer "In9.Cu")
	)
	(gr_line
		(start 335.317592 -52.104544)
		(end 335.337404 -52.09032)
		(stroke
			(width 0.05715)
			(type default)
		)
		(layer "In9.Cu")
	)
	(gr_line
		(start 335.337404 -52.09032)
		(end 335.360772 -52.085748)
		(stroke
			(width 0.05715)
			(type default)
		)
		(layer "In9.Cu")
	)
	(gr_line
		(start 335.467452 -120.750076)
		(end 335.85404 -121.136664)
		(stroke
			(width 0.05715)
			(type default)
		)
		(layer "In9.Cu")
	)
	(gr_line
		(start 335.652364 -120.455436)
		(end 335.87944 -120.22836)
		(stroke
			(width 0.05715)
			(type default)
		)
		(layer "In9.Cu")
	)
	(gr_line
		(start 335.85404 -121.136664)
		(end 335.85404 -121.282968)
		(stroke
			(width 0.05715)
			(type default)
		)
		(layer "In9.Cu")
	)
	(gr_line
		(start 335.87944 -120.038368)
		(end 335.87944 -120.22836)
		(stroke
			(width 0.05715)
			(type default)
		)
		(layer "In9.Cu")
	)
	(gr_line
		(start 337.462368 -118.795546)
		(end 337.672426 -119.005604)
		(stroke
			(width 0.05715)
			(type default)
		)
		(layer "In9.Cu")
	)
	(gr_line
		(start 337.462368 -118.378986)
		(end 337.672426 -118.168928)
		(stroke
			(width 0.05715)
			(type default)
		)
		(layer "In9.Cu")
	)
	(gr_line
		(start 337.672426 -119.005604)
		(end 337.672426 -119.211598)
		(stroke
			(width 0.05715)
			(type default)
		)
		(layer "In9.Cu")
	)
	(gr_line
		(start 337.672426 -117.941598)
		(end 337.672426 -118.168928)
		(stroke
			(width 0.05715)
			(type default)
		)
		(layer "In9.Cu")
	)
	(gr_line
		(start 338.303108 -48.739552)
		(end 338.326476 -48.734726)
		(stroke
			(width 0.05715)
			(type default)
		)
		(layer "In9.Cu")
	)
	(gr_line
		(start 338.303108 -47.365666)
		(end 338.324444 -47.361348)
		(stroke
			(width 0.05715)
			(type default)
		)
		(layer "In9.Cu")
	)
	(gr_line
		(start 338.30387 -50.11293)
		(end 338.325206 -50.108612)
		(stroke
			(width 0.05715)
			(type default)
		)
		(layer "In9.Cu")
	)
	(gr_line
		(start 338.304124 -51.486562)
		(end 338.32546 -51.482244)
		(stroke
			(width 0.05715)
			(type default)
		)
		(layer "In9.Cu")
	)
	(gr_line
		(start 338.304124 -50.799492)
		(end 338.32546 -50.795174)
		(stroke
			(width 0.05715)
			(type default)
		)
		(layer "In9.Cu")
	)
	(gr_line
		(start 338.304124 -49.42586)
		(end 338.32546 -49.421542)
		(stroke
			(width 0.05715)
			(type default)
		)
		(layer "In9.Cu")
	)
	(gr_line
		(start 338.304124 -48.052228)
		(end 338.32546 -48.04791)
		(stroke
			(width 0.05715)
			(type default)
		)
		(layer "In9.Cu")
	)
	(gr_line
		(start 338.304124 -46.678342)
		(end 338.32546 -46.674024)
		(stroke
			(width 0.05715)
			(type default)
		)
		(layer "In9.Cu")
	)
	(gr_line
		(start 338.324444 -47.361348)
		(end 338.34578 -47.365666)
		(stroke
			(width 0.05715)
			(type default)
		)
		(layer "In9.Cu")
	)
	(gr_line
		(start 338.325206 -50.108612)
		(end 338.346542 -50.11293)
		(stroke
			(width 0.05715)
			(type default)
		)
		(layer "In9.Cu")
	)
	(gr_line
		(start 338.32546 -51.482244)
		(end 338.346796 -51.486562)
		(stroke
			(width 0.05715)
			(type default)
		)
		(layer "In9.Cu")
	)
	(gr_line
		(start 338.32546 -50.795174)
		(end 338.346796 -50.799492)
		(stroke
			(width 0.05715)
			(type default)
		)
		(layer "In9.Cu")
	)
	(gr_line
		(start 338.32546 -49.421542)
		(end 338.346796 -49.42586)
		(stroke
			(width 0.05715)
			(type default)
		)
		(layer "In9.Cu")
	)
	(gr_line
		(start 338.32546 -48.04791)
		(end 338.346796 -48.052228)
		(stroke
			(width 0.05715)
			(type default)
		)
		(layer "In9.Cu")
	)
	(gr_line
		(start 338.32546 -46.674024)
		(end 338.346796 -46.678342)
		(stroke
			(width 0.05715)
			(type default)
		)
		(layer "In9.Cu")
	)
	(gr_line
		(start 338.326476 -48.734726)
		(end 338.349336 -48.739298)
		(stroke
			(width 0.05715)
			(type default)
		)
		(layer "In9.Cu")
	)
	(gr_line
		(start 339.1154 -109.46384)
		(end 339.1154 -109.855)
		(stroke
			(width 0.0635)
			(type default)
		)
		(layer "In9.Cu")
	)
	(gr_line
		(start 339.1154 -109.46384)
		(end 339.19414 -109.3851)
		(stroke
			(width 0.0635)
			(type default)
		)
		(layer "In9.Cu")
	)
	(gr_line
		(start 339.1154 -108.943648)
		(end 339.19414 -109.022388)
		(stroke
			(width 0.0635)
			(type default)
		)
		(layer "In9.Cu")
	)
	(gr_line
		(start 339.1154 -108.585)
		(end 339.1154 -108.943648)
		(stroke
			(width 0.0635)
			(type default)
		)
		(layer "In9.Cu")
	)
	(gr_line
		(start 340.546182 -51.545236)
		(end 340.575646 -51.551332)
		(stroke
			(width 0.05715)
			(type default)
		)
		(layer "In9.Cu")
	)
	(gr_line
		(start 340.575646 -51.551332)
		(end 340.604602 -51.543458)
		(stroke
			(width 0.05715)
			(type default)
		)
		(layer "In9.Cu")
	)
	(gr_line
		(start 340.586822 -50.866548)
		(end 340.616286 -50.872644)
		(stroke
			(width 0.05715)
			(type default)
		)
		(layer "In9.Cu")
	)
	(gr_line
		(start 340.616286 -50.872644)
		(end 340.645242 -50.86477)
		(stroke
			(width 0.05715)
			(type default)
		)
		(layer "In9.Cu")
	)
	(gr_line
		(start 340.639146 -50.1904)
		(end 340.66861 -50.196496)
		(stroke
			(width 0.05715)
			(type default)
		)
		(layer "In9.Cu")
	)
	(gr_line
		(start 340.66734 -52.257198)
		(end 340.698582 -52.263548)
		(stroke
			(width 0.05715)
			(type default)
		)
		(layer "In9.Cu")
	)
	(gr_line
		(start 340.66861 -50.196496)
		(end 340.697566 -50.188622)
		(stroke
			(width 0.05715)
			(type default)
		)
		(layer "In9.Cu")
	)
	(gr_line
		(start 340.674706 -49.51095)
		(end 340.70417 -49.517046)
		(stroke
			(width 0.05715)
			(type default)
		)
		(layer "In9.Cu")
	)
	(gr_line
		(start 340.698582 -52.263548)
		(end 340.72957 -52.255166)
		(stroke
			(width 0.05715)
			(type default)
		)
		(layer "In9.Cu")
	)
	(gr_line
		(start 340.70417 -49.517046)
		(end 340.733126 -49.509172)
		(stroke
			(width 0.05715)
			(type default)
		)
		(layer "In9.Cu")
	)
	(gr_line
		(start 340.733888 -48.836072)
		(end 340.763352 -48.842168)
		(stroke
			(width 0.05715)
			(type default)
		)
		(layer "In9.Cu")
	)
	(gr_line
		(start 340.763352 -48.842168)
		(end 340.792308 -48.834294)
		(stroke
			(width 0.05715)
			(type default)
		)
		(layer "In9.Cu")
	)
	(gr_line
		(start 340.77656 -48.157892)
		(end 340.806024 -48.163988)
		(stroke
			(width 0.05715)
			(type default)
		)
		(layer "In9.Cu")
	)
	(gr_line
		(start 340.806024 -48.163988)
		(end 340.83498 -48.156114)
		(stroke
			(width 0.05715)
			(type default)
		)
		(layer "In9.Cu")
	)
	(gr_line
		(start 340.81085 -47.47768)
		(end 340.840314 -47.483776)
		(stroke
			(width 0.05715)
			(type default)
		)
		(layer "In9.Cu")
	)
	(gr_line
		(start 340.840314 -47.483776)
		(end 340.86927 -47.475902)
		(stroke
			(width 0.05715)
			(type default)
		)
		(layer "In9.Cu")
	)
	(gr_line
		(start 344.033602 -121.495312)
		(end 344.057986 -121.456704)
		(stroke
			(width 0.05715)
			(type default)
		)
		(layer "In9.Cu")
	)
	(gr_line
		(start 344.420444 -120.87987)
		(end 344.439748 -120.848882)
		(stroke
			(width 0.05715)
			(type default)
		)
		(layer "In9.Cu")
	)
	(gr_line
		(start 344.439748 -120.848882)
		(end 344.471752 -120.830594)
		(stroke
			(width 0.05715)
			(type default)
		)
		(layer "In9.Cu")
	)
	(gr_line
		(start 344.694764 -121.753884)
		(end 344.718894 -121.715276)
		(stroke
			(width 0.05715)
			(type default)
		)
		(layer "In9.Cu")
	)
	(gr_line
		(start 344.9447 -121.355612)
		(end 344.963496 -121.32564)
		(stroke
			(width 0.05715)
			(type default)
		)
		(layer "In9.Cu")
	)
	(gr_line
		(start 344.963496 -121.32564)
		(end 344.99423 -121.308114)
		(stroke
			(width 0.05715)
			(type default)
		)
		(layer "In9.Cu")
	)
	(gr_line
		(start 344.990674 -125.452632)
		(end 345.049602 -125.51156)
		(stroke
			(width 0.05715)
			(type default)
		)
		(layer "In9.Cu")
	)
	(gr_line
		(start 344.992198 -125.037596)
		(end 345.222322 -125.037596)
		(stroke
			(width 0.05715)
			(type default)
		)
		(layer "In9.Cu")
	)
	(gr_line
		(start 345.222322 -125.037596)
		(end 345.464638 -125.279912)
		(stroke
			(width 0.05715)
			(type default)
		)
		(layer "In9.Cu")
	)
	(gr_line
		(start 345.464638 -125.279912)
		(end 345.464638 -125.510036)
		(stroke
			(width 0.05715)
			(type default)
		)
		(layer "In9.Cu")
	)
	(gr_line
		(start 345.731084 -120.11279)
		(end 345.737434 -120.109234)
		(stroke
			(width 0.05715)
			(type default)
		)
		(layer "In9.Cu")
	)
	(gr_line
		(start 345.737434 -120.109234)
		(end 345.744546 -120.10771)
		(stroke
			(width 0.05715)
			(type default)
		)
		(layer "In9.Cu")
	)
	(gr_line
		(start 346.053664 -120.703848)
		(end 346.060014 -120.700292)
		(stroke
			(width 0.05715)
			(type default)
		)
		(layer "In9.Cu")
	)
	(gr_line
		(start 346.060014 -120.700292)
		(end 346.067126 -120.698768)
		(stroke
			(width 0.05715)
			(type default)
		)
		(layer "In9.Cu")
	)
	(gr_line
		(start 347.042486 -123.50877)
		(end 347.042486 -123.600972)
		(stroke
			(width 0.05715)
			(type default)
		)
		(layer "In9.Cu")
	)
	(gr_line
		(start 347.042486 -123.50877)
		(end 347.401134 -123.150122)
		(stroke
			(width 0.05715)
			(type default)
		)
		(layer "In9.Cu")
	)
	(gr_line
		(start 347.050614 -122.383042)
		(end 347.401134 -122.733562)
		(stroke
			(width 0.05715)
			(type default)
		)
		(layer "In9.Cu")
	)
	(gr_line
		(start 347.584014 -126.021592)
		(end 347.584014 -126.370842)
		(stroke
			(width 0.05715)
			(type default)
		)
		(layer "In9.Cu")
	)
	(gr_line
		(start 347.584014 -126.021592)
		(end 347.636084 -125.969522)
		(stroke
			(width 0.05715)
			(type default)
		)
		(layer "In9.Cu")
	)
	(gr_line
		(start 347.584014 -125.500892)
		(end 347.636084 -125.552962)
		(stroke
			(width 0.05715)
			(type default)
		)
		(layer "In9.Cu")
	)
	(gr_line
		(start 347.584014 -125.151642)
		(end 347.584014 -125.500892)
		(stroke
			(width 0.05715)
			(type default)
		)
		(layer "In9.Cu")
	)
	(gr_line
		(start 348.553532 -122.341132)
		(end 348.553532 -122.571256)
		(stroke
			(width 0.05715)
			(type default)
		)
		(layer "In9.Cu")
	)
	(gr_line
		(start 348.553532 -122.341132)
		(end 348.795848 -122.098816)
		(stroke
			(width 0.05715)
			(type default)
		)
		(layer "In9.Cu")
	)
	(gr_line
		(start 348.74327 -126.840234)
		(end 348.90583 -126.677674)
		(stroke
			(width 0.05715)
			(type default)
		)
		(layer "In9.Cu")
	)
	(gr_line
		(start 348.795848 -122.098816)
		(end 349.025972 -122.098816)
		(stroke
			(width 0.05715)
			(type default)
		)
		(layer "In9.Cu")
	)
	(gr_line
		(start 348.90583 -126.677674)
		(end 349.24873 -126.677674)
		(stroke
			(width 0.05715)
			(type default)
		)
		(layer "In9.Cu")
	)
	(gr_line
		(start 348.968568 -122.57278)
		(end 349.027496 -122.513852)
		(stroke
			(width 0.05715)
			(type default)
		)
		(layer "In9.Cu")
	)
	(gr_line
		(start 349.03537 -127.134874)
		(end 349.11919 -127.134874)
		(stroke
			(width 0.05715)
			(type default)
		)
		(layer "In9.Cu")
	)
	(gr_line
		(start 349.24873 -126.677674)
		(end 349.41129 -126.840234)
		(stroke
			(width 0.05715)
			(type default)
		)
		(layer "In9.Cu")
	)
	(gr_line
		(start 349.271844 -121.62282)
		(end 349.271844 -121.852944)
		(stroke
			(width 0.05715)
			(type default)
		)
		(layer "In9.Cu")
	)
	(gr_line
		(start 349.271844 -121.62282)
		(end 349.51416 -121.380504)
		(stroke
			(width 0.05715)
			(type default)
		)
		(layer "In9.Cu")
	)
	(gr_line
		(start 349.51416 -121.380504)
		(end 349.744284 -121.380504)
		(stroke
			(width 0.05715)
			(type default)
		)
		(layer "In9.Cu")
	)
	(gr_line
		(start 349.68688 -121.854468)
		(end 349.745808 -121.79554)
		(stroke
			(width 0.05715)
			(type default)
		)
		(layer "In9.Cu")
	)
	(gr_line
		(start 349.75927 -126.840234)
		(end 349.92183 -126.677674)
		(stroke
			(width 0.05715)
			(type default)
		)
		(layer "In9.Cu")
	)
	(gr_line
		(start 349.821754 -122.204988)
		(end 349.880682 -122.14606)
		(stroke
			(width 0.05715)
			(type default)
		)
		(layer "In9.Cu")
	)
	(gr_line
		(start 349.92183 -126.677674)
		(end 350.26473 -126.677674)
		(stroke
			(width 0.05715)
			(type default)
		)
		(layer "In9.Cu")
	)
	(gr_line
		(start 349.990156 -120.904508)
		(end 349.990156 -121.134632)
		(stroke
			(width 0.05715)
			(type default)
		)
		(layer "In9.Cu")
	)
	(gr_line
		(start 349.990156 -120.904508)
		(end 350.232472 -120.662192)
		(stroke
			(width 0.05715)
			(type default)
		)
		(layer "In9.Cu")
	)
	(gr_line
		(start 350.05137 -127.134874)
		(end 350.13519 -127.134874)
		(stroke
			(width 0.05715)
			(type default)
		)
		(layer "In9.Cu")
	)
	(gr_line
		(start 350.232472 -120.662192)
		(end 350.37776 -120.662192)
		(stroke
			(width 0.05715)
			(type default)
		)
		(layer "In9.Cu")
	)
	(gr_line
		(start 350.26473 -126.677674)
		(end 350.42729 -126.840234)
		(stroke
			(width 0.05715)
			(type default)
		)
		(layer "In9.Cu")
	)
	(gr_line
		(start 350.38284 -120.662192)
		(end 350.465898 -120.662192)
		(stroke
			(width 0.05715)
			(type default)
		)
		(layer "In9.Cu")
	)
	(gr_line
		(start 350.405192 -121.136156)
		(end 350.46412 -121.077228)
		(stroke
			(width 0.05715)
			(type default)
		)
		(layer "In9.Cu")
	)
	(gr_line
		(start 350.6724 -120.868948)
		(end 350.672654 -120.868948)
		(stroke
			(width 0.05715)
			(type default)
		)
		(layer "In9.Cu")
	)
	(gr_line
		(start 350.710246 -120.417844)
		(end 350.759268 -120.40743)
		(stroke
			(width 0.05715)
			(type default)
		)
		(layer "In9.Cu")
	)
	(gr_line
		(start 350.860868 -121.165874)
		(end 350.896428 -121.130314)
		(stroke
			(width 0.05715)
			(type default)
		)
		(layer "In9.Cu")
	)
	(gr_line
		(start 350.896428 -121.130314)
		(end 350.94545 -121.1199)
		(stroke
			(width 0.05715)
			(type default)
		)
		(layer "In9.Cu")
	)
	(gr_line
		(start 351.716594 -123.391422)
		(end 352.105214 -123.780042)
		(stroke
			(width 0.05715)
			(type default)
		)
		(layer "In9.Cu")
	)
	(gr_line
		(start 351.716594 -122.974862)
		(end 352.105214 -122.586242)
		(stroke
			(width 0.05715)
			(type default)
		)
		(layer "In9.Cu")
	)
	(gr_line
		(start 352.734626 -126.336298)
		(end 352.734626 -126.68123)
		(stroke
			(width 0.05715)
			(type default)
		)
		(layer "In9.Cu")
	)
	(gr_line
		(start 352.734626 -126.336298)
		(end 352.847402 -126.22403)
		(stroke
			(width 0.05715)
			(type default)
		)
		(layer "In9.Cu")
	)
	(gr_line
		(start 352.740214 -125.802898)
		(end 352.864928 -125.927612)
		(stroke
			(width 0.05715)
			(type default)
		)
		(layer "In9.Cu")
	)
	(gr_line
		(start 352.740214 -125.380242)
		(end 352.740214 -125.802898)
		(stroke
			(width 0.05715)
			(type default)
		)
		(layer "In9.Cu")
	)
	(gr_line
		(start 353.217988 -125.93066)
		(end 353.274122 -125.93066)
		(stroke
			(width 0.05715)
			(type default)
		)
		(layer "In9.Cu")
	)
	(gr_line
		(start 353.274122 -125.93066)
		(end 353.319842 -125.96368)
		(stroke
			(width 0.05715)
			(type default)
		)
		(layer "In9.Cu")
	)
	(gr_line
		(start 353.59975 -126.166118)
		(end 353.68992 -126.231396)
		(stroke
			(width 0.05715)
			(type default)
		)
		(layer "In9.Cu")
	)
	(gr_line
		(start 355.606096 -43.52671)
		(end 355.615494 -43.52417)
		(stroke
			(width 0.05715)
			(type default)
		)
		(layer "In9.Cu")
	)
	(gr_line
		(start 355.615494 -43.52417)
		(end 355.623368 -43.518836)
		(stroke
			(width 0.05715)
			(type default)
		)
		(layer "In9.Cu")
	)
	(gr_line
		(start 355.875336 -44.124372)
		(end 355.884734 -44.121832)
		(stroke
			(width 0.05715)
			(type default)
		)
		(layer "In9.Cu")
	)
	(gr_line
		(start 355.884734 -44.121832)
		(end 355.892608 -44.116498)
		(stroke
			(width 0.05715)
			(type default)
		)
		(layer "In9.Cu")
	)
	(gr_line
		(start 356.149656 -44.718478)
		(end 356.159054 -44.715938)
		(stroke
			(width 0.05715)
			(type default)
		)
		(layer "In9.Cu")
	)
	(gr_line
		(start 356.159054 -44.715938)
		(end 356.166928 -44.710604)
		(stroke
			(width 0.05715)
			(type default)
		)
		(layer "In9.Cu")
	)
	(gr_line
		(start 356.227634 -68.519294)
		(end 356.235 -68.556632)
		(stroke
			(width 0.05715)
			(type default)
		)
		(layer "In9.Cu")
	)
	(gr_line
		(start 356.227634 -68.519294)
		(end 356.239064 -68.483734)
		(stroke
			(width 0.05715)
			(type default)
		)
		(layer "In9.Cu")
	)
	(gr_line
		(start 356.234746 -68.556632)
		(end 356.235 -68.557648)
		(stroke
			(width 0.05715)
			(type default)
		)
		(layer "In9.Cu")
	)
	(gr_line
		(start 356.44963 -45.296836)
		(end 356.459028 -45.294296)
		(stroke
			(width 0.05715)
			(type default)
		)
		(layer "In9.Cu")
	)
	(gr_line
		(start 356.459028 -45.294296)
		(end 356.466902 -45.288962)
		(stroke
			(width 0.05715)
			(type default)
		)
		(layer "In9.Cu")
	)
	(gr_line
		(start 356.6033 -67.352418)
		(end 356.605332 -67.346322)
		(stroke
			(width 0.05715)
			(type default)
		)
		(layer "In9.Cu")
	)
	(gr_line
		(start 356.605332 -67.346322)
		(end 356.609142 -67.341242)
		(stroke
			(width 0.05715)
			(type default)
		)
		(layer "In9.Cu")
	)
	(gr_line
		(start 356.637336 -42.854626)
		(end 356.669848 -42.83329)
		(stroke
			(width 0.05715)
			(type default)
		)
		(layer "In9.Cu")
	)
	(gr_line
		(start 356.669848 -42.83329)
		(end 356.687882 -42.799254)
		(stroke
			(width 0.05715)
			(type default)
		)
		(layer "In9.Cu")
	)
	(gr_line
		(start 356.715568 -45.896022)
		(end 356.724966 -45.893482)
		(stroke
			(width 0.05715)
			(type default)
		)
		(layer "In9.Cu")
	)
	(gr_line
		(start 356.724966 -45.893482)
		(end 356.73284 -45.888148)
		(stroke
			(width 0.05715)
			(type default)
		)
		(layer "In9.Cu")
	)
	(gr_line
		(start 356.828852 -98.85299)
		(end 356.833932 -98.876358)
		(stroke
			(width 0.05715)
			(type default)
		)
		(layer "In9.Cu")
	)
	(gr_line
		(start 356.828852 -98.85299)
		(end 356.833932 -98.829876)
		(stroke
			(width 0.05715)
			(type default)
		)
		(layer "In9.Cu")
	)
	(gr_line
		(start 356.9208 -68.56984)
		(end 356.92842 -68.607686)
		(stroke
			(width 0.05715)
			(type default)
		)
		(layer "In9.Cu")
	)
	(gr_line
		(start 356.9208 -68.56984)
		(end 356.932738 -68.532756)
		(stroke
			(width 0.05715)
			(type default)
		)
		(layer "In9.Cu")
	)
	(gr_line
		(start 357.008176 -46.478698)
		(end 357.017574 -46.476158)
		(stroke
			(width 0.05715)
			(type default)
		)
		(layer "In9.Cu")
	)
	(gr_line
		(start 357.017574 -46.476158)
		(end 357.025448 -46.470824)
		(stroke
			(width 0.05715)
			(type default)
		)
		(layer "In9.Cu")
	)
	(gr_line
		(start 357.14813 -43.2943)
		(end 357.180642 -43.272964)
		(stroke
			(width 0.05715)
			(type default)
		)
		(layer "In9.Cu")
	)
	(gr_line
		(start 357.180642 -43.272964)
		(end 357.198676 -43.238928)
		(stroke
			(width 0.05715)
			(type default)
		)
		(layer "In9.Cu")
	)
	(gr_line
		(start 357.189532 -67.73418)
		(end 357.191564 -67.728084)
		(stroke
			(width 0.05715)
			(type default)
		)
		(layer "In9.Cu")
	)
	(gr_line
		(start 357.191564 -67.728084)
		(end 357.195374 -67.723004)
		(stroke
			(width 0.05715)
			(type default)
		)
		(layer "In9.Cu")
	)
	(gr_line
		(start 357.261668 -41.717722)
		(end 357.264208 -41.712896)
		(stroke
			(width 0.05715)
			(type default)
		)
		(layer "In9.Cu")
	)
	(gr_line
		(start 357.264208 -41.712896)
		(end 357.265224 -41.707816)
		(stroke
			(width 0.05715)
			(type default)
		)
		(layer "In9.Cu")
	)
	(gr_line
		(start 357.286306 -47.071534)
		(end 357.294434 -47.069248)
		(stroke
			(width 0.05715)
			(type default)
		)
		(layer "In9.Cu")
	)
	(gr_line
		(start 357.294434 -47.069248)
		(end 357.301038 -47.06493)
		(stroke
			(width 0.05715)
			(type default)
		)
		(layer "In9.Cu")
	)
	(gr_line
		(start 357.40467 -93.41993)
		(end 357.40975 -93.443298)
		(stroke
			(width 0.05715)
			(type default)
		)
		(layer "In9.Cu")
	)
	(gr_line
		(start 357.40467 -93.41993)
		(end 357.40975 -93.396816)
		(stroke
			(width 0.05715)
			(type default)
		)
		(layer "In9.Cu")
	)
	(gr_line
		(start 357.410512 -80.07223)
		(end 357.469186 -80.013556)
		(stroke
			(width 0.05715)
			(type default)
		)
		(layer "In9.Cu")
	)
	(gr_line
		(start 357.570532 -47.660052)
		(end 357.578406 -47.657766)
		(stroke
			(width 0.05715)
			(type default)
		)
		(layer "In9.Cu")
	)
	(gr_line
		(start 357.578406 -47.657766)
		(end 357.584756 -47.653448)
		(stroke
			(width 0.05715)
			(type default)
		)
		(layer "In9.Cu")
	)
	(gr_line
		(start 357.593138 -68.589144)
		(end 357.600504 -68.627244)
		(stroke
			(width 0.05715)
			(type default)
		)
		(layer "In9.Cu")
	)
	(gr_line
		(start 357.593138 -68.589144)
		(end 357.604822 -68.552822)
		(stroke
			(width 0.05715)
			(type default)
		)
		(layer "In9.Cu")
	)
	(gr_line
		(start 357.603044 -92.485718)
		(end 357.726996 -91.90228)
		(stroke
			(width 0.05715)
			(type default)
		)
		(layer "In9.Cu")
	)
	(gr_line
		(start 357.681276 -43.719242)
		(end 357.713534 -43.69816)
		(stroke
			(width 0.05715)
			(type default)
		)
		(layer "In9.Cu")
	)
	(gr_line
		(start 357.713534 -43.69816)
		(end 357.731568 -43.664124)
		(stroke
			(width 0.05715)
			(type default)
		)
		(layer "In9.Cu")
	)
	(gr_line
		(start 357.759 -68.075302)
		(end 357.761286 -68.06819)
		(stroke
			(width 0.05715)
			(type default)
		)
		(layer "In9.Cu")
	)
	(gr_line
		(start 357.761286 -68.06819)
		(end 357.765604 -68.062094)
		(stroke
			(width 0.05715)
			(type default)
		)
		(layer "In9.Cu")
	)
	(gr_line
		(start 357.814118 -91.49207)
		(end 357.938324 -90.907362)
		(stroke
			(width 0.05715)
			(type default)
		)
		(layer "In9.Cu")
	)
	(gr_line
		(start 357.850948 -42.00906)
		(end 357.853488 -42.004234)
		(stroke
			(width 0.05715)
			(type default)
		)
		(layer "In9.Cu")
	)
	(gr_line
		(start 357.853488 -42.004234)
		(end 357.854504 -41.999154)
		(stroke
			(width 0.05715)
			(type default)
		)
		(layer "In9.Cu")
	)
	(gr_line
		(start 357.883968 -92.581476)
		(end 358.076754 -92.456254)
		(stroke
			(width 0.05715)
			(type default)
		)
		(layer "In9.Cu")
	)
	(gr_line
		(start 357.93045 -65.977516)
		(end 357.943404 -65.959482)
		(stroke
			(width 0.05715)
			(type default)
		)
		(layer "In9.Cu")
	)
	(gr_line
		(start 357.943404 -65.959482)
		(end 357.94823 -65.93713)
		(stroke
			(width 0.05715)
			(type default)
		)
		(layer "In9.Cu")
	)
	(gr_line
		(start 357.9749 -107.6706)
		(end 357.990902 -107.700572)
		(stroke
			(width 0.05715)
			(type default)
		)
		(layer "In9.Cu")
	)
	(gr_line
		(start 357.9749 -106.512868)
		(end 357.9749 -106.596688)
		(stroke
			(width 0.05715)
			(type default)
		)
		(layer "In9.Cu")
	)
	(gr_line
		(start 357.987346 -94.805246)
		(end 357.992426 -94.78137)
		(stroke
			(width 0.05715)
			(type default)
		)
		(layer "In9.Cu")
	)
	(gr_line
		(start 357.987346 -94.756986)
		(end 357.9876 -94.758002)
		(stroke
			(width 0.05715)
			(type default)
		)
		(layer "In9.Cu")
	)
	(gr_line
		(start 357.9876 -94.758256)
		(end 357.992426 -94.78137)
		(stroke
			(width 0.05715)
			(type default)
		)
		(layer "In9.Cu")
	)
	(gr_line
		(start 358.022652 -91.92768)
		(end 358.148128 -92.12072)
		(stroke
			(width 0.05715)
			(type default)
		)
		(layer "In9.Cu")
	)
	(gr_line
		(start 358.024938 -90.499184)
		(end 358.149652 -89.911936)
		(stroke
			(width 0.05715)
			(type default)
		)
		(layer "In9.Cu")
	)
	(gr_line
		(start 358.058466 -54.19344)
		(end 358.067356 -54.234842)
		(stroke
			(width 0.05715)
			(type default)
		)
		(layer "In9.Cu")
	)
	(gr_line
		(start 358.058466 -54.19344)
		(end 358.072182 -54.153562)
		(stroke
			(width 0.05715)
			(type default)
		)
		(layer "In9.Cu")
	)
	(gr_line
		(start 358.076754 -92.456254)
		(end 358.148128 -92.12072)
		(stroke
			(width 0.05715)
			(type default)
		)
		(layer "In9.Cu")
	)
	(gr_line
		(start 358.095042 -91.587828)
		(end 358.288082 -91.462352)
		(stroke
			(width 0.05715)
			(type default)
		)
		(layer "In9.Cu")
	)
	(gr_line
		(start 358.185212 -108.06557)
		(end 358.20223 -108.09732)
		(stroke
			(width 0.05715)
			(type default)
		)
		(layer "In9.Cu")
	)
	(gr_line
		(start 358.189784 -44.159932)
		(end 358.220264 -44.14012)
		(stroke
			(width 0.05715)
			(type default)
		)
		(layer "In9.Cu")
	)
	(gr_line
		(start 358.20223 -108.09732)
		(end 358.231948 -108.117132)
		(stroke
			(width 0.05715)
			(type default)
		)
		(layer "In9.Cu")
	)
	(gr_line
		(start 358.220264 -44.14012)
		(end 358.23779 -44.1071)
		(stroke
			(width 0.05715)
			(type default)
		)
		(layer "In9.Cu")
	)
	(gr_line
		(start 358.233726 -90.934032)
		(end 358.359202 -91.126818)
		(stroke
			(width 0.05715)
			(type default)
		)
		(layer "In9.Cu")
	)
	(gr_line
		(start 358.236266 -89.504266)
		(end 358.360472 -88.919558)
		(stroke
			(width 0.05715)
			(type default)
		)
		(layer "In9.Cu")
	)
	(gr_line
		(start 358.26954 -106.888788)
		(end 358.4321 -106.726228)
		(stroke
			(width 0.05715)
			(type default)
		)
		(layer "In9.Cu")
	)
	(gr_line
		(start 358.26954 -106.220768)
		(end 358.4321 -106.383328)
		(stroke
			(width 0.05715)
			(type default)
		)
		(layer "In9.Cu")
	)
	(gr_line
		(start 358.277414 -55.223664)
		(end 358.401366 -55.807102)
		(stroke
			(width 0.05715)
			(type default)
		)
		(layer "In9.Cu")
	)
	(gr_line
		(start 358.288082 -91.462352)
		(end 358.359202 -91.126818)
		(stroke
			(width 0.05715)
			(type default)
		)
		(layer "In9.Cu")
	)
	(gr_line
		(start 358.29875 -50.793142)
		(end 358.303068 -50.814732)
		(stroke
			(width 0.05715)
			(type default)
		)
		(layer "In9.Cu")
	)
	(gr_line
		(start 358.29875 -50.793142)
		(end 358.303068 -50.771044)
		(stroke
			(width 0.05715)
			(type default)
		)
		(layer "In9.Cu")
	)
	(gr_line
		(start 358.306116 -90.593926)
		(end 358.499156 -90.46845)
		(stroke
			(width 0.05715)
			(type default)
		)
		(layer "In9.Cu")
	)
	(gr_line
		(start 358.413812 -50.216308)
		(end 358.416098 -50.205132)
		(stroke
			(width 0.05715)
			(type default)
		)
		(layer "In9.Cu")
	)
	(gr_line
		(start 358.416098 -50.205132)
		(end 358.421686 -50.195734)
		(stroke
			(width 0.05715)
			(type default)
		)
		(layer "In9.Cu")
	)
	(gr_line
		(start 358.4321 -106.383328)
		(end 358.4321 -106.726228)
		(stroke
			(width 0.05715)
			(type default)
		)
		(layer "In9.Cu")
	)
	(gr_line
		(start 358.441752 -42.325036)
		(end 358.444292 -42.32021)
		(stroke
			(width 0.05715)
			(type default)
		)
		(layer "In9.Cu")
	)
	(gr_line
		(start 358.444292 -42.32021)
		(end 358.445308 -42.31513)
		(stroke
			(width 0.05715)
			(type default)
		)
		(layer "In9.Cu")
	)
	(gr_line
		(start 358.4448 -89.939876)
		(end 358.570276 -90.13317)
		(stroke
			(width 0.05715)
			(type default)
		)
		(layer "In9.Cu")
	)
	(gr_line
		(start 358.462326 -117.70233)
		(end 358.491028 -117.696234)
		(stroke
			(width 0.05715)
			(type default)
		)
		(layer "In9.Cu")
	)
	(gr_line
		(start 358.475534 -34.377376)
		(end 358.482138 -34.345372)
		(stroke
			(width 0.05715)
			(type default)
		)
		(layer "In9.Cu")
	)
	(gr_line
		(start 358.482138 -34.345372)
		(end 358.502966 -34.319718)
		(stroke
			(width 0.05715)
			(type default)
		)
		(layer "In9.Cu")
	)
	(gr_line
		(start 358.488996 -56.21909)
		(end 358.612694 -56.801512)
		(stroke
			(width 0.05715)
			(type default)
		)
		(layer "In9.Cu")
	)
	(gr_line
		(start 358.491028 -117.696234)
		(end 358.514396 -117.678454)
		(stroke
			(width 0.05715)
			(type default)
		)
		(layer "In9.Cu")
	)
	(gr_line
		(start 358.499156 -90.46845)
		(end 358.570276 -90.13317)
		(stroke
			(width 0.05715)
			(type default)
		)
		(layer "In9.Cu")
	)
	(gr_line
		(start 358.51719 -89.600024)
		(end 358.71023 -89.474802)
		(stroke
			(width 0.05715)
			(type default)
		)
		(layer "In9.Cu")
	)
	(gr_line
		(start 358.530398 -66.340228)
		(end 358.543352 -66.32194)
		(stroke
			(width 0.05715)
			(type default)
		)
		(layer "In9.Cu")
	)
	(gr_line
		(start 358.53243 -79.364078)
		(end 358.591104 -79.305404)
		(stroke
			(width 0.05715)
			(type default)
		)
		(layer "In9.Cu")
	)
	(gr_line
		(start 358.543352 -66.32194)
		(end 358.547924 -66.300604)
		(stroke
			(width 0.05715)
			(type default)
		)
		(layer "In9.Cu")
	)
	(gr_line
		(start 358.558338 -55.12816)
		(end 358.751124 -55.253636)
		(stroke
			(width 0.05715)
			(type default)
		)
		(layer "In9.Cu")
	)
	(gr_line
		(start 358.58069 -73.795382)
		(end 358.591104 -73.817226)
		(stroke
			(width 0.05715)
			(type default)
		)
		(layer "In9.Cu")
	)
	(gr_line
		(start 358.655874 -88.945974)
		(end 358.78135 -89.139268)
		(stroke
			(width 0.05715)
			(type default)
		)
		(layer "In9.Cu")
	)
	(gr_line
		(start 358.697276 -55.781702)
		(end 358.822498 -55.58917)
		(stroke
			(width 0.05715)
			(type default)
		)
		(layer "In9.Cu")
	)
	(gr_line
		(start 358.699562 -57.21096)
		(end 358.824022 -57.79643)
		(stroke
			(width 0.05715)
			(type default)
		)
		(layer "In9.Cu")
	)
	(gr_line
		(start 358.71023 -89.474802)
		(end 358.78135 -89.139268)
		(stroke
			(width 0.05715)
			(type default)
		)
		(layer "In9.Cu")
	)
	(gr_line
		(start 358.719628 -44.587668)
		(end 358.751886 -44.566586)
		(stroke
			(width 0.05715)
			(type default)
		)
		(layer "In9.Cu")
	)
	(gr_line
		(start 358.751124 -55.253636)
		(end 358.822498 -55.58917)
		(stroke
			(width 0.05715)
			(type default)
		)
		(layer "In9.Cu")
	)
	(gr_line
		(start 358.751886 -44.566586)
		(end 358.76992 -44.53255)
		(stroke
			(width 0.05715)
			(type default)
		)
		(layer "In9.Cu")
	)
	(gr_line
		(start 358.769412 -56.122062)
		(end 358.962452 -56.247538)
		(stroke
			(width 0.05715)
			(type default)
		)
		(layer "In9.Cu")
	)
	(gr_line
		(start 358.801416 -118.29034)
		(end 358.830118 -118.284244)
		(stroke
			(width 0.05715)
			(type default)
		)
		(layer "In9.Cu")
	)
	(gr_line
		(start 358.830118 -118.284244)
		(end 358.853486 -118.266464)
		(stroke
			(width 0.05715)
			(type default)
		)
		(layer "In9.Cu")
	)
	(gr_line
		(start 358.881934 -53.915056)
		(end 358.89057 -53.955696)
		(stroke
			(width 0.05715)
			(type default)
		)
		(layer "In9.Cu")
	)
	(gr_line
		(start 358.881934 -53.915056)
		(end 358.89565 -53.874924)
		(stroke
			(width 0.05715)
			(type default)
		)
		(layer "In9.Cu")
	)
	(gr_line
		(start 358.90835 -56.776112)
		(end 359.033826 -56.583072)
		(stroke
			(width 0.05715)
			(type default)
		)
		(layer "In9.Cu")
	)
	(gr_line
		(start 358.91089 -58.205116)
		(end 359.034842 -58.788808)
		(stroke
			(width 0.05715)
			(type default)
		)
		(layer "In9.Cu")
	)
	(gr_line
		(start 358.9274 -52.550822)
		(end 358.939592 -52.515008)
		(stroke
			(width 0.05715)
			(type default)
		)
		(layer "In9.Cu")
	)
	(gr_line
		(start 358.93248 -52.472082)
		(end 358.940608 -52.512214)
		(stroke
			(width 0.05715)
			(type default)
		)
		(layer "In9.Cu")
	)
	(gr_line
		(start 358.939592 -52.515008)
		(end 358.940608 -52.512214)
		(stroke
			(width 0.05715)
			(type default)
		)
		(layer "In9.Cu")
	)
	(gr_line
		(start 358.962452 -56.247538)
		(end 359.033826 -56.583072)
		(stroke
			(width 0.05715)
			(type default)
		)
		(layer "In9.Cu")
	)
	(gr_line
		(start 358.980486 -57.115964)
		(end 359.173526 -57.24144)
		(stroke
			(width 0.05715)
			(type default)
		)
		(layer "In9.Cu")
	)
	(gr_line
		(start 359.038652 -34.796984)
		(end 359.045256 -34.76498)
		(stroke
			(width 0.05715)
			(type default)
		)
		(layer "In9.Cu")
	)
	(gr_line
		(start 359.04424 -50.671476)
		(end 359.04805 -50.690526)
		(stroke
			(width 0.05715)
			(type default)
		)
		(layer "In9.Cu")
	)
	(gr_line
		(start 359.04424 -50.671476)
		(end 359.048304 -50.65141)
		(stroke
			(width 0.05715)
			(type default)
		)
		(layer "In9.Cu")
	)
	(gr_line
		(start 359.045256 -34.76498)
		(end 359.066084 -34.739326)
		(stroke
			(width 0.05715)
			(type default)
		)
		(layer "In9.Cu")
	)
	(gr_line
		(start 359.055162 -118.94312)
		(end 359.083864 -118.937024)
		(stroke
			(width 0.05715)
			(type default)
		)
		(layer "In9.Cu")
	)
	(gr_line
		(start 359.07091 -42.53611)
		(end 359.07345 -42.531284)
		(stroke
			(width 0.05715)
			(type default)
		)
		(layer "In9.Cu")
	)
	(gr_line
		(start 359.07345 -42.531284)
		(end 359.074466 -42.526204)
		(stroke
			(width 0.05715)
			(type default)
		)
		(layer "In9.Cu")
	)
	(gr_line
		(start 359.083864 -118.937024)
		(end 359.107232 -118.919244)
		(stroke
			(width 0.05715)
			(type default)
		)
		(layer "In9.Cu")
	)
	(gr_line
		(start 359.117646 -50.303684)
		(end 359.119932 -50.292508)
		(stroke
			(width 0.05715)
			(type default)
		)
		(layer "In9.Cu")
	)
	(gr_line
		(start 359.119424 -57.76976)
		(end 359.2449 -57.576974)
		(stroke
			(width 0.05715)
			(type default)
		)
		(layer "In9.Cu")
	)
	(gr_line
		(start 359.119932 -50.292508)
		(end 359.12552 -50.28311)
		(stroke
			(width 0.05715)
			(type default)
		)
		(layer "In9.Cu")
	)
	(gr_line
		(start 359.147872 -66.612516)
		(end 359.161842 -66.592704)
		(stroke
			(width 0.05715)
			(type default)
		)
		(layer "In9.Cu")
	)
	(gr_line
		(start 359.161842 -66.592704)
		(end 359.166922 -66.568828)
		(stroke
			(width 0.05715)
			(type default)
		)
		(layer "In9.Cu")
	)
	(gr_line
		(start 359.173526 -57.24144)
		(end 359.2449 -57.576974)
		(stroke
			(width 0.05715)
			(type default)
		)
		(layer "In9.Cu")
	)
	(gr_line
		(start 359.191814 -58.109866)
		(end 359.384854 -58.235342)
		(stroke
			(width 0.05715)
			(type default)
		)
		(layer "In9.Cu")
	)
	(gr_line
		(start 359.227882 -45.02912)
		(end 359.26014 -45.008038)
		(stroke
			(width 0.05715)
			(type default)
		)
		(layer "In9.Cu")
	)
	(gr_line
		(start 359.228644 -119.65813)
		(end 359.257346 -119.652034)
		(stroke
			(width 0.05715)
			(type default)
		)
		(layer "In9.Cu")
	)
	(gr_line
		(start 359.257346 -119.652034)
		(end 359.280714 -119.634254)
		(stroke
			(width 0.05715)
			(type default)
		)
		(layer "In9.Cu")
	)
	(gr_line
		(start 359.26014 -45.008038)
		(end 359.278174 -44.974002)
		(stroke
			(width 0.05715)
			(type default)
		)
		(layer "In9.Cu")
	)
	(gr_line
		(start 359.32999 -108.497624)
		(end 359.397046 -108.542328)
		(stroke
			(width 0.05715)
			(type default)
		)
		(layer "In9.Cu")
	)
	(gr_line
		(start 359.330752 -58.763408)
		(end 359.455974 -58.570876)
		(stroke
			(width 0.05715)
			(type default)
		)
		(layer "In9.Cu")
	)
	(gr_line
		(start 359.340912 -69.052186)
		(end 359.345484 -69.029326)
		(stroke
			(width 0.05715)
			(type default)
		)
		(layer "In9.Cu")
	)
	(gr_line
		(start 359.340912 -69.052186)
		(end 359.345738 -69.075046)
		(stroke
			(width 0.05715)
			(type default)
		)
		(layer "In9.Cu")
	)
	(gr_line
		(start 359.384854 -58.235342)
		(end 359.455974 -58.570876)
		(stroke
			(width 0.05715)
			(type default)
		)
		(layer "In9.Cu")
	)
	(gr_line
		(start 359.38714 -67.221354)
		(end 359.391712 -67.244214)
		(stroke
			(width 0.05715)
			(type default)
		)
		(layer "In9.Cu")
	)
	(gr_line
		(start 359.38714 -67.221354)
		(end 359.391966 -67.198748)
		(stroke
			(width 0.05715)
			(type default)
		)
		(layer "In9.Cu")
	)
	(gr_line
		(start 359.395014 -59.078622)
		(end 359.400094 -59.10199)
		(stroke
			(width 0.05715)
			(type default)
		)
		(layer "In9.Cu")
	)
	(gr_line
		(start 359.395268 -59.124596)
		(end 359.400094 -59.10199)
		(stroke
			(width 0.05715)
			(type default)
		)
		(layer "In9.Cu")
	)
	(gr_line
		(start 359.397046 -108.542328)
		(end 359.41381 -108.621068)
		(stroke
			(width 0.05715)
			(type default)
		)
		(layer "In9.Cu")
	)
	(gr_line
		(start 359.527348 -116.90477)
		(end 359.583736 -116.86159)
		(stroke
			(width 0.05715)
			(type default)
		)
		(layer "In9.Cu")
	)
	(gr_line
		(start 359.583736 -116.86159)
		(end 359.598722 -116.790978)
		(stroke
			(width 0.05715)
			(type default)
		)
		(layer "In9.Cu")
	)
	(gr_line
		(start 359.60304 -49.460658)
		(end 359.645458 -49.38776)
		(stroke
			(width 0.05715)
			(type default)
		)
		(layer "In9.Cu")
	)
	(gr_line
		(start 359.638092 -35.072574)
		(end 359.644696 -35.04057)
		(stroke
			(width 0.05715)
			(type default)
		)
		(layer "In9.Cu")
	)
	(gr_line
		(start 359.644696 -35.04057)
		(end 359.665524 -35.014916)
		(stroke
			(width 0.05715)
			(type default)
		)
		(layer "In9.Cu")
	)
	(gr_line
		(start 359.645458 -49.38776)
		(end 359.726484 -49.366424)
		(stroke
			(width 0.05715)
			(type default)
		)
		(layer "In9.Cu")
	)
	(gr_line
		(start 359.679748 -42.817542)
		(end 359.682288 -42.812716)
		(stroke
			(width 0.05715)
			(type default)
		)
		(layer "In9.Cu")
	)
	(gr_line
		(start 359.68178 -52.474876)
		(end 359.694988 -52.436014)
		(stroke
			(width 0.05715)
			(type default)
		)
		(layer "In9.Cu")
	)
	(gr_line
		(start 359.682288 -42.812716)
		(end 359.683304 -42.807636)
		(stroke
			(width 0.05715)
			(type default)
		)
		(layer "In9.Cu")
	)
	(gr_line
		(start 359.68686 -52.395882)
		(end 359.694988 -52.436014)
		(stroke
			(width 0.05715)
			(type default)
		)
		(layer "In9.Cu")
	)
	(gr_line
		(start 359.701338 -45.493178)
		(end 359.73258 -45.472858)
		(stroke
			(width 0.05715)
			(type default)
		)
		(layer "In9.Cu")
	)
	(gr_line
		(start 359.73258 -45.473112)
		(end 359.733088 -45.472604)
		(stroke
			(width 0.05715)
			(type default)
		)
		(layer "In9.Cu")
	)
	(gr_line
		(start 359.73258 -45.472858)
		(end 359.73258 -45.473112)
		(stroke
			(width 0.05715)
			(type default)
		)
		(layer "In9.Cu")
	)
	(gr_line
		(start 359.733088 -45.472604)
		(end 359.751122 -45.438568)
		(stroke
			(width 0.05715)
			(type default)
		)
		(layer "In9.Cu")
	)
	(gr_line
		(start 359.760266 -54.201568)
		(end 359.769156 -54.24297)
		(stroke
			(width 0.05715)
			(type default)
		)
		(layer "In9.Cu")
	)
	(gr_line
		(start 359.760266 -54.201568)
		(end 359.773982 -54.16169)
		(stroke
			(width 0.05715)
			(type default)
		)
		(layer "In9.Cu")
	)
	(gr_line
		(start 359.841038 -68.040758)
		(end 359.845102 -68.020692)
		(stroke
			(width 0.05715)
			(type default)
		)
		(layer "In9.Cu")
	)
	(gr_line
		(start 359.841292 -68.001642)
		(end 359.845102 -68.020692)
		(stroke
			(width 0.05715)
			(type default)
		)
		(layer "In9.Cu")
	)
	(gr_line
		(start 359.953814 -49.305718)
		(end 360.035094 -49.284128)
		(stroke
			(width 0.05715)
			(type default)
		)
		(layer "In9.Cu")
	)
	(gr_line
		(start 360.035094 -49.284128)
		(end 360.107992 -49.326546)
		(stroke
			(width 0.05715)
			(type default)
		)
		(layer "In9.Cu")
	)
	(gr_line
		(start 360.051858 -69.102732)
		(end 360.05643 -69.079872)
		(stroke
			(width 0.05715)
			(type default)
		)
		(layer "In9.Cu")
	)
	(gr_line
		(start 360.051858 -69.102732)
		(end 360.056684 -69.125338)
		(stroke
			(width 0.05715)
			(type default)
		)
		(layer "In9.Cu")
	)
	(gr_line
		(start 360.065574 -67.235832)
		(end 360.070146 -67.258946)
		(stroke
			(width 0.05715)
			(type default)
		)
		(layer "In9.Cu")
	)
	(gr_line
		(start 360.065574 -67.235832)
		(end 360.0704 -67.212972)
		(stroke
			(width 0.05715)
			(type default)
		)
		(layer "In9.Cu")
	)
	(gr_line
		(start 360.075226 -49.645824)
		(end 360.148632 -49.688496)
		(stroke
			(width 0.05715)
			(type default)
		)
		(layer "In9.Cu")
	)
	(gr_line
		(start 360.148632 -49.688496)
		(end 360.230166 -49.666906)
		(stroke
			(width 0.05715)
			(type default)
		)
		(layer "In9.Cu")
	)
	(gr_line
		(start 360.161078 -48.499014)
		(end 360.182668 -48.579786)
		(stroke
			(width 0.05715)
			(type default)
		)
		(layer "In9.Cu")
	)
	(gr_line
		(start 360.161078 -48.499014)
		(end 360.203496 -48.426116)
		(stroke
			(width 0.05715)
			(type default)
		)
		(layer "In9.Cu")
	)
	(gr_line
		(start 360.17454 -58.640218)
		(end 360.17962 -58.617104)
		(stroke
			(width 0.05715)
			(type default)
		)
		(layer "In9.Cu")
	)
	(gr_line
		(start 360.17454 -58.593736)
		(end 360.17962 -58.617104)
		(stroke
			(width 0.05715)
			(type default)
		)
		(layer "In9.Cu")
	)
	(gr_line
		(start 360.200956 -45.940218)
		(end 360.233722 -45.918628)
		(stroke
			(width 0.05715)
			(type default)
		)
		(layer "In9.Cu")
	)
	(gr_line
		(start 360.209084 -122.167904)
		(end 360.284014 -122.242834)
		(stroke
			(width 0.05715)
			(type default)
		)
		(layer "In9.Cu")
	)
	(gr_line
		(start 360.209084 -121.751344)
		(end 360.258614 -121.701814)
		(stroke
			(width 0.05715)
			(type default)
		)
		(layer "In9.Cu")
	)
	(gr_line
		(start 360.233214 -124.338842)
		(end 360.659934 -124.765562)
		(stroke
			(width 0.05715)
			(type default)
		)
		(layer "In9.Cu")
	)
	(gr_line
		(start 360.233722 -45.918628)
		(end 360.251248 -45.885354)
		(stroke
			(width 0.05715)
			(type default)
		)
		(layer "In9.Cu")
	)
	(gr_line
		(start 360.243374 -48.807624)
		(end 360.26471 -48.88865)
		(stroke
			(width 0.05715)
			(type default)
		)
		(layer "In9.Cu")
	)
	(gr_line
		(start 360.246422 -35.384486)
		(end 360.253026 -35.352482)
		(stroke
			(width 0.05715)
			(type default)
		)
		(layer "In9.Cu")
	)
	(gr_line
		(start 360.253026 -35.352482)
		(end 360.273854 -35.326828)
		(stroke
			(width 0.05715)
			(type default)
		)
		(layer "In9.Cu")
	)
	(gr_line
		(start 360.258614 -125.583442)
		(end 360.659934 -125.182122)
		(stroke
			(width 0.05715)
			(type default)
		)
		(layer "In9.Cu")
	)
	(gr_line
		(start 360.258614 -121.240042)
		(end 360.258614 -121.701814)
		(stroke
			(width 0.05715)
			(type default)
		)
		(layer "In9.Cu")
	)
	(gr_line
		(start 360.26471 -48.88865)
		(end 360.337608 -48.931068)
		(stroke
			(width 0.05715)
			(type default)
		)
		(layer "In9.Cu")
	)
	(gr_line
		(start 360.284014 -122.242834)
		(end 360.284014 -122.560842)
		(stroke
			(width 0.05715)
			(type default)
		)
		(layer "In9.Cu")
	)
	(gr_line
		(start 360.311446 -75.757532)
		(end 360.322114 -75.791314)
		(stroke
			(width 0.05715)
			(type default)
		)
		(layer "In9.Cu")
	)
	(gr_line
		(start 360.311446 -43.025822)
		(end 360.313986 -43.020996)
		(stroke
			(width 0.05715)
			(type default)
		)
		(layer "In9.Cu")
	)
	(gr_line
		(start 360.3117 -115.333272)
		(end 360.383074 -114.997738)
		(stroke
			(width 0.05715)
			(type default)
		)
		(layer "In9.Cu")
	)
	(gr_line
		(start 360.3117 -115.333272)
		(end 360.437176 -115.526312)
		(stroke
			(width 0.05715)
			(type default)
		)
		(layer "In9.Cu")
	)
	(gr_line
		(start 360.313986 -43.020996)
		(end 360.315002 -43.015916)
		(stroke
			(width 0.05715)
			(type default)
		)
		(layer "In9.Cu")
	)
	(gr_line
		(start 360.322114 -75.791314)
		(end 360.34726 -75.81646)
		(stroke
			(width 0.05715)
			(type default)
		)
		(layer "In9.Cu")
	)
	(gr_line
		(start 360.35234 -117.121686)
		(end 360.408728 -117.078506)
		(stroke
			(width 0.05715)
			(type default)
		)
		(layer "In9.Cu")
	)
	(gr_line
		(start 360.368342 -113.162334)
		(end 360.373422 -113.13922)
		(stroke
			(width 0.05715)
			(type default)
		)
		(layer "In9.Cu")
	)
	(gr_line
		(start 360.368342 -113.115852)
		(end 360.373422 -113.13922)
		(stroke
			(width 0.05715)
			(type default)
		)
		(layer "In9.Cu")
	)
	(gr_line
		(start 360.383074 -114.997738)
		(end 360.57586 -114.87277)
		(stroke
			(width 0.05715)
			(type default)
		)
		(layer "In9.Cu")
	)
	(gr_line
		(start 360.408728 -117.078506)
		(end 360.42346 -117.009164)
		(stroke
			(width 0.05715)
			(type default)
		)
		(layer "In9.Cu")
	)
	(gr_line
		(start 360.457242 -49.606454)
		(end 360.53903 -49.58461)
		(stroke
			(width 0.05715)
			(type default)
		)
		(layer "In9.Cu")
	)
	(gr_line
		(start 360.522774 -114.33937)
		(end 360.594148 -114.003836)
		(stroke
			(width 0.05715)
			(type default)
		)
		(layer "In9.Cu")
	)
	(gr_line
		(start 360.522774 -114.33937)
		(end 360.64825 -114.53241)
		(stroke
			(width 0.05715)
			(type default)
		)
		(layer "In9.Cu")
	)
	(gr_line
		(start 360.53903 -49.58461)
		(end 360.581448 -49.511712)
		(stroke
			(width 0.05715)
			(type default)
		)
		(layer "In9.Cu")
	)
	(gr_line
		(start 360.539538 -68.114672)
		(end 360.543602 -68.134484)
		(stroke
			(width 0.05715)
			(type default)
		)
		(layer "In9.Cu")
	)
	(gr_line
		(start 360.539792 -68.153534)
		(end 360.543602 -68.134484)
		(stroke
			(width 0.05715)
			(type default)
		)
		(layer "In9.Cu")
	)
	(gr_line
		(start 360.594148 -114.003836)
		(end 360.786934 -113.878868)
		(stroke
			(width 0.05715)
			(type default)
		)
		(layer "In9.Cu")
	)
	(gr_line
		(start 360.599736 -48.745394)
		(end 360.671618 -48.78705)
		(stroke
			(width 0.05715)
			(type default)
		)
		(layer "In9.Cu")
	)
	(gr_line
		(start 360.671618 -48.78705)
		(end 360.693208 -48.867568)
		(stroke
			(width 0.05715)
			(type default)
		)
		(layer "In9.Cu")
	)
	(gr_line
		(start 360.724196 -67.277996)
		(end 360.728768 -67.300856)
		(stroke
			(width 0.05715)
			(type default)
		)
		(layer "In9.Cu")
	)
	(gr_line
		(start 360.724196 -67.277996)
		(end 360.729022 -67.255136)
		(stroke
			(width 0.05715)
			(type default)
		)
		(layer "In9.Cu")
	)
	(gr_line
		(start 360.730038 -69.167502)
		(end 360.73461 -69.144642)
		(stroke
			(width 0.05715)
			(type default)
		)
		(layer "In9.Cu")
	)
	(gr_line
		(start 360.730038 -69.167502)
		(end 360.734864 -69.190108)
		(stroke
			(width 0.05715)
			(type default)
		)
		(layer "In9.Cu")
	)
	(gr_line
		(start 360.732578 -115.552728)
		(end 360.856022 -114.97056)
		(stroke
			(width 0.05715)
			(type default)
		)
		(layer "In9.Cu")
	)
	(gr_line
		(start 360.733594 -49.249584)
		(end 360.775758 -49.177194)
		(stroke
			(width 0.05715)
			(type default)
		)
		(layer "In9.Cu")
	)
	(gr_line
		(start 360.745532 -109.174026)
		(end 360.908092 -109.336586)
		(stroke
			(width 0.05715)
			(type default)
		)
		(layer "In9.Cu")
	)
	(gr_line
		(start 360.745532 -108.831126)
		(end 360.745532 -109.174026)
		(stroke
			(width 0.05715)
			(type default)
		)
		(layer "In9.Cu")
	)
	(gr_line
		(start 360.745532 -108.831126)
		(end 360.908092 -108.668566)
		(stroke
			(width 0.05715)
			(type default)
		)
		(layer "In9.Cu")
	)
	(gr_line
		(start 360.745532 -108.158026)
		(end 360.908092 -108.320586)
		(stroke
			(width 0.05715)
			(type default)
		)
		(layer "In9.Cu")
	)
	(gr_line
		(start 360.745532 -107.815126)
		(end 360.745532 -108.158026)
		(stroke
			(width 0.05715)
			(type default)
		)
		(layer "In9.Cu")
	)
	(gr_line
		(start 360.745532 -107.815126)
		(end 360.908092 -107.652566)
		(stroke
			(width 0.05715)
			(type default)
		)
		(layer "In9.Cu")
	)
	(gr_line
		(start 360.745532 -107.142026)
		(end 360.908092 -107.304586)
		(stroke
			(width 0.05715)
			(type default)
		)
		(layer "In9.Cu")
	)
	(gr_line
		(start 360.745532 -106.799126)
		(end 360.745532 -107.142026)
		(stroke
			(width 0.05715)
			(type default)
		)
		(layer "In9.Cu")
	)
	(gr_line
		(start 360.745532 -106.799126)
		(end 360.908092 -106.636566)
		(stroke
			(width 0.05715)
			(type default)
		)
		(layer "In9.Cu")
	)
	(gr_line
		(start 360.745532 -106.126026)
		(end 360.908092 -106.288586)
		(stroke
			(width 0.05715)
			(type default)
		)
		(layer "In9.Cu")
	)
	(gr_line
		(start 360.745532 -105.783126)
		(end 360.745532 -106.126026)
		(stroke
			(width 0.05715)
			(type default)
		)
		(layer "In9.Cu")
	)
	(gr_line
		(start 360.745532 -105.783126)
		(end 360.908092 -105.620566)
		(stroke
			(width 0.05715)
			(type default)
		)
		(layer "In9.Cu")
	)
	(gr_line
		(start 360.753914 -49.09566)
		(end 360.775758 -49.177194)
		(stroke
			(width 0.05715)
			(type default)
		)
		(layer "In9.Cu")
	)
	(gr_line
		(start 360.753914 -49.095152)
		(end 360.754168 -49.095914)
		(stroke
			(width 0.05715)
			(type default)
		)
		(layer "In9.Cu")
	)
	(gr_line
		(start 360.82859 -35.791902)
		(end 360.835194 -35.759898)
		(stroke
			(width 0.05715)
			(type default)
		)
		(layer "In9.Cu")
	)
	(gr_line
		(start 360.835194 -35.759898)
		(end 360.856022 -35.734244)
		(stroke
			(width 0.05715)
			(type default)
		)
		(layer "In9.Cu")
	)
	(gr_line
		(start 360.88447 -75.289918)
		(end 360.894884 -75.322938)
		(stroke
			(width 0.05715)
			(type default)
		)
		(layer "In9.Cu")
	)
	(gr_line
		(start 360.894884 -75.322938)
		(end 360.919776 -75.34783)
		(stroke
			(width 0.05715)
			(type default)
		)
		(layer "In9.Cu")
	)
	(gr_line
		(start 360.913426 -117.539262)
		(end 360.96956 -117.496336)
		(stroke
			(width 0.05715)
			(type default)
		)
		(layer "In9.Cu")
	)
	(gr_line
		(start 360.9213 -58.311288)
		(end 360.92638 -58.28792)
		(stroke
			(width 0.05715)
			(type default)
		)
		(layer "In9.Cu")
	)
	(gr_line
		(start 360.9213 -58.264806)
		(end 360.92638 -58.28792)
		(stroke
			(width 0.05715)
			(type default)
		)
		(layer "In9.Cu")
	)
	(gr_line
		(start 360.94289 -43.191684)
		(end 360.94543 -43.186858)
		(stroke
			(width 0.05715)
			(type default)
		)
		(layer "In9.Cu")
	)
	(gr_line
		(start 360.943652 -114.558826)
		(end 361.067604 -113.975896)
		(stroke
			(width 0.05715)
			(type default)
		)
		(layer "In9.Cu")
	)
	(gr_line
		(start 360.94543 -43.186858)
		(end 360.946446 -43.181778)
		(stroke
			(width 0.05715)
			(type default)
		)
		(layer "In9.Cu")
	)
	(gr_line
		(start 360.96956 -117.496336)
		(end 360.984292 -117.426994)
		(stroke
			(width 0.05715)
			(type default)
		)
		(layer "In9.Cu")
	)
	(gr_line
		(start 361.109514 -29.12237)
		(end 361.113578 -29.142182)
		(stroke
			(width 0.05715)
			(type default)
		)
		(layer "In9.Cu")
	)
	(gr_line
		(start 361.109514 -29.12237)
		(end 361.113578 -29.10205)
		(stroke
			(width 0.05715)
			(type default)
		)
		(layer "In9.Cu")
	)
	(gr_line
		(start 361.131104 -52.219606)
		(end 361.150154 -52.27701)
		(stroke
			(width 0.05715)
			(type default)
		)
		(layer "In9.Cu")
	)
	(gr_line
		(start 361.131104 -52.219606)
		(end 361.150916 -52.16144)
		(stroke
			(width 0.05715)
			(type default)
		)
		(layer "In9.Cu")
	)
	(gr_line
		(start 361.154726 -113.564416)
		(end 361.159806 -113.541302)
		(stroke
			(width 0.05715)
			(type default)
		)
		(layer "In9.Cu")
	)
	(gr_line
		(start 361.154726 -113.517934)
		(end 361.159806 -113.541302)
		(stroke
			(width 0.05715)
			(type default)
		)
		(layer "In9.Cu")
	)
	(gr_line
		(start 361.202732 -108.960666)
		(end 361.202732 -109.044486)
		(stroke
			(width 0.05715)
			(type default)
		)
		(layer "In9.Cu")
	)
	(gr_line
		(start 361.202732 -107.944666)
		(end 361.202732 -108.028486)
		(stroke
			(width 0.05715)
			(type default)
		)
		(layer "In9.Cu")
	)
	(gr_line
		(start 361.202732 -106.928666)
		(end 361.202732 -107.012486)
		(stroke
			(width 0.05715)
			(type default)
		)
		(layer "In9.Cu")
	)
	(gr_line
		(start 361.202732 -105.912666)
		(end 361.202732 -105.996486)
		(stroke
			(width 0.05715)
			(type default)
		)
		(layer "In9.Cu")
	)
	(gr_line
		(start 361.210098 -68.217034)
		(end 361.214162 -68.236846)
		(stroke
			(width 0.05715)
			(type default)
		)
		(layer "In9.Cu")
	)
	(gr_line
		(start 361.210352 -68.255896)
		(end 361.214162 -68.236846)
		(stroke
			(width 0.05715)
			(type default)
		)
		(layer "In9.Cu")
	)
	(gr_line
		(start 361.230672 -76.286614)
		(end 361.2896 -76.345542)
		(stroke
			(width 0.05715)
			(type default)
		)
		(layer "In9.Cu")
	)
	(gr_line
		(start 361.239562 -31.41091)
		(end 361.261914 -31.383224)
		(stroke
			(width 0.05715)
			(type default)
		)
		(layer "In9.Cu")
	)
	(gr_line
		(start 361.261914 -31.383224)
		(end 361.268772 -31.349188)
		(stroke
			(width 0.05715)
			(type default)
		)
		(layer "In9.Cu")
	)
	(gr_line
		(start 361.268264 -123.19)
		(end 361.430824 -123.35256)
		(stroke
			(width 0.05715)
			(type default)
		)
		(layer "In9.Cu")
	)
	(gr_line
		(start 361.268264 -122.8471)
		(end 361.268264 -123.19)
		(stroke
			(width 0.05715)
			(type default)
		)
		(layer "In9.Cu")
	)
	(gr_line
		(start 361.268264 -122.8471)
		(end 361.430824 -122.68454)
		(stroke
			(width 0.05715)
			(type default)
		)
		(layer "In9.Cu")
	)
	(gr_line
		(start 361.268264 -122.174)
		(end 361.430824 -122.33656)
		(stroke
			(width 0.05715)
			(type default)
		)
		(layer "In9.Cu")
	)
	(gr_line
		(start 361.268264 -121.8311)
		(end 361.268264 -122.174)
		(stroke
			(width 0.05715)
			(type default)
		)
		(layer "In9.Cu")
	)
	(gr_line
		(start 361.268264 -121.8311)
		(end 361.430824 -121.66854)
		(stroke
			(width 0.05715)
			(type default)
		)
		(layer "In9.Cu")
	)
	(gr_line
		(start 361.391708 -67.236594)
		(end 361.39628 -67.259454)
		(stroke
			(width 0.05715)
			(type default)
		)
		(layer "In9.Cu")
	)
	(gr_line
		(start 361.391708 -67.236594)
		(end 361.396534 -67.213734)
		(stroke
			(width 0.05715)
			(type default)
		)
		(layer "In9.Cu")
	)
	(gr_line
		(start 361.404408 -69.285358)
		(end 361.40898 -69.263006)
		(stroke
			(width 0.05715)
			(type default)
		)
		(layer "In9.Cu")
	)
	(gr_line
		(start 361.404408 -69.285358)
		(end 361.409234 -69.307964)
		(stroke
			(width 0.05715)
			(type default)
		)
		(layer "In9.Cu")
	)
	(gr_line
		(start 361.447588 -36.062412)
		(end 361.454192 -36.030408)
		(stroke
			(width 0.05715)
			(type default)
		)
		(layer "In9.Cu")
	)
	(gr_line
		(start 361.454192 -36.030408)
		(end 361.47502 -36.004754)
		(stroke
			(width 0.05715)
			(type default)
		)
		(layer "In9.Cu")
	)
	(gr_line
		(start 361.473496 -117.959632)
		(end 361.529884 -117.916452)
		(stroke
			(width 0.05715)
			(type default)
		)
		(layer "In9.Cu")
	)
	(gr_line
		(start 361.527344 -74.991976)
		(end 361.538012 -75.025758)
		(stroke
			(width 0.05715)
			(type default)
		)
		(layer "In9.Cu")
	)
	(gr_line
		(start 361.529884 -117.916452)
		(end 361.544616 -117.84711)
		(stroke
			(width 0.05715)
			(type default)
		)
		(layer "In9.Cu")
	)
	(gr_line
		(start 361.538012 -75.025758)
		(end 361.563158 -75.050904)
		(stroke
			(width 0.05715)
			(type default)
		)
		(layer "In9.Cu")
	)
	(gr_line
		(start 361.556808 -29.869384)
		(end 361.560872 -29.889196)
		(stroke
			(width 0.05715)
			(type default)
		)
		(layer "In9.Cu")
	)
	(gr_line
		(start 361.557062 -29.908246)
		(end 361.560872 -29.889196)
		(stroke
			(width 0.05715)
			(type default)
		)
		(layer "In9.Cu")
	)
	(gr_line
		(start 361.571286 -109.89056)
		(end 361.733846 -110.05312)
		(stroke
			(width 0.05715)
			(type default)
		)
		(layer "In9.Cu")
	)
	(gr_line
		(start 361.571286 -109.54766)
		(end 361.571286 -109.89056)
		(stroke
			(width 0.05715)
			(type default)
		)
		(layer "In9.Cu")
	)
	(gr_line
		(start 361.571286 -109.54766)
		(end 361.733846 -109.3851)
		(stroke
			(width 0.05715)
			(type default)
		)
		(layer "In9.Cu")
	)
	(gr_line
		(start 361.571286 -108.87456)
		(end 361.733846 -109.03712)
		(stroke
			(width 0.05715)
			(type default)
		)
		(layer "In9.Cu")
	)
	(gr_line
		(start 361.571286 -108.53166)
		(end 361.571286 -108.87456)
		(stroke
			(width 0.05715)
			(type default)
		)
		(layer "In9.Cu")
	)
	(gr_line
		(start 361.571286 -108.53166)
		(end 361.733846 -108.3691)
		(stroke
			(width 0.05715)
			(type default)
		)
		(layer "In9.Cu")
	)
	(gr_line
		(start 361.571286 -106.35869)
		(end 361.733846 -106.52125)
		(stroke
			(width 0.05715)
			(type default)
		)
		(layer "In9.Cu")
	)
	(gr_line
		(start 361.571286 -106.01579)
		(end 361.571286 -106.35869)
		(stroke
			(width 0.05715)
			(type default)
		)
		(layer "In9.Cu")
	)
	(gr_line
		(start 361.571286 -106.01579)
		(end 361.733846 -105.85323)
		(stroke
			(width 0.05715)
			(type default)
		)
		(layer "In9.Cu")
	)
	(gr_line
		(start 361.571286 -105.34269)
		(end 361.733846 -105.50525)
		(stroke
			(width 0.05715)
			(type default)
		)
		(layer "In9.Cu")
	)
	(gr_line
		(start 361.571286 -104.99979)
		(end 361.571286 -105.34269)
		(stroke
			(width 0.05715)
			(type default)
		)
		(layer "In9.Cu")
	)
	(gr_line
		(start 361.571286 -104.99979)
		(end 361.733846 -104.83723)
		(stroke
			(width 0.05715)
			(type default)
		)
		(layer "In9.Cu")
	)
	(gr_line
		(start 361.585256 -43.370754)
		(end 361.587796 -43.365928)
		(stroke
			(width 0.05715)
			(type default)
		)
		(layer "In9.Cu")
	)
	(gr_line
		(start 361.587796 -43.365928)
		(end 361.588812 -43.360848)
		(stroke
			(width 0.05715)
			(type default)
		)
		(layer "In9.Cu")
	)
	(gr_line
		(start 361.629452 -47.31639)
		(end 361.633262 -47.29734)
		(stroke
			(width 0.05715)
			(type default)
		)
		(layer "In9.Cu")
	)
	(gr_line
		(start 361.633262 -47.29734)
		(end 361.64393 -47.281084)
		(stroke
			(width 0.05715)
			(type default)
		)
		(layer "In9.Cu")
	)
	(gr_line
		(start 361.725464 -122.97664)
		(end 361.725464 -123.06046)
		(stroke
			(width 0.05715)
			(type default)
		)
		(layer "In9.Cu")
	)
	(gr_line
		(start 361.725464 -121.96064)
		(end 361.725464 -122.04446)
		(stroke
			(width 0.05715)
			(type default)
		)
		(layer "In9.Cu")
	)
	(gr_line
		(start 361.782614 -29.084016)
		(end 361.786678 -29.064204)
		(stroke
			(width 0.05715)
			(type default)
		)
		(layer "In9.Cu")
	)
	(gr_line
		(start 361.830874 -113.439702)
		(end 361.835954 -113.416334)
		(stroke
			(width 0.05715)
			(type default)
		)
		(layer "In9.Cu")
	)
	(gr_line
		(start 361.830874 -113.39322)
		(end 361.835954 -113.416334)
		(stroke
			(width 0.05715)
			(type default)
		)
		(layer "In9.Cu")
	)
	(gr_line
		(start 361.865672 -75.880468)
		(end 361.9246 -75.939396)
		(stroke
			(width 0.05715)
			(type default)
		)
		(layer "In9.Cu")
	)
	(gr_line
		(start 361.897168 -68.31457)
		(end 361.901232 -68.294758)
		(stroke
			(width 0.05715)
			(type default)
		)
		(layer "In9.Cu")
	)
	(gr_line
		(start 361.897422 -68.275708)
		(end 361.901232 -68.294758)
		(stroke
			(width 0.05715)
			(type default)
		)
		(layer "In9.Cu")
	)
	(gr_line
		(start 361.912154 -25.107138)
		(end 361.928664 -25.024842)
		(stroke
			(width 0.05715)
			(type default)
		)
		(layer "In9.Cu")
	)
	(gr_line
		(start 361.928664 -25.024842)
		(end 361.998006 -24.978614)
		(stroke
			(width 0.05715)
			(type default)
		)
		(layer "In9.Cu")
	)
	(gr_line
		(start 361.94492 -31.656528)
		(end 361.96778 -31.628334)
		(stroke
			(width 0.05715)
			(type default)
		)
		(layer "In9.Cu")
	)
	(gr_line
		(start 361.96778 -31.628334)
		(end 361.974892 -31.593028)
		(stroke
			(width 0.05715)
			(type default)
		)
		(layer "In9.Cu")
	)
	(gr_line
		(start 362.028486 -109.6772)
		(end 362.028486 -109.76102)
		(stroke
			(width 0.05715)
			(type default)
		)
		(layer "In9.Cu")
	)
	(gr_line
		(start 362.028486 -108.6612)
		(end 362.028486 -108.74502)
		(stroke
			(width 0.05715)
			(type default)
		)
		(layer "In9.Cu")
	)
	(gr_line
		(start 362.028486 -106.14533)
		(end 362.028486 -106.22915)
		(stroke
			(width 0.05715)
			(type default)
		)
		(layer "In9.Cu")
	)
	(gr_line
		(start 362.028486 -105.12933)
		(end 362.028486 -105.21315)
		(stroke
			(width 0.05715)
			(type default)
		)
		(layer "In9.Cu")
	)
	(gr_line
		(start 362.04398 -36.398962)
		(end 362.050584 -36.366958)
		(stroke
			(width 0.05715)
			(type default)
		)
		(layer "In9.Cu")
	)
	(gr_line
		(start 362.050584 -36.366958)
		(end 362.071412 -36.341304)
		(stroke
			(width 0.05715)
			(type default)
		)
		(layer "In9.Cu")
	)
	(gr_line
		(start 362.071158 -74.593196)
		(end 362.081572 -74.62647)
		(stroke
			(width 0.05715)
			(type default)
		)
		(layer "In9.Cu")
	)
	(gr_line
		(start 362.081826 -74.626724)
		(end 362.08208 -74.626724)
		(stroke
			(width 0.05715)
			(type default)
		)
		(layer "In9.Cu")
	)
	(gr_line
		(start 362.17225 -51.344576)
		(end 362.176822 -51.321716)
		(stroke
			(width 0.05715)
			(type default)
		)
		(layer "In9.Cu")
	)
	(gr_line
		(start 362.17225 -51.344576)
		(end 362.177076 -51.367182)
		(stroke
			(width 0.05715)
			(type default)
		)
		(layer "In9.Cu")
	)
	(gr_line
		(start 362.274358 -30.053534)
		(end 362.278422 -30.073346)
		(stroke
			(width 0.05715)
			(type default)
		)
		(layer "In9.Cu")
	)
	(gr_line
		(start 362.274612 -30.092396)
		(end 362.278422 -30.073346)
		(stroke
			(width 0.05715)
			(type default)
		)
		(layer "In9.Cu")
	)
	(gr_line
		(start 362.279692 -120.243346)
		(end 362.279692 -120.47347)
		(stroke
			(width 0.05715)
			(type default)
		)
		(layer "In9.Cu")
	)
	(gr_line
		(start 362.279692 -120.243346)
		(end 362.522008 -120.00103)
		(stroke
			(width 0.05715)
			(type default)
		)
		(layer "In9.Cu")
	)
	(gr_line
		(start 362.28909 -47.50435)
		(end 362.292646 -47.485554)
		(stroke
			(width 0.05715)
			(type default)
		)
		(layer "In9.Cu")
	)
	(gr_line
		(start 362.292646 -47.485554)
		(end 362.303314 -47.469552)
		(stroke
			(width 0.05715)
			(type default)
		)
		(layer "In9.Cu")
	)
	(gr_line
		(start 362.336588 -65.92062)
		(end 362.341668 -65.943734)
		(stroke
			(width 0.05715)
			(type default)
		)
		(layer "In9.Cu")
	)
	(gr_line
		(start 362.336588 -65.92062)
		(end 362.341668 -65.897252)
		(stroke
			(width 0.05715)
			(type default)
		)
		(layer "In9.Cu")
	)
	(gr_line
		(start 362.468414 -29.13507)
		(end 362.472224 -29.15412)
		(stroke
			(width 0.05715)
			(type default)
		)
		(layer "In9.Cu")
	)
	(gr_line
		(start 362.468414 -29.13507)
		(end 362.472478 -29.115258)
		(stroke
			(width 0.05715)
			(type default)
		)
		(layer "In9.Cu")
	)
	(gr_line
		(start 362.48594 -113.413794)
		(end 362.49102 -113.390426)
		(stroke
			(width 0.05715)
			(type default)
		)
		(layer "In9.Cu")
	)
	(gr_line
		(start 362.48594 -113.367312)
		(end 362.49102 -113.390426)
		(stroke
			(width 0.05715)
			(type default)
		)
		(layer "In9.Cu")
	)
	(gr_line
		(start 362.501688 -25.489408)
		(end 362.51769 -25.408382)
		(stroke
			(width 0.05715)
			(type default)
		)
		(layer "In9.Cu")
	)
	(gr_line
		(start 362.51769 -25.408382)
		(end 362.586778 -25.362154)
		(stroke
			(width 0.05715)
			(type default)
		)
		(layer "In9.Cu")
	)
	(gr_line
		(start 362.522008 -120.00103)
		(end 362.752132 -120.00103)
		(stroke
			(width 0.05715)
			(type default)
		)
		(layer "In9.Cu")
	)
	(gr_line
		(start 362.54182 -43.681904)
		(end 362.547916 -43.671236)
		(stroke
			(width 0.05715)
			(type default)
		)
		(layer "In9.Cu")
	)
	(gr_line
		(start 362.547916 -43.671236)
		(end 362.549948 -43.66006)
		(stroke
			(width 0.05715)
			(type default)
		)
		(layer "In9.Cu")
	)
	(gr_line
		(start 362.560616 -66.975228)
		(end 362.564426 -66.993008)
		(stroke
			(width 0.05715)
			(type default)
		)
		(layer "In9.Cu")
	)
	(gr_line
		(start 362.564426 -66.993008)
		(end 362.575094 -67.009264)
		(stroke
			(width 0.05715)
			(type default)
		)
		(layer "In9.Cu")
	)
	(gr_line
		(start 362.633768 -31.820866)
		(end 362.655866 -31.793434)
		(stroke
			(width 0.05715)
			(type default)
		)
		(layer "In9.Cu")
	)
	(gr_line
		(start 362.655866 -31.793434)
		(end 362.66247 -31.759398)
		(stroke
			(width 0.05715)
			(type default)
		)
		(layer "In9.Cu")
	)
	(gr_line
		(start 362.659168 -36.712144)
		(end 362.665772 -36.68014)
		(stroke
			(width 0.05715)
			(type default)
		)
		(layer "In9.Cu")
	)
	(gr_line
		(start 362.66501 -74.23277)
		(end 362.67517 -74.265028)
		(stroke
			(width 0.05715)
			(type default)
		)
		(layer "In9.Cu")
	)
	(gr_line
		(start 362.665772 -36.68014)
		(end 362.6866 -36.654486)
		(stroke
			(width 0.05715)
			(type default)
		)
		(layer "In9.Cu")
	)
	(gr_line
		(start 362.694728 -120.474994)
		(end 362.753656 -120.416066)
		(stroke
			(width 0.05715)
			(type default)
		)
		(layer "In9.Cu")
	)
	(gr_line
		(start 362.767626 -56.424068)
		(end 362.803186 -56.35117)
		(stroke
			(width 0.05715)
			(type default)
		)
		(layer "In9.Cu")
	)
	(gr_line
		(start 362.77804 -56.27497)
		(end 362.803186 -56.35117)
		(stroke
			(width 0.05715)
			(type default)
		)
		(layer "In9.Cu")
	)
	(gr_line
		(start 362.790994 -69.8881)
		(end 362.797598 -69.918326)
		(stroke
			(width 0.05715)
			(type default)
		)
		(layer "In9.Cu")
	)
	(gr_line
		(start 362.790994 -69.8881)
		(end 362.798868 -69.858128)
		(stroke
			(width 0.05715)
			(type default)
		)
		(layer "In9.Cu")
	)
	(gr_line
		(start 362.798868 -69.857874)
		(end 362.799122 -69.857112)
		(stroke
			(width 0.05715)
			(type default)
		)
		(layer "In9.Cu")
	)
	(gr_line
		(start 362.865162 -47.883572)
		(end 362.868718 -47.864776)
		(stroke
			(width 0.05715)
			(type default)
		)
		(layer "In9.Cu")
	)
	(gr_line
		(start 362.868718 -47.864776)
		(end 362.87964 -47.848266)
		(stroke
			(width 0.05715)
			(type default)
		)
		(layer "In9.Cu")
	)
	(gr_line
		(start 362.972858 -30.207204)
		(end 362.976922 -30.187138)
		(stroke
			(width 0.05715)
			(type default)
		)
		(layer "In9.Cu")
	)
	(gr_line
		(start 362.973112 -30.168088)
		(end 362.976922 -30.187138)
		(stroke
			(width 0.05715)
			(type default)
		)
		(layer "In9.Cu")
	)
	(gr_line
		(start 362.998004 -119.525034)
		(end 362.998004 -119.755158)
		(stroke
			(width 0.05715)
			(type default)
		)
		(layer "In9.Cu")
	)
	(gr_line
		(start 362.998004 -119.525034)
		(end 363.24032 -119.282718)
		(stroke
			(width 0.05715)
			(type default)
		)
		(layer "In9.Cu")
	)
	(gr_line
		(start 363.020102 -52.223162)
		(end 363.028992 -52.264564)
		(stroke
			(width 0.05715)
			(type default)
		)
		(layer "In9.Cu")
	)
	(gr_line
		(start 363.020102 -52.223162)
		(end 363.033818 -52.183284)
		(stroke
			(width 0.05715)
			(type default)
		)
		(layer "In9.Cu")
	)
	(gr_line
		(start 363.11713 -25.89149)
		(end 363.13364 -25.809194)
		(stroke
			(width 0.05715)
			(type default)
		)
		(layer "In9.Cu")
	)
	(gr_line
		(start 363.126274 -29.172916)
		(end 363.130084 -29.191966)
		(stroke
			(width 0.05715)
			(type default)
		)
		(layer "In9.Cu")
	)
	(gr_line
		(start 363.126274 -29.172916)
		(end 363.130338 -29.153104)
		(stroke
			(width 0.05715)
			(type default)
		)
		(layer "In9.Cu")
	)
	(gr_line
		(start 363.13364 -25.809194)
		(end 363.202982 -25.762966)
		(stroke
			(width 0.05715)
			(type default)
		)
		(layer "In9.Cu")
	)
	(gr_line
		(start 363.215174 -43.821858)
		(end 363.221016 -43.811698)
		(stroke
			(width 0.05715)
			(type default)
		)
		(layer "In9.Cu")
	)
	(gr_line
		(start 363.221016 -43.811698)
		(end 363.223302 -43.800268)
		(stroke
			(width 0.05715)
			(type default)
		)
		(layer "In9.Cu")
	)
	(gr_line
		(start 363.24032 -119.282718)
		(end 363.470444 -119.282718)
		(stroke
			(width 0.05715)
			(type default)
		)
		(layer "In9.Cu")
	)
	(gr_line
		(start 363.268006 -32.101536)
		(end 363.290866 -32.073342)
		(stroke
			(width 0.05715)
			(type default)
		)
		(layer "In9.Cu")
	)
	(gr_line
		(start 363.290866 -32.073342)
		(end 363.297978 -32.038036)
		(stroke
			(width 0.05715)
			(type default)
		)
		(layer "In9.Cu")
	)
	(gr_line
		(start 363.41304 -119.756682)
		(end 363.471968 -119.697754)
		(stroke
			(width 0.05715)
			(type default)
		)
		(layer "In9.Cu")
	)
	(gr_line
		(start 363.41431 -67.742054)
		(end 363.424978 -67.757802)
		(stroke
			(width 0.05715)
			(type default)
		)
		(layer "In9.Cu")
	)
	(gr_line
		(start 363.424978 -67.757802)
		(end 363.428788 -67.776852)
		(stroke
			(width 0.05715)
			(type default)
		)
		(layer "In9.Cu")
	)
	(gr_line
		(start 363.514894 -56.444134)
		(end 363.54258 -56.387238)
		(stroke
			(width 0.05715)
			(type default)
		)
		(layer "In9.Cu")
	)
	(gr_line
		(start 363.51591 -68.280534)
		(end 363.516164 -68.280026)
		(stroke
			(width 0.05715)
			(type default)
		)
		(layer "In9.Cu")
	)
	(gr_line
		(start 363.516164 -68.28028)
		(end 363.524038 -68.2498)
		(stroke
			(width 0.05715)
			(type default)
		)
		(layer "In9.Cu")
	)
	(gr_line
		(start 363.517942 -68.219574)
		(end 363.524038 -68.2498)
		(stroke
			(width 0.05715)
			(type default)
		)
		(layer "In9.Cu")
	)
	(gr_line
		(start 363.529372 -56.3245)
		(end 363.54258 -56.387238)
		(stroke
			(width 0.05715)
			(type default)
		)
		(layer "In9.Cu")
	)
	(gr_line
		(start 363.616494 -36.833048)
		(end 363.623606 -36.797742)
		(stroke
			(width 0.05715)
			(type default)
		)
		(layer "In9.Cu")
	)
	(gr_line
		(start 363.623606 -36.797742)
		(end 363.646466 -36.769548)
		(stroke
			(width 0.05715)
			(type default)
		)
		(layer "In9.Cu")
	)
	(gr_line
		(start 363.643418 -30.309312)
		(end 363.647482 -30.2895)
		(stroke
			(width 0.05715)
			(type default)
		)
		(layer "In9.Cu")
	)
	(gr_line
		(start 363.643672 -30.27045)
		(end 363.647482 -30.2895)
		(stroke
			(width 0.05715)
			(type default)
		)
		(layer "In9.Cu")
	)
	(gr_line
		(start 363.703108 -26.288746)
		(end 363.719618 -26.20645)
		(stroke
			(width 0.05715)
			(type default)
		)
		(layer "In9.Cu")
	)
	(gr_line
		(start 363.716316 -118.806722)
		(end 363.716316 -119.036846)
		(stroke
			(width 0.05715)
			(type default)
		)
		(layer "In9.Cu")
	)
	(gr_line
		(start 363.716316 -118.806722)
		(end 363.958632 -118.564406)
		(stroke
			(width 0.05715)
			(type default)
		)
		(layer "In9.Cu")
	)
	(gr_line
		(start 363.719618 -26.20645)
		(end 363.789468 -26.159968)
		(stroke
			(width 0.05715)
			(type default)
		)
		(layer "In9.Cu")
	)
	(gr_line
		(start 363.72927 -52.409598)
		(end 363.73816 -52.451)
		(stroke
			(width 0.05715)
			(type default)
		)
		(layer "In9.Cu")
	)
	(gr_line
		(start 363.72927 -52.409598)
		(end 363.742732 -52.370482)
		(stroke
			(width 0.05715)
			(type default)
		)
		(layer "In9.Cu")
	)
	(gr_line
		(start 363.738668 -74.350372)
		(end 363.749082 -74.399394)
		(stroke
			(width 0.05715)
			(type default)
		)
		(layer "In9.Cu")
	)
	(gr_line
		(start 363.74578 -44.654724)
		(end 363.756448 -44.638468)
		(stroke
			(width 0.05715)
			(type default)
		)
		(layer "In9.Cu")
	)
	(gr_line
		(start 363.749082 -74.399394)
		(end 363.784642 -74.434954)
		(stroke
			(width 0.05715)
			(type default)
		)
		(layer "In9.Cu")
	)
	(gr_line
		(start 363.756448 -44.638468)
		(end 363.760258 -44.619418)
		(stroke
			(width 0.05715)
			(type default)
		)
		(layer "In9.Cu")
	)
	(gr_line
		(start 363.806994 -29.198316)
		(end 363.810804 -29.179266)
		(stroke
			(width 0.05715)
			(type default)
		)
		(layer "In9.Cu")
	)
	(gr_line
		(start 363.806994 -29.198316)
		(end 363.811058 -29.218382)
		(stroke
			(width 0.05715)
			(type default)
		)
		(layer "In9.Cu")
	)
	(gr_line
		(start 363.89564 -32.45231)
		(end 363.9185 -32.424116)
		(stroke
			(width 0.05715)
			(type default)
		)
		(layer "In9.Cu")
	)
	(gr_line
		(start 363.9185 -32.424116)
		(end 363.925612 -32.38881)
		(stroke
			(width 0.05715)
			(type default)
		)
		(layer "In9.Cu")
	)
	(gr_line
		(start 363.958124 -24.023066)
		(end 364.026196 -23.9776)
		(stroke
			(width 0.05715)
			(type default)
		)
		(layer "In9.Cu")
	)
	(gr_line
		(start 363.958632 -118.564406)
		(end 364.188756 -118.564406)
		(stroke
			(width 0.05715)
			(type default)
		)
		(layer "In9.Cu")
	)
	(gr_line
		(start 364.026196 -23.9776)
		(end 364.04296 -23.897336)
		(stroke
			(width 0.05715)
			(type default)
		)
		(layer "In9.Cu")
	)
	(gr_line
		(start 364.131352 -119.03837)
		(end 364.19028 -118.979442)
		(stroke
			(width 0.05715)
			(type default)
		)
		(layer "In9.Cu")
	)
	(gr_line
		(start 364.19282 -56.530494)
		(end 364.22076 -56.47309)
		(stroke
			(width 0.05715)
			(type default)
		)
		(layer "In9.Cu")
	)
	(gr_line
		(start 364.207552 -56.411114)
		(end 364.22076 -56.47309)
		(stroke
			(width 0.05715)
			(type default)
		)
		(layer "In9.Cu")
	)
	(gr_line
		(start 364.252256 -37.068252)
		(end 364.25886 -37.034978)
		(stroke
			(width 0.05715)
			(type default)
		)
		(layer "In9.Cu")
	)
	(gr_line
		(start 364.25886 -37.034978)
		(end 364.279942 -37.00907)
		(stroke
			(width 0.05715)
			(type default)
		)
		(layer "In9.Cu")
	)
	(gr_line
		(start 364.269782 -48.55718)
		(end 364.284514 -48.513492)
		(stroke
			(width 0.05715)
			(type default)
		)
		(layer "In9.Cu")
	)
	(gr_line
		(start 364.284514 -48.513492)
		(end 364.320328 -48.483774)
		(stroke
			(width 0.05715)
			(type default)
		)
		(layer "In9.Cu")
	)
	(gr_line
		(start 364.317026 -26.64841)
		(end 364.333282 -26.566114)
		(stroke
			(width 0.05715)
			(type default)
		)
		(layer "In9.Cu")
	)
	(gr_line
		(start 364.330488 -30.327346)
		(end 364.334552 -30.347412)
		(stroke
			(width 0.05715)
			(type default)
		)
		(layer "In9.Cu")
	)
	(gr_line
		(start 364.330742 -30.366462)
		(end 364.334552 -30.347412)
		(stroke
			(width 0.05715)
			(type default)
		)
		(layer "In9.Cu")
	)
	(gr_line
		(start 364.333282 -26.566114)
		(end 364.403894 -26.519124)
		(stroke
			(width 0.05715)
			(type default)
		)
		(layer "In9.Cu")
	)
	(gr_line
		(start 364.345982 -44.948856)
		(end 364.35665 -44.932854)
		(stroke
			(width 0.05715)
			(type default)
		)
		(layer "In9.Cu")
	)
	(gr_line
		(start 364.35665 -44.932854)
		(end 364.360206 -44.914058)
		(stroke
			(width 0.05715)
			(type default)
		)
		(layer "In9.Cu")
	)
	(gr_line
		(start 364.405672 -74.642472)
		(end 364.4646 -74.7014)
		(stroke
			(width 0.05715)
			(type default)
		)
		(layer "In9.Cu")
	)
	(gr_line
		(start 364.434628 -118.08841)
		(end 364.434628 -118.318534)
		(stroke
			(width 0.05715)
			(type default)
		)
		(layer "In9.Cu")
	)
	(gr_line
		(start 364.434628 -118.08841)
		(end 364.676944 -117.846094)
		(stroke
			(width 0.05715)
			(type default)
		)
		(layer "In9.Cu")
	)
	(gr_line
		(start 364.45825 -52.676044)
		(end 364.466886 -52.716938)
		(stroke
			(width 0.05715)
			(type default)
		)
		(layer "In9.Cu")
	)
	(gr_line
		(start 364.45825 -52.676044)
		(end 364.471966 -52.635404)
		(stroke
			(width 0.05715)
			(type default)
		)
		(layer "In9.Cu")
	)
	(gr_line
		(start 364.464346 -29.155898)
		(end 364.468156 -29.136848)
		(stroke
			(width 0.05715)
			(type default)
		)
		(layer "In9.Cu")
	)
	(gr_line
		(start 364.464346 -29.155898)
		(end 364.46841 -29.175964)
		(stroke
			(width 0.05715)
			(type default)
		)
		(layer "In9.Cu")
	)
	(gr_line
		(start 364.471966 -52.635658)
		(end 364.47222 -52.63515)
		(stroke
			(width 0.05715)
			(type default)
		)
		(layer "In9.Cu")
	)
	(gr_line
		(start 364.483142 -32.760666)
		(end 364.504224 -32.734504)
		(stroke
			(width 0.05715)
			(type default)
		)
		(layer "In9.Cu")
	)
	(gr_line
		(start 364.504224 -32.734504)
		(end 364.510828 -32.701484)
		(stroke
			(width 0.05715)
			(type default)
		)
		(layer "In9.Cu")
	)
	(gr_line
		(start 364.52683 -24.41702)
		(end 364.59541 -24.3713)
		(stroke
			(width 0.05715)
			(type default)
		)
		(layer "In9.Cu")
	)
	(gr_line
		(start 364.59541 -24.3713)
		(end 364.61192 -24.29129)
		(stroke
			(width 0.05715)
			(type default)
		)
		(layer "In9.Cu")
	)
	(gr_line
		(start 364.676944 -117.846094)
		(end 364.907068 -117.846094)
		(stroke
			(width 0.05715)
			(type default)
		)
		(layer "In9.Cu")
	)
	(gr_line
		(start 364.768892 -41.383712)
		(end 364.775242 -41.350946)
		(stroke
			(width 0.05715)
			(type default)
		)
		(layer "In9.Cu")
	)
	(gr_line
		(start 364.775242 -41.350946)
		(end 364.796324 -41.324022)
		(stroke
			(width 0.05715)
			(type default)
		)
		(layer "In9.Cu")
	)
	(gr_line
		(start 364.849664 -118.320058)
		(end 364.908592 -118.26113)
		(stroke
			(width 0.05715)
			(type default)
		)
		(layer "In9.Cu")
	)
	(gr_line
		(start 364.884208 -56.634888)
		(end 364.884462 -56.63438)
		(stroke
			(width 0.05715)
			(type default)
		)
		(layer "In9.Cu")
	)
	(gr_line
		(start 364.884462 -56.634126)
		(end 364.912402 -56.576976)
		(stroke
			(width 0.05715)
			(type default)
		)
		(layer "In9.Cu")
	)
	(gr_line
		(start 364.885224 -27.048968)
		(end 364.901734 -26.966672)
		(stroke
			(width 0.05715)
			(type default)
		)
		(layer "In9.Cu")
	)
	(gr_line
		(start 364.887002 -49.017936)
		(end 364.901226 -48.976026)
		(stroke
			(width 0.05715)
			(type default)
		)
		(layer "In9.Cu")
	)
	(gr_line
		(start 364.899194 -56.514746)
		(end 364.912402 -56.576976)
		(stroke
			(width 0.05715)
			(type default)
		)
		(layer "In9.Cu")
	)
	(gr_line
		(start 364.901226 -48.976026)
		(end 364.935516 -48.947832)
		(stroke
			(width 0.05715)
			(type default)
		)
		(layer "In9.Cu")
	)
	(gr_line
		(start 364.901734 -26.966672)
		(end 364.970822 -26.920952)
		(stroke
			(width 0.05715)
			(type default)
		)
		(layer "In9.Cu")
	)
	(gr_line
		(start 364.907068 -37.393372)
		(end 364.91418 -37.358066)
		(stroke
			(width 0.05715)
			(type default)
		)
		(layer "In9.Cu")
	)
	(gr_line
		(start 364.91418 -37.358066)
		(end 364.93704 -37.329872)
		(stroke
			(width 0.05715)
			(type default)
		)
		(layer "In9.Cu")
	)
	(gr_line
		(start 364.942374 -44.12869)
		(end 364.946184 -44.10964)
		(stroke
			(width 0.05715)
			(type default)
		)
		(layer "In9.Cu")
	)
	(gr_line
		(start 364.946184 -44.10964)
		(end 364.956852 -44.093638)
		(stroke
			(width 0.05715)
			(type default)
		)
		(layer "In9.Cu")
	)
	(gr_line
		(start 364.987332 -30.322266)
		(end 364.991396 -30.302454)
		(stroke
			(width 0.05715)
			(type default)
		)
		(layer "In9.Cu")
	)
	(gr_line
		(start 364.987586 -30.283404)
		(end 364.991396 -30.302454)
		(stroke
			(width 0.05715)
			(type default)
		)
		(layer "In9.Cu")
	)
	(gr_line
		(start 365.007144 -116.352066)
		(end 365.169704 -116.514626)
		(stroke
			(width 0.05715)
			(type default)
		)
		(layer "In9.Cu")
	)
	(gr_line
		(start 365.007144 -116.009166)
		(end 365.007144 -116.352066)
		(stroke
			(width 0.05715)
			(type default)
		)
		(layer "In9.Cu")
	)
	(gr_line
		(start 365.007144 -116.009166)
		(end 365.169704 -115.846606)
		(stroke
			(width 0.05715)
			(type default)
		)
		(layer "In9.Cu")
	)
	(gr_line
		(start 365.007144 -115.336066)
		(end 365.169704 -115.498626)
		(stroke
			(width 0.05715)
			(type default)
		)
		(layer "In9.Cu")
	)
	(gr_line
		(start 365.007144 -114.993166)
		(end 365.007144 -115.336066)
		(stroke
			(width 0.05715)
			(type default)
		)
		(layer "In9.Cu")
	)
	(gr_line
		(start 365.007144 -114.993166)
		(end 365.169704 -114.830606)
		(stroke
			(width 0.05715)
			(type default)
		)
		(layer "In9.Cu")
	)
	(gr_line
		(start 365.007144 -112.799114)
		(end 365.169704 -112.961674)
		(stroke
			(width 0.05715)
			(type default)
		)
		(layer "In9.Cu")
	)
	(gr_line
		(start 365.007144 -112.456214)
		(end 365.007144 -112.799114)
		(stroke
			(width 0.05715)
			(type default)
		)
		(layer "In9.Cu")
	)
	(gr_line
		(start 365.007144 -112.456214)
		(end 365.169704 -112.293654)
		(stroke
			(width 0.05715)
			(type default)
		)
		(layer "In9.Cu")
	)
	(gr_line
		(start 365.007144 -111.783114)
		(end 365.169704 -111.945674)
		(stroke
			(width 0.05715)
			(type default)
		)
		(layer "In9.Cu")
	)
	(gr_line
		(start 365.007144 -111.440214)
		(end 365.007144 -111.783114)
		(stroke
			(width 0.05715)
			(type default)
		)
		(layer "In9.Cu")
	)
	(gr_line
		(start 365.007144 -111.440214)
		(end 365.169704 -111.277654)
		(stroke
			(width 0.05715)
			(type default)
		)
		(layer "In9.Cu")
	)
	(gr_line
		(start 365.021114 -45.182282)
		(end 365.032544 -45.16501)
		(stroke
			(width 0.05715)
			(type default)
		)
		(layer "In9.Cu")
	)
	(gr_line
		(start 365.032544 -45.16501)
		(end 365.036608 -45.144944)
		(stroke
			(width 0.05715)
			(type default)
		)
		(layer "In9.Cu")
	)
	(gr_line
		(start 365.094774 -24.852884)
		(end 365.162592 -24.807672)
		(stroke
			(width 0.05715)
			(type default)
		)
		(layer "In9.Cu")
	)
	(gr_line
		(start 365.162592 -24.807672)
		(end 365.17961 -24.727154)
		(stroke
			(width 0.05715)
			(type default)
		)
		(layer "In9.Cu")
	)
	(gr_line
		(start 365.212122 -29.51734)
		(end 365.215932 -29.53639)
		(stroke
			(width 0.05715)
			(type default)
		)
		(layer "In9.Cu")
	)
	(gr_line
		(start 365.212122 -29.51734)
		(end 365.216186 -29.497528)
		(stroke
			(width 0.05715)
			(type default)
		)
		(layer "In9.Cu")
	)
	(gr_line
		(start 365.216694 -32.92856)
		(end 365.237776 -32.902398)
		(stroke
			(width 0.05715)
			(type default)
		)
		(layer "In9.Cu")
	)
	(gr_line
		(start 365.237776 -32.902398)
		(end 365.24438 -32.869378)
		(stroke
			(width 0.05715)
			(type default)
		)
		(layer "In9.Cu")
	)
	(gr_line
		(start 365.391192 -16.00835)
		(end 365.391954 -16.004794)
		(stroke
			(width 0.05715)
			(type default)
		)
		(layer "In9.Cu")
	)
	(gr_line
		(start 365.391954 -16.004794)
		(end 365.393478 -16.002254)
		(stroke
			(width 0.05715)
			(type default)
		)
		(layer "In9.Cu")
	)
	(gr_line
		(start 365.418116 -43.401996)
		(end 365.430308 -43.383708)
		(stroke
			(width 0.05715)
			(type default)
		)
		(layer "In9.Cu")
	)
	(gr_line
		(start 365.430308 -43.383708)
		(end 365.448342 -43.371516)
		(stroke
			(width 0.05715)
			(type default)
		)
		(layer "In9.Cu")
	)
	(gr_line
		(start 365.464344 -116.138706)
		(end 365.464344 -116.222526)
		(stroke
			(width 0.05715)
			(type default)
		)
		(layer "In9.Cu")
	)
	(gr_line
		(start 365.464344 -115.122706)
		(end 365.464344 -115.206526)
		(stroke
			(width 0.05715)
			(type default)
		)
		(layer "In9.Cu")
	)
	(gr_line
		(start 365.464344 -112.585754)
		(end 365.464344 -112.669574)
		(stroke
			(width 0.05715)
			(type default)
		)
		(layer "In9.Cu")
	)
	(gr_line
		(start 365.464344 -111.569754)
		(end 365.464344 -111.653574)
		(stroke
			(width 0.05715)
			(type default)
		)
		(layer "In9.Cu")
	)
	(gr_line
		(start 365.575088 -56.731408)
		(end 365.575342 -56.7309)
		(stroke
			(width 0.05715)
			(type default)
		)
		(layer "In9.Cu")
	)
	(gr_line
		(start 365.575088 -56.731154)
		(end 365.60252 -56.67502)
		(stroke
			(width 0.05715)
			(type default)
		)
		(layer "In9.Cu")
	)
	(gr_line
		(start 365.58982 -56.614314)
		(end 365.60252 -56.67502)
		(stroke
			(width 0.05715)
			(type default)
		)
		(layer "In9.Cu")
	)
	(gr_line
		(start 365.623856 -49.26203)
		(end 365.63808 -49.22012)
		(stroke
			(width 0.05715)
			(type default)
		)
		(layer "In9.Cu")
	)
	(gr_line
		(start 365.63808 -49.22012)
		(end 365.67237 -49.191926)
		(stroke
			(width 0.05715)
			(type default)
		)
		(layer "In9.Cu")
	)
	(gr_line
		(start 365.642144 -27.36596)
		(end 365.658654 -27.283664)
		(stroke
			(width 0.05715)
			(type default)
		)
		(layer "In9.Cu")
	)
	(gr_line
		(start 365.658654 -27.283664)
		(end 365.727996 -27.237436)
		(stroke
			(width 0.05715)
			(type default)
		)
		(layer "In9.Cu")
	)
	(gr_line
		(start 365.671354 -25.254966)
		(end 365.738664 -25.210008)
		(stroke
			(width 0.05715)
			(type default)
		)
		(layer "In9.Cu")
	)
	(gr_line
		(start 365.708692 -30.510734)
		(end 365.712756 -30.530546)
		(stroke
			(width 0.05715)
			(type default)
		)
		(layer "In9.Cu")
	)
	(gr_line
		(start 365.708946 -30.549596)
		(end 365.712756 -30.530546)
		(stroke
			(width 0.05715)
			(type default)
		)
		(layer "In9.Cu")
	)
	(gr_line
		(start 365.738664 -25.210008)
		(end 365.755682 -25.131014)
		(stroke
			(width 0.05715)
			(type default)
		)
		(layer "In9.Cu")
	)
	(gr_line
		(start 365.890048 -29.581856)
		(end 365.893858 -29.562806)
		(stroke
			(width 0.05715)
			(type default)
		)
		(layer "In9.Cu")
	)
	(gr_line
		(start 365.890048 -29.581856)
		(end 365.894112 -29.601922)
		(stroke
			(width 0.05715)
			(type default)
		)
		(layer "In9.Cu")
	)
	(gr_line
		(start 365.924846 -16.593058)
		(end 365.925608 -16.589502)
		(stroke
			(width 0.05715)
			(type default)
		)
		(layer "In9.Cu")
	)
	(gr_line
		(start 365.925608 -16.589502)
		(end 365.927132 -16.586962)
		(stroke
			(width 0.05715)
			(type default)
		)
		(layer "In9.Cu")
	)
	(gr_line
		(start 365.99622 -33.039812)
		(end 366.01908 -33.011618)
		(stroke
			(width 0.05715)
			(type default)
		)
		(layer "In9.Cu")
	)
	(gr_line
		(start 366.01908 -33.011618)
		(end 366.026192 -32.976312)
		(stroke
			(width 0.05715)
			(type default)
		)
		(layer "In9.Cu")
	)
	(gr_line
		(start 366.196118 -122.222514)
		(end 366.227868 -122.254264)
		(stroke
			(width 0.05715)
			(type default)
		)
		(layer "In9.Cu")
	)
	(gr_line
		(start 366.196118 -121.8057)
		(end 366.303814 -121.698004)
		(stroke
			(width 0.05715)
			(type default)
		)
		(layer "In9.Cu")
	)
	(gr_line
		(start 366.201706 -125.181614)
		(end 366.278414 -125.258322)
		(stroke
			(width 0.05715)
			(type default)
		)
		(layer "In9.Cu")
	)
	(gr_line
		(start 366.201706 -124.765054)
		(end 366.278414 -124.688346)
		(stroke
			(width 0.05715)
			(type default)
		)
		(layer "In9.Cu")
	)
	(gr_line
		(start 366.227868 -122.254264)
		(end 366.227868 -122.662696)
		(stroke
			(width 0.05715)
			(type default)
		)
		(layer "In9.Cu")
	)
	(gr_line
		(start 366.260888 -27.728164)
		(end 366.277144 -27.646884)
		(stroke
			(width 0.05715)
			(type default)
		)
		(layer "In9.Cu")
	)
	(gr_line
		(start 366.264698 -25.631394)
		(end 366.331754 -25.58669)
		(stroke
			(width 0.05715)
			(type default)
		)
		(layer "In9.Cu")
	)
	(gr_line
		(start 366.278414 -125.258322)
		(end 366.278414 -125.583442)
		(stroke
			(width 0.05715)
			(type default)
		)
		(layer "In9.Cu")
	)
	(gr_line
		(start 366.278414 -124.262642)
		(end 366.278414 -124.688346)
		(stroke
			(width 0.05715)
			(type default)
		)
		(layer "In9.Cu")
	)
	(gr_line
		(start 366.303814 -121.316242)
		(end 366.303814 -121.698004)
		(stroke
			(width 0.05715)
			(type default)
		)
		(layer "In9.Cu")
	)
	(gr_line
		(start 366.331754 -25.58669)
		(end 366.348772 -25.507442)
		(stroke
			(width 0.05715)
			(type default)
		)
		(layer "In9.Cu")
	)
	(gr_line
		(start 366.442244 -30.855158)
		(end 366.446308 -30.875224)
		(stroke
			(width 0.05715)
			(type default)
		)
		(layer "In9.Cu")
	)
	(gr_line
		(start 366.442498 -30.894274)
		(end 366.446308 -30.875224)
		(stroke
			(width 0.05715)
			(type default)
		)
		(layer "In9.Cu")
	)
	(gr_line
		(start 366.466628 -43.044364)
		(end 366.483646 -43.032934)
		(stroke
			(width 0.05715)
			(type default)
		)
		(layer "In9.Cu")
	)
	(gr_line
		(start 366.483646 -43.032934)
		(end 366.494568 -43.016424)
		(stroke
			(width 0.05715)
			(type default)
		)
		(layer "In9.Cu")
	)
	(gr_line
		(start 366.501934 -17.049496)
		(end 366.50295 -17.04467)
		(stroke
			(width 0.05715)
			(type default)
		)
		(layer "In9.Cu")
	)
	(gr_line
		(start 366.50295 -17.04467)
		(end 366.505236 -17.040352)
		(stroke
			(width 0.05715)
			(type default)
		)
		(layer "In9.Cu")
	)
	(gr_line
		(start 366.724946 -36.178236)
		(end 366.732058 -36.14674)
		(stroke
			(width 0.05715)
			(type default)
		)
		(layer "In9.Cu")
	)
	(gr_line
		(start 366.728502 -29.67228)
		(end 366.732312 -29.65323)
		(stroke
			(width 0.05715)
			(type default)
		)
		(layer "In9.Cu")
	)
	(gr_line
		(start 366.728502 -29.67228)
		(end 366.732566 -29.692346)
		(stroke
			(width 0.05715)
			(type default)
		)
		(layer "In9.Cu")
	)
	(gr_line
		(start 366.732058 -36.14674)
		(end 366.752124 -36.122356)
		(stroke
			(width 0.05715)
			(type default)
		)
		(layer "In9.Cu")
	)
	(gr_line
		(start 366.749838 -33.410652)
		(end 366.772698 -33.382458)
		(stroke
			(width 0.05715)
			(type default)
		)
		(layer "In9.Cu")
	)
	(gr_line
		(start 366.772698 -33.382458)
		(end 366.77981 -33.347152)
		(stroke
			(width 0.05715)
			(type default)
		)
		(layer "In9.Cu")
	)
	(gr_line
		(start 366.797082 -44.611798)
		(end 366.800892 -44.592748)
		(stroke
			(width 0.05715)
			(type default)
		)
		(layer "In9.Cu")
	)
	(gr_line
		(start 366.797082 -44.611798)
		(end 366.801146 -44.63161)
		(stroke
			(width 0.05715)
			(type default)
		)
		(layer "In9.Cu")
	)
	(gr_line
		(start 366.800638 -16.488918)
		(end 367.082832 -15.962122)
		(stroke
			(width 0.05715)
			(type default)
		)
		(layer "In9.Cu")
	)
	(gr_line
		(start 366.851184 -26.020014)
		(end 366.919764 -25.974294)
		(stroke
			(width 0.05715)
			(type default)
		)
		(layer "In9.Cu")
	)
	(gr_line
		(start 366.919764 -25.974294)
		(end 366.93729 -25.89403)
		(stroke
			(width 0.05715)
			(type default)
		)
		(layer "In9.Cu")
	)
	(gr_line
		(start 367.000028 -17.942814)
		(end 367.00079 -17.939512)
		(stroke
			(width 0.05715)
			(type default)
		)
		(layer "In9.Cu")
	)
	(gr_line
		(start 367.00079 -17.939512)
		(end 367.002568 -17.93621)
		(stroke
			(width 0.05715)
			(type default)
		)
		(layer "In9.Cu")
	)
	(gr_line
		(start 367.029746 -28.164282)
		(end 367.046256 -28.081732)
		(stroke
			(width 0.05715)
			(type default)
		)
		(layer "In9.Cu")
	)
	(gr_line
		(start 367.043462 -16.659352)
		(end 367.263934 -16.592804)
		(stroke
			(width 0.05715)
			(type default)
		)
		(layer "In9.Cu")
	)
	(gr_line
		(start 367.046256 -28.081732)
		(end 367.116106 -28.035504)
		(stroke
			(width 0.05715)
			(type default)
		)
		(layer "In9.Cu")
	)
	(gr_line
		(start 367.121186 -46.542706)
		(end 367.171732 -46.50105)
		(stroke
			(width 0.05715)
			(type default)
		)
		(layer "In9.Cu")
	)
	(gr_line
		(start 367.171732 -46.50105)
		(end 367.184686 -46.436534)
		(stroke
			(width 0.05715)
			(type default)
		)
		(layer "In9.Cu")
	)
	(gr_line
		(start 367.19256 -42.634662)
		(end 367.19637 -42.614596)
		(stroke
			(width 0.05715)
			(type default)
		)
		(layer "In9.Cu")
	)
	(gr_line
		(start 367.19637 -42.614596)
		(end 367.207546 -42.597578)
		(stroke
			(width 0.05715)
			(type default)
		)
		(layer "In9.Cu")
	)
	(gr_line
		(start 367.263934 -16.592804)
		(end 367.425732 -16.290544)
		(stroke
			(width 0.05715)
			(type default)
		)
		(layer "In9.Cu")
	)
	(gr_line
		(start 367.266728 -30.87624)
		(end 367.270792 -30.896306)
		(stroke
			(width 0.05715)
			(type default)
		)
		(layer "In9.Cu")
	)
	(gr_line
		(start 367.266982 -30.915356)
		(end 367.270792 -30.896306)
		(stroke
			(width 0.05715)
			(type default)
		)
		(layer "In9.Cu")
	)
	(gr_line
		(start 367.279936 -15.594076)
		(end 367.562638 -15.066264)
		(stroke
			(width 0.05715)
			(type default)
		)
		(layer "In9.Cu")
	)
	(gr_line
		(start 367.31829 -45.729144)
		(end 367.322354 -45.748956)
		(stroke
			(width 0.05715)
			(type default)
		)
		(layer "In9.Cu")
	)
	(gr_line
		(start 367.359184 -16.070326)
		(end 367.425732 -16.290544)
		(stroke
			(width 0.05715)
			(type default)
		)
		(layer "In9.Cu")
	)
	(gr_line
		(start 367.432844 -26.452322)
		(end 367.499138 -26.408126)
		(stroke
			(width 0.05715)
			(type default)
		)
		(layer "In9.Cu")
	)
	(gr_line
		(start 367.499138 -26.408126)
		(end 367.516664 -26.32964)
		(stroke
			(width 0.05715)
			(type default)
		)
		(layer "In9.Cu")
	)
	(gr_line
		(start 367.523268 -15.763748)
		(end 367.74374 -15.6972)
		(stroke
			(width 0.05715)
			(type default)
		)
		(layer "In9.Cu")
	)
	(gr_line
		(start 367.600738 -18.269458)
		(end 367.6015 -18.266156)
		(stroke
			(width 0.05715)
			(type default)
		)
		(layer "In9.Cu")
	)
	(gr_line
		(start 367.6015 -18.266156)
		(end 367.603278 -18.262854)
		(stroke
			(width 0.05715)
			(type default)
		)
		(layer "In9.Cu")
	)
	(gr_line
		(start 367.669064 -40.728646)
		(end 367.681256 -40.710358)
		(stroke
			(width 0.05715)
			(type default)
		)
		(layer "In9.Cu")
	)
	(gr_line
		(start 367.681256 -40.710358)
		(end 367.699544 -40.698166)
		(stroke
			(width 0.05715)
			(type default)
		)
		(layer "In9.Cu")
	)
	(gr_line
		(start 367.74374 -15.6972)
		(end 367.905538 -15.39494)
		(stroke
			(width 0.05715)
			(type default)
		)
		(layer "In9.Cu")
	)
	(gr_line
		(start 367.820956 -13.05179)
		(end 367.83137 -13.032232)
		(stroke
			(width 0.05715)
			(type default)
		)
		(layer "In9.Cu")
	)
	(gr_line
		(start 367.831116 -13.032232)
		(end 367.83137 -13.032232)
		(stroke
			(width 0.05715)
			(type default)
		)
		(layer "In9.Cu")
	)
	(gr_line
		(start 367.831116 -13.032232)
		(end 367.831624 -13.031724)
		(stroke
			(width 0.05715)
			(type default)
		)
		(layer "In9.Cu")
	)
	(gr_line
		(start 367.831624 -13.031724)
		(end 367.849404 -13.017754)
		(stroke
			(width 0.05715)
			(type default)
		)
		(layer "In9.Cu")
	)
	(gr_line
		(start 367.83899 -15.174722)
		(end 367.905538 -15.39494)
		(stroke
			(width 0.05715)
			(type default)
		)
		(layer "In9.Cu")
	)
	(gr_line
		(start 367.994946 -26.857198)
		(end 368.060224 -26.814018)
		(stroke
			(width 0.05715)
			(type default)
		)
		(layer "In9.Cu")
	)
	(gr_line
		(start 368.020346 -41.378886)
		(end 368.032538 -41.360598)
		(stroke
			(width 0.05715)
			(type default)
		)
		(layer "In9.Cu")
	)
	(gr_line
		(start 368.032538 -41.360598)
		(end 368.050826 -41.348406)
		(stroke
			(width 0.05715)
			(type default)
		)
		(layer "In9.Cu")
	)
	(gr_line
		(start 368.060224 -26.814018)
		(end 368.077496 -26.736548)
		(stroke
			(width 0.05715)
			(type default)
		)
		(layer "In9.Cu")
	)
	(gr_line
		(start 368.165634 -13.941044)
		(end 368.176302 -13.920978)
		(stroke
			(width 0.05715)
			(type default)
		)
		(layer "In9.Cu")
	)
	(gr_line
		(start 368.176302 -13.920978)
		(end 368.19459 -13.9065)
		(stroke
			(width 0.05715)
			(type default)
		)
		(layer "In9.Cu")
	)
	(gr_line
		(start 368.260376 -18.427192)
		(end 368.261646 -18.421858)
		(stroke
			(width 0.05715)
			(type default)
		)
		(layer "In9.Cu")
	)
	(gr_line
		(start 368.261646 -18.421858)
		(end 368.264186 -18.417032)
		(stroke
			(width 0.05715)
			(type default)
		)
		(layer "In9.Cu")
	)
	(gr_line
		(start 368.472212 -20.693888)
		(end 368.542824 -20.648676)
		(stroke
			(width 0.05715)
			(type default)
		)
		(layer "In9.Cu")
	)
	(gr_line
		(start 368.491516 -12.51458)
		(end 368.961924 -12.145772)
		(stroke
			(width 0.05715)
			(type default)
		)
		(layer "In9.Cu")
	)
	(gr_line
		(start 368.540284 -27.089862)
		(end 368.553746 -27.080972)
		(stroke
			(width 0.05715)
			(type default)
		)
		(layer "In9.Cu")
	)
	(gr_line
		(start 368.553746 -27.080972)
		(end 368.569494 -27.077416)
		(stroke
			(width 0.05715)
			(type default)
		)
		(layer "In9.Cu")
	)
	(gr_line
		(start 368.64544 -12.768326)
		(end 368.87404 -12.795758)
		(stroke
			(width 0.05715)
			(type default)
		)
		(layer "In9.Cu")
	)
	(gr_line
		(start 368.693446 -22.630892)
		(end 368.71021 -22.554946)
		(stroke
			(width 0.05715)
			(type default)
		)
		(layer "In9.Cu")
	)
	(gr_line
		(start 368.71021 -22.554946)
		(end 368.775742 -22.511258)
		(stroke
			(width 0.05715)
			(type default)
		)
		(layer "In9.Cu")
	)
	(gr_line
		(start 368.764312 -17.496028)
		(end 369.050316 -16.969232)
		(stroke
			(width 0.05715)
			(type default)
		)
		(layer "In9.Cu")
	)
	(gr_line
		(start 368.87404 -12.795758)
		(end 369.143788 -12.58443)
		(stroke
			(width 0.05715)
			(type default)
		)
		(layer "In9.Cu")
	)
	(gr_line
		(start 368.899948 -30.729936)
		(end 368.94516 -30.955742)
		(stroke
			(width 0.05715)
			(type default)
		)
		(layer "In9.Cu")
	)
	(gr_line
		(start 368.899948 -30.729936)
		(end 369.090194 -30.444694)
		(stroke
			(width 0.05715)
			(type default)
		)
		(layer "In9.Cu")
	)
	(gr_line
		(start 369.006628 -17.667224)
		(end 369.227354 -17.601438)
		(stroke
			(width 0.05715)
			(type default)
		)
		(layer "In9.Cu")
	)
	(gr_line
		(start 369.06454 -14.088618)
		(end 369.076224 -14.067028)
		(stroke
			(width 0.05715)
			(type default)
		)
		(layer "In9.Cu")
	)
	(gr_line
		(start 369.076224 -14.067028)
		(end 369.095528 -14.051788)
		(stroke
			(width 0.05715)
			(type default)
		)
		(layer "In9.Cu")
	)
	(gr_line
		(start 369.090194 -30.444694)
		(end 369.316 -30.399228)
		(stroke
			(width 0.05715)
			(type default)
		)
		(layer "In9.Cu")
	)
	(gr_line
		(start 369.143788 -12.58443)
		(end 369.171474 -12.35583)
		(stroke
			(width 0.05715)
			(type default)
		)
		(layer "In9.Cu")
	)
	(gr_line
		(start 369.157504 -28.72613)
		(end 369.174014 -28.644088)
		(stroke
			(width 0.05715)
			(type default)
		)
		(layer "In9.Cu")
	)
	(gr_line
		(start 369.157504 -28.72613)
		(end 369.203986 -28.795726)
		(stroke
			(width 0.05715)
			(type default)
		)
		(layer "In9.Cu")
	)
	(gr_line
		(start 369.210336 -31.089346)
		(end 369.542822 -30.59049)
		(stroke
			(width 0.05715)
			(type default)
		)
		(layer "In9.Cu")
	)
	(gr_line
		(start 369.227354 -17.601438)
		(end 369.39093 -17.300194)
		(stroke
			(width 0.05715)
			(type default)
		)
		(layer "In9.Cu")
	)
	(gr_line
		(start 369.23345 -28.346146)
		(end 369.24996 -28.26385)
		(stroke
			(width 0.05715)
			(type default)
		)
		(layer "In9.Cu")
	)
	(gr_line
		(start 369.24996 -28.26385)
		(end 369.31981 -28.217368)
		(stroke
			(width 0.05715)
			(type default)
		)
		(layer "In9.Cu")
	)
	(gr_line
		(start 369.24996 -16.601694)
		(end 369.533932 -16.0782)
		(stroke
			(width 0.05715)
			(type default)
		)
		(layer "In9.Cu")
	)
	(gr_line
		(start 369.260374 -37.971984)
		(end 369.264184 -37.952934)
		(stroke
			(width 0.05715)
			(type default)
		)
		(layer "In9.Cu")
	)
	(gr_line
		(start 369.260374 -37.971984)
		(end 369.264438 -37.99205)
		(stroke
			(width 0.05715)
			(type default)
		)
		(layer "In9.Cu")
	)
	(gr_line
		(start 369.283234 -39.99357)
		(end 369.351814 -39.94785)
		(stroke
			(width 0.05715)
			(type default)
		)
		(layer "In9.Cu")
	)
	(gr_line
		(start 369.292124 -11.8872)
		(end 369.761516 -11.519154)
		(stroke
			(width 0.05715)
			(type default)
		)
		(layer "In9.Cu")
	)
	(gr_line
		(start 369.325652 -17.079468)
		(end 369.39093 -17.300194)
		(stroke
			(width 0.05715)
			(type default)
		)
		(layer "In9.Cu")
	)
	(gr_line
		(start 369.335304 -28.992068)
		(end 369.381786 -29.06141)
		(stroke
			(width 0.05715)
			(type default)
		)
		(layer "In9.Cu")
	)
	(gr_line
		(start 369.351814 -39.94785)
		(end 369.369086 -39.867332)
		(stroke
			(width 0.05715)
			(type default)
		)
		(layer "In9.Cu")
	)
	(gr_line
		(start 369.378992 -27.198066)
		(end 369.44681 -27.18308)
		(stroke
			(width 0.05715)
			(type default)
		)
		(layer "In9.Cu")
	)
	(gr_line
		(start 369.381786 -29.06141)
		(end 369.463066 -29.077666)
		(stroke
			(width 0.05715)
			(type default)
		)
		(layer "In9.Cu")
	)
	(gr_line
		(start 369.445286 -12.141454)
		(end 369.673632 -12.16914)
		(stroke
			(width 0.05715)
			(type default)
		)
		(layer "In9.Cu")
	)
	(gr_line
		(start 369.44681 -27.18308)
		(end 369.489228 -27.126692)
		(stroke
			(width 0.05715)
			(type default)
		)
		(layer "In9.Cu")
	)
	(gr_line
		(start 369.49126 -16.773906)
		(end 369.711986 -16.708628)
		(stroke
			(width 0.05715)
			(type default)
		)
		(layer "In9.Cu")
	)
	(gr_line
		(start 369.515644 -28.086558)
		(end 369.585748 -28.039822)
		(stroke
			(width 0.05715)
			(type default)
		)
		(layer "In9.Cu")
	)
	(gr_line
		(start 369.551204 -8.243316)
		(end 369.598956 -8.154416)
		(stroke
			(width 0.05715)
			(type default)
		)
		(layer "In9.Cu")
	)
	(gr_line
		(start 369.598956 -8.154416)
		(end 369.697762 -8.134604)
		(stroke
			(width 0.05715)
			(type default)
		)
		(layer "In9.Cu")
	)
	(gr_line
		(start 369.631468 -45.435774)
		(end 369.682014 -45.394118)
		(stroke
			(width 0.05715)
			(type default)
		)
		(layer "In9.Cu")
	)
	(gr_line
		(start 369.64493 -14.453362)
		(end 369.656106 -14.432788)
		(stroke
			(width 0.05715)
			(type default)
		)
		(layer "In9.Cu")
	)
	(gr_line
		(start 369.656106 -14.432788)
		(end 369.674394 -14.41831)
		(stroke
			(width 0.05715)
			(type default)
		)
		(layer "In9.Cu")
	)
	(gr_line
		(start 369.65763 -38.515544)
		(end 369.662456 -38.492684)
		(stroke
			(width 0.05715)
			(type default)
		)
		(layer "In9.Cu")
	)
	(gr_line
		(start 369.657884 -38.470078)
		(end 369.662456 -38.492684)
		(stroke
			(width 0.05715)
			(type default)
		)
		(layer "In9.Cu")
	)
	(gr_line
		(start 369.673632 -12.16914)
		(end 369.943634 -11.957558)
		(stroke
			(width 0.05715)
			(type default)
		)
		(layer "In9.Cu")
	)
	(gr_line
		(start 369.682014 -45.394118)
		(end 369.694968 -45.329602)
		(stroke
			(width 0.05715)
			(type default)
		)
		(layer "In9.Cu")
	)
	(gr_line
		(start 369.688618 -28.824682)
		(end 369.770914 -28.841192)
		(stroke
			(width 0.05715)
			(type default)
		)
		(layer "In9.Cu")
	)
	(gr_line
		(start 369.711986 -16.708628)
		(end 369.875562 -16.40713)
		(stroke
			(width 0.05715)
			(type default)
		)
		(layer "In9.Cu")
	)
	(gr_line
		(start 369.734084 -15.709646)
		(end 370.01958 -15.183358)
		(stroke
			(width 0.05715)
			(type default)
		)
		(layer "In9.Cu")
	)
	(gr_line
		(start 369.747292 -26.782014)
		(end 369.763294 -26.760932)
		(stroke
			(width 0.05715)
			(type default)
		)
		(layer "In9.Cu")
	)
	(gr_line
		(start 369.763294 -26.760932)
		(end 369.769136 -26.73477)
		(stroke
			(width 0.05715)
			(type default)
		)
		(layer "In9.Cu")
	)
	(gr_line
		(start 369.770914 -28.841192)
		(end 369.81765 -28.911042)
		(stroke
			(width 0.05715)
			(type default)
		)
		(layer "In9.Cu")
	)
	(gr_line
		(start 369.772946 -30.245304)
		(end 369.78463 -30.227524)
		(stroke
			(width 0.05715)
			(type default)
		)
		(layer "In9.Cu")
	)
	(gr_line
		(start 369.777772 -28.376372)
		(end 369.860576 -28.392882)
		(stroke
			(width 0.05715)
			(type default)
		)
		(layer "In9.Cu")
	)
	(gr_line
		(start 369.78463 -30.227524)
		(end 369.78844 -30.207458)
		(stroke
			(width 0.05715)
			(type default)
		)
		(layer "In9.Cu")
	)
	(gr_line
		(start 369.810284 -16.186404)
		(end 369.875562 -16.40713)
		(stroke
			(width 0.05715)
			(type default)
		)
		(layer "In9.Cu")
	)
	(gr_line
		(start 369.860576 -28.392882)
		(end 369.930426 -28.3464)
		(stroke
			(width 0.05715)
			(type default)
		)
		(layer "In9.Cu")
	)
	(gr_line
		(start 369.926616 -40.448992)
		(end 369.99545 -40.403018)
		(stroke
			(width 0.05715)
			(type default)
		)
		(layer "In9.Cu")
	)
	(gr_line
		(start 369.943634 -11.957558)
		(end 369.971066 -11.729212)
		(stroke
			(width 0.05715)
			(type default)
		)
		(layer "In9.Cu")
	)
	(gr_line
		(start 369.947952 -29.106876)
		(end 369.994688 -29.176726)
		(stroke
			(width 0.05715)
			(type default)
		)
		(layer "In9.Cu")
	)
	(gr_line
		(start 369.974876 -37.93109)
		(end 369.978686 -37.91204)
		(stroke
			(width 0.05715)
			(type default)
		)
		(layer "In9.Cu")
	)
	(gr_line
		(start 369.974876 -37.93109)
		(end 369.97894 -37.950902)
		(stroke
			(width 0.05715)
			(type default)
		)
		(layer "In9.Cu")
	)
	(gr_line
		(start 369.975892 -15.881096)
		(end 370.196618 -15.815564)
		(stroke
			(width 0.05715)
			(type default)
		)
		(layer "In9.Cu")
	)
	(gr_line
		(start 369.978178 -29.259276)
		(end 369.994688 -29.176726)
		(stroke
			(width 0.05715)
			(type default)
		)
		(layer "In9.Cu")
	)
	(gr_line
		(start 369.99545 -40.403018)
		(end 370.011706 -40.322246)
		(stroke
			(width 0.05715)
			(type default)
		)
		(layer "In9.Cu")
	)
	(gr_line
		(start 370.0907 -11.26109)
		(end 370.114576 -11.242548)
		(stroke
			(width 0.05715)
			(type default)
		)
		(layer "In9.Cu")
	)
	(gr_line
		(start 370.114576 -11.242548)
		(end 370.144294 -11.236198)
		(stroke
			(width 0.05715)
			(type default)
		)
		(layer "In9.Cu")
	)
	(gr_line
		(start 370.12626 -28.21559)
		(end 370.19611 -28.168854)
		(stroke
			(width 0.05715)
			(type default)
		)
		(layer "In9.Cu")
	)
	(gr_line
		(start 370.142516 -23.708868)
		(end 370.14658 -23.690834)
		(stroke
			(width 0.05715)
			(type default)
		)
		(layer "In9.Cu")
	)
	(gr_line
		(start 370.14658 -23.690834)
		(end 370.15674 -23.67534)
		(stroke
			(width 0.05715)
			(type default)
		)
		(layer "In9.Cu")
	)
	(gr_line
		(start 370.19611 -28.168854)
		(end 370.21262 -28.086558)
		(stroke
			(width 0.05715)
			(type default)
		)
		(layer "In9.Cu")
	)
	(gr_line
		(start 370.196618 -15.815564)
		(end 370.360194 -15.51432)
		(stroke
			(width 0.05715)
			(type default)
		)
		(layer "In9.Cu")
	)
	(gr_line
		(start 370.218208 -14.81709)
		(end 370.229384 -14.796516)
		(stroke
			(width 0.05715)
			(type default)
		)
		(layer "In9.Cu")
	)
	(gr_line
		(start 370.229384 -14.796516)
		(end 370.247672 -14.782038)
		(stroke
			(width 0.05715)
			(type default)
		)
		(layer "In9.Cu")
	)
	(gr_line
		(start 370.239036 -45.786548)
		(end 370.291106 -45.743368)
		(stroke
			(width 0.05715)
			(type default)
		)
		(layer "In9.Cu")
	)
	(gr_line
		(start 370.291106 -45.743368)
		(end 370.30406 -45.677582)
		(stroke
			(width 0.05715)
			(type default)
		)
		(layer "In9.Cu")
	)
	(gr_line
		(start 370.294916 -15.293594)
		(end 370.360194 -15.51432)
		(stroke
			(width 0.05715)
			(type default)
		)
		(layer "In9.Cu")
	)
	(gr_line
		(start 370.317776 -32.68472)
		(end 370.321586 -32.66567)
		(stroke
			(width 0.05715)
			(type default)
		)
		(layer "In9.Cu")
	)
	(gr_line
		(start 370.321586 -32.66567)
		(end 370.332254 -32.649668)
		(stroke
			(width 0.05715)
			(type default)
		)
		(layer "In9.Cu")
	)
	(gr_line
		(start 370.37772 -38.455854)
		(end 370.381784 -38.475666)
		(stroke
			(width 0.05715)
			(type default)
		)
		(layer "In9.Cu")
	)
	(gr_line
		(start 370.377974 -38.494716)
		(end 370.381784 -38.475666)
		(stroke
			(width 0.05715)
			(type default)
		)
		(layer "In9.Cu")
	)
	(gr_line
		(start 370.414042 -30.467808)
		(end 370.425218 -30.451044)
		(stroke
			(width 0.05715)
			(type default)
		)
		(layer "In9.Cu")
	)
	(gr_line
		(start 370.425218 -30.451044)
		(end 370.429282 -30.431232)
		(stroke
			(width 0.05715)
			(type default)
		)
		(layer "In9.Cu")
	)
	(gr_line
		(start 370.485162 -19.254216)
		(end 370.815362 -18.75917)
		(stroke
			(width 0.05715)
			(type default)
		)
		(layer "In9.Cu")
	)
	(gr_line
		(start 370.4971 -19.74596)
		(end 370.516404 -19.733768)
		(stroke
			(width 0.05715)
			(type default)
		)
		(layer "In9.Cu")
	)
	(gr_line
		(start 370.516404 -19.733768)
		(end 370.529358 -19.714464)
		(stroke
			(width 0.05715)
			(type default)
		)
		(layer "In9.Cu")
	)
	(gr_line
		(start 370.665502 -37.955728)
		(end 370.669312 -37.936678)
		(stroke
			(width 0.05715)
			(type default)
		)
		(layer "In9.Cu")
	)
	(gr_line
		(start 370.665502 -37.955728)
		(end 370.669566 -37.97554)
		(stroke
			(width 0.05715)
			(type default)
		)
		(layer "In9.Cu")
	)
	(gr_line
		(start 370.709952 -19.447764)
		(end 370.935504 -19.402552)
		(stroke
			(width 0.05715)
			(type default)
		)
		(layer "In9.Cu")
	)
	(gr_line
		(start 370.715032 -24.084788)
		(end 370.718842 -24.065738)
		(stroke
			(width 0.05715)
			(type default)
		)
		(layer "In9.Cu")
	)
	(gr_line
		(start 370.718842 -24.065738)
		(end 370.72951 -24.049482)
		(stroke
			(width 0.05715)
			(type default)
		)
		(layer "In9.Cu")
	)
	(gr_line
		(start 370.731796 -21.559266)
		(end 370.74983 -21.547074)
		(stroke
			(width 0.05715)
			(type default)
		)
		(layer "In9.Cu")
	)
	(gr_line
		(start 370.74983 -21.547074)
		(end 370.762022 -21.528786)
		(stroke
			(width 0.05715)
			(type default)
		)
		(layer "In9.Cu")
	)
	(gr_line
		(start 370.935504 -19.402552)
		(end 371.12575 -19.11731)
		(stroke
			(width 0.05715)
			(type default)
		)
		(layer "In9.Cu")
	)
	(gr_line
		(start 370.946426 -11.749278)
		(end 370.970556 -11.730482)
		(stroke
			(width 0.05715)
			(type default)
		)
		(layer "In9.Cu")
	)
	(gr_line
		(start 370.970556 -11.730482)
		(end 371.00002 -11.724132)
		(stroke
			(width 0.05715)
			(type default)
		)
		(layer "In9.Cu")
	)
	(gr_line
		(start 370.989352 -32.856932)
		(end 370.993162 -32.837882)
		(stroke
			(width 0.05715)
			(type default)
		)
		(layer "In9.Cu")
	)
	(gr_line
		(start 370.993162 -32.837882)
		(end 371.00383 -32.82188)
		(stroke
			(width 0.05715)
			(type default)
		)
		(layer "In9.Cu")
	)
	(gr_line
		(start 371.020594 -30.715204)
		(end 371.030246 -30.700472)
		(stroke
			(width 0.05715)
			(type default)
		)
		(layer "In9.Cu")
	)
	(gr_line
		(start 371.030246 -30.700472)
		(end 371.033802 -30.683708)
		(stroke
			(width 0.05715)
			(type default)
		)
		(layer "In9.Cu")
	)
	(gr_line
		(start 371.048534 -18.409412)
		(end 371.378988 -17.913604)
		(stroke
			(width 0.05715)
			(type default)
		)
		(layer "In9.Cu")
	)
	(gr_line
		(start 371.063012 -38.493446)
		(end 371.067076 -38.473634)
		(stroke
			(width 0.05715)
			(type default)
		)
		(layer "In9.Cu")
	)
	(gr_line
		(start 371.063266 -38.454584)
		(end 371.067076 -38.473634)
		(stroke
			(width 0.05715)
			(type default)
		)
		(layer "In9.Cu")
	)
	(gr_line
		(start 371.080792 -18.891758)
		(end 371.12575 -19.11731)
		(stroke
			(width 0.05715)
			(type default)
		)
		(layer "In9.Cu")
	)
	(gr_line
		(start 371.239288 -10.44575)
		(end 371.256814 -10.5283)
		(stroke
			(width 0.05715)
			(type default)
		)
		(layer "In9.Cu")
	)
	(gr_line
		(start 371.239288 -10.44575)
		(end 371.286024 -10.373868)
		(stroke
			(width 0.05715)
			(type default)
		)
		(layer "In9.Cu")
	)
	(gr_line
		(start 371.273578 -18.602452)
		(end 371.49913 -18.55724)
		(stroke
			(width 0.05715)
			(type default)
		)
		(layer "In9.Cu")
	)
	(gr_line
		(start 371.291358 -12.331192)
		(end 371.314726 -12.312904)
		(stroke
			(width 0.05715)
			(type default)
		)
		(layer "In9.Cu")
	)
	(gr_line
		(start 371.308122 -7.812532)
		(end 371.327172 -7.808722)
		(stroke
			(width 0.05715)
			(type default)
		)
		(layer "In9.Cu")
	)
	(gr_line
		(start 371.314726 -12.312904)
		(end 371.34419 -12.306554)
		(stroke
			(width 0.05715)
			(type default)
		)
		(layer "In9.Cu")
	)
	(gr_line
		(start 371.327172 -7.808722)
		(end 371.346222 -7.812532)
		(stroke
			(width 0.05715)
			(type default)
		)
		(layer "In9.Cu")
	)
	(gr_line
		(start 371.339618 -11.280394)
		(end 371.42039 -11.263122)
		(stroke
			(width 0.05715)
			(type default)
		)
		(layer "In9.Cu")
	)
	(gr_line
		(start 371.347238 -24.406098)
		(end 371.351302 -24.386286)
		(stroke
			(width 0.05715)
			(type default)
		)
		(layer "In9.Cu")
	)
	(gr_line
		(start 371.351302 -24.386286)
		(end 371.362478 -24.369268)
		(stroke
			(width 0.05715)
			(type default)
		)
		(layer "In9.Cu")
	)
	(gr_line
		(start 371.413786 -10.17778)
		(end 371.459506 -10.107676)
		(stroke
			(width 0.05715)
			(type default)
		)
		(layer "In9.Cu")
	)
	(gr_line
		(start 371.42039 -11.263122)
		(end 371.465602 -11.19378)
		(stroke
			(width 0.05715)
			(type default)
		)
		(layer "In9.Cu")
	)
	(gr_line
		(start 371.49913 -18.55724)
		(end 371.689376 -18.271998)
		(stroke
			(width 0.05715)
			(type default)
		)
		(layer "In9.Cu")
	)
	(gr_line
		(start 371.5512 -31.349188)
		(end 371.560852 -31.33471)
		(stroke
			(width 0.05715)
			(type default)
		)
		(layer "In9.Cu")
	)
	(gr_line
		(start 371.560852 -31.33471)
		(end 371.564408 -31.317946)
		(stroke
			(width 0.05715)
			(type default)
		)
		(layer "In9.Cu")
	)
	(gr_line
		(start 371.564154 -12.936728)
		(end 371.58803 -12.918186)
		(stroke
			(width 0.05715)
			(type default)
		)
		(layer "In9.Cu")
	)
	(gr_line
		(start 371.58803 -12.918186)
		(end 371.617494 -12.911836)
		(stroke
			(width 0.05715)
			(type default)
		)
		(layer "In9.Cu")
	)
	(gr_line
		(start 371.59438 -10.995152)
		(end 371.6401 -10.925048)
		(stroke
			(width 0.05715)
			(type default)
		)
		(layer "In9.Cu")
	)
	(gr_line
		(start 371.605556 -33.256728)
		(end 371.609366 -33.237678)
		(stroke
			(width 0.05715)
			(type default)
		)
		(layer "In9.Cu")
	)
	(gr_line
		(start 371.609366 -33.237678)
		(end 371.620034 -33.221422)
		(stroke
			(width 0.05715)
			(type default)
		)
		(layer "In9.Cu")
	)
	(gr_line
		(start 371.612668 -17.56283)
		(end 371.943122 -17.067022)
		(stroke
			(width 0.05715)
			(type default)
		)
		(layer "In9.Cu")
	)
	(gr_line
		(start 371.622574 -10.842244)
		(end 371.622574 -10.842498)
		(stroke
			(width 0.05715)
			(type default)
		)
		(layer "In9.Cu")
	)
	(gr_line
		(start 371.622574 -10.84199)
		(end 371.6401 -10.925048)
		(stroke
			(width 0.05715)
			(type default)
		)
		(layer "In9.Cu")
	)
	(gr_line
		(start 371.644418 -18.046446)
		(end 371.689376 -18.271998)
		(stroke
			(width 0.05715)
			(type default)
		)
		(layer "In9.Cu")
	)
	(gr_line
		(start 371.826028 -13.543026)
		(end 371.84965 -13.52423)
		(stroke
			(width 0.05715)
			(type default)
		)
		(layer "In9.Cu")
	)
	(gr_line
		(start 371.837204 -17.756886)
		(end 372.062756 -17.711928)
		(stroke
			(width 0.05715)
			(type default)
		)
		(layer "In9.Cu")
	)
	(gr_line
		(start 371.837966 -10.02665)
		(end 371.920008 -10.009124)
		(stroke
			(width 0.05715)
			(type default)
		)
		(layer "In9.Cu")
	)
	(gr_line
		(start 371.84965 -13.52423)
		(end 371.879368 -13.51788)
		(stroke
			(width 0.05715)
			(type default)
		)
		(layer "In9.Cu")
	)
	(gr_line
		(start 371.920008 -10.009124)
		(end 371.989604 -10.054336)
		(stroke
			(width 0.05715)
			(type default)
		)
		(layer "In9.Cu")
	)
	(gr_line
		(start 371.977412 -35.811714)
		(end 371.993922 -35.729418)
		(stroke
			(width 0.05715)
			(type default)
		)
		(layer "In9.Cu")
	)
	(gr_line
		(start 371.993922 -35.729418)
		(end 372.063264 -35.68319)
		(stroke
			(width 0.05715)
			(type default)
		)
		(layer "In9.Cu")
	)
	(gr_line
		(start 372.028466 -24.601678)
		(end 372.032022 -24.584914)
		(stroke
			(width 0.05715)
			(type default)
		)
		(layer "In9.Cu")
	)
	(gr_line
		(start 372.032022 -24.584914)
		(end 372.041674 -24.570182)
		(stroke
			(width 0.05715)
			(type default)
		)
		(layer "In9.Cu")
	)
	(gr_line
		(start 372.062756 -17.711928)
		(end 372.253002 -17.426686)
		(stroke
			(width 0.05715)
			(type default)
		)
		(layer "In9.Cu")
	)
	(gr_line
		(start 372.070122 -10.749026)
		(end 372.087394 -10.829798)
		(stroke
			(width 0.05715)
			(type default)
		)
		(layer "In9.Cu")
	)
	(gr_line
		(start 372.087394 -10.829798)
		(end 372.156736 -10.87501)
		(stroke
			(width 0.05715)
			(type default)
		)
		(layer "In9.Cu")
	)
	(gr_line
		(start 372.174516 -16.720058)
		(end 372.50751 -16.22044)
		(stroke
			(width 0.05715)
			(type default)
		)
		(layer "In9.Cu")
	)
	(gr_line
		(start 372.180612 -31.585154)
		(end 372.190264 -31.570676)
		(stroke
			(width 0.05715)
			(type default)
		)
		(layer "In9.Cu")
	)
	(gr_line
		(start 372.189502 -10.184384)
		(end 372.258336 -10.229088)
		(stroke
			(width 0.05715)
			(type default)
		)
		(layer "In9.Cu")
	)
	(gr_line
		(start 372.190264 -31.570676)
		(end 372.19382 -31.553912)
		(stroke
			(width 0.05715)
			(type default)
		)
		(layer "In9.Cu")
	)
	(gr_line
		(start 372.20779 -17.20088)
		(end 372.253002 -17.426686)
		(stroke
			(width 0.05715)
			(type default)
		)
		(layer "In9.Cu")
	)
	(gr_line
		(start 372.258336 -10.229088)
		(end 372.275608 -10.310114)
		(stroke
			(width 0.05715)
			(type default)
		)
		(layer "In9.Cu")
	)
	(gr_line
		(start 372.331996 -8.307578)
		(end 372.351046 -8.311388)
		(stroke
			(width 0.05715)
			(type default)
		)
		(layer "In9.Cu")
	)
	(gr_line
		(start 372.351046 -8.311388)
		(end 372.370096 -8.307578)
		(stroke
			(width 0.05715)
			(type default)
		)
		(layer "In9.Cu")
	)
	(gr_line
		(start 372.356634 -11.004804)
		(end 372.425468 -11.049508)
		(stroke
			(width 0.05715)
			(type default)
		)
		(layer "In9.Cu")
	)
	(gr_line
		(start 372.400576 -16.912082)
		(end 372.626382 -16.866616)
		(stroke
			(width 0.05715)
			(type default)
		)
		(layer "In9.Cu")
	)
	(gr_line
		(start 372.425468 -11.049508)
		(end 372.505478 -11.03249)
		(stroke
			(width 0.05715)
			(type default)
		)
		(layer "In9.Cu")
	)
	(gr_line
		(start 372.625112 -24.925274)
		(end 372.628668 -24.90851)
		(stroke
			(width 0.05715)
			(type default)
		)
		(layer "In9.Cu")
	)
	(gr_line
		(start 372.626382 -16.866616)
		(end 372.816628 -16.581374)
		(stroke
			(width 0.05715)
			(type default)
		)
		(layer "In9.Cu")
	)
	(gr_line
		(start 372.628668 -24.90851)
		(end 372.63832 -24.893778)
		(stroke
			(width 0.05715)
			(type default)
		)
		(layer "In9.Cu")
	)
	(gr_line
		(start 372.771416 -16.355568)
		(end 372.816628 -16.581374)
		(stroke
			(width 0.05715)
			(type default)
		)
		(layer "In9.Cu")
	)
	(gr_line
		(start 372.846092 -31.909512)
		(end 372.857014 -31.893002)
		(stroke
			(width 0.05715)
			(type default)
		)
		(layer "In9.Cu")
	)
	(gr_line
		(start 372.857014 -31.893002)
		(end 372.860824 -31.873952)
		(stroke
			(width 0.05715)
			(type default)
		)
		(layer "In9.Cu")
	)
	(gr_line
		(start 372.910608 -15.615666)
		(end 372.922292 -15.59814)
		(stroke
			(width 0.05715)
			(type default)
		)
		(layer "In9.Cu")
	)
	(gr_line
		(start 372.922292 -15.59814)
		(end 372.94058 -15.585948)
		(stroke
			(width 0.05715)
			(type default)
		)
		(layer "In9.Cu")
	)
	(gr_line
		(start 373.249698 -25.18283)
		(end 373.253254 -25.166066)
		(stroke
			(width 0.05715)
			(type default)
		)
		(layer "In9.Cu")
	)
	(gr_line
		(start 373.253254 -25.166066)
		(end 373.262906 -25.151334)
		(stroke
			(width 0.05715)
			(type default)
		)
		(layer "In9.Cu")
	)
	(gr_line
		(start 373.344186 -7.815072)
		(end 373.363236 -7.811262)
		(stroke
			(width 0.05715)
			(type default)
		)
		(layer "In9.Cu")
	)
	(gr_line
		(start 373.363236 -7.811262)
		(end 373.382286 -7.815072)
		(stroke
			(width 0.05715)
			(type default)
		)
		(layer "In9.Cu")
	)
	(gr_line
		(start 373.84101 -25.484074)
		(end 373.84482 -25.464008)
		(stroke
			(width 0.05715)
			(type default)
		)
		(layer "In9.Cu")
	)
	(gr_line
		(start 373.84482 -25.464008)
		(end 373.856504 -25.446482)
		(stroke
			(width 0.05715)
			(type default)
		)
		(layer "In9.Cu")
	)
	(gr_line
		(start 374.589802 -15.260828)
		(end 374.601994 -15.24254)
		(stroke
			(width 0.05715)
			(type default)
		)
		(layer "In9.Cu")
	)
	(gr_line
		(start 374.601994 -15.24254)
		(end 374.620282 -15.230348)
		(stroke
			(width 0.05715)
			(type default)
		)
		(layer "In9.Cu")
	)
	(gr_line
		(start 374.702832 -31.406592)
		(end 374.709182 -31.434532)
		(stroke
			(width 0.05715)
			(type default)
		)
		(layer "In9.Cu")
	)
	(gr_line
		(start 374.702832 -31.406592)
		(end 374.709182 -31.379414)
		(stroke
			(width 0.05715)
			(type default)
		)
		(layer "In9.Cu")
	)
	(gr_line
		(start 374.74906 -34.244026)
		(end 374.760744 -34.236406)
		(stroke
			(width 0.05715)
			(type default)
		)
		(layer "In9.Cu")
	)
	(gr_line
		(start 374.760744 -34.236406)
		(end 374.76938 -34.224468)
		(stroke
			(width 0.05715)
			(type default)
		)
		(layer "In9.Cu")
	)
	(gr_line
		(start 374.780556 -8.392668)
		(end 374.803416 -8.39724)
		(stroke
			(width 0.05715)
			(type default)
		)
		(layer "In9.Cu")
	)
	(gr_line
		(start 374.803416 -8.39724)
		(end 374.826022 -8.392414)
		(stroke
			(width 0.05715)
			(type default)
		)
		(layer "In9.Cu")
	)
	(gr_line
		(start 375.018808 -26.792428)
		(end 375.025412 -26.822654)
		(stroke
			(width 0.05715)
			(type default)
		)
		(layer "In9.Cu")
	)
	(gr_line
		(start 375.018808 -26.792428)
		(end 375.026936 -26.761694)
		(stroke
			(width 0.05715)
			(type default)
		)
		(layer "In9.Cu")
	)
	(gr_line
		(start 375.026682 -26.761948)
		(end 375.026936 -26.760932)
		(stroke
			(width 0.05715)
			(type default)
		)
		(layer "In9.Cu")
	)
	(gr_line
		(start 375.379742 -33.374838)
		(end 375.435622 -33.297114)
		(stroke
			(width 0.05715)
			(type default)
		)
		(layer "In9.Cu")
	)
	(gr_line
		(start 375.414286 -33.204404)
		(end 375.435622 -33.297114)
		(stroke
			(width 0.05715)
			(type default)
		)
		(layer "In9.Cu")
	)
	(gr_line
		(start 375.426732 -15.769336)
		(end 375.438924 -15.751048)
		(stroke
			(width 0.05715)
			(type default)
		)
		(layer "In9.Cu")
	)
	(gr_line
		(start 375.438924 -15.751048)
		(end 375.457212 -15.738856)
		(stroke
			(width 0.05715)
			(type default)
		)
		(layer "In9.Cu")
	)
	(gr_line
		(start 375.675652 -28.535376)
		(end 375.682002 -28.508198)
		(stroke
			(width 0.05715)
			(type default)
		)
		(layer "In9.Cu")
	)
	(gr_line
		(start 375.67616 -28.480766)
		(end 375.682002 -28.508198)
		(stroke
			(width 0.05715)
			(type default)
		)
		(layer "In9.Cu")
	)
	(gr_line
		(start 375.845578 -23.645622)
		(end 375.848626 -23.634192)
		(stroke
			(width 0.05715)
			(type default)
		)
		(layer "In9.Cu")
	)
	(gr_line
		(start 375.848626 -23.634192)
		(end 375.85523 -23.624286)
		(stroke
			(width 0.05715)
			(type default)
		)
		(layer "In9.Cu")
	)
	(gr_line
		(start 375.89968 -16.292576)
		(end 375.911872 -16.274288)
		(stroke
			(width 0.05715)
			(type default)
		)
		(layer "In9.Cu")
	)
	(gr_line
		(start 375.911872 -16.274288)
		(end 375.929906 -16.262096)
		(stroke
			(width 0.05715)
			(type default)
		)
		(layer "In9.Cu")
	)
	(gr_line
		(start 375.995438 -7.845044)
		(end 376.018552 -7.839964)
		(stroke
			(width 0.05715)
			(type default)
		)
		(layer "In9.Cu")
	)
	(gr_line
		(start 376.018552 -7.839964)
		(end 376.041666 -7.845044)
		(stroke
			(width 0.05715)
			(type default)
		)
		(layer "In9.Cu")
	)
	(gr_line
		(start 376.467878 -16.709136)
		(end 376.48007 -16.691102)
		(stroke
			(width 0.05715)
			(type default)
		)
		(layer "In9.Cu")
	)
	(gr_line
		(start 376.48007 -16.691102)
		(end 376.498104 -16.67891)
		(stroke
			(width 0.05715)
			(type default)
		)
		(layer "In9.Cu")
	)
	(gr_line
		(start 376.490484 -13.219176)
		(end 376.506486 -13.208508)
		(stroke
			(width 0.05715)
			(type default)
		)
		(layer "In9.Cu")
	)
	(gr_line
		(start 376.506486 -13.208508)
		(end 376.525282 -13.204444)
		(stroke
			(width 0.05715)
			(type default)
		)
		(layer "In9.Cu")
	)
	(gr_line
		(start 376.74169 -13.815568)
		(end 376.757692 -13.8049)
		(stroke
			(width 0.05715)
			(type default)
		)
		(layer "In9.Cu")
	)
	(gr_line
		(start 376.757692 -13.8049)
		(end 376.776488 -13.800836)
		(stroke
			(width 0.05715)
			(type default)
		)
		(layer "In9.Cu")
	)
	(gr_line
		(start 376.9868 -17.150842)
		(end 376.998992 -17.132554)
		(stroke
			(width 0.05715)
			(type default)
		)
		(layer "In9.Cu")
	)
	(gr_line
		(start 376.998992 -17.132554)
		(end 377.01728 -17.120362)
		(stroke
			(width 0.05715)
			(type default)
		)
		(layer "In9.Cu")
	)
	(gr_line
		(start 377.202446 -8.389874)
		(end 377.22556 -8.394954)
		(stroke
			(width 0.05715)
			(type default)
		)
		(layer "In9.Cu")
	)
	(gr_line
		(start 377.22556 -8.394954)
		(end 377.248674 -8.389874)
		(stroke
			(width 0.05715)
			(type default)
		)
		(layer "In9.Cu")
	)
	(gr_line
		(start 377.257056 -14.538706)
		(end 377.273058 -14.528038)
		(stroke
			(width 0.05715)
			(type default)
		)
		(layer "In9.Cu")
	)
	(gr_line
		(start 377.273058 -14.528038)
		(end 377.291854 -14.523974)
		(stroke
			(width 0.05715)
			(type default)
		)
		(layer "In9.Cu")
	)
	(gr_line
		(start 377.519438 -19.961098)
		(end 377.542552 -19.926554)
		(stroke
			(width 0.05715)
			(type default)
		)
		(layer "In9.Cu")
	)
	(gr_line
		(start 377.525026 -17.562576)
		(end 377.537218 -17.544288)
		(stroke
			(width 0.05715)
			(type default)
		)
		(layer "In9.Cu")
	)
	(gr_line
		(start 377.537218 -17.544288)
		(end 377.555252 -17.532096)
		(stroke
			(width 0.05715)
			(type default)
		)
		(layer "In9.Cu")
	)
	(gr_line
		(start 377.542552 -19.926554)
		(end 377.580144 -19.908266)
		(stroke
			(width 0.05715)
			(type default)
		)
		(layer "In9.Cu")
	)
	(gr_line
		(start 377.617482 -15.137384)
		(end 377.632214 -15.127732)
		(stroke
			(width 0.05715)
			(type default)
		)
		(layer "In9.Cu")
	)
	(gr_line
		(start 377.632214 -15.127732)
		(end 377.64847 -15.12443)
		(stroke
			(width 0.05715)
			(type default)
		)
		(layer "In9.Cu")
	)
	(gr_line
		(start 377.923298 -20.5232)
		(end 377.947174 -20.487386)
		(stroke
			(width 0.05715)
			(type default)
		)
		(layer "In9.Cu")
	)
	(gr_line
		(start 377.939554 -15.718282)
		(end 377.954286 -15.70863)
		(stroke
			(width 0.05715)
			(type default)
		)
		(layer "In9.Cu")
	)
	(gr_line
		(start 377.947174 -20.487386)
		(end 377.985782 -20.46859)
		(stroke
			(width 0.05715)
			(type default)
		)
		(layer "In9.Cu")
	)
	(gr_line
		(start 377.954286 -15.70863)
		(end 377.970542 -15.705328)
		(stroke
			(width 0.05715)
			(type default)
		)
		(layer "In9.Cu")
	)
	(gr_line
		(start 377.982226 -18.070068)
		(end 377.994418 -18.052034)
		(stroke
			(width 0.05715)
			(type default)
		)
		(layer "In9.Cu")
	)
	(gr_line
		(start 377.994418 -18.052034)
		(end 378.012452 -18.039842)
		(stroke
			(width 0.05715)
			(type default)
		)
		(layer "In9.Cu")
	)
	(gr_line
		(start 378.071888 -16.41729)
		(end 378.08662 -16.407638)
		(stroke
			(width 0.05715)
			(type default)
		)
		(layer "In9.Cu")
	)
	(gr_line
		(start 378.08662 -16.407638)
		(end 378.103384 -16.404082)
		(stroke
			(width 0.05715)
			(type default)
		)
		(layer "In9.Cu")
	)
	(gr_line
		(start 378.122942 -17.15389)
		(end 378.137674 -17.144238)
		(stroke
			(width 0.05715)
			(type default)
		)
		(layer "In9.Cu")
	)
	(gr_line
		(start 378.137674 -17.144238)
		(end 378.154438 -17.140682)
		(stroke
			(width 0.05715)
			(type default)
		)
		(layer "In9.Cu")
	)
	(gr_line
		(start 378.381006 -17.794224)
		(end 378.397262 -17.783556)
		(stroke
			(width 0.05715)
			(type default)
		)
		(layer "In9.Cu")
	)
	(gr_line
		(start 378.397262 -17.783556)
		(end 378.416058 -17.779492)
		(stroke
			(width 0.05715)
			(type default)
		)
		(layer "In9.Cu")
	)
	(gr_line
		(start 379.307598 -15.420848)
		(end 379.330712 -15.415768)
		(stroke
			(width 0.05715)
			(type default)
		)
		(layer "In9.Cu")
	)
	(gr_line
		(start 379.330712 -15.415768)
		(end 379.353826 -15.420848)
		(stroke
			(width 0.05715)
			(type default)
		)
		(layer "In9.Cu")
	)
	(gr_line
		(start 379.35281 -16.138652)
		(end 379.375924 -16.133572)
		(stroke
			(width 0.05715)
			(type default)
		)
		(layer "In9.Cu")
	)
	(gr_line
		(start 379.375924 -16.133572)
		(end 379.399038 -16.138652)
		(stroke
			(width 0.05715)
			(type default)
		)
		(layer "In9.Cu")
	)
	(gr_line
		(start 379.400562 -14.751558)
		(end 379.423676 -14.746478)
		(stroke
			(width 0.05715)
			(type default)
		)
		(layer "In9.Cu")
	)
	(gr_line
		(start 379.40742 -11.255756)
		(end 379.431296 -11.250676)
		(stroke
			(width 0.05715)
			(type default)
		)
		(layer "In9.Cu")
	)
	(gr_line
		(start 379.41758 -9.266174)
		(end 379.440694 -9.261094)
		(stroke
			(width 0.05715)
			(type default)
		)
		(layer "In9.Cu")
	)
	(gr_line
		(start 379.423676 -14.746478)
		(end 379.44679 -14.751558)
		(stroke
			(width 0.05715)
			(type default)
		)
		(layer "In9.Cu")
	)
	(gr_line
		(start 379.431042 -11.913362)
		(end 379.454156 -11.908282)
		(stroke
			(width 0.05715)
			(type default)
		)
		(layer "In9.Cu")
	)
	(gr_line
		(start 379.431296 -11.250676)
		(end 379.431804 -11.250676)
		(stroke
			(width 0.05715)
			(type default)
		)
		(layer "In9.Cu")
	)
	(gr_line
		(start 379.431804 -11.250676)
		(end 379.454918 -11.255756)
		(stroke
			(width 0.05715)
			(type default)
		)
		(layer "In9.Cu")
	)
	(gr_line
		(start 379.432566 -13.237718)
		(end 379.45568 -13.232638)
		(stroke
			(width 0.05715)
			(type default)
		)
		(layer "In9.Cu")
	)
	(gr_line
		(start 379.440694 -9.261094)
		(end 379.463808 -9.266174)
		(stroke
			(width 0.05715)
			(type default)
		)
		(layer "In9.Cu")
	)
	(gr_line
		(start 379.447806 -10.585704)
		(end 379.47092 -10.580624)
		(stroke
			(width 0.05715)
			(type default)
		)
		(layer "In9.Cu")
	)
	(gr_line
		(start 379.454156 -11.908282)
		(end 379.47727 -11.913362)
		(stroke
			(width 0.05715)
			(type default)
		)
		(layer "In9.Cu")
	)
	(gr_line
		(start 379.45568 -13.232638)
		(end 379.478794 -13.237718)
		(stroke
			(width 0.05715)
			(type default)
		)
		(layer "In9.Cu")
	)
	(gr_line
		(start 379.459236 -9.927844)
		(end 379.48235 -9.922764)
		(stroke
			(width 0.05715)
			(type default)
		)
		(layer "In9.Cu")
	)
	(gr_line
		(start 379.460506 -12.582144)
		(end 379.48362 -12.577064)
		(stroke
			(width 0.05715)
			(type default)
		)
		(layer "In9.Cu")
	)
	(gr_line
		(start 379.462792 -14.063218)
		(end 379.485906 -14.058138)
		(stroke
			(width 0.05715)
			(type default)
		)
		(layer "In9.Cu")
	)
	(gr_line
		(start 379.47092 -10.580624)
		(end 379.494034 -10.585704)
		(stroke
			(width 0.05715)
			(type default)
		)
		(layer "In9.Cu")
	)
	(gr_line
		(start 379.472444 -16.86052)
		(end 379.495558 -16.85544)
		(stroke
			(width 0.05715)
			(type default)
		)
		(layer "In9.Cu")
	)
	(gr_line
		(start 379.477524 -17.554448)
		(end 379.500638 -17.549368)
		(stroke
			(width 0.05715)
			(type default)
		)
		(layer "In9.Cu")
	)
	(gr_line
		(start 379.48235 -9.922764)
		(end 379.505464 -9.927844)
		(stroke
			(width 0.05715)
			(type default)
		)
		(layer "In9.Cu")
	)
	(gr_line
		(start 379.48362 -12.577064)
		(end 379.506734 -12.582144)
		(stroke
			(width 0.05715)
			(type default)
		)
		(layer "In9.Cu")
	)
	(gr_line
		(start 379.485906 -14.058138)
		(end 379.50902 -14.063218)
		(stroke
			(width 0.05715)
			(type default)
		)
		(layer "In9.Cu")
	)
	(gr_line
		(start 379.495558 -16.85544)
		(end 379.518672 -16.86052)
		(stroke
			(width 0.05715)
			(type default)
		)
		(layer "In9.Cu")
	)
	(gr_line
		(start 379.500638 -17.549368)
		(end 379.523752 -17.554448)
		(stroke
			(width 0.05715)
			(type default)
		)
		(layer "In9.Cu")
	)
	(gr_line
		(start 379.822202 -17.916144)
		(end 379.845316 -17.921224)
		(stroke
			(width 0.05715)
			(type default)
		)
		(layer "In9.Cu")
	)
	(gr_line
		(start 379.82779 -7.842758)
		(end 379.846586 -7.838694)
		(stroke
			(width 0.05715)
			(type default)
		)
		(layer "In9.Cu")
	)
	(gr_line
		(start 379.845316 -17.921224)
		(end 379.86843 -17.916144)
		(stroke
			(width 0.05715)
			(type default)
		)
		(layer "In9.Cu")
	)
	(gr_line
		(start 379.846586 -7.838694)
		(end 379.862588 -7.828026)
		(stroke
			(width 0.05715)
			(type default)
		)
		(layer "In9.Cu")
	)
	(gr_line
		(start 379.881892 -17.236186)
		(end 379.905006 -17.241266)
		(stroke
			(width 0.05715)
			(type default)
		)
		(layer "In9.Cu")
	)
	(gr_line
		(start 379.905006 -17.241266)
		(end 379.92812 -17.236186)
		(stroke
			(width 0.05715)
			(type default)
		)
		(layer "In9.Cu")
	)
	(gr_line
		(start 379.94209 -16.552418)
		(end 379.965204 -16.557498)
		(stroke
			(width 0.05715)
			(type default)
		)
		(layer "In9.Cu")
	)
	(gr_line
		(start 379.965204 -16.557498)
		(end 379.988318 -16.552418)
		(stroke
			(width 0.05715)
			(type default)
		)
		(layer "In9.Cu")
	)
	(gr_line
		(start 380.07163 -15.871952)
		(end 380.094744 -15.877032)
		(stroke
			(width 0.05715)
			(type default)
		)
		(layer "In9.Cu")
	)
	(gr_line
		(start 380.094744 -15.877032)
		(end 380.117858 -15.871952)
		(stroke
			(width 0.05715)
			(type default)
		)
		(layer "In9.Cu")
	)
	(gr_line
		(start 380.130304 -15.19555)
		(end 380.15291 -15.200376)
		(stroke
			(width 0.05715)
			(type default)
		)
		(layer "In9.Cu")
	)
	(gr_line
		(start 380.15291 -15.200376)
		(end 380.176278 -15.195296)
		(stroke
			(width 0.05715)
			(type default)
		)
		(layer "In9.Cu")
	)
	(gr_line
		(start 380.247652 -14.518386)
		(end 380.270258 -14.523212)
		(stroke
			(width 0.05715)
			(type default)
		)
		(layer "In9.Cu")
	)
	(gr_line
		(start 380.257812 -13.701522)
		(end 380.280926 -13.706602)
		(stroke
			(width 0.05715)
			(type default)
		)
		(layer "In9.Cu")
	)
	(gr_line
		(start 380.270258 -14.523212)
		(end 380.29388 -14.518132)
		(stroke
			(width 0.05715)
			(type default)
		)
		(layer "In9.Cu")
	)
	(gr_line
		(start 380.279148 -13.044678)
		(end 380.302516 -13.049758)
		(stroke
			(width 0.05715)
			(type default)
		)
		(layer "In9.Cu")
	)
	(gr_line
		(start 380.280164 -9.737852)
		(end 380.303278 -9.742932)
		(stroke
			(width 0.05715)
			(type default)
		)
		(layer "In9.Cu")
	)
	(gr_line
		(start 380.280926 -13.706602)
		(end 380.30404 -13.701522)
		(stroke
			(width 0.05715)
			(type default)
		)
		(layer "In9.Cu")
	)
	(gr_line
		(start 380.289308 -11.731498)
		(end 380.312422 -11.736578)
		(stroke
			(width 0.05715)
			(type default)
		)
		(layer "In9.Cu")
	)
	(gr_line
		(start 380.294642 -12.385294)
		(end 380.317756 -12.390374)
		(stroke
			(width 0.05715)
			(type default)
		)
		(layer "In9.Cu")
	)
	(gr_line
		(start 380.302516 -13.049758)
		(end 380.325122 -13.044932)
		(stroke
			(width 0.05715)
			(type default)
		)
		(layer "In9.Cu")
	)
	(gr_line
		(start 380.303278 -9.742932)
		(end 380.326392 -9.737852)
		(stroke
			(width 0.05715)
			(type default)
		)
		(layer "In9.Cu")
	)
	(gr_line
		(start 380.312422 -11.736578)
		(end 380.335536 -11.731498)
		(stroke
			(width 0.05715)
			(type default)
		)
		(layer "In9.Cu")
	)
	(gr_line
		(start 380.317756 -12.390374)
		(end 380.34087 -12.385294)
		(stroke
			(width 0.05715)
			(type default)
		)
		(layer "In9.Cu")
	)
	(gr_line
		(start 380.332488 -11.062208)
		(end 380.355602 -11.067288)
		(stroke
			(width 0.05715)
			(type default)
		)
		(layer "In9.Cu")
	)
	(gr_line
		(start 380.332996 -10.401808)
		(end 380.35611 -10.406888)
		(stroke
			(width 0.05715)
			(type default)
		)
		(layer "In9.Cu")
	)
	(gr_line
		(start 380.355602 -11.067288)
		(end 380.378716 -11.062208)
		(stroke
			(width 0.05715)
			(type default)
		)
		(layer "In9.Cu")
	)
	(gr_line
		(start 380.35611 -10.406888)
		(end 380.379224 -10.401808)
		(stroke
			(width 0.05715)
			(type default)
		)
		(layer "In9.Cu")
	)
	(gr_line
		(start 380.454408 -18.172938)
		(end 380.472696 -18.160238)
		(stroke
			(width 0.05715)
			(type default)
		)
		(layer "In9.Cu")
	)
	(gr_line
		(start 380.472696 -18.160238)
		(end 380.494032 -18.155666)
		(stroke
			(width 0.05715)
			(type default)
		)
		(layer "In9.Cu")
	)
	(gr_line
		(start 380.77013 -18.768314)
		(end 380.788418 -18.755614)
		(stroke
			(width 0.05715)
			(type default)
		)
		(layer "In9.Cu")
	)
	(gr_line
		(start 380.788418 -18.755614)
		(end 380.809754 -18.751042)
		(stroke
			(width 0.05715)
			(type default)
		)
		(layer "In9.Cu")
	)
	(gr_line
		(start 383.1336 -124.3076)
		(end 383.1336 -124.329698)
		(stroke
			(width 0.04445)
			(type default)
		)
		(layer "In9.Cu")
	)
	(gr_line
		(start 383.1336 -124.3076)
		(end 383.143252 -124.297948)
		(stroke
			(width 0.04445)
			(type default)
		)
		(layer "In9.Cu")
	)
	(gr_line
		(start 383.14503 -124.29617)
		(end 383.1844 -124.2568)
		(stroke
			(width 0.04445)
			(type default)
		)
		(layer "In9.Cu")
	)
	(gr_line
		(start 383.3749 -124.2568)
		(end 383.41427 -124.29617)
		(stroke
			(width 0.04445)
			(type default)
		)
		(layer "In9.Cu")
	)
	(gr_line
		(start 383.416048 -124.297948)
		(end 383.4257 -124.3076)
		(stroke
			(width 0.04445)
			(type default)
		)
		(layer "In9.Cu")
	)
	(gr_line
		(start 383.4257 -124.3076)
		(end 383.4257 -124.329698)
		(stroke
			(width 0.04445)
			(type default)
		)
		(layer "In9.Cu")
	)
	(gr_line
		(start 384.12928 -4.632198)
		(end 384.629152 -4.29895)
		(stroke
			(width 0.05715)
			(type default)
		)
		(layer "In9.Cu")
	)
	(gr_line
		(start 384.264408 -4.896104)
		(end 384.490214 -4.941316)
		(stroke
			(width 0.05715)
			(type default)
		)
		(layer "In9.Cu")
	)
	(gr_line
		(start 384.27025 -121.245884)
		(end 384.535172 -121.245884)
		(stroke
			(width 0.04445)
			(type default)
		)
		(layer "In9.Cu")
	)
	(gr_line
		(start 384.470148 -123.309634)
		(end 384.470402 -123.309634)
		(stroke
			(width 0.04445)
			(type default)
		)
		(layer "In9.Cu")
	)
	(gr_line
		(start 384.490214 -4.941316)
		(end 384.775456 -4.75107)
		(stroke
			(width 0.05715)
			(type default)
		)
		(layer "In9.Cu")
	)
	(gr_arc
		(start 384.66014 -121.2977)
		(mid 384.602812 -121.259352)
		(end 384.535172 -121.245884)
		(stroke
			(width 0.04445)
			(type default)
		)
		(layer "In9.Cu")
	)
	(gr_line
		(start 384.66014 -121.2977)
		(end 384.666236 -121.303796)
		(stroke
			(width 0.04445)
			(type default)
		)
		(layer "In9.Cu")
	)
	(gr_line
		(start 384.775456 -4.75107)
		(end 384.820922 -4.525264)
		(stroke
			(width 0.05715)
			(type default)
		)
		(layer "In9.Cu")
	)
	(gr_line
		(start 384.857752 -121.310908)
		(end 384.863848 -121.304812)
		(stroke
			(width 0.04445)
			(type default)
		)
		(layer "In9.Cu")
	)
	(gr_line
		(start 384.974084 -4.068826)
		(end 385.47548 -3.734562)
		(stroke
			(width 0.05715)
			(type default)
		)
		(layer "In9.Cu")
	)
	(gr_arc
		(start 385.006088 -121.245884)
		(mid 384.929104 -121.261198)
		(end 384.863848 -121.304812)
		(stroke
			(width 0.04445)
			(type default)
		)
		(layer "In9.Cu")
	)
	(gr_line
		(start 385.006088 -121.245884)
		(end 385.26085 -121.245884)
		(stroke
			(width 0.04445)
			(type default)
		)
		(layer "In9.Cu")
	)
	(gr_line
		(start 385.106164 -126.703582)
		(end 385.106164 -126.72568)
		(stroke
			(width 0.04445)
			(type default)
		)
		(layer "In9.Cu")
	)
	(gr_line
		(start 385.106164 -126.703582)
		(end 385.115816 -126.69393)
		(stroke
			(width 0.04445)
			(type default)
		)
		(layer "In9.Cu")
	)
	(gr_line
		(start 385.10972 -4.332478)
		(end 385.335526 -4.37769)
		(stroke
			(width 0.05715)
			(type default)
		)
		(layer "In9.Cu")
	)
	(gr_line
		(start 385.117594 -126.692152)
		(end 385.156964 -126.652782)
		(stroke
			(width 0.04445)
			(type default)
		)
		(layer "In9.Cu")
	)
	(gr_arc
		(start 385.1656 -123.799854)
		(mid 385.165586 -123.803791)
		(end 385.1656 -123.807728)
		(stroke
			(width 0.04445)
			(type default)
		)
		(layer "In9.Cu")
	)
	(gr_line
		(start 385.335526 -4.37769)
		(end 385.620768 -4.187444)
		(stroke
			(width 0.05715)
			(type default)
		)
		(layer "In9.Cu")
	)
	(gr_line
		(start 385.347464 -126.652782)
		(end 385.386834 -126.692152)
		(stroke
			(width 0.04445)
			(type default)
		)
		(layer "In9.Cu")
	)
	(gr_line
		(start 385.388612 -126.69393)
		(end 385.398264 -126.703582)
		(stroke
			(width 0.04445)
			(type default)
		)
		(layer "In9.Cu")
	)
	(gr_line
		(start 385.398264 -126.703582)
		(end 385.398264 -126.72568)
		(stroke
			(width 0.04445)
			(type default)
		)
		(layer "In9.Cu")
	)
	(gr_line
		(start 385.620768 -4.187444)
		(end 385.666234 -3.961638)
		(stroke
			(width 0.05715)
			(type default)
		)
		(layer "In9.Cu")
	)
	(gr_line
		(start 385.81838 -3.505708)
		(end 386.320538 -3.170936)
		(stroke
			(width 0.05715)
			(type default)
		)
		(layer "In9.Cu")
	)
	(gr_line
		(start 385.901184 -126.81331)
		(end 385.901184 -126.835408)
		(stroke
			(width 0.04445)
			(type default)
		)
		(layer "In9.Cu")
	)
	(gr_line
		(start 385.901184 -126.81331)
		(end 385.910836 -126.803658)
		(stroke
			(width 0.04445)
			(type default)
		)
		(layer "In9.Cu")
	)
	(gr_line
		(start 385.912614 -126.80188)
		(end 385.951984 -126.76251)
		(stroke
			(width 0.04445)
			(type default)
		)
		(layer "In9.Cu")
	)
	(gr_line
		(start 385.955286 -3.769106)
		(end 386.180838 -3.814064)
		(stroke
			(width 0.05715)
			(type default)
		)
		(layer "In9.Cu")
	)
	(gr_line
		(start 386.142484 -126.76251)
		(end 386.181854 -126.80188)
		(stroke
			(width 0.04445)
			(type default)
		)
		(layer "In9.Cu")
	)
	(gr_line
		(start 386.155184 0.850646)
		(end 386.372862 0.850646)
		(stroke
			(width 0.050546)
			(type default)
		)
		(layer "In9.Cu")
	)
	(gr_line
		(start 386.180838 -3.814064)
		(end 386.46608 -3.623818)
		(stroke
			(width 0.05715)
			(type default)
		)
		(layer "In9.Cu")
	)
	(gr_line
		(start 386.183632 -126.803658)
		(end 386.193284 -126.81331)
		(stroke
			(width 0.04445)
			(type default)
		)
		(layer "In9.Cu")
	)
	(gr_line
		(start 386.193284 -126.81331)
		(end 386.193284 -126.835408)
		(stroke
			(width 0.04445)
			(type default)
		)
		(layer "In9.Cu")
	)
	(gr_line
		(start 386.25145 -122.962924)
		(end 386.506212 -122.962924)
		(stroke
			(width 0.04445)
			(type default)
		)
		(layer "In9.Cu")
	)
	(gr_arc
		(start 386.381498 -132.221986)
		(mid 386.462482 -132.27068)
		(end 386.556504 -132.280152)
		(stroke
			(width 0.05715)
			(type default)
		)
		(layer "In9.Cu")
	)
	(gr_line
		(start 386.383022 -132.637022)
		(end 386.675884 -132.929884)
		(stroke
			(width 0.05715)
			(type default)
		)
		(layer "In9.Cu")
	)
	(gr_line
		(start 386.46608 -3.623818)
		(end 386.511292 -3.398266)
		(stroke
			(width 0.05715)
			(type default)
		)
		(layer "In9.Cu")
	)
	(gr_line
		(start 386.571998 1.2446)
		(end 386.908802 1.2446)
		(stroke
			(width 0.050546)
			(type default)
		)
		(layer "In9.Cu")
	)
	(gr_arc
		(start 386.648452 -123.021852)
		(mid 386.583198 -122.978223)
		(end 386.506212 -122.962924)
		(stroke
			(width 0.04445)
			(type default)
		)
		(layer "In9.Cu")
	)
	(gr_line
		(start 386.648452 -123.021852)
		(end 386.654548 -123.027948)
		(stroke
			(width 0.04445)
			(type default)
		)
		(layer "In9.Cu")
	)
	(gr_line
		(start 386.664708 -2.941574)
		(end 387.16458 -2.608326)
		(stroke
			(width 0.05715)
			(type default)
		)
		(layer "In9.Cu")
	)
	(gr_arc
		(start 386.714238 -121.514108)
		(mid 387.0064 -121.435598)
		(end 387.24205 -121.245884)
		(stroke
			(width 0.04445)
			(type default)
		)
		(layer "In9.Cu")
	)
	(gr_arc
		(start 386.73151 -132.338572)
		(mid 386.650563 -132.289713)
		(end 386.556504 -132.280152)
		(stroke
			(width 0.05715)
			(type default)
		)
		(layer "In9.Cu")
	)
	(gr_line
		(start 386.73151 -132.338572)
		(end 386.97408 -132.581142)
		(stroke
			(width 0.05715)
			(type default)
		)
		(layer "In9.Cu")
	)
	(gr_line
		(start 386.74675 -122.104404)
		(end 386.77469 -122.115072)
		(stroke
			(width 0.04445)
			(type default)
		)
		(layer "In9.Cu")
	)
	(gr_line
		(start 386.755894 -125.573028)
		(end 386.755894 -125.987048)
		(stroke
			(width 0.05715)
			(type default)
		)
		(layer "In9.Cu")
	)
	(gr_line
		(start 386.755894 -124.84862)
		(end 386.755894 -124.870718)
		(stroke
			(width 0.04445)
			(type default)
		)
		(layer "In9.Cu")
	)
	(gr_line
		(start 386.755894 -124.84862)
		(end 386.759958 -124.844556)
		(stroke
			(width 0.04445)
			(type default)
		)
		(layer "In9.Cu")
	)
	(gr_line
		(start 386.761736 -124.842778)
		(end 386.806694 -124.79782)
		(stroke
			(width 0.04445)
			(type default)
		)
		(layer "In9.Cu")
	)
	(gr_arc
		(start 386.77469 -122.115072)
		(mid 386.928608 -122.110235)
		(end 387.034024 -121.997978)
		(stroke
			(width 0.04445)
			(type default)
		)
		(layer "In9.Cu")
	)
	(gr_line
		(start 386.800598 -3.20548)
		(end 387.02615 -3.250438)
		(stroke
			(width 0.05715)
			(type default)
		)
		(layer "In9.Cu")
	)
	(gr_line
		(start 386.846064 -123.020836)
		(end 386.85216 -123.01474)
		(stroke
			(width 0.04445)
			(type default)
		)
		(layer "In9.Cu")
	)
	(gr_arc
		(start 386.977128 -122.962924)
		(mid 386.90949 -122.976396)
		(end 386.85216 -123.01474)
		(stroke
			(width 0.04445)
			(type default)
		)
		(layer "In9.Cu")
	)
	(gr_line
		(start 386.977128 -122.962924)
		(end 387.24205 -122.962924)
		(stroke
			(width 0.04445)
			(type default)
		)
		(layer "In9.Cu")
	)
	(gr_line
		(start 386.997194 -124.808742)
		(end 387.03123 -124.842778)
		(stroke
			(width 0.04445)
			(type default)
		)
		(layer "In9.Cu")
	)
	(gr_line
		(start 387.02615 -3.250438)
		(end 387.311392 -3.060192)
		(stroke
			(width 0.05715)
			(type default)
		)
		(layer "In9.Cu")
	)
	(gr_arc
		(start 387.0325 -132.756148)
		(mid 387.02291 -132.662099)
		(end 386.97408 -132.581142)
		(stroke
			(width 0.05715)
			(type default)
		)
		(layer "In9.Cu")
	)
	(gr_arc
		(start 387.0325 -132.756148)
		(mid 387.042004 -132.850352)
		(end 387.09092 -132.931408)
		(stroke
			(width 0.05715)
			(type default)
		)
		(layer "In9.Cu")
	)
	(gr_line
		(start 387.033008 -124.844556)
		(end 387.047994 -124.859542)
		(stroke
			(width 0.04445)
			(type default)
		)
		(layer "In9.Cu")
	)
	(gr_arc
		(start 387.034024 -121.997724)
		(mid 387.029187 -121.843806)
		(end 386.91693 -121.73839)
		(stroke
			(width 0.04445)
			(type default)
		)
		(layer "In9.Cu")
	)
	(gr_line
		(start 387.034024 -121.997724)
		(end 387.034024 -121.997978)
		(stroke
			(width 0.04445)
			(type default)
		)
		(layer "In9.Cu")
	)
	(gr_line
		(start 387.041898 -123.309634)
		(end 387.042152 -123.309634)
		(stroke
			(width 0.04445)
			(type default)
		)
		(layer "In9.Cu")
	)
	(gr_arc
		(start 387.047994 -125.278388)
		(mid 387.070762 -125.370185)
		(end 387.130544 -125.443488)
		(stroke
			(width 0.05715)
			(type default)
		)
		(layer "In9.Cu")
	)
	(gr_line
		(start 387.047994 -124.859542)
		(end 387.047994 -124.870718)
		(stroke
			(width 0.04445)
			(type default)
		)
		(layer "In9.Cu")
	)
	(gr_line
		(start 387.107938 0.850646)
		(end 387.325616 0.850646)
		(stroke
			(width 0.050546)
			(type default)
		)
		(layer "In9.Cu")
	)
	(gr_arc
		(start 387.130544 -126.116588)
		(mid 387.070718 -126.189869)
		(end 387.047994 -126.281688)
		(stroke
			(width 0.05715)
			(type default)
		)
		(layer "In9.Cu")
	)
	(gr_arc
		(start 387.130544 -126.116588)
		(mid 387.190312 -126.043287)
		(end 387.213094 -125.951488)
		(stroke
			(width 0.05715)
			(type default)
		)
		(layer "In9.Cu")
	)
	(gr_line
		(start 387.134608 -17.407636)
		(end 387.157468 -17.40281)
		(stroke
			(width 0.05715)
			(type default)
		)
		(layer "In9.Cu")
	)
	(gr_line
		(start 387.157468 -17.40281)
		(end 387.17982 -17.407382)
		(stroke
			(width 0.05715)
			(type default)
		)
		(layer "In9.Cu")
	)
	(gr_arc
		(start 387.169406 -131.54406)
		(mid 387.250387 -131.592769)
		(end 387.344412 -131.602226)
		(stroke
			(width 0.05715)
			(type default)
		)
		(layer "In9.Cu")
	)
	(gr_line
		(start 387.17093 -131.959096)
		(end 387.463792 -132.251958)
		(stroke
			(width 0.05715)
			(type default)
		)
		(layer "In9.Cu")
	)
	(gr_line
		(start 387.175248 -15.399258)
		(end 387.198362 -15.394178)
		(stroke
			(width 0.05715)
			(type default)
		)
		(layer "In9.Cu")
	)
	(gr_line
		(start 387.198362 -15.394178)
		(end 387.221476 -15.399258)
		(stroke
			(width 0.05715)
			(type default)
		)
		(layer "In9.Cu")
	)
	(gr_line
		(start 387.203188 -14.721332)
		(end 387.226302 -14.716252)
		(stroke
			(width 0.05715)
			(type default)
		)
		(layer "In9.Cu")
	)
	(gr_line
		(start 387.205982 -16.059404)
		(end 387.231128 -16.05407)
		(stroke
			(width 0.05715)
			(type default)
		)
		(layer "In9.Cu")
	)
	(gr_arc
		(start 387.213094 -125.608588)
		(mid 387.190384 -125.516751)
		(end 387.130544 -125.443488)
		(stroke
			(width 0.05715)
			(type default)
		)
		(layer "In9.Cu")
	)
	(gr_line
		(start 387.213094 -125.608588)
		(end 387.213094 -125.951488)
		(stroke
			(width 0.05715)
			(type default)
		)
		(layer "In9.Cu")
	)
	(gr_line
		(start 387.226302 -14.716252)
		(end 387.249416 -14.721332)
		(stroke
			(width 0.05715)
			(type default)
		)
		(layer "In9.Cu")
	)
	(gr_line
		(start 387.231128 -16.05407)
		(end 387.256274 -16.059404)
		(stroke
			(width 0.05715)
			(type default)
		)
		(layer "In9.Cu")
	)
	(gr_line
		(start 387.254242 -16.72082)
		(end 387.279388 -16.715486)
		(stroke
			(width 0.05715)
			(type default)
		)
		(layer "In9.Cu")
	)
	(gr_line
		(start 387.279388 -16.715486)
		(end 387.304534 -16.72082)
		(stroke
			(width 0.05715)
			(type default)
		)
		(layer "In9.Cu")
	)
	(gr_line
		(start 387.311392 -3.060192)
		(end 387.356604 -2.83464)
		(stroke
			(width 0.05715)
			(type default)
		)
		(layer "In9.Cu")
	)
	(gr_arc
		(start 387.33349 -133.173978)
		(mid 387.414473 -133.222677)
		(end 387.508496 -133.232144)
		(stroke
			(width 0.05715)
			(type default)
		)
		(layer "In9.Cu")
	)
	(gr_line
		(start 387.335014 -133.589014)
		(end 387.627876 -133.881876)
		(stroke
			(width 0.05715)
			(type default)
		)
		(layer "In9.Cu")
	)
	(gr_line
		(start 387.34238 -14.038834)
		(end 387.365494 -14.033754)
		(stroke
			(width 0.05715)
			(type default)
		)
		(layer "In9.Cu")
	)
	(gr_line
		(start 387.34492 -13.373862)
		(end 387.368034 -13.368782)
		(stroke
			(width 0.05715)
			(type default)
		)
		(layer "In9.Cu")
	)
	(gr_line
		(start 387.365494 -14.033754)
		(end 387.388608 -14.038834)
		(stroke
			(width 0.05715)
			(type default)
		)
		(layer "In9.Cu")
	)
	(gr_line
		(start 387.368034 -13.368782)
		(end 387.391148 -13.373862)
		(stroke
			(width 0.05715)
			(type default)
		)
		(layer "In9.Cu")
	)
	(gr_line
		(start 387.50367 -12.689078)
		(end 387.526784 -12.683998)
		(stroke
			(width 0.05715)
			(type default)
		)
		(layer "In9.Cu")
	)
	(gr_line
		(start 387.511798 -2.376932)
		(end 387.528816 -2.365756)
		(stroke
			(width 0.05715)
			(type default)
		)
		(layer "In9.Cu")
	)
	(gr_line
		(start 387.513068 -11.872214)
		(end 387.536182 -11.867134)
		(stroke
			(width 0.05715)
			(type default)
		)
		(layer "In9.Cu")
	)
	(gr_arc
		(start 387.519418 -131.660646)
		(mid 387.438464 -131.611806)
		(end 387.344412 -131.602226)
		(stroke
			(width 0.05715)
			(type default)
		)
		(layer "In9.Cu")
	)
	(gr_line
		(start 387.519418 -131.660646)
		(end 387.761988 -131.903216)
		(stroke
			(width 0.05715)
			(type default)
		)
		(layer "In9.Cu")
	)
	(gr_line
		(start 387.526784 -12.683998)
		(end 387.549898 -12.689078)
		(stroke
			(width 0.05715)
			(type default)
		)
		(layer "In9.Cu")
	)
	(gr_line
		(start 387.528816 -2.365756)
		(end 387.548882 -2.361692)
		(stroke
			(width 0.05715)
			(type default)
		)
		(layer "In9.Cu")
	)
	(gr_line
		(start 387.536182 -11.867134)
		(end 387.559296 -11.872214)
		(stroke
			(width 0.05715)
			(type default)
		)
		(layer "In9.Cu")
	)
	(gr_line
		(start 387.57098 -11.20775)
		(end 387.594094 -11.20267)
		(stroke
			(width 0.05715)
			(type default)
		)
		(layer "In9.Cu")
	)
	(gr_line
		(start 387.594094 -11.20267)
		(end 387.617208 -11.20775)
		(stroke
			(width 0.05715)
			(type default)
		)
		(layer "In9.Cu")
	)
	(gr_line
		(start 387.600952 -10.545572)
		(end 387.624066 -10.540492)
		(stroke
			(width 0.05715)
			(type default)
		)
		(layer "In9.Cu")
	)
	(gr_line
		(start 387.624066 -10.540492)
		(end 387.64718 -10.545572)
		(stroke
			(width 0.05715)
			(type default)
		)
		(layer "In9.Cu")
	)
	(gr_line
		(start 387.65353 -9.87933)
		(end 387.676644 -9.87425)
		(stroke
			(width 0.05715)
			(type default)
		)
		(layer "In9.Cu")
	)
	(gr_line
		(start 387.676644 -9.87425)
		(end 387.699758 -9.87933)
		(stroke
			(width 0.05715)
			(type default)
		)
		(layer "In9.Cu")
	)
	(gr_arc
		(start 387.683502 -133.290564)
		(mid 387.602555 -133.241705)
		(end 387.508496 -133.232144)
		(stroke
			(width 0.05715)
			(type default)
		)
		(layer "In9.Cu")
	)
	(gr_line
		(start 387.683502 -133.290564)
		(end 387.926072 -133.533134)
		(stroke
			(width 0.05715)
			(type default)
		)
		(layer "In9.Cu")
	)
	(gr_arc
		(start 387.73735 -122.104404)
		(mid 388.067759 -122.269241)
		(end 388.413244 -122.399552)
		(stroke
			(width 0.04445)
			(type default)
		)
		(layer "In9.Cu")
	)
	(gr_line
		(start 387.771894 -131.204716)
		(end 388.4295 -131.862576)
		(stroke
			(width 0.05715)
			(type default)
		)
		(layer "In9.Cu")
	)
	(gr_arc
		(start 387.820408 -132.078222)
		(mid 387.810839 -131.984165)
		(end 387.761988 -131.903216)
		(stroke
			(width 0.05715)
			(type default)
		)
		(layer "In9.Cu")
	)
	(gr_arc
		(start 387.820408 -132.078222)
		(mid 387.829929 -132.172415)
		(end 387.878828 -132.253482)
		(stroke
			(width 0.05715)
			(type default)
		)
		(layer "In9.Cu")
	)
	(gr_arc
		(start 387.952488 -130.971798)
		(mid 388.033555 -131.020697)
		(end 388.127748 -131.030218)
		(stroke
			(width 0.05715)
			(type default)
		)
		(layer "In9.Cu")
	)
	(gr_arc
		(start 387.984492 -133.70814)
		(mid 387.974902 -133.614091)
		(end 387.926072 -133.533134)
		(stroke
			(width 0.05715)
			(type default)
		)
		(layer "In9.Cu")
	)
	(gr_arc
		(start 387.984492 -133.70814)
		(mid 387.994031 -133.802324)
		(end 388.042912 -133.8834)
		(stroke
			(width 0.05715)
			(type default)
		)
		(layer "In9.Cu")
	)
	(gr_arc
		(start 388.0485 -125.400054)
		(mid 388.062565 -125.44858)
		(end 388.09295 -125.488954)
		(stroke
			(width 0.04445)
			(type default)
		)
		(layer "In9.Cu")
	)
	(gr_line
		(start 388.0485 -125.133354)
		(end 388.0485 -125.400054)
		(stroke
			(width 0.04445)
			(type default)
		)
		(layer "In9.Cu")
	)
	(gr_arc
		(start 388.0485 -124.511054)
		(mid 388.062565 -124.55958)
		(end 388.09295 -124.599954)
		(stroke
			(width 0.04445)
			(type default)
		)
		(layer "In9.Cu")
	)
	(gr_line
		(start 388.0485 -124.244354)
		(end 388.0485 -124.511054)
		(stroke
			(width 0.04445)
			(type default)
		)
		(layer "In9.Cu")
	)
	(gr_arc
		(start 388.085076 -122.591068)
		(mid 387.973108 -122.850673)
		(end 388.23265 -122.962924)
		(stroke
			(width 0.04445)
			(type default)
		)
		(layer "In9.Cu")
	)
	(gr_arc
		(start 388.09295 -125.044454)
		(mid 388.062529 -125.08481)
		(end 388.0485 -125.133354)
		(stroke
			(width 0.04445)
			(type default)
		)
		(layer "In9.Cu")
	)
	(gr_arc
		(start 388.09295 -125.044454)
		(mid 388.12334 -125.004086)
		(end 388.1374 -124.955554)
		(stroke
			(width 0.04445)
			(type default)
		)
		(layer "In9.Cu")
	)
	(gr_arc
		(start 388.09295 -124.155454)
		(mid 388.062529 -124.19581)
		(end 388.0485 -124.244354)
		(stroke
			(width 0.04445)
			(type default)
		)
		(layer "In9.Cu")
	)
	(gr_arc
		(start 388.09295 -124.155454)
		(mid 388.12334 -124.115086)
		(end 388.1374 -124.066554)
		(stroke
			(width 0.04445)
			(type default)
		)
		(layer "In9.Cu")
	)
	(gr_arc
		(start 388.121398 -132.496052)
		(mid 388.202379 -132.544761)
		(end 388.296404 -132.554218)
		(stroke
			(width 0.05715)
			(type default)
		)
		(layer "In9.Cu")
	)
	(gr_line
		(start 388.122922 -132.911088)
		(end 388.415784 -133.20395)
		(stroke
			(width 0.05715)
			(type default)
		)
		(layer "In9.Cu")
	)
	(gr_arc
		(start 388.1374 -125.577854)
		(mid 388.12338 -125.529299)
		(end 388.09295 -125.488954)
		(stroke
			(width 0.04445)
			(type default)
		)
		(layer "In9.Cu")
	)
	(gr_arc
		(start 388.1374 -124.688854)
		(mid 388.12338 -124.640299)
		(end 388.09295 -124.599954)
		(stroke
			(width 0.04445)
			(type default)
		)
		(layer "In9.Cu")
	)
	(gr_line
		(start 388.2263 -126.800102)
		(end 388.2263 -126.8222)
		(stroke
			(width 0.04445)
			(type default)
		)
		(layer "In9.Cu")
	)
	(gr_line
		(start 388.2263 -126.800102)
		(end 388.230364 -126.796038)
		(stroke
			(width 0.04445)
			(type default)
		)
		(layer "In9.Cu")
	)
	(gr_line
		(start 388.232142 -126.79426)
		(end 388.2771 -126.749302)
		(stroke
			(width 0.04445)
			(type default)
		)
		(layer "In9.Cu")
	)
	(gr_arc
		(start 388.285482 -134.12597)
		(mid 388.366465 -134.174673)
		(end 388.460488 -134.184136)
		(stroke
			(width 0.05715)
			(type default)
		)
		(layer "In9.Cu")
	)
	(gr_line
		(start 388.287006 -134.541006)
		(end 388.579868 -134.833868)
		(stroke
			(width 0.05715)
			(type default)
		)
		(layer "In9.Cu")
	)
	(gr_arc
		(start 388.302754 -131.088638)
		(mid 388.221798 -131.039825)
		(end 388.127748 -131.030218)
		(stroke
			(width 0.05715)
			(type default)
		)
		(layer "In9.Cu")
	)
	(gr_line
		(start 388.302754 -131.088638)
		(end 388.545324 -131.331208)
		(stroke
			(width 0.05715)
			(type default)
		)
		(layer "In9.Cu")
	)
	(gr_line
		(start 388.3279 -125.148594)
		(end 388.3279 -125.384814)
		(stroke
			(width 0.04445)
			(type default)
		)
		(layer "In9.Cu")
	)
	(gr_line
		(start 388.3279 -124.259594)
		(end 388.3279 -124.495814)
		(stroke
			(width 0.04445)
			(type default)
		)
		(layer "In9.Cu")
	)
	(gr_line
		(start 388.4676 -126.760224)
		(end 388.501636 -126.79426)
		(stroke
			(width 0.04445)
			(type default)
		)
		(layer "In9.Cu")
	)
	(gr_arc
		(start 388.47141 -132.612638)
		(mid 388.390456 -132.563803)
		(end 388.296404 -132.554218)
		(stroke
			(width 0.05715)
			(type default)
		)
		(layer "In9.Cu")
	)
	(gr_line
		(start 388.47141 -132.612638)
		(end 388.71398 -132.855208)
		(stroke
			(width 0.05715)
			(type default)
		)
		(layer "In9.Cu")
	)
	(gr_line
		(start 388.503414 -126.796038)
		(end 388.5184 -126.811024)
		(stroke
			(width 0.04445)
			(type default)
		)
		(layer "In9.Cu")
	)
	(gr_line
		(start 388.5184 -126.811024)
		(end 388.5184 -126.8222)
		(stroke
			(width 0.04445)
			(type default)
		)
		(layer "In9.Cu")
	)
	(gr_arc
		(start 388.60349 -131.506214)
		(mid 388.594028 -131.41219)
		(end 388.545324 -131.331208)
		(stroke
			(width 0.05715)
			(type default)
		)
		(layer "In9.Cu")
	)
	(gr_arc
		(start 388.60349 -131.506214)
		(mid 388.613011 -131.600407)
		(end 388.66191 -131.681474)
		(stroke
			(width 0.05715)
			(type default)
		)
		(layer "In9.Cu")
	)
	(gr_arc
		(start 388.635494 -134.242556)
		(mid 388.554547 -134.193697)
		(end 388.460488 -134.184136)
		(stroke
			(width 0.05715)
			(type default)
		)
		(layer "In9.Cu")
	)
	(gr_line
		(start 388.635494 -134.242556)
		(end 388.878064 -134.485126)
		(stroke
			(width 0.05715)
			(type default)
		)
		(layer "In9.Cu")
	)
	(gr_line
		(start 388.723632 -132.156962)
		(end 389.382 -132.815584)
		(stroke
			(width 0.05715)
			(type default)
		)
		(layer "In9.Cu")
	)
	(gr_line
		(start 388.72795 -123.821444)
		(end 388.89686 -123.528328)
		(stroke
			(width 0.04445)
			(type default)
		)
		(layer "In9.Cu")
	)
	(gr_line
		(start 388.72795 -122.104404)
		(end 389.066024 -122.104404)
		(stroke
			(width 0.04445)
			(type default)
		)
		(layer "In9.Cu")
	)
	(gr_line
		(start 388.741666 -8.98779)
		(end 389.32612 -8.863584)
		(stroke
			(width 0.05715)
			(type default)
		)
		(layer "In9.Cu")
	)
	(gr_line
		(start 388.768844 -9.283192)
		(end 388.96163 -9.408668)
		(stroke
			(width 0.05715)
			(type default)
		)
		(layer "In9.Cu")
	)
	(gr_arc
		(start 388.7724 -133.030214)
		(mid 388.762827 -132.936159)
		(end 388.71398 -132.855208)
		(stroke
			(width 0.05715)
			(type default)
		)
		(layer "In9.Cu")
	)
	(gr_arc
		(start 388.7724 -133.030214)
		(mid 388.781921 -133.124407)
		(end 388.83082 -133.205474)
		(stroke
			(width 0.05715)
			(type default)
		)
		(layer "In9.Cu")
	)
	(gr_line
		(start 388.89686 -123.528328)
		(end 388.973822 -123.507754)
		(stroke
			(width 0.04445)
			(type default)
		)
		(layer "In9.Cu")
	)
	(gr_arc
		(start 388.904226 -131.924044)
		(mid 388.985293 -131.972943)
		(end 389.079486 -131.982464)
		(stroke
			(width 0.05715)
			(type default)
		)
		(layer "In9.Cu")
	)
	(gr_arc
		(start 388.936484 -134.660132)
		(mid 388.926894 -134.566083)
		(end 388.878064 -134.485126)
		(stroke
			(width 0.05715)
			(type default)
		)
		(layer "In9.Cu")
	)
	(gr_arc
		(start 388.936484 -134.660132)
		(mid 388.946019 -134.754318)
		(end 388.994904 -134.835392)
		(stroke
			(width 0.05715)
			(type default)
		)
		(layer "In9.Cu")
	)
	(gr_line
		(start 388.96163 -9.408668)
		(end 389.297164 -9.337294)
		(stroke
			(width 0.05715)
			(type default)
		)
		(layer "In9.Cu")
	)
	(gr_line
		(start 389.05434 -123.25604)
		(end 389.077962 -123.34367)
		(stroke
			(width 0.04445)
			(type default)
		)
		(layer "In9.Cu")
	)
	(gr_line
		(start 389.05434 -123.25604)
		(end 389.22325 -122.962924)
		(stroke
			(width 0.04445)
			(type default)
		)
		(layer "In9.Cu")
	)
	(gr_line
		(start 389.066024 -122.104404)
		(end 389.086852 -122.125232)
		(stroke
			(width 0.04445)
			(type default)
		)
		(layer "In9.Cu")
	)
	(gr_arc
		(start 389.07339 -133.448044)
		(mid 389.154371 -133.496753)
		(end 389.248396 -133.50621)
		(stroke
			(width 0.05715)
			(type default)
		)
		(layer "In9.Cu")
	)
	(gr_line
		(start 389.074914 -133.86308)
		(end 389.550402 -134.338568)
		(stroke
			(width 0.05715)
			(type default)
		)
		(layer "In9.Cu")
	)
	(gr_line
		(start 389.08863 -122.12701)
		(end 389.131048 -122.169428)
		(stroke
			(width 0.04445)
			(type default)
		)
		(layer "In9.Cu")
	)
	(gr_arc
		(start 389.173212 -130.554476)
		(mid 389.254279 -130.603375)
		(end 389.348472 -130.612896)
		(stroke
			(width 0.05715)
			(type default)
		)
		(layer "In9.Cu")
	)
	(gr_line
		(start 389.174736 -130.969512)
		(end 389.467598 -131.262374)
		(stroke
			(width 0.05715)
			(type default)
		)
		(layer "In9.Cu")
	)
	(gr_line
		(start 389.22325 -121.245884)
		(end 389.263128 -121.256552)
		(stroke
			(width 0.04445)
			(type default)
		)
		(layer "In9.Cu")
	)
	(gr_arc
		(start 389.254492 -132.040884)
		(mid 389.173539 -131.992046)
		(end 389.079486 -131.982464)
		(stroke
			(width 0.05715)
			(type default)
		)
		(layer "In9.Cu")
	)
	(gr_line
		(start 389.254492 -132.040884)
		(end 389.497062 -132.2832)
		(stroke
			(width 0.05715)
			(type default)
		)
		(layer "In9.Cu")
	)
	(gr_line
		(start 389.263128 -121.256552)
		(end 389.276082 -121.261378)
		(stroke
			(width 0.04445)
			(type default)
		)
		(layer "In9.Cu")
	)
	(gr_arc
		(start 389.269732 -120.656858)
		(mid 389.537256 -120.59395)
		(end 389.71855 -120.387364)
		(stroke
			(width 0.04445)
			(type default)
		)
		(layer "In9.Cu")
	)
	(gr_arc
		(start 389.276082 -121.261378)
		(mid 389.53948 -121.149465)
		(end 389.427212 -120.88622)
		(stroke
			(width 0.04445)
			(type default)
		)
		(layer "In9.Cu")
	)
	(gr_line
		(start 389.297164 -9.337294)
		(end 389.422386 -9.144508)
		(stroke
			(width 0.05715)
			(type default)
		)
		(layer "In9.Cu")
	)
	(gr_line
		(start 389.320278 -120.857772)
		(end 389.412226 -120.881394)
		(stroke
			(width 0.04445)
			(type default)
		)
		(layer "In9.Cu")
	)
	(gr_line
		(start 389.322564 -122.162316)
		(end 389.35787 -122.12701)
		(stroke
			(width 0.04445)
			(type default)
		)
		(layer "In9.Cu")
	)
	(gr_line
		(start 389.359648 -122.125232)
		(end 389.380476 -122.104404)
		(stroke
			(width 0.04445)
			(type default)
		)
		(layer "In9.Cu")
	)
	(gr_line
		(start 389.380476 -122.104404)
		(end 389.71855 -122.104404)
		(stroke
			(width 0.04445)
			(type default)
		)
		(layer "In9.Cu")
	)
	(gr_arc
		(start 389.423402 -133.56463)
		(mid 389.342451 -133.515778)
		(end 389.248396 -133.50621)
		(stroke
			(width 0.05715)
			(type default)
		)
		(layer "In9.Cu")
	)
	(gr_line
		(start 389.423402 -133.56463)
		(end 389.665972 -133.8072)
		(stroke
			(width 0.05715)
			(type default)
		)
		(layer "In9.Cu")
	)
	(gr_arc
		(start 389.427212 -120.88622)
		(mid 389.419811 -120.88352)
		(end 389.412226 -120.881394)
		(stroke
			(width 0.04445)
			(type default)
		)
		(layer "In9.Cu")
	)
	(gr_arc
		(start 389.429752 -124.587508)
		(mid 389.422746 -124.537344)
		(end 389.398256 -124.49302)
		(stroke
			(width 0.04445)
			(type default)
		)
		(layer "In9.Cu")
	)
	(gr_arc
		(start 389.429752 -124.587508)
		(mid 389.436878 -124.63751)
		(end 389.461248 -124.681742)
		(stroke
			(width 0.04445)
			(type default)
		)
		(layer "In9.Cu")
	)
	(gr_line
		(start 389.461248 -124.681742)
		(end 389.649716 -124.87021)
		(stroke
			(width 0.04445)
			(type default)
		)
		(layer "In9.Cu")
	)
	(gr_arc
		(start 389.523478 -130.671316)
		(mid 389.442526 -130.622476)
		(end 389.348472 -130.612896)
		(stroke
			(width 0.05715)
			(type default)
		)
		(layer "In9.Cu")
	)
	(gr_line
		(start 389.523478 -130.671316)
		(end 389.766048 -130.913886)
		(stroke
			(width 0.05715)
			(type default)
		)
		(layer "In9.Cu")
	)
	(gr_arc
		(start 389.555228 -132.45846)
		(mid 389.545798 -132.36431)
		(end 389.497062 -132.2832)
		(stroke
			(width 0.05715)
			(type default)
		)
		(layer "In9.Cu")
	)
	(gr_arc
		(start 389.555228 -132.45846)
		(mid 389.564818 -132.552509)
		(end 389.613648 -132.633466)
		(stroke
			(width 0.05715)
			(type default)
		)
		(layer "In9.Cu")
	)
	(gr_arc
		(start 389.649716 -124.87021)
		(mid 389.694047 -124.894687)
		(end 389.744204 -124.901706)
		(stroke
			(width 0.04445)
			(type default)
		)
		(layer "In9.Cu")
	)
	(gr_line
		(start 389.669528 -124.494544)
		(end 389.836914 -124.66193)
		(stroke
			(width 0.04445)
			(type default)
		)
		(layer "In9.Cu")
	)
	(gr_arc
		(start 389.724392 -133.982206)
		(mid 389.714816 -133.888153)
		(end 389.665972 -133.8072)
		(stroke
			(width 0.05715)
			(type default)
		)
		(layer "In9.Cu")
	)
	(gr_arc
		(start 389.724392 -133.982206)
		(mid 389.733913 -134.076399)
		(end 389.782812 -134.157466)
		(stroke
			(width 0.05715)
			(type default)
		)
		(layer "In9.Cu")
	)
	(gr_line
		(start 389.737346 -8.776462)
		(end 390.319006 -8.652764)
		(stroke
			(width 0.05715)
			(type default)
		)
		(layer "In9.Cu")
	)
	(gr_line
		(start 389.762492 -9.072118)
		(end 389.955532 -9.197594)
		(stroke
			(width 0.05715)
			(type default)
		)
		(layer "In9.Cu")
	)
	(gr_arc
		(start 389.824468 -131.088892)
		(mid 389.814889 -130.994839)
		(end 389.766048 -130.913886)
		(stroke
			(width 0.05715)
			(type default)
		)
		(layer "In9.Cu")
	)
	(gr_arc
		(start 389.824468 -131.088892)
		(mid 389.833933 -131.182915)
		(end 389.882634 -131.263898)
		(stroke
			(width 0.05715)
			(type default)
		)
		(layer "In9.Cu")
	)
	(gr_arc
		(start 389.838438 -124.933202)
		(mid 389.794207 -124.90885)
		(end 389.744204 -124.901706)
		(stroke
			(width 0.04445)
			(type default)
		)
		(layer "In9.Cu")
	)
	(gr_line
		(start 389.955532 -9.197594)
		(end 390.291066 -9.12622)
		(stroke
			(width 0.05715)
			(type default)
		)
		(layer "In9.Cu")
	)
	(gr_arc
		(start 390.058402 -125.216158)
		(mid 390.051396 -125.165994)
		(end 390.026906 -125.12167)
		(stroke
			(width 0.04445)
			(type default)
		)
		(layer "In9.Cu")
	)
	(gr_arc
		(start 390.058402 -125.216158)
		(mid 390.065546 -125.26615)
		(end 390.089898 -125.310392)
		(stroke
			(width 0.04445)
			(type default)
		)
		(layer "In9.Cu")
	)
	(gr_line
		(start 390.089898 -125.310392)
		(end 390.278366 -125.49886)
		(stroke
			(width 0.04445)
			(type default)
		)
		(layer "In9.Cu")
	)
	(gr_arc
		(start 390.125204 -131.506468)
		(mid 390.206271 -131.555367)
		(end 390.300464 -131.564888)
		(stroke
			(width 0.05715)
			(type default)
		)
		(layer "In9.Cu")
	)
	(gr_line
		(start 390.126728 -131.921504)
		(end 390.41959 -132.214366)
		(stroke
			(width 0.05715)
			(type default)
		)
		(layer "In9.Cu")
	)
	(gr_arc
		(start 390.21385 -121.245884)
		(mid 390.413659 -121.446067)
		(end 390.688322 -121.5136)
		(stroke
			(width 0.04445)
			(type default)
		)
		(layer "In9.Cu")
	)
	(gr_arc
		(start 390.278366 -125.49886)
		(mid 390.322697 -125.523345)
		(end 390.372854 -125.530356)
		(stroke
			(width 0.04445)
			(type default)
		)
		(layer "In9.Cu")
	)
	(gr_line
		(start 390.291066 -9.12622)
		(end 390.416034 -8.933434)
		(stroke
			(width 0.05715)
			(type default)
		)
		(layer "In9.Cu")
	)
	(gr_line
		(start 390.298178 -125.123194)
		(end 390.465564 -125.29058)
		(stroke
			(width 0.04445)
			(type default)
		)
		(layer "In9.Cu")
	)
	(gr_arc
		(start 390.467088 -125.561852)
		(mid 390.422857 -125.5375)
		(end 390.372854 -125.530356)
		(stroke
			(width 0.04445)
			(type default)
		)
		(layer "In9.Cu")
	)
	(gr_arc
		(start 390.47547 -131.623308)
		(mid 390.394517 -131.574473)
		(end 390.300464 -131.564888)
		(stroke
			(width 0.05715)
			(type default)
		)
		(layer "In9.Cu")
	)
	(gr_line
		(start 390.47547 -131.623308)
		(end 390.71804 -131.865878)
		(stroke
			(width 0.05715)
			(type default)
		)
		(layer "In9.Cu")
	)
	(gr_line
		(start 390.55421 -121.835672)
		(end 390.571736 -121.770902)
		(stroke
			(width 0.04445)
			(type default)
		)
		(layer "In9.Cu")
	)
	(gr_line
		(start 390.55421 -121.835672)
		(end 390.70915 -122.104404)
		(stroke
			(width 0.04445)
			(type default)
		)
		(layer "In9.Cu")
	)
	(gr_arc
		(start 390.6139 -127.434594)
		(mid 390.627933 -127.483139)
		(end 390.65835 -127.523494)
		(stroke
			(width 0.04445)
			(type default)
		)
		(layer "In9.Cu")
	)
	(gr_line
		(start 390.6139 -127.167894)
		(end 390.6139 -127.434594)
		(stroke
			(width 0.04445)
			(type default)
		)
		(layer "In9.Cu")
	)
	(gr_arc
		(start 390.6139 -126.545594)
		(mid 390.627933 -126.594139)
		(end 390.65835 -126.634494)
		(stroke
			(width 0.04445)
			(type default)
		)
		(layer "In9.Cu")
	)
	(gr_line
		(start 390.6139 -126.278894)
		(end 390.6139 -126.545594)
		(stroke
			(width 0.04445)
			(type default)
		)
		(layer "In9.Cu")
	)
	(gr_line
		(start 390.652 -127.892302)
		(end 390.652 -127.9144)
		(stroke
			(width 0.04445)
			(type default)
		)
		(layer "In9.Cu")
	)
	(gr_line
		(start 390.652 -127.892302)
		(end 390.661652 -127.88265)
		(stroke
			(width 0.04445)
			(type default)
		)
		(layer "In9.Cu")
	)
	(gr_arc
		(start 390.654794 -121.70537)
		(mid 390.602478 -121.724456)
		(end 390.571736 -121.770902)
		(stroke
			(width 0.04445)
			(type default)
		)
		(layer "In9.Cu")
	)
	(gr_line
		(start 390.654794 -121.70537)
		(end 390.663938 -121.705116)
		(stroke
			(width 0.04445)
			(type default)
		)
		(layer "In9.Cu")
	)
	(gr_arc
		(start 390.65835 -127.078994)
		(mid 390.627973 -127.119366)
		(end 390.6139 -127.167894)
		(stroke
			(width 0.04445)
			(type default)
		)
		(layer "In9.Cu")
	)
	(gr_arc
		(start 390.65835 -127.078994)
		(mid 390.688771 -127.038638)
		(end 390.7028 -126.990094)
		(stroke
			(width 0.04445)
			(type default)
		)
		(layer "In9.Cu")
	)
	(gr_arc
		(start 390.65835 -126.189994)
		(mid 390.627973 -126.230366)
		(end 390.6139 -126.278894)
		(stroke
			(width 0.04445)
			(type default)
		)
		(layer "In9.Cu")
	)
	(gr_line
		(start 390.66343 -127.880872)
		(end 390.7028 -127.841502)
		(stroke
			(width 0.04445)
			(type default)
		)
		(layer "In9.Cu")
	)
	(gr_arc
		(start 390.7028 -127.612394)
		(mid 390.688735 -127.563868)
		(end 390.65835 -127.523494)
		(stroke
			(width 0.04445)
			(type default)
		)
		(layer "In9.Cu")
	)
	(gr_arc
		(start 390.7028 -126.723394)
		(mid 390.688735 -126.674868)
		(end 390.65835 -126.634494)
		(stroke
			(width 0.04445)
			(type default)
		)
		(layer "In9.Cu")
	)
	(gr_line
		(start 390.730486 -8.565642)
		(end 390.7536 -8.560562)
		(stroke
			(width 0.05715)
			(type default)
		)
		(layer "In9.Cu")
	)
	(gr_line
		(start 390.7536 -8.560562)
		(end 390.776714 -8.565642)
		(stroke
			(width 0.05715)
			(type default)
		)
		(layer "In9.Cu")
	)
	(gr_arc
		(start 390.77646 -132.040884)
		(mid 390.766916 -131.946811)
		(end 390.71804 -131.865878)
		(stroke
			(width 0.05715)
			(type default)
		)
		(layer "In9.Cu")
	)
	(gr_arc
		(start 390.77646 -132.040884)
		(mid 390.785925 -132.134907)
		(end 390.834626 -132.21589)
		(stroke
			(width 0.05715)
			(type default)
		)
		(layer "In9.Cu")
	)
	(gr_line
		(start 390.777222 -1.71577)
		(end 390.796272 -1.71196)
		(stroke
			(width 0.05715)
			(type default)
		)
		(layer "In9.Cu")
	)
	(gr_line
		(start 390.796272 -1.71196)
		(end 390.815322 -1.71577)
		(stroke
			(width 0.05715)
			(type default)
		)
		(layer "In9.Cu")
	)
	(gr_line
		(start 390.844278 -7.880858)
		(end 390.867392 -7.875778)
		(stroke
			(width 0.05715)
			(type default)
		)
		(layer "In9.Cu")
	)
	(gr_line
		(start 390.867392 -7.875778)
		(end 390.890506 -7.880858)
		(stroke
			(width 0.05715)
			(type default)
		)
		(layer "In9.Cu")
	)
	(gr_line
		(start 390.8933 -127.841502)
		(end 390.93267 -127.880872)
		(stroke
			(width 0.04445)
			(type default)
		)
		(layer "In9.Cu")
	)
	(gr_line
		(start 390.8933 -127.183134)
		(end 390.8933 -127.419354)
		(stroke
			(width 0.04445)
			(type default)
		)
		(layer "In9.Cu")
	)
	(gr_line
		(start 390.8933 -126.294134)
		(end 390.8933 -126.530354)
		(stroke
			(width 0.04445)
			(type default)
		)
		(layer "In9.Cu")
	)
	(gr_line
		(start 390.934448 -127.88265)
		(end 390.9441 -127.892302)
		(stroke
			(width 0.04445)
			(type default)
		)
		(layer "In9.Cu")
	)
	(gr_line
		(start 390.9441 -127.892302)
		(end 390.9441 -127.9144)
		(stroke
			(width 0.04445)
			(type default)
		)
		(layer "In9.Cu")
	)
	(gr_line
		(start 391.004552 -121.592594)
		(end 391.004552 -121.592848)
		(stroke
			(width 0.04445)
			(type default)
		)
		(layer "In9.Cu")
	)
	(gr_line
		(start 391.101834 -7.151878)
		(end 391.124948 -7.146798)
		(stroke
			(width 0.05715)
			(type default)
		)
		(layer "In9.Cu")
	)
	(gr_line
		(start 391.124948 -7.146798)
		(end 391.148062 -7.151878)
		(stroke
			(width 0.05715)
			(type default)
		)
		(layer "In9.Cu")
	)
	(gr_arc
		(start 391.15238 -124.842524)
		(mid 391.19671 -124.86701)
		(end 391.246868 -124.87402)
		(stroke
			(width 0.04445)
			(type default)
		)
		(layer "In9.Cu")
	)
	(gr_line
		(start 391.153904 -125.113796)
		(end 391.32129 -125.281182)
		(stroke
			(width 0.04445)
			(type default)
		)
		(layer "In9.Cu")
	)
	(gr_line
		(start 391.195814 -18.512028)
		(end 391.218674 -18.5166)
		(stroke
			(width 0.05715)
			(type default)
		)
		(layer "In9.Cu")
	)
	(gr_line
		(start 391.218674 -18.5166)
		(end 391.241026 -18.511774)
		(stroke
			(width 0.05715)
			(type default)
		)
		(layer "In9.Cu")
	)
	(gr_line
		(start 391.22858 -17.85366)
		(end 391.251948 -17.85874)
		(stroke
			(width 0.05715)
			(type default)
		)
		(layer "In9.Cu")
	)
	(gr_line
		(start 391.232898 -17.202404)
		(end 391.256012 -17.207484)
		(stroke
			(width 0.05715)
			(type default)
		)
		(layer "In9.Cu")
	)
	(gr_line
		(start 391.23747 -16.550894)
		(end 391.260584 -16.555974)
		(stroke
			(width 0.05715)
			(type default)
		)
		(layer "In9.Cu")
	)
	(gr_line
		(start 391.251948 -17.85874)
		(end 391.274554 -17.853914)
		(stroke
			(width 0.05715)
			(type default)
		)
		(layer "In9.Cu")
	)
	(gr_line
		(start 391.256012 -17.207484)
		(end 391.279126 -17.202404)
		(stroke
			(width 0.05715)
			(type default)
		)
		(layer "In9.Cu")
	)
	(gr_line
		(start 391.260584 -16.555974)
		(end 391.283698 -16.550894)
		(stroke
			(width 0.05715)
			(type default)
		)
		(layer "In9.Cu")
	)
	(gr_line
		(start 391.315448 -15.884144)
		(end 391.338562 -15.889224)
		(stroke
			(width 0.05715)
			(type default)
		)
		(layer "In9.Cu")
	)
	(gr_line
		(start 391.338562 -15.889224)
		(end 391.361676 -15.884144)
		(stroke
			(width 0.05715)
			(type default)
		)
		(layer "In9.Cu")
	)
	(gr_arc
		(start 391.341102 -124.905516)
		(mid 391.296871 -124.881164)
		(end 391.246868 -124.87402)
		(stroke
			(width 0.04445)
			(type default)
		)
		(layer "In9.Cu")
	)
	(gr_line
		(start 391.341102 -124.905516)
		(end 391.52957 -125.093984)
		(stroke
			(width 0.04445)
			(type default)
		)
		(layer "In9.Cu")
	)
	(gr_line
		(start 391.462006 -15.202154)
		(end 391.48512 -15.207234)
		(stroke
			(width 0.05715)
			(type default)
		)
		(layer "In9.Cu")
	)
	(gr_line
		(start 391.48512 -15.207234)
		(end 391.508234 -15.202154)
		(stroke
			(width 0.05715)
			(type default)
		)
		(layer "In9.Cu")
	)
	(gr_line
		(start 391.497566 -14.544294)
		(end 391.52068 -14.549374)
		(stroke
			(width 0.05715)
			(type default)
		)
		(layer "In9.Cu")
	)
	(gr_line
		(start 391.52068 -14.549374)
		(end 391.543794 -14.544294)
		(stroke
			(width 0.05715)
			(type default)
		)
		(layer "In9.Cu")
	)
	(gr_arc
		(start 391.561066 -125.188472)
		(mid 391.55406 -125.138308)
		(end 391.52957 -125.093984)
		(stroke
			(width 0.04445)
			(type default)
		)
		(layer "In9.Cu")
	)
	(gr_arc
		(start 391.561066 -125.188472)
		(mid 391.568213 -125.238463)
		(end 391.592562 -125.282706)
		(stroke
			(width 0.04445)
			(type default)
		)
		(layer "In9.Cu")
	)
	(gr_line
		(start 391.658856 -13.860526)
		(end 391.68197 -13.865606)
		(stroke
			(width 0.05715)
			(type default)
		)
		(layer "In9.Cu")
	)
	(gr_line
		(start 391.668254 -11.698732)
		(end 391.691368 -11.703812)
		(stroke
			(width 0.05715)
			(type default)
		)
		(layer "In9.Cu")
	)
	(gr_line
		(start 391.68197 -13.865606)
		(end 391.705084 -13.860526)
		(stroke
			(width 0.05715)
			(type default)
		)
		(layer "In9.Cu")
	)
	(gr_line
		(start 391.682986 -11.024362)
		(end 391.7061 -11.029442)
		(stroke
			(width 0.05715)
			(type default)
		)
		(layer "In9.Cu")
	)
	(gr_line
		(start 391.686542 -13.047726)
		(end 391.709656 -13.052806)
		(stroke
			(width 0.05715)
			(type default)
		)
		(layer "In9.Cu")
	)
	(gr_line
		(start 391.691368 -11.703812)
		(end 391.714482 -11.698732)
		(stroke
			(width 0.05715)
			(type default)
		)
		(layer "In9.Cu")
	)
	(gr_line
		(start 391.7061 -11.029442)
		(end 391.729214 -11.024362)
		(stroke
			(width 0.05715)
			(type default)
		)
		(layer "In9.Cu")
	)
	(gr_line
		(start 391.709656 -13.052806)
		(end 391.73277 -13.047726)
		(stroke
			(width 0.05715)
			(type default)
		)
		(layer "In9.Cu")
	)
	(gr_line
		(start 391.720578 -12.378182)
		(end 391.743692 -12.383262)
		(stroke
			(width 0.05715)
			(type default)
		)
		(layer "In9.Cu")
	)
	(gr_line
		(start 391.743692 -12.383262)
		(end 391.766806 -12.378182)
		(stroke
			(width 0.05715)
			(type default)
		)
		(layer "In9.Cu")
	)
	(gr_line
		(start 391.895584 -7.608824)
		(end 391.918698 -7.613904)
		(stroke
			(width 0.05715)
			(type default)
		)
		(layer "In9.Cu")
	)
	(gr_line
		(start 391.918698 -7.613904)
		(end 391.941812 -7.608824)
		(stroke
			(width 0.05715)
			(type default)
		)
		(layer "In9.Cu")
	)
	(gr_line
		(start 391.981436 -8.41121)
		(end 392.00455 -8.41629)
		(stroke
			(width 0.05715)
			(type default)
		)
		(layer "In9.Cu")
	)
	(gr_line
		(start 392.00455 -8.41629)
		(end 392.027664 -8.41121)
		(stroke
			(width 0.05715)
			(type default)
		)
		(layer "In9.Cu")
	)
	(gr_line
		(start 392.442954 -9.218168)
		(end 392.466068 -9.223248)
		(stroke
			(width 0.05715)
			(type default)
		)
		(layer "In9.Cu")
	)
	(gr_line
		(start 392.466068 -9.223248)
		(end 392.489182 -9.218168)
		(stroke
			(width 0.05715)
			(type default)
		)
		(layer "In9.Cu")
	)
	(gr_arc
		(start 392.73226 -131.693412)
		(mid 392.824086 -131.670687)
		(end 392.89736 -131.610862)
		(stroke
			(width 0.05715)
			(type default)
		)
		(layer "In9.Cu")
	)
	(gr_line
		(start 392.958066 -2.44221)
		(end 392.977116 -2.44602)
		(stroke
			(width 0.05715)
			(type default)
		)
		(layer "In9.Cu")
	)
	(gr_line
		(start 392.977116 -2.44602)
		(end 392.996166 -2.44221)
		(stroke
			(width 0.05715)
			(type default)
		)
		(layer "In9.Cu")
	)
	(gr_line
		(start 392.996166 -7.0866)
		(end 393.579858 -6.962648)
		(stroke
			(width 0.05715)
			(type default)
		)
		(layer "In9.Cu")
	)
	(gr_line
		(start 393.022582 -7.382002)
		(end 393.215622 -7.507478)
		(stroke
			(width 0.05715)
			(type default)
		)
		(layer "In9.Cu")
	)
	(gr_line
		(start 393.0269 -131.985512)
		(end 393.44092 -131.985512)
		(stroke
			(width 0.05715)
			(type default)
		)
		(layer "In9.Cu")
	)
	(gr_arc
		(start 393.033504 -124.634752)
		(mid 392.993148 -124.604331)
		(end 392.944604 -124.590302)
		(stroke
			(width 0.04445)
			(type default)
		)
		(layer "In9.Cu")
	)
	(gr_arc
		(start 393.033504 -124.634752)
		(mid 393.073869 -124.665154)
		(end 393.122404 -124.679202)
		(stroke
			(width 0.04445)
			(type default)
		)
		(layer "In9.Cu")
	)
	(gr_arc
		(start 393.06246 -131.528312)
		(mid 392.970663 -131.55108)
		(end 392.89736 -131.610862)
		(stroke
			(width 0.05715)
			(type default)
		)
		(layer "In9.Cu")
	)
	(gr_line
		(start 393.06246 -131.528312)
		(end 393.40536 -131.528312)
		(stroke
			(width 0.05715)
			(type default)
		)
		(layer "In9.Cu")
	)
	(gr_line
		(start 393.118086 -9.77646)
		(end 393.135612 -9.858756)
		(stroke
			(width 0.05715)
			(type default)
		)
		(layer "In9.Cu")
	)
	(gr_line
		(start 393.118086 -9.77646)
		(end 393.16406 -9.705848)
		(stroke
			(width 0.05715)
			(type default)
		)
		(layer "In9.Cu")
	)
	(gr_line
		(start 393.122404 -124.679202)
		(end 393.389104 -124.679202)
		(stroke
			(width 0.04445)
			(type default)
		)
		(layer "In9.Cu")
	)
	(gr_line
		(start 393.137644 -124.399802)
		(end 393.373864 -124.399802)
		(stroke
			(width 0.04445)
			(type default)
		)
		(layer "In9.Cu")
	)
	(gr_line
		(start 393.215622 -7.507478)
		(end 393.550902 -7.436358)
		(stroke
			(width 0.05715)
			(type default)
		)
		(layer "In9.Cu")
	)
	(gr_line
		(start 393.238228 -10.703814)
		(end 393.319 -10.686542)
		(stroke
			(width 0.05715)
			(type default)
		)
		(layer "In9.Cu")
	)
	(gr_line
		(start 393.292838 -9.508236)
		(end 393.338304 -9.438386)
		(stroke
			(width 0.05715)
			(type default)
		)
		(layer "In9.Cu")
	)
	(gr_line
		(start 393.319 -10.686542)
		(end 393.364212 -10.6172)
		(stroke
			(width 0.05715)
			(type default)
		)
		(layer "In9.Cu")
	)
	(gr_line
		(start 393.338304 -9.438386)
		(end 393.419838 -9.42086)
		(stroke
			(width 0.05715)
			(type default)
		)
		(layer "In9.Cu")
	)
	(gr_arc
		(start 393.389104 -124.679202)
		(mid 393.437647 -124.665166)
		(end 393.478004 -124.634752)
		(stroke
			(width 0.04445)
			(type default)
		)
		(layer "In9.Cu")
	)
	(gr_line
		(start 393.49299 -10.418572)
		(end 393.53871 -10.348468)
		(stroke
			(width 0.05715)
			(type default)
		)
		(layer "In9.Cu")
	)
	(gr_line
		(start 393.521184 -10.266426)
		(end 393.53871 -10.348468)
		(stroke
			(width 0.05715)
			(type default)
		)
		(layer "In9.Cu")
	)
	(gr_line
		(start 393.521184 -10.265664)
		(end 393.521184 -10.265918)
		(stroke
			(width 0.05715)
			(type default)
		)
		(layer "In9.Cu")
	)
	(gr_line
		(start 393.550902 -7.436358)
		(end 393.676378 -7.243318)
		(stroke
			(width 0.05715)
			(type default)
		)
		(layer "In9.Cu")
	)
	(gr_arc
		(start 393.566904 -124.590302)
		(mid 393.518378 -124.604367)
		(end 393.478004 -124.634752)
		(stroke
			(width 0.04445)
			(type default)
		)
		(layer "In9.Cu")
	)
	(gr_arc
		(start 393.57046 -131.610862)
		(mid 393.497179 -131.551036)
		(end 393.40536 -131.528312)
		(stroke
			(width 0.05715)
			(type default)
		)
		(layer "In9.Cu")
	)
	(gr_arc
		(start 393.57046 -131.610862)
		(mid 393.643758 -131.670636)
		(end 393.73556 -131.693412)
		(stroke
			(width 0.05715)
			(type default)
		)
		(layer "In9.Cu")
	)
	(gr_line
		(start 393.75461 -9.349486)
		(end 393.836144 -9.33196)
		(stroke
			(width 0.05715)
			(type default)
		)
		(layer "In9.Cu")
	)
	(gr_line
		(start 393.789408 -127.28067)
		(end 393.789408 -127.302768)
		(stroke
			(width 0.04445)
			(type default)
		)
		(layer "In9.Cu")
	)
	(gr_line
		(start 393.789408 -127.28067)
		(end 393.79906 -127.271018)
		(stroke
			(width 0.04445)
			(type default)
		)
		(layer "In9.Cu")
	)
	(gr_line
		(start 393.800838 -127.26924)
		(end 393.840208 -127.22987)
		(stroke
			(width 0.04445)
			(type default)
		)
		(layer "In9.Cu")
	)
	(gr_line
		(start 393.836144 -9.33196)
		(end 393.906756 -9.37768)
		(stroke
			(width 0.05715)
			(type default)
		)
		(layer "In9.Cu")
	)
	(gr_line
		(start 393.990576 -6.87578)
		(end 394.571474 -6.75259)
		(stroke
			(width 0.05715)
			(type default)
		)
		(layer "In9.Cu")
	)
	(gr_line
		(start 394.00607 -10.164318)
		(end 394.023342 -10.245344)
		(stroke
			(width 0.05715)
			(type default)
		)
		(layer "In9.Cu")
	)
	(gr_line
		(start 394.016484 -7.171182)
		(end 394.209524 -7.296658)
		(stroke
			(width 0.05715)
			(type default)
		)
		(layer "In9.Cu")
	)
	(gr_line
		(start 394.023342 -10.245344)
		(end 394.092684 -10.290556)
		(stroke
			(width 0.05715)
			(type default)
		)
		(layer "In9.Cu")
	)
	(gr_line
		(start 394.030708 -127.22987)
		(end 394.070078 -127.26924)
		(stroke
			(width 0.04445)
			(type default)
		)
		(layer "In9.Cu")
	)
	(gr_line
		(start 394.071856 -127.271018)
		(end 394.081508 -127.28067)
		(stroke
			(width 0.04445)
			(type default)
		)
		(layer "In9.Cu")
	)
	(gr_line
		(start 394.081508 -127.28067)
		(end 394.081508 -127.302768)
		(stroke
			(width 0.04445)
			(type default)
		)
		(layer "In9.Cu")
	)
	(gr_line
		(start 394.104114 -9.506204)
		(end 394.174726 -9.552178)
		(stroke
			(width 0.05715)
			(type default)
		)
		(layer "In9.Cu")
	)
	(gr_arc
		(start 394.147802 -124.89942)
		(mid 394.140913 -124.84928)
		(end 394.11656 -124.804932)
		(stroke
			(width 0.04445)
			(type default)
		)
		(layer "In9.Cu")
	)
	(gr_arc
		(start 394.147802 -124.89942)
		(mid 394.154856 -124.949444)
		(end 394.179298 -124.993654)
		(stroke
			(width 0.04445)
			(type default)
		)
		(layer "In9.Cu")
	)
	(gr_line
		(start 394.174726 -9.552178)
		(end 394.192252 -9.634728)
		(stroke
			(width 0.05715)
			(type default)
		)
		(layer "In9.Cu")
	)
	(gr_line
		(start 394.179298 -124.993654)
		(end 394.36802 -125.182122)
		(stroke
			(width 0.04445)
			(type default)
		)
		(layer "In9.Cu")
	)
	(gr_line
		(start 394.209524 -7.296658)
		(end 394.544804 -7.225284)
		(stroke
			(width 0.05715)
			(type default)
		)
		(layer "In9.Cu")
	)
	(gr_line
		(start 394.273024 -124.691902)
		(end 394.554964 -124.973842)
		(stroke
			(width 0.04445)
			(type default)
		)
		(layer "In9.Cu")
	)
	(gr_line
		(start 394.291312 -10.419334)
		(end 394.361416 -10.465054)
		(stroke
			(width 0.05715)
			(type default)
		)
		(layer "In9.Cu")
	)
	(gr_line
		(start 394.361416 -10.465054)
		(end 394.443966 -10.447528)
		(stroke
			(width 0.05715)
			(type default)
		)
		(layer "In9.Cu")
	)
	(gr_arc
		(start 394.36802 -125.182122)
		(mid 394.412231 -125.20657)
		(end 394.462254 -125.213618)
		(stroke
			(width 0.04445)
			(type default)
		)
		(layer "In9.Cu")
	)
	(gr_line
		(start 394.544804 -7.225284)
		(end 394.670026 -7.032498)
		(stroke
			(width 0.05715)
			(type default)
		)
		(layer "In9.Cu")
	)
	(gr_arc
		(start 394.556488 -125.245114)
		(mid 394.512266 -125.220718)
		(end 394.462254 -125.213618)
		(stroke
			(width 0.04445)
			(type default)
		)
		(layer "In9.Cu")
	)
	(gr_line
		(start 394.583158 -1.827276)
		(end 394.602208 -1.823466)
		(stroke
			(width 0.05715)
			(type default)
		)
		(layer "In9.Cu")
	)
	(gr_line
		(start 394.602208 -1.823466)
		(end 394.621258 -1.827276)
		(stroke
			(width 0.05715)
			(type default)
		)
		(layer "In9.Cu")
	)
	(gr_arc
		(start 394.776452 -125.52807)
		(mid 394.769446 -125.477906)
		(end 394.744956 -125.433582)
		(stroke
			(width 0.04445)
			(type default)
		)
		(layer "In9.Cu")
	)
	(gr_arc
		(start 394.776452 -125.52807)
		(mid 394.783598 -125.578061)
		(end 394.807948 -125.622304)
		(stroke
			(width 0.04445)
			(type default)
		)
		(layer "In9.Cu")
	)
	(gr_line
		(start 394.807948 -125.622304)
		(end 394.996416 -125.810772)
		(stroke
			(width 0.04445)
			(type default)
		)
		(layer "In9.Cu")
	)
	(gr_arc
		(start 394.996416 -125.810772)
		(mid 395.040746 -125.835256)
		(end 395.090904 -125.842268)
		(stroke
			(width 0.04445)
			(type default)
		)
		(layer "In9.Cu")
	)
	(gr_line
		(start 395.016228 -125.435106)
		(end 395.183614 -125.602492)
		(stroke
			(width 0.04445)
			(type default)
		)
		(layer "In9.Cu")
	)
	(gr_line
		(start 395.16685 -107.049316)
		(end 395.504924 -107.049316)
		(stroke
			(width 0.04445)
			(type default)
		)
		(layer "In9.Cu")
	)
	(gr_arc
		(start 395.185138 -125.873764)
		(mid 395.140907 -125.849412)
		(end 395.090904 -125.842268)
		(stroke
			(width 0.04445)
			(type default)
		)
		(layer "In9.Cu")
	)
	(gr_line
		(start 395.40815 -126.168912)
		(end 395.423644 -126.184406)
		(stroke
			(width 0.04445)
			(type default)
		)
		(layer "In9.Cu")
	)
	(gr_line
		(start 395.40815 -126.155196)
		(end 395.40815 -126.168912)
		(stroke
			(width 0.04445)
			(type default)
		)
		(layer "In9.Cu")
	)
	(gr_line
		(start 395.40815 -126.096776)
		(end 395.40815 -126.152656)
		(stroke
			(width 0.04445)
			(type default)
		)
		(layer "In9.Cu")
	)
	(gr_line
		(start 395.416278 -10.240772)
		(end 395.480286 -10.227056)
		(stroke
			(width 0.05715)
			(type default)
		)
		(layer "In9.Cu")
	)
	(gr_line
		(start 395.480286 -10.227056)
		(end 395.521942 -10.176002)
		(stroke
			(width 0.05715)
			(type default)
		)
		(layer "In9.Cu")
	)
	(gr_line
		(start 395.504924 -107.049316)
		(end 395.525498 -107.028742)
		(stroke
			(width 0.04445)
			(type default)
		)
		(layer "In9.Cu")
	)
	(gr_line
		(start 395.527276 -107.026964)
		(end 395.569694 -106.984546)
		(stroke
			(width 0.04445)
			(type default)
		)
		(layer "In9.Cu")
	)
	(gr_line
		(start 395.543278 -125.962156)
		(end 395.59865 -125.962156)
		(stroke
			(width 0.04445)
			(type default)
		)
		(layer "In9.Cu")
	)
	(gr_line
		(start 395.60119 -125.962156)
		(end 395.614906 -125.962156)
		(stroke
			(width 0.04445)
			(type default)
		)
		(layer "In9.Cu")
	)
	(gr_line
		(start 395.614906 -125.962156)
		(end 395.6304 -125.97765)
		(stroke
			(width 0.04445)
			(type default)
		)
		(layer "In9.Cu")
	)
	(gr_line
		(start 395.761718 -106.991658)
		(end 395.797024 -107.026964)
		(stroke
			(width 0.04445)
			(type default)
		)
		(layer "In9.Cu")
	)
	(gr_line
		(start 395.798802 -107.028742)
		(end 395.819376 -107.049316)
		(stroke
			(width 0.04445)
			(type default)
		)
		(layer "In9.Cu")
	)
	(gr_line
		(start 395.819376 -107.049316)
		(end 396.15745 -107.049316)
		(stroke
			(width 0.04445)
			(type default)
		)
		(layer "In9.Cu")
	)
	(gr_line
		(start 396.467076 -8.554212)
		(end 396.494 -8.521192)
		(stroke
			(width 0.05715)
			(type default)
		)
		(layer "In9.Cu")
	)
	(gr_line
		(start 396.494 -8.521192)
		(end 396.53337 -8.50646)
		(stroke
			(width 0.05715)
			(type default)
		)
		(layer "In9.Cu")
	)
	(gr_line
		(start 396.646654 -127.92583)
		(end 396.65148 -127.938784)
		(stroke
			(width 0.05715)
			(type default)
		)
		(layer "In9.Cu")
	)
	(gr_line
		(start 396.646654 -127.9144)
		(end 396.646654 -127.92583)
		(stroke
			(width 0.05715)
			(type default)
		)
		(layer "In9.Cu")
	)
	(gr_line
		(start 396.646654 -127.911606)
		(end 396.646654 -127.9144)
		(stroke
			(width 0.05715)
			(type default)
		)
		(layer "In9.Cu")
	)
	(gr_line
		(start 396.720314 -128.123442)
		(end 396.738602 -128.17221)
		(stroke
			(width 0.05715)
			(type default)
		)
		(layer "In9.Cu")
	)
	(gr_line
		(start 396.738602 -128.17221)
		(end 396.780766 -128.202182)
		(stroke
			(width 0.05715)
			(type default)
		)
		(layer "In9.Cu")
	)
	(gr_line
		(start 396.74165 -2.54889)
		(end 396.7607 -2.5527)
		(stroke
			(width 0.05715)
			(type default)
		)
		(layer "In9.Cu")
	)
	(gr_line
		(start 396.7607 -2.5527)
		(end 396.77975 -2.54889)
		(stroke
			(width 0.05715)
			(type default)
		)
		(layer "In9.Cu")
	)
	(gr_line
		(start 396.78991 -126.568708)
		(end 396.810484 -126.470664)
		(stroke
			(width 0.05715)
			(type default)
		)
		(layer "In9.Cu")
	)
	(gr_line
		(start 396.810484 -126.470664)
		(end 396.899638 -126.424436)
		(stroke
			(width 0.05715)
			(type default)
		)
		(layer "In9.Cu")
	)
	(gr_line
		(start 396.974314 -128.340358)
		(end 397.019526 -128.372616)
		(stroke
			(width 0.05715)
			(type default)
		)
		(layer "In9.Cu")
	)
	(gr_line
		(start 397.14805 -117.811804)
		(end 397.300196 -117.797072)
		(stroke
			(width 0.04445)
			(type default)
		)
		(layer "In9.Cu")
	)
	(gr_line
		(start 397.14805 -105.332276)
		(end 397.486124 -105.332276)
		(stroke
			(width 0.04445)
			(type default)
		)
		(layer "In9.Cu")
	)
	(gr_line
		(start 397.25854 -117.36578)
		(end 397.258794 -117.36578)
		(stroke
			(width 0.04445)
			(type default)
		)
		(layer "In9.Cu")
	)
	(gr_arc
		(start 397.300196 -117.797072)
		(mid 397.446796 -117.719289)
		(end 397.495268 -117.560598)
		(stroke
			(width 0.04445)
			(type default)
		)
		(layer "In9.Cu")
	)
	(gr_line
		(start 397.33728 -128.434846)
		(end 397.51 -128.607566)
		(stroke
			(width 0.05715)
			(type default)
		)
		(layer "In9.Cu")
	)
	(gr_line
		(start 397.33728 -128.018286)
		(end 397.51 -127.845566)
		(stroke
			(width 0.05715)
			(type default)
		)
		(layer "In9.Cu")
	)
	(gr_line
		(start 397.486124 -105.332276)
		(end 397.506698 -105.35285)
		(stroke
			(width 0.04445)
			(type default)
		)
		(layer "In9.Cu")
	)
	(gr_arc
		(start 397.495268 -117.560598)
		(mid 397.417388 -117.414188)
		(end 397.258794 -117.36578)
		(stroke
			(width 0.04445)
			(type default)
		)
		(layer "In9.Cu")
	)
	(gr_line
		(start 397.508476 -105.354628)
		(end 397.550894 -105.397046)
		(stroke
			(width 0.04445)
			(type default)
		)
		(layer "In9.Cu")
	)
	(gr_line
		(start 397.60271 -126.059946)
		(end 397.66621 -126.02718)
		(stroke
			(width 0.05715)
			(type default)
		)
		(layer "In9.Cu")
	)
	(gr_arc
		(start 397.64335 -116.953284)
		(mid 397.238436 -117.104829)
		(end 396.852648 -117.299994)
		(stroke
			(width 0.04445)
			(type default)
		)
		(layer "In9.Cu")
	)
	(gr_line
		(start 397.66621 -126.02718)
		(end 397.735552 -126.043944)
		(stroke
			(width 0.05715)
			(type default)
		)
		(layer "In9.Cu")
	)
	(gr_line
		(start 397.737584 -8.057134)
		(end 398.2974 -7.848346)
		(stroke
			(width 0.05715)
			(type default)
		)
		(layer "In9.Cu")
	)
	(gr_line
		(start 397.742918 -105.389934)
		(end 397.778224 -105.354628)
		(stroke
			(width 0.04445)
			(type default)
		)
		(layer "In9.Cu")
	)
	(gr_line
		(start 397.780002 -105.35285)
		(end 397.800576 -105.332276)
		(stroke
			(width 0.04445)
			(type default)
		)
		(layer "In9.Cu")
	)
	(gr_line
		(start 397.800576 -105.332276)
		(end 398.13865 -105.332276)
		(stroke
			(width 0.04445)
			(type default)
		)
		(layer "In9.Cu")
	)
	(gr_line
		(start 397.806418 -8.345932)
		(end 398.015968 -8.441436)
		(stroke
			(width 0.05715)
			(type default)
		)
		(layer "In9.Cu")
	)
	(gr_line
		(start 398.00149 -10.3632)
		(end 398.08023 -10.346436)
		(stroke
			(width 0.05715)
			(type default)
		)
		(layer "In9.Cu")
	)
	(gr_line
		(start 398.015968 -8.441436)
		(end 398.337024 -8.321548)
		(stroke
			(width 0.05715)
			(type default)
		)
		(layer "In9.Cu")
	)
	(gr_line
		(start 398.08023 -10.346436)
		(end 398.124934 -10.27938)
		(stroke
			(width 0.05715)
			(type default)
		)
		(layer "In9.Cu")
	)
	(gr_line
		(start 398.175988 -126.45009)
		(end 398.221708 -126.461266)
		(stroke
			(width 0.05715)
			(type default)
		)
		(layer "In9.Cu")
	)
	(gr_line
		(start 398.221708 -126.461266)
		(end 398.26565 -126.446026)
		(stroke
			(width 0.05715)
			(type default)
		)
		(layer "In9.Cu")
	)
	(gr_line
		(start 398.337024 -8.321548)
		(end 398.432782 -8.111998)
		(stroke
			(width 0.05715)
			(type default)
		)
		(layer "In9.Cu")
	)
	(gr_line
		(start 398.353534 -1.935734)
		(end 398.372584 -1.931924)
		(stroke
			(width 0.05715)
			(type default)
		)
		(layer "In9.Cu")
	)
	(gr_line
		(start 398.372584 -1.931924)
		(end 398.391634 -1.935734)
		(stroke
			(width 0.05715)
			(type default)
		)
		(layer "In9.Cu")
	)
	(gr_line
		(start 398.687036 -7.702804)
		(end 399.250154 -7.492492)
		(stroke
			(width 0.05715)
			(type default)
		)
		(layer "In9.Cu")
	)
	(gr_line
		(start 398.758156 -7.990586)
		(end 398.96796 -8.08609)
		(stroke
			(width 0.05715)
			(type default)
		)
		(layer "In9.Cu")
	)
	(gr_line
		(start 398.833848 -119.017034)
		(end 398.834102 -119.01678)
		(stroke
			(width 0.04445)
			(type default)
		)
		(layer "In9.Cu")
	)
	(gr_line
		(start 398.834102 -119.01678)
		(end 398.834102 -119.017034)
		(stroke
			(width 0.04445)
			(type default)
		)
		(layer "In9.Cu")
	)
	(gr_line
		(start 398.839436 -125.93955)
		(end 399.40357 -125.745494)
		(stroke
			(width 0.05715)
			(type default)
		)
		(layer "In9.Cu")
	)
	(gr_line
		(start 398.840706 -8.678164)
		(end 398.872202 -8.63092)
		(stroke
			(width 0.05715)
			(type default)
		)
		(layer "In9.Cu")
	)
	(gr_line
		(start 398.872202 -8.63092)
		(end 398.925796 -8.610854)
		(stroke
			(width 0.05715)
			(type default)
		)
		(layer "In9.Cu")
	)
	(gr_line
		(start 398.901412 -126.229872)
		(end 399.107914 -126.330964)
		(stroke
			(width 0.05715)
			(type default)
		)
		(layer "In9.Cu")
	)
	(gr_line
		(start 398.96796 -8.08609)
		(end 399.28927 -7.966202)
		(stroke
			(width 0.05715)
			(type default)
		)
		(layer "In9.Cu")
	)
	(gr_line
		(start 399.107914 -126.330964)
		(end 399.432272 -126.219204)
		(stroke
			(width 0.05715)
			(type default)
		)
		(layer "In9.Cu")
	)
	(gr_line
		(start 399.28927 -7.966202)
		(end 399.384774 -7.756652)
		(stroke
			(width 0.05715)
			(type default)
		)
		(layer "In9.Cu")
	)
	(gr_line
		(start 399.329148 -107.395772)
		(end 399.329148 -107.396026)
		(stroke
			(width 0.04445)
			(type default)
		)
		(layer "In9.Cu")
	)
	(gr_line
		(start 399.398236 -118.9355)
		(end 399.484596 -118.84914)
		(stroke
			(width 0.04445)
			(type default)
		)
		(layer "In9.Cu")
	)
	(gr_line
		(start 399.432272 -126.219204)
		(end 399.53311 -126.012448)
		(stroke
			(width 0.05715)
			(type default)
		)
		(layer "In9.Cu")
	)
	(gr_line
		(start 399.484596 -118.84914)
		(end 399.751296 -118.84914)
		(stroke
			(width 0.04445)
			(type default)
		)
		(layer "In9.Cu")
	)
	(gr_line
		(start 399.588736 -119.12854)
		(end 399.647156 -119.12854)
		(stroke
			(width 0.04445)
			(type default)
		)
		(layer "In9.Cu")
	)
	(gr_line
		(start 399.636996 -7.347712)
		(end 400.202146 -7.136892)
		(stroke
			(width 0.05715)
			(type default)
		)
		(layer "In9.Cu")
	)
	(gr_line
		(start 399.683478 -2.49174)
		(end 399.702528 -2.49555)
		(stroke
			(width 0.05715)
			(type default)
		)
		(layer "In9.Cu")
	)
	(gr_line
		(start 399.702528 -2.49555)
		(end 399.721578 -2.49174)
		(stroke
			(width 0.05715)
			(type default)
		)
		(layer "In9.Cu")
	)
	(gr_line
		(start 399.710148 -7.63524)
		(end 399.919698 -7.730744)
		(stroke
			(width 0.05715)
			(type default)
		)
		(layer "In9.Cu")
	)
	(gr_line
		(start 399.751296 -118.84914)
		(end 399.837656 -118.9355)
		(stroke
			(width 0.04445)
			(type default)
		)
		(layer "In9.Cu")
	)
	(gr_line
		(start 399.779998 -107.316778)
		(end 399.961862 -107.316778)
		(stroke
			(width 0.04445)
			(type default)
		)
		(layer "In9.Cu")
	)
	(gr_line
		(start 399.79854 -125.609604)
		(end 400.362674 -125.415548)
		(stroke
			(width 0.05715)
			(type default)
		)
		(layer "In9.Cu")
	)
	(gr_line
		(start 399.86204 -125.899418)
		(end 400.068796 -126.000256)
		(stroke
			(width 0.05715)
			(type default)
		)
		(layer "In9.Cu")
	)
	(gr_line
		(start 399.919698 -7.730744)
		(end 400.241008 -7.610856)
		(stroke
			(width 0.05715)
			(type default)
		)
		(layer "In9.Cu")
	)
	(gr_line
		(start 399.961862 -107.316778)
		(end 400.009106 -107.269534)
		(stroke
			(width 0.04445)
			(type default)
		)
		(layer "In9.Cu")
	)
	(gr_line
		(start 399.977102 -107.507532)
		(end 400.009106 -107.539536)
		(stroke
			(width 0.04445)
			(type default)
		)
		(layer "In9.Cu")
	)
	(gr_line
		(start 400.010884 -107.541314)
		(end 400.083782 -107.614212)
		(stroke
			(width 0.04445)
			(type default)
		)
		(layer "In9.Cu")
	)
	(gr_line
		(start 400.010884 -107.267756)
		(end 400.083782 -107.194858)
		(stroke
			(width 0.04445)
			(type default)
		)
		(layer "In9.Cu")
	)
	(gr_line
		(start 400.054064 -105.790492)
		(end 400.093688 -105.830116)
		(stroke
			(width 0.04445)
			(type default)
		)
		(layer "In9.Cu")
	)
	(gr_line
		(start 400.054064 -105.599738)
		(end 400.093688 -105.560114)
		(stroke
			(width 0.04445)
			(type default)
		)
		(layer "In9.Cu")
	)
	(gr_line
		(start 400.068796 -126.000256)
		(end 400.3929 -125.88875)
		(stroke
			(width 0.05715)
			(type default)
		)
		(layer "In9.Cu")
	)
	(gr_line
		(start 400.083782 -107.614212)
		(end 400.265646 -107.614212)
		(stroke
			(width 0.050546)
			(type default)
		)
		(layer "In9.Cu")
	)
	(gr_line
		(start 400.095466 -105.831894)
		(end 400.168364 -105.904792)
		(stroke
			(width 0.04445)
			(type default)
		)
		(layer "In9.Cu")
	)
	(gr_line
		(start 400.095466 -105.558336)
		(end 400.168364 -105.485438)
		(stroke
			(width 0.04445)
			(type default)
		)
		(layer "In9.Cu")
	)
	(gr_line
		(start 400.168364 -105.904792)
		(end 400.262344 -105.904792)
		(stroke
			(width 0.04445)
			(type default)
		)
		(layer "In9.Cu")
	)
	(gr_line
		(start 400.168364 -105.485438)
		(end 400.190462 -105.485438)
		(stroke
			(width 0.04445)
			(type default)
		)
		(layer "In9.Cu")
	)
	(gr_line
		(start 400.237198 -10.57656)
		(end 400.317208 -10.559542)
		(stroke
			(width 0.05715)
			(type default)
		)
		(layer "In9.Cu")
	)
	(gr_line
		(start 400.241008 -7.610856)
		(end 400.336512 -7.40156)
		(stroke
			(width 0.05715)
			(type default)
		)
		(layer "In9.Cu")
	)
	(gr_line
		(start 400.317208 -10.559542)
		(end 400.362928 -10.491216)
		(stroke
			(width 0.05715)
			(type default)
		)
		(layer "In9.Cu")
	)
	(gr_line
		(start 400.3929 -125.88875)
		(end 400.493738 -125.681994)
		(stroke
			(width 0.05715)
			(type default)
		)
		(layer "In9.Cu")
	)
	(gr_line
		(start 400.590258 -6.992112)
		(end 401.15236 -6.782308)
		(stroke
			(width 0.05715)
			(type default)
		)
		(layer "In9.Cu")
	)
	(gr_line
		(start 400.66214 -7.279894)
		(end 400.871436 -7.375398)
		(stroke
			(width 0.05715)
			(type default)
		)
		(layer "In9.Cu")
	)
	(gr_line
		(start 400.705066 -119.39778)
		(end 400.746722 -119.439436)
		(stroke
			(width 0.04445)
			(type default)
		)
		(layer "In9.Cu")
	)
	(gr_line
		(start 400.706844 -119.126508)
		(end 400.829272 -119.126508)
		(stroke
			(width 0.04445)
			(type default)
		)
		(layer "In9.Cu")
	)
	(gr_line
		(start 400.829272 -119.126508)
		(end 401.017994 -119.31523)
		(stroke
			(width 0.04445)
			(type default)
		)
		(layer "In9.Cu")
	)
	(gr_line
		(start 400.871436 -7.375398)
		(end 401.192746 -7.25551)
		(stroke
			(width 0.05715)
			(type default)
		)
		(layer "In9.Cu")
	)
	(gr_line
		(start 400.979386 -10.225786)
		(end 400.996912 -10.307828)
		(stroke
			(width 0.05715)
			(type default)
		)
		(layer "In9.Cu")
	)
	(gr_line
		(start 400.979386 -10.225786)
		(end 401.025106 -10.155174)
		(stroke
			(width 0.05715)
			(type default)
		)
		(layer "In9.Cu")
	)
	(gr_line
		(start 401.017994 -119.31523)
		(end 401.017994 -119.437658)
		(stroke
			(width 0.04445)
			(type default)
		)
		(layer "In9.Cu")
	)
	(gr_line
		(start 401.078954 -11.059922)
		(end 401.16125 -11.042396)
		(stroke
			(width 0.05715)
			(type default)
		)
		(layer "In9.Cu")
	)
	(gr_line
		(start 401.153122 -9.958324)
		(end 401.199096 -9.887712)
		(stroke
			(width 0.05715)
			(type default)
		)
		(layer "In9.Cu")
	)
	(gr_line
		(start 401.15998 -8.76808)
		(end 401.192492 -8.719312)
		(stroke
			(width 0.05715)
			(type default)
		)
		(layer "In9.Cu")
	)
	(gr_line
		(start 401.16125 -11.042396)
		(end 401.20697 -10.971784)
		(stroke
			(width 0.05715)
			(type default)
		)
		(layer "In9.Cu")
	)
	(gr_line
		(start 401.192492 -8.719312)
		(end 401.24761 -8.698738)
		(stroke
			(width 0.05715)
			(type default)
		)
		(layer "In9.Cu")
	)
	(gr_line
		(start 401.192746 -7.25551)
		(end 401.287996 -7.046214)
		(stroke
			(width 0.05715)
			(type default)
		)
		(layer "In9.Cu")
	)
	(gr_line
		(start 401.199096 -9.887712)
		(end 401.281138 -9.870186)
		(stroke
			(width 0.05715)
			(type default)
		)
		(layer "In9.Cu")
	)
	(gr_line
		(start 401.334732 -10.774172)
		(end 401.380452 -10.703306)
		(stroke
			(width 0.05715)
			(type default)
		)
		(layer "In9.Cu")
	)
	(gr_line
		(start 401.362926 -10.62101)
		(end 401.362926 -10.621264)
		(stroke
			(width 0.05715)
			(type default)
		)
		(layer "In9.Cu")
	)
	(gr_line
		(start 401.362926 -10.620756)
		(end 401.380452 -10.703306)
		(stroke
			(width 0.05715)
			(type default)
		)
		(layer "In9.Cu")
	)
	(gr_line
		(start 401.544028 -6.636258)
		(end 401.588224 -6.619748)
		(stroke
			(width 0.05715)
			(type default)
		)
		(layer "In9.Cu")
	)
	(gr_line
		(start 401.588224 -6.619748)
		(end 401.634452 -6.629654)
		(stroke
			(width 0.05715)
			(type default)
		)
		(layer "In9.Cu")
	)
	(gr_line
		(start 401.615656 -9.798812)
		(end 401.697952 -9.781286)
		(stroke
			(width 0.05715)
			(type default)
		)
		(layer "In9.Cu")
	)
	(gr_line
		(start 401.64512 -120.20296)
		(end 401.66036 -120.269254)
		(stroke
			(width 0.04445)
			(type default)
		)
		(layer "In9.Cu")
	)
	(gr_line
		(start 401.66036 -120.269254)
		(end 401.679156 -120.280938)
		(stroke
			(width 0.04445)
			(type default)
		)
		(layer "In9.Cu")
	)
	(gr_line
		(start 401.697952 -9.781286)
		(end 401.76831 -9.827006)
		(stroke
			(width 0.05715)
			(type default)
		)
		(layer "In9.Cu")
	)
	(gr_line
		(start 401.748498 -120.037098)
		(end 401.8153 -120.021604)
		(stroke
			(width 0.04445)
			(type default)
		)
		(layer "In9.Cu")
	)
	(gr_line
		(start 401.8153 -120.021604)
		(end 401.834096 -120.033288)
		(stroke
			(width 0.04445)
			(type default)
		)
		(layer "In9.Cu")
	)
	(gr_line
		(start 401.834858 -10.457688)
		(end 401.85213 -10.53846)
		(stroke
			(width 0.05715)
			(type default)
		)
		(layer "In9.Cu")
	)
	(gr_line
		(start 401.85213 -10.53846)
		(end 401.92198 -10.583926)
		(stroke
			(width 0.05715)
			(type default)
		)
		(layer "In9.Cu")
	)
	(gr_line
		(start 401.955254 -7.4803)
		(end 401.99945 -7.46379)
		(stroke
			(width 0.05715)
			(type default)
		)
		(layer "In9.Cu")
	)
	(gr_line
		(start 401.96643 -9.955784)
		(end 402.036026 -10.000996)
		(stroke
			(width 0.05715)
			(type default)
		)
		(layer "In9.Cu")
	)
	(gr_line
		(start 401.99945 -7.46379)
		(end 402.045678 -7.473696)
		(stroke
			(width 0.05715)
			(type default)
		)
		(layer "In9.Cu")
	)
	(gr_line
		(start 402.036026 -10.000996)
		(end 402.053298 -10.081514)
		(stroke
			(width 0.05715)
			(type default)
		)
		(layer "In9.Cu")
	)
	(gr_line
		(start 402.147278 -124.801376)
		(end 402.205952 -124.781056)
		(stroke
			(width 0.05715)
			(type default)
		)
		(layer "In9.Cu")
	)
	(gr_line
		(start 402.169884 -10.742422)
		(end 402.38553 -10.779506)
		(stroke
			(width 0.05715)
			(type default)
		)
		(layer "In9.Cu")
	)
	(gr_line
		(start 402.205952 -124.781056)
		(end 402.265134 -124.801122)
		(stroke
			(width 0.05715)
			(type default)
		)
		(layer "In9.Cu")
	)
	(gr_line
		(start 402.219414 -1.694688)
		(end 402.806916 -1.57734)
		(stroke
			(width 0.05715)
			(type default)
		)
		(layer "In9.Cu")
	)
	(gr_line
		(start 402.244052 -1.990344)
		(end 402.435568 -2.118106)
		(stroke
			(width 0.05715)
			(type default)
		)
		(layer "In9.Cu")
	)
	(gr_line
		(start 402.278088 -10.467086)
		(end 402.323046 -10.49655)
		(stroke
			(width 0.05715)
			(type default)
		)
		(layer "In9.Cu")
	)
	(gr_line
		(start 402.323046 -10.49655)
		(end 402.328634 -10.495534)
		(stroke
			(width 0.05715)
			(type default)
		)
		(layer "In9.Cu")
	)
	(gr_line
		(start 402.328634 -10.495534)
		(end 402.330412 -10.49528)
		(stroke
			(width 0.05715)
			(type default)
		)
		(layer "In9.Cu")
	)
	(gr_line
		(start 402.330412 -10.49528)
		(end 402.37918 -10.484866)
		(stroke
			(width 0.05715)
			(type default)
		)
		(layer "In9.Cu")
	)
	(gr_line
		(start 402.387054 -148.72462)
		(end 402.387054 -149.13864)
		(stroke
			(width 0.05715)
			(type default)
		)
		(layer "In9.Cu")
	)
	(gr_line
		(start 402.387054 -146.323304)
		(end 402.387054 -146.737324)
		(stroke
			(width 0.05715)
			(type default)
		)
		(layer "In9.Cu")
	)
	(gr_line
		(start 402.387054 -142.529052)
		(end 402.387054 -142.943072)
		(stroke
			(width 0.05715)
			(type default)
		)
		(layer "In9.Cu")
	)
	(gr_line
		(start 402.408136 -8.266938)
		(end 402.45284 -8.250428)
		(stroke
			(width 0.05715)
			(type default)
		)
		(layer "In9.Cu")
	)
	(gr_line
		(start 402.435568 -2.118106)
		(end 402.771864 -2.050796)
		(stroke
			(width 0.05715)
			(type default)
		)
		(layer "In9.Cu")
	)
	(gr_line
		(start 402.45284 -8.250428)
		(end 402.499576 -8.260334)
		(stroke
			(width 0.05715)
			(type default)
		)
		(layer "In9.Cu")
	)
	(gr_line
		(start 402.46427 -120.771666)
		(end 402.474176 -120.778016)
		(stroke
			(width 0.05715)
			(type default)
		)
		(layer "In9.Cu")
	)
	(gr_line
		(start 402.474176 -120.778016)
		(end 402.486114 -120.78081)
		(stroke
			(width 0.05715)
			(type default)
		)
		(layer "In9.Cu")
	)
	(gr_line
		(start 402.637752 -9.542018)
		(end 402.655278 -9.623298)
		(stroke
			(width 0.05715)
			(type default)
		)
		(layer "In9.Cu")
	)
	(gr_line
		(start 402.637752 -9.542018)
		(end 402.683472 -9.471406)
		(stroke
			(width 0.05715)
			(type default)
		)
		(layer "In9.Cu")
	)
	(gr_arc
		(start 402.679154 -148.42998)
		(mid 402.701891 -148.521795)
		(end 402.761704 -148.59508)
		(stroke
			(width 0.05715)
			(type default)
		)
		(layer "In9.Cu")
	)
	(gr_arc
		(start 402.679154 -146.028664)
		(mid 402.701886 -146.120483)
		(end 402.761704 -146.193764)
		(stroke
			(width 0.05715)
			(type default)
		)
		(layer "In9.Cu")
	)
	(gr_arc
		(start 402.679154 -142.234412)
		(mid 402.701868 -142.326245)
		(end 402.761704 -142.399512)
		(stroke
			(width 0.05715)
			(type default)
		)
		(layer "In9.Cu")
	)
	(gr_line
		(start 402.68144 -10.7188)
		(end 402.763482 -10.701274)
		(stroke
			(width 0.05715)
			(type default)
		)
		(layer "In9.Cu")
	)
	(gr_arc
		(start 402.761704 -149.26818)
		(mid 402.701912 -149.341475)
		(end 402.679154 -149.43328)
		(stroke
			(width 0.05715)
			(type default)
		)
		(layer "In9.Cu")
	)
	(gr_arc
		(start 402.761704 -149.26818)
		(mid 402.82153 -149.194899)
		(end 402.844254 -149.10308)
		(stroke
			(width 0.05715)
			(type default)
		)
		(layer "In9.Cu")
	)
	(gr_arc
		(start 402.761704 -146.866864)
		(mid 402.701907 -146.940158)
		(end 402.679154 -147.031964)
		(stroke
			(width 0.05715)
			(type default)
		)
		(layer "In9.Cu")
	)
	(gr_arc
		(start 402.761704 -146.866864)
		(mid 402.82153 -146.793583)
		(end 402.844254 -146.701764)
		(stroke
			(width 0.05715)
			(type default)
		)
		(layer "In9.Cu")
	)
	(gr_arc
		(start 402.761704 -143.072612)
		(mid 402.701923 -143.145909)
		(end 402.679154 -143.237712)
		(stroke
			(width 0.05715)
			(type default)
		)
		(layer "In9.Cu")
	)
	(gr_arc
		(start 402.761704 -143.072612)
		(mid 402.82153 -142.999331)
		(end 402.844254 -142.907512)
		(stroke
			(width 0.05715)
			(type default)
		)
		(layer "In9.Cu")
	)
	(gr_line
		(start 402.763482 -10.701274)
		(end 402.80971 -10.630408)
		(stroke
			(width 0.05715)
			(type default)
		)
		(layer "In9.Cu")
	)
	(gr_line
		(start 402.771864 -2.050796)
		(end 402.899372 -1.859534)
		(stroke
			(width 0.05715)
			(type default)
		)
		(layer "In9.Cu")
	)
	(gr_line
		(start 402.811488 -9.274556)
		(end 402.857462 -9.203944)
		(stroke
			(width 0.05715)
			(type default)
		)
		(layer "In9.Cu")
	)
	(gr_line
		(start 402.833332 -15.74927)
		(end 402.855176 -15.744444)
		(stroke
			(width 0.05715)
			(type default)
		)
		(layer "In9.Cu")
	)
	(gr_arc
		(start 402.844254 -148.76018)
		(mid 402.821486 -148.668383)
		(end 402.761704 -148.59508)
		(stroke
			(width 0.05715)
			(type default)
		)
		(layer "In9.Cu")
	)
	(gr_line
		(start 402.844254 -148.76018)
		(end 402.844254 -149.10308)
		(stroke
			(width 0.05715)
			(type default)
		)
		(layer "In9.Cu")
	)
	(gr_arc
		(start 402.844254 -146.358864)
		(mid 402.821486 -146.267067)
		(end 402.761704 -146.193764)
		(stroke
			(width 0.05715)
			(type default)
		)
		(layer "In9.Cu")
	)
	(gr_line
		(start 402.844254 -146.358864)
		(end 402.844254 -146.701764)
		(stroke
			(width 0.05715)
			(type default)
		)
		(layer "In9.Cu")
	)
	(gr_arc
		(start 402.844254 -142.564612)
		(mid 402.821486 -142.472815)
		(end 402.761704 -142.399512)
		(stroke
			(width 0.05715)
			(type default)
		)
		(layer "In9.Cu")
	)
	(gr_line
		(start 402.844254 -142.564612)
		(end 402.844254 -142.907512)
		(stroke
			(width 0.05715)
			(type default)
		)
		(layer "In9.Cu")
	)
	(gr_line
		(start 402.855176 -15.744444)
		(end 402.877782 -15.749016)
		(stroke
			(width 0.05715)
			(type default)
		)
		(layer "In9.Cu")
	)
	(gr_line
		(start 402.857462 -9.203944)
		(end 402.939504 -9.186418)
		(stroke
			(width 0.05715)
			(type default)
		)
		(layer "In9.Cu")
	)
	(gr_arc
		(start 402.918422 -127.486918)
		(mid 402.845141 -127.427092)
		(end 402.753322 -127.404368)
		(stroke
			(width 0.05715)
			(type default)
		)
		(layer "In9.Cu")
	)
	(gr_arc
		(start 402.918422 -127.486918)
		(mid 402.991722 -127.54669)
		(end 403.083522 -127.569468)
		(stroke
			(width 0.05715)
			(type default)
		)
		(layer "In9.Cu")
	)
	(gr_line
		(start 403.021292 -125.36678)
		(end 403.0599 -125.379988)
		(stroke
			(width 0.05715)
			(type default)
		)
		(layer "In9.Cu")
	)
	(gr_line
		(start 403.035008 -10.283698)
		(end 403.080474 -10.214102)
		(stroke
			(width 0.05715)
			(type default)
		)
		(layer "In9.Cu")
	)
	(gr_line
		(start 403.047962 -127.112268)
		(end 403.461982 -127.112268)
		(stroke
			(width 0.05715)
			(type default)
		)
		(layer "In9.Cu")
	)
	(gr_line
		(start 403.0599 -125.379988)
		(end 403.10054 -125.371606)
		(stroke
			(width 0.05715)
			(type default)
		)
		(layer "In9.Cu")
	)
	(gr_line
		(start 403.062948 -10.132822)
		(end 403.080474 -10.214102)
		(stroke
			(width 0.05715)
			(type default)
		)
		(layer "In9.Cu")
	)
	(gr_line
		(start 403.083522 -127.569468)
		(end 403.426422 -127.569468)
		(stroke
			(width 0.05715)
			(type default)
		)
		(layer "In9.Cu")
	)
	(gr_line
		(start 403.217126 -1.495552)
		(end 403.80158 -1.378712)
		(stroke
			(width 0.05715)
			(type default)
		)
		(layer "In9.Cu")
	)
	(gr_line
		(start 403.240494 -1.791208)
		(end 403.431756 -1.91897)
		(stroke
			(width 0.05715)
			(type default)
		)
		(layer "In9.Cu")
	)
	(gr_line
		(start 403.274022 -9.115044)
		(end 403.356318 -9.097518)
		(stroke
			(width 0.05715)
			(type default)
		)
		(layer "In9.Cu")
	)
	(gr_line
		(start 403.356318 -9.097518)
		(end 403.426676 -9.143238)
		(stroke
			(width 0.05715)
			(type default)
		)
		(layer "In9.Cu")
	)
	(gr_arc
		(start 403.426422 -127.569468)
		(mid 403.518254 -127.546752)
		(end 403.591522 -127.486918)
		(stroke
			(width 0.05715)
			(type default)
		)
		(layer "In9.Cu")
	)
	(gr_line
		(start 403.431756 -1.91897)
		(end 403.768052 -1.85166)
		(stroke
			(width 0.05715)
			(type default)
		)
		(layer "In9.Cu")
	)
	(gr_line
		(start 403.573996 -10.150602)
		(end 403.591776 -10.23366)
		(stroke
			(width 0.05715)
			(type default)
		)
		(layer "In9.Cu")
	)
	(gr_line
		(start 403.591776 -10.23366)
		(end 403.662896 -10.279888)
		(stroke
			(width 0.05715)
			(type default)
		)
		(layer "In9.Cu")
	)
	(gr_line
		(start 403.624796 -9.272016)
		(end 403.694392 -9.317228)
		(stroke
			(width 0.05715)
			(type default)
		)
		(layer "In9.Cu")
	)
	(gr_line
		(start 403.647148 -121.049034)
		(end 403.686772 -121.058178)
		(stroke
			(width 0.05715)
			(type default)
		)
		(layer "In9.Cu")
	)
	(gr_line
		(start 403.686772 -121.058178)
		(end 403.724872 -121.046748)
		(stroke
			(width 0.05715)
			(type default)
		)
		(layer "In9.Cu")
	)
	(gr_line
		(start 403.694392 -9.317228)
		(end 403.711664 -9.397746)
		(stroke
			(width 0.05715)
			(type default)
		)
		(layer "In9.Cu")
	)
	(gr_line
		(start 403.744938 -3.550666)
		(end 403.787102 -3.534918)
		(stroke
			(width 0.05715)
			(type default)
		)
		(layer "In9.Cu")
	)
	(gr_arc
		(start 403.756622 -127.404368)
		(mid 403.664825 -127.427136)
		(end 403.591522 -127.486918)
		(stroke
			(width 0.05715)
			(type default)
		)
		(layer "In9.Cu")
	)
	(gr_line
		(start 403.759924 -4.23037)
		(end 403.802088 -4.214622)
		(stroke
			(width 0.05715)
			(type default)
		)
		(layer "In9.Cu")
	)
	(gr_line
		(start 403.768052 -1.85166)
		(end 403.89556 -1.660398)
		(stroke
			(width 0.05715)
			(type default)
		)
		(layer "In9.Cu")
	)
	(gr_line
		(start 403.787102 -3.534918)
		(end 403.831806 -3.544062)
		(stroke
			(width 0.05715)
			(type default)
		)
		(layer "In9.Cu")
	)
	(gr_line
		(start 403.802088 -4.214622)
		(end 403.803866 -4.214876)
		(stroke
			(width 0.05715)
			(type default)
		)
		(layer "In9.Cu")
	)
	(gr_line
		(start 403.803866 -4.214876)
		(end 403.847554 -4.223766)
		(stroke
			(width 0.05715)
			(type default)
		)
		(layer "In9.Cu")
	)
	(gr_line
		(start 403.861778 -10.408666)
		(end 403.930358 -10.453116)
		(stroke
			(width 0.05715)
			(type default)
		)
		(layer "In9.Cu")
	)
	(gr_line
		(start 403.892258 -8.853932)
		(end 403.91588 -8.859012)
		(stroke
			(width 0.05715)
			(type default)
		)
		(layer "In9.Cu")
	)
	(gr_line
		(start 403.91588 -8.859012)
		(end 403.938486 -8.854186)
		(stroke
			(width 0.05715)
			(type default)
		)
		(layer "In9.Cu")
	)
	(gr_line
		(start 403.930358 -10.453116)
		(end 404.010368 -10.436098)
		(stroke
			(width 0.05715)
			(type default)
		)
		(layer "In9.Cu")
	)
	(gr_line
		(start 403.963124 -8.1788)
		(end 403.986238 -8.18388)
		(stroke
			(width 0.05715)
			(type default)
		)
		(layer "In9.Cu")
	)
	(gr_line
		(start 403.986238 -8.18388)
		(end 404.009352 -8.1788)
		(stroke
			(width 0.05715)
			(type default)
		)
		(layer "In9.Cu")
	)
	(gr_line
		(start 404.140924 -4.975352)
		(end 404.183088 -4.959604)
		(stroke
			(width 0.05715)
			(type default)
		)
		(layer "In9.Cu")
	)
	(gr_line
		(start 404.171404 -7.465822)
		(end 404.194518 -7.470902)
		(stroke
			(width 0.05715)
			(type default)
		)
		(layer "In9.Cu")
	)
	(gr_line
		(start 404.183088 -4.959604)
		(end 404.228046 -4.968748)
		(stroke
			(width 0.05715)
			(type default)
		)
		(layer "In9.Cu")
	)
	(gr_line
		(start 404.194518 -7.470902)
		(end 404.217632 -7.465822)
		(stroke
			(width 0.05715)
			(type default)
		)
		(layer "In9.Cu")
	)
	(gr_line
		(start 404.254716 -148.168614)
		(end 404.254716 -148.582634)
		(stroke
			(width 0.05715)
			(type default)
		)
		(layer "In9.Cu")
	)
	(gr_arc
		(start 404.264622 -127.486918)
		(mid 404.191341 -127.427092)
		(end 404.099522 -127.404368)
		(stroke
			(width 0.05715)
			(type default)
		)
		(layer "In9.Cu")
	)
	(gr_arc
		(start 404.264622 -127.486918)
		(mid 404.337922 -127.54669)
		(end 404.429722 -127.569468)
		(stroke
			(width 0.05715)
			(type default)
		)
		(layer "In9.Cu")
	)
	(gr_line
		(start 404.338536 -1.271524)
		(end 404.357586 -1.267714)
		(stroke
			(width 0.05715)
			(type default)
		)
		(layer "In9.Cu")
	)
	(gr_line
		(start 404.357586 -1.267714)
		(end 404.377144 -1.271778)
		(stroke
			(width 0.05715)
			(type default)
		)
		(layer "In9.Cu")
	)
	(gr_line
		(start 404.394162 -127.112268)
		(end 404.808182 -127.112268)
		(stroke
			(width 0.05715)
			(type default)
		)
		(layer "In9.Cu")
	)
	(gr_line
		(start 404.426674 -106.522774)
		(end 404.729442 -106.825542)
		(stroke
			(width 0.050546)
			(type default)
		)
		(layer "In9.Cu")
	)
	(gr_line
		(start 404.429722 -127.569468)
		(end 404.772622 -127.569468)
		(stroke
			(width 0.05715)
			(type default)
		)
		(layer "In9.Cu")
	)
	(gr_line
		(start 404.44801 -120.524524)
		(end 404.48738 -120.51284)
		(stroke
			(width 0.05715)
			(type default)
		)
		(layer "In9.Cu")
	)
	(gr_line
		(start 404.48738 -120.51284)
		(end 404.526496 -120.522238)
		(stroke
			(width 0.05715)
			(type default)
		)
		(layer "In9.Cu")
	)
	(gr_arc
		(start 404.546816 -147.873974)
		(mid 404.569548 -147.965794)
		(end 404.629366 -148.039074)
		(stroke
			(width 0.05715)
			(type default)
		)
		(layer "In9.Cu")
	)
	(gr_arc
		(start 404.629366 -148.712174)
		(mid 404.569582 -148.785472)
		(end 404.546816 -148.877274)
		(stroke
			(width 0.05715)
			(type default)
		)
		(layer "In9.Cu")
	)
	(gr_arc
		(start 404.629366 -148.712174)
		(mid 404.689192 -148.638893)
		(end 404.711916 -148.547074)
		(stroke
			(width 0.05715)
			(type default)
		)
		(layer "In9.Cu")
	)
	(gr_arc
		(start 404.711916 -148.204174)
		(mid 404.689148 -148.112377)
		(end 404.629366 -148.039074)
		(stroke
			(width 0.05715)
			(type default)
		)
		(layer "In9.Cu")
	)
	(gr_line
		(start 404.711916 -148.204174)
		(end 404.711916 -148.547074)
		(stroke
			(width 0.05715)
			(type default)
		)
		(layer "In9.Cu")
	)
	(gr_line
		(start 404.729442 -106.825542)
		(end 405.03348 -106.825542)
		(stroke
			(width 0.050546)
			(type default)
		)
		(layer "In9.Cu")
	)
	(gr_arc
		(start 404.772622 -127.569468)
		(mid 404.864454 -127.546752)
		(end 404.937722 -127.486918)
		(stroke
			(width 0.05715)
			(type default)
		)
		(layer "In9.Cu")
	)
	(gr_line
		(start 404.811484 -4.042664)
		(end 404.833074 -4.046982)
		(stroke
			(width 0.05715)
			(type default)
		)
		(layer "In9.Cu")
	)
	(gr_line
		(start 404.822914 -5.388356)
		(end 404.84425 -5.392674)
		(stroke
			(width 0.05715)
			(type default)
		)
		(layer "In9.Cu")
	)
	(gr_line
		(start 404.833074 -4.046982)
		(end 404.854156 -4.042664)
		(stroke
			(width 0.05715)
			(type default)
		)
		(layer "In9.Cu")
	)
	(gr_line
		(start 404.840694 -4.725162)
		(end 404.861522 -4.72948)
		(stroke
			(width 0.05715)
			(type default)
		)
		(layer "In9.Cu")
	)
	(gr_line
		(start 404.84425 -5.392674)
		(end 404.865332 -5.388356)
		(stroke
			(width 0.05715)
			(type default)
		)
		(layer "In9.Cu")
	)
	(gr_line
		(start 404.846028 -106.10088)
		(end 404.916894 -106.10088)
		(stroke
			(width 0.050546)
			(type default)
		)
		(layer "In9.Cu")
	)
	(gr_line
		(start 404.861522 -4.72948)
		(end 404.882604 -4.725162)
		(stroke
			(width 0.05715)
			(type default)
		)
		(layer "In9.Cu")
	)
	(gr_line
		(start 405.03348 -106.825542)
		(end 405.336248 -106.522774)
		(stroke
			(width 0.050546)
			(type default)
		)
		(layer "In9.Cu")
	)
	(gr_line
		(start 405.050498 -10.214864)
		(end 405.128984 -10.198354)
		(stroke
			(width 0.05715)
			(type default)
		)
		(layer "In9.Cu")
	)
	(gr_arc
		(start 405.102822 -127.404368)
		(mid 405.011025 -127.427136)
		(end 404.937722 -127.486918)
		(stroke
			(width 0.05715)
			(type default)
		)
		(layer "In9.Cu")
	)
	(gr_line
		(start 405.128984 -10.198354)
		(end 405.174196 -10.13079)
		(stroke
			(width 0.05715)
			(type default)
		)
		(layer "In9.Cu")
	)
	(gr_line
		(start 405.171402 -120.976644)
		(end 405.217376 -120.987566)
		(stroke
			(width 0.05715)
			(type default)
		)
		(layer "In9.Cu")
	)
	(gr_line
		(start 405.217376 -120.987566)
		(end 405.261826 -120.972072)
		(stroke
			(width 0.05715)
			(type default)
		)
		(layer "In9.Cu")
	)
	(gr_line
		(start 405.290528 -124.618496)
		(end 405.318976 -124.612654)
		(stroke
			(width 0.05715)
			(type default)
		)
		(layer "In9.Cu")
	)
	(gr_line
		(start 405.318976 -124.612654)
		(end 405.34717 -124.619766)
		(stroke
			(width 0.05715)
			(type default)
		)
		(layer "In9.Cu")
	)
	(gr_line
		(start 405.514048 -16.583152)
		(end 405.535384 -16.58747)
		(stroke
			(width 0.05715)
			(type default)
		)
		(layer "In9.Cu")
	)
	(gr_line
		(start 405.535384 -16.58747)
		(end 405.556466 -16.583152)
		(stroke
			(width 0.05715)
			(type default)
		)
		(layer "In9.Cu")
	)
	(gr_arc
		(start 405.549862 -152.90673)
		(mid 405.630928 -152.955629)
		(end 405.725122 -152.96515)
		(stroke
			(width 0.05715)
			(type default)
		)
		(layer "In9.Cu")
	)
	(gr_line
		(start 405.551386 -153.321766)
		(end 405.844248 -153.614628)
		(stroke
			(width 0.05715)
			(type default)
		)
		(layer "In9.Cu")
	)
	(gr_line
		(start 405.584406 -1.811274)
		(end 405.625808 -1.819656)
		(stroke
			(width 0.05715)
			(type default)
		)
		(layer "In9.Cu")
	)
	(gr_arc
		(start 405.610822 -127.486918)
		(mid 405.537541 -127.427092)
		(end 405.445722 -127.404368)
		(stroke
			(width 0.05715)
			(type default)
		)
		(layer "In9.Cu")
	)
	(gr_arc
		(start 405.610822 -127.486918)
		(mid 405.684122 -127.54669)
		(end 405.775922 -127.569468)
		(stroke
			(width 0.05715)
			(type default)
		)
		(layer "In9.Cu")
	)
	(gr_line
		(start 405.625808 -1.819656)
		(end 405.666448 -1.805686)
		(stroke
			(width 0.05715)
			(type default)
		)
		(layer "In9.Cu")
	)
	(gr_line
		(start 405.634698 -8.914638)
		(end 405.67991 -8.847074)
		(stroke
			(width 0.05715)
			(type default)
		)
		(layer "In9.Cu")
	)
	(gr_line
		(start 405.67991 -8.847074)
		(end 405.759412 -8.830056)
		(stroke
			(width 0.05715)
			(type default)
		)
		(layer "In9.Cu")
	)
	(gr_line
		(start 405.714454 -4.920234)
		(end 405.733504 -4.916424)
		(stroke
			(width 0.05715)
			(type default)
		)
		(layer "In9.Cu")
	)
	(gr_line
		(start 405.733504 -4.916424)
		(end 405.752554 -4.920234)
		(stroke
			(width 0.05715)
			(type default)
		)
		(layer "In9.Cu")
	)
	(gr_line
		(start 405.740362 -127.112268)
		(end 406.154382 -127.112268)
		(stroke
			(width 0.05715)
			(type default)
		)
		(layer "In9.Cu")
	)
	(gr_line
		(start 405.75738 -3.564636)
		(end 405.776938 -3.560572)
		(stroke
			(width 0.05715)
			(type default)
		)
		(layer "In9.Cu")
	)
	(gr_line
		(start 405.76373 -4.251198)
		(end 405.78278 -4.247388)
		(stroke
			(width 0.05715)
			(type default)
		)
		(layer "In9.Cu")
	)
	(gr_line
		(start 405.775922 -127.569468)
		(end 406.118822 -127.569468)
		(stroke
			(width 0.05715)
			(type default)
		)
		(layer "In9.Cu")
	)
	(gr_line
		(start 405.776938 -3.560572)
		(end 405.795988 -3.564382)
		(stroke
			(width 0.05715)
			(type default)
		)
		(layer "In9.Cu")
	)
	(gr_line
		(start 405.78278 -4.247388)
		(end 405.80183 -4.251198)
		(stroke
			(width 0.05715)
			(type default)
		)
		(layer "In9.Cu")
	)
	(gr_arc
		(start 405.900128 -153.02357)
		(mid 405.819181 -152.974711)
		(end 405.725122 -152.96515)
		(stroke
			(width 0.05715)
			(type default)
		)
		(layer "In9.Cu")
	)
	(gr_line
		(start 405.900128 -153.02357)
		(end 406.142698 -153.26614)
		(stroke
			(width 0.05715)
			(type default)
		)
		(layer "In9.Cu")
	)
	(gr_arc
		(start 406.118822 -127.569468)
		(mid 406.210654 -127.546752)
		(end 406.283922 -127.486918)
		(stroke
			(width 0.05715)
			(type default)
		)
		(layer "In9.Cu")
	)
	(gr_line
		(start 406.122124 -120.361456)
		(end 406.18029 -120.341136)
		(stroke
			(width 0.05715)
			(type default)
		)
		(layer "In9.Cu")
	)
	(gr_line
		(start 406.18029 -120.341136)
		(end 406.237948 -120.360186)
		(stroke
			(width 0.05715)
			(type default)
		)
		(layer "In9.Cu")
	)
	(gr_arc
		(start 406.201118 -153.441146)
		(mid 406.191528 -153.347097)
		(end 406.142698 -153.26614)
		(stroke
			(width 0.05715)
			(type default)
		)
		(layer "In9.Cu")
	)
	(gr_arc
		(start 406.201118 -153.441146)
		(mid 406.210565 -153.535179)
		(end 406.259284 -153.616152)
		(stroke
			(width 0.05715)
			(type default)
		)
		(layer "In9.Cu")
	)
	(gr_line
		(start 406.357074 -140.623544)
		(end 406.649936 -140.330682)
		(stroke
			(width 0.05715)
			(type default)
		)
		(layer "In9.Cu")
	)
	(gr_arc
		(start 406.449022 -127.404368)
		(mid 406.357225 -127.427136)
		(end 406.283922 -127.486918)
		(stroke
			(width 0.05715)
			(type default)
		)
		(layer "In9.Cu")
	)
	(gr_line
		(start 406.478486 -16.395192)
		(end 406.560274 -16.378428)
		(stroke
			(width 0.05715)
			(type default)
		)
		(layer "In9.Cu")
	)
	(gr_arc
		(start 406.530556 -140.980414)
		(mid 406.436533 -140.989879)
		(end 406.35555 -141.03858)
		(stroke
			(width 0.05715)
			(type default)
		)
		(layer "In9.Cu")
	)
	(gr_arc
		(start 406.530556 -140.980414)
		(mid 406.624618 -140.970853)
		(end 406.705562 -140.921994)
		(stroke
			(width 0.05715)
			(type default)
		)
		(layer "In9.Cu")
	)
	(gr_line
		(start 406.560274 -16.378428)
		(end 406.606502 -16.308578)
		(stroke
			(width 0.05715)
			(type default)
		)
		(layer "In9.Cu")
	)
	(gr_line
		(start 406.61209 -1.47701)
		(end 406.612344 -1.47701)
		(stroke
			(width 0.05715)
			(type default)
		)
		(layer "In9.Cu")
	)
	(gr_line
		(start 406.70226 -120.82399)
		(end 406.805638 -121.029222)
		(stroke
			(width 0.05715)
			(type default)
		)
		(layer "In9.Cu")
	)
	(gr_line
		(start 406.705562 -140.921994)
		(end 406.948132 -140.679424)
		(stroke
			(width 0.05715)
			(type default)
		)
		(layer "In9.Cu")
	)
	(gr_line
		(start 406.805638 -121.029222)
		(end 407.131266 -121.136918)
		(stroke
			(width 0.05715)
			(type default)
		)
		(layer "In9.Cu")
	)
	(gr_line
		(start 406.82926 -120.555512)
		(end 407.39568 -120.74271)
		(stroke
			(width 0.05715)
			(type default)
		)
		(layer "In9.Cu")
	)
	(gr_line
		(start 406.888696 -125.311408)
		(end 406.92578 -125.320806)
		(stroke
			(width 0.05715)
			(type default)
		)
		(layer "In9.Cu")
	)
	(gr_line
		(start 406.92578 -125.320806)
		(end 406.96261 -125.3109)
		(stroke
			(width 0.05715)
			(type default)
		)
		(layer "In9.Cu")
	)
	(gr_arc
		(start 406.948132 -140.679424)
		(mid 406.996941 -140.598468)
		(end 407.006552 -140.504418)
		(stroke
			(width 0.05715)
			(type default)
		)
		(layer "In9.Cu")
	)
	(gr_arc
		(start 406.973532 -153.89225)
		(mid 407.017252 -153.883524)
		(end 407.054304 -153.858722)
		(stroke
			(width 0.05715)
			(type default)
		)
		(layer "In9.Cu")
	)
	(gr_arc
		(start 406.987502 -150.91918)
		(mid 407.0312 -150.910404)
		(end 407.068274 -150.885652)
		(stroke
			(width 0.05715)
			(type default)
		)
		(layer "In9.Cu")
	)
	(gr_arc
		(start 407.054304 -154.217878)
		(mid 407.017261 -154.193053)
		(end 406.973532 -154.18435)
		(stroke
			(width 0.05715)
			(type default)
		)
		(layer "In9.Cu")
	)
	(gr_line
		(start 407.054304 -154.217878)
		(end 407.382726 -154.5463)
		(stroke
			(width 0.05715)
			(type default)
		)
		(layer "In9.Cu")
	)
	(gr_line
		(start 407.054304 -153.858722)
		(end 407.382726 -153.5303)
		(stroke
			(width 0.05715)
			(type default)
		)
		(layer "In9.Cu")
	)
	(gr_arc
		(start 407.064972 -140.329158)
		(mid 407.016073 -140.410225)
		(end 407.006552 -140.504418)
		(stroke
			(width 0.05715)
			(type default)
		)
		(layer "In9.Cu")
	)
	(gr_arc
		(start 407.065734 -151.244808)
		(mid 407.028675 -151.220046)
		(end 406.984962 -151.21128)
		(stroke
			(width 0.05715)
			(type default)
		)
		(layer "In9.Cu")
	)
	(gr_line
		(start 407.065734 -151.244808)
		(end 407.395426 -151.5745)
		(stroke
			(width 0.05715)
			(type default)
		)
		(layer "In9.Cu")
	)
	(gr_line
		(start 407.068274 -150.885652)
		(end 407.395426 -150.5585)
		(stroke
			(width 0.05715)
			(type default)
		)
		(layer "In9.Cu")
	)
	(gr_line
		(start 407.131266 -121.136918)
		(end 407.336752 -121.03354)
		(stroke
			(width 0.05715)
			(type default)
		)
		(layer "In9.Cu")
	)
	(gr_line
		(start 407.18486 -14.904974)
		(end 407.230834 -14.835632)
		(stroke
			(width 0.05715)
			(type default)
		)
		(layer "In9.Cu")
	)
	(gr_line
		(start 407.230834 -14.835632)
		(end 407.312622 -14.818106)
		(stroke
			(width 0.05715)
			(type default)
		)
		(layer "In9.Cu")
	)
	(gr_line
		(start 407.666952 -121.142506)
		(end 407.770584 -121.347992)
		(stroke
			(width 0.05715)
			(type default)
		)
		(layer "In9.Cu")
	)
	(gr_line
		(start 407.721308 -0.385572)
		(end 407.725372 -0.383032)
		(stroke
			(width 0.05715)
			(type default)
		)
		(layer "In9.Cu")
	)
	(gr_line
		(start 407.725372 -0.383032)
		(end 407.729944 -0.381508)
		(stroke
			(width 0.05715)
			(type default)
		)
		(layer "In9.Cu")
	)
	(gr_line
		(start 407.765504 -14.72184)
		(end 407.792174 -14.715998)
		(stroke
			(width 0.05715)
			(type default)
		)
		(layer "In9.Cu")
	)
	(gr_line
		(start 407.770584 -121.347992)
		(end 408.095958 -121.455688)
		(stroke
			(width 0.05715)
			(type default)
		)
		(layer "In9.Cu")
	)
	(gr_line
		(start 407.786332 -14.045438)
		(end 407.809446 -14.040358)
		(stroke
			(width 0.05715)
			(type default)
		)
		(layer "In9.Cu")
	)
	(gr_line
		(start 407.792174 -14.715998)
		(end 407.818844 -14.72184)
		(stroke
			(width 0.05715)
			(type default)
		)
		(layer "In9.Cu")
	)
	(gr_line
		(start 407.793698 -120.874282)
		(end 408.36088 -121.06148)
		(stroke
			(width 0.05715)
			(type default)
		)
		(layer "In9.Cu")
	)
	(gr_line
		(start 407.809446 -14.040358)
		(end 407.83256 -14.045438)
		(stroke
			(width 0.05715)
			(type default)
		)
		(layer "In9.Cu")
	)
	(gr_line
		(start 407.823162 -13.387832)
		(end 407.846276 -13.382752)
		(stroke
			(width 0.05715)
			(type default)
		)
		(layer "In9.Cu")
	)
	(gr_line
		(start 407.846276 -13.382752)
		(end 407.86939 -13.387832)
		(stroke
			(width 0.05715)
			(type default)
		)
		(layer "In9.Cu")
	)
	(gr_line
		(start 407.867358 -12.727686)
		(end 407.890472 -12.722606)
		(stroke
			(width 0.05715)
			(type default)
		)
		(layer "In9.Cu")
	)
	(gr_line
		(start 407.890472 -12.722606)
		(end 407.913586 -12.727686)
		(stroke
			(width 0.05715)
			(type default)
		)
		(layer "In9.Cu")
	)
	(gr_line
		(start 407.935684 -12.062714)
		(end 407.958798 -12.057634)
		(stroke
			(width 0.05715)
			(type default)
		)
		(layer "In9.Cu")
	)
	(gr_line
		(start 407.958798 -12.057634)
		(end 407.981912 -12.062714)
		(stroke
			(width 0.05715)
			(type default)
		)
		(layer "In9.Cu")
	)
	(gr_line
		(start 407.99004 -11.400028)
		(end 408.016202 -11.39444)
		(stroke
			(width 0.05715)
			(type default)
		)
		(layer "In9.Cu")
	)
	(gr_line
		(start 408.016202 -11.39444)
		(end 408.04084 -11.399774)
		(stroke
			(width 0.05715)
			(type default)
		)
		(layer "In9.Cu")
	)
	(gr_arc
		(start 408.023314 -127.486918)
		(mid 407.950033 -127.427092)
		(end 407.858214 -127.404368)
		(stroke
			(width 0.05715)
			(type default)
		)
		(layer "In9.Cu")
	)
	(gr_arc
		(start 408.023314 -127.486918)
		(mid 408.096613 -127.546693)
		(end 408.188414 -127.569468)
		(stroke
			(width 0.05715)
			(type default)
		)
		(layer "In9.Cu")
	)
	(gr_line
		(start 408.055572 -102.637336)
		(end 408.055572 -103.054658)
		(stroke
			(width 0.050546)
			(type default)
		)
		(layer "In9.Cu")
	)
	(gr_line
		(start 408.055572 -102.637336)
		(end 408.306778 -102.38613)
		(stroke
			(width 0.050546)
			(type default)
		)
		(layer "In9.Cu")
	)
	(gr_line
		(start 408.063446 -10.734548)
		(end 408.08656 -10.729468)
		(stroke
			(width 0.05715)
			(type default)
		)
		(layer "In9.Cu")
	)
	(gr_line
		(start 408.08656 -10.729468)
		(end 408.109674 -10.734548)
		(stroke
			(width 0.05715)
			(type default)
		)
		(layer "In9.Cu")
	)
	(gr_line
		(start 408.095958 -121.455688)
		(end 408.301698 -121.35231)
		(stroke
			(width 0.05715)
			(type default)
		)
		(layer "In9.Cu")
	)
	(gr_line
		(start 408.152854 -127.112268)
		(end 408.566874 -127.112268)
		(stroke
			(width 0.05715)
			(type default)
		)
		(layer "In9.Cu")
	)
	(gr_line
		(start 408.188414 -127.569468)
		(end 408.531314 -127.569468)
		(stroke
			(width 0.05715)
			(type default)
		)
		(layer "In9.Cu")
	)
	(gr_line
		(start 408.19832 -10.056368)
		(end 408.221434 -10.051288)
		(stroke
			(width 0.05715)
			(type default)
		)
		(layer "In9.Cu")
	)
	(gr_line
		(start 408.221434 -10.051288)
		(end 408.244548 -10.056368)
		(stroke
			(width 0.05715)
			(type default)
		)
		(layer "In9.Cu")
	)
	(gr_line
		(start 408.306778 -102.38613)
		(end 408.7241 -102.38613)
		(stroke
			(width 0.050546)
			(type default)
		)
		(layer "In9.Cu")
	)
	(gr_line
		(start 408.359102 -124.62891)
		(end 408.401266 -124.61748)
		(stroke
			(width 0.05715)
			(type default)
		)
		(layer "In9.Cu")
	)
	(gr_line
		(start 408.37993 -5.064506)
		(end 408.40279 -5.069078)
		(stroke
			(width 0.05715)
			(type default)
		)
		(layer "In9.Cu")
	)
	(gr_line
		(start 408.401266 -124.61748)
		(end 408.442668 -124.629164)
		(stroke
			(width 0.05715)
			(type default)
		)
		(layer "In9.Cu")
	)
	(gr_line
		(start 408.40279 -5.069078)
		(end 408.42565 -5.064252)
		(stroke
			(width 0.05715)
			(type default)
		)
		(layer "In9.Cu")
	)
	(gr_line
		(start 408.44089 -4.390898)
		(end 408.46375 -4.39547)
		(stroke
			(width 0.05715)
			(type default)
		)
		(layer "In9.Cu")
	)
	(gr_line
		(start 408.45232 -5.757672)
		(end 408.47518 -5.762244)
		(stroke
			(width 0.05715)
			(type default)
		)
		(layer "In9.Cu")
	)
	(gr_line
		(start 408.46375 -4.39547)
		(end 408.48661 -4.390644)
		(stroke
			(width 0.05715)
			(type default)
		)
		(layer "In9.Cu")
	)
	(gr_line
		(start 408.47518 -5.762244)
		(end 408.49804 -5.757418)
		(stroke
			(width 0.05715)
			(type default)
		)
		(layer "In9.Cu")
	)
	(gr_arc
		(start 408.531314 -127.569468)
		(mid 408.623148 -127.546755)
		(end 408.696414 -127.486918)
		(stroke
			(width 0.05715)
			(type default)
		)
		(layer "In9.Cu")
	)
	(gr_line
		(start 408.631644 -121.461276)
		(end 408.735276 -121.666762)
		(stroke
			(width 0.05715)
			(type default)
		)
		(layer "In9.Cu")
	)
	(gr_line
		(start 408.65044 -103.056436)
		(end 408.725878 -102.980998)
		(stroke
			(width 0.050546)
			(type default)
		)
		(layer "In9.Cu")
	)
	(gr_line
		(start 408.735276 -121.666762)
		(end 409.06065 -121.774458)
		(stroke
			(width 0.05715)
			(type default)
		)
		(layer "In9.Cu")
	)
	(gr_line
		(start 408.757882 -121.192798)
		(end 409.324302 -121.379742)
		(stroke
			(width 0.05715)
			(type default)
		)
		(layer "In9.Cu")
	)
	(gr_arc
		(start 408.861514 -127.404368)
		(mid 408.769717 -127.427136)
		(end 408.696414 -127.486918)
		(stroke
			(width 0.05715)
			(type default)
		)
		(layer "In9.Cu")
	)
	(gr_line
		(start 408.904186 -0.019304)
		(end 408.953716 -0.004064)
		(stroke
			(width 0.05715)
			(type default)
		)
		(layer "In9.Cu")
	)
	(gr_line
		(start 408.9146 -8.158734)
		(end 408.99461 -8.141716)
		(stroke
			(width 0.05715)
			(type default)
		)
		(layer "In9.Cu")
	)
	(gr_line
		(start 408.953716 -0.004064)
		(end 409.003754 -0.01905)
		(stroke
			(width 0.05715)
			(type default)
		)
		(layer "In9.Cu")
	)
	(gr_line
		(start 408.99461 -8.141716)
		(end 409.063698 -8.18642)
		(stroke
			(width 0.05715)
			(type default)
		)
		(layer "In9.Cu")
	)
	(gr_line
		(start 409.06065 -121.774458)
		(end 409.26639 -121.670826)
		(stroke
			(width 0.05715)
			(type default)
		)
		(layer "In9.Cu")
	)
	(gr_line
		(start 409.11526 -101.87813)
		(end 409.11526 -101.998526)
		(stroke
			(width 0.050546)
			(type default)
		)
		(layer "In9.Cu")
	)
	(gr_line
		(start 409.11526 -101.56698)
		(end 409.11526 -101.87305)
		(stroke
			(width 0.050546)
			(type default)
		)
		(layer "In9.Cu")
	)
	(gr_line
		(start 409.11526 -101.56698)
		(end 409.330144 -101.351842)
		(stroke
			(width 0.050546)
			(type default)
		)
		(layer "In9.Cu")
	)
	(gr_line
		(start 409.165806 -8.909558)
		(end 409.183078 -8.99033)
		(stroke
			(width 0.05715)
			(type default)
		)
		(layer "In9.Cu")
	)
	(gr_line
		(start 409.183078 -8.99033)
		(end 409.253182 -9.035796)
		(stroke
			(width 0.05715)
			(type default)
		)
		(layer "In9.Cu")
	)
	(gr_line
		(start 409.278582 -8.325612)
		(end 409.349702 -8.37184)
		(stroke
			(width 0.05715)
			(type default)
		)
		(layer "In9.Cu")
	)
	(gr_line
		(start 409.311094 -133.947408)
		(end 409.311094 -134.361428)
		(stroke
			(width 0.05715)
			(type default)
		)
		(layer "In9.Cu")
	)
	(gr_line
		(start 409.330144 -101.351842)
		(end 409.758134 -101.351842)
		(stroke
			(width 0.050546)
			(type default)
		)
		(layer "In9.Cu")
	)
	(gr_line
		(start 409.349702 -8.37184)
		(end 409.367228 -8.453882)
		(stroke
			(width 0.05715)
			(type default)
		)
		(layer "In9.Cu")
	)
	(gr_arc
		(start 409.369514 -127.486918)
		(mid 409.296233 -127.427092)
		(end 409.204414 -127.404368)
		(stroke
			(width 0.05715)
			(type default)
		)
		(layer "In9.Cu")
	)
	(gr_arc
		(start 409.369514 -127.486918)
		(mid 409.442813 -127.546693)
		(end 409.534614 -127.569468)
		(stroke
			(width 0.05715)
			(type default)
		)
		(layer "In9.Cu")
	)
	(gr_arc
		(start 409.381452 -152.57145)
		(mid 409.425193 -152.562749)
		(end 409.462224 -152.537922)
		(stroke
			(width 0.05715)
			(type default)
		)
		(layer "In9.Cu")
	)
	(gr_line
		(start 409.411678 -102.294944)
		(end 409.411678 -102.295198)
		(stroke
			(width 0.050546)
			(type default)
		)
		(layer "In9.Cu")
	)
	(gr_line
		(start 409.451048 -9.163812)
		(end 409.520644 -9.209024)
		(stroke
			(width 0.05715)
			(type default)
		)
		(layer "In9.Cu")
	)
	(gr_arc
		(start 409.462224 -152.897078)
		(mid 409.425188 -152.872237)
		(end 409.381452 -152.86355)
		(stroke
			(width 0.05715)
			(type default)
		)
		(layer "In9.Cu")
	)
	(gr_line
		(start 409.462224 -152.897078)
		(end 409.790646 -153.2255)
		(stroke
			(width 0.05715)
			(type default)
		)
		(layer "In9.Cu")
	)
	(gr_line
		(start 409.462224 -152.537922)
		(end 409.790646 -152.2095)
		(stroke
			(width 0.05715)
			(type default)
		)
		(layer "In9.Cu")
	)
	(gr_arc
		(start 409.465526 -149.216364)
		(mid 409.546348 -149.182886)
		(end 409.579826 -149.102064)
		(stroke
			(width 0.05715)
			(type default)
		)
		(layer "In9.Cu")
	)
	(gr_line
		(start 409.499054 -127.112268)
		(end 409.913074 -127.112268)
		(stroke
			(width 0.05715)
			(type default)
		)
		(layer "In9.Cu")
	)
	(gr_line
		(start 409.520644 -9.209024)
		(end 409.601924 -9.191752)
		(stroke
			(width 0.05715)
			(type default)
		)
		(layer "In9.Cu")
	)
	(gr_line
		(start 409.534614 -127.569468)
		(end 409.877514 -127.569468)
		(stroke
			(width 0.05715)
			(type default)
		)
		(layer "In9.Cu")
	)
	(gr_arc
		(start 409.579826 -149.651212)
		(mid 409.538019 -149.550274)
		(end 409.437078 -149.508464)
		(stroke
			(width 0.05715)
			(type default)
		)
		(layer "In9.Cu")
	)
	(gr_line
		(start 409.579826 -149.651212)
		(end 409.579826 -149.861016)
		(stroke
			(width 0.05715)
			(type default)
		)
		(layer "In9.Cu")
	)
	(gr_line
		(start 409.579826 -148.845016)
		(end 409.579826 -149.102064)
		(stroke
			(width 0.05715)
			(type default)
		)
		(layer "In9.Cu")
	)
	(gr_arc
		(start 409.603194 -133.652768)
		(mid 409.625962 -133.744565)
		(end 409.685744 -133.817868)
		(stroke
			(width 0.05715)
			(type default)
		)
		(layer "In9.Cu")
	)
	(gr_arc
		(start 409.685744 -134.490968)
		(mid 409.625918 -134.564249)
		(end 409.603194 -134.656068)
		(stroke
			(width 0.05715)
			(type default)
		)
		(layer "In9.Cu")
	)
	(gr_arc
		(start 409.685744 -134.490968)
		(mid 409.745505 -134.417665)
		(end 409.768294 -134.325868)
		(stroke
			(width 0.05715)
			(type default)
		)
		(layer "In9.Cu")
	)
	(gr_line
		(start 409.710128 -101.996494)
		(end 409.759912 -101.94671)
		(stroke
			(width 0.050546)
			(type default)
		)
		(layer "In9.Cu")
	)
	(gr_line
		(start 409.720034 -121.8184)
		(end 409.767278 -121.833894)
		(stroke
			(width 0.05715)
			(type default)
		)
		(layer "In9.Cu")
	)
	(gr_line
		(start 409.767278 -121.833894)
		(end 409.815284 -121.821194)
		(stroke
			(width 0.05715)
			(type default)
		)
		(layer "In9.Cu")
	)
	(gr_arc
		(start 409.768294 -133.982968)
		(mid 409.745577 -133.891136)
		(end 409.685744 -133.817868)
		(stroke
			(width 0.05715)
			(type default)
		)
		(layer "In9.Cu")
	)
	(gr_line
		(start 409.768294 -133.982968)
		(end 409.768294 -134.325868)
		(stroke
			(width 0.05715)
			(type default)
		)
		(layer "In9.Cu")
	)
	(gr_line
		(start 409.831794 -8.256016)
		(end 409.84932 -8.33882)
		(stroke
			(width 0.05715)
			(type default)
		)
		(layer "In9.Cu")
	)
	(gr_line
		(start 409.831794 -8.256016)
		(end 409.87726 -8.185658)
		(stroke
			(width 0.05715)
			(type default)
		)
		(layer "In9.Cu")
	)
	(gr_arc
		(start 409.877514 -127.569468)
		(mid 409.969348 -127.546755)
		(end 410.042614 -127.486918)
		(stroke
			(width 0.05715)
			(type default)
		)
		(layer "In9.Cu")
	)
	(gr_line
		(start 409.937458 -9.120886)
		(end 410.020516 -9.10336)
		(stroke
			(width 0.05715)
			(type default)
		)
		(layer "In9.Cu")
	)
	(gr_line
		(start 409.951682 -4.441444)
		(end 409.974796 -4.436364)
		(stroke
			(width 0.05715)
			(type default)
		)
		(layer "In9.Cu")
	)
	(gr_line
		(start 409.974796 -4.436364)
		(end 409.99791 -4.441444)
		(stroke
			(width 0.05715)
			(type default)
		)
		(layer "In9.Cu")
	)
	(gr_line
		(start 409.976828 -100.705158)
		(end 409.976828 -101.133148)
		(stroke
			(width 0.050546)
			(type default)
		)
		(layer "In9.Cu")
	)
	(gr_line
		(start 409.976828 -100.705158)
		(end 410.191966 -100.49002)
		(stroke
			(width 0.050546)
			(type default)
		)
		(layer "In9.Cu")
	)
	(gr_line
		(start 409.983686 -3.774186)
		(end 410.0068 -3.769106)
		(stroke
			(width 0.05715)
			(type default)
		)
		(layer "In9.Cu")
	)
	(gr_line
		(start 410.005022 -7.988046)
		(end 410.050996 -7.91718)
		(stroke
			(width 0.05715)
			(type default)
		)
		(layer "In9.Cu")
	)
	(gr_line
		(start 410.0068 -3.769106)
		(end 410.029914 -3.774186)
		(stroke
			(width 0.05715)
			(type default)
		)
		(layer "In9.Cu")
	)
	(gr_line
		(start 410.020516 -9.10336)
		(end 410.066744 -9.031986)
		(stroke
			(width 0.05715)
			(type default)
		)
		(layer "In9.Cu")
	)
	(gr_line
		(start 410.050996 -7.91718)
		(end 410.133038 -7.899654)
		(stroke
			(width 0.05715)
			(type default)
		)
		(layer "In9.Cu")
	)
	(gr_line
		(start 410.091636 -5.120894)
		(end 410.11475 -5.115814)
		(stroke
			(width 0.05715)
			(type default)
		)
		(layer "In9.Cu")
	)
	(gr_line
		(start 410.11475 -5.115814)
		(end 410.137864 -5.120894)
		(stroke
			(width 0.05715)
			(type default)
		)
		(layer "In9.Cu")
	)
	(gr_line
		(start 410.191966 -100.49002)
		(end 410.62021 -100.49002)
		(stroke
			(width 0.050546)
			(type default)
		)
		(layer "In9.Cu")
	)
	(gr_line
		(start 410.193998 -8.834628)
		(end 410.239464 -8.764524)
		(stroke
			(width 0.05715)
			(type default)
		)
		(layer "In9.Cu")
	)
	(gr_arc
		(start 410.207714 -127.404368)
		(mid 410.115917 -127.427136)
		(end 410.042614 -127.486918)
		(stroke
			(width 0.05715)
			(type default)
		)
		(layer "In9.Cu")
	)
	(gr_line
		(start 410.221938 -8.68172)
		(end 410.239464 -8.764524)
		(stroke
			(width 0.05715)
			(type default)
		)
		(layer "In9.Cu")
	)
	(gr_line
		(start 410.307028 -101.399594)
		(end 410.887672 -100.819204)
		(stroke
			(width 0.050546)
			(type default)
		)
		(layer "In9.Cu")
	)
	(gr_line
		(start 410.412438 -121.360438)
		(end 410.446728 -121.351294)
		(stroke
			(width 0.05715)
			(type default)
		)
		(layer "In9.Cu")
	)
	(gr_line
		(start 410.416756 -5.851906)
		(end 410.43987 -5.846826)
		(stroke
			(width 0.05715)
			(type default)
		)
		(layer "In9.Cu")
	)
	(gr_line
		(start 410.422852 -7.837932)
		(end 410.445712 -7.833106)
		(stroke
			(width 0.05715)
			(type default)
		)
		(layer "In9.Cu")
	)
	(gr_line
		(start 410.43987 -5.846826)
		(end 410.462984 -5.851906)
		(stroke
			(width 0.05715)
			(type default)
		)
		(layer "In9.Cu")
	)
	(gr_line
		(start 410.440632 -6.515608)
		(end 410.463746 -6.510528)
		(stroke
			(width 0.05715)
			(type default)
		)
		(layer "In9.Cu")
	)
	(gr_line
		(start 410.445712 -7.833106)
		(end 410.468826 -7.838186)
		(stroke
			(width 0.05715)
			(type default)
		)
		(layer "In9.Cu")
	)
	(gr_line
		(start 410.446728 -121.351294)
		(end 410.482034 -121.35993)
		(stroke
			(width 0.05715)
			(type default)
		)
		(layer "In9.Cu")
	)
	(gr_line
		(start 410.45003 -7.172706)
		(end 410.473144 -7.167626)
		(stroke
			(width 0.05715)
			(type default)
		)
		(layer "In9.Cu")
	)
	(gr_line
		(start 410.454348 -125.50267)
		(end 410.519118 -125.520958)
		(stroke
			(width 0.05715)
			(type default)
		)
		(layer "In9.Cu")
	)
	(gr_line
		(start 410.463746 -6.510528)
		(end 410.48686 -6.515608)
		(stroke
			(width 0.05715)
			(type default)
		)
		(layer "In9.Cu")
	)
	(gr_line
		(start 410.473144 -7.167626)
		(end 410.496258 -7.172706)
		(stroke
			(width 0.05715)
			(type default)
		)
		(layer "In9.Cu")
	)
	(gr_line
		(start 410.519118 -125.520958)
		(end 410.58084 -125.493526)
		(stroke
			(width 0.05715)
			(type default)
		)
		(layer "In9.Cu")
	)
	(gr_arc
		(start 410.715714 -127.486918)
		(mid 410.642433 -127.427092)
		(end 410.550614 -127.404368)
		(stroke
			(width 0.05715)
			(type default)
		)
		(layer "In9.Cu")
	)
	(gr_arc
		(start 410.715714 -127.486918)
		(mid 410.789013 -127.546693)
		(end 410.880814 -127.569468)
		(stroke
			(width 0.05715)
			(type default)
		)
		(layer "In9.Cu")
	)
	(gr_line
		(start 410.845254 -127.112268)
		(end 411.259274 -127.112268)
		(stroke
			(width 0.05715)
			(type default)
		)
		(layer "In9.Cu")
	)
	(gr_line
		(start 410.880814 -127.569468)
		(end 411.223714 -127.569468)
		(stroke
			(width 0.05715)
			(type default)
		)
		(layer "In9.Cu")
	)
	(gr_line
		(start 411.183328 -142.523718)
		(end 411.183328 -142.937738)
		(stroke
			(width 0.05715)
			(type default)
		)
		(layer "In9.Cu")
	)
	(gr_line
		(start 411.183328 -141.177518)
		(end 411.183328 -141.591538)
		(stroke
			(width 0.05715)
			(type default)
		)
		(layer "In9.Cu")
	)
	(gr_arc
		(start 411.223714 -127.569468)
		(mid 411.315548 -127.546755)
		(end 411.388814 -127.486918)
		(stroke
			(width 0.05715)
			(type default)
		)
		(layer "In9.Cu")
	)
	(gr_line
		(start 411.250892 -0.997458)
		(end 411.29966 -1.01219)
		(stroke
			(width 0.05715)
			(type default)
		)
		(layer "In9.Cu")
	)
	(gr_line
		(start 411.29966 -1.01219)
		(end 411.348428 -0.997458)
		(stroke
			(width 0.05715)
			(type default)
		)
		(layer "In9.Cu")
	)
	(gr_line
		(start 411.43047 -121.893076)
		(end 411.477206 -121.904506)
		(stroke
			(width 0.05715)
			(type default)
		)
		(layer "In9.Cu")
	)
	(gr_arc
		(start 411.475428 -142.229078)
		(mid 411.498196 -142.320875)
		(end 411.557978 -142.394178)
		(stroke
			(width 0.05715)
			(type default)
		)
		(layer "In9.Cu")
	)
	(gr_arc
		(start 411.475428 -140.882878)
		(mid 411.498196 -140.974675)
		(end 411.557978 -141.047978)
		(stroke
			(width 0.05715)
			(type default)
		)
		(layer "In9.Cu")
	)
	(gr_line
		(start 411.477206 -121.904506)
		(end 411.522672 -121.888758)
		(stroke
			(width 0.05715)
			(type default)
		)
		(layer "In9.Cu")
	)
	(gr_arc
		(start 411.553914 -127.404368)
		(mid 411.462117 -127.427136)
		(end 411.388814 -127.486918)
		(stroke
			(width 0.05715)
			(type default)
		)
		(layer "In9.Cu")
	)
	(gr_arc
		(start 411.557978 -143.067278)
		(mid 411.498152 -143.140559)
		(end 411.475428 -143.232378)
		(stroke
			(width 0.05715)
			(type default)
		)
		(layer "In9.Cu")
	)
	(gr_arc
		(start 411.557978 -143.067278)
		(mid 411.61776 -142.993982)
		(end 411.640528 -142.902178)
		(stroke
			(width 0.05715)
			(type default)
		)
		(layer "In9.Cu")
	)
	(gr_arc
		(start 411.557978 -141.721078)
		(mid 411.498152 -141.794359)
		(end 411.475428 -141.886178)
		(stroke
			(width 0.05715)
			(type default)
		)
		(layer "In9.Cu")
	)
	(gr_arc
		(start 411.557978 -141.721078)
		(mid 411.61776 -141.647782)
		(end 411.640528 -141.555978)
		(stroke
			(width 0.05715)
			(type default)
		)
		(layer "In9.Cu")
	)
	(gr_arc
		(start 411.640528 -142.559278)
		(mid 411.617817 -142.467441)
		(end 411.557978 -142.394178)
		(stroke
			(width 0.05715)
			(type default)
		)
		(layer "In9.Cu")
	)
	(gr_line
		(start 411.640528 -142.559278)
		(end 411.640528 -142.902178)
		(stroke
			(width 0.05715)
			(type default)
		)
		(layer "In9.Cu")
	)
	(gr_arc
		(start 411.640528 -141.213078)
		(mid 411.617817 -141.121241)
		(end 411.557978 -141.047978)
		(stroke
			(width 0.05715)
			(type default)
		)
		(layer "In9.Cu")
	)
	(gr_line
		(start 411.640528 -141.213078)
		(end 411.640528 -141.555978)
		(stroke
			(width 0.05715)
			(type default)
		)
		(layer "In9.Cu")
	)
	(gr_arc
		(start 411.741874 -131.27482)
		(mid 411.822854 -131.323538)
		(end 411.91688 -131.332986)
		(stroke
			(width 0.05715)
			(type default)
		)
		(layer "In9.Cu")
	)
	(gr_line
		(start 411.743398 -131.689856)
		(end 412.03626 -131.982718)
		(stroke
			(width 0.05715)
			(type default)
		)
		(layer "In9.Cu")
	)
	(gr_line
		(start 411.861 -93.13164)
		(end 412.08706 -93.3577)
		(stroke
			(width 0.050546)
			(type default)
		)
		(layer "In9.Cu")
	)
	(gr_line
		(start 411.861 -92.776294)
		(end 411.861 -93.13164)
		(stroke
			(width 0.050546)
			(type default)
		)
		(layer "In9.Cu")
	)
	(gr_line
		(start 411.861 -92.776294)
		(end 412.08706 -92.550234)
		(stroke
			(width 0.050546)
			(type default)
		)
		(layer "In9.Cu")
	)
	(gr_line
		(start 411.973268 -5.159248)
		(end 411.996382 -5.164328)
		(stroke
			(width 0.05715)
			(type default)
		)
		(layer "In9.Cu")
	)
	(gr_line
		(start 411.996382 -5.164328)
		(end 412.019496 -5.159248)
		(stroke
			(width 0.05715)
			(type default)
		)
		(layer "In9.Cu")
	)
	(gr_line
		(start 412.013654 -4.493768)
		(end 412.036768 -4.498848)
		(stroke
			(width 0.05715)
			(type default)
		)
		(layer "In9.Cu")
	)
	(gr_line
		(start 412.036768 -4.498848)
		(end 412.059882 -4.493768)
		(stroke
			(width 0.05715)
			(type default)
		)
		(layer "In9.Cu")
	)
	(gr_arc
		(start 412.061914 -127.486918)
		(mid 411.988633 -127.427092)
		(end 411.896814 -127.404368)
		(stroke
			(width 0.05715)
			(type default)
		)
		(layer "In9.Cu")
	)
	(gr_arc
		(start 412.061914 -127.486918)
		(mid 412.135213 -127.546693)
		(end 412.227014 -127.569468)
		(stroke
			(width 0.05715)
			(type default)
		)
		(layer "In9.Cu")
	)
	(gr_arc
		(start 412.091886 -131.391406)
		(mid 412.010939 -131.342547)
		(end 411.91688 -131.332986)
		(stroke
			(width 0.05715)
			(type default)
		)
		(layer "In9.Cu")
	)
	(gr_line
		(start 412.091886 -131.391406)
		(end 412.334456 -131.633976)
		(stroke
			(width 0.05715)
			(type default)
		)
		(layer "In9.Cu")
	)
	(gr_line
		(start 412.191454 -127.112268)
		(end 412.605474 -127.112268)
		(stroke
			(width 0.05715)
			(type default)
		)
		(layer "In9.Cu")
	)
	(gr_line
		(start 412.2039 -149.770846)
		(end 412.2039 -149.7711)
		(stroke
			(width 0.05715)
			(type default)
		)
		(layer "In9.Cu")
	)
	(gr_line
		(start 412.227014 -127.569468)
		(end 412.569914 -127.569468)
		(stroke
			(width 0.05715)
			(type default)
		)
		(layer "In9.Cu")
	)
	(gr_arc
		(start 412.392876 -131.808982)
		(mid 412.383286 -131.714933)
		(end 412.334456 -131.633976)
		(stroke
			(width 0.05715)
			(type default)
		)
		(layer "In9.Cu")
	)
	(gr_arc
		(start 412.392876 -131.808982)
		(mid 412.402395 -131.903175)
		(end 412.451296 -131.984242)
		(stroke
			(width 0.05715)
			(type default)
		)
		(layer "In9.Cu")
	)
	(gr_line
		(start 412.410656 -149.56409)
		(end 412.410656 -149.564344)
		(stroke
			(width 0.05715)
			(type default)
		)
		(layer "In9.Cu")
	)
	(gr_arc
		(start 412.569914 -127.569468)
		(mid 412.661748 -127.546755)
		(end 412.735014 -127.486918)
		(stroke
			(width 0.05715)
			(type default)
		)
		(layer "In9.Cu")
	)
	(gr_line
		(start 412.719266 -124.543566)
		(end 412.802578 -124.506482)
		(stroke
			(width 0.05715)
			(type default)
		)
		(layer "In9.Cu")
	)
	(gr_line
		(start 412.74111 -123.773184)
		(end 412.932626 -123.204224)
		(stroke
			(width 0.05715)
			(type default)
		)
		(layer "In9.Cu")
	)
	(gr_line
		(start 412.747714 -121.463562)
		(end 412.846774 -121.429272)
		(stroke
			(width 0.05715)
			(type default)
		)
		(layer "In9.Cu")
	)
	(gr_line
		(start 412.802578 -124.506482)
		(end 412.831788 -124.41936)
		(stroke
			(width 0.05715)
			(type default)
		)
		(layer "In9.Cu")
	)
	(gr_line
		(start 412.83128 -4.688332)
		(end 413.413956 -4.564634)
		(stroke
			(width 0.05715)
			(type default)
		)
		(layer "In9.Cu")
	)
	(gr_line
		(start 412.846774 -121.429272)
		(end 412.880556 -121.329196)
		(stroke
			(width 0.05715)
			(type default)
		)
		(layer "In9.Cu")
	)
	(gr_line
		(start 412.857696 -4.983734)
		(end 413.050736 -5.10921)
		(stroke
			(width 0.05715)
			(type default)
		)
		(layer "In9.Cu")
	)
	(gr_line
		(start 412.88462 -119.452644)
		(end 412.901638 -119.507762)
		(stroke
			(width 0.05715)
			(type default)
		)
		(layer "In9.Cu")
	)
	(gr_line
		(start 412.88462 -119.452644)
		(end 412.904178 -119.397526)
		(stroke
			(width 0.05715)
			(type default)
		)
		(layer "In9.Cu")
	)
	(gr_arc
		(start 412.900114 -127.404368)
		(mid 412.808317 -127.427136)
		(end 412.735014 -127.486918)
		(stroke
			(width 0.05715)
			(type default)
		)
		(layer "In9.Cu")
	)
	(gr_line
		(start 413.009334 -123.899676)
		(end 413.215582 -123.797314)
		(stroke
			(width 0.05715)
			(type default)
		)
		(layer "In9.Cu")
	)
	(gr_line
		(start 413.040576 -0.178308)
		(end 413.083756 -0.1651)
		(stroke
			(width 0.05715)
			(type default)
		)
		(layer "In9.Cu")
	)
	(gr_line
		(start 413.050736 -5.10921)
		(end 413.38627 -5.037836)
		(stroke
			(width 0.05715)
			(type default)
		)
		(layer "In9.Cu")
	)
	(gr_line
		(start 413.065722 -122.810016)
		(end 413.25673 -122.243088)
		(stroke
			(width 0.05715)
			(type default)
		)
		(layer "In9.Cu")
	)
	(gr_line
		(start 413.083756 -0.1651)
		(end 413.127444 -0.176276)
		(stroke
			(width 0.05715)
			(type default)
		)
		(layer "In9.Cu")
	)
	(gr_line
		(start 413.215582 -123.797314)
		(end 413.325056 -123.472194)
		(stroke
			(width 0.05715)
			(type default)
		)
		(layer "In9.Cu")
	)
	(gr_line
		(start 413.222694 -123.265946)
		(end 413.325056 -123.472194)
		(stroke
			(width 0.05715)
			(type default)
		)
		(layer "In9.Cu")
	)
	(gr_line
		(start 413.306006 -118.260876)
		(end 413.328358 -118.197376)
		(stroke
			(width 0.05715)
			(type default)
		)
		(layer "In9.Cu")
	)
	(gr_line
		(start 413.325818 -120.007888)
		(end 413.343598 -119.955056)
		(stroke
			(width 0.05715)
			(type default)
		)
		(layer "In9.Cu")
	)
	(gr_line
		(start 413.327342 -119.901462)
		(end 413.327342 -119.901716)
		(stroke
			(width 0.05715)
			(type default)
		)
		(layer "In9.Cu")
	)
	(gr_line
		(start 413.327342 -119.901208)
		(end 413.343598 -119.955056)
		(stroke
			(width 0.05715)
			(type default)
		)
		(layer "In9.Cu")
	)
	(gr_line
		(start 413.328358 -118.197376)
		(end 413.387032 -118.162324)
		(stroke
			(width 0.05715)
			(type default)
		)
		(layer "In9.Cu")
	)
	(gr_line
		(start 413.333692 -122.937016)
		(end 413.53994 -122.8344)
		(stroke
			(width 0.05715)
			(type default)
		)
		(layer "In9.Cu")
	)
	(gr_line
		(start 413.38627 -5.037836)
		(end 413.511238 -4.84505)
		(stroke
			(width 0.05715)
			(type default)
		)
		(layer "In9.Cu")
	)
	(gr_line
		(start 413.53994 -122.8344)
		(end 413.649414 -122.509534)
		(stroke
			(width 0.05715)
			(type default)
		)
		(layer "In9.Cu")
	)
	(gr_line
		(start 413.547052 -122.303032)
		(end 413.649414 -122.509534)
		(stroke
			(width 0.05715)
			(type default)
		)
		(layer "In9.Cu")
	)
	(gr_line
		(start 413.67837 -135.995664)
		(end 413.67837 -136.409684)
		(stroke
			(width 0.05715)
			(type default)
		)
		(layer "In9.Cu")
	)
	(gr_line
		(start 413.67837 -134.649464)
		(end 413.67837 -135.063484)
		(stroke
			(width 0.05715)
			(type default)
		)
		(layer "In9.Cu")
	)
	(gr_line
		(start 413.824166 -4.477258)
		(end 414.408874 -4.353052)
		(stroke
			(width 0.05715)
			(type default)
		)
		(layer "In9.Cu")
	)
	(gr_line
		(start 413.851598 -4.77266)
		(end 414.044638 -4.898136)
		(stroke
			(width 0.05715)
			(type default)
		)
		(layer "In9.Cu")
	)
	(gr_line
		(start 413.88792 -119.47525)
		(end 413.90443 -119.530114)
		(stroke
			(width 0.05715)
			(type default)
		)
		(layer "In9.Cu")
	)
	(gr_line
		(start 413.88792 -119.47525)
		(end 413.907224 -119.421402)
		(stroke
			(width 0.05715)
			(type default)
		)
		(layer "In9.Cu")
	)
	(gr_arc
		(start 413.97047 -135.701024)
		(mid 413.993182 -135.792861)
		(end 414.05302 -135.866124)
		(stroke
			(width 0.05715)
			(type default)
		)
		(layer "In9.Cu")
	)
	(gr_arc
		(start 413.97047 -134.354824)
		(mid 413.993182 -134.446661)
		(end 414.05302 -134.519924)
		(stroke
			(width 0.05715)
			(type default)
		)
		(layer "In9.Cu")
	)
	(gr_line
		(start 414.044638 -4.898136)
		(end 414.380172 -4.826762)
		(stroke
			(width 0.05715)
			(type default)
		)
		(layer "In9.Cu")
	)
	(gr_arc
		(start 414.05302 -136.539224)
		(mid 413.993239 -136.612521)
		(end 413.97047 -136.704324)
		(stroke
			(width 0.05715)
			(type default)
		)
		(layer "In9.Cu")
	)
	(gr_arc
		(start 414.05302 -136.539224)
		(mid 414.112846 -136.465943)
		(end 414.13557 -136.374124)
		(stroke
			(width 0.05715)
			(type default)
		)
		(layer "In9.Cu")
	)
	(gr_arc
		(start 414.05302 -135.193024)
		(mid 413.993239 -135.266321)
		(end 413.97047 -135.358124)
		(stroke
			(width 0.05715)
			(type default)
		)
		(layer "In9.Cu")
	)
	(gr_arc
		(start 414.05302 -135.193024)
		(mid 414.112846 -135.119743)
		(end 414.13557 -135.027924)
		(stroke
			(width 0.05715)
			(type default)
		)
		(layer "In9.Cu")
	)
	(gr_line
		(start 414.087056 -118.919752)
		(end 414.110932 -118.852696)
		(stroke
			(width 0.05715)
			(type default)
		)
		(layer "In9.Cu")
	)
	(gr_line
		(start 414.110932 -118.852696)
		(end 414.17367 -118.817644)
		(stroke
			(width 0.05715)
			(type default)
		)
		(layer "In9.Cu")
	)
	(gr_arc
		(start 414.13557 -136.031224)
		(mid 414.112802 -135.939427)
		(end 414.05302 -135.866124)
		(stroke
			(width 0.05715)
			(type default)
		)
		(layer "In9.Cu")
	)
	(gr_line
		(start 414.13557 -136.031224)
		(end 414.13557 -136.374124)
		(stroke
			(width 0.05715)
			(type default)
		)
		(layer "In9.Cu")
	)
	(gr_arc
		(start 414.13557 -134.685024)
		(mid 414.112802 -134.593227)
		(end 414.05302 -134.519924)
		(stroke
			(width 0.05715)
			(type default)
		)
		(layer "In9.Cu")
	)
	(gr_line
		(start 414.13557 -134.685024)
		(end 414.13557 -135.027924)
		(stroke
			(width 0.05715)
			(type default)
		)
		(layer "In9.Cu")
	)
	(gr_line
		(start 414.243012 -0.765048)
		(end 414.280096 -0.774446)
		(stroke
			(width 0.05715)
			(type default)
		)
		(layer "In9.Cu")
	)
	(gr_line
		(start 414.280096 -0.774446)
		(end 414.316672 -0.76454)
		(stroke
			(width 0.05715)
			(type default)
		)
		(layer "In9.Cu")
	)
	(gr_line
		(start 414.31845 -120.005094)
		(end 414.335976 -119.953786)
		(stroke
			(width 0.05715)
			(type default)
		)
		(layer "In9.Cu")
	)
	(gr_line
		(start 414.320228 -119.901208)
		(end 414.335976 -119.953786)
		(stroke
			(width 0.05715)
			(type default)
		)
		(layer "In9.Cu")
	)
	(gr_line
		(start 414.320228 -119.9007)
		(end 414.320228 -119.900954)
		(stroke
			(width 0.05715)
			(type default)
		)
		(layer "In9.Cu")
	)
	(gr_line
		(start 414.380172 -4.826762)
		(end 414.50514 -4.633976)
		(stroke
			(width 0.05715)
			(type default)
		)
		(layer "In9.Cu")
	)
	(gr_line
		(start 414.467548 -15.0876)
		(end 414.490408 -15.092426)
		(stroke
			(width 0.05715)
			(type default)
		)
		(layer "In9.Cu")
	)
	(gr_line
		(start 414.483804 -14.42085)
		(end 414.506664 -14.425676)
		(stroke
			(width 0.05715)
			(type default)
		)
		(layer "In9.Cu")
	)
	(gr_line
		(start 414.490408 -15.092426)
		(end 414.513268 -15.087854)
		(stroke
			(width 0.05715)
			(type default)
		)
		(layer "In9.Cu")
	)
	(gr_line
		(start 414.506664 -14.425676)
		(end 414.529524 -14.421104)
		(stroke
			(width 0.05715)
			(type default)
		)
		(layer "In9.Cu")
	)
	(gr_line
		(start 414.55467 -13.758418)
		(end 414.577276 -13.763244)
		(stroke
			(width 0.05715)
			(type default)
		)
		(layer "In9.Cu")
	)
	(gr_line
		(start 414.56102 -12.40282)
		(end 414.58388 -12.407646)
		(stroke
			(width 0.05715)
			(type default)
		)
		(layer "In9.Cu")
	)
	(gr_line
		(start 414.577276 -13.763244)
		(end 414.600136 -13.758672)
		(stroke
			(width 0.05715)
			(type default)
		)
		(layer "In9.Cu")
	)
	(gr_line
		(start 414.58388 -12.407646)
		(end 414.60674 -12.403074)
		(stroke
			(width 0.05715)
			(type default)
		)
		(layer "In9.Cu")
	)
	(gr_line
		(start 414.600136 -16.500094)
		(end 414.626044 -16.505682)
		(stroke
			(width 0.05715)
			(type default)
		)
		(layer "In9.Cu")
	)
	(gr_line
		(start 414.601406 -13.090906)
		(end 414.624266 -13.095732)
		(stroke
			(width 0.05715)
			(type default)
		)
		(layer "In9.Cu")
	)
	(gr_line
		(start 414.61436 -15.78102)
		(end 414.637474 -15.7861)
		(stroke
			(width 0.05715)
			(type default)
		)
		(layer "In9.Cu")
	)
	(gr_line
		(start 414.623758 -11.709908)
		(end 414.646618 -11.714734)
		(stroke
			(width 0.05715)
			(type default)
		)
		(layer "In9.Cu")
	)
	(gr_line
		(start 414.624266 -13.095732)
		(end 414.647126 -13.09116)
		(stroke
			(width 0.05715)
			(type default)
		)
		(layer "In9.Cu")
	)
	(gr_line
		(start 414.626044 -16.505682)
		(end 414.651952 -16.500094)
		(stroke
			(width 0.05715)
			(type default)
		)
		(layer "In9.Cu")
	)
	(gr_line
		(start 414.637474 -15.7861)
		(end 414.661096 -15.78102)
		(stroke
			(width 0.05715)
			(type default)
		)
		(layer "In9.Cu")
	)
	(gr_line
		(start 414.646618 -11.714734)
		(end 414.669478 -11.710162)
		(stroke
			(width 0.05715)
			(type default)
		)
		(layer "In9.Cu")
	)
	(gr_line
		(start 414.72104 -117.368066)
		(end 414.80359 -117.319044)
		(stroke
			(width 0.05715)
			(type default)
		)
		(layer "In9.Cu")
	)
	(gr_line
		(start 414.80359 -117.319044)
		(end 414.894522 -117.349016)
		(stroke
			(width 0.05715)
			(type default)
		)
		(layer "In9.Cu")
	)
	(gr_line
		(start 414.809178 -118.463822)
		(end 414.889188 -118.419372)
		(stroke
			(width 0.05715)
			(type default)
		)
		(layer "In9.Cu")
	)
	(gr_line
		(start 414.819592 -4.266184)
		(end 414.842706 -4.261104)
		(stroke
			(width 0.05715)
			(type default)
		)
		(layer "In9.Cu")
	)
	(gr_line
		(start 414.82899 -3.607562)
		(end 414.852104 -3.602482)
		(stroke
			(width 0.05715)
			(type default)
		)
		(layer "In9.Cu")
	)
	(gr_line
		(start 414.842706 -4.261104)
		(end 414.86582 -4.266184)
		(stroke
			(width 0.05715)
			(type default)
		)
		(layer "In9.Cu")
	)
	(gr_line
		(start 414.852104 -3.602482)
		(end 414.875218 -3.607562)
		(stroke
			(width 0.05715)
			(type default)
		)
		(layer "In9.Cu")
	)
	(gr_line
		(start 415.179764 -4.633976)
		(end 415.30524 -4.827016)
		(stroke
			(width 0.05715)
			(type default)
		)
		(layer "In9.Cu")
	)
	(gr_arc
		(start 415.251646 -137.361676)
		(mid 415.242125 -137.267483)
		(end 415.193226 -137.186416)
		(stroke
			(width 0.05715)
			(type default)
		)
		(layer "In9.Cu")
	)
	(gr_arc
		(start 415.251646 -137.361676)
		(mid 415.261105 -137.455701)
		(end 415.309812 -137.536682)
		(stroke
			(width 0.05715)
			(type default)
		)
		(layer "In9.Cu")
	)
	(gr_line
		(start 415.275268 -4.353052)
		(end 415.859722 -4.477512)
		(stroke
			(width 0.05715)
			(type default)
		)
		(layer "In9.Cu")
	)
	(gr_line
		(start 415.30524 -4.827016)
		(end 415.640774 -4.89839)
		(stroke
			(width 0.05715)
			(type default)
		)
		(layer "In9.Cu")
	)
	(gr_line
		(start 415.309812 -137.536682)
		(end 415.552382 -137.779252)
		(stroke
			(width 0.05715)
			(type default)
		)
		(layer "In9.Cu")
	)
	(gr_line
		(start 415.426398 -137.006076)
		(end 416.084258 -137.663936)
		(stroke
			(width 0.05715)
			(type default)
		)
		(layer "In9.Cu")
	)
	(gr_line
		(start 415.457132 -9.195308)
		(end 415.480246 -9.200388)
		(stroke
			(width 0.05715)
			(type default)
		)
		(layer "In9.Cu")
	)
	(gr_line
		(start 415.480246 -9.200388)
		(end 415.50336 -9.195308)
		(stroke
			(width 0.05715)
			(type default)
		)
		(layer "In9.Cu")
	)
	(gr_line
		(start 415.480246 -7.875016)
		(end 415.50336 -7.880096)
		(stroke
			(width 0.05715)
			(type default)
		)
		(layer "In9.Cu")
	)
	(gr_line
		(start 415.486342 -7.216902)
		(end 415.509456 -7.221982)
		(stroke
			(width 0.05715)
			(type default)
		)
		(layer "In9.Cu")
	)
	(gr_line
		(start 415.493454 -8.532622)
		(end 415.516568 -8.537702)
		(stroke
			(width 0.05715)
			(type default)
		)
		(layer "In9.Cu")
	)
	(gr_line
		(start 415.50336 -7.880096)
		(end 415.526474 -7.875016)
		(stroke
			(width 0.05715)
			(type default)
		)
		(layer "In9.Cu")
	)
	(gr_line
		(start 415.506408 -6.560058)
		(end 415.529522 -6.565138)
		(stroke
			(width 0.05715)
			(type default)
		)
		(layer "In9.Cu")
	)
	(gr_line
		(start 415.509456 -7.221982)
		(end 415.53257 -7.216902)
		(stroke
			(width 0.05715)
			(type default)
		)
		(layer "In9.Cu")
	)
	(gr_line
		(start 415.516568 -8.537702)
		(end 415.539682 -8.532622)
		(stroke
			(width 0.05715)
			(type default)
		)
		(layer "In9.Cu")
	)
	(gr_line
		(start 415.529522 -6.565138)
		(end 415.552636 -6.560058)
		(stroke
			(width 0.05715)
			(type default)
		)
		(layer "In9.Cu")
	)
	(gr_line
		(start 415.53257 -0.136652)
		(end 415.586926 -0.122174)
		(stroke
			(width 0.05715)
			(type default)
		)
		(layer "In9.Cu")
	)
	(gr_arc
		(start 415.552382 -137.779252)
		(mid 415.633475 -137.828044)
		(end 415.727642 -137.837418)
		(stroke
			(width 0.05715)
			(type default)
		)
		(layer "In9.Cu")
	)
	(gr_line
		(start 415.586926 -0.122174)
		(end 415.639504 -0.141986)
		(stroke
			(width 0.05715)
			(type default)
		)
		(layer "In9.Cu")
	)
	(gr_line
		(start 415.640774 -4.89839)
		(end 415.83356 -4.773168)
		(stroke
			(width 0.05715)
			(type default)
		)
		(layer "In9.Cu")
	)
	(gr_arc
		(start 415.902648 -137.895838)
		(mid 415.821701 -137.846979)
		(end 415.727642 -137.837418)
		(stroke
			(width 0.05715)
			(type default)
		)
		(layer "In9.Cu")
	)
	(gr_line
		(start 415.939986 -119.07774)
		(end 415.990278 -119.063262)
		(stroke
			(width 0.05715)
			(type default)
		)
		(layer "In9.Cu")
	)
	(gr_line
		(start 415.967926 -118.010686)
		(end 416.019742 -118.027704)
		(stroke
			(width 0.05715)
			(type default)
		)
		(layer "In9.Cu")
	)
	(gr_line
		(start 416.019742 -118.027704)
		(end 416.07105 -118.01221)
		(stroke
			(width 0.05715)
			(type default)
		)
		(layer "In9.Cu")
	)
	(gr_line
		(start 416.068256 -85.964776)
		(end 416.158426 -85.874606)
		(stroke
			(width 0.050546)
			(type default)
		)
		(layer "In9.Cu")
	)
	(gr_line
		(start 416.173666 -4.845304)
		(end 416.299142 -5.038344)
		(stroke
			(width 0.05715)
			(type default)
		)
		(layer "In9.Cu")
	)
	(gr_arc
		(start 416.203638 -138.313414)
		(mid 416.194117 -138.219221)
		(end 416.145218 -138.138154)
		(stroke
			(width 0.05715)
			(type default)
		)
		(layer "In9.Cu")
	)
	(gr_arc
		(start 416.203638 -138.313414)
		(mid 416.213111 -138.407431)
		(end 416.261804 -138.48842)
		(stroke
			(width 0.05715)
			(type default)
		)
		(layer "In9.Cu")
	)
	(gr_line
		(start 416.261804 -138.48842)
		(end 416.504374 -138.73099)
		(stroke
			(width 0.05715)
			(type default)
		)
		(layer "In9.Cu")
	)
	(gr_line
		(start 416.26917 -4.56438)
		(end 416.853624 -4.68884)
		(stroke
			(width 0.05715)
			(type default)
		)
		(layer "In9.Cu")
	)
	(gr_line
		(start 416.299142 -5.038344)
		(end 416.634676 -5.109718)
		(stroke
			(width 0.05715)
			(type default)
		)
		(layer "In9.Cu")
	)
	(gr_line
		(start 416.377882 -137.957306)
		(end 417.03625 -138.615674)
		(stroke
			(width 0.05715)
			(type default)
		)
		(layer "In9.Cu")
	)
	(gr_arc
		(start 416.504374 -138.73099)
		(mid 416.585469 -138.779776)
		(end 416.679634 -138.789156)
		(stroke
			(width 0.05715)
			(type default)
		)
		(layer "In9.Cu")
	)
	(gr_line
		(start 416.614864 -92.447872)
		(end 416.627564 -92.460572)
		(stroke
			(width 0.050546)
			(type default)
		)
		(layer "In9.Cu")
	)
	(gr_line
		(start 416.614864 -91.851226)
		(end 416.627564 -91.838526)
		(stroke
			(width 0.050546)
			(type default)
		)
		(layer "In9.Cu")
	)
	(gr_line
		(start 416.627564 -92.460572)
		(end 416.627564 -92.837)
		(stroke
			(width 0.050546)
			(type default)
		)
		(layer "In9.Cu")
	)
	(gr_line
		(start 416.627564 -91.567)
		(end 416.627564 -91.838526)
		(stroke
			(width 0.050546)
			(type default)
		)
		(layer "In9.Cu")
	)
	(gr_line
		(start 416.634676 -5.109718)
		(end 416.827462 -4.984496)
		(stroke
			(width 0.05715)
			(type default)
		)
		(layer "In9.Cu")
	)
	(gr_line
		(start 416.77209 -0.569468)
		(end 416.823144 -0.588772)
		(stroke
			(width 0.05715)
			(type default)
		)
		(layer "In9.Cu")
	)
	(gr_line
		(start 416.823144 -0.588772)
		(end 416.853878 -0.633984)
		(stroke
			(width 0.05715)
			(type default)
		)
		(layer "In9.Cu")
	)
	(gr_arc
		(start 416.85464 -138.847576)
		(mid 416.773693 -138.798717)
		(end 416.679634 -138.789156)
		(stroke
			(width 0.05715)
			(type default)
		)
		(layer "In9.Cu")
	)
	(gr_line
		(start 417.094162 -8.559038)
		(end 417.117276 -8.553958)
		(stroke
			(width 0.05715)
			(type default)
		)
		(layer "In9.Cu")
	)
	(gr_line
		(start 417.110672 -7.900416)
		(end 417.133786 -7.895336)
		(stroke
			(width 0.05715)
			(type default)
		)
		(layer "In9.Cu")
	)
	(gr_line
		(start 417.114736 -7.239254)
		(end 417.13785 -7.234174)
		(stroke
			(width 0.05715)
			(type default)
		)
		(layer "In9.Cu")
	)
	(gr_line
		(start 417.117276 -8.553958)
		(end 417.14039 -8.559038)
		(stroke
			(width 0.05715)
			(type default)
		)
		(layer "In9.Cu")
	)
	(gr_line
		(start 417.127436 -6.57987)
		(end 417.15055 -6.57479)
		(stroke
			(width 0.05715)
			(type default)
		)
		(layer "In9.Cu")
	)
	(gr_line
		(start 417.133786 -7.895336)
		(end 417.1569 -7.900416)
		(stroke
			(width 0.05715)
			(type default)
		)
		(layer "In9.Cu")
	)
	(gr_line
		(start 417.13785 -7.234174)
		(end 417.160964 -7.239254)
		(stroke
			(width 0.05715)
			(type default)
		)
		(layer "In9.Cu")
	)
	(gr_line
		(start 417.149788 -5.922518)
		(end 417.172902 -5.917438)
		(stroke
			(width 0.05715)
			(type default)
		)
		(layer "In9.Cu")
	)
	(gr_line
		(start 417.15055 -6.57479)
		(end 417.173664 -6.57987)
		(stroke
			(width 0.05715)
			(type default)
		)
		(layer "In9.Cu")
	)
	(gr_arc
		(start 417.15563 -139.265152)
		(mid 417.146109 -139.170959)
		(end 417.09721 -139.089892)
		(stroke
			(width 0.05715)
			(type default)
		)
		(layer "In9.Cu")
	)
	(gr_arc
		(start 417.15563 -139.265152)
		(mid 417.165079 -139.359183)
		(end 417.213796 -139.440158)
		(stroke
			(width 0.05715)
			(type default)
		)
		(layer "In9.Cu")
	)
	(gr_line
		(start 417.167568 -5.056632)
		(end 417.293044 -5.249672)
		(stroke
			(width 0.05715)
			(type default)
		)
		(layer "In9.Cu")
	)
	(gr_line
		(start 417.172902 -5.917438)
		(end 417.196016 -5.922518)
		(stroke
			(width 0.05715)
			(type default)
		)
		(layer "In9.Cu")
	)
	(gr_line
		(start 417.213796 -139.440158)
		(end 417.456366 -139.682728)
		(stroke
			(width 0.05715)
			(type default)
		)
		(layer "In9.Cu")
	)
	(gr_line
		(start 417.263072 -4.775708)
		(end 417.847526 -4.900168)
		(stroke
			(width 0.05715)
			(type default)
		)
		(layer "In9.Cu")
	)
	(gr_line
		(start 417.293044 -5.249672)
		(end 417.628578 -5.321046)
		(stroke
			(width 0.05715)
			(type default)
		)
		(layer "In9.Cu")
	)
	(gr_line
		(start 417.30295 -1.819148)
		(end 417.311078 -1.831086)
		(stroke
			(width 0.05715)
			(type default)
		)
		(layer "In9.Cu")
	)
	(gr_line
		(start 417.311078 -1.831086)
		(end 417.322508 -1.839468)
		(stroke
			(width 0.05715)
			(type default)
		)
		(layer "In9.Cu")
	)
	(gr_line
		(start 417.329874 -138.909044)
		(end 417.988242 -139.567412)
		(stroke
			(width 0.05715)
			(type default)
		)
		(layer "In9.Cu")
	)
	(gr_line
		(start 417.383976 -103.671878)
		(end 417.394136 -103.629206)
		(stroke
			(width 0.05715)
			(type default)
		)
		(layer "In9.Cu")
	)
	(gr_line
		(start 417.383976 -103.671878)
		(end 417.39693 -103.712772)
		(stroke
			(width 0.05715)
			(type default)
		)
		(layer "In9.Cu")
	)
	(gr_line
		(start 417.38931 -101.96195)
		(end 417.39947 -101.919024)
		(stroke
			(width 0.05715)
			(type default)
		)
		(layer "In9.Cu")
	)
	(gr_line
		(start 417.38931 -101.96195)
		(end 417.402264 -102.002336)
		(stroke
			(width 0.05715)
			(type default)
		)
		(layer "In9.Cu")
	)
	(gr_arc
		(start 417.456366 -139.682728)
		(mid 417.537462 -139.731509)
		(end 417.631626 -139.740894)
		(stroke
			(width 0.05715)
			(type default)
		)
		(layer "In9.Cu")
	)
	(gr_line
		(start 417.628578 -5.321046)
		(end 417.821364 -5.195824)
		(stroke
			(width 0.05715)
			(type default)
		)
		(layer "In9.Cu")
	)
	(gr_arc
		(start 417.806632 -139.799314)
		(mid 417.725685 -139.750455)
		(end 417.631626 -139.740894)
		(stroke
			(width 0.05715)
			(type default)
		)
		(layer "In9.Cu")
	)
	(gr_line
		(start 417.88842 -9.016492)
		(end 417.911534 -9.021572)
		(stroke
			(width 0.05715)
			(type default)
		)
		(layer "In9.Cu")
	)
	(gr_line
		(start 417.900358 -7.694676)
		(end 417.923472 -7.699756)
		(stroke
			(width 0.05715)
			(type default)
		)
		(layer "In9.Cu")
	)
	(gr_line
		(start 417.907216 -102.633272)
		(end 417.920424 -102.674928)
		(stroke
			(width 0.05715)
			(type default)
		)
		(layer "In9.Cu")
	)
	(gr_line
		(start 417.908994 -8.358632)
		(end 417.932108 -8.363712)
		(stroke
			(width 0.05715)
			(type default)
		)
		(layer "In9.Cu")
	)
	(gr_line
		(start 417.910264 -102.717092)
		(end 417.920424 -102.674928)
		(stroke
			(width 0.05715)
			(type default)
		)
		(layer "In9.Cu")
	)
	(gr_line
		(start 417.911534 -9.021572)
		(end 417.934648 -9.016492)
		(stroke
			(width 0.05715)
			(type default)
		)
		(layer "In9.Cu")
	)
	(gr_line
		(start 417.923472 -7.699756)
		(end 417.946586 -7.694676)
		(stroke
			(width 0.05715)
			(type default)
		)
		(layer "In9.Cu")
	)
	(gr_line
		(start 417.924742 -6.3754)
		(end 417.947856 -6.38048)
		(stroke
			(width 0.05715)
			(type default)
		)
		(layer "In9.Cu")
	)
	(gr_line
		(start 417.926012 -7.037832)
		(end 417.949126 -7.042912)
		(stroke
			(width 0.05715)
			(type default)
		)
		(layer "In9.Cu")
	)
	(gr_line
		(start 417.932108 -8.363712)
		(end 417.955222 -8.358632)
		(stroke
			(width 0.05715)
			(type default)
		)
		(layer "In9.Cu")
	)
	(gr_line
		(start 417.947856 -6.38048)
		(end 417.97097 -6.3754)
		(stroke
			(width 0.05715)
			(type default)
		)
		(layer "In9.Cu")
	)
	(gr_line
		(start 417.949126 -7.042912)
		(end 417.97224 -7.037832)
		(stroke
			(width 0.05715)
			(type default)
		)
		(layer "In9.Cu")
	)
	(gr_line
		(start 417.969192 -15.478252)
		(end 417.993576 -15.472918)
		(stroke
			(width 0.05715)
			(type default)
		)
		(layer "In9.Cu")
	)
	(gr_line
		(start 417.987988 -14.780006)
		(end 418.01161 -14.774926)
		(stroke
			(width 0.05715)
			(type default)
		)
		(layer "In9.Cu")
	)
	(gr_line
		(start 417.993576 -15.472918)
		(end 418.018468 -15.478252)
		(stroke
			(width 0.05715)
			(type default)
		)
		(layer "In9.Cu")
	)
	(gr_line
		(start 418.01161 -14.774926)
		(end 418.035486 -14.780006)
		(stroke
			(width 0.05715)
			(type default)
		)
		(layer "In9.Cu")
	)
	(gr_line
		(start 418.029898 -2.359152)
		(end 418.065458 -2.586736)
		(stroke
			(width 0.05715)
			(type default)
		)
		(layer "In9.Cu")
	)
	(gr_line
		(start 418.065458 -2.586736)
		(end 418.342318 -2.78892)
		(stroke
			(width 0.05715)
			(type default)
		)
		(layer "In9.Cu")
	)
	(gr_arc
		(start 418.107622 -140.21689)
		(mid 418.098101 -140.122697)
		(end 418.049202 -140.04163)
		(stroke
			(width 0.05715)
			(type default)
		)
		(layer "In9.Cu")
	)
	(gr_arc
		(start 418.107622 -140.21689)
		(mid 418.117086 -140.310913)
		(end 418.165788 -140.391896)
		(stroke
			(width 0.05715)
			(type default)
		)
		(layer "In9.Cu")
	)
	(gr_line
		(start 418.117528 -98.888042)
		(end 418.136578 -98.808032)
		(stroke
			(width 0.05715)
			(type default)
		)
		(layer "In9.Cu")
	)
	(gr_line
		(start 418.136578 -98.808032)
		(end 418.206174 -98.763836)
		(stroke
			(width 0.05715)
			(type default)
		)
		(layer "In9.Cu")
	)
	(gr_line
		(start 418.16147 -5.26796)
		(end 418.286946 -5.461254)
		(stroke
			(width 0.05715)
			(type default)
		)
		(layer "In9.Cu")
	)
	(gr_line
		(start 418.165788 -140.391896)
		(end 418.408358 -140.634466)
		(stroke
			(width 0.05715)
			(type default)
		)
		(layer "In9.Cu")
	)
	(gr_line
		(start 418.231828 -2.141728)
		(end 418.715698 -2.495296)
		(stroke
			(width 0.05715)
			(type default)
		)
		(layer "In9.Cu")
	)
	(gr_line
		(start 418.245544 -84.379562)
		(end 418.335714 -84.289392)
		(stroke
			(width 0.050546)
			(type default)
		)
		(layer "In9.Cu")
	)
	(gr_line
		(start 418.255958 -4.987036)
		(end 418.84219 -5.11175)
		(stroke
			(width 0.05715)
			(type default)
		)
		(layer "In9.Cu")
	)
	(gr_line
		(start 418.265356 -14.03858)
		(end 418.288216 -14.034008)
		(stroke
			(width 0.05715)
			(type default)
		)
		(layer "In9.Cu")
	)
	(gr_line
		(start 418.281866 -139.861036)
		(end 418.939218 -140.518388)
		(stroke
			(width 0.05715)
			(type default)
		)
		(layer "In9.Cu")
	)
	(gr_line
		(start 418.286946 -5.461254)
		(end 418.62248 -5.532374)
		(stroke
			(width 0.05715)
			(type default)
		)
		(layer "In9.Cu")
	)
	(gr_line
		(start 418.288216 -14.034008)
		(end 418.311076 -14.038834)
		(stroke
			(width 0.05715)
			(type default)
		)
		(layer "In9.Cu")
	)
	(gr_line
		(start 418.321236 -13.364718)
		(end 418.34435 -13.360146)
		(stroke
			(width 0.05715)
			(type default)
		)
		(layer "In9.Cu")
	)
	(gr_line
		(start 418.342318 -2.78892)
		(end 418.569648 -2.753614)
		(stroke
			(width 0.05715)
			(type default)
		)
		(layer "In9.Cu")
	)
	(gr_line
		(start 418.34435 -13.360146)
		(end 418.366702 -13.364972)
		(stroke
			(width 0.05715)
			(type default)
		)
		(layer "In9.Cu")
	)
	(gr_line
		(start 418.386006 -101.996748)
		(end 418.396166 -101.954076)
		(stroke
			(width 0.05715)
			(type default)
		)
		(layer "In9.Cu")
	)
	(gr_line
		(start 418.386006 -101.996748)
		(end 418.39896 -102.037134)
		(stroke
			(width 0.05715)
			(type default)
		)
		(layer "In9.Cu")
	)
	(gr_line
		(start 418.386768 -103.72598)
		(end 418.396928 -103.683308)
		(stroke
			(width 0.05715)
			(type default)
		)
		(layer "In9.Cu")
	)
	(gr_line
		(start 418.386768 -103.72598)
		(end 418.399722 -103.766874)
		(stroke
			(width 0.05715)
			(type default)
		)
		(layer "In9.Cu")
	)
	(gr_arc
		(start 418.408358 -140.634466)
		(mid 418.489426 -140.683359)
		(end 418.583618 -140.692886)
		(stroke
			(width 0.05715)
			(type default)
		)
		(layer "In9.Cu")
	)
	(gr_line
		(start 418.46119 -117.298724)
		(end 418.531548 -117.277896)
		(stroke
			(width 0.05715)
			(type default)
		)
		(layer "In9.Cu")
	)
	(gr_line
		(start 418.52088 -11.321796)
		(end 418.543994 -11.317224)
		(stroke
			(width 0.05715)
			(type default)
		)
		(layer "In9.Cu")
	)
	(gr_line
		(start 418.531548 -117.277642)
		(end 418.531548 -117.277896)
		(stroke
			(width 0.05715)
			(type default)
		)
		(layer "In9.Cu")
	)
	(gr_line
		(start 418.531548 -117.277642)
		(end 418.569394 -117.216936)
		(stroke
			(width 0.05715)
			(type default)
		)
		(layer "In9.Cu")
	)
	(gr_line
		(start 418.543994 -11.317224)
		(end 418.565838 -11.32205)
		(stroke
			(width 0.05715)
			(type default)
		)
		(layer "In9.Cu")
	)
	(gr_line
		(start 418.615368 -12.657836)
		(end 418.638228 -12.653264)
		(stroke
			(width 0.05715)
			(type default)
		)
		(layer "In9.Cu")
	)
	(gr_line
		(start 418.619432 -11.998452)
		(end 418.643562 -11.993626)
		(stroke
			(width 0.05715)
			(type default)
		)
		(layer "In9.Cu")
	)
	(gr_line
		(start 418.62248 -5.532374)
		(end 418.81552 -5.407152)
		(stroke
			(width 0.05715)
			(type default)
		)
		(layer "In9.Cu")
	)
	(gr_line
		(start 418.638228 -12.653264)
		(end 418.661088 -12.65809)
		(stroke
			(width 0.05715)
			(type default)
		)
		(layer "In9.Cu")
	)
	(gr_line
		(start 418.643562 -11.993626)
		(end 418.667438 -11.998706)
		(stroke
			(width 0.05715)
			(type default)
		)
		(layer "In9.Cu")
	)
	(gr_arc
		(start 418.758624 -140.751052)
		(mid 418.677643 -140.702343)
		(end 418.583618 -140.692886)
		(stroke
			(width 0.05715)
			(type default)
		)
		(layer "In9.Cu")
	)
	(gr_line
		(start 418.784024 -10.589006)
		(end 418.806884 -10.584434)
		(stroke
			(width 0.05715)
			(type default)
		)
		(layer "In9.Cu")
	)
	(gr_line
		(start 418.806884 -10.584434)
		(end 418.829236 -10.58926)
		(stroke
			(width 0.05715)
			(type default)
		)
		(layer "In9.Cu")
	)
	(gr_line
		(start 418.910008 -102.687374)
		(end 418.923216 -102.72903)
		(stroke
			(width 0.05715)
			(type default)
		)
		(layer "In9.Cu")
	)
	(gr_line
		(start 418.913056 -102.771194)
		(end 418.923216 -102.72903)
		(stroke
			(width 0.05715)
			(type default)
		)
		(layer "In9.Cu")
	)
	(gr_line
		(start 418.97046 -87.878666)
		(end 418.97046 -87.949532)
		(stroke
			(width 0.050546)
			(type default)
		)
		(layer "In9.Cu")
	)
	(gr_line
		(start 418.97046 -86.659974)
		(end 418.97046 -86.73084)
		(stroke
			(width 0.050546)
			(type default)
		)
		(layer "In9.Cu")
	)
	(gr_line
		(start 418.97046 -85.441282)
		(end 418.97046 -85.512148)
		(stroke
			(width 0.050546)
			(type default)
		)
		(layer "In9.Cu")
	)
	(gr_line
		(start 418.974524 -99.510342)
		(end 418.99332 -99.431094)
		(stroke
			(width 0.05715)
			(type default)
		)
		(layer "In9.Cu")
	)
	(gr_line
		(start 418.99332 -99.431094)
		(end 419.062916 -99.386898)
		(stroke
			(width 0.05715)
			(type default)
		)
		(layer "In9.Cu")
	)
	(gr_line
		(start 419.05301 -2.74193)
		(end 419.073838 -2.75717)
		(stroke
			(width 0.05715)
			(type default)
		)
		(layer "In9.Cu")
	)
	(gr_line
		(start 419.06063 -8.479028)
		(end 419.083744 -8.473948)
		(stroke
			(width 0.05715)
			(type default)
		)
		(layer "In9.Cu")
	)
	(gr_line
		(start 419.072568 -7.157212)
		(end 419.095682 -7.152132)
		(stroke
			(width 0.05715)
			(type default)
		)
		(layer "In9.Cu")
	)
	(gr_line
		(start 419.073838 -2.75717)
		(end 419.086284 -2.779522)
		(stroke
			(width 0.05715)
			(type default)
		)
		(layer "In9.Cu")
	)
	(gr_line
		(start 419.081204 -7.821168)
		(end 419.104318 -7.816088)
		(stroke
			(width 0.05715)
			(type default)
		)
		(layer "In9.Cu")
	)
	(gr_line
		(start 419.083744 -8.473948)
		(end 419.106858 -8.479028)
		(stroke
			(width 0.05715)
			(type default)
		)
		(layer "In9.Cu")
	)
	(gr_line
		(start 419.08603 -118.17985)
		(end 419.15715 -118.15953)
		(stroke
			(width 0.05715)
			(type default)
		)
		(layer "In9.Cu")
	)
	(gr_line
		(start 419.095682 -7.152132)
		(end 419.118796 -7.157212)
		(stroke
			(width 0.05715)
			(type default)
		)
		(layer "In9.Cu")
	)
	(gr_line
		(start 419.097206 -5.837936)
		(end 419.12032 -5.832856)
		(stroke
			(width 0.05715)
			(type default)
		)
		(layer "In9.Cu")
	)
	(gr_line
		(start 419.098222 -6.500368)
		(end 419.121336 -6.495288)
		(stroke
			(width 0.05715)
			(type default)
		)
		(layer "In9.Cu")
	)
	(gr_line
		(start 419.104318 -7.816088)
		(end 419.127432 -7.821168)
		(stroke
			(width 0.05715)
			(type default)
		)
		(layer "In9.Cu")
	)
	(gr_line
		(start 419.12032 -5.832856)
		(end 419.143434 -5.837936)
		(stroke
			(width 0.05715)
			(type default)
		)
		(layer "In9.Cu")
	)
	(gr_line
		(start 419.121336 -6.495288)
		(end 419.14445 -6.500368)
		(stroke
			(width 0.05715)
			(type default)
		)
		(layer "In9.Cu")
	)
	(gr_line
		(start 419.15715 -118.15953)
		(end 419.196266 -118.0973)
		(stroke
			(width 0.05715)
			(type default)
		)
		(layer "In9.Cu")
	)
	(gr_line
		(start 419.320726 -155.64485)
		(end 419.320726 -156.0068)
		(stroke
			(width 0.05715)
			(type default)
		)
		(layer "In9.Cu")
	)
	(gr_arc
		(start 419.320726 -155.12415)
		(mid 419.354204 -155.204972)
		(end 419.435026 -155.23845)
		(stroke
			(width 0.05715)
			(type default)
		)
		(layer "In9.Cu")
	)
	(gr_line
		(start 419.320726 -154.7368)
		(end 419.320726 -155.12415)
		(stroke
			(width 0.05715)
			(type default)
		)
		(layer "In9.Cu")
	)
	(gr_line
		(start 419.392354 -88.368886)
		(end 419.695122 -88.066118)
		(stroke
			(width 0.050546)
			(type default)
		)
		(layer "In9.Cu")
	)
	(gr_line
		(start 419.392354 -87.459312)
		(end 419.695122 -87.76208)
		(stroke
			(width 0.050546)
			(type default)
		)
		(layer "In9.Cu")
	)
	(gr_line
		(start 419.392354 -87.150194)
		(end 419.695122 -86.847426)
		(stroke
			(width 0.050546)
			(type default)
		)
		(layer "In9.Cu")
	)
	(gr_line
		(start 419.392354 -86.24062)
		(end 419.695122 -86.543388)
		(stroke
			(width 0.050546)
			(type default)
		)
		(layer "In9.Cu")
	)
	(gr_line
		(start 419.392354 -85.931502)
		(end 419.695122 -85.628734)
		(stroke
			(width 0.050546)
			(type default)
		)
		(layer "In9.Cu")
	)
	(gr_line
		(start 419.392354 -85.021928)
		(end 419.695122 -85.324696)
		(stroke
			(width 0.050546)
			(type default)
		)
		(layer "In9.Cu")
	)
	(gr_line
		(start 419.430708 -3.998214)
		(end 419.443154 -4.020312)
		(stroke
			(width 0.05715)
			(type default)
		)
		(layer "In9.Cu")
	)
	(gr_arc
		(start 419.435026 -155.53055)
		(mid 419.354169 -155.564015)
		(end 419.320726 -155.64485)
		(stroke
			(width 0.05715)
			(type default)
		)
		(layer "In9.Cu")
	)
	(gr_line
		(start 419.443154 -4.020312)
		(end 419.46322 -4.035044)
		(stroke
			(width 0.05715)
			(type default)
		)
		(layer "In9.Cu")
	)
	(gr_line
		(start 419.521894 -112.906302)
		(end 419.53815 -112.958626)
		(stroke
			(width 0.05715)
			(type default)
		)
		(layer "In9.Cu")
	)
	(gr_line
		(start 419.521894 -112.906302)
		(end 419.538404 -112.853724)
		(stroke
			(width 0.05715)
			(type default)
		)
		(layer "In9.Cu")
	)
	(gr_line
		(start 419.556692 -11.04265)
		(end 419.579806 -11.04773)
		(stroke
			(width 0.05715)
			(type default)
		)
		(layer "In9.Cu")
	)
	(gr_line
		(start 419.579806 -11.04773)
		(end 419.602666 -11.042904)
		(stroke
			(width 0.05715)
			(type default)
		)
		(layer "In9.Cu")
	)
	(gr_arc
		(start 419.620446 -151.22525)
		(mid 419.701268 -151.191772)
		(end 419.734746 -151.11095)
		(stroke
			(width 0.05715)
			(type default)
		)
		(layer "In9.Cu")
	)
	(gr_line
		(start 419.636194 -92.531946)
		(end 419.655244 -92.550996)
		(stroke
			(width 0.050546)
			(type default)
		)
		(layer "In9.Cu")
	)
	(gr_line
		(start 419.636194 -91.9353)
		(end 419.655244 -91.91625)
		(stroke
			(width 0.050546)
			(type default)
		)
		(layer "In9.Cu")
	)
	(gr_line
		(start 419.655244 -92.550996)
		(end 419.655244 -92.8624)
		(stroke
			(width 0.050546)
			(type default)
		)
		(layer "In9.Cu")
	)
	(gr_line
		(start 419.655244 -91.5924)
		(end 419.655244 -91.91625)
		(stroke
			(width 0.050546)
			(type default)
		)
		(layer "In9.Cu")
	)
	(gr_line
		(start 419.695122 -87.76208)
		(end 419.695122 -88.066118)
		(stroke
			(width 0.050546)
			(type default)
		)
		(layer "In9.Cu")
	)
	(gr_line
		(start 419.695122 -86.543388)
		(end 419.695122 -86.847426)
		(stroke
			(width 0.050546)
			(type default)
		)
		(layer "In9.Cu")
	)
	(gr_line
		(start 419.695122 -85.324696)
		(end 419.695122 -85.628734)
		(stroke
			(width 0.050546)
			(type default)
		)
		(layer "In9.Cu")
	)
	(gr_arc
		(start 419.734746 -151.63165)
		(mid 419.701253 -151.550844)
		(end 419.620446 -151.51735)
		(stroke
			(width 0.05715)
			(type default)
		)
		(layer "In9.Cu")
	)
	(gr_line
		(start 419.734746 -151.63165)
		(end 419.734746 -151.8793)
		(stroke
			(width 0.05715)
			(type default)
		)
		(layer "In9.Cu")
	)
	(gr_line
		(start 419.734746 -150.8633)
		(end 419.734746 -151.11095)
		(stroke
			(width 0.05715)
			(type default)
		)
		(layer "In9.Cu")
	)
	(gr_line
		(start 419.788848 -4.275836)
		(end 419.810184 -4.291838)
		(stroke
			(width 0.05715)
			(type default)
		)
		(layer "In9.Cu")
	)
	(gr_line
		(start 419.810184 -4.291838)
		(end 419.836346 -4.297172)
		(stroke
			(width 0.05715)
			(type default)
		)
		(layer "In9.Cu")
	)
	(gr_line
		(start 420.141654 -114.023902)
		(end 420.157402 -113.973864)
		(stroke
			(width 0.05715)
			(type default)
		)
		(layer "In9.Cu")
	)
	(gr_line
		(start 420.141654 -113.922556)
		(end 420.157402 -113.973864)
		(stroke
			(width 0.05715)
			(type default)
		)
		(layer "In9.Cu")
	)
	(gr_line
		(start 420.198296 -111.738918)
		(end 420.21506 -111.685832)
		(stroke
			(width 0.05715)
			(type default)
		)
		(layer "In9.Cu")
	)
	(gr_line
		(start 420.198296 -111.633)
		(end 420.21506 -111.685832)
		(stroke
			(width 0.05715)
			(type default)
		)
		(layer "In9.Cu")
	)
	(gr_line
		(start 420.264336 -7.036816)
		(end 420.28745 -7.041896)
		(stroke
			(width 0.05715)
			(type default)
		)
		(layer "In9.Cu")
	)
	(gr_line
		(start 420.26459 -9.02335)
		(end 420.287704 -9.02843)
		(stroke
			(width 0.05715)
			(type default)
		)
		(layer "In9.Cu")
	)
	(gr_line
		(start 420.26459 -8.361172)
		(end 420.287704 -8.366252)
		(stroke
			(width 0.05715)
			(type default)
		)
		(layer "In9.Cu")
	)
	(gr_line
		(start 420.26459 -7.698994)
		(end 420.287704 -7.704074)
		(stroke
			(width 0.05715)
			(type default)
		)
		(layer "In9.Cu")
	)
	(gr_line
		(start 420.286942 -6.379464)
		(end 420.310056 -6.384544)
		(stroke
			(width 0.05715)
			(type default)
		)
		(layer "In9.Cu")
	)
	(gr_line
		(start 420.28745 -7.041896)
		(end 420.310564 -7.036816)
		(stroke
			(width 0.05715)
			(type default)
		)
		(layer "In9.Cu")
	)
	(gr_line
		(start 420.287704 -9.02843)
		(end 420.310818 -9.02335)
		(stroke
			(width 0.05715)
			(type default)
		)
		(layer "In9.Cu")
	)
	(gr_line
		(start 420.287704 -8.366252)
		(end 420.310818 -8.361172)
		(stroke
			(width 0.05715)
			(type default)
		)
		(layer "In9.Cu")
	)
	(gr_line
		(start 420.287704 -7.704074)
		(end 420.310818 -7.698994)
		(stroke
			(width 0.05715)
			(type default)
		)
		(layer "In9.Cu")
	)
	(gr_line
		(start 420.299896 -5.72008)
		(end 420.32301 -5.72516)
		(stroke
			(width 0.05715)
			(type default)
		)
		(layer "In9.Cu")
	)
	(gr_line
		(start 420.310056 -6.384544)
		(end 420.33317 -6.379464)
		(stroke
			(width 0.05715)
			(type default)
		)
		(layer "In9.Cu")
	)
	(gr_line
		(start 420.32301 -5.72516)
		(end 420.346124 -5.72008)
		(stroke
			(width 0.05715)
			(type default)
		)
		(layer "In9.Cu")
	)
	(gr_line
		(start 420.32428 -5.062982)
		(end 420.347394 -5.068062)
		(stroke
			(width 0.05715)
			(type default)
		)
		(layer "In9.Cu")
	)
	(gr_line
		(start 420.347394 -5.068062)
		(end 420.370508 -5.062982)
		(stroke
			(width 0.05715)
			(type default)
		)
		(layer "In9.Cu")
	)
	(gr_line
		(start 420.350188 -4.406392)
		(end 420.373302 -4.411472)
		(stroke
			(width 0.05715)
			(type default)
		)
		(layer "In9.Cu")
	)
	(gr_line
		(start 420.373302 -4.411472)
		(end 420.396416 -4.406392)
		(stroke
			(width 0.05715)
			(type default)
		)
		(layer "In9.Cu")
	)
	(gr_line
		(start 420.562024 -112.764316)
		(end 420.578026 -112.816386)
		(stroke
			(width 0.05715)
			(type default)
		)
		(layer "In9.Cu")
	)
	(gr_line
		(start 420.562024 -112.764316)
		(end 420.578534 -112.712246)
		(stroke
			(width 0.05715)
			(type default)
		)
		(layer "In9.Cu")
	)
	(gr_line
		(start 420.578534 -112.711992)
		(end 420.578788 -112.71123)
		(stroke
			(width 0.05715)
			(type default)
		)
		(layer "In9.Cu")
	)
	(gr_arc
		(start 420.816532 -153.33345)
		(mid 420.860243 -153.324695)
		(end 420.897304 -153.299922)
		(stroke
			(width 0.05715)
			(type default)
		)
		(layer "In9.Cu")
	)
	(gr_arc
		(start 420.897304 -153.659078)
		(mid 420.860245 -153.634316)
		(end 420.816532 -153.62555)
		(stroke
			(width 0.05715)
			(type default)
		)
		(layer "In9.Cu")
	)
	(gr_line
		(start 420.897304 -153.659078)
		(end 421.225726 -153.9875)
		(stroke
			(width 0.05715)
			(type default)
		)
		(layer "In9.Cu")
	)
	(gr_line
		(start 420.897304 -153.299922)
		(end 421.225726 -152.9715)
		(stroke
			(width 0.05715)
			(type default)
		)
		(layer "In9.Cu")
	)
	(gr_line
		(start 421.05326 -10.435082)
		(end 421.07612 -10.430256)
		(stroke
			(width 0.05715)
			(type default)
		)
		(layer "In9.Cu")
	)
	(gr_line
		(start 421.07612 -10.430256)
		(end 421.099234 -10.435336)
		(stroke
			(width 0.05715)
			(type default)
		)
		(layer "In9.Cu")
	)
	(gr_line
		(start 421.189404 -111.754158)
		(end 421.206168 -111.701326)
		(stroke
			(width 0.05715)
			(type default)
		)
		(layer "In9.Cu")
	)
	(gr_line
		(start 421.189404 -111.648494)
		(end 421.206168 -111.701326)
		(stroke
			(width 0.05715)
			(type default)
		)
		(layer "In9.Cu")
	)
	(gr_line
		(start 421.207438 -113.964466)
		(end 421.223186 -113.914428)
		(stroke
			(width 0.05715)
			(type default)
		)
		(layer "In9.Cu")
	)
	(gr_line
		(start 421.207438 -113.863882)
		(end 421.223186 -113.914428)
		(stroke
			(width 0.05715)
			(type default)
		)
		(layer "In9.Cu")
	)
	(gr_line
		(start 421.256206 -96.828356)
		(end 421.29583 -96.80321)
		(stroke
			(width 0.05715)
			(type default)
		)
		(layer "In9.Cu")
	)
	(gr_line
		(start 421.39235 -12.221464)
		(end 421.415464 -12.226544)
		(stroke
			(width 0.05715)
			(type default)
		)
		(layer "In9.Cu")
	)
	(gr_line
		(start 421.415464 -12.226544)
		(end 421.438578 -12.221464)
		(stroke
			(width 0.05715)
			(type default)
		)
		(layer "In9.Cu")
	)
	(gr_line
		(start 421.435276 -12.886182)
		(end 421.459406 -12.891262)
		(stroke
			(width 0.05715)
			(type default)
		)
		(layer "In9.Cu")
	)
	(gr_line
		(start 421.449246 -7.158482)
		(end 421.47236 -7.153402)
		(stroke
			(width 0.05715)
			(type default)
		)
		(layer "In9.Cu")
	)
	(gr_line
		(start 421.449246 -6.496304)
		(end 421.47236 -6.491224)
		(stroke
			(width 0.05715)
			(type default)
		)
		(layer "In9.Cu")
	)
	(gr_line
		(start 421.4495 -8.482838)
		(end 421.472614 -8.477758)
		(stroke
			(width 0.05715)
			(type default)
		)
		(layer "In9.Cu")
	)
	(gr_line
		(start 421.4495 -7.82066)
		(end 421.472614 -7.81558)
		(stroke
			(width 0.05715)
			(type default)
		)
		(layer "In9.Cu")
	)
	(gr_line
		(start 421.459406 -12.891262)
		(end 421.482774 -12.886436)
		(stroke
			(width 0.05715)
			(type default)
		)
		(layer "In9.Cu")
	)
	(gr_line
		(start 421.471852 -5.838952)
		(end 421.494966 -5.833872)
		(stroke
			(width 0.05715)
			(type default)
		)
		(layer "In9.Cu")
	)
	(gr_line
		(start 421.47236 -7.153402)
		(end 421.495474 -7.158482)
		(stroke
			(width 0.05715)
			(type default)
		)
		(layer "In9.Cu")
	)
	(gr_line
		(start 421.47236 -6.491224)
		(end 421.495474 -6.496304)
		(stroke
			(width 0.05715)
			(type default)
		)
		(layer "In9.Cu")
	)
	(gr_line
		(start 421.472614 -8.477758)
		(end 421.495728 -8.482838)
		(stroke
			(width 0.05715)
			(type default)
		)
		(layer "In9.Cu")
	)
	(gr_line
		(start 421.472614 -7.81558)
		(end 421.495728 -7.82066)
		(stroke
			(width 0.05715)
			(type default)
		)
		(layer "In9.Cu")
	)
	(gr_line
		(start 421.484806 -5.179568)
		(end 421.50792 -5.174488)
		(stroke
			(width 0.05715)
			(type default)
		)
		(layer "In9.Cu")
	)
	(gr_line
		(start 421.494966 -5.833872)
		(end 421.51808 -5.838952)
		(stroke
			(width 0.05715)
			(type default)
		)
		(layer "In9.Cu")
	)
	(gr_line
		(start 421.50792 -5.174488)
		(end 421.531034 -5.179568)
		(stroke
			(width 0.05715)
			(type default)
		)
		(layer "In9.Cu")
	)
	(gr_line
		(start 421.50919 -4.52247)
		(end 421.532304 -4.51739)
		(stroke
			(width 0.05715)
			(type default)
		)
		(layer "In9.Cu")
	)
	(gr_line
		(start 421.532304 -4.51739)
		(end 421.555418 -4.52247)
		(stroke
			(width 0.05715)
			(type default)
		)
		(layer "In9.Cu")
	)
	(gr_line
		(start 421.535352 -3.86588)
		(end 421.558466 -3.8608)
		(stroke
			(width 0.05715)
			(type default)
		)
		(layer "In9.Cu")
	)
	(gr_line
		(start 421.558466 -3.8608)
		(end 421.58158 -3.86588)
		(stroke
			(width 0.05715)
			(type default)
		)
		(layer "In9.Cu")
	)
	(gr_line
		(start 421.610536 -97.770188)
		(end 421.65016 -97.745042)
		(stroke
			(width 0.05715)
			(type default)
		)
		(layer "In9.Cu")
	)
	(gr_line
		(start 421.81272 -150.0505)
		(end 422.16451 -149.69871)
		(stroke
			(width 0.05715)
			(type default)
		)
		(layer "In9.Cu")
	)
	(gr_line
		(start 421.81272 -149.0345)
		(end 422.117774 -149.339554)
		(stroke
			(width 0.05715)
			(type default)
		)
		(layer "In9.Cu")
	)
	(gr_arc
		(start 422.245282 -149.665182)
		(mid 422.201564 -149.673929)
		(end 422.16451 -149.69871)
		(stroke
			(width 0.05715)
			(type default)
		)
		(layer "In9.Cu")
	)
	(gr_line
		(start 422.691814 -9.035288)
		(end 422.714928 -9.040368)
		(stroke
			(width 0.05715)
			(type default)
		)
		(layer "In9.Cu")
	)
	(gr_line
		(start 422.691814 -8.37311)
		(end 422.714928 -8.37819)
		(stroke
			(width 0.05715)
			(type default)
		)
		(layer "In9.Cu")
	)
	(gr_line
		(start 422.691814 -7.710932)
		(end 422.714928 -7.716012)
		(stroke
			(width 0.05715)
			(type default)
		)
		(layer "In9.Cu")
	)
	(gr_line
		(start 422.692068 -7.048754)
		(end 422.715182 -7.053834)
		(stroke
			(width 0.05715)
			(type default)
		)
		(layer "In9.Cu")
	)
	(gr_line
		(start 422.692068 -6.38683)
		(end 422.715182 -6.39191)
		(stroke
			(width 0.05715)
			(type default)
		)
		(layer "In9.Cu")
	)
	(gr_line
		(start 422.692068 -5.724652)
		(end 422.715182 -5.729732)
		(stroke
			(width 0.05715)
			(type default)
		)
		(layer "In9.Cu")
	)
	(gr_line
		(start 422.708832 -5.06603)
		(end 422.731946 -5.07111)
		(stroke
			(width 0.05715)
			(type default)
		)
		(layer "In9.Cu")
	)
	(gr_line
		(start 422.714928 -9.040368)
		(end 422.738042 -9.035288)
		(stroke
			(width 0.05715)
			(type default)
		)
		(layer "In9.Cu")
	)
	(gr_line
		(start 422.714928 -8.37819)
		(end 422.738042 -8.37311)
		(stroke
			(width 0.05715)
			(type default)
		)
		(layer "In9.Cu")
	)
	(gr_line
		(start 422.714928 -7.716012)
		(end 422.738042 -7.710932)
		(stroke
			(width 0.05715)
			(type default)
		)
		(layer "In9.Cu")
	)
	(gr_line
		(start 422.715182 -7.053834)
		(end 422.738296 -7.048754)
		(stroke
			(width 0.05715)
			(type default)
		)
		(layer "In9.Cu")
	)
	(gr_line
		(start 422.715182 -6.39191)
		(end 422.738296 -6.38683)
		(stroke
			(width 0.05715)
			(type default)
		)
		(layer "In9.Cu")
	)
	(gr_line
		(start 422.715182 -5.729732)
		(end 422.738296 -5.724652)
		(stroke
			(width 0.05715)
			(type default)
		)
		(layer "In9.Cu")
	)
	(gr_line
		(start 422.725342 -4.407408)
		(end 422.748456 -4.412488)
		(stroke
			(width 0.05715)
			(type default)
		)
		(layer "In9.Cu")
	)
	(gr_line
		(start 422.731946 -5.07111)
		(end 422.75506 -5.06603)
		(stroke
			(width 0.05715)
			(type default)
		)
		(layer "In9.Cu")
	)
	(gr_line
		(start 422.748456 -4.412488)
		(end 422.77157 -4.407408)
		(stroke
			(width 0.05715)
			(type default)
		)
		(layer "In9.Cu")
	)
	(gr_line
		(start 423.174668 -11.175238)
		(end 423.197782 -11.180318)
		(stroke
			(width 0.05715)
			(type default)
		)
		(layer "In9.Cu")
	)
	(gr_line
		(start 423.197782 -11.180318)
		(end 423.220896 -11.175238)
		(stroke
			(width 0.05715)
			(type default)
		)
		(layer "In9.Cu")
	)
	(gr_line
		(start 423.24274 -97.09531)
		(end 423.283634 -97.06864)
		(stroke
			(width 0.05715)
			(type default)
		)
		(layer "In9.Cu")
	)
	(gr_line
		(start 423.33672 -76.558394)
		(end 423.338498 -76.563728)
		(stroke
			(width 0.05715)
			(type default)
		)
		(layer "In9.Cu")
	)
	(gr_line
		(start 423.361612 -81.20126)
		(end 423.371518 -81.159096)
		(stroke
			(width 0.05715)
			(type default)
		)
		(layer "In9.Cu")
	)
	(gr_line
		(start 423.361612 -81.20126)
		(end 423.37482 -81.24317)
		(stroke
			(width 0.05715)
			(type default)
		)
		(layer "In9.Cu")
	)
	(gr_line
		(start 423.53865 -85.440012)
		(end 423.548556 -85.397848)
		(stroke
			(width 0.05715)
			(type default)
		)
		(layer "In9.Cu")
	)
	(gr_line
		(start 423.53865 -85.440012)
		(end 423.551858 -85.481922)
		(stroke
			(width 0.05715)
			(type default)
		)
		(layer "In9.Cu")
	)
	(gr_line
		(start 423.619422 -98.037142)
		(end 423.659554 -98.010726)
		(stroke
			(width 0.05715)
			(type default)
		)
		(layer "In9.Cu")
	)
	(gr_line
		(start 423.7101 -89.723976)
		(end 423.72026 -89.68105)
		(stroke
			(width 0.05715)
			(type default)
		)
		(layer "In9.Cu")
	)
	(gr_line
		(start 423.7101 -89.723976)
		(end 423.723308 -89.765886)
		(stroke
			(width 0.05715)
			(type default)
		)
		(layer "In9.Cu")
	)
	(gr_line
		(start 423.782744 -96.74225)
		(end 423.849038 -96.69907)
		(stroke
			(width 0.05715)
			(type default)
		)
		(layer "In9.Cu")
	)
	(gr_line
		(start 423.849038 -96.69907)
		(end 423.867326 -96.621854)
		(stroke
			(width 0.05715)
			(type default)
		)
		(layer "In9.Cu")
	)
	(gr_line
		(start 423.869358 -8.496808)
		(end 423.892472 -8.491728)
		(stroke
			(width 0.05715)
			(type default)
		)
		(layer "In9.Cu")
	)
	(gr_line
		(start 423.869358 -7.83463)
		(end 423.892472 -7.82955)
		(stroke
			(width 0.05715)
			(type default)
		)
		(layer "In9.Cu")
	)
	(gr_line
		(start 423.869612 -7.172452)
		(end 423.892726 -7.167372)
		(stroke
			(width 0.05715)
			(type default)
		)
		(layer "In9.Cu")
	)
	(gr_line
		(start 423.869612 -6.510274)
		(end 423.892726 -6.505194)
		(stroke
			(width 0.05715)
			(type default)
		)
		(layer "In9.Cu")
	)
	(gr_line
		(start 423.869612 -5.848096)
		(end 423.892726 -5.843016)
		(stroke
			(width 0.05715)
			(type default)
		)
		(layer "In9.Cu")
	)
	(gr_line
		(start 423.869866 -5.186172)
		(end 423.89298 -5.181092)
		(stroke
			(width 0.05715)
			(type default)
		)
		(layer "In9.Cu")
	)
	(gr_line
		(start 423.88663 -4.52755)
		(end 423.909744 -4.52247)
		(stroke
			(width 0.05715)
			(type default)
		)
		(layer "In9.Cu")
	)
	(gr_line
		(start 423.892472 -8.491728)
		(end 423.915586 -8.496808)
		(stroke
			(width 0.05715)
			(type default)
		)
		(layer "In9.Cu")
	)
	(gr_line
		(start 423.892472 -7.82955)
		(end 423.915586 -7.83463)
		(stroke
			(width 0.05715)
			(type default)
		)
		(layer "In9.Cu")
	)
	(gr_line
		(start 423.892726 -7.167372)
		(end 423.91584 -7.172452)
		(stroke
			(width 0.05715)
			(type default)
		)
		(layer "In9.Cu")
	)
	(gr_line
		(start 423.892726 -6.505194)
		(end 423.91584 -6.510274)
		(stroke
			(width 0.05715)
			(type default)
		)
		(layer "In9.Cu")
	)
	(gr_line
		(start 423.892726 -5.843016)
		(end 423.91584 -5.848096)
		(stroke
			(width 0.05715)
			(type default)
		)
		(layer "In9.Cu")
	)
	(gr_line
		(start 423.89298 -5.181092)
		(end 423.916094 -5.186172)
		(stroke
			(width 0.05715)
			(type default)
		)
		(layer "In9.Cu")
	)
	(gr_line
		(start 423.90314 -3.868928)
		(end 423.926254 -3.863848)
		(stroke
			(width 0.05715)
			(type default)
		)
		(layer "In9.Cu")
	)
	(gr_line
		(start 423.909744 -4.52247)
		(end 423.932858 -4.52755)
		(stroke
			(width 0.05715)
			(type default)
		)
		(layer "In9.Cu")
	)
	(gr_line
		(start 423.926254 -3.863848)
		(end 423.949368 -3.868928)
		(stroke
			(width 0.05715)
			(type default)
		)
		(layer "In9.Cu")
	)
	(gr_line
		(start 424.007534 -14.859508)
		(end 424.029886 -14.864334)
		(stroke
			(width 0.05715)
			(type default)
		)
		(layer "In9.Cu")
	)
	(gr_line
		(start 424.029886 -14.864334)
		(end 424.052746 -14.859762)
		(stroke
			(width 0.05715)
			(type default)
		)
		(layer "In9.Cu")
	)
	(gr_line
		(start 424.107102 -14.10462)
		(end 424.1292 -14.109446)
		(stroke
			(width 0.05715)
			(type default)
		)
		(layer "In9.Cu")
	)
	(gr_line
		(start 424.120056 -15.570962)
		(end 424.142916 -15.575788)
		(stroke
			(width 0.05715)
			(type default)
		)
		(layer "In9.Cu")
	)
	(gr_line
		(start 424.1292 -14.109446)
		(end 424.151806 -14.104874)
		(stroke
			(width 0.05715)
			(type default)
		)
		(layer "In9.Cu")
	)
	(gr_line
		(start 424.142916 -15.575788)
		(end 424.165268 -15.571216)
		(stroke
			(width 0.05715)
			(type default)
		)
		(layer "In9.Cu")
	)
	(gr_line
		(start 424.267884 -78.54188)
		(end 424.281092 -78.584044)
		(stroke
			(width 0.05715)
			(type default)
		)
		(layer "In9.Cu")
	)
	(gr_line
		(start 424.271186 -78.6257)
		(end 424.281092 -78.584044)
		(stroke
			(width 0.05715)
			(type default)
		)
		(layer "In9.Cu")
	)
	(gr_line
		(start 424.27652 -76.199238)
		(end 424.278552 -76.205334)
		(stroke
			(width 0.05715)
			(type default)
		)
		(layer "In9.Cu")
	)
	(gr_line
		(start 424.325288 -83.286092)
		(end 424.338496 -83.328256)
		(stroke
			(width 0.05715)
			(type default)
		)
		(layer "In9.Cu")
	)
	(gr_line
		(start 424.32859 -83.369912)
		(end 424.338496 -83.328256)
		(stroke
			(width 0.05715)
			(type default)
		)
		(layer "In9.Cu")
	)
	(gr_line
		(start 424.349672 -81.109058)
		(end 424.359578 -81.066894)
		(stroke
			(width 0.05715)
			(type default)
		)
		(layer "In9.Cu")
	)
	(gr_line
		(start 424.349672 -81.109058)
		(end 424.36288 -81.150968)
		(stroke
			(width 0.05715)
			(type default)
		)
		(layer "In9.Cu")
	)
	(gr_line
		(start 424.505374 -87.53475)
		(end 424.518582 -87.576914)
		(stroke
			(width 0.05715)
			(type default)
		)
		(layer "In9.Cu")
	)
	(gr_line
		(start 424.508676 -87.61857)
		(end 424.518582 -87.576914)
		(stroke
			(width 0.05715)
			(type default)
		)
		(layer "In9.Cu")
	)
	(gr_line
		(start 424.541442 -85.494368)
		(end 424.551348 -85.452204)
		(stroke
			(width 0.05715)
			(type default)
		)
		(layer "In9.Cu")
	)
	(gr_line
		(start 424.541442 -85.494368)
		(end 424.55465 -85.536278)
		(stroke
			(width 0.05715)
			(type default)
		)
		(layer "In9.Cu")
	)
	(gr_line
		(start 424.625262 -97.379282)
		(end 424.692064 -97.335594)
		(stroke
			(width 0.05715)
			(type default)
		)
		(layer "In9.Cu")
	)
	(gr_line
		(start 424.692064 -97.335594)
		(end 424.710352 -97.258632)
		(stroke
			(width 0.05715)
			(type default)
		)
		(layer "In9.Cu")
	)
	(gr_line
		(start 424.692826 -89.653618)
		(end 424.702732 -89.611454)
		(stroke
			(width 0.05715)
			(type default)
		)
		(layer "In9.Cu")
	)
	(gr_line
		(start 424.692826 -89.653618)
		(end 424.706034 -89.695528)
		(stroke
			(width 0.05715)
			(type default)
		)
		(layer "In9.Cu")
	)
	(gr_line
		(start 424.763184 -11.909298)
		(end 424.784266 -11.90498)
		(stroke
			(width 0.05715)
			(type default)
		)
		(layer "In9.Cu")
	)
	(gr_line
		(start 424.78325 -11.211306)
		(end 424.805094 -11.20648)
		(stroke
			(width 0.05715)
			(type default)
		)
		(layer "In9.Cu")
	)
	(gr_line
		(start 424.784266 -11.90498)
		(end 424.785028 -11.90498)
		(stroke
			(width 0.05715)
			(type default)
		)
		(layer "In9.Cu")
	)
	(gr_line
		(start 424.785028 -11.90498)
		(end 424.806618 -11.909298)
		(stroke
			(width 0.05715)
			(type default)
		)
		(layer "In9.Cu")
	)
	(gr_line
		(start 424.805094 -11.20648)
		(end 424.827446 -11.211052)
		(stroke
			(width 0.05715)
			(type default)
		)
		(layer "In9.Cu")
	)
	(gr_line
		(start 424.811444 -10.53846)
		(end 424.833796 -10.533634)
		(stroke
			(width 0.05715)
			(type default)
		)
		(layer "In9.Cu")
	)
	(gr_line
		(start 424.814238 -14.408658)
		(end 424.834558 -14.404594)
		(stroke
			(width 0.05715)
			(type default)
		)
		(layer "In9.Cu")
	)
	(gr_line
		(start 424.833796 -10.533634)
		(end 424.855894 -10.538206)
		(stroke
			(width 0.05715)
			(type default)
		)
		(layer "In9.Cu")
	)
	(gr_line
		(start 424.834558 -14.404594)
		(end 424.853862 -14.408404)
		(stroke
			(width 0.05715)
			(type default)
		)
		(layer "In9.Cu")
	)
	(gr_line
		(start 424.850306 -92.369132)
		(end 424.863514 -92.411296)
		(stroke
			(width 0.05715)
			(type default)
		)
		(layer "In9.Cu")
	)
	(gr_line
		(start 424.853608 -92.452952)
		(end 424.863514 -92.411296)
		(stroke
			(width 0.05715)
			(type default)
		)
		(layer "In9.Cu")
	)
	(gr_line
		(start 424.964098 -9.018016)
		(end 424.987212 -9.023096)
		(stroke
			(width 0.05715)
			(type default)
		)
		(layer "In9.Cu")
	)
	(gr_line
		(start 424.964098 -8.355838)
		(end 424.987212 -8.360918)
		(stroke
			(width 0.05715)
			(type default)
		)
		(layer "In9.Cu")
	)
	(gr_line
		(start 424.964352 -7.69366)
		(end 424.987466 -7.69874)
		(stroke
			(width 0.05715)
			(type default)
		)
		(layer "In9.Cu")
	)
	(gr_line
		(start 424.979846 -7.034784)
		(end 425.00296 -7.039864)
		(stroke
			(width 0.05715)
			(type default)
		)
		(layer "In9.Cu")
	)
	(gr_line
		(start 424.987212 -9.023096)
		(end 425.010326 -9.018016)
		(stroke
			(width 0.05715)
			(type default)
		)
		(layer "In9.Cu")
	)
	(gr_line
		(start 424.987212 -8.360918)
		(end 425.010326 -8.355838)
		(stroke
			(width 0.05715)
			(type default)
		)
		(layer "In9.Cu")
	)
	(gr_line
		(start 424.987466 -7.69874)
		(end 425.01058 -7.69366)
		(stroke
			(width 0.05715)
			(type default)
		)
		(layer "In9.Cu")
	)
	(gr_line
		(start 425.00296 -7.039864)
		(end 425.026074 -7.034784)
		(stroke
			(width 0.05715)
			(type default)
		)
		(layer "In9.Cu")
	)
	(gr_line
		(start 425.006262 -6.378194)
		(end 425.029376 -6.383274)
		(stroke
			(width 0.05715)
			(type default)
		)
		(layer "In9.Cu")
	)
	(gr_line
		(start 425.023026 -5.719826)
		(end 425.04614 -5.724906)
		(stroke
			(width 0.05715)
			(type default)
		)
		(layer "In9.Cu")
	)
	(gr_line
		(start 425.029376 -6.383274)
		(end 425.05249 -6.378194)
		(stroke
			(width 0.05715)
			(type default)
		)
		(layer "In9.Cu")
	)
	(gr_line
		(start 425.033186 -15.099284)
		(end 425.05249 -15.09522)
		(stroke
			(width 0.05715)
			(type default)
		)
		(layer "In9.Cu")
	)
	(gr_line
		(start 425.04487 -5.06222)
		(end 425.067984 -5.0673)
		(stroke
			(width 0.05715)
			(type default)
		)
		(layer "In9.Cu")
	)
	(gr_line
		(start 425.04614 -5.724906)
		(end 425.069254 -5.719826)
		(stroke
			(width 0.05715)
			(type default)
		)
		(layer "In9.Cu")
	)
	(gr_line
		(start 425.05249 -15.09522)
		(end 425.07154 -15.09903)
		(stroke
			(width 0.05715)
			(type default)
		)
		(layer "In9.Cu")
	)
	(gr_line
		(start 425.067984 -5.0673)
		(end 425.091098 -5.06222)
		(stroke
			(width 0.05715)
			(type default)
		)
		(layer "In9.Cu")
	)
	(gr_line
		(start 425.070524 -4.40563)
		(end 425.093638 -4.41071)
		(stroke
			(width 0.05715)
			(type default)
		)
		(layer "In9.Cu")
	)
	(gr_line
		(start 425.090082 -13.91412)
		(end 425.108878 -13.91031)
		(stroke
			(width 0.05715)
			(type default)
		)
		(layer "In9.Cu")
	)
	(gr_line
		(start 425.093638 -4.41071)
		(end 425.116752 -4.40563)
		(stroke
			(width 0.05715)
			(type default)
		)
		(layer "In9.Cu")
	)
	(gr_line
		(start 425.108878 -13.91031)
		(end 425.124372 -13.899896)
		(stroke
			(width 0.05715)
			(type default)
		)
		(layer "In9.Cu")
	)
	(gr_line
		(start 425.171616 -12.281662)
		(end 425.192952 -12.28598)
		(stroke
			(width 0.05715)
			(type default)
		)
		(layer "In9.Cu")
	)
	(gr_line
		(start 425.192952 -12.28598)
		(end 425.214542 -12.281662)
		(stroke
			(width 0.05715)
			(type default)
		)
		(layer "In9.Cu")
	)
	(gr_line
		(start 425.232322 -11.591798)
		(end 425.253404 -11.596116)
		(stroke
			(width 0.05715)
			(type default)
		)
		(layer "In9.Cu")
	)
	(gr_line
		(start 425.253404 -11.596116)
		(end 425.27474 -11.591798)
		(stroke
			(width 0.05715)
			(type default)
		)
		(layer "In9.Cu")
	)
	(gr_line
		(start 425.271946 -78.383384)
		(end 425.285154 -78.42504)
		(stroke
			(width 0.05715)
			(type default)
		)
		(layer "In9.Cu")
	)
	(gr_line
		(start 425.275248 -78.466696)
		(end 425.285154 -78.42504)
		(stroke
			(width 0.05715)
			(type default)
		)
		(layer "In9.Cu")
	)
	(gr_line
		(start 425.290996 -10.924794)
		(end 425.312586 -10.929112)
		(stroke
			(width 0.05715)
			(type default)
		)
		(layer "In9.Cu")
	)
	(gr_line
		(start 425.312586 -10.929112)
		(end 425.333922 -10.924794)
		(stroke
			(width 0.05715)
			(type default)
		)
		(layer "In9.Cu")
	)
	(gr_line
		(start 425.34205 -83.283806)
		(end 425.355258 -83.325462)
		(stroke
			(width 0.05715)
			(type default)
		)
		(layer "In9.Cu")
	)
	(gr_line
		(start 425.345352 -83.367118)
		(end 425.355258 -83.325462)
		(stroke
			(width 0.05715)
			(type default)
		)
		(layer "In9.Cu")
	)
	(gr_line
		(start 425.479972 -87.498936)
		(end 425.49318 -87.5411)
		(stroke
			(width 0.05715)
			(type default)
		)
		(layer "In9.Cu")
	)
	(gr_line
		(start 425.483274 -87.582756)
		(end 425.49318 -87.5411)
		(stroke
			(width 0.05715)
			(type default)
		)
		(layer "In9.Cu")
	)
	(gr_line
		(start 425.536106 -13.27785)
		(end 425.5516 -13.267436)
		(stroke
			(width 0.05715)
			(type default)
		)
		(layer "In9.Cu")
	)
	(gr_line
		(start 425.5516 -13.267436)
		(end 425.570396 -13.263626)
		(stroke
			(width 0.05715)
			(type default)
		)
		(layer "In9.Cu")
	)
	(gr_line
		(start 425.849288 -92.349828)
		(end 425.862496 -92.39123)
		(stroke
			(width 0.05715)
			(type default)
		)
		(layer "In9.Cu")
	)
	(gr_line
		(start 425.85259 -92.432886)
		(end 425.862496 -92.39123)
		(stroke
			(width 0.05715)
			(type default)
		)
		(layer "In9.Cu")
	)
	(gr_line
		(start 426.198792 -11.105642)
		(end 426.220128 -11.101324)
		(stroke
			(width 0.05715)
			(type default)
		)
		(layer "In9.Cu")
	)
	(gr_line
		(start 426.215048 -11.780266)
		(end 426.235876 -11.775948)
		(stroke
			(width 0.05715)
			(type default)
		)
		(layer "In9.Cu")
	)
	(gr_line
		(start 426.220128 -11.101324)
		(end 426.24121 -11.105642)
		(stroke
			(width 0.05715)
			(type default)
		)
		(layer "In9.Cu")
	)
	(gr_line
		(start 426.224446 -10.445242)
		(end 426.246036 -10.440924)
		(stroke
			(width 0.05715)
			(type default)
		)
		(layer "In9.Cu")
	)
	(gr_line
		(start 426.235876 -11.775948)
		(end 426.257212 -11.780266)
		(stroke
			(width 0.05715)
			(type default)
		)
		(layer "In9.Cu")
	)
	(gr_line
		(start 426.246036 -10.440924)
		(end 426.267372 -10.445242)
		(stroke
			(width 0.05715)
			(type default)
		)
		(layer "In9.Cu")
	)
	(gr_line
		(start 426.277786 -8.45058)
		(end 426.3009 -8.4455)
		(stroke
			(width 0.05715)
			(type default)
		)
		(layer "In9.Cu")
	)
	(gr_line
		(start 426.277786 -7.788402)
		(end 426.3009 -7.783322)
		(stroke
			(width 0.05715)
			(type default)
		)
		(layer "In9.Cu")
	)
	(gr_line
		(start 426.27804 -7.126224)
		(end 426.301154 -7.121144)
		(stroke
			(width 0.05715)
			(type default)
		)
		(layer "In9.Cu")
	)
	(gr_line
		(start 426.293534 -6.467348)
		(end 426.316648 -6.462268)
		(stroke
			(width 0.05715)
			(type default)
		)
		(layer "In9.Cu")
	)
	(gr_line
		(start 426.3009 -8.4455)
		(end 426.324014 -8.45058)
		(stroke
			(width 0.05715)
			(type default)
		)
		(layer "In9.Cu")
	)
	(gr_line
		(start 426.3009 -7.783322)
		(end 426.324014 -7.788402)
		(stroke
			(width 0.05715)
			(type default)
		)
		(layer "In9.Cu")
	)
	(gr_line
		(start 426.301154 -7.121144)
		(end 426.324268 -7.126224)
		(stroke
			(width 0.05715)
			(type default)
		)
		(layer "In9.Cu")
	)
	(gr_line
		(start 426.316648 -6.462268)
		(end 426.339762 -6.467348)
		(stroke
			(width 0.05715)
			(type default)
		)
		(layer "In9.Cu")
	)
	(gr_line
		(start 426.31995 -5.810758)
		(end 426.343064 -5.805678)
		(stroke
			(width 0.05715)
			(type default)
		)
		(layer "In9.Cu")
	)
	(gr_line
		(start 426.336968 -5.152136)
		(end 426.360082 -5.147056)
		(stroke
			(width 0.05715)
			(type default)
		)
		(layer "In9.Cu")
	)
	(gr_line
		(start 426.343064 -5.805678)
		(end 426.366178 -5.810758)
		(stroke
			(width 0.05715)
			(type default)
		)
		(layer "In9.Cu")
	)
	(gr_line
		(start 426.358812 -4.49453)
		(end 426.381926 -4.48945)
		(stroke
			(width 0.05715)
			(type default)
		)
		(layer "In9.Cu")
	)
	(gr_line
		(start 426.360082 -5.147056)
		(end 426.383196 -5.152136)
		(stroke
			(width 0.05715)
			(type default)
		)
		(layer "In9.Cu")
	)
	(gr_line
		(start 426.381926 -4.48945)
		(end 426.40504 -4.49453)
		(stroke
			(width 0.05715)
			(type default)
		)
		(layer "In9.Cu")
	)
	(gr_line
		(start 426.38472 -3.83794)
		(end 426.407834 -3.83286)
		(stroke
			(width 0.05715)
			(type default)
		)
		(layer "In9.Cu")
	)
	(gr_line
		(start 426.407834 -3.83286)
		(end 426.430948 -3.83794)
		(stroke
			(width 0.05715)
			(type default)
		)
		(layer "In9.Cu")
	)
	(gr_line
		(start 426.520864 -13.070586)
		(end 426.542454 -13.066268)
		(stroke
			(width 0.05715)
			(type default)
		)
		(layer "In9.Cu")
	)
	(gr_line
		(start 426.542454 -13.066268)
		(end 426.564044 -13.070586)
		(stroke
			(width 0.05715)
			(type default)
		)
		(layer "In9.Cu")
	)
	(gr_line
		(start 426.768768 -11.88466)
		(end 426.788072 -11.888724)
		(stroke
			(width 0.05715)
			(type default)
		)
		(layer "In9.Cu")
	)
	(gr_line
		(start 426.788072 -11.888724)
		(end 426.804328 -11.899392)
		(stroke
			(width 0.05715)
			(type default)
		)
		(layer "In9.Cu")
	)
	(gr_line
		(start 426.846238 -13.127228)
		(end 426.866304 -13.131292)
		(stroke
			(width 0.05715)
			(type default)
		)
		(layer "In9.Cu")
	)
	(gr_line
		(start 426.866304 -13.131292)
		(end 426.883576 -13.142722)
		(stroke
			(width 0.05715)
			(type default)
		)
		(layer "In9.Cu")
	)
	(gr_line
		(start 427.027594 -12.048236)
		(end 427.046644 -12.060936)
		(stroke
			(width 0.05715)
			(type default)
		)
		(layer "In9.Cu")
	)
	(gr_line
		(start 427.046644 -12.060936)
		(end 427.05909 -12.079732)
		(stroke
			(width 0.05715)
			(type default)
		)
		(layer "In9.Cu")
	)
	(gr_line
		(start 427.151292 -12.748514)
		(end 427.162722 -12.765786)
		(stroke
			(width 0.05715)
			(type default)
		)
		(layer "In9.Cu")
	)
	(gr_line
		(start 427.162722 -12.765786)
		(end 427.179994 -12.777216)
		(stroke
			(width 0.05715)
			(type default)
		)
		(layer "In9.Cu")
	)
	(gr_line
		(start 427.175422 -11.296142)
		(end 427.19498 -11.300206)
		(stroke
			(width 0.05715)
			(type default)
		)
		(layer "In9.Cu")
	)
	(gr_line
		(start 427.19498 -11.300206)
		(end 427.21149 -11.311128)
		(stroke
			(width 0.05715)
			(type default)
		)
		(layer "In9.Cu")
	)
	(gr_line
		(start 427.404784 -13.838428)
		(end 427.421294 -13.84935)
		(stroke
			(width 0.05715)
			(type default)
		)
		(layer "In9.Cu")
	)
	(gr_line
		(start 427.421294 -13.84935)
		(end 427.440598 -13.853414)
		(stroke
			(width 0.05715)
			(type default)
		)
		(layer "In9.Cu")
	)
	(gr_line
		(start 427.439074 -10.683494)
		(end 427.458378 -10.687558)
		(stroke
			(width 0.05715)
			(type default)
		)
		(layer "In9.Cu")
	)
	(gr_line
		(start 427.439328 -11.812524)
		(end 427.455838 -11.823446)
		(stroke
			(width 0.05715)
			(type default)
		)
		(layer "In9.Cu")
	)
	(gr_line
		(start 427.455838 -11.823446)
		(end 427.475142 -11.82751)
		(stroke
			(width 0.05715)
			(type default)
		)
		(layer "In9.Cu")
	)
	(gr_line
		(start 427.458378 -10.687558)
		(end 427.475142 -10.69848)
		(stroke
			(width 0.05715)
			(type default)
		)
		(layer "In9.Cu")
	)
	(gr_line
		(start 427.552358 -15.226538)
		(end 427.5709 -15.230094)
		(stroke
			(width 0.05715)
			(type default)
		)
		(layer "In9.Cu")
	)
	(gr_line
		(start 427.5709 -15.230094)
		(end 427.58868 -15.226538)
		(stroke
			(width 0.05715)
			(type default)
		)
		(layer "In9.Cu")
	)
	(gr_line
		(start 427.574964 -9.014714)
		(end 427.598078 -9.019794)
		(stroke
			(width 0.05715)
			(type default)
		)
		(layer "In9.Cu")
	)
	(gr_line
		(start 427.585886 -7.03072)
		(end 427.609 -7.0358)
		(stroke
			(width 0.05715)
			(type default)
		)
		(layer "In9.Cu")
	)
	(gr_line
		(start 427.589696 -6.36905)
		(end 427.61281 -6.37413)
		(stroke
			(width 0.05715)
			(type default)
		)
		(layer "In9.Cu")
	)
	(gr_line
		(start 427.598078 -9.019794)
		(end 427.621192 -9.014714)
		(stroke
			(width 0.05715)
			(type default)
		)
		(layer "In9.Cu")
	)
	(gr_line
		(start 427.600618 -8.358124)
		(end 427.623732 -8.363204)
		(stroke
			(width 0.05715)
			(type default)
		)
		(layer "In9.Cu")
	)
	(gr_line
		(start 427.606206 -7.697216)
		(end 427.62932 -7.702296)
		(stroke
			(width 0.05715)
			(type default)
		)
		(layer "In9.Cu")
	)
	(gr_line
		(start 427.609 -7.0358)
		(end 427.632114 -7.03072)
		(stroke
			(width 0.05715)
			(type default)
		)
		(layer "In9.Cu")
	)
	(gr_line
		(start 427.612048 -5.711952)
		(end 427.635162 -5.717032)
		(stroke
			(width 0.05715)
			(type default)
		)
		(layer "In9.Cu")
	)
	(gr_line
		(start 427.61281 -6.37413)
		(end 427.635924 -6.36905)
		(stroke
			(width 0.05715)
			(type default)
		)
		(layer "In9.Cu")
	)
	(gr_line
		(start 427.623732 -8.363204)
		(end 427.646846 -8.358124)
		(stroke
			(width 0.05715)
			(type default)
		)
		(layer "In9.Cu")
	)
	(gr_line
		(start 427.62932 -7.702296)
		(end 427.652434 -7.697216)
		(stroke
			(width 0.05715)
			(type default)
		)
		(layer "In9.Cu")
	)
	(gr_line
		(start 427.635162 -5.717032)
		(end 427.658276 -5.711952)
		(stroke
			(width 0.05715)
			(type default)
		)
		(layer "In9.Cu")
	)
	(gr_line
		(start 427.637448 -5.055108)
		(end 427.660562 -5.060188)
		(stroke
			(width 0.05715)
			(type default)
		)
		(layer "In9.Cu")
	)
	(gr_line
		(start 427.641258 -4.393692)
		(end 427.664372 -4.398772)
		(stroke
			(width 0.05715)
			(type default)
		)
		(layer "In9.Cu")
	)
	(gr_line
		(start 427.660562 -5.060188)
		(end 427.683676 -5.055108)
		(stroke
			(width 0.05715)
			(type default)
		)
		(layer "In9.Cu")
	)
	(gr_line
		(start 427.664372 -4.398772)
		(end 427.687486 -4.393692)
		(stroke
			(width 0.05715)
			(type default)
		)
		(layer "In9.Cu")
	)
	(gr_line
		(start 427.71822 -13.133578)
		(end 427.73346 -13.143484)
		(stroke
			(width 0.05715)
			(type default)
		)
		(layer "In9.Cu")
	)
	(gr_line
		(start 427.722538 -11.213084)
		(end 427.739302 -11.224006)
		(stroke
			(width 0.05715)
			(type default)
		)
		(layer "In9.Cu")
	)
	(gr_line
		(start 427.73346 -13.143484)
		(end 427.750732 -13.14704)
		(stroke
			(width 0.05715)
			(type default)
		)
		(layer "In9.Cu")
	)
	(gr_line
		(start 427.739302 -11.224006)
		(end 427.75886 -11.22807)
		(stroke
			(width 0.05715)
			(type default)
		)
		(layer "In9.Cu")
	)
	(gr_line
		(start 428.000922 -15.98168)
		(end 428.019972 -15.98549)
		(stroke
			(width 0.05715)
			(type default)
		)
		(layer "In9.Cu")
	)
	(gr_line
		(start 428.019972 -15.98549)
		(end 428.039022 -15.98168)
		(stroke
			(width 0.05715)
			(type default)
		)
		(layer "In9.Cu")
	)
	(gr_line
		(start 428.148242 -13.228574)
		(end 428.169324 -13.232892)
		(stroke
			(width 0.05715)
			(type default)
		)
		(layer "In9.Cu")
	)
	(gr_line
		(start 428.169324 -13.232892)
		(end 428.190152 -13.228574)
		(stroke
			(width 0.05715)
			(type default)
		)
		(layer "In9.Cu")
	)
	(gr_line
		(start 428.236888 -57.56148)
		(end 428.327058 -57.47131)
		(stroke
			(width 0.050546)
			(type default)
		)
		(layer "In9.Cu")
	)
	(gr_line
		(start 428.419514 -17.968468)
		(end 428.440342 -17.972786)
		(stroke
			(width 0.05715)
			(type default)
		)
		(layer "In9.Cu")
	)
	(gr_line
		(start 428.440342 -17.972786)
		(end 428.460662 -17.968722)
		(stroke
			(width 0.05715)
			(type default)
		)
		(layer "In9.Cu")
	)
	(gr_line
		(start 428.533052 -11.38555)
		(end 428.554388 -11.389868)
		(stroke
			(width 0.05715)
			(type default)
		)
		(layer "In9.Cu")
	)
	(gr_line
		(start 428.53483 -17.28089)
		(end 428.558198 -17.28597)
		(stroke
			(width 0.05715)
			(type default)
		)
		(layer "In9.Cu")
	)
	(gr_line
		(start 428.554388 -11.389868)
		(end 428.575724 -11.38555)
		(stroke
			(width 0.05715)
			(type default)
		)
		(layer "In9.Cu")
	)
	(gr_line
		(start 428.558198 -17.28597)
		(end 428.558452 -17.28597)
		(stroke
			(width 0.05715)
			(type default)
		)
		(layer "In9.Cu")
	)
	(gr_line
		(start 428.558452 -17.28597)
		(end 428.582328 -17.28089)
		(stroke
			(width 0.05715)
			(type default)
		)
		(layer "In9.Cu")
	)
	(gr_line
		(start 428.65167 -14.715744)
		(end 428.67326 -14.711426)
		(stroke
			(width 0.05715)
			(type default)
		)
		(layer "In9.Cu")
	)
	(gr_line
		(start 428.656242 -8.4963)
		(end 428.679356 -8.49122)
		(stroke
			(width 0.05715)
			(type default)
		)
		(layer "In9.Cu")
	)
	(gr_line
		(start 428.66691 -6.512306)
		(end 428.690024 -6.507226)
		(stroke
			(width 0.05715)
			(type default)
		)
		(layer "In9.Cu")
	)
	(gr_line
		(start 428.67072 -5.850636)
		(end 428.693834 -5.845556)
		(stroke
			(width 0.05715)
			(type default)
		)
		(layer "In9.Cu")
	)
	(gr_line
		(start 428.67326 -14.711426)
		(end 428.69485 -14.715744)
		(stroke
			(width 0.05715)
			(type default)
		)
		(layer "In9.Cu")
	)
	(gr_line
		(start 428.679356 -8.49122)
		(end 428.70247 -8.4963)
		(stroke
			(width 0.05715)
			(type default)
		)
		(layer "In9.Cu")
	)
	(gr_line
		(start 428.680372 -12.072366)
		(end 428.701708 -12.076684)
		(stroke
			(width 0.05715)
			(type default)
		)
		(layer "In9.Cu")
	)
	(gr_line
		(start 428.681896 -7.83971)
		(end 428.70501 -7.83463)
		(stroke
			(width 0.05715)
			(type default)
		)
		(layer "In9.Cu")
	)
	(gr_line
		(start 428.687738 -7.178802)
		(end 428.710852 -7.173722)
		(stroke
			(width 0.05715)
			(type default)
		)
		(layer "In9.Cu")
	)
	(gr_line
		(start 428.690024 -6.507226)
		(end 428.713138 -6.512306)
		(stroke
			(width 0.05715)
			(type default)
		)
		(layer "In9.Cu")
	)
	(gr_line
		(start 428.693326 -5.193284)
		(end 428.71644 -5.188204)
		(stroke
			(width 0.05715)
			(type default)
		)
		(layer "In9.Cu")
	)
	(gr_line
		(start 428.693834 -5.845556)
		(end 428.716948 -5.850636)
		(stroke
			(width 0.05715)
			(type default)
		)
		(layer "In9.Cu")
	)
	(gr_line
		(start 428.701708 -12.076684)
		(end 428.723044 -12.072366)
		(stroke
			(width 0.05715)
			(type default)
		)
		(layer "In9.Cu")
	)
	(gr_line
		(start 428.70501 -7.83463)
		(end 428.728124 -7.83971)
		(stroke
			(width 0.05715)
			(type default)
		)
		(layer "In9.Cu")
	)
	(gr_line
		(start 428.710852 -7.173722)
		(end 428.733966 -7.178802)
		(stroke
			(width 0.05715)
			(type default)
		)
		(layer "In9.Cu")
	)
	(gr_line
		(start 428.71644 -5.188204)
		(end 428.739554 -5.193284)
		(stroke
			(width 0.05715)
			(type default)
		)
		(layer "In9.Cu")
	)
	(gr_line
		(start 428.718472 -4.53644)
		(end 428.741586 -4.53136)
		(stroke
			(width 0.05715)
			(type default)
		)
		(layer "In9.Cu")
	)
	(gr_line
		(start 428.722028 -3.875278)
		(end 428.745142 -3.870198)
		(stroke
			(width 0.05715)
			(type default)
		)
		(layer "In9.Cu")
	)
	(gr_line
		(start 428.725076 -13.120116)
		(end 428.743872 -13.116306)
		(stroke
			(width 0.05715)
			(type default)
		)
		(layer "In9.Cu")
	)
	(gr_line
		(start 428.741586 -4.53136)
		(end 428.7647 -4.53644)
		(stroke
			(width 0.05715)
			(type default)
		)
		(layer "In9.Cu")
	)
	(gr_line
		(start 428.743872 -13.116306)
		(end 428.759366 -13.105892)
		(stroke
			(width 0.05715)
			(type default)
		)
		(layer "In9.Cu")
	)
	(gr_line
		(start 428.745142 -3.870198)
		(end 428.768256 -3.875278)
		(stroke
			(width 0.05715)
			(type default)
		)
		(layer "In9.Cu")
	)
	(gr_line
		(start 428.770796 -14.12367)
		(end 428.792132 -14.127988)
		(stroke
			(width 0.05715)
			(type default)
		)
		(layer "In9.Cu")
	)
	(gr_line
		(start 428.792132 -14.127988)
		(end 428.813468 -14.12367)
		(stroke
			(width 0.05715)
			(type default)
		)
		(layer "In9.Cu")
	)
	(gr_line
		(start 429.104044 -15.470124)
		(end 429.125126 -15.465806)
		(stroke
			(width 0.05715)
			(type default)
		)
		(layer "In9.Cu")
	)
	(gr_line
		(start 429.125126 -15.465806)
		(end 429.146716 -15.470124)
		(stroke
			(width 0.05715)
			(type default)
		)
		(layer "In9.Cu")
	)
	(gr_line
		(start 429.331882 -16.822928)
		(end 429.353726 -16.818102)
		(stroke
			(width 0.05715)
			(type default)
		)
		(layer "In9.Cu")
	)
	(gr_line
		(start 429.346614 -17.493488)
		(end 429.368204 -17.48917)
		(stroke
			(width 0.05715)
			(type default)
		)
		(layer "In9.Cu")
	)
	(gr_line
		(start 429.353726 -16.818102)
		(end 429.376332 -16.822674)
		(stroke
			(width 0.05715)
			(type default)
		)
		(layer "In9.Cu")
	)
	(gr_line
		(start 429.357536 -12.359894)
		(end 429.3743 -12.348972)
		(stroke
			(width 0.05715)
			(type default)
		)
		(layer "In9.Cu")
	)
	(gr_line
		(start 429.368204 -17.48917)
		(end 429.389794 -17.493488)
		(stroke
			(width 0.05715)
			(type default)
		)
		(layer "In9.Cu")
	)
	(gr_line
		(start 429.3743 -12.348972)
		(end 429.393858 -12.344908)
		(stroke
			(width 0.05715)
			(type default)
		)
		(layer "In9.Cu")
	)
	(gr_line
		(start 429.662336 -12.290298)
		(end 429.683672 -12.28598)
		(stroke
			(width 0.05715)
			(type default)
		)
		(layer "In9.Cu")
	)
	(gr_line
		(start 429.683672 -12.28598)
		(end 429.705262 -12.290298)
		(stroke
			(width 0.05715)
			(type default)
		)
		(layer "In9.Cu")
	)
	(gr_line
		(start 429.745394 -55.460138)
		(end 429.835564 -55.369968)
		(stroke
			(width 0.050546)
			(type default)
		)
		(layer "In9.Cu")
	)
	(gr_line
		(start 429.770286 -13.630656)
		(end 429.791876 -13.626338)
		(stroke
			(width 0.05715)
			(type default)
		)
		(layer "In9.Cu")
	)
	(gr_line
		(start 429.791876 -13.626338)
		(end 429.813466 -13.630656)
		(stroke
			(width 0.05715)
			(type default)
		)
		(layer "In9.Cu")
	)
	(gr_line
		(start 429.84801 -7.713726)
		(end 429.871124 -7.718806)
		(stroke
			(width 0.05715)
			(type default)
		)
		(layer "In9.Cu")
	)
	(gr_line
		(start 429.85182 -9.038844)
		(end 429.874934 -9.043924)
		(stroke
			(width 0.05715)
			(type default)
		)
		(layer "In9.Cu")
	)
	(gr_line
		(start 429.852328 -6.390386)
		(end 429.875442 -6.395466)
		(stroke
			(width 0.05715)
			(type default)
		)
		(layer "In9.Cu")
	)
	(gr_line
		(start 429.86071 -7.054342)
		(end 429.883824 -7.059422)
		(stroke
			(width 0.05715)
			(type default)
		)
		(layer "In9.Cu")
	)
	(gr_line
		(start 429.869854 -5.731764)
		(end 429.892968 -5.736844)
		(stroke
			(width 0.05715)
			(type default)
		)
		(layer "In9.Cu")
	)
	(gr_line
		(start 429.870362 -4.407662)
		(end 429.893476 -4.412742)
		(stroke
			(width 0.05715)
			(type default)
		)
		(layer "In9.Cu")
	)
	(gr_line
		(start 429.871124 -7.718806)
		(end 429.894238 -7.713726)
		(stroke
			(width 0.05715)
			(type default)
		)
		(layer "In9.Cu")
	)
	(gr_line
		(start 429.874426 -8.381492)
		(end 429.89754 -8.386572)
		(stroke
			(width 0.05715)
			(type default)
		)
		(layer "In9.Cu")
	)
	(gr_line
		(start 429.874934 -9.043924)
		(end 429.898048 -9.038844)
		(stroke
			(width 0.05715)
			(type default)
		)
		(layer "In9.Cu")
	)
	(gr_line
		(start 429.875442 -6.395466)
		(end 429.898556 -6.390386)
		(stroke
			(width 0.05715)
			(type default)
		)
		(layer "In9.Cu")
	)
	(gr_line
		(start 429.883824 -7.059422)
		(end 429.906938 -7.054342)
		(stroke
			(width 0.05715)
			(type default)
		)
		(layer "In9.Cu")
	)
	(gr_line
		(start 429.892968 -5.736844)
		(end 429.916082 -5.731764)
		(stroke
			(width 0.05715)
			(type default)
		)
		(layer "In9.Cu")
	)
	(gr_line
		(start 429.893476 -4.412742)
		(end 429.91659 -4.407662)
		(stroke
			(width 0.05715)
			(type default)
		)
		(layer "In9.Cu")
	)
	(gr_line
		(start 429.895254 -5.075174)
		(end 429.918368 -5.080254)
		(stroke
			(width 0.05715)
			(type default)
		)
		(layer "In9.Cu")
	)
	(gr_line
		(start 429.89754 -8.386572)
		(end 429.920654 -8.381492)
		(stroke
			(width 0.05715)
			(type default)
		)
		(layer "In9.Cu")
	)
	(gr_line
		(start 429.918368 -5.080254)
		(end 429.941482 -5.075174)
		(stroke
			(width 0.05715)
			(type default)
		)
		(layer "In9.Cu")
	)
	(gr_line
		(start 430.5808 -2.874518)
		(end 430.840642 -2.874518)
		(stroke
			(width 0.05715)
			(type default)
		)
		(layer "In9.Cu")
	)
	(gr_line
		(start 430.840642 -2.874518)
		(end 430.955958 -2.759202)
		(stroke
			(width 0.05715)
			(type default)
		)
		(layer "In9.Cu")
	)
	(gr_line
		(start 431.102516 -10.573004)
		(end 431.123852 -10.568686)
		(stroke
			(width 0.05715)
			(type default)
		)
		(layer "In9.Cu")
	)
	(gr_line
		(start 431.123852 -10.568686)
		(end 431.145188 -10.573004)
		(stroke
			(width 0.05715)
			(type default)
		)
		(layer "In9.Cu")
	)
	(gr_line
		(start 431.169572 -11.276584)
		(end 431.190908 -11.272266)
		(stroke
			(width 0.05715)
			(type default)
		)
		(layer "In9.Cu")
	)
	(gr_line
		(start 431.190908 -11.272266)
		(end 431.212244 -11.276584)
		(stroke
			(width 0.05715)
			(type default)
		)
		(layer "In9.Cu")
	)
	(gr_line
		(start 431.279808 -17.507966)
		(end 431.301144 -17.512284)
		(stroke
			(width 0.05715)
			(type default)
		)
		(layer "In9.Cu")
	)
	(gr_line
		(start 431.294794 -8.443468)
		(end 431.330862 -8.435848)
		(stroke
			(width 0.05715)
			(type default)
		)
		(layer "In9.Cu")
	)
	(gr_line
		(start 431.301144 -17.512284)
		(end 431.322226 -17.507966)
		(stroke
			(width 0.05715)
			(type default)
		)
		(layer "In9.Cu")
	)
	(gr_line
		(start 431.330862 -8.435848)
		(end 431.366168 -8.446008)
		(stroke
			(width 0.05715)
			(type default)
		)
		(layer "In9.Cu")
	)
	(gr_line
		(start 431.338736 -7.78129)
		(end 431.374804 -7.77367)
		(stroke
			(width 0.05715)
			(type default)
		)
		(layer "In9.Cu")
	)
	(gr_line
		(start 431.34153 -7.107428)
		(end 431.377598 -7.099808)
		(stroke
			(width 0.05715)
			(type default)
		)
		(layer "In9.Cu")
	)
	(gr_line
		(start 431.372518 -2.759202)
		(end 431.487834 -2.874518)
		(stroke
			(width 0.05715)
			(type default)
		)
		(layer "In9.Cu")
	)
	(gr_line
		(start 431.374804 -7.77367)
		(end 431.409856 -7.78383)
		(stroke
			(width 0.05715)
			(type default)
		)
		(layer "In9.Cu")
	)
	(gr_line
		(start 431.37709 -6.443472)
		(end 431.413158 -6.435852)
		(stroke
			(width 0.05715)
			(type default)
		)
		(layer "In9.Cu")
	)
	(gr_line
		(start 431.377598 -7.099808)
		(end 431.41265 -7.109968)
		(stroke
			(width 0.05715)
			(type default)
		)
		(layer "In9.Cu")
	)
	(gr_line
		(start 431.395124 -5.773928)
		(end 431.431192 -5.766308)
		(stroke
			(width 0.05715)
			(type default)
		)
		(layer "In9.Cu")
	)
	(gr_line
		(start 431.413158 -6.435852)
		(end 431.44821 -6.446012)
		(stroke
			(width 0.05715)
			(type default)
		)
		(layer "In9.Cu")
	)
	(gr_line
		(start 431.431192 -5.766308)
		(end 431.466498 -5.776468)
		(stroke
			(width 0.05715)
			(type default)
		)
		(layer "In9.Cu")
	)
	(gr_line
		(start 431.433732 -5.11048)
		(end 431.4698 -5.10286)
		(stroke
			(width 0.05715)
			(type default)
		)
		(layer "In9.Cu")
	)
	(gr_line
		(start 431.4698 -5.10286)
		(end 431.504344 -5.11302)
		(stroke
			(width 0.05715)
			(type default)
		)
		(layer "In9.Cu")
	)
	(gr_line
		(start 431.480214 -4.449318)
		(end 431.516282 -4.441698)
		(stroke
			(width 0.05715)
			(type default)
		)
		(layer "In9.Cu")
	)
	(gr_line
		(start 431.484024 -3.775456)
		(end 431.519838 -3.767836)
		(stroke
			(width 0.05715)
			(type default)
		)
		(layer "In9.Cu")
	)
	(gr_line
		(start 431.487834 -2.874518)
		(end 431.8508 -2.874518)
		(stroke
			(width 0.05715)
			(type default)
		)
		(layer "In9.Cu")
	)
	(gr_line
		(start 431.516282 -4.441698)
		(end 431.551588 -4.451858)
		(stroke
			(width 0.05715)
			(type default)
		)
		(layer "In9.Cu")
	)
	(gr_line
		(start 431.519838 -3.767836)
		(end 431.555144 -3.777996)
		(stroke
			(width 0.05715)
			(type default)
		)
		(layer "In9.Cu")
	)
	(gr_line
		(start 431.526696 -18.226278)
		(end 431.548032 -18.230596)
		(stroke
			(width 0.05715)
			(type default)
		)
		(layer "In9.Cu")
	)
	(gr_line
		(start 431.548032 -18.230596)
		(end 431.569368 -18.226278)
		(stroke
			(width 0.05715)
			(type default)
		)
		(layer "In9.Cu")
	)
	(gr_line
		(start 431.615342 -10.078466)
		(end 431.754534 -10.078466)
		(stroke
			(width 0.05715)
			(type default)
		)
		(layer "In9.Cu")
	)
	(gr_line
		(start 431.754534 -10.078466)
		(end 431.87112 -9.96188)
		(stroke
			(width 0.05715)
			(type default)
		)
		(layer "In9.Cu")
	)
	(gr_line
		(start 431.94732 -8.615934)
		(end 431.98288 -8.626348)
		(stroke
			(width 0.05715)
			(type default)
		)
		(layer "In9.Cu")
	)
	(gr_line
		(start 431.988214 -17.842738)
		(end 432.009804 -17.83842)
		(stroke
			(width 0.05715)
			(type default)
		)
		(layer "In9.Cu")
	)
	(gr_line
		(start 432.009804 -17.83842)
		(end 432.031394 -17.842738)
		(stroke
			(width 0.05715)
			(type default)
		)
		(layer "In9.Cu")
	)
	(gr_line
		(start 432.278536 -11.491468)
		(end 432.298348 -11.495532)
		(stroke
			(width 0.05715)
			(type default)
		)
		(layer "In9.Cu")
	)
	(gr_line
		(start 432.28768 -9.96188)
		(end 432.404266 -10.078466)
		(stroke
			(width 0.05715)
			(type default)
		)
		(layer "In9.Cu")
	)
	(gr_line
		(start 432.298348 -11.495532)
		(end 432.314604 -11.5062)
		(stroke
			(width 0.05715)
			(type default)
		)
		(layer "In9.Cu")
	)
	(gr_line
		(start 432.386486 -8.373618)
		(end 432.421792 -8.384032)
		(stroke
			(width 0.05715)
			(type default)
		)
		(layer "In9.Cu")
	)
	(gr_line
		(start 432.402742 -16.13281)
		(end 432.4223 -16.136874)
		(stroke
			(width 0.05715)
			(type default)
		)
		(layer "In9.Cu")
	)
	(gr_line
		(start 432.404266 -10.078466)
		(end 432.580542 -10.078466)
		(stroke
			(width 0.05715)
			(type default)
		)
		(layer "In9.Cu")
	)
	(gr_line
		(start 432.410616 -7.031736)
		(end 432.445668 -7.041896)
		(stroke
			(width 0.05715)
			(type default)
		)
		(layer "In9.Cu")
	)
	(gr_line
		(start 432.41087 -7.706106)
		(end 432.446176 -7.716266)
		(stroke
			(width 0.05715)
			(type default)
		)
		(layer "In9.Cu")
	)
	(gr_line
		(start 432.421792 -8.384032)
		(end 432.457606 -8.376412)
		(stroke
			(width 0.05715)
			(type default)
		)
		(layer "In9.Cu")
	)
	(gr_line
		(start 432.4223 -16.136874)
		(end 432.439064 -16.147796)
		(stroke
			(width 0.05715)
			(type default)
		)
		(layer "In9.Cu")
	)
	(gr_line
		(start 432.441858 -6.366002)
		(end 432.477164 -6.376162)
		(stroke
			(width 0.05715)
			(type default)
		)
		(layer "In9.Cu")
	)
	(gr_line
		(start 432.445668 -7.041896)
		(end 432.481736 -7.034276)
		(stroke
			(width 0.05715)
			(type default)
		)
		(layer "In9.Cu")
	)
	(gr_line
		(start 432.446176 -7.716266)
		(end 432.48199 -7.708646)
		(stroke
			(width 0.05715)
			(type default)
		)
		(layer "In9.Cu")
	)
	(gr_line
		(start 432.47691 -16.974312)
		(end 432.497992 -16.969994)
		(stroke
			(width 0.05715)
			(type default)
		)
		(layer "In9.Cu")
	)
	(gr_line
		(start 432.477164 -6.376162)
		(end 432.512978 -6.368542)
		(stroke
			(width 0.05715)
			(type default)
		)
		(layer "In9.Cu")
	)
	(gr_line
		(start 432.491642 -5.705348)
		(end 432.526186 -5.715508)
		(stroke
			(width 0.05715)
			(type default)
		)
		(layer "In9.Cu")
	)
	(gr_line
		(start 432.495706 -16.536162)
		(end 432.51247 -16.547084)
		(stroke
			(width 0.05715)
			(type default)
		)
		(layer "In9.Cu")
	)
	(gr_line
		(start 432.497992 -16.969994)
		(end 432.519328 -16.974312)
		(stroke
			(width 0.05715)
			(type default)
		)
		(layer "In9.Cu")
	)
	(gr_line
		(start 432.51247 -16.547084)
		(end 432.532028 -16.551148)
		(stroke
			(width 0.05715)
			(type default)
		)
		(layer "In9.Cu")
	)
	(gr_line
		(start 432.515518 -5.037836)
		(end 432.550824 -5.047996)
		(stroke
			(width 0.05715)
			(type default)
		)
		(layer "In9.Cu")
	)
	(gr_line
		(start 432.526186 -5.715508)
		(end 432.562 -5.707888)
		(stroke
			(width 0.05715)
			(type default)
		)
		(layer "In9.Cu")
	)
	(gr_line
		(start 432.54041 -4.370324)
		(end 432.575716 -4.380484)
		(stroke
			(width 0.05715)
			(type default)
		)
		(layer "In9.Cu")
	)
	(gr_line
		(start 432.550824 -5.047996)
		(end 432.586638 -5.040376)
		(stroke
			(width 0.05715)
			(type default)
		)
		(layer "In9.Cu")
	)
	(gr_line
		(start 432.575716 -4.380484)
		(end 432.61153 -4.372864)
		(stroke
			(width 0.05715)
			(type default)
		)
		(layer "In9.Cu")
	)
	(gr_line
		(start 432.649122 -12.077192)
		(end 432.664616 -12.087606)
		(stroke
			(width 0.05715)
			(type default)
		)
		(layer "In9.Cu")
	)
	(gr_line
		(start 432.658266 -15.81658)
		(end 433.24653 -15.935706)
		(stroke
			(width 0.05715)
			(type default)
		)
		(layer "In9.Cu")
	)
	(gr_line
		(start 432.664616 -12.087606)
		(end 432.683412 -12.091416)
		(stroke
			(width 0.05715)
			(type default)
		)
		(layer "In9.Cu")
	)
	(gr_line
		(start 432.683158 -15.520924)
		(end 432.875182 -15.39367)
		(stroke
			(width 0.05715)
			(type default)
		)
		(layer "In9.Cu")
	)
	(gr_line
		(start 432.693064 -8.02767)
		(end 432.73853 -8.018018)
		(stroke
			(width 0.05715)
			(type default)
		)
		(layer "In9.Cu")
	)
	(gr_line
		(start 432.73853 -8.018018)
		(end 432.782218 -8.033766)
		(stroke
			(width 0.05715)
			(type default)
		)
		(layer "In9.Cu")
	)
	(gr_line
		(start 432.875182 -15.39367)
		(end 433.211224 -15.461742)
		(stroke
			(width 0.05715)
			(type default)
		)
		(layer "In9.Cu")
	)
	(gr_line
		(start 433.011834 -2.860294)
		(end 433.36845 -2.860294)
		(stroke
			(width 0.05715)
			(type default)
		)
		(layer "In9.Cu")
	)
	(gr_line
		(start 433.211224 -15.461742)
		(end 433.338478 -15.653766)
		(stroke
			(width 0.05715)
			(type default)
		)
		(layer "In9.Cu")
	)
	(gr_line
		(start 433.243736 -11.297666)
		(end 433.263802 -11.30173)
		(stroke
			(width 0.05715)
			(type default)
		)
		(layer "In9.Cu")
	)
	(gr_line
		(start 433.30622 -11.310874)
		(end 433.312316 -11.314938)
		(stroke
			(width 0.05715)
			(type default)
		)
		(layer "In9.Cu")
	)
	(gr_line
		(start 433.312316 -11.314938)
		(end 433.33543 -11.309858)
		(stroke
			(width 0.05715)
			(type default)
		)
		(layer "In9.Cu")
	)
	(gr_line
		(start 433.312316 -11.016234)
		(end 433.312316 -11.01598)
		(stroke
			(width 0.05715)
			(type default)
		)
		(layer "In9.Cu")
	)
	(gr_line
		(start 433.312316 -11.016234)
		(end 433.31257 -11.016234)
		(stroke
			(width 0.05715)
			(type default)
		)
		(layer "In9.Cu")
	)
	(gr_line
		(start 433.34305 -7.2263)
		(end 433.399184 -7.214362)
		(stroke
			(width 0.05715)
			(type default)
		)
		(layer "In9.Cu")
	)
	(gr_line
		(start 433.36845 -2.860294)
		(end 433.432712 -2.796032)
		(stroke
			(width 0.05715)
			(type default)
		)
		(layer "In9.Cu")
	)
	(gr_line
		(start 433.399184 -7.214362)
		(end 433.451762 -7.237476)
		(stroke
			(width 0.05715)
			(type default)
		)
		(layer "In9.Cu")
	)
	(gr_line
		(start 433.399692 -6.540246)
		(end 433.45608 -6.528308)
		(stroke
			(width 0.05715)
			(type default)
		)
		(layer "In9.Cu")
	)
	(gr_line
		(start 433.452778 -5.869432)
		(end 433.509166 -5.857494)
		(stroke
			(width 0.05715)
			(type default)
		)
		(layer "In9.Cu")
	)
	(gr_line
		(start 433.45608 -6.528308)
		(end 433.508912 -6.551422)
		(stroke
			(width 0.05715)
			(type default)
		)
		(layer "In9.Cu")
	)
	(gr_line
		(start 433.509166 -5.857494)
		(end 433.561744 -5.880608)
		(stroke
			(width 0.05715)
			(type default)
		)
		(layer "In9.Cu")
	)
	(gr_line
		(start 433.520088 -5.204968)
		(end 433.576476 -5.19303)
		(stroke
			(width 0.05715)
			(type default)
		)
		(layer "In9.Cu")
	)
	(gr_line
		(start 433.568856 -4.532376)
		(end 433.625244 -4.520438)
		(stroke
			(width 0.05715)
			(type default)
		)
		(layer "In9.Cu")
	)
	(gr_line
		(start 433.576476 -5.19303)
		(end 433.629054 -5.216144)
		(stroke
			(width 0.05715)
			(type default)
		)
		(layer "In9.Cu")
	)
	(gr_line
		(start 433.617878 -3.859784)
		(end 433.674012 -3.847846)
		(stroke
			(width 0.05715)
			(type default)
		)
		(layer "In9.Cu")
	)
	(gr_line
		(start 433.625244 -4.520438)
		(end 433.67706 -4.543298)
		(stroke
			(width 0.05715)
			(type default)
		)
		(layer "In9.Cu")
	)
	(gr_line
		(start 433.653946 -16.018256)
		(end 434.24221 -16.137382)
		(stroke
			(width 0.05715)
			(type default)
		)
		(layer "In9.Cu")
	)
	(gr_line
		(start 433.674012 -3.847846)
		(end 433.726844 -3.87096)
		(stroke
			(width 0.05715)
			(type default)
		)
		(layer "In9.Cu")
	)
	(gr_line
		(start 433.679092 -15.7226)
		(end 433.870862 -15.595346)
		(stroke
			(width 0.05715)
			(type default)
		)
		(layer "In9.Cu")
	)
	(gr_line
		(start 433.849272 -2.796032)
		(end 433.913534 -2.860294)
		(stroke
			(width 0.05715)
			(type default)
		)
		(layer "In9.Cu")
	)
	(gr_line
		(start 433.870862 -15.595346)
		(end 434.206904 -15.663418)
		(stroke
			(width 0.05715)
			(type default)
		)
		(layer "In9.Cu")
	)
	(gr_line
		(start 433.913534 -2.860294)
		(end 434.281834 -2.860294)
		(stroke
			(width 0.05715)
			(type default)
		)
		(layer "In9.Cu")
	)
	(gr_line
		(start 433.961032 -9.9949)
		(end 434.124354 -9.9949)
		(stroke
			(width 0.05715)
			(type default)
		)
		(layer "In9.Cu")
	)
	(gr_line
		(start 434.082698 -8.504936)
		(end 434.133752 -8.523478)
		(stroke
			(width 0.05715)
			(type default)
		)
		(layer "In9.Cu")
	)
	(gr_line
		(start 434.124354 -9.9949)
		(end 434.29936 -9.819386)
		(stroke
			(width 0.05715)
			(type default)
		)
		(layer "In9.Cu")
	)
	(gr_line
		(start 434.133752 -8.523478)
		(end 434.16474 -8.567674)
		(stroke
			(width 0.05715)
			(type default)
		)
		(layer "In9.Cu")
	)
	(gr_line
		(start 434.181504 -18.273522)
		(end 434.263546 -18.290032)
		(stroke
			(width 0.05715)
			(type default)
		)
		(layer "In9.Cu")
	)
	(gr_line
		(start 434.206904 -15.663418)
		(end 434.334158 -15.855188)
		(stroke
			(width 0.05715)
			(type default)
		)
		(layer "In9.Cu")
	)
	(gr_line
		(start 434.263546 -18.290032)
		(end 434.310028 -18.359374)
		(stroke
			(width 0.05715)
			(type default)
		)
		(layer "In9.Cu")
	)
	(gr_line
		(start 434.440584 -19.080226)
		(end 434.481224 -19.140678)
		(stroke
			(width 0.05715)
			(type default)
		)
		(layer "In9.Cu")
	)
	(gr_line
		(start 434.473858 -17.371822)
		(end 434.5686 -17.391126)
		(stroke
			(width 0.05715)
			(type default)
		)
		(layer "In9.Cu")
	)
	(gr_line
		(start 434.481224 -19.140678)
		(end 434.551328 -19.159474)
		(stroke
			(width 0.05715)
			(type default)
		)
		(layer "In9.Cu")
	)
	(gr_line
		(start 434.563266 -9.136126)
		(end 434.594 -9.180068)
		(stroke
			(width 0.05715)
			(type default)
		)
		(layer "In9.Cu")
	)
	(gr_line
		(start 434.5686 -17.391126)
		(end 434.616098 -17.475708)
		(stroke
			(width 0.05715)
			(type default)
		)
		(layer "In9.Cu")
	)
	(gr_line
		(start 434.594 -9.8552)
		(end 434.7337 -9.9949)
		(stroke
			(width 0.05715)
			(type default)
		)
		(layer "In9.Cu")
	)
	(gr_line
		(start 434.649372 -16.219932)
		(end 435.236874 -16.33855)
		(stroke
			(width 0.05715)
			(type default)
		)
		(layer "In9.Cu")
	)
	(gr_line
		(start 434.674772 -15.924276)
		(end 434.866542 -15.797022)
		(stroke
			(width 0.05715)
			(type default)
		)
		(layer "In9.Cu")
	)
	(gr_line
		(start 434.7337 -9.9949)
		(end 434.926232 -9.9949)
		(stroke
			(width 0.05715)
			(type default)
		)
		(layer "In9.Cu")
	)
	(gr_line
		(start 434.817012 -18.427446)
		(end 434.861462 -18.506186)
		(stroke
			(width 0.05715)
			(type default)
		)
		(layer "In9.Cu")
	)
	(gr_line
		(start 434.861462 -18.506186)
		(end 434.949346 -18.52676)
		(stroke
			(width 0.05715)
			(type default)
		)
		(layer "In9.Cu")
	)
	(gr_line
		(start 434.866542 -15.797022)
		(end 435.202584 -15.865094)
		(stroke
			(width 0.05715)
			(type default)
		)
		(layer "In9.Cu")
	)
	(gr_line
		(start 434.938932 -0.968248)
		(end 435.101492 -1.130808)
		(stroke
			(width 0.05715)
			(type default)
		)
		(layer "In9.Cu")
	)
	(gr_line
		(start 435.101492 -1.130808)
		(end 435.444392 -1.130808)
		(stroke
			(width 0.05715)
			(type default)
		)
		(layer "In9.Cu")
	)
	(gr_line
		(start 435.202584 -15.865094)
		(end 435.329838 -16.056864)
		(stroke
			(width 0.05715)
			(type default)
		)
		(layer "In9.Cu")
	)
	(gr_line
		(start 435.231032 -0.673608)
		(end 435.314852 -0.673608)
		(stroke
			(width 0.05715)
			(type default)
		)
		(layer "In9.Cu")
	)
	(gr_line
		(start 435.298342 -10.594594)
		(end 435.321456 -10.589514)
		(stroke
			(width 0.05715)
			(type default)
		)
		(layer "In9.Cu")
	)
	(gr_line
		(start 435.321456 -10.589514)
		(end 435.34457 -10.594594)
		(stroke
			(width 0.05715)
			(type default)
		)
		(layer "In9.Cu")
	)
	(gr_line
		(start 435.431438 -2.83972)
		(end 435.757066 -2.83972)
		(stroke
			(width 0.05715)
			(type default)
		)
		(layer "In9.Cu")
	)
	(gr_line
		(start 435.444392 -1.130808)
		(end 435.606952 -0.968248)
		(stroke
			(width 0.05715)
			(type default)
		)
		(layer "In9.Cu")
	)
	(gr_line
		(start 435.623716 -18.68424)
		(end 435.648354 -18.690082)
		(stroke
			(width 0.05715)
			(type default)
		)
		(layer "In9.Cu")
	)
	(gr_line
		(start 435.646576 -16.421608)
		(end 435.667912 -16.425926)
		(stroke
			(width 0.05715)
			(type default)
		)
		(layer "In9.Cu")
	)
	(gr_line
		(start 435.648354 -18.690082)
		(end 435.672738 -18.685002)
		(stroke
			(width 0.05715)
			(type default)
		)
		(layer "In9.Cu")
	)
	(gr_line
		(start 435.667912 -16.425926)
		(end 435.689248 -16.421608)
		(stroke
			(width 0.05715)
			(type default)
		)
		(layer "In9.Cu")
	)
	(gr_line
		(start 435.67223 -13.495528)
		(end 435.690772 -13.499084)
		(stroke
			(width 0.05715)
			(type default)
		)
		(layer "In9.Cu")
	)
	(gr_line
		(start 435.690772 -13.499084)
		(end 435.70652 -13.509752)
		(stroke
			(width 0.05715)
			(type default)
		)
		(layer "In9.Cu")
	)
	(gr_line
		(start 435.757066 -2.83972)
		(end 435.82082 -2.775966)
		(stroke
			(width 0.05715)
			(type default)
		)
		(layer "In9.Cu")
	)
	(gr_line
		(start 435.9021 -2.10439)
		(end 435.943248 -2.05359)
		(stroke
			(width 0.05715)
			(type default)
		)
		(layer "In9.Cu")
	)
	(gr_line
		(start 436.088028 -17.274794)
		(end 436.109364 -17.279112)
		(stroke
			(width 0.05715)
			(type default)
		)
		(layer "In9.Cu")
	)
	(gr_line
		(start 436.09006 -8.396986)
		(end 436.107078 -8.404606)
		(stroke
			(width 0.05715)
			(type default)
		)
		(layer "In9.Cu")
	)
	(gr_line
		(start 436.107078 -8.404606)
		(end 436.120286 -8.417814)
		(stroke
			(width 0.05715)
			(type default)
		)
		(layer "In9.Cu")
	)
	(gr_line
		(start 436.109364 -17.279112)
		(end 436.1307 -17.274794)
		(stroke
			(width 0.05715)
			(type default)
		)
		(layer "In9.Cu")
	)
	(gr_line
		(start 436.234332 -14.212316)
		(end 436.252112 -14.224)
		(stroke
			(width 0.05715)
			(type default)
		)
		(layer "In9.Cu")
	)
	(gr_line
		(start 436.23738 -2.775966)
		(end 436.301134 -2.83972)
		(stroke
			(width 0.05715)
			(type default)
		)
		(layer "In9.Cu")
	)
	(gr_line
		(start 436.252112 -14.224)
		(end 436.272178 -14.22781)
		(stroke
			(width 0.05715)
			(type default)
		)
		(layer "In9.Cu")
	)
	(gr_line
		(start 436.290212 -18.263362)
		(end 436.309262 -18.259552)
		(stroke
			(width 0.05715)
			(type default)
		)
		(layer "In9.Cu")
	)
	(gr_line
		(start 436.301134 -2.83972)
		(end 436.701438 -2.83972)
		(stroke
			(width 0.05715)
			(type default)
		)
		(layer "In9.Cu")
	)
	(gr_line
		(start 436.309262 -18.259552)
		(end 436.328312 -18.263362)
		(stroke
			(width 0.05715)
			(type default)
		)
		(layer "In9.Cu")
	)
	(gr_line
		(start 436.328566 -1.57861)
		(end 436.369968 -1.527556)
		(stroke
			(width 0.05715)
			(type default)
		)
		(layer "In9.Cu")
	)
	(gr_line
		(start 436.33136 -61.235336)
		(end 436.634128 -61.538104)
		(stroke
			(width 0.050546)
			(type default)
		)
		(layer "In9.Cu")
	)
	(gr_line
		(start 436.361332 -10.12952)
		(end 436.555134 -10.12952)
		(stroke
			(width 0.05715)
			(type default)
		)
		(layer "In9.Cu")
	)
	(gr_line
		(start 436.369968 -1.527556)
		(end 436.434484 -1.51384)
		(stroke
			(width 0.05715)
			(type default)
		)
		(layer "In9.Cu")
	)
	(gr_line
		(start 436.459884 -12.860528)
		(end 436.48122 -12.864846)
		(stroke
			(width 0.05715)
			(type default)
		)
		(layer "In9.Cu")
	)
	(gr_line
		(start 436.48122 -12.864846)
		(end 436.502556 -12.860528)
		(stroke
			(width 0.05715)
			(type default)
		)
		(layer "In9.Cu")
	)
	(gr_line
		(start 436.555134 -10.12952)
		(end 436.64632 -10.038334)
		(stroke
			(width 0.05715)
			(type default)
		)
		(layer "In9.Cu")
	)
	(gr_line
		(start 436.634128 -61.538104)
		(end 436.938166 -61.538104)
		(stroke
			(width 0.050546)
			(type default)
		)
		(layer "In9.Cu")
	)
	(gr_line
		(start 436.750714 -60.813442)
		(end 436.82158 -60.813442)
		(stroke
			(width 0.050546)
			(type default)
		)
		(layer "In9.Cu")
	)
	(gr_line
		(start 436.938166 -61.538104)
		(end 437.240934 -61.235336)
		(stroke
			(width 0.050546)
			(type default)
		)
		(layer "In9.Cu")
	)
	(gr_line
		(start 436.984902 -14.370304)
		(end 437.003952 -14.374114)
		(stroke
			(width 0.05715)
			(type default)
		)
		(layer "In9.Cu")
	)
	(gr_line
		(start 437.003952 -14.374114)
		(end 437.023002 -14.370304)
		(stroke
			(width 0.05715)
			(type default)
		)
		(layer "In9.Cu")
	)
	(gr_line
		(start 437.06288 -10.038334)
		(end 437.154066 -10.12952)
		(stroke
			(width 0.05715)
			(type default)
		)
		(layer "In9.Cu")
	)
	(gr_line
		(start 437.154066 -10.12952)
		(end 437.326532 -10.12952)
		(stroke
			(width 0.05715)
			(type default)
		)
		(layer "In9.Cu")
	)
	(gr_line
		(start 437.178704 -18.731738)
		(end 437.197754 -18.735548)
		(stroke
			(width 0.05715)
			(type default)
		)
		(layer "In9.Cu")
	)
	(gr_line
		(start 437.197754 -18.735548)
		(end 437.216804 -18.731738)
		(stroke
			(width 0.05715)
			(type default)
		)
		(layer "In9.Cu")
	)
	(gr_line
		(start 437.231282 -15.809468)
		(end 437.252618 -15.80515)
		(stroke
			(width 0.05715)
			(type default)
		)
		(layer "In9.Cu")
	)
	(gr_line
		(start 437.252618 -15.80515)
		(end 437.273954 -15.809468)
		(stroke
			(width 0.05715)
			(type default)
		)
		(layer "In9.Cu")
	)
	(gr_line
		(start 437.814212 -2.890774)
		(end 438.205626 -2.890774)
		(stroke
			(width 0.05715)
			(type default)
		)
		(layer "In9.Cu")
	)
	(gr_line
		(start 438.198768 -12.219432)
		(end 438.220104 -12.215114)
		(stroke
			(width 0.05715)
			(type default)
		)
		(layer "In9.Cu")
	)
	(gr_line
		(start 438.205626 -2.890774)
		(end 438.24652 -2.84988)
		(stroke
			(width 0.05715)
			(type default)
		)
		(layer "In9.Cu")
	)
	(gr_line
		(start 438.220104 -12.215114)
		(end 438.241694 -12.219432)
		(stroke
			(width 0.05715)
			(type default)
		)
		(layer "In9.Cu")
	)
	(gr_line
		(start 438.442608 -16.777716)
		(end 438.461404 -16.78178)
		(stroke
			(width 0.05715)
			(type default)
		)
		(layer "In9.Cu")
	)
	(gr_line
		(start 438.461404 -16.78178)
		(end 438.477406 -16.792448)
		(stroke
			(width 0.05715)
			(type default)
		)
		(layer "In9.Cu")
	)
	(gr_line
		(start 438.549796 -11.574018)
		(end 438.57291 -11.579098)
		(stroke
			(width 0.05715)
			(type default)
		)
		(layer "In9.Cu")
	)
	(gr_line
		(start 438.57291 -11.579098)
		(end 438.596024 -11.574018)
		(stroke
			(width 0.05715)
			(type default)
		)
		(layer "In9.Cu")
	)
	(gr_line
		(start 438.66308 -2.84988)
		(end 438.703974 -2.890774)
		(stroke
			(width 0.05715)
			(type default)
		)
		(layer "In9.Cu")
	)
	(gr_line
		(start 438.703974 -2.890774)
		(end 439.084212 -2.890774)
		(stroke
			(width 0.05715)
			(type default)
		)
		(layer "In9.Cu")
	)
	(gr_line
		(start 438.755282 -10.02411)
		(end 438.96915 -10.02411)
		(stroke
			(width 0.05715)
			(type default)
		)
		(layer "In9.Cu")
	)
	(gr_line
		(start 438.762648 -17.33423)
		(end 438.772046 -17.340326)
		(stroke
			(width 0.05715)
			(type default)
		)
		(layer "In9.Cu")
	)
	(gr_line
		(start 438.772046 -17.340326)
		(end 438.78246 -17.34312)
		(stroke
			(width 0.05715)
			(type default)
		)
		(layer "In9.Cu")
	)
	(gr_line
		(start 438.823862 -8.88746)
		(end 438.84088 -8.89508)
		(stroke
			(width 0.05715)
			(type default)
		)
		(layer "In9.Cu")
	)
	(gr_line
		(start 438.84088 -8.89508)
		(end 438.854088 -8.908288)
		(stroke
			(width 0.05715)
			(type default)
		)
		(layer "In9.Cu")
	)
	(gr_line
		(start 438.858152 -18.105628)
		(end 438.879742 -18.10131)
		(stroke
			(width 0.05715)
			(type default)
		)
		(layer "In9.Cu")
	)
	(gr_line
		(start 438.879742 -18.10131)
		(end 438.879996 -18.10131)
		(stroke
			(width 0.05715)
			(type default)
		)
		(layer "In9.Cu")
	)
	(gr_line
		(start 438.879996 -18.10131)
		(end 438.901586 -18.105628)
		(stroke
			(width 0.05715)
			(type default)
		)
		(layer "In9.Cu")
	)
	(gr_line
		(start 438.96915 -10.02411)
		(end 439.06821 -9.92505)
		(stroke
			(width 0.05715)
			(type default)
		)
		(layer "In9.Cu")
	)
	(gr_line
		(start 439.170064 -16.19123)
		(end 439.189114 -16.19504)
		(stroke
			(width 0.05715)
			(type default)
		)
		(layer "In9.Cu")
	)
	(gr_line
		(start 439.189114 -16.19504)
		(end 439.20537 -16.205708)
		(stroke
			(width 0.05715)
			(type default)
		)
		(layer "In9.Cu")
	)
	(gr_line
		(start 439.230262 -13.63091)
		(end 439.253122 -13.626338)
		(stroke
			(width 0.05715)
			(type default)
		)
		(layer "In9.Cu")
	)
	(gr_line
		(start 439.253122 -13.626338)
		(end 439.275982 -13.631164)
		(stroke
			(width 0.05715)
			(type default)
		)
		(layer "In9.Cu")
	)
	(gr_line
		(start 439.316622 -9.370822)
		(end 439.37555 -9.42975)
		(stroke
			(width 0.05715)
			(type default)
		)
		(layer "In9.Cu")
	)
	(gr_line
		(start 439.31713 -12.7381)
		(end 439.399426 -12.754864)
		(stroke
			(width 0.05715)
			(type default)
		)
		(layer "In9.Cu")
	)
	(gr_line
		(start 439.399426 -15.548864)
		(end 439.420762 -15.553182)
		(stroke
			(width 0.05715)
			(type default)
		)
		(layer "In9.Cu")
	)
	(gr_line
		(start 439.399426 -12.754864)
		(end 439.469784 -12.708382)
		(stroke
			(width 0.05715)
			(type default)
		)
		(layer "In9.Cu")
	)
	(gr_line
		(start 439.420762 -15.553182)
		(end 439.43905 -15.565374)
		(stroke
			(width 0.05715)
			(type default)
		)
		(layer "In9.Cu")
	)
	(gr_line
		(start 439.48477 -9.92505)
		(end 439.58383 -10.02411)
		(stroke
			(width 0.05715)
			(type default)
		)
		(layer "In9.Cu")
	)
	(gr_line
		(start 439.521346 -12.121896)
		(end 439.538364 -12.039092)
		(stroke
			(width 0.05715)
			(type default)
		)
		(layer "In9.Cu")
	)
	(gr_line
		(start 439.538364 -12.039092)
		(end 439.608214 -11.993118)
		(stroke
			(width 0.05715)
			(type default)
		)
		(layer "In9.Cu")
	)
	(gr_line
		(start 439.58383 -10.02411)
		(end 439.720482 -10.02411)
		(stroke
			(width 0.05715)
			(type default)
		)
		(layer "In9.Cu")
	)
	(gr_line
		(start 439.592974 -8.156956)
		(end 439.614056 -8.1661)
		(stroke
			(width 0.05715)
			(type default)
		)
		(layer "In9.Cu")
	)
	(gr_line
		(start 439.593736 -6.769862)
		(end 439.614818 -6.779006)
		(stroke
			(width 0.05715)
			(type default)
		)
		(layer "In9.Cu")
	)
	(gr_line
		(start 439.598562 -8.85317)
		(end 439.619644 -8.862314)
		(stroke
			(width 0.05715)
			(type default)
		)
		(layer "In9.Cu")
	)
	(gr_line
		(start 439.660538 -16.86052)
		(end 439.673492 -16.869156)
		(stroke
			(width 0.05715)
			(type default)
		)
		(layer "In9.Cu")
	)
	(gr_line
		(start 439.664856 -12.579604)
		(end 439.735722 -12.532614)
		(stroke
			(width 0.05715)
			(type default)
		)
		(layer "In9.Cu")
	)
	(gr_line
		(start 439.673492 -16.869156)
		(end 439.688224 -16.872712)
		(stroke
			(width 0.05715)
			(type default)
		)
		(layer "In9.Cu")
	)
	(gr_line
		(start 439.680858 -7.50189)
		(end 439.70194 -7.511034)
		(stroke
			(width 0.05715)
			(type default)
		)
		(layer "In9.Cu")
	)
	(gr_line
		(start 439.735722 -12.532614)
		(end 439.75274 -12.44981)
		(stroke
			(width 0.05715)
			(type default)
		)
		(layer "In9.Cu")
	)
	(gr_line
		(start 439.757566 -16.129762)
		(end 439.76671 -16.135858)
		(stroke
			(width 0.05715)
			(type default)
		)
		(layer "In9.Cu")
	)
	(gr_line
		(start 439.76671 -16.135858)
		(end 439.777378 -16.138652)
		(stroke
			(width 0.05715)
			(type default)
		)
		(layer "In9.Cu")
	)
	(gr_line
		(start 439.805826 -11.862816)
		(end 439.875168 -11.816842)
		(stroke
			(width 0.05715)
			(type default)
		)
		(layer "In9.Cu")
	)
	(gr_line
		(start 439.875168 -11.816842)
		(end 439.957464 -11.833606)
		(stroke
			(width 0.05715)
			(type default)
		)
		(layer "In9.Cu")
	)
	(gr_line
		(start 440.183778 -12.624308)
		(end 440.200542 -12.542012)
		(stroke
			(width 0.05715)
			(type default)
		)
		(layer "In9.Cu")
	)
	(gr_line
		(start 440.183778 -12.624308)
		(end 440.23026 -12.69492)
		(stroke
			(width 0.05715)
			(type default)
		)
		(layer "In9.Cu")
	)
	(gr_line
		(start 440.224672 -5.667248)
		(end 440.610752 -5.667248)
		(stroke
			(width 0.05715)
			(type default)
		)
		(layer "In9.Cu")
	)
	(gr_line
		(start 440.255152 -11.89482)
		(end 440.33694 -11.91133)
		(stroke
			(width 0.05715)
			(type default)
		)
		(layer "In9.Cu")
	)
	(gr_line
		(start 440.33694 -11.91133)
		(end 440.382914 -11.98118)
		(stroke
			(width 0.05715)
			(type default)
		)
		(layer "In9.Cu")
	)
	(gr_line
		(start 440.360054 -12.891262)
		(end 440.406282 -12.960858)
		(stroke
			(width 0.05715)
			(type default)
		)
		(layer "In9.Cu")
	)
	(gr_line
		(start 440.406282 -12.960858)
		(end 440.488324 -12.977622)
		(stroke
			(width 0.05715)
			(type default)
		)
		(layer "In9.Cu")
	)
	(gr_line
		(start 440.513216 -12.178792)
		(end 440.55919 -12.248134)
		(stroke
			(width 0.05715)
			(type default)
		)
		(layer "In9.Cu")
	)
	(gr_line
		(start 440.540648 -3.345688)
		(end 440.550554 -3.352292)
		(stroke
			(width 0.05715)
			(type default)
		)
		(layer "In9.Cu")
	)
	(gr_line
		(start 440.542426 -12.33043)
		(end 440.55919 -12.248134)
		(stroke
			(width 0.05715)
			(type default)
		)
		(layer "In9.Cu")
	)
	(gr_line
		(start 440.542426 -12.330176)
		(end 440.542426 -12.330684)
		(stroke
			(width 0.05715)
			(type default)
		)
		(layer "In9.Cu")
	)
	(gr_line
		(start 440.550554 -3.352292)
		(end 440.561984 -3.35534)
		(stroke
			(width 0.05715)
			(type default)
		)
		(layer "In9.Cu")
	)
	(gr_line
		(start 440.610752 -5.667248)
		(end 440.68492 -5.59308)
		(stroke
			(width 0.05715)
			(type default)
		)
		(layer "In9.Cu")
	)
	(gr_line
		(start 440.765692 -10.814558)
		(end 440.788552 -10.809732)
		(stroke
			(width 0.05715)
			(type default)
		)
		(layer "In9.Cu")
	)
	(gr_line
		(start 440.782964 -17.133062)
		(end 440.802014 -17.137634)
		(stroke
			(width 0.05715)
			(type default)
		)
		(layer "In9.Cu")
	)
	(gr_line
		(start 440.788552 -10.809732)
		(end 440.811412 -10.814304)
		(stroke
			(width 0.05715)
			(type default)
		)
		(layer "In9.Cu")
	)
	(gr_line
		(start 440.796426 -17.879822)
		(end 440.816492 -17.885156)
		(stroke
			(width 0.05715)
			(type default)
		)
		(layer "In9.Cu")
	)
	(gr_line
		(start 440.802014 -17.137634)
		(end 440.82208 -17.134586)
		(stroke
			(width 0.05715)
			(type default)
		)
		(layer "In9.Cu")
	)
	(gr_line
		(start 440.816492 -17.885156)
		(end 440.837066 -17.882362)
		(stroke
			(width 0.05715)
			(type default)
		)
		(layer "In9.Cu")
	)
	(gr_line
		(start 440.895486 -16.430498)
		(end 440.923934 -16.437864)
		(stroke
			(width 0.05715)
			(type default)
		)
		(layer "In9.Cu")
	)
	(gr_line
		(start 440.923934 -16.437864)
		(end 440.952382 -16.432022)
		(stroke
			(width 0.05715)
			(type default)
		)
		(layer "In9.Cu")
	)
	(gr_line
		(start 441.10148 -5.59308)
		(end 441.175648 -5.667248)
		(stroke
			(width 0.05715)
			(type default)
		)
		(layer "In9.Cu")
	)
	(gr_line
		(start 441.1218 -10.0584)
		(end 441.2742 -10.0584)
		(stroke
			(width 0.05715)
			(type default)
		)
		(layer "In9.Cu")
	)
	(gr_line
		(start 441.175648 -5.667248)
		(end 441.494672 -5.667248)
		(stroke
			(width 0.05715)
			(type default)
		)
		(layer "In9.Cu")
	)
	(gr_line
		(start 441.191396 -4.64947)
		(end 441.191396 -4.649724)
		(stroke
			(width 0.05715)
			(type default)
		)
		(layer "In9.Cu")
	)
	(gr_line
		(start 441.191396 -4.64947)
		(end 441.240418 -4.639056)
		(stroke
			(width 0.05715)
			(type default)
		)
		(layer "In9.Cu")
	)
	(gr_line
		(start 441.2742 -10.0584)
		(end 441.44692 -9.88568)
		(stroke
			(width 0.05715)
			(type default)
		)
		(layer "In9.Cu")
	)
	(gr_line
		(start 441.86348 -9.88568)
		(end 442.007244 -10.029444)
		(stroke
			(width 0.05715)
			(type default)
		)
		(layer "In9.Cu")
	)
	(gr_line
		(start 441.889134 -11.326876)
		(end 441.908692 -11.33094)
		(stroke
			(width 0.05715)
			(type default)
		)
		(layer "In9.Cu")
	)
	(gr_line
		(start 441.908692 -11.33094)
		(end 441.927742 -11.32713)
		(stroke
			(width 0.05715)
			(type default)
		)
		(layer "In9.Cu")
	)
	(gr_line
		(start 442.007244 -10.029444)
		(end 442.111892 -10.029444)
		(stroke
			(width 0.05715)
			(type default)
		)
		(layer "In9.Cu")
	)
	(gr_line
		(start 442.618622 -12.67587)
		(end 442.698886 -12.659868)
		(stroke
			(width 0.05715)
			(type default)
		)
		(layer "In9.Cu")
	)
	(gr_line
		(start 442.621924 -21.307044)
		(end 442.651134 -21.314918)
		(stroke
			(width 0.05715)
			(type default)
		)
		(layer "In9.Cu")
	)
	(gr_line
		(start 442.651134 -21.314918)
		(end 442.681106 -21.308822)
		(stroke
			(width 0.05715)
			(type default)
		)
		(layer "In9.Cu")
	)
	(gr_line
		(start 442.698886 -12.659868)
		(end 442.767466 -12.705588)
		(stroke
			(width 0.05715)
			(type default)
		)
		(layer "In9.Cu")
	)
	(gr_line
		(start 442.754004 -14.669008)
		(end 442.776864 -14.673834)
		(stroke
			(width 0.05715)
			(type default)
		)
		(layer "In9.Cu")
	)
	(gr_line
		(start 442.760608 -5.892038)
		(end 443.135258 -5.892038)
		(stroke
			(width 0.05715)
			(type default)
		)
		(layer "In9.Cu")
	)
	(gr_line
		(start 442.776864 -14.673834)
		(end 442.799724 -14.669262)
		(stroke
			(width 0.05715)
			(type default)
		)
		(layer "In9.Cu")
	)
	(gr_line
		(start 442.854842 -13.471906)
		(end 442.871098 -13.552932)
		(stroke
			(width 0.05715)
			(type default)
		)
		(layer "In9.Cu")
	)
	(gr_line
		(start 442.871098 -13.552932)
		(end 442.939932 -13.598906)
		(stroke
			(width 0.05715)
			(type default)
		)
		(layer "In9.Cu")
	)
	(gr_line
		(start 442.96584 -12.837922)
		(end 443.034674 -12.883896)
		(stroke
			(width 0.05715)
			(type default)
		)
		(layer "In9.Cu")
	)
	(gr_line
		(start 443.015624 -17.29105)
		(end 443.0268 -17.289526)
		(stroke
			(width 0.05715)
			(type default)
		)
		(layer "In9.Cu")
	)
	(gr_line
		(start 443.0268 -17.289526)
		(end 443.037468 -17.291812)
		(stroke
			(width 0.05715)
			(type default)
		)
		(layer "In9.Cu")
	)
	(gr_line
		(start 443.034674 -12.883896)
		(end 443.05093 -12.964922)
		(stroke
			(width 0.05715)
			(type default)
		)
		(layer "In9.Cu")
	)
	(gr_line
		(start 443.135258 -5.892038)
		(end 443.187328 -5.839968)
		(stroke
			(width 0.05715)
			(type default)
		)
		(layer "In9.Cu")
	)
	(gr_line
		(start 443.137544 -13.730732)
		(end 443.206886 -13.77696)
		(stroke
			(width 0.05715)
			(type default)
		)
		(layer "In9.Cu")
	)
	(gr_line
		(start 443.206886 -13.77696)
		(end 443.28842 -13.76045)
		(stroke
			(width 0.05715)
			(type default)
		)
		(layer "In9.Cu")
	)
	(gr_line
		(start 443.249558 -5.445506)
		(end 443.30747 -5.386832)
		(stroke
			(width 0.05715)
			(type default)
		)
		(layer "In9.Cu")
	)
	(gr_line
		(start 443.333124 -19.305524)
		(end 443.91834 -19.42465)
		(stroke
			(width 0.05715)
			(type default)
		)
		(layer "In9.Cu")
	)
	(gr_line
		(start 443.356492 -19.009614)
		(end 443.548516 -18.882614)
		(stroke
			(width 0.05715)
			(type default)
		)
		(layer "In9.Cu")
	)
	(gr_line
		(start 443.482984 -12.79398)
		(end 443.499494 -12.876276)
		(stroke
			(width 0.05715)
			(type default)
		)
		(layer "In9.Cu")
	)
	(gr_line
		(start 443.482984 -12.79398)
		(end 443.529212 -12.724638)
		(stroke
			(width 0.05715)
			(type default)
		)
		(layer "In9.Cu")
	)
	(gr_line
		(start 443.548516 -18.882614)
		(end 443.884558 -18.95094)
		(stroke
			(width 0.05715)
			(type default)
		)
		(layer "In9.Cu")
	)
	(gr_line
		(start 443.587886 -13.699998)
		(end 443.668404 -13.683996)
		(stroke
			(width 0.05715)
			(type default)
		)
		(layer "In9.Cu")
	)
	(gr_line
		(start 443.603888 -5.839968)
		(end 443.655958 -5.892038)
		(stroke
			(width 0.05715)
			(type default)
		)
		(layer "In9.Cu")
	)
	(gr_line
		(start 443.6237 -9.12495)
		(end 443.832996 -9.12495)
		(stroke
			(width 0.05715)
			(type default)
		)
		(layer "In9.Cu")
	)
	(gr_line
		(start 443.655958 -5.892038)
		(end 444.030608 -5.892038)
		(stroke
			(width 0.05715)
			(type default)
		)
		(layer "In9.Cu")
	)
	(gr_line
		(start 443.661038 -12.526772)
		(end 443.706758 -12.458192)
		(stroke
			(width 0.05715)
			(type default)
		)
		(layer "In9.Cu")
	)
	(gr_line
		(start 443.668404 -13.683996)
		(end 443.714632 -13.614908)
		(stroke
			(width 0.05715)
			(type default)
		)
		(layer "In9.Cu")
	)
	(gr_line
		(start 443.706758 -12.458192)
		(end 443.787784 -12.441936)
		(stroke
			(width 0.05715)
			(type default)
		)
		(layer "In9.Cu")
	)
	(gr_line
		(start 443.832996 -9.12495)
		(end 443.88532 -9.072626)
		(stroke
			(width 0.05715)
			(type default)
		)
		(layer "In9.Cu")
	)
	(gr_line
		(start 443.846204 -13.417804)
		(end 443.892432 -13.348462)
		(stroke
			(width 0.05715)
			(type default)
		)
		(layer "In9.Cu")
	)
	(gr_line
		(start 443.875922 -13.266166)
		(end 443.892432 -13.348462)
		(stroke
			(width 0.05715)
			(type default)
		)
		(layer "In9.Cu")
	)
	(gr_line
		(start 443.884558 -18.95094)
		(end 444.011558 -19.142964)
		(stroke
			(width 0.05715)
			(type default)
		)
		(layer "In9.Cu")
	)
	(gr_line
		(start 443.94374 -4.744974)
		(end 443.978538 -4.709922)
		(stroke
			(width 0.05715)
			(type default)
		)
		(layer "In9.Cu")
	)
	(gr_line
		(start 443.978538 -4.709922)
		(end 444.027052 -4.699508)
		(stroke
			(width 0.05715)
			(type default)
		)
		(layer "In9.Cu")
	)
	(gr_line
		(start 444.087758 -12.381738)
		(end 444.169292 -12.365228)
		(stroke
			(width 0.05715)
			(type default)
		)
		(layer "In9.Cu")
	)
	(gr_line
		(start 444.137288 -10.587482)
		(end 444.156338 -10.583672)
		(stroke
			(width 0.05715)
			(type default)
		)
		(layer "In9.Cu")
	)
	(gr_line
		(start 444.156338 -10.583672)
		(end 444.175388 -10.587482)
		(stroke
			(width 0.05715)
			(type default)
		)
		(layer "In9.Cu")
	)
	(gr_line
		(start 444.180468 -15.7861)
		(end 444.199518 -15.78229)
		(stroke
			(width 0.05715)
			(type default)
		)
		(layer "In9.Cu")
	)
	(gr_line
		(start 444.199518 -15.78229)
		(end 444.215774 -15.771622)
		(stroke
			(width 0.05715)
			(type default)
		)
		(layer "In9.Cu")
	)
	(gr_line
		(start 444.30188 -9.072626)
		(end 444.354204 -9.12495)
		(stroke
			(width 0.05715)
			(type default)
		)
		(layer "In9.Cu")
	)
	(gr_line
		(start 444.324994 -13.177012)
		(end 444.34125 -13.258038)
		(stroke
			(width 0.05715)
			(type default)
		)
		(layer "In9.Cu")
	)
	(gr_line
		(start 444.328296 -19.507962)
		(end 444.915036 -19.627342)
		(stroke
			(width 0.05715)
			(type default)
		)
		(layer "In9.Cu")
	)
	(gr_line
		(start 444.34125 -13.258038)
		(end 444.410084 -13.304012)
		(stroke
			(width 0.05715)
			(type default)
		)
		(layer "In9.Cu")
	)
	(gr_line
		(start 444.352172 -19.212306)
		(end 444.544196 -19.085052)
		(stroke
			(width 0.05715)
			(type default)
		)
		(layer "In9.Cu")
	)
	(gr_line
		(start 444.354204 -9.12495)
		(end 444.5635 -9.12495)
		(stroke
			(width 0.05715)
			(type default)
		)
		(layer "In9.Cu")
	)
	(gr_line
		(start 444.436246 -12.543282)
		(end 444.504826 -12.589002)
		(stroke
			(width 0.05715)
			(type default)
		)
		(layer "In9.Cu")
	)
	(gr_line
		(start 444.49873 -20.939506)
		(end 444.549276 -20.929092)
		(stroke
			(width 0.05715)
			(type default)
		)
		(layer "In9.Cu")
	)
	(gr_line
		(start 444.504826 -12.589002)
		(end 444.521082 -12.670028)
		(stroke
			(width 0.05715)
			(type default)
		)
		(layer "In9.Cu")
	)
	(gr_line
		(start 444.544196 -19.085052)
		(end 444.880238 -19.153378)
		(stroke
			(width 0.05715)
			(type default)
		)
		(layer "In9.Cu")
	)
	(gr_line
		(start 444.549276 -20.929092)
		(end 444.585852 -20.892516)
		(stroke
			(width 0.05715)
			(type default)
		)
		(layer "In9.Cu")
	)
	(gr_line
		(start 444.607696 -13.435838)
		(end 444.677038 -13.482066)
		(stroke
			(width 0.05715)
			(type default)
		)
		(layer "In9.Cu")
	)
	(gr_line
		(start 444.677038 -13.482066)
		(end 444.758572 -13.465556)
		(stroke
			(width 0.05715)
			(type default)
		)
		(layer "In9.Cu")
	)
	(gr_line
		(start 444.83655 -20.22856)
		(end 444.87211 -20.193)
		(stroke
			(width 0.05715)
			(type default)
		)
		(layer "In9.Cu")
	)
	(gr_line
		(start 444.87211 -20.193)
		(end 444.92037 -20.183348)
		(stroke
			(width 0.05715)
			(type default)
		)
		(layer "In9.Cu")
	)
	(gr_line
		(start 444.880238 -19.153378)
		(end 445.007238 -19.345656)
		(stroke
			(width 0.05715)
			(type default)
		)
		(layer "In9.Cu")
	)
	(gr_line
		(start 444.953136 -12.499086)
		(end 444.969646 -12.581382)
		(stroke
			(width 0.05715)
			(type default)
		)
		(layer "In9.Cu")
	)
	(gr_line
		(start 444.953136 -12.499086)
		(end 444.99911 -12.429998)
		(stroke
			(width 0.05715)
			(type default)
		)
		(layer "In9.Cu")
	)
	(gr_line
		(start 444.999364 -12.42949)
		(end 444.999364 -12.429744)
		(stroke
			(width 0.05715)
			(type default)
		)
		(layer "In9.Cu")
	)
	(gr_line
		(start 445.008 -9.87171)
		(end 445.264794 -9.87171)
		(stroke
			(width 0.05715)
			(type default)
		)
		(layer "In9.Cu")
	)
	(gr_line
		(start 445.058038 -13.405104)
		(end 445.138556 -13.389102)
		(stroke
			(width 0.05715)
			(type default)
		)
		(layer "In9.Cu")
	)
	(gr_line
		(start 445.130936 -12.232386)
		(end 445.17691 -12.163552)
		(stroke
			(width 0.05715)
			(type default)
		)
		(layer "In9.Cu")
	)
	(gr_line
		(start 445.138556 -13.389102)
		(end 445.184784 -13.320014)
		(stroke
			(width 0.05715)
			(type default)
		)
		(layer "In9.Cu")
	)
	(gr_line
		(start 445.17691 -12.163552)
		(end 445.257936 -12.147296)
		(stroke
			(width 0.05715)
			(type default)
		)
		(layer "In9.Cu")
	)
	(gr_line
		(start 445.264794 -9.87171)
		(end 445.265048 -9.871964)
		(stroke
			(width 0.05715)
			(type default)
		)
		(layer "In9.Cu")
	)
	(gr_line
		(start 445.316356 -13.12291)
		(end 445.362584 -13.053568)
		(stroke
			(width 0.05715)
			(type default)
		)
		(layer "In9.Cu")
	)
	(gr_line
		(start 445.323468 -19.710654)
		(end 445.345058 -19.714972)
		(stroke
			(width 0.05715)
			(type default)
		)
		(layer "In9.Cu")
	)
	(gr_line
		(start 445.345058 -19.714972)
		(end 445.36614 -19.710654)
		(stroke
			(width 0.05715)
			(type default)
		)
		(layer "In9.Cu")
	)
	(gr_line
		(start 445.346074 -12.971272)
		(end 445.362584 -13.053568)
		(stroke
			(width 0.05715)
			(type default)
		)
		(layer "In9.Cu")
	)
	(gr_line
		(start 445.383412 -18.05813)
		(end 445.402462 -18.06194)
		(stroke
			(width 0.05715)
			(type default)
		)
		(layer "In9.Cu")
	)
	(gr_line
		(start 445.402462 -18.06194)
		(end 445.421766 -18.057876)
		(stroke
			(width 0.05715)
			(type default)
		)
		(layer "In9.Cu")
	)
	(gr_line
		(start 445.406526 -14.1478)
		(end 445.425576 -14.14399)
		(stroke
			(width 0.05715)
			(type default)
		)
		(layer "In9.Cu")
	)
	(gr_line
		(start 445.651636 -62.653926)
		(end 445.954404 -62.956694)
		(stroke
			(width 0.050546)
			(type default)
		)
		(layer "In9.Cu")
	)
	(gr_line
		(start 445.680084 -9.767316)
		(end 445.680084 -9.87044)
		(stroke
			(width 0.05715)
			(type default)
		)
		(layer "In9.Cu")
	)
	(gr_line
		(start 445.680084 -9.767316)
		(end 445.8716 -9.5758)
		(stroke
			(width 0.05715)
			(type default)
		)
		(layer "In9.Cu")
	)
	(gr_line
		(start 445.780922 -13.553186)
		(end 445.826134 -13.327634)
		(stroke
			(width 0.05715)
			(type default)
		)
		(layer "In9.Cu")
	)
	(gr_line
		(start 445.826134 -13.327634)
		(end 446.111376 -13.137388)
		(stroke
			(width 0.05715)
			(type default)
		)
		(layer "In9.Cu")
	)
	(gr_line
		(start 445.910716 -60.378848)
		(end 446.23482 -60.378848)
		(stroke
			(width 0.050546)
			(type default)
		)
		(layer "In9.Cu")
	)
	(gr_line
		(start 445.954404 -62.956694)
		(end 446.258442 -62.956694)
		(stroke
			(width 0.050546)
			(type default)
		)
		(layer "In9.Cu")
	)
	(gr_line
		(start 446.07099 -62.232032)
		(end 446.141856 -62.232032)
		(stroke
			(width 0.050546)
			(type default)
		)
		(layer "In9.Cu")
	)
	(gr_line
		(start 446.107566 -11.272012)
		(end 446.129156 -11.27633)
		(stroke
			(width 0.05715)
			(type default)
		)
		(layer "In9.Cu")
	)
	(gr_line
		(start 446.111376 -13.137388)
		(end 446.336928 -13.182346)
		(stroke
			(width 0.05715)
			(type default)
		)
		(layer "In9.Cu")
	)
	(gr_line
		(start 446.129156 -11.27633)
		(end 446.150746 -11.272012)
		(stroke
			(width 0.05715)
			(type default)
		)
		(layer "In9.Cu")
	)
	(gr_line
		(start 446.16878 -8.435594)
		(end 446.25133 -8.518144)
		(stroke
			(width 0.05715)
			(type default)
		)
		(layer "In9.Cu")
	)
	(gr_line
		(start 446.16878 -8.01878)
		(end 446.25133 -7.93623)
		(stroke
			(width 0.05715)
			(type default)
		)
		(layer "In9.Cu")
	)
	(gr_line
		(start 446.187576 -13.636244)
		(end 446.47104 -13.447268)
		(stroke
			(width 0.05715)
			(type default)
		)
		(layer "In9.Cu")
	)
	(gr_line
		(start 446.23482 -60.378848)
		(end 446.24752 -60.391548)
		(stroke
			(width 0.050546)
			(type default)
		)
		(layer "In9.Cu")
	)
	(gr_line
		(start 446.25133 -8.518144)
		(end 446.25133 -8.700008)
		(stroke
			(width 0.05715)
			(type default)
		)
		(layer "In9.Cu")
	)
	(gr_line
		(start 446.25133 -7.734808)
		(end 446.25133 -7.93623)
		(stroke
			(width 0.05715)
			(type default)
		)
		(layer "In9.Cu")
	)
	(gr_line
		(start 446.258442 -62.956694)
		(end 446.56121 -62.653926)
		(stroke
			(width 0.050546)
			(type default)
		)
		(layer "In9.Cu")
	)
	(gr_line
		(start 446.275968 -5.081778)
		(end 446.285874 -5.081778)
		(stroke
			(width 0.05715)
			(type default)
		)
		(layer "In9.Cu")
	)
	(gr_line
		(start 446.285874 -5.081778)
		(end 446.532762 -5.328666)
		(stroke
			(width 0.05715)
			(type default)
		)
		(layer "In9.Cu")
	)
	(gr_line
		(start 446.364106 -6.72846)
		(end 446.409826 -6.738874)
		(stroke
			(width 0.05715)
			(type default)
		)
		(layer "In9.Cu")
	)
	(gr_line
		(start 446.409826 -6.738874)
		(end 446.4431 -6.772402)
		(stroke
			(width 0.05715)
			(type default)
		)
		(layer "In9.Cu")
	)
	(gr_line
		(start 446.423542 -19.87677)
		(end 446.444878 -19.872452)
		(stroke
			(width 0.05715)
			(type default)
		)
		(layer "In9.Cu")
	)
	(gr_line
		(start 446.444878 -19.872452)
		(end 446.466468 -19.87677)
		(stroke
			(width 0.05715)
			(type default)
		)
		(layer "In9.Cu")
	)
	(gr_line
		(start 446.728342 -15.655798)
		(end 446.756028 -15.64894)
		(stroke
			(width 0.05715)
			(type default)
		)
		(layer "In9.Cu")
	)
	(gr_line
		(start 446.756028 -15.64894)
		(end 446.783968 -15.654528)
		(stroke
			(width 0.05715)
			(type default)
		)
		(layer "In9.Cu")
	)
	(gr_line
		(start 446.824608 -12.130786)
		(end 446.8495 -12.125706)
		(stroke
			(width 0.05715)
			(type default)
		)
		(layer "In9.Cu")
	)
	(gr_line
		(start 446.839594 -7.17042)
		(end 446.85331 -7.184136)
		(stroke
			(width 0.05715)
			(type default)
		)
		(layer "In9.Cu")
	)
	(gr_line
		(start 446.844166 -60.391548)
		(end 446.856866 -60.378848)
		(stroke
			(width 0.050546)
			(type default)
		)
		(layer "In9.Cu")
	)
	(gr_line
		(start 446.8495 -12.125706)
		(end 446.870074 -12.110974)
		(stroke
			(width 0.05715)
			(type default)
		)
		(layer "In9.Cu")
	)
	(gr_line
		(start 446.85331 -7.184136)
		(end 446.86093 -7.202424)
		(stroke
			(width 0.05715)
			(type default)
		)
		(layer "In9.Cu")
	)
	(gr_line
		(start 446.856866 -60.378848)
		(end 447.180716 -60.378848)
		(stroke
			(width 0.050546)
			(type default)
		)
		(layer "In9.Cu")
	)
	(gr_line
		(start 446.870328 -62.653926)
		(end 447.173096 -62.956694)
		(stroke
			(width 0.050546)
			(type default)
		)
		(layer "In9.Cu")
	)
	(gr_line
		(start 446.949576 -5.328666)
		(end 447.186812 -5.09143)
		(stroke
			(width 0.05715)
			(type default)
		)
		(layer "In9.Cu")
	)
	(gr_line
		(start 447.093848 -11.08075)
		(end 447.117724 -11.075924)
		(stroke
			(width 0.05715)
			(type default)
		)
		(layer "In9.Cu")
	)
	(gr_line
		(start 447.117724 -11.075924)
		(end 447.137536 -11.0617)
		(stroke
			(width 0.05715)
			(type default)
		)
		(layer "In9.Cu")
	)
	(gr_line
		(start 447.173096 -62.956694)
		(end 447.477134 -62.956694)
		(stroke
			(width 0.050546)
			(type default)
		)
		(layer "In9.Cu")
	)
	(gr_line
		(start 447.186812 -5.09143)
		(end 447.216022 -5.09143)
		(stroke
			(width 0.05715)
			(type default)
		)
		(layer "In9.Cu")
	)
	(gr_line
		(start 447.19113 -12.613386)
		(end 447.236088 -12.387834)
		(stroke
			(width 0.05715)
			(type default)
		)
		(layer "In9.Cu")
	)
	(gr_line
		(start 447.236088 -12.387834)
		(end 447.52133 -12.197588)
		(stroke
			(width 0.05715)
			(type default)
		)
		(layer "In9.Cu")
	)
	(gr_line
		(start 447.276728 -9.82345)
		(end 447.282824 -9.810242)
		(stroke
			(width 0.05715)
			(type default)
		)
		(layer "In9.Cu")
	)
	(gr_line
		(start 447.289682 -62.232032)
		(end 447.360548 -62.232032)
		(stroke
			(width 0.050546)
			(type default)
		)
		(layer "In9.Cu")
	)
	(gr_line
		(start 447.384678 -12.838176)
		(end 447.879724 -12.50823)
		(stroke
			(width 0.05715)
			(type default)
		)
		(layer "In9.Cu")
	)
	(gr_line
		(start 447.477134 -62.956694)
		(end 447.779902 -62.653926)
		(stroke
			(width 0.050546)
			(type default)
		)
		(layer "In9.Cu")
	)
	(gr_line
		(start 447.52133 -12.197588)
		(end 447.746882 -12.2428)
		(stroke
			(width 0.05715)
			(type default)
		)
		(layer "In9.Cu")
	)
	(gr_line
		(start 447.532506 -8.828786)
		(end 447.55308 -8.878824)
		(stroke
			(width 0.05715)
			(type default)
		)
		(layer "In9.Cu")
	)
	(gr_line
		(start 447.54165 -8.931656)
		(end 447.55308 -8.878824)
		(stroke
			(width 0.05715)
			(type default)
		)
		(layer "In9.Cu")
	)
	(gr_line
		(start 447.542666 -6.669024)
		(end 447.55054 -6.688074)
		(stroke
			(width 0.05715)
			(type default)
		)
		(layer "In9.Cu")
	)
	(gr_line
		(start 447.566288 -18.968466)
		(end 447.693542 -18.77695)
		(stroke
			(width 0.05715)
			(type default)
		)
		(layer "In9.Cu")
	)
	(gr_line
		(start 447.66103 -19.249898)
		(end 448.24396 -19.132804)
		(stroke
			(width 0.05715)
			(type default)
		)
		(layer "In9.Cu")
	)
	(gr_line
		(start 447.693542 -18.77695)
		(end 448.029838 -18.70964)
		(stroke
			(width 0.05715)
			(type default)
		)
		(layer "In9.Cu")
	)
	(gr_line
		(start 447.764408 -10.610596)
		(end 447.783966 -10.596626)
		(stroke
			(width 0.05715)
			(type default)
		)
		(layer "In9.Cu")
	)
	(gr_line
		(start 447.783966 -10.596626)
		(end 447.796412 -10.575036)
		(stroke
			(width 0.05715)
			(type default)
		)
		(layer "In9.Cu")
	)
	(gr_line
		(start 447.813176 -17.278604)
		(end 447.812922 -17.278604)
		(stroke
			(width 0.05715)
			(type default)
		)
		(layer "In9.Cu")
	)
	(gr_line
		(start 447.89344 -6.09854)
		(end 448.156076 -6.361176)
		(stroke
			(width 0.05715)
			(type default)
		)
		(layer "In9.Cu")
	)
	(gr_line
		(start 447.909442 -17.556988)
		(end 447.980816 -17.542764)
		(stroke
			(width 0.05715)
			(type default)
		)
		(layer "In9.Cu")
	)
	(gr_line
		(start 447.97726 -16.190976)
		(end 448.0052 -16.196564)
		(stroke
			(width 0.05715)
			(type default)
		)
		(layer "In9.Cu")
	)
	(gr_line
		(start 447.980816 -17.542764)
		(end 448.024758 -17.483582)
		(stroke
			(width 0.05715)
			(type default)
		)
		(layer "In9.Cu")
	)
	(gr_line
		(start 448.0052 -16.196564)
		(end 448.033394 -16.189198)
		(stroke
			(width 0.05715)
			(type default)
		)
		(layer "In9.Cu")
	)
	(gr_line
		(start 448.029838 -18.70964)
		(end 448.221354 -18.837148)
		(stroke
			(width 0.05715)
			(type default)
		)
		(layer "In9.Cu")
	)
	(gr_line
		(start 448.036442 -12.050014)
		(end 448.0814 -11.824208)
		(stroke
			(width 0.05715)
			(type default)
		)
		(layer "In9.Cu")
	)
	(gr_line
		(start 448.0814 -11.824208)
		(end 448.366896 -11.634216)
		(stroke
			(width 0.05715)
			(type default)
		)
		(layer "In9.Cu")
	)
	(gr_line
		(start 448.08902 -62.653926)
		(end 448.391788 -62.956694)
		(stroke
			(width 0.050546)
			(type default)
		)
		(layer "In9.Cu")
	)
	(gr_line
		(start 448.163442 -9.938766)
		(end 448.166998 -9.932416)
		(stroke
			(width 0.05715)
			(type default)
		)
		(layer "In9.Cu")
	)
	(gr_line
		(start 448.166998 -9.932416)
		(end 448.168522 -9.925812)
		(stroke
			(width 0.05715)
			(type default)
		)
		(layer "In9.Cu")
	)
	(gr_line
		(start 448.184524 -1.367536)
		(end 448.205098 -1.37668)
		(stroke
			(width 0.05715)
			(type default)
		)
		(layer "In9.Cu")
	)
	(gr_line
		(start 448.229228 -12.275566)
		(end 448.726814 -11.943842)
		(stroke
			(width 0.05715)
			(type default)
		)
		(layer "In9.Cu")
	)
	(gr_line
		(start 448.257422 -7.210298)
		(end 448.264788 -7.228332)
		(stroke
			(width 0.05715)
			(type default)
		)
		(layer "In9.Cu")
	)
	(gr_line
		(start 448.266058 -0.673608)
		(end 448.287902 -0.683006)
		(stroke
			(width 0.05715)
			(type default)
		)
		(layer "In9.Cu")
	)
	(gr_line
		(start 448.329304 -15.806166)
		(end 448.445128 -15.607538)
		(stroke
			(width 0.05715)
			(type default)
		)
		(layer "In9.Cu")
	)
	(gr_line
		(start 448.329304 -11.060938)
		(end 448.34683 -11.048238)
		(stroke
			(width 0.05715)
			(type default)
		)
		(layer "In9.Cu")
	)
	(gr_line
		(start 448.34683 -11.048238)
		(end 448.357498 -11.030458)
		(stroke
			(width 0.05715)
			(type default)
		)
		(layer "In9.Cu")
	)
	(gr_line
		(start 448.366896 -11.634216)
		(end 448.592448 -11.679174)
		(stroke
			(width 0.05715)
			(type default)
		)
		(layer "In9.Cu")
	)
	(gr_line
		(start 448.391788 -62.956694)
		(end 448.695826 -62.956694)
		(stroke
			(width 0.050546)
			(type default)
		)
		(layer "In9.Cu")
	)
	(gr_line
		(start 448.400424 -16.489426)
		(end 448.43954 -16.437102)
		(stroke
			(width 0.05715)
			(type default)
		)
		(layer "In9.Cu")
	)
	(gr_line
		(start 448.400932 -8.752332)
		(end 448.401186 -8.75284)
		(stroke
			(width 0.05715)
			(type default)
		)
		(layer "In9.Cu")
	)
	(gr_line
		(start 448.401186 -8.753094)
		(end 448.422268 -8.804148)
		(stroke
			(width 0.05715)
			(type default)
		)
		(layer "In9.Cu")
	)
	(gr_line
		(start 448.410076 -8.857996)
		(end 448.422268 -8.804148)
		(stroke
			(width 0.05715)
			(type default)
		)
		(layer "In9.Cu")
	)
	(gr_line
		(start 448.415664 -0.03175)
		(end 448.435984 -0.04064)
		(stroke
			(width 0.05715)
			(type default)
		)
		(layer "In9.Cu")
	)
	(gr_line
		(start 448.439032 -16.08201)
		(end 449.015866 -15.929864)
		(stroke
			(width 0.05715)
			(type default)
		)
		(layer "In9.Cu")
	)
	(gr_line
		(start 448.43954 -16.437102)
		(end 448.502786 -16.420338)
		(stroke
			(width 0.05715)
			(type default)
		)
		(layer "In9.Cu")
	)
	(gr_line
		(start 448.445128 -15.607538)
		(end 448.776598 -15.519908)
		(stroke
			(width 0.05715)
			(type default)
		)
		(layer "In9.Cu")
	)
	(gr_line
		(start 448.460368 -20.576286)
		(end 448.482212 -20.580604)
		(stroke
			(width 0.05715)
			(type default)
		)
		(layer "In9.Cu")
	)
	(gr_line
		(start 448.482212 -20.580604)
		(end 448.503802 -20.576286)
		(stroke
			(width 0.05715)
			(type default)
		)
		(layer "In9.Cu")
	)
	(gr_line
		(start 448.508374 -62.232032)
		(end 448.57924 -62.232032)
		(stroke
			(width 0.050546)
			(type default)
		)
		(layer "In9.Cu")
	)
	(gr_line
		(start 448.57289 -6.361176)
		(end 448.835526 -6.09854)
		(stroke
			(width 0.05715)
			(type default)
		)
		(layer "In9.Cu")
	)
	(gr_line
		(start 448.679062 -4.180332)
		(end 448.698874 -4.188968)
		(stroke
			(width 0.05715)
			(type default)
		)
		(layer "In9.Cu")
	)
	(gr_line
		(start 448.695826 -62.956694)
		(end 448.998594 -62.653926)
		(stroke
			(width 0.050546)
			(type default)
		)
		(layer "In9.Cu")
	)
	(gr_line
		(start 448.776598 -15.519908)
		(end 448.975226 -15.635732)
		(stroke
			(width 0.05715)
			(type default)
		)
		(layer "In9.Cu")
	)
	(gr_line
		(start 448.882008 -11.486388)
		(end 448.926966 -11.260836)
		(stroke
			(width 0.05715)
			(type default)
		)
		(layer "In9.Cu")
	)
	(gr_line
		(start 448.883786 -3.545332)
		(end 448.902836 -3.553714)
		(stroke
			(width 0.05715)
			(type default)
		)
		(layer "In9.Cu")
	)
	(gr_line
		(start 448.926966 -11.260836)
		(end 449.212208 -11.07059)
		(stroke
			(width 0.05715)
			(type default)
		)
		(layer "In9.Cu")
	)
	(gr_line
		(start 449.03136 -9.925558)
		(end 449.037202 -9.915906)
		(stroke
			(width 0.05715)
			(type default)
		)
		(layer "In9.Cu")
	)
	(gr_line
		(start 449.037202 -9.915906)
		(end 449.039742 -9.904476)
		(stroke
			(width 0.05715)
			(type default)
		)
		(layer "In9.Cu")
	)
	(gr_line
		(start 449.074286 -11.712194)
		(end 449.57111 -11.381232)
		(stroke
			(width 0.05715)
			(type default)
		)
		(layer "In9.Cu")
	)
	(gr_line
		(start 449.183506 -2.910332)
		(end 449.206874 -2.921)
		(stroke
			(width 0.05715)
			(type default)
		)
		(layer "In9.Cu")
	)
	(gr_line
		(start 449.212208 -11.07059)
		(end 449.43776 -11.115802)
		(stroke
			(width 0.05715)
			(type default)
		)
		(layer "In9.Cu")
	)
	(gr_line
		(start 449.241926 -8.83285)
		(end 449.242434 -8.833866)
		(stroke
			(width 0.05715)
			(type default)
		)
		(layer "In9.Cu")
	)
	(gr_line
		(start 449.24218 -8.833612)
		(end 449.263008 -8.884158)
		(stroke
			(width 0.05715)
			(type default)
		)
		(layer "In9.Cu")
	)
	(gr_line
		(start 449.251578 -8.93699)
		(end 449.263008 -8.884158)
		(stroke
			(width 0.05715)
			(type default)
		)
		(layer "In9.Cu")
	)
	(gr_line
		(start 449.307712 -62.653926)
		(end 449.61048 -62.956694)
		(stroke
			(width 0.050546)
			(type default)
		)
		(layer "In9.Cu")
	)
	(gr_line
		(start 449.327778 -16.202152)
		(end 449.367402 -16.191738)
		(stroke
			(width 0.05715)
			(type default)
		)
		(layer "In9.Cu")
	)
	(gr_line
		(start 449.367402 -16.191738)
		(end 449.406772 -16.202406)
		(stroke
			(width 0.05715)
			(type default)
		)
		(layer "In9.Cu")
	)
	(gr_line
		(start 449.446396 -15.513812)
		(end 449.490592 -15.502128)
		(stroke
			(width 0.05715)
			(type default)
		)
		(layer "In9.Cu")
	)
	(gr_line
		(start 449.490592 -15.502128)
		(end 449.490846 -15.502128)
		(stroke
			(width 0.05715)
			(type default)
		)
		(layer "In9.Cu")
	)
	(gr_line
		(start 449.490846 -15.502128)
		(end 449.53428 -15.515336)
		(stroke
			(width 0.05715)
			(type default)
		)
		(layer "In9.Cu")
	)
	(gr_line
		(start 449.61048 -62.956694)
		(end 449.914518 -62.956694)
		(stroke
			(width 0.050546)
			(type default)
		)
		(layer "In9.Cu")
	)
	(gr_line
		(start 449.640452 -18.852642)
		(end 449.659502 -18.848832)
		(stroke
			(width 0.05715)
			(type default)
		)
		(layer "In9.Cu")
	)
	(gr_line
		(start 449.659502 -18.848832)
		(end 449.675758 -18.838164)
		(stroke
			(width 0.05715)
			(type default)
		)
		(layer "In9.Cu")
	)
	(gr_line
		(start 449.698364 -9.227566)
		(end 449.702936 -9.250426)
		(stroke
			(width 0.05715)
			(type default)
		)
		(layer "In9.Cu")
	)
	(gr_line
		(start 449.698364 -9.227566)
		(end 449.70319 -9.204706)
		(stroke
			(width 0.05715)
			(type default)
		)
		(layer "In9.Cu")
	)
	(gr_line
		(start 449.727066 -62.232032)
		(end 449.797932 -62.232032)
		(stroke
			(width 0.050546)
			(type default)
		)
		(layer "In9.Cu")
	)
	(gr_line
		(start 449.914518 -62.956694)
		(end 450.217286 -62.653926)
		(stroke
			(width 0.050546)
			(type default)
		)
		(layer "In9.Cu")
	)
	(gr_line
		(start 449.920106 -11.148568)
		(end 449.989448 -11.10234)
		(stroke
			(width 0.05715)
			(type default)
		)
		(layer "In9.Cu")
	)
	(gr_line
		(start 449.989448 -11.10234)
		(end 450.005958 -11.020044)
		(stroke
			(width 0.05715)
			(type default)
		)
		(layer "In9.Cu")
	)
	(gr_line
		(start 450.035676 -15.973552)
		(end 450.091556 -15.99057)
		(stroke
			(width 0.05715)
			(type default)
		)
		(layer "In9.Cu")
	)
	(gr_line
		(start 450.091556 -15.99057)
		(end 450.146166 -15.970504)
		(stroke
			(width 0.05715)
			(type default)
		)
		(layer "In9.Cu")
	)
	(gr_line
		(start 450.159374 -4.816348)
		(end 450.26453 -4.86156)
		(stroke
			(width 0.05715)
			(type default)
		)
		(layer "In9.Cu")
	)
	(gr_line
		(start 450.176138 -10.167874)
		(end 450.180202 -10.147808)
		(stroke
			(width 0.05715)
			(type default)
		)
		(layer "In9.Cu")
	)
	(gr_line
		(start 450.176392 -10.128758)
		(end 450.180202 -10.147808)
		(stroke
			(width 0.05715)
			(type default)
		)
		(layer "In9.Cu")
	)
	(gr_line
		(start 450.1896 -16.714978)
		(end 450.239892 -16.72844)
		(stroke
			(width 0.05715)
			(type default)
		)
		(layer "In9.Cu")
	)
	(gr_line
		(start 450.19849 -20.237196)
		(end 450.284088 -20.219924)
		(stroke
			(width 0.05715)
			(type default)
		)
		(layer "In9.Cu")
	)
	(gr_line
		(start 450.239892 -16.72844)
		(end 450.240654 -16.730218)
		(stroke
			(width 0.05715)
			(type default)
		)
		(layer "In9.Cu")
	)
	(gr_line
		(start 450.240654 -16.730218)
		(end 450.294248 -16.71066)
		(stroke
			(width 0.05715)
			(type default)
		)
		(layer "In9.Cu")
	)
	(gr_line
		(start 450.264276 -4.86156)
		(end 450.26453 -4.86156)
		(stroke
			(width 0.05715)
			(type default)
		)
		(layer "In9.Cu")
	)
	(gr_line
		(start 450.264276 -4.86156)
		(end 450.287898 -4.97205)
		(stroke
			(width 0.05715)
			(type default)
		)
		(layer "In9.Cu")
	)
	(gr_line
		(start 450.284088 -20.219924)
		(end 450.330824 -20.146518)
		(stroke
			(width 0.05715)
			(type default)
		)
		(layer "In9.Cu")
	)
	(gr_line
		(start 450.372734 -9.170162)
		(end 450.377306 -9.193022)
		(stroke
			(width 0.05715)
			(type default)
		)
		(layer "In9.Cu")
	)
	(gr_line
		(start 450.372734 -9.170162)
		(end 450.37756 -9.147302)
		(stroke
			(width 0.05715)
			(type default)
		)
		(layer "In9.Cu")
	)
	(gr_line
		(start 450.527674 -11.56462)
		(end 450.597016 -11.518392)
		(stroke
			(width 0.05715)
			(type default)
		)
		(layer "In9.Cu")
	)
	(gr_line
		(start 450.558408 -15.821406)
		(end 450.585332 -15.8115)
		(stroke
			(width 0.05715)
			(type default)
		)
		(layer "In9.Cu")
	)
	(gr_line
		(start 450.585332 -15.8115)
		(end 450.605144 -15.791434)
		(stroke
			(width 0.05715)
			(type default)
		)
		(layer "In9.Cu")
	)
	(gr_line
		(start 450.58965 -6.438392)
		(end 450.59473 -6.41477)
		(stroke
			(width 0.05715)
			(type default)
		)
		(layer "In9.Cu")
	)
	(gr_line
		(start 450.58965 -6.391402)
		(end 450.59473 -6.41477)
		(stroke
			(width 0.05715)
			(type default)
		)
		(layer "In9.Cu")
	)
	(gr_line
		(start 450.597016 -11.518392)
		(end 450.613526 -11.436096)
		(stroke
			(width 0.05715)
			(type default)
		)
		(layer "In9.Cu")
	)
	(gr_line
		(start 450.614542 -17.432528)
		(end 450.66458 -17.657318)
		(stroke
			(width 0.05715)
			(type default)
		)
		(layer "In9.Cu")
	)
	(gr_line
		(start 450.614542 -17.432528)
		(end 450.798692 -17.143222)
		(stroke
			(width 0.05715)
			(type default)
		)
		(layer "In9.Cu")
	)
	(gr_line
		(start 450.67347 -18.172938)
		(end 450.694806 -18.158714)
		(stroke
			(width 0.05715)
			(type default)
		)
		(layer "In9.Cu")
	)
	(gr_line
		(start 450.694806 -18.158714)
		(end 450.708014 -18.137886)
		(stroke
			(width 0.05715)
			(type default)
		)
		(layer "In9.Cu")
	)
	(gr_line
		(start 450.727572 -4.337558)
		(end 450.831458 -4.382262)
		(stroke
			(width 0.05715)
			(type default)
		)
		(layer "In9.Cu")
	)
	(gr_line
		(start 450.798692 -17.143222)
		(end 451.023482 -17.093184)
		(stroke
			(width 0.05715)
			(type default)
		)
		(layer "In9.Cu")
	)
	(gr_line
		(start 450.831458 -4.382262)
		(end 450.85508 -4.492752)
		(stroke
			(width 0.05715)
			(type default)
		)
		(layer "In9.Cu")
	)
	(gr_line
		(start 450.838316 -16.513302)
		(end 450.864732 -16.50365)
		(stroke
			(width 0.05715)
			(type default)
		)
		(layer "In9.Cu")
	)
	(gr_line
		(start 450.864478 -10.179812)
		(end 450.868542 -10.159746)
		(stroke
			(width 0.05715)
			(type default)
		)
		(layer "In9.Cu")
	)
	(gr_line
		(start 450.864732 -16.50365)
		(end 450.884544 -16.483838)
		(stroke
			(width 0.05715)
			(type default)
		)
		(layer "In9.Cu")
	)
	(gr_line
		(start 450.864732 -10.140696)
		(end 450.868542 -10.159746)
		(stroke
			(width 0.05715)
			(type default)
		)
		(layer "In9.Cu")
	)
	(gr_line
		(start 450.91731 -12.29868)
		(end 450.988684 -12.634214)
		(stroke
			(width 0.05715)
			(type default)
		)
		(layer "In9.Cu")
	)
	(gr_line
		(start 450.91731 -12.29868)
		(end 451.042786 -12.10564)
		(stroke
			(width 0.05715)
			(type default)
		)
		(layer "In9.Cu")
	)
	(gr_line
		(start 450.932042 -17.785334)
		(end 451.253606 -17.280382)
		(stroke
			(width 0.05715)
			(type default)
		)
		(layer "In9.Cu")
	)
	(gr_line
		(start 450.97319 -11.767566)
		(end 450.977762 -11.744706)
		(stroke
			(width 0.05715)
			(type default)
		)
		(layer "In9.Cu")
	)
	(gr_line
		(start 450.97319 -11.767566)
		(end 450.978016 -11.790172)
		(stroke
			(width 0.05715)
			(type default)
		)
		(layer "In9.Cu")
	)
	(gr_line
		(start 450.988684 -12.634214)
		(end 451.181724 -12.759436)
		(stroke
			(width 0.05715)
			(type default)
		)
		(layer "In9.Cu")
	)
	(gr_line
		(start 451.038214 -9.154414)
		(end 451.043294 -9.177782)
		(stroke
			(width 0.05715)
			(type default)
		)
		(layer "In9.Cu")
	)
	(gr_line
		(start 451.038214 -9.154414)
		(end 451.043294 -9.1313)
		(stroke
			(width 0.05715)
			(type default)
		)
		(layer "In9.Cu")
	)
	(gr_line
		(start 451.255384 -6.417818)
		(end 451.260464 -6.394196)
		(stroke
			(width 0.05715)
			(type default)
		)
		(layer "In9.Cu")
	)
	(gr_line
		(start 451.255384 -6.370828)
		(end 451.260464 -6.394196)
		(stroke
			(width 0.05715)
			(type default)
		)
		(layer "In9.Cu")
	)
	(gr_line
		(start 451.292722 -3.88239)
		(end 451.393052 -3.928618)
		(stroke
			(width 0.05715)
			(type default)
		)
		(layer "In9.Cu")
	)
	(gr_line
		(start 451.338442 -12.08024)
		(end 451.46214 -12.662662)
		(stroke
			(width 0.05715)
			(type default)
		)
		(layer "In9.Cu")
	)
	(gr_line
		(start 451.375272 -2.765806)
		(end 451.420484 -2.785618)
		(stroke
			(width 0.05715)
			(type default)
		)
		(layer "In9.Cu")
	)
	(gr_line
		(start 451.393052 -3.928618)
		(end 451.415912 -4.036314)
		(stroke
			(width 0.05715)
			(type default)
		)
		(layer "In9.Cu")
	)
	(gr_line
		(start 451.420484 -2.785618)
		(end 451.447916 -2.826766)
		(stroke
			(width 0.05715)
			(type default)
		)
		(layer "In9.Cu")
	)
	(gr_line
		(start 451.56755 -10.239502)
		(end 451.572376 -10.262108)
		(stroke
			(width 0.05715)
			(type default)
		)
		(layer "In9.Cu")
	)
	(gr_line
		(start 451.567804 -10.284968)
		(end 451.572376 -10.262108)
		(stroke
			(width 0.05715)
			(type default)
		)
		(layer "In9.Cu")
	)
	(gr_line
		(start 451.69582 -12.0523)
		(end 451.7009 -12.075922)
		(stroke
			(width 0.05715)
			(type default)
		)
		(layer "In9.Cu")
	)
	(gr_line
		(start 451.69582 -12.0523)
		(end 451.7009 -12.029186)
		(stroke
			(width 0.05715)
			(type default)
		)
		(layer "In9.Cu")
	)
	(gr_line
		(start 451.741794 -14.270228)
		(end 451.789038 -14.199108)
		(stroke
			(width 0.05715)
			(type default)
		)
		(layer "In9.Cu")
	)
	(gr_line
		(start 451.771258 -14.115796)
		(end 451.789038 -14.199108)
		(stroke
			(width 0.05715)
			(type default)
		)
		(layer "In9.Cu")
	)
	(gr_line
		(start 451.82663 -2.234438)
		(end 451.871842 -2.25425)
		(stroke
			(width 0.05715)
			(type default)
		)
		(layer "In9.Cu")
	)
	(gr_line
		(start 451.88632 -11.156442)
		(end 451.89013 -11.138662)
		(stroke
			(width 0.05715)
			(type default)
		)
		(layer "In9.Cu")
	)
	(gr_line
		(start 451.89013 -11.138662)
		(end 451.90029 -11.123422)
		(stroke
			(width 0.05715)
			(type default)
		)
		(layer "In9.Cu")
	)
	(gr_line
		(start 451.914514 -6.433058)
		(end 451.919594 -6.409944)
		(stroke
			(width 0.05715)
			(type default)
		)
		(layer "In9.Cu")
	)
	(gr_line
		(start 451.914514 -6.386576)
		(end 451.919594 -6.409944)
		(stroke
			(width 0.05715)
			(type default)
		)
		(layer "In9.Cu")
	)
	(gr_line
		(start 452.163688 -5.11302)
		(end 452.167498 -5.13207)
		(stroke
			(width 0.05715)
			(type default)
		)
		(layer "In9.Cu")
	)
	(gr_line
		(start 452.167498 -5.13207)
		(end 452.178674 -5.148834)
		(stroke
			(width 0.05715)
			(type default)
		)
		(layer "In9.Cu")
	)
	(gr_line
		(start 452.218298 -3.982212)
		(end 452.228966 -3.998214)
		(stroke
			(width 0.05715)
			(type default)
		)
		(layer "In9.Cu")
	)
	(gr_line
		(start 452.228966 -3.998214)
		(end 452.23303 -4.017264)
		(stroke
			(width 0.05715)
			(type default)
		)
		(layer "In9.Cu")
	)
	(gr_line
		(start 452.297546 -1.734312)
		(end 452.341234 -1.753616)
		(stroke
			(width 0.05715)
			(type default)
		)
		(layer "In9.Cu")
	)
	(gr_line
		(start 452.341234 -1.753616)
		(end 452.367904 -1.793494)
		(stroke
			(width 0.05715)
			(type default)
		)
		(layer "In9.Cu")
	)
	(gr_line
		(start 452.396606 -12.29106)
		(end 452.401178 -12.268454)
		(stroke
			(width 0.05715)
			(type default)
		)
		(layer "In9.Cu")
	)
	(gr_line
		(start 452.396606 -12.29106)
		(end 452.401432 -12.314174)
		(stroke
			(width 0.05715)
			(type default)
		)
		(layer "In9.Cu")
	)
	(gr_line
		(start 452.401432 -12.31392)
		(end 452.401432 -12.314174)
		(stroke
			(width 0.05715)
			(type default)
		)
		(layer "In9.Cu")
	)
	(gr_line
		(start 452.435468 -14.400022)
		(end 452.47941 -14.330934)
		(stroke
			(width 0.05715)
			(type default)
		)
		(layer "In9.Cu")
	)
	(gr_line
		(start 452.462392 -14.251178)
		(end 452.47941 -14.330934)
		(stroke
			(width 0.05715)
			(type default)
		)
		(layer "In9.Cu")
	)
	(gr_line
		(start 452.571612 -11.414252)
		(end 452.575422 -11.394186)
		(stroke
			(width 0.05715)
			(type default)
		)
		(layer "In9.Cu")
	)
	(gr_line
		(start 452.575422 -11.394186)
		(end 452.587106 -11.376406)
		(stroke
			(width 0.05715)
			(type default)
		)
		(layer "In9.Cu")
	)
	(gr_line
		(start 452.725536 -5.968746)
		(end 452.737728 -5.987034)
		(stroke
			(width 0.05715)
			(type default)
		)
		(layer "In9.Cu")
	)
	(gr_line
		(start 452.737728 -5.987034)
		(end 452.756016 -5.999226)
		(stroke
			(width 0.05715)
			(type default)
		)
		(layer "In9.Cu")
	)
	(gr_line
		(start 452.788528 -4.156456)
		(end 452.80072 -4.174744)
		(stroke
			(width 0.05715)
			(type default)
		)
		(layer "In9.Cu")
	)
	(gr_line
		(start 452.80072 -4.174744)
		(end 452.819008 -4.186936)
		(stroke
			(width 0.05715)
			(type default)
		)
		(layer "In9.Cu")
	)
	(gr_line
		(start 453.061324 -9.914636)
		(end 453.071484 -9.899396)
		(stroke
			(width 0.05715)
			(type default)
		)
		(layer "In9.Cu")
	)
	(gr_line
		(start 453.071484 -9.899396)
		(end 453.075294 -9.881616)
		(stroke
			(width 0.05715)
			(type default)
		)
		(layer "In9.Cu")
	)
	(gr_line
		(start 453.121522 -14.571726)
		(end 453.165464 -14.502638)
		(stroke
			(width 0.05715)
			(type default)
		)
		(layer "In9.Cu")
	)
	(gr_line
		(start 453.148446 -14.42339)
		(end 453.165464 -14.502638)
		(stroke
			(width 0.05715)
			(type default)
		)
		(layer "In9.Cu")
	)
	(gr_line
		(start 453.284844 -3.698748)
		(end 453.296274 -3.715766)
		(stroke
			(width 0.05715)
			(type default)
		)
		(layer "In9.Cu")
	)
	(gr_line
		(start 453.296274 -3.715766)
		(end 453.31253 -3.726434)
		(stroke
			(width 0.05715)
			(type default)
		)
		(layer "In9.Cu")
	)
	(gr_line
		(start 453.426576 -6.095492)
		(end 453.443594 -6.106922)
		(stroke
			(width 0.05715)
			(type default)
		)
		(layer "In9.Cu")
	)
	(gr_line
		(start 453.443594 -6.106922)
		(end 453.455024 -6.12394)
		(stroke
			(width 0.05715)
			(type default)
		)
		(layer "In9.Cu")
	)
	(gr_line
		(start 453.715882 -10.210546)
		(end 453.72655 -10.19429)
		(stroke
			(width 0.05715)
			(type default)
		)
		(layer "In9.Cu")
	)
	(gr_line
		(start 453.72528 -6.529324)
		(end 453.772778 -6.600952)
		(stroke
			(width 0.05715)
			(type default)
		)
		(layer "In9.Cu")
	)
	(gr_line
		(start 453.72655 -10.193782)
		(end 453.72655 -10.19429)
		(stroke
			(width 0.05715)
			(type default)
		)
		(layer "In9.Cu")
	)
	(gr_line
		(start 453.72655 -10.193782)
		(end 453.730106 -10.177018)
		(stroke
			(width 0.05715)
			(type default)
		)
		(layer "In9.Cu")
	)
	(gr_line
		(start 453.754998 -6.683756)
		(end 453.772778 -6.600952)
		(stroke
			(width 0.05715)
			(type default)
		)
		(layer "In9.Cu")
	)
	(gr_line
		(start 454.039224 -14.316964)
		(end 454.048114 -14.302994)
		(stroke
			(width 0.05715)
			(type default)
		)
		(layer "In9.Cu")
	)
	(gr_line
		(start 454.048114 -14.302994)
		(end 454.051416 -14.286738)
		(stroke
			(width 0.05715)
			(type default)
		)
		(layer "In9.Cu")
	)
	(gr_line
		(start 454.061322 -12.74826)
		(end 454.065132 -12.72921)
		(stroke
			(width 0.05715)
			(type default)
		)
		(layer "In9.Cu")
	)
	(gr_line
		(start 454.065132 -12.72921)
		(end 454.0758 -12.712954)
		(stroke
			(width 0.05715)
			(type default)
		)
		(layer "In9.Cu")
	)
	(gr_line
		(start 454.209404 -12.21486)
		(end 454.254616 -12.440412)
		(stroke
			(width 0.05715)
			(type default)
		)
		(layer "In9.Cu")
	)
	(gr_line
		(start 454.209404 -12.21486)
		(end 454.39965 -11.929618)
		(stroke
			(width 0.05715)
			(type default)
		)
		(layer "In9.Cu")
	)
	(gr_line
		(start 454.22566 -6.44144)
		(end 454.229216 -6.424676)
		(stroke
			(width 0.05715)
			(type default)
		)
		(layer "In9.Cu")
	)
	(gr_line
		(start 454.229216 -6.424676)
		(end 454.238868 -6.409944)
		(stroke
			(width 0.05715)
			(type default)
		)
		(layer "In9.Cu")
	)
	(gr_line
		(start 454.39965 -11.929618)
		(end 454.625202 -11.88466)
		(stroke
			(width 0.05715)
			(type default)
		)
		(layer "In9.Cu")
	)
	(gr_line
		(start 454.5203 -12.573)
		(end 454.850246 -12.0777)
		(stroke
			(width 0.05715)
			(type default)
		)
		(layer "In9.Cu")
	)
	(gr_line
		(start 454.66381 -5.065776)
		(end 454.73366 -5.112512)
		(stroke
			(width 0.05715)
			(type default)
		)
		(layer "In9.Cu")
	)
	(gr_line
		(start 454.724262 -6.20903)
		(end 454.735946 -6.191504)
		(stroke
			(width 0.05715)
			(type default)
		)
		(layer "In9.Cu")
	)
	(gr_line
		(start 454.73366 -5.112512)
		(end 454.75017 -5.194808)
		(stroke
			(width 0.05715)
			(type default)
		)
		(layer "In9.Cu")
	)
	(gr_line
		(start 454.735946 -6.191504)
		(end 454.74001 -6.171184)
		(stroke
			(width 0.05715)
			(type default)
		)
		(layer "In9.Cu")
	)
	(gr_line
		(start 454.838308 -5.677154)
		(end 454.842372 -5.657088)
		(stroke
			(width 0.05715)
			(type default)
		)
		(layer "In9.Cu")
	)
	(gr_line
		(start 454.838562 -5.638038)
		(end 454.842372 -5.657088)
		(stroke
			(width 0.05715)
			(type default)
		)
		(layer "In9.Cu")
	)
	(gr_line
		(start 455.46264 -4.80822)
		(end 455.480674 -4.820412)
		(stroke
			(width 0.05715)
			(type default)
		)
		(layer "In9.Cu")
	)
	(gr_line
		(start 455.480674 -4.820412)
		(end 455.492866 -4.8387)
		(stroke
			(width 0.05715)
			(type default)
		)
		(layer "In9.Cu")
	)
	(gr_line
		(start 455.519536 -63.626492)
		(end 455.856086 -63.289942)
		(stroke
			(width 0.050546)
			(type default)
		)
		(layer "In9.Cu")
	)
	(gr_line
		(start 455.678286 -10.308844)
		(end 455.724514 -10.239502)
		(stroke
			(width 0.05715)
			(type default)
		)
		(layer "In9.Cu")
	)
	(gr_line
		(start 455.724514 -10.239502)
		(end 455.80681 -10.222992)
		(stroke
			(width 0.05715)
			(type default)
		)
		(layer "In9.Cu")
	)
	(gr_line
		(start 456.414632 -7.044944)
		(end 456.45959 -6.819392)
		(stroke
			(width 0.05715)
			(type default)
		)
		(layer "In9.Cu")
	)
	(gr_line
		(start 456.414632 -7.044944)
		(end 456.604878 -7.330186)
		(stroke
			(width 0.05715)
			(type default)
		)
		(layer "In9.Cu")
	)
	(gr_line
		(start 456.452986 -63.289942)
		(end 456.789536 -63.626492)
		(stroke
			(width 0.050546)
			(type default)
		)
		(layer "In9.Cu")
	)
	(gr_line
		(start 456.604878 -7.330186)
		(end 456.830684 -7.375652)
		(stroke
			(width 0.05715)
			(type default)
		)
		(layer "In9.Cu")
	)
	(gr_line
		(start 456.724258 -6.685026)
		(end 457.056998 -7.183882)
		(stroke
			(width 0.05715)
			(type default)
		)
		(layer "In9.Cu")
	)
	(gr_line
		(start 457.097384 -8.068818)
		(end 457.142342 -7.843012)
		(stroke
			(width 0.05715)
			(type default)
		)
		(layer "In9.Cu")
	)
	(gr_line
		(start 457.097384 -8.068818)
		(end 457.28763 -8.35406)
		(stroke
			(width 0.05715)
			(type default)
		)
		(layer "In9.Cu")
	)
	(gr_line
		(start 457.21524 -10.239502)
		(end 457.297536 -10.222992)
		(stroke
			(width 0.05715)
			(type default)
		)
		(layer "In9.Cu")
	)
	(gr_line
		(start 457.28763 -8.35406)
		(end 457.513436 -8.399272)
		(stroke
			(width 0.05715)
			(type default)
		)
		(layer "In9.Cu")
	)
	(gr_line
		(start 457.297536 -10.222992)
		(end 457.343764 -10.15365)
		(stroke
			(width 0.05715)
			(type default)
		)
		(layer "In9.Cu")
	)
	(gr_line
		(start 457.40701 -7.708646)
		(end 457.739496 -8.207248)
		(stroke
			(width 0.05715)
			(type default)
		)
		(layer "In9.Cu")
	)
	(gr_line
		(start 457.941934 -9.256268)
		(end 457.952602 -9.240012)
		(stroke
			(width 0.05715)
			(type default)
		)
		(layer "In9.Cu")
	)
	(gr_line
		(start 457.952602 -9.240012)
		(end 457.956412 -9.220962)
		(stroke
			(width 0.05715)
			(type default)
		)
		(layer "In9.Cu")
	)
	(gr_line
		(start 458.015848 -8.621522)
		(end 458.062584 -8.691626)
		(stroke
			(width 0.05715)
			(type default)
		)
		(layer "In9.Cu")
	)
	(gr_line
		(start 458.046074 -8.773668)
		(end 458.062584 -8.691626)
		(stroke
			(width 0.05715)
			(type default)
		)
		(layer "In9.Cu")
	)
	(gr_line
		(start 469.015318 -64.389)
		(end 469.244934 -64.389)
		(stroke
			(width 0.05715)
			(type default)
		)
		(layer "In9.Cu")
	)
	(gr_line
		(start 469.244934 -64.389)
		(end 469.291162 -64.342772)
		(stroke
			(width 0.05715)
			(type default)
		)
		(layer "In9.Cu")
	)
	(gr_line
		(start 469.707976 -64.342772)
		(end 469.754204 -64.389)
		(stroke
			(width 0.05715)
			(type default)
		)
		(layer "In9.Cu")
	)
	(gr_line
		(start 469.754204 -64.389)
		(end 469.95588 -64.389)
		(stroke
			(width 0.05715)
			(type default)
		)
		(layer "In9.Cu")
	)
	(gr_line
		(start 471.09888 -64.4398)
		(end 471.36558 -64.4398)
		(stroke
			(width 0.05715)
			(type default)
		)
		(layer "In9.Cu")
	)
	(gr_line
		(start 471.36558 -64.4398)
		(end 471.39225 -64.46647)
		(stroke
			(width 0.05715)
			(type default)
		)
		(layer "In9.Cu")
	)
	(gr_line
		(start 471.80881 -64.46647)
		(end 471.83548 -64.4398)
		(stroke
			(width 0.05715)
			(type default)
		)
		(layer "In9.Cu")
	)
	(gr_line
		(start 471.83548 -64.4398)
		(end 472.03868 -64.4398)
		(stroke
			(width 0.05715)
			(type default)
		)
		(layer "In9.Cu")
	)
	(gr_line
		(start 475.021656 -3.60299)
		(end 475.275402 -3.349244)
		(stroke
			(width 0.050546)
			(type default)
		)
		(layer "In9.Cu")
	)
	(gr_line
		(start 482.43617 3.977894)
		(end 482.665024 3.74904)
		(stroke
			(width 0.050546)
			(type default)
		)
		(layer "In9.Cu")
	)
	(gr_line
		(start 482.43617 4.57454)
		(end 482.665024 4.803394)
		(stroke
			(width 0.050546)
			(type default)
		)
		(layer "In9.Cu")
	)
	(gr_line
		(start 1.1684 -67.0052)
		(end 2.8702 -68.707)
		(stroke
			(width 1.27)
			(type default)
		)
		(layer "In10.Cu")
	)
	(gr_line
		(start 1.1684 -60.1218)
		(end 1.1684 -67.0052)
		(stroke
			(width 1.27)
			(type default)
		)
		(layer "In10.Cu")
	)
	(gr_line
		(start 2.4384 -58.8518)
		(end 1.1684 -60.1218)
		(stroke
			(width 1.27)
			(type default)
		)
		(layer "In10.Cu")
	)
	(gr_line
		(start 2.4384 -50.0634)
		(end 2.4384 -58.8518)
		(stroke
			(width 1.27)
			(type default)
		)
		(layer "In10.Cu")
	)
	(gr_line
		(start 2.8702 -85.8266)
		(end 3.8608 -86.8172)
		(stroke
			(width 1.27)
			(type default)
		)
		(layer "In10.Cu")
	)
	(gr_line
		(start 2.8702 -68.707)
		(end 2.8702 -85.8266)
		(stroke
			(width 1.27)
			(type default)
		)
		(layer "In10.Cu")
	)
	(gr_line
		(start 3.0988 -49.403)
		(end 2.4384 -50.0634)
		(stroke
			(width 1.27)
			(type default)
		)
		(layer "In10.Cu")
	)
	(gr_line
		(start 3.8608 -86.8172)
		(end 10.107422 -86.8172)
		(stroke
			(width 1.27)
			(type default)
		)
		(layer "In10.Cu")
	)
	(gr_line
		(start 9.72185 -49.403)
		(end 3.0988 -49.403)
		(stroke
			(width 1.27)
			(type default)
		)
		(layer "In10.Cu")
	)
	(gr_line
		(start 10.107422 -86.8172)
		(end 10.727436 -86.197186)
		(stroke
			(width 1.27)
			(type default)
		)
		(layer "In10.Cu")
	)
	(gr_line
		(start 10.727436 -86.197186)
		(end 10.727436 -50.408586)
		(stroke
			(width 1.27)
			(type default)
		)
		(layer "In10.Cu")
	)
	(gr_line
		(start 10.727436 -50.408586)
		(end 9.72185 -49.403)
		(stroke
			(width 1.27)
			(type default)
		)
		(layer "In10.Cu")
	)
	(gr_line
		(start 429.82007 -137.109454)
		(end 431.09007 -137.109454)
		(stroke
			(width 0.2)
			(type default)
		)
		(layer "In10.Cu")
	)
	(gr_arc
		(start 429.82007 -135.580374)
		(mid 429.05553 -136.344914)
		(end 429.82007 -137.109454)
		(stroke
			(width 0.2)
			(type default)
		)
		(layer "In10.Cu")
	)
	(gr_arc
		(start 431.09007 -137.109454)
		(mid 431.629783 -136.886423)
		(end 431.85461 -136.347454)
		(stroke
			(width 0.2)
			(type default)
		)
		(layer "In10.Cu")
	)
	(gr_line
		(start 431.09007 -135.580374)
		(end 429.82007 -135.580374)
		(stroke
			(width 0.2)
			(type default)
		)
		(layer "In10.Cu")
	)
	(gr_line
		(start 431.666142 -136.347454)
		(end 431.666142 -136.344914)
		(stroke
			(width 0.2)
			(type default)
		)
		(layer "In10.Cu")
	)
	(gr_line
		(start 431.666142 -136.344914)
		(end 431.85461 -136.344914)
		(stroke
			(width 0.2)
			(type default)
		)
		(layer "In10.Cu")
	)
	(gr_line
		(start 431.85461 -136.347454)
		(end 431.666142 -136.347454)
		(stroke
			(width 0.2)
			(type default)
		)
		(layer "In10.Cu")
	)
	(gr_arc
		(start 431.85461 -136.344914)
		(mid 431.630681 -135.804303)
		(end 431.09007 -135.580374)
		(stroke
			(width 0.2)
			(type default)
		)
		(layer "In10.Cu")
	)
	(gr_line
		(start 433.63007 -137.109454)
		(end 434.90007 -137.109454)
		(stroke
			(width 0.2)
			(type default)
		)
		(layer "In10.Cu")
	)
	(gr_arc
		(start 433.63007 -135.580374)
		(mid 432.86553 -136.344914)
		(end 433.63007 -137.109454)
		(stroke
			(width 0.2)
			(type default)
		)
		(layer "In10.Cu")
	)
	(gr_arc
		(start 434.90007 -137.109454)
		(mid 435.439783 -136.886423)
		(end 435.66461 -136.347454)
		(stroke
			(width 0.2)
			(type default)
		)
		(layer "In10.Cu")
	)
	(gr_line
		(start 434.90007 -135.580374)
		(end 433.63007 -135.580374)
		(stroke
			(width 0.2)
			(type default)
		)
		(layer "In10.Cu")
	)
	(gr_line
		(start 435.473856 -136.347454)
		(end 435.473856 -136.344914)
		(stroke
			(width 0.2)
			(type default)
		)
		(layer "In10.Cu")
	)
	(gr_line
		(start 435.473856 -136.344914)
		(end 435.66461 -136.344914)
		(stroke
			(width 0.2)
			(type default)
		)
		(layer "In10.Cu")
	)
	(gr_line
		(start 435.66461 -136.347454)
		(end 435.473856 -136.347454)
		(stroke
			(width 0.2)
			(type default)
		)
		(layer "In10.Cu")
	)
	(gr_arc
		(start 435.66461 -136.344914)
		(mid 435.440681 -135.804303)
		(end 434.90007 -135.580374)
		(stroke
			(width 0.2)
			(type default)
		)
		(layer "In10.Cu")
	)
	(gr_line
		(start -3.899916 -27.71013)
		(end -3.55473 -27.71013)
		(stroke
			(width 0.05715)
			(type default)
		)
		(layer "In11.Cu")
	)
	(gr_line
		(start -3.55473 -27.71013)
		(end -3.41757 -27.57297)
		(stroke
			(width 0.05715)
			(type default)
		)
		(layer "In11.Cu")
	)
	(gr_line
		(start -3.000756 -27.57297)
		(end -2.863596 -27.71013)
		(stroke
			(width 0.05715)
			(type default)
		)
		(layer "In11.Cu")
	)
	(gr_line
		(start -2.863596 -27.71013)
		(end -2.500122 -27.71013)
		(stroke
			(width 0.05715)
			(type default)
		)
		(layer "In11.Cu")
	)
	(gr_poly
		(pts
			(xy 367.6396 -106.0196) (xy 364.9726 -106.0196) (xy 364.9726 -109.22) (xy 367.6396 -109.22)
		)
		(stroke
			(width 0)
			(type solid)
		)
		(fill yes)
		(layer "In11.Cu")
		(net "GND")
	)
	(gr_poly
		(pts
			(xy 368.2238 -96.2406) (xy 366.5982 -96.2406) (xy 366.5982 -100.9142) (xy 368.2238 -100.9142)
		)
		(stroke
			(width 0)
			(type solid)
		)
		(fill yes)
		(layer "In11.Cu")
		(net "GND")
	)
	(gr_poly
		(pts
			(xy 408.498548 -98.246946) (xy 405.88184 -98.246946) (xy 405.88184 -100.721414) (xy 408.498548 -100.721414)
		)
		(stroke
			(width 0)
			(type solid)
		)
		(fill yes)
		(layer "In11.Cu")
		(net "GND")
	)
	(gr_poly
		(pts
			(xy 475.5134 -40.0558) (xy 472.8718 -40.0558) (xy 472.8718 -43.307) (xy 475.5134 -43.307)
		)
		(stroke
			(width 0)
			(type solid)
		)
		(fill yes)
		(layer "In11.Cu")
		(net "GND")
	)
	(gr_poly
		(pts
			(xy 64.15024 -90.542364) (xy 64.06134 -90.349324) (xy 63.83274 -90.349324) (xy 63.74384 -90.542364)
			(xy 63.74384 -90.586814) (xy 64.15024 -90.586814)
		)
		(stroke
			(width 0)
			(type solid)
		)
		(fill yes)
		(layer "In11.Cu")
		(net "M_M_DQ<6>")
	)
	(gr_poly
		(pts
			(xy 64.191134 -92.116656) (xy 64.191134 -92.072206) (xy 63.784734 -92.072206) (xy 63.784734 -92.116656)
			(xy 63.873634 -92.309696) (xy 64.102234 -92.309696)
		)
		(stroke
			(width 0)
			(type solid)
		)
		(fill yes)
		(layer "In11.Cu")
		(net "M_M_DQ<3>")
	)
	(gr_poly
		(pts
			(xy 64.191134 -91.837764) (xy 64.102234 -91.644724) (xy 63.873634 -91.644724) (xy 63.784734 -91.837764)
			(xy 63.784734 -91.882214) (xy 64.191134 -91.882214)
		)
		(stroke
			(width 0)
			(type solid)
		)
		(fill yes)
		(layer "In11.Cu")
		(net "M_M_DQ<2>")
	)
	(gr_poly
		(pts
			(xy 64.22644 -90.821256) (xy 64.22644 -90.776806) (xy 63.82004 -90.776806) (xy 63.82004 -90.821256)
			(xy 63.90894 -91.014296) (xy 64.13754 -91.014296)
		)
		(stroke
			(width 0)
			(type solid)
		)
		(fill yes)
		(layer "In11.Cu")
		(net "M_M_DQ<7>")
	)
	(gr_poly
		(pts
			(xy 64.256412 -89.59723) (xy 64.25692 -89.552526) (xy 63.857886 -89.553034) (xy 63.857886 -89.59723)
			(xy 63.946786 -89.76741) (xy 64.167766 -89.76741)
		)
		(stroke
			(width 0)
			(type solid)
		)
		(fill yes)
		(layer "In11.Cu")
		(net "M_M_DQS_DP<0>")
	)
	(gr_poly
		(pts
			(xy 64.256412 -89.315798) (xy 64.167766 -89.145618) (xy 63.946786 -89.145618) (xy 63.857886 -89.315798)
			(xy 63.857886 -89.359994) (xy 64.25692 -89.360502)
		)
		(stroke
			(width 0)
			(type solid)
		)
		(fill yes)
		(layer "In11.Cu")
		(net "M_M_DQS_DN<0>")
	)
	(gr_poly
		(pts
			(xy 64.96685 -87.443056) (xy 64.96685 -87.398606) (xy 64.56045 -87.398606) (xy 64.56045 -87.443056)
			(xy 64.64935 -87.636096) (xy 64.87795 -87.636096)
		)
		(stroke
			(width 0)
			(type solid)
		)
		(fill yes)
		(layer "In11.Cu")
		(net "M_M_DQ<1>")
	)
	(gr_poly
		(pts
			(xy 65.058544 -95.076772) (xy 65.058798 -95.032322) (xy 64.652144 -95.032322) (xy 64.652398 -95.076772)
			(xy 64.741298 -95.269812) (xy 64.969644 -95.269812)
		)
		(stroke
			(width 0)
			(type solid)
		)
		(fill yes)
		(layer "In11.Cu")
		(net "M_M_DQ<9>")
	)
	(gr_poly
		(pts
			(xy 65.14084 -90.542364) (xy 65.05194 -90.349324) (xy 64.82334 -90.349324) (xy 64.73444 -90.542364)
			(xy 64.73444 -90.586814) (xy 65.14084 -90.586814)
		)
		(stroke
			(width 0)
			(type solid)
		)
		(fill yes)
		(layer "In11.Cu")
		(net "M_M_DQ<6>")
	)
	(gr_poly
		(pts
			(xy 65.181734 -92.116656) (xy 65.181734 -92.072206) (xy 64.775334 -92.072206) (xy 64.775334 -92.116656)
			(xy 64.864234 -92.309696) (xy 65.092834 -92.309696)
		)
		(stroke
			(width 0)
			(type solid)
		)
		(fill yes)
		(layer "In11.Cu")
		(net "M_M_DQ<3>")
	)
	(gr_poly
		(pts
			(xy 65.181734 -91.837764) (xy 65.092834 -91.644724) (xy 64.864234 -91.644724) (xy 64.775334 -91.837764)
			(xy 64.775334 -91.882214) (xy 65.181734 -91.882214)
		)
		(stroke
			(width 0)
			(type solid)
		)
		(fill yes)
		(layer "In11.Cu")
		(net "M_M_DQ<2>")
	)
	(gr_poly
		(pts
			(xy 65.19164 -97.468944) (xy 65.19164 -97.424494) (xy 64.78524 -97.424494) (xy 64.78524 -97.468944)
			(xy 64.87414 -97.661984) (xy 65.10274 -97.661984)
		)
		(stroke
			(width 0)
			(type solid)
		)
		(fill yes)
		(layer "In11.Cu")
		(net "M_M_DQS_DP<1>")
	)
	(gr_poly
		(pts
			(xy 65.19164 -97.189544) (xy 65.10274 -96.996504) (xy 64.87414 -96.996504) (xy 64.78524 -97.189544)
			(xy 64.78524 -97.233994) (xy 65.19164 -97.233994)
		)
		(stroke
			(width 0)
			(type solid)
		)
		(fill yes)
		(layer "In11.Cu")
		(net "M_M_DQS_DN<1>")
	)
	(gr_poly
		(pts
			(xy 65.21704 -90.821256) (xy 65.21704 -90.776806) (xy 64.81064 -90.776806) (xy 64.81064 -90.821256)
			(xy 64.89954 -91.014296) (xy 65.12814 -91.014296)
		)
		(stroke
			(width 0)
			(type solid)
		)
		(fill yes)
		(layer "In11.Cu")
		(net "M_M_DQ<7>")
	)
	(gr_poly
		(pts
			(xy 65.247012 -89.59723) (xy 65.24752 -89.552526) (xy 64.848486 -89.553034) (xy 64.848486 -89.59723)
			(xy 64.937386 -89.76741) (xy 65.158366 -89.76741)
		)
		(stroke
			(width 0)
			(type solid)
		)
		(fill yes)
		(layer "In11.Cu")
		(net "M_M_DQS_DP<0>")
	)
	(gr_poly
		(pts
			(xy 65.247012 -89.315798) (xy 65.158366 -89.145618) (xy 64.937386 -89.145618) (xy 64.848486 -89.315798)
			(xy 64.848486 -89.359994) (xy 65.24752 -89.360502)
		)
		(stroke
			(width 0)
			(type solid)
		)
		(fill yes)
		(layer "In11.Cu")
		(net "M_M_DQS_DN<0>")
	)
	(gr_poly
		(pts
			(xy 65.570354 -93.657928) (xy 65.570608 -93.613732) (xy 65.163954 -93.613732) (xy 65.163954 -93.657928)
			(xy 65.253108 -93.851222) (xy 65.481454 -93.851222)
		)
		(stroke
			(width 0)
			(type solid)
		)
		(fill yes)
		(layer "In11.Cu")
		(net "M_M_DQ<13>")
	)
	(gr_poly
		(pts
			(xy 65.83045 -87.443056) (xy 65.83045 -87.398606) (xy 65.42405 -87.398606) (xy 65.42405 -87.443056)
			(xy 65.51295 -87.636096) (xy 65.74155 -87.636096)
		)
		(stroke
			(width 0)
			(type solid)
		)
		(fill yes)
		(layer "In11.Cu")
		(net "M_M_DQ<1>")
	)
	(gr_poly
		(pts
			(xy 65.83045 -87.164164) (xy 65.74155 -86.971124) (xy 65.51295 -86.971124) (xy 65.42405 -87.164164)
			(xy 65.42405 -87.208614) (xy 65.83045 -87.208614)
		)
		(stroke
			(width 0)
			(type solid)
		)
		(fill yes)
		(layer "In11.Cu")
		(net "M_M_DQ<0>")
	)
	(gr_poly
		(pts
			(xy 65.846452 -98.974656) (xy 65.846452 -98.930206) (xy 65.440052 -98.930206) (xy 65.440052 -98.974656)
			(xy 65.528952 -99.167696) (xy 65.757552 -99.167696)
		)
		(stroke
			(width 0)
			(type solid)
		)
		(fill yes)
		(layer "In11.Cu")
		(net "M_M_DQ<15>")
	)
	(gr_poly
		(pts
			(xy 65.846452 -98.695764) (xy 65.757552 -98.502724) (xy 65.528952 -98.502724) (xy 65.440052 -98.695764)
			(xy 65.440052 -98.740214) (xy 65.846452 -98.740214)
		)
		(stroke
			(width 0)
			(type solid)
		)
		(fill yes)
		(layer "In11.Cu")
		(net "M_M_DQ<14>")
	)
	(gr_poly
		(pts
			(xy 65.970658 -94.387416) (xy 65.939162 -94.356174) (xy 65.739772 -94.282514) (xy 65.578228 -94.444058)
			(xy 65.651888 -94.643448) (xy 65.68313 -94.674944)
		)
		(stroke
			(width 0)
			(type solid)
		)
		(fill yes)
		(layer "In11.Cu")
		(net "M_M_DQ<8>")
	)
	(gr_poly
		(pts
			(xy 66.030094 -58.368184) (xy 65.941194 -58.175144) (xy 65.712594 -58.175144) (xy 65.623694 -58.368184)
			(xy 65.623694 -58.412634) (xy 66.030094 -58.412634)
		)
		(stroke
			(width 0)
			(type solid)
		)
		(fill yes)
		(layer "In11.Cu")
		(net "M_J_DQ<9>")
	)
	(gr_poly
		(pts
			(xy 66.03365 -58.647584) (xy 66.03365 -58.603134) (xy 65.627504 -58.603134) (xy 65.627504 -58.647584)
			(xy 65.71615 -58.840624) (xy 65.945004 -58.840624)
		)
		(stroke
			(width 0)
			(type solid)
		)
		(fill yes)
		(layer "In11.Cu")
		(net "M_J_DQ<8>")
	)
	(gr_poly
		(pts
			(xy 66.090546 -95.32366) (xy 66.05905 -95.292164) (xy 65.859914 -95.218504) (xy 65.698116 -95.380302)
			(xy 65.771776 -95.579438) (xy 65.803272 -95.610934)
		)
		(stroke
			(width 0)
			(type solid)
		)
		(fill yes)
		(layer "In11.Cu")
		(net "M_M_DQS_DP<10>")
	)
	(gr_poly
		(pts
			(xy 66.124582 -86.26983) (xy 66.212466 -86.099142) (xy 66.212466 -86.054692) (xy 65.813686 -86.056978)
			(xy 65.81394 -86.101174) (xy 65.903602 -86.270846)
		)
		(stroke
			(width 0)
			(type solid)
		)
		(fill yes)
		(layer "In11.Cu")
		(net "M_M_DQ<5>")
	)
	(gr_poly
		(pts
			(xy 66.13144 -90.542364) (xy 66.04254 -90.349324) (xy 65.81394 -90.349324) (xy 65.72504 -90.542364)
			(xy 65.72504 -90.586814) (xy 66.13144 -90.586814)
		)
		(stroke
			(width 0)
			(type solid)
		)
		(fill yes)
		(layer "In11.Cu")
		(net "M_M_DQ<6>")
	)
	(gr_poly
		(pts
			(xy 66.172334 -92.116656) (xy 66.172334 -92.072206) (xy 65.765934 -92.072206) (xy 65.765934 -92.116656)
			(xy 65.854834 -92.309696) (xy 66.083434 -92.309696)
		)
		(stroke
			(width 0)
			(type solid)
		)
		(fill yes)
		(layer "In11.Cu")
		(net "M_M_DQ<3>")
	)
	(gr_poly
		(pts
			(xy 66.172334 -91.837764) (xy 66.083434 -91.644724) (xy 65.854834 -91.644724) (xy 65.765934 -91.837764)
			(xy 65.765934 -91.882214) (xy 66.172334 -91.882214)
		)
		(stroke
			(width 0)
			(type solid)
		)
		(fill yes)
		(layer "In11.Cu")
		(net "M_M_DQ<2>")
	)
	(gr_poly
		(pts
			(xy 66.173604 -93.081602) (xy 66.142108 -93.05036) (xy 65.942718 -92.9767) (xy 65.781174 -93.138244)
			(xy 65.854834 -93.337634) (xy 65.886076 -93.36913)
		)
		(stroke
			(width 0)
			(type solid)
		)
		(fill yes)
		(layer "In11.Cu")
		(net "M_M_DQ<12>")
	)
	(gr_poly
		(pts
			(xy 66.18224 -97.468944) (xy 66.18224 -97.424494) (xy 65.77584 -97.424494) (xy 65.77584 -97.468944)
			(xy 65.86474 -97.661984) (xy 66.09334 -97.661984)
		)
		(stroke
			(width 0)
			(type solid)
		)
		(fill yes)
		(layer "In11.Cu")
		(net "M_M_DQS_DP<1>")
	)
	(gr_poly
		(pts
			(xy 66.18224 -97.189544) (xy 66.09334 -96.996504) (xy 65.86474 -96.996504) (xy 65.77584 -97.189544)
			(xy 65.77584 -97.233994) (xy 66.18224 -97.233994)
		)
		(stroke
			(width 0)
			(type solid)
		)
		(fill yes)
		(layer "In11.Cu")
		(net "M_M_DQS_DN<1>")
	)
	(gr_poly
		(pts
			(xy 66.20764 -90.821256) (xy 66.20764 -90.776806) (xy 65.80124 -90.776806) (xy 65.80124 -90.821256)
			(xy 65.89014 -91.014296) (xy 66.11874 -91.014296)
		)
		(stroke
			(width 0)
			(type solid)
		)
		(fill yes)
		(layer "In11.Cu")
		(net "M_M_DQ<7>")
	)
	(gr_poly
		(pts
			(xy 66.209926 -94.752668) (xy 66.136266 -94.553278) (xy 66.105024 -94.521782) (xy 65.817496 -94.80931)
			(xy 65.848992 -94.840552) (xy 66.048382 -94.914212)
		)
		(stroke
			(width 0)
			(type solid)
		)
		(fill yes)
		(layer "In11.Cu")
		(net "M_M_DQ<9>")
	)
	(gr_poly
		(pts
			(xy 66.237612 -89.59723) (xy 66.23812 -89.552526) (xy 65.839086 -89.553034) (xy 65.839086 -89.59723)
			(xy 65.927986 -89.76741) (xy 66.148966 -89.76741)
		)
		(stroke
			(width 0)
			(type solid)
		)
		(fill yes)
		(layer "In11.Cu")
		(net "M_M_DQS_DP<0>")
	)
	(gr_poly
		(pts
			(xy 66.237612 -89.315798) (xy 66.148966 -89.145618) (xy 65.927986 -89.145618) (xy 65.839086 -89.315798)
			(xy 65.839086 -89.359994) (xy 66.23812 -89.360502)
		)
		(stroke
			(width 0)
			(type solid)
		)
		(fill yes)
		(layer "In11.Cu")
		(net "M_M_DQS_DN<0>")
	)
	(gr_poly
		(pts
			(xy 66.330322 -95.689166) (xy 66.256662 -95.489776) (xy 66.22542 -95.45828) (xy 65.937892 -95.745808)
			(xy 65.969388 -95.77705) (xy 66.168778 -95.85071)
		)
		(stroke
			(width 0)
			(type solid)
		)
		(fill yes)
		(layer "In11.Cu")
		(net "M_M_DQS_DN<10>")
	)
	(gr_poly
		(pts
			(xy 66.412872 -93.446854) (xy 66.339212 -93.247464) (xy 66.30797 -93.215968) (xy 66.020442 -93.503496)
			(xy 66.051938 -93.534738) (xy 66.251328 -93.608398)
		)
		(stroke
			(width 0)
			(type solid)
		)
		(fill yes)
		(layer "In11.Cu")
		(net "M_M_DQ<13>")
	)
	(gr_poly
		(pts
			(xy 66.425572 -96.400366) (xy 66.381122 -96.400366) (xy 66.188082 -96.489266) (xy 66.188082 -96.717866)
			(xy 66.381122 -96.806766) (xy 66.425572 -96.806766)
		)
		(stroke
			(width 0)
			(type solid)
		)
		(fill yes)
		(layer "In11.Cu")
		(net "M_M_DQS_DN<1>")
	)
	(gr_poly
		(pts
			(xy 66.443098 -88.610186) (xy 66.443098 -88.565736) (xy 66.036698 -88.565736) (xy 66.036698 -88.610186)
			(xy 66.125598 -88.803226) (xy 66.354198 -88.803226)
		)
		(stroke
			(width 0)
			(type solid)
		)
		(fill yes)
		(layer "In11.Cu")
		(net "M_M_DQS_DN<9>")
	)
	(gr_poly
		(pts
			(xy 66.443098 -88.330786) (xy 66.354198 -88.137746) (xy 66.125598 -88.137746) (xy 66.036698 -88.330786)
			(xy 66.036698 -88.375236) (xy 66.443098 -88.375236)
		)
		(stroke
			(width 0)
			(type solid)
		)
		(fill yes)
		(layer "In11.Cu")
		(net "M_M_DQS_DP<9>")
	)
	(gr_poly
		(pts
			(xy 66.486786 -87.780114) (xy 66.518282 -87.748618) (xy 66.231008 -87.46109) (xy 66.199512 -87.492586)
			(xy 66.125852 -87.691976) (xy 66.28765 -87.85352)
		)
		(stroke
			(width 0)
			(type solid)
		)
		(fill yes)
		(layer "In11.Cu")
		(net "M_M_DQ<1>")
	)
	(gr_poly
		(pts
			(xy 66.660014 -57.21604) (xy 66.660014 -57.17159) (xy 66.253614 -57.17159) (xy 66.253614 -57.21604)
			(xy 66.342514 -57.40908) (xy 66.571114 -57.40908)
		)
		(stroke
			(width 0)
			(type solid)
		)
		(fill yes)
		(layer "In11.Cu")
		(net "M_J_DQS_DP<10>")
	)
	(gr_poly
		(pts
			(xy 66.660014 -56.93664) (xy 66.571114 -56.7436) (xy 66.342514 -56.7436) (xy 66.253614 -56.93664)
			(xy 66.253614 -56.98109) (xy 66.660014 -56.98109)
		)
		(stroke
			(width 0)
			(type solid)
		)
		(fill yes)
		(layer "In11.Cu")
		(net "M_J_DQS_DN<10>")
	)
	(gr_poly
		(pts
			(xy 66.66992 -56.201564) (xy 66.66992 -56.157114) (xy 66.26352 -56.157114) (xy 66.26352 -56.201564)
			(xy 66.35242 -56.394604) (xy 66.58102 -56.394604)
		)
		(stroke
			(width 0)
			(type solid)
		)
		(fill yes)
		(layer "In11.Cu")
		(net "M_J_DQS_DP<1>")
	)
	(gr_poly
		(pts
			(xy 66.66992 -55.922164) (xy 66.58102 -55.729124) (xy 66.35242 -55.729124) (xy 66.26352 -55.922164)
			(xy 66.26352 -55.966614) (xy 66.66992 -55.966614)
		)
		(stroke
			(width 0)
			(type solid)
		)
		(fill yes)
		(layer "In11.Cu")
		(net "M_J_DQS_DN<1>")
	)
	(gr_poly
		(pts
			(xy 66.67119 -93.686884) (xy 66.639694 -93.655642) (xy 66.440304 -93.581982) (xy 66.27876 -93.743526)
			(xy 66.35242 -93.942916) (xy 66.383662 -93.974412)
		)
		(stroke
			(width 0)
			(type solid)
		)
		(fill yes)
		(layer "In11.Cu")
		(net "M_M_DQ<8>")
	)
	(gr_poly
		(pts
			(xy 66.684144 -87.582756) (xy 66.757804 -87.383366) (xy 66.596006 -87.221822) (xy 66.396616 -87.295482)
			(xy 66.365374 -87.326978) (xy 66.652648 -87.614252)
		)
		(stroke
			(width 0)
			(type solid)
		)
		(fill yes)
		(layer "In11.Cu")
		(net "M_M_DQ<0>")
	)
	(gr_poly
		(pts
			(xy 66.721228 -86.132924) (xy 66.778378 -85.94979) (xy 66.622168 -85.793834) (xy 66.439034 -85.851238)
			(xy 66.407538 -85.882734) (xy 66.689986 -86.16442)
		)
		(stroke
			(width 0)
			(type solid)
		)
		(fill yes)
		(layer "In11.Cu")
		(net "M_M_DQ<4>")
	)
	(gr_poly
		(pts
			(xy 66.791078 -94.623128) (xy 66.759582 -94.591632) (xy 66.560192 -94.517972) (xy 66.398648 -94.67977)
			(xy 66.472308 -94.87916) (xy 66.503804 -94.910402)
		)
		(stroke
			(width 0)
			(type solid)
		)
		(fill yes)
		(layer "In11.Cu")
		(net "M_M_DQS_DP<10>")
	)
	(gr_poly
		(pts
			(xy 66.80835 -86.913974) (xy 66.839846 -86.882478) (xy 66.556128 -86.602062) (xy 66.52514 -86.633558)
			(xy 66.468498 -86.816946) (xy 66.62547 -86.972394)
		)
		(stroke
			(width 0)
			(type solid)
		)
		(fill yes)
		(layer "In11.Cu")
		(net "M_M_DQ<5>")
	)
	(gr_poly
		(pts
			(xy 66.81216 -65.14084) (xy 66.81216 -65.09639) (xy 66.40576 -65.09639) (xy 66.40576 -65.14084) (xy 66.49466 -65.33388)
			(xy 66.72326 -65.33388)
		)
		(stroke
			(width 0)
			(type solid)
		)
		(fill yes)
		(layer "In11.Cu")
		(net "M_J_DQS_DP<9>")
	)
	(gr_poly
		(pts
			(xy 66.81216 -64.86144) (xy 66.72326 -64.6684) (xy 66.49466 -64.6684) (xy 66.40576 -64.86144) (xy 66.40576 -64.90589)
			(xy 66.81216 -64.90589)
		)
		(stroke
			(width 0)
			(type solid)
		)
		(fill yes)
		(layer "In11.Cu")
		(net "M_J_DQS_DN<9>")
	)
	(gr_poly
		(pts
			(xy 66.837052 -98.974656) (xy 66.837052 -98.930206) (xy 66.430652 -98.930206) (xy 66.430652 -98.974656)
			(xy 66.519552 -99.167696) (xy 66.748152 -99.167696)
		)
		(stroke
			(width 0)
			(type solid)
		)
		(fill yes)
		(layer "In11.Cu")
		(net "M_M_DQ<15>")
	)
	(gr_poly
		(pts
			(xy 66.837052 -98.695764) (xy 66.748152 -98.502724) (xy 66.519552 -98.502724) (xy 66.430652 -98.695764)
			(xy 66.430652 -98.740214) (xy 66.837052 -98.740214)
		)
		(stroke
			(width 0)
			(type solid)
		)
		(fill yes)
		(layer "In11.Cu")
		(net "M_M_DQ<14>")
	)
	(gr_poly
		(pts
			(xy 66.85026 -60.011056) (xy 66.85026 -59.966606) (xy 66.44386 -59.966606) (xy 66.44386 -60.011056)
			(xy 66.53276 -60.204096) (xy 66.76136 -60.204096)
		)
		(stroke
			(width 0)
			(type solid)
		)
		(fill yes)
		(layer "In11.Cu")
		(net "M_J_DQ<12>")
	)
	(gr_poly
		(pts
			(xy 66.85026 -59.732164) (xy 66.76136 -59.539124) (xy 66.53276 -59.539124) (xy 66.44386 -59.732164)
			(xy 66.44386 -59.776614) (xy 66.85026 -59.776614)
		)
		(stroke
			(width 0)
			(type solid)
		)
		(fill yes)
		(layer "In11.Cu")
		(net "M_J_DQ<13>")
	)
	(gr_poly
		(pts
			(xy 66.853562 -96.717866) (xy 66.853562 -96.489266) (xy 66.660522 -96.400366) (xy 66.616072 -96.400366)
			(xy 66.616072 -96.806766) (xy 66.660522 -96.806766)
		)
		(stroke
			(width 0)
			(type solid)
		)
		(fill yes)
		(layer "In11.Cu")
		(net "M_M_DQS_DP<1>")
	)
	(gr_poly
		(pts
			(xy 66.874136 -92.38107) (xy 66.84264 -92.349828) (xy 66.64325 -92.276168) (xy 66.481706 -92.437712)
			(xy 66.555366 -92.637102) (xy 66.586608 -92.668598)
		)
		(stroke
			(width 0)
			(type solid)
		)
		(fill yes)
		(layer "In11.Cu")
		(net "M_M_DQ<12>")
	)
	(gr_poly
		(pts
			(xy 66.910458 -94.052136) (xy 66.836798 -93.852746) (xy 66.805556 -93.82125) (xy 66.518028 -94.108778)
			(xy 66.549524 -94.14002) (xy 66.748914 -94.21368)
		)
		(stroke
			(width 0)
			(type solid)
		)
		(fill yes)
		(layer "In11.Cu")
		(net "M_M_DQ<9>")
	)
	(gr_poly
		(pts
			(xy 67.020694 -58.368184) (xy 66.931794 -58.175144) (xy 66.703194 -58.175144) (xy 66.614294 -58.368184)
			(xy 66.614294 -58.412634) (xy 67.020694 -58.412634)
		)
		(stroke
			(width 0)
			(type solid)
		)
		(fill yes)
		(layer "In11.Cu")
		(net "M_J_DQ<9>")
	)
	(gr_poly
		(pts
			(xy 67.02425 -58.647584) (xy 67.02425 -58.603134) (xy 66.618104 -58.603134) (xy 66.618104 -58.647584)
			(xy 66.70675 -58.840624) (xy 66.935604 -58.840624)
		)
		(stroke
			(width 0)
			(type solid)
		)
		(fill yes)
		(layer "In11.Cu")
		(net "M_J_DQ<8>")
	)
	(gr_poly
		(pts
			(xy 67.030854 -94.988634) (xy 66.957194 -94.789244) (xy 66.925698 -94.758002) (xy 66.638424 -95.045276)
			(xy 66.66992 -95.076772) (xy 66.86931 -95.150432)
		)
		(stroke
			(width 0)
			(type solid)
		)
		(fill yes)
		(layer "In11.Cu")
		(net "M_M_DQS_DN<10>")
	)
	(gr_poly
		(pts
			(xy 67.11315 -95.43669) (xy 67.0814 -95.405448) (xy 66.881756 -95.332804) (xy 66.720974 -95.49511)
			(xy 66.795396 -95.693992) (xy 66.826892 -95.725488)
		)
		(stroke
			(width 0)
			(type solid)
		)
		(fill yes)
		(layer "In11.Cu")
		(net "M_M_DQS_DN<1>")
	)
	(gr_poly
		(pts
			(xy 67.113404 -92.746322) (xy 67.039744 -92.546932) (xy 67.008502 -92.515436) (xy 66.720974 -92.802964)
			(xy 66.75247 -92.834206) (xy 66.95186 -92.907866)
		)
		(stroke
			(width 0)
			(type solid)
		)
		(fill yes)
		(layer "In11.Cu")
		(net "M_M_DQ<13>")
	)
	(gr_poly
		(pts
			(xy 67.269868 -93.088206) (xy 67.238626 -93.05671) (xy 67.039236 -92.98305) (xy 66.877438 -93.144594)
			(xy 66.951098 -93.343984) (xy 66.982594 -93.37548)
		)
		(stroke
			(width 0)
			(type solid)
		)
		(fill yes)
		(layer "In11.Cu")
		(net "M_M_DQ<8>")
	)
	(gr_poly
		(pts
			(xy 67.289934 -91.664536) (xy 67.289934 -91.620086) (xy 66.883534 -91.620086) (xy 66.883534 -91.664536)
			(xy 66.972434 -91.857576) (xy 67.201034 -91.857576)
		)
		(stroke
			(width 0)
			(type solid)
		)
		(fill yes)
		(layer "In11.Cu")
		(net "M_M_DQ<3>")
	)
	(gr_poly
		(pts
			(xy 67.289934 -91.385644) (xy 67.201034 -91.192604) (xy 66.972434 -91.192604) (xy 66.883534 -91.385644)
			(xy 66.883534 -91.430094) (xy 67.289934 -91.430094)
		)
		(stroke
			(width 0)
			(type solid)
		)
		(fill yes)
		(layer "In11.Cu")
		(net "M_M_DQ<2>")
	)
	(gr_poly
		(pts
			(xy 67.296792 -97.980754) (xy 67.252342 -97.980754) (xy 67.059302 -98.069654) (xy 67.059302 -98.298254)
			(xy 67.252342 -98.387154) (xy 67.296792 -98.387154)
		)
		(stroke
			(width 0)
			(type solid)
		)
		(fill yes)
		(layer "In11.Cu")
		(net "M_M_DQ<14>")
	)
	(gr_poly
		(pts
			(xy 67.296792 -96.990154) (xy 67.252342 -96.990154) (xy 67.059302 -97.079054) (xy 67.059302 -97.307654)
			(xy 67.252342 -97.396554) (xy 67.296792 -97.396554)
		)
		(stroke
			(width 0)
			(type solid)
		)
		(fill yes)
		(layer "In11.Cu")
		(net "M_M_DQ<14>")
	)
	(gr_poly
		(pts
			(xy 67.35445 -95.80118) (xy 67.280028 -95.602298) (xy 67.248532 -95.570802) (xy 66.962274 -95.8596)
			(xy 66.99377 -95.890842) (xy 67.193668 -95.963486)
		)
		(stroke
			(width 0)
			(type solid)
		)
		(fill yes)
		(layer "In11.Cu")
		(net "M_M_DQS_DP<1>")
	)
	(gr_poly
		(pts
			(xy 67.361308 -100.346002) (xy 67.361308 -100.301552) (xy 66.954908 -100.301552) (xy 66.954908 -100.346002)
			(xy 67.043808 -100.539042) (xy 67.272408 -100.539042)
		)
		(stroke
			(width 0)
			(type solid)
		)
		(fill yes)
		(layer "In11.Cu")
		(net "M_M_DQ<11>")
	)
	(gr_poly
		(pts
			(xy 67.361308 -100.06711) (xy 67.272408 -99.87407) (xy 67.043808 -99.87407) (xy 66.954908 -100.06711)
			(xy 66.954908 -100.11156) (xy 67.361308 -100.11156)
		)
		(stroke
			(width 0)
			(type solid)
		)
		(fill yes)
		(layer "In11.Cu")
		(net "M_M_DQ<10>")
	)
	(gr_poly
		(pts
			(xy 67.50939 -93.453204) (xy 67.43573 -93.253814) (xy 67.404234 -93.222572) (xy 67.11696 -93.509846)
			(xy 67.148456 -93.541342) (xy 67.347846 -93.615002)
		)
		(stroke
			(width 0)
			(type solid)
		)
		(fill yes)
		(layer "In11.Cu")
		(net "M_M_DQ<9>")
	)
	(gr_poly
		(pts
			(xy 67.559174 -54.168548) (xy 67.59067 -54.137052) (xy 67.303396 -53.849778) (xy 67.2719 -53.881274)
			(xy 67.19824 -54.08041) (xy 67.360038 -54.242208)
		)
		(stroke
			(width 0)
			(type solid)
		)
		(fill yes)
		(layer "In11.Cu")
		(net "M_J_DQ<10>")
	)
	(gr_poly
		(pts
			(xy 67.656456 -96.04375) (xy 67.62496 -96.012508) (xy 67.42557 -95.938848) (xy 67.264026 -96.100392)
			(xy 67.337686 -96.299782) (xy 67.368928 -96.331278)
		)
		(stroke
			(width 0)
			(type solid)
		)
		(fill yes)
		(layer "In11.Cu")
		(net "M_M_DQ<14>")
	)
	(gr_poly
		(pts
			(xy 67.662298 -62.173358) (xy 67.651122 -61.981588) (xy 67.628008 -61.943488) (xy 67.286378 -62.149228)
			(xy 67.309238 -62.187328) (xy 67.473068 -62.28715)
		)
		(stroke
			(width 0)
			(type solid)
		)
		(fill yes)
		(layer "In11.Cu")
		(net "M_J_DQ<2>")
	)
	(gr_poly
		(pts
			(xy 67.677792 -94.225364) (xy 67.588892 -94.032324) (xy 67.360292 -94.032324) (xy 67.271392 -94.225364)
			(xy 67.271392 -94.269814) (xy 67.677792 -94.269814)
		)
		(stroke
			(width 0)
			(type solid)
		)
		(fill yes)
		(layer "In11.Cu")
		(net "M_M_DQS_DP<10>")
	)
	(gr_poly
		(pts
			(xy 67.68211 -89.909396) (xy 67.673982 -89.717626) (xy 67.651884 -89.679018) (xy 67.306444 -89.878662)
			(xy 67.328796 -89.917016) (xy 67.490848 -90.019886)
		)
		(stroke
			(width 0)
			(type solid)
		)
		(fill yes)
		(layer "In11.Cu")
		(net "M_M_DQS_DP<0>")
	)
	(gr_poly
		(pts
			(xy 67.68211 -88.918796) (xy 67.673982 -88.727026) (xy 67.651884 -88.688418) (xy 67.306444 -88.888062)
			(xy 67.328796 -88.926416) (xy 67.490848 -89.029286)
		)
		(stroke
			(width 0)
			(type solid)
		)
		(fill yes)
		(layer "In11.Cu")
		(net "M_M_DQS_DN<9>")
	)
	(gr_poly
		(pts
			(xy 67.68211 -65.144396) (xy 67.673982 -64.952626) (xy 67.651884 -64.914018) (xy 67.306444 -65.113408)
			(xy 67.328796 -65.152016) (xy 67.490848 -65.254886)
		)
		(stroke
			(width 0)
			(type solid)
		)
		(fill yes)
		(layer "In11.Cu")
		(net "M_J_DQS_DP<9>")
	)
	(gr_poly
		(pts
			(xy 67.68211 -64.153796) (xy 67.673982 -63.962026) (xy 67.651884 -63.923418) (xy 67.306444 -64.122808)
			(xy 67.328796 -64.161416) (xy 67.490848 -64.264286)
		)
		(stroke
			(width 0)
			(type solid)
		)
		(fill yes)
		(layer "In11.Cu")
		(net "M_J_DQS_DP<0>")
	)
	(gr_poly
		(pts
			(xy 67.683888 -87.92718) (xy 67.67576 -87.73541) (xy 67.653662 -87.696802) (xy 67.308222 -87.896446)
			(xy 67.330574 -87.9348) (xy 67.492626 -88.03767)
		)
		(stroke
			(width 0)
			(type solid)
		)
		(fill yes)
		(layer "In11.Cu")
		(net "M_M_DQ<1>")
	)
	(gr_poly
		(pts
			(xy 67.683888 -86.93658) (xy 67.67576 -86.74481) (xy 67.653662 -86.706202) (xy 67.308222 -86.905846)
			(xy 67.330574 -86.9442) (xy 67.492626 -87.04707)
		)
		(stroke
			(width 0)
			(type solid)
		)
		(fill yes)
		(layer "In11.Cu")
		(net "M_M_DQ<5>")
	)
	(gr_poly
		(pts
			(xy 67.683888 -67.12458) (xy 67.67576 -66.93281) (xy 67.653662 -66.894456) (xy 67.308222 -67.093592)
			(xy 67.330574 -67.1322) (xy 67.492626 -67.23507)
		)
		(stroke
			(width 0)
			(type solid)
		)
		(fill yes)
		(layer "In11.Cu")
		(net "M_J_DQ<4>")
	)
	(gr_poly
		(pts
			(xy 67.683888 -66.13398) (xy 67.67576 -65.94221) (xy 67.653662 -65.903602) (xy 67.308222 -66.102992)
			(xy 67.330574 -66.1416) (xy 67.492626 -66.24447)
		)
		(stroke
			(width 0)
			(type solid)
		)
		(fill yes)
		(layer "In11.Cu")
		(net "M_J_DQ<0>")
	)
	(gr_poly
		(pts
			(xy 67.683888 -63.16218) (xy 67.67576 -62.97041) (xy 67.653662 -62.931802) (xy 67.308222 -63.131192)
			(xy 67.330574 -63.1698) (xy 67.492626 -63.27267)
		)
		(stroke
			(width 0)
			(type solid)
		)
		(fill yes)
		(layer "In11.Cu")
		(net "M_J_DQ<6>")
	)
	(gr_poly
		(pts
			(xy 67.68592 -55.380128) (xy 67.717416 -55.348632) (xy 67.430142 -55.061358) (xy 67.398646 -55.092854)
			(xy 67.324986 -55.29199) (xy 67.486784 -55.453788)
		)
		(stroke
			(width 0)
			(type solid)
		)
		(fill yes)
		(layer "In11.Cu")
		(net "M_J_DQ<14>")
	)
	(gr_poly
		(pts
			(xy 67.724274 -98.298254) (xy 67.724274 -98.069654) (xy 67.531234 -97.980754) (xy 67.486784 -97.980754)
			(xy 67.486784 -98.387154) (xy 67.531234 -98.387154)
		)
		(stroke
			(width 0)
			(type solid)
		)
		(fill yes)
		(layer "In11.Cu")
		(net "M_M_DQ<15>")
	)
	(gr_poly
		(pts
			(xy 67.724274 -97.307654) (xy 67.724274 -97.079054) (xy 67.531234 -96.990154) (xy 67.486784 -96.990154)
			(xy 67.486784 -97.396554) (xy 67.531234 -97.396554)
		)
		(stroke
			(width 0)
			(type solid)
		)
		(fill yes)
		(layer "In11.Cu")
		(net "M_M_DQ<15>")
	)
	(gr_poly
		(pts
			(xy 67.7672 -53.982112) (xy 67.84086 -53.782722) (xy 67.679316 -53.620924) (xy 67.479926 -53.694584)
			(xy 67.44843 -53.72608) (xy 67.735704 -54.013354)
		)
		(stroke
			(width 0)
			(type solid)
		)
		(fill yes)
		(layer "In11.Cu")
		(net "M_J_DQ<11>")
	)
	(gr_poly
		(pts
			(xy 67.799204 -92.472256) (xy 67.799204 -92.427806) (xy 67.392804 -92.427806) (xy 67.392804 -92.472256)
			(xy 67.481704 -92.665296) (xy 67.710304 -92.665296)
		)
		(stroke
			(width 0)
			(type solid)
		)
		(fill yes)
		(layer "In11.Cu")
		(net "M_M_DQ<13>")
	)
	(gr_poly
		(pts
			(xy 67.799204 -92.193364) (xy 67.710304 -92.000324) (xy 67.481704 -92.000324) (xy 67.392804 -92.193364)
			(xy 67.392804 -92.237814) (xy 67.799204 -92.237814)
		)
		(stroke
			(width 0)
			(type solid)
		)
		(fill yes)
		(layer "In11.Cu")
		(net "M_M_DQ<12>")
	)
	(gr_poly
		(pts
			(xy 67.808602 -61.40069) (xy 67.780154 -61.366654) (xy 67.602608 -61.293502) (xy 67.433444 -61.435488)
			(xy 67.474592 -61.623194) (xy 67.503294 -61.65723)
		)
		(stroke
			(width 0)
			(type solid)
		)
		(fill yes)
		(layer "In11.Cu")
		(net "M_J_DQ<3>")
	)
	(gr_poly
		(pts
			(xy 67.864228 -57.728866) (xy 67.895724 -57.69737) (xy 67.60845 -57.410096) (xy 67.576954 -57.441592)
			(xy 67.503294 -57.640728) (xy 67.665092 -57.802526)
		)
		(stroke
			(width 0)
			(type solid)
		)
		(fill yes)
		(layer "In11.Cu")
		(net "M_J_DQS_DP<10>")
	)
	(gr_poly
		(pts
			(xy 67.880992 -94.504764) (xy 67.880992 -94.460314) (xy 67.474592 -94.460314) (xy 67.474592 -94.504764)
			(xy 67.563492 -94.697804) (xy 67.792092 -94.697804)
		)
		(stroke
			(width 0)
			(type solid)
		)
		(fill yes)
		(layer "In11.Cu")
		(net "M_M_DQS_DN<10>")
	)
	(gr_poly
		(pts
			(xy 67.883532 -55.182516) (xy 67.957192 -54.983126) (xy 67.795648 -54.821582) (xy 67.596258 -54.895242)
			(xy 67.564762 -54.926484) (xy 67.85229 -55.214012)
		)
		(stroke
			(width 0)
			(type solid)
		)
		(fill yes)
		(layer "In11.Cu")
		(net "M_J_DQ<15>")
	)
	(gr_poly
		(pts
			(xy 67.904106 -90.150696) (xy 67.881754 -90.112088) (xy 67.719702 -90.009218) (xy 67.52844 -90.119708)
			(xy 67.536568 -90.311478) (xy 67.558666 -90.350086)
		)
		(stroke
			(width 0)
			(type solid)
		)
		(fill yes)
		(layer "In11.Cu")
		(net "M_M_DQ<6>")
	)
	(gr_poly
		(pts
			(xy 67.90563 -89.15908) (xy 67.883278 -89.120726) (xy 67.721226 -89.017856) (xy 67.529964 -89.128346)
			(xy 67.538092 -89.320116) (xy 67.56019 -89.35847)
		)
		(stroke
			(width 0)
			(type solid)
		)
		(fill yes)
		(layer "In11.Cu")
		(net "M_M_DQS_DN<0>")
	)
	(gr_poly
		(pts
			(xy 67.90563 -88.16848) (xy 67.883278 -88.130126) (xy 67.721226 -88.027256) (xy 67.529964 -88.137746)
			(xy 67.538092 -88.329516) (xy 67.56019 -88.36787)
		)
		(stroke
			(width 0)
			(type solid)
		)
		(fill yes)
		(layer "In11.Cu")
		(net "M_M_DQS_DP<9>")
	)
	(gr_poly
		(pts
			(xy 67.90563 -87.17788) (xy 67.883278 -87.139526) (xy 67.721226 -87.036656) (xy 67.529964 -87.147146)
			(xy 67.538092 -87.338916) (xy 67.56019 -87.37727)
		)
		(stroke
			(width 0)
			(type solid)
		)
		(fill yes)
		(layer "In11.Cu")
		(net "M_M_DQ<0>")
	)
	(gr_poly
		(pts
			(xy 67.90563 -86.18728) (xy 67.883278 -86.148926) (xy 67.721226 -86.046056) (xy 67.529964 -86.156546)
			(xy 67.538092 -86.348316) (xy 67.56019 -86.38667)
		)
		(stroke
			(width 0)
			(type solid)
		)
		(fill yes)
		(layer "In11.Cu")
		(net "M_M_DQ<4>")
	)
	(gr_poly
		(pts
			(xy 67.90563 -66.37528) (xy 67.883278 -66.336926) (xy 67.721226 -66.234056) (xy 67.529964 -66.344546)
			(xy 67.538092 -66.536316) (xy 67.56019 -66.574924)
		)
		(stroke
			(width 0)
			(type solid)
		)
		(fill yes)
		(layer "In11.Cu")
		(net "M_J_DQ<5>")
	)
	(gr_poly
		(pts
			(xy 67.90563 -65.38468) (xy 67.883278 -65.346326) (xy 67.721226 -65.243456) (xy 67.529964 -65.353946)
			(xy 67.538092 -65.545716) (xy 67.56019 -65.584324)
		)
		(stroke
			(width 0)
			(type solid)
		)
		(fill yes)
		(layer "In11.Cu")
		(net "M_J_DQ<1>")
	)
	(gr_poly
		(pts
			(xy 67.90563 -62.41288) (xy 67.883278 -62.374526) (xy 67.721226 -62.271656) (xy 67.529964 -62.382146)
			(xy 67.538092 -62.573916) (xy 67.56019 -62.612524)
		)
		(stroke
			(width 0)
			(type solid)
		)
		(fill yes)
		(layer "In11.Cu")
		(net "M_J_DQ<7>")
	)
	(gr_poly
		(pts
			(xy 67.910964 -90.594434) (xy 67.839844 -90.416126) (xy 67.806062 -90.387424) (xy 67.546728 -90.690446)
			(xy 67.58051 -90.719148) (xy 67.767454 -90.762328)
		)
		(stroke
			(width 0)
			(type solid)
		)
		(fill yes)
		(layer "In11.Cu")
		(net "M_M_DQ<7>")
	)
	(gr_poly
		(pts
			(xy 67.912996 -63.399416) (xy 67.890644 -63.360808) (xy 67.728592 -63.257938) (xy 67.53733 -63.368428)
			(xy 67.545458 -63.560198) (xy 67.567556 -63.598806)
		)
		(stroke
			(width 0)
			(type solid)
		)
		(fill yes)
		(layer "In11.Cu")
		(net "M_J_DQS_DN<0>")
	)
	(gr_poly
		(pts
			(xy 67.91325 -64.390016) (xy 67.890898 -64.351408) (xy 67.728846 -64.248538) (xy 67.537584 -64.359028)
			(xy 67.545712 -64.550798) (xy 67.56781 -64.589406)
		)
		(stroke
			(width 0)
			(type solid)
		)
		(fill yes)
		(layer "In11.Cu")
		(net "M_J_DQS_DN<9>")
	)
	(gr_poly
		(pts
			(xy 68.06184 -57.531254) (xy 68.1355 -57.331864) (xy 67.973956 -57.17032) (xy 67.774566 -57.24398)
			(xy 67.74307 -57.275222) (xy 68.030598 -57.56275)
		)
		(stroke
			(width 0)
			(type solid)
		)
		(fill yes)
		(layer "In11.Cu")
		(net "M_J_DQS_DN<10>")
	)
	(gr_poly
		(pts
			(xy 68.11137 -91.10218) (xy 68.023232 -90.931492) (xy 67.802506 -90.93073) (xy 67.712844 -91.100402)
			(xy 67.712336 -91.144852) (xy 68.11137 -91.14663)
		)
		(stroke
			(width 0)
			(type solid)
		)
		(fill yes)
		(layer "In11.Cu")
		(net "M_M_DQ<2>")
	)
	(gr_poly
		(pts
			(xy 68.147184 -95.266764) (xy 68.147184 -95.222314) (xy 67.740784 -95.222314) (xy 67.740784 -95.266764)
			(xy 67.829684 -95.459804) (xy 68.058284 -95.459804)
		)
		(stroke
			(width 0)
			(type solid)
		)
		(fill yes)
		(layer "In11.Cu")
		(net "M_M_DQS_DP<1>")
	)
	(gr_poly
		(pts
			(xy 68.147184 -94.987364) (xy 68.058284 -94.794324) (xy 67.829684 -94.794324) (xy 67.740784 -94.987364)
			(xy 67.740784 -95.031814) (xy 68.147184 -95.031814)
		)
		(stroke
			(width 0)
			(type solid)
		)
		(fill yes)
		(layer "In11.Cu")
		(net "M_M_DQS_DN<1>")
	)
	(gr_poly
		(pts
			(xy 68.160392 -92.917772) (xy 68.071492 -92.724732) (xy 67.842892 -92.724732) (xy 67.753992 -92.917772)
			(xy 67.753992 -92.962222) (xy 68.160392 -92.962222)
		)
		(stroke
			(width 0)
			(type solid)
		)
		(fill yes)
		(layer "In11.Cu")
		(net "M_M_DQ<8>")
	)
	(gr_poly
		(pts
			(xy 68.270374 -54.879748) (xy 68.30187 -54.848252) (xy 68.014596 -54.560978) (xy 67.9831 -54.592474)
			(xy 67.90944 -54.79161) (xy 68.071238 -54.953408)
		)
		(stroke
			(width 0)
			(type solid)
		)
		(fill yes)
		(layer "In11.Cu")
		(net "M_J_DQ<10>")
	)
	(gr_poly
		(pts
			(xy 68.276978 -59.300618) (xy 68.308474 -59.269122) (xy 68.0212 -58.981848) (xy 67.989958 -59.013344)
			(xy 67.916044 -59.21248) (xy 68.077842 -59.374278)
		)
		(stroke
			(width 0)
			(type solid)
		)
		(fill yes)
		(layer "In11.Cu")
		(net "M_J_DQ<8>")
	)
	(gr_poly
		(pts
			(xy 68.303648 -98.97745) (xy 68.259198 -98.97745) (xy 68.089018 -99.06635) (xy 68.089018 -99.28733)
			(xy 68.259198 -99.37623) (xy 68.303648 -99.37623)
		)
		(stroke
			(width 0)
			(type solid)
		)
		(fill yes)
		(layer "In11.Cu")
		(net "M_M_DQ<10>")
	)
	(gr_poly
		(pts
			(xy 68.303648 -97.9805) (xy 68.259198 -97.9805) (xy 68.089018 -98.0694) (xy 68.089018 -98.29038)
			(xy 68.259198 -98.37928) (xy 68.303648 -98.37928)
		)
		(stroke
			(width 0)
			(type solid)
		)
		(fill yes)
		(layer "In11.Cu")
		(net "M_M_DQ<10>")
	)
	(gr_poly
		(pts
			(xy 68.303648 -96.9899) (xy 68.259198 -96.9899) (xy 68.089018 -97.0788) (xy 68.089018 -97.29978)
			(xy 68.259198 -97.38868) (xy 68.303648 -97.38868)
		)
		(stroke
			(width 0)
			(type solid)
		)
		(fill yes)
		(layer "In11.Cu")
		(net "M_M_DQ<10>")
	)
	(gr_poly
		(pts
			(xy 68.363338 -57.142888) (xy 68.394834 -57.111392) (xy 68.10756 -56.824118) (xy 68.076064 -56.855614)
			(xy 68.002404 -57.05475) (xy 68.164202 -57.216548)
		)
		(stroke
			(width 0)
			(type solid)
		)
		(fill yes)
		(layer "In11.Cu")
		(net "M_J_DQS_DP<1>")
	)
	(gr_poly
		(pts
			(xy 68.39712 -56.091328) (xy 68.428616 -56.059832) (xy 68.141342 -55.772558) (xy 68.109846 -55.804054)
			(xy 68.036186 -56.00319) (xy 68.197984 -56.164988)
		)
		(stroke
			(width 0)
			(type solid)
		)
		(fill yes)
		(layer "In11.Cu")
		(net "M_J_DQ<14>")
	)
	(gr_poly
		(pts
			(xy 68.414392 -93.196664) (xy 68.414392 -93.152214) (xy 68.007992 -93.152214) (xy 68.007992 -93.196664)
			(xy 68.096892 -93.389704) (xy 68.325492 -93.389704)
		)
		(stroke
			(width 0)
			(type solid)
		)
		(fill yes)
		(layer "In11.Cu")
		(net "M_M_DQ<9>")
	)
	(gr_poly
		(pts
			(xy 68.419218 -59.04738) (xy 68.492878 -58.84799) (xy 68.331334 -58.686446) (xy 68.131944 -58.760106)
			(xy 68.100448 -58.791348) (xy 68.387976 -59.078876)
		)
		(stroke
			(width 0)
			(type solid)
		)
		(fill yes)
		(layer "In11.Cu")
		(net "M_J_DQ<9>")
	)
	(gr_poly
		(pts
			(xy 68.467732 -54.68239) (xy 68.541392 -54.483254) (xy 68.379594 -54.321456) (xy 68.180458 -54.395116)
			(xy 68.148962 -54.426612) (xy 68.436236 -54.713886)
		)
		(stroke
			(width 0)
			(type solid)
		)
		(fill yes)
		(layer "In11.Cu")
		(net "M_J_DQ<11>")
	)
	(gr_poly
		(pts
			(xy 68.526914 -64.550798) (xy 68.535042 -64.359028) (xy 68.34378 -64.248538) (xy 68.181728 -64.351408)
			(xy 68.159376 -64.390016) (xy 68.504816 -64.589406)
		)
		(stroke
			(width 0)
			(type solid)
		)
		(fill yes)
		(layer "In11.Cu")
		(net "M_J_DQS_DN<9>")
	)
	(gr_poly
		(pts
			(xy 68.526914 -63.560198) (xy 68.535042 -63.368428) (xy 68.34378 -63.257938) (xy 68.181728 -63.360808)
			(xy 68.159376 -63.399416) (xy 68.504816 -63.598806)
		)
		(stroke
			(width 0)
			(type solid)
		)
		(fill yes)
		(layer "In11.Cu")
		(net "M_J_DQS_DN<0>")
	)
	(gr_poly
		(pts
			(xy 68.53428 -66.536316) (xy 68.542408 -66.344546) (xy 68.351146 -66.234056) (xy 68.189094 -66.336926)
			(xy 68.166742 -66.37528) (xy 68.512182 -66.574924)
		)
		(stroke
			(width 0)
			(type solid)
		)
		(fill yes)
		(layer "In11.Cu")
		(net "M_J_DQ<5>")
	)
	(gr_poly
		(pts
			(xy 68.53428 -65.545716) (xy 68.542408 -65.353946) (xy 68.351146 -65.243456) (xy 68.189094 -65.346326)
			(xy 68.166742 -65.38468) (xy 68.512182 -65.584324)
		)
		(stroke
			(width 0)
			(type solid)
		)
		(fill yes)
		(layer "In11.Cu")
		(net "M_J_DQ<1>")
	)
	(gr_poly
		(pts
			(xy 68.53428 -62.573916) (xy 68.542408 -62.382146) (xy 68.351146 -62.271656) (xy 68.189094 -62.374526)
			(xy 68.166742 -62.41288) (xy 68.512182 -62.612524)
		)
		(stroke
			(width 0)
			(type solid)
		)
		(fill yes)
		(layer "In11.Cu")
		(net "M_J_DQ<7>")
	)
	(gr_poly
		(pts
			(xy 68.53428 -61.583316) (xy 68.542408 -61.391546) (xy 68.351146 -61.281056) (xy 68.189094 -61.383926)
			(xy 68.166742 -61.42228) (xy 68.512182 -61.621924)
		)
		(stroke
			(width 0)
			(type solid)
		)
		(fill yes)
		(layer "In11.Cu")
		(net "M_J_DQ<3>")
	)
	(gr_poly
		(pts
			(xy 68.543932 -90.402664) (xy 68.535804 -90.210894) (xy 68.513706 -90.172286) (xy 68.168266 -90.37193)
			(xy 68.190618 -90.410284) (xy 68.35267 -90.513154)
		)
		(stroke
			(width 0)
			(type solid)
		)
		(fill yes)
		(layer "In11.Cu")
		(net "M_M_DQ<7>")
	)
	(gr_poly
		(pts
			(xy 68.543932 -89.412064) (xy 68.535804 -89.220294) (xy 68.513706 -89.181686) (xy 68.168266 -89.38133)
			(xy 68.190618 -89.419684) (xy 68.35267 -89.522554)
		)
		(stroke
			(width 0)
			(type solid)
		)
		(fill yes)
		(layer "In11.Cu")
		(net "M_M_DQS_DP<0>")
	)
	(gr_poly
		(pts
			(xy 68.543932 -88.421464) (xy 68.535804 -88.229694) (xy 68.513706 -88.191086) (xy 68.168266 -88.39073)
			(xy 68.190618 -88.429084) (xy 68.35267 -88.531954)
		)
		(stroke
			(width 0)
			(type solid)
		)
		(fill yes)
		(layer "In11.Cu")
		(net "M_M_DQS_DN<9>")
	)
	(gr_poly
		(pts
			(xy 68.543932 -87.430864) (xy 68.535804 -87.239094) (xy 68.513706 -87.200486) (xy 68.168266 -87.40013)
			(xy 68.190618 -87.438484) (xy 68.35267 -87.541354)
		)
		(stroke
			(width 0)
			(type solid)
		)
		(fill yes)
		(layer "In11.Cu")
		(net "M_M_DQ<1>")
	)
	(gr_poly
		(pts
			(xy 68.543932 -86.440264) (xy 68.535804 -86.248494) (xy 68.513706 -86.209886) (xy 68.168266 -86.40953)
			(xy 68.190618 -86.447884) (xy 68.35267 -86.550754)
		)
		(stroke
			(width 0)
			(type solid)
		)
		(fill yes)
		(layer "In11.Cu")
		(net "M_M_DQ<5>")
	)
	(gr_poly
		(pts
			(xy 68.56095 -56.945276) (xy 68.63461 -56.745886) (xy 68.473066 -56.584342) (xy 68.273676 -56.658002)
			(xy 68.24218 -56.689244) (xy 68.529708 -56.976772)
		)
		(stroke
			(width 0)
			(type solid)
		)
		(fill yes)
		(layer "In11.Cu")
		(net "M_J_DQS_DN<1>")
	)
	(gr_poly
		(pts
			(xy 68.575428 -58.440066) (xy 68.606924 -58.40857) (xy 68.31965 -58.121296) (xy 68.288154 -58.152792)
			(xy 68.214494 -58.351928) (xy 68.376292 -58.513726)
		)
		(stroke
			(width 0)
			(type solid)
		)
		(fill yes)
		(layer "In11.Cu")
		(net "M_J_DQS_DP<10>")
	)
	(gr_poly
		(pts
			(xy 68.576952 -96.104456) (xy 68.576952 -96.060006) (xy 68.170552 -96.060006) (xy 68.170552 -96.104456)
			(xy 68.259452 -96.297496) (xy 68.488052 -96.297496)
		)
		(stroke
			(width 0)
			(type solid)
		)
		(fill yes)
		(layer "In11.Cu")
		(net "M_M_DQ<15>")
	)
	(gr_poly
		(pts
			(xy 68.576952 -95.825564) (xy 68.488052 -95.632524) (xy 68.259452 -95.632524) (xy 68.170552 -95.825564)
			(xy 68.170552 -95.870014) (xy 68.576952 -95.870014)
		)
		(stroke
			(width 0)
			(type solid)
		)
		(fill yes)
		(layer "In11.Cu")
		(net "M_M_DQ<14>")
	)
	(gr_poly
		(pts
			(xy 68.594732 -55.893716) (xy 68.668392 -55.694326) (xy 68.506848 -55.532782) (xy 68.307458 -55.606442)
			(xy 68.275962 -55.637684) (xy 68.56349 -55.925212)
		)
		(stroke
			(width 0)
			(type solid)
		)
		(fill yes)
		(layer "In11.Cu")
		(net "M_J_DQ<15>")
	)
	(gr_poly
		(pts
			(xy 68.740274 -53.262784) (xy 68.762626 -53.22443) (xy 68.417186 -53.024786) (xy 68.395088 -53.063394)
			(xy 68.38696 -53.255164) (xy 68.578222 -53.365654)
		)
		(stroke
			(width 0)
			(type solid)
		)
		(fill yes)
		(layer "In11.Cu")
		(net "M_J_DQ<20>")
	)
	(gr_poly
		(pts
			(xy 68.741798 -67.1322) (xy 68.76415 -67.093592) (xy 68.41871 -66.894456) (xy 68.396612 -66.93281)
			(xy 68.388484 -67.12458) (xy 68.579746 -67.23507)
		)
		(stroke
			(width 0)
			(type solid)
		)
		(fill yes)
		(layer "In11.Cu")
		(net "M_J_DQ<4>")
	)
	(gr_poly
		(pts
			(xy 68.741798 -66.1416) (xy 68.76415 -66.102992) (xy 68.41871 -65.903602) (xy 68.396612 -65.94221)
			(xy 68.388484 -66.13398) (xy 68.579746 -66.24447)
		)
		(stroke
			(width 0)
			(type solid)
		)
		(fill yes)
		(layer "In11.Cu")
		(net "M_J_DQ<0>")
	)
	(gr_poly
		(pts
			(xy 68.741798 -63.1698) (xy 68.76415 -63.131192) (xy 68.41871 -62.931802) (xy 68.396612 -62.97041)
			(xy 68.388484 -63.16218) (xy 68.579746 -63.27267)
		)
		(stroke
			(width 0)
			(type solid)
		)
		(fill yes)
		(layer "In11.Cu")
		(net "M_J_DQ<6>")
	)
	(gr_poly
		(pts
			(xy 68.741798 -62.1792) (xy 68.76415 -62.140592) (xy 68.41871 -61.941202) (xy 68.396612 -61.97981)
			(xy 68.388484 -62.17158) (xy 68.579746 -62.28207)
		)
		(stroke
			(width 0)
			(type solid)
		)
		(fill yes)
		(layer "In11.Cu")
		(net "M_J_DQ<2>")
	)
	(gr_poly
		(pts
			(xy 68.741798 -61.1886) (xy 68.76415 -61.149992) (xy 68.41871 -60.950602) (xy 68.396612 -60.98921)
			(xy 68.388484 -61.18098) (xy 68.579746 -61.29147)
		)
		(stroke
			(width 0)
			(type solid)
		)
		(fill yes)
		(layer "In11.Cu")
		(net "M_J_DQ<12>")
	)
	(gr_poly
		(pts
			(xy 68.749164 -65.155318) (xy 68.771516 -65.116964) (xy 68.426076 -64.91732) (xy 68.403978 -64.955928)
			(xy 68.39585 -65.147698) (xy 68.587112 -65.258188)
		)
		(stroke
			(width 0)
			(type solid)
		)
		(fill yes)
		(layer "In11.Cu")
		(net "M_J_DQS_DP<9>")
	)
	(gr_poly
		(pts
			(xy 68.749164 -64.164718) (xy 68.771516 -64.126364) (xy 68.426076 -63.92672) (xy 68.403978 -63.965328)
			(xy 68.39585 -64.157098) (xy 68.587112 -64.267588)
		)
		(stroke
			(width 0)
			(type solid)
		)
		(fill yes)
		(layer "In11.Cu")
		(net "M_J_DQS_DP<0>")
	)
	(gr_poly
		(pts
			(xy 68.755006 -96.555306) (xy 68.732654 -96.516952) (xy 68.570602 -96.414082) (xy 68.37934 -96.524318)
			(xy 68.387214 -96.716088) (xy 68.409312 -96.754696)
		)
		(stroke
			(width 0)
			(type solid)
		)
		(fill yes)
		(layer "In11.Cu")
		(net "M_M_DQ<10>")
	)
	(gr_poly
		(pts
			(xy 68.762626 -90.64625) (xy 68.740274 -90.607642) (xy 68.578222 -90.504772) (xy 68.38696 -90.615262)
			(xy 68.395088 -90.807032) (xy 68.417186 -90.84564)
		)
		(stroke
			(width 0)
			(type solid)
		)
		(fill yes)
		(layer "In11.Cu")
		(net "M_M_DQ<2>")
	)
	(gr_poly
		(pts
			(xy 68.762626 -89.65565) (xy 68.740274 -89.617042) (xy 68.578222 -89.514172) (xy 68.38696 -89.624662)
			(xy 68.395088 -89.816432) (xy 68.417186 -89.85504)
		)
		(stroke
			(width 0)
			(type solid)
		)
		(fill yes)
		(layer "In11.Cu")
		(net "M_M_DQ<6>")
	)
	(gr_poly
		(pts
			(xy 68.762626 -88.66505) (xy 68.740274 -88.626442) (xy 68.578222 -88.523572) (xy 68.38696 -88.634062)
			(xy 68.395088 -88.825832) (xy 68.417186 -88.86444)
		)
		(stroke
			(width 0)
			(type solid)
		)
		(fill yes)
		(layer "In11.Cu")
		(net "M_M_DQS_DN<0>")
	)
	(gr_poly
		(pts
			(xy 68.762626 -87.67445) (xy 68.740274 -87.635842) (xy 68.578222 -87.532972) (xy 68.38696 -87.643462)
			(xy 68.395088 -87.835232) (xy 68.417186 -87.87384)
		)
		(stroke
			(width 0)
			(type solid)
		)
		(fill yes)
		(layer "In11.Cu")
		(net "M_M_DQS_DP<9>")
	)
	(gr_poly
		(pts
			(xy 68.762626 -86.68385) (xy 68.740274 -86.645242) (xy 68.578222 -86.542372) (xy 68.38696 -86.652862)
			(xy 68.395088 -86.844632) (xy 68.417186 -86.88324)
		)
		(stroke
			(width 0)
			(type solid)
		)
		(fill yes)
		(layer "In11.Cu")
		(net "M_M_DQ<0>")
	)
	(gr_poly
		(pts
			(xy 68.762626 -85.69325) (xy 68.740274 -85.654642) (xy 68.578222 -85.551772) (xy 68.38696 -85.662262)
			(xy 68.395088 -85.854032) (xy 68.417186 -85.89264)
		)
		(stroke
			(width 0)
			(type solid)
		)
		(fill yes)
		(layer "In11.Cu")
		(net "M_M_DQ<4>")
	)
	(gr_poly
		(pts
			(xy 68.766436 -100.54971) (xy 68.744084 -100.511356) (xy 68.582032 -100.408486) (xy 68.39077 -100.518976)
			(xy 68.398898 -100.710746) (xy 68.420996 -100.749354)
		)
		(stroke
			(width 0)
			(type solid)
		)
		(fill yes)
		(layer "In11.Cu")
		(net "M_M_DQ<20>")
	)
	(gr_poly
		(pts
			(xy 68.769738 -91.157044) (xy 68.712334 -90.97391) (xy 68.681092 -90.942668) (xy 68.398898 -91.224354)
			(xy 68.430648 -91.25585) (xy 68.613782 -91.313508)
		)
		(stroke
			(width 0)
			(type solid)
		)
		(fill yes)
		(layer "In11.Cu")
		(net "M_M_DQ<3>")
	)
	(gr_poly
		(pts
			(xy 68.77304 -58.242454) (xy 68.8467 -58.043064) (xy 68.685156 -57.88152) (xy 68.485766 -57.95518)
			(xy 68.45427 -57.986422) (xy 68.741798 -58.27395)
		)
		(stroke
			(width 0)
			(type solid)
		)
		(fill yes)
		(layer "In11.Cu")
		(net "M_J_DQS_DN<10>")
	)
	(gr_poly
		(pts
			(xy 68.831968 -91.540838) (xy 68.800472 -91.509342) (xy 68.601336 -91.435682) (xy 68.439538 -91.59748)
			(xy 68.513198 -91.796616) (xy 68.544694 -91.828112)
		)
		(stroke
			(width 0)
			(type solid)
		)
		(fill yes)
		(layer "In11.Cu")
		(net "M_M_DQ<12>")
	)
	(gr_poly
		(pts
			(xy 68.841874 -99.77628) (xy 68.841874 -99.5553) (xy 68.671694 -99.4664) (xy 68.627244 -99.4664)
			(xy 68.627244 -99.86518) (xy 68.671694 -99.86518)
		)
		(stroke
			(width 0)
			(type solid)
		)
		(fill yes)
		(layer "In11.Cu")
		(net "M_M_DQ<11>")
	)
	(gr_poly
		(pts
			(xy 68.841874 -98.798126) (xy 68.841874 -98.577146) (xy 68.671694 -98.488246) (xy 68.627244 -98.488246)
			(xy 68.627244 -98.887026) (xy 68.671694 -98.887026)
		)
		(stroke
			(width 0)
			(type solid)
		)
		(fill yes)
		(layer "In11.Cu")
		(net "M_M_DQ<11>")
	)
	(gr_poly
		(pts
			(xy 68.841874 -97.807526) (xy 68.841874 -97.586546) (xy 68.671694 -97.497646) (xy 68.627244 -97.497646)
			(xy 68.627244 -97.896426) (xy 68.671694 -97.896426)
		)
		(stroke
			(width 0)
			(type solid)
		)
		(fill yes)
		(layer "In11.Cu")
		(net "M_M_DQ<11>")
	)
	(gr_poly
		(pts
			(xy 68.882768 -93.496638) (xy 68.851272 -93.465142) (xy 68.652136 -93.391482) (xy 68.490338 -93.55328)
			(xy 68.563998 -93.752416) (xy 68.595494 -93.783912)
		)
		(stroke
			(width 0)
			(type solid)
		)
		(fill yes)
		(layer "In11.Cu")
		(net "M_M_DQS_DP<10>")
	)
	(gr_poly
		(pts
			(xy 68.909692 -92.464382) (xy 68.878196 -92.43314) (xy 68.678806 -92.35948) (xy 68.517262 -92.521024)
			(xy 68.590922 -92.720414) (xy 68.622164 -92.75191)
		)
		(stroke
			(width 0)
			(type solid)
		)
		(fill yes)
		(layer "In11.Cu")
		(net "M_M_DQ<8>")
	)
	(gr_poly
		(pts
			(xy 68.968874 -94.436438) (xy 68.937378 -94.404942) (xy 68.738242 -94.331282) (xy 68.576444 -94.49308)
			(xy 68.650104 -94.692216) (xy 68.6816 -94.723712)
		)
		(stroke
			(width 0)
			(type solid)
		)
		(fill yes)
		(layer "In11.Cu")
		(net "M_M_DQS_DN<1>")
	)
	(gr_poly
		(pts
			(xy 68.981574 -55.590948) (xy 69.01307 -55.559452) (xy 68.725796 -55.272178) (xy 68.6943 -55.303674)
			(xy 68.62064 -55.50281) (xy 68.782438 -55.664608)
		)
		(stroke
			(width 0)
			(type solid)
		)
		(fill yes)
		(layer "In11.Cu")
		(net "M_J_DQ<10>")
	)
	(gr_poly
		(pts
			(xy 69.013832 -102.407974) (xy 68.982336 -102.376732) (xy 68.782946 -102.303072) (xy 68.621402 -102.464616)
			(xy 68.695062 -102.664006) (xy 68.726304 -102.695502)
		)
		(stroke
			(width 0)
			(type solid)
		)
		(fill yes)
		(layer "In11.Cu")
		(net "M_M_DQ<16>")
	)
	(gr_poly
		(pts
			(xy 69.071744 -91.906344) (xy 68.998084 -91.706954) (xy 68.966842 -91.675458) (xy 68.679314 -91.962986)
			(xy 68.71081 -91.994228) (xy 68.9102 -92.067888)
		)
		(stroke
			(width 0)
			(type solid)
		)
		(fill yes)
		(layer "In11.Cu")
		(net "M_M_DQ<13>")
	)
	(gr_poly
		(pts
			(xy 69.116702 -95.538798) (xy 69.085206 -95.507556) (xy 68.885816 -95.433896) (xy 68.724272 -95.59544)
			(xy 68.797932 -95.79483) (xy 68.829174 -95.826326)
		)
		(stroke
			(width 0)
			(type solid)
		)
		(fill yes)
		(layer "In11.Cu")
		(net "M_M_DQ<14>")
	)
	(gr_poly
		(pts
			(xy 69.122544 -93.862144) (xy 69.048884 -93.662754) (xy 69.017642 -93.631258) (xy 68.730114 -93.918786)
			(xy 68.76161 -93.950028) (xy 68.961 -94.023688)
		)
		(stroke
			(width 0)
			(type solid)
		)
		(fill yes)
		(layer "In11.Cu")
		(net "M_M_DQS_DN<10>")
	)
	(gr_poly
		(pts
			(xy 69.14896 -92.829634) (xy 69.0753 -92.630244) (xy 69.044058 -92.598748) (xy 68.75653 -92.886276)
			(xy 68.788026 -92.917518) (xy 68.987416 -92.991178)
		)
		(stroke
			(width 0)
			(type solid)
		)
		(fill yes)
		(layer "In11.Cu")
		(net "M_M_DQ<9>")
	)
	(gr_poly
		(pts
			(xy 69.162168 -99.4664) (xy 69.117718 -99.4664) (xy 68.947538 -99.5553) (xy 68.947538 -99.77628)
			(xy 69.117718 -99.86518) (xy 69.162168 -99.86518)
		)
		(stroke
			(width 0)
			(type solid)
		)
		(fill yes)
		(layer "In11.Cu")
		(net "M_M_DQ<20>")
	)
	(gr_poly
		(pts
			(xy 69.162168 -98.48215) (xy 69.117718 -98.48215) (xy 68.947538 -98.57105) (xy 68.947538 -98.79203)
			(xy 69.117718 -98.88093) (xy 69.162168 -98.88093)
		)
		(stroke
			(width 0)
			(type solid)
		)
		(fill yes)
		(layer "In11.Cu")
		(net "M_M_DQ<20>")
	)
	(gr_poly
		(pts
			(xy 69.162422 -51.913028) (xy 69.117972 -51.913282) (xy 68.947792 -52.001928) (xy 68.947792 -52.222908)
			(xy 69.117972 -52.311808) (xy 69.162422 -52.312062)
		)
		(stroke
			(width 0)
			(type solid)
		)
		(fill yes)
		(layer "In11.Cu")
		(net "M_J_DQ<16>")
	)
	(gr_poly
		(pts
			(xy 69.178932 -55.39359) (xy 69.252592 -55.194454) (xy 69.090794 -55.032656) (xy 68.891658 -55.106316)
			(xy 68.860162 -55.137812) (xy 69.147436 -55.425086)
		)
		(stroke
			(width 0)
			(type solid)
		)
		(fill yes)
		(layer "In11.Cu")
		(net "M_J_DQ<11>")
	)
	(gr_poly
		(pts
			(xy 69.20865 -94.801944) (xy 69.13499 -94.602554) (xy 69.103748 -94.571058) (xy 68.81622 -94.858586)
			(xy 68.847716 -94.889828) (xy 69.047106 -94.963488)
		)
		(stroke
			(width 0)
			(type solid)
		)
		(fill yes)
		(layer "In11.Cu")
		(net "M_M_DQS_DP<1>")
	)
	(gr_poly
		(pts
			(xy 69.236082 -98.042476) (xy 69.132958 -97.657158) (xy 69.090032 -97.668842) (xy 68.948554 -97.79889)
			(xy 69.005704 -98.01225) (xy 69.193156 -98.053906)
		)
		(stroke
			(width 0)
			(type solid)
		)
		(fill yes)
		(layer "In11.Cu")
		(net "M_M_DQ<20>")
	)
	(gr_poly
		(pts
			(xy 69.2531 -102.773226) (xy 69.17944 -102.573836) (xy 69.148198 -102.54234) (xy 68.86067 -102.829868)
			(xy 68.892166 -102.86111) (xy 69.091556 -102.93477)
		)
		(stroke
			(width 0)
			(type solid)
		)
		(fill yes)
		(layer "In11.Cu")
		(net "M_M_DQ<17>")
	)
	(gr_poly
		(pts
			(xy 69.297296 -54.585108) (xy 69.33565 -54.56301) (xy 69.13626 -54.21757) (xy 69.097906 -54.239922)
			(xy 68.995036 -54.401974) (xy 69.105526 -54.593236)
		)
		(stroke
			(width 0)
			(type solid)
		)
		(fill yes)
		(layer "In11.Cu")
		(net "M_J_DQ<20>")
	)
	(gr_poly
		(pts
			(xy 69.369178 -90.926412) (xy 69.36105 -90.734642) (xy 69.338952 -90.696288) (xy 68.993512 -90.895424)
			(xy 69.015864 -90.934032) (xy 69.177916 -91.036902)
		)
		(stroke
			(width 0)
			(type solid)
		)
		(fill yes)
		(layer "In11.Cu")
		(net "M_M_DQ<3>")
	)
	(gr_poly
		(pts
			(xy 69.3928 -53.16347) (xy 69.400928 -52.9717) (xy 69.209666 -52.86121) (xy 69.047614 -52.96408)
			(xy 69.025262 -53.002434) (xy 69.370702 -53.202078)
		)
		(stroke
			(width 0)
			(type solid)
		)
		(fill yes)
		(layer "In11.Cu")
		(net "M_J_DQ<21>")
	)
	(gr_poly
		(pts
			(xy 69.393054 -100.809552) (xy 69.38518 -100.617782) (xy 69.362828 -100.579174) (xy 69.017388 -100.778564)
			(xy 69.039994 -100.816918) (xy 69.201792 -100.920042)
		)
		(stroke
			(width 0)
			(type solid)
		)
		(fill yes)
		(layer "In11.Cu")
		(net "M_M_DQ<21>")
	)
	(gr_poly
		(pts
			(xy 69.393562 -65.147698) (xy 69.385434 -64.955928) (xy 69.363336 -64.91732) (xy 69.017896 -65.116964)
			(xy 69.040248 -65.155318) (xy 69.2023 -65.258188)
		)
		(stroke
			(width 0)
			(type solid)
		)
		(fill yes)
		(layer "In11.Cu")
		(net "M_J_DQS_DP<9>")
	)
	(gr_poly
		(pts
			(xy 69.393562 -64.157098) (xy 69.385434 -63.965328) (xy 69.363336 -63.92672) (xy 69.017896 -64.126364)
			(xy 69.040248 -64.164718) (xy 69.2023 -64.267588)
		)
		(stroke
			(width 0)
			(type solid)
		)
		(fill yes)
		(layer "In11.Cu")
		(net "M_J_DQS_DP<0>")
	)
	(gr_poly
		(pts
			(xy 69.400928 -96.84258) (xy 69.3928 -96.65081) (xy 69.370702 -96.612202) (xy 69.025262 -96.811846)
			(xy 69.047614 -96.8502) (xy 69.209666 -96.95307)
		)
		(stroke
			(width 0)
			(type solid)
		)
		(fill yes)
		(layer "In11.Cu")
		(net "M_M_DQ<11>")
	)
	(gr_poly
		(pts
			(xy 69.400928 -89.90838) (xy 69.3928 -89.71661) (xy 69.370702 -89.678002) (xy 69.025262 -89.877646)
			(xy 69.047614 -89.916) (xy 69.209666 -90.01887)
		)
		(stroke
			(width 0)
			(type solid)
		)
		(fill yes)
		(layer "In11.Cu")
		(net "M_M_DQ<7>")
	)
	(gr_poly
		(pts
			(xy 69.400928 -88.91778) (xy 69.3928 -88.72601) (xy 69.370702 -88.687402) (xy 69.025262 -88.887046)
			(xy 69.047614 -88.9254) (xy 69.209666 -89.02827)
		)
		(stroke
			(width 0)
			(type solid)
		)
		(fill yes)
		(layer "In11.Cu")
		(net "M_M_DQS_DP<0>")
	)
	(gr_poly
		(pts
			(xy 69.400928 -87.92718) (xy 69.3928 -87.73541) (xy 69.370702 -87.696802) (xy 69.025262 -87.896446)
			(xy 69.047614 -87.9348) (xy 69.209666 -88.03767)
		)
		(stroke
			(width 0)
			(type solid)
		)
		(fill yes)
		(layer "In11.Cu")
		(net "M_M_DQS_DN<9>")
	)
	(gr_poly
		(pts
			(xy 69.400928 -86.93658) (xy 69.3928 -86.74481) (xy 69.370702 -86.706202) (xy 69.025262 -86.905846)
			(xy 69.047614 -86.9442) (xy 69.209666 -87.04707)
		)
		(stroke
			(width 0)
			(type solid)
		)
		(fill yes)
		(layer "In11.Cu")
		(net "M_M_DQ<1>")
	)
	(gr_poly
		(pts
			(xy 69.400928 -85.94598) (xy 69.3928 -85.75421) (xy 69.370702 -85.715602) (xy 69.025262 -85.915246)
			(xy 69.047614 -85.9536) (xy 69.209666 -86.05647)
		)
		(stroke
			(width 0)
			(type solid)
		)
		(fill yes)
		(layer "In11.Cu")
		(net "M_M_DQ<5>")
	)
	(gr_poly
		(pts
			(xy 69.400928 -67.12458) (xy 69.3928 -66.93281) (xy 69.370702 -66.894456) (xy 69.025262 -67.093592)
			(xy 69.047614 -67.1322) (xy 69.209666 -67.23507)
		)
		(stroke
			(width 0)
			(type solid)
		)
		(fill yes)
		(layer "In11.Cu")
		(net "M_J_DQ<4>")
	)
	(gr_poly
		(pts
			(xy 69.400928 -66.13398) (xy 69.3928 -65.94221) (xy 69.370702 -65.903602) (xy 69.025262 -66.102992)
			(xy 69.047614 -66.1416) (xy 69.209666 -66.24447)
		)
		(stroke
			(width 0)
			(type solid)
		)
		(fill yes)
		(layer "In11.Cu")
		(net "M_J_DQ<0>")
	)
	(gr_poly
		(pts
			(xy 69.400928 -63.16218) (xy 69.3928 -62.97041) (xy 69.370702 -62.931802) (xy 69.025262 -63.131192)
			(xy 69.047614 -63.1698) (xy 69.209666 -63.27267)
		)
		(stroke
			(width 0)
			(type solid)
		)
		(fill yes)
		(layer "In11.Cu")
		(net "M_J_DQ<6>")
	)
	(gr_poly
		(pts
			(xy 69.400928 -62.17158) (xy 69.3928 -61.97981) (xy 69.370702 -61.941202) (xy 69.025262 -62.140592)
			(xy 69.047614 -62.1792) (xy 69.209666 -62.28207)
		)
		(stroke
			(width 0)
			(type solid)
		)
		(fill yes)
		(layer "In11.Cu")
		(net "M_J_DQ<2>")
	)
	(gr_poly
		(pts
			(xy 69.400928 -61.18098) (xy 69.3928 -60.98921) (xy 69.370702 -60.950602) (xy 69.025262 -61.149992)
			(xy 69.047614 -61.1886) (xy 69.209666 -61.29147)
		)
		(stroke
			(width 0)
			(type solid)
		)
		(fill yes)
		(layer "In11.Cu")
		(net "M_J_DQ<12>")
	)
	(gr_poly
		(pts
			(xy 69.424042 -95.8469) (xy 69.350382 -95.64751) (xy 69.31914 -95.616014) (xy 69.031612 -95.903542)
			(xy 69.063108 -95.934784) (xy 69.262498 -96.008444)
		)
		(stroke
			(width 0)
			(type solid)
		)
		(fill yes)
		(layer "In11.Cu")
		(net "M_M_DQ<15>")
	)
	(gr_poly
		(pts
			(xy 69.427598 -96.21266) (xy 69.396102 -96.181418) (xy 69.212968 -96.124014) (xy 69.056758 -96.280224)
			(xy 69.114416 -96.463358) (xy 69.145658 -96.494854)
		)
		(stroke
			(width 0)
			(type solid)
		)
		(fill yes)
		(layer "In11.Cu")
		(net "M_M_DQ<10>")
	)
	(gr_poly
		(pts
			(xy 69.429122 -59.692286) (xy 69.429122 -59.647836) (xy 69.022722 -59.647836) (xy 69.022722 -59.692286)
			(xy 69.111622 -59.885326) (xy 69.340222 -59.885326)
		)
		(stroke
			(width 0)
			(type solid)
		)
		(fill yes)
		(layer "In11.Cu")
		(net "M_J_DQ<8>")
	)
	(gr_poly
		(pts
			(xy 69.429122 -59.412886) (xy 69.340222 -59.219846) (xy 69.111622 -59.219846) (xy 69.022722 -59.412886)
			(xy 69.022722 -59.457336) (xy 69.429122 -59.457336)
		)
		(stroke
			(width 0)
			(type solid)
		)
		(fill yes)
		(layer "In11.Cu")
		(net "M_J_DQ<9>")
	)
	(gr_poly
		(pts
			(xy 69.4817 -58.422286) (xy 69.3928 -58.229246) (xy 69.164454 -58.229246) (xy 69.075554 -58.422286)
			(xy 69.0753 -58.466736) (xy 69.481954 -58.466736)
		)
		(stroke
			(width 0)
			(type solid)
		)
		(fill yes)
		(layer "In11.Cu")
		(net "M_J_DQS_DN<10>")
	)
	(gr_poly
		(pts
			(xy 69.514974 -58.701686) (xy 69.514974 -58.657236) (xy 69.108574 -58.657236) (xy 69.108574 -58.701686)
			(xy 69.197474 -58.894726) (xy 69.426074 -58.894726)
		)
		(stroke
			(width 0)
			(type solid)
		)
		(fill yes)
		(layer "In11.Cu")
		(net "M_J_DQS_DP<10>")
	)
	(gr_poly
		(pts
			(xy 69.522086 -56.724804) (xy 69.522086 -56.6801) (xy 69.115686 -56.6801) (xy 69.115686 -56.724804)
			(xy 69.204586 -56.91759) (xy 69.433186 -56.91759)
		)
		(stroke
			(width 0)
			(type solid)
		)
		(fill yes)
		(layer "In11.Cu")
		(net "M_J_DQ<14>")
	)
	(gr_poly
		(pts
			(xy 69.522086 -56.44515) (xy 69.433186 -56.25211) (xy 69.204586 -56.25211) (xy 69.115686 -56.44515)
			(xy 69.115686 -56.4896) (xy 69.522086 -56.4896)
		)
		(stroke
			(width 0)
			(type solid)
		)
		(fill yes)
		(layer "In11.Cu")
		(net "M_J_DQ<15>")
	)
	(gr_poly
		(pts
			(xy 69.52996 -100.366322) (xy 69.70014 -100.277676) (xy 69.70014 -100.056696) (xy 69.530214 -99.967796)
			(xy 69.48551 -99.967796) (xy 69.48551 -100.366576)
		)
		(stroke
			(width 0)
			(type solid)
		)
		(fill yes)
		(layer "In11.Cu")
		(net "M_M_DQ<21>")
	)
	(gr_poly
		(pts
			(xy 69.598794 -52.767738) (xy 69.621146 -52.729384) (xy 69.275706 -52.52974) (xy 69.253608 -52.568348)
			(xy 69.24548 -52.760118) (xy 69.436742 -52.870608)
		)
		(stroke
			(width 0)
			(type solid)
		)
		(fill yes)
		(layer "In11.Cu")
		(net "M_J_DQ<16>")
	)
	(gr_poly
		(pts
			(xy 69.621146 -95.103442) (xy 69.598794 -95.065088) (xy 69.436742 -94.962218) (xy 69.24548 -95.072708)
			(xy 69.253608 -95.264478) (xy 69.275706 -95.303086)
		)
		(stroke
			(width 0)
			(type solid)
		)
		(fill yes)
		(layer "In11.Cu")
		(net "M_M_DQ<14>")
	)
	(gr_poly
		(pts
			(xy 69.62267 -101.04628) (xy 69.600318 -101.007926) (xy 69.438266 -100.905056) (xy 69.247004 -101.015546)
			(xy 69.255132 -101.207316) (xy 69.27723 -101.24567)
		)
		(stroke
			(width 0)
			(type solid)
		)
		(fill yes)
		(layer "In11.Cu")
		(net "M_M_DQ<16>")
	)
	(gr_poly
		(pts
			(xy 69.62267 -90.14968) (xy 69.600318 -90.111326) (xy 69.438266 -90.008456) (xy 69.247004 -90.118946)
			(xy 69.255132 -90.310716) (xy 69.27723 -90.34907)
		)
		(stroke
			(width 0)
			(type solid)
		)
		(fill yes)
		(layer "In11.Cu")
		(net "M_M_DQ<2>")
	)
	(gr_poly
		(pts
			(xy 69.62267 -89.15908) (xy 69.600318 -89.120726) (xy 69.438266 -89.017856) (xy 69.247004 -89.128346)
			(xy 69.255132 -89.320116) (xy 69.27723 -89.35847)
		)
		(stroke
			(width 0)
			(type solid)
		)
		(fill yes)
		(layer "In11.Cu")
		(net "M_M_DQ<6>")
	)
	(gr_poly
		(pts
			(xy 69.62267 -88.16848) (xy 69.600318 -88.130126) (xy 69.438266 -88.027256) (xy 69.247004 -88.137746)
			(xy 69.255132 -88.329516) (xy 69.27723 -88.36787)
		)
		(stroke
			(width 0)
			(type solid)
		)
		(fill yes)
		(layer "In11.Cu")
		(net "M_M_DQS_DN<0>")
	)
	(gr_poly
		(pts
			(xy 69.62267 -87.17788) (xy 69.600318 -87.139526) (xy 69.438266 -87.036656) (xy 69.247004 -87.147146)
			(xy 69.255132 -87.338916) (xy 69.27723 -87.37727)
		)
		(stroke
			(width 0)
			(type solid)
		)
		(fill yes)
		(layer "In11.Cu")
		(net "M_M_DQS_DP<9>")
	)
	(gr_poly
		(pts
			(xy 69.62267 -86.18728) (xy 69.600318 -86.148926) (xy 69.438266 -86.046056) (xy 69.247004 -86.156546)
			(xy 69.255132 -86.348316) (xy 69.27723 -86.38667)
		)
		(stroke
			(width 0)
			(type solid)
		)
		(fill yes)
		(layer "In11.Cu")
		(net "M_M_DQ<0>")
	)
	(gr_poly
		(pts
			(xy 69.62267 -85.19668) (xy 69.600318 -85.158326) (xy 69.438266 -85.055456) (xy 69.247004 -85.165946)
			(xy 69.255132 -85.357716) (xy 69.27723 -85.39607)
		)
		(stroke
			(width 0)
			(type solid)
		)
		(fill yes)
		(layer "In11.Cu")
		(net "M_M_DQ<4>")
	)
	(gr_poly
		(pts
			(xy 69.62267 -66.37528) (xy 69.600318 -66.336926) (xy 69.438266 -66.234056) (xy 69.247004 -66.344546)
			(xy 69.255132 -66.536316) (xy 69.27723 -66.574924)
		)
		(stroke
			(width 0)
			(type solid)
		)
		(fill yes)
		(layer "In11.Cu")
		(net "M_J_DQ<5>")
	)
	(gr_poly
		(pts
			(xy 69.62267 -65.38468) (xy 69.600318 -65.346326) (xy 69.438266 -65.243456) (xy 69.247004 -65.353946)
			(xy 69.255132 -65.545716) (xy 69.27723 -65.584324)
		)
		(stroke
			(width 0)
			(type solid)
		)
		(fill yes)
		(layer "In11.Cu")
		(net "M_J_DQ<1>")
	)
	(gr_poly
		(pts
			(xy 69.62267 -62.41288) (xy 69.600318 -62.374526) (xy 69.438266 -62.271656) (xy 69.247004 -62.382146)
			(xy 69.255132 -62.573916) (xy 69.27723 -62.612524)
		)
		(stroke
			(width 0)
			(type solid)
		)
		(fill yes)
		(layer "In11.Cu")
		(net "M_J_DQ<7>")
	)
	(gr_poly
		(pts
			(xy 69.62267 -61.42228) (xy 69.600318 -61.383926) (xy 69.438266 -61.281056) (xy 69.247004 -61.391546)
			(xy 69.255132 -61.583316) (xy 69.27723 -61.621924)
		)
		(stroke
			(width 0)
			(type solid)
		)
		(fill yes)
		(layer "In11.Cu")
		(net "M_J_DQ<3>")
	)
	(gr_poly
		(pts
			(xy 69.62267 -60.43168) (xy 69.600318 -60.393326) (xy 69.438266 -60.290456) (xy 69.247004 -60.400946)
			(xy 69.255132 -60.592716) (xy 69.27723 -60.631324)
		)
		(stroke
			(width 0)
			(type solid)
		)
		(fill yes)
		(layer "In11.Cu")
		(net "M_J_DQ<13>")
	)
	(gr_poly
		(pts
			(xy 69.624956 -97.082864) (xy 69.602604 -97.04451) (xy 69.440552 -96.941386) (xy 69.249036 -97.051876)
			(xy 69.257418 -97.243646) (xy 69.279516 -97.282254)
		)
		(stroke
			(width 0)
			(type solid)
		)
		(fill yes)
		(layer "In11.Cu")
		(net "M_M_DQ<20>")
	)
	(gr_poly
		(pts
			(xy 69.63029 -64.390016) (xy 69.607938 -64.351408) (xy 69.445886 -64.248538) (xy 69.254624 -64.359028)
			(xy 69.262752 -64.550798) (xy 69.28485 -64.589406)
		)
		(stroke
			(width 0)
			(type solid)
		)
		(fill yes)
		(layer "In11.Cu")
		(net "M_J_DQS_DN<9>")
	)
	(gr_poly
		(pts
			(xy 69.63029 -63.399416) (xy 69.607938 -63.360808) (xy 69.445886 -63.257938) (xy 69.254624 -63.368428)
			(xy 69.262752 -63.560198) (xy 69.28485 -63.598806)
		)
		(stroke
			(width 0)
			(type solid)
		)
		(fill yes)
		(layer "In11.Cu")
		(net "M_J_DQS_DN<0>")
	)
	(gr_poly
		(pts
			(xy 69.699886 -53.728874) (xy 69.699886 -53.507894) (xy 69.52996 -53.418994) (xy 69.48551 -53.418994)
			(xy 69.485256 -53.817774) (xy 69.529706 -53.817774)
		)
		(stroke
			(width 0)
			(type solid)
		)
		(fill yes)
		(layer "In11.Cu")
		(net "M_J_DQ<21>")
	)
	(gr_poly
		(pts
			(xy 69.700394 -99.28733) (xy 69.700394 -99.06635) (xy 69.530214 -98.97745) (xy 69.485764 -98.97745)
			(xy 69.485764 -99.37623) (xy 69.530214 -99.37623)
		)
		(stroke
			(width 0)
			(type solid)
		)
		(fill yes)
		(layer "In11.Cu")
		(net "M_M_DQ<21>")
	)
	(gr_poly
		(pts
			(xy 69.700394 -98.29673) (xy 69.700394 -98.07575) (xy 69.530214 -97.98685) (xy 69.485764 -97.98685)
			(xy 69.485764 -98.38563) (xy 69.530214 -98.38563)
		)
		(stroke
			(width 0)
			(type solid)
		)
		(fill yes)
		(layer "In11.Cu")
		(net "M_M_DQ<21>")
	)
	(gr_poly
		(pts
			(xy 69.700394 -51.73853) (xy 69.700394 -51.51755) (xy 69.530214 -51.42865) (xy 69.485764 -51.42865)
			(xy 69.485764 -51.82743) (xy 69.530214 -51.82743)
		)
		(stroke
			(width 0)
			(type solid)
		)
		(fill yes)
		(layer "In11.Cu")
		(net "M_J_DQ<17>")
	)
	(gr_poly
		(pts
			(xy 69.935598 -50.728118) (xy 69.97446 -50.705766) (xy 69.774816 -50.36058) (xy 69.736462 -50.382678)
			(xy 69.633592 -50.54473) (xy 69.744082 -50.736246)
		)
		(stroke
			(width 0)
			(type solid)
		)
		(fill yes)
		(layer "In11.Cu")
		(net "M_J_DQS_DP<11>")
	)
	(gr_poly
		(pts
			(xy 70.020688 -99.974146) (xy 69.976238 -99.974146) (xy 69.806058 -100.063046) (xy 69.806058 -100.284026)
			(xy 69.976238 -100.372926) (xy 70.020688 -100.372926)
		)
		(stroke
			(width 0)
			(type solid)
		)
		(fill yes)
		(layer "In11.Cu")
		(net "M_M_DQ<16>")
	)
	(gr_poly
		(pts
			(xy 70.020688 -98.97745) (xy 69.976238 -98.97745) (xy 69.806058 -99.06635) (xy 69.806058 -99.28733)
			(xy 69.976238 -99.37623) (xy 70.020688 -99.37623)
		)
		(stroke
			(width 0)
			(type solid)
		)
		(fill yes)
		(layer "In11.Cu")
		(net "M_M_DQ<16>")
	)
	(gr_poly
		(pts
			(xy 70.020942 -53.398928) (xy 69.976492 -53.399182) (xy 69.806312 -53.487828) (xy 69.806312 -53.708808)
			(xy 69.976492 -53.797708) (xy 70.020942 -53.797962)
		)
		(stroke
			(width 0)
			(type solid)
		)
		(fill yes)
		(layer "In11.Cu")
		(net "M_J_DQ<16>")
	)
	(gr_poly
		(pts
			(xy 70.021196 -51.421538) (xy 69.976746 -51.421538) (xy 69.806566 -51.510438) (xy 69.806566 -51.731418)
			(xy 69.976492 -51.820318) (xy 70.021196 -51.820318)
		)
		(stroke
			(width 0)
			(type solid)
		)
		(fill yes)
		(layer "In11.Cu")
		(net "M_J_DQS_DP<11>")
	)
	(gr_poly
		(pts
			(xy 70.194424 -97.727516) (xy 70.155816 -97.705418) (xy 69.964046 -97.69729) (xy 69.853556 -97.888552)
			(xy 69.956426 -98.050604) (xy 69.99478 -98.072956)
		)
		(stroke
			(width 0)
			(type solid)
		)
		(fill yes)
		(layer "In11.Cu")
		(net "M_M_DQ<16>")
	)
	(gr_poly
		(pts
			(xy 70.243954 -64.550798) (xy 70.252082 -64.359028) (xy 70.06082 -64.248538) (xy 69.898768 -64.351408)
			(xy 69.876416 -64.390016) (xy 70.221856 -64.589406)
		)
		(stroke
			(width 0)
			(type solid)
		)
		(fill yes)
		(layer "In11.Cu")
		(net "M_J_DQS_DN<9>")
	)
	(gr_poly
		(pts
			(xy 70.243954 -63.560198) (xy 70.252082 -63.368428) (xy 70.06082 -63.257938) (xy 69.898768 -63.360808)
			(xy 69.876416 -63.399416) (xy 70.221856 -63.598806)
		)
		(stroke
			(width 0)
			(type solid)
		)
		(fill yes)
		(layer "In11.Cu")
		(net "M_J_DQS_DN<0>")
	)
	(gr_poly
		(pts
			(xy 70.25132 -66.536316) (xy 70.259448 -66.344546) (xy 70.068186 -66.234056) (xy 69.906134 -66.336926)
			(xy 69.883782 -66.37528) (xy 70.229222 -66.574924)
		)
		(stroke
			(width 0)
			(type solid)
		)
		(fill yes)
		(layer "In11.Cu")
		(net "M_J_DQ<5>")
	)
	(gr_poly
		(pts
			(xy 70.25132 -65.545716) (xy 70.259448 -65.353946) (xy 70.068186 -65.243456) (xy 69.906134 -65.346326)
			(xy 69.883782 -65.38468) (xy 70.229222 -65.584324)
		)
		(stroke
			(width 0)
			(type solid)
		)
		(fill yes)
		(layer "In11.Cu")
		(net "M_J_DQ<1>")
	)
	(gr_poly
		(pts
			(xy 70.25132 -62.573916) (xy 70.259448 -62.382146) (xy 70.068186 -62.271656) (xy 69.906134 -62.374526)
			(xy 69.883782 -62.41288) (xy 70.229222 -62.612524)
		)
		(stroke
			(width 0)
			(type solid)
		)
		(fill yes)
		(layer "In11.Cu")
		(net "M_J_DQ<7>")
	)
	(gr_poly
		(pts
			(xy 70.25132 -61.583316) (xy 70.259448 -61.391546) (xy 70.068186 -61.281056) (xy 69.906134 -61.383926)
			(xy 69.883782 -61.42228) (xy 70.229222 -61.621924)
		)
		(stroke
			(width 0)
			(type solid)
		)
		(fill yes)
		(layer "In11.Cu")
		(net "M_J_DQ<3>")
	)
	(gr_poly
		(pts
			(xy 70.25132 -60.592716) (xy 70.259448 -60.400946) (xy 70.068186 -60.290456) (xy 69.906134 -60.393326)
			(xy 69.883782 -60.43168) (xy 70.229222 -60.631324)
		)
		(stroke
			(width 0)
			(type solid)
		)
		(fill yes)
		(layer "In11.Cu")
		(net "M_J_DQ<13>")
	)
	(gr_poly
		(pts
			(xy 70.25132 -59.602116) (xy 70.259448 -59.410346) (xy 70.068186 -59.299856) (xy 69.906134 -59.402726)
			(xy 69.883782 -59.44108) (xy 70.229222 -59.640724)
		)
		(stroke
			(width 0)
			(type solid)
		)
		(fill yes)
		(layer "In11.Cu")
		(net "M_J_DQ<9>")
	)
	(gr_poly
		(pts
			(xy 70.25132 -56.630316) (xy 70.259448 -56.438546) (xy 70.068186 -56.328056) (xy 69.906134 -56.430926)
			(xy 69.883782 -56.46928) (xy 70.229222 -56.668924)
		)
		(stroke
			(width 0)
			(type solid)
		)
		(fill yes)
		(layer "In11.Cu")
		(net "M_J_DQ<15>")
	)
	(gr_poly
		(pts
			(xy 70.25132 -55.639716) (xy 70.259448 -55.447946) (xy 70.068186 -55.337456) (xy 69.906134 -55.440326)
			(xy 69.883782 -55.47868) (xy 70.229222 -55.678324)
		)
		(stroke
			(width 0)
			(type solid)
		)
		(fill yes)
		(layer "In11.Cu")
		(net "M_J_DQ<11>")
	)
	(gr_poly
		(pts
			(xy 70.25132 -54.649116) (xy 70.259448 -54.457346) (xy 70.068186 -54.346856) (xy 69.906134 -54.449726)
			(xy 69.883782 -54.48808) (xy 70.229222 -54.687724)
		)
		(stroke
			(width 0)
			(type solid)
		)
		(fill yes)
		(layer "In11.Cu")
		(net "M_J_DQ<21>")
	)
	(gr_poly
		(pts
			(xy 70.252844 -58.612278) (xy 70.260972 -58.420508) (xy 70.06971 -58.310018) (xy 69.907658 -58.412888)
			(xy 69.885306 -58.451242) (xy 70.230746 -58.650632)
		)
		(stroke
			(width 0)
			(type solid)
		)
		(fill yes)
		(layer "In11.Cu")
		(net "M_J_DQS_DN<10>")
	)
	(gr_poly
		(pts
			(xy 70.252844 -57.621932) (xy 70.260972 -57.430162) (xy 70.06971 -57.319672) (xy 69.907658 -57.422542)
			(xy 69.885306 -57.460896) (xy 70.230746 -57.660286)
		)
		(stroke
			(width 0)
			(type solid)
		)
		(fill yes)
		(layer "In11.Cu")
		(net "M_J_DQS_DN<1>")
	)
	(gr_poly
		(pts
			(xy 70.252844 -52.668678) (xy 70.260972 -52.476908) (xy 70.06971 -52.366418) (xy 69.907658 -52.469288)
			(xy 69.885306 -52.507642) (xy 70.230746 -52.707286)
		)
		(stroke
			(width 0)
			(type solid)
		)
		(fill yes)
		(layer "In11.Cu")
		(net "M_J_DQ<17>")
	)
	(gr_poly
		(pts
			(xy 70.257162 -97.33915) (xy 70.249034 -97.14738) (xy 70.226936 -97.108772) (xy 69.881496 -97.308162)
			(xy 69.903848 -97.34677) (xy 70.0659 -97.44964)
		)
		(stroke
			(width 0)
			(type solid)
		)
		(fill yes)
		(layer "In11.Cu")
		(net "M_M_DQ<21>")
	)
	(gr_poly
		(pts
			(xy 70.257162 -93.37675) (xy 70.249034 -93.18498) (xy 70.226936 -93.146372) (xy 69.881496 -93.345762)
			(xy 69.903848 -93.38437) (xy 70.0659 -93.48724)
		)
		(stroke
			(width 0)
			(type solid)
		)
		(fill yes)
		(layer "In11.Cu")
		(net "M_M_DQS_DN<10>")
	)
	(gr_poly
		(pts
			(xy 70.259448 -95.35668) (xy 70.25132 -95.16491) (xy 70.229222 -95.126302) (xy 69.883782 -95.325946)
			(xy 69.906134 -95.3643) (xy 70.068186 -95.46717)
		)
		(stroke
			(width 0)
			(type solid)
		)
		(fill yes)
		(layer "In11.Cu")
		(net "M_M_DQ<15>")
	)
	(gr_poly
		(pts
			(xy 70.259448 -94.36608) (xy 70.25132 -94.17431) (xy 70.229222 -94.135702) (xy 69.883782 -94.335346)
			(xy 69.906134 -94.3737) (xy 70.068186 -94.47657)
		)
		(stroke
			(width 0)
			(type solid)
		)
		(fill yes)
		(layer "In11.Cu")
		(net "M_M_DQS_DP<1>")
	)
	(gr_poly
		(pts
			(xy 70.260972 -101.299264) (xy 70.253098 -101.107494) (xy 70.231 -101.06914) (xy 69.885306 -101.26853)
			(xy 69.907658 -101.306884) (xy 70.06971 -101.409754)
		)
		(stroke
			(width 0)
			(type solid)
		)
		(fill yes)
		(layer "In11.Cu")
		(net "M_M_DQ<17>")
	)
	(gr_poly
		(pts
			(xy 70.260972 -96.346264) (xy 70.252844 -96.154494) (xy 70.230746 -96.115886) (xy 69.885306 -96.31553)
			(xy 69.907658 -96.353884) (xy 70.06971 -96.456754)
		)
		(stroke
			(width 0)
			(type solid)
		)
		(fill yes)
		(layer "In11.Cu")
		(net "M_M_DQ<11>")
	)
	(gr_poly
		(pts
			(xy 70.260972 -92.383864) (xy 70.252844 -92.192094) (xy 70.230746 -92.153486) (xy 69.885306 -92.35313)
			(xy 69.907658 -92.391484) (xy 70.06971 -92.494354)
		)
		(stroke
			(width 0)
			(type solid)
		)
		(fill yes)
		(layer "In11.Cu")
		(net "M_M_DQ<9>")
	)
	(gr_poly
		(pts
			(xy 70.260972 -91.393264) (xy 70.252844 -91.201494) (xy 70.230746 -91.162886) (xy 69.885306 -91.36253)
			(xy 69.907658 -91.400884) (xy 70.06971 -91.503754)
		)
		(stroke
			(width 0)
			(type solid)
		)
		(fill yes)
		(layer "In11.Cu")
		(net "M_M_DQ<13>")
	)
	(gr_poly
		(pts
			(xy 70.260972 -90.402664) (xy 70.252844 -90.210894) (xy 70.230746 -90.172286) (xy 69.885306 -90.37193)
			(xy 69.907658 -90.410284) (xy 70.06971 -90.513154)
		)
		(stroke
			(width 0)
			(type solid)
		)
		(fill yes)
		(layer "In11.Cu")
		(net "M_M_DQ<3>")
	)
	(gr_poly
		(pts
			(xy 70.260972 -89.412064) (xy 70.252844 -89.220294) (xy 70.230746 -89.181686) (xy 69.885306 -89.38133)
			(xy 69.907658 -89.419684) (xy 70.06971 -89.522554)
		)
		(stroke
			(width 0)
			(type solid)
		)
		(fill yes)
		(layer "In11.Cu")
		(net "M_M_DQ<7>")
	)
	(gr_poly
		(pts
			(xy 70.260972 -88.421464) (xy 70.252844 -88.229694) (xy 70.230746 -88.191086) (xy 69.885306 -88.39073)
			(xy 69.907658 -88.429084) (xy 70.06971 -88.531954)
		)
		(stroke
			(width 0)
			(type solid)
		)
		(fill yes)
		(layer "In11.Cu")
		(net "M_M_DQS_DP<0>")
	)
	(gr_poly
		(pts
			(xy 70.260972 -87.430864) (xy 70.252844 -87.239094) (xy 70.230746 -87.200486) (xy 69.885306 -87.40013)
			(xy 69.907658 -87.438484) (xy 70.06971 -87.541354)
		)
		(stroke
			(width 0)
			(type solid)
		)
		(fill yes)
		(layer "In11.Cu")
		(net "M_M_DQS_DN<9>")
	)
	(gr_poly
		(pts
			(xy 70.260972 -86.440264) (xy 70.252844 -86.248494) (xy 70.230746 -86.209886) (xy 69.885306 -86.40953)
			(xy 69.907658 -86.447884) (xy 70.06971 -86.550754)
		)
		(stroke
			(width 0)
			(type solid)
		)
		(fill yes)
		(layer "In11.Cu")
		(net "M_M_DQ<1>")
	)
	(gr_poly
		(pts
			(xy 70.260972 -85.449664) (xy 70.252844 -85.257894) (xy 70.230746 -85.219286) (xy 69.885306 -85.41893)
			(xy 69.907658 -85.457284) (xy 70.06971 -85.560154)
		)
		(stroke
			(width 0)
			(type solid)
		)
		(fill yes)
		(layer "In11.Cu")
		(net "M_M_DQ<5>")
	)
	(gr_poly
		(pts
			(xy 70.38848 -100.850954) (xy 70.55866 -100.762054) (xy 70.55866 -100.541074) (xy 70.38848 -100.452174)
			(xy 70.344284 -100.452174) (xy 70.34403 -100.851208)
		)
		(stroke
			(width 0)
			(type solid)
		)
		(fill yes)
		(layer "In11.Cu")
		(net "M_M_DQ<17>")
	)
	(gr_poly
		(pts
			(xy 70.38848 -53.323744) (xy 70.55866 -53.235098) (xy 70.55866 -53.014118) (xy 70.38848 -52.925218)
			(xy 70.34403 -52.924964) (xy 70.34403 -53.323998)
		)
		(stroke
			(width 0)
			(type solid)
		)
		(fill yes)
		(layer "In11.Cu")
		(net "M_J_DQ<17>")
	)
	(gr_poly
		(pts
			(xy 70.40245 -103.39832) (xy 70.32879 -103.19893) (xy 70.297548 -103.167434) (xy 70.01002 -103.454962)
			(xy 70.041516 -103.486204) (xy 70.240906 -103.559864)
		)
		(stroke
			(width 0)
			(type solid)
		)
		(fill yes)
		(layer "In11.Cu")
		(net "M_M_DQS_DN<11>")
	)
	(gr_poly
		(pts
			(xy 70.416674 -102.778814) (xy 70.385178 -102.747318) (xy 70.186042 -102.673658) (xy 70.024244 -102.835456)
			(xy 70.097904 -103.034592) (xy 70.1294 -103.066088)
		)
		(stroke
			(width 0)
			(type solid)
		)
		(fill yes)
		(layer "In11.Cu")
		(net "M_M_DQS_DP<11>")
	)
	(gr_poly
		(pts
			(xy 70.457314 -65.150238) (xy 70.479666 -65.111884) (xy 70.134226 -64.91224) (xy 70.112128 -64.950848)
			(xy 70.104 -65.142618) (xy 70.295262 -65.253108)
		)
		(stroke
			(width 0)
			(type solid)
		)
		(fill yes)
		(layer "In11.Cu")
		(net "M_J_DQS_DP<9>")
	)
	(gr_poly
		(pts
			(xy 70.457314 -60.197238) (xy 70.479666 -60.158884) (xy 70.134226 -59.95924) (xy 70.112128 -59.997848)
			(xy 70.104 -60.189618) (xy 70.295262 -60.300108)
		)
		(stroke
			(width 0)
			(type solid)
		)
		(fill yes)
		(layer "In11.Cu")
		(net "M_J_DQ<8>")
	)
	(gr_poly
		(pts
			(xy 70.457314 -58.216038) (xy 70.479666 -58.177684) (xy 70.134226 -57.97804) (xy 70.112128 -58.016648)
			(xy 70.104 -58.208418) (xy 70.295262 -58.318908)
		)
		(stroke
			(width 0)
			(type solid)
		)
		(fill yes)
		(layer "In11.Cu")
		(net "M_J_DQS_DP<1>")
	)
	(gr_poly
		(pts
			(xy 70.457314 -54.253638) (xy 70.479666 -54.215284) (xy 70.134226 -54.01564) (xy 70.112128 -54.054248)
			(xy 70.104 -54.246018) (xy 70.295262 -54.356508)
		)
		(stroke
			(width 0)
			(type solid)
		)
		(fill yes)
		(layer "In11.Cu")
		(net "M_J_DQ<16>")
	)
	(gr_poly
		(pts
			(xy 70.458838 -67.1322) (xy 70.48119 -67.093592) (xy 70.13575 -66.894456) (xy 70.113652 -66.93281)
			(xy 70.105524 -67.12458) (xy 70.296786 -67.23507)
		)
		(stroke
			(width 0)
			(type solid)
		)
		(fill yes)
		(layer "In11.Cu")
		(net "M_J_DQ<4>")
	)
	(gr_poly
		(pts
			(xy 70.458838 -66.1416) (xy 70.48119 -66.102992) (xy 70.13575 -65.903602) (xy 70.113652 -65.94221)
			(xy 70.105524 -66.13398) (xy 70.296786 -66.24447)
		)
		(stroke
			(width 0)
			(type solid)
		)
		(fill yes)
		(layer "In11.Cu")
		(net "M_J_DQ<0>")
	)
	(gr_poly
		(pts
			(xy 70.458838 -63.1698) (xy 70.48119 -63.131192) (xy 70.13575 -62.931802) (xy 70.113652 -62.97041)
			(xy 70.105524 -63.16218) (xy 70.296786 -63.27267)
		)
		(stroke
			(width 0)
			(type solid)
		)
		(fill yes)
		(layer "In11.Cu")
		(net "M_J_DQ<6>")
	)
	(gr_poly
		(pts
			(xy 70.458838 -62.1792) (xy 70.48119 -62.140592) (xy 70.13575 -61.941202) (xy 70.113652 -61.97981)
			(xy 70.105524 -62.17158) (xy 70.296786 -62.28207)
		)
		(stroke
			(width 0)
			(type solid)
		)
		(fill yes)
		(layer "In11.Cu")
		(net "M_J_DQ<2>")
	)
	(gr_poly
		(pts
			(xy 70.458838 -61.1886) (xy 70.48119 -61.149992) (xy 70.13575 -60.950602) (xy 70.113652 -60.98921)
			(xy 70.105524 -61.18098) (xy 70.296786 -61.29147)
		)
		(stroke
			(width 0)
			(type solid)
		)
		(fill yes)
		(layer "In11.Cu")
		(net "M_J_DQ<12>")
	)
	(gr_poly
		(pts
			(xy 70.458838 -57.2262) (xy 70.48119 -57.187592) (xy 70.13575 -56.988202) (xy 70.113652 -57.02681)
			(xy 70.105524 -57.21858) (xy 70.296786 -57.32907)
		)
		(stroke
			(width 0)
			(type solid)
		)
		(fill yes)
		(layer "In11.Cu")
		(net "M_J_DQ<14>")
	)
	(gr_poly
		(pts
			(xy 70.458838 -56.2356) (xy 70.48119 -56.196992) (xy 70.13575 -55.997602) (xy 70.113652 -56.03621)
			(xy 70.105524 -56.22798) (xy 70.296786 -56.33847)
		)
		(stroke
			(width 0)
			(type solid)
		)
		(fill yes)
		(layer "In11.Cu")
		(net "M_J_DQ<10>")
	)
	(gr_poly
		(pts
			(xy 70.458838 -55.245) (xy 70.48119 -55.206392) (xy 70.13575 -55.007002) (xy 70.113652 -55.04561)
			(xy 70.105524 -55.23738) (xy 70.296786 -55.34787)
		)
		(stroke
			(width 0)
			(type solid)
		)
		(fill yes)
		(layer "In11.Cu")
		(net "M_J_DQ<20>")
	)
	(gr_poly
		(pts
			(xy 70.460616 -52.274216) (xy 70.482968 -52.235608) (xy 70.137528 -52.036218) (xy 70.11543 -52.074826)
			(xy 70.107302 -52.266596) (xy 70.298564 -52.377086)
		)
		(stroke
			(width 0)
			(type solid)
		)
		(fill yes)
		(layer "In11.Cu")
		(net "M_J_DQS_DP<11>")
	)
	(gr_poly
		(pts
			(xy 70.461124 -59.20867) (xy 70.483476 -59.170316) (xy 70.138036 -58.970672) (xy 70.115938 -59.00928)
			(xy 70.10781 -59.20105) (xy 70.299072 -59.31154)
		)
		(stroke
			(width 0)
			(type solid)
		)
		(fill yes)
		(layer "In11.Cu")
		(net "M_J_DQS_DP<10>")
	)
	(gr_poly
		(pts
			(xy 70.479666 -96.58985) (xy 70.457314 -96.551242) (xy 70.295262 -96.448372) (xy 70.104 -96.558862)
			(xy 70.112128 -96.750632) (xy 70.134226 -96.78924)
		)
		(stroke
			(width 0)
			(type solid)
		)
		(fill yes)
		(layer "In11.Cu")
		(net "M_M_DQ<20>")
	)
	(gr_poly
		(pts
			(xy 70.479666 -95.59925) (xy 70.457314 -95.560642) (xy 70.295262 -95.457772) (xy 70.104 -95.568262)
			(xy 70.112128 -95.760032) (xy 70.134226 -95.79864)
		)
		(stroke
			(width 0)
			(type solid)
		)
		(fill yes)
		(layer "In11.Cu")
		(net "M_M_DQ<10>")
	)
	(gr_poly
		(pts
			(xy 70.479666 -92.62745) (xy 70.457314 -92.588842) (xy 70.295262 -92.485972) (xy 70.104 -92.596462)
			(xy 70.112128 -92.788232) (xy 70.134226 -92.82684)
		)
		(stroke
			(width 0)
			(type solid)
		)
		(fill yes)
		(layer "In11.Cu")
		(net "M_M_DQS_DP<10>")
	)
	(gr_poly
		(pts
			(xy 70.479666 -91.63685) (xy 70.457314 -91.598242) (xy 70.295262 -91.495372) (xy 70.104 -91.605862)
			(xy 70.112128 -91.797632) (xy 70.134226 -91.83624)
		)
		(stroke
			(width 0)
			(type solid)
		)
		(fill yes)
		(layer "In11.Cu")
		(net "M_M_DQ<8>")
	)
	(gr_poly
		(pts
			(xy 70.479666 -90.64625) (xy 70.457314 -90.607642) (xy 70.295262 -90.504772) (xy 70.104 -90.615262)
			(xy 70.112128 -90.807032) (xy 70.134226 -90.84564)
		)
		(stroke
			(width 0)
			(type solid)
		)
		(fill yes)
		(layer "In11.Cu")
		(net "M_M_DQ<12>")
	)
	(gr_poly
		(pts
			(xy 70.479666 -89.65565) (xy 70.457314 -89.617042) (xy 70.295262 -89.514172) (xy 70.104 -89.624662)
			(xy 70.112128 -89.816432) (xy 70.134226 -89.85504)
		)
		(stroke
			(width 0)
			(type solid)
		)
		(fill yes)
		(layer "In11.Cu")
		(net "M_M_DQ<2>")
	)
	(gr_poly
		(pts
			(xy 70.479666 -88.66505) (xy 70.457314 -88.626442) (xy 70.295262 -88.523572) (xy 70.104 -88.634062)
			(xy 70.112128 -88.825832) (xy 70.134226 -88.86444)
		)
		(stroke
			(width 0)
			(type solid)
		)
		(fill yes)
		(layer "In11.Cu")
		(net "M_M_DQ<6>")
	)
	(gr_poly
		(pts
			(xy 70.479666 -87.67445) (xy 70.457314 -87.635842) (xy 70.295262 -87.532972) (xy 70.104 -87.643462)
			(xy 70.112128 -87.835232) (xy 70.134226 -87.87384)
		)
		(stroke
			(width 0)
			(type solid)
		)
		(fill yes)
		(layer "In11.Cu")
		(net "M_M_DQS_DN<0>")
	)
	(gr_poly
		(pts
			(xy 70.479666 -86.68385) (xy 70.457314 -86.645242) (xy 70.295262 -86.542372) (xy 70.104 -86.652862)
			(xy 70.112128 -86.844632) (xy 70.134226 -86.88324)
		)
		(stroke
			(width 0)
			(type solid)
		)
		(fill yes)
		(layer "In11.Cu")
		(net "M_M_DQS_DP<9>")
	)
	(gr_poly
		(pts
			(xy 70.479666 -85.69325) (xy 70.457314 -85.654642) (xy 70.295262 -85.551772) (xy 70.104 -85.662262)
			(xy 70.112128 -85.854032) (xy 70.134226 -85.89264)
		)
		(stroke
			(width 0)
			(type solid)
		)
		(fill yes)
		(layer "In11.Cu")
		(net "M_M_DQ<0>")
	)
	(gr_poly
		(pts
			(xy 70.479666 -84.70265) (xy 70.457314 -84.664042) (xy 70.295262 -84.561172) (xy 70.104 -84.671662)
			(xy 70.112128 -84.863432) (xy 70.134226 -84.90204)
		)
		(stroke
			(width 0)
			(type solid)
		)
		(fill yes)
		(layer "In11.Cu")
		(net "M_M_DQ<4>")
	)
	(gr_poly
		(pts
			(xy 70.48119 -93.61678) (xy 70.458838 -93.578426) (xy 70.296786 -93.475556) (xy 70.105524 -93.586046)
			(xy 70.113652 -93.777816) (xy 70.13575 -93.81617)
		)
		(stroke
			(width 0)
			(type solid)
		)
		(fill yes)
		(layer "In11.Cu")
		(net "M_M_DQS_DN<1>")
	)
	(gr_poly
		(pts
			(xy 70.483476 -94.60611) (xy 70.461124 -94.567756) (xy 70.299072 -94.464886) (xy 70.10781 -94.575376)
			(xy 70.115938 -94.767146) (xy 70.138036 -94.805754)
		)
		(stroke
			(width 0)
			(type solid)
		)
		(fill yes)
		(layer "In11.Cu")
		(net "M_M_DQ<14>")
	)
	(gr_poly
		(pts
			(xy 70.55866 -51.24958) (xy 70.55866 -51.0286) (xy 70.38848 -50.9397) (xy 70.34403 -50.9397) (xy 70.34403 -51.33848)
			(xy 70.38848 -51.33848)
		)
		(stroke
			(width 0)
			(type solid)
		)
		(fill yes)
		(layer "In11.Cu")
		(net "M_J_DQS_DN<11>")
	)
	(gr_poly
		(pts
			(xy 70.558914 -99.77628) (xy 70.558914 -99.5553) (xy 70.388734 -99.4664) (xy 70.344284 -99.4664)
			(xy 70.344284 -99.86518) (xy 70.388734 -99.86518)
		)
		(stroke
			(width 0)
			(type solid)
		)
		(fill yes)
		(layer "In11.Cu")
		(net "M_M_DQ<17>")
	)
	(gr_poly
		(pts
			(xy 70.558914 -98.79203) (xy 70.558914 -98.57105) (xy 70.388734 -98.48215) (xy 70.344284 -98.48215)
			(xy 70.344284 -98.88093) (xy 70.388734 -98.88093)
		)
		(stroke
			(width 0)
			(type solid)
		)
		(fill yes)
		(layer "In11.Cu")
		(net "M_M_DQ<17>")
	)
	(gr_poly
		(pts
			(xy 70.68566 -104.552242) (xy 70.612 -104.352852) (xy 70.580758 -104.321356) (xy 70.29323 -104.608884)
			(xy 70.324726 -104.640126) (xy 70.524116 -104.713786)
		)
		(stroke
			(width 0)
			(type solid)
		)
		(fill yes)
		(layer "In11.Cu")
		(net "M_M_DQS_DP<2>")
	)
	(gr_poly
		(pts
			(xy 70.870572 -101.714554) (xy 70.826122 -101.714554) (xy 70.633082 -101.803454) (xy 70.633082 -102.032054)
			(xy 70.826122 -102.120954) (xy 70.870572 -102.120954)
		)
		(stroke
			(width 0)
			(type solid)
		)
		(fill yes)
		(layer "In11.Cu")
		(net "M_M_DQS_DP<11>")
	)
	(gr_poly
		(pts
			(xy 70.879208 -100.463096) (xy 70.834758 -100.463096) (xy 70.664578 -100.551996) (xy 70.664578 -100.772976)
			(xy 70.834758 -100.861876) (xy 70.879208 -100.861876)
		)
		(stroke
			(width 0)
			(type solid)
		)
		(fill yes)
		(layer "In11.Cu")
		(net "M_M_DQS_DP<11>")
	)
	(gr_poly
		(pts
			(xy 70.879208 -99.4664) (xy 70.834758 -99.4664) (xy 70.664578 -99.5553) (xy 70.664578 -99.77628)
			(xy 70.834758 -99.86518) (xy 70.879208 -99.86518)
		)
		(stroke
			(width 0)
			(type solid)
		)
		(fill yes)
		(layer "In11.Cu")
		(net "M_M_DQS_DP<11>")
	)
	(gr_poly
		(pts
			(xy 70.879716 -52.907184) (xy 70.835266 -52.907184) (xy 70.665086 -52.996084) (xy 70.665086 -53.217064)
			(xy 70.835012 -53.305964) (xy 70.879716 -53.305964)
		)
		(stroke
			(width 0)
			(type solid)
		)
		(fill yes)
		(layer "In11.Cu")
		(net "M_J_DQS_DP<11>")
	)
	(gr_poly
		(pts
			(xy 70.896988 -98.47326) (xy 70.852538 -98.473514) (xy 70.682358 -98.562414) (xy 70.682358 -98.78314)
			(xy 70.852538 -98.87204) (xy 70.896734 -98.872294)
		)
		(stroke
			(width 0)
			(type solid)
		)
		(fill yes)
		(layer "In11.Cu")
		(net "M_M_DQS_DP<11>")
	)
	(gr_poly
		(pts
			(xy 71.102982 -102.697788) (xy 71.029322 -102.498398) (xy 70.99808 -102.466902) (xy 70.710552 -102.75443)
			(xy 70.742048 -102.785672) (xy 70.941438 -102.859332)
		)
		(stroke
			(width 0)
			(type solid)
		)
		(fill yes)
		(layer "In11.Cu")
		(net "M_M_DQS_DN<11>")
	)
	(gr_poly
		(pts
			(xy 71.107554 -59.105546) (xy 71.115682 -58.913776) (xy 70.92442 -58.803286) (xy 70.762368 -58.906156)
			(xy 70.740016 -58.94451) (xy 71.085456 -59.1439)
		)
		(stroke
			(width 0)
			(type solid)
		)
		(fill yes)
		(layer "In11.Cu")
		(net "M_J_DQS_DN<10>")
	)
	(gr_poly
		(pts
			(xy 71.10984 -65.05067) (xy 71.117968 -64.8589) (xy 70.926706 -64.74841) (xy 70.764654 -64.85128)
			(xy 70.742302 -64.889634) (xy 71.087742 -65.089024)
		)
		(stroke
			(width 0)
			(type solid)
		)
		(fill yes)
		(layer "In11.Cu")
		(net "M_J_DQS_DN<9>")
	)
	(gr_poly
		(pts
			(xy 71.10984 -52.172616) (xy 71.117968 -51.980846) (xy 70.926706 -51.870356) (xy 70.764654 -51.973226)
			(xy 70.742302 -52.01158) (xy 71.087742 -52.211224)
		)
		(stroke
			(width 0)
			(type solid)
		)
		(fill yes)
		(layer "In11.Cu")
		(net "M_J_DQS_DN<11>")
	)
	(gr_poly
		(pts
			(xy 71.111364 -67.032632) (xy 71.119492 -66.840862) (xy 70.92823 -66.730372) (xy 70.766178 -66.833242)
			(xy 70.743826 -66.871596) (xy 71.089266 -67.07124)
		)
		(stroke
			(width 0)
			(type solid)
		)
		(fill yes)
		(layer "In11.Cu")
		(net "M_J_DQ<5>")
	)
	(gr_poly
		(pts
			(xy 71.111364 -66.042032) (xy 71.119492 -65.850262) (xy 70.92823 -65.739772) (xy 70.766178 -65.842642)
			(xy 70.743826 -65.880996) (xy 71.089266 -66.08064)
		)
		(stroke
			(width 0)
			(type solid)
		)
		(fill yes)
		(layer "In11.Cu")
		(net "M_J_DQ<1>")
	)
	(gr_poly
		(pts
			(xy 71.111364 -64.060832) (xy 71.119492 -63.869062) (xy 70.92823 -63.758572) (xy 70.766178 -63.861442)
			(xy 70.743826 -63.899796) (xy 71.089266 -64.09944)
		)
		(stroke
			(width 0)
			(type solid)
		)
		(fill yes)
		(layer "In11.Cu")
		(net "M_J_DQS_DN<0>")
	)
	(gr_poly
		(pts
			(xy 71.111364 -63.070232) (xy 71.119492 -62.878462) (xy 70.92823 -62.767972) (xy 70.766178 -62.870842)
			(xy 70.743826 -62.909196) (xy 71.089266 -63.10884)
		)
		(stroke
			(width 0)
			(type solid)
		)
		(fill yes)
		(layer "In11.Cu")
		(net "M_J_DQ<7>")
	)
	(gr_poly
		(pts
			(xy 71.111364 -62.079632) (xy 71.119492 -61.887862) (xy 70.92823 -61.777372) (xy 70.766178 -61.880242)
			(xy 70.743826 -61.918596) (xy 71.089266 -62.11824)
		)
		(stroke
			(width 0)
			(type solid)
		)
		(fill yes)
		(layer "In11.Cu")
		(net "M_J_DQ<3>")
	)
	(gr_poly
		(pts
			(xy 71.111364 -61.089032) (xy 71.119492 -60.897262) (xy 70.92823 -60.786772) (xy 70.766178 -60.889642)
			(xy 70.743826 -60.927996) (xy 71.089266 -61.12764)
		)
		(stroke
			(width 0)
			(type solid)
		)
		(fill yes)
		(layer "In11.Cu")
		(net "M_J_DQ<13>")
	)
	(gr_poly
		(pts
			(xy 71.111364 -60.098432) (xy 71.119492 -59.906662) (xy 70.92823 -59.796172) (xy 70.766178 -59.899042)
			(xy 70.743826 -59.937396) (xy 71.089266 -60.13704)
		)
		(stroke
			(width 0)
			(type solid)
		)
		(fill yes)
		(layer "In11.Cu")
		(net "M_J_DQ<9>")
	)
	(gr_poly
		(pts
			(xy 71.111364 -58.116978) (xy 71.119492 -57.925208) (xy 70.92823 -57.814718) (xy 70.766178 -57.917588)
			(xy 70.743826 -57.955942) (xy 71.089266 -58.155332)
		)
		(stroke
			(width 0)
			(type solid)
		)
		(fill yes)
		(layer "In11.Cu")
		(net "M_J_DQS_DN<1>")
	)
	(gr_poly
		(pts
			(xy 71.111364 -57.126632) (xy 71.119492 -56.934862) (xy 70.92823 -56.824372) (xy 70.766178 -56.927242)
			(xy 70.743826 -56.965596) (xy 71.089266 -57.16524)
		)
		(stroke
			(width 0)
			(type solid)
		)
		(fill yes)
		(layer "In11.Cu")
		(net "M_J_DQ<15>")
	)
	(gr_poly
		(pts
			(xy 71.111364 -56.136032) (xy 71.119492 -55.944262) (xy 70.92823 -55.833772) (xy 70.766178 -55.936642)
			(xy 70.743826 -55.974996) (xy 71.089266 -56.17464)
		)
		(stroke
			(width 0)
			(type solid)
		)
		(fill yes)
		(layer "In11.Cu")
		(net "M_J_DQ<11>")
	)
	(gr_poly
		(pts
			(xy 71.111364 -55.145432) (xy 71.119492 -54.953662) (xy 70.92823 -54.843172) (xy 70.766178 -54.946042)
			(xy 70.743826 -54.984396) (xy 71.089266 -55.18404)
		)
		(stroke
			(width 0)
			(type solid)
		)
		(fill yes)
		(layer "In11.Cu")
		(net "M_J_DQ<21>")
	)
	(gr_poly
		(pts
			(xy 71.111364 -54.154832) (xy 71.119492 -53.963062) (xy 70.92823 -53.852572) (xy 70.766178 -53.955442)
			(xy 70.743826 -53.993796) (xy 71.089266 -54.19344)
		)
		(stroke
			(width 0)
			(type solid)
		)
		(fill yes)
		(layer "In11.Cu")
		(net "M_J_DQ<17>")
	)
	(gr_poly
		(pts
			(xy 71.115682 -94.86265) (xy 71.107554 -94.67088) (xy 71.085456 -94.632272) (xy 70.740016 -94.831662)
			(xy 70.762368 -94.87027) (xy 70.92442 -94.97314)
		)
		(stroke
			(width 0)
			(type solid)
		)
		(fill yes)
		(layer "In11.Cu")
		(net "M_M_DQ<15>")
	)
	(gr_poly
		(pts
			(xy 71.117968 -97.83318) (xy 71.10984 -97.64141) (xy 71.087742 -97.602802) (xy 70.742302 -97.802446)
			(xy 70.764654 -97.8408) (xy 70.926706 -97.94367)
		)
		(stroke
			(width 0)
			(type solid)
		)
		(fill yes)
		(layer "In11.Cu")
		(net "M_M_DQ<17>")
	)
	(gr_poly
		(pts
			(xy 71.117968 -96.84258) (xy 71.10984 -96.65081) (xy 71.087742 -96.612202) (xy 70.742302 -96.811846)
			(xy 70.764654 -96.8502) (xy 70.926706 -96.95307)
		)
		(stroke
			(width 0)
			(type solid)
		)
		(fill yes)
		(layer "In11.Cu")
		(net "M_M_DQ<21>")
	)
	(gr_poly
		(pts
			(xy 71.117968 -95.85198) (xy 71.10984 -95.66021) (xy 71.087742 -95.621602) (xy 70.742302 -95.821246)
			(xy 70.764654 -95.8596) (xy 70.926706 -95.96247)
		)
		(stroke
			(width 0)
			(type solid)
		)
		(fill yes)
		(layer "In11.Cu")
		(net "M_M_DQ<11>")
	)
	(gr_poly
		(pts
			(xy 71.117968 -92.88018) (xy 71.10984 -92.68841) (xy 71.087742 -92.649802) (xy 70.742302 -92.849446)
			(xy 70.764654 -92.8878) (xy 70.926706 -92.99067)
		)
		(stroke
			(width 0)
			(type solid)
		)
		(fill yes)
		(layer "In11.Cu")
		(net "M_M_DQS_DN<10>")
	)
	(gr_poly
		(pts
			(xy 71.117968 -91.88958) (xy 71.10984 -91.69781) (xy 71.087742 -91.659202) (xy 70.742302 -91.858846)
			(xy 70.764654 -91.8972) (xy 70.926706 -92.00007)
		)
		(stroke
			(width 0)
			(type solid)
		)
		(fill yes)
		(layer "In11.Cu")
		(net "M_M_DQ<9>")
	)
	(gr_poly
		(pts
			(xy 71.117968 -90.89898) (xy 71.10984 -90.70721) (xy 71.087742 -90.668602) (xy 70.742302 -90.868246)
			(xy 70.764654 -90.9066) (xy 70.926706 -91.00947)
		)
		(stroke
			(width 0)
			(type solid)
		)
		(fill yes)
		(layer "In11.Cu")
		(net "M_M_DQ<13>")
	)
	(gr_poly
		(pts
			(xy 71.117968 -89.90838) (xy 71.10984 -89.71661) (xy 71.087742 -89.678002) (xy 70.742302 -89.877646)
			(xy 70.764654 -89.916) (xy 70.926706 -90.01887)
		)
		(stroke
			(width 0)
			(type solid)
		)
		(fill yes)
		(layer "In11.Cu")
		(net "M_M_DQ<3>")
	)
	(gr_poly
		(pts
			(xy 71.117968 -88.91778) (xy 71.10984 -88.72601) (xy 71.087742 -88.687402) (xy 70.742302 -88.887046)
			(xy 70.764654 -88.9254) (xy 70.926706 -89.02827)
		)
		(stroke
			(width 0)
			(type solid)
		)
		(fill yes)
		(layer "In11.Cu")
		(net "M_M_DQ<7>")
	)
	(gr_poly
		(pts
			(xy 71.117968 -87.92718) (xy 71.10984 -87.73541) (xy 71.087742 -87.696802) (xy 70.742302 -87.896446)
			(xy 70.764654 -87.9348) (xy 70.926706 -88.03767)
		)
		(stroke
			(width 0)
			(type solid)
		)
		(fill yes)
		(layer "In11.Cu")
		(net "M_M_DQS_DP<0>")
	)
	(gr_poly
		(pts
			(xy 71.117968 -86.93658) (xy 71.10984 -86.74481) (xy 71.087742 -86.706202) (xy 70.742302 -86.905846)
			(xy 70.764654 -86.9442) (xy 70.926706 -87.04707)
		)
		(stroke
			(width 0)
			(type solid)
		)
		(fill yes)
		(layer "In11.Cu")
		(net "M_M_DQS_DN<9>")
	)
	(gr_poly
		(pts
			(xy 71.117968 -85.94598) (xy 71.10984 -85.75421) (xy 71.087742 -85.715602) (xy 70.742302 -85.915246)
			(xy 70.764654 -85.9536) (xy 70.926706 -86.05647)
		)
		(stroke
			(width 0)
			(type solid)
		)
		(fill yes)
		(layer "In11.Cu")
		(net "M_M_DQ<1>")
	)
	(gr_poly
		(pts
			(xy 71.117968 -84.95538) (xy 71.10984 -84.76361) (xy 71.087742 -84.725002) (xy 70.742302 -84.924646)
			(xy 70.764654 -84.963) (xy 70.926706 -85.06587)
		)
		(stroke
			(width 0)
			(type solid)
		)
		(fill yes)
		(layer "In11.Cu")
		(net "M_M_DQ<5>")
	)
	(gr_poly
		(pts
			(xy 71.119492 -93.870018) (xy 71.111364 -93.678248) (xy 71.089266 -93.639894) (xy 70.743826 -93.83903)
			(xy 70.766178 -93.877638) (xy 70.92823 -93.980508)
		)
		(stroke
			(width 0)
			(type solid)
		)
		(fill yes)
		(layer "In11.Cu")
		(net "M_M_DQS_DP<1>")
	)
	(gr_poly
		(pts
			(xy 71.137526 -103.47706) (xy 71.10603 -103.445818) (xy 70.90664 -103.372158) (xy 70.745096 -103.533702)
			(xy 70.818756 -103.733092) (xy 70.849998 -103.764588)
		)
		(stroke
			(width 0)
			(type solid)
		)
		(fill yes)
		(layer "In11.Cu")
		(net "M_M_DQS_DN<2>")
	)
	(gr_poly
		(pts
			(xy 71.315834 -67.626484) (xy 71.338186 -67.587876) (xy 70.992746 -67.38874) (xy 70.970648 -67.427094)
			(xy 70.96252 -67.618864) (xy 71.153782 -67.729354)
		)
		(stroke
			(width 0)
			(type solid)
		)
		(fill yes)
		(layer "In11.Cu")
		(net "M_J_DQ<4>")
	)
	(gr_poly
		(pts
			(xy 71.315834 -66.635884) (xy 71.338186 -66.597276) (xy 70.992746 -66.397886) (xy 70.970648 -66.436494)
			(xy 70.96252 -66.628264) (xy 71.153782 -66.738754)
		)
		(stroke
			(width 0)
			(type solid)
		)
		(fill yes)
		(layer "In11.Cu")
		(net "M_J_DQ<0>")
	)
	(gr_poly
		(pts
			(xy 71.315834 -65.645284) (xy 71.338186 -65.60693) (xy 70.992746 -65.407286) (xy 70.970648 -65.445894)
			(xy 70.96252 -65.637664) (xy 71.153782 -65.748154)
		)
		(stroke
			(width 0)
			(type solid)
		)
		(fill yes)
		(layer "In11.Cu")
		(net "M_J_DQS_DP<9>")
	)
	(gr_poly
		(pts
			(xy 71.315834 -64.654684) (xy 71.338186 -64.61633) (xy 70.992746 -64.416686) (xy 70.970648 -64.455294)
			(xy 70.96252 -64.647064) (xy 71.153782 -64.757554)
		)
		(stroke
			(width 0)
			(type solid)
		)
		(fill yes)
		(layer "In11.Cu")
		(net "M_J_DQS_DP<0>")
	)
	(gr_poly
		(pts
			(xy 71.315834 -63.664084) (xy 71.338186 -63.62573) (xy 70.992746 -63.426086) (xy 70.970648 -63.464694)
			(xy 70.96252 -63.656464) (xy 71.153782 -63.766954)
		)
		(stroke
			(width 0)
			(type solid)
		)
		(fill yes)
		(layer "In11.Cu")
		(net "M_J_DQ<6>")
	)
	(gr_poly
		(pts
			(xy 71.315834 -62.673484) (xy 71.338186 -62.63513) (xy 70.992746 -62.435486) (xy 70.970648 -62.474094)
			(xy 70.96252 -62.665864) (xy 71.153782 -62.776354)
		)
		(stroke
			(width 0)
			(type solid)
		)
		(fill yes)
		(layer "In11.Cu")
		(net "M_J_DQ<2>")
	)
	(gr_poly
		(pts
			(xy 71.315834 -61.682884) (xy 71.338186 -61.64453) (xy 70.992746 -61.444886) (xy 70.970648 -61.483494)
			(xy 70.96252 -61.675264) (xy 71.153782 -61.785754)
		)
		(stroke
			(width 0)
			(type solid)
		)
		(fill yes)
		(layer "In11.Cu")
		(net "M_J_DQ<12>")
	)
	(gr_poly
		(pts
			(xy 71.315834 -60.692284) (xy 71.338186 -60.65393) (xy 70.992746 -60.454286) (xy 70.970648 -60.492894)
			(xy 70.96252 -60.684664) (xy 71.153782 -60.795154)
		)
		(stroke
			(width 0)
			(type solid)
		)
		(fill yes)
		(layer "In11.Cu")
		(net "M_J_DQ<8>")
	)
	(gr_poly
		(pts
			(xy 71.315834 -59.701684) (xy 71.338186 -59.66333) (xy 70.992746 -59.463686) (xy 70.970648 -59.502294)
			(xy 70.96252 -59.694064) (xy 71.153782 -59.804554)
		)
		(stroke
			(width 0)
			(type solid)
		)
		(fill yes)
		(layer "In11.Cu")
		(net "M_J_DQS_DP<10>")
	)
	(gr_poly
		(pts
			(xy 71.315834 -58.711338) (xy 71.338186 -58.672984) (xy 70.992746 -58.47334) (xy 70.970648 -58.511948)
			(xy 70.96252 -58.703718) (xy 71.153782 -58.814208)
		)
		(stroke
			(width 0)
			(type solid)
		)
		(fill yes)
		(layer "In11.Cu")
		(net "M_J_DQS_DP<1>")
	)
	(gr_poly
		(pts
			(xy 71.315834 -56.729884) (xy 71.338186 -56.69153) (xy 70.992746 -56.491886) (xy 70.970648 -56.530494)
			(xy 70.96252 -56.722264) (xy 71.153782 -56.832754)
		)
		(stroke
			(width 0)
			(type solid)
		)
		(fill yes)
		(layer "In11.Cu")
		(net "M_J_DQ<10>")
	)
	(gr_poly
		(pts
			(xy 71.315834 -55.739284) (xy 71.338186 -55.70093) (xy 70.992746 -55.501286) (xy 70.970648 -55.539894)
			(xy 70.96252 -55.731664) (xy 71.153782 -55.842154)
		)
		(stroke
			(width 0)
			(type solid)
		)
		(fill yes)
		(layer "In11.Cu")
		(net "M_J_DQ<20>")
	)
	(gr_poly
		(pts
			(xy 71.315834 -54.748684) (xy 71.338186 -54.71033) (xy 70.992746 -54.510686) (xy 70.970648 -54.549294)
			(xy 70.96252 -54.741064) (xy 71.153782 -54.851554)
		)
		(stroke
			(width 0)
			(type solid)
		)
		(fill yes)
		(layer "In11.Cu")
		(net "M_J_DQ<16>")
	)
	(gr_poly
		(pts
			(xy 71.319136 -53.759862) (xy 71.341488 -53.721254) (xy 70.996048 -53.521864) (xy 70.97395 -53.560472)
			(xy 70.965822 -53.752242) (xy 71.157084 -53.862732)
		)
		(stroke
			(width 0)
			(type solid)
		)
		(fill yes)
		(layer "In11.Cu")
		(net "M_J_DQS_DP<11>")
	)
	(gr_poly
		(pts
			(xy 71.319644 -57.72277) (xy 71.341996 -57.684416) (xy 70.996556 -57.484772) (xy 70.974458 -57.52338)
			(xy 70.96633 -57.71515) (xy 71.157592 -57.82564)
		)
		(stroke
			(width 0)
			(type solid)
		)
		(fill yes)
		(layer "In11.Cu")
		(net "M_J_DQ<14>")
	)
	(gr_poly
		(pts
			(xy 71.338186 -94.112842) (xy 71.315834 -94.074488) (xy 71.153782 -93.971618) (xy 70.96252 -94.082108)
			(xy 70.970648 -94.273878) (xy 70.992746 -94.312486)
		)
		(stroke
			(width 0)
			(type solid)
		)
		(fill yes)
		(layer "In11.Cu")
		(net "M_M_DQ<14>")
	)
	(gr_poly
		(pts
			(xy 71.33971 -97.08388) (xy 71.317358 -97.045526) (xy 71.155306 -96.942656) (xy 70.964044 -97.053146)
			(xy 70.972172 -97.244916) (xy 70.99427 -97.28327)
		)
		(stroke
			(width 0)
			(type solid)
		)
		(fill yes)
		(layer "In11.Cu")
		(net "M_M_DQ<16>")
	)
	(gr_poly
		(pts
			(xy 71.33971 -96.09328) (xy 71.317358 -96.054926) (xy 71.155306 -95.952056) (xy 70.964044 -96.062546)
			(xy 70.972172 -96.254316) (xy 70.99427 -96.29267)
		)
		(stroke
			(width 0)
			(type solid)
		)
		(fill yes)
		(layer "In11.Cu")
		(net "M_M_DQ<20>")
	)
	(gr_poly
		(pts
			(xy 71.33971 -95.10268) (xy 71.317358 -95.064326) (xy 71.155306 -94.961456) (xy 70.964044 -95.071946)
			(xy 70.972172 -95.263716) (xy 70.99427 -95.30207)
		)
		(stroke
			(width 0)
			(type solid)
		)
		(fill yes)
		(layer "In11.Cu")
		(net "M_M_DQ<10>")
	)
	(gr_poly
		(pts
			(xy 71.33971 -92.13088) (xy 71.317358 -92.092526) (xy 71.155306 -91.989656) (xy 70.964044 -92.100146)
			(xy 70.972172 -92.291916) (xy 70.99427 -92.33027)
		)
		(stroke
			(width 0)
			(type solid)
		)
		(fill yes)
		(layer "In11.Cu")
		(net "M_M_DQS_DP<10>")
	)
	(gr_poly
		(pts
			(xy 71.33971 -91.14028) (xy 71.317358 -91.101926) (xy 71.155306 -90.999056) (xy 70.964044 -91.109546)
			(xy 70.972172 -91.301316) (xy 70.99427 -91.33967)
		)
		(stroke
			(width 0)
			(type solid)
		)
		(fill yes)
		(layer "In11.Cu")
		(net "M_M_DQ<8>")
	)
	(gr_poly
		(pts
			(xy 71.33971 -90.14968) (xy 71.317358 -90.111326) (xy 71.155306 -90.008456) (xy 70.964044 -90.118946)
			(xy 70.972172 -90.310716) (xy 70.99427 -90.34907)
		)
		(stroke
			(width 0)
			(type solid)
		)
		(fill yes)
		(layer "In11.Cu")
		(net "M_M_DQ<12>")
	)
	(gr_poly
		(pts
			(xy 71.33971 -89.15908) (xy 71.317358 -89.120726) (xy 71.155306 -89.017856) (xy 70.964044 -89.128346)
			(xy 70.972172 -89.320116) (xy 70.99427 -89.35847)
		)
		(stroke
			(width 0)
			(type solid)
		)
		(fill yes)
		(layer "In11.Cu")
		(net "M_M_DQ<2>")
	)
	(gr_poly
		(pts
			(xy 71.33971 -88.16848) (xy 71.317358 -88.130126) (xy 71.155306 -88.027256) (xy 70.964044 -88.137746)
			(xy 70.972172 -88.329516) (xy 70.99427 -88.36787)
		)
		(stroke
			(width 0)
			(type solid)
		)
		(fill yes)
		(layer "In11.Cu")
		(net "M_M_DQ<6>")
	)
	(gr_poly
		(pts
			(xy 71.33971 -87.17788) (xy 71.317358 -87.139526) (xy 71.155306 -87.036656) (xy 70.964044 -87.147146)
			(xy 70.972172 -87.338916) (xy 70.99427 -87.37727)
		)
		(stroke
			(width 0)
			(type solid)
		)
		(fill yes)
		(layer "In11.Cu")
		(net "M_M_DQS_DN<0>")
	)
	(gr_poly
		(pts
			(xy 71.33971 -86.18728) (xy 71.317358 -86.148926) (xy 71.155306 -86.046056) (xy 70.964044 -86.156546)
			(xy 70.972172 -86.348316) (xy 70.99427 -86.38667)
		)
		(stroke
			(width 0)
			(type solid)
		)
		(fill yes)
		(layer "In11.Cu")
		(net "M_M_DQS_DP<9>")
	)
	(gr_poly
		(pts
			(xy 71.33971 -85.19668) (xy 71.317358 -85.158326) (xy 71.155306 -85.055456) (xy 70.964044 -85.165946)
			(xy 70.972172 -85.357716) (xy 70.99427 -85.39607)
		)
		(stroke
			(width 0)
			(type solid)
		)
		(fill yes)
		(layer "In11.Cu")
		(net "M_M_DQ<0>")
	)
	(gr_poly
		(pts
			(xy 71.33971 -84.20608) (xy 71.317358 -84.167726) (xy 71.155306 -84.064856) (xy 70.964044 -84.175346)
			(xy 70.972172 -84.367116) (xy 70.99427 -84.40547)
		)
		(stroke
			(width 0)
			(type solid)
		)
		(fill yes)
		(layer "In11.Cu")
		(net "M_M_DQ<4>")
	)
	(gr_poly
		(pts
			(xy 71.341996 -93.12021) (xy 71.319644 -93.081856) (xy 71.157592 -92.978986) (xy 70.96633 -93.089476)
			(xy 70.974458 -93.281246) (xy 70.996556 -93.319854)
		)
		(stroke
			(width 0)
			(type solid)
		)
		(fill yes)
		(layer "In11.Cu")
		(net "M_M_DQS_DN<1>")
	)
	(gr_poly
		(pts
			(xy 71.355966 -98.063558) (xy 71.33336 -98.025204) (xy 71.171308 -97.922334) (xy 70.9803 -98.03257)
			(xy 70.988428 -98.22434) (xy 71.010272 -98.262948)
		)
		(stroke
			(width 0)
			(type solid)
		)
		(fill yes)
		(layer "In11.Cu")
		(net "M_M_DQS_DP<11>")
	)
	(gr_poly
		(pts
			(xy 71.386192 -103.85171) (xy 71.312532 -103.65232) (xy 71.28129 -103.620824) (xy 70.993762 -103.908352)
			(xy 71.025258 -103.939594) (xy 71.224648 -104.013254)
		)
		(stroke
			(width 0)
			(type solid)
		)
		(fill yes)
		(layer "In11.Cu")
		(net "M_M_DQS_DP<2>")
	)
	(gr_poly
		(pts
			(xy 71.416926 -52.73802) (xy 71.416926 -52.51704) (xy 71.247 -52.42814) (xy 71.20255 -52.42814) (xy 71.202296 -52.82692)
			(xy 71.246746 -52.82692)
		)
		(stroke
			(width 0)
			(type solid)
		)
		(fill yes)
		(layer "In11.Cu")
		(net "M_J_DQS_DN<11>")
	)
	(gr_poly
		(pts
			(xy 71.417434 -101.26218) (xy 71.417434 -101.0412) (xy 71.247254 -100.9523) (xy 71.202804 -100.9523)
			(xy 71.202804 -101.35108) (xy 71.247254 -101.35108)
		)
		(stroke
			(width 0)
			(type solid)
		)
		(fill yes)
		(layer "In11.Cu")
		(net "M_M_DQS_DN<11>")
	)
	(gr_poly
		(pts
			(xy 71.417434 -100.284026) (xy 71.417434 -100.063046) (xy 71.247254 -99.974146) (xy 71.202804 -99.974146)
			(xy 71.202804 -100.372926) (xy 71.247254 -100.372926)
		)
		(stroke
			(width 0)
			(type solid)
		)
		(fill yes)
		(layer "In11.Cu")
		(net "M_M_DQS_DN<11>")
	)
	(gr_poly
		(pts
			(xy 71.417434 -99.28733) (xy 71.417434 -99.06635) (xy 71.247254 -98.97745) (xy 71.202804 -98.97745)
			(xy 71.202804 -99.37623) (xy 71.247254 -99.37623)
		)
		(stroke
			(width 0)
			(type solid)
		)
		(fill yes)
		(layer "In11.Cu")
		(net "M_M_DQS_DN<11>")
	)
	(gr_poly
		(pts
			(xy 71.737728 -100.952554) (xy 71.693278 -100.952554) (xy 71.523098 -101.041454) (xy 71.523098 -101.262434)
			(xy 71.693278 -101.351334) (xy 71.737728 -101.351334)
		)
		(stroke
			(width 0)
			(type solid)
		)
		(fill yes)
		(layer "In11.Cu")
		(net "M_M_DQS_DN<2>")
	)
	(gr_poly
		(pts
			(xy 71.737728 -99.974146) (xy 71.693278 -99.974146) (xy 71.523098 -100.063046) (xy 71.523098 -100.284026)
			(xy 71.693278 -100.372926) (xy 71.737728 -100.372926)
		)
		(stroke
			(width 0)
			(type solid)
		)
		(fill yes)
		(layer "In11.Cu")
		(net "M_M_DQS_DN<2>")
	)
	(gr_poly
		(pts
			(xy 71.737728 -51.42865) (xy 71.693278 -51.42865) (xy 71.523098 -51.51755) (xy 71.523098 -51.73853)
			(xy 71.693278 -51.82743) (xy 71.737728 -51.82743)
		)
		(stroke
			(width 0)
			(type solid)
		)
		(fill yes)
		(layer "In11.Cu")
		(net "M_J_DQS_DP<2>")
	)
	(gr_poly
		(pts
			(xy 71.737982 -98.988118) (xy 71.693532 -98.988372) (xy 71.523352 -99.077272) (xy 71.523352 -99.298252)
			(xy 71.693532 -99.387152) (xy 71.737728 -99.387152)
		)
		(stroke
			(width 0)
			(type solid)
		)
		(fill yes)
		(layer "In11.Cu")
		(net "M_M_DQS_DN<2>")
	)
	(gr_poly
		(pts
			(xy 71.737982 -52.418996) (xy 71.693278 -52.418996) (xy 71.523352 -52.507896) (xy 71.523352 -52.728876)
			(xy 71.693532 -52.817522) (xy 71.737728 -52.817776)
		)
		(stroke
			(width 0)
			(type solid)
		)
		(fill yes)
		(layer "In11.Cu")
		(net "M_J_DQS_DP<2>")
	)
	(gr_poly
		(pts
			(xy 71.838058 -102.776528) (xy 71.806562 -102.745286) (xy 71.607172 -102.671626) (xy 71.445628 -102.83317)
			(xy 71.519288 -103.03256) (xy 71.55053 -103.064056)
		)
		(stroke
			(width 0)
			(type solid)
		)
		(fill yes)
		(layer "In11.Cu")
		(net "M_M_DQS_DN<2>")
	)
	(gr_poly
		(pts
			(xy 71.873872 -101.96576) (xy 71.829422 -101.96576) (xy 71.636382 -102.05466) (xy 71.636382 -102.28326)
			(xy 71.829422 -102.37216) (xy 71.873872 -102.37216)
		)
		(stroke
			(width 0)
			(type solid)
		)
		(fill yes)
		(layer "In11.Cu")
		(net "M_M_DQS_DN<2>")
	)
	(gr_poly
		(pts
			(xy 71.966074 -57.619646) (xy 71.974202 -57.427876) (xy 71.78294 -57.317386) (xy 71.620888 -57.420256)
			(xy 71.598536 -57.45861) (xy 71.943976 -57.658)
		)
		(stroke
			(width 0)
			(type solid)
		)
		(fill yes)
		(layer "In11.Cu")
		(net "M_J_DQ<15>")
	)
	(gr_poly
		(pts
			(xy 71.96836 -67.526916) (xy 71.976488 -67.335146) (xy 71.785226 -67.224656) (xy 71.623174 -67.327526)
			(xy 71.600822 -67.36588) (xy 71.946262 -67.565524)
		)
		(stroke
			(width 0)
			(type solid)
		)
		(fill yes)
		(layer "In11.Cu")
		(net "M_J_DQ<5>")
	)
	(gr_poly
		(pts
			(xy 71.96836 -66.536316) (xy 71.976488 -66.344546) (xy 71.785226 -66.234056) (xy 71.623174 -66.336926)
			(xy 71.600822 -66.37528) (xy 71.946262 -66.574924)
		)
		(stroke
			(width 0)
			(type solid)
		)
		(fill yes)
		(layer "In11.Cu")
		(net "M_J_DQ<1>")
	)
	(gr_poly
		(pts
			(xy 71.96836 -65.545716) (xy 71.976488 -65.353946) (xy 71.785226 -65.243456) (xy 71.623174 -65.346326)
			(xy 71.600822 -65.38468) (xy 71.946262 -65.58407)
		)
		(stroke
			(width 0)
			(type solid)
		)
		(fill yes)
		(layer "In11.Cu")
		(net "M_J_DQS_DN<9>")
	)
	(gr_poly
		(pts
			(xy 71.96836 -64.555116) (xy 71.976488 -64.363346) (xy 71.785226 -64.252856) (xy 71.623174 -64.355726)
			(xy 71.600822 -64.39408) (xy 71.946262 -64.593724)
		)
		(stroke
			(width 0)
			(type solid)
		)
		(fill yes)
		(layer "In11.Cu")
		(net "M_J_DQS_DN<0>")
	)
	(gr_poly
		(pts
			(xy 71.96836 -63.564516) (xy 71.976488 -63.372746) (xy 71.785226 -63.262256) (xy 71.623174 -63.365126)
			(xy 71.600822 -63.40348) (xy 71.946262 -63.603124)
		)
		(stroke
			(width 0)
			(type solid)
		)
		(fill yes)
		(layer "In11.Cu")
		(net "M_J_DQ<7>")
	)
	(gr_poly
		(pts
			(xy 71.96836 -62.573916) (xy 71.976488 -62.382146) (xy 71.785226 -62.271656) (xy 71.623174 -62.374526)
			(xy 71.600822 -62.41288) (xy 71.946262 -62.612524)
		)
		(stroke
			(width 0)
			(type solid)
		)
		(fill yes)
		(layer "In11.Cu")
		(net "M_J_DQ<3>")
	)
	(gr_poly
		(pts
			(xy 71.96836 -61.583316) (xy 71.976488 -61.391546) (xy 71.785226 -61.281056) (xy 71.623174 -61.383926)
			(xy 71.600822 -61.42228) (xy 71.946262 -61.621924)
		)
		(stroke
			(width 0)
			(type solid)
		)
		(fill yes)
		(layer "In11.Cu")
		(net "M_J_DQ<13>")
	)
	(gr_poly
		(pts
			(xy 71.96836 -60.592716) (xy 71.976488 -60.400946) (xy 71.785226 -60.290456) (xy 71.623174 -60.393326)
			(xy 71.600822 -60.43168) (xy 71.946262 -60.631324)
		)
		(stroke
			(width 0)
			(type solid)
		)
		(fill yes)
		(layer "In11.Cu")
		(net "M_J_DQ<9>")
	)
	(gr_poly
		(pts
			(xy 71.96836 -59.602116) (xy 71.976488 -59.410346) (xy 71.785226 -59.299856) (xy 71.623174 -59.402726)
			(xy 71.600822 -59.44108) (xy 71.946262 -59.640724)
		)
		(stroke
			(width 0)
			(type solid)
		)
		(fill yes)
		(layer "In11.Cu")
		(net "M_J_DQS_DN<10>")
	)
	(gr_poly
		(pts
			(xy 71.96836 -55.639716) (xy 71.976488 -55.447946) (xy 71.785226 -55.337456) (xy 71.623174 -55.440326)
			(xy 71.600822 -55.47868) (xy 71.946262 -55.678324)
		)
		(stroke
			(width 0)
			(type solid)
		)
		(fill yes)
		(layer "In11.Cu")
		(net "M_J_DQ<21>")
	)
	(gr_poly
		(pts
			(xy 71.96836 -54.649116) (xy 71.976488 -54.457346) (xy 71.785226 -54.346856) (xy 71.623174 -54.449726)
			(xy 71.600822 -54.48808) (xy 71.946262 -54.687724)
		)
		(stroke
			(width 0)
			(type solid)
		)
		(fill yes)
		(layer "In11.Cu")
		(net "M_J_DQ<17>")
	)
	(gr_poly
		(pts
			(xy 71.96836 -53.658516) (xy 71.976488 -53.466746) (xy 71.785226 -53.356256) (xy 71.623174 -53.459126)
			(xy 71.600822 -53.49748) (xy 71.946262 -53.697124)
		)
		(stroke
			(width 0)
			(type solid)
		)
		(fill yes)
		(layer "In11.Cu")
		(net "M_J_DQS_DN<11>")
	)
	(gr_poly
		(pts
			(xy 71.969884 -58.612278) (xy 71.978012 -58.420508) (xy 71.78675 -58.310018) (xy 71.624698 -58.412888)
			(xy 71.602346 -58.451242) (xy 71.947786 -58.650632)
		)
		(stroke
			(width 0)
			(type solid)
		)
		(fill yes)
		(layer "In11.Cu")
		(net "M_J_DQS_DN<1>")
	)
	(gr_poly
		(pts
			(xy 71.969884 -56.631078) (xy 71.978012 -56.439308) (xy 71.78675 -56.328818) (xy 71.624698 -56.431688)
			(xy 71.602346 -56.470042) (xy 71.947786 -56.669686)
		)
		(stroke
			(width 0)
			(type solid)
		)
		(fill yes)
		(layer "In11.Cu")
		(net "M_J_DQ<11>")
	)
	(gr_poly
		(pts
			(xy 71.974202 -93.37675) (xy 71.966074 -93.18498) (xy 71.943976 -93.146372) (xy 71.598536 -93.345762)
			(xy 71.620888 -93.38437) (xy 71.78294 -93.48724)
		)
		(stroke
			(width 0)
			(type solid)
		)
		(fill yes)
		(layer "In11.Cu")
		(net "M_M_DQS_DP<1>")
	)
	(gr_poly
		(pts
			(xy 71.976488 -94.36608) (xy 71.96836 -94.17431) (xy 71.946262 -94.135702) (xy 71.600822 -94.335346)
			(xy 71.623174 -94.3737) (xy 71.785226 -94.47657)
		)
		(stroke
			(width 0)
			(type solid)
		)
		(fill yes)
		(layer "In11.Cu")
		(net "M_M_DQ<15>")
	)
	(gr_poly
		(pts
			(xy 71.978012 -98.327464) (xy 71.969884 -98.135694) (xy 71.947786 -98.097086) (xy 71.602346 -98.29673)
			(xy 71.624698 -98.335084) (xy 71.78675 -98.437954)
		)
		(stroke
			(width 0)
			(type solid)
		)
		(fill yes)
		(layer "In11.Cu")
		(net "M_M_DQS_DN<11>")
	)
	(gr_poly
		(pts
			(xy 71.978012 -97.336864) (xy 71.969884 -97.145094) (xy 71.947786 -97.106486) (xy 71.602346 -97.30613)
			(xy 71.624698 -97.344484) (xy 71.78675 -97.447354)
		)
		(stroke
			(width 0)
			(type solid)
		)
		(fill yes)
		(layer "In11.Cu")
		(net "M_M_DQ<17>")
	)
	(gr_poly
		(pts
			(xy 71.978012 -96.346264) (xy 71.969884 -96.154494) (xy 71.947786 -96.115886) (xy 71.602346 -96.31553)
			(xy 71.624698 -96.353884) (xy 71.78675 -96.456754)
		)
		(stroke
			(width 0)
			(type solid)
		)
		(fill yes)
		(layer "In11.Cu")
		(net "M_M_DQ<21>")
	)
	(gr_poly
		(pts
			(xy 71.978012 -95.355664) (xy 71.969884 -95.163894) (xy 71.947786 -95.125286) (xy 71.602346 -95.32493)
			(xy 71.624698 -95.363284) (xy 71.78675 -95.466154)
		)
		(stroke
			(width 0)
			(type solid)
		)
		(fill yes)
		(layer "In11.Cu")
		(net "M_M_DQ<11>")
	)
	(gr_poly
		(pts
			(xy 71.978012 -92.383864) (xy 71.969884 -92.192094) (xy 71.947786 -92.153486) (xy 71.602346 -92.35313)
			(xy 71.624698 -92.391484) (xy 71.78675 -92.494354)
		)
		(stroke
			(width 0)
			(type solid)
		)
		(fill yes)
		(layer "In11.Cu")
		(net "M_M_DQS_DN<10>")
	)
	(gr_poly
		(pts
			(xy 71.978012 -91.393264) (xy 71.969884 -91.201494) (xy 71.947786 -91.162886) (xy 71.602346 -91.36253)
			(xy 71.624698 -91.400884) (xy 71.78675 -91.503754)
		)
		(stroke
			(width 0)
			(type solid)
		)
		(fill yes)
		(layer "In11.Cu")
		(net "M_M_DQ<9>")
	)
	(gr_poly
		(pts
			(xy 71.978012 -90.402664) (xy 71.969884 -90.210894) (xy 71.947786 -90.172286) (xy 71.602346 -90.37193)
			(xy 71.624698 -90.410284) (xy 71.78675 -90.513154)
		)
		(stroke
			(width 0)
			(type solid)
		)
		(fill yes)
		(layer "In11.Cu")
		(net "M_M_DQ<13>")
	)
	(gr_poly
		(pts
			(xy 71.978012 -89.412064) (xy 71.969884 -89.220294) (xy 71.947786 -89.181686) (xy 71.602346 -89.38133)
			(xy 71.624698 -89.419684) (xy 71.78675 -89.522554)
		)
		(stroke
			(width 0)
			(type solid)
		)
		(fill yes)
		(layer "In11.Cu")
		(net "M_M_DQ<3>")
	)
	(gr_poly
		(pts
			(xy 71.978012 -88.421464) (xy 71.969884 -88.229694) (xy 71.947786 -88.191086) (xy 71.602346 -88.39073)
			(xy 71.624698 -88.429084) (xy 71.78675 -88.531954)
		)
		(stroke
			(width 0)
			(type solid)
		)
		(fill yes)
		(layer "In11.Cu")
		(net "M_M_DQ<7>")
	)
	(gr_poly
		(pts
			(xy 71.978012 -87.430864) (xy 71.969884 -87.239094) (xy 71.947786 -87.200486) (xy 71.602346 -87.40013)
			(xy 71.624698 -87.438484) (xy 71.78675 -87.541354)
		)
		(stroke
			(width 0)
			(type solid)
		)
		(fill yes)
		(layer "In11.Cu")
		(net "M_M_DQS_DP<0>")
	)
	(gr_poly
		(pts
			(xy 71.978012 -86.440264) (xy 71.969884 -86.248494) (xy 71.947786 -86.209886) (xy 71.602346 -86.40953)
			(xy 71.624698 -86.447884) (xy 71.78675 -86.550754)
		)
		(stroke
			(width 0)
			(type solid)
		)
		(fill yes)
		(layer "In11.Cu")
		(net "M_M_DQS_DN<9>")
	)
	(gr_poly
		(pts
			(xy 71.978012 -85.449664) (xy 71.969884 -85.257894) (xy 71.947786 -85.219286) (xy 71.602346 -85.41893)
			(xy 71.624698 -85.457284) (xy 71.78675 -85.560154)
		)
		(stroke
			(width 0)
			(type solid)
		)
		(fill yes)
		(layer "In11.Cu")
		(net "M_M_DQ<1>")
	)
	(gr_poly
		(pts
			(xy 71.978012 -84.459064) (xy 71.969884 -84.267294) (xy 71.947786 -84.228686) (xy 71.602346 -84.42833)
			(xy 71.624698 -84.466684) (xy 71.78675 -84.569554)
		)
		(stroke
			(width 0)
			(type solid)
		)
		(fill yes)
		(layer "In11.Cu")
		(net "M_M_DQ<5>")
	)
	(gr_poly
		(pts
			(xy 72.086724 -103.151178) (xy 72.013064 -102.951788) (xy 71.981822 -102.920292) (xy 71.694294 -103.20782)
			(xy 71.72579 -103.239062) (xy 71.92518 -103.312722)
		)
		(stroke
			(width 0)
			(type solid)
		)
		(fill yes)
		(layer "In11.Cu")
		(net "M_M_DQS_DP<2>")
	)
	(gr_poly
		(pts
			(xy 72.174354 -60.197238) (xy 72.196706 -60.158884) (xy 71.851266 -59.95924) (xy 71.829168 -59.997848)
			(xy 71.82104 -60.189618) (xy 72.012302 -60.300108)
		)
		(stroke
			(width 0)
			(type solid)
		)
		(fill yes)
		(layer "In11.Cu")
		(net "M_J_DQS_DP<10>")
	)
	(gr_poly
		(pts
			(xy 72.174354 -58.216038) (xy 72.196706 -58.177684) (xy 71.851266 -57.97804) (xy 71.829168 -58.016648)
			(xy 71.82104 -58.208418) (xy 72.012302 -58.318908)
		)
		(stroke
			(width 0)
			(type solid)
		)
		(fill yes)
		(layer "In11.Cu")
		(net "M_J_DQ<14>")
	)
	(gr_poly
		(pts
			(xy 72.175878 -68.1228) (xy 72.19823 -68.084192) (xy 71.85279 -67.885056) (xy 71.830692 -67.92341)
			(xy 71.822564 -68.11518) (xy 72.013826 -68.22567)
		)
		(stroke
			(width 0)
			(type solid)
		)
		(fill yes)
		(layer "In11.Cu")
		(net "M_J_DQ<4>")
	)
	(gr_poly
		(pts
			(xy 72.175878 -67.1322) (xy 72.19823 -67.093592) (xy 71.85279 -66.894456) (xy 71.830692 -66.93281)
			(xy 71.822564 -67.12458) (xy 72.013826 -67.23507)
		)
		(stroke
			(width 0)
			(type solid)
		)
		(fill yes)
		(layer "In11.Cu")
		(net "M_J_DQ<0>")
	)
	(gr_poly
		(pts
			(xy 72.175878 -66.1416) (xy 72.19823 -66.102992) (xy 71.85279 -65.903602) (xy 71.830692 -65.94221)
			(xy 71.822564 -66.13398) (xy 72.013826 -66.24447)
		)
		(stroke
			(width 0)
			(type solid)
		)
		(fill yes)
		(layer "In11.Cu")
		(net "M_J_DQS_DP<9>")
	)
	(gr_poly
		(pts
			(xy 72.175878 -65.151) (xy 72.19823 -65.112392) (xy 71.85279 -64.913002) (xy 71.830692 -64.95161)
			(xy 71.822564 -65.14338) (xy 72.013826 -65.25387)
		)
		(stroke
			(width 0)
			(type solid)
		)
		(fill yes)
		(layer "In11.Cu")
		(net "M_J_DQS_DP<0>")
	)
	(gr_poly
		(pts
			(xy 72.175878 -64.1604) (xy 72.19823 -64.121792) (xy 71.85279 -63.922402) (xy 71.830692 -63.96101)
			(xy 71.822564 -64.15278) (xy 72.013826 -64.26327)
		)
		(stroke
			(width 0)
			(type solid)
		)
		(fill yes)
		(layer "In11.Cu")
		(net "M_J_DQ<6>")
	)
	(gr_poly
		(pts
			(xy 72.175878 -63.1698) (xy 72.19823 -63.131192) (xy 71.85279 -62.931802) (xy 71.830692 -62.97041)
			(xy 71.822564 -63.16218) (xy 72.013826 -63.27267)
		)
		(stroke
			(width 0)
			(type solid)
		)
		(fill yes)
		(layer "In11.Cu")
		(net "M_J_DQ<2>")
	)
	(gr_poly
		(pts
			(xy 72.175878 -62.1792) (xy 72.19823 -62.140592) (xy 71.85279 -61.941202) (xy 71.830692 -61.97981)
			(xy 71.822564 -62.17158) (xy 72.013826 -62.28207)
		)
		(stroke
			(width 0)
			(type solid)
		)
		(fill yes)
		(layer "In11.Cu")
		(net "M_J_DQ<12>")
	)
	(gr_poly
		(pts
			(xy 72.175878 -61.1886) (xy 72.19823 -61.149992) (xy 71.85279 -60.950602) (xy 71.830692 -60.98921)
			(xy 71.822564 -61.18098) (xy 72.013826 -61.29147)
		)
		(stroke
			(width 0)
			(type solid)
		)
		(fill yes)
		(layer "In11.Cu")
		(net "M_J_DQ<8>")
	)
	(gr_poly
		(pts
			(xy 72.175878 -57.2262) (xy 72.19823 -57.187592) (xy 71.85279 -56.988202) (xy 71.830692 -57.02681)
			(xy 71.822564 -57.21858) (xy 72.013826 -57.32907)
		)
		(stroke
			(width 0)
			(type solid)
		)
		(fill yes)
		(layer "In11.Cu")
		(net "M_J_DQ<10>")
	)
	(gr_poly
		(pts
			(xy 72.175878 -56.2356) (xy 72.19823 -56.196992) (xy 71.85279 -55.997602) (xy 71.830692 -56.03621)
			(xy 71.822564 -56.22798) (xy 72.013826 -56.33847)
		)
		(stroke
			(width 0)
			(type solid)
		)
		(fill yes)
		(layer "In11.Cu")
		(net "M_J_DQ<20>")
	)
	(gr_poly
		(pts
			(xy 72.175878 -55.245) (xy 72.19823 -55.206392) (xy 71.85279 -55.007002) (xy 71.830692 -55.04561)
			(xy 71.822564 -55.23738) (xy 72.013826 -55.34787)
		)
		(stroke
			(width 0)
			(type solid)
		)
		(fill yes)
		(layer "In11.Cu")
		(net "M_J_DQ<16>")
	)
	(gr_poly
		(pts
			(xy 72.177656 -54.255416) (xy 72.200008 -54.216808) (xy 71.854568 -54.017418) (xy 71.83247 -54.056026)
			(xy 71.824342 -54.247796) (xy 72.015604 -54.358286)
		)
		(stroke
			(width 0)
			(type solid)
		)
		(fill yes)
		(layer "In11.Cu")
		(net "M_J_DQS_DP<11>")
	)
	(gr_poly
		(pts
			(xy 72.178164 -59.20867) (xy 72.200516 -59.170316) (xy 71.855076 -58.970672) (xy 71.832978 -59.00928)
			(xy 71.82485 -59.20105) (xy 72.016112 -59.31154)
		)
		(stroke
			(width 0)
			(type solid)
		)
		(fill yes)
		(layer "In11.Cu")
		(net "M_J_DQS_DP<1>")
	)
	(gr_poly
		(pts
			(xy 72.19315 -53.27015) (xy 72.214994 -53.231796) (xy 71.86676 -53.037232) (xy 71.84517 -53.076348)
			(xy 71.839836 -53.267864) (xy 72.032876 -53.37556)
		)
		(stroke
			(width 0)
			(type solid)
		)
		(fill yes)
		(layer "In11.Cu")
		(net "M_J_DQS_DP<2>")
	)
	(gr_poly
		(pts
			(xy 72.196706 -98.570796) (xy 72.174354 -98.532442) (xy 72.012302 -98.429572) (xy 71.82104 -98.540062)
			(xy 71.828914 -98.731832) (xy 71.851012 -98.770186)
		)
		(stroke
			(width 0)
			(type solid)
		)
		(fill yes)
		(layer "In11.Cu")
		(net "M_M_DQS_DN<2>")
	)
	(gr_poly
		(pts
			(xy 72.196706 -97.58045) (xy 72.174354 -97.541842) (xy 72.012302 -97.438972) (xy 71.82104 -97.549462)
			(xy 71.829168 -97.741232) (xy 71.851266 -97.77984)
		)
		(stroke
			(width 0)
			(type solid)
		)
		(fill yes)
		(layer "In11.Cu")
		(net "M_M_DQS_DP<11>")
	)
	(gr_poly
		(pts
			(xy 72.196706 -96.58985) (xy 72.174354 -96.551242) (xy 72.012302 -96.448372) (xy 71.82104 -96.558862)
			(xy 71.829168 -96.750632) (xy 71.851266 -96.78924)
		)
		(stroke
			(width 0)
			(type solid)
		)
		(fill yes)
		(layer "In11.Cu")
		(net "M_M_DQ<16>")
	)
	(gr_poly
		(pts
			(xy 72.196706 -95.59925) (xy 72.174354 -95.560642) (xy 72.012302 -95.457772) (xy 71.82104 -95.568262)
			(xy 71.829168 -95.760032) (xy 71.851266 -95.79864)
		)
		(stroke
			(width 0)
			(type solid)
		)
		(fill yes)
		(layer "In11.Cu")
		(net "M_M_DQ<20>")
	)
	(gr_poly
		(pts
			(xy 72.196706 -92.62745) (xy 72.174354 -92.588842) (xy 72.012302 -92.485972) (xy 71.82104 -92.596462)
			(xy 71.829168 -92.788232) (xy 71.851266 -92.82684)
		)
		(stroke
			(width 0)
			(type solid)
		)
		(fill yes)
		(layer "In11.Cu")
		(net "M_M_DQS_DN<1>")
	)
	(gr_poly
		(pts
			(xy 72.196706 -91.63685) (xy 72.174354 -91.598242) (xy 72.012302 -91.495372) (xy 71.82104 -91.605862)
			(xy 71.829168 -91.797632) (xy 71.851266 -91.83624)
		)
		(stroke
			(width 0)
			(type solid)
		)
		(fill yes)
		(layer "In11.Cu")
		(net "M_M_DQS_DP<10>")
	)
	(gr_poly
		(pts
			(xy 72.196706 -90.64625) (xy 72.174354 -90.607642) (xy 72.012302 -90.504772) (xy 71.82104 -90.615262)
			(xy 71.829168 -90.807032) (xy 71.851266 -90.84564)
		)
		(stroke
			(width 0)
			(type solid)
		)
		(fill yes)
		(layer "In11.Cu")
		(net "M_M_DQ<8>")
	)
	(gr_poly
		(pts
			(xy 72.196706 -89.65565) (xy 72.174354 -89.617042) (xy 72.012302 -89.514172) (xy 71.82104 -89.624662)
			(xy 71.829168 -89.816432) (xy 71.851266 -89.85504)
		)
		(stroke
			(width 0)
			(type solid)
		)
		(fill yes)
		(layer "In11.Cu")
		(net "M_M_DQ<12>")
	)
	(gr_poly
		(pts
			(xy 72.196706 -88.66505) (xy 72.174354 -88.626442) (xy 72.012302 -88.523572) (xy 71.82104 -88.634062)
			(xy 71.829168 -88.825832) (xy 71.851266 -88.86444)
		)
		(stroke
			(width 0)
			(type solid)
		)
		(fill yes)
		(layer "In11.Cu")
		(net "M_M_DQ<2>")
	)
	(gr_poly
		(pts
			(xy 72.196706 -87.67445) (xy 72.174354 -87.635842) (xy 72.012302 -87.532972) (xy 71.82104 -87.643462)
			(xy 71.829168 -87.835232) (xy 71.851266 -87.87384)
		)
		(stroke
			(width 0)
			(type solid)
		)
		(fill yes)
		(layer "In11.Cu")
		(net "M_M_DQ<6>")
	)
	(gr_poly
		(pts
			(xy 72.196706 -86.68385) (xy 72.174354 -86.645242) (xy 72.012302 -86.542372) (xy 71.82104 -86.652862)
			(xy 71.829168 -86.844632) (xy 71.851266 -86.88324)
		)
		(stroke
			(width 0)
			(type solid)
		)
		(fill yes)
		(layer "In11.Cu")
		(net "M_M_DQS_DN<0>")
	)
	(gr_poly
		(pts
			(xy 72.196706 -85.69325) (xy 72.174354 -85.654642) (xy 72.012302 -85.551772) (xy 71.82104 -85.662262)
			(xy 71.829168 -85.854032) (xy 71.851266 -85.89264)
		)
		(stroke
			(width 0)
			(type solid)
		)
		(fill yes)
		(layer "In11.Cu")
		(net "M_M_DQS_DP<9>")
	)
	(gr_poly
		(pts
			(xy 72.196706 -84.70265) (xy 72.174354 -84.664042) (xy 72.012302 -84.561172) (xy 71.82104 -84.671662)
			(xy 71.829168 -84.863432) (xy 71.851266 -84.90204)
		)
		(stroke
			(width 0)
			(type solid)
		)
		(fill yes)
		(layer "In11.Cu")
		(net "M_M_DQ<0>")
	)
	(gr_poly
		(pts
			(xy 72.196706 -83.71205) (xy 72.174354 -83.673442) (xy 72.012302 -83.570572) (xy 71.82104 -83.681062)
			(xy 71.829168 -83.872832) (xy 71.851266 -83.91144)
		)
		(stroke
			(width 0)
			(type solid)
		)
		(fill yes)
		(layer "In11.Cu")
		(net "M_M_DQ<4>")
	)
	(gr_poly
		(pts
			(xy 72.19823 -93.61678) (xy 72.175878 -93.578426) (xy 72.013826 -93.475556) (xy 71.822564 -93.586046)
			(xy 71.830692 -93.777816) (xy 71.85279 -93.81617)
		)
		(stroke
			(width 0)
			(type solid)
		)
		(fill yes)
		(layer "In11.Cu")
		(net "M_M_DQ<14>")
	)
	(gr_poly
		(pts
			(xy 72.200516 -94.60611) (xy 72.178164 -94.567756) (xy 72.016112 -94.464886) (xy 71.82485 -94.575376)
			(xy 71.832978 -94.767146) (xy 71.855076 -94.805754)
		)
		(stroke
			(width 0)
			(type solid)
		)
		(fill yes)
		(layer "In11.Cu")
		(net "M_M_DQ<10>")
	)
	(gr_poly
		(pts
			(xy 72.275954 -100.772976) (xy 72.275954 -100.551996) (xy 72.105774 -100.463096) (xy 72.061324 -100.463096)
			(xy 72.061324 -100.861876) (xy 72.105774 -100.861876)
		)
		(stroke
			(width 0)
			(type solid)
		)
		(fill yes)
		(layer "In11.Cu")
		(net "M_M_DQS_DP<2>")
	)
	(gr_poly
		(pts
			(xy 72.275954 -99.77628) (xy 72.275954 -99.5553) (xy 72.105774 -99.4664) (xy 72.061324 -99.4664)
			(xy 72.061324 -99.86518) (xy 72.105774 -99.86518)
		)
		(stroke
			(width 0)
			(type solid)
		)
		(fill yes)
		(layer "In11.Cu")
		(net "M_M_DQS_DP<2>")
	)
	(gr_poly
		(pts
			(xy 72.275954 -52.22748) (xy 72.275954 -52.0065) (xy 72.105774 -51.9176) (xy 72.061324 -51.9176)
			(xy 72.061324 -52.31638) (xy 72.105774 -52.31638)
		)
		(stroke
			(width 0)
			(type solid)
		)
		(fill yes)
		(layer "In11.Cu")
		(net "M_J_DQS_DN<2>")
	)
	(gr_poly
		(pts
			(xy 72.275954 -51.249326) (xy 72.275954 -51.028346) (xy 72.105774 -50.939446) (xy 72.061324 -50.939446)
			(xy 72.061324 -51.338226) (xy 72.105774 -51.338226)
		)
		(stroke
			(width 0)
			(type solid)
		)
		(fill yes)
		(layer "In11.Cu")
		(net "M_J_DQS_DN<2>")
	)
	(gr_poly
		(pts
			(xy 72.301862 -102.28326) (xy 72.301862 -102.05466) (xy 72.108822 -101.96576) (xy 72.064372 -101.96576)
			(xy 72.064372 -102.37216) (xy 72.108822 -102.37216)
		)
		(stroke
			(width 0)
			(type solid)
		)
		(fill yes)
		(layer "In11.Cu")
		(net "M_M_DQS_DP<2>")
	)
	(gr_poly
		(pts
			(xy 72.596248 -50.939446) (xy 72.551798 -50.939446) (xy 72.381618 -51.028346) (xy 72.381618 -51.249326)
			(xy 72.551798 -51.338226) (xy 72.596248 -51.338226)
		)
		(stroke
			(width 0)
			(type solid)
		)
		(fill yes)
		(layer "In11.Cu")
		(net "M_J_DQ<22>")
	)
	(gr_poly
		(pts
			(xy 72.596756 -51.916584) (xy 72.552306 -51.916584) (xy 72.382126 -52.00523) (xy 72.381618 -52.225956)
			(xy 72.551544 -52.31511) (xy 72.595994 -52.315364)
		)
		(stroke
			(width 0)
			(type solid)
		)
		(fill yes)
		(layer "In11.Cu")
		(net "M_J_DQ<22>")
	)
	(gr_poly
		(pts
			(xy 72.68083 -103.934514) (xy 72.649334 -103.903272) (xy 72.449944 -103.829612) (xy 72.2884 -103.991156)
			(xy 72.36206 -104.190546) (xy 72.393302 -104.222042)
		)
		(stroke
			(width 0)
			(type solid)
		)
		(fill yes)
		(layer "In11.Cu")
		(net "M_M_DQ<22>")
	)
	(gr_poly
		(pts
			(xy 72.729344 -49.642776) (xy 72.684894 -49.642776) (xy 72.491854 -49.731676) (xy 72.491854 -49.960276)
			(xy 72.684894 -50.049176) (xy 72.729344 -50.049176)
		)
		(stroke
			(width 0)
			(type solid)
		)
		(fill yes)
		(layer "In11.Cu")
		(net "M_J_DQ<22>")
	)
	(gr_poly
		(pts
			(xy 72.824594 -59.105546) (xy 72.832722 -58.913776) (xy 72.64146 -58.803286) (xy 72.479408 -58.906156)
			(xy 72.457056 -58.94451) (xy 72.802496 -59.1439)
		)
		(stroke
			(width 0)
			(type solid)
		)
		(fill yes)
		(layer "In11.Cu")
		(net "M_J_DQS_DN<1>")
	)
	(gr_poly
		(pts
			(xy 72.82688 -66.04127) (xy 72.835008 -65.8495) (xy 72.643746 -65.73901) (xy 72.481694 -65.84188)
			(xy 72.459342 -65.880234) (xy 72.804782 -66.079624)
		)
		(stroke
			(width 0)
			(type solid)
		)
		(fill yes)
		(layer "In11.Cu")
		(net "M_J_DQS_DN<9>")
	)
	(gr_poly
		(pts
			(xy 72.82688 -58.116216) (xy 72.835008 -57.924446) (xy 72.643746 -57.813956) (xy 72.481694 -57.916826)
			(xy 72.459342 -57.95518) (xy 72.804782 -58.154824)
		)
		(stroke
			(width 0)
			(type solid)
		)
		(fill yes)
		(layer "In11.Cu")
		(net "M_J_DQ<15>")
	)
	(gr_poly
		(pts
			(xy 72.82688 -53.16347) (xy 72.835008 -52.9717) (xy 72.643746 -52.86121) (xy 72.481694 -52.96408)
			(xy 72.459342 -53.002434) (xy 72.804782 -53.202078)
		)
		(stroke
			(width 0)
			(type solid)
		)
		(fill yes)
		(layer "In11.Cu")
		(net "M_J_DQS_DN<2>")
	)
	(gr_poly
		(pts
			(xy 72.828404 -68.023232) (xy 72.836532 -67.831462) (xy 72.64527 -67.720972) (xy 72.483218 -67.823842)
			(xy 72.460866 -67.862196) (xy 72.806306 -68.06184)
		)
		(stroke
			(width 0)
			(type solid)
		)
		(fill yes)
		(layer "In11.Cu")
		(net "M_J_DQ<5>")
	)
	(gr_poly
		(pts
			(xy 72.828404 -67.032632) (xy 72.836532 -66.840862) (xy 72.64527 -66.730372) (xy 72.483218 -66.833242)
			(xy 72.460866 -66.871596) (xy 72.806306 -67.07124)
		)
		(stroke
			(width 0)
			(type solid)
		)
		(fill yes)
		(layer "In11.Cu")
		(net "M_J_DQ<1>")
	)
	(gr_poly
		(pts
			(xy 72.828404 -65.051432) (xy 72.836532 -64.859662) (xy 72.64527 -64.749172) (xy 72.483218 -64.852042)
			(xy 72.460866 -64.890396) (xy 72.806306 -65.09004)
		)
		(stroke
			(width 0)
			(type solid)
		)
		(fill yes)
		(layer "In11.Cu")
		(net "M_J_DQS_DN<0>")
	)
	(gr_poly
		(pts
			(xy 72.828404 -64.060832) (xy 72.836532 -63.869062) (xy 72.64527 -63.758572) (xy 72.483218 -63.861442)
			(xy 72.460866 -63.899796) (xy 72.806306 -64.09944)
		)
		(stroke
			(width 0)
			(type solid)
		)
		(fill yes)
		(layer "In11.Cu")
		(net "M_J_DQ<7>")
	)
	(gr_poly
		(pts
			(xy 72.828404 -63.070232) (xy 72.836532 -62.878462) (xy 72.64527 -62.767972) (xy 72.483218 -62.870842)
			(xy 72.460866 -62.909196) (xy 72.806306 -63.10884)
		)
		(stroke
			(width 0)
			(type solid)
		)
		(fill yes)
		(layer "In11.Cu")
		(net "M_J_DQ<3>")
	)
	(gr_poly
		(pts
			(xy 72.828404 -62.079632) (xy 72.836532 -61.887862) (xy 72.64527 -61.777372) (xy 72.483218 -61.880242)
			(xy 72.460866 -61.918596) (xy 72.806306 -62.11824)
		)
		(stroke
			(width 0)
			(type solid)
		)
		(fill yes)
		(layer "In11.Cu")
		(net "M_J_DQ<13>")
	)
	(gr_poly
		(pts
			(xy 72.828404 -61.089032) (xy 72.836532 -60.897262) (xy 72.64527 -60.786772) (xy 72.483218 -60.889642)
			(xy 72.460866 -60.927996) (xy 72.806306 -61.12764)
		)
		(stroke
			(width 0)
			(type solid)
		)
		(fill yes)
		(layer "In11.Cu")
		(net "M_J_DQ<9>")
	)
	(gr_poly
		(pts
			(xy 72.828404 -60.098432) (xy 72.836532 -59.906662) (xy 72.64527 -59.796172) (xy 72.483218 -59.899042)
			(xy 72.460866 -59.937396) (xy 72.806306 -60.13704)
		)
		(stroke
			(width 0)
			(type solid)
		)
		(fill yes)
		(layer "In11.Cu")
		(net "M_J_DQS_DN<10>")
	)
	(gr_poly
		(pts
			(xy 72.828404 -57.126632) (xy 72.836532 -56.934862) (xy 72.64527 -56.824372) (xy 72.483218 -56.927242)
			(xy 72.460866 -56.965596) (xy 72.806306 -57.16524)
		)
		(stroke
			(width 0)
			(type solid)
		)
		(fill yes)
		(layer "In11.Cu")
		(net "M_J_DQ<11>")
	)
	(gr_poly
		(pts
			(xy 72.828404 -56.136032) (xy 72.836532 -55.944262) (xy 72.64527 -55.833772) (xy 72.483218 -55.936642)
			(xy 72.460866 -55.974996) (xy 72.806306 -56.17464)
		)
		(stroke
			(width 0)
			(type solid)
		)
		(fill yes)
		(layer "In11.Cu")
		(net "M_J_DQ<21>")
	)
	(gr_poly
		(pts
			(xy 72.828404 -55.145432) (xy 72.836532 -54.953662) (xy 72.64527 -54.843172) (xy 72.483218 -54.946042)
			(xy 72.460866 -54.984396) (xy 72.806306 -55.18404)
		)
		(stroke
			(width 0)
			(type solid)
		)
		(fill yes)
		(layer "In11.Cu")
		(net "M_J_DQ<17>")
	)
	(gr_poly
		(pts
			(xy 72.828404 -54.154832) (xy 72.836532 -53.963062) (xy 72.64527 -53.852572) (xy 72.483218 -53.955442)
			(xy 72.460866 -53.993796) (xy 72.806306 -54.19344)
		)
		(stroke
			(width 0)
			(type solid)
		)
		(fill yes)
		(layer "In11.Cu")
		(net "M_J_DQS_DN<11>")
	)
	(gr_poly
		(pts
			(xy 72.832722 -94.86265) (xy 72.824594 -94.67088) (xy 72.802496 -94.632272) (xy 72.457056 -94.831662)
			(xy 72.479408 -94.87027) (xy 72.64146 -94.97314)
		)
		(stroke
			(width 0)
			(type solid)
		)
		(fill yes)
		(layer "In11.Cu")
		(net "M_M_DQ<11>")
	)
	(gr_poly
		(pts
			(xy 72.835008 -98.82378) (xy 72.82688 -98.63201) (xy 72.804782 -98.593402) (xy 72.459342 -98.793046)
			(xy 72.481694 -98.8314) (xy 72.643746 -98.93427)
		)
		(stroke
			(width 0)
			(type solid)
		)
		(fill yes)
		(layer "In11.Cu")
		(net "M_M_DQS_DP<2>")
	)
	(gr_poly
		(pts
			(xy 72.835008 -97.83318) (xy 72.82688 -97.64141) (xy 72.804782 -97.602802) (xy 72.459342 -97.802446)
			(xy 72.481694 -97.8408) (xy 72.643746 -97.94367)
		)
		(stroke
			(width 0)
			(type solid)
		)
		(fill yes)
		(layer "In11.Cu")
		(net "M_M_DQS_DN<11>")
	)
	(gr_poly
		(pts
			(xy 72.835008 -96.84258) (xy 72.82688 -96.65081) (xy 72.804782 -96.612202) (xy 72.459342 -96.811846)
			(xy 72.481694 -96.8502) (xy 72.643746 -96.95307)
		)
		(stroke
			(width 0)
			(type solid)
		)
		(fill yes)
		(layer "In11.Cu")
		(net "M_M_DQ<17>")
	)
	(gr_poly
		(pts
			(xy 72.835008 -95.85198) (xy 72.82688 -95.66021) (xy 72.804782 -95.621602) (xy 72.459342 -95.821246)
			(xy 72.481694 -95.8596) (xy 72.643746 -95.96247)
		)
		(stroke
			(width 0)
			(type solid)
		)
		(fill yes)
		(layer "In11.Cu")
		(net "M_M_DQ<21>")
	)
	(gr_poly
		(pts
			(xy 72.835008 -92.88018) (xy 72.82688 -92.68841) (xy 72.804782 -92.649802) (xy 72.459342 -92.849446)
			(xy 72.481694 -92.8878) (xy 72.643746 -92.99067)
		)
		(stroke
			(width 0)
			(type solid)
		)
		(fill yes)
		(layer "In11.Cu")
		(net "M_M_DQS_DP<1>")
	)
	(gr_poly
		(pts
			(xy 72.835008 -91.88958) (xy 72.82688 -91.69781) (xy 72.804782 -91.659202) (xy 72.459342 -91.858846)
			(xy 72.481694 -91.8972) (xy 72.643746 -92.00007)
		)
		(stroke
			(width 0)
			(type solid)
		)
		(fill yes)
		(layer "In11.Cu")
		(net "M_M_DQS_DN<10>")
	)
	(gr_poly
		(pts
			(xy 72.835008 -90.89898) (xy 72.82688 -90.70721) (xy 72.804782 -90.668602) (xy 72.459342 -90.868246)
			(xy 72.481694 -90.9066) (xy 72.643746 -91.00947)
		)
		(stroke
			(width 0)
			(type solid)
		)
		(fill yes)
		(layer "In11.Cu")
		(net "M_M_DQ<9>")
	)
	(gr_poly
		(pts
			(xy 72.835008 -89.90838) (xy 72.82688 -89.71661) (xy 72.804782 -89.678002) (xy 72.459342 -89.877646)
			(xy 72.481694 -89.916) (xy 72.643746 -90.01887)
		)
		(stroke
			(width 0)
			(type solid)
		)
		(fill yes)
		(layer "In11.Cu")
		(net "M_M_DQ<13>")
	)
	(gr_poly
		(pts
			(xy 72.835008 -88.91778) (xy 72.82688 -88.72601) (xy 72.804782 -88.687402) (xy 72.459342 -88.887046)
			(xy 72.481694 -88.9254) (xy 72.643746 -89.02827)
		)
		(stroke
			(width 0)
			(type solid)
		)
		(fill yes)
		(layer "In11.Cu")
		(net "M_M_DQ<3>")
	)
	(gr_poly
		(pts
			(xy 72.835008 -87.92718) (xy 72.82688 -87.73541) (xy 72.804782 -87.696802) (xy 72.459342 -87.896446)
			(xy 72.481694 -87.9348) (xy 72.643746 -88.03767)
		)
		(stroke
			(width 0)
			(type solid)
		)
		(fill yes)
		(layer "In11.Cu")
		(net "M_M_DQ<7>")
	)
	(gr_poly
		(pts
			(xy 72.835008 -86.93658) (xy 72.82688 -86.74481) (xy 72.804782 -86.706202) (xy 72.459342 -86.905846)
			(xy 72.481694 -86.9442) (xy 72.643746 -87.04707)
		)
		(stroke
			(width 0)
			(type solid)
		)
		(fill yes)
		(layer "In11.Cu")
		(net "M_M_DQS_DP<0>")
	)
	(gr_poly
		(pts
			(xy 72.835008 -85.94598) (xy 72.82688 -85.75421) (xy 72.804782 -85.715602) (xy 72.459342 -85.915246)
			(xy 72.481694 -85.9536) (xy 72.643746 -86.05647)
		)
		(stroke
			(width 0)
			(type solid)
		)
		(fill yes)
		(layer "In11.Cu")
		(net "M_M_DQS_DN<9>")
	)
	(gr_poly
		(pts
			(xy 72.835008 -84.95538) (xy 72.82688 -84.76361) (xy 72.804782 -84.725002) (xy 72.459342 -84.924646)
			(xy 72.481694 -84.963) (xy 72.643746 -85.06587)
		)
		(stroke
			(width 0)
			(type solid)
		)
		(fill yes)
		(layer "In11.Cu")
		(net "M_M_DQ<1>")
	)
	(gr_poly
		(pts
			(xy 72.835008 -83.96478) (xy 72.82688 -83.77301) (xy 72.804782 -83.734402) (xy 72.459342 -83.934046)
			(xy 72.481694 -83.9724) (xy 72.643746 -84.07527)
		)
		(stroke
			(width 0)
			(type solid)
		)
		(fill yes)
		(layer "In11.Cu")
		(net "M_M_DQ<5>")
	)
	(gr_poly
		(pts
			(xy 72.836532 -93.870018) (xy 72.828404 -93.678248) (xy 72.806306 -93.639894) (xy 72.460866 -93.83903)
			(xy 72.483218 -93.877638) (xy 72.64527 -93.980508)
		)
		(stroke
			(width 0)
			(type solid)
		)
		(fill yes)
		(layer "In11.Cu")
		(net "M_M_DQ<15>")
	)
	(gr_poly
		(pts
			(xy 72.920098 -104.299766) (xy 72.846438 -104.100376) (xy 72.815196 -104.06888) (xy 72.527668 -104.356408)
			(xy 72.559164 -104.38765) (xy 72.758554 -104.46131)
		)
		(stroke
			(width 0)
			(type solid)
		)
		(fill yes)
		(layer "In11.Cu")
		(net "M_M_DQ<23>")
	)
	(gr_poly
		(pts
			(xy 73.032874 -68.617084) (xy 73.055226 -68.578476) (xy 72.709786 -68.37934) (xy 72.687688 -68.417694)
			(xy 72.67956 -68.609464) (xy 72.870822 -68.719954)
		)
		(stroke
			(width 0)
			(type solid)
		)
		(fill yes)
		(layer "In11.Cu")
		(net "M_J_DQ<4>")
	)
	(gr_poly
		(pts
			(xy 73.032874 -67.626484) (xy 73.055226 -67.587876) (xy 72.709786 -67.38874) (xy 72.687688 -67.427094)
			(xy 72.67956 -67.618864) (xy 72.870822 -67.729354)
		)
		(stroke
			(width 0)
			(type solid)
		)
		(fill yes)
		(layer "In11.Cu")
		(net "M_J_DQ<0>")
	)
	(gr_poly
		(pts
			(xy 73.032874 -66.635884) (xy 73.055226 -66.597276) (xy 72.709786 -66.397886) (xy 72.687688 -66.436494)
			(xy 72.67956 -66.628264) (xy 72.870822 -66.738754)
		)
		(stroke
			(width 0)
			(type solid)
		)
		(fill yes)
		(layer "In11.Cu")
		(net "M_J_DQS_DP<9>")
	)
	(gr_poly
		(pts
			(xy 73.032874 -65.645284) (xy 73.055226 -65.60693) (xy 72.709786 -65.407286) (xy 72.687688 -65.445894)
			(xy 72.67956 -65.637664) (xy 72.870822 -65.748154)
		)
		(stroke
			(width 0)
			(type solid)
		)
		(fill yes)
		(layer "In11.Cu")
		(net "M_J_DQS_DP<0>")
	)
	(gr_poly
		(pts
			(xy 73.032874 -64.654684) (xy 73.055226 -64.61633) (xy 72.709786 -64.416686) (xy 72.687688 -64.455294)
			(xy 72.67956 -64.647064) (xy 72.870822 -64.757554)
		)
		(stroke
			(width 0)
			(type solid)
		)
		(fill yes)
		(layer "In11.Cu")
		(net "M_J_DQ<6>")
	)
	(gr_poly
		(pts
			(xy 73.032874 -63.664084) (xy 73.055226 -63.62573) (xy 72.709786 -63.426086) (xy 72.687688 -63.464694)
			(xy 72.67956 -63.656464) (xy 72.870822 -63.766954)
		)
		(stroke
			(width 0)
			(type solid)
		)
		(fill yes)
		(layer "In11.Cu")
		(net "M_J_DQ<2>")
	)
	(gr_poly
		(pts
			(xy 73.032874 -62.673484) (xy 73.055226 -62.63513) (xy 72.709786 -62.435486) (xy 72.687688 -62.474094)
			(xy 72.67956 -62.665864) (xy 72.870822 -62.776354)
		)
		(stroke
			(width 0)
			(type solid)
		)
		(fill yes)
		(layer "In11.Cu")
		(net "M_J_DQ<12>")
	)
	(gr_poly
		(pts
			(xy 73.032874 -61.682884) (xy 73.055226 -61.64453) (xy 72.709786 -61.444886) (xy 72.687688 -61.483494)
			(xy 72.67956 -61.675264) (xy 72.870822 -61.785754)
		)
		(stroke
			(width 0)
			(type solid)
		)
		(fill yes)
		(layer "In11.Cu")
		(net "M_J_DQ<8>")
	)
	(gr_poly
		(pts
			(xy 73.032874 -60.692284) (xy 73.055226 -60.65393) (xy 72.709786 -60.454286) (xy 72.687688 -60.492894)
			(xy 72.67956 -60.684664) (xy 72.870822 -60.795154)
		)
		(stroke
			(width 0)
			(type solid)
		)
		(fill yes)
		(layer "In11.Cu")
		(net "M_J_DQS_DP<10>")
	)
	(gr_poly
		(pts
			(xy 73.032874 -59.701684) (xy 73.055226 -59.66333) (xy 72.709786 -59.463686) (xy 72.687688 -59.502294)
			(xy 72.67956 -59.694064) (xy 72.870822 -59.804554)
		)
		(stroke
			(width 0)
			(type solid)
		)
		(fill yes)
		(layer "In11.Cu")
		(net "M_J_DQS_DP<1>")
	)
	(gr_poly
		(pts
			(xy 73.032874 -58.711338) (xy 73.055226 -58.672984) (xy 72.709786 -58.47334) (xy 72.687688 -58.511948)
			(xy 72.67956 -58.703718) (xy 72.870822 -58.814208)
		)
		(stroke
			(width 0)
			(type solid)
		)
		(fill yes)
		(layer "In11.Cu")
		(net "M_J_DQ<14>")
	)
	(gr_poly
		(pts
			(xy 73.032874 -56.729884) (xy 73.055226 -56.69153) (xy 72.709786 -56.491886) (xy 72.687688 -56.530494)
			(xy 72.67956 -56.722264) (xy 72.870822 -56.832754)
		)
		(stroke
			(width 0)
			(type solid)
		)
		(fill yes)
		(layer "In11.Cu")
		(net "M_J_DQ<20>")
	)
	(gr_poly
		(pts
			(xy 73.032874 -55.739284) (xy 73.055226 -55.70093) (xy 72.709786 -55.501286) (xy 72.687688 -55.539894)
			(xy 72.67956 -55.731664) (xy 72.870822 -55.842154)
		)
		(stroke
			(width 0)
			(type solid)
		)
		(fill yes)
		(layer "In11.Cu")
		(net "M_J_DQ<16>")
	)
	(gr_poly
		(pts
			(xy 73.032874 -53.758084) (xy 73.055226 -53.71973) (xy 72.709786 -53.520086) (xy 72.687688 -53.558694)
			(xy 72.67956 -53.750464) (xy 72.870822 -53.860954)
		)
		(stroke
			(width 0)
			(type solid)
		)
		(fill yes)
		(layer "In11.Cu")
		(net "M_J_DQS_DP<2>")
	)
	(gr_poly
		(pts
			(xy 73.034398 -54.749446) (xy 73.05675 -54.711092) (xy 72.71131 -54.511448) (xy 72.689212 -54.550056)
			(xy 72.681084 -54.741826) (xy 72.872346 -54.852316)
		)
		(stroke
			(width 0)
			(type solid)
		)
		(fill yes)
		(layer "In11.Cu")
		(net "M_J_DQS_DP<11>")
	)
	(gr_poly
		(pts
			(xy 73.036684 -57.72277) (xy 73.059036 -57.684416) (xy 72.713596 -57.484772) (xy 72.691498 -57.52338)
			(xy 72.68337 -57.71515) (xy 72.874632 -57.82564)
		)
		(stroke
			(width 0)
			(type solid)
		)
		(fill yes)
		(layer "In11.Cu")
		(net "M_J_DQ<10>")
	)
	(gr_poly
		(pts
			(xy 73.036684 -52.770024) (xy 73.059036 -52.73167) (xy 72.713596 -52.532026) (xy 72.691498 -52.570634)
			(xy 72.68337 -52.762404) (xy 72.874632 -52.872894)
		)
		(stroke
			(width 0)
			(type solid)
		)
		(fill yes)
		(layer "In11.Cu")
		(net "M_J_DQ<22>")
	)
	(gr_poly
		(pts
			(xy 73.055226 -94.112842) (xy 73.032874 -94.074488) (xy 72.870822 -93.971618) (xy 72.67956 -94.082108)
			(xy 72.687688 -94.273878) (xy 72.709786 -94.312486)
		)
		(stroke
			(width 0)
			(type solid)
		)
		(fill yes)
		(layer "In11.Cu")
		(net "M_M_DQ<10>")
	)
	(gr_poly
		(pts
			(xy 73.05675 -98.07448) (xy 73.034398 -98.036126) (xy 72.872346 -97.933256) (xy 72.681084 -98.043746)
			(xy 72.689212 -98.235516) (xy 72.71131 -98.27387)
		)
		(stroke
			(width 0)
			(type solid)
		)
		(fill yes)
		(layer "In11.Cu")
		(net "M_M_DQS_DN<2>")
	)
	(gr_poly
		(pts
			(xy 73.05675 -97.08388) (xy 73.034398 -97.045526) (xy 72.872346 -96.942656) (xy 72.681084 -97.053146)
			(xy 72.689212 -97.244916) (xy 72.71131 -97.28327)
		)
		(stroke
			(width 0)
			(type solid)
		)
		(fill yes)
		(layer "In11.Cu")
		(net "M_M_DQS_DP<11>")
	)
	(gr_poly
		(pts
			(xy 73.05675 -96.09328) (xy 73.034398 -96.054926) (xy 72.872346 -95.952056) (xy 72.681084 -96.062546)
			(xy 72.689212 -96.254316) (xy 72.71131 -96.29267)
		)
		(stroke
			(width 0)
			(type solid)
		)
		(fill yes)
		(layer "In11.Cu")
		(net "M_M_DQ<16>")
	)
	(gr_poly
		(pts
			(xy 73.05675 -95.10268) (xy 73.034398 -95.064326) (xy 72.872346 -94.961456) (xy 72.681084 -95.071946)
			(xy 72.689212 -95.263716) (xy 72.71131 -95.30207)
		)
		(stroke
			(width 0)
			(type solid)
		)
		(fill yes)
		(layer "In11.Cu")
		(net "M_M_DQ<20>")
	)
	(gr_poly
		(pts
			(xy 73.05675 -92.13088) (xy 73.034398 -92.092526) (xy 72.872346 -91.989656) (xy 72.681084 -92.100146)
			(xy 72.689212 -92.291916) (xy 72.71131 -92.33027)
		)
		(stroke
			(width 0)
			(type solid)
		)
		(fill yes)
		(layer "In11.Cu")
		(net "M_M_DQS_DN<1>")
	)
	(gr_poly
		(pts
			(xy 73.05675 -91.14028) (xy 73.034398 -91.101926) (xy 72.872346 -90.999056) (xy 72.681084 -91.109546)
			(xy 72.689212 -91.301316) (xy 72.71131 -91.33967)
		)
		(stroke
			(width 0)
			(type solid)
		)
		(fill yes)
		(layer "In11.Cu")
		(net "M_M_DQS_DP<10>")
	)
	(gr_poly
		(pts
			(xy 73.05675 -90.14968) (xy 73.034398 -90.111326) (xy 72.872346 -90.008456) (xy 72.681084 -90.118946)
			(xy 72.689212 -90.310716) (xy 72.71131 -90.34907)
		)
		(stroke
			(width 0)
			(type solid)
		)
		(fill yes)
		(layer "In11.Cu")
		(net "M_M_DQ<8>")
	)
	(gr_poly
		(pts
			(xy 73.05675 -89.15908) (xy 73.034398 -89.120726) (xy 72.872346 -89.017856) (xy 72.681084 -89.128346)
			(xy 72.689212 -89.320116) (xy 72.71131 -89.35847)
		)
		(stroke
			(width 0)
			(type solid)
		)
		(fill yes)
		(layer "In11.Cu")
		(net "M_M_DQ<12>")
	)
	(gr_poly
		(pts
			(xy 73.05675 -88.16848) (xy 73.034398 -88.130126) (xy 72.872346 -88.027256) (xy 72.681084 -88.137746)
			(xy 72.689212 -88.329516) (xy 72.71131 -88.36787)
		)
		(stroke
			(width 0)
			(type solid)
		)
		(fill yes)
		(layer "In11.Cu")
		(net "M_M_DQ<2>")
	)
	(gr_poly
		(pts
			(xy 73.05675 -87.17788) (xy 73.034398 -87.139526) (xy 72.872346 -87.036656) (xy 72.681084 -87.147146)
			(xy 72.689212 -87.338916) (xy 72.71131 -87.37727)
		)
		(stroke
			(width 0)
			(type solid)
		)
		(fill yes)
		(layer "In11.Cu")
		(net "M_M_DQ<6>")
	)
	(gr_poly
		(pts
			(xy 73.05675 -86.18728) (xy 73.034398 -86.148926) (xy 72.872346 -86.046056) (xy 72.681084 -86.156546)
			(xy 72.689212 -86.348316) (xy 72.71131 -86.38667)
		)
		(stroke
			(width 0)
			(type solid)
		)
		(fill yes)
		(layer "In11.Cu")
		(net "M_M_DQS_DN<0>")
	)
	(gr_poly
		(pts
			(xy 73.05675 -85.19668) (xy 73.034398 -85.158326) (xy 72.872346 -85.055456) (xy 72.681084 -85.165946)
			(xy 72.689212 -85.357716) (xy 72.71131 -85.39607)
		)
		(stroke
			(width 0)
			(type solid)
		)
		(fill yes)
		(layer "In11.Cu")
		(net "M_M_DQS_DP<9>")
	)
	(gr_poly
		(pts
			(xy 73.05675 -84.20608) (xy 73.034398 -84.167726) (xy 72.872346 -84.064856) (xy 72.681084 -84.175346)
			(xy 72.689212 -84.367116) (xy 72.71131 -84.40547)
		)
		(stroke
			(width 0)
			(type solid)
		)
		(fill yes)
		(layer "In11.Cu")
		(net "M_M_DQ<0>")
	)
	(gr_poly
		(pts
			(xy 73.05675 -83.21548) (xy 73.034398 -83.177126) (xy 72.872346 -83.074256) (xy 72.681084 -83.184746)
			(xy 72.689212 -83.376516) (xy 72.71131 -83.41487)
		)
		(stroke
			(width 0)
			(type solid)
		)
		(fill yes)
		(layer "In11.Cu")
		(net "M_M_DQ<4>")
	)
	(gr_poly
		(pts
			(xy 73.059036 -93.12021) (xy 73.036684 -93.081856) (xy 72.874632 -92.978986) (xy 72.68337 -93.089476)
			(xy 72.691498 -93.281246) (xy 72.713596 -93.319854)
		)
		(stroke
			(width 0)
			(type solid)
		)
		(fill yes)
		(layer "In11.Cu")
		(net "M_M_DQ<14>")
	)
	(gr_poly
		(pts
			(xy 73.134474 -51.73853) (xy 73.134474 -51.51755) (xy 72.964294 -51.42865) (xy 72.919844 -51.42865)
			(xy 72.919844 -51.82743) (xy 72.964294 -51.82743)
		)
		(stroke
			(width 0)
			(type solid)
		)
		(fill yes)
		(layer "In11.Cu")
		(net "M_J_DQ<23>")
	)
	(gr_poly
		(pts
			(xy 73.15708 -49.960276) (xy 73.15708 -49.731676) (xy 72.96404 -49.642776) (xy 72.91959 -49.642776)
			(xy 72.91959 -50.049176) (xy 72.96404 -50.049176)
		)
		(stroke
			(width 0)
			(type solid)
		)
		(fill yes)
		(layer "In11.Cu")
		(net "M_J_DQ<23>")
	)
	(gr_poly
		(pts
			(xy 73.31583 -103.299514) (xy 73.284334 -103.268272) (xy 73.084944 -103.194612) (xy 72.9234 -103.356156)
			(xy 72.99706 -103.555546) (xy 73.028302 -103.587042)
		)
		(stroke
			(width 0)
			(type solid)
		)
		(fill yes)
		(layer "In11.Cu")
		(net "M_M_DQ<22>")
	)
	(gr_poly
		(pts
			(xy 73.454768 -100.9523) (xy 73.410318 -100.9523) (xy 73.240138 -101.0412) (xy 73.240138 -101.26218)
			(xy 73.410318 -101.35108) (xy 73.454768 -101.35108)
		)
		(stroke
			(width 0)
			(type solid)
		)
		(fill yes)
		(layer "In11.Cu")
		(net "M_M_DQ<22>")
	)
	(gr_poly
		(pts
			(xy 73.454768 -99.974146) (xy 73.410318 -99.974146) (xy 73.240138 -100.063046) (xy 73.240138 -100.284026)
			(xy 73.410318 -100.372926) (xy 73.454768 -100.372926)
		)
		(stroke
			(width 0)
			(type solid)
		)
		(fill yes)
		(layer "In11.Cu")
		(net "M_M_DQ<22>")
	)
	(gr_poly
		(pts
			(xy 73.455022 -98.988118) (xy 73.410572 -98.988372) (xy 73.240392 -99.077272) (xy 73.240392 -99.298252)
			(xy 73.410572 -99.387152) (xy 73.454768 -99.387152)
		)
		(stroke
			(width 0)
			(type solid)
		)
		(fill yes)
		(layer "In11.Cu")
		(net "M_M_DQ<22>")
	)
	(gr_poly
		(pts
			(xy 73.455022 -51.420014) (xy 73.410572 -51.420268) (xy 73.240392 -51.509422) (xy 73.240646 -51.730402)
			(xy 73.410826 -51.819048) (xy 73.45553 -51.819048)
		)
		(stroke
			(width 0)
			(type solid)
		)
		(fill yes)
		(layer "In11.Cu")
		(net "M_J_DQ<18>")
	)
	(gr_poly
		(pts
			(xy 73.455022 -50.429414) (xy 73.410572 -50.429668) (xy 73.240392 -50.518822) (xy 73.240646 -50.739802)
			(xy 73.410826 -50.828448) (xy 73.45553 -50.828448)
		)
		(stroke
			(width 0)
			(type solid)
		)
		(fill yes)
		(layer "In11.Cu")
		(net "M_J_DQ<18>")
	)
	(gr_poly
		(pts
			(xy 73.555098 -103.664766) (xy 73.481438 -103.465376) (xy 73.450196 -103.43388) (xy 73.162668 -103.721408)
			(xy 73.194164 -103.75265) (xy 73.393554 -103.82631)
		)
		(stroke
			(width 0)
			(type solid)
		)
		(fill yes)
		(layer "In11.Cu")
		(net "M_M_DQ<23>")
	)
	(gr_poly
		(pts
			(xy 73.607168 -102.1207) (xy 73.562718 -102.1207) (xy 73.392538 -102.2096) (xy 73.392538 -102.43058)
			(xy 73.562718 -102.51948) (xy 73.607168 -102.51948)
		)
		(stroke
			(width 0)
			(type solid)
		)
		(fill yes)
		(layer "In11.Cu")
		(net "M_M_DQ<22>")
	)
	(gr_poly
		(pts
			(xy 73.683114 -57.619646) (xy 73.691242 -57.427876) (xy 73.49998 -57.317386) (xy 73.337928 -57.420256)
			(xy 73.315576 -57.45861) (xy 73.661016 -57.658)
		)
		(stroke
			(width 0)
			(type solid)
		)
		(fill yes)
		(layer "In11.Cu")
		(net "M_J_DQ<11>")
	)
	(gr_poly
		(pts
			(xy 73.6854 -68.517516) (xy 73.693528 -68.325746) (xy 73.502266 -68.215256) (xy 73.340214 -68.318126)
			(xy 73.317862 -68.35648) (xy 73.663302 -68.556124)
		)
		(stroke
			(width 0)
			(type solid)
		)
		(fill yes)
		(layer "In11.Cu")
		(net "M_J_DQ<5>")
	)
	(gr_poly
		(pts
			(xy 73.6854 -67.526916) (xy 73.693528 -67.335146) (xy 73.502266 -67.224656) (xy 73.340214 -67.327526)
			(xy 73.317862 -67.36588) (xy 73.663302 -67.565524)
		)
		(stroke
			(width 0)
			(type solid)
		)
		(fill yes)
		(layer "In11.Cu")
		(net "M_J_DQ<1>")
	)
	(gr_poly
		(pts
			(xy 73.6854 -66.536316) (xy 73.693528 -66.344546) (xy 73.502266 -66.234056) (xy 73.340214 -66.336926)
			(xy 73.317862 -66.37528) (xy 73.663302 -66.57467)
		)
		(stroke
			(width 0)
			(type solid)
		)
		(fill yes)
		(layer "In11.Cu")
		(net "M_J_DQS_DN<9>")
	)
	(gr_poly
		(pts
			(xy 73.6854 -64.555116) (xy 73.693528 -64.363346) (xy 73.502266 -64.252856) (xy 73.340214 -64.355726)
			(xy 73.317862 -64.39408) (xy 73.663302 -64.593724)
		)
		(stroke
			(width 0)
			(type solid)
		)
		(fill yes)
		(layer "In11.Cu")
		(net "M_J_DQ<7>")
	)
	(gr_poly
		(pts
			(xy 73.6854 -63.564516) (xy 73.693528 -63.372746) (xy 73.502266 -63.262256) (xy 73.340214 -63.365126)
			(xy 73.317862 -63.40348) (xy 73.663302 -63.603124)
		)
		(stroke
			(width 0)
			(type solid)
		)
		(fill yes)
		(layer "In11.Cu")
		(net "M_J_DQ<3>")
	)
	(gr_poly
		(pts
			(xy 73.6854 -62.573916) (xy 73.693528 -62.382146) (xy 73.502266 -62.271656) (xy 73.340214 -62.374526)
			(xy 73.317862 -62.41288) (xy 73.663302 -62.612524)
		)
		(stroke
			(width 0)
			(type solid)
		)
		(fill yes)
		(layer "In11.Cu")
		(net "M_J_DQ<13>")
	)
	(gr_poly
		(pts
			(xy 73.6854 -61.583316) (xy 73.693528 -61.391546) (xy 73.502266 -61.281056) (xy 73.340214 -61.383926)
			(xy 73.317862 -61.42228) (xy 73.663302 -61.621924)
		)
		(stroke
			(width 0)
			(type solid)
		)
		(fill yes)
		(layer "In11.Cu")
		(net "M_J_DQ<9>")
	)
	(gr_poly
		(pts
			(xy 73.6854 -60.592716) (xy 73.693528 -60.400946) (xy 73.502266 -60.290456) (xy 73.340214 -60.393326)
			(xy 73.317862 -60.43168) (xy 73.663302 -60.631324)
		)
		(stroke
			(width 0)
			(type solid)
		)
		(fill yes)
		(layer "In11.Cu")
		(net "M_J_DQS_DN<10>")
	)
	(gr_poly
		(pts
			(xy 73.6854 -59.602116) (xy 73.693528 -59.410346) (xy 73.502266 -59.299856) (xy 73.340214 -59.402726)
			(xy 73.317862 -59.44108) (xy 73.663302 -59.640724)
		)
		(stroke
			(width 0)
			(type solid)
		)
		(fill yes)
		(layer "In11.Cu")
		(net "M_J_DQS_DN<1>")
	)
	(gr_poly
		(pts
			(xy 73.6854 -55.639716) (xy 73.693528 -55.447946) (xy 73.502266 -55.337456) (xy 73.340214 -55.440326)
			(xy 73.317862 -55.47868) (xy 73.663302 -55.678324)
		)
		(stroke
			(width 0)
			(type solid)
		)
		(fill yes)
		(layer "In11.Cu")
		(net "M_J_DQ<17>")
	)
	(gr_poly
		(pts
			(xy 73.6854 -54.649116) (xy 73.693528 -54.457346) (xy 73.502266 -54.346856) (xy 73.340214 -54.449726)
			(xy 73.317862 -54.48808) (xy 73.663302 -54.687724)
		)
		(stroke
			(width 0)
			(type solid)
		)
		(fill yes)
		(layer "In11.Cu")
		(net "M_J_DQS_DN<11>")
	)
	(gr_poly
		(pts
			(xy 73.6854 -53.658516) (xy 73.693528 -53.466746) (xy 73.502266 -53.356256) (xy 73.340214 -53.459126)
			(xy 73.317862 -53.49748) (xy 73.663302 -53.697124)
		)
		(stroke
			(width 0)
			(type solid)
		)
		(fill yes)
		(layer "In11.Cu")
		(net "M_J_DQS_DN<2>")
	)
	(gr_poly
		(pts
			(xy 73.686924 -65.546478) (xy 73.695052 -65.354708) (xy 73.50379 -65.244218) (xy 73.341738 -65.347088)
			(xy 73.319386 -65.385442) (xy 73.664826 -65.585086)
		)
		(stroke
			(width 0)
			(type solid)
		)
		(fill yes)
		(layer "In11.Cu")
		(net "M_J_DQS_DN<0>")
	)
	(gr_poly
		(pts
			(xy 73.686924 -58.612278) (xy 73.695052 -58.420508) (xy 73.50379 -58.310018) (xy 73.341738 -58.412888)
			(xy 73.319386 -58.451242) (xy 73.664826 -58.650632)
		)
		(stroke
			(width 0)
			(type solid)
		)
		(fill yes)
		(layer "In11.Cu")
		(net "M_J_DQ<15>")
	)
	(gr_poly
		(pts
			(xy 73.686924 -56.631078) (xy 73.695052 -56.439308) (xy 73.50379 -56.328818) (xy 73.341738 -56.431688)
			(xy 73.319386 -56.470042) (xy 73.664826 -56.669686)
		)
		(stroke
			(width 0)
			(type solid)
		)
		(fill yes)
		(layer "In11.Cu")
		(net "M_J_DQ<21>")
	)
	(gr_poly
		(pts
			(xy 73.686924 -52.668678) (xy 73.695052 -52.476908) (xy 73.50379 -52.366418) (xy 73.341738 -52.469288)
			(xy 73.319386 -52.507642) (xy 73.664826 -52.707032)
		)
		(stroke
			(width 0)
			(type solid)
		)
		(fill yes)
		(layer "In11.Cu")
		(net "M_J_DQ<23>")
	)
	(gr_poly
		(pts
			(xy 73.691242 -93.37675) (xy 73.683114 -93.18498) (xy 73.661016 -93.146372) (xy 73.315576 -93.345762)
			(xy 73.337928 -93.38437) (xy 73.49998 -93.48724)
		)
		(stroke
			(width 0)
			(type solid)
		)
		(fill yes)
		(layer "In11.Cu")
		(net "M_M_DQ<15>")
	)
	(gr_poly
		(pts
			(xy 73.693528 -94.36608) (xy 73.6854 -94.17431) (xy 73.663302 -94.135702) (xy 73.317862 -94.335346)
			(xy 73.340214 -94.3737) (xy 73.502266 -94.47657)
		)
		(stroke
			(width 0)
			(type solid)
		)
		(fill yes)
		(layer "In11.Cu")
		(net "M_M_DQ<11>")
	)
	(gr_poly
		(pts
			(xy 73.695052 -98.327464) (xy 73.686924 -98.135694) (xy 73.664826 -98.097086) (xy 73.319386 -98.29673)
			(xy 73.341738 -98.335084) (xy 73.50379 -98.437954)
		)
		(stroke
			(width 0)
			(type solid)
		)
		(fill yes)
		(layer "In11.Cu")
		(net "M_M_DQS_DP<2>")
	)
	(gr_poly
		(pts
			(xy 73.695052 -97.336864) (xy 73.686924 -97.145094) (xy 73.664826 -97.106486) (xy 73.319386 -97.30613)
			(xy 73.341738 -97.344484) (xy 73.50379 -97.447354)
		)
		(stroke
			(width 0)
			(type solid)
		)
		(fill yes)
		(layer "In11.Cu")
		(net "M_M_DQS_DN<11>")
	)
	(gr_poly
		(pts
			(xy 73.695052 -96.346264) (xy 73.686924 -96.154494) (xy 73.664826 -96.115886) (xy 73.319386 -96.31553)
			(xy 73.341738 -96.353884) (xy 73.50379 -96.456754)
		)
		(stroke
			(width 0)
			(type solid)
		)
		(fill yes)
		(layer "In11.Cu")
		(net "M_M_DQ<17>")
	)
	(gr_poly
		(pts
			(xy 73.695052 -95.355664) (xy 73.686924 -95.163894) (xy 73.664826 -95.125286) (xy 73.319386 -95.32493)
			(xy 73.341738 -95.363284) (xy 73.50379 -95.466154)
		)
		(stroke
			(width 0)
			(type solid)
		)
		(fill yes)
		(layer "In11.Cu")
		(net "M_M_DQ<21>")
	)
	(gr_poly
		(pts
			(xy 73.695052 -92.383864) (xy 73.686924 -92.192094) (xy 73.664826 -92.153486) (xy 73.319386 -92.35313)
			(xy 73.341738 -92.391484) (xy 73.50379 -92.494354)
		)
		(stroke
			(width 0)
			(type solid)
		)
		(fill yes)
		(layer "In11.Cu")
		(net "M_M_DQS_DP<1>")
	)
	(gr_poly
		(pts
			(xy 73.695052 -91.393264) (xy 73.686924 -91.201494) (xy 73.664826 -91.162886) (xy 73.319386 -91.36253)
			(xy 73.341738 -91.400884) (xy 73.50379 -91.503754)
		)
		(stroke
			(width 0)
			(type solid)
		)
		(fill yes)
		(layer "In11.Cu")
		(net "M_M_DQS_DN<10>")
	)
	(gr_poly
		(pts
			(xy 73.695052 -90.402664) (xy 73.686924 -90.210894) (xy 73.664826 -90.172286) (xy 73.319386 -90.37193)
			(xy 73.341738 -90.410284) (xy 73.50379 -90.513154)
		)
		(stroke
			(width 0)
			(type solid)
		)
		(fill yes)
		(layer "In11.Cu")
		(net "M_M_DQ<9>")
	)
	(gr_poly
		(pts
			(xy 73.695052 -89.412064) (xy 73.686924 -89.220294) (xy 73.664826 -89.181686) (xy 73.319386 -89.38133)
			(xy 73.341738 -89.419684) (xy 73.50379 -89.522554)
		)
		(stroke
			(width 0)
			(type solid)
		)
		(fill yes)
		(layer "In11.Cu")
		(net "M_M_DQ<13>")
	)
	(gr_poly
		(pts
			(xy 73.695052 -88.421464) (xy 73.686924 -88.229694) (xy 73.664826 -88.191086) (xy 73.319386 -88.39073)
			(xy 73.341738 -88.429084) (xy 73.50379 -88.531954)
		)
		(stroke
			(width 0)
			(type solid)
		)
		(fill yes)
		(layer "In11.Cu")
		(net "M_M_DQ<3>")
	)
	(gr_poly
		(pts
			(xy 73.695052 -87.430864) (xy 73.686924 -87.239094) (xy 73.664826 -87.200486) (xy 73.319386 -87.40013)
			(xy 73.341738 -87.438484) (xy 73.50379 -87.541354)
		)
		(stroke
			(width 0)
			(type solid)
		)
		(fill yes)
		(layer "In11.Cu")
		(net "M_M_DQ<7>")
	)
	(gr_poly
		(pts
			(xy 73.695052 -86.440264) (xy 73.686924 -86.248494) (xy 73.664826 -86.209886) (xy 73.319386 -86.40953)
			(xy 73.341738 -86.447884) (xy 73.50379 -86.550754)
		)
		(stroke
			(width 0)
			(type solid)
		)
		(fill yes)
		(layer "In11.Cu")
		(net "M_M_DQS_DP<0>")
	)
	(gr_poly
		(pts
			(xy 73.695052 -85.449664) (xy 73.686924 -85.257894) (xy 73.664826 -85.219286) (xy 73.319386 -85.41893)
			(xy 73.341738 -85.457284) (xy 73.50379 -85.560154)
		)
		(stroke
			(width 0)
			(type solid)
		)
		(fill yes)
		(layer "In11.Cu")
		(net "M_M_DQS_DN<9>")
	)
	(gr_poly
		(pts
			(xy 73.695052 -84.459064) (xy 73.686924 -84.267294) (xy 73.664826 -84.228686) (xy 73.319386 -84.42833)
			(xy 73.341738 -84.466684) (xy 73.50379 -84.569554)
		)
		(stroke
			(width 0)
			(type solid)
		)
		(fill yes)
		(layer "In11.Cu")
		(net "M_M_DQ<1>")
	)
	(gr_poly
		(pts
			(xy 73.695052 -83.468718) (xy 73.686924 -83.276948) (xy 73.664826 -83.238594) (xy 73.319386 -83.43773)
			(xy 73.341738 -83.476338) (xy 73.50379 -83.579208)
		)
		(stroke
			(width 0)
			(type solid)
		)
		(fill yes)
		(layer "In11.Cu")
		(net "M_M_DQ<5>")
	)
	(gr_poly
		(pts
			(xy 73.80605 -49.397666) (xy 73.7616 -49.397666) (xy 73.56856 -49.486566) (xy 73.56856 -49.715166)
			(xy 73.7616 -49.804066) (xy 73.80605 -49.804066)
		)
		(stroke
			(width 0)
			(type solid)
		)
		(fill yes)
		(layer "In11.Cu")
		(net "M_J_DQ<18>")
	)
	(gr_poly
		(pts
			(xy 73.891394 -60.197238) (xy 73.913746 -60.158884) (xy 73.568306 -59.95924) (xy 73.546208 -59.997848)
			(xy 73.53808 -60.189618) (xy 73.729342 -60.300108)
		)
		(stroke
			(width 0)
			(type solid)
		)
		(fill yes)
		(layer "In11.Cu")
		(net "M_J_DQS_DP<1>")
	)
	(gr_poly
		(pts
			(xy 73.891394 -58.216038) (xy 73.913746 -58.177684) (xy 73.568306 -57.97804) (xy 73.546208 -58.016648)
			(xy 73.53808 -58.208418) (xy 73.729342 -58.318908)
		)
		(stroke
			(width 0)
			(type solid)
		)
		(fill yes)
		(layer "In11.Cu")
		(net "M_J_DQ<10>")
	)
	(gr_poly
		(pts
			(xy 73.892918 -68.1228) (xy 73.91527 -68.084192) (xy 73.56983 -67.885056) (xy 73.547732 -67.92341)
			(xy 73.539604 -68.11518) (xy 73.730866 -68.22567)
		)
		(stroke
			(width 0)
			(type solid)
		)
		(fill yes)
		(layer "In11.Cu")
		(net "M_J_DQ<0>")
	)
	(gr_poly
		(pts
			(xy 73.892918 -65.151) (xy 73.91527 -65.112392) (xy 73.56983 -64.913002) (xy 73.547732 -64.95161)
			(xy 73.539604 -65.14338) (xy 73.730866 -65.25387)
		)
		(stroke
			(width 0)
			(type solid)
		)
		(fill yes)
		(layer "In11.Cu")
		(net "M_J_DQ<6>")
	)
	(gr_poly
		(pts
			(xy 73.892918 -64.1604) (xy 73.91527 -64.121792) (xy 73.56983 -63.922402) (xy 73.547732 -63.96101)
			(xy 73.539604 -64.15278) (xy 73.730866 -64.26327)
		)
		(stroke
			(width 0)
			(type solid)
		)
		(fill yes)
		(layer "In11.Cu")
		(net "M_J_DQ<2>")
	)
	(gr_poly
		(pts
			(xy 73.892918 -63.1698) (xy 73.91527 -63.131192) (xy 73.56983 -62.931802) (xy 73.547732 -62.97041)
			(xy 73.539604 -63.16218) (xy 73.730866 -63.27267)
		)
		(stroke
			(width 0)
			(type solid)
		)
		(fill yes)
		(layer "In11.Cu")
		(net "M_J_DQ<12>")
	)
	(gr_poly
		(pts
			(xy 73.892918 -62.1792) (xy 73.91527 -62.140592) (xy 73.56983 -61.941202) (xy 73.547732 -61.97981)
			(xy 73.539604 -62.17158) (xy 73.730866 -62.28207)
		)
		(stroke
			(width 0)
			(type solid)
		)
		(fill yes)
		(layer "In11.Cu")
		(net "M_J_DQ<8>")
	)
	(gr_poly
		(pts
			(xy 73.892918 -61.1886) (xy 73.91527 -61.149992) (xy 73.56983 -60.950602) (xy 73.547732 -60.98921)
			(xy 73.539604 -61.18098) (xy 73.730866 -61.29147)
		)
		(stroke
			(width 0)
			(type solid)
		)
		(fill yes)
		(layer "In11.Cu")
		(net "M_J_DQS_DP<10>")
	)
	(gr_poly
		(pts
			(xy 73.892918 -57.2262) (xy 73.91527 -57.187592) (xy 73.56983 -56.988202) (xy 73.547732 -57.02681)
			(xy 73.539604 -57.21858) (xy 73.730866 -57.32907)
		)
		(stroke
			(width 0)
			(type solid)
		)
		(fill yes)
		(layer "In11.Cu")
		(net "M_J_DQ<20>")
	)
	(gr_poly
		(pts
			(xy 73.892918 -56.2356) (xy 73.91527 -56.196992) (xy 73.56983 -55.997602) (xy 73.547732 -56.03621)
			(xy 73.539604 -56.22798) (xy 73.730866 -56.33847)
		)
		(stroke
			(width 0)
			(type solid)
		)
		(fill yes)
		(layer "In11.Cu")
		(net "M_J_DQ<16>")
	)
	(gr_poly
		(pts
			(xy 73.892918 -54.2544) (xy 73.91527 -54.215792) (xy 73.56983 -54.016402) (xy 73.547732 -54.05501)
			(xy 73.539604 -54.24678) (xy 73.730866 -54.35727)
		)
		(stroke
			(width 0)
			(type solid)
		)
		(fill yes)
		(layer "In11.Cu")
		(net "M_J_DQS_DP<2>")
	)
	(gr_poly
		(pts
			(xy 73.892918 -52.2732) (xy 73.91527 -52.234592) (xy 73.56983 -52.035202) (xy 73.547732 -52.07381)
			(xy 73.539604 -52.26558) (xy 73.730866 -52.37607)
		)
		(stroke
			(width 0)
			(type solid)
		)
		(fill yes)
		(layer "In11.Cu")
		(net "M_J_DQ<18>")
	)
	(gr_poly
		(pts
			(xy 73.894696 -55.246016) (xy 73.917048 -55.207408) (xy 73.571608 -55.008018) (xy 73.54951 -55.046626)
			(xy 73.541382 -55.238396) (xy 73.732644 -55.348886)
		)
		(stroke
			(width 0)
			(type solid)
		)
		(fill yes)
		(layer "In11.Cu")
		(net "M_J_DQS_DP<11>")
	)
	(gr_poly
		(pts
			(xy 73.895204 -59.20867) (xy 73.917556 -59.170316) (xy 73.572116 -58.970672) (xy 73.550018 -59.00928)
			(xy 73.54189 -59.20105) (xy 73.733152 -59.31154)
		)
		(stroke
			(width 0)
			(type solid)
		)
		(fill yes)
		(layer "In11.Cu")
		(net "M_J_DQ<14>")
	)
	(gr_poly
		(pts
			(xy 73.895204 -53.26507) (xy 73.917556 -53.226716) (xy 73.572116 -53.027072) (xy 73.550018 -53.06568)
			(xy 73.54189 -53.25745) (xy 73.733152 -53.36794)
		)
		(stroke
			(width 0)
			(type solid)
		)
		(fill yes)
		(layer "In11.Cu")
		(net "M_J_DQ<22>")
	)
	(gr_poly
		(pts
			(xy 73.900538 -67.136518) (xy 73.92289 -67.098164) (xy 73.57745 -66.89852) (xy 73.555352 -66.937128)
			(xy 73.547224 -67.128898) (xy 73.738486 -67.239388)
		)
		(stroke
			(width 0)
			(type solid)
		)
		(fill yes)
		(layer "In11.Cu")
		(net "M_J_DQS_DP<9>")
	)
	(gr_poly
		(pts
			(xy 73.900538 -66.145918) (xy 73.92289 -66.107564) (xy 73.57745 -65.90792) (xy 73.555352 -65.946528)
			(xy 73.547224 -66.138298) (xy 73.738486 -66.248788)
		)
		(stroke
			(width 0)
			(type solid)
		)
		(fill yes)
		(layer "In11.Cu")
		(net "M_J_DQS_DP<0>")
	)
	(gr_poly
		(pts
			(xy 73.913746 -98.570796) (xy 73.891394 -98.532442) (xy 73.729342 -98.429572) (xy 73.53808 -98.540062)
			(xy 73.545954 -98.731832) (xy 73.568052 -98.770186)
		)
		(stroke
			(width 0)
			(type solid)
		)
		(fill yes)
		(layer "In11.Cu")
		(net "M_M_DQ<22>")
	)
	(gr_poly
		(pts
			(xy 73.913746 -97.58045) (xy 73.891394 -97.541842) (xy 73.729342 -97.438972) (xy 73.53808 -97.549462)
			(xy 73.546208 -97.741232) (xy 73.568306 -97.77984)
		)
		(stroke
			(width 0)
			(type solid)
		)
		(fill yes)
		(layer "In11.Cu")
		(net "M_M_DQS_DN<2>")
	)
	(gr_poly
		(pts
			(xy 73.913746 -96.58985) (xy 73.891394 -96.551242) (xy 73.729342 -96.448372) (xy 73.53808 -96.558862)
			(xy 73.546208 -96.750632) (xy 73.568306 -96.78924)
		)
		(stroke
			(width 0)
			(type solid)
		)
		(fill yes)
		(layer "In11.Cu")
		(net "M_M_DQS_DP<11>")
	)
	(gr_poly
		(pts
			(xy 73.913746 -95.59925) (xy 73.891394 -95.560642) (xy 73.729342 -95.457772) (xy 73.53808 -95.568262)
			(xy 73.546208 -95.760032) (xy 73.568306 -95.79864)
		)
		(stroke
			(width 0)
			(type solid)
		)
		(fill yes)
		(layer "In11.Cu")
		(net "M_M_DQ<16>")
	)
	(gr_poly
		(pts
			(xy 73.913746 -92.62745) (xy 73.891394 -92.588842) (xy 73.729342 -92.485972) (xy 73.53808 -92.596462)
			(xy 73.546208 -92.788232) (xy 73.568306 -92.82684)
		)
		(stroke
			(width 0)
			(type solid)
		)
		(fill yes)
		(layer "In11.Cu")
		(net "M_M_DQ<14>")
	)
	(gr_poly
		(pts
			(xy 73.913746 -91.63685) (xy 73.891394 -91.598242) (xy 73.729342 -91.495372) (xy 73.53808 -91.605862)
			(xy 73.546208 -91.797632) (xy 73.568306 -91.83624)
		)
		(stroke
			(width 0)
			(type solid)
		)
		(fill yes)
		(layer "In11.Cu")
		(net "M_M_DQS_DN<1>")
	)
	(gr_poly
		(pts
			(xy 73.913746 -90.64625) (xy 73.891394 -90.607642) (xy 73.729342 -90.504772) (xy 73.53808 -90.615262)
			(xy 73.546208 -90.807032) (xy 73.568306 -90.84564)
		)
		(stroke
			(width 0)
			(type solid)
		)
		(fill yes)
		(layer "In11.Cu")
		(net "M_M_DQS_DP<10>")
	)
	(gr_poly
		(pts
			(xy 73.913746 -89.65565) (xy 73.891394 -89.617042) (xy 73.729342 -89.514172) (xy 73.53808 -89.624662)
			(xy 73.546208 -89.816432) (xy 73.568306 -89.85504)
		)
		(stroke
			(width 0)
			(type solid)
		)
		(fill yes)
		(layer "In11.Cu")
		(net "M_M_DQ<8>")
	)
	(gr_poly
		(pts
			(xy 73.913746 -88.66505) (xy 73.891394 -88.626442) (xy 73.729342 -88.523572) (xy 73.53808 -88.634062)
			(xy 73.546208 -88.825832) (xy 73.568306 -88.86444)
		)
		(stroke
			(width 0)
			(type solid)
		)
		(fill yes)
		(layer "In11.Cu")
		(net "M_M_DQ<12>")
	)
	(gr_poly
		(pts
			(xy 73.913746 -87.67445) (xy 73.891394 -87.635842) (xy 73.729342 -87.532972) (xy 73.53808 -87.643462)
			(xy 73.546208 -87.835232) (xy 73.568306 -87.87384)
		)
		(stroke
			(width 0)
			(type solid)
		)
		(fill yes)
		(layer "In11.Cu")
		(net "M_M_DQ<2>")
	)
	(gr_poly
		(pts
			(xy 73.913746 -86.68385) (xy 73.891394 -86.645242) (xy 73.729342 -86.542372) (xy 73.53808 -86.652862)
			(xy 73.546208 -86.844632) (xy 73.568306 -86.88324)
		)
		(stroke
			(width 0)
			(type solid)
		)
		(fill yes)
		(layer "In11.Cu")
		(net "M_M_DQ<6>")
	)
	(gr_poly
		(pts
			(xy 73.913746 -85.69325) (xy 73.891394 -85.654642) (xy 73.729342 -85.551772) (xy 73.53808 -85.662262)
			(xy 73.546208 -85.854032) (xy 73.568306 -85.89264)
		)
		(stroke
			(width 0)
			(type solid)
		)
		(fill yes)
		(layer "In11.Cu")
		(net "M_M_DQS_DN<0>")
	)
	(gr_poly
		(pts
			(xy 73.913746 -84.70265) (xy 73.891394 -84.664042) (xy 73.729342 -84.561172) (xy 73.53808 -84.671662)
			(xy 73.546208 -84.863432) (xy 73.568306 -84.90204)
		)
		(stroke
			(width 0)
			(type solid)
		)
		(fill yes)
		(layer "In11.Cu")
		(net "M_M_DQS_DP<9>")
	)
	(gr_poly
		(pts
			(xy 73.913746 -83.71205) (xy 73.891394 -83.673442) (xy 73.729342 -83.570572) (xy 73.53808 -83.681062)
			(xy 73.546208 -83.872832) (xy 73.568306 -83.91144)
		)
		(stroke
			(width 0)
			(type solid)
		)
		(fill yes)
		(layer "In11.Cu")
		(net "M_M_DQ<0>")
	)
	(gr_poly
		(pts
			(xy 73.913746 -82.72145) (xy 73.891394 -82.682842) (xy 73.729342 -82.579972) (xy 73.53808 -82.690462)
			(xy 73.546208 -82.882232) (xy 73.568306 -82.92084)
		)
		(stroke
			(width 0)
			(type solid)
		)
		(fill yes)
		(layer "In11.Cu")
		(net "M_M_DQ<4>")
	)
	(gr_poly
		(pts
			(xy 73.91527 -93.61678) (xy 73.892918 -93.578426) (xy 73.730866 -93.475556) (xy 73.539604 -93.586046)
			(xy 73.547732 -93.777816) (xy 73.56983 -93.81617)
		)
		(stroke
			(width 0)
			(type solid)
		)
		(fill yes)
		(layer "In11.Cu")
		(net "M_M_DQ<10>")
	)
	(gr_poly
		(pts
			(xy 73.917556 -94.60611) (xy 73.895204 -94.567756) (xy 73.733152 -94.464886) (xy 73.54189 -94.575376)
			(xy 73.550018 -94.767146) (xy 73.572116 -94.805754)
		)
		(stroke
			(width 0)
			(type solid)
		)
		(fill yes)
		(layer "In11.Cu")
		(net "M_M_DQ<20>")
	)
	(gr_poly
		(pts
			(xy 73.992994 -100.772976) (xy 73.992994 -100.551996) (xy 73.822814 -100.463096) (xy 73.778364 -100.463096)
			(xy 73.778364 -100.861876) (xy 73.822814 -100.861876)
		)
		(stroke
			(width 0)
			(type solid)
		)
		(fill yes)
		(layer "In11.Cu")
		(net "M_M_DQ<23>")
	)
	(gr_poly
		(pts
			(xy 73.992994 -99.77628) (xy 73.992994 -99.5553) (xy 73.822814 -99.4664) (xy 73.778364 -99.4664)
			(xy 73.778364 -99.86518) (xy 73.822814 -99.86518)
		)
		(stroke
			(width 0)
			(type solid)
		)
		(fill yes)
		(layer "In11.Cu")
		(net "M_M_DQ<23>")
	)
	(gr_poly
		(pts
			(xy 73.992994 -51.249326) (xy 73.992994 -51.028346) (xy 73.822814 -50.939446) (xy 73.778364 -50.939446)
			(xy 73.778364 -51.338226) (xy 73.822814 -51.338226)
		)
		(stroke
			(width 0)
			(type solid)
		)
		(fill yes)
		(layer "In11.Cu")
		(net "M_J_DQ<19>")
	)
	(gr_poly
		(pts
			(xy 74.02449 -102.979982) (xy 74.02449 -102.751382) (xy 73.83145 -102.662482) (xy 73.787 -102.662482)
			(xy 73.787 -103.068882) (xy 73.83145 -103.068882)
		)
		(stroke
			(width 0)
			(type solid)
		)
		(fill yes)
		(layer "In11.Cu")
		(net "M_M_DQ<23>")
	)
	(gr_poly
		(pts
			(xy 74.02449 -101.989382) (xy 74.02449 -101.760782) (xy 73.83145 -101.671882) (xy 73.787 -101.671882)
			(xy 73.787 -102.078282) (xy 73.83145 -102.078282)
		)
		(stroke
			(width 0)
			(type solid)
		)
		(fill yes)
		(layer "In11.Cu")
		(net "M_M_DQ<23>")
	)
	(gr_poly
		(pts
			(xy 74.035666 -105.306114) (xy 73.962006 -105.106724) (xy 73.930764 -105.075228) (xy 73.643236 -105.362502)
			(xy 73.674732 -105.393998) (xy 73.874122 -105.467658)
		)
		(stroke
			(width 0)
			(type solid)
		)
		(fill yes)
		(layer "In11.Cu")
		(net "M_M_DQ<19>")
	)
	(gr_poly
		(pts
			(xy 74.13117 -104.607106) (xy 74.099928 -104.57561) (xy 73.900538 -104.50195) (xy 73.73874 -104.663494)
			(xy 73.8124 -104.862884) (xy 73.843896 -104.89438)
		)
		(stroke
			(width 0)
			(type solid)
		)
		(fill yes)
		(layer "In11.Cu")
		(net "M_M_DQ<18>")
	)
	(gr_poly
		(pts
			(xy 74.23404 -49.715166) (xy 74.23404 -49.486566) (xy 74.041 -49.397666) (xy 73.99655 -49.397666)
			(xy 73.99655 -49.804066) (xy 74.041 -49.804066)
		)
		(stroke
			(width 0)
			(type solid)
		)
		(fill yes)
		(layer "In11.Cu")
		(net "M_J_DQ<19>")
	)
	(gr_poly
		(pts
			(xy 74.541634 -59.105546) (xy 74.549762 -58.913776) (xy 74.3585 -58.803286) (xy 74.196448 -58.906156)
			(xy 74.174096 -58.94451) (xy 74.519536 -59.1439)
		)
		(stroke
			(width 0)
			(type solid)
		)
		(fill yes)
		(layer "In11.Cu")
		(net "M_J_DQ<15>")
	)
	(gr_poly
		(pts
			(xy 74.541634 -53.161946) (xy 74.549762 -52.970176) (xy 74.3585 -52.859686) (xy 74.196448 -52.962556)
			(xy 74.174096 -53.00091) (xy 74.519536 -53.2003)
		)
		(stroke
			(width 0)
			(type solid)
		)
		(fill yes)
		(layer "In11.Cu")
		(net "M_J_DQ<23>")
	)
	(gr_poly
		(pts
			(xy 74.54392 -58.116216) (xy 74.552048 -57.924446) (xy 74.360786 -57.813956) (xy 74.198734 -57.916826)
			(xy 74.176382 -57.95518) (xy 74.521822 -58.154824)
		)
		(stroke
			(width 0)
			(type solid)
		)
		(fill yes)
		(layer "In11.Cu")
		(net "M_J_DQ<11>")
	)
	(gr_poly
		(pts
			(xy 74.544428 -67.128898) (xy 74.5363 -66.937128) (xy 74.514202 -66.89852) (xy 74.168762 -67.098164)
			(xy 74.191114 -67.136518) (xy 74.353166 -67.239388)
		)
		(stroke
			(width 0)
			(type solid)
		)
		(fill yes)
		(layer "In11.Cu")
		(net "M_J_DQS_DP<9>")
	)
	(gr_poly
		(pts
			(xy 74.544428 -66.138298) (xy 74.5363 -65.946528) (xy 74.514202 -65.90792) (xy 74.168762 -66.107564)
			(xy 74.191114 -66.145918) (xy 74.353166 -66.248788)
		)
		(stroke
			(width 0)
			(type solid)
		)
		(fill yes)
		(layer "In11.Cu")
		(net "M_J_DQS_DP<0>")
	)
	(gr_poly
		(pts
			(xy 74.545444 -84.863432) (xy 74.553572 -84.671662) (xy 74.36231 -84.561172) (xy 74.200258 -84.664042)
			(xy 74.177906 -84.70265) (xy 74.523346 -84.90204)
		)
		(stroke
			(width 0)
			(type solid)
		)
		(fill yes)
		(layer "In11.Cu")
		(net "M_M_DQS_DP<9>")
	)
	(gr_poly
		(pts
			(xy 74.545444 -83.872832) (xy 74.553572 -83.681062) (xy 74.36231 -83.570572) (xy 74.200258 -83.673442)
			(xy 74.177906 -83.71205) (xy 74.523346 -83.91144)
		)
		(stroke
			(width 0)
			(type solid)
		)
		(fill yes)
		(layer "In11.Cu")
		(net "M_M_DQ<0>")
	)
	(gr_poly
		(pts
			(xy 74.545444 -82.882232) (xy 74.553572 -82.690462) (xy 74.36231 -82.579972) (xy 74.200258 -82.682842)
			(xy 74.177906 -82.72145) (xy 74.523346 -82.92084)
		)
		(stroke
			(width 0)
			(type solid)
		)
		(fill yes)
		(layer "In11.Cu")
		(net "M_M_DQ<4>")
	)
	(gr_poly
		(pts
			(xy 74.545444 -60.098432) (xy 74.553572 -59.906662) (xy 74.36231 -59.796172) (xy 74.200258 -59.899042)
			(xy 74.177906 -59.937396) (xy 74.523346 -60.13704)
		)
		(stroke
			(width 0)
			(type solid)
		)
		(fill yes)
		(layer "In11.Cu")
		(net "M_J_DQS_DN<1>")
	)
	(gr_poly
		(pts
			(xy 74.545444 -57.126632) (xy 74.553572 -56.934862) (xy 74.36231 -56.824372) (xy 74.200258 -56.927242)
			(xy 74.177906 -56.965596) (xy 74.523346 -57.16524)
		)
		(stroke
			(width 0)
			(type solid)
		)
		(fill yes)
		(layer "In11.Cu")
		(net "M_J_DQ<21>")
	)
	(gr_poly
		(pts
			(xy 74.545444 -56.136032) (xy 74.553572 -55.944262) (xy 74.36231 -55.833772) (xy 74.200258 -55.936642)
			(xy 74.177906 -55.974996) (xy 74.523346 -56.17464)
		)
		(stroke
			(width 0)
			(type solid)
		)
		(fill yes)
		(layer "In11.Cu")
		(net "M_J_DQ<17>")
	)
	(gr_poly
		(pts
			(xy 74.545444 -55.145432) (xy 74.553572 -54.953662) (xy 74.36231 -54.843172) (xy 74.200258 -54.946042)
			(xy 74.177906 -54.984396) (xy 74.523346 -55.18404)
		)
		(stroke
			(width 0)
			(type solid)
		)
		(fill yes)
		(layer "In11.Cu")
		(net "M_J_DQS_DN<11>")
	)
	(gr_poly
		(pts
			(xy 74.545444 -54.154832) (xy 74.553572 -53.963062) (xy 74.36231 -53.852572) (xy 74.200258 -53.955442)
			(xy 74.177906 -53.993796) (xy 74.523346 -54.19344)
		)
		(stroke
			(width 0)
			(type solid)
		)
		(fill yes)
		(layer "In11.Cu")
		(net "M_J_DQS_DN<2>")
	)
	(gr_poly
		(pts
			(xy 74.545444 -52.173632) (xy 74.553572 -51.981862) (xy 74.36231 -51.871372) (xy 74.200258 -51.974242)
			(xy 74.177906 -52.012596) (xy 74.523346 -52.211986)
		)
		(stroke
			(width 0)
			(type solid)
		)
		(fill yes)
		(layer "In11.Cu")
		(net "M_J_DQ<19>")
	)
	(gr_poly
		(pts
			(xy 74.549762 -94.86265) (xy 74.541634 -94.67088) (xy 74.519536 -94.632272) (xy 74.174096 -94.831662)
			(xy 74.196448 -94.87027) (xy 74.3585 -94.97314)
		)
		(stroke
			(width 0)
			(type solid)
		)
		(fill yes)
		(layer "In11.Cu")
		(net "M_M_DQ<21>")
	)
	(gr_poly
		(pts
			(xy 74.55027 -90.899996) (xy 74.542142 -90.708226) (xy 74.520044 -90.669618) (xy 74.174604 -90.869262)
			(xy 74.196956 -90.907616) (xy 74.359008 -91.010486)
		)
		(stroke
			(width 0)
			(type solid)
		)
		(fill yes)
		(layer "In11.Cu")
		(net "M_M_DQS_DN<10>")
	)
	(gr_poly
		(pts
			(xy 74.552048 -98.82378) (xy 74.54392 -98.63201) (xy 74.521822 -98.593402) (xy 74.176382 -98.793046)
			(xy 74.198734 -98.8314) (xy 74.360786 -98.93427)
		)
		(stroke
			(width 0)
			(type solid)
		)
		(fill yes)
		(layer "In11.Cu")
		(net "M_M_DQ<23>")
	)
	(gr_poly
		(pts
			(xy 74.552048 -97.83318) (xy 74.54392 -97.64141) (xy 74.521822 -97.602802) (xy 74.176382 -97.802446)
			(xy 74.198734 -97.8408) (xy 74.360786 -97.94367)
		)
		(stroke
			(width 0)
			(type solid)
		)
		(fill yes)
		(layer "In11.Cu")
		(net "M_M_DQS_DP<2>")
	)
	(gr_poly
		(pts
			(xy 74.552048 -96.84258) (xy 74.54392 -96.65081) (xy 74.521822 -96.612202) (xy 74.176382 -96.811846)
			(xy 74.198734 -96.8502) (xy 74.360786 -96.95307)
		)
		(stroke
			(width 0)
			(type solid)
		)
		(fill yes)
		(layer "In11.Cu")
		(net "M_M_DQS_DN<11>")
	)
	(gr_poly
		(pts
			(xy 74.552048 -95.85198) (xy 74.54392 -95.66021) (xy 74.521822 -95.621602) (xy 74.176382 -95.821246)
			(xy 74.198734 -95.8596) (xy 74.360786 -95.96247)
		)
		(stroke
			(width 0)
			(type solid)
		)
		(fill yes)
		(layer "In11.Cu")
		(net "M_M_DQ<17>")
	)
	(gr_poly
		(pts
			(xy 74.552048 -91.88958) (xy 74.54392 -91.69781) (xy 74.521822 -91.659202) (xy 74.176382 -91.858846)
			(xy 74.198734 -91.8972) (xy 74.360786 -92.00007)
		)
		(stroke
			(width 0)
			(type solid)
		)
		(fill yes)
		(layer "In11.Cu")
		(net "M_M_DQS_DP<1>")
	)
	(gr_poly
		(pts
			(xy 74.552048 -89.90838) (xy 74.54392 -89.71661) (xy 74.521822 -89.678002) (xy 74.176382 -89.877646)
			(xy 74.198734 -89.916) (xy 74.360786 -90.01887)
		)
		(stroke
			(width 0)
			(type solid)
		)
		(fill yes)
		(layer "In11.Cu")
		(net "M_M_DQ<9>")
	)
	(gr_poly
		(pts
			(xy 74.552048 -88.91778) (xy 74.54392 -88.72601) (xy 74.521822 -88.687402) (xy 74.176382 -88.887046)
			(xy 74.198734 -88.9254) (xy 74.360786 -89.02827)
		)
		(stroke
			(width 0)
			(type solid)
		)
		(fill yes)
		(layer "In11.Cu")
		(net "M_M_DQ<13>")
	)
	(gr_poly
		(pts
			(xy 74.552048 -68.11518) (xy 74.54392 -67.92341) (xy 74.521822 -67.885056) (xy 74.176382 -68.084192)
			(xy 74.198734 -68.1228) (xy 74.360786 -68.22567)
		)
		(stroke
			(width 0)
			(type solid)
		)
		(fill yes)
		(layer "In11.Cu")
		(net "M_J_DQ<0>")
	)
	(gr_poly
		(pts
			(xy 74.553572 -93.870018) (xy 74.545444 -93.678248) (xy 74.523346 -93.639894) (xy 74.177906 -93.83903)
			(xy 74.200258 -93.877638) (xy 74.36231 -93.980508)
		)
		(stroke
			(width 0)
			(type solid)
		)
		(fill yes)
		(layer "In11.Cu")
		(net "M_M_DQ<11>")
	)
	(gr_poly
		(pts
			(xy 74.736198 -104.605582) (xy 74.662538 -104.406192) (xy 74.631296 -104.374696) (xy 74.343768 -104.66197)
			(xy 74.375264 -104.693466) (xy 74.574654 -104.767126)
		)
		(stroke
			(width 0)
			(type solid)
		)
		(fill yes)
		(layer "In11.Cu")
		(net "M_M_DQ<19>")
	)
	(gr_poly
		(pts
			(xy 74.749914 -85.457284) (xy 74.772266 -85.41893) (xy 74.426826 -85.219286) (xy 74.404728 -85.257894)
			(xy 74.3966 -85.449664) (xy 74.587862 -85.560154)
		)
		(stroke
			(width 0)
			(type solid)
		)
		(fill yes)
		(layer "In11.Cu")
		(net "M_M_DQS_DN<9>")
	)
	(gr_poly
		(pts
			(xy 74.749914 -84.466684) (xy 74.772266 -84.42833) (xy 74.426826 -84.228686) (xy 74.404728 -84.267294)
			(xy 74.3966 -84.459064) (xy 74.587862 -84.569554)
		)
		(stroke
			(width 0)
			(type solid)
		)
		(fill yes)
		(layer "In11.Cu")
		(net "M_M_DQ<1>")
	)
	(gr_poly
		(pts
			(xy 74.749914 -83.476338) (xy 74.772266 -83.43773) (xy 74.426826 -83.238594) (xy 74.404728 -83.276948)
			(xy 74.3966 -83.468718) (xy 74.587862 -83.579208)
		)
		(stroke
			(width 0)
			(type solid)
		)
		(fill yes)
		(layer "In11.Cu")
		(net "M_M_DQ<5>")
	)
	(gr_poly
		(pts
			(xy 74.749914 -60.692284) (xy 74.772266 -60.65393) (xy 74.426826 -60.454286) (xy 74.404728 -60.492894)
			(xy 74.3966 -60.684664) (xy 74.587862 -60.795154)
		)
		(stroke
			(width 0)
			(type solid)
		)
		(fill yes)
		(layer "In11.Cu")
		(net "M_J_DQS_DP<1>")
	)
	(gr_poly
		(pts
			(xy 74.749914 -56.729884) (xy 74.772266 -56.69153) (xy 74.426826 -56.491886) (xy 74.404728 -56.530494)
			(xy 74.3966 -56.722264) (xy 74.587862 -56.832754)
		)
		(stroke
			(width 0)
			(type solid)
		)
		(fill yes)
		(layer "In11.Cu")
		(net "M_J_DQ<16>")
	)
	(gr_poly
		(pts
			(xy 74.749914 -54.748684) (xy 74.772266 -54.71033) (xy 74.426826 -54.510686) (xy 74.404728 -54.549294)
			(xy 74.3966 -54.741064) (xy 74.587862 -54.851554)
		)
		(stroke
			(width 0)
			(type solid)
		)
		(fill yes)
		(layer "In11.Cu")
		(net "M_J_DQS_DP<2>")
	)
	(gr_poly
		(pts
			(xy 74.749914 -53.758084) (xy 74.772266 -53.71973) (xy 74.426826 -53.520086) (xy 74.404728 -53.558694)
			(xy 74.3966 -53.750464) (xy 74.587862 -53.860954)
		)
		(stroke
			(width 0)
			(type solid)
		)
		(fill yes)
		(layer "In11.Cu")
		(net "M_J_DQ<22>")
	)
	(gr_poly
		(pts
			(xy 74.751438 -55.740046) (xy 74.77379 -55.701692) (xy 74.42835 -55.502048) (xy 74.406252 -55.540656)
			(xy 74.398124 -55.732426) (xy 74.589386 -55.842916)
		)
		(stroke
			(width 0)
			(type solid)
		)
		(fill yes)
		(layer "In11.Cu")
		(net "M_J_DQS_DP<11>")
	)
	(gr_poly
		(pts
			(xy 74.751438 -52.7685) (xy 74.77379 -52.729892) (xy 74.42835 -52.530502) (xy 74.406252 -52.56911)
			(xy 74.398124 -52.76088) (xy 74.589386 -52.87137)
		)
		(stroke
			(width 0)
			(type solid)
		)
		(fill yes)
		(layer "In11.Cu")
		(net "M_J_DQ<18>")
	)
	(gr_poly
		(pts
			(xy 74.753724 -57.72277) (xy 74.776076 -57.684416) (xy 74.430636 -57.484772) (xy 74.408538 -57.52338)
			(xy 74.40041 -57.71515) (xy 74.591672 -57.82564)
		)
		(stroke
			(width 0)
			(type solid)
		)
		(fill yes)
		(layer "In11.Cu")
		(net "M_J_DQ<20>")
	)
	(gr_poly
		(pts
			(xy 74.772266 -94.112842) (xy 74.749914 -94.074488) (xy 74.587862 -93.971618) (xy 74.3966 -94.082108)
			(xy 74.404728 -94.273878) (xy 74.426826 -94.312486)
		)
		(stroke
			(width 0)
			(type solid)
		)
		(fill yes)
		(layer "In11.Cu")
		(net "M_M_DQ<20>")
	)
	(gr_poly
		(pts
			(xy 74.77379 -98.07448) (xy 74.751438 -98.036126) (xy 74.589386 -97.933256) (xy 74.398124 -98.043746)
			(xy 74.406252 -98.235516) (xy 74.42835 -98.27387)
		)
		(stroke
			(width 0)
			(type solid)
		)
		(fill yes)
		(layer "In11.Cu")
		(net "M_M_DQ<22>")
	)
	(gr_poly
		(pts
			(xy 74.77379 -97.08388) (xy 74.751438 -97.045526) (xy 74.589386 -96.942656) (xy 74.398124 -97.053146)
			(xy 74.406252 -97.244916) (xy 74.42835 -97.28327)
		)
		(stroke
			(width 0)
			(type solid)
		)
		(fill yes)
		(layer "In11.Cu")
		(net "M_M_DQS_DN<2>")
	)
	(gr_poly
		(pts
			(xy 74.77379 -96.09328) (xy 74.751438 -96.054926) (xy 74.589386 -95.952056) (xy 74.398124 -96.062546)
			(xy 74.406252 -96.254316) (xy 74.42835 -96.29267)
		)
		(stroke
			(width 0)
			(type solid)
		)
		(fill yes)
		(layer "In11.Cu")
		(net "M_M_DQS_DP<11>")
	)
	(gr_poly
		(pts
			(xy 74.77379 -95.10268) (xy 74.751438 -95.064326) (xy 74.589386 -94.961456) (xy 74.398124 -95.071946)
			(xy 74.406252 -95.263716) (xy 74.42835 -95.30207)
		)
		(stroke
			(width 0)
			(type solid)
		)
		(fill yes)
		(layer "In11.Cu")
		(net "M_M_DQ<16>")
	)
	(gr_poly
		(pts
			(xy 74.77379 -91.14028) (xy 74.751438 -91.101926) (xy 74.589386 -90.999056) (xy 74.398124 -91.109546)
			(xy 74.406252 -91.301316) (xy 74.42835 -91.33967)
		)
		(stroke
			(width 0)
			(type solid)
		)
		(fill yes)
		(layer "In11.Cu")
		(net "M_M_DQS_DN<1>")
	)
	(gr_poly
		(pts
			(xy 74.77379 -89.15908) (xy 74.751438 -89.120726) (xy 74.589386 -89.017856) (xy 74.398124 -89.128346)
			(xy 74.406252 -89.320116) (xy 74.42835 -89.35847)
		)
		(stroke
			(width 0)
			(type solid)
		)
		(fill yes)
		(layer "In11.Cu")
		(net "M_M_DQ<8>")
	)
	(gr_poly
		(pts
			(xy 74.77379 -88.16848) (xy 74.751438 -88.130126) (xy 74.589386 -88.027256) (xy 74.398124 -88.137746)
			(xy 74.406252 -88.329516) (xy 74.42835 -88.36787)
		)
		(stroke
			(width 0)
			(type solid)
		)
		(fill yes)
		(layer "In11.Cu")
		(net "M_M_DQ<12>")
	)
	(gr_poly
		(pts
			(xy 74.77379 -87.17788) (xy 74.751438 -87.139526) (xy 74.589386 -87.036656) (xy 74.398124 -87.147146)
			(xy 74.406252 -87.338916) (xy 74.42835 -87.37727)
		)
		(stroke
			(width 0)
			(type solid)
		)
		(fill yes)
		(layer "In11.Cu")
		(net "M_M_DQ<2>")
	)
	(gr_poly
		(pts
			(xy 74.77379 -68.35648) (xy 74.751438 -68.318126) (xy 74.589386 -68.215256) (xy 74.398124 -68.325746)
			(xy 74.406252 -68.517516) (xy 74.42835 -68.556124)
		)
		(stroke
			(width 0)
			(type solid)
		)
		(fill yes)
		(layer "In11.Cu")
		(net "M_J_DQ<5>")
	)
	(gr_poly
		(pts
			(xy 74.77379 -67.36588) (xy 74.751438 -67.327526) (xy 74.589386 -67.224656) (xy 74.398124 -67.335146)
			(xy 74.406252 -67.526916) (xy 74.42835 -67.565524)
		)
		(stroke
			(width 0)
			(type solid)
		)
		(fill yes)
		(layer "In11.Cu")
		(net "M_J_DQ<1>")
	)
	(gr_poly
		(pts
			(xy 74.77379 -64.39408) (xy 74.751438 -64.355726) (xy 74.589386 -64.252856) (xy 74.398124 -64.363346)
			(xy 74.406252 -64.555116) (xy 74.42835 -64.593724)
		)
		(stroke
			(width 0)
			(type solid)
		)
		(fill yes)
		(layer "In11.Cu")
		(net "M_J_DQ<7>")
	)
	(gr_poly
		(pts
			(xy 74.775568 -65.383664) (xy 74.753216 -65.34531) (xy 74.591164 -65.24244) (xy 74.399902 -65.35293)
			(xy 74.40803 -65.5447) (xy 74.430128 -65.583308)
		)
		(stroke
			(width 0)
			(type solid)
		)
		(fill yes)
		(layer "In11.Cu")
		(net "M_J_DQS_DN<0>")
	)
	(gr_poly
		(pts
			(xy 74.776076 -93.12021) (xy 74.753724 -93.081856) (xy 74.591672 -92.978986) (xy 74.40041 -93.089476)
			(xy 74.408538 -93.281246) (xy 74.430636 -93.319854)
		)
		(stroke
			(width 0)
			(type solid)
		)
		(fill yes)
		(layer "In11.Cu")
		(net "M_M_DQ<10>")
	)
	(gr_poly
		(pts
			(xy 74.781156 -90.145362) (xy 74.758804 -90.107008) (xy 74.596752 -90.004138) (xy 74.40549 -90.114628)
			(xy 74.413618 -90.306398) (xy 74.435716 -90.345006)
		)
		(stroke
			(width 0)
			(type solid)
		)
		(fill yes)
		(layer "In11.Cu")
		(net "M_M_DQS_DP<10>")
	)
	(gr_poly
		(pts
			(xy 74.831702 -103.906574) (xy 74.80046 -103.875078) (xy 74.60107 -103.801418) (xy 74.439272 -103.962962)
			(xy 74.512932 -104.162352) (xy 74.544428 -104.193848)
		)
		(stroke
			(width 0)
			(type solid)
		)
		(fill yes)
		(layer "In11.Cu")
		(net "M_M_DQ<18>")
	)
	(gr_poly
		(pts
			(xy 75.171808 -100.9523) (xy 75.127358 -100.9523) (xy 74.957178 -101.0412) (xy 74.957178 -101.26218)
			(xy 75.127358 -101.35108) (xy 75.171808 -101.35108)
		)
		(stroke
			(width 0)
			(type solid)
		)
		(fill yes)
		(layer "In11.Cu")
		(net "M_M_DQ<18>")
	)
	(gr_poly
		(pts
			(xy 75.171808 -99.974146) (xy 75.127358 -99.974146) (xy 74.957178 -100.063046) (xy 74.957178 -100.284026)
			(xy 75.127358 -100.372926) (xy 75.171808 -100.372926)
		)
		(stroke
			(width 0)
			(type solid)
		)
		(fill yes)
		(layer "In11.Cu")
		(net "M_M_DQ<18>")
	)
	(gr_poly
		(pts
			(xy 75.172062 -98.988118) (xy 75.127612 -98.988372) (xy 74.957432 -99.077272) (xy 74.957432 -99.298252)
			(xy 75.127612 -99.387152) (xy 75.171808 -99.387152)
		)
		(stroke
			(width 0)
			(type solid)
		)
		(fill yes)
		(layer "In11.Cu")
		(net "M_M_DQ<18>")
	)
	(gr_poly
		(pts
			(xy 75.314048 -64.483742) (xy 75.30592 -64.291972) (xy 75.283822 -64.253364) (xy 74.938382 -64.453008)
			(xy 74.960734 -64.491362) (xy 75.122786 -64.594232)
		)
		(stroke
			(width 0)
			(type solid)
		)
		(fill yes)
		(layer "In11.Cu")
		(net "M_J_DQ<7>")
	)
	(gr_poly
		(pts
			(xy 75.349862 -102.869238) (xy 75.305412 -102.869238) (xy 75.112372 -102.958138) (xy 75.112372 -103.186738)
			(xy 75.305412 -103.275638) (xy 75.349862 -103.275638)
		)
		(stroke
			(width 0)
			(type solid)
		)
		(fill yes)
		(layer "In11.Cu")
		(net "M_M_DQ<18>")
	)
	(gr_poly
		(pts
			(xy 75.349862 -101.878638) (xy 75.305412 -101.878638) (xy 75.112372 -101.967538) (xy 75.112372 -102.196138)
			(xy 75.305412 -102.285038) (xy 75.349862 -102.285038)
		)
		(stroke
			(width 0)
			(type solid)
		)
		(fill yes)
		(layer "In11.Cu")
		(net "M_M_DQ<18>")
	)
	(gr_poly
		(pts
			(xy 75.395074 -90.306398) (xy 75.403202 -90.114628) (xy 75.21194 -90.004138) (xy 75.049888 -90.107008)
			(xy 75.027536 -90.145362) (xy 75.372976 -90.345006)
		)
		(stroke
			(width 0)
			(type solid)
		)
		(fill yes)
		(layer "In11.Cu")
		(net "M_M_DQS_DP<10>")
	)
	(gr_poly
		(pts
			(xy 75.400154 -57.619646) (xy 75.408282 -57.427876) (xy 75.21702 -57.317386) (xy 75.054968 -57.420256)
			(xy 75.032616 -57.45861) (xy 75.378056 -57.658)
		)
		(stroke
			(width 0)
			(type solid)
		)
		(fill yes)
		(layer "In11.Cu")
		(net "M_J_DQ<21>")
	)
	(gr_poly
		(pts
			(xy 75.40244 -89.320116) (xy 75.410568 -89.128346) (xy 75.219306 -89.017856) (xy 75.057254 -89.120726)
			(xy 75.034902 -89.15908) (xy 75.380342 -89.35847)
		)
		(stroke
			(width 0)
			(type solid)
		)
		(fill yes)
		(layer "In11.Cu")
		(net "M_M_DQ<8>")
	)
	(gr_poly
		(pts
			(xy 75.40244 -88.329516) (xy 75.410568 -88.137746) (xy 75.219306 -88.027256) (xy 75.057254 -88.130126)
			(xy 75.034902 -88.16848) (xy 75.380342 -88.36787)
		)
		(stroke
			(width 0)
			(type solid)
		)
		(fill yes)
		(layer "In11.Cu")
		(net "M_M_DQ<12>")
	)
	(gr_poly
		(pts
			(xy 75.40244 -85.357716) (xy 75.410568 -85.165946) (xy 75.219306 -85.055456) (xy 75.057254 -85.158326)
			(xy 75.034902 -85.19668) (xy 75.380342 -85.39607)
		)
		(stroke
			(width 0)
			(type solid)
		)
		(fill yes)
		(layer "In11.Cu")
		(net "M_M_DQS_DP<9>")
	)
	(gr_poly
		(pts
			(xy 75.40244 -84.367116) (xy 75.410568 -84.175346) (xy 75.219306 -84.064856) (xy 75.057254 -84.167726)
			(xy 75.034902 -84.20608) (xy 75.380342 -84.40547)
		)
		(stroke
			(width 0)
			(type solid)
		)
		(fill yes)
		(layer "In11.Cu")
		(net "M_M_DQ<0>")
	)
	(gr_poly
		(pts
			(xy 75.40244 -83.376516) (xy 75.410568 -83.184746) (xy 75.219306 -83.074256) (xy 75.057254 -83.177126)
			(xy 75.034902 -83.21548) (xy 75.380342 -83.41487)
		)
		(stroke
			(width 0)
			(type solid)
		)
		(fill yes)
		(layer "In11.Cu")
		(net "M_M_DQ<4>")
	)
	(gr_poly
		(pts
			(xy 75.40244 -55.639716) (xy 75.410568 -55.447946) (xy 75.219306 -55.337456) (xy 75.057254 -55.440326)
			(xy 75.034902 -55.47868) (xy 75.380342 -55.678324)
		)
		(stroke
			(width 0)
			(type solid)
		)
		(fill yes)
		(layer "In11.Cu")
		(net "M_J_DQS_DN<11>")
	)
	(gr_poly
		(pts
			(xy 75.40244 -54.649116) (xy 75.410568 -54.457346) (xy 75.219306 -54.346856) (xy 75.057254 -54.449726)
			(xy 75.034902 -54.48808) (xy 75.380342 -54.687724)
		)
		(stroke
			(width 0)
			(type solid)
		)
		(fill yes)
		(layer "In11.Cu")
		(net "M_J_DQS_DN<2>")
	)
	(gr_poly
		(pts
			(xy 75.40244 -53.658516) (xy 75.410568 -53.466746) (xy 75.219306 -53.356256) (xy 75.057254 -53.459126)
			(xy 75.034902 -53.49748) (xy 75.380342 -53.697124)
		)
		(stroke
			(width 0)
			(type solid)
		)
		(fill yes)
		(layer "In11.Cu")
		(net "M_J_DQ<23>")
	)
	(gr_poly
		(pts
			(xy 75.403964 -56.631078) (xy 75.412092 -56.439308) (xy 75.22083 -56.328818) (xy 75.058778 -56.431688)
			(xy 75.036426 -56.470042) (xy 75.381866 -56.669686)
		)
		(stroke
			(width 0)
			(type solid)
		)
		(fill yes)
		(layer "In11.Cu")
		(net "M_J_DQ<17>")
	)
	(gr_poly
		(pts
			(xy 75.403964 -52.668678) (xy 75.412092 -52.476908) (xy 75.22083 -52.366418) (xy 75.058778 -52.469288)
			(xy 75.036426 -52.507642) (xy 75.381866 -52.707032)
		)
		(stroke
			(width 0)
			(type solid)
		)
		(fill yes)
		(layer "In11.Cu")
		(net "M_J_DQ<19>")
	)
	(gr_poly
		(pts
			(xy 75.410568 -94.36608) (xy 75.40244 -94.17431) (xy 75.380342 -94.135702) (xy 75.034902 -94.335346)
			(xy 75.057254 -94.3737) (xy 75.219306 -94.47657)
		)
		(stroke
			(width 0)
			(type solid)
		)
		(fill yes)
		(layer "In11.Cu")
		(net "M_M_DQ<21>")
	)
	(gr_poly
		(pts
			(xy 75.412092 -98.327464) (xy 75.403964 -98.135694) (xy 75.381866 -98.097086) (xy 75.036426 -98.29673)
			(xy 75.058778 -98.335084) (xy 75.22083 -98.437954)
		)
		(stroke
			(width 0)
			(type solid)
		)
		(fill yes)
		(layer "In11.Cu")
		(net "M_M_DQ<23>")
	)
	(gr_poly
		(pts
			(xy 75.412092 -97.336864) (xy 75.403964 -97.145094) (xy 75.381866 -97.106486) (xy 75.036426 -97.30613)
			(xy 75.058778 -97.344484) (xy 75.22083 -97.447354)
		)
		(stroke
			(width 0)
			(type solid)
		)
		(fill yes)
		(layer "In11.Cu")
		(net "M_M_DQS_DP<2>")
	)
	(gr_poly
		(pts
			(xy 75.412092 -96.346264) (xy 75.403964 -96.154494) (xy 75.381866 -96.115886) (xy 75.036426 -96.31553)
			(xy 75.058778 -96.353884) (xy 75.22083 -96.456754)
		)
		(stroke
			(width 0)
			(type solid)
		)
		(fill yes)
		(layer "In11.Cu")
		(net "M_M_DQS_DN<11>")
	)
	(gr_poly
		(pts
			(xy 75.412092 -95.355664) (xy 75.403964 -95.163894) (xy 75.381866 -95.125286) (xy 75.036426 -95.32493)
			(xy 75.058778 -95.363284) (xy 75.22083 -95.466154)
		)
		(stroke
			(width 0)
			(type solid)
		)
		(fill yes)
		(layer "In11.Cu")
		(net "M_M_DQ<17>")
	)
	(gr_poly
		(pts
			(xy 75.412092 -68.609464) (xy 75.403964 -68.417694) (xy 75.381866 -68.37934) (xy 75.036426 -68.578476)
			(xy 75.058778 -68.617084) (xy 75.22083 -68.719954)
		)
		(stroke
			(width 0)
			(type solid)
		)
		(fill yes)
		(layer "In11.Cu")
		(net "M_J_DQ<4>")
	)
	(gr_poly
		(pts
			(xy 75.412092 -67.618864) (xy 75.403964 -67.427094) (xy 75.381866 -67.38874) (xy 75.036426 -67.587876)
			(xy 75.058778 -67.626484) (xy 75.22083 -67.729354)
		)
		(stroke
			(width 0)
			(type solid)
		)
		(fill yes)
		(layer "In11.Cu")
		(net "M_J_DQ<0>")
	)
	(gr_poly
		(pts
			(xy 75.412092 -65.637664) (xy 75.403964 -65.445894) (xy 75.381866 -65.407286) (xy 75.036426 -65.60693)
			(xy 75.058778 -65.645284) (xy 75.22083 -65.748154)
		)
		(stroke
			(width 0)
			(type solid)
		)
		(fill yes)
		(layer "In11.Cu")
		(net "M_J_DQS_DP<0>")
	)
	(gr_poly
		(pts
			(xy 75.412092 -62.665864) (xy 75.403964 -62.474094) (xy 75.381866 -62.435486) (xy 75.036426 -62.63513)
			(xy 75.058778 -62.673484) (xy 75.22083 -62.776354)
		)
		(stroke
			(width 0)
			(type solid)
		)
		(fill yes)
		(layer "In11.Cu")
		(net "M_J_DQ<13>")
	)
	(gr_poly
		(pts
			(xy 75.412092 -61.675264) (xy 75.403964 -61.483494) (xy 75.381866 -61.444886) (xy 75.036426 -61.64453)
			(xy 75.058778 -61.682884) (xy 75.22083 -61.785754)
		)
		(stroke
			(width 0)
			(type solid)
		)
		(fill yes)
		(layer "In11.Cu")
		(net "M_J_DQ<9>")
	)
	(gr_poly
		(pts
			(xy 75.412092 -60.684664) (xy 75.403964 -60.492894) (xy 75.381866 -60.454286) (xy 75.036426 -60.65393)
			(xy 75.058778 -60.692284) (xy 75.22083 -60.795154)
		)
		(stroke
			(width 0)
			(type solid)
		)
		(fill yes)
		(layer "In11.Cu")
		(net "M_J_DQS_DP<1>")
	)
	(gr_poly
		(pts
			(xy 75.43673 -103.90505) (xy 75.36307 -103.70566) (xy 75.331828 -103.674164) (xy 75.0443 -103.961438)
			(xy 75.075796 -103.992934) (xy 75.275186 -104.066594)
		)
		(stroke
			(width 0)
			(type solid)
		)
		(fill yes)
		(layer "In11.Cu")
		(net "M_M_DQ<19>")
	)
	(gr_poly
		(pts
			(xy 75.608434 -58.216038) (xy 75.630786 -58.177684) (xy 75.285346 -57.97804) (xy 75.263248 -58.016648)
			(xy 75.25512 -58.208418) (xy 75.446382 -58.318908)
		)
		(stroke
			(width 0)
			(type solid)
		)
		(fill yes)
		(layer "In11.Cu")
		(net "M_J_DQ<20>")
	)
	(gr_poly
		(pts
			(xy 75.609958 -88.9254) (xy 75.63231 -88.887046) (xy 75.28687 -88.687402) (xy 75.264772 -88.72601)
			(xy 75.256644 -88.91778) (xy 75.447906 -89.02827)
		)
		(stroke
			(width 0)
			(type solid)
		)
		(fill yes)
		(layer "In11.Cu")
		(net "M_M_DQ<13>")
	)
	(gr_poly
		(pts
			(xy 75.609958 -85.9536) (xy 75.63231 -85.915246) (xy 75.28687 -85.715602) (xy 75.264772 -85.75421)
			(xy 75.256644 -85.94598) (xy 75.447906 -86.05647)
		)
		(stroke
			(width 0)
			(type solid)
		)
		(fill yes)
		(layer "In11.Cu")
		(net "M_M_DQS_DN<9>")
	)
	(gr_poly
		(pts
			(xy 75.609958 -83.9724) (xy 75.63231 -83.934046) (xy 75.28687 -83.734402) (xy 75.264772 -83.77301)
			(xy 75.256644 -83.96478) (xy 75.447906 -84.07527)
		)
		(stroke
			(width 0)
			(type solid)
		)
		(fill yes)
		(layer "In11.Cu")
		(net "M_M_DQ<5>")
	)
	(gr_poly
		(pts
			(xy 75.609958 -57.2262) (xy 75.63231 -57.187592) (xy 75.28687 -56.988202) (xy 75.264772 -57.02681)
			(xy 75.256644 -57.21858) (xy 75.447906 -57.32907)
		)
		(stroke
			(width 0)
			(type solid)
		)
		(fill yes)
		(layer "In11.Cu")
		(net "M_J_DQ<16>")
	)
	(gr_poly
		(pts
			(xy 75.609958 -56.2356) (xy 75.63231 -56.197246) (xy 75.28687 -55.997602) (xy 75.264772 -56.03621)
			(xy 75.256644 -56.22798) (xy 75.447906 -56.33847)
		)
		(stroke
			(width 0)
			(type solid)
		)
		(fill yes)
		(layer "In11.Cu")
		(net "M_J_DQS_DP<11>")
	)
	(gr_poly
		(pts
			(xy 75.609958 -55.245) (xy 75.63231 -55.206392) (xy 75.28687 -55.007002) (xy 75.264772 -55.04561)
			(xy 75.256644 -55.23738) (xy 75.447906 -55.34787)
		)
		(stroke
			(width 0)
			(type solid)
		)
		(fill yes)
		(layer "In11.Cu")
		(net "M_J_DQS_DP<2>")
	)
	(gr_poly
		(pts
			(xy 75.609958 -54.2544) (xy 75.63231 -54.215792) (xy 75.28687 -54.016402) (xy 75.264772 -54.05501)
			(xy 75.256644 -54.24678) (xy 75.447906 -54.35727)
		)
		(stroke
			(width 0)
			(type solid)
		)
		(fill yes)
		(layer "In11.Cu")
		(net "M_J_DQ<22>")
	)
	(gr_poly
		(pts
			(xy 75.612244 -53.26507) (xy 75.634596 -53.226716) (xy 75.289156 -53.027072) (xy 75.267058 -53.06568)
			(xy 75.25893 -53.25745) (xy 75.450192 -53.36794)
		)
		(stroke
			(width 0)
			(type solid)
		)
		(fill yes)
		(layer "In11.Cu")
		(net "M_J_DQ<18>")
	)
	(gr_poly
		(pts
			(xy 75.630786 -98.570796) (xy 75.608434 -98.532442) (xy 75.446382 -98.429572) (xy 75.25512 -98.540062)
			(xy 75.262994 -98.731832) (xy 75.285092 -98.770186)
		)
		(stroke
			(width 0)
			(type solid)
		)
		(fill yes)
		(layer "In11.Cu")
		(net "M_M_DQ<18>")
	)
	(gr_poly
		(pts
			(xy 75.630786 -97.58045) (xy 75.608434 -97.541842) (xy 75.446382 -97.438972) (xy 75.25512 -97.549462)
			(xy 75.263248 -97.741232) (xy 75.285346 -97.77984)
		)
		(stroke
			(width 0)
			(type solid)
		)
		(fill yes)
		(layer "In11.Cu")
		(net "M_M_DQ<22>")
	)
	(gr_poly
		(pts
			(xy 75.630786 -96.58985) (xy 75.608434 -96.551242) (xy 75.446382 -96.448372) (xy 75.25512 -96.558862)
			(xy 75.263248 -96.750632) (xy 75.285346 -96.78924)
		)
		(stroke
			(width 0)
			(type solid)
		)
		(fill yes)
		(layer "In11.Cu")
		(net "M_M_DQS_DN<2>")
	)
	(gr_poly
		(pts
			(xy 75.630786 -95.59925) (xy 75.608434 -95.560642) (xy 75.446382 -95.457772) (xy 75.25512 -95.568262)
			(xy 75.263248 -95.760032) (xy 75.285346 -95.79864)
		)
		(stroke
			(width 0)
			(type solid)
		)
		(fill yes)
		(layer "In11.Cu")
		(net "M_M_DQS_DP<11>")
	)
	(gr_poly
		(pts
			(xy 75.630786 -92.62745) (xy 75.608434 -92.588842) (xy 75.446382 -92.485972) (xy 75.25512 -92.596462)
			(xy 75.263248 -92.788232) (xy 75.285346 -92.82684)
		)
		(stroke
			(width 0)
			(type solid)
		)
		(fill yes)
		(layer "In11.Cu")
		(net "M_M_DQ<10>")
	)
	(gr_poly
		(pts
			(xy 75.630786 -67.862196) (xy 75.608434 -67.823842) (xy 75.446382 -67.720972) (xy 75.25512 -67.831462)
			(xy 75.263248 -68.023232) (xy 75.285346 -68.06184)
		)
		(stroke
			(width 0)
			(type solid)
		)
		(fill yes)
		(layer "In11.Cu")
		(net "M_J_DQ<5>")
	)
	(gr_poly
		(pts
			(xy 75.630786 -64.890396) (xy 75.608434 -64.852042) (xy 75.446382 -64.749172) (xy 75.25512 -64.859662)
			(xy 75.263248 -65.051432) (xy 75.285346 -65.09004)
		)
		(stroke
			(width 0)
			(type solid)
		)
		(fill yes)
		(layer "In11.Cu")
		(net "M_J_DQS_DN<0>")
	)
	(gr_poly
		(pts
			(xy 75.630786 -62.909196) (xy 75.608434 -62.870842) (xy 75.446382 -62.767972) (xy 75.25512 -62.878462)
			(xy 75.263248 -63.070232) (xy 75.285346 -63.10884)
		)
		(stroke
			(width 0)
			(type solid)
		)
		(fill yes)
		(layer "In11.Cu")
		(net "M_J_DQ<12>")
	)
	(gr_poly
		(pts
			(xy 75.630786 -59.937396) (xy 75.608434 -59.899042) (xy 75.446382 -59.796172) (xy 75.25512 -59.906662)
			(xy 75.263248 -60.098432) (xy 75.285346 -60.13704)
		)
		(stroke
			(width 0)
			(type solid)
		)
		(fill yes)
		(layer "In11.Cu")
		(net "M_J_DQS_DN<1>")
	)
	(gr_poly
		(pts
			(xy 75.63231 -93.61678) (xy 75.609958 -93.578426) (xy 75.447906 -93.475556) (xy 75.256644 -93.586046)
			(xy 75.264772 -93.777816) (xy 75.28687 -93.81617)
		)
		(stroke
			(width 0)
			(type solid)
		)
		(fill yes)
		(layer "In11.Cu")
		(net "M_M_DQ<20>")
	)
	(gr_poly
		(pts
			(xy 75.634596 -94.60611) (xy 75.612244 -94.567756) (xy 75.450192 -94.464886) (xy 75.25893 -94.575376)
			(xy 75.267058 -94.767146) (xy 75.289156 -94.805754)
		)
		(stroke
			(width 0)
			(type solid)
		)
		(fill yes)
		(layer "In11.Cu")
		(net "M_M_DQ<16>")
	)
	(gr_poly
		(pts
			(xy 75.710034 -100.772976) (xy 75.710034 -100.551996) (xy 75.539854 -100.463096) (xy 75.495404 -100.463096)
			(xy 75.495404 -100.861876) (xy 75.539854 -100.861876)
		)
		(stroke
			(width 0)
			(type solid)
		)
		(fill yes)
		(layer "In11.Cu")
		(net "M_M_DQ<19>")
	)
	(gr_poly
		(pts
			(xy 75.710034 -99.77628) (xy 75.710034 -99.5553) (xy 75.539854 -99.4664) (xy 75.495404 -99.4664)
			(xy 75.495404 -99.86518) (xy 75.539854 -99.86518)
		)
		(stroke
			(width 0)
			(type solid)
		)
		(fill yes)
		(layer "In11.Cu")
		(net "M_M_DQ<19>")
	)
	(gr_poly
		(pts
			(xy 75.750674 -86.738714) (xy 75.750928 -86.694518) (xy 75.351894 -86.694264) (xy 75.352148 -86.738714)
			(xy 75.440794 -86.908894) (xy 75.661774 -86.908894)
		)
		(stroke
			(width 0)
			(type solid)
		)
		(fill yes)
		(layer "In11.Cu")
		(net "M_M_DQ<6>")
	)
	(gr_poly
		(pts
			(xy 75.777344 -103.059738) (xy 75.777344 -102.831138) (xy 75.584304 -102.742238) (xy 75.539854 -102.742238)
			(xy 75.539854 -103.148638) (xy 75.584304 -103.148638)
		)
		(stroke
			(width 0)
			(type solid)
		)
		(fill yes)
		(layer "In11.Cu")
		(net "M_M_DQ<19>")
	)
	(gr_poly
		(pts
			(xy 75.777344 -102.069138) (xy 75.777344 -101.840538) (xy 75.584304 -101.751638) (xy 75.539854 -101.751638)
			(xy 75.539854 -102.158038) (xy 75.584304 -102.158038)
		)
		(stroke
			(width 0)
			(type solid)
		)
		(fill yes)
		(layer "In11.Cu")
		(net "M_M_DQ<19>")
	)
	(gr_poly
		(pts
			(xy 76.17079 -62.998858) (xy 76.162662 -62.807088) (xy 76.140564 -62.76848) (xy 75.795124 -62.968124)
			(xy 75.817476 -63.006478) (xy 75.979528 -63.109348)
		)
		(stroke
			(width 0)
			(type solid)
		)
		(fill yes)
		(layer "In11.Cu")
		(net "M_J_DQ<12>")
	)
	(gr_poly
		(pts
			(xy 76.26096 -58.116216) (xy 76.269088 -57.924446) (xy 76.077826 -57.813956) (xy 75.915774 -57.916826)
			(xy 75.893422 -57.95518) (xy 76.238862 -58.154824)
		)
		(stroke
			(width 0)
			(type solid)
		)
		(fill yes)
		(layer "In11.Cu")
		(net "M_J_DQ<21>")
	)
	(gr_poly
		(pts
			(xy 76.262484 -90.807032) (xy 76.270612 -90.615262) (xy 76.07935 -90.504772) (xy 75.917298 -90.607642)
			(xy 75.894946 -90.64625) (xy 76.240386 -90.84564)
		)
		(stroke
			(width 0)
			(type solid)
		)
		(fill yes)
		(layer "In11.Cu")
		(net "M_M_DQS_DP<10>")
	)
	(gr_poly
		(pts
			(xy 76.262484 -89.816432) (xy 76.270612 -89.624662) (xy 76.07935 -89.514172) (xy 75.917298 -89.617042)
			(xy 75.894946 -89.65565) (xy 76.240386 -89.85504)
		)
		(stroke
			(width 0)
			(type solid)
		)
		(fill yes)
		(layer "In11.Cu")
		(net "M_M_DQ<8>")
	)
	(gr_poly
		(pts
			(xy 76.262484 -88.825832) (xy 76.270612 -88.634062) (xy 76.07935 -88.523572) (xy 75.917298 -88.626442)
			(xy 75.894946 -88.66505) (xy 76.240386 -88.86444)
		)
		(stroke
			(width 0)
			(type solid)
		)
		(fill yes)
		(layer "In11.Cu")
		(net "M_M_DQ<12>")
	)
	(gr_poly
		(pts
			(xy 76.262484 -86.844632) (xy 76.270612 -86.652862) (xy 76.07935 -86.542372) (xy 75.917298 -86.645242)
			(xy 75.894946 -86.68385) (xy 76.240386 -86.88324)
		)
		(stroke
			(width 0)
			(type solid)
		)
		(fill yes)
		(layer "In11.Cu")
		(net "M_M_DQ<6>")
	)
	(gr_poly
		(pts
			(xy 76.262484 -85.854032) (xy 76.270612 -85.662262) (xy 76.07935 -85.551772) (xy 75.917298 -85.654642)
			(xy 75.894946 -85.69325) (xy 76.240386 -85.89264)
		)
		(stroke
			(width 0)
			(type solid)
		)
		(fill yes)
		(layer "In11.Cu")
		(net "M_M_DQS_DP<9>")
	)
	(gr_poly
		(pts
			(xy 76.262484 -84.863432) (xy 76.270612 -84.671662) (xy 76.07935 -84.561172) (xy 75.917298 -84.664042)
			(xy 75.894946 -84.70265) (xy 76.240386 -84.90204)
		)
		(stroke
			(width 0)
			(type solid)
		)
		(fill yes)
		(layer "In11.Cu")
		(net "M_M_DQ<0>")
	)
	(gr_poly
		(pts
			(xy 76.262484 -83.872832) (xy 76.270612 -83.681062) (xy 76.07935 -83.570572) (xy 75.917298 -83.673442)
			(xy 75.894946 -83.71205) (xy 76.240386 -83.91144)
		)
		(stroke
			(width 0)
			(type solid)
		)
		(fill yes)
		(layer "In11.Cu")
		(net "M_M_DQ<4>")
	)
	(gr_poly
		(pts
			(xy 76.262484 -57.126632) (xy 76.270612 -56.934862) (xy 76.07935 -56.824372) (xy 75.917298 -56.927242)
			(xy 75.894946 -56.965596) (xy 76.240386 -57.16524)
		)
		(stroke
			(width 0)
			(type solid)
		)
		(fill yes)
		(layer "In11.Cu")
		(net "M_J_DQ<17>")
	)
	(gr_poly
		(pts
			(xy 76.262484 -56.136032) (xy 76.270612 -55.944262) (xy 76.07935 -55.833772) (xy 75.917298 -55.936642)
			(xy 75.894946 -55.974996) (xy 76.240386 -56.17464)
		)
		(stroke
			(width 0)
			(type solid)
		)
		(fill yes)
		(layer "In11.Cu")
		(net "M_J_DQS_DN<11>")
	)
	(gr_poly
		(pts
			(xy 76.262484 -55.145432) (xy 76.270612 -54.953662) (xy 76.07935 -54.843172) (xy 75.917298 -54.946042)
			(xy 75.894946 -54.984396) (xy 76.240386 -55.18404)
		)
		(stroke
			(width 0)
			(type solid)
		)
		(fill yes)
		(layer "In11.Cu")
		(net "M_J_DQS_DN<2>")
	)
	(gr_poly
		(pts
			(xy 76.262484 -54.154832) (xy 76.270612 -53.963062) (xy 76.07935 -53.852572) (xy 75.917298 -53.955442)
			(xy 75.894946 -53.993796) (xy 76.240386 -54.19344)
		)
		(stroke
			(width 0)
			(type solid)
		)
		(fill yes)
		(layer "In11.Cu")
		(net "M_J_DQ<23>")
	)
	(gr_poly
		(pts
			(xy 76.262484 -53.164232) (xy 76.270612 -52.972462) (xy 76.07935 -52.861972) (xy 75.917298 -52.964842)
			(xy 75.894946 -53.003196) (xy 76.240386 -53.202586)
		)
		(stroke
			(width 0)
			(type solid)
		)
		(fill yes)
		(layer "In11.Cu")
		(net "M_J_DQ<19>")
	)
	(gr_poly
		(pts
			(xy 76.266802 -94.86265) (xy 76.258674 -94.67088) (xy 76.236576 -94.632272) (xy 75.891136 -94.831662)
			(xy 75.913488 -94.87027) (xy 76.07554 -94.97314)
		)
		(stroke
			(width 0)
			(type solid)
		)
		(fill yes)
		(layer "In11.Cu")
		(net "M_M_DQ<17>")
	)
	(gr_poly
		(pts
			(xy 76.269088 -98.82378) (xy 76.26096 -98.63201) (xy 76.238862 -98.593402) (xy 75.893422 -98.793046)
			(xy 75.915774 -98.8314) (xy 76.077826 -98.93427)
		)
		(stroke
			(width 0)
			(type solid)
		)
		(fill yes)
		(layer "In11.Cu")
		(net "M_M_DQ<19>")
	)
	(gr_poly
		(pts
			(xy 76.269088 -97.83318) (xy 76.26096 -97.64141) (xy 76.238862 -97.602802) (xy 75.893422 -97.802446)
			(xy 75.915774 -97.8408) (xy 76.077826 -97.94367)
		)
		(stroke
			(width 0)
			(type solid)
		)
		(fill yes)
		(layer "In11.Cu")
		(net "M_M_DQ<23>")
	)
	(gr_poly
		(pts
			(xy 76.269088 -96.84258) (xy 76.26096 -96.65081) (xy 76.238862 -96.612202) (xy 75.893422 -96.811846)
			(xy 75.915774 -96.8502) (xy 76.077826 -96.95307)
		)
		(stroke
			(width 0)
			(type solid)
		)
		(fill yes)
		(layer "In11.Cu")
		(net "M_M_DQS_DP<2>")
	)
	(gr_poly
		(pts
			(xy 76.269088 -95.85198) (xy 76.26096 -95.66021) (xy 76.238862 -95.621602) (xy 75.893422 -95.821246)
			(xy 75.915774 -95.8596) (xy 76.077826 -95.96247)
		)
		(stroke
			(width 0)
			(type solid)
		)
		(fill yes)
		(layer "In11.Cu")
		(net "M_M_DQS_DN<11>")
	)
	(gr_poly
		(pts
			(xy 76.269088 -65.14338) (xy 76.26096 -64.95161) (xy 76.238862 -64.913002) (xy 75.893422 -65.112392)
			(xy 75.915774 -65.151) (xy 76.077826 -65.25387)
		)
		(stroke
			(width 0)
			(type solid)
		)
		(fill yes)
		(layer "In11.Cu")
		(net "M_J_DQS_DP<0>")
	)
	(gr_poly
		(pts
			(xy 76.269088 -62.17158) (xy 76.26096 -61.97981) (xy 76.238862 -61.941202) (xy 75.893422 -62.140592)
			(xy 75.915774 -62.1792) (xy 76.077826 -62.28207)
		)
		(stroke
			(width 0)
			(type solid)
		)
		(fill yes)
		(layer "In11.Cu")
		(net "M_J_DQ<13>")
	)
	(gr_poly
		(pts
			(xy 76.269088 -60.19038) (xy 76.26096 -59.99861) (xy 76.238862 -59.960002) (xy 75.893422 -60.159392)
			(xy 75.915774 -60.198) (xy 76.077826 -60.30087)
		)
		(stroke
			(width 0)
			(type solid)
		)
		(fill yes)
		(layer "In11.Cu")
		(net "M_J_DQS_DP<1>")
	)
	(gr_poly
		(pts
			(xy 76.270612 -93.870018) (xy 76.262484 -93.678248) (xy 76.240386 -93.639894) (xy 75.894946 -93.83903)
			(xy 75.917298 -93.877638) (xy 76.07935 -93.980508)
		)
		(stroke
			(width 0)
			(type solid)
		)
		(fill yes)
		(layer "In11.Cu")
		(net "M_M_DQ<21>")
	)
	(gr_poly
		(pts
			(xy 76.466954 -91.400884) (xy 76.489306 -91.36253) (xy 76.143866 -91.162886) (xy 76.121768 -91.201494)
			(xy 76.11364 -91.393264) (xy 76.304902 -91.503754)
		)
		(stroke
			(width 0)
			(type solid)
		)
		(fill yes)
		(layer "In11.Cu")
		(net "M_M_DQS_DN<10>")
	)
	(gr_poly
		(pts
			(xy 76.466954 -86.447884) (xy 76.489306 -86.40953) (xy 76.143866 -86.209886) (xy 76.121768 -86.248494)
			(xy 76.11364 -86.440264) (xy 76.304902 -86.550754)
		)
		(stroke
			(width 0)
			(type solid)
		)
		(fill yes)
		(layer "In11.Cu")
		(net "M_M_DQS_DN<9>")
	)
	(gr_poly
		(pts
			(xy 76.466954 -55.739284) (xy 76.489306 -55.70093) (xy 76.143866 -55.501286) (xy 76.121768 -55.539894)
			(xy 76.11364 -55.731664) (xy 76.304902 -55.842154)
		)
		(stroke
			(width 0)
			(type solid)
		)
		(fill yes)
		(layer "In11.Cu")
		(net "M_J_DQS_DP<2>")
	)
	(gr_poly
		(pts
			(xy 76.466954 -54.748684) (xy 76.489306 -54.71033) (xy 76.143866 -54.510686) (xy 76.121768 -54.549294)
			(xy 76.11364 -54.741064) (xy 76.304902 -54.851554)
		)
		(stroke
			(width 0)
			(type solid)
		)
		(fill yes)
		(layer "In11.Cu")
		(net "M_J_DQ<22>")
	)
	(gr_poly
		(pts
			(xy 76.468478 -58.7121) (xy 76.49083 -58.673492) (xy 76.14539 -58.474102) (xy 76.123292 -58.51271)
			(xy 76.115164 -58.70448) (xy 76.306426 -58.81497)
		)
		(stroke
			(width 0)
			(type solid)
		)
		(fill yes)
		(layer "In11.Cu")
		(net "M_J_DQ<20>")
	)
	(gr_poly
		(pts
			(xy 76.468478 -56.730646) (xy 76.49083 -56.692292) (xy 76.14539 -56.492648) (xy 76.123292 -56.531256)
			(xy 76.115164 -56.723026) (xy 76.306426 -56.833516)
		)
		(stroke
			(width 0)
			(type solid)
		)
		(fill yes)
		(layer "In11.Cu")
		(net "M_J_DQS_DP<11>")
	)
	(gr_poly
		(pts
			(xy 76.468478 -53.758846) (xy 76.49083 -53.720238) (xy 76.14539 -53.520848) (xy 76.123292 -53.559456)
			(xy 76.115164 -53.751226) (xy 76.306426 -53.861716)
		)
		(stroke
			(width 0)
			(type solid)
		)
		(fill yes)
		(layer "In11.Cu")
		(net "M_J_DQ<18>")
	)
	(gr_poly
		(pts
			(xy 76.470764 -57.72277) (xy 76.493116 -57.684416) (xy 76.147676 -57.484772) (xy 76.125578 -57.52338)
			(xy 76.11745 -57.71515) (xy 76.308712 -57.82564)
		)
		(stroke
			(width 0)
			(type solid)
		)
		(fill yes)
		(layer "In11.Cu")
		(net "M_J_DQ<16>")
	)
	(gr_poly
		(pts
			(xy 76.489306 -94.112842) (xy 76.466954 -94.074488) (xy 76.304902 -93.971618) (xy 76.11364 -94.082108)
			(xy 76.121768 -94.273878) (xy 76.143866 -94.312486)
		)
		(stroke
			(width 0)
			(type solid)
		)
		(fill yes)
		(layer "In11.Cu")
		(net "M_M_DQ<16>")
	)
	(gr_poly
		(pts
			(xy 76.49083 -98.07448) (xy 76.468478 -98.036126) (xy 76.306426 -97.933256) (xy 76.115164 -98.043746)
			(xy 76.123292 -98.235516) (xy 76.14539 -98.27387)
		)
		(stroke
			(width 0)
			(type solid)
		)
		(fill yes)
		(layer "In11.Cu")
		(net "M_M_DQ<18>")
	)
	(gr_poly
		(pts
			(xy 76.49083 -97.08388) (xy 76.468478 -97.045526) (xy 76.306426 -96.942656) (xy 76.115164 -97.053146)
			(xy 76.123292 -97.244916) (xy 76.14539 -97.28327)
		)
		(stroke
			(width 0)
			(type solid)
		)
		(fill yes)
		(layer "In11.Cu")
		(net "M_M_DQ<22>")
	)
	(gr_poly
		(pts
			(xy 76.49083 -96.09328) (xy 76.468478 -96.054926) (xy 76.306426 -95.952056) (xy 76.115164 -96.062546)
			(xy 76.123292 -96.254316) (xy 76.14539 -96.29267)
		)
		(stroke
			(width 0)
			(type solid)
		)
		(fill yes)
		(layer "In11.Cu")
		(net "M_M_DQS_DN<2>")
	)
	(gr_poly
		(pts
			(xy 76.49083 -95.10268) (xy 76.468478 -95.064326) (xy 76.306426 -94.961456) (xy 76.115164 -95.071946)
			(xy 76.123292 -95.263716) (xy 76.14539 -95.30207)
		)
		(stroke
			(width 0)
			(type solid)
		)
		(fill yes)
		(layer "In11.Cu")
		(net "M_M_DQS_DP<11>")
	)
	(gr_poly
		(pts
			(xy 76.49083 -59.44108) (xy 76.468478 -59.402726) (xy 76.306426 -59.299856) (xy 76.115164 -59.410346)
			(xy 76.123292 -59.602116) (xy 76.14539 -59.640724)
		)
		(stroke
			(width 0)
			(type solid)
		)
		(fill yes)
		(layer "In11.Cu")
		(net "M_J_DQS_DN<1>")
	)
	(gr_poly
		(pts
			(xy 76.493116 -93.12021) (xy 76.470764 -93.081856) (xy 76.308712 -92.978986) (xy 76.11745 -93.089476)
			(xy 76.125578 -93.281246) (xy 76.147676 -93.319854)
		)
		(stroke
			(width 0)
			(type solid)
		)
		(fill yes)
		(layer "In11.Cu")
		(net "M_M_DQ<20>")
	)
	(gr_poly
		(pts
			(xy 77.102208 -86.342982) (xy 77.110082 -86.151212) (xy 76.91882 -86.040722) (xy 76.756768 -86.143592)
			(xy 76.73467 -86.181946) (xy 77.08011 -86.38159)
		)
		(stroke
			(width 0)
			(type solid)
		)
		(fill yes)
		(layer "In11.Cu")
		(net "M_M_DQS_DP<9>")
	)
	(gr_poly
		(pts
			(xy 77.109574 -91.304364) (xy 77.125576 -91.113102) (xy 76.938886 -90.994992) (xy 76.77277 -91.091258)
			(xy 76.748894 -91.128596) (xy 77.085952 -91.341956)
		)
		(stroke
			(width 0)
			(type solid)
		)
		(fill yes)
		(layer "In11.Cu")
		(net "M_M_DQS_DP<10>")
	)
	(gr_poly
		(pts
			(xy 77.117194 -57.619646) (xy 77.125322 -57.427876) (xy 76.93406 -57.317386) (xy 76.772008 -57.420256)
			(xy 76.749656 -57.45861) (xy 77.095096 -57.658)
		)
		(stroke
			(width 0)
			(type solid)
		)
		(fill yes)
		(layer "In11.Cu")
		(net "M_J_DQ<17>")
	)
	(gr_poly
		(pts
			(xy 77.11948 -89.320116) (xy 77.127608 -89.128346) (xy 76.936346 -89.017856) (xy 76.774294 -89.120726)
			(xy 76.751942 -89.15908) (xy 77.097382 -89.35847)
		)
		(stroke
			(width 0)
			(type solid)
		)
		(fill yes)
		(layer "In11.Cu")
		(net "M_M_DQ<12>")
	)
	(gr_poly
		(pts
			(xy 77.11948 -84.367116) (xy 77.127608 -84.175346) (xy 76.936346 -84.064856) (xy 76.774294 -84.167726)
			(xy 76.751942 -84.20608) (xy 77.097382 -84.40547)
		)
		(stroke
			(width 0)
			(type solid)
		)
		(fill yes)
		(layer "In11.Cu")
		(net "M_M_DQ<4>")
	)
	(gr_poly
		(pts
			(xy 77.11948 -55.639716) (xy 77.127608 -55.447946) (xy 76.936346 -55.337456) (xy 76.774294 -55.440326)
			(xy 76.751942 -55.47868) (xy 77.097382 -55.678324)
		)
		(stroke
			(width 0)
			(type solid)
		)
		(fill yes)
		(layer "In11.Cu")
		(net "M_J_DQS_DN<2>")
	)
	(gr_poly
		(pts
			(xy 77.11948 -54.649116) (xy 77.127608 -54.457346) (xy 76.936346 -54.346856) (xy 76.774294 -54.449726)
			(xy 76.751942 -54.48808) (xy 77.097382 -54.687724)
		)
		(stroke
			(width 0)
			(type solid)
		)
		(fill yes)
		(layer "In11.Cu")
		(net "M_J_DQ<23>")
	)
	(gr_poly
		(pts
			(xy 77.11948 -53.658516) (xy 77.127608 -53.466746) (xy 76.936346 -53.356256) (xy 76.774294 -53.459126)
			(xy 76.751942 -53.49748) (xy 77.097382 -53.697124)
		)
		(stroke
			(width 0)
			(type solid)
		)
		(fill yes)
		(layer "In11.Cu")
		(net "M_J_DQ<19>")
	)
	(gr_poly
		(pts
			(xy 77.121004 -58.612278) (xy 77.129132 -58.420508) (xy 76.93787 -58.310018) (xy 76.775818 -58.412888)
			(xy 76.753466 -58.451242) (xy 77.098906 -58.650632)
		)
		(stroke
			(width 0)
			(type solid)
		)
		(fill yes)
		(layer "In11.Cu")
		(net "M_J_DQ<21>")
	)
	(gr_poly
		(pts
			(xy 77.121004 -56.631078) (xy 77.129132 -56.439308) (xy 76.93787 -56.328818) (xy 76.775818 -56.431688)
			(xy 76.753466 -56.470042) (xy 77.098906 -56.669686)
		)
		(stroke
			(width 0)
			(type solid)
		)
		(fill yes)
		(layer "In11.Cu")
		(net "M_J_DQS_DN<11>")
	)
	(gr_poly
		(pts
			(xy 77.125322 -93.37675) (xy 77.117194 -93.18498) (xy 77.095096 -93.146372) (xy 76.749656 -93.345762)
			(xy 76.772008 -93.38437) (xy 76.93406 -93.48724)
		)
		(stroke
			(width 0)
			(type solid)
		)
		(fill yes)
		(layer "In11.Cu")
		(net "M_M_DQ<21>")
	)
	(gr_poly
		(pts
			(xy 77.127608 -94.36608) (xy 77.11948 -94.17431) (xy 77.097382 -94.135702) (xy 76.751942 -94.335346)
			(xy 76.774294 -94.3737) (xy 76.936346 -94.47657)
		)
		(stroke
			(width 0)
			(type solid)
		)
		(fill yes)
		(layer "In11.Cu")
		(net "M_M_DQ<17>")
	)
	(gr_poly
		(pts
			(xy 77.129132 -98.327464) (xy 77.121004 -98.135694) (xy 77.098906 -98.097086) (xy 76.753466 -98.29673)
			(xy 76.775818 -98.335084) (xy 76.93787 -98.437954)
		)
		(stroke
			(width 0)
			(type solid)
		)
		(fill yes)
		(layer "In11.Cu")
		(net "M_M_DQ<19>")
	)
	(gr_poly
		(pts
			(xy 77.129132 -97.336864) (xy 77.121004 -97.145094) (xy 77.098906 -97.106486) (xy 76.753466 -97.30613)
			(xy 76.775818 -97.344484) (xy 76.93787 -97.447354)
		)
		(stroke
			(width 0)
			(type solid)
		)
		(fill yes)
		(layer "In11.Cu")
		(net "M_M_DQ<23>")
	)
	(gr_poly
		(pts
			(xy 77.129132 -96.346264) (xy 77.121004 -96.154494) (xy 77.098906 -96.115886) (xy 76.753466 -96.31553)
			(xy 76.775818 -96.353884) (xy 76.93787 -96.456754)
		)
		(stroke
			(width 0)
			(type solid)
		)
		(fill yes)
		(layer "In11.Cu")
		(net "M_M_DQS_DP<2>")
	)
	(gr_poly
		(pts
			(xy 77.129132 -95.355664) (xy 77.121004 -95.163894) (xy 77.098906 -95.125286) (xy 76.753466 -95.32493)
			(xy 76.775818 -95.363284) (xy 76.93787 -95.466154)
		)
		(stroke
			(width 0)
			(type solid)
		)
		(fill yes)
		(layer "In11.Cu")
		(net "M_M_DQS_DN<11>")
	)
	(gr_poly
		(pts
			(xy 77.325474 -58.216038) (xy 77.347826 -58.177684) (xy 77.002386 -57.97804) (xy 76.980288 -58.016648)
			(xy 76.97216 -58.208418) (xy 77.163422 -58.318908)
		)
		(stroke
			(width 0)
			(type solid)
		)
		(fill yes)
		(layer "In11.Cu")
		(net "M_J_DQ<16>")
	)
	(gr_poly
		(pts
			(xy 77.325474 -56.234838) (xy 77.347826 -56.196484) (xy 77.002386 -55.99684) (xy 76.980288 -56.035448)
			(xy 76.97216 -56.227218) (xy 77.163422 -56.337708)
		)
		(stroke
			(width 0)
			(type solid)
		)
		(fill yes)
		(layer "In11.Cu")
		(net "M_J_DQS_DP<2>")
	)
	(gr_poly
		(pts
			(xy 77.326998 -57.2262) (xy 77.34935 -57.187846) (xy 77.00391 -56.988202) (xy 76.981812 -57.02681)
			(xy 76.973684 -57.21858) (xy 77.164946 -57.32907)
		)
		(stroke
			(width 0)
			(type solid)
		)
		(fill yes)
		(layer "In11.Cu")
		(net "M_J_DQS_DP<11>")
	)
	(gr_poly
		(pts
			(xy 77.326998 -55.245) (xy 77.34935 -55.206392) (xy 77.00391 -55.007002) (xy 76.981812 -55.04561)
			(xy 76.973684 -55.23738) (xy 77.164946 -55.34787)
		)
		(stroke
			(width 0)
			(type solid)
		)
		(fill yes)
		(layer "In11.Cu")
		(net "M_J_DQ<22>")
	)
	(gr_poly
		(pts
			(xy 77.326998 -54.254654) (xy 77.34935 -54.2163) (xy 77.00391 -54.016656) (xy 76.981812 -54.055264)
			(xy 76.973684 -54.247034) (xy 77.164946 -54.357524)
		)
		(stroke
			(width 0)
			(type solid)
		)
		(fill yes)
		(layer "In11.Cu")
		(net "M_J_DQ<18>")
	)
	(gr_poly
		(pts
			(xy 77.329284 -59.20867) (xy 77.351636 -59.170316) (xy 77.006196 -58.970672) (xy 76.984098 -59.00928)
			(xy 76.97597 -59.20105) (xy 77.167232 -59.31154)
		)
		(stroke
			(width 0)
			(type solid)
		)
		(fill yes)
		(layer "In11.Cu")
		(net "M_J_DQ<20>")
	)
	(gr_poly
		(pts
			(xy 77.347826 -97.58045) (xy 77.325474 -97.541842) (xy 77.163422 -97.438972) (xy 76.97216 -97.549462)
			(xy 76.980288 -97.741232) (xy 77.002386 -97.77984)
		)
		(stroke
			(width 0)
			(type solid)
		)
		(fill yes)
		(layer "In11.Cu")
		(net "M_M_DQ<18>")
	)
	(gr_poly
		(pts
			(xy 77.347826 -96.58985) (xy 77.325474 -96.551242) (xy 77.163422 -96.448372) (xy 76.97216 -96.558862)
			(xy 76.980288 -96.750632) (xy 77.002386 -96.78924)
		)
		(stroke
			(width 0)
			(type solid)
		)
		(fill yes)
		(layer "In11.Cu")
		(net "M_M_DQ<22>")
	)
	(gr_poly
		(pts
			(xy 77.347826 -95.59925) (xy 77.325474 -95.560642) (xy 77.163422 -95.457772) (xy 76.97216 -95.568262)
			(xy 76.980288 -95.760032) (xy 77.002386 -95.79864)
		)
		(stroke
			(width 0)
			(type solid)
		)
		(fill yes)
		(layer "In11.Cu")
		(net "M_M_DQS_DN<2>")
	)
	(gr_poly
		(pts
			(xy 77.347826 -92.62745) (xy 77.325474 -92.588842) (xy 77.163422 -92.485972) (xy 76.97216 -92.596462)
			(xy 76.980288 -92.788232) (xy 77.002386 -92.82684)
		)
		(stroke
			(width 0)
			(type solid)
		)
		(fill yes)
		(layer "In11.Cu")
		(net "M_M_DQ<20>")
	)
	(gr_poly
		(pts
			(xy 77.34935 -93.61678) (xy 77.326998 -93.578426) (xy 77.164946 -93.475556) (xy 76.973684 -93.586046)
			(xy 76.981812 -93.777816) (xy 77.00391 -93.81617)
		)
		(stroke
			(width 0)
			(type solid)
		)
		(fill yes)
		(layer "In11.Cu")
		(net "M_M_DQ<16>")
	)
	(gr_poly
		(pts
			(xy 77.351636 -94.60611) (xy 77.329284 -94.567756) (xy 77.167232 -94.464886) (xy 76.97597 -94.575376)
			(xy 76.984098 -94.767146) (xy 77.006196 -94.805754)
		)
		(stroke
			(width 0)
			(type solid)
		)
		(fill yes)
		(layer "In11.Cu")
		(net "M_M_DQS_DP<11>")
	)
	(gr_poly
		(pts
			(xy 77.532992 -101.759258) (xy 77.488542 -101.759258) (xy 77.295502 -101.848158) (xy 77.295502 -102.076758)
			(xy 77.488542 -102.165658) (xy 77.532992 -102.165658)
		)
		(stroke
			(width 0)
			(type solid)
		)
		(fill yes)
		(layer "In11.Cu")
		(net "M_M_DQ<28>")
	)
	(gr_poly
		(pts
			(xy 77.960474 -102.076758) (xy 77.960474 -101.848158) (xy 77.767434 -101.759258) (xy 77.722984 -101.759258)
			(xy 77.722984 -102.165658) (xy 77.767434 -102.165658)
		)
		(stroke
			(width 0)
			(type solid)
		)
		(fill yes)
		(layer "In11.Cu")
		(net "M_M_DQ<29>")
	)
	(gr_poly
		(pts
			(xy 77.97038 -100.663248) (xy 77.938884 -100.631752) (xy 77.739494 -100.558092) (xy 77.57795 -100.71989)
			(xy 77.65161 -100.919026) (xy 77.683106 -100.950522)
		)
		(stroke
			(width 0)
			(type solid)
		)
		(fill yes)
		(layer "In11.Cu")
		(net "M_M_DQ<28>")
	)
	(gr_poly
		(pts
			(xy 77.977746 -59.106562) (xy 77.985874 -58.914792) (xy 77.794612 -58.804302) (xy 77.63256 -58.907172)
			(xy 77.610208 -58.945526) (xy 77.955648 -59.144916)
		)
		(stroke
			(width 0)
			(type solid)
		)
		(fill yes)
		(layer "In11.Cu")
		(net "M_J_DQ<21>")
	)
	(gr_poly
		(pts
			(xy 77.978 -56.13527) (xy 77.986128 -55.9435) (xy 77.794866 -55.83301) (xy 77.632814 -55.93588) (xy 77.610462 -55.974234)
			(xy 77.955902 -56.173878)
		)
		(stroke
			(width 0)
			(type solid)
		)
		(fill yes)
		(layer "In11.Cu")
		(net "M_J_DQS_DN<2>")
	)
	(gr_poly
		(pts
			(xy 77.978 -55.14467) (xy 77.986128 -54.9529) (xy 77.794866 -54.84241) (xy 77.632814 -54.94528) (xy 77.610462 -54.983634)
			(xy 77.955902 -55.183278)
		)
		(stroke
			(width 0)
			(type solid)
		)
		(fill yes)
		(layer "In11.Cu")
		(net "M_J_DQ<23>")
	)
	(gr_poly
		(pts
			(xy 77.979524 -58.116978) (xy 77.987652 -57.925208) (xy 77.79639 -57.814718) (xy 77.634338 -57.917588)
			(xy 77.611986 -57.955942) (xy 77.957426 -58.155332)
		)
		(stroke
			(width 0)
			(type solid)
		)
		(fill yes)
		(layer "In11.Cu")
		(net "M_J_DQ<17>")
	)
	(gr_poly
		(pts
			(xy 77.979524 -57.126632) (xy 77.987652 -56.934862) (xy 77.79639 -56.824372) (xy 77.634338 -56.927242)
			(xy 77.611986 -56.965596) (xy 77.957426 -57.16524)
		)
		(stroke
			(width 0)
			(type solid)
		)
		(fill yes)
		(layer "In11.Cu")
		(net "M_J_DQS_DN<11>")
	)
	(gr_poly
		(pts
			(xy 77.979524 -54.154832) (xy 77.987652 -53.963062) (xy 77.79639 -53.852572) (xy 77.634338 -53.955442)
			(xy 77.611986 -53.993796) (xy 77.957426 -54.193186)
		)
		(stroke
			(width 0)
			(type solid)
		)
		(fill yes)
		(layer "In11.Cu")
		(net "M_J_DQ<19>")
	)
	(gr_poly
		(pts
			(xy 77.983842 -94.86265) (xy 77.975714 -94.67088) (xy 77.953616 -94.632272) (xy 77.608176 -94.831662)
			(xy 77.630528 -94.87027) (xy 77.79258 -94.97314)
		)
		(stroke
			(width 0)
			(type solid)
		)
		(fill yes)
		(layer "In11.Cu")
		(net "M_M_DQS_DN<11>")
	)
	(gr_poly
		(pts
			(xy 77.986128 -97.83318) (xy 77.978 -97.64141) (xy 77.955902 -97.602802) (xy 77.610462 -97.802446)
			(xy 77.632814 -97.8408) (xy 77.794866 -97.94367)
		)
		(stroke
			(width 0)
			(type solid)
		)
		(fill yes)
		(layer "In11.Cu")
		(net "M_M_DQ<19>")
	)
	(gr_poly
		(pts
			(xy 77.986128 -96.84258) (xy 77.978 -96.65081) (xy 77.955902 -96.612202) (xy 77.610462 -96.811846)
			(xy 77.632814 -96.8502) (xy 77.794866 -96.95307)
		)
		(stroke
			(width 0)
			(type solid)
		)
		(fill yes)
		(layer "In11.Cu")
		(net "M_M_DQ<23>")
	)
	(gr_poly
		(pts
			(xy 77.986128 -95.85198) (xy 77.978 -95.66021) (xy 77.955902 -95.621602) (xy 77.610462 -95.821246)
			(xy 77.632814 -95.8596) (xy 77.794866 -95.96247)
		)
		(stroke
			(width 0)
			(type solid)
		)
		(fill yes)
		(layer "In11.Cu")
		(net "M_M_DQS_DP<2>")
	)
	(gr_poly
		(pts
			(xy 77.986128 -92.88018) (xy 77.978 -92.68841) (xy 77.955902 -92.649802) (xy 77.610462 -92.849446)
			(xy 77.632814 -92.8878) (xy 77.794866 -92.99067)
		)
		(stroke
			(width 0)
			(type solid)
		)
		(fill yes)
		(layer "In11.Cu")
		(net "M_M_DQ<21>")
	)
	(gr_poly
		(pts
			(xy 77.987652 -93.870018) (xy 77.979524 -93.678248) (xy 77.957426 -93.639894) (xy 77.611986 -93.83903)
			(xy 77.634338 -93.877638) (xy 77.79639 -93.980508)
		)
		(stroke
			(width 0)
			(type solid)
		)
		(fill yes)
		(layer "In11.Cu")
		(net "M_M_DQ<17>")
	)
	(gr_poly
		(pts
			(xy 78.016354 -52.348384) (xy 78.04785 -52.316888) (xy 77.760576 -52.029614) (xy 77.72908 -52.06111)
			(xy 77.65542 -52.260246) (xy 77.817218 -52.422044)
		)
		(stroke
			(width 0)
			(type solid)
		)
		(fill yes)
		(layer "In11.Cu")
		(net "M_J_DQ<28>")
	)
	(gr_poly
		(pts
			(xy 78.185264 -58.7121) (xy 78.207616 -58.673492) (xy 77.862176 -58.474102) (xy 77.840078 -58.51271)
			(xy 77.83195 -58.70448) (xy 78.023212 -58.81497)
		)
		(stroke
			(width 0)
			(type solid)
		)
		(fill yes)
		(layer "In11.Cu")
		(net "M_J_DQ<16>")
	)
	(gr_poly
		(pts
			(xy 78.185264 -56.730646) (xy 78.207616 -56.692038) (xy 77.862176 -56.492648) (xy 77.840078 -56.531256)
			(xy 77.83195 -56.723026) (xy 78.023212 -56.833516)
		)
		(stroke
			(width 0)
			(type solid)
		)
		(fill yes)
		(layer "In11.Cu")
		(net "M_J_DQS_DP<2>")
	)
	(gr_poly
		(pts
			(xy 78.185264 -55.740046) (xy 78.207616 -55.701438) (xy 77.862176 -55.502048) (xy 77.840078 -55.540656)
			(xy 77.83195 -55.732426) (xy 78.023212 -55.842916)
		)
		(stroke
			(width 0)
			(type solid)
		)
		(fill yes)
		(layer "In11.Cu")
		(net "M_J_DQ<22>")
	)
	(gr_poly
		(pts
			(xy 78.185264 -54.749446) (xy 78.207616 -54.710838) (xy 77.862176 -54.511448) (xy 77.840078 -54.550056)
			(xy 77.83195 -54.741826) (xy 78.023212 -54.852316)
		)
		(stroke
			(width 0)
			(type solid)
		)
		(fill yes)
		(layer "In11.Cu")
		(net "M_J_DQ<18>")
	)
	(gr_poly
		(pts
			(xy 78.196186 -57.727596) (xy 78.218538 -57.689242) (xy 77.873098 -57.489852) (xy 77.851 -57.528206)
			(xy 77.842872 -57.719976) (xy 78.034134 -57.830466)
		)
		(stroke
			(width 0)
			(type solid)
		)
		(fill yes)
		(layer "In11.Cu")
		(net "M_J_DQS_DP<11>")
	)
	(gr_poly
		(pts
			(xy 78.206092 -94.112842) (xy 78.18374 -94.074488) (xy 78.021688 -93.971618) (xy 77.830426 -94.082108)
			(xy 77.838554 -94.273878) (xy 77.860652 -94.312486)
		)
		(stroke
			(width 0)
			(type solid)
		)
		(fill yes)
		(layer "In11.Cu")
		(net "M_M_DQS_DP<11>")
	)
	(gr_poly
		(pts
			(xy 78.207616 -97.08388) (xy 78.185264 -97.045526) (xy 78.023212 -96.942656) (xy 77.83195 -97.053146)
			(xy 77.840078 -97.244916) (xy 77.862176 -97.28327)
		)
		(stroke
			(width 0)
			(type solid)
		)
		(fill yes)
		(layer "In11.Cu")
		(net "M_M_DQ<18>")
	)
	(gr_poly
		(pts
			(xy 78.207616 -96.09328) (xy 78.185264 -96.054926) (xy 78.023212 -95.952056) (xy 77.83195 -96.062546)
			(xy 77.840078 -96.254316) (xy 77.862176 -96.29267)
		)
		(stroke
			(width 0)
			(type solid)
		)
		(fill yes)
		(layer "In11.Cu")
		(net "M_M_DQ<22>")
	)
	(gr_poly
		(pts
			(xy 78.207616 -95.10268) (xy 78.185264 -95.064326) (xy 78.023212 -94.961456) (xy 77.83195 -95.071946)
			(xy 77.840078 -95.263716) (xy 77.862176 -95.30207)
		)
		(stroke
			(width 0)
			(type solid)
		)
		(fill yes)
		(layer "In11.Cu")
		(net "M_M_DQS_DN<2>")
	)
	(gr_poly
		(pts
			(xy 78.207616 -92.13088) (xy 78.185264 -92.092526) (xy 78.023212 -91.989656) (xy 77.83195 -92.100146)
			(xy 77.840078 -92.291916) (xy 77.862176 -92.33027)
		)
		(stroke
			(width 0)
			(type solid)
		)
		(fill yes)
		(layer "In11.Cu")
		(net "M_M_DQ<20>")
	)
	(gr_poly
		(pts
			(xy 78.209902 -101.028246) (xy 78.136242 -100.82911) (xy 78.104746 -100.797614) (xy 77.817472 -101.084888)
			(xy 77.848714 -101.116384) (xy 78.048104 -101.190044)
		)
		(stroke
			(width 0)
			(type solid)
		)
		(fill yes)
		(layer "In11.Cu")
		(net "M_M_DQ<29>")
	)
	(gr_poly
		(pts
			(xy 78.214474 -52.150264) (xy 78.288134 -51.951128) (xy 78.126336 -51.78933) (xy 77.9272 -51.86299)
			(xy 77.895704 -51.894486) (xy 78.182978 -52.18176)
		)
		(stroke
			(width 0)
			(type solid)
		)
		(fill yes)
		(layer "In11.Cu")
		(net "M_J_DQ<29>")
	)
	(gr_poly
		(pts
			(xy 78.220316 -93.118178) (xy 78.197964 -93.079824) (xy 78.035912 -92.976954) (xy 77.84465 -93.087444)
			(xy 77.852778 -93.279214) (xy 77.874876 -93.317822)
		)
		(stroke
			(width 0)
			(type solid)
		)
		(fill yes)
		(layer "In11.Cu")
		(net "M_M_DQ<16>")
	)
	(gr_poly
		(pts
			(xy 78.55458 -99.291648) (xy 78.523084 -99.260152) (xy 78.323694 -99.186492) (xy 78.16215 -99.34829)
			(xy 78.23581 -99.547426) (xy 78.267306 -99.578922)
		)
		(stroke
			(width 0)
			(type solid)
		)
		(fill yes)
		(layer "In11.Cu")
		(net "M_M_DQ<28>")
	)
	(gr_poly
		(pts
			(xy 78.605888 -97.991168) (xy 78.561184 -97.991422) (xy 78.391258 -98.080322) (xy 78.391004 -98.301048)
			(xy 78.561184 -98.389948) (xy 78.605888 -98.390202)
		)
		(stroke
			(width 0)
			(type solid)
		)
		(fill yes)
		(layer "In11.Cu")
		(net "M_M_DQ<28>")
	)
	(gr_poly
		(pts
			(xy 78.727554 -53.059584) (xy 78.75905 -53.028088) (xy 78.471776 -52.740814) (xy 78.44028 -52.77231)
			(xy 78.36662 -52.971446) (xy 78.528418 -53.133244)
		)
		(stroke
			(width 0)
			(type solid)
		)
		(fill yes)
		(layer "In11.Cu")
		(net "M_J_DQ<28>")
	)
	(gr_poly
		(pts
			(xy 78.794102 -99.656646) (xy 78.720442 -99.45751) (xy 78.688946 -99.426014) (xy 78.401672 -99.713288)
			(xy 78.432914 -99.744784) (xy 78.632304 -99.818444)
		)
		(stroke
			(width 0)
			(type solid)
		)
		(fill yes)
		(layer "In11.Cu")
		(net "M_M_DQ<29>")
	)
	(gr_poly
		(pts
			(xy 78.836266 -56.630316) (xy 78.844394 -56.438546) (xy 78.653132 -56.328056) (xy 78.49108 -56.430926)
			(xy 78.468728 -56.46928) (xy 78.814168 -56.668924)
		)
		(stroke
			(width 0)
			(type solid)
		)
		(fill yes)
		(layer "In11.Cu")
		(net "M_J_DQS_DN<2>")
	)
	(gr_poly
		(pts
			(xy 78.836266 -55.639716) (xy 78.844394 -55.447946) (xy 78.653132 -55.337456) (xy 78.49108 -55.440326)
			(xy 78.468728 -55.47868) (xy 78.814168 -55.678324)
		)
		(stroke
			(width 0)
			(type solid)
		)
		(fill yes)
		(layer "In11.Cu")
		(net "M_J_DQ<23>")
	)
	(gr_poly
		(pts
			(xy 78.83779 -54.649878) (xy 78.845918 -54.458108) (xy 78.654656 -54.347618) (xy 78.492604 -54.450488)
			(xy 78.470252 -54.488842) (xy 78.815692 -54.688232)
		)
		(stroke
			(width 0)
			(type solid)
		)
		(fill yes)
		(layer "In11.Cu")
		(net "M_J_DQ<19>")
	)
	(gr_poly
		(pts
			(xy 78.844394 -94.36608) (xy 78.836266 -94.17431) (xy 78.814168 -94.135702) (xy 78.468728 -94.335346)
			(xy 78.49108 -94.3737) (xy 78.653132 -94.47657)
		)
		(stroke
			(width 0)
			(type solid)
		)
		(fill yes)
		(layer "In11.Cu")
		(net "M_M_DQS_DN<11>")
	)
	(gr_poly
		(pts
			(xy 78.845918 -97.336864) (xy 78.83779 -97.145094) (xy 78.815692 -97.106486) (xy 78.470252 -97.30613)
			(xy 78.492604 -97.344484) (xy 78.654656 -97.447354)
		)
		(stroke
			(width 0)
			(type solid)
		)
		(fill yes)
		(layer "In11.Cu")
		(net "M_M_DQ<19>")
	)
	(gr_poly
		(pts
			(xy 78.845918 -96.346264) (xy 78.83779 -96.154494) (xy 78.815692 -96.115886) (xy 78.470252 -96.31553)
			(xy 78.492604 -96.353884) (xy 78.654656 -96.456754)
		)
		(stroke
			(width 0)
			(type solid)
		)
		(fill yes)
		(layer "In11.Cu")
		(net "M_M_DQ<23>")
	)
	(gr_poly
		(pts
			(xy 78.845918 -95.355664) (xy 78.83779 -95.163894) (xy 78.815692 -95.125286) (xy 78.470252 -95.32493)
			(xy 78.492604 -95.363284) (xy 78.654656 -95.466154)
		)
		(stroke
			(width 0)
			(type solid)
		)
		(fill yes)
		(layer "In11.Cu")
		(net "M_M_DQS_DP<2>")
	)
	(gr_poly
		(pts
			(xy 78.853792 -101.536246) (xy 78.809342 -101.536246) (xy 78.616302 -101.625146) (xy 78.616302 -101.853746)
			(xy 78.809342 -101.942646) (xy 78.853792 -101.942646)
		)
		(stroke
			(width 0)
			(type solid)
		)
		(fill yes)
		(layer "In11.Cu")
		(net "M_M_DQ<24>")
	)
	(gr_poly
		(pts
			(xy 78.853792 -100.545646) (xy 78.809342 -100.545646) (xy 78.616302 -100.634546) (xy 78.616302 -100.863146)
			(xy 78.809342 -100.952046) (xy 78.853792 -100.952046)
		)
		(stroke
			(width 0)
			(type solid)
		)
		(fill yes)
		(layer "In11.Cu")
		(net "M_M_DQ<24>")
	)
	(gr_poly
		(pts
			(xy 78.925674 -52.861464) (xy 78.999334 -52.662328) (xy 78.837536 -52.50053) (xy 78.6384 -52.57419)
			(xy 78.606904 -52.605686) (xy 78.894178 -52.89296)
		)
		(stroke
			(width 0)
			(type solid)
		)
		(fill yes)
		(layer "In11.Cu")
		(net "M_J_DQ<29>")
	)
	(gr_poly
		(pts
			(xy 79.043784 -57.2262) (xy 79.066136 -57.187592) (xy 78.720696 -56.988202) (xy 78.698598 -57.02681)
			(xy 78.69047 -57.21858) (xy 78.881732 -57.32907)
		)
		(stroke
			(width 0)
			(type solid)
		)
		(fill yes)
		(layer "In11.Cu")
		(net "M_J_DQS_DP<2>")
	)
	(gr_poly
		(pts
			(xy 79.043784 -56.2356) (xy 79.066136 -56.196992) (xy 78.720696 -55.997602) (xy 78.698598 -56.03621)
			(xy 78.69047 -56.22798) (xy 78.881732 -56.33847)
		)
		(stroke
			(width 0)
			(type solid)
		)
		(fill yes)
		(layer "In11.Cu")
		(net "M_J_DQ<22>")
	)
	(gr_poly
		(pts
			(xy 79.043784 -55.245) (xy 79.066136 -55.206392) (xy 78.720696 -55.007002) (xy 78.698598 -55.04561)
			(xy 78.69047 -55.23738) (xy 78.881732 -55.34787)
		)
		(stroke
			(width 0)
			(type solid)
		)
		(fill yes)
		(layer "In11.Cu")
		(net "M_J_DQ<18>")
	)
	(gr_poly
		(pts
			(xy 79.064612 -96.58985) (xy 79.04226 -96.551242) (xy 78.880208 -96.448372) (xy 78.688946 -96.558862)
			(xy 78.697074 -96.750632) (xy 78.719172 -96.78924)
		)
		(stroke
			(width 0)
			(type solid)
		)
		(fill yes)
		(layer "In11.Cu")
		(net "M_M_DQ<18>")
	)
	(gr_poly
		(pts
			(xy 79.064612 -95.59925) (xy 79.04226 -95.560642) (xy 78.880208 -95.457772) (xy 78.688946 -95.568262)
			(xy 78.697074 -95.760032) (xy 78.719172 -95.79864)
		)
		(stroke
			(width 0)
			(type solid)
		)
		(fill yes)
		(layer "In11.Cu")
		(net "M_M_DQ<22>")
	)
	(gr_poly
		(pts
			(xy 79.066136 -93.61678) (xy 79.043784 -93.578426) (xy 78.881732 -93.475556) (xy 78.69047 -93.586046)
			(xy 78.698598 -93.777816) (xy 78.720696 -93.81617)
		)
		(stroke
			(width 0)
			(type solid)
		)
		(fill yes)
		(layer "In11.Cu")
		(net "M_M_DQS_DP<11>")
	)
	(gr_poly
		(pts
			(xy 79.0702 -97.577148) (xy 79.047594 -97.53854) (xy 78.885796 -97.43567) (xy 78.694534 -97.545906)
			(xy 78.702408 -97.737676) (xy 78.72476 -97.776538)
		)
		(stroke
			(width 0)
			(type solid)
		)
		(fill yes)
		(layer "In11.Cu")
		(net "M_M_DQ<28>")
	)
	(gr_poly
		(pts
			(xy 79.162656 -92.790518) (xy 79.140304 -92.752164) (xy 78.978252 -92.649294) (xy 78.78699 -92.759784)
			(xy 78.795118 -92.951554) (xy 78.817216 -92.990162)
		)
		(stroke
			(width 0)
			(type solid)
		)
		(fill yes)
		(layer "In11.Cu")
		(net "M_M_DQ<16>")
	)
	(gr_poly
		(pts
			(xy 79.206598 -91.783408) (xy 79.117952 -91.612974) (xy 78.897226 -91.612466) (xy 78.807818 -91.782392)
			(xy 78.807818 -91.826842) (xy 79.206344 -91.828112)
		)
		(stroke
			(width 0)
			(type solid)
		)
		(fill yes)
		(layer "In11.Cu")
		(net "M_M_DQ<20>")
	)
	(gr_poly
		(pts
			(xy 79.21371 -98.958908) (xy 79.21371 -98.730054) (xy 79.020924 -98.641154) (xy 78.976474 -98.641154)
			(xy 78.976474 -99.047554) (xy 79.02067 -99.047808)
		)
		(stroke
			(width 0)
			(type solid)
		)
		(fill yes)
		(layer "In11.Cu")
		(net "M_M_DQ<29>")
	)
	(gr_poly
		(pts
			(xy 79.281274 -101.853746) (xy 79.281274 -101.625146) (xy 79.088234 -101.536246) (xy 79.043784 -101.536246)
			(xy 79.043784 -101.942646) (xy 79.088234 -101.942646)
		)
		(stroke
			(width 0)
			(type solid)
		)
		(fill yes)
		(layer "In11.Cu")
		(net "M_M_DQ<25>")
	)
	(gr_poly
		(pts
			(xy 79.281274 -100.863146) (xy 79.281274 -100.634546) (xy 79.088234 -100.545646) (xy 79.043784 -100.545646)
			(xy 79.043784 -100.952046) (xy 79.088234 -100.952046)
		)
		(stroke
			(width 0)
			(type solid)
		)
		(fill yes)
		(layer "In11.Cu")
		(net "M_M_DQ<25>")
	)
	(gr_poly
		(pts
			(xy 79.464154 -98.975926) (xy 79.419704 -98.975926) (xy 79.226664 -99.064826) (xy 79.226664 -99.293426)
			(xy 79.419704 -99.382326) (xy 79.464154 -99.382326)
		)
		(stroke
			(width 0)
			(type solid)
		)
		(fill yes)
		(layer "In11.Cu")
		(net "M_M_DQ<24>")
	)
	(gr_poly
		(pts
			(xy 79.69631 -57.126632) (xy 79.704438 -56.934862) (xy 79.513176 -56.824372) (xy 79.351124 -56.927242)
			(xy 79.328772 -56.965596) (xy 79.674212 -57.16524)
		)
		(stroke
			(width 0)
			(type solid)
		)
		(fill yes)
		(layer "In11.Cu")
		(net "M_J_DQS_DN<2>")
	)
	(gr_poly
		(pts
			(xy 79.69631 -56.136032) (xy 79.704438 -55.944262) (xy 79.513176 -55.833772) (xy 79.351124 -55.936642)
			(xy 79.328772 -55.974996) (xy 79.674212 -56.17464)
		)
		(stroke
			(width 0)
			(type solid)
		)
		(fill yes)
		(layer "In11.Cu")
		(net "M_J_DQ<23>")
	)
	(gr_poly
		(pts
			(xy 79.69631 -55.145432) (xy 79.704438 -54.953662) (xy 79.513176 -54.843172) (xy 79.351124 -54.946042)
			(xy 79.328772 -54.984396) (xy 79.674212 -55.18404)
		)
		(stroke
			(width 0)
			(type solid)
		)
		(fill yes)
		(layer "In11.Cu")
		(net "M_J_DQ<19>")
	)
	(gr_poly
		(pts
			(xy 79.702914 -97.83318) (xy 79.694786 -97.64141) (xy 79.672688 -97.602802) (xy 79.327248 -97.802446)
			(xy 79.3496 -97.8408) (xy 79.511652 -97.94367)
		)
		(stroke
			(width 0)
			(type solid)
		)
		(fill yes)
		(layer "In11.Cu")
		(net "M_M_DQ<29>")
	)
	(gr_poly
		(pts
			(xy 79.702914 -96.84258) (xy 79.694786 -96.65081) (xy 79.672688 -96.612202) (xy 79.327248 -96.811846)
			(xy 79.3496 -96.8502) (xy 79.511652 -96.95307)
		)
		(stroke
			(width 0)
			(type solid)
		)
		(fill yes)
		(layer "In11.Cu")
		(net "M_M_DQ<19>")
	)
	(gr_poly
		(pts
			(xy 79.702914 -95.85198) (xy 79.694786 -95.66021) (xy 79.672688 -95.621602) (xy 79.327248 -95.821246)
			(xy 79.3496 -95.8596) (xy 79.511652 -95.96247)
		)
		(stroke
			(width 0)
			(type solid)
		)
		(fill yes)
		(layer "In11.Cu")
		(net "M_M_DQ<23>")
	)
	(gr_poly
		(pts
			(xy 79.704438 -93.870018) (xy 79.69631 -93.678248) (xy 79.674212 -93.639894) (xy 79.328772 -93.83903)
			(xy 79.351124 -93.877638) (xy 79.513176 -93.980508)
		)
		(stroke
			(width 0)
			(type solid)
		)
		(fill yes)
		(layer "In11.Cu")
		(net "M_M_DQS_DN<11>")
	)
	(gr_poly
		(pts
			(xy 79.892144 -99.293426) (xy 79.892144 -99.064826) (xy 79.699104 -98.975926) (xy 79.654654 -98.975926)
			(xy 79.654654 -99.382326) (xy 79.699104 -99.382326)
		)
		(stroke
			(width 0)
			(type solid)
		)
		(fill yes)
		(layer "In11.Cu")
		(net "M_M_DQ<25>")
	)
	(gr_poly
		(pts
			(xy 79.90078 -55.739284) (xy 79.923132 -55.70093) (xy 79.577692 -55.501286) (xy 79.555594 -55.539894)
			(xy 79.547466 -55.731664) (xy 79.738728 -55.842154)
		)
		(stroke
			(width 0)
			(type solid)
		)
		(fill yes)
		(layer "In11.Cu")
		(net "M_J_DQ<18>")
	)
	(gr_poly
		(pts
			(xy 79.90459 -57.72277) (xy 79.926942 -57.684416) (xy 79.581502 -57.484772) (xy 79.559404 -57.52338)
			(xy 79.551276 -57.71515) (xy 79.742538 -57.82564)
		)
		(stroke
			(width 0)
			(type solid)
		)
		(fill yes)
		(layer "In11.Cu")
		(net "M_J_DQS_DP<2>")
	)
	(gr_poly
		(pts
			(xy 79.924656 -97.08388) (xy 79.902304 -97.045526) (xy 79.740252 -96.942656) (xy 79.54899 -97.053146)
			(xy 79.557118 -97.244916) (xy 79.579216 -97.28327)
		)
		(stroke
			(width 0)
			(type solid)
		)
		(fill yes)
		(layer "In11.Cu")
		(net "M_M_DQ<28>")
	)
	(gr_poly
		(pts
			(xy 79.924656 -96.09328) (xy 79.902304 -96.054926) (xy 79.740252 -95.952056) (xy 79.54899 -96.062546)
			(xy 79.557118 -96.254316) (xy 79.579216 -96.29267)
		)
		(stroke
			(width 0)
			(type solid)
		)
		(fill yes)
		(layer "In11.Cu")
		(net "M_M_DQ<18>")
	)
	(gr_poly
		(pts
			(xy 79.926688 -98.07321) (xy 79.90459 -98.034602) (xy 79.742538 -97.931732) (xy 79.551276 -98.042222)
			(xy 79.55915 -98.233992) (xy 79.581502 -98.272346)
		)
		(stroke
			(width 0)
			(type solid)
		)
		(fill yes)
		(layer "In11.Cu")
		(net "M_M_DQ<24>")
	)
	(gr_poly
		(pts
			(xy 79.926942 -93.12021) (xy 79.90459 -93.081856) (xy 79.742538 -92.978986) (xy 79.551276 -93.089476)
			(xy 79.559404 -93.281246) (xy 79.581502 -93.319854)
		)
		(stroke
			(width 0)
			(type solid)
		)
		(fill yes)
		(layer "In11.Cu")
		(net "M_M_DQS_DP<11>")
	)
	(gr_poly
		(pts
			(xy 80.019652 -95.353124) (xy 80.110838 -95.151956) (xy 79.992474 -95.000826) (xy 79.952088 -94.982284)
			(xy 79.787496 -95.345758) (xy 79.828136 -95.363792)
		)
		(stroke
			(width 0)
			(type solid)
		)
		(fill yes)
		(layer "In11.Cu")
		(net "M_M_DQ<23>")
	)
	(gr_poly
		(pts
			(xy 80.022954 -92.294202) (xy 80.000602 -92.255848) (xy 79.83855 -92.152978) (xy 79.647288 -92.263468)
			(xy 79.655416 -92.455238) (xy 79.677514 -92.493846)
		)
		(stroke
			(width 0)
			(type solid)
		)
		(fill yes)
		(layer "In11.Cu")
		(net "M_M_DQ<16>")
	)
	(gr_poly
		(pts
			(xy 80.0862 -101.718618) (xy 80.04175 -101.718618) (xy 79.84871 -101.807518) (xy 79.84871 -102.036118)
			(xy 80.04175 -102.125018) (xy 80.0862 -102.125018)
		)
		(stroke
			(width 0)
			(type solid)
		)
		(fill yes)
		(layer "In11.Cu")
		(net "M_M_DQS_DP<12>")
	)
	(gr_poly
		(pts
			(xy 80.0862 -100.728018) (xy 80.04175 -100.728018) (xy 79.84871 -100.816918) (xy 79.84871 -101.045518)
			(xy 80.04175 -101.134418) (xy 80.0862 -101.134418)
		)
		(stroke
			(width 0)
			(type solid)
		)
		(fill yes)
		(layer "In11.Cu")
		(net "M_M_DQS_DP<12>")
	)
	(gr_poly
		(pts
			(xy 80.51419 -102.036118) (xy 80.51419 -101.807518) (xy 80.32115 -101.718618) (xy 80.2767 -101.718618)
			(xy 80.2767 -102.125018) (xy 80.32115 -102.125018)
		)
		(stroke
			(width 0)
			(type solid)
		)
		(fill yes)
		(layer "In11.Cu")
		(net "M_M_DQS_DN<12>")
	)
	(gr_poly
		(pts
			(xy 80.51419 -101.045518) (xy 80.51419 -100.816918) (xy 80.32115 -100.728018) (xy 80.2767 -100.728018)
			(xy 80.2767 -101.134418) (xy 80.32115 -101.134418)
		)
		(stroke
			(width 0)
			(type solid)
		)
		(fill yes)
		(layer "In11.Cu")
		(net "M_M_DQS_DN<12>")
	)
	(gr_poly
		(pts
			(xy 80.55102 -57.619646) (xy 80.559148 -57.427876) (xy 80.367886 -57.317386) (xy 80.205834 -57.420256)
			(xy 80.183482 -57.45861) (xy 80.528922 -57.658)
		)
		(stroke
			(width 0)
			(type solid)
		)
		(fill yes)
		(layer "In11.Cu")
		(net "M_J_DQS_DN<2>")
	)
	(gr_poly
		(pts
			(xy 80.553306 -55.639716) (xy 80.561434 -55.447946) (xy 80.370172 -55.337456) (xy 80.20812 -55.440326)
			(xy 80.185768 -55.47868) (xy 80.531208 -55.678324)
		)
		(stroke
			(width 0)
			(type solid)
		)
		(fill yes)
		(layer "In11.Cu")
		(net "M_J_DQ<19>")
	)
	(gr_poly
		(pts
			(xy 80.55483 -56.631078) (xy 80.562958 -56.439308) (xy 80.371696 -56.328818) (xy 80.209644 -56.431688)
			(xy 80.187292 -56.470042) (xy 80.532732 -56.669686)
		)
		(stroke
			(width 0)
			(type solid)
		)
		(fill yes)
		(layer "In11.Cu")
		(net "M_J_DQ<23>")
	)
	(gr_poly
		(pts
			(xy 80.559148 -93.37675) (xy 80.55102 -93.18498) (xy 80.528922 -93.146372) (xy 80.183482 -93.345762)
			(xy 80.205834 -93.38437) (xy 80.367886 -93.48724)
		)
		(stroke
			(width 0)
			(type solid)
		)
		(fill yes)
		(layer "In11.Cu")
		(net "M_M_DQS_DN<11>")
	)
	(gr_poly
		(pts
			(xy 80.561434 -94.36608) (xy 80.553306 -94.17431) (xy 80.531208 -94.135702) (xy 80.185768 -94.335346)
			(xy 80.20812 -94.3737) (xy 80.370172 -94.47657)
		)
		(stroke
			(width 0)
			(type solid)
		)
		(fill yes)
		(layer "In11.Cu")
		(net "M_M_DQ<22>")
	)
	(gr_poly
		(pts
			(xy 80.562958 -98.327464) (xy 80.55483 -98.135694) (xy 80.532732 -98.097086) (xy 80.187292 -98.29673)
			(xy 80.209644 -98.335084) (xy 80.371696 -98.437954)
		)
		(stroke
			(width 0)
			(type solid)
		)
		(fill yes)
		(layer "In11.Cu")
		(net "M_M_DQ<25>")
	)
	(gr_poly
		(pts
			(xy 80.562958 -97.336864) (xy 80.55483 -97.145094) (xy 80.532732 -97.106486) (xy 80.187292 -97.30613)
			(xy 80.209644 -97.344484) (xy 80.371696 -97.447354)
		)
		(stroke
			(width 0)
			(type solid)
		)
		(fill yes)
		(layer "In11.Cu")
		(net "M_M_DQ<29>")
	)
	(gr_poly
		(pts
			(xy 80.562958 -96.346264) (xy 80.55483 -96.154494) (xy 80.532732 -96.115886) (xy 80.187292 -96.31553)
			(xy 80.209644 -96.353884) (xy 80.371696 -96.456754)
		)
		(stroke
			(width 0)
			(type solid)
		)
		(fill yes)
		(layer "In11.Cu")
		(net "M_M_DQ<19>")
	)
	(gr_poly
		(pts
			(xy 80.7593 -58.216038) (xy 80.781652 -58.177684) (xy 80.436212 -57.97804) (xy 80.414114 -58.016648)
			(xy 80.405986 -58.208418) (xy 80.597248 -58.318908)
		)
		(stroke
			(width 0)
			(type solid)
		)
		(fill yes)
		(layer "In11.Cu")
		(net "M_J_DQS_DP<2>")
	)
	(gr_poly
		(pts
			(xy 80.781652 -97.58045) (xy 80.7593 -97.541842) (xy 80.597248 -97.438972) (xy 80.405986 -97.549462)
			(xy 80.414114 -97.741232) (xy 80.436212 -97.77984)
		)
		(stroke
			(width 0)
			(type solid)
		)
		(fill yes)
		(layer "In11.Cu")
		(net "M_M_DQ<24>")
	)
	(gr_poly
		(pts
			(xy 80.781652 -96.58985) (xy 80.7593 -96.551242) (xy 80.597248 -96.448372) (xy 80.405986 -96.558862)
			(xy 80.414114 -96.750632) (xy 80.436212 -96.78924)
		)
		(stroke
			(width 0)
			(type solid)
		)
		(fill yes)
		(layer "In11.Cu")
		(net "M_M_DQ<28>")
	)
	(gr_poly
		(pts
			(xy 80.859122 -57.062878) (xy 80.881474 -57.024524) (xy 80.536034 -56.82488) (xy 80.513936 -56.863488)
			(xy 80.505808 -57.055258) (xy 80.69707 -57.165748)
		)
		(stroke
			(width 0)
			(type solid)
		)
		(fill yes)
		(layer "In11.Cu")
		(net "M_J_DQ<23>")
	)
	(gr_poly
		(pts
			(xy 80.873092 -101.991414) (xy 80.828642 -101.991414) (xy 80.635602 -102.080314) (xy 80.635602 -102.308914)
			(xy 80.828642 -102.397814) (xy 80.873092 -102.397814)
		)
		(stroke
			(width 0)
			(type solid)
		)
		(fill yes)
		(layer "In11.Cu")
		(net "M_M_DQS_DN<3>")
	)
	(gr_poly
		(pts
			(xy 80.873092 -101.000814) (xy 80.828642 -101.000814) (xy 80.635602 -101.089714) (xy 80.635602 -101.318314)
			(xy 80.828642 -101.407214) (xy 80.873092 -101.407214)
		)
		(stroke
			(width 0)
			(type solid)
		)
		(fill yes)
		(layer "In11.Cu")
		(net "M_M_DQS_DN<3>")
	)
	(gr_poly
		(pts
			(xy 80.878426 -93.78188) (xy 80.856074 -93.743526) (xy 80.694022 -93.640656) (xy 80.50276 -93.751146)
			(xy 80.510888 -93.942916) (xy 80.532986 -93.98127)
		)
		(stroke
			(width 0)
			(type solid)
		)
		(fill yes)
		(layer "In11.Cu")
		(net "M_M_DQ<22>")
	)
	(gr_poly
		(pts
			(xy 80.879696 -94.771718) (xy 80.857344 -94.733364) (xy 80.695292 -94.630494) (xy 80.50403 -94.740984)
			(xy 80.512158 -94.932754) (xy 80.534256 -94.971362)
		)
		(stroke
			(width 0)
			(type solid)
		)
		(fill yes)
		(layer "In11.Cu")
		(net "M_M_DQ<18>")
	)
	(gr_poly
		(pts
			(xy 80.890618 -53.906928) (xy 80.964278 -53.707792) (xy 80.80248 -53.545994) (xy 80.603344 -53.619654)
			(xy 80.571848 -53.65115) (xy 80.859122 -53.938424)
		)
		(stroke
			(width 0)
			(type solid)
		)
		(fill yes)
		(layer "In11.Cu")
		(net "M_J_DQ<29>")
	)
	(gr_poly
		(pts
			(xy 80.891888 -95.845884) (xy 80.979772 -95.643192) (xy 80.859122 -95.494094) (xy 80.818228 -95.47606)
			(xy 80.659732 -95.842328) (xy 80.700626 -95.859854)
		)
		(stroke
			(width 0)
			(type solid)
		)
		(fill yes)
		(layer "In11.Cu")
		(net "M_M_DQ<19>")
	)
	(gr_poly
		(pts
			(xy 81.098136 -54.860444) (xy 81.129632 -54.828948) (xy 80.842358 -54.541674) (xy 80.810862 -54.57317)
			(xy 80.737202 -54.772306) (xy 80.899 -54.934104)
		)
		(stroke
			(width 0)
			(type solid)
		)
		(fill yes)
		(layer "In11.Cu")
		(net "M_J_DQ<28>")
	)
	(gr_poly
		(pts
			(xy 81.128616 -52.741576) (xy 81.160112 -52.710334) (xy 80.872584 -52.422806) (xy 80.841342 -52.454302)
			(xy 80.767682 -52.653692) (xy 80.929226 -52.815236)
		)
		(stroke
			(width 0)
			(type solid)
		)
		(fill yes)
		(layer "In11.Cu")
		(net "M_J_DQ<24>")
	)
	(gr_poly
		(pts
			(xy 81.16062 -102.924102) (xy 81.11617 -102.924102) (xy 80.92313 -103.013002) (xy 80.92313 -103.241602)
			(xy 81.11617 -103.330502) (xy 81.16062 -103.330502)
		)
		(stroke
			(width 0)
			(type solid)
		)
		(fill yes)
		(layer "In11.Cu")
		(net "M_M_DQS_DN<3>")
	)
	(gr_poly
		(pts
			(xy 81.296256 -54.662324) (xy 81.369916 -54.463188) (xy 81.208118 -54.30139) (xy 81.008982 -54.37505)
			(xy 80.977486 -54.406546) (xy 81.26476 -54.69382)
		)
		(stroke
			(width 0)
			(type solid)
		)
		(fill yes)
		(layer "In11.Cu")
		(net "M_J_DQ<29>")
	)
	(gr_poly
		(pts
			(xy 81.301082 -101.750114) (xy 81.301082 -101.521514) (xy 81.108042 -101.432614) (xy 81.063592 -101.432614)
			(xy 81.063592 -101.839014) (xy 81.108042 -101.839014)
		)
		(stroke
			(width 0)
			(type solid)
		)
		(fill yes)
		(layer "In11.Cu")
		(net "M_M_DQS_DP<3>")
	)
	(gr_poly
		(pts
			(xy 81.32572 -52.544472) (xy 81.39938 -52.345082) (xy 81.237836 -52.183538) (xy 81.038446 -52.257198)
			(xy 81.00695 -52.28844) (xy 81.294478 -52.575968)
		)
		(stroke
			(width 0)
			(type solid)
		)
		(fill yes)
		(layer "In11.Cu")
		(net "M_J_DQ<25>")
	)
	(gr_poly
		(pts
			(xy 81.40954 -56.143398) (xy 81.424272 -55.951882) (xy 81.23682 -55.834788) (xy 81.071212 -55.93207)
			(xy 81.047844 -55.969916) (xy 81.385918 -56.18099)
		)
		(stroke
			(width 0)
			(type solid)
		)
		(fill yes)
		(layer "In11.Cu")
		(net "M_J_DQ<19>")
	)
	(gr_poly
		(pts
			(xy 81.4197 -96.843088) (xy 81.411572 -96.651064) (xy 81.389474 -96.612456) (xy 81.044288 -96.8121)
			(xy 81.066386 -96.850454) (xy 81.228438 -96.953324)
		)
		(stroke
			(width 0)
			(type solid)
		)
		(fill yes)
		(layer "In11.Cu")
		(net "M_M_DQ<29>")
	)
	(gr_poly
		(pts
			(xy 81.419954 -97.83318) (xy 81.411826 -97.64141) (xy 81.389728 -97.602802) (xy 81.044288 -97.802446)
			(xy 81.06664 -97.8408) (xy 81.228692 -97.94367)
		)
		(stroke
			(width 0)
			(type solid)
		)
		(fill yes)
		(layer "In11.Cu")
		(net "M_M_DQ<25>")
	)
	(gr_poly
		(pts
			(xy 81.45653 -93.759782) (xy 81.450688 -93.715586) (xy 81.340452 -93.558614) (xy 81.121504 -93.587316)
			(xy 81.055464 -93.767402) (xy 81.061052 -93.811344)
		)
		(stroke
			(width 0)
			(type solid)
		)
		(fill yes)
		(layer "In11.Cu")
		(net "M_M_DQ<22>")
	)
	(gr_poly
		(pts
			(xy 81.461864 -51.064414) (xy 81.49336 -51.033172) (xy 81.205832 -50.745644) (xy 81.17459 -50.77714)
			(xy 81.10093 -50.97653) (xy 81.262474 -51.138074)
		)
		(stroke
			(width 0)
			(type solid)
		)
		(fill yes)
		(layer "In11.Cu")
		(net "M_J_DQS_DP<12>")
	)
	(gr_poly
		(pts
			(xy 81.58861 -103.241602) (xy 81.58861 -103.013002) (xy 81.39557 -102.924102) (xy 81.35112 -102.924102)
			(xy 81.35112 -103.330502) (xy 81.39557 -103.330502)
		)
		(stroke
			(width 0)
			(type solid)
		)
		(fill yes)
		(layer "In11.Cu")
		(net "M_M_DQS_DP<3>")
	)
	(gr_poly
		(pts
			(xy 81.637632 -56.759348) (xy 81.475326 -56.395366) (xy 81.434686 -56.4134) (xy 81.315306 -56.563768)
			(xy 81.405222 -56.765698) (xy 81.596992 -56.777636)
		)
		(stroke
			(width 0)
			(type solid)
		)
		(fill yes)
		(layer "In11.Cu")
		(net "M_J_DQ<19>")
	)
	(gr_poly
		(pts
			(xy 81.641696 -95.102426) (xy 81.619598 -95.064072) (xy 81.457546 -94.961202) (xy 81.266284 -95.071438)
			(xy 81.274412 -95.263208) (xy 81.29651 -95.30207)
		)
		(stroke
			(width 0)
			(type solid)
		)
		(fill yes)
		(layer "In11.Cu")
		(net "M_M_DQ<28>")
	)
	(gr_poly
		(pts
			(xy 81.64957 -97.079562) (xy 81.627218 -97.041208) (xy 81.465166 -96.938338) (xy 81.273904 -97.048828)
			(xy 81.282032 -97.240598) (xy 81.30413 -97.279206)
		)
		(stroke
			(width 0)
			(type solid)
		)
		(fill yes)
		(layer "In11.Cu")
		(net "M_M_DQ<24>")
	)
	(gr_poly
		(pts
			(xy 81.687924 -100.106988) (xy 81.656428 -100.075492) (xy 81.457038 -100.001832) (xy 81.295494 -100.16363)
			(xy 81.369154 -100.36302) (xy 81.40065 -100.394262)
		)
		(stroke
			(width 0)
			(type solid)
		)
		(fill yes)
		(layer "In11.Cu")
		(net "M_M_DQS_DN<3>")
	)
	(gr_poly
		(pts
			(xy 81.719166 -96.30664) (xy 81.719166 -96.085914) (xy 81.548986 -95.997014) (xy 81.504536 -95.99676)
			(xy 81.50479 -96.39554) (xy 81.548986 -96.39554)
		)
		(stroke
			(width 0)
			(type solid)
		)
		(fill yes)
		(layer "In11.Cu")
		(net "M_M_DQ<29>")
	)
	(gr_poly
		(pts
			(xy 81.786476 -50.993802) (xy 81.860136 -50.794666) (xy 81.698338 -50.632868) (xy 81.499202 -50.706528)
			(xy 81.467706 -50.738024) (xy 81.75498 -51.025298)
		)
		(stroke
			(width 0)
			(type solid)
		)
		(fill yes)
		(layer "In11.Cu")
		(net "M_J_DQS_DN<12>")
	)
	(gr_poly
		(pts
			(xy 81.809336 -55.571644) (xy 81.840832 -55.540148) (xy 81.553558 -55.252874) (xy 81.522062 -55.28437)
			(xy 81.448402 -55.483506) (xy 81.6102 -55.645304)
		)
		(stroke
			(width 0)
			(type solid)
		)
		(fill yes)
		(layer "In11.Cu")
		(net "M_J_DQ<28>")
	)
	(gr_poly
		(pts
			(xy 81.839816 -53.452776) (xy 81.871312 -53.421534) (xy 81.583784 -53.134006) (xy 81.552542 -53.165502)
			(xy 81.478882 -53.364892) (xy 81.640426 -53.526436)
		)
		(stroke
			(width 0)
			(type solid)
		)
		(fill yes)
		(layer "In11.Cu")
		(net "M_J_DQ<24>")
	)
	(gr_poly
		(pts
			(xy 81.9277 -100.472494) (xy 81.85404 -100.273104) (xy 81.822544 -100.241862) (xy 81.53527 -100.529136)
			(xy 81.566766 -100.560632) (xy 81.766156 -100.634292)
		)
		(stroke
			(width 0)
			(type solid)
		)
		(fill yes)
		(layer "In11.Cu")
		(net "M_M_DQS_DP<3>")
	)
	(gr_poly
		(pts
			(xy 82.007456 -55.373524) (xy 82.081116 -55.174388) (xy 81.919318 -55.01259) (xy 81.720182 -55.08625)
			(xy 81.688686 -55.117746) (xy 81.97596 -55.40502)
		)
		(stroke
			(width 0)
			(type solid)
		)
		(fill yes)
		(layer "In11.Cu")
		(net "M_J_DQ<29>")
	)
	(gr_poly
		(pts
			(xy 82.028792 -97.896934) (xy 81.997296 -97.865438) (xy 81.797906 -97.791778) (xy 81.636362 -97.953576)
			(xy 81.710022 -98.152966) (xy 81.741518 -98.184208)
		)
		(stroke
			(width 0)
			(type solid)
		)
		(fill yes)
		(layer "In11.Cu")
		(net "M_M_DQS_DP<12>")
	)
	(gr_poly
		(pts
			(xy 82.03692 -53.255672) (xy 82.11058 -53.056282) (xy 81.949036 -52.894738) (xy 81.749646 -52.968398)
			(xy 81.71815 -52.99964) (xy 82.005678 -53.287168)
		)
		(stroke
			(width 0)
			(type solid)
		)
		(fill yes)
		(layer "In11.Cu")
		(net "M_J_DQ<25>")
	)
	(gr_poly
		(pts
			(xy 82.039714 -96.010222) (xy 81.995264 -96.010222) (xy 81.825338 -96.099122) (xy 81.825084 -96.319848)
			(xy 81.995264 -96.408748) (xy 82.039968 -96.409002)
		)
		(stroke
			(width 0)
			(type solid)
		)
		(fill yes)
		(layer "In11.Cu")
		(net "M_M_DQ<24>")
	)
	(gr_poly
		(pts
			(xy 82.039714 -94.030546) (xy 81.995264 -94.030546) (xy 81.825084 -94.119446) (xy 81.825084 -94.340426)
			(xy 81.995264 -94.429326) (xy 82.039714 -94.429326)
		)
		(stroke
			(width 0)
			(type solid)
		)
		(fill yes)
		(layer "In11.Cu")
		(net "M_M_DQ<28>")
	)
	(gr_poly
		(pts
			(xy 82.039714 -93.03385) (xy 81.995264 -93.03385) (xy 81.825084 -93.12275) (xy 81.825084 -93.34373)
			(xy 81.995264 -93.43263) (xy 82.039714 -93.43263)
		)
		(stroke
			(width 0)
			(type solid)
		)
		(fill yes)
		(layer "In11.Cu")
		(net "M_M_DQ<28>")
	)
	(gr_poly
		(pts
			(xy 82.039714 -92.047822) (xy 81.995264 -92.047822) (xy 81.825338 -92.136722) (xy 81.825084 -92.357448)
			(xy 81.995264 -92.446348) (xy 82.039968 -92.446602)
		)
		(stroke
			(width 0)
			(type solid)
		)
		(fill yes)
		(layer "In11.Cu")
		(net "M_M_DQ<28>")
	)
	(gr_poly
		(pts
			(xy 82.039714 -64.3001) (xy 81.995264 -64.3001) (xy 81.825084 -64.389) (xy 81.825084 -64.60998) (xy 81.995264 -64.69888)
			(xy 82.039714 -64.69888)
		)
		(stroke
			(width 0)
			(type solid)
		)
		(fill yes)
		(layer "In11.Cu")
		(net "M_J_DQ<28>")
	)
	(gr_poly
		(pts
			(xy 82.039714 -63.3095) (xy 81.995264 -63.3095) (xy 81.825084 -63.3984) (xy 81.825084 -63.61938)
			(xy 81.995264 -63.70828) (xy 82.039714 -63.70828)
		)
		(stroke
			(width 0)
			(type solid)
		)
		(fill yes)
		(layer "In11.Cu")
		(net "M_J_DQ<28>")
	)
	(gr_poly
		(pts
			(xy 82.039714 -62.3189) (xy 81.995264 -62.3189) (xy 81.825084 -62.4078) (xy 81.825084 -62.62878)
			(xy 81.995264 -62.71768) (xy 82.039714 -62.71768)
		)
		(stroke
			(width 0)
			(type solid)
		)
		(fill yes)
		(layer "In11.Cu")
		(net "M_J_DQ<28>")
	)
	(gr_poly
		(pts
			(xy 82.039714 -61.3283) (xy 81.995264 -61.3283) (xy 81.825084 -61.4172) (xy 81.825084 -61.63818)
			(xy 81.995264 -61.72708) (xy 82.039714 -61.72708)
		)
		(stroke
			(width 0)
			(type solid)
		)
		(fill yes)
		(layer "In11.Cu")
		(net "M_J_DQ<28>")
	)
	(gr_poly
		(pts
			(xy 82.039714 -60.3377) (xy 81.995264 -60.3377) (xy 81.825084 -60.4266) (xy 81.825084 -60.64758)
			(xy 81.995264 -60.73648) (xy 82.039714 -60.73648)
		)
		(stroke
			(width 0)
			(type solid)
		)
		(fill yes)
		(layer "In11.Cu")
		(net "M_J_DQ<28>")
	)
	(gr_poly
		(pts
			(xy 82.039714 -59.3471) (xy 81.995264 -59.3471) (xy 81.825084 -59.436) (xy 81.825084 -59.65698) (xy 81.995264 -59.74588)
			(xy 82.039714 -59.74588)
		)
		(stroke
			(width 0)
			(type solid)
		)
		(fill yes)
		(layer "In11.Cu")
		(net "M_J_DQ<28>")
	)
	(gr_poly
		(pts
			(xy 82.039714 -58.368946) (xy 81.995264 -58.368946) (xy 81.825084 -58.457846) (xy 81.825084 -58.678826)
			(xy 81.995264 -58.767726) (xy 82.039714 -58.767726)
		)
		(stroke
			(width 0)
			(type solid)
		)
		(fill yes)
		(layer "In11.Cu")
		(net "M_J_DQ<28>")
	)
	(gr_poly
		(pts
			(xy 82.039714 -57.37225) (xy 81.995264 -57.37225) (xy 81.825084 -57.46115) (xy 81.825084 -57.68213)
			(xy 81.995264 -57.77103) (xy 82.039714 -57.77103)
		)
		(stroke
			(width 0)
			(type solid)
		)
		(fill yes)
		(layer "In11.Cu")
		(net "M_J_DQ<28>")
	)
	(gr_poly
		(pts
			(xy 82.039714 -56.3753) (xy 81.995264 -56.3753) (xy 81.825084 -56.4642) (xy 81.825084 -56.68518)
			(xy 81.995264 -56.77408) (xy 82.039714 -56.77408)
		)
		(stroke
			(width 0)
			(type solid)
		)
		(fill yes)
		(layer "In11.Cu")
		(net "M_J_DQ<28>")
	)
	(gr_poly
		(pts
			(xy 82.091784 -97.448624) (xy 82.13344 -97.261172) (xy 82.122264 -97.217992) (xy 81.736692 -97.32137)
			(xy 81.74863 -97.364296) (xy 81.878424 -97.50552)
		)
		(stroke
			(width 0)
			(type solid)
		)
		(fill yes)
		(layer "In11.Cu")
		(net "M_M_DQ<25>")
	)
	(gr_poly
		(pts
			(xy 82.180938 -52.440586) (xy 82.212434 -52.409344) (xy 81.924906 -52.121816) (xy 81.893664 -52.153312)
			(xy 81.820004 -52.352702) (xy 81.981548 -52.514246)
		)
		(stroke
			(width 0)
			(type solid)
		)
		(fill yes)
		(layer "In11.Cu")
		(net "M_J_DQS_DP<12>")
	)
	(gr_poly
		(pts
			(xy 82.262218 -54.3687) (xy 82.217768 -54.3687) (xy 82.024728 -54.4576) (xy 82.024728 -54.6862) (xy 82.217768 -54.7751)
			(xy 82.262218 -54.7751)
		)
		(stroke
			(width 0)
			(type solid)
		)
		(fill yes)
		(layer "In11.Cu")
		(net "M_J_DQ<24>")
	)
	(gr_poly
		(pts
			(xy 82.268568 -98.26244) (xy 82.194908 -98.06305) (xy 82.163412 -98.031808) (xy 81.876138 -98.319082)
			(xy 81.907634 -98.350578) (xy 82.107024 -98.424238)
		)
		(stroke
			(width 0)
			(type solid)
		)
		(fill yes)
		(layer "In11.Cu")
		(net "M_M_DQS_DN<12>")
	)
	(gr_poly
		(pts
			(xy 82.279998 -95.355664) (xy 82.272124 -95.163894) (xy 82.250026 -95.12554) (xy 81.904586 -95.32493)
			(xy 81.926684 -95.363284) (xy 82.088736 -95.466154)
		)
		(stroke
			(width 0)
			(type solid)
		)
		(fill yes)
		(layer "In11.Cu")
		(net "M_M_DQ<29>")
	)
	(gr_poly
		(pts
			(xy 82.388456 -99.406456) (xy 82.35696 -99.375214) (xy 82.15757 -99.301554) (xy 81.996026 -99.463098)
			(xy 82.069686 -99.662488) (xy 82.100928 -99.693984)
		)
		(stroke
			(width 0)
			(type solid)
		)
		(fill yes)
		(layer "In11.Cu")
		(net "M_M_DQS_DN<3>")
	)
	(gr_poly
		(pts
			(xy 82.40776 -96.894904) (xy 82.577686 -96.806004) (xy 82.57794 -96.585278) (xy 82.40776 -96.496378)
			(xy 82.363056 -96.496124) (xy 82.363056 -96.895158)
		)
		(stroke
			(width 0)
			(type solid)
		)
		(fill yes)
		(layer "In11.Cu")
		(net "M_M_DQ<25>")
	)
	(gr_poly
		(pts
			(xy 82.504026 -95.595694) (xy 82.481674 -95.55734) (xy 82.319876 -95.45447) (xy 82.12836 -95.564706)
			(xy 82.136488 -95.756476) (xy 82.15884 -95.795338)
		)
		(stroke
			(width 0)
			(type solid)
		)
		(fill yes)
		(layer "In11.Cu")
		(net "M_M_DQ<24>")
	)
	(gr_poly
		(pts
			(xy 82.504026 -91.633294) (xy 82.481674 -91.59494) (xy 82.319876 -91.49207) (xy 82.12836 -91.602306)
			(xy 82.136488 -91.794076) (xy 82.15884 -91.832938)
		)
		(stroke
			(width 0)
			(type solid)
		)
		(fill yes)
		(layer "In11.Cu")
		(net "M_M_DQ<28>")
	)
	(gr_poly
		(pts
			(xy 82.53095 -52.395374) (xy 82.60461 -52.196238) (xy 82.442812 -52.03444) (xy 82.243676 -52.1081)
			(xy 82.21218 -52.139596) (xy 82.499454 -52.42687)
		)
		(stroke
			(width 0)
			(type solid)
		)
		(fill yes)
		(layer "In11.Cu")
		(net "M_J_DQS_DN<12>")
	)
	(gr_poly
		(pts
			(xy 82.577686 -94.818454) (xy 82.577686 -94.597474) (xy 82.407506 -94.508574) (xy 82.36331 -94.508574)
			(xy 82.36331 -94.907354) (xy 82.407506 -94.907354)
		)
		(stroke
			(width 0)
			(type solid)
		)
		(fill yes)
		(layer "In11.Cu")
		(net "M_M_DQ<29>")
	)
	(gr_poly
		(pts
			(xy 82.57794 -93.83268) (xy 82.57794 -93.6117) (xy 82.40776 -93.5228) (xy 82.36331 -93.5228) (xy 82.36331 -93.92158)
			(xy 82.40776 -93.92158)
		)
		(stroke
			(width 0)
			(type solid)
		)
		(fill yes)
		(layer "In11.Cu")
		(net "M_M_DQ<29>")
	)
	(gr_poly
		(pts
			(xy 82.57794 -92.854526) (xy 82.57794 -92.633546) (xy 82.40776 -92.544646) (xy 82.36331 -92.544646)
			(xy 82.36331 -92.943426) (xy 82.40776 -92.943426)
		)
		(stroke
			(width 0)
			(type solid)
		)
		(fill yes)
		(layer "In11.Cu")
		(net "M_M_DQ<29>")
	)
	(gr_poly
		(pts
			(xy 82.57794 -64.127126) (xy 82.57794 -63.906146) (xy 82.40776 -63.817246) (xy 82.36331 -63.817246)
			(xy 82.36331 -64.216026) (xy 82.40776 -64.216026)
		)
		(stroke
			(width 0)
			(type solid)
		)
		(fill yes)
		(layer "In11.Cu")
		(net "M_J_DQ<29>")
	)
	(gr_poly
		(pts
			(xy 82.57794 -63.136526) (xy 82.57794 -62.915546) (xy 82.40776 -62.826646) (xy 82.36331 -62.826646)
			(xy 82.36331 -63.225426) (xy 82.40776 -63.225426)
		)
		(stroke
			(width 0)
			(type solid)
		)
		(fill yes)
		(layer "In11.Cu")
		(net "M_J_DQ<29>")
	)
	(gr_poly
		(pts
			(xy 82.57794 -62.145926) (xy 82.57794 -61.924946) (xy 82.40776 -61.836046) (xy 82.36331 -61.836046)
			(xy 82.36331 -62.234826) (xy 82.40776 -62.234826)
		)
		(stroke
			(width 0)
			(type solid)
		)
		(fill yes)
		(layer "In11.Cu")
		(net "M_J_DQ<29>")
	)
	(gr_poly
		(pts
			(xy 82.57794 -61.155326) (xy 82.57794 -60.934346) (xy 82.40776 -60.845446) (xy 82.36331 -60.845446)
			(xy 82.36331 -61.244226) (xy 82.40776 -61.244226)
		)
		(stroke
			(width 0)
			(type solid)
		)
		(fill yes)
		(layer "In11.Cu")
		(net "M_J_DQ<29>")
	)
	(gr_poly
		(pts
			(xy 82.57794 -60.164726) (xy 82.57794 -59.943746) (xy 82.40776 -59.854846) (xy 82.36331 -59.854846)
			(xy 82.36331 -60.253626) (xy 82.40776 -60.253626)
		)
		(stroke
			(width 0)
			(type solid)
		)
		(fill yes)
		(layer "In11.Cu")
		(net "M_J_DQ<29>")
	)
	(gr_poly
		(pts
			(xy 82.57794 -59.167776) (xy 82.57794 -58.946796) (xy 82.40776 -58.857896) (xy 82.36331 -58.857896)
			(xy 82.36331 -59.256676) (xy 82.40776 -59.256676)
		)
		(stroke
			(width 0)
			(type solid)
		)
		(fill yes)
		(layer "In11.Cu")
		(net "M_J_DQ<29>")
	)
	(gr_poly
		(pts
			(xy 82.57794 -58.17108) (xy 82.57794 -57.9501) (xy 82.40776 -57.8612) (xy 82.36331 -57.8612) (xy 82.36331 -58.25998)
			(xy 82.40776 -58.25998)
		)
		(stroke
			(width 0)
			(type solid)
		)
		(fill yes)
		(layer "In11.Cu")
		(net "M_J_DQ<29>")
	)
	(gr_poly
		(pts
			(xy 82.57794 -57.192926) (xy 82.57794 -56.971946) (xy 82.40776 -56.883046) (xy 82.36331 -56.883046)
			(xy 82.36331 -57.281826) (xy 82.40776 -57.281826)
		)
		(stroke
			(width 0)
			(type solid)
		)
		(fill yes)
		(layer "In11.Cu")
		(net "M_J_DQ<29>")
	)
	(gr_poly
		(pts
			(xy 82.57794 -56.195976) (xy 82.57794 -55.974996) (xy 82.40776 -55.886096) (xy 82.36331 -55.886096)
			(xy 82.36331 -56.284876) (xy 82.40776 -56.284876)
		)
		(stroke
			(width 0)
			(type solid)
		)
		(fill yes)
		(layer "In11.Cu")
		(net "M_J_DQ<29>")
	)
	(gr_poly
		(pts
			(xy 82.628232 -99.771962) (xy 82.554572 -99.572826) (xy 82.523076 -99.54133) (xy 82.235802 -99.828604)
			(xy 82.267298 -99.8601) (xy 82.466434 -99.93376)
		)
		(stroke
			(width 0)
			(type solid)
		)
		(fill yes)
		(layer "In11.Cu")
		(net "M_M_DQS_DP<3>")
	)
	(gr_poly
		(pts
			(xy 82.690208 -54.651402) (xy 82.690208 -54.422802) (xy 82.496914 -54.333902) (xy 82.452718 -54.333648)
			(xy 82.452718 -54.740302) (xy 82.496914 -54.740302)
		)
		(stroke
			(width 0)
			(type solid)
		)
		(fill yes)
		(layer "In11.Cu")
		(net "M_J_DQ<25>")
	)
	(gr_poly
		(pts
			(xy 82.691478 -55.46725) (xy 82.722974 -55.435754) (xy 82.435446 -55.14848) (xy 82.404204 -55.179976)
			(xy 82.330544 -55.379112) (xy 82.492088 -55.54091)
		)
		(stroke
			(width 0)
			(type solid)
		)
		(fill yes)
		(layer "In11.Cu")
		(net "M_J_DQ<24>")
	)
	(gr_poly
		(pts
			(xy 82.71256 -102.044246) (xy 82.681064 -102.013004) (xy 82.481674 -101.939344) (xy 82.32013 -102.100888)
			(xy 82.39379 -102.300278) (xy 82.425032 -102.331774)
		)
		(stroke
			(width 0)
			(type solid)
		)
		(fill yes)
		(layer "In11.Cu")
		(net "M_M_DQ<30>")
	)
	(gr_poly
		(pts
			(xy 82.729324 -97.196402) (xy 82.697828 -97.16516) (xy 82.498438 -97.0915) (xy 82.336894 -97.253044)
			(xy 82.410554 -97.452434) (xy 82.441796 -97.48393)
		)
		(stroke
			(width 0)
			(type solid)
		)
		(fill yes)
		(layer "In11.Cu")
		(net "M_M_DQS_DP<12>")
	)
	(gr_poly
		(pts
			(xy 82.747104 -50.419762) (xy 82.702654 -50.420016) (xy 82.509614 -50.508916) (xy 82.509614 -50.737262)
			(xy 82.702654 -50.826162) (xy 82.747104 -50.826416)
		)
		(stroke
			(width 0)
			(type solid)
		)
		(fill yes)
		(layer "In11.Cu")
		(net "M_J_DQS_DP<3>")
	)
	(gr_poly
		(pts
			(xy 82.8294 -100.92944) (xy 82.78495 -100.92944) (xy 82.59191 -101.01834) (xy 82.59191 -101.24694)
			(xy 82.78495 -101.33584) (xy 82.8294 -101.33584)
		)
		(stroke
			(width 0)
			(type solid)
		)
		(fill yes)
		(layer "In11.Cu")
		(net "M_M_DQ<30>")
	)
	(gr_poly
		(pts
			(xy 82.89417 -55.70601) (xy 82.84972 -55.70601) (xy 82.67954 -55.79491) (xy 82.67954 -56.01589) (xy 82.84972 -56.10479)
			(xy 82.89417 -56.10479)
		)
		(stroke
			(width 0)
			(type solid)
		)
		(fill yes)
		(layer "In11.Cu")
		(net "M_J_DQ<24>")
	)
	(gr_poly
		(pts
			(xy 82.898234 -94.519496) (xy 82.853784 -94.519496) (xy 82.683604 -94.608396) (xy 82.683604 -94.829376)
			(xy 82.853784 -94.918276) (xy 82.898234 -94.918276)
		)
		(stroke
			(width 0)
			(type solid)
		)
		(fill yes)
		(layer "In11.Cu")
		(net "M_M_DQ<24>")
	)
	(gr_poly
		(pts
			(xy 82.898234 -93.5228) (xy 82.853784 -93.5228) (xy 82.683604 -93.6117) (xy 82.683604 -93.83268)
			(xy 82.853784 -93.92158) (xy 82.898234 -93.92158)
		)
		(stroke
			(width 0)
			(type solid)
		)
		(fill yes)
		(layer "In11.Cu")
		(net "M_M_DQ<24>")
	)
	(gr_poly
		(pts
			(xy 82.898234 -90.563446) (xy 82.853784 -90.563446) (xy 82.683604 -90.652346) (xy 82.683604 -90.873326)
			(xy 82.853784 -90.962226) (xy 82.898234 -90.962226)
		)
		(stroke
			(width 0)
			(type solid)
		)
		(fill yes)
		(layer "In11.Cu")
		(net "M_M_DQ<28>")
	)
	(gr_poly
		(pts
			(xy 82.898234 -89.572846) (xy 82.853784 -89.572846) (xy 82.683604 -89.661746) (xy 82.683604 -89.882726)
			(xy 82.853784 -89.971626) (xy 82.898234 -89.971626)
		)
		(stroke
			(width 0)
			(type solid)
		)
		(fill yes)
		(layer "In11.Cu")
		(net "M_M_DQ<28>")
	)
	(gr_poly
		(pts
			(xy 82.898234 -88.582246) (xy 82.853784 -88.582246) (xy 82.683604 -88.671146) (xy 82.683604 -88.892126)
			(xy 82.853784 -88.981026) (xy 82.898234 -88.981026)
		)
		(stroke
			(width 0)
			(type solid)
		)
		(fill yes)
		(layer "In11.Cu")
		(net "M_M_DQ<28>")
	)
	(gr_poly
		(pts
			(xy 82.898234 -87.591646) (xy 82.853784 -87.591646) (xy 82.683604 -87.680546) (xy 82.683604 -87.901526)
			(xy 82.853784 -87.990426) (xy 82.898234 -87.990426)
		)
		(stroke
			(width 0)
			(type solid)
		)
		(fill yes)
		(layer "In11.Cu")
		(net "M_M_DQ<28>")
	)
	(gr_poly
		(pts
			(xy 82.898234 -86.601046) (xy 82.853784 -86.601046) (xy 82.683604 -86.689946) (xy 82.683604 -86.910926)
			(xy 82.853784 -86.999826) (xy 82.898234 -86.999826)
		)
		(stroke
			(width 0)
			(type solid)
		)
		(fill yes)
		(layer "In11.Cu")
		(net "M_M_DQ<28>")
	)
	(gr_poly
		(pts
			(xy 82.898234 -63.81115) (xy 82.853784 -63.81115) (xy 82.683604 -63.90005) (xy 82.683604 -64.12103)
			(xy 82.853784 -64.20993) (xy 82.898234 -64.20993)
		)
		(stroke
			(width 0)
			(type solid)
		)
		(fill yes)
		(layer "In11.Cu")
		(net "M_J_DQ<24>")
	)
	(gr_poly
		(pts
			(xy 82.898234 -62.826646) (xy 82.853784 -62.826646) (xy 82.683604 -62.915546) (xy 82.683604 -63.136526)
			(xy 82.853784 -63.225426) (xy 82.898234 -63.225426)
		)
		(stroke
			(width 0)
			(type solid)
		)
		(fill yes)
		(layer "In11.Cu")
		(net "M_J_DQ<24>")
	)
	(gr_poly
		(pts
			(xy 82.898234 -61.836046) (xy 82.853784 -61.836046) (xy 82.683604 -61.924946) (xy 82.683604 -62.145926)
			(xy 82.853784 -62.234826) (xy 82.898234 -62.234826)
		)
		(stroke
			(width 0)
			(type solid)
		)
		(fill yes)
		(layer "In11.Cu")
		(net "M_J_DQ<24>")
	)
	(gr_poly
		(pts
			(xy 82.898234 -60.845446) (xy 82.853784 -60.845446) (xy 82.683604 -60.934346) (xy 82.683604 -61.155326)
			(xy 82.853784 -61.244226) (xy 82.898234 -61.244226)
		)
		(stroke
			(width 0)
			(type solid)
		)
		(fill yes)
		(layer "In11.Cu")
		(net "M_J_DQ<24>")
	)
	(gr_poly
		(pts
			(xy 82.898234 -59.854846) (xy 82.853784 -59.854846) (xy 82.683604 -59.943746) (xy 82.683604 -60.164726)
			(xy 82.853784 -60.253626) (xy 82.898234 -60.253626)
		)
		(stroke
			(width 0)
			(type solid)
		)
		(fill yes)
		(layer "In11.Cu")
		(net "M_J_DQ<24>")
	)
	(gr_poly
		(pts
			(xy 82.898234 -58.857896) (xy 82.853784 -58.857896) (xy 82.683604 -58.946796) (xy 82.683604 -59.167776)
			(xy 82.853784 -59.256676) (xy 82.898234 -59.256676)
		)
		(stroke
			(width 0)
			(type solid)
		)
		(fill yes)
		(layer "In11.Cu")
		(net "M_J_DQ<24>")
	)
	(gr_poly
		(pts
			(xy 82.898234 -57.8612) (xy 82.853784 -57.8612) (xy 82.683604 -57.9501) (xy 82.683604 -58.17108)
			(xy 82.853784 -58.25998) (xy 82.898234 -58.25998)
		)
		(stroke
			(width 0)
			(type solid)
		)
		(fill yes)
		(layer "In11.Cu")
		(net "M_J_DQ<24>")
	)
	(gr_poly
		(pts
			(xy 82.898234 -56.883046) (xy 82.853784 -56.883046) (xy 82.683604 -56.971946) (xy 82.683604 -57.192926)
			(xy 82.853784 -57.281826) (xy 82.898234 -57.281826)
		)
		(stroke
			(width 0)
			(type solid)
		)
		(fill yes)
		(layer "In11.Cu")
		(net "M_J_DQ<24>")
	)
	(gr_poly
		(pts
			(xy 82.898488 -92.53855) (xy 82.854038 -92.53855) (xy 82.683858 -92.62745) (xy 82.683858 -92.84843)
			(xy 82.854038 -92.93733) (xy 82.898488 -92.93733)
		)
		(stroke
			(width 0)
			(type solid)
		)
		(fill yes)
		(layer "In11.Cu")
		(net "M_M_DQ<24>")
	)
	(gr_poly
		(pts
			(xy 82.917538 -53.177186) (xy 82.949034 -53.145944) (xy 82.661506 -52.858416) (xy 82.630264 -52.889912)
			(xy 82.556604 -53.089302) (xy 82.718148 -53.250846)
		)
		(stroke
			(width 0)
			(type solid)
		)
		(fill yes)
		(layer "In11.Cu")
		(net "M_J_DQS_DP<12>")
	)
	(gr_poly
		(pts
			(xy 82.943446 -55.324502) (xy 83.017106 -55.125366) (xy 82.855308 -54.963568) (xy 82.656172 -55.037228)
			(xy 82.624676 -55.068724) (xy 82.91195 -55.355998)
		)
		(stroke
			(width 0)
			(type solid)
		)
		(fill yes)
		(layer "In11.Cu")
		(net "M_J_DQ<25>")
	)
	(gr_poly
		(pts
			(xy 82.9691 -97.561908) (xy 82.89544 -97.362772) (xy 82.863944 -97.331276) (xy 82.57667 -97.61855)
			(xy 82.608166 -97.650046) (xy 82.807302 -97.723706)
		)
		(stroke
			(width 0)
			(type solid)
		)
		(fill yes)
		(layer "In11.Cu")
		(net "M_M_DQS_DN<12>")
	)
	(gr_poly
		(pts
			(xy 82.982562 -102.389432) (xy 82.908902 -102.190042) (xy 82.87766 -102.158546) (xy 82.590132 -102.446074)
			(xy 82.621628 -102.477316) (xy 82.821018 -102.550976)
		)
		(stroke
			(width 0)
			(type solid)
		)
		(fill yes)
		(layer "In11.Cu")
		(net "M_M_DQ<31>")
	)
	(gr_poly
		(pts
			(xy 83.088734 -98.706178) (xy 83.057492 -98.674682) (xy 82.858102 -98.601022) (xy 82.696304 -98.762566)
			(xy 82.769964 -98.961956) (xy 82.80146 -98.993452)
		)
		(stroke
			(width 0)
			(type solid)
		)
		(fill yes)
		(layer "In11.Cu")
		(net "M_M_DQS_DN<3>")
	)
	(gr_poly
		(pts
			(xy 83.120992 -53.862224) (xy 83.076542 -53.862224) (xy 82.883502 -53.951124) (xy 82.883502 -54.179724)
			(xy 83.076542 -54.268624) (xy 83.120992 -54.268624)
		)
		(stroke
			(width 0)
			(type solid)
		)
		(fill yes)
		(layer "In11.Cu")
		(net "M_J_DQS_DP<12>")
	)
	(gr_poly
		(pts
			(xy 83.13674 -95.852488) (xy 83.128612 -95.660464) (xy 83.106514 -95.621856) (xy 82.761328 -95.8215)
			(xy 82.783426 -95.859854) (xy 82.945478 -95.962724)
		)
		(stroke
			(width 0)
			(type solid)
		)
		(fill yes)
		(layer "In11.Cu")
		(net "M_M_DQ<25>")
	)
	(gr_poly
		(pts
			(xy 83.13674 -91.890088) (xy 83.128612 -91.698064) (xy 83.106514 -91.659456) (xy 82.761328 -91.8591)
			(xy 82.783426 -91.897454) (xy 82.945478 -92.000324)
		)
		(stroke
			(width 0)
			(type solid)
		)
		(fill yes)
		(layer "In11.Cu")
		(net "M_M_DQ<29>")
	)
	(gr_poly
		(pts
			(xy 83.166204 -100.00107) (xy 83.134708 -99.969574) (xy 82.935318 -99.895914) (xy 82.773774 -100.057712)
			(xy 82.847434 -100.257102) (xy 82.87893 -100.288344)
		)
		(stroke
			(width 0)
			(type solid)
		)
		(fill yes)
		(layer "In11.Cu")
		(net "M_M_DQ<30>")
	)
	(gr_poly
		(pts
			(xy 83.17484 -51.307492) (xy 83.17484 -51.078638) (xy 82.9818 -50.989992) (xy 82.93735 -50.989992)
			(xy 82.93735 -51.396138) (xy 82.9818 -51.396138)
		)
		(stroke
			(width 0)
			(type solid)
		)
		(fill yes)
		(layer "In11.Cu")
		(net "M_J_DQS_DN<3>")
	)
	(gr_poly
		(pts
			(xy 83.24215 -53.106574) (xy 83.31581 -52.907438) (xy 83.154012 -52.74564) (xy 82.954876 -52.8193)
			(xy 82.92338 -52.850796) (xy 83.210654 -53.13807)
		)
		(stroke
			(width 0)
			(type solid)
		)
		(fill yes)
		(layer "In11.Cu")
		(net "M_J_DQS_DN<12>")
	)
	(gr_poly
		(pts
			(xy 83.256882 -101.24694) (xy 83.256882 -101.01834) (xy 83.063842 -100.92944) (xy 83.019392 -100.92944)
			(xy 83.019392 -101.33584) (xy 83.063842 -101.33584)
		)
		(stroke
			(width 0)
			(type solid)
		)
		(fill yes)
		(layer "In11.Cu")
		(net "M_M_DQ<31>")
	)
	(gr_poly
		(pts
			(xy 83.275678 -64.835278) (xy 83.312 -64.809878) (xy 83.0834 -64.483234) (xy 83.046824 -64.508634)
			(xy 82.958432 -64.679068) (xy 83.085178 -64.86017)
		)
		(stroke
			(width 0)
			(type solid)
		)
		(fill yes)
		(layer "In11.Cu")
		(net "M_J_DQ<24>")
	)
	(gr_poly
		(pts
			(xy 83.328764 -99.071684) (xy 83.255104 -98.872294) (xy 83.223608 -98.840798) (xy 82.936334 -99.128072)
			(xy 82.967576 -99.159568) (xy 83.166966 -99.233228)
		)
		(stroke
			(width 0)
			(type solid)
		)
		(fill yes)
		(layer "In11.Cu")
		(net "M_M_DQS_DP<3>")
	)
	(gr_poly
		(pts
			(xy 83.357212 -66.682112) (xy 83.196938 -66.31686) (xy 83.156298 -66.33464) (xy 83.036156 -66.4845)
			(xy 83.124802 -66.686684) (xy 83.316572 -66.700146)
		)
		(stroke
			(width 0)
			(type solid)
		)
		(fill yes)
		(layer "In11.Cu")
		(net "M_J_DQ<25>")
	)
	(gr_poly
		(pts
			(xy 83.366356 -92.126562) (xy 83.344004 -92.087954) (xy 83.181952 -91.985084) (xy 82.99069 -92.095574)
			(xy 82.998818 -92.287344) (xy 83.020916 -92.325952)
		)
		(stroke
			(width 0)
			(type solid)
		)
		(fill yes)
		(layer "In11.Cu")
		(net "M_M_DQ<24>")
	)
	(gr_poly
		(pts
			(xy 83.405726 -100.366322) (xy 83.332066 -100.166932) (xy 83.30057 -100.135436) (xy 83.013296 -100.42271)
			(xy 83.044538 -100.454206) (xy 83.243928 -100.527866)
		)
		(stroke
			(width 0)
			(type solid)
		)
		(fill yes)
		(layer "In11.Cu")
		(net "M_M_DQ<31>")
	)
	(gr_poly
		(pts
			(xy 83.429602 -96.496124) (xy 83.39836 -96.464628) (xy 83.19897 -96.390968) (xy 83.037172 -96.552512)
			(xy 83.110832 -96.751902) (xy 83.142328 -96.783398)
		)
		(stroke
			(width 0)
			(type solid)
		)
		(fill yes)
		(layer "In11.Cu")
		(net "M_M_DQS_DP<12>")
	)
	(gr_poly
		(pts
			(xy 83.436206 -95.31604) (xy 83.436206 -95.095314) (xy 83.266026 -95.006414) (xy 83.221576 -95.00616)
			(xy 83.22183 -95.40494) (xy 83.266026 -95.40494)
		)
		(stroke
			(width 0)
			(type solid)
		)
		(fill yes)
		(layer "In11.Cu")
		(net "M_M_DQ<25>")
	)
	(gr_poly
		(pts
			(xy 83.436206 -93.343984) (xy 83.436206 -93.123004) (xy 83.266026 -93.034104) (xy 83.221576 -93.034104)
			(xy 83.221576 -93.432884) (xy 83.266026 -93.432884)
		)
		(stroke
			(width 0)
			(type solid)
		)
		(fill yes)
		(layer "In11.Cu")
		(net "M_M_DQ<25>")
	)
	(gr_poly
		(pts
			(xy 83.436206 -91.35364) (xy 83.436206 -91.132914) (xy 83.266026 -91.044014) (xy 83.221576 -91.04376)
			(xy 83.22183 -91.44254) (xy 83.266026 -91.44254)
		)
		(stroke
			(width 0)
			(type solid)
		)
		(fill yes)
		(layer "In11.Cu")
		(net "M_M_DQ<29>")
	)
	(gr_poly
		(pts
			(xy 83.436206 -63.62573) (xy 83.436206 -63.40475) (xy 83.266026 -63.31585) (xy 83.221576 -63.31585)
			(xy 83.221576 -63.71463) (xy 83.266026 -63.71463)
		)
		(stroke
			(width 0)
			(type solid)
		)
		(fill yes)
		(layer "In11.Cu")
		(net "M_J_DQ<25>")
	)
	(gr_poly
		(pts
			(xy 83.43646 -94.340426) (xy 83.43646 -94.119446) (xy 83.26628 -94.030546) (xy 83.22183 -94.030546)
			(xy 83.22183 -94.429326) (xy 83.26628 -94.429326)
		)
		(stroke
			(width 0)
			(type solid)
		)
		(fill yes)
		(layer "In11.Cu")
		(net "M_M_DQ<25>")
	)
	(gr_poly
		(pts
			(xy 83.43646 -90.36558) (xy 83.43646 -90.1446) (xy 83.26628 -90.0557) (xy 83.22183 -90.0557) (xy 83.22183 -90.45448)
			(xy 83.26628 -90.45448)
		)
		(stroke
			(width 0)
			(type solid)
		)
		(fill yes)
		(layer "In11.Cu")
		(net "M_M_DQ<29>")
	)
	(gr_poly
		(pts
			(xy 83.43646 -89.37498) (xy 83.43646 -89.154) (xy 83.26628 -89.0651) (xy 83.22183 -89.0651) (xy 83.22183 -89.46388)
			(xy 83.26628 -89.46388)
		)
		(stroke
			(width 0)
			(type solid)
		)
		(fill yes)
		(layer "In11.Cu")
		(net "M_M_DQ<29>")
	)
	(gr_poly
		(pts
			(xy 83.43646 -88.38438) (xy 83.43646 -88.1634) (xy 83.26628 -88.0745) (xy 83.22183 -88.0745) (xy 83.22183 -88.47328)
			(xy 83.26628 -88.47328)
		)
		(stroke
			(width 0)
			(type solid)
		)
		(fill yes)
		(layer "In11.Cu")
		(net "M_M_DQ<29>")
	)
	(gr_poly
		(pts
			(xy 83.43646 -62.62878) (xy 83.43646 -62.4078) (xy 83.26628 -62.3189) (xy 83.22183 -62.3189) (xy 83.22183 -62.71768)
			(xy 83.26628 -62.71768)
		)
		(stroke
			(width 0)
			(type solid)
		)
		(fill yes)
		(layer "In11.Cu")
		(net "M_J_DQ<25>")
	)
	(gr_poly
		(pts
			(xy 83.43646 -61.63818) (xy 83.43646 -61.4172) (xy 83.26628 -61.3283) (xy 83.22183 -61.3283) (xy 83.22183 -61.72708)
			(xy 83.26628 -61.72708)
		)
		(stroke
			(width 0)
			(type solid)
		)
		(fill yes)
		(layer "In11.Cu")
		(net "M_J_DQ<25>")
	)
	(gr_poly
		(pts
			(xy 83.43646 -60.64758) (xy 83.43646 -60.4266) (xy 83.26628 -60.3377) (xy 83.22183 -60.3377) (xy 83.22183 -60.73648)
			(xy 83.26628 -60.73648)
		)
		(stroke
			(width 0)
			(type solid)
		)
		(fill yes)
		(layer "In11.Cu")
		(net "M_J_DQ<25>")
	)
	(gr_poly
		(pts
			(xy 83.43646 -59.65698) (xy 83.43646 -59.436) (xy 83.26628 -59.3471) (xy 83.22183 -59.3471) (xy 83.22183 -59.74588)
			(xy 83.26628 -59.74588)
		)
		(stroke
			(width 0)
			(type solid)
		)
		(fill yes)
		(layer "In11.Cu")
		(net "M_J_DQ<25>")
	)
	(gr_poly
		(pts
			(xy 83.43646 -58.678826) (xy 83.43646 -58.457846) (xy 83.26628 -58.368946) (xy 83.22183 -58.368946)
			(xy 83.22183 -58.767726) (xy 83.26628 -58.767726)
		)
		(stroke
			(width 0)
			(type solid)
		)
		(fill yes)
		(layer "In11.Cu")
		(net "M_J_DQ<25>")
	)
	(gr_poly
		(pts
			(xy 83.43646 -57.68213) (xy 83.43646 -57.46115) (xy 83.26628 -57.37225) (xy 83.22183 -57.37225) (xy 83.22183 -57.77103)
			(xy 83.26628 -57.77103)
		)
		(stroke
			(width 0)
			(type solid)
		)
		(fill yes)
		(layer "In11.Cu")
		(net "M_J_DQ<25>")
	)
	(gr_poly
		(pts
			(xy 83.43646 -56.68518) (xy 83.43646 -56.4642) (xy 83.26628 -56.3753) (xy 83.22183 -56.3753) (xy 83.22183 -56.77408)
			(xy 83.26628 -56.77408)
		)
		(stroke
			(width 0)
			(type solid)
		)
		(fill yes)
		(layer "In11.Cu")
		(net "M_J_DQ<25>")
	)
	(gr_poly
		(pts
			(xy 83.47075 -50.56632) (xy 83.4263 -50.56632) (xy 83.23326 -50.654966) (xy 83.23326 -50.88382) (xy 83.4263 -50.972466)
			(xy 83.47075 -50.972466)
		)
		(stroke
			(width 0)
			(type solid)
		)
		(fill yes)
		(layer "In11.Cu")
		(net "M_J_DQ<30>")
	)
	(gr_poly
		(pts
			(xy 83.505548 -52.575968) (xy 83.537044 -52.544726) (xy 83.249516 -52.257198) (xy 83.218274 -52.288694)
			(xy 83.144614 -52.488084) (xy 83.306158 -52.649628)
		)
		(stroke
			(width 0)
			(type solid)
		)
		(fill yes)
		(layer "In11.Cu")
		(net "M_J_DQS_DP<3>")
	)
	(gr_poly
		(pts
			(xy 83.548982 -54.306724) (xy 83.548982 -54.078124) (xy 83.355942 -53.989224) (xy 83.311492 -53.989224)
			(xy 83.311492 -54.395624) (xy 83.355942 -54.395624)
		)
		(stroke
			(width 0)
			(type solid)
		)
		(fill yes)
		(layer "In11.Cu")
		(net "M_J_DQS_DN<12>")
	)
	(gr_poly
		(pts
			(xy 83.616292 -97.651062) (xy 83.571842 -97.651062) (xy 83.378802 -97.739962) (xy 83.378802 -97.968562)
			(xy 83.571842 -98.057462) (xy 83.616292 -98.057462)
		)
		(stroke
			(width 0)
			(type solid)
		)
		(fill yes)
		(layer "In11.Cu")
		(net "M_M_DQS_DN<3>")
	)
	(gr_poly
		(pts
			(xy 83.63585 -55.6133) (xy 83.674458 -55.590948) (xy 83.475068 -55.245762) (xy 83.43646 -55.26786)
			(xy 83.33359 -55.429912) (xy 83.44408 -55.621428)
		)
		(stroke
			(width 0)
			(type solid)
		)
		(fill yes)
		(layer "In11.Cu")
		(net "M_J_DQS_DP<12>")
	)
	(gr_poly
		(pts
			(xy 83.669632 -96.86163) (xy 83.595972 -96.66224) (xy 83.564476 -96.630744) (xy 83.277202 -96.918018)
			(xy 83.308444 -96.949514) (xy 83.507834 -97.023174)
		)
		(stroke
			(width 0)
			(type solid)
		)
		(fill yes)
		(layer "In11.Cu")
		(net "M_M_DQS_DN<12>")
	)
	(gr_poly
		(pts
			(xy 83.70316 -52.378356) (xy 83.77682 -52.17922) (xy 83.615022 -52.017422) (xy 83.415886 -52.091082)
			(xy 83.38439 -52.122578) (xy 83.671664 -52.409852)
		)
		(stroke
			(width 0)
			(type solid)
		)
		(fill yes)
		(layer "In11.Cu")
		(net "M_J_DQS_DN<3>")
	)
	(gr_poly
		(pts
			(xy 83.705192 -101.500432) (xy 83.660742 -101.500432) (xy 83.467702 -101.589332) (xy 83.467702 -101.817932)
			(xy 83.660742 -101.906832) (xy 83.705192 -101.906832)
		)
		(stroke
			(width 0)
			(type solid)
		)
		(fill yes)
		(layer "In11.Cu")
		(net "M_M_DQ<26>")
	)
	(gr_poly
		(pts
			(xy 83.756754 -95.0087) (xy 83.712304 -95.0087) (xy 83.542124 -95.0976) (xy 83.542124 -95.31858)
			(xy 83.712304 -95.40748) (xy 83.756754 -95.40748)
		)
		(stroke
			(width 0)
			(type solid)
		)
		(fill yes)
		(layer "In11.Cu")
		(net "M_M_DQS_DP<12>")
	)
	(gr_poly
		(pts
			(xy 83.756754 -94.030546) (xy 83.712304 -94.030546) (xy 83.542124 -94.119446) (xy 83.542124 -94.340426)
			(xy 83.712304 -94.429326) (xy 83.756754 -94.429326)
		)
		(stroke
			(width 0)
			(type solid)
		)
		(fill yes)
		(layer "In11.Cu")
		(net "M_M_DQS_DP<12>")
	)
	(gr_poly
		(pts
			(xy 83.756754 -93.044772) (xy 83.712558 -93.044772) (xy 83.542378 -93.133672) (xy 83.542378 -93.354652)
			(xy 83.712558 -93.443552) (xy 83.757008 -93.443552)
		)
		(stroke
			(width 0)
			(type solid)
		)
		(fill yes)
		(layer "In11.Cu")
		(net "M_M_DQS_DP<12>")
	)
	(gr_poly
		(pts
			(xy 83.756754 -91.052904) (xy 83.712304 -91.052904) (xy 83.542124 -91.141804) (xy 83.542124 -91.362784)
			(xy 83.712304 -91.451684) (xy 83.756754 -91.451684)
		)
		(stroke
			(width 0)
			(type solid)
		)
		(fill yes)
		(layer "In11.Cu")
		(net "M_M_DQ<24>")
	)
	(gr_poly
		(pts
			(xy 83.756754 -90.062304) (xy 83.712304 -90.062304) (xy 83.542124 -90.151204) (xy 83.542124 -90.372184)
			(xy 83.712304 -90.461084) (xy 83.756754 -90.461084)
		)
		(stroke
			(width 0)
			(type solid)
		)
		(fill yes)
		(layer "In11.Cu")
		(net "M_M_DQ<24>")
	)
	(gr_poly
		(pts
			(xy 83.756754 -89.071704) (xy 83.712304 -89.071704) (xy 83.542124 -89.160604) (xy 83.542124 -89.381584)
			(xy 83.712304 -89.470484) (xy 83.756754 -89.470484)
		)
		(stroke
			(width 0)
			(type solid)
		)
		(fill yes)
		(layer "In11.Cu")
		(net "M_M_DQ<24>")
	)
	(gr_poly
		(pts
			(xy 83.756754 -88.081104) (xy 83.712304 -88.081104) (xy 83.542124 -88.170004) (xy 83.542124 -88.390984)
			(xy 83.712304 -88.479884) (xy 83.756754 -88.479884)
		)
		(stroke
			(width 0)
			(type solid)
		)
		(fill yes)
		(layer "In11.Cu")
		(net "M_M_DQ<24>")
	)
	(gr_poly
		(pts
			(xy 83.756754 -87.090504) (xy 83.712304 -87.090504) (xy 83.542124 -87.179404) (xy 83.542124 -87.400384)
			(xy 83.712304 -87.489284) (xy 83.756754 -87.489284)
		)
		(stroke
			(width 0)
			(type solid)
		)
		(fill yes)
		(layer "In11.Cu")
		(net "M_M_DQ<24>")
	)
	(gr_poly
		(pts
			(xy 83.756754 -63.3095) (xy 83.712304 -63.3095) (xy 83.542124 -63.3984) (xy 83.542124 -63.61938)
			(xy 83.712304 -63.70828) (xy 83.756754 -63.70828)
		)
		(stroke
			(width 0)
			(type solid)
		)
		(fill yes)
		(layer "In11.Cu")
		(net "M_J_DQS_DP<12>")
	)
	(gr_poly
		(pts
			(xy 83.756754 -62.3189) (xy 83.712304 -62.3189) (xy 83.542124 -62.4078) (xy 83.542124 -62.62878)
			(xy 83.712304 -62.71768) (xy 83.756754 -62.71768)
		)
		(stroke
			(width 0)
			(type solid)
		)
		(fill yes)
		(layer "In11.Cu")
		(net "M_J_DQS_DP<12>")
	)
	(gr_poly
		(pts
			(xy 83.756754 -61.3283) (xy 83.712304 -61.3283) (xy 83.542124 -61.4172) (xy 83.542124 -61.63818)
			(xy 83.712304 -61.72708) (xy 83.756754 -61.72708)
		)
		(stroke
			(width 0)
			(type solid)
		)
		(fill yes)
		(layer "In11.Cu")
		(net "M_J_DQS_DP<12>")
	)
	(gr_poly
		(pts
			(xy 83.756754 -60.3377) (xy 83.712304 -60.3377) (xy 83.542124 -60.4266) (xy 83.542124 -60.64758)
			(xy 83.712304 -60.73648) (xy 83.756754 -60.73648)
		)
		(stroke
			(width 0)
			(type solid)
		)
		(fill yes)
		(layer "In11.Cu")
		(net "M_J_DQS_DP<12>")
	)
	(gr_poly
		(pts
			(xy 83.756754 -59.3471) (xy 83.712304 -59.3471) (xy 83.542124 -59.436) (xy 83.542124 -59.65698) (xy 83.712304 -59.74588)
			(xy 83.756754 -59.74588)
		)
		(stroke
			(width 0)
			(type solid)
		)
		(fill yes)
		(layer "In11.Cu")
		(net "M_J_DQS_DP<12>")
	)
	(gr_poly
		(pts
			(xy 83.756754 -58.368946) (xy 83.712304 -58.368946) (xy 83.542124 -58.457846) (xy 83.542124 -58.678826)
			(xy 83.712304 -58.767726) (xy 83.756754 -58.767726)
		)
		(stroke
			(width 0)
			(type solid)
		)
		(fill yes)
		(layer "In11.Cu")
		(net "M_J_DQS_DP<12>")
	)
	(gr_poly
		(pts
			(xy 83.756754 -57.37225) (xy 83.712304 -57.37225) (xy 83.542124 -57.46115) (xy 83.542124 -57.68213)
			(xy 83.712304 -57.77103) (xy 83.756754 -57.77103)
		)
		(stroke
			(width 0)
			(type solid)
		)
		(fill yes)
		(layer "In11.Cu")
		(net "M_J_DQS_DP<12>")
	)
	(gr_poly
		(pts
			(xy 83.756754 -56.3753) (xy 83.712304 -56.3753) (xy 83.542124 -56.4642) (xy 83.542124 -56.68518)
			(xy 83.712304 -56.77408) (xy 83.756754 -56.77408)
		)
		(stroke
			(width 0)
			(type solid)
		)
		(fill yes)
		(layer "In11.Cu")
		(net "M_J_DQS_DP<12>")
	)
	(gr_poly
		(pts
			(xy 83.833462 -51.821588) (xy 83.864958 -51.790092) (xy 83.577684 -51.502818) (xy 83.546188 -51.534314)
			(xy 83.472528 -51.73345) (xy 83.634326 -51.895248)
		)
		(stroke
			(width 0)
			(type solid)
		)
		(fill yes)
		(layer "In11.Cu")
		(net "M_J_DQ<30>")
	)
	(gr_poly
		(pts
			(xy 83.846162 -65.535048) (xy 83.805014 -65.347342) (xy 83.776312 -65.313306) (xy 83.471004 -65.569846)
			(xy 83.499452 -65.603882) (xy 83.676998 -65.677034)
		)
		(stroke
			(width 0)
			(type solid)
		)
		(fill yes)
		(layer "In11.Cu")
		(net "M_J_DQ<25>")
	)
	(gr_poly
		(pts
			(xy 83.866736 -99.300538) (xy 83.83524 -99.269296) (xy 83.63585 -99.195636) (xy 83.474306 -99.35718)
			(xy 83.547966 -99.55657) (xy 83.579208 -99.588066)
		)
		(stroke
			(width 0)
			(type solid)
		)
		(fill yes)
		(layer "In11.Cu")
		(net "M_M_DQ<30>")
	)
	(gr_poly
		(pts
			(xy 83.891374 -55.497222) (xy 83.994244 -55.334916) (xy 83.883754 -55.143654) (xy 83.691984 -55.151782)
			(xy 83.653376 -55.17388) (xy 83.85302 -55.51932)
		)
		(stroke
			(width 0)
			(type solid)
		)
		(fill yes)
		(layer "In11.Cu")
		(net "M_J_DQS_DN<12>")
	)
	(gr_poly
		(pts
			(xy 83.898486 -50.769266) (xy 83.898486 -50.540412) (xy 83.705446 -50.451512) (xy 83.660996 -50.451512)
			(xy 83.660996 -50.857912) (xy 83.705446 -50.857912)
		)
		(stroke
			(width 0)
			(type solid)
		)
		(fill yes)
		(layer "In11.Cu")
		(net "M_J_DQ<31>")
	)
	(gr_poly
		(pts
			(xy 83.928204 -53.279802) (xy 83.883754 -53.279802) (xy 83.690714 -53.368702) (xy 83.690714 -53.597302)
			(xy 83.883754 -53.686202) (xy 83.928204 -53.686202)
		)
		(stroke
			(width 0)
			(type solid)
		)
		(fill yes)
		(layer "In11.Cu")
		(net "M_J_DQS_DP<3>")
	)
	(gr_poly
		(pts
			(xy 83.98764 -92.389452) (xy 83.979766 -92.197682) (xy 83.957668 -92.159074) (xy 83.611974 -92.358464)
			(xy 83.634326 -92.396818) (xy 83.796378 -92.499942)
		)
		(stroke
			(width 0)
			(type solid)
		)
		(fill yes)
		(layer "In11.Cu")
		(net "M_M_DQ<25>")
	)
	(gr_poly
		(pts
			(xy 84.044282 -97.968562) (xy 84.044282 -97.739962) (xy 83.851242 -97.651062) (xy 83.806792 -97.651062)
			(xy 83.806792 -98.057462) (xy 83.851242 -98.057462)
		)
		(stroke
			(width 0)
			(type solid)
		)
		(fill yes)
		(layer "In11.Cu")
		(net "M_M_DQS_DP<3>")
	)
	(gr_poly
		(pts
			(xy 84.106004 -99.66579) (xy 84.032344 -99.4664) (xy 84.001102 -99.434904) (xy 83.713574 -99.722432)
			(xy 83.74507 -99.753674) (xy 83.94446 -99.827334)
		)
		(stroke
			(width 0)
			(type solid)
		)
		(fill yes)
		(layer "In11.Cu")
		(net "M_M_DQ<31>")
	)
	(gr_poly
		(pts
			(xy 84.124546 -91.946222) (xy 84.294726 -91.857576) (xy 84.294726 -91.636596) (xy 84.1248 -91.547696)
			(xy 84.08035 -91.547442) (xy 84.080096 -91.946476)
		)
		(stroke
			(width 0)
			(type solid)
		)
		(fill yes)
		(layer "In11.Cu")
		(net "M_M_DQ<25>")
	)
	(gr_poly
		(pts
			(xy 84.132674 -102.452932) (xy 84.132674 -102.224332) (xy 83.939634 -102.135432) (xy 83.895184 -102.135432)
			(xy 83.895184 -102.541832) (xy 83.939634 -102.541832)
		)
		(stroke
			(width 0)
			(type solid)
		)
		(fill yes)
		(layer "In11.Cu")
		(net "M_M_DQ<27>")
	)
	(gr_poly
		(pts
			(xy 84.132674 -101.462332) (xy 84.132674 -101.233732) (xy 83.939634 -101.144832) (xy 83.895184 -101.144832)
			(xy 83.895184 -101.551232) (xy 83.939634 -101.551232)
		)
		(stroke
			(width 0)
			(type solid)
		)
		(fill yes)
		(layer "In11.Cu")
		(net "M_M_DQ<27>")
	)
	(gr_poly
		(pts
			(xy 84.187792 -100.080318) (xy 84.156296 -100.048822) (xy 83.956906 -99.975162) (xy 83.795362 -100.13696)
			(xy 83.869022 -100.33635) (xy 83.900518 -100.367592)
		)
		(stroke
			(width 0)
			(type solid)
		)
		(fill yes)
		(layer "In11.Cu")
		(net "M_M_DQ<26>")
	)
	(gr_poly
		(pts
			(xy 84.215478 -92.627196) (xy 84.19338 -92.588842) (xy 84.031328 -92.485972) (xy 83.840066 -92.596462)
			(xy 83.84794 -92.788232) (xy 83.870292 -92.82684)
		)
		(stroke
			(width 0)
			(type solid)
		)
		(fill yes)
		(layer "In11.Cu")
		(net "M_M_DQS_DP<12>")
	)
	(gr_poly
		(pts
			(xy 84.267548 -96.878394) (xy 84.236052 -96.847152) (xy 84.036662 -96.773492) (xy 83.875118 -96.935036)
			(xy 83.948778 -97.134426) (xy 83.98002 -97.165922)
		)
		(stroke
			(width 0)
			(type solid)
		)
		(fill yes)
		(layer "In11.Cu")
		(net "M_M_DQS_DN<3>")
	)
	(gr_poly
		(pts
			(xy 84.29498 -95.826326) (xy 84.29498 -95.605346) (xy 84.1248 -95.516446) (xy 84.08035 -95.516446)
			(xy 84.08035 -95.915226) (xy 84.1248 -95.915226)
		)
		(stroke
			(width 0)
			(type solid)
		)
		(fill yes)
		(layer "In11.Cu")
		(net "M_M_DQS_DN<12>")
	)
	(gr_poly
		(pts
			(xy 84.29498 -94.829376) (xy 84.29498 -94.608396) (xy 84.1248 -94.519496) (xy 84.08035 -94.519496)
			(xy 84.08035 -94.918276) (xy 84.1248 -94.918276)
		)
		(stroke
			(width 0)
			(type solid)
		)
		(fill yes)
		(layer "In11.Cu")
		(net "M_M_DQS_DN<12>")
	)
	(gr_poly
		(pts
			(xy 84.29498 -93.83268) (xy 84.29498 -93.6117) (xy 84.1248 -93.5228) (xy 84.08035 -93.5228) (xy 84.08035 -93.92158)
			(xy 84.1248 -93.92158)
		)
		(stroke
			(width 0)
			(type solid)
		)
		(fill yes)
		(layer "In11.Cu")
		(net "M_M_DQS_DN<12>")
	)
	(gr_poly
		(pts
			(xy 84.29498 -90.867484) (xy 84.29498 -90.646504) (xy 84.1248 -90.557604) (xy 84.08035 -90.557604)
			(xy 84.08035 -90.956384) (xy 84.1248 -90.956384)
		)
		(stroke
			(width 0)
			(type solid)
		)
		(fill yes)
		(layer "In11.Cu")
		(net "M_M_DQ<25>")
	)
	(gr_poly
		(pts
			(xy 84.29498 -89.876884) (xy 84.29498 -89.655904) (xy 84.1248 -89.567004) (xy 84.08035 -89.567004)
			(xy 84.08035 -89.965784) (xy 84.1248 -89.965784)
		)
		(stroke
			(width 0)
			(type solid)
		)
		(fill yes)
		(layer "In11.Cu")
		(net "M_M_DQ<25>")
	)
	(gr_poly
		(pts
			(xy 84.29498 -88.886284) (xy 84.29498 -88.665304) (xy 84.1248 -88.576404) (xy 84.08035 -88.576404)
			(xy 84.08035 -88.975184) (xy 84.1248 -88.975184)
		)
		(stroke
			(width 0)
			(type solid)
		)
		(fill yes)
		(layer "In11.Cu")
		(net "M_M_DQ<25>")
	)
	(gr_poly
		(pts
			(xy 84.29498 -63.136526) (xy 84.29498 -62.915546) (xy 84.1248 -62.826646) (xy 84.08035 -62.826646)
			(xy 84.08035 -63.225426) (xy 84.1248 -63.225426)
		)
		(stroke
			(width 0)
			(type solid)
		)
		(fill yes)
		(layer "In11.Cu")
		(net "M_J_DQS_DN<12>")
	)
	(gr_poly
		(pts
			(xy 84.29498 -62.145926) (xy 84.29498 -61.924946) (xy 84.1248 -61.836046) (xy 84.08035 -61.836046)
			(xy 84.08035 -62.234826) (xy 84.1248 -62.234826)
		)
		(stroke
			(width 0)
			(type solid)
		)
		(fill yes)
		(layer "In11.Cu")
		(net "M_J_DQS_DN<12>")
	)
	(gr_poly
		(pts
			(xy 84.29498 -61.155326) (xy 84.29498 -60.934346) (xy 84.1248 -60.845446) (xy 84.08035 -60.845446)
			(xy 84.08035 -61.244226) (xy 84.1248 -61.244226)
		)
		(stroke
			(width 0)
			(type solid)
		)
		(fill yes)
		(layer "In11.Cu")
		(net "M_J_DQS_DN<12>")
	)
	(gr_poly
		(pts
			(xy 84.29498 -60.164726) (xy 84.29498 -59.943746) (xy 84.1248 -59.854846) (xy 84.08035 -59.854846)
			(xy 84.08035 -60.253626) (xy 84.1248 -60.253626)
		)
		(stroke
			(width 0)
			(type solid)
		)
		(fill yes)
		(layer "In11.Cu")
		(net "M_J_DQS_DN<12>")
	)
	(gr_poly
		(pts
			(xy 84.29498 -59.167776) (xy 84.29498 -58.946796) (xy 84.1248 -58.857896) (xy 84.08035 -58.857896)
			(xy 84.08035 -59.256676) (xy 84.1248 -59.256676)
		)
		(stroke
			(width 0)
			(type solid)
		)
		(fill yes)
		(layer "In11.Cu")
		(net "M_J_DQS_DN<12>")
	)
	(gr_poly
		(pts
			(xy 84.29498 -58.17108) (xy 84.29498 -57.9501) (xy 84.1248 -57.8612) (xy 84.08035 -57.8612) (xy 84.08035 -58.25998)
			(xy 84.1248 -58.25998)
		)
		(stroke
			(width 0)
			(type solid)
		)
		(fill yes)
		(layer "In11.Cu")
		(net "M_J_DQS_DN<12>")
	)
	(gr_poly
		(pts
			(xy 84.29498 -57.192926) (xy 84.29498 -56.971946) (xy 84.1248 -56.883046) (xy 84.08035 -56.883046)
			(xy 84.08035 -57.281826) (xy 84.1248 -57.281826)
		)
		(stroke
			(width 0)
			(type solid)
		)
		(fill yes)
		(layer "In11.Cu")
		(net "M_J_DQS_DN<12>")
	)
	(gr_poly
		(pts
			(xy 84.29498 -56.202326) (xy 84.29498 -55.981346) (xy 84.1248 -55.892446) (xy 84.08035 -55.892446)
			(xy 84.08035 -56.291226) (xy 84.1248 -56.291226)
		)
		(stroke
			(width 0)
			(type solid)
		)
		(fill yes)
		(layer "In11.Cu")
		(net "M_J_DQS_DN<12>")
	)
	(gr_poly
		(pts
			(xy 84.356194 -53.597302) (xy 84.356194 -53.368702) (xy 84.163154 -53.279802) (xy 84.118704 -53.279802)
			(xy 84.118704 -53.686202) (xy 84.163154 -53.686202)
		)
		(stroke
			(width 0)
			(type solid)
		)
		(fill yes)
		(layer "In11.Cu")
		(net "M_J_DQS_DN<3>")
	)
	(gr_poly
		(pts
			(xy 84.393532 -51.986434) (xy 84.467192 -51.787298) (xy 84.305394 -51.6255) (xy 84.106258 -51.69916)
			(xy 84.074762 -51.730656) (xy 84.362036 -52.01793)
		)
		(stroke
			(width 0)
			(type solid)
		)
		(fill yes)
		(layer "In11.Cu")
		(net "M_J_DQ<31>")
	)
	(gr_poly
		(pts
			(xy 84.507324 -97.2439) (xy 84.433664 -97.044764) (xy 84.402168 -97.013268) (xy 84.114894 -97.300542)
			(xy 84.14639 -97.332038) (xy 84.345526 -97.405698)
		)
		(stroke
			(width 0)
			(type solid)
		)
		(fill yes)
		(layer "In11.Cu")
		(net "M_M_DQS_DP<3>")
	)
	(gr_poly
		(pts
			(xy 84.544662 -52.532788) (xy 84.576158 -52.501292) (xy 84.288884 -52.214018) (xy 84.257388 -52.245514)
			(xy 84.183728 -52.44465) (xy 84.345526 -52.606448)
		)
		(stroke
			(width 0)
			(type solid)
		)
		(fill yes)
		(layer "In11.Cu")
		(net "M_J_DQ<30>")
	)
	(gr_poly
		(pts
			(xy 84.567014 -98.60026) (xy 84.535772 -98.568764) (xy 84.336382 -98.495104) (xy 84.174584 -98.656648)
			(xy 84.248244 -98.856038) (xy 84.27974 -98.887534)
		)
		(stroke
			(width 0)
			(type solid)
		)
		(fill yes)
		(layer "In11.Cu")
		(net "M_M_DQ<30>")
	)
	(gr_poly
		(pts
			(xy 84.615274 -95.516446) (xy 84.570824 -95.516446) (xy 84.400644 -95.605346) (xy 84.400644 -95.826326)
			(xy 84.570824 -95.915226) (xy 84.615274 -95.915226)
		)
		(stroke
			(width 0)
			(type solid)
		)
		(fill yes)
		(layer "In11.Cu")
		(net "M_M_DQS_DN<3>")
	)
	(gr_poly
		(pts
			(xy 84.615274 -94.519496) (xy 84.570824 -94.519496) (xy 84.400644 -94.608396) (xy 84.400644 -94.829376)
			(xy 84.570824 -94.918276) (xy 84.615274 -94.918276)
		)
		(stroke
			(width 0)
			(type solid)
		)
		(fill yes)
		(layer "In11.Cu")
		(net "M_M_DQS_DN<3>")
	)
	(gr_poly
		(pts
			(xy 84.615274 -91.554046) (xy 84.570824 -91.554046) (xy 84.400644 -91.642946) (xy 84.400644 -91.863926)
			(xy 84.570824 -91.952826) (xy 84.615274 -91.952826)
		)
		(stroke
			(width 0)
			(type solid)
		)
		(fill yes)
		(layer "In11.Cu")
		(net "M_M_DQS_DP<12>")
	)
	(gr_poly
		(pts
			(xy 84.615274 -90.563446) (xy 84.570824 -90.563446) (xy 84.400644 -90.652346) (xy 84.400644 -90.873326)
			(xy 84.570824 -90.962226) (xy 84.615274 -90.962226)
		)
		(stroke
			(width 0)
			(type solid)
		)
		(fill yes)
		(layer "In11.Cu")
		(net "M_M_DQS_DP<12>")
	)
	(gr_poly
		(pts
			(xy 84.615274 -89.572846) (xy 84.570824 -89.572846) (xy 84.400644 -89.661746) (xy 84.400644 -89.882726)
			(xy 84.570824 -89.971626) (xy 84.615274 -89.971626)
		)
		(stroke
			(width 0)
			(type solid)
		)
		(fill yes)
		(layer "In11.Cu")
		(net "M_M_DQS_DP<12>")
	)
	(gr_poly
		(pts
			(xy 84.615274 -88.582246) (xy 84.570824 -88.582246) (xy 84.400644 -88.671146) (xy 84.400644 -88.892126)
			(xy 84.570824 -88.981026) (xy 84.615274 -88.981026)
		)
		(stroke
			(width 0)
			(type solid)
		)
		(fill yes)
		(layer "In11.Cu")
		(net "M_M_DQS_DP<12>")
	)
	(gr_poly
		(pts
			(xy 84.615274 -87.591646) (xy 84.570824 -87.591646) (xy 84.400644 -87.680546) (xy 84.400644 -87.901526)
			(xy 84.570824 -87.990426) (xy 84.615274 -87.990426)
		)
		(stroke
			(width 0)
			(type solid)
		)
		(fill yes)
		(layer "In11.Cu")
		(net "M_M_DQS_DP<12>")
	)
	(gr_poly
		(pts
			(xy 84.615274 -86.601046) (xy 84.570824 -86.601046) (xy 84.400644 -86.689946) (xy 84.400644 -86.910926)
			(xy 84.570824 -86.999826) (xy 84.615274 -86.999826)
		)
		(stroke
			(width 0)
			(type solid)
		)
		(fill yes)
		(layer "In11.Cu")
		(net "M_M_DQS_DP<12>")
	)
	(gr_poly
		(pts
			(xy 84.615274 -85.610446) (xy 84.570824 -85.610446) (xy 84.400644 -85.699346) (xy 84.400644 -85.920326)
			(xy 84.570824 -86.009226) (xy 84.615274 -86.009226)
		)
		(stroke
			(width 0)
			(type solid)
		)
		(fill yes)
		(layer "In11.Cu")
		(net "M_M_DQS_DP<12>")
	)
	(gr_poly
		(pts
			(xy 84.615274 -65.798446) (xy 84.570824 -65.798446) (xy 84.400644 -65.887346) (xy 84.400644 -66.108326)
			(xy 84.570824 -66.197226) (xy 84.615274 -66.197226)
		)
		(stroke
			(width 0)
			(type solid)
		)
		(fill yes)
		(layer "In11.Cu")
		(net "M_J_DQS_DP<3>")
	)
	(gr_poly
		(pts
			(xy 84.615274 -64.807846) (xy 84.570824 -64.807846) (xy 84.400644 -64.896746) (xy 84.400644 -65.117726)
			(xy 84.570824 -65.206626) (xy 84.615274 -65.206626)
		)
		(stroke
			(width 0)
			(type solid)
		)
		(fill yes)
		(layer "In11.Cu")
		(net "M_J_DQS_DP<3>")
	)
	(gr_poly
		(pts
			(xy 84.615274 -63.817246) (xy 84.570824 -63.817246) (xy 84.400644 -63.906146) (xy 84.400644 -64.127126)
			(xy 84.570824 -64.216026) (xy 84.615274 -64.216026)
		)
		(stroke
			(width 0)
			(type solid)
		)
		(fill yes)
		(layer "In11.Cu")
		(net "M_J_DQS_DP<3>")
	)
	(gr_poly
		(pts
			(xy 84.615274 -62.826646) (xy 84.570824 -62.826646) (xy 84.400644 -62.915546) (xy 84.400644 -63.136526)
			(xy 84.570824 -63.225426) (xy 84.615274 -63.225426)
		)
		(stroke
			(width 0)
			(type solid)
		)
		(fill yes)
		(layer "In11.Cu")
		(net "M_J_DQS_DP<3>")
	)
	(gr_poly
		(pts
			(xy 84.615274 -61.836046) (xy 84.570824 -61.836046) (xy 84.400644 -61.924946) (xy 84.400644 -62.145926)
			(xy 84.570824 -62.234826) (xy 84.615274 -62.234826)
		)
		(stroke
			(width 0)
			(type solid)
		)
		(fill yes)
		(layer "In11.Cu")
		(net "M_J_DQS_DP<3>")
	)
	(gr_poly
		(pts
			(xy 84.615274 -60.845446) (xy 84.570824 -60.845446) (xy 84.400644 -60.934346) (xy 84.400644 -61.155326)
			(xy 84.570824 -61.244226) (xy 84.615274 -61.244226)
		)
		(stroke
			(width 0)
			(type solid)
		)
		(fill yes)
		(layer "In11.Cu")
		(net "M_J_DQS_DP<3>")
	)
	(gr_poly
		(pts
			(xy 84.615274 -59.854846) (xy 84.570824 -59.854846) (xy 84.400644 -59.943746) (xy 84.400644 -60.164726)
			(xy 84.570824 -60.253626) (xy 84.615274 -60.253626)
		)
		(stroke
			(width 0)
			(type solid)
		)
		(fill yes)
		(layer "In11.Cu")
		(net "M_J_DQS_DP<3>")
	)
	(gr_poly
		(pts
			(xy 84.615274 -58.857896) (xy 84.570824 -58.857896) (xy 84.400644 -58.946796) (xy 84.400644 -59.167776)
			(xy 84.570824 -59.256676) (xy 84.615274 -59.256676)
		)
		(stroke
			(width 0)
			(type solid)
		)
		(fill yes)
		(layer "In11.Cu")
		(net "M_J_DQS_DP<3>")
	)
	(gr_poly
		(pts
			(xy 84.615274 -57.8612) (xy 84.570824 -57.8612) (xy 84.400644 -57.9501) (xy 84.400644 -58.17108)
			(xy 84.570824 -58.25998) (xy 84.615274 -58.25998)
		)
		(stroke
			(width 0)
			(type solid)
		)
		(fill yes)
		(layer "In11.Cu")
		(net "M_J_DQS_DP<3>")
	)
	(gr_poly
		(pts
			(xy 84.615274 -56.883046) (xy 84.570824 -56.883046) (xy 84.400644 -56.971946) (xy 84.400644 -57.192926)
			(xy 84.570824 -57.281826) (xy 84.615274 -57.281826)
		)
		(stroke
			(width 0)
			(type solid)
		)
		(fill yes)
		(layer "In11.Cu")
		(net "M_J_DQS_DP<3>")
	)
	(gr_poly
		(pts
			(xy 84.615274 -55.892446) (xy 84.570824 -55.892446) (xy 84.400644 -55.981346) (xy 84.400644 -56.202326)
			(xy 84.570824 -56.291226) (xy 84.615274 -56.291226)
		)
		(stroke
			(width 0)
			(type solid)
		)
		(fill yes)
		(layer "In11.Cu")
		(net "M_J_DQS_DP<3>")
	)
	(gr_poly
		(pts
			(xy 84.615528 -93.52915) (xy 84.571078 -93.529404) (xy 84.400898 -93.61805) (xy 84.400898 -93.83903)
			(xy 84.570824 -93.92793) (xy 84.615274 -93.928184)
		)
		(stroke
			(width 0)
			(type solid)
		)
		(fill yes)
		(layer "In11.Cu")
		(net "M_M_DQS_DN<3>")
	)
	(gr_poly
		(pts
			(xy 84.616544 -97.795334) (xy 84.572094 -97.795334) (xy 84.379054 -97.884234) (xy 84.379054 -98.112834)
			(xy 84.572094 -98.201734) (xy 84.616544 -98.201734)
		)
		(stroke
			(width 0)
			(type solid)
		)
		(fill yes)
		(layer "In11.Cu")
		(net "M_M_DQ<30>")
	)
	(gr_poly
		(pts
			(xy 84.681314 -100.19157) (xy 84.607654 -99.99218) (xy 84.576158 -99.960684) (xy 84.288884 -100.247958)
			(xy 84.320126 -100.279454) (xy 84.519516 -100.353114)
		)
		(stroke
			(width 0)
			(type solid)
		)
		(fill yes)
		(layer "In11.Cu")
		(net "M_M_DQ<27>")
	)
	(gr_poly
		(pts
			(xy 84.696808 -53.116226) (xy 84.652358 -53.116226) (xy 84.459318 -53.205126) (xy 84.459318 -53.433726)
			(xy 84.652358 -53.522626) (xy 84.696808 -53.522626)
		)
		(stroke
			(width 0)
			(type solid)
		)
		(fill yes)
		(layer "In11.Cu")
		(net "M_J_DQ<30>")
	)
	(gr_poly
		(pts
			(xy 84.723732 -49.918874) (xy 84.692236 -49.887632) (xy 84.492846 -49.813972) (xy 84.331302 -49.975516)
			(xy 84.404962 -50.174906) (xy 84.436204 -50.206402)
		)
		(stroke
			(width 0)
			(type solid)
		)
		(fill yes)
		(layer "In11.Cu")
		(net "M_J_DQ<26>")
	)
	(gr_poly
		(pts
			(xy 84.806536 -98.965258) (xy 84.732876 -98.765868) (xy 84.70138 -98.734626) (xy 84.414106 -99.0219)
			(xy 84.445602 -99.053396) (xy 84.644992 -99.127056)
		)
		(stroke
			(width 0)
			(type solid)
		)
		(fill yes)
		(layer "In11.Cu")
		(net "M_M_DQ<31>")
	)
	(gr_poly
		(pts
			(xy 84.85378 -92.880688) (xy 84.845652 -92.688918) (xy 84.823554 -92.650056) (xy 84.478368 -92.8497)
			(xy 84.500466 -92.888054) (xy 84.662518 -92.990924)
		)
		(stroke
			(width 0)
			(type solid)
		)
		(fill yes)
		(layer "In11.Cu")
		(net "M_M_DQS_DN<12>")
	)
	(gr_poly
		(pts
			(xy 84.888324 -99.379786) (xy 84.856828 -99.348544) (xy 84.657438 -99.274884) (xy 84.495894 -99.436428)
			(xy 84.569554 -99.635818) (xy 84.600796 -99.667314)
		)
		(stroke
			(width 0)
			(type solid)
		)
		(fill yes)
		(layer "In11.Cu")
		(net "M_M_DQ<26>")
	)
	(gr_poly
		(pts
			(xy 85.0011 -51.55438) (xy 85.032596 -51.523138) (xy 84.745068 -51.23561) (xy 84.713826 -51.267106)
			(xy 84.640166 -51.466496) (xy 84.80171 -51.62804)
		)
		(stroke
			(width 0)
			(type solid)
		)
		(fill yes)
		(layer "In11.Cu")
		(net "M_J_DQ<26>")
	)
	(gr_poly
		(pts
			(xy 85.044026 -98.290634) (xy 85.044026 -98.062034) (xy 84.850986 -97.973134) (xy 84.806536 -97.973134)
			(xy 84.806536 -98.379534) (xy 84.850986 -98.379534)
		)
		(stroke
			(width 0)
			(type solid)
		)
		(fill yes)
		(layer "In11.Cu")
		(net "M_M_DQ<31>")
	)
	(gr_poly
		(pts
			(xy 85.08365 -93.117162) (xy 85.061044 -93.078808) (xy 84.899246 -92.975684) (xy 84.707984 -93.086174)
			(xy 84.715858 -93.277944) (xy 84.737956 -93.316552)
		)
		(stroke
			(width 0)
			(type solid)
		)
		(fill yes)
		(layer "In11.Cu")
		(net "M_M_DQS_DN<3>")
	)
	(gr_poly
		(pts
			(xy 85.124798 -53.433726) (xy 85.124798 -53.205126) (xy 84.931758 -53.116226) (xy 84.887308 -53.116226)
			(xy 84.887308 -53.522626) (xy 84.931758 -53.522626)
		)
		(stroke
			(width 0)
			(type solid)
		)
		(fill yes)
		(layer "In11.Cu")
		(net "M_J_DQ<31>")
	)
	(gr_poly
		(pts
			(xy 85.15096 -66.603626) (xy 85.154516 -66.3829) (xy 84.985606 -66.29146) (xy 84.94141 -66.290698)
			(xy 84.934806 -66.689224) (xy 84.979256 -66.689986)
		)
		(stroke
			(width 0)
			(type solid)
		)
		(fill yes)
		(layer "In11.Cu")
		(net "M_J_DQS_DN<3>")
	)
	(gr_poly
		(pts
			(xy 85.153246 -96.30918) (xy 85.153246 -96.0882) (xy 84.983066 -95.9993) (xy 84.938616 -95.9993)
			(xy 84.938616 -96.39808) (xy 84.983066 -96.39808)
		)
		(stroke
			(width 0)
			(type solid)
		)
		(fill yes)
		(layer "In11.Cu")
		(net "M_M_DQS_DP<3>")
	)
	(gr_poly
		(pts
			(xy 85.153246 -92.34424) (xy 85.153246 -92.123514) (xy 84.98332 -92.034614) (xy 84.938616 -92.03436)
			(xy 84.93887 -92.43314) (xy 84.983066 -92.43314)
		)
		(stroke
			(width 0)
			(type solid)
		)
		(fill yes)
		(layer "In11.Cu")
		(net "M_M_DQS_DN<12>")
	)
	(gr_poly
		(pts
			(xy 85.1535 -95.31858) (xy 85.1535 -95.0976) (xy 84.98332 -95.0087) (xy 84.93887 -95.0087) (xy 84.93887 -95.40748)
			(xy 84.98332 -95.40748)
		)
		(stroke
			(width 0)
			(type solid)
		)
		(fill yes)
		(layer "In11.Cu")
		(net "M_M_DQS_DP<3>")
	)
	(gr_poly
		(pts
			(xy 85.1535 -94.340426) (xy 85.1535 -94.119446) (xy 84.98332 -94.030546) (xy 84.93887 -94.030546)
			(xy 84.93887 -94.429326) (xy 84.98332 -94.429326)
		)
		(stroke
			(width 0)
			(type solid)
		)
		(fill yes)
		(layer "In11.Cu")
		(net "M_M_DQS_DP<3>")
	)
	(gr_poly
		(pts
			(xy 85.1535 -91.35618) (xy 85.1535 -91.1352) (xy 84.98332 -91.0463) (xy 84.93887 -91.0463) (xy 84.93887 -91.44508)
			(xy 84.98332 -91.44508)
		)
		(stroke
			(width 0)
			(type solid)
		)
		(fill yes)
		(layer "In11.Cu")
		(net "M_M_DQS_DN<12>")
	)
	(gr_poly
		(pts
			(xy 85.1535 -90.36558) (xy 85.1535 -90.1446) (xy 84.98332 -90.0557) (xy 84.93887 -90.0557) (xy 84.93887 -90.45448)
			(xy 84.98332 -90.45448)
		)
		(stroke
			(width 0)
			(type solid)
		)
		(fill yes)
		(layer "In11.Cu")
		(net "M_M_DQS_DN<12>")
	)
	(gr_poly
		(pts
			(xy 85.1535 -89.37498) (xy 85.1535 -89.154) (xy 84.98332 -89.0651) (xy 84.93887 -89.0651) (xy 84.93887 -89.46388)
			(xy 84.98332 -89.46388)
		)
		(stroke
			(width 0)
			(type solid)
		)
		(fill yes)
		(layer "In11.Cu")
		(net "M_M_DQS_DN<12>")
	)
	(gr_poly
		(pts
			(xy 85.1535 -88.38438) (xy 85.1535 -88.1634) (xy 84.98332 -88.0745) (xy 84.93887 -88.0745) (xy 84.93887 -88.47328)
			(xy 84.98332 -88.47328)
		)
		(stroke
			(width 0)
			(type solid)
		)
		(fill yes)
		(layer "In11.Cu")
		(net "M_M_DQS_DN<12>")
	)
	(gr_poly
		(pts
			(xy 85.1535 -87.39378) (xy 85.1535 -87.1728) (xy 84.98332 -87.0839) (xy 84.93887 -87.0839) (xy 84.93887 -87.48268)
			(xy 84.98332 -87.48268)
		)
		(stroke
			(width 0)
			(type solid)
		)
		(fill yes)
		(layer "In11.Cu")
		(net "M_M_DQS_DN<12>")
	)
	(gr_poly
		(pts
			(xy 85.1535 -86.40318) (xy 85.1535 -86.1822) (xy 84.98332 -86.0933) (xy 84.93887 -86.0933) (xy 84.93887 -86.49208)
			(xy 84.98332 -86.49208)
		)
		(stroke
			(width 0)
			(type solid)
		)
		(fill yes)
		(layer "In11.Cu")
		(net "M_M_DQS_DN<12>")
	)
	(gr_poly
		(pts
			(xy 85.1535 -65.60058) (xy 85.1535 -65.3796) (xy 84.98332 -65.2907) (xy 84.93887 -65.2907) (xy 84.93887 -65.68948)
			(xy 84.98332 -65.68948)
		)
		(stroke
			(width 0)
			(type solid)
		)
		(fill yes)
		(layer "In11.Cu")
		(net "M_J_DQS_DN<3>")
	)
	(gr_poly
		(pts
			(xy 85.1535 -64.60998) (xy 85.1535 -64.389) (xy 84.98332 -64.3001) (xy 84.93887 -64.3001) (xy 84.93887 -64.69888)
			(xy 84.98332 -64.69888)
		)
		(stroke
			(width 0)
			(type solid)
		)
		(fill yes)
		(layer "In11.Cu")
		(net "M_J_DQS_DN<3>")
	)
	(gr_poly
		(pts
			(xy 85.1535 -63.61938) (xy 85.1535 -63.3984) (xy 84.98332 -63.3095) (xy 84.93887 -63.3095) (xy 84.93887 -63.70828)
			(xy 84.98332 -63.70828)
		)
		(stroke
			(width 0)
			(type solid)
		)
		(fill yes)
		(layer "In11.Cu")
		(net "M_J_DQS_DN<3>")
	)
	(gr_poly
		(pts
			(xy 85.1535 -62.62878) (xy 85.1535 -62.4078) (xy 84.98332 -62.3189) (xy 84.93887 -62.3189) (xy 84.93887 -62.71768)
			(xy 84.98332 -62.71768)
		)
		(stroke
			(width 0)
			(type solid)
		)
		(fill yes)
		(layer "In11.Cu")
		(net "M_J_DQS_DN<3>")
	)
	(gr_poly
		(pts
			(xy 85.1535 -61.63818) (xy 85.1535 -61.4172) (xy 84.98332 -61.3283) (xy 84.93887 -61.3283) (xy 84.93887 -61.72708)
			(xy 84.98332 -61.72708)
		)
		(stroke
			(width 0)
			(type solid)
		)
		(fill yes)
		(layer "In11.Cu")
		(net "M_J_DQS_DN<3>")
	)
	(gr_poly
		(pts
			(xy 85.1535 -60.64758) (xy 85.1535 -60.4266) (xy 84.98332 -60.3377) (xy 84.93887 -60.3377) (xy 84.93887 -60.73648)
			(xy 84.98332 -60.73648)
		)
		(stroke
			(width 0)
			(type solid)
		)
		(fill yes)
		(layer "In11.Cu")
		(net "M_J_DQS_DN<3>")
	)
	(gr_poly
		(pts
			(xy 85.1535 -59.65698) (xy 85.1535 -59.436) (xy 84.98332 -59.3471) (xy 84.93887 -59.3471) (xy 84.93887 -59.74588)
			(xy 84.98332 -59.74588)
		)
		(stroke
			(width 0)
			(type solid)
		)
		(fill yes)
		(layer "In11.Cu")
		(net "M_J_DQS_DN<3>")
	)
	(gr_poly
		(pts
			(xy 85.1535 -58.678826) (xy 85.1535 -58.457846) (xy 84.98332 -58.368946) (xy 84.93887 -58.368946)
			(xy 84.93887 -58.767726) (xy 84.98332 -58.767726)
		)
		(stroke
			(width 0)
			(type solid)
		)
		(fill yes)
		(layer "In11.Cu")
		(net "M_J_DQS_DN<3>")
	)
	(gr_poly
		(pts
			(xy 85.1535 -57.68213) (xy 85.1535 -57.46115) (xy 84.98332 -57.37225) (xy 84.93887 -57.37225) (xy 84.93887 -57.77103)
			(xy 84.98332 -57.77103)
		)
		(stroke
			(width 0)
			(type solid)
		)
		(fill yes)
		(layer "In11.Cu")
		(net "M_J_DQS_DN<3>")
	)
	(gr_poly
		(pts
			(xy 85.1535 -56.68518) (xy 85.1535 -56.4642) (xy 84.98332 -56.3753) (xy 84.93887 -56.3753) (xy 84.93887 -56.77408)
			(xy 84.98332 -56.77408)
		)
		(stroke
			(width 0)
			(type solid)
		)
		(fill yes)
		(layer "In11.Cu")
		(net "M_J_DQS_DN<3>")
	)
	(gr_poly
		(pts
			(xy 85.1535 -55.69458) (xy 85.1535 -55.4736) (xy 84.98332 -55.3847) (xy 84.93887 -55.3847) (xy 84.93887 -55.78348)
			(xy 84.98332 -55.78348)
		)
		(stroke
			(width 0)
			(type solid)
		)
		(fill yes)
		(layer "In11.Cu")
		(net "M_J_DQS_DN<3>")
	)
	(gr_poly
		(pts
			(xy 85.198458 -51.357022) (xy 85.272118 -51.157632) (xy 85.110574 -50.996088) (xy 84.911184 -51.069748)
			(xy 84.879688 -51.10099) (xy 85.167216 -51.388518)
		)
		(stroke
			(width 0)
			(type solid)
		)
		(fill yes)
		(layer "In11.Cu")
		(net "M_J_DQ<27>")
	)
	(gr_poly
		(pts
			(xy 85.221826 -54.604412) (xy 85.253322 -54.572916) (xy 84.966048 -54.285642) (xy 84.934552 -54.317138)
			(xy 84.860892 -54.516274) (xy 85.02269 -54.678072)
		)
		(stroke
			(width 0)
			(type solid)
		)
		(fill yes)
		(layer "In11.Cu")
		(net "M_J_DQ<30>")
	)
	(gr_poly
		(pts
			(xy 85.381592 -99.491038) (xy 85.307932 -99.291648) (xy 85.27669 -99.260152) (xy 84.989162 -99.54768)
			(xy 85.020658 -99.578922) (xy 85.220048 -99.652582)
		)
		(stroke
			(width 0)
			(type solid)
		)
		(fill yes)
		(layer "In11.Cu")
		(net "M_M_DQ<27>")
	)
	(gr_poly
		(pts
			(xy 85.419692 -54.406546) (xy 85.493352 -54.20741) (xy 85.331554 -54.045612) (xy 85.132418 -54.119272)
			(xy 85.100922 -54.150768) (xy 85.388196 -54.438042)
		)
		(stroke
			(width 0)
			(type solid)
		)
		(fill yes)
		(layer "In11.Cu")
		(net "M_J_DQ<31>")
	)
	(gr_poly
		(pts
			(xy 85.465412 -53.285644) (xy 85.420962 -53.285644) (xy 85.227922 -53.374544) (xy 85.227922 -53.603144)
			(xy 85.420962 -53.692044) (xy 85.465412 -53.692044)
		)
		(stroke
			(width 0)
			(type solid)
		)
		(fill yes)
		(layer "In11.Cu")
		(net "M_J_DQ<26>")
	)
	(gr_poly
		(pts
			(xy 85.465412 -52.295044) (xy 85.420962 -52.295044) (xy 85.227922 -52.383944) (xy 85.227922 -52.612544)
			(xy 85.420962 -52.701444) (xy 85.465412 -52.701444)
		)
		(stroke
			(width 0)
			(type solid)
		)
		(fill yes)
		(layer "In11.Cu")
		(net "M_J_DQ<26>")
	)
	(gr_poly
		(pts
			(xy 85.473794 -95.9993) (xy 85.429344 -95.9993) (xy 85.259164 -96.0882) (xy 85.259164 -96.30918)
			(xy 85.429344 -96.39808) (xy 85.473794 -96.39808)
		)
		(stroke
			(width 0)
			(type solid)
		)
		(fill yes)
		(layer "In11.Cu")
		(net "M_M_DQ<30>")
	)
	(gr_poly
		(pts
			(xy 85.473794 -95.0087) (xy 85.429344 -95.0087) (xy 85.259164 -95.0976) (xy 85.259164 -95.31858)
			(xy 85.429344 -95.40748) (xy 85.473794 -95.40748)
		)
		(stroke
			(width 0)
			(type solid)
		)
		(fill yes)
		(layer "In11.Cu")
		(net "M_M_DQ<30>")
	)
	(gr_poly
		(pts
			(xy 85.473794 -94.033086) (xy 85.429598 -94.033086) (xy 85.259418 -94.121986) (xy 85.259418 -94.342712)
			(xy 85.429598 -94.431612) (xy 85.474048 -94.431866)
		)
		(stroke
			(width 0)
			(type solid)
		)
		(fill yes)
		(layer "In11.Cu")
		(net "M_M_DQ<30>")
	)
	(gr_poly
		(pts
			(xy 85.473794 -92.0369) (xy 85.429344 -92.0369) (xy 85.259164 -92.1258) (xy 85.259164 -92.34678)
			(xy 85.429344 -92.43568) (xy 85.473794 -92.43568)
		)
		(stroke
			(width 0)
			(type solid)
		)
		(fill yes)
		(layer "In11.Cu")
		(net "M_M_DQS_DN<3>")
	)
	(gr_poly
		(pts
			(xy 85.473794 -91.0463) (xy 85.429344 -91.0463) (xy 85.259164 -91.1352) (xy 85.259164 -91.35618)
			(xy 85.429344 -91.44508) (xy 85.473794 -91.44508)
		)
		(stroke
			(width 0)
			(type solid)
		)
		(fill yes)
		(layer "In11.Cu")
		(net "M_M_DQS_DN<3>")
	)
	(gr_poly
		(pts
			(xy 85.473794 -90.0557) (xy 85.429344 -90.0557) (xy 85.259164 -90.1446) (xy 85.259164 -90.36558)
			(xy 85.429344 -90.45448) (xy 85.473794 -90.45448)
		)
		(stroke
			(width 0)
			(type solid)
		)
		(fill yes)
		(layer "In11.Cu")
		(net "M_M_DQS_DN<3>")
	)
	(gr_poly
		(pts
			(xy 85.473794 -89.0651) (xy 85.429344 -89.0651) (xy 85.259164 -89.154) (xy 85.259164 -89.37498) (xy 85.429344 -89.46388)
			(xy 85.473794 -89.46388)
		)
		(stroke
			(width 0)
			(type solid)
		)
		(fill yes)
		(layer "In11.Cu")
		(net "M_M_DQS_DN<3>")
	)
	(gr_poly
		(pts
			(xy 85.473794 -62.3189) (xy 85.429344 -62.3189) (xy 85.259164 -62.4078) (xy 85.259164 -62.62878)
			(xy 85.429344 -62.71768) (xy 85.473794 -62.71768)
		)
		(stroke
			(width 0)
			(type solid)
		)
		(fill yes)
		(layer "In11.Cu")
		(net "M_J_DQ<30>")
	)
	(gr_poly
		(pts
			(xy 85.473794 -61.3283) (xy 85.429344 -61.3283) (xy 85.259164 -61.4172) (xy 85.259164 -61.63818)
			(xy 85.429344 -61.72708) (xy 85.473794 -61.72708)
		)
		(stroke
			(width 0)
			(type solid)
		)
		(fill yes)
		(layer "In11.Cu")
		(net "M_J_DQ<30>")
	)
	(gr_poly
		(pts
			(xy 85.473794 -60.3377) (xy 85.429344 -60.3377) (xy 85.259164 -60.4266) (xy 85.259164 -60.64758)
			(xy 85.429344 -60.73648) (xy 85.473794 -60.73648)
		)
		(stroke
			(width 0)
			(type solid)
		)
		(fill yes)
		(layer "In11.Cu")
		(net "M_J_DQ<30>")
	)
	(gr_poly
		(pts
			(xy 85.473794 -59.3471) (xy 85.429344 -59.3471) (xy 85.259164 -59.436) (xy 85.259164 -59.65698) (xy 85.429344 -59.74588)
			(xy 85.473794 -59.74588)
		)
		(stroke
			(width 0)
			(type solid)
		)
		(fill yes)
		(layer "In11.Cu")
		(net "M_J_DQ<30>")
	)
	(gr_poly
		(pts
			(xy 85.473794 -58.368946) (xy 85.429344 -58.368946) (xy 85.259164 -58.457846) (xy 85.259164 -58.678826)
			(xy 85.429344 -58.767726) (xy 85.473794 -58.767726)
		)
		(stroke
			(width 0)
			(type solid)
		)
		(fill yes)
		(layer "In11.Cu")
		(net "M_J_DQ<30>")
	)
	(gr_poly
		(pts
			(xy 85.473794 -57.37225) (xy 85.429344 -57.37225) (xy 85.259164 -57.46115) (xy 85.259164 -57.68213)
			(xy 85.429344 -57.77103) (xy 85.473794 -57.77103)
		)
		(stroke
			(width 0)
			(type solid)
		)
		(fill yes)
		(layer "In11.Cu")
		(net "M_J_DQ<30>")
	)
	(gr_poly
		(pts
			(xy 85.473794 -56.3753) (xy 85.429344 -56.3753) (xy 85.259164 -56.4642) (xy 85.259164 -56.68518)
			(xy 85.429344 -56.77408) (xy 85.473794 -56.77408)
		)
		(stroke
			(width 0)
			(type solid)
		)
		(fill yes)
		(layer "In11.Cu")
		(net "M_J_DQ<30>")
	)
	(gr_poly
		(pts
			(xy 85.473794 -55.397146) (xy 85.429344 -55.397146) (xy 85.259164 -55.486046) (xy 85.259164 -55.707026)
			(xy 85.429344 -55.795926) (xy 85.473794 -55.795926)
		)
		(stroke
			(width 0)
			(type solid)
		)
		(fill yes)
		(layer "In11.Cu")
		(net "M_J_DQ<30>")
	)
	(gr_poly
		(pts
			(xy 85.474048 -63.31585) (xy 85.429598 -63.31585) (xy 85.259418 -63.40475) (xy 85.259418 -63.62573)
			(xy 85.429598 -63.71463) (xy 85.474048 -63.71463)
		)
		(stroke
			(width 0)
			(type solid)
		)
		(fill yes)
		(layer "In11.Cu")
		(net "M_J_DQ<30>")
	)
	(gr_poly
		(pts
			(xy 85.588602 -98.679508) (xy 85.55736 -98.648012) (xy 85.35797 -98.574352) (xy 85.196172 -98.735896)
			(xy 85.269832 -98.935286) (xy 85.301328 -98.966782)
		)
		(stroke
			(width 0)
			(type solid)
		)
		(fill yes)
		(layer "In11.Cu")
		(net "M_M_DQ<26>")
	)
	(gr_poly
		(pts
			(xy 85.664548 -86.09457) (xy 85.620098 -86.09457) (xy 85.449918 -86.18347) (xy 85.449918 -86.40445)
			(xy 85.620098 -86.49335) (xy 85.664548 -86.49335)
		)
		(stroke
			(width 0)
			(type solid)
		)
		(fill yes)
		(layer "In11.Cu")
		(net "M_M_DQ<30>")
	)
	(gr_poly
		(pts
			(xy 85.704934 -93.380306) (xy 85.69706 -93.188536) (xy 85.674962 -93.149928) (xy 85.329522 -93.349318)
			(xy 85.35162 -93.387672) (xy 85.513672 -93.490542)
		)
		(stroke
			(width 0)
			(type solid)
		)
		(fill yes)
		(layer "In11.Cu")
		(net "M_M_DQS_DP<3>")
	)
	(gr_poly
		(pts
			(xy 85.708744 -97.34042) (xy 85.700616 -97.14865) (xy 85.678518 -97.110042) (xy 85.333078 -97.309432)
			(xy 85.35543 -97.347786) (xy 85.517228 -97.450656)
		)
		(stroke
			(width 0)
			(type solid)
		)
		(fill yes)
		(layer "In11.Cu")
		(net "M_M_DQ<31>")
	)
	(gr_poly
		(pts
			(xy 85.893402 -53.223922) (xy 85.893402 -52.995322) (xy 85.700362 -52.906422) (xy 85.655912 -52.906422)
			(xy 85.655912 -53.312822) (xy 85.700362 -53.312822)
		)
		(stroke
			(width 0)
			(type solid)
		)
		(fill yes)
		(layer "In11.Cu")
		(net "M_J_DQ<27>")
	)
	(gr_poly
		(pts
			(xy 85.893402 -52.233322) (xy 85.893402 -52.004722) (xy 85.700362 -51.915822) (xy 85.655912 -51.915822)
			(xy 85.655912 -52.322222) (xy 85.700362 -52.322222)
		)
		(stroke
			(width 0)
			(type solid)
		)
		(fill yes)
		(layer "In11.Cu")
		(net "M_J_DQ<27>")
	)
	(gr_poly
		(pts
			(xy 85.934296 -93.616526) (xy 85.912198 -93.578172) (xy 85.750146 -93.475302) (xy 85.558884 -93.585538)
			(xy 85.567012 -93.777562) (xy 85.58911 -93.81617)
		)
		(stroke
			(width 0)
			(type solid)
		)
		(fill yes)
		(layer "In11.Cu")
		(net "M_M_DQ<30>")
	)
	(gr_poly
		(pts
			(xy 86.011766 -96.806004) (xy 86.01202 -96.585278) (xy 85.84184 -96.496378) (xy 85.79739 -96.496124)
			(xy 85.79739 -96.894904) (xy 85.84184 -96.894904)
		)
		(stroke
			(width 0)
			(type solid)
		)
		(fill yes)
		(layer "In11.Cu")
		(net "M_M_DQ<31>")
	)
	(gr_poly
		(pts
			(xy 86.01202 -95.826326) (xy 86.01202 -95.605346) (xy 85.84184 -95.516446) (xy 85.79739 -95.516446)
			(xy 85.79739 -95.915226) (xy 85.84184 -95.915226)
		)
		(stroke
			(width 0)
			(type solid)
		)
		(fill yes)
		(layer "In11.Cu")
		(net "M_M_DQ<31>")
	)
	(gr_poly
		(pts
			(xy 86.01202 -94.829376) (xy 86.01202 -94.608396) (xy 85.84184 -94.519496) (xy 85.79739 -94.519496)
			(xy 85.79739 -94.918276) (xy 85.84184 -94.918276)
		)
		(stroke
			(width 0)
			(type solid)
		)
		(fill yes)
		(layer "In11.Cu")
		(net "M_M_DQ<31>")
	)
	(gr_poly
		(pts
			(xy 86.01202 -92.847922) (xy 86.012274 -92.627196) (xy 85.842094 -92.538042) (xy 85.797644 -92.538042)
			(xy 85.797644 -92.936822) (xy 85.84184 -92.936822)
		)
		(stroke
			(width 0)
			(type solid)
		)
		(fill yes)
		(layer "In11.Cu")
		(net "M_M_DQS_DP<3>")
	)
	(gr_poly
		(pts
			(xy 86.01202 -91.863926) (xy 86.01202 -91.642946) (xy 85.84184 -91.554046) (xy 85.79739 -91.554046)
			(xy 85.79739 -91.952826) (xy 85.84184 -91.952826)
		)
		(stroke
			(width 0)
			(type solid)
		)
		(fill yes)
		(layer "In11.Cu")
		(net "M_M_DQS_DP<3>")
	)
	(gr_poly
		(pts
			(xy 86.01202 -90.873326) (xy 86.01202 -90.652346) (xy 85.84184 -90.563446) (xy 85.79739 -90.563446)
			(xy 85.79739 -90.962226) (xy 85.84184 -90.962226)
		)
		(stroke
			(width 0)
			(type solid)
		)
		(fill yes)
		(layer "In11.Cu")
		(net "M_M_DQS_DP<3>")
	)
	(gr_poly
		(pts
			(xy 86.01202 -89.882726) (xy 86.01202 -89.661746) (xy 85.84184 -89.572846) (xy 85.79739 -89.572846)
			(xy 85.79739 -89.971626) (xy 85.84184 -89.971626)
		)
		(stroke
			(width 0)
			(type solid)
		)
		(fill yes)
		(layer "In11.Cu")
		(net "M_M_DQS_DP<3>")
	)
	(gr_poly
		(pts
			(xy 86.01202 -88.892126) (xy 86.01202 -88.671146) (xy 85.84184 -88.582246) (xy 85.79739 -88.582246)
			(xy 85.79739 -88.981026) (xy 85.84184 -88.981026)
		)
		(stroke
			(width 0)
			(type solid)
		)
		(fill yes)
		(layer "In11.Cu")
		(net "M_M_DQS_DP<3>")
	)
	(gr_poly
		(pts
			(xy 86.01202 -86.910926) (xy 86.01202 -86.689946) (xy 85.84184 -86.601046) (xy 85.79739 -86.601046)
			(xy 85.79739 -86.999826) (xy 85.84184 -86.999826)
		)
		(stroke
			(width 0)
			(type solid)
		)
		(fill yes)
		(layer "In11.Cu")
		(net "M_M_DQ<30>")
	)
	(gr_poly
		(pts
			(xy 86.01202 -65.11163) (xy 86.01202 -64.89065) (xy 85.84184 -64.80175) (xy 85.79739 -64.80175) (xy 85.79739 -65.20053)
			(xy 85.84184 -65.20053)
		)
		(stroke
			(width 0)
			(type solid)
		)
		(fill yes)
		(layer "In11.Cu")
		(net "M_J_DQ<31>")
	)
	(gr_poly
		(pts
			(xy 86.01202 -64.12103) (xy 86.01202 -63.90005) (xy 85.84184 -63.81115) (xy 85.79739 -63.81115) (xy 85.79739 -64.20993)
			(xy 85.84184 -64.20993)
		)
		(stroke
			(width 0)
			(type solid)
		)
		(fill yes)
		(layer "In11.Cu")
		(net "M_J_DQ<31>")
	)
	(gr_poly
		(pts
			(xy 86.01202 -63.136526) (xy 86.01202 -62.915546) (xy 85.84184 -62.826646) (xy 85.79739 -62.826646)
			(xy 85.79739 -63.225426) (xy 85.84184 -63.225426)
		)
		(stroke
			(width 0)
			(type solid)
		)
		(fill yes)
		(layer "In11.Cu")
		(net "M_J_DQ<31>")
	)
	(gr_poly
		(pts
			(xy 86.01202 -62.145926) (xy 86.01202 -61.924946) (xy 85.84184 -61.836046) (xy 85.79739 -61.836046)
			(xy 85.79739 -62.234826) (xy 85.84184 -62.234826)
		)
		(stroke
			(width 0)
			(type solid)
		)
		(fill yes)
		(layer "In11.Cu")
		(net "M_J_DQ<31>")
	)
	(gr_poly
		(pts
			(xy 86.01202 -61.155326) (xy 86.01202 -60.934346) (xy 85.84184 -60.845446) (xy 85.79739 -60.845446)
			(xy 85.79739 -61.244226) (xy 85.84184 -61.244226)
		)
		(stroke
			(width 0)
			(type solid)
		)
		(fill yes)
		(layer "In11.Cu")
		(net "M_J_DQ<31>")
	)
	(gr_poly
		(pts
			(xy 86.01202 -60.164726) (xy 86.01202 -59.943746) (xy 85.84184 -59.854846) (xy 85.79739 -59.854846)
			(xy 85.79739 -60.253626) (xy 85.84184 -60.253626)
		)
		(stroke
			(width 0)
			(type solid)
		)
		(fill yes)
		(layer "In11.Cu")
		(net "M_J_DQ<31>")
	)
	(gr_poly
		(pts
			(xy 86.01202 -59.167776) (xy 86.01202 -58.946796) (xy 85.84184 -58.857896) (xy 85.79739 -58.857896)
			(xy 85.79739 -59.256676) (xy 85.84184 -59.256676)
		)
		(stroke
			(width 0)
			(type solid)
		)
		(fill yes)
		(layer "In11.Cu")
		(net "M_J_DQ<31>")
	)
	(gr_poly
		(pts
			(xy 86.01202 -58.17108) (xy 86.01202 -57.9501) (xy 85.84184 -57.8612) (xy 85.79739 -57.8612) (xy 85.79739 -58.25998)
			(xy 85.84184 -58.25998)
		)
		(stroke
			(width 0)
			(type solid)
		)
		(fill yes)
		(layer "In11.Cu")
		(net "M_J_DQ<31>")
	)
	(gr_poly
		(pts
			(xy 86.01202 -57.192926) (xy 86.01202 -56.971946) (xy 85.84184 -56.883046) (xy 85.79739 -56.883046)
			(xy 85.79739 -57.281826) (xy 85.84184 -57.281826)
		)
		(stroke
			(width 0)
			(type solid)
		)
		(fill yes)
		(layer "In11.Cu")
		(net "M_J_DQ<31>")
	)
	(gr_poly
		(pts
			(xy 86.01202 -56.202326) (xy 86.01202 -55.981346) (xy 85.84184 -55.892446) (xy 85.79739 -55.892446)
			(xy 85.79739 -56.291226) (xy 85.84184 -56.291226)
		)
		(stroke
			(width 0)
			(type solid)
		)
		(fill yes)
		(layer "In11.Cu")
		(net "M_J_DQ<31>")
	)
	(gr_poly
		(pts
			(xy 86.01202 -55.211726) (xy 86.01202 -54.990746) (xy 85.84184 -54.901846) (xy 85.79739 -54.901846)
			(xy 85.79739 -55.300626) (xy 85.84184 -55.300626)
		)
		(stroke
			(width 0)
			(type solid)
		)
		(fill yes)
		(layer "In11.Cu")
		(net "M_J_DQ<31>")
	)
	(gr_poly
		(pts
			(xy 86.133686 -97.877376) (xy 86.095332 -97.855024) (xy 85.88375 -97.83572) (xy 85.76945 -98.033586)
			(xy 85.892386 -98.207068) (xy 85.93074 -98.22942)
		)
		(stroke
			(width 0)
			(type solid)
		)
		(fill yes)
		(layer "In11.Cu")
		(net "M_M_DQ<26>")
	)
	(gr_poly
		(pts
			(xy 86.332314 -96.507046) (xy 86.287864 -96.507046) (xy 86.117684 -96.595946) (xy 86.117684 -96.816926)
			(xy 86.287864 -96.905826) (xy 86.332314 -96.905826)
		)
		(stroke
			(width 0)
			(type solid)
		)
		(fill yes)
		(layer "In11.Cu")
		(net "M_M_DQ<26>")
	)
	(gr_poly
		(pts
			(xy 86.332314 -95.516446) (xy 86.287864 -95.516446) (xy 86.117684 -95.605346) (xy 86.117684 -95.826326)
			(xy 86.287864 -95.915226) (xy 86.332314 -95.915226)
		)
		(stroke
			(width 0)
			(type solid)
		)
		(fill yes)
		(layer "In11.Cu")
		(net "M_M_DQ<26>")
	)
	(gr_poly
		(pts
			(xy 86.332314 -92.544646) (xy 86.287864 -92.544646) (xy 86.117684 -92.633546) (xy 86.117684 -92.854526)
			(xy 86.287864 -92.943426) (xy 86.332314 -92.943426)
		)
		(stroke
			(width 0)
			(type solid)
		)
		(fill yes)
		(layer "In11.Cu")
		(net "M_M_DQ<30>")
	)
	(gr_poly
		(pts
			(xy 86.332314 -91.554046) (xy 86.287864 -91.554046) (xy 86.117684 -91.642946) (xy 86.117684 -91.863926)
			(xy 86.287864 -91.952826) (xy 86.332314 -91.952826)
		)
		(stroke
			(width 0)
			(type solid)
		)
		(fill yes)
		(layer "In11.Cu")
		(net "M_M_DQ<30>")
	)
	(gr_poly
		(pts
			(xy 86.332314 -90.563446) (xy 86.287864 -90.563446) (xy 86.117684 -90.652346) (xy 86.117684 -90.873326)
			(xy 86.287864 -90.962226) (xy 86.332314 -90.962226)
		)
		(stroke
			(width 0)
			(type solid)
		)
		(fill yes)
		(layer "In11.Cu")
		(net "M_M_DQ<30>")
	)
	(gr_poly
		(pts
			(xy 86.332314 -89.572846) (xy 86.287864 -89.572846) (xy 86.117684 -89.661746) (xy 86.117684 -89.882726)
			(xy 86.287864 -89.971626) (xy 86.332314 -89.971626)
		)
		(stroke
			(width 0)
			(type solid)
		)
		(fill yes)
		(layer "In11.Cu")
		(net "M_M_DQ<30>")
	)
	(gr_poly
		(pts
			(xy 86.332314 -88.582246) (xy 86.287864 -88.582246) (xy 86.117684 -88.671146) (xy 86.117684 -88.892126)
			(xy 86.287864 -88.981026) (xy 86.332314 -88.981026)
		)
		(stroke
			(width 0)
			(type solid)
		)
		(fill yes)
		(layer "In11.Cu")
		(net "M_M_DQ<30>")
	)
	(gr_poly
		(pts
			(xy 86.332314 -63.817246) (xy 86.287864 -63.817246) (xy 86.117684 -63.906146) (xy 86.117684 -64.127126)
			(xy 86.287864 -64.216026) (xy 86.332314 -64.216026)
		)
		(stroke
			(width 0)
			(type solid)
		)
		(fill yes)
		(layer "In11.Cu")
		(net "M_J_DQ<26>")
	)
	(gr_poly
		(pts
			(xy 86.332314 -62.826646) (xy 86.287864 -62.826646) (xy 86.117684 -62.915546) (xy 86.117684 -63.136526)
			(xy 86.287864 -63.225426) (xy 86.332314 -63.225426)
		)
		(stroke
			(width 0)
			(type solid)
		)
		(fill yes)
		(layer "In11.Cu")
		(net "M_J_DQ<26>")
	)
	(gr_poly
		(pts
			(xy 86.332314 -61.836046) (xy 86.287864 -61.836046) (xy 86.117684 -61.924946) (xy 86.117684 -62.145926)
			(xy 86.287864 -62.234826) (xy 86.332314 -62.234826)
		)
		(stroke
			(width 0)
			(type solid)
		)
		(fill yes)
		(layer "In11.Cu")
		(net "M_J_DQ<26>")
	)
	(gr_poly
		(pts
			(xy 86.332314 -60.845446) (xy 86.287864 -60.845446) (xy 86.117684 -60.934346) (xy 86.117684 -61.155326)
			(xy 86.287864 -61.244226) (xy 86.332314 -61.244226)
		)
		(stroke
			(width 0)
			(type solid)
		)
		(fill yes)
		(layer "In11.Cu")
		(net "M_J_DQ<26>")
	)
	(gr_poly
		(pts
			(xy 86.332314 -59.854846) (xy 86.287864 -59.854846) (xy 86.117684 -59.943746) (xy 86.117684 -60.164726)
			(xy 86.287864 -60.253626) (xy 86.332314 -60.253626)
		)
		(stroke
			(width 0)
			(type solid)
		)
		(fill yes)
		(layer "In11.Cu")
		(net "M_J_DQ<26>")
	)
	(gr_poly
		(pts
			(xy 86.332314 -58.857896) (xy 86.287864 -58.857896) (xy 86.117684 -58.946796) (xy 86.117684 -59.167776)
			(xy 86.287864 -59.256676) (xy 86.332314 -59.256676)
		)
		(stroke
			(width 0)
			(type solid)
		)
		(fill yes)
		(layer "In11.Cu")
		(net "M_J_DQ<26>")
	)
	(gr_poly
		(pts
			(xy 86.332314 -57.8612) (xy 86.287864 -57.8612) (xy 86.117684 -57.9501) (xy 86.117684 -58.17108)
			(xy 86.287864 -58.25998) (xy 86.332314 -58.25998)
		)
		(stroke
			(width 0)
			(type solid)
		)
		(fill yes)
		(layer "In11.Cu")
		(net "M_J_DQ<26>")
	)
	(gr_poly
		(pts
			(xy 86.332314 -56.883046) (xy 86.287864 -56.883046) (xy 86.117684 -56.971946) (xy 86.117684 -57.192926)
			(xy 86.287864 -57.281826) (xy 86.332314 -57.281826)
		)
		(stroke
			(width 0)
			(type solid)
		)
		(fill yes)
		(layer "In11.Cu")
		(net "M_J_DQ<26>")
	)
	(gr_poly
		(pts
			(xy 86.332314 -55.892446) (xy 86.287864 -55.892446) (xy 86.117684 -55.981346) (xy 86.117684 -56.202326)
			(xy 86.287864 -56.291226) (xy 86.332314 -56.291226)
		)
		(stroke
			(width 0)
			(type solid)
		)
		(fill yes)
		(layer "In11.Cu")
		(net "M_J_DQ<26>")
	)
	(gr_poly
		(pts
			(xy 86.332314 -54.901846) (xy 86.287864 -54.901846) (xy 86.117684 -54.990746) (xy 86.117684 -55.211726)
			(xy 86.287864 -55.300626) (xy 86.332314 -55.300626)
		)
		(stroke
			(width 0)
			(type solid)
		)
		(fill yes)
		(layer "In11.Cu")
		(net "M_J_DQ<26>")
	)
	(gr_poly
		(pts
			(xy 86.332568 -94.530164) (xy 86.288118 -94.530418) (xy 86.117938 -94.619318) (xy 86.117938 -94.840298)
			(xy 86.288118 -94.929198) (xy 86.332568 -94.929198)
		)
		(stroke
			(width 0)
			(type solid)
		)
		(fill yes)
		(layer "In11.Cu")
		(net "M_M_DQ<26>")
	)
	(gr_poly
		(pts
			(xy 86.459822 -98.167952) (xy 86.33714 -97.99447) (xy 86.298532 -97.972118) (xy 86.095586 -98.324416)
			(xy 86.134194 -98.346514) (xy 86.345776 -98.365818)
		)
		(stroke
			(width 0)
			(type solid)
		)
		(fill yes)
		(layer "In11.Cu")
		(net "M_M_DQ<27>")
	)
	(gr_poly
		(pts
			(xy 86.523068 -86.599776) (xy 86.478618 -86.599776) (xy 86.308438 -86.688676) (xy 86.308438 -86.909656)
			(xy 86.478618 -86.998556) (xy 86.523068 -86.998556)
		)
		(stroke
			(width 0)
			(type solid)
		)
		(fill yes)
		(layer "In11.Cu")
		(net "M_M_DQ<26>")
	)
	(gr_poly
		(pts
			(xy 86.572598 -93.870018) (xy 86.56447 -93.678248) (xy 86.542626 -93.639894) (xy 86.197186 -93.839284)
			(xy 86.219284 -93.877638) (xy 86.381336 -93.980508)
		)
		(stroke
			(width 0)
			(type solid)
		)
		(fill yes)
		(layer "In11.Cu")
		(net "M_M_DQ<31>")
	)
	(gr_poly
		(pts
			(xy 86.700868 -54.802024) (xy 86.870794 -54.712616) (xy 86.870032 -54.49189) (xy 86.699852 -54.403498)
			(xy 86.655402 -54.403498) (xy 86.656164 -54.802278)
		)
		(stroke
			(width 0)
			(type solid)
		)
		(fill yes)
		(layer "In11.Cu")
		(net "M_J_DQ<27>")
	)
	(gr_poly
		(pts
			(xy 86.791292 -94.112842) (xy 86.76894 -94.074488) (xy 86.606888 -93.971618) (xy 86.415626 -94.082108)
			(xy 86.4235 -94.273878) (xy 86.445852 -94.312486)
		)
		(stroke
			(width 0)
			(type solid)
		)
		(fill yes)
		(layer "In11.Cu")
		(net "M_M_DQ<26>")
	)
	(gr_poly
		(pts
			(xy 86.870286 -93.332808) (xy 86.870286 -93.111828) (xy 86.700106 -93.023182) (xy 86.65591 -93.022928)
			(xy 86.65591 -93.421708) (xy 86.700106 -93.421708)
		)
		(stroke
			(width 0)
			(type solid)
		)
		(fill yes)
		(layer "In11.Cu")
		(net "M_M_DQ<31>")
	)
	(gr_poly
		(pts
			(xy 86.87054 -97.29978) (xy 86.87054 -97.0788) (xy 86.70036 -96.9899) (xy 86.65591 -96.9899) (xy 86.65591 -97.38868)
			(xy 86.70036 -97.38868)
		)
		(stroke
			(width 0)
			(type solid)
		)
		(fill yes)
		(layer "In11.Cu")
		(net "M_M_DQ<27>")
	)
	(gr_poly
		(pts
			(xy 86.87054 -96.30918) (xy 86.87054 -96.0882) (xy 86.70036 -95.9993) (xy 86.65591 -95.9993) (xy 86.65591 -96.39808)
			(xy 86.70036 -96.39808)
		)
		(stroke
			(width 0)
			(type solid)
		)
		(fill yes)
		(layer "In11.Cu")
		(net "M_M_DQ<27>")
	)
	(gr_poly
		(pts
			(xy 86.87054 -95.31858) (xy 86.87054 -95.0976) (xy 86.70036 -95.0087) (xy 86.65591 -95.0087) (xy 86.65591 -95.40748)
			(xy 86.70036 -95.40748)
		)
		(stroke
			(width 0)
			(type solid)
		)
		(fill yes)
		(layer "In11.Cu")
		(net "M_M_DQ<27>")
	)
	(gr_poly
		(pts
			(xy 86.87054 -92.34678) (xy 86.87054 -92.1258) (xy 86.70036 -92.0369) (xy 86.65591 -92.0369) (xy 86.65591 -92.43568)
			(xy 86.70036 -92.43568)
		)
		(stroke
			(width 0)
			(type solid)
		)
		(fill yes)
		(layer "In11.Cu")
		(net "M_M_DQ<31>")
	)
	(gr_poly
		(pts
			(xy 86.87054 -91.35618) (xy 86.87054 -91.1352) (xy 86.70036 -91.0463) (xy 86.65591 -91.0463) (xy 86.65591 -91.44508)
			(xy 86.70036 -91.44508)
		)
		(stroke
			(width 0)
			(type solid)
		)
		(fill yes)
		(layer "In11.Cu")
		(net "M_M_DQ<31>")
	)
	(gr_poly
		(pts
			(xy 86.87054 -90.36558) (xy 86.87054 -90.1446) (xy 86.70036 -90.0557) (xy 86.65591 -90.0557) (xy 86.65591 -90.45448)
			(xy 86.70036 -90.45448)
		)
		(stroke
			(width 0)
			(type solid)
		)
		(fill yes)
		(layer "In11.Cu")
		(net "M_M_DQ<31>")
	)
	(gr_poly
		(pts
			(xy 86.87054 -89.37498) (xy 86.87054 -89.154) (xy 86.70036 -89.0651) (xy 86.65591 -89.0651) (xy 86.65591 -89.46388)
			(xy 86.70036 -89.46388)
		)
		(stroke
			(width 0)
			(type solid)
		)
		(fill yes)
		(layer "In11.Cu")
		(net "M_M_DQ<31>")
	)
	(gr_poly
		(pts
			(xy 86.87054 -88.38438) (xy 86.87054 -88.1634) (xy 86.70036 -88.0745) (xy 86.65591 -88.0745) (xy 86.65591 -88.47328)
			(xy 86.70036 -88.47328)
		)
		(stroke
			(width 0)
			(type solid)
		)
		(fill yes)
		(layer "In11.Cu")
		(net "M_M_DQ<31>")
	)
	(gr_poly
		(pts
			(xy 86.87054 -65.60058) (xy 86.87054 -65.3796) (xy 86.70036 -65.2907) (xy 86.65591 -65.2907) (xy 86.65591 -65.68948)
			(xy 86.70036 -65.68948)
		)
		(stroke
			(width 0)
			(type solid)
		)
		(fill yes)
		(layer "In11.Cu")
		(net "M_J_DQ<27>")
	)
	(gr_poly
		(pts
			(xy 86.87054 -64.60998) (xy 86.87054 -64.389) (xy 86.70036 -64.3001) (xy 86.65591 -64.3001) (xy 86.65591 -64.69888)
			(xy 86.70036 -64.69888)
		)
		(stroke
			(width 0)
			(type solid)
		)
		(fill yes)
		(layer "In11.Cu")
		(net "M_J_DQ<27>")
	)
	(gr_poly
		(pts
			(xy 86.87054 -63.61938) (xy 86.87054 -63.3984) (xy 86.70036 -63.3095) (xy 86.65591 -63.3095) (xy 86.65591 -63.70828)
			(xy 86.70036 -63.70828)
		)
		(stroke
			(width 0)
			(type solid)
		)
		(fill yes)
		(layer "In11.Cu")
		(net "M_J_DQ<27>")
	)
	(gr_poly
		(pts
			(xy 86.87054 -62.62878) (xy 86.87054 -62.4078) (xy 86.70036 -62.3189) (xy 86.65591 -62.3189) (xy 86.65591 -62.71768)
			(xy 86.70036 -62.71768)
		)
		(stroke
			(width 0)
			(type solid)
		)
		(fill yes)
		(layer "In11.Cu")
		(net "M_J_DQ<27>")
	)
	(gr_poly
		(pts
			(xy 86.87054 -61.63818) (xy 86.87054 -61.4172) (xy 86.70036 -61.3283) (xy 86.65591 -61.3283) (xy 86.65591 -61.72708)
			(xy 86.70036 -61.72708)
		)
		(stroke
			(width 0)
			(type solid)
		)
		(fill yes)
		(layer "In11.Cu")
		(net "M_J_DQ<27>")
	)
	(gr_poly
		(pts
			(xy 86.87054 -60.64758) (xy 86.87054 -60.4266) (xy 86.70036 -60.3377) (xy 86.65591 -60.3377) (xy 86.65591 -60.73648)
			(xy 86.70036 -60.73648)
		)
		(stroke
			(width 0)
			(type solid)
		)
		(fill yes)
		(layer "In11.Cu")
		(net "M_J_DQ<27>")
	)
	(gr_poly
		(pts
			(xy 86.87054 -59.65698) (xy 86.87054 -59.436) (xy 86.70036 -59.3471) (xy 86.65591 -59.3471) (xy 86.65591 -59.74588)
			(xy 86.70036 -59.74588)
		)
		(stroke
			(width 0)
			(type solid)
		)
		(fill yes)
		(layer "In11.Cu")
		(net "M_J_DQ<27>")
	)
	(gr_poly
		(pts
			(xy 86.87054 -58.678826) (xy 86.87054 -58.457846) (xy 86.70036 -58.368946) (xy 86.65591 -58.368946)
			(xy 86.65591 -58.767726) (xy 86.70036 -58.767726)
		)
		(stroke
			(width 0)
			(type solid)
		)
		(fill yes)
		(layer "In11.Cu")
		(net "M_J_DQ<27>")
	)
	(gr_poly
		(pts
			(xy 86.87054 -57.68213) (xy 86.87054 -57.46115) (xy 86.70036 -57.37225) (xy 86.65591 -57.37225) (xy 86.65591 -57.77103)
			(xy 86.70036 -57.77103)
		)
		(stroke
			(width 0)
			(type solid)
		)
		(fill yes)
		(layer "In11.Cu")
		(net "M_J_DQ<27>")
	)
	(gr_poly
		(pts
			(xy 86.87054 -56.68518) (xy 86.87054 -56.4642) (xy 86.70036 -56.3753) (xy 86.65591 -56.3753) (xy 86.65591 -56.77408)
			(xy 86.70036 -56.77408)
		)
		(stroke
			(width 0)
			(type solid)
		)
		(fill yes)
		(layer "In11.Cu")
		(net "M_J_DQ<27>")
	)
	(gr_poly
		(pts
			(xy 86.87054 -55.69458) (xy 86.87054 -55.4736) (xy 86.70036 -55.3847) (xy 86.65591 -55.3847) (xy 86.65591 -55.78348)
			(xy 86.70036 -55.78348)
		)
		(stroke
			(width 0)
			(type solid)
		)
		(fill yes)
		(layer "In11.Cu")
		(net "M_J_DQ<27>")
	)
	(gr_poly
		(pts
			(xy 87.190834 -93.03385) (xy 87.146384 -93.03385) (xy 86.976204 -93.12275) (xy 86.976204 -93.34373)
			(xy 87.146384 -93.43263) (xy 87.190834 -93.43263)
		)
		(stroke
			(width 0)
			(type solid)
		)
		(fill yes)
		(layer "In11.Cu")
		(net "M_M_DQ<26>")
	)
	(gr_poly
		(pts
			(xy 87.190834 -92.0369) (xy 87.146384 -92.0369) (xy 86.976204 -92.1258) (xy 86.976204 -92.34678)
			(xy 87.146384 -92.43568) (xy 87.190834 -92.43568)
		)
		(stroke
			(width 0)
			(type solid)
		)
		(fill yes)
		(layer "In11.Cu")
		(net "M_M_DQ<26>")
	)
	(gr_poly
		(pts
			(xy 87.190834 -91.0463) (xy 87.146384 -91.0463) (xy 86.976204 -91.1352) (xy 86.976204 -91.35618)
			(xy 87.146384 -91.44508) (xy 87.190834 -91.44508)
		)
		(stroke
			(width 0)
			(type solid)
		)
		(fill yes)
		(layer "In11.Cu")
		(net "M_M_DQ<26>")
	)
	(gr_poly
		(pts
			(xy 87.190834 -90.0557) (xy 87.146384 -90.0557) (xy 86.976204 -90.1446) (xy 86.976204 -90.36558)
			(xy 87.146384 -90.45448) (xy 87.190834 -90.45448)
		)
		(stroke
			(width 0)
			(type solid)
		)
		(fill yes)
		(layer "In11.Cu")
		(net "M_M_DQ<26>")
	)
	(gr_poly
		(pts
			(xy 87.190834 -89.0651) (xy 87.146384 -89.0651) (xy 86.976204 -89.154) (xy 86.976204 -89.37498) (xy 87.146384 -89.46388)
			(xy 87.190834 -89.46388)
		)
		(stroke
			(width 0)
			(type solid)
		)
		(fill yes)
		(layer "In11.Cu")
		(net "M_M_DQ<26>")
	)
	(gr_poly
		(pts
			(xy 87.190834 -88.0745) (xy 87.146384 -88.0745) (xy 86.976204 -88.1634) (xy 86.976204 -88.38438)
			(xy 87.146384 -88.47328) (xy 87.190834 -88.47328)
		)
		(stroke
			(width 0)
			(type solid)
		)
		(fill yes)
		(layer "In11.Cu")
		(net "M_M_DQ<26>")
	)
	(gr_poly
		(pts
			(xy 87.42934 -94.366588) (xy 87.421212 -94.174818) (xy 87.399114 -94.135956) (xy 87.053928 -94.3356)
			(xy 87.076026 -94.373954) (xy 87.238078 -94.476824)
		)
		(stroke
			(width 0)
			(type solid)
		)
		(fill yes)
		(layer "In11.Cu")
		(net "M_M_DQ<27>")
	)
	(gr_poly
		(pts
			(xy 87.728806 -93.83014) (xy 87.728806 -93.609414) (xy 87.55888 -93.520514) (xy 87.514176 -93.52026)
			(xy 87.51443 -93.91904) (xy 87.558626 -93.91904)
		)
		(stroke
			(width 0)
			(type solid)
		)
		(fill yes)
		(layer "In11.Cu")
		(net "M_M_DQ<27>")
	)
	(gr_poly
		(pts
			(xy 87.72906 -92.854526) (xy 87.72906 -92.633546) (xy 87.55888 -92.544646) (xy 87.51443 -92.544646)
			(xy 87.51443 -92.943426) (xy 87.55888 -92.943426)
		)
		(stroke
			(width 0)
			(type solid)
		)
		(fill yes)
		(layer "In11.Cu")
		(net "M_M_DQ<27>")
	)
	(gr_poly
		(pts
			(xy 87.72906 -91.863926) (xy 87.72906 -91.642946) (xy 87.55888 -91.554046) (xy 87.51443 -91.554046)
			(xy 87.51443 -91.952826) (xy 87.55888 -91.952826)
		)
		(stroke
			(width 0)
			(type solid)
		)
		(fill yes)
		(layer "In11.Cu")
		(net "M_M_DQ<27>")
	)
	(gr_poly
		(pts
			(xy 87.72906 -90.873326) (xy 87.72906 -90.652346) (xy 87.55888 -90.563446) (xy 87.51443 -90.563446)
			(xy 87.51443 -90.962226) (xy 87.55888 -90.962226)
		)
		(stroke
			(width 0)
			(type solid)
		)
		(fill yes)
		(layer "In11.Cu")
		(net "M_M_DQ<27>")
	)
	(gr_poly
		(pts
			(xy 87.72906 -89.882726) (xy 87.72906 -89.661746) (xy 87.55888 -89.572846) (xy 87.51443 -89.572846)
			(xy 87.51443 -89.971626) (xy 87.55888 -89.971626)
		)
		(stroke
			(width 0)
			(type solid)
		)
		(fill yes)
		(layer "In11.Cu")
		(net "M_M_DQ<27>")
	)
	(gr_poly
		(pts
			(xy 87.72906 -88.892126) (xy 87.72906 -88.671146) (xy 87.55888 -88.582246) (xy 87.51443 -88.582246)
			(xy 87.51443 -88.981026) (xy 87.55888 -88.981026)
		)
		(stroke
			(width 0)
			(type solid)
		)
		(fill yes)
		(layer "In11.Cu")
		(net "M_M_DQ<27>")
	)
	(gr_poly
		(pts
			(xy 87.72906 -87.901526) (xy 87.72906 -87.680546) (xy 87.55888 -87.591646) (xy 87.51443 -87.591646)
			(xy 87.51443 -87.990426) (xy 87.55888 -87.990426)
		)
		(stroke
			(width 0)
			(type solid)
		)
		(fill yes)
		(layer "In11.Cu")
		(net "M_M_DQ<27>")
	)
	(gr_poly
		(pts
			(xy 106.173778 -99.297744) (xy 106.129328 -99.297744) (xy 105.959148 -99.386644) (xy 105.959148 -99.607624)
			(xy 106.129328 -99.696524) (xy 106.173778 -99.696524)
		)
		(stroke
			(width 0)
			(type solid)
		)
		(fill yes)
		(layer "In11.Cu")
		(net "M_M_DQ<36>")
	)
	(gr_poly
		(pts
			(xy 106.173778 -98.307144) (xy 106.129328 -98.307144) (xy 105.959148 -98.396044) (xy 105.959148 -98.617024)
			(xy 106.129328 -98.705924) (xy 106.173778 -98.705924)
		)
		(stroke
			(width 0)
			(type solid)
		)
		(fill yes)
		(layer "In11.Cu")
		(net "M_M_DQ<36>")
	)
	(gr_poly
		(pts
			(xy 106.173778 -97.316544) (xy 106.129328 -97.316544) (xy 105.959148 -97.405444) (xy 105.959148 -97.626424)
			(xy 106.129328 -97.715324) (xy 106.173778 -97.715324)
		)
		(stroke
			(width 0)
			(type solid)
		)
		(fill yes)
		(layer "In11.Cu")
		(net "M_M_DQ<36>")
	)
	(gr_poly
		(pts
			(xy 106.173778 -96.325944) (xy 106.129328 -96.325944) (xy 105.959148 -96.414844) (xy 105.959148 -96.635824)
			(xy 106.129328 -96.724724) (xy 106.173778 -96.724724)
		)
		(stroke
			(width 0)
			(type solid)
		)
		(fill yes)
		(layer "In11.Cu")
		(net "M_M_DQ<36>")
	)
	(gr_poly
		(pts
			(xy 106.173778 -95.328994) (xy 106.129328 -95.328994) (xy 105.959148 -95.417894) (xy 105.959148 -95.638874)
			(xy 106.129328 -95.727774) (xy 106.173778 -95.727774)
		)
		(stroke
			(width 0)
			(type solid)
		)
		(fill yes)
		(layer "In11.Cu")
		(net "M_M_DQ<36>")
	)
	(gr_poly
		(pts
			(xy 106.173778 -94.332298) (xy 106.129328 -94.332298) (xy 105.959148 -94.421198) (xy 105.959148 -94.642178)
			(xy 106.129328 -94.731078) (xy 106.173778 -94.731078)
		)
		(stroke
			(width 0)
			(type solid)
		)
		(fill yes)
		(layer "In11.Cu")
		(net "M_M_DQ<36>")
	)
	(gr_poly
		(pts
			(xy 106.34726 -93.088714) (xy 106.308906 -93.066616) (xy 106.117136 -93.058488) (xy 106.006646 -93.24975)
			(xy 106.109516 -93.411802) (xy 106.148124 -93.434154)
		)
		(stroke
			(width 0)
			(type solid)
		)
		(fill yes)
		(layer "In11.Cu")
		(net "M_M_DQ<36>")
	)
	(gr_poly
		(pts
			(xy 106.712004 -99.099878) (xy 106.712004 -98.878898) (xy 106.541824 -98.789998) (xy 106.497374 -98.789998)
			(xy 106.497374 -99.188778) (xy 106.541824 -99.188778)
		)
		(stroke
			(width 0)
			(type solid)
		)
		(fill yes)
		(layer "In11.Cu")
		(net "M_M_DQ<37>")
	)
	(gr_poly
		(pts
			(xy 106.712004 -98.109278) (xy 106.712004 -97.888298) (xy 106.541824 -97.799398) (xy 106.497374 -97.799398)
			(xy 106.497374 -98.198178) (xy 106.541824 -98.198178)
		)
		(stroke
			(width 0)
			(type solid)
		)
		(fill yes)
		(layer "In11.Cu")
		(net "M_M_DQ<37>")
	)
	(gr_poly
		(pts
			(xy 106.712004 -97.118678) (xy 106.712004 -96.897698) (xy 106.541824 -96.808798) (xy 106.497374 -96.808798)
			(xy 106.497374 -97.207578) (xy 106.541824 -97.207578)
		)
		(stroke
			(width 0)
			(type solid)
		)
		(fill yes)
		(layer "In11.Cu")
		(net "M_M_DQ<37>")
	)
	(gr_poly
		(pts
			(xy 106.712004 -96.128078) (xy 106.712004 -95.907098) (xy 106.541824 -95.818198) (xy 106.497374 -95.818198)
			(xy 106.497374 -96.216978) (xy 106.541824 -96.216978)
		)
		(stroke
			(width 0)
			(type solid)
		)
		(fill yes)
		(layer "In11.Cu")
		(net "M_M_DQ<37>")
	)
	(gr_poly
		(pts
			(xy 106.712004 -95.149924) (xy 106.712004 -94.928944) (xy 106.541824 -94.840044) (xy 106.497374 -94.840044)
			(xy 106.497374 -95.238824) (xy 106.541824 -95.238824)
		)
		(stroke
			(width 0)
			(type solid)
		)
		(fill yes)
		(layer "In11.Cu")
		(net "M_M_DQ<37>")
	)
	(gr_poly
		(pts
			(xy 106.712004 -94.153228) (xy 106.712004 -93.932248) (xy 106.541824 -93.843348) (xy 106.497374 -93.843348)
			(xy 106.497374 -94.242128) (xy 106.541824 -94.242128)
		)
		(stroke
			(width 0)
			(type solid)
		)
		(fill yes)
		(layer "In11.Cu")
		(net "M_M_DQ<37>")
	)
	(gr_poly
		(pts
			(xy 106.736134 -100.989384) (xy 106.76763 -100.957888) (xy 106.480356 -100.670614) (xy 106.44886 -100.70211)
			(xy 106.3752 -100.901246) (xy 106.536998 -101.063044)
		)
		(stroke
			(width 0)
			(type solid)
		)
		(fill yes)
		(layer "In11.Cu")
		(net "M_M_DQ<36>")
	)
	(gr_poly
		(pts
			(xy 106.747564 -58.676794) (xy 106.703114 -58.676794) (xy 106.532934 -58.765694) (xy 106.532934 -58.986674)
			(xy 106.703114 -59.075574) (xy 106.747564 -59.075574)
		)
		(stroke
			(width 0)
			(type solid)
		)
		(fill yes)
		(layer "In11.Cu")
		(net "M_J_DQ<36>")
	)
	(gr_poly
		(pts
			(xy 106.747818 -57.692544) (xy 106.703368 -57.692544) (xy 106.533188 -57.781444) (xy 106.533188 -58.002424)
			(xy 106.703368 -58.091324) (xy 106.747818 -58.091324)
		)
		(stroke
			(width 0)
			(type solid)
		)
		(fill yes)
		(layer "In11.Cu")
		(net "M_J_DQ<36>")
	)
	(gr_poly
		(pts
			(xy 106.747818 -56.701944) (xy 106.703368 -56.701944) (xy 106.533188 -56.790844) (xy 106.533188 -57.011824)
			(xy 106.703368 -57.100724) (xy 106.747818 -57.100724)
		)
		(stroke
			(width 0)
			(type solid)
		)
		(fill yes)
		(layer "In11.Cu")
		(net "M_J_DQ<36>")
	)
	(gr_poly
		(pts
			(xy 106.747818 -55.711344) (xy 106.703368 -55.711344) (xy 106.533188 -55.800244) (xy 106.533188 -56.021224)
			(xy 106.703368 -56.110124) (xy 106.747818 -56.110124)
		)
		(stroke
			(width 0)
			(type solid)
		)
		(fill yes)
		(layer "In11.Cu")
		(net "M_J_DQ<36>")
	)
	(gr_poly
		(pts
			(xy 106.747818 -54.720744) (xy 106.703368 -54.720744) (xy 106.533188 -54.809644) (xy 106.533188 -55.030624)
			(xy 106.703368 -55.119524) (xy 106.747818 -55.119524)
		)
		(stroke
			(width 0)
			(type solid)
		)
		(fill yes)
		(layer "In11.Cu")
		(net "M_J_DQ<36>")
	)
	(gr_poly
		(pts
			(xy 106.821732 -52.942998) (xy 106.777282 -52.942998) (xy 106.584242 -53.031898) (xy 106.584242 -53.260498)
			(xy 106.777282 -53.349398) (xy 106.821732 -53.349398)
		)
		(stroke
			(width 0)
			(type solid)
		)
		(fill yes)
		(layer "In11.Cu")
		(net "M_J_DQ<36>")
	)
	(gr_poly
		(pts
			(xy 106.821732 -51.952398) (xy 106.777282 -51.952398) (xy 106.584242 -52.041298) (xy 106.584242 -52.269898)
			(xy 106.777282 -52.358798) (xy 106.821732 -52.358798)
		)
		(stroke
			(width 0)
			(type solid)
		)
		(fill yes)
		(layer "In11.Cu")
		(net "M_J_DQ<36>")
	)
	(gr_poly
		(pts
			(xy 106.933746 -100.791772) (xy 107.007406 -100.592382) (xy 106.845862 -100.430838) (xy 106.646472 -100.504498)
			(xy 106.614976 -100.53574) (xy 106.902504 -100.823268)
		)
		(stroke
			(width 0)
			(type solid)
		)
		(fill yes)
		(layer "In11.Cu")
		(net "M_M_DQ<37>")
	)
	(gr_poly
		(pts
			(xy 107.028488 -103.291386) (xy 106.984038 -103.291386) (xy 106.790998 -103.380286) (xy 106.790998 -103.608886)
			(xy 106.984038 -103.697786) (xy 107.028488 -103.697786)
		)
		(stroke
			(width 0)
			(type solid)
		)
		(fill yes)
		(layer "In11.Cu")
		(net "M_M_DQ<36>")
	)
	(gr_poly
		(pts
			(xy 107.028488 -102.300786) (xy 106.984038 -102.300786) (xy 106.790998 -102.389686) (xy 106.790998 -102.618286)
			(xy 106.984038 -102.707186) (xy 107.028488 -102.707186)
		)
		(stroke
			(width 0)
			(type solid)
		)
		(fill yes)
		(layer "In11.Cu")
		(net "M_M_DQ<36>")
	)
	(gr_poly
		(pts
			(xy 107.028488 -101.310186) (xy 106.984038 -101.310186) (xy 106.790998 -101.399086) (xy 106.790998 -101.627686)
			(xy 106.984038 -101.716586) (xy 107.028488 -101.716586)
		)
		(stroke
			(width 0)
			(type solid)
		)
		(fill yes)
		(layer "In11.Cu")
		(net "M_M_DQ<36>")
	)
	(gr_poly
		(pts
			(xy 107.032298 -99.780598) (xy 106.987848 -99.780598) (xy 106.817668 -99.869498) (xy 106.817668 -100.090478)
			(xy 106.987848 -100.179378) (xy 107.032298 -100.179378)
		)
		(stroke
			(width 0)
			(type solid)
		)
		(fill yes)
		(layer "In11.Cu")
		(net "M_M_DQ<32>")
	)
	(gr_poly
		(pts
			(xy 107.032298 -98.789998) (xy 106.987848 -98.789998) (xy 106.817668 -98.878898) (xy 106.817668 -99.099878)
			(xy 106.987848 -99.188778) (xy 107.032298 -99.188778)
		)
		(stroke
			(width 0)
			(type solid)
		)
		(fill yes)
		(layer "In11.Cu")
		(net "M_M_DQ<32>")
	)
	(gr_poly
		(pts
			(xy 107.032298 -97.799398) (xy 106.987848 -97.799398) (xy 106.817668 -97.888298) (xy 106.817668 -98.109278)
			(xy 106.987848 -98.198178) (xy 107.032298 -98.198178)
		)
		(stroke
			(width 0)
			(type solid)
		)
		(fill yes)
		(layer "In11.Cu")
		(net "M_M_DQ<32>")
	)
	(gr_poly
		(pts
			(xy 107.032298 -96.808798) (xy 106.987848 -96.808798) (xy 106.817668 -96.897698) (xy 106.817668 -97.118678)
			(xy 106.987848 -97.207578) (xy 107.032298 -97.207578)
		)
		(stroke
			(width 0)
			(type solid)
		)
		(fill yes)
		(layer "In11.Cu")
		(net "M_M_DQ<32>")
	)
	(gr_poly
		(pts
			(xy 107.032298 -95.818198) (xy 106.987848 -95.818198) (xy 106.817668 -95.907098) (xy 106.817668 -96.128078)
			(xy 106.987848 -96.216978) (xy 107.032298 -96.216978)
		)
		(stroke
			(width 0)
			(type solid)
		)
		(fill yes)
		(layer "In11.Cu")
		(net "M_M_DQ<32>")
	)
	(gr_poly
		(pts
			(xy 107.032298 -94.840044) (xy 106.987848 -94.840044) (xy 106.817668 -94.928944) (xy 106.817668 -95.149924)
			(xy 106.987848 -95.238824) (xy 107.032298 -95.238824)
		)
		(stroke
			(width 0)
			(type solid)
		)
		(fill yes)
		(layer "In11.Cu")
		(net "M_M_DQ<32>")
	)
	(gr_poly
		(pts
			(xy 107.032298 -93.849444) (xy 106.987848 -93.849444) (xy 106.817668 -93.938344) (xy 106.817668 -94.159324)
			(xy 106.987848 -94.248224) (xy 107.032298 -94.248224)
		)
		(stroke
			(width 0)
			(type solid)
		)
		(fill yes)
		(layer "In11.Cu")
		(net "M_M_DQ<32>")
	)
	(gr_poly
		(pts
			(xy 107.065826 -93.345508) (xy 107.139486 -93.168216) (xy 107.135676 -93.12402) (xy 106.73842 -93.158564)
			(xy 106.74223 -93.203014) (xy 106.845608 -93.364812)
		)
		(stroke
			(width 0)
			(type solid)
		)
		(fill yes)
		(layer "In11.Cu")
		(net "M_M_DQ<37>")
	)
	(gr_poly
		(pts
			(xy 107.18038 -91.61399) (xy 107.139994 -91.595194) (xy 106.948224 -91.60383) (xy 106.854752 -91.803982)
			(xy 106.971592 -91.956382) (xy 107.011724 -91.975178)
		)
		(stroke
			(width 0)
			(type solid)
		)
		(fill yes)
		(layer "In11.Cu")
		(net "M_M_DQ<36>")
	)
	(gr_poly
		(pts
			(xy 107.183428 -51.403758) (xy 107.151932 -51.372262) (xy 106.952542 -51.298602) (xy 106.790998 -51.4604)
			(xy 106.864658 -51.65979) (xy 106.896154 -51.691032)
		)
		(stroke
			(width 0)
			(type solid)
		)
		(fill yes)
		(layer "In11.Cu")
		(net "M_J_DQ<36>")
	)
	(gr_poly
		(pts
			(xy 107.249468 -53.260498) (xy 107.249468 -53.031898) (xy 107.056428 -52.942998) (xy 107.011978 -52.942998)
			(xy 107.011978 -53.349398) (xy 107.056428 -53.349398)
		)
		(stroke
			(width 0)
			(type solid)
		)
		(fill yes)
		(layer "In11.Cu")
		(net "M_J_DQ<37>")
	)
	(gr_poly
		(pts
			(xy 107.249468 -52.269898) (xy 107.249468 -52.041298) (xy 107.056428 -51.952398) (xy 107.011978 -51.952398)
			(xy 107.011978 -52.358798) (xy 107.056428 -52.358798)
		)
		(stroke
			(width 0)
			(type solid)
		)
		(fill yes)
		(layer "In11.Cu")
		(net "M_J_DQ<37>")
	)
	(gr_poly
		(pts
			(xy 107.286044 -58.491374) (xy 107.286044 -58.270394) (xy 107.115864 -58.181494) (xy 107.071414 -58.181494)
			(xy 107.071414 -58.580274) (xy 107.115864 -58.580274)
		)
		(stroke
			(width 0)
			(type solid)
		)
		(fill yes)
		(layer "In11.Cu")
		(net "M_J_DQ<37>")
	)
	(gr_poly
		(pts
			(xy 107.286044 -57.494678) (xy 107.286044 -57.273698) (xy 107.115864 -57.184798) (xy 107.071414 -57.184798)
			(xy 107.071414 -57.583578) (xy 107.115864 -57.583578)
		)
		(stroke
			(width 0)
			(type solid)
		)
		(fill yes)
		(layer "In11.Cu")
		(net "M_J_DQ<37>")
	)
	(gr_poly
		(pts
			(xy 107.286044 -56.504078) (xy 107.286044 -56.283098) (xy 107.115864 -56.194198) (xy 107.071414 -56.194198)
			(xy 107.071414 -56.592978) (xy 107.115864 -56.592978)
		)
		(stroke
			(width 0)
			(type solid)
		)
		(fill yes)
		(layer "In11.Cu")
		(net "M_J_DQ<37>")
	)
	(gr_poly
		(pts
			(xy 107.286044 -55.513478) (xy 107.286044 -55.292498) (xy 107.115864 -55.203598) (xy 107.071414 -55.203598)
			(xy 107.071414 -55.602378) (xy 107.115864 -55.602378)
		)
		(stroke
			(width 0)
			(type solid)
		)
		(fill yes)
		(layer "In11.Cu")
		(net "M_J_DQ<37>")
	)
	(gr_poly
		(pts
			(xy 107.38739 -49.244504) (xy 107.418886 -49.213008) (xy 107.131612 -48.925734) (xy 107.100116 -48.95723)
			(xy 107.026456 -49.156366) (xy 107.188254 -49.318164)
		)
		(stroke
			(width 0)
			(type solid)
		)
		(fill yes)
		(layer "In11.Cu")
		(net "M_J_DQ<36>")
	)
	(gr_poly
		(pts
			(xy 107.460796 -103.608886) (xy 107.460796 -103.380286) (xy 107.267756 -103.291386) (xy 107.223306 -103.291386)
			(xy 107.223306 -103.697786) (xy 107.267756 -103.697786)
		)
		(stroke
			(width 0)
			(type solid)
		)
		(fill yes)
		(layer "In11.Cu")
		(net "M_M_DQ<37>")
	)
	(gr_poly
		(pts
			(xy 107.460796 -102.618286) (xy 107.460796 -102.389686) (xy 107.267756 -102.300786) (xy 107.223306 -102.300786)
			(xy 107.223306 -102.707186) (xy 107.267756 -102.707186)
		)
		(stroke
			(width 0)
			(type solid)
		)
		(fill yes)
		(layer "In11.Cu")
		(net "M_M_DQ<37>")
	)
	(gr_poly
		(pts
			(xy 107.460796 -101.627686) (xy 107.460796 -101.399086) (xy 107.267756 -101.310186) (xy 107.223306 -101.310186)
			(xy 107.223306 -101.716586) (xy 107.267756 -101.716586)
		)
		(stroke
			(width 0)
			(type solid)
		)
		(fill yes)
		(layer "In11.Cu")
		(net "M_M_DQ<37>")
	)
	(gr_poly
		(pts
			(xy 107.477052 -100.635562) (xy 107.49915 -100.597208) (xy 107.153964 -100.397564) (xy 107.131612 -100.436172)
			(xy 107.123738 -100.627942) (xy 107.315 -100.738432)
		)
		(stroke
			(width 0)
			(type solid)
		)
		(fill yes)
		(layer "In11.Cu")
		(net "M_M_DQ<32>")
	)
	(gr_poly
		(pts
			(xy 107.5055 -49.9872) (xy 107.46105 -49.9872) (xy 107.26801 -50.0761) (xy 107.26801 -50.3047) (xy 107.46105 -50.3936)
			(xy 107.5055 -50.3936)
		)
		(stroke
			(width 0)
			(type solid)
		)
		(fill yes)
		(layer "In11.Cu")
		(net "M_J_DQ<36>")
	)
	(gr_poly
		(pts
			(xy 107.570524 -99.607624) (xy 107.570524 -99.386644) (xy 107.400344 -99.297744) (xy 107.355894 -99.297744)
			(xy 107.355894 -99.696524) (xy 107.400344 -99.696524)
		)
		(stroke
			(width 0)
			(type solid)
		)
		(fill yes)
		(layer "In11.Cu")
		(net "M_M_DQ<33>")
	)
	(gr_poly
		(pts
			(xy 107.570524 -98.617024) (xy 107.570524 -98.396044) (xy 107.400344 -98.307144) (xy 107.355894 -98.307144)
			(xy 107.355894 -98.705924) (xy 107.400344 -98.705924)
		)
		(stroke
			(width 0)
			(type solid)
		)
		(fill yes)
		(layer "In11.Cu")
		(net "M_M_DQ<33>")
	)
	(gr_poly
		(pts
			(xy 107.570524 -97.626424) (xy 107.570524 -97.405444) (xy 107.400344 -97.316544) (xy 107.355894 -97.316544)
			(xy 107.355894 -97.715324) (xy 107.400344 -97.715324)
		)
		(stroke
			(width 0)
			(type solid)
		)
		(fill yes)
		(layer "In11.Cu")
		(net "M_M_DQ<33>")
	)
	(gr_poly
		(pts
			(xy 107.570524 -96.635824) (xy 107.570524 -96.414844) (xy 107.400344 -96.325944) (xy 107.355894 -96.325944)
			(xy 107.355894 -96.724724) (xy 107.400344 -96.724724)
		)
		(stroke
			(width 0)
			(type solid)
		)
		(fill yes)
		(layer "In11.Cu")
		(net "M_M_DQ<33>")
	)
	(gr_poly
		(pts
			(xy 107.570524 -95.638874) (xy 107.570524 -95.417894) (xy 107.400344 -95.328994) (xy 107.355894 -95.328994)
			(xy 107.355894 -95.727774) (xy 107.400344 -95.727774)
		)
		(stroke
			(width 0)
			(type solid)
		)
		(fill yes)
		(layer "In11.Cu")
		(net "M_M_DQ<33>")
	)
	(gr_poly
		(pts
			(xy 107.570524 -94.642178) (xy 107.570524 -94.421198) (xy 107.400344 -94.332298) (xy 107.355894 -94.332298)
			(xy 107.355894 -94.731078) (xy 107.400344 -94.731078)
		)
		(stroke
			(width 0)
			(type solid)
		)
		(fill yes)
		(layer "In11.Cu")
		(net "M_M_DQ<33>")
	)
	(gr_poly
		(pts
			(xy 107.585002 -49.046892) (xy 107.658662 -48.847502) (xy 107.497118 -48.685958) (xy 107.297728 -48.759618)
			(xy 107.266232 -48.79086) (xy 107.55376 -49.078388)
		)
		(stroke
			(width 0)
			(type solid)
		)
		(fill yes)
		(layer "In11.Cu")
		(net "M_J_DQ<37>")
	)
	(gr_poly
		(pts
			(xy 107.602782 -51.589432) (xy 107.529122 -51.390296) (xy 107.497626 -51.3588) (xy 107.210352 -51.646074)
			(xy 107.241848 -51.67757) (xy 107.440984 -51.75123)
		)
		(stroke
			(width 0)
			(type solid)
		)
		(fill yes)
		(layer "In11.Cu")
		(net "M_J_DQ<37>")
	)
	(gr_poly
		(pts
			(xy 107.606084 -58.181494) (xy 107.561634 -58.181494) (xy 107.391454 -58.270394) (xy 107.391454 -58.491374)
			(xy 107.561634 -58.580274) (xy 107.606084 -58.580274)
		)
		(stroke
			(width 0)
			(type solid)
		)
		(fill yes)
		(layer "In11.Cu")
		(net "M_J_DQ<32>")
	)
	(gr_poly
		(pts
			(xy 107.606338 -57.184798) (xy 107.561888 -57.184798) (xy 107.391708 -57.273698) (xy 107.391708 -57.494678)
			(xy 107.561888 -57.583578) (xy 107.606338 -57.583578)
		)
		(stroke
			(width 0)
			(type solid)
		)
		(fill yes)
		(layer "In11.Cu")
		(net "M_J_DQ<32>")
	)
	(gr_poly
		(pts
			(xy 107.606338 -56.194198) (xy 107.561888 -56.194198) (xy 107.391708 -56.283098) (xy 107.391708 -56.504078)
			(xy 107.561888 -56.592978) (xy 107.606338 -56.592978)
		)
		(stroke
			(width 0)
			(type solid)
		)
		(fill yes)
		(layer "In11.Cu")
		(net "M_J_DQ<32>")
	)
	(gr_poly
		(pts
			(xy 107.606338 -55.203598) (xy 107.561888 -55.203598) (xy 107.391708 -55.292498) (xy 107.391708 -55.513478)
			(xy 107.561888 -55.602378) (xy 107.606338 -55.602378)
		)
		(stroke
			(width 0)
			(type solid)
		)
		(fill yes)
		(layer "In11.Cu")
		(net "M_J_DQ<32>")
	)
	(gr_poly
		(pts
			(xy 107.647486 -54.102762) (xy 107.603036 -54.102762) (xy 107.409996 -54.191662) (xy 107.409996 -54.420262)
			(xy 107.603036 -54.509162) (xy 107.647486 -54.509162)
		)
		(stroke
			(width 0)
			(type solid)
		)
		(fill yes)
		(layer "In11.Cu")
		(net "M_J_DQ<32>")
	)
	(gr_poly
		(pts
			(xy 107.647486 -53.112162) (xy 107.603036 -53.112162) (xy 107.409996 -53.201062) (xy 107.409996 -53.429662)
			(xy 107.603036 -53.518562) (xy 107.647486 -53.518562)
		)
		(stroke
			(width 0)
			(type solid)
		)
		(fill yes)
		(layer "In11.Cu")
		(net "M_J_DQ<32>")
	)
	(gr_poly
		(pts
			(xy 107.677712 -59.550046) (xy 107.691682 -59.35853) (xy 107.503722 -59.242198) (xy 107.338622 -59.340242)
			(xy 107.315 -59.377834) (xy 107.654344 -59.587892)
		)
		(stroke
			(width 0)
			(type solid)
		)
		(fill yes)
		(layer "In11.Cu")
		(net "M_J_DQ<37>")
	)
	(gr_poly
		(pts
			(xy 107.890818 -99.297744) (xy 107.846368 -99.297744) (xy 107.676188 -99.386644) (xy 107.676188 -99.607624)
			(xy 107.846368 -99.696524) (xy 107.890818 -99.696524)
		)
		(stroke
			(width 0)
			(type solid)
		)
		(fill yes)
		(layer "In11.Cu")
		(net "M_M_DQS_DP<13>")
	)
	(gr_poly
		(pts
			(xy 107.890818 -98.307144) (xy 107.846368 -98.307144) (xy 107.676188 -98.396044) (xy 107.676188 -98.617024)
			(xy 107.846368 -98.705924) (xy 107.890818 -98.705924)
		)
		(stroke
			(width 0)
			(type solid)
		)
		(fill yes)
		(layer "In11.Cu")
		(net "M_M_DQS_DP<13>")
	)
	(gr_poly
		(pts
			(xy 107.890818 -97.316544) (xy 107.846368 -97.316544) (xy 107.676188 -97.405444) (xy 107.676188 -97.626424)
			(xy 107.846368 -97.715324) (xy 107.890818 -97.715324)
		)
		(stroke
			(width 0)
			(type solid)
		)
		(fill yes)
		(layer "In11.Cu")
		(net "M_M_DQS_DP<13>")
	)
	(gr_poly
		(pts
			(xy 107.890818 -96.325944) (xy 107.846368 -96.325944) (xy 107.676188 -96.414844) (xy 107.676188 -96.635824)
			(xy 107.846368 -96.724724) (xy 107.890818 -96.724724)
		)
		(stroke
			(width 0)
			(type solid)
		)
		(fill yes)
		(layer "In11.Cu")
		(net "M_M_DQS_DP<13>")
	)
	(gr_poly
		(pts
			(xy 107.890818 -95.328994) (xy 107.846368 -95.328994) (xy 107.676188 -95.417894) (xy 107.676188 -95.638874)
			(xy 107.846368 -95.727774) (xy 107.890818 -95.727774)
		)
		(stroke
			(width 0)
			(type solid)
		)
		(fill yes)
		(layer "In11.Cu")
		(net "M_M_DQS_DP<13>")
	)
	(gr_poly
		(pts
			(xy 107.890818 -94.338394) (xy 107.846368 -94.338394) (xy 107.676188 -94.427294) (xy 107.676188 -94.648274)
			(xy 107.846368 -94.737174) (xy 107.890818 -94.737174)
		)
		(stroke
			(width 0)
			(type solid)
		)
		(fill yes)
		(layer "In11.Cu")
		(net "M_M_DQS_DP<13>")
	)
	(gr_poly
		(pts
			(xy 107.93349 -50.9397) (xy 107.93349 -50.7111) (xy 107.74045 -50.6222) (xy 107.696 -50.6222) (xy 107.696 -51.0286)
			(xy 107.74045 -51.0286)
		)
		(stroke
			(width 0)
			(type solid)
		)
		(fill yes)
		(layer "In11.Cu")
		(net "M_J_DQ<37>")
	)
	(gr_poly
		(pts
			(xy 107.93349 -49.9491) (xy 107.93349 -49.7205) (xy 107.74045 -49.6316) (xy 107.696 -49.6316) (xy 107.696 -50.038)
			(xy 107.74045 -50.038)
		)
		(stroke
			(width 0)
			(type solid)
		)
		(fill yes)
		(layer "In11.Cu")
		(net "M_J_DQ<37>")
	)
	(gr_poly
		(pts
			(xy 108.02366 -103.228394) (xy 107.97921 -103.228394) (xy 107.78617 -103.317294) (xy 107.78617 -103.545894)
			(xy 107.97921 -103.634794) (xy 108.02366 -103.634794)
		)
		(stroke
			(width 0)
			(type solid)
		)
		(fill yes)
		(layer "In11.Cu")
		(net "M_M_DQ<32>")
	)
	(gr_poly
		(pts
			(xy 108.02366 -102.237794) (xy 107.97921 -102.237794) (xy 107.78617 -102.326694) (xy 107.78617 -102.555294)
			(xy 107.97921 -102.644194) (xy 108.02366 -102.644194)
		)
		(stroke
			(width 0)
			(type solid)
		)
		(fill yes)
		(layer "In11.Cu")
		(net "M_M_DQ<32>")
	)
	(gr_poly
		(pts
			(xy 108.02366 -101.247194) (xy 107.97921 -101.247194) (xy 107.78617 -101.336094) (xy 107.78617 -101.564694)
			(xy 107.97921 -101.653594) (xy 108.02366 -101.653594)
		)
		(stroke
			(width 0)
			(type solid)
		)
		(fill yes)
		(layer "In11.Cu")
		(net "M_M_DQ<32>")
	)
	(gr_poly
		(pts
			(xy 108.03128 -93.526356) (xy 108.023152 -93.334586) (xy 108.001054 -93.295978) (xy 107.655614 -93.495622)
			(xy 107.677966 -93.533976) (xy 107.840018 -93.636846)
		)
		(stroke
			(width 0)
			(type solid)
		)
		(fill yes)
		(layer "In11.Cu")
		(net "M_M_DQ<32>")
	)
	(gr_poly
		(pts
			(xy 108.043726 -61.020706) (xy 107.885484 -60.654438) (xy 107.845098 -60.671964) (xy 107.724194 -60.821316)
			(xy 107.811316 -61.024008) (xy 108.003086 -61.038232)
		)
		(stroke
			(width 0)
			(type solid)
		)
		(fill yes)
		(layer "In11.Cu")
		(net "M_J_DQ<33>")
	)
	(gr_poly
		(pts
			(xy 108.075476 -54.420262) (xy 108.075476 -54.191662) (xy 107.882436 -54.102762) (xy 107.837986 -54.102762)
			(xy 107.837986 -54.509162) (xy 107.882436 -54.509162)
		)
		(stroke
			(width 0)
			(type solid)
		)
		(fill yes)
		(layer "In11.Cu")
		(net "M_J_DQ<33>")
	)
	(gr_poly
		(pts
			(xy 108.075476 -53.429662) (xy 108.075476 -53.201062) (xy 107.882436 -53.112162) (xy 107.837986 -53.112162)
			(xy 107.837986 -53.518562) (xy 107.882436 -53.518562)
		)
		(stroke
			(width 0)
			(type solid)
		)
		(fill yes)
		(layer "In11.Cu")
		(net "M_J_DQ<33>")
	)
	(gr_poly
		(pts
			(xy 108.11383 -100.526088) (xy 108.121704 -100.334318) (xy 107.930442 -100.224082) (xy 107.76839 -100.326952)
			(xy 107.746292 -100.365306) (xy 108.091732 -100.564696)
		)
		(stroke
			(width 0)
			(type solid)
		)
		(fill yes)
		(layer "In11.Cu")
		(net "M_M_DQ<33>")
	)
	(gr_poly
		(pts
			(xy 108.117132 -48.252888) (xy 108.072682 -48.252888) (xy 107.879642 -48.341788) (xy 107.879642 -48.570388)
			(xy 108.072682 -48.659288) (xy 108.117132 -48.659288)
		)
		(stroke
			(width 0)
			(type solid)
		)
		(fill yes)
		(layer "In11.Cu")
		(net "M_J_DQ<32>")
	)
	(gr_poly
		(pts
			(xy 108.130594 -51.540664) (xy 108.099098 -51.509168) (xy 107.899962 -51.435508) (xy 107.738164 -51.597306)
			(xy 107.811824 -51.796442) (xy 107.84332 -51.827938)
		)
		(stroke
			(width 0)
			(type solid)
		)
		(fill yes)
		(layer "In11.Cu")
		(net "M_J_DQ<32>")
	)
	(gr_poly
		(pts
			(xy 108.14431 -58.002424) (xy 108.14431 -57.781444) (xy 107.97413 -57.692544) (xy 107.92968 -57.692544)
			(xy 107.92968 -58.091324) (xy 107.97413 -58.091324)
		)
		(stroke
			(width 0)
			(type solid)
		)
		(fill yes)
		(layer "In11.Cu")
		(net "M_J_DQ<33>")
	)
	(gr_poly
		(pts
			(xy 108.144564 -57.011824) (xy 108.144564 -56.790844) (xy 107.974384 -56.701944) (xy 107.929934 -56.701944)
			(xy 107.929934 -57.100724) (xy 107.974384 -57.100724)
		)
		(stroke
			(width 0)
			(type solid)
		)
		(fill yes)
		(layer "In11.Cu")
		(net "M_J_DQ<33>")
	)
	(gr_poly
		(pts
			(xy 108.144564 -56.021224) (xy 108.144564 -55.800244) (xy 107.974384 -55.711344) (xy 107.929934 -55.711344)
			(xy 107.929934 -56.110124) (xy 107.974384 -56.110124)
		)
		(stroke
			(width 0)
			(type solid)
		)
		(fill yes)
		(layer "In11.Cu")
		(net "M_J_DQ<33>")
	)
	(gr_poly
		(pts
			(xy 108.27258 -50.748438) (xy 108.22813 -50.748438) (xy 108.03509 -50.837338) (xy 108.03509 -51.065938)
			(xy 108.22813 -51.154838) (xy 108.27258 -51.154838)
		)
		(stroke
			(width 0)
			(type solid)
		)
		(fill yes)
		(layer "In11.Cu")
		(net "M_J_DQ<32>")
	)
	(gr_poly
		(pts
			(xy 108.27258 -49.757838) (xy 108.22813 -49.757838) (xy 108.03509 -49.846738) (xy 108.03509 -50.075338)
			(xy 108.22813 -50.164238) (xy 108.27258 -50.164238)
		)
		(stroke
			(width 0)
			(type solid)
		)
		(fill yes)
		(layer "In11.Cu")
		(net "M_J_DQ<32>")
	)
	(gr_poly
		(pts
			(xy 108.336842 -100.140516) (xy 108.359194 -100.102162) (xy 108.0135 -99.902772) (xy 107.991402 -99.94138)
			(xy 107.983528 -100.13315) (xy 108.17479 -100.24364)
		)
		(stroke
			(width 0)
			(type solid)
		)
		(fill yes)
		(layer "In11.Cu")
		(net "M_M_DQS_DP<13>")
	)
	(gr_poly
		(pts
			(xy 108.35894 -93.926406) (xy 108.336588 -93.888052) (xy 108.174536 -93.785182) (xy 107.983274 -93.895418)
			(xy 107.991148 -94.087188) (xy 108.0135 -94.12605)
		)
		(stroke
			(width 0)
			(type solid)
		)
		(fill yes)
		(layer "In11.Cu")
		(net "M_M_DQS_DP<13>")
	)
	(gr_poly
		(pts
			(xy 108.370116 -51.905662) (xy 108.296456 -51.706526) (xy 108.26496 -51.67503) (xy 107.977686 -51.962304)
			(xy 108.009182 -51.9938) (xy 108.208318 -52.06746)
		)
		(stroke
			(width 0)
			(type solid)
		)
		(fill yes)
		(layer "In11.Cu")
		(net "M_J_DQ<33>")
	)
	(gr_poly
		(pts
			(xy 108.429044 -99.099878) (xy 108.429044 -98.878898) (xy 108.258864 -98.789998) (xy 108.214414 -98.789998)
			(xy 108.214414 -99.188778) (xy 108.258864 -99.188778)
		)
		(stroke
			(width 0)
			(type solid)
		)
		(fill yes)
		(layer "In11.Cu")
		(net "M_M_DQS_DN<13>")
	)
	(gr_poly
		(pts
			(xy 108.429044 -98.109278) (xy 108.429044 -97.888298) (xy 108.258864 -97.799398) (xy 108.214414 -97.799398)
			(xy 108.214414 -98.198178) (xy 108.258864 -98.198178)
		)
		(stroke
			(width 0)
			(type solid)
		)
		(fill yes)
		(layer "In11.Cu")
		(net "M_M_DQS_DN<13>")
	)
	(gr_poly
		(pts
			(xy 108.429044 -97.118678) (xy 108.429044 -96.897698) (xy 108.258864 -96.808798) (xy 108.214414 -96.808798)
			(xy 108.214414 -97.207578) (xy 108.258864 -97.207578)
		)
		(stroke
			(width 0)
			(type solid)
		)
		(fill yes)
		(layer "In11.Cu")
		(net "M_M_DQS_DN<13>")
	)
	(gr_poly
		(pts
			(xy 108.429044 -96.128078) (xy 108.429044 -95.907098) (xy 108.258864 -95.818198) (xy 108.214414 -95.818198)
			(xy 108.214414 -96.216978) (xy 108.258864 -96.216978)
		)
		(stroke
			(width 0)
			(type solid)
		)
		(fill yes)
		(layer "In11.Cu")
		(net "M_M_DQS_DN<13>")
	)
	(gr_poly
		(pts
			(xy 108.429044 -95.149924) (xy 108.429044 -94.928944) (xy 108.258864 -94.840044) (xy 108.214414 -94.840044)
			(xy 108.214414 -95.238824) (xy 108.258864 -95.238824)
		)
		(stroke
			(width 0)
			(type solid)
		)
		(fill yes)
		(layer "In11.Cu")
		(net "M_M_DQS_DN<13>")
	)
	(gr_poly
		(pts
			(xy 108.446062 -54.219348) (xy 108.401612 -54.219348) (xy 108.208572 -54.308248) (xy 108.208572 -54.536848)
			(xy 108.401612 -54.625748) (xy 108.446062 -54.625748)
		)
		(stroke
			(width 0)
			(type solid)
		)
		(fill yes)
		(layer "In11.Cu")
		(net "M_J_DQS_DP<13>")
	)
	(gr_poly
		(pts
			(xy 108.446062 -53.228748) (xy 108.401612 -53.228748) (xy 108.208572 -53.317648) (xy 108.208572 -53.546248)
			(xy 108.401612 -53.635148) (xy 108.446062 -53.635148)
		)
		(stroke
			(width 0)
			(type solid)
		)
		(fill yes)
		(layer "In11.Cu")
		(net "M_J_DQS_DP<13>")
	)
	(gr_poly
		(pts
			(xy 108.452158 -103.418894) (xy 108.452158 -103.190294) (xy 108.259118 -103.101394) (xy 108.214668 -103.101394)
			(xy 108.214668 -103.507794) (xy 108.259118 -103.507794)
		)
		(stroke
			(width 0)
			(type solid)
		)
		(fill yes)
		(layer "In11.Cu")
		(net "M_M_DQ<33>")
	)
	(gr_poly
		(pts
			(xy 108.452158 -102.428294) (xy 108.452158 -102.199694) (xy 108.259118 -102.110794) (xy 108.214668 -102.110794)
			(xy 108.214668 -102.517194) (xy 108.259118 -102.517194)
		)
		(stroke
			(width 0)
			(type solid)
		)
		(fill yes)
		(layer "In11.Cu")
		(net "M_M_DQ<33>")
	)
	(gr_poly
		(pts
			(xy 108.452158 -101.437694) (xy 108.452158 -101.209094) (xy 108.259118 -101.120194) (xy 108.214668 -101.120194)
			(xy 108.214668 -101.526594) (xy 108.259118 -101.526594)
		)
		(stroke
			(width 0)
			(type solid)
		)
		(fill yes)
		(layer "In11.Cu")
		(net "M_M_DQ<33>")
	)
	(gr_poly
		(pts
			(xy 108.464858 -57.680098) (xy 108.420408 -57.680098) (xy 108.250228 -57.768998) (xy 108.250228 -57.989978)
			(xy 108.420408 -58.078878) (xy 108.464858 -58.078878)
		)
		(stroke
			(width 0)
			(type solid)
		)
		(fill yes)
		(layer "In11.Cu")
		(net "M_J_DQS_DP<13>")
	)
	(gr_poly
		(pts
			(xy 108.464858 -56.689498) (xy 108.420408 -56.689498) (xy 108.250228 -56.778398) (xy 108.250228 -56.999378)
			(xy 108.420408 -57.088278) (xy 108.464858 -57.088278)
		)
		(stroke
			(width 0)
			(type solid)
		)
		(fill yes)
		(layer "In11.Cu")
		(net "M_J_DQS_DP<13>")
	)
	(gr_poly
		(pts
			(xy 108.464858 -55.698898) (xy 108.420408 -55.698898) (xy 108.250228 -55.787798) (xy 108.250228 -56.008778)
			(xy 108.420408 -56.097678) (xy 108.464858 -56.097678)
		)
		(stroke
			(width 0)
			(type solid)
		)
		(fill yes)
		(layer "In11.Cu")
		(net "M_J_DQS_DP<13>")
	)
	(gr_poly
		(pts
			(xy 108.545122 -48.570388) (xy 108.545122 -48.341788) (xy 108.352082 -48.252888) (xy 108.307632 -48.252888)
			(xy 108.307632 -48.659288) (xy 108.352082 -48.659288)
		)
		(stroke
			(width 0)
			(type solid)
		)
		(fill yes)
		(layer "In11.Cu")
		(net "M_J_DQ<33>")
	)
	(gr_poly
		(pts
			(xy 108.634276 -59.816746) (xy 108.576618 -59.633358) (xy 108.545376 -59.601862) (xy 108.263436 -59.884056)
			(xy 108.294678 -59.915298) (xy 108.478066 -59.972702)
		)
		(stroke
			(width 0)
			(type solid)
		)
		(fill yes)
		(layer "In11.Cu")
		(net "M_J_DQ<33>")
	)
	(gr_poly
		(pts
			(xy 108.70057 -51.065938) (xy 108.70057 -50.837338) (xy 108.50753 -50.748438) (xy 108.46308 -50.748438)
			(xy 108.46308 -51.154838) (xy 108.50753 -51.154838)
		)
		(stroke
			(width 0)
			(type solid)
		)
		(fill yes)
		(layer "In11.Cu")
		(net "M_J_DQ<33>")
	)
	(gr_poly
		(pts
			(xy 108.70057 -50.075338) (xy 108.70057 -49.846738) (xy 108.50753 -49.757838) (xy 108.46308 -49.757838)
			(xy 108.46308 -50.164238) (xy 108.50753 -50.164238)
		)
		(stroke
			(width 0)
			(type solid)
		)
		(fill yes)
		(layer "In11.Cu")
		(net "M_J_DQ<33>")
	)
	(gr_poly
		(pts
			(xy 108.749338 -98.789998) (xy 108.704888 -98.789998) (xy 108.534708 -98.878898) (xy 108.534708 -99.099878)
			(xy 108.704888 -99.188778) (xy 108.749338 -99.188778)
		)
		(stroke
			(width 0)
			(type solid)
		)
		(fill yes)
		(layer "In11.Cu")
		(net "M_M_DQS_DN<4>")
	)
	(gr_poly
		(pts
			(xy 108.749338 -97.799398) (xy 108.704888 -97.799398) (xy 108.534708 -97.888298) (xy 108.534708 -98.109278)
			(xy 108.704888 -98.198178) (xy 108.749338 -98.198178)
		)
		(stroke
			(width 0)
			(type solid)
		)
		(fill yes)
		(layer "In11.Cu")
		(net "M_M_DQS_DN<4>")
	)
	(gr_poly
		(pts
			(xy 108.749338 -96.808798) (xy 108.704888 -96.808798) (xy 108.534708 -96.897698) (xy 108.534708 -97.118678)
			(xy 108.704888 -97.207578) (xy 108.749338 -97.207578)
		)
		(stroke
			(width 0)
			(type solid)
		)
		(fill yes)
		(layer "In11.Cu")
		(net "M_M_DQS_DN<4>")
	)
	(gr_poly
		(pts
			(xy 108.749338 -95.818198) (xy 108.704888 -95.818198) (xy 108.534708 -95.907098) (xy 108.534708 -96.128078)
			(xy 108.704888 -96.216978) (xy 108.749338 -96.216978)
		)
		(stroke
			(width 0)
			(type solid)
		)
		(fill yes)
		(layer "In11.Cu")
		(net "M_M_DQS_DN<4>")
	)
	(gr_poly
		(pts
			(xy 108.749592 -94.838774) (xy 108.705142 -94.838774) (xy 108.534962 -94.927674) (xy 108.534962 -95.148654)
			(xy 108.705142 -95.237554) (xy 108.749592 -95.237554)
		)
		(stroke
			(width 0)
			(type solid)
		)
		(fill yes)
		(layer "In11.Cu")
		(net "M_M_DQS_DN<4>")
	)
	(gr_poly
		(pts
			(xy 108.749592 -92.845382) (xy 108.705142 -92.845382) (xy 108.534962 -92.934282) (xy 108.534962 -93.155262)
			(xy 108.705142 -93.244162) (xy 108.749592 -93.244162)
		)
		(stroke
			(width 0)
			(type solid)
		)
		(fill yes)
		(layer "In11.Cu")
		(net "M_M_DQS_DP<13>")
	)
	(gr_poly
		(pts
			(xy 108.874052 -54.536848) (xy 108.874052 -54.308248) (xy 108.681012 -54.219348) (xy 108.636562 -54.219348)
			(xy 108.636562 -54.625748) (xy 108.681012 -54.625748)
		)
		(stroke
			(width 0)
			(type solid)
		)
		(fill yes)
		(layer "In11.Cu")
		(net "M_J_DQS_DN<13>")
	)
	(gr_poly
		(pts
			(xy 108.874052 -53.546248) (xy 108.874052 -53.317648) (xy 108.681012 -53.228748) (xy 108.636562 -53.228748)
			(xy 108.636562 -53.635148) (xy 108.681012 -53.635148)
		)
		(stroke
			(width 0)
			(type solid)
		)
		(fill yes)
		(layer "In11.Cu")
		(net "M_J_DQS_DN<13>")
	)
	(gr_poly
		(pts
			(xy 108.977684 -100.034598) (xy 108.985812 -99.842828) (xy 108.79455 -99.732338) (xy 108.632498 -99.835208)
			(xy 108.610146 -99.873562) (xy 108.955586 -100.073206)
		)
		(stroke
			(width 0)
			(type solid)
		)
		(fill yes)
		(layer "In11.Cu")
		(net "M_M_DQS_DN<13>")
	)
	(gr_poly
		(pts
			(xy 108.980224 -94.18955) (xy 108.97235 -93.99778) (xy 108.950252 -93.959172) (xy 108.604558 -94.158562)
			(xy 108.62691 -94.196916) (xy 108.788962 -94.30004)
		)
		(stroke
			(width 0)
			(type solid)
		)
		(fill yes)
		(layer "In11.Cu")
		(net "M_M_DQS_DN<13>")
	)
	(gr_poly
		(pts
			(xy 109.003084 -57.507124) (xy 109.003084 -57.286144) (xy 108.832904 -57.197244) (xy 108.788454 -57.197244)
			(xy 108.788454 -57.596024) (xy 108.832904 -57.596024)
		)
		(stroke
			(width 0)
			(type solid)
		)
		(fill yes)
		(layer "In11.Cu")
		(net "M_J_DQS_DN<13>")
	)
	(gr_poly
		(pts
			(xy 109.003084 -56.510174) (xy 109.003084 -56.289194) (xy 108.832904 -56.200294) (xy 108.788454 -56.200294)
			(xy 108.788454 -56.599074) (xy 108.832904 -56.599074)
		)
		(stroke
			(width 0)
			(type solid)
		)
		(fill yes)
		(layer "In11.Cu")
		(net "M_J_DQS_DN<13>")
	)
	(gr_poly
		(pts
			(xy 109.003084 -55.513478) (xy 109.003084 -55.292498) (xy 108.832904 -55.203598) (xy 108.788454 -55.203598)
			(xy 108.788454 -55.602378) (xy 108.832904 -55.602378)
		)
		(stroke
			(width 0)
			(type solid)
		)
		(fill yes)
		(layer "In11.Cu")
		(net "M_J_DQS_DN<13>")
	)
	(gr_poly
		(pts
			(xy 109.03966 -51.163474) (xy 108.99521 -51.163474) (xy 108.80217 -51.252374) (xy 108.80217 -51.480974)
			(xy 108.99521 -51.569874) (xy 109.03966 -51.569874)
		)
		(stroke
			(width 0)
			(type solid)
		)
		(fill yes)
		(layer "In11.Cu")
		(net "M_J_DQS_DP<13>")
	)
	(gr_poly
		(pts
			(xy 109.03966 -50.172874) (xy 108.99521 -50.172874) (xy 108.80217 -50.261774) (xy 108.80217 -50.490374)
			(xy 108.99521 -50.579274) (xy 109.03966 -50.579274)
		)
		(stroke
			(width 0)
			(type solid)
		)
		(fill yes)
		(layer "In11.Cu")
		(net "M_J_DQS_DP<13>")
	)
	(gr_poly
		(pts
			(xy 109.03966 -49.182274) (xy 108.99521 -49.182274) (xy 108.80217 -49.271174) (xy 108.80217 -49.499774)
			(xy 108.99521 -49.588674) (xy 109.03966 -49.588674)
		)
		(stroke
			(width 0)
			(type solid)
		)
		(fill yes)
		(layer "In11.Cu")
		(net "M_J_DQS_DP<13>")
	)
	(gr_poly
		(pts
			(xy 109.03966 -48.191674) (xy 108.99521 -48.191674) (xy 108.80217 -48.280574) (xy 108.80217 -48.509174)
			(xy 108.99521 -48.598074) (xy 109.03966 -48.598074)
		)
		(stroke
			(width 0)
			(type solid)
		)
		(fill yes)
		(layer "In11.Cu")
		(net "M_J_DQS_DP<13>")
	)
	(gr_poly
		(pts
			(xy 109.075728 -52.657248) (xy 109.075728 -52.428648) (xy 108.882688 -52.339748) (xy 108.838238 -52.339748)
			(xy 108.838238 -52.746148) (xy 108.882688 -52.746148)
		)
		(stroke
			(width 0)
			(type solid)
		)
		(fill yes)
		(layer "In11.Cu")
		(net "M_J_DQS_DN<13>")
	)
	(gr_poly
		(pts
			(xy 109.11713 -93.74632) (xy 109.28731 -93.657674) (xy 109.28731 -93.436694) (xy 109.117384 -93.347794)
			(xy 109.072934 -93.34754) (xy 109.07268 -93.746574)
		)
		(stroke
			(width 0)
			(type solid)
		)
		(fill yes)
		(layer "In11.Cu")
		(net "M_M_DQS_DN<13>")
	)
	(gr_poly
		(pts
			(xy 109.187742 -99.641152) (xy 109.20984 -99.602798) (xy 108.864654 -99.403154) (xy 108.842556 -99.442016)
			(xy 108.834428 -99.633786) (xy 109.02569 -99.744022)
		)
		(stroke
			(width 0)
			(type solid)
		)
		(fill yes)
		(layer "In11.Cu")
		(net "M_M_DQS_DN<4>")
	)
	(gr_poly
		(pts
			(xy 109.287564 -98.617024) (xy 109.287564 -98.396044) (xy 109.117384 -98.307144) (xy 109.072934 -98.307144)
			(xy 109.072934 -98.705924) (xy 109.117384 -98.705924)
		)
		(stroke
			(width 0)
			(type solid)
		)
		(fill yes)
		(layer "In11.Cu")
		(net "M_M_DQS_DP<4>")
	)
	(gr_poly
		(pts
			(xy 109.287564 -97.626424) (xy 109.287564 -97.405444) (xy 109.117384 -97.316544) (xy 109.072934 -97.316544)
			(xy 109.072934 -97.715324) (xy 109.117384 -97.715324)
		)
		(stroke
			(width 0)
			(type solid)
		)
		(fill yes)
		(layer "In11.Cu")
		(net "M_M_DQS_DP<4>")
	)
	(gr_poly
		(pts
			(xy 109.287564 -96.635824) (xy 109.287564 -96.414844) (xy 109.117384 -96.325944) (xy 109.072934 -96.325944)
			(xy 109.072934 -96.724724) (xy 109.117384 -96.724724)
		)
		(stroke
			(width 0)
			(type solid)
		)
		(fill yes)
		(layer "In11.Cu")
		(net "M_M_DQS_DP<4>")
	)
	(gr_poly
		(pts
			(xy 109.287564 -95.638874) (xy 109.287564 -95.417894) (xy 109.117384 -95.328994) (xy 109.072934 -95.328994)
			(xy 109.072934 -95.727774) (xy 109.117384 -95.727774)
		)
		(stroke
			(width 0)
			(type solid)
		)
		(fill yes)
		(layer "In11.Cu")
		(net "M_M_DQS_DP<4>")
	)
	(gr_poly
		(pts
			(xy 109.323124 -60.153804) (xy 109.278674 -60.153804) (xy 109.108494 -60.242704) (xy 109.108494 -60.463684)
			(xy 109.278674 -60.552584) (xy 109.323124 -60.552584)
		)
		(stroke
			(width 0)
			(type solid)
		)
		(fill yes)
		(layer "In11.Cu")
		(net "M_J_DQS_DP<4>")
	)
	(gr_poly
		(pts
			(xy 109.323124 -59.178444) (xy 109.278674 -59.178444) (xy 109.108494 -59.267344) (xy 109.108494 -59.488324)
			(xy 109.278674 -59.577224) (xy 109.323124 -59.577224)
		)
		(stroke
			(width 0)
			(type solid)
		)
		(fill yes)
		(layer "In11.Cu")
		(net "M_J_DQS_DP<4>")
	)
	(gr_poly
		(pts
			(xy 109.323124 -58.175398) (xy 109.278674 -58.175398) (xy 109.108494 -58.264298) (xy 109.108494 -58.485278)
			(xy 109.278674 -58.574178) (xy 109.323124 -58.574178)
		)
		(stroke
			(width 0)
			(type solid)
		)
		(fill yes)
		(layer "In11.Cu")
		(net "M_J_DQS_DP<4>")
	)
	(gr_poly
		(pts
			(xy 109.323124 -57.182004) (xy 109.278674 -57.182004) (xy 109.108494 -57.270904) (xy 109.108494 -57.491884)
			(xy 109.278674 -57.580784) (xy 109.323124 -57.580784)
		)
		(stroke
			(width 0)
			(type solid)
		)
		(fill yes)
		(layer "In11.Cu")
		(net "M_J_DQS_DP<4>")
	)
	(gr_poly
		(pts
			(xy 109.323124 -56.191404) (xy 109.278674 -56.191404) (xy 109.108494 -56.280304) (xy 109.108494 -56.501284)
			(xy 109.278674 -56.590184) (xy 109.323124 -56.590184)
		)
		(stroke
			(width 0)
			(type solid)
		)
		(fill yes)
		(layer "In11.Cu")
		(net "M_J_DQS_DP<4>")
	)
	(gr_poly
		(pts
			(xy 109.323124 -55.200804) (xy 109.278674 -55.200804) (xy 109.108494 -55.289704) (xy 109.108494 -55.510684)
			(xy 109.278674 -55.599584) (xy 109.323124 -55.599584)
		)
		(stroke
			(width 0)
			(type solid)
		)
		(fill yes)
		(layer "In11.Cu")
		(net "M_J_DQS_DP<4>")
	)
	(gr_poly
		(pts
			(xy 109.323124 -54.212998) (xy 109.278674 -54.212998) (xy 109.108494 -54.301898) (xy 109.108494 -54.522878)
			(xy 109.278674 -54.611778) (xy 109.323124 -54.611778)
		)
		(stroke
			(width 0)
			(type solid)
		)
		(fill yes)
		(layer "In11.Cu")
		(net "M_J_DQS_DP<4>")
	)
	(gr_poly
		(pts
			(xy 109.323124 -53.236622) (xy 109.278674 -53.236622) (xy 109.108494 -53.325522) (xy 109.108494 -53.546502)
			(xy 109.278674 -53.635402) (xy 109.323124 -53.635402)
		)
		(stroke
			(width 0)
			(type solid)
		)
		(fill yes)
		(layer "In11.Cu")
		(net "M_J_DQS_DP<4>")
	)
	(gr_poly
		(pts
			(xy 109.467396 -51.607974) (xy 109.467396 -51.379374) (xy 109.274356 -51.290474) (xy 109.229906 -51.290474)
			(xy 109.229906 -51.696874) (xy 109.274356 -51.696874)
		)
		(stroke
			(width 0)
			(type solid)
		)
		(fill yes)
		(layer "In11.Cu")
		(net "M_J_DQS_DN<13>")
	)
	(gr_poly
		(pts
			(xy 109.467396 -50.617374) (xy 109.467396 -50.388774) (xy 109.274356 -50.299874) (xy 109.229906 -50.299874)
			(xy 109.229906 -50.706274) (xy 109.274356 -50.706274)
		)
		(stroke
			(width 0)
			(type solid)
		)
		(fill yes)
		(layer "In11.Cu")
		(net "M_J_DQS_DN<13>")
	)
	(gr_poly
		(pts
			(xy 109.467396 -49.626774) (xy 109.467396 -49.398174) (xy 109.274356 -49.309274) (xy 109.229906 -49.309274)
			(xy 109.229906 -49.715674) (xy 109.274356 -49.715674)
		)
		(stroke
			(width 0)
			(type solid)
		)
		(fill yes)
		(layer "In11.Cu")
		(net "M_J_DQS_DN<13>")
	)
	(gr_poly
		(pts
			(xy 109.467396 -48.636174) (xy 109.467396 -48.407574) (xy 109.274356 -48.318674) (xy 109.229906 -48.318674)
			(xy 109.229906 -48.725074) (xy 109.274356 -48.725074)
		)
		(stroke
			(width 0)
			(type solid)
		)
		(fill yes)
		(layer "In11.Cu")
		(net "M_J_DQS_DN<13>")
	)
	(gr_poly
		(pts
			(xy 109.607858 -98.307144) (xy 109.563408 -98.307144) (xy 109.393228 -98.396044) (xy 109.393228 -98.617024)
			(xy 109.563408 -98.705924) (xy 109.607858 -98.705924)
		)
		(stroke
			(width 0)
			(type solid)
		)
		(fill yes)
		(layer "In11.Cu")
		(net "M_M_DQ<38>")
	)
	(gr_poly
		(pts
			(xy 109.607858 -97.316544) (xy 109.563408 -97.316544) (xy 109.393228 -97.405444) (xy 109.393228 -97.626424)
			(xy 109.563408 -97.715324) (xy 109.607858 -97.715324)
		)
		(stroke
			(width 0)
			(type solid)
		)
		(fill yes)
		(layer "In11.Cu")
		(net "M_M_DQ<38>")
	)
	(gr_poly
		(pts
			(xy 109.607858 -96.325944) (xy 109.563408 -96.325944) (xy 109.393228 -96.414844) (xy 109.393228 -96.635824)
			(xy 109.563408 -96.724724) (xy 109.607858 -96.724724)
		)
		(stroke
			(width 0)
			(type solid)
		)
		(fill yes)
		(layer "In11.Cu")
		(net "M_M_DQ<38>")
	)
	(gr_poly
		(pts
			(xy 109.607858 -95.328994) (xy 109.563408 -95.328994) (xy 109.393228 -95.417894) (xy 109.393228 -95.638874)
			(xy 109.563408 -95.727774) (xy 109.607858 -95.727774)
		)
		(stroke
			(width 0)
			(type solid)
		)
		(fill yes)
		(layer "In11.Cu")
		(net "M_M_DQ<38>")
	)
	(gr_poly
		(pts
			(xy 109.607858 -93.354144) (xy 109.563408 -93.354144) (xy 109.393228 -93.443044) (xy 109.393228 -93.664024)
			(xy 109.563408 -93.752924) (xy 109.607858 -93.752924)
		)
		(stroke
			(width 0)
			(type solid)
		)
		(fill yes)
		(layer "In11.Cu")
		(net "M_M_DQ<38>")
	)
	(gr_poly
		(pts
			(xy 109.634528 -100.883974) (xy 109.708188 -100.684584) (xy 109.54639 -100.522786) (xy 109.347 -100.596446)
			(xy 109.315758 -100.627942) (xy 109.603032 -100.91547)
		)
		(stroke
			(width 0)
			(type solid)
		)
		(fill yes)
		(layer "In11.Cu")
		(net "M_M_DQS_DN<13>")
	)
	(gr_poly
		(pts
			(xy 109.644688 -103.46182) (xy 109.600238 -103.46182) (xy 109.407198 -103.55072) (xy 109.407198 -103.77932)
			(xy 109.600238 -103.86822) (xy 109.644688 -103.86822)
		)
		(stroke
			(width 0)
			(type solid)
		)
		(fill yes)
		(layer "In11.Cu")
		(net "M_M_DQS_DP<13>")
	)
	(gr_poly
		(pts
			(xy 109.644688 -102.47122) (xy 109.600238 -102.47122) (xy 109.407198 -102.56012) (xy 109.407198 -102.78872)
			(xy 109.600238 -102.87762) (xy 109.644688 -102.87762)
		)
		(stroke
			(width 0)
			(type solid)
		)
		(fill yes)
		(layer "In11.Cu")
		(net "M_M_DQS_DP<13>")
	)
	(gr_poly
		(pts
			(xy 109.644688 -101.48062) (xy 109.600238 -101.48062) (xy 109.407198 -101.56952) (xy 109.407198 -101.79812)
			(xy 109.600238 -101.88702) (xy 109.644688 -101.88702)
		)
		(stroke
			(width 0)
			(type solid)
		)
		(fill yes)
		(layer "In11.Cu")
		(net "M_M_DQS_DP<13>")
	)
	(gr_poly
		(pts
			(xy 109.80674 -50.865278) (xy 109.76229 -50.865278) (xy 109.56925 -50.954178) (xy 109.56925 -51.182778)
			(xy 109.76229 -51.271678) (xy 109.80674 -51.271678)
		)
		(stroke
			(width 0)
			(type solid)
		)
		(fill yes)
		(layer "In11.Cu")
		(net "M_J_DQS_DP<4>")
	)
	(gr_poly
		(pts
			(xy 109.80674 -49.874678) (xy 109.76229 -49.874678) (xy 109.56925 -49.963578) (xy 109.56925 -50.192178)
			(xy 109.76229 -50.281078) (xy 109.80674 -50.281078)
		)
		(stroke
			(width 0)
			(type solid)
		)
		(fill yes)
		(layer "In11.Cu")
		(net "M_J_DQS_DP<4>")
	)
	(gr_poly
		(pts
			(xy 109.80674 -48.884078) (xy 109.76229 -48.884078) (xy 109.56925 -48.972978) (xy 109.56925 -49.201578)
			(xy 109.76229 -49.290478) (xy 109.80674 -49.290478)
		)
		(stroke
			(width 0)
			(type solid)
		)
		(fill yes)
		(layer "In11.Cu")
		(net "M_J_DQS_DP<4>")
	)
	(gr_poly
		(pts
			(xy 109.840014 -99.54133) (xy 109.848142 -99.34956) (xy 109.65688 -99.23907) (xy 109.494828 -99.34194)
			(xy 109.472476 -99.380294) (xy 109.817916 -99.579938)
		)
		(stroke
			(width 0)
			(type solid)
		)
		(fill yes)
		(layer "In11.Cu")
		(net "M_M_DQS_DP<4>")
	)
	(gr_poly
		(pts
			(xy 109.861096 -60.956952) (xy 109.861096 -60.735972) (xy 109.690916 -60.647072) (xy 109.646212 -60.647072)
			(xy 109.64672 -61.045852) (xy 109.690916 -61.045852)
		)
		(stroke
			(width 0)
			(type solid)
		)
		(fill yes)
		(layer "In11.Cu")
		(net "M_J_DQS_DN<4>")
	)
	(gr_poly
		(pts
			(xy 109.86135 -54.02453) (xy 109.86135 -53.80355) (xy 109.69117 -53.71465) (xy 109.64672 -53.71465)
			(xy 109.64672 -54.11343) (xy 109.69117 -54.11343)
		)
		(stroke
			(width 0)
			(type solid)
		)
		(fill yes)
		(layer "In11.Cu")
		(net "M_J_DQS_DN<4>")
	)
	(gr_poly
		(pts
			(xy 109.861604 -59.983624) (xy 109.861604 -59.762644) (xy 109.691424 -59.673744) (xy 109.646974 -59.673744)
			(xy 109.646974 -60.072524) (xy 109.691424 -60.072524)
		)
		(stroke
			(width 0)
			(type solid)
		)
		(fill yes)
		(layer "In11.Cu")
		(net "M_J_DQS_DN<4>")
	)
	(gr_poly
		(pts
			(xy 109.861604 -58.980578) (xy 109.861604 -58.759598) (xy 109.691424 -58.670698) (xy 109.646974 -58.670698)
			(xy 109.646974 -59.069478) (xy 109.691424 -59.069478)
		)
		(stroke
			(width 0)
			(type solid)
		)
		(fill yes)
		(layer "In11.Cu")
		(net "M_J_DQS_DN<4>")
	)
	(gr_poly
		(pts
			(xy 109.861604 -58.005218) (xy 109.861604 -57.784238) (xy 109.691424 -57.695338) (xy 109.646974 -57.695338)
			(xy 109.646974 -58.094118) (xy 109.691424 -58.094118)
		)
		(stroke
			(width 0)
			(type solid)
		)
		(fill yes)
		(layer "In11.Cu")
		(net "M_J_DQS_DN<4>")
	)
	(gr_poly
		(pts
			(xy 109.861604 -57.014618) (xy 109.861604 -56.793638) (xy 109.691424 -56.704738) (xy 109.646974 -56.704738)
			(xy 109.646974 -57.103518) (xy 109.691424 -57.103518)
		)
		(stroke
			(width 0)
			(type solid)
		)
		(fill yes)
		(layer "In11.Cu")
		(net "M_J_DQS_DN<4>")
	)
	(gr_poly
		(pts
			(xy 109.861604 -56.024018) (xy 109.861604 -55.803038) (xy 109.691424 -55.714138) (xy 109.646974 -55.714138)
			(xy 109.646974 -56.112918) (xy 109.691424 -56.112918)
		)
		(stroke
			(width 0)
			(type solid)
		)
		(fill yes)
		(layer "In11.Cu")
		(net "M_J_DQS_DN<4>")
	)
	(gr_poly
		(pts
			(xy 109.861604 -55.033418) (xy 109.861604 -54.812438) (xy 109.691424 -54.723538) (xy 109.646974 -54.723538)
			(xy 109.646974 -55.122318) (xy 109.691424 -55.122318)
		)
		(stroke
			(width 0)
			(type solid)
		)
		(fill yes)
		(layer "In11.Cu")
		(net "M_J_DQS_DN<4>")
	)
	(gr_poly
		(pts
			(xy 109.95533 -94.148148) (xy 109.95533 -93.927168) (xy 109.78515 -93.838268) (xy 109.7407 -93.838268)
			(xy 109.7407 -94.237048) (xy 109.78515 -94.237048)
		)
		(stroke
			(width 0)
			(type solid)
		)
		(fill yes)
		(layer "In11.Cu")
		(net "M_M_DQ<38>")
	)
	(gr_poly
		(pts
			(xy 110.049818 -99.147884) (xy 110.072424 -99.10953) (xy 109.726984 -98.909886) (xy 109.704632 -98.948748)
			(xy 109.696504 -99.140518) (xy 109.88802 -99.250754)
		)
		(stroke
			(width 0)
			(type solid)
		)
		(fill yes)
		(layer "In11.Cu")
		(net "M_M_DQ<38>")
	)
	(gr_poly
		(pts
			(xy 110.072678 -103.77932) (xy 110.072678 -103.55072) (xy 109.879638 -103.46182) (xy 109.835188 -103.46182)
			(xy 109.835188 -103.86822) (xy 109.879638 -103.86822)
		)
		(stroke
			(width 0)
			(type solid)
		)
		(fill yes)
		(layer "In11.Cu")
		(net "M_M_DQS_DN<13>")
	)
	(gr_poly
		(pts
			(xy 110.072678 -102.78872) (xy 110.072678 -102.56012) (xy 109.879638 -102.47122) (xy 109.835188 -102.47122)
			(xy 109.835188 -102.87762) (xy 109.879638 -102.87762)
		)
		(stroke
			(width 0)
			(type solid)
		)
		(fill yes)
		(layer "In11.Cu")
		(net "M_M_DQS_DN<13>")
	)
	(gr_poly
		(pts
			(xy 110.072678 -101.79812) (xy 110.072678 -101.56952) (xy 109.879638 -101.48062) (xy 109.835188 -101.48062)
			(xy 109.835188 -101.88702) (xy 109.879638 -101.88702)
		)
		(stroke
			(width 0)
			(type solid)
		)
		(fill yes)
		(layer "In11.Cu")
		(net "M_M_DQS_DN<13>")
	)
	(gr_poly
		(pts
			(xy 110.146084 -98.109278) (xy 110.146084 -97.888298) (xy 109.975904 -97.799398) (xy 109.931454 -97.799398)
			(xy 109.931454 -98.198178) (xy 109.975904 -98.198178)
		)
		(stroke
			(width 0)
			(type solid)
		)
		(fill yes)
		(layer "In11.Cu")
		(net "M_M_DQ<39>")
	)
	(gr_poly
		(pts
			(xy 110.146084 -97.118678) (xy 110.146084 -96.897698) (xy 109.975904 -96.808798) (xy 109.931454 -96.808798)
			(xy 109.931454 -97.207578) (xy 109.975904 -97.207578)
		)
		(stroke
			(width 0)
			(type solid)
		)
		(fill yes)
		(layer "In11.Cu")
		(net "M_M_DQ<39>")
	)
	(gr_poly
		(pts
			(xy 110.146084 -96.128078) (xy 110.146084 -95.907098) (xy 109.975904 -95.818198) (xy 109.931454 -95.818198)
			(xy 109.931454 -96.216978) (xy 109.975904 -96.216978)
		)
		(stroke
			(width 0)
			(type solid)
		)
		(fill yes)
		(layer "In11.Cu")
		(net "M_M_DQ<39>")
	)
	(gr_poly
		(pts
			(xy 110.146084 -95.149924) (xy 110.146084 -94.928944) (xy 109.975904 -94.840044) (xy 109.931454 -94.840044)
			(xy 109.931454 -95.238824) (xy 109.975904 -95.238824)
		)
		(stroke
			(width 0)
			(type solid)
		)
		(fill yes)
		(layer "In11.Cu")
		(net "M_M_DQ<39>")
	)
	(gr_poly
		(pts
			(xy 110.181644 -56.701944) (xy 110.137194 -56.701944) (xy 109.967014 -56.790844) (xy 109.967014 -57.011824)
			(xy 110.137194 -57.100724) (xy 110.181644 -57.100724)
		)
		(stroke
			(width 0)
			(type solid)
		)
		(fill yes)
		(layer "In11.Cu")
		(net "M_J_DQ<38>")
	)
	(gr_poly
		(pts
			(xy 110.181644 -55.711344) (xy 110.137194 -55.711344) (xy 109.967014 -55.800244) (xy 109.967014 -56.021224)
			(xy 110.137194 -56.110124) (xy 110.181644 -56.110124)
		)
		(stroke
			(width 0)
			(type solid)
		)
		(fill yes)
		(layer "In11.Cu")
		(net "M_J_DQ<38>")
	)
	(gr_poly
		(pts
			(xy 110.181644 -54.720744) (xy 110.137194 -54.720744) (xy 109.967014 -54.809644) (xy 109.967014 -55.030624)
			(xy 110.137194 -55.119524) (xy 110.181644 -55.119524)
		)
		(stroke
			(width 0)
			(type solid)
		)
		(fill yes)
		(layer "In11.Cu")
		(net "M_J_DQ<38>")
	)
	(gr_poly
		(pts
			(xy 110.181898 -58.683144) (xy 110.137448 -58.683144) (xy 109.967268 -58.772044) (xy 109.967268 -58.993024)
			(xy 110.137448 -59.081924) (xy 110.181898 -59.081924)
		)
		(stroke
			(width 0)
			(type solid)
		)
		(fill yes)
		(layer "In11.Cu")
		(net "M_J_DQ<38>")
	)
	(gr_poly
		(pts
			(xy 110.181898 -57.692544) (xy 110.137448 -57.692544) (xy 109.967268 -57.781444) (xy 109.967268 -58.002424)
			(xy 110.137448 -58.091324) (xy 110.181898 -58.091324)
		)
		(stroke
			(width 0)
			(type solid)
		)
		(fill yes)
		(layer "In11.Cu")
		(net "M_J_DQ<38>")
	)
	(gr_poly
		(pts
			(xy 110.182152 -52.940458) (xy 110.137702 -52.940458) (xy 109.944662 -53.029358) (xy 109.944662 -53.257958)
			(xy 110.137702 -53.346858) (xy 110.182152 -53.346858)
		)
		(stroke
			(width 0)
			(type solid)
		)
		(fill yes)
		(layer "In11.Cu")
		(net "M_J_DQ<38>")
	)
	(gr_poly
		(pts
			(xy 110.23473 -51.182778) (xy 110.23473 -50.954178) (xy 110.04169 -50.865278) (xy 109.99724 -50.865278)
			(xy 109.99724 -51.271678) (xy 110.04169 -51.271678)
		)
		(stroke
			(width 0)
			(type solid)
		)
		(fill yes)
		(layer "In11.Cu")
		(net "M_J_DQS_DN<4>")
	)
	(gr_poly
		(pts
			(xy 110.23473 -50.192178) (xy 110.23473 -49.963578) (xy 110.04169 -49.874678) (xy 109.99724 -49.874678)
			(xy 109.99724 -50.281078) (xy 110.04169 -50.281078)
		)
		(stroke
			(width 0)
			(type solid)
		)
		(fill yes)
		(layer "In11.Cu")
		(net "M_J_DQS_DN<4>")
	)
	(gr_poly
		(pts
			(xy 110.23473 -49.201578) (xy 110.23473 -48.972978) (xy 110.04169 -48.884078) (xy 109.99724 -48.884078)
			(xy 109.99724 -49.290478) (xy 110.04169 -49.290478)
		)
		(stroke
			(width 0)
			(type solid)
		)
		(fill yes)
		(layer "In11.Cu")
		(net "M_J_DQS_DN<4>")
	)
	(gr_poly
		(pts
			(xy 110.342172 -100.633022) (xy 110.373668 -100.601526) (xy 110.086394 -100.314252) (xy 110.054898 -100.345748)
			(xy 109.981238 -100.544884) (xy 110.143036 -100.706682)
		)
		(stroke
			(width 0)
			(type solid)
		)
		(fill yes)
		(layer "In11.Cu")
		(net "M_M_DQS_DN<4>")
	)
	(gr_poly
		(pts
			(xy 110.348268 -59.77382) (xy 110.30458 -59.7662) (xy 110.121446 -59.824112) (xy 110.083092 -60.04179)
			(xy 110.235238 -60.158884) (xy 110.27918 -60.166504)
		)
		(stroke
			(width 0)
			(type solid)
		)
		(fill yes)
		(layer "In11.Cu")
		(net "M_J_DQ<39>")
	)
	(gr_poly
		(pts
			(xy 110.466124 -97.796604) (xy 110.421674 -97.796604) (xy 110.251494 -97.885504) (xy 110.251494 -98.106484)
			(xy 110.421674 -98.195384) (xy 110.466124 -98.195384)
		)
		(stroke
			(width 0)
			(type solid)
		)
		(fill yes)
		(layer "In11.Cu")
		(net "M_M_DQ<34>")
	)
	(gr_poly
		(pts
			(xy 110.466124 -96.806004) (xy 110.421674 -96.806004) (xy 110.251494 -96.894904) (xy 110.251494 -97.115884)
			(xy 110.421674 -97.204784) (xy 110.466124 -97.204784)
		)
		(stroke
			(width 0)
			(type solid)
		)
		(fill yes)
		(layer "In11.Cu")
		(net "M_M_DQ<34>")
	)
	(gr_poly
		(pts
			(xy 110.466124 -95.815404) (xy 110.421674 -95.815404) (xy 110.251494 -95.904304) (xy 110.251494 -96.125284)
			(xy 110.421674 -96.214184) (xy 110.466124 -96.214184)
		)
		(stroke
			(width 0)
			(type solid)
		)
		(fill yes)
		(layer "In11.Cu")
		(net "M_M_DQ<34>")
	)
	(gr_poly
		(pts
			(xy 110.466124 -94.840044) (xy 110.421674 -94.840044) (xy 110.251494 -94.928944) (xy 110.251494 -95.149924)
			(xy 110.421674 -95.238824) (xy 110.466124 -95.238824)
		)
		(stroke
			(width 0)
			(type solid)
		)
		(fill yes)
		(layer "In11.Cu")
		(net "M_M_DQ<34>")
	)
	(gr_poly
		(pts
			(xy 110.466124 -93.849444) (xy 110.421674 -93.849444) (xy 110.251494 -93.938344) (xy 110.251494 -94.159324)
			(xy 110.421674 -94.248224) (xy 110.466124 -94.248224)
		)
		(stroke
			(width 0)
			(type solid)
		)
		(fill yes)
		(layer "In11.Cu")
		(net "M_M_DQ<34>")
	)
	(gr_poly
		(pts
			(xy 110.540038 -100.435156) (xy 110.613698 -100.23602) (xy 110.4519 -100.074222) (xy 110.252764 -100.147882)
			(xy 110.221268 -100.179378) (xy 110.508542 -100.466652)
		)
		(stroke
			(width 0)
			(type solid)
		)
		(fill yes)
		(layer "In11.Cu")
		(net "M_M_DQS_DP<4>")
	)
	(gr_poly
		(pts
			(xy 110.597188 -103.940356) (xy 110.552738 -103.940356) (xy 110.359698 -104.029256) (xy 110.359698 -104.257856)
			(xy 110.552738 -104.346756) (xy 110.597188 -104.346756)
		)
		(stroke
			(width 0)
			(type solid)
		)
		(fill yes)
		(layer "In11.Cu")
		(net "M_M_DQS_DN<4>")
	)
	(gr_poly
		(pts
			(xy 110.597188 -102.949756) (xy 110.552738 -102.949756) (xy 110.359698 -103.038656) (xy 110.359698 -103.267256)
			(xy 110.552738 -103.356156) (xy 110.597188 -103.356156)
		)
		(stroke
			(width 0)
			(type solid)
		)
		(fill yes)
		(layer "In11.Cu")
		(net "M_M_DQS_DN<4>")
	)
	(gr_poly
		(pts
			(xy 110.597188 -101.959156) (xy 110.552738 -101.959156) (xy 110.359698 -102.048056) (xy 110.359698 -102.276656)
			(xy 110.552738 -102.365556) (xy 110.597188 -102.365556)
		)
		(stroke
			(width 0)
			(type solid)
		)
		(fill yes)
		(layer "In11.Cu")
		(net "M_M_DQS_DN<4>")
	)
	(gr_poly
		(pts
			(xy 110.597188 -100.968556) (xy 110.552738 -100.968556) (xy 110.359698 -101.057456) (xy 110.359698 -101.286056)
			(xy 110.552738 -101.374956) (xy 110.597188 -101.374956)
		)
		(stroke
			(width 0)
			(type solid)
		)
		(fill yes)
		(layer "In11.Cu")
		(net "M_M_DQS_DN<4>")
	)
	(gr_poly
		(pts
			(xy 110.610142 -53.486558) (xy 110.610142 -53.257958) (xy 110.417102 -53.169058) (xy 110.372652 -53.169058)
			(xy 110.372652 -53.575458) (xy 110.417102 -53.575458)
		)
		(stroke
			(width 0)
			(type solid)
		)
		(fill yes)
		(layer "In11.Cu")
		(net "M_J_DQ<39>")
	)
	(gr_poly
		(pts
			(xy 110.682786 -52.24145) (xy 110.65129 -52.210208) (xy 110.4519 -52.136548) (xy 110.290356 -52.298092)
			(xy 110.364016 -52.497482) (xy 110.395258 -52.528978)
		)
		(stroke
			(width 0)
			(type solid)
		)
		(fill yes)
		(layer "In11.Cu")
		(net "M_J_DQ<38>")
	)
	(gr_poly
		(pts
			(xy 110.69701 -99.045014) (xy 110.705138 -98.853244) (xy 110.513876 -98.742754) (xy 110.351824 -98.845624)
			(xy 110.329472 -98.883978) (xy 110.674912 -99.083622)
		)
		(stroke
			(width 0)
			(type solid)
		)
		(fill yes)
		(layer "In11.Cu")
		(net "M_M_DQ<39>")
	)
	(gr_poly
		(pts
			(xy 110.71987 -58.491374) (xy 110.71987 -58.270394) (xy 110.54969 -58.181494) (xy 110.50524 -58.181494)
			(xy 110.50524 -58.580274) (xy 110.54969 -58.580274)
		)
		(stroke
			(width 0)
			(type solid)
		)
		(fill yes)
		(layer "In11.Cu")
		(net "M_J_DQ<39>")
	)
	(gr_poly
		(pts
			(xy 110.71987 -57.494678) (xy 110.71987 -57.273698) (xy 110.54969 -57.184798) (xy 110.50524 -57.184798)
			(xy 110.50524 -57.583578) (xy 110.54969 -57.583578)
		)
		(stroke
			(width 0)
			(type solid)
		)
		(fill yes)
		(layer "In11.Cu")
		(net "M_J_DQ<39>")
	)
	(gr_poly
		(pts
			(xy 110.71987 -56.504078) (xy 110.71987 -56.283098) (xy 110.54969 -56.194198) (xy 110.50524 -56.194198)
			(xy 110.50524 -56.592978) (xy 110.54969 -56.592978)
		)
		(stroke
			(width 0)
			(type solid)
		)
		(fill yes)
		(layer "In11.Cu")
		(net "M_J_DQ<39>")
	)
	(gr_poly
		(pts
			(xy 110.71987 -55.513478) (xy 110.71987 -55.292498) (xy 110.54969 -55.203598) (xy 110.50524 -55.203598)
			(xy 110.50524 -55.602378) (xy 110.54969 -55.602378)
		)
		(stroke
			(width 0)
			(type solid)
		)
		(fill yes)
		(layer "In11.Cu")
		(net "M_J_DQ<39>")
	)
	(gr_poly
		(pts
			(xy 110.71987 -54.522878) (xy 110.71987 -54.301898) (xy 110.54969 -54.212998) (xy 110.50524 -54.212998)
			(xy 110.50524 -54.611778) (xy 110.54969 -54.611778)
		)
		(stroke
			(width 0)
			(type solid)
		)
		(fill yes)
		(layer "In11.Cu")
		(net "M_J_DQ<39>")
	)
	(gr_poly
		(pts
			(xy 110.885732 -50.771552) (xy 110.841282 -50.771552) (xy 110.648242 -50.860452) (xy 110.648242 -51.089052)
			(xy 110.841282 -51.177952) (xy 110.885732 -51.177952)
		)
		(stroke
			(width 0)
			(type solid)
		)
		(fill yes)
		(layer "In11.Cu")
		(net "M_J_DQ<38>")
	)
	(gr_poly
		(pts
			(xy 110.885732 -49.780952) (xy 110.841282 -49.780952) (xy 110.648242 -49.869852) (xy 110.648242 -50.098452)
			(xy 110.841282 -50.187352) (xy 110.885732 -50.187352)
		)
		(stroke
			(width 0)
			(type solid)
		)
		(fill yes)
		(layer "In11.Cu")
		(net "M_J_DQ<38>")
	)
	(gr_poly
		(pts
			(xy 110.885732 -48.790352) (xy 110.841282 -48.790352) (xy 110.648242 -48.879252) (xy 110.648242 -49.107852)
			(xy 110.841282 -49.196752) (xy 110.885732 -49.196752)
		)
		(stroke
			(width 0)
			(type solid)
		)
		(fill yes)
		(layer "In11.Cu")
		(net "M_J_DQ<38>")
	)
	(gr_poly
		(pts
			(xy 110.904274 -99.640898) (xy 110.926626 -99.60229) (xy 110.581186 -99.403154) (xy 110.559088 -99.441508)
			(xy 110.55096 -99.633278) (xy 110.742222 -99.743768)
		)
		(stroke
			(width 0)
			(type solid)
		)
		(fill yes)
		(layer "In11.Cu")
		(net "M_M_DQ<38>")
	)
	(gr_poly
		(pts
			(xy 110.904274 -98.650298) (xy 110.92688 -98.611944) (xy 110.581186 -98.412554) (xy 110.559088 -98.451162)
			(xy 110.55096 -98.642932) (xy 110.742476 -98.753168)
		)
		(stroke
			(width 0)
			(type solid)
		)
		(fill yes)
		(layer "In11.Cu")
		(net "M_M_DQ<34>")
	)
	(gr_poly
		(pts
			(xy 110.927896 -93.428566) (xy 110.902496 -93.39199) (xy 110.732062 -93.303598) (xy 110.55096 -93.430344)
			(xy 110.575852 -93.62059) (xy 110.601252 -93.656912)
		)
		(stroke
			(width 0)
			(type solid)
		)
		(fill yes)
		(layer "In11.Cu")
		(net "M_M_DQ<34>")
	)
	(gr_poly
		(pts
			(xy 110.972854 -52.555902) (xy 110.899194 -52.356512) (xy 110.867952 -52.325016) (xy 110.580424 -52.612544)
			(xy 110.61192 -52.643786) (xy 110.81131 -52.717446)
		)
		(stroke
			(width 0)
			(type solid)
		)
		(fill yes)
		(layer "In11.Cu")
		(net "M_J_DQ<39>")
	)
	(gr_poly
		(pts
			(xy 111.004604 -97.629218) (xy 111.004604 -97.408238) (xy 110.834424 -97.319338) (xy 110.789974 -97.319338)
			(xy 110.789974 -97.718118) (xy 110.834424 -97.718118)
		)
		(stroke
			(width 0)
			(type solid)
		)
		(fill yes)
		(layer "In11.Cu")
		(net "M_M_DQ<35>")
	)
	(gr_poly
		(pts
			(xy 111.004604 -96.638618) (xy 111.004604 -96.417638) (xy 110.834424 -96.328738) (xy 110.789974 -96.328738)
			(xy 110.789974 -96.727518) (xy 110.834424 -96.727518)
		)
		(stroke
			(width 0)
			(type solid)
		)
		(fill yes)
		(layer "In11.Cu")
		(net "M_M_DQ<35>")
	)
	(gr_poly
		(pts
			(xy 111.004604 -95.645224) (xy 111.004604 -95.424244) (xy 110.834424 -95.335344) (xy 110.789974 -95.335344)
			(xy 110.789974 -95.734124) (xy 110.834424 -95.734124)
		)
		(stroke
			(width 0)
			(type solid)
		)
		(fill yes)
		(layer "In11.Cu")
		(net "M_M_DQ<35>")
	)
	(gr_poly
		(pts
			(xy 111.004604 -94.642178) (xy 111.004604 -94.421198) (xy 110.834424 -94.332298) (xy 110.789974 -94.332298)
			(xy 110.789974 -94.731078) (xy 110.834424 -94.731078)
		)
		(stroke
			(width 0)
			(type solid)
		)
		(fill yes)
		(layer "In11.Cu")
		(net "M_M_DQ<35>")
	)
	(gr_poly
		(pts
			(xy 111.025178 -104.257856) (xy 111.025178 -104.029256) (xy 110.832138 -103.940356) (xy 110.787688 -103.940356)
			(xy 110.787688 -104.346756) (xy 110.832138 -104.346756)
		)
		(stroke
			(width 0)
			(type solid)
		)
		(fill yes)
		(layer "In11.Cu")
		(net "M_M_DQS_DP<4>")
	)
	(gr_poly
		(pts
			(xy 111.025178 -103.267256) (xy 111.025178 -103.038656) (xy 110.832138 -102.949756) (xy 110.787688 -102.949756)
			(xy 110.787688 -103.356156) (xy 110.832138 -103.356156)
		)
		(stroke
			(width 0)
			(type solid)
		)
		(fill yes)
		(layer "In11.Cu")
		(net "M_M_DQS_DP<4>")
	)
	(gr_poly
		(pts
			(xy 111.025178 -102.276656) (xy 111.025178 -102.048056) (xy 110.832138 -101.959156) (xy 110.787688 -101.959156)
			(xy 110.787688 -102.365556) (xy 110.832138 -102.365556)
		)
		(stroke
			(width 0)
			(type solid)
		)
		(fill yes)
		(layer "In11.Cu")
		(net "M_M_DQS_DP<4>")
	)
	(gr_poly
		(pts
			(xy 111.025178 -101.286056) (xy 111.025178 -101.057456) (xy 110.832138 -100.968556) (xy 110.787688 -100.968556)
			(xy 110.787688 -101.374956) (xy 110.832138 -101.374956)
		)
		(stroke
			(width 0)
			(type solid)
		)
		(fill yes)
		(layer "In11.Cu")
		(net "M_M_DQS_DP<4>")
	)
	(gr_poly
		(pts
			(xy 111.040164 -58.181748) (xy 110.995714 -58.181748) (xy 110.825534 -58.270648) (xy 110.825534 -58.491628)
			(xy 110.995714 -58.580528) (xy 111.040164 -58.580528)
		)
		(stroke
			(width 0)
			(type solid)
		)
		(fill yes)
		(layer "In11.Cu")
		(net "M_J_DQ<34>")
	)
	(gr_poly
		(pts
			(xy 111.040164 -57.184798) (xy 110.995714 -57.184798) (xy 110.825534 -57.273698) (xy 110.825534 -57.494678)
			(xy 110.995714 -57.583578) (xy 111.040164 -57.583578)
		)
		(stroke
			(width 0)
			(type solid)
		)
		(fill yes)
		(layer "In11.Cu")
		(net "M_J_DQ<34>")
	)
	(gr_poly
		(pts
			(xy 111.040164 -56.194198) (xy 110.995714 -56.194198) (xy 110.825534 -56.283098) (xy 110.825534 -56.504078)
			(xy 110.995714 -56.592978) (xy 111.040164 -56.592978)
		)
		(stroke
			(width 0)
			(type solid)
		)
		(fill yes)
		(layer "In11.Cu")
		(net "M_J_DQ<34>")
	)
	(gr_poly
		(pts
			(xy 111.040164 -55.203598) (xy 110.995714 -55.203598) (xy 110.825534 -55.292498) (xy 110.825534 -55.513478)
			(xy 110.995714 -55.602378) (xy 111.040164 -55.602378)
		)
		(stroke
			(width 0)
			(type solid)
		)
		(fill yes)
		(layer "In11.Cu")
		(net "M_J_DQ<34>")
	)
	(gr_poly
		(pts
			(xy 111.040164 -54.212998) (xy 110.995714 -54.212998) (xy 110.825534 -54.301898) (xy 110.825534 -54.522878)
			(xy 110.995714 -54.611778) (xy 111.040164 -54.611778)
		)
		(stroke
			(width 0)
			(type solid)
		)
		(fill yes)
		(layer "In11.Cu")
		(net "M_J_DQ<34>")
	)
	(gr_poly
		(pts
			(xy 111.040164 -53.196998) (xy 110.995714 -53.196998) (xy 110.825534 -53.285898) (xy 110.825534 -53.506878)
			(xy 110.995714 -53.595778) (xy 111.040164 -53.595778)
		)
		(stroke
			(width 0)
			(type solid)
		)
		(fill yes)
		(layer "In11.Cu")
		(net "M_J_DQ<34>")
	)
	(gr_poly
		(pts
			(xy 111.313214 -51.724052) (xy 111.313214 -51.495452) (xy 111.120174 -51.406552) (xy 111.075724 -51.406552)
			(xy 111.075724 -51.812952) (xy 111.120174 -51.812952)
		)
		(stroke
			(width 0)
			(type solid)
		)
		(fill yes)
		(layer "In11.Cu")
		(net "M_J_DQ<39>")
	)
	(gr_poly
		(pts
			(xy 111.313214 -50.733452) (xy 111.313214 -50.504852) (xy 111.120174 -50.415952) (xy 111.075724 -50.415952)
			(xy 111.075724 -50.822352) (xy 111.120174 -50.822352)
		)
		(stroke
			(width 0)
			(type solid)
		)
		(fill yes)
		(layer "In11.Cu")
		(net "M_J_DQ<39>")
	)
	(gr_poly
		(pts
			(xy 111.313214 -49.742852) (xy 111.313214 -49.514252) (xy 111.120174 -49.425352) (xy 111.075724 -49.425352)
			(xy 111.075724 -49.831752) (xy 111.120174 -49.831752)
		)
		(stroke
			(width 0)
			(type solid)
		)
		(fill yes)
		(layer "In11.Cu")
		(net "M_J_DQ<39>")
	)
	(gr_poly
		(pts
			(xy 111.324644 -97.316544) (xy 111.280194 -97.316544) (xy 111.110014 -97.405444) (xy 111.110014 -97.626424)
			(xy 111.280194 -97.715324) (xy 111.324644 -97.715324)
		)
		(stroke
			(width 0)
			(type solid)
		)
		(fill yes)
		(layer "In11.Cu")
		(net "M_M_DQ<52>")
	)
	(gr_poly
		(pts
			(xy 111.324644 -96.325944) (xy 111.280194 -96.325944) (xy 111.110014 -96.414844) (xy 111.110014 -96.635824)
			(xy 111.280194 -96.724724) (xy 111.324644 -96.724724)
		)
		(stroke
			(width 0)
			(type solid)
		)
		(fill yes)
		(layer "In11.Cu")
		(net "M_M_DQ<52>")
	)
	(gr_poly
		(pts
			(xy 111.324644 -95.328994) (xy 111.280194 -95.328994) (xy 111.110014 -95.417894) (xy 111.110014 -95.638874)
			(xy 111.280194 -95.727774) (xy 111.324644 -95.727774)
		)
		(stroke
			(width 0)
			(type solid)
		)
		(fill yes)
		(layer "In11.Cu")
		(net "M_M_DQ<52>")
	)
	(gr_poly
		(pts
			(xy 111.324644 -94.332298) (xy 111.280194 -94.332298) (xy 111.110014 -94.421198) (xy 111.110014 -94.642178)
			(xy 111.280194 -94.731078) (xy 111.324644 -94.731078)
		)
		(stroke
			(width 0)
			(type solid)
		)
		(fill yes)
		(layer "In11.Cu")
		(net "M_M_DQ<52>")
	)
	(gr_poly
		(pts
			(xy 111.324644 -92.363544) (xy 111.280194 -92.363544) (xy 111.110014 -92.452444) (xy 111.110014 -92.673424)
			(xy 111.280194 -92.762324) (xy 111.324644 -92.762324)
		)
		(stroke
			(width 0)
			(type solid)
		)
		(fill yes)
		(layer "In11.Cu")
		(net "M_M_DQ<52>")
	)
	(gr_poly
		(pts
			(xy 111.324644 -91.372944) (xy 111.280194 -91.372944) (xy 111.110014 -91.461844) (xy 111.110014 -91.682824)
			(xy 111.280194 -91.771724) (xy 111.324644 -91.771724)
		)
		(stroke
			(width 0)
			(type solid)
		)
		(fill yes)
		(layer "In11.Cu")
		(net "M_M_DQ<52>")
	)
	(gr_poly
		(pts
			(xy 111.49457 -52.513992) (xy 111.463074 -52.48275) (xy 111.263684 -52.40909) (xy 111.10214 -52.570634)
			(xy 111.1758 -52.770024) (xy 111.207042 -52.80152)
		)
		(stroke
			(width 0)
			(type solid)
		)
		(fill yes)
		(layer "In11.Cu")
		(net "M_J_DQ<34>")
	)
	(gr_poly
		(pts
			(xy 111.5568 -99.54133) (xy 111.564928 -99.34956) (xy 111.373666 -99.23907) (xy 111.211614 -99.34194)
			(xy 111.189262 -99.380294) (xy 111.534702 -99.579938)
		)
		(stroke
			(width 0)
			(type solid)
		)
		(fill yes)
		(layer "In11.Cu")
		(net "M_M_DQ<39>")
	)
	(gr_poly
		(pts
			(xy 111.5568 -98.55073) (xy 111.564928 -98.35896) (xy 111.373666 -98.24847) (xy 111.211614 -98.35134)
			(xy 111.189262 -98.389694) (xy 111.534702 -98.589338)
		)
		(stroke
			(width 0)
			(type solid)
		)
		(fill yes)
		(layer "In11.Cu")
		(net "M_M_DQ<35>")
	)
	(gr_poly
		(pts
			(xy 111.57839 -59.977274) (xy 111.57839 -59.756294) (xy 111.40821 -59.667394) (xy 111.36376 -59.667394)
			(xy 111.36376 -60.066174) (xy 111.40821 -60.066174)
		)
		(stroke
			(width 0)
			(type solid)
		)
		(fill yes)
		(layer "In11.Cu")
		(net "M_J_DQ<35>")
	)
	(gr_poly
		(pts
			(xy 111.57839 -58.980578) (xy 111.57839 -58.759598) (xy 111.40821 -58.670698) (xy 111.36376 -58.670698)
			(xy 111.36376 -59.069478) (xy 111.40821 -59.069478)
		)
		(stroke
			(width 0)
			(type solid)
		)
		(fill yes)
		(layer "In11.Cu")
		(net "M_J_DQ<35>")
	)
	(gr_poly
		(pts
			(xy 111.57839 -58.002424) (xy 111.57839 -57.781444) (xy 111.40821 -57.692544) (xy 111.36376 -57.692544)
			(xy 111.36376 -58.091324) (xy 111.40821 -58.091324)
		)
		(stroke
			(width 0)
			(type solid)
		)
		(fill yes)
		(layer "In11.Cu")
		(net "M_J_DQ<35>")
	)
	(gr_poly
		(pts
			(xy 111.57839 -57.011824) (xy 111.57839 -56.790844) (xy 111.40821 -56.701944) (xy 111.36376 -56.701944)
			(xy 111.36376 -57.100724) (xy 111.40821 -57.100724)
		)
		(stroke
			(width 0)
			(type solid)
		)
		(fill yes)
		(layer "In11.Cu")
		(net "M_J_DQ<35>")
	)
	(gr_poly
		(pts
			(xy 111.57839 -56.021224) (xy 111.57839 -55.800244) (xy 111.40821 -55.711344) (xy 111.36376 -55.711344)
			(xy 111.36376 -56.110124) (xy 111.40821 -56.110124)
		)
		(stroke
			(width 0)
			(type solid)
		)
		(fill yes)
		(layer "In11.Cu")
		(net "M_J_DQ<35>")
	)
	(gr_poly
		(pts
			(xy 111.57839 -55.030624) (xy 111.57839 -54.809644) (xy 111.40821 -54.720744) (xy 111.36376 -54.720744)
			(xy 111.36376 -55.119524) (xy 111.40821 -55.119524)
		)
		(stroke
			(width 0)
			(type solid)
		)
		(fill yes)
		(layer "In11.Cu")
		(net "M_J_DQ<35>")
	)
	(gr_poly
		(pts
			(xy 111.57839 -54.033674) (xy 111.57839 -53.812694) (xy 111.40821 -53.723794) (xy 111.36376 -53.723794)
			(xy 111.36376 -54.122574) (xy 111.40821 -54.122574)
		)
		(stroke
			(width 0)
			(type solid)
		)
		(fill yes)
		(layer "In11.Cu")
		(net "M_J_DQ<35>")
	)
	(gr_poly
		(pts
			(xy 111.609632 -51.750722) (xy 111.565182 -51.750722) (xy 111.372142 -51.839622) (xy 111.372142 -52.068222)
			(xy 111.565182 -52.157122) (xy 111.609632 -52.157122)
		)
		(stroke
			(width 0)
			(type solid)
		)
		(fill yes)
		(layer "In11.Cu")
		(net "M_J_DQ<34>")
	)
	(gr_poly
		(pts
			(xy 111.609632 -50.760122) (xy 111.565182 -50.760122) (xy 111.372142 -50.849022) (xy 111.372142 -51.077622)
			(xy 111.565182 -51.166522) (xy 111.609632 -51.166522)
		)
		(stroke
			(width 0)
			(type solid)
		)
		(fill yes)
		(layer "In11.Cu")
		(net "M_J_DQ<34>")
	)
	(gr_poly
		(pts
			(xy 111.609632 -49.769522) (xy 111.565182 -49.769522) (xy 111.372142 -49.858422) (xy 111.372142 -50.087022)
			(xy 111.565182 -50.175922) (xy 111.609632 -50.175922)
		)
		(stroke
			(width 0)
			(type solid)
		)
		(fill yes)
		(layer "In11.Cu")
		(net "M_J_DQ<34>")
	)
	(gr_poly
		(pts
			(xy 111.76127 -100.135182) (xy 111.783622 -100.096574) (xy 111.438182 -99.897438) (xy 111.416084 -99.935792)
			(xy 111.407956 -100.127562) (xy 111.599218 -100.238052)
		)
		(stroke
			(width 0)
			(type solid)
		)
		(fill yes)
		(layer "In11.Cu")
		(net "M_M_DQ<38>")
	)
	(gr_poly
		(pts
			(xy 111.76127 -99.144582) (xy 111.783622 -99.105974) (xy 111.438182 -98.906838) (xy 111.416084 -98.945192)
			(xy 111.407956 -99.136962) (xy 111.599218 -99.247452)
		)
		(stroke
			(width 0)
			(type solid)
		)
		(fill yes)
		(layer "In11.Cu")
		(net "M_M_DQ<34>")
	)
	(gr_poly
		(pts
			(xy 111.766604 -98.157284) (xy 111.78921 -98.11893) (xy 111.443516 -97.91954) (xy 111.421418 -97.958148)
			(xy 111.41329 -98.149918) (xy 111.604806 -98.260154)
		)
		(stroke
			(width 0)
			(type solid)
		)
		(fill yes)
		(layer "In11.Cu")
		(net "M_M_DQ<52>")
	)
	(gr_poly
		(pts
			(xy 111.7854 -52.828952) (xy 111.71174 -52.629816) (xy 111.680244 -52.59832) (xy 111.39297 -52.885594)
			(xy 111.424466 -52.91709) (xy 111.623602 -52.99075)
		)
		(stroke
			(width 0)
			(type solid)
		)
		(fill yes)
		(layer "In11.Cu")
		(net "M_J_DQ<35>")
	)
	(gr_poly
		(pts
			(xy 111.86287 -97.118678) (xy 111.86287 -96.897698) (xy 111.69269 -96.808798) (xy 111.64824 -96.808798)
			(xy 111.64824 -97.207578) (xy 111.69269 -97.207578)
		)
		(stroke
			(width 0)
			(type solid)
		)
		(fill yes)
		(layer "In11.Cu")
		(net "M_M_DQ<53>")
	)
	(gr_poly
		(pts
			(xy 111.86287 -96.128078) (xy 111.86287 -95.907098) (xy 111.69269 -95.818198) (xy 111.64824 -95.818198)
			(xy 111.64824 -96.216978) (xy 111.69269 -96.216978)
		)
		(stroke
			(width 0)
			(type solid)
		)
		(fill yes)
		(layer "In11.Cu")
		(net "M_M_DQ<53>")
	)
	(gr_poly
		(pts
			(xy 111.86287 -95.149924) (xy 111.86287 -94.928944) (xy 111.69269 -94.840044) (xy 111.64824 -94.840044)
			(xy 111.64824 -95.238824) (xy 111.69269 -95.238824)
		)
		(stroke
			(width 0)
			(type solid)
		)
		(fill yes)
		(layer "In11.Cu")
		(net "M_M_DQ<53>")
	)
	(gr_poly
		(pts
			(xy 111.86287 -94.153228) (xy 111.86287 -93.932248) (xy 111.69269 -93.843348) (xy 111.64824 -93.843348)
			(xy 111.64824 -94.242128) (xy 111.69269 -94.242128)
		)
		(stroke
			(width 0)
			(type solid)
		)
		(fill yes)
		(layer "In11.Cu")
		(net "M_M_DQ<53>")
	)
	(gr_poly
		(pts
			(xy 111.86287 -93.156278) (xy 111.86287 -92.935298) (xy 111.69269 -92.846398) (xy 111.64824 -92.846398)
			(xy 111.64824 -93.245178) (xy 111.69269 -93.245178)
		)
		(stroke
			(width 0)
			(type solid)
		)
		(fill yes)
		(layer "In11.Cu")
		(net "M_M_DQ<53>")
	)
	(gr_poly
		(pts
			(xy 112.037622 -51.331622) (xy 112.037622 -51.103022) (xy 111.844582 -51.014122) (xy 111.800132 -51.014122)
			(xy 111.800132 -51.420522) (xy 111.844582 -51.420522)
		)
		(stroke
			(width 0)
			(type solid)
		)
		(fill yes)
		(layer "In11.Cu")
		(net "M_J_DQ<35>")
	)
	(gr_poly
		(pts
			(xy 112.037622 -50.341022) (xy 112.037622 -50.112422) (xy 111.844582 -50.023522) (xy 111.800132 -50.023522)
			(xy 111.800132 -50.429922) (xy 111.844582 -50.429922)
		)
		(stroke
			(width 0)
			(type solid)
		)
		(fill yes)
		(layer "In11.Cu")
		(net "M_J_DQ<35>")
	)
	(gr_poly
		(pts
			(xy 112.183164 -101.76764) (xy 112.138714 -101.76764) (xy 111.968534 -101.85654) (xy 111.968534 -102.07752)
			(xy 112.138714 -102.16642) (xy 112.183164 -102.16642)
		)
		(stroke
			(width 0)
			(type solid)
		)
		(fill yes)
		(layer "In11.Cu")
		(net "M_M_DQ<38>")
	)
	(gr_poly
		(pts
			(xy 112.183164 -100.783136) (xy 112.138714 -100.783136) (xy 111.968534 -100.872036) (xy 111.968534 -101.093016)
			(xy 112.138714 -101.181916) (xy 112.183164 -101.181916)
		)
		(stroke
			(width 0)
			(type solid)
		)
		(fill yes)
		(layer "In11.Cu")
		(net "M_M_DQ<38>")
	)
	(gr_poly
		(pts
			(xy 112.183164 -96.808798) (xy 112.138714 -96.808798) (xy 111.968534 -96.897698) (xy 111.968534 -97.118678)
			(xy 112.138714 -97.207578) (xy 112.183164 -97.207578)
		)
		(stroke
			(width 0)
			(type solid)
		)
		(fill yes)
		(layer "In11.Cu")
		(net "M_M_DQ<48>")
	)
	(gr_poly
		(pts
			(xy 112.183164 -95.818198) (xy 112.138714 -95.818198) (xy 111.968534 -95.907098) (xy 111.968534 -96.128078)
			(xy 112.138714 -96.216978) (xy 112.183164 -96.216978)
		)
		(stroke
			(width 0)
			(type solid)
		)
		(fill yes)
		(layer "In11.Cu")
		(net "M_M_DQ<48>")
	)
	(gr_poly
		(pts
			(xy 112.183164 -94.840044) (xy 112.138714 -94.840044) (xy 111.968534 -94.928944) (xy 111.968534 -95.149924)
			(xy 112.138714 -95.238824) (xy 112.183164 -95.238824)
		)
		(stroke
			(width 0)
			(type solid)
		)
		(fill yes)
		(layer "In11.Cu")
		(net "M_M_DQ<48>")
	)
	(gr_poly
		(pts
			(xy 112.183164 -93.843348) (xy 112.138714 -93.843348) (xy 111.968534 -93.932248) (xy 111.968534 -94.153228)
			(xy 112.138714 -94.242128) (xy 112.183164 -94.242128)
		)
		(stroke
			(width 0)
			(type solid)
		)
		(fill yes)
		(layer "In11.Cu")
		(net "M_M_DQ<48>")
	)
	(gr_poly
		(pts
			(xy 112.183164 -92.846398) (xy 112.138714 -92.846398) (xy 111.968534 -92.935298) (xy 111.968534 -93.156278)
			(xy 112.138714 -93.245178) (xy 112.183164 -93.245178)
		)
		(stroke
			(width 0)
			(type solid)
		)
		(fill yes)
		(layer "In11.Cu")
		(net "M_M_DQ<48>")
	)
	(gr_poly
		(pts
			(xy 112.183164 -91.855798) (xy 112.138714 -91.855798) (xy 111.968534 -91.944698) (xy 111.968534 -92.165678)
			(xy 112.138714 -92.254578) (xy 112.183164 -92.254578)
		)
		(stroke
			(width 0)
			(type solid)
		)
		(fill yes)
		(layer "In11.Cu")
		(net "M_M_DQ<48>")
	)
	(gr_poly
		(pts
			(xy 112.183164 -90.865198) (xy 112.138714 -90.865198) (xy 111.968534 -90.954098) (xy 111.968534 -91.175078)
			(xy 112.138714 -91.263978) (xy 112.183164 -91.263978)
		)
		(stroke
			(width 0)
			(type solid)
		)
		(fill yes)
		(layer "In11.Cu")
		(net "M_M_DQ<48>")
	)
	(gr_poly
		(pts
			(xy 112.353344 -48.65878) (xy 112.321848 -48.627538) (xy 112.122458 -48.553878) (xy 111.960914 -48.715422)
			(xy 112.034574 -48.914812) (xy 112.065816 -48.946308)
		)
		(stroke
			(width 0)
			(type solid)
		)
		(fill yes)
		(layer "In11.Cu")
		(net "M_J_DQ<34>")
	)
	(gr_poly
		(pts
			(xy 112.413796 -99.045014) (xy 112.421924 -98.853244) (xy 112.230662 -98.742754) (xy 112.06861 -98.845624)
			(xy 112.046258 -98.883978) (xy 112.391698 -99.083622)
		)
		(stroke
			(width 0)
			(type solid)
		)
		(fill yes)
		(layer "In11.Cu")
		(net "M_M_DQ<35>")
	)
	(gr_poly
		(pts
			(xy 112.413796 -98.054414) (xy 112.421924 -97.862644) (xy 112.230662 -97.752154) (xy 112.06861 -97.855024)
			(xy 112.046258 -97.893378) (xy 112.391698 -98.093022)
		)
		(stroke
			(width 0)
			(type solid)
		)
		(fill yes)
		(layer "In11.Cu")
		(net "M_M_DQ<53>")
	)
	(gr_poly
		(pts
			(xy 112.41532 -100.03663) (xy 112.423448 -99.84486) (xy 112.232186 -99.73437) (xy 112.070134 -99.83724)
			(xy 112.047782 -99.875594) (xy 112.393222 -100.075238)
		)
		(stroke
			(width 0)
			(type solid)
		)
		(fill yes)
		(layer "In11.Cu")
		(net "M_M_DQ<39>")
	)
	(gr_poly
		(pts
			(xy 112.59312 -49.02454) (xy 112.51946 -48.82515) (xy 112.488218 -48.793654) (xy 112.20069 -49.081182)
			(xy 112.232186 -49.112424) (xy 112.431576 -49.186084)
		)
		(stroke
			(width 0)
			(type solid)
		)
		(fill yes)
		(layer "In11.Cu")
		(net "M_J_DQ<35>")
	)
	(gr_poly
		(pts
			(xy 112.621314 -98.650298) (xy 112.643666 -98.61169) (xy 112.298226 -98.412554) (xy 112.276128 -98.450908)
			(xy 112.268 -98.642678) (xy 112.459262 -98.753168)
		)
		(stroke
			(width 0)
			(type solid)
		)
		(fill yes)
		(layer "In11.Cu")
		(net "M_M_DQ<52>")
	)
	(gr_poly
		(pts
			(xy 112.621568 -97.659952) (xy 112.64392 -97.621598) (xy 112.298226 -97.422208) (xy 112.276382 -97.460816)
			(xy 112.268254 -97.652586) (xy 112.459516 -97.762822)
		)
		(stroke
			(width 0)
			(type solid)
		)
		(fill yes)
		(layer "In11.Cu")
		(net "M_M_DQ<48>")
	)
	(gr_poly
		(pts
			(xy 112.628426 -99.63912) (xy 112.650778 -99.600766) (xy 112.305338 -99.401122) (xy 112.28324 -99.43973)
			(xy 112.275112 -99.6315) (xy 112.466374 -99.74199)
		)
		(stroke
			(width 0)
			(type solid)
		)
		(fill yes)
		(layer "In11.Cu")
		(net "M_M_DQ<34>")
	)
	(gr_poly
		(pts
			(xy 112.72139 -102.57917) (xy 112.72139 -102.35819) (xy 112.55121 -102.26929) (xy 112.50676 -102.26929)
			(xy 112.50676 -102.66807) (xy 112.55121 -102.66807)
		)
		(stroke
			(width 0)
			(type solid)
		)
		(fill yes)
		(layer "In11.Cu")
		(net "M_M_DQ<39>")
	)
	(gr_poly
		(pts
			(xy 112.72139 -101.58222) (xy 112.72139 -101.36124) (xy 112.55121 -101.27234) (xy 112.50676 -101.27234)
			(xy 112.50676 -101.67112) (xy 112.55121 -101.67112)
		)
		(stroke
			(width 0)
			(type solid)
		)
		(fill yes)
		(layer "In11.Cu")
		(net "M_M_DQ<39>")
	)
	(gr_poly
		(pts
			(xy 112.72139 -100.59162) (xy 112.72139 -100.37064) (xy 112.55121 -100.28174) (xy 112.50676 -100.28174)
			(xy 112.50676 -100.68052) (xy 112.55121 -100.68052)
		)
		(stroke
			(width 0)
			(type solid)
		)
		(fill yes)
		(layer "In11.Cu")
		(net "M_M_DQ<39>")
	)
	(gr_poly
		(pts
			(xy 112.72139 -96.635824) (xy 112.72139 -96.414844) (xy 112.55121 -96.325944) (xy 112.50676 -96.325944)
			(xy 112.50676 -96.724724) (xy 112.55121 -96.724724)
		)
		(stroke
			(width 0)
			(type solid)
		)
		(fill yes)
		(layer "In11.Cu")
		(net "M_M_DQ<49>")
	)
	(gr_poly
		(pts
			(xy 112.72139 -95.638874) (xy 112.72139 -95.417894) (xy 112.55121 -95.328994) (xy 112.50676 -95.328994)
			(xy 112.50676 -95.727774) (xy 112.55121 -95.727774)
		)
		(stroke
			(width 0)
			(type solid)
		)
		(fill yes)
		(layer "In11.Cu")
		(net "M_M_DQ<49>")
	)
	(gr_poly
		(pts
			(xy 112.72139 -94.642178) (xy 112.72139 -94.421198) (xy 112.55121 -94.332298) (xy 112.50676 -94.332298)
			(xy 112.50676 -94.731078) (xy 112.55121 -94.731078)
		)
		(stroke
			(width 0)
			(type solid)
		)
		(fill yes)
		(layer "In11.Cu")
		(net "M_M_DQ<49>")
	)
	(gr_poly
		(pts
			(xy 112.72139 -93.664024) (xy 112.72139 -93.443044) (xy 112.55121 -93.354144) (xy 112.50676 -93.354144)
			(xy 112.50676 -93.752924) (xy 112.55121 -93.752924)
		)
		(stroke
			(width 0)
			(type solid)
		)
		(fill yes)
		(layer "In11.Cu")
		(net "M_M_DQ<49>")
	)
	(gr_poly
		(pts
			(xy 113.041684 -102.273354) (xy 112.997234 -102.273354) (xy 112.827054 -102.362254) (xy 112.827054 -102.583234)
			(xy 112.997234 -102.672134) (xy 113.041684 -102.672134)
		)
		(stroke
			(width 0)
			(type solid)
		)
		(fill yes)
		(layer "In11.Cu")
		(net "M_M_DQ<34>")
	)
	(gr_poly
		(pts
			(xy 113.041684 -101.272086) (xy 112.997234 -101.272086) (xy 112.827054 -101.360986) (xy 112.827054 -101.581966)
			(xy 112.997234 -101.670866) (xy 113.041684 -101.670866)
		)
		(stroke
			(width 0)
			(type solid)
		)
		(fill yes)
		(layer "In11.Cu")
		(net "M_M_DQ<34>")
	)
	(gr_poly
		(pts
			(xy 113.041684 -100.27539) (xy 112.997234 -100.27539) (xy 112.827054 -100.36429) (xy 112.827054 -100.58527)
			(xy 112.997234 -100.67417) (xy 113.041684 -100.67417)
		)
		(stroke
			(width 0)
			(type solid)
		)
		(fill yes)
		(layer "In11.Cu")
		(net "M_M_DQ<34>")
	)
	(gr_poly
		(pts
			(xy 113.041684 -96.319594) (xy 112.997234 -96.319594) (xy 112.827054 -96.408494) (xy 112.827054 -96.629474)
			(xy 112.997234 -96.718374) (xy 113.041684 -96.718374)
		)
		(stroke
			(width 0)
			(type solid)
		)
		(fill yes)
		(layer "In11.Cu")
		(net "M_M_DQS_DP<15>")
	)
	(gr_poly
		(pts
			(xy 113.041684 -95.328994) (xy 112.997234 -95.328994) (xy 112.827054 -95.417894) (xy 112.827054 -95.638874)
			(xy 112.997234 -95.727774) (xy 113.041684 -95.727774)
		)
		(stroke
			(width 0)
			(type solid)
		)
		(fill yes)
		(layer "In11.Cu")
		(net "M_M_DQS_DP<15>")
	)
	(gr_poly
		(pts
			(xy 113.041684 -94.332298) (xy 112.997234 -94.332298) (xy 112.827054 -94.421198) (xy 112.827054 -94.642178)
			(xy 112.997234 -94.731078) (xy 113.041684 -94.731078)
		)
		(stroke
			(width 0)
			(type solid)
		)
		(fill yes)
		(layer "In11.Cu")
		(net "M_M_DQS_DP<15>")
	)
	(gr_poly
		(pts
			(xy 113.041684 -93.354144) (xy 112.997234 -93.354144) (xy 112.827054 -93.443044) (xy 112.827054 -93.664024)
			(xy 112.997234 -93.752924) (xy 113.041684 -93.752924)
		)
		(stroke
			(width 0)
			(type solid)
		)
		(fill yes)
		(layer "In11.Cu")
		(net "M_M_DQS_DP<15>")
	)
	(gr_poly
		(pts
			(xy 113.041684 -92.363544) (xy 112.997234 -92.363544) (xy 112.827054 -92.452444) (xy 112.827054 -92.673424)
			(xy 112.997234 -92.762324) (xy 113.041684 -92.762324)
		)
		(stroke
			(width 0)
			(type solid)
		)
		(fill yes)
		(layer "In11.Cu")
		(net "M_M_DQS_DP<15>")
	)
	(gr_poly
		(pts
			(xy 113.041684 -91.372944) (xy 112.997234 -91.372944) (xy 112.827054 -91.461844) (xy 112.827054 -91.682824)
			(xy 112.997234 -91.771724) (xy 113.041684 -91.771724)
		)
		(stroke
			(width 0)
			(type solid)
		)
		(fill yes)
		(layer "In11.Cu")
		(net "M_M_DQS_DP<15>")
	)
	(gr_poly
		(pts
			(xy 113.041684 -90.382344) (xy 112.997234 -90.382344) (xy 112.827054 -90.471244) (xy 112.827054 -90.692224)
			(xy 112.997234 -90.781124) (xy 113.041684 -90.781124)
		)
		(stroke
			(width 0)
			(type solid)
		)
		(fill yes)
		(layer "In11.Cu")
		(net "M_M_DQS_DP<15>")
	)
	(gr_poly
		(pts
			(xy 113.272316 -99.540314) (xy 113.280444 -99.348544) (xy 113.089182 -99.238054) (xy 112.92713 -99.340924)
			(xy 112.904778 -99.379278) (xy 113.250218 -99.578922)
		)
		(stroke
			(width 0)
			(type solid)
		)
		(fill yes)
		(layer "In11.Cu")
		(net "M_M_DQ<35>")
	)
	(gr_poly
		(pts
			(xy 113.27384 -98.55073) (xy 113.281968 -98.35896) (xy 113.090706 -98.24847) (xy 112.928654 -98.35134)
			(xy 112.906302 -98.389694) (xy 113.251742 -98.589338)
		)
		(stroke
			(width 0)
			(type solid)
		)
		(fill yes)
		(layer "In11.Cu")
		(net "M_M_DQ<53>")
	)
	(gr_poly
		(pts
			(xy 113.27384 -97.56013) (xy 113.281968 -97.36836) (xy 113.090706 -97.25787) (xy 112.928654 -97.36074)
			(xy 112.906302 -97.399094) (xy 113.251742 -97.598738)
		)
		(stroke
			(width 0)
			(type solid)
		)
		(fill yes)
		(layer "In11.Cu")
		(net "M_M_DQ<49>")
	)
	(gr_poly
		(pts
			(xy 113.47831 -99.144582) (xy 113.500662 -99.105974) (xy 113.155222 -98.906838) (xy 113.133124 -98.945192)
			(xy 113.124996 -99.136962) (xy 113.316258 -99.247452)
		)
		(stroke
			(width 0)
			(type solid)
		)
		(fill yes)
		(layer "In11.Cu")
		(net "M_M_DQ<52>")
	)
	(gr_poly
		(pts
			(xy 113.47831 -98.153982) (xy 113.500662 -98.115374) (xy 113.155222 -97.916238) (xy 113.133124 -97.954592)
			(xy 113.124996 -98.146362) (xy 113.316258 -98.256852)
		)
		(stroke
			(width 0)
			(type solid)
		)
		(fill yes)
		(layer "In11.Cu")
		(net "M_M_DQ<48>")
	)
	(gr_poly
		(pts
			(xy 113.483644 -97.166684) (xy 113.50625 -97.12833) (xy 113.160556 -96.92894) (xy 113.138458 -96.967548)
			(xy 113.13033 -97.159318) (xy 113.321846 -97.269554)
		)
		(stroke
			(width 0)
			(type solid)
		)
		(fill yes)
		(layer "In11.Cu")
		(net "M_M_DQS_DP<15>")
	)
	(gr_poly
		(pts
			(xy 113.57991 -102.07117) (xy 113.57991 -101.85019) (xy 113.40973 -101.76129) (xy 113.36528 -101.76129)
			(xy 113.36528 -102.16007) (xy 113.40973 -102.16007)
		)
		(stroke
			(width 0)
			(type solid)
		)
		(fill yes)
		(layer "In11.Cu")
		(net "M_M_DQ<35>")
	)
	(gr_poly
		(pts
			(xy 113.57991 -101.093016) (xy 113.57991 -100.872036) (xy 113.40973 -100.783136) (xy 113.36528 -100.783136)
			(xy 113.36528 -101.181916) (xy 113.40973 -101.181916)
		)
		(stroke
			(width 0)
			(type solid)
		)
		(fill yes)
		(layer "In11.Cu")
		(net "M_M_DQ<35>")
	)
	(gr_poly
		(pts
			(xy 113.57991 -100.102416) (xy 113.57991 -99.881436) (xy 113.40973 -99.792536) (xy 113.36528 -99.792536)
			(xy 113.36528 -100.191316) (xy 113.40973 -100.191316)
		)
		(stroke
			(width 0)
			(type solid)
		)
		(fill yes)
		(layer "In11.Cu")
		(net "M_M_DQ<35>")
	)
	(gr_poly
		(pts
			(xy 113.57991 -96.128078) (xy 113.57991 -95.907098) (xy 113.40973 -95.818198) (xy 113.36528 -95.818198)
			(xy 113.36528 -96.216978) (xy 113.40973 -96.216978)
		)
		(stroke
			(width 0)
			(type solid)
		)
		(fill yes)
		(layer "In11.Cu")
		(net "M_M_DQS_DN<15>")
	)
	(gr_poly
		(pts
			(xy 113.57991 -95.149924) (xy 113.57991 -94.928944) (xy 113.40973 -94.840044) (xy 113.36528 -94.840044)
			(xy 113.36528 -95.238824) (xy 113.40973 -95.238824)
		)
		(stroke
			(width 0)
			(type solid)
		)
		(fill yes)
		(layer "In11.Cu")
		(net "M_M_DQS_DN<15>")
	)
	(gr_poly
		(pts
			(xy 113.57991 -94.153228) (xy 113.57991 -93.932248) (xy 113.40973 -93.843348) (xy 113.36528 -93.843348)
			(xy 113.36528 -94.242128) (xy 113.40973 -94.242128)
		)
		(stroke
			(width 0)
			(type solid)
		)
		(fill yes)
		(layer "In11.Cu")
		(net "M_M_DQS_DN<15>")
	)
	(gr_poly
		(pts
			(xy 113.57991 -93.156278) (xy 113.57991 -92.935298) (xy 113.40973 -92.846398) (xy 113.36528 -92.846398)
			(xy 113.36528 -93.245178) (xy 113.40973 -93.245178)
		)
		(stroke
			(width 0)
			(type solid)
		)
		(fill yes)
		(layer "In11.Cu")
		(net "M_M_DQS_DN<15>")
	)
	(gr_poly
		(pts
			(xy 113.57991 -92.165678) (xy 113.57991 -91.944698) (xy 113.40973 -91.855798) (xy 113.36528 -91.855798)
			(xy 113.36528 -92.254578) (xy 113.40973 -92.254578)
		)
		(stroke
			(width 0)
			(type solid)
		)
		(fill yes)
		(layer "In11.Cu")
		(net "M_M_DQS_DN<15>")
	)
	(gr_poly
		(pts
			(xy 113.57991 -91.175078) (xy 113.57991 -90.954098) (xy 113.40973 -90.865198) (xy 113.36528 -90.865198)
			(xy 113.36528 -91.263978) (xy 113.40973 -91.263978)
		)
		(stroke
			(width 0)
			(type solid)
		)
		(fill yes)
		(layer "In11.Cu")
		(net "M_M_DQS_DN<15>")
	)
	(gr_poly
		(pts
			(xy 113.900204 -95.830644) (xy 113.855754 -95.830644) (xy 113.685574 -95.919544) (xy 113.685574 -96.140524)
			(xy 113.855754 -96.229424) (xy 113.900204 -96.229424)
		)
		(stroke
			(width 0)
			(type solid)
		)
		(fill yes)
		(layer "In11.Cu")
		(net "M_M_DQS_DN<6>")
	)
	(gr_poly
		(pts
			(xy 113.900204 -94.840044) (xy 113.855754 -94.840044) (xy 113.685574 -94.928944) (xy 113.685574 -95.149924)
			(xy 113.855754 -95.238824) (xy 113.900204 -95.238824)
		)
		(stroke
			(width 0)
			(type solid)
		)
		(fill yes)
		(layer "In11.Cu")
		(net "M_M_DQS_DN<6>")
	)
	(gr_poly
		(pts
			(xy 113.900458 -93.843348) (xy 113.856008 -93.843348) (xy 113.685828 -93.932248) (xy 113.685828 -94.153228)
			(xy 113.856008 -94.242128) (xy 113.900458 -94.242128)
		)
		(stroke
			(width 0)
			(type solid)
		)
		(fill yes)
		(layer "In11.Cu")
		(net "M_M_DQS_DN<6>")
	)
	(gr_poly
		(pts
			(xy 114.090958 -90.866468) (xy 114.046508 -90.866468) (xy 113.876328 -90.955368) (xy 113.876328 -91.176348)
			(xy 114.046508 -91.265248) (xy 114.090958 -91.265248)
		)
		(stroke
			(width 0)
			(type solid)
		)
		(fill yes)
		(layer "In11.Cu")
		(net "M_M_DQ<54>")
	)
	(gr_poly
		(pts
			(xy 114.130836 -99.045014) (xy 114.138964 -98.853244) (xy 113.947702 -98.742754) (xy 113.78565 -98.845624)
			(xy 113.763298 -98.883978) (xy 114.108738 -99.083622)
		)
		(stroke
			(width 0)
			(type solid)
		)
		(fill yes)
		(layer "In11.Cu")
		(net "M_M_DQ<53>")
	)
	(gr_poly
		(pts
			(xy 114.130836 -98.054414) (xy 114.138964 -97.862644) (xy 113.947702 -97.752154) (xy 113.78565 -97.855024)
			(xy 113.763298 -97.893378) (xy 114.108738 -98.093022)
		)
		(stroke
			(width 0)
			(type solid)
		)
		(fill yes)
		(layer "In11.Cu")
		(net "M_M_DQ<49>")
	)
	(gr_poly
		(pts
			(xy 114.130836 -97.063814) (xy 114.138964 -96.872044) (xy 113.947702 -96.761554) (xy 113.78565 -96.864424)
			(xy 113.763298 -96.902778) (xy 114.108738 -97.102422)
		)
		(stroke
			(width 0)
			(type solid)
		)
		(fill yes)
		(layer "In11.Cu")
		(net "M_M_DQS_DN<15>")
	)
	(gr_poly
		(pts
			(xy 114.279172 -52.091082) (xy 114.234722 -52.091082) (xy 114.041682 -52.179982) (xy 114.041682 -52.408582)
			(xy 114.234722 -52.497482) (xy 114.279172 -52.497482)
		)
		(stroke
			(width 0)
			(type solid)
		)
		(fill yes)
		(layer "In11.Cu")
		(net "M_J_DQ<52>")
	)
	(gr_poly
		(pts
			(xy 114.279172 -51.100482) (xy 114.234722 -51.100482) (xy 114.041682 -51.189382) (xy 114.041682 -51.417982)
			(xy 114.234722 -51.506882) (xy 114.279172 -51.506882)
		)
		(stroke
			(width 0)
			(type solid)
		)
		(fill yes)
		(layer "In11.Cu")
		(net "M_J_DQ<52>")
	)
	(gr_poly
		(pts
			(xy 114.279172 -50.109882) (xy 114.234722 -50.109882) (xy 114.041682 -50.198782) (xy 114.041682 -50.427382)
			(xy 114.234722 -50.516282) (xy 114.279172 -50.516282)
		)
		(stroke
			(width 0)
			(type solid)
		)
		(fill yes)
		(layer "In11.Cu")
		(net "M_J_DQ<52>")
	)
	(gr_poly
		(pts
			(xy 114.279172 -49.119282) (xy 114.234722 -49.119282) (xy 114.041682 -49.208182) (xy 114.041682 -49.436782)
			(xy 114.234722 -49.525682) (xy 114.279172 -49.525682)
		)
		(stroke
			(width 0)
			(type solid)
		)
		(fill yes)
		(layer "In11.Cu")
		(net "M_J_DQ<52>")
	)
	(gr_poly
		(pts
			(xy 114.279172 -48.128682) (xy 114.234722 -48.128682) (xy 114.041682 -48.217582) (xy 114.041682 -48.446182)
			(xy 114.234722 -48.535082) (xy 114.279172 -48.535082)
		)
		(stroke
			(width 0)
			(type solid)
		)
		(fill yes)
		(layer "In11.Cu")
		(net "M_J_DQ<52>")
	)
	(gr_poly
		(pts
			(xy 114.338354 -99.640898) (xy 114.360706 -99.60229) (xy 114.015266 -99.403154) (xy 113.993168 -99.441508)
			(xy 113.98504 -99.633278) (xy 114.176302 -99.743768)
		)
		(stroke
			(width 0)
			(type solid)
		)
		(fill yes)
		(layer "In11.Cu")
		(net "M_M_DQ<52>")
	)
	(gr_poly
		(pts
			(xy 114.338354 -98.650298) (xy 114.360706 -98.61169) (xy 114.015266 -98.412554) (xy 113.993168 -98.450908)
			(xy 113.98504 -98.642678) (xy 114.176302 -98.753168)
		)
		(stroke
			(width 0)
			(type solid)
		)
		(fill yes)
		(layer "In11.Cu")
		(net "M_M_DQ<48>")
	)
	(gr_poly
		(pts
			(xy 114.338354 -97.659698) (xy 114.360706 -97.62109) (xy 114.015266 -97.421954) (xy 113.993168 -97.460308)
			(xy 113.98504 -97.652078) (xy 114.176302 -97.762568)
		)
		(stroke
			(width 0)
			(type solid)
		)
		(fill yes)
		(layer "In11.Cu")
		(net "M_M_DQS_DP<15>")
	)
	(gr_poly
		(pts
			(xy 114.338608 -96.669352) (xy 114.36096 -96.630998) (xy 114.015266 -96.431608) (xy 113.993422 -96.470216)
			(xy 113.985294 -96.661986) (xy 114.176556 -96.772222)
		)
		(stroke
			(width 0)
			(type solid)
		)
		(fill yes)
		(layer "In11.Cu")
		(net "M_M_DQS_DN<6>")
	)
	(gr_poly
		(pts
			(xy 114.43843 -95.638874) (xy 114.43843 -95.417894) (xy 114.26825 -95.328994) (xy 114.2238 -95.328994)
			(xy 114.2238 -95.727774) (xy 114.26825 -95.727774)
		)
		(stroke
			(width 0)
			(type solid)
		)
		(fill yes)
		(layer "In11.Cu")
		(net "M_M_DQS_DP<6>")
	)
	(gr_poly
		(pts
			(xy 114.43843 -94.642178) (xy 114.43843 -94.421198) (xy 114.26825 -94.332298) (xy 114.2238 -94.332298)
			(xy 114.2238 -94.731078) (xy 114.26825 -94.731078)
		)
		(stroke
			(width 0)
			(type solid)
		)
		(fill yes)
		(layer "In11.Cu")
		(net "M_M_DQS_DP<6>")
	)
	(gr_poly
		(pts
			(xy 114.43843 -93.651578) (xy 114.43843 -93.430598) (xy 114.26825 -93.341698) (xy 114.2238 -93.341698)
			(xy 114.2238 -93.740478) (xy 114.26825 -93.740478)
		)
		(stroke
			(width 0)
			(type solid)
		)
		(fill yes)
		(layer "In11.Cu")
		(net "M_M_DQS_DP<6>")
	)
	(gr_poly
		(pts
			(xy 114.43843 -91.682824) (xy 114.43843 -91.461844) (xy 114.26825 -91.372944) (xy 114.2238 -91.372944)
			(xy 114.2238 -91.771724) (xy 114.26825 -91.771724)
		)
		(stroke
			(width 0)
			(type solid)
		)
		(fill yes)
		(layer "In11.Cu")
		(net "M_M_DQ<54>")
	)
	(gr_poly
		(pts
			(xy 114.474244 -62.137798) (xy 114.429794 -62.137798) (xy 114.259614 -62.226698) (xy 114.259614 -62.447678)
			(xy 114.429794 -62.536578) (xy 114.474244 -62.536578)
		)
		(stroke
			(width 0)
			(type solid)
		)
		(fill yes)
		(layer "In11.Cu")
		(net "M_J_DQ<52>")
	)
	(gr_poly
		(pts
			(xy 114.474244 -61.147198) (xy 114.429794 -61.147198) (xy 114.259614 -61.236098) (xy 114.259614 -61.457078)
			(xy 114.429794 -61.545978) (xy 114.474244 -61.545978)
		)
		(stroke
			(width 0)
			(type solid)
		)
		(fill yes)
		(layer "In11.Cu")
		(net "M_J_DQ<52>")
	)
	(gr_poly
		(pts
			(xy 114.474244 -60.156598) (xy 114.429794 -60.156598) (xy 114.259614 -60.245498) (xy 114.259614 -60.466478)
			(xy 114.429794 -60.555378) (xy 114.474244 -60.555378)
		)
		(stroke
			(width 0)
			(type solid)
		)
		(fill yes)
		(layer "In11.Cu")
		(net "M_J_DQ<52>")
	)
	(gr_poly
		(pts
			(xy 114.474244 -59.178444) (xy 114.429794 -59.178444) (xy 114.259614 -59.267344) (xy 114.259614 -59.488324)
			(xy 114.429794 -59.577224) (xy 114.474244 -59.577224)
		)
		(stroke
			(width 0)
			(type solid)
		)
		(fill yes)
		(layer "In11.Cu")
		(net "M_J_DQ<52>")
	)
	(gr_poly
		(pts
			(xy 114.474244 -58.181748) (xy 114.429794 -58.181748) (xy 114.259614 -58.270648) (xy 114.259614 -58.491628)
			(xy 114.429794 -58.580528) (xy 114.474244 -58.580528)
		)
		(stroke
			(width 0)
			(type solid)
		)
		(fill yes)
		(layer "In11.Cu")
		(net "M_J_DQ<52>")
	)
	(gr_poly
		(pts
			(xy 114.474244 -57.184798) (xy 114.429794 -57.184798) (xy 114.259614 -57.273698) (xy 114.259614 -57.494678)
			(xy 114.429794 -57.583578) (xy 114.474244 -57.583578)
		)
		(stroke
			(width 0)
			(type solid)
		)
		(fill yes)
		(layer "In11.Cu")
		(net "M_J_DQ<52>")
	)
	(gr_poly
		(pts
			(xy 114.474244 -56.194198) (xy 114.429794 -56.194198) (xy 114.259614 -56.283098) (xy 114.259614 -56.504078)
			(xy 114.429794 -56.592978) (xy 114.474244 -56.592978)
		)
		(stroke
			(width 0)
			(type solid)
		)
		(fill yes)
		(layer "In11.Cu")
		(net "M_J_DQ<52>")
	)
	(gr_poly
		(pts
			(xy 114.474244 -55.203598) (xy 114.429794 -55.203598) (xy 114.259614 -55.292498) (xy 114.259614 -55.513478)
			(xy 114.429794 -55.602378) (xy 114.474244 -55.602378)
		)
		(stroke
			(width 0)
			(type solid)
		)
		(fill yes)
		(layer "In11.Cu")
		(net "M_J_DQ<52>")
	)
	(gr_poly
		(pts
			(xy 114.474244 -54.212998) (xy 114.429794 -54.212998) (xy 114.259614 -54.301898) (xy 114.259614 -54.522878)
			(xy 114.429794 -54.611778) (xy 114.474244 -54.611778)
		)
		(stroke
			(width 0)
			(type solid)
		)
		(fill yes)
		(layer "In11.Cu")
		(net "M_J_DQ<52>")
	)
	(gr_poly
		(pts
			(xy 114.707162 -52.408582) (xy 114.707162 -52.179982) (xy 114.514122 -52.091082) (xy 114.469672 -52.091082)
			(xy 114.469672 -52.497482) (xy 114.514122 -52.497482)
		)
		(stroke
			(width 0)
			(type solid)
		)
		(fill yes)
		(layer "In11.Cu")
		(net "M_J_DQ<53>")
	)
	(gr_poly
		(pts
			(xy 114.707162 -51.417982) (xy 114.707162 -51.189382) (xy 114.514122 -51.100482) (xy 114.469672 -51.100482)
			(xy 114.469672 -51.506882) (xy 114.514122 -51.506882)
		)
		(stroke
			(width 0)
			(type solid)
		)
		(fill yes)
		(layer "In11.Cu")
		(net "M_J_DQ<53>")
	)
	(gr_poly
		(pts
			(xy 114.707162 -50.427382) (xy 114.707162 -50.198782) (xy 114.514122 -50.109882) (xy 114.469672 -50.109882)
			(xy 114.469672 -50.516282) (xy 114.514122 -50.516282)
		)
		(stroke
			(width 0)
			(type solid)
		)
		(fill yes)
		(layer "In11.Cu")
		(net "M_J_DQ<53>")
	)
	(gr_poly
		(pts
			(xy 114.707162 -49.436782) (xy 114.707162 -49.208182) (xy 114.514122 -49.119282) (xy 114.469672 -49.119282)
			(xy 114.469672 -49.525682) (xy 114.514122 -49.525682)
		)
		(stroke
			(width 0)
			(type solid)
		)
		(fill yes)
		(layer "In11.Cu")
		(net "M_J_DQ<53>")
	)
	(gr_poly
		(pts
			(xy 114.707162 -48.446182) (xy 114.707162 -48.217582) (xy 114.514122 -48.128682) (xy 114.469672 -48.128682)
			(xy 114.469672 -48.535082) (xy 114.514122 -48.535082)
		)
		(stroke
			(width 0)
			(type solid)
		)
		(fill yes)
		(layer "In11.Cu")
		(net "M_J_DQ<53>")
	)
	(gr_poly
		(pts
			(xy 114.758724 -95.322898) (xy 114.714274 -95.322898) (xy 114.544094 -95.411798) (xy 114.544094 -95.632778)
			(xy 114.714274 -95.721678) (xy 114.758724 -95.721678)
		)
		(stroke
			(width 0)
			(type solid)
		)
		(fill yes)
		(layer "In11.Cu")
		(net "M_M_DQ<54>")
	)
	(gr_poly
		(pts
			(xy 114.758724 -94.332298) (xy 114.714274 -94.332298) (xy 114.544094 -94.421198) (xy 114.544094 -94.642178)
			(xy 114.714274 -94.731078) (xy 114.758724 -94.731078)
		)
		(stroke
			(width 0)
			(type solid)
		)
		(fill yes)
		(layer "In11.Cu")
		(net "M_M_DQ<54>")
	)
	(gr_poly
		(pts
			(xy 114.758724 -93.354144) (xy 114.714274 -93.354144) (xy 114.544094 -93.443044) (xy 114.544094 -93.664024)
			(xy 114.714274 -93.752924) (xy 114.758724 -93.752924)
		)
		(stroke
			(width 0)
			(type solid)
		)
		(fill yes)
		(layer "In11.Cu")
		(net "M_M_DQ<54>")
	)
	(gr_poly
		(pts
			(xy 114.909092 -91.722448) (xy 114.90833 -91.323922) (xy 114.86388 -91.323922) (xy 114.693954 -91.413076)
			(xy 114.694208 -91.633802) (xy 114.864642 -91.722702)
		)
		(stroke
			(width 0)
			(type solid)
		)
		(fill yes)
		(layer "In11.Cu")
		(net "M_M_DQ<50>")
	)
	(gr_poly
		(pts
			(xy 114.99088 -99.54133) (xy 114.999008 -99.34956) (xy 114.807746 -99.23907) (xy 114.645694 -99.34194)
			(xy 114.623342 -99.380294) (xy 114.968782 -99.579938)
		)
		(stroke
			(width 0)
			(type solid)
		)
		(fill yes)
		(layer "In11.Cu")
		(net "M_M_DQ<53>")
	)
	(gr_poly
		(pts
			(xy 114.99088 -98.55073) (xy 114.999008 -98.35896) (xy 114.807746 -98.24847) (xy 114.645694 -98.35134)
			(xy 114.623342 -98.389694) (xy 114.968782 -98.589338)
		)
		(stroke
			(width 0)
			(type solid)
		)
		(fill yes)
		(layer "In11.Cu")
		(net "M_M_DQ<49>")
	)
	(gr_poly
		(pts
			(xy 114.99088 -97.56013) (xy 114.999008 -97.36836) (xy 114.807746 -97.25787) (xy 114.645694 -97.36074)
			(xy 114.623342 -97.399094) (xy 114.968782 -97.598738)
		)
		(stroke
			(width 0)
			(type solid)
		)
		(fill yes)
		(layer "In11.Cu")
		(net "M_M_DQS_DN<15>")
	)
	(gr_poly
		(pts
			(xy 114.99088 -96.56953) (xy 114.999008 -96.37776) (xy 114.807746 -96.26727) (xy 114.645694 -96.37014)
			(xy 114.623342 -96.408494) (xy 114.968782 -96.608138)
		)
		(stroke
			(width 0)
			(type solid)
		)
		(fill yes)
		(layer "In11.Cu")
		(net "M_M_DQS_DP<6>")
	)
	(gr_poly
		(pts
			(xy 115.01247 -61.964824) (xy 115.01247 -61.743844) (xy 114.84229 -61.654944) (xy 114.79784 -61.654944)
			(xy 114.79784 -62.053724) (xy 114.84229 -62.053724)
		)
		(stroke
			(width 0)
			(type solid)
		)
		(fill yes)
		(layer "In11.Cu")
		(net "M_J_DQ<53>")
	)
	(gr_poly
		(pts
			(xy 115.01247 -60.974224) (xy 115.01247 -60.753244) (xy 114.84229 -60.664344) (xy 114.79784 -60.664344)
			(xy 114.79784 -61.063124) (xy 114.84229 -61.063124)
		)
		(stroke
			(width 0)
			(type solid)
		)
		(fill yes)
		(layer "In11.Cu")
		(net "M_J_DQ<53>")
	)
	(gr_poly
		(pts
			(xy 115.01247 -59.977274) (xy 115.01247 -59.756294) (xy 114.84229 -59.667394) (xy 114.79784 -59.667394)
			(xy 114.79784 -60.066174) (xy 114.84229 -60.066174)
		)
		(stroke
			(width 0)
			(type solid)
		)
		(fill yes)
		(layer "In11.Cu")
		(net "M_J_DQ<53>")
	)
	(gr_poly
		(pts
			(xy 115.01247 -58.980578) (xy 115.01247 -58.759598) (xy 114.84229 -58.670698) (xy 114.79784 -58.670698)
			(xy 114.79784 -59.069478) (xy 114.84229 -59.069478)
		)
		(stroke
			(width 0)
			(type solid)
		)
		(fill yes)
		(layer "In11.Cu")
		(net "M_J_DQ<53>")
	)
	(gr_poly
		(pts
			(xy 115.01247 -58.002424) (xy 115.01247 -57.781444) (xy 114.84229 -57.692544) (xy 114.79784 -57.692544)
			(xy 114.79784 -58.091324) (xy 114.84229 -58.091324)
		)
		(stroke
			(width 0)
			(type solid)
		)
		(fill yes)
		(layer "In11.Cu")
		(net "M_J_DQ<53>")
	)
	(gr_poly
		(pts
			(xy 115.01247 -57.011824) (xy 115.01247 -56.790844) (xy 114.84229 -56.701944) (xy 114.79784 -56.701944)
			(xy 114.79784 -57.100724) (xy 114.84229 -57.100724)
		)
		(stroke
			(width 0)
			(type solid)
		)
		(fill yes)
		(layer "In11.Cu")
		(net "M_J_DQ<53>")
	)
	(gr_poly
		(pts
			(xy 115.01247 -56.021224) (xy 115.01247 -55.800244) (xy 114.84229 -55.711344) (xy 114.79784 -55.711344)
			(xy 114.79784 -56.110124) (xy 114.84229 -56.110124)
		)
		(stroke
			(width 0)
			(type solid)
		)
		(fill yes)
		(layer "In11.Cu")
		(net "M_J_DQ<53>")
	)
	(gr_poly
		(pts
			(xy 115.01247 -55.030624) (xy 115.01247 -54.809644) (xy 114.84229 -54.720744) (xy 114.79784 -54.720744)
			(xy 114.79784 -55.119524) (xy 114.84229 -55.119524)
		)
		(stroke
			(width 0)
			(type solid)
		)
		(fill yes)
		(layer "In11.Cu")
		(net "M_J_DQ<53>")
	)
	(gr_poly
		(pts
			(xy 115.046252 -52.628038) (xy 115.001802 -52.628038) (xy 114.808762 -52.716938) (xy 114.808762 -52.945538)
			(xy 115.001802 -53.034438) (xy 115.046252 -53.034438)
		)
		(stroke
			(width 0)
			(type solid)
		)
		(fill yes)
		(layer "In11.Cu")
		(net "M_J_DQ<48>")
	)
	(gr_poly
		(pts
			(xy 115.046252 -51.637438) (xy 115.001802 -51.637438) (xy 114.808762 -51.726338) (xy 114.808762 -51.954938)
			(xy 115.001802 -52.043838) (xy 115.046252 -52.043838)
		)
		(stroke
			(width 0)
			(type solid)
		)
		(fill yes)
		(layer "In11.Cu")
		(net "M_J_DQ<48>")
	)
	(gr_poly
		(pts
			(xy 115.046252 -50.646838) (xy 115.001802 -50.646838) (xy 114.808762 -50.735738) (xy 114.808762 -50.964338)
			(xy 115.001802 -51.053238) (xy 115.046252 -51.053238)
		)
		(stroke
			(width 0)
			(type solid)
		)
		(fill yes)
		(layer "In11.Cu")
		(net "M_J_DQ<48>")
	)
	(gr_poly
		(pts
			(xy 115.046252 -49.656238) (xy 115.001802 -49.656238) (xy 114.808762 -49.745138) (xy 114.808762 -49.973738)
			(xy 115.001802 -50.062638) (xy 115.046252 -50.062638)
		)
		(stroke
			(width 0)
			(type solid)
		)
		(fill yes)
		(layer "In11.Cu")
		(net "M_J_DQ<48>")
	)
	(gr_poly
		(pts
			(xy 115.046252 -48.665638) (xy 115.001802 -48.665638) (xy 114.808762 -48.754538) (xy 114.808762 -48.983138)
			(xy 115.001802 -49.072038) (xy 115.046252 -49.072038)
		)
		(stroke
			(width 0)
			(type solid)
		)
		(fill yes)
		(layer "In11.Cu")
		(net "M_J_DQ<48>")
	)
	(gr_poly
		(pts
			(xy 115.19535 -100.135182) (xy 115.217702 -100.096574) (xy 114.872262 -99.897438) (xy 114.850164 -99.935792)
			(xy 114.842036 -100.127562) (xy 115.033298 -100.238052)
		)
		(stroke
			(width 0)
			(type solid)
		)
		(fill yes)
		(layer "In11.Cu")
		(net "M_M_DQ<52>")
	)
	(gr_poly
		(pts
			(xy 115.19535 -99.144582) (xy 115.217702 -99.105974) (xy 114.872262 -98.906838) (xy 114.850164 -98.945192)
			(xy 114.842036 -99.136962) (xy 115.033298 -99.247452)
		)
		(stroke
			(width 0)
			(type solid)
		)
		(fill yes)
		(layer "In11.Cu")
		(net "M_M_DQ<48>")
	)
	(gr_poly
		(pts
			(xy 115.19535 -98.153982) (xy 115.217702 -98.115374) (xy 114.872262 -97.916238) (xy 114.850164 -97.954592)
			(xy 114.842036 -98.146362) (xy 115.033298 -98.256852)
		)
		(stroke
			(width 0)
			(type solid)
		)
		(fill yes)
		(layer "In11.Cu")
		(net "M_M_DQS_DP<15>")
	)
	(gr_poly
		(pts
			(xy 115.19535 -97.163382) (xy 115.217702 -97.124774) (xy 114.872262 -96.925638) (xy 114.850164 -96.963992)
			(xy 114.842036 -97.155762) (xy 115.033298 -97.266252)
		)
		(stroke
			(width 0)
			(type solid)
		)
		(fill yes)
		(layer "In11.Cu")
		(net "M_M_DQS_DN<6>")
	)
	(gr_poly
		(pts
			(xy 115.19535 -96.172782) (xy 115.217702 -96.134428) (xy 114.872008 -95.935038) (xy 114.850164 -95.973392)
			(xy 114.842036 -96.165162) (xy 115.033298 -96.275652)
		)
		(stroke
			(width 0)
			(type solid)
		)
		(fill yes)
		(layer "In11.Cu")
		(net "M_M_DQ<54>")
	)
	(gr_poly
		(pts
			(xy 115.287044 -92.174314) (xy 115.318286 -92.142818) (xy 115.034568 -91.862402) (xy 115.003326 -91.894152)
			(xy 114.946938 -92.07754) (xy 115.104164 -92.232988)
		)
		(stroke
			(width 0)
			(type solid)
		)
		(fill yes)
		(layer "In11.Cu")
		(net "M_M_DQ<50>")
	)
	(gr_poly
		(pts
			(xy 115.29695 -95.149924) (xy 115.29695 -94.928944) (xy 115.12677 -94.840044) (xy 115.08232 -94.840044)
			(xy 115.08232 -95.238824) (xy 115.12677 -95.238824)
		)
		(stroke
			(width 0)
			(type solid)
		)
		(fill yes)
		(layer "In11.Cu")
		(net "M_M_DQ<55>")
	)
	(gr_poly
		(pts
			(xy 115.29695 -94.153228) (xy 115.29695 -93.932248) (xy 115.12677 -93.843348) (xy 115.08232 -93.843348)
			(xy 115.08232 -94.242128) (xy 115.12677 -94.242128)
		)
		(stroke
			(width 0)
			(type solid)
		)
		(fill yes)
		(layer "In11.Cu")
		(net "M_M_DQ<55>")
	)
	(gr_poly
		(pts
			(xy 115.29695 -93.156278) (xy 115.29695 -92.935298) (xy 115.12677 -92.846398) (xy 115.08232 -92.846398)
			(xy 115.08232 -93.245178) (xy 115.12677 -93.245178)
		)
		(stroke
			(width 0)
			(type solid)
		)
		(fill yes)
		(layer "In11.Cu")
		(net "M_M_DQ<55>")
	)
	(gr_poly
		(pts
			(xy 115.332764 -61.654944) (xy 115.288314 -61.654944) (xy 115.118134 -61.743844) (xy 115.118134 -61.964824)
			(xy 115.288314 -62.053724) (xy 115.332764 -62.053724)
		)
		(stroke
			(width 0)
			(type solid)
		)
		(fill yes)
		(layer "In11.Cu")
		(net "M_J_DQ<48>")
	)
	(gr_poly
		(pts
			(xy 115.332764 -60.664344) (xy 115.288314 -60.664344) (xy 115.118134 -60.753244) (xy 115.118134 -60.974224)
			(xy 115.288314 -61.063124) (xy 115.332764 -61.063124)
		)
		(stroke
			(width 0)
			(type solid)
		)
		(fill yes)
		(layer "In11.Cu")
		(net "M_J_DQ<48>")
	)
	(gr_poly
		(pts
			(xy 115.332764 -59.667394) (xy 115.288314 -59.667394) (xy 115.118134 -59.756294) (xy 115.118134 -59.977274)
			(xy 115.288314 -60.066174) (xy 115.332764 -60.066174)
		)
		(stroke
			(width 0)
			(type solid)
		)
		(fill yes)
		(layer "In11.Cu")
		(net "M_J_DQ<48>")
	)
	(gr_poly
		(pts
			(xy 115.332764 -58.670698) (xy 115.288314 -58.670698) (xy 115.118134 -58.759598) (xy 115.118134 -58.980578)
			(xy 115.288314 -59.069478) (xy 115.332764 -59.069478)
		)
		(stroke
			(width 0)
			(type solid)
		)
		(fill yes)
		(layer "In11.Cu")
		(net "M_J_DQ<48>")
	)
	(gr_poly
		(pts
			(xy 115.332764 -57.692544) (xy 115.288314 -57.692544) (xy 115.118134 -57.781444) (xy 115.118134 -58.002424)
			(xy 115.288314 -58.091324) (xy 115.332764 -58.091324)
		)
		(stroke
			(width 0)
			(type solid)
		)
		(fill yes)
		(layer "In11.Cu")
		(net "M_J_DQ<48>")
	)
	(gr_poly
		(pts
			(xy 115.332764 -56.701944) (xy 115.288314 -56.701944) (xy 115.118134 -56.790844) (xy 115.118134 -57.011824)
			(xy 115.288314 -57.100724) (xy 115.332764 -57.100724)
		)
		(stroke
			(width 0)
			(type solid)
		)
		(fill yes)
		(layer "In11.Cu")
		(net "M_J_DQ<48>")
	)
	(gr_poly
		(pts
			(xy 115.332764 -55.711344) (xy 115.288314 -55.711344) (xy 115.118134 -55.800244) (xy 115.118134 -56.021224)
			(xy 115.288314 -56.110124) (xy 115.332764 -56.110124)
		)
		(stroke
			(width 0)
			(type solid)
		)
		(fill yes)
		(layer "In11.Cu")
		(net "M_J_DQ<48>")
	)
	(gr_poly
		(pts
			(xy 115.332764 -54.720744) (xy 115.288314 -54.720744) (xy 115.118134 -54.809644) (xy 115.118134 -55.030624)
			(xy 115.288314 -55.119524) (xy 115.332764 -55.119524)
		)
		(stroke
			(width 0)
			(type solid)
		)
		(fill yes)
		(layer "In11.Cu")
		(net "M_J_DQ<48>")
	)
	(gr_poly
		(pts
			(xy 115.391692 -63.013336) (xy 115.420648 -62.823598) (xy 115.24234 -62.693042) (xy 115.070128 -62.777878)
			(xy 115.043712 -62.813692) (xy 115.36553 -63.04915)
		)
		(stroke
			(width 0)
			(type solid)
		)
		(fill yes)
		(layer "In11.Cu")
		(net "M_J_DQ<53>")
	)
	(gr_poly
		(pts
			(xy 115.474242 -52.945538) (xy 115.474242 -52.716938) (xy 115.281202 -52.628038) (xy 115.236752 -52.628038)
			(xy 115.236752 -53.034438) (xy 115.281202 -53.034438)
		)
		(stroke
			(width 0)
			(type solid)
		)
		(fill yes)
		(layer "In11.Cu")
		(net "M_J_DQ<49>")
	)
	(gr_poly
		(pts
			(xy 115.474242 -51.954938) (xy 115.474242 -51.726338) (xy 115.281202 -51.637438) (xy 115.236752 -51.637438)
			(xy 115.236752 -52.043838) (xy 115.281202 -52.043838)
		)
		(stroke
			(width 0)
			(type solid)
		)
		(fill yes)
		(layer "In11.Cu")
		(net "M_J_DQ<49>")
	)
	(gr_poly
		(pts
			(xy 115.474242 -50.964338) (xy 115.474242 -50.735738) (xy 115.281202 -50.646838) (xy 115.236752 -50.646838)
			(xy 115.236752 -51.053238) (xy 115.281202 -51.053238)
		)
		(stroke
			(width 0)
			(type solid)
		)
		(fill yes)
		(layer "In11.Cu")
		(net "M_J_DQ<49>")
	)
	(gr_poly
		(pts
			(xy 115.474242 -49.973738) (xy 115.474242 -49.745138) (xy 115.281202 -49.656238) (xy 115.236752 -49.656238)
			(xy 115.236752 -50.062638) (xy 115.281202 -50.062638)
		)
		(stroke
			(width 0)
			(type solid)
		)
		(fill yes)
		(layer "In11.Cu")
		(net "M_J_DQ<49>")
	)
	(gr_poly
		(pts
			(xy 115.474242 -48.983138) (xy 115.474242 -48.754538) (xy 115.281202 -48.665638) (xy 115.236752 -48.665638)
			(xy 115.236752 -49.072038) (xy 115.281202 -49.072038)
		)
		(stroke
			(width 0)
			(type solid)
		)
		(fill yes)
		(layer "In11.Cu")
		(net "M_J_DQ<49>")
	)
	(gr_poly
		(pts
			(xy 115.479068 -105.320338) (xy 115.447572 -105.288842) (xy 115.248436 -105.215182) (xy 115.086638 -105.37698)
			(xy 115.160298 -105.576116) (xy 115.191794 -105.607612)
		)
		(stroke
			(width 0)
			(type solid)
		)
		(fill yes)
		(layer "In11.Cu")
		(net "M_M_DQ<52>")
	)
	(gr_poly
		(pts
			(xy 115.617244 -103.742998) (xy 115.572794 -103.742998) (xy 115.402614 -103.831898) (xy 115.402614 -104.052878)
			(xy 115.572794 -104.141778) (xy 115.617244 -104.141778)
		)
		(stroke
			(width 0)
			(type solid)
		)
		(fill yes)
		(layer "In11.Cu")
		(net "M_M_DQ<52>")
	)
	(gr_poly
		(pts
			(xy 115.617244 -102.752398) (xy 115.572794 -102.752398) (xy 115.402614 -102.841298) (xy 115.402614 -103.062278)
			(xy 115.572794 -103.151178) (xy 115.617244 -103.151178)
		)
		(stroke
			(width 0)
			(type solid)
		)
		(fill yes)
		(layer "In11.Cu")
		(net "M_M_DQ<52>")
	)
	(gr_poly
		(pts
			(xy 115.617244 -101.761798) (xy 115.572794 -101.761798) (xy 115.402614 -101.850698) (xy 115.402614 -102.071678)
			(xy 115.572794 -102.160578) (xy 115.617244 -102.160578)
		)
		(stroke
			(width 0)
			(type solid)
		)
		(fill yes)
		(layer "In11.Cu")
		(net "M_M_DQ<52>")
	)
	(gr_poly
		(pts
			(xy 115.617244 -100.771198) (xy 115.572794 -100.771198) (xy 115.402614 -100.860098) (xy 115.402614 -101.081078)
			(xy 115.572794 -101.169978) (xy 115.617244 -101.169978)
		)
		(stroke
			(width 0)
			(type solid)
		)
		(fill yes)
		(layer "In11.Cu")
		(net "M_M_DQ<52>")
	)
	(gr_poly
		(pts
			(xy 115.617244 -94.833948) (xy 115.572794 -94.833948) (xy 115.402614 -94.922848) (xy 115.402614 -95.143828)
			(xy 115.572794 -95.232728) (xy 115.617244 -95.232728)
		)
		(stroke
			(width 0)
			(type solid)
		)
		(fill yes)
		(layer "In11.Cu")
		(net "M_M_DQ<50>")
	)
	(gr_poly
		(pts
			(xy 115.617244 -93.843348) (xy 115.572794 -93.843348) (xy 115.402614 -93.932248) (xy 115.402614 -94.153228)
			(xy 115.572794 -94.242128) (xy 115.617244 -94.242128)
		)
		(stroke
			(width 0)
			(type solid)
		)
		(fill yes)
		(layer "In11.Cu")
		(net "M_M_DQ<50>")
	)
	(gr_poly
		(pts
			(xy 115.617244 -92.846398) (xy 115.572794 -92.846398) (xy 115.402614 -92.935298) (xy 115.402614 -93.156278)
			(xy 115.572794 -93.245178) (xy 115.617244 -93.245178)
		)
		(stroke
			(width 0)
			(type solid)
		)
		(fill yes)
		(layer "In11.Cu")
		(net "M_M_DQ<50>")
	)
	(gr_poly
		(pts
			(xy 115.719098 -105.686098) (xy 115.645438 -105.486708) (xy 115.614196 -105.455212) (xy 115.326668 -105.74274)
			(xy 115.358164 -105.773982) (xy 115.557554 -105.847642)
		)
		(stroke
			(width 0)
			(type solid)
		)
		(fill yes)
		(layer "In11.Cu")
		(net "M_M_DQ<53>")
	)
	(gr_poly
		(pts
			(xy 115.847622 -100.035106) (xy 115.85575 -99.843336) (xy 115.664488 -99.7331) (xy 115.502436 -99.83597)
			(xy 115.480084 -99.874324) (xy 115.825778 -100.073714)
		)
		(stroke
			(width 0)
			(type solid)
		)
		(fill yes)
		(layer "In11.Cu")
		(net "M_M_DQ<53>")
	)
	(gr_poly
		(pts
			(xy 115.847876 -99.045014) (xy 115.856004 -98.853244) (xy 115.664742 -98.742754) (xy 115.50269 -98.845624)
			(xy 115.480338 -98.883978) (xy 115.825778 -99.083622)
		)
		(stroke
			(width 0)
			(type solid)
		)
		(fill yes)
		(layer "In11.Cu")
		(net "M_M_DQ<49>")
	)
	(gr_poly
		(pts
			(xy 115.847876 -98.054414) (xy 115.856004 -97.862644) (xy 115.664742 -97.752154) (xy 115.50269 -97.855024)
			(xy 115.480338 -97.893378) (xy 115.825778 -98.093022)
		)
		(stroke
			(width 0)
			(type solid)
		)
		(fill yes)
		(layer "In11.Cu")
		(net "M_M_DQS_DN<15>")
	)
	(gr_poly
		(pts
			(xy 115.847876 -97.063814) (xy 115.856004 -96.872044) (xy 115.664742 -96.761554) (xy 115.50269 -96.864424)
			(xy 115.480338 -96.902778) (xy 115.825778 -97.102422)
		)
		(stroke
			(width 0)
			(type solid)
		)
		(fill yes)
		(layer "In11.Cu")
		(net "M_M_DQS_DP<6>")
	)
	(gr_poly
		(pts
			(xy 115.847876 -96.073214) (xy 115.856004 -95.881444) (xy 115.664742 -95.770954) (xy 115.50269 -95.873824)
			(xy 115.480338 -95.912178) (xy 115.825778 -96.111822)
		)
		(stroke
			(width 0)
			(type solid)
		)
		(fill yes)
		(layer "In11.Cu")
		(net "M_M_DQ<55>")
	)
	(gr_poly
		(pts
			(xy 115.87099 -61.457078) (xy 115.87099 -61.236098) (xy 115.70081 -61.147198) (xy 115.65636 -61.147198)
			(xy 115.65636 -61.545978) (xy 115.70081 -61.545978)
		)
		(stroke
			(width 0)
			(type solid)
		)
		(fill yes)
		(layer "In11.Cu")
		(net "M_J_DQ<49>")
	)
	(gr_poly
		(pts
			(xy 115.87099 -60.466478) (xy 115.87099 -60.245498) (xy 115.70081 -60.156598) (xy 115.65636 -60.156598)
			(xy 115.65636 -60.555378) (xy 115.70081 -60.555378)
		)
		(stroke
			(width 0)
			(type solid)
		)
		(fill yes)
		(layer "In11.Cu")
		(net "M_J_DQ<49>")
	)
	(gr_poly
		(pts
			(xy 115.87099 -59.488324) (xy 115.87099 -59.267344) (xy 115.70081 -59.178444) (xy 115.65636 -59.178444)
			(xy 115.65636 -59.577224) (xy 115.70081 -59.577224)
		)
		(stroke
			(width 0)
			(type solid)
		)
		(fill yes)
		(layer "In11.Cu")
		(net "M_J_DQ<49>")
	)
	(gr_poly
		(pts
			(xy 115.87099 -58.491628) (xy 115.87099 -58.270648) (xy 115.70081 -58.181748) (xy 115.65636 -58.181748)
			(xy 115.65636 -58.580528) (xy 115.70081 -58.580528)
		)
		(stroke
			(width 0)
			(type solid)
		)
		(fill yes)
		(layer "In11.Cu")
		(net "M_J_DQ<49>")
	)
	(gr_poly
		(pts
			(xy 115.87099 -57.494678) (xy 115.87099 -57.273698) (xy 115.70081 -57.184798) (xy 115.65636 -57.184798)
			(xy 115.65636 -57.583578) (xy 115.70081 -57.583578)
		)
		(stroke
			(width 0)
			(type solid)
		)
		(fill yes)
		(layer "In11.Cu")
		(net "M_J_DQ<49>")
	)
	(gr_poly
		(pts
			(xy 115.87099 -56.504078) (xy 115.87099 -56.283098) (xy 115.70081 -56.194198) (xy 115.65636 -56.194198)
			(xy 115.65636 -56.592978) (xy 115.70081 -56.592978)
		)
		(stroke
			(width 0)
			(type solid)
		)
		(fill yes)
		(layer "In11.Cu")
		(net "M_J_DQ<49>")
	)
	(gr_poly
		(pts
			(xy 115.87099 -55.513478) (xy 115.87099 -55.292498) (xy 115.70081 -55.203598) (xy 115.65636 -55.203598)
			(xy 115.65636 -55.602378) (xy 115.70081 -55.602378)
		)
		(stroke
			(width 0)
			(type solid)
		)
		(fill yes)
		(layer "In11.Cu")
		(net "M_J_DQ<49>")
	)
	(gr_poly
		(pts
			(xy 115.87099 -54.522878) (xy 115.87099 -54.301898) (xy 115.70081 -54.212998) (xy 115.65636 -54.212998)
			(xy 115.65636 -54.611778) (xy 115.70081 -54.611778)
		)
		(stroke
			(width 0)
			(type solid)
		)
		(fill yes)
		(layer "In11.Cu")
		(net "M_J_DQ<49>")
	)
	(gr_poly
		(pts
			(xy 116.041932 -49.688242) (xy 115.997482 -49.688242) (xy 115.827302 -49.777142) (xy 115.827302 -49.998122)
			(xy 115.997482 -50.087022) (xy 116.041932 -50.087022)
		)
		(stroke
			(width 0)
			(type solid)
		)
		(fill yes)
		(layer "In11.Cu")
		(net "M_J_DQS_DP<15>")
	)
	(gr_poly
		(pts
			(xy 116.041932 -48.697642) (xy 115.997482 -48.697642) (xy 115.827302 -48.786542) (xy 115.827302 -49.007522)
			(xy 115.997482 -49.096422) (xy 116.041932 -49.096422)
		)
		(stroke
			(width 0)
			(type solid)
		)
		(fill yes)
		(layer "In11.Cu")
		(net "M_J_DQS_DP<15>")
	)
	(gr_poly
		(pts
			(xy 116.055394 -99.640898) (xy 116.077746 -99.60229) (xy 115.732306 -99.403154) (xy 115.710208 -99.441508)
			(xy 115.70208 -99.633278) (xy 115.893342 -99.743768)
		)
		(stroke
			(width 0)
			(type solid)
		)
		(fill yes)
		(layer "In11.Cu")
		(net "M_M_DQ<48>")
	)
	(gr_poly
		(pts
			(xy 116.055394 -98.650298) (xy 116.077746 -98.61169) (xy 115.732306 -98.412554) (xy 115.710208 -98.450908)
			(xy 115.70208 -98.642678) (xy 115.893342 -98.753168)
		)
		(stroke
			(width 0)
			(type solid)
		)
		(fill yes)
		(layer "In11.Cu")
		(net "M_M_DQS_DP<15>")
	)
	(gr_poly
		(pts
			(xy 116.055394 -97.659698) (xy 116.077746 -97.62109) (xy 115.732306 -97.421954) (xy 115.710208 -97.460308)
			(xy 115.70208 -97.652078) (xy 115.893342 -97.762568)
		)
		(stroke
			(width 0)
			(type solid)
		)
		(fill yes)
		(layer "In11.Cu")
		(net "M_M_DQS_DN<6>")
	)
	(gr_poly
		(pts
			(xy 116.055394 -96.669098) (xy 116.077746 -96.63049) (xy 115.732306 -96.431354) (xy 115.710208 -96.469708)
			(xy 115.70208 -96.661478) (xy 115.893342 -96.771968)
		)
		(stroke
			(width 0)
			(type solid)
		)
		(fill yes)
		(layer "In11.Cu")
		(net "M_M_DQ<54>")
	)
	(gr_poly
		(pts
			(xy 116.063014 -95.68307) (xy 116.085366 -95.644716) (xy 115.739672 -95.445326) (xy 115.717574 -95.483934)
			(xy 115.7097 -95.675704) (xy 115.900962 -95.78594)
		)
		(stroke
			(width 0)
			(type solid)
		)
		(fill yes)
		(layer "In11.Cu")
		(net "M_M_DQ<50>")
	)
	(gr_poly
		(pts
			(xy 116.15547 -104.560624) (xy 116.15547 -104.339644) (xy 115.98529 -104.250744) (xy 115.94084 -104.250744)
			(xy 115.94084 -104.649524) (xy 115.98529 -104.649524)
		)
		(stroke
			(width 0)
			(type solid)
		)
		(fill yes)
		(layer "In11.Cu")
		(net "M_M_DQ<53>")
	)
	(gr_poly
		(pts
			(xy 116.15547 -103.570024) (xy 116.15547 -103.349044) (xy 115.98529 -103.260144) (xy 115.94084 -103.260144)
			(xy 115.94084 -103.658924) (xy 115.98529 -103.658924)
		)
		(stroke
			(width 0)
			(type solid)
		)
		(fill yes)
		(layer "In11.Cu")
		(net "M_M_DQ<53>")
	)
	(gr_poly
		(pts
			(xy 116.15547 -102.579424) (xy 116.15547 -102.358444) (xy 115.98529 -102.269544) (xy 115.94084 -102.269544)
			(xy 115.94084 -102.668324) (xy 115.98529 -102.668324)
		)
		(stroke
			(width 0)
			(type solid)
		)
		(fill yes)
		(layer "In11.Cu")
		(net "M_M_DQ<53>")
	)
	(gr_poly
		(pts
			(xy 116.15547 -101.588824) (xy 116.15547 -101.367844) (xy 115.98529 -101.278944) (xy 115.94084 -101.278944)
			(xy 115.94084 -101.677724) (xy 115.98529 -101.677724)
		)
		(stroke
			(width 0)
			(type solid)
		)
		(fill yes)
		(layer "In11.Cu")
		(net "M_M_DQ<53>")
	)
	(gr_poly
		(pts
			(xy 116.15547 -100.598224) (xy 116.15547 -100.377244) (xy 115.98529 -100.288344) (xy 115.94084 -100.288344)
			(xy 115.94084 -100.687124) (xy 115.98529 -100.687124)
		)
		(stroke
			(width 0)
			(type solid)
		)
		(fill yes)
		(layer "In11.Cu")
		(net "M_M_DQ<53>")
	)
	(gr_poly
		(pts
			(xy 116.15547 -94.642178) (xy 116.15547 -94.421198) (xy 115.98529 -94.332298) (xy 115.94084 -94.332298)
			(xy 115.94084 -94.731078) (xy 115.98529 -94.731078)
		)
		(stroke
			(width 0)
			(type solid)
		)
		(fill yes)
		(layer "In11.Cu")
		(net "M_M_DQ<51>")
	)
	(gr_poly
		(pts
			(xy 116.15547 -93.664024) (xy 116.15547 -93.443044) (xy 115.98529 -93.354144) (xy 115.94084 -93.354144)
			(xy 115.94084 -93.752924) (xy 115.98529 -93.752924)
		)
		(stroke
			(width 0)
			(type solid)
		)
		(fill yes)
		(layer "In11.Cu")
		(net "M_M_DQ<51>")
	)
	(gr_poly
		(pts
			(xy 116.15547 -92.673424) (xy 116.15547 -92.452444) (xy 115.98529 -92.363544) (xy 115.94084 -92.363544)
			(xy 115.94084 -92.762324) (xy 115.98529 -92.762324)
		)
		(stroke
			(width 0)
			(type solid)
		)
		(fill yes)
		(layer "In11.Cu")
		(net "M_M_DQ<51>")
	)
	(gr_poly
		(pts
			(xy 116.191284 -61.153548) (xy 116.146834 -61.153548) (xy 115.976654 -61.242448) (xy 115.976654 -61.463428)
			(xy 116.146834 -61.552328) (xy 116.191284 -61.552328)
		)
		(stroke
			(width 0)
			(type solid)
		)
		(fill yes)
		(layer "In11.Cu")
		(net "M_J_DQS_DP<15>")
	)
	(gr_poly
		(pts
			(xy 116.191284 -60.156598) (xy 116.146834 -60.156598) (xy 115.976654 -60.245498) (xy 115.976654 -60.466478)
			(xy 116.146834 -60.555378) (xy 116.191284 -60.555378)
		)
		(stroke
			(width 0)
			(type solid)
		)
		(fill yes)
		(layer "In11.Cu")
		(net "M_J_DQS_DP<15>")
	)
	(gr_poly
		(pts
			(xy 116.191284 -59.165998) (xy 116.146834 -59.165998) (xy 115.976654 -59.254898) (xy 115.976654 -59.475878)
			(xy 116.146834 -59.564778) (xy 116.191284 -59.564778)
		)
		(stroke
			(width 0)
			(type solid)
		)
		(fill yes)
		(layer "In11.Cu")
		(net "M_J_DQS_DP<15>")
	)
	(gr_poly
		(pts
			(xy 116.191284 -58.181748) (xy 116.146834 -58.181748) (xy 115.976654 -58.270648) (xy 115.976654 -58.491628)
			(xy 116.146834 -58.580528) (xy 116.191284 -58.580528)
		)
		(stroke
			(width 0)
			(type solid)
		)
		(fill yes)
		(layer "In11.Cu")
		(net "M_J_DQS_DP<15>")
	)
	(gr_poly
		(pts
			(xy 116.191284 -57.184798) (xy 116.146834 -57.184798) (xy 115.976654 -57.273698) (xy 115.976654 -57.494678)
			(xy 116.146834 -57.583578) (xy 116.191284 -57.583578)
		)
		(stroke
			(width 0)
			(type solid)
		)
		(fill yes)
		(layer "In11.Cu")
		(net "M_J_DQS_DP<15>")
	)
	(gr_poly
		(pts
			(xy 116.191284 -56.194198) (xy 116.146834 -56.194198) (xy 115.976654 -56.283098) (xy 115.976654 -56.504078)
			(xy 116.146834 -56.592978) (xy 116.191284 -56.592978)
		)
		(stroke
			(width 0)
			(type solid)
		)
		(fill yes)
		(layer "In11.Cu")
		(net "M_J_DQS_DP<15>")
	)
	(gr_poly
		(pts
			(xy 116.191284 -55.203598) (xy 116.146834 -55.203598) (xy 115.976654 -55.292498) (xy 115.976654 -55.513478)
			(xy 116.146834 -55.602378) (xy 116.191284 -55.602378)
		)
		(stroke
			(width 0)
			(type solid)
		)
		(fill yes)
		(layer "In11.Cu")
		(net "M_J_DQS_DP<15>")
	)
	(gr_poly
		(pts
			(xy 116.191284 -54.212998) (xy 116.146834 -54.212998) (xy 115.976654 -54.301898) (xy 115.976654 -54.522878)
			(xy 116.146834 -54.611778) (xy 116.191284 -54.611778)
		)
		(stroke
			(width 0)
			(type solid)
		)
		(fill yes)
		(layer "In11.Cu")
		(net "M_J_DQS_DP<15>")
	)
	(gr_poly
		(pts
			(xy 116.219986 -51.591972) (xy 116.251482 -51.56073) (xy 115.963954 -51.273202) (xy 115.932712 -51.304698)
			(xy 115.859052 -51.504088) (xy 116.020596 -51.665632)
		)
		(stroke
			(width 0)
			(type solid)
		)
		(fill yes)
		(layer "In11.Cu")
		(net "M_J_DQS_DP<15>")
	)
	(gr_poly
		(pts
			(xy 116.3066 -63.3349) (xy 116.26596 -63.147194) (xy 116.237512 -63.113158) (xy 115.931188 -63.368428)
			(xy 115.959636 -63.402464) (xy 116.136674 -63.476378)
		)
		(stroke
			(width 0)
			(type solid)
		)
		(fill yes)
		(layer "In11.Cu")
		(net "M_J_DQ<49>")
	)
	(gr_poly
		(pts
			(xy 116.324126 -53.20919) (xy 116.279676 -53.20919) (xy 116.086636 -53.29809) (xy 116.086636 -53.52669)
			(xy 116.279676 -53.61559) (xy 116.324126 -53.61559)
		)
		(stroke
			(width 0)
			(type solid)
		)
		(fill yes)
		(layer "In11.Cu")
		(net "M_J_DQS_DP<15>")
	)
	(gr_poly
		(pts
			(xy 116.324126 -52.21859) (xy 116.279676 -52.21859) (xy 116.086636 -52.30749) (xy 116.086636 -52.53609)
			(xy 116.279676 -52.62499) (xy 116.324126 -52.62499)
		)
		(stroke
			(width 0)
			(type solid)
		)
		(fill yes)
		(layer "In11.Cu")
		(net "M_J_DQS_DP<15>")
	)
	(gr_poly
		(pts
			(xy 116.447062 -49.998122) (xy 116.447062 -49.777142) (xy 116.276882 -49.688242) (xy 116.232432 -49.688242)
			(xy 116.232432 -50.087022) (xy 116.276882 -50.087022)
		)
		(stroke
			(width 0)
			(type solid)
		)
		(fill yes)
		(layer "In11.Cu")
		(net "M_J_DQS_DN<15>")
	)
	(gr_poly
		(pts
			(xy 116.447062 -49.007522) (xy 116.447062 -48.786542) (xy 116.276882 -48.697642) (xy 116.232432 -48.697642)
			(xy 116.232432 -49.096422) (xy 116.276882 -49.096422)
		)
		(stroke
			(width 0)
			(type solid)
		)
		(fill yes)
		(layer "In11.Cu")
		(net "M_J_DQS_DN<15>")
	)
	(gr_poly
		(pts
			(xy 116.475764 -105.243884) (xy 116.431314 -105.243884) (xy 116.261134 -105.332784) (xy 116.261134 -105.553764)
			(xy 116.431314 -105.642664) (xy 116.475764 -105.642664)
		)
		(stroke
			(width 0)
			(type solid)
		)
		(fill yes)
		(layer "In11.Cu")
		(net "M_M_DQ<48>")
	)
	(gr_poly
		(pts
			(xy 116.475764 -104.253284) (xy 116.431314 -104.253284) (xy 116.261134 -104.342184) (xy 116.261134 -104.563164)
			(xy 116.431314 -104.652064) (xy 116.475764 -104.652064)
		)
		(stroke
			(width 0)
			(type solid)
		)
		(fill yes)
		(layer "In11.Cu")
		(net "M_M_DQ<48>")
	)
	(gr_poly
		(pts
			(xy 116.475764 -103.262684) (xy 116.431314 -103.262684) (xy 116.261134 -103.351584) (xy 116.261134 -103.572564)
			(xy 116.431314 -103.661464) (xy 116.475764 -103.661464)
		)
		(stroke
			(width 0)
			(type solid)
		)
		(fill yes)
		(layer "In11.Cu")
		(net "M_M_DQ<48>")
	)
	(gr_poly
		(pts
			(xy 116.475764 -102.272084) (xy 116.431314 -102.272084) (xy 116.261134 -102.360984) (xy 116.261134 -102.581964)
			(xy 116.431314 -102.670864) (xy 116.475764 -102.670864)
		)
		(stroke
			(width 0)
			(type solid)
		)
		(fill yes)
		(layer "In11.Cu")
		(net "M_M_DQ<48>")
	)
	(gr_poly
		(pts
			(xy 116.475764 -101.281484) (xy 116.431314 -101.281484) (xy 116.261134 -101.370384) (xy 116.261134 -101.591364)
			(xy 116.431314 -101.680264) (xy 116.475764 -101.680264)
		)
		(stroke
			(width 0)
			(type solid)
		)
		(fill yes)
		(layer "In11.Cu")
		(net "M_M_DQ<48>")
	)
	(gr_poly
		(pts
			(xy 116.475764 -100.290884) (xy 116.431314 -100.290884) (xy 116.261134 -100.379784) (xy 116.261134 -100.600764)
			(xy 116.431314 -100.689664) (xy 116.475764 -100.689664)
		)
		(stroke
			(width 0)
			(type solid)
		)
		(fill yes)
		(layer "In11.Cu")
		(net "M_M_DQ<48>")
	)
	(gr_poly
		(pts
			(xy 116.475764 -94.344744) (xy 116.431314 -94.344744) (xy 116.261134 -94.433644) (xy 116.261134 -94.654624)
			(xy 116.431314 -94.743524) (xy 116.475764 -94.743524)
		)
		(stroke
			(width 0)
			(type solid)
		)
		(fill yes)
		(layer "In11.Cu")
		(net "M_M_DQ<60>")
	)
	(gr_poly
		(pts
			(xy 116.475764 -93.354144) (xy 116.431314 -93.354144) (xy 116.261134 -93.443044) (xy 116.261134 -93.664024)
			(xy 116.431314 -93.752924) (xy 116.475764 -93.752924)
		)
		(stroke
			(width 0)
			(type solid)
		)
		(fill yes)
		(layer "In11.Cu")
		(net "M_M_DQ<60>")
	)
	(gr_poly
		(pts
			(xy 116.475764 -92.363544) (xy 116.431314 -92.363544) (xy 116.261134 -92.452444) (xy 116.261134 -92.673424)
			(xy 116.431314 -92.762324) (xy 116.475764 -92.762324)
		)
		(stroke
			(width 0)
			(type solid)
		)
		(fill yes)
		(layer "In11.Cu")
		(net "M_M_DQ<60>")
	)
	(gr_poly
		(pts
			(xy 116.475764 -91.372944) (xy 116.431314 -91.372944) (xy 116.261134 -91.461844) (xy 116.261134 -91.682824)
			(xy 116.431314 -91.771724) (xy 116.475764 -91.771724)
		)
		(stroke
			(width 0)
			(type solid)
		)
		(fill yes)
		(layer "In11.Cu")
		(net "M_M_DQ<60>")
	)
	(gr_poly
		(pts
			(xy 116.596414 -47.731426) (xy 116.564918 -47.69993) (xy 116.381784 -47.642526) (xy 116.225574 -47.798736)
			(xy 116.282978 -47.98187) (xy 116.314474 -48.013366)
		)
		(stroke
			(width 0)
			(type solid)
		)
		(fill yes)
		(layer "In11.Cu")
		(net "M_J_DQS_DP<15>")
	)
	(gr_poly
		(pts
			(xy 116.702586 -99.537774) (xy 116.710714 -99.346004) (xy 116.519198 -99.235768) (xy 116.3574 -99.338638)
			(xy 116.334794 -99.376992) (xy 116.680488 -99.576382)
		)
		(stroke
			(width 0)
			(type solid)
		)
		(fill yes)
		(layer "In11.Cu")
		(net "M_M_DQ<49>")
	)
	(gr_poly
		(pts
			(xy 116.70411 -95.576644) (xy 116.712238 -95.384874) (xy 116.520976 -95.274384) (xy 116.358924 -95.377254)
			(xy 116.336572 -95.415862) (xy 116.682012 -95.614998)
		)
		(stroke
			(width 0)
			(type solid)
		)
		(fill yes)
		(layer "In11.Cu")
		(net "M_M_DQ<51>")
	)
	(gr_poly
		(pts
			(xy 116.70792 -98.55073) (xy 116.716048 -98.35896) (xy 116.524786 -98.24847) (xy 116.362734 -98.35134)
			(xy 116.340382 -98.389694) (xy 116.685822 -98.589338)
		)
		(stroke
			(width 0)
			(type solid)
		)
		(fill yes)
		(layer "In11.Cu")
		(net "M_M_DQS_DN<15>")
	)
	(gr_poly
		(pts
			(xy 116.70792 -97.56013) (xy 116.716048 -97.36836) (xy 116.524786 -97.25787) (xy 116.362734 -97.36074)
			(xy 116.340382 -97.399094) (xy 116.685822 -97.598738)
		)
		(stroke
			(width 0)
			(type solid)
		)
		(fill yes)
		(layer "In11.Cu")
		(net "M_M_DQS_DP<6>")
	)
	(gr_poly
		(pts
			(xy 116.70792 -96.56953) (xy 116.716048 -96.37776) (xy 116.524786 -96.26727) (xy 116.362734 -96.37014)
			(xy 116.340382 -96.408494) (xy 116.685822 -96.608138)
		)
		(stroke
			(width 0)
			(type solid)
		)
		(fill yes)
		(layer "In11.Cu")
		(net "M_M_DQ<55>")
	)
	(gr_poly
		(pts
			(xy 116.72951 -60.974224) (xy 116.72951 -60.753244) (xy 116.55933 -60.664344) (xy 116.51488 -60.664344)
			(xy 116.51488 -61.063124) (xy 116.55933 -61.063124)
		)
		(stroke
			(width 0)
			(type solid)
		)
		(fill yes)
		(layer "In11.Cu")
		(net "M_J_DQS_DN<15>")
	)
	(gr_poly
		(pts
			(xy 116.72951 -59.977274) (xy 116.72951 -59.756294) (xy 116.55933 -59.667394) (xy 116.51488 -59.667394)
			(xy 116.51488 -60.066174) (xy 116.55933 -60.066174)
		)
		(stroke
			(width 0)
			(type solid)
		)
		(fill yes)
		(layer "In11.Cu")
		(net "M_J_DQS_DN<15>")
	)
	(gr_poly
		(pts
			(xy 116.72951 -58.980578) (xy 116.72951 -58.759598) (xy 116.55933 -58.670698) (xy 116.51488 -58.670698)
			(xy 116.51488 -59.069478) (xy 116.55933 -59.069478)
		)
		(stroke
			(width 0)
			(type solid)
		)
		(fill yes)
		(layer "In11.Cu")
		(net "M_J_DQS_DN<15>")
	)
	(gr_poly
		(pts
			(xy 116.72951 -58.002424) (xy 116.72951 -57.781444) (xy 116.55933 -57.692544) (xy 116.51488 -57.692544)
			(xy 116.51488 -58.091324) (xy 116.55933 -58.091324)
		)
		(stroke
			(width 0)
			(type solid)
		)
		(fill yes)
		(layer "In11.Cu")
		(net "M_J_DQS_DN<15>")
	)
	(gr_poly
		(pts
			(xy 116.72951 -57.011824) (xy 116.72951 -56.790844) (xy 116.55933 -56.701944) (xy 116.51488 -56.701944)
			(xy 116.51488 -57.100724) (xy 116.55933 -57.100724)
		)
		(stroke
			(width 0)
			(type solid)
		)
		(fill yes)
		(layer "In11.Cu")
		(net "M_J_DQS_DN<15>")
	)
	(gr_poly
		(pts
			(xy 116.72951 -56.021224) (xy 116.72951 -55.800244) (xy 116.55933 -55.711344) (xy 116.51488 -55.711344)
			(xy 116.51488 -56.110124) (xy 116.55933 -56.110124)
		)
		(stroke
			(width 0)
			(type solid)
		)
		(fill yes)
		(layer "In11.Cu")
		(net "M_J_DQS_DN<15>")
	)
	(gr_poly
		(pts
			(xy 116.72951 -55.030624) (xy 116.72951 -54.809644) (xy 116.55933 -54.720744) (xy 116.51488 -54.720744)
			(xy 116.51488 -55.119524) (xy 116.55933 -55.119524)
		)
		(stroke
			(width 0)
			(type solid)
		)
		(fill yes)
		(layer "In11.Cu")
		(net "M_J_DQS_DN<15>")
	)
	(gr_poly
		(pts
			(xy 116.752116 -53.88229) (xy 116.752116 -53.65369) (xy 116.559076 -53.56479) (xy 116.514626 -53.56479)
			(xy 116.514626 -53.97119) (xy 116.559076 -53.97119)
		)
		(stroke
			(width 0)
			(type solid)
		)
		(fill yes)
		(layer "In11.Cu")
		(net "M_J_DQS_DN<15>")
	)
	(gr_poly
		(pts
			(xy 116.752116 -52.89169) (xy 116.752116 -52.66309) (xy 116.559076 -52.57419) (xy 116.514626 -52.57419)
			(xy 116.514626 -52.98059) (xy 116.559076 -52.98059)
		)
		(stroke
			(width 0)
			(type solid)
		)
		(fill yes)
		(layer "In11.Cu")
		(net "M_J_DQS_DN<15>")
	)
	(gr_poly
		(pts
			(xy 116.752116 -51.90109) (xy 116.752116 -51.67249) (xy 116.559076 -51.58359) (xy 116.514626 -51.58359)
			(xy 116.514626 -51.98999) (xy 116.559076 -51.98999)
		)
		(stroke
			(width 0)
			(type solid)
		)
		(fill yes)
		(layer "In11.Cu")
		(net "M_J_DQS_DN<15>")
	)
	(gr_poly
		(pts
			(xy 116.763292 -49.727866) (xy 116.718842 -49.727866) (xy 116.548662 -49.816766) (xy 116.548662 -50.038)
			(xy 116.718842 -50.1269) (xy 116.763292 -50.1269)
		)
		(stroke
			(width 0)
			(type solid)
		)
		(fill yes)
		(layer "In11.Cu")
		(net "M_J_DQS_DP<6>")
	)
	(gr_poly
		(pts
			(xy 116.868702 -46.868588) (xy 116.824252 -46.868588) (xy 116.631212 -46.957488) (xy 116.631212 -47.186088)
			(xy 116.824252 -47.274988) (xy 116.868702 -47.274988)
		)
		(stroke
			(width 0)
			(type solid)
		)
		(fill yes)
		(layer "In11.Cu")
		(net "M_J_DQS_DP<15>")
	)
	(gr_poly
		(pts
			(xy 116.875814 -48.024796) (xy 116.81841 -47.841662) (xy 116.786914 -47.810166) (xy 116.504974 -48.092106)
			(xy 116.53647 -48.123602) (xy 116.719604 -48.181006)
		)
		(stroke
			(width 0)
			(type solid)
		)
		(fill yes)
		(layer "In11.Cu")
		(net "M_J_DQS_DN<15>")
	)
	(gr_poly
		(pts
			(xy 116.91239 -99.144582) (xy 116.934742 -99.105974) (xy 116.589302 -98.906838) (xy 116.567204 -98.945192)
			(xy 116.559076 -99.136962) (xy 116.750338 -99.247452)
		)
		(stroke
			(width 0)
			(type solid)
		)
		(fill yes)
		(layer "In11.Cu")
		(net "M_M_DQS_DP<15>")
	)
	(gr_poly
		(pts
			(xy 116.91239 -98.153982) (xy 116.934742 -98.115374) (xy 116.589302 -97.916238) (xy 116.567204 -97.954592)
			(xy 116.559076 -98.146362) (xy 116.750338 -98.256852)
		)
		(stroke
			(width 0)
			(type solid)
		)
		(fill yes)
		(layer "In11.Cu")
		(net "M_M_DQS_DN<6>")
	)
	(gr_poly
		(pts
			(xy 116.91239 -97.163382) (xy 116.934742 -97.124774) (xy 116.589302 -96.925638) (xy 116.567204 -96.963992)
			(xy 116.559076 -97.155762) (xy 116.750338 -97.266252)
		)
		(stroke
			(width 0)
			(type solid)
		)
		(fill yes)
		(layer "In11.Cu")
		(net "M_M_DQ<54>")
	)
	(gr_poly
		(pts
			(xy 116.91239 -96.172782) (xy 116.934742 -96.134174) (xy 116.589302 -95.935038) (xy 116.567204 -95.973392)
			(xy 116.559076 -96.165162) (xy 116.750338 -96.275652)
		)
		(stroke
			(width 0)
			(type solid)
		)
		(fill yes)
		(layer "In11.Cu")
		(net "M_M_DQ<50>")
	)
	(gr_poly
		(pts
			(xy 116.914168 -95.183452) (xy 116.93652 -95.145098) (xy 116.590826 -94.945708) (xy 116.568982 -94.984316)
			(xy 116.560854 -95.176086) (xy 116.752116 -95.286322)
		)
		(stroke
			(width 0)
			(type solid)
		)
		(fill yes)
		(layer "In11.Cu")
		(net "M_M_DQ<60>")
	)
	(gr_poly
		(pts
			(xy 117.01399 -106.031284) (xy 117.01399 -105.810304) (xy 116.84381 -105.721404) (xy 116.79936 -105.721404)
			(xy 116.79936 -106.120184) (xy 116.84381 -106.120184)
		)
		(stroke
			(width 0)
			(type solid)
		)
		(fill yes)
		(layer "In11.Cu")
		(net "M_M_DQ<49>")
	)
	(gr_poly
		(pts
			(xy 117.01399 -105.040684) (xy 117.01399 -104.819704) (xy 116.84381 -104.730804) (xy 116.79936 -104.730804)
			(xy 116.79936 -105.129584) (xy 116.84381 -105.129584)
		)
		(stroke
			(width 0)
			(type solid)
		)
		(fill yes)
		(layer "In11.Cu")
		(net "M_M_DQ<49>")
	)
	(gr_poly
		(pts
			(xy 117.01399 -104.050084) (xy 117.01399 -103.829104) (xy 116.84381 -103.740204) (xy 116.79936 -103.740204)
			(xy 116.79936 -104.138984) (xy 116.84381 -104.138984)
		)
		(stroke
			(width 0)
			(type solid)
		)
		(fill yes)
		(layer "In11.Cu")
		(net "M_M_DQ<49>")
	)
	(gr_poly
		(pts
			(xy 117.01399 -103.059484) (xy 117.01399 -102.838504) (xy 116.84381 -102.749604) (xy 116.79936 -102.749604)
			(xy 116.79936 -103.148384) (xy 116.84381 -103.148384)
		)
		(stroke
			(width 0)
			(type solid)
		)
		(fill yes)
		(layer "In11.Cu")
		(net "M_M_DQ<49>")
	)
	(gr_poly
		(pts
			(xy 117.01399 -102.068884) (xy 117.01399 -101.847904) (xy 116.84381 -101.759004) (xy 116.79936 -101.759004)
			(xy 116.79936 -102.157784) (xy 116.84381 -102.157784)
		)
		(stroke
			(width 0)
			(type solid)
		)
		(fill yes)
		(layer "In11.Cu")
		(net "M_M_DQ<49>")
	)
	(gr_poly
		(pts
			(xy 117.01399 -101.078284) (xy 117.01399 -100.857304) (xy 116.84381 -100.768404) (xy 116.79936 -100.768404)
			(xy 116.79936 -101.167184) (xy 116.84381 -101.167184)
		)
		(stroke
			(width 0)
			(type solid)
		)
		(fill yes)
		(layer "In11.Cu")
		(net "M_M_DQ<49>")
	)
	(gr_poly
		(pts
			(xy 117.01399 -100.087684) (xy 117.01399 -99.866704) (xy 116.84381 -99.777804) (xy 116.79936 -99.777804)
			(xy 116.79936 -100.176584) (xy 116.84381 -100.176584)
		)
		(stroke
			(width 0)
			(type solid)
		)
		(fill yes)
		(layer "In11.Cu")
		(net "M_M_DQ<49>")
	)
	(gr_poly
		(pts
			(xy 117.01399 -94.153228) (xy 117.01399 -93.932248) (xy 116.84381 -93.843348) (xy 116.79936 -93.843348)
			(xy 116.79936 -94.242128) (xy 116.84381 -94.242128)
		)
		(stroke
			(width 0)
			(type solid)
		)
		(fill yes)
		(layer "In11.Cu")
		(net "M_M_DQ<61>")
	)
	(gr_poly
		(pts
			(xy 117.01399 -93.156278) (xy 117.01399 -92.935298) (xy 116.84381 -92.846398) (xy 116.79936 -92.846398)
			(xy 116.79936 -93.245178) (xy 116.84381 -93.245178)
		)
		(stroke
			(width 0)
			(type solid)
		)
		(fill yes)
		(layer "In11.Cu")
		(net "M_M_DQ<61>")
	)
	(gr_poly
		(pts
			(xy 117.049804 -63.636144) (xy 117.005354 -63.636144) (xy 116.835174 -63.725044) (xy 116.835174 -63.946024)
			(xy 117.005354 -64.034924) (xy 117.049804 -64.034924)
		)
		(stroke
			(width 0)
			(type solid)
		)
		(fill yes)
		(layer "In11.Cu")
		(net "M_J_DQS_DP<6>")
	)
	(gr_poly
		(pts
			(xy 117.049804 -62.645544) (xy 117.005354 -62.645544) (xy 116.835174 -62.734444) (xy 116.835174 -62.955424)
			(xy 117.005354 -63.044324) (xy 117.049804 -63.044324)
		)
		(stroke
			(width 0)
			(type solid)
		)
		(fill yes)
		(layer "In11.Cu")
		(net "M_J_DQS_DP<6>")
	)
	(gr_poly
		(pts
			(xy 117.049804 -61.654944) (xy 117.005354 -61.654944) (xy 116.835174 -61.743844) (xy 116.835174 -61.964824)
			(xy 117.005354 -62.053724) (xy 117.049804 -62.053724)
		)
		(stroke
			(width 0)
			(type solid)
		)
		(fill yes)
		(layer "In11.Cu")
		(net "M_J_DQS_DP<6>")
	)
	(gr_poly
		(pts
			(xy 117.049804 -60.664344) (xy 117.005354 -60.664344) (xy 116.835174 -60.753244) (xy 116.835174 -60.974224)
			(xy 117.005354 -61.063124) (xy 117.049804 -61.063124)
		)
		(stroke
			(width 0)
			(type solid)
		)
		(fill yes)
		(layer "In11.Cu")
		(net "M_J_DQS_DP<6>")
	)
	(gr_poly
		(pts
			(xy 117.049804 -59.667394) (xy 117.005354 -59.667394) (xy 116.835174 -59.756294) (xy 116.835174 -59.977274)
			(xy 117.005354 -60.066174) (xy 117.049804 -60.066174)
		)
		(stroke
			(width 0)
			(type solid)
		)
		(fill yes)
		(layer "In11.Cu")
		(net "M_J_DQS_DP<6>")
	)
	(gr_poly
		(pts
			(xy 117.049804 -58.670698) (xy 117.005354 -58.670698) (xy 116.835174 -58.759598) (xy 116.835174 -58.980578)
			(xy 117.005354 -59.069478) (xy 117.049804 -59.069478)
		)
		(stroke
			(width 0)
			(type solid)
		)
		(fill yes)
		(layer "In11.Cu")
		(net "M_J_DQS_DP<6>")
	)
	(gr_poly
		(pts
			(xy 117.049804 -57.692544) (xy 117.005354 -57.692544) (xy 116.835174 -57.781444) (xy 116.835174 -58.002424)
			(xy 117.005354 -58.091324) (xy 117.049804 -58.091324)
		)
		(stroke
			(width 0)
			(type solid)
		)
		(fill yes)
		(layer "In11.Cu")
		(net "M_J_DQS_DP<6>")
	)
	(gr_poly
		(pts
			(xy 117.049804 -56.701944) (xy 117.005354 -56.701944) (xy 116.835174 -56.790844) (xy 116.835174 -57.011824)
			(xy 117.005354 -57.100724) (xy 117.049804 -57.100724)
		)
		(stroke
			(width 0)
			(type solid)
		)
		(fill yes)
		(layer "In11.Cu")
		(net "M_J_DQS_DP<6>")
	)
	(gr_poly
		(pts
			(xy 117.049804 -55.711344) (xy 117.005354 -55.711344) (xy 116.835174 -55.800244) (xy 116.835174 -56.021224)
			(xy 117.005354 -56.110124) (xy 117.049804 -56.110124)
		)
		(stroke
			(width 0)
			(type solid)
		)
		(fill yes)
		(layer "In11.Cu")
		(net "M_J_DQS_DP<6>")
	)
	(gr_poly
		(pts
			(xy 117.049804 -54.720744) (xy 117.005354 -54.720744) (xy 116.835174 -54.809644) (xy 116.835174 -55.030624)
			(xy 117.005354 -55.119524) (xy 117.049804 -55.119524)
		)
		(stroke
			(width 0)
			(type solid)
		)
		(fill yes)
		(layer "In11.Cu")
		(net "M_J_DQS_DP<6>")
	)
	(gr_poly
		(pts
			(xy 117.091206 -53.481478) (xy 117.046756 -53.481478) (xy 116.853716 -53.570378) (xy 116.853716 -53.798978)
			(xy 117.046756 -53.887878) (xy 117.091206 -53.887878)
		)
		(stroke
			(width 0)
			(type solid)
		)
		(fill yes)
		(layer "In11.Cu")
		(net "M_J_DQS_DP<6>")
	)
	(gr_poly
		(pts
			(xy 117.091206 -52.490878) (xy 117.046756 -52.490878) (xy 116.853716 -52.579778) (xy 116.853716 -52.808378)
			(xy 117.046756 -52.897278) (xy 117.091206 -52.897278)
		)
		(stroke
			(width 0)
			(type solid)
		)
		(fill yes)
		(layer "In11.Cu")
		(net "M_J_DQS_DP<6>")
	)
	(gr_poly
		(pts
			(xy 117.091206 -51.500278) (xy 117.046756 -51.500278) (xy 116.853716 -51.589178) (xy 116.853716 -51.817778)
			(xy 117.046756 -51.906678) (xy 117.091206 -51.906678)
		)
		(stroke
			(width 0)
			(type solid)
		)
		(fill yes)
		(layer "In11.Cu")
		(net "M_J_DQS_DP<6>")
	)
	(gr_poly
		(pts
			(xy 117.168422 -50.038) (xy 117.168422 -49.816766) (xy 116.998242 -49.727866) (xy 116.953792 -49.727866)
			(xy 116.953792 -50.1269) (xy 116.998242 -50.1269)
		)
		(stroke
			(width 0)
			(type solid)
		)
		(fill yes)
		(layer "In11.Cu")
		(net "M_J_DQS_DN<6>")
	)
	(gr_poly
		(pts
			(xy 117.296692 -47.236888) (xy 117.296692 -47.008288) (xy 117.103652 -46.919388) (xy 117.059202 -46.919388)
			(xy 117.059202 -47.325788) (xy 117.103652 -47.325788)
		)
		(stroke
			(width 0)
			(type solid)
		)
		(fill yes)
		(layer "In11.Cu")
		(net "M_J_DQS_DN<15>")
	)
	(gr_poly
		(pts
			(xy 117.334284 -104.730804) (xy 117.289834 -104.730804) (xy 117.119654 -104.819704) (xy 117.119654 -105.040684)
			(xy 117.289834 -105.129584) (xy 117.334284 -105.129584)
		)
		(stroke
			(width 0)
			(type solid)
		)
		(fill yes)
		(layer "In11.Cu")
		(net "M_M_DQS_DP<15>")
	)
	(gr_poly
		(pts
			(xy 117.334284 -103.740204) (xy 117.289834 -103.740204) (xy 117.119654 -103.829104) (xy 117.119654 -104.050084)
			(xy 117.289834 -104.138984) (xy 117.334284 -104.138984)
		)
		(stroke
			(width 0)
			(type solid)
		)
		(fill yes)
		(layer "In11.Cu")
		(net "M_M_DQS_DP<15>")
	)
	(gr_poly
		(pts
			(xy 117.334284 -102.749604) (xy 117.289834 -102.749604) (xy 117.119654 -102.838504) (xy 117.119654 -103.059484)
			(xy 117.289834 -103.148384) (xy 117.334284 -103.148384)
		)
		(stroke
			(width 0)
			(type solid)
		)
		(fill yes)
		(layer "In11.Cu")
		(net "M_M_DQS_DP<15>")
	)
	(gr_poly
		(pts
			(xy 117.334284 -101.76764) (xy 117.289834 -101.76764) (xy 117.119654 -101.85654) (xy 117.119654 -102.07752)
			(xy 117.289834 -102.16642) (xy 117.334284 -102.16642)
		)
		(stroke
			(width 0)
			(type solid)
		)
		(fill yes)
		(layer "In11.Cu")
		(net "M_M_DQS_DP<15>")
	)
	(gr_poly
		(pts
			(xy 117.334284 -100.783136) (xy 117.289834 -100.783136) (xy 117.119654 -100.872036) (xy 117.119654 -101.093016)
			(xy 117.289834 -101.181916) (xy 117.334284 -101.181916)
		)
		(stroke
			(width 0)
			(type solid)
		)
		(fill yes)
		(layer "In11.Cu")
		(net "M_M_DQS_DP<15>")
	)
	(gr_poly
		(pts
			(xy 117.334284 -99.79279) (xy 117.289834 -99.79279) (xy 117.119654 -99.88169) (xy 117.119654 -100.10267)
			(xy 117.289834 -100.19157) (xy 117.334284 -100.19157)
		)
		(stroke
			(width 0)
			(type solid)
		)
		(fill yes)
		(layer "In11.Cu")
		(net "M_M_DQS_DP<15>")
	)
	(gr_poly
		(pts
			(xy 117.334284 -93.836998) (xy 117.289834 -93.836998) (xy 117.119654 -93.925898) (xy 117.119654 -94.146878)
			(xy 117.289834 -94.235778) (xy 117.334284 -94.235778)
		)
		(stroke
			(width 0)
			(type solid)
		)
		(fill yes)
		(layer "In11.Cu")
		(net "M_M_DQ<56>")
	)
	(gr_poly
		(pts
			(xy 117.334284 -92.846398) (xy 117.289834 -92.846398) (xy 117.119654 -92.935298) (xy 117.119654 -93.156278)
			(xy 117.289834 -93.245178) (xy 117.334284 -93.245178)
		)
		(stroke
			(width 0)
			(type solid)
		)
		(fill yes)
		(layer "In11.Cu")
		(net "M_M_DQ<56>")
	)
	(gr_poly
		(pts
			(xy 117.334284 -91.855798) (xy 117.289834 -91.855798) (xy 117.119654 -91.944698) (xy 117.119654 -92.165678)
			(xy 117.289834 -92.254578) (xy 117.334284 -92.254578)
		)
		(stroke
			(width 0)
			(type solid)
		)
		(fill yes)
		(layer "In11.Cu")
		(net "M_M_DQ<56>")
	)
	(gr_poly
		(pts
			(xy 117.467888 -48.57877) (xy 117.436392 -48.547528) (xy 117.237002 -48.473868) (xy 117.075458 -48.635412)
			(xy 117.149118 -48.834802) (xy 117.18036 -48.866298)
		)
		(stroke
			(width 0)
			(type solid)
		)
		(fill yes)
		(layer "In11.Cu")
		(net "M_J_DQS_DP<6>")
	)
	(gr_poly
		(pts
			(xy 117.519196 -53.798978) (xy 117.519196 -53.570378) (xy 117.326156 -53.481478) (xy 117.281706 -53.481478)
			(xy 117.281706 -53.887878) (xy 117.326156 -53.887878)
		)
		(stroke
			(width 0)
			(type solid)
		)
		(fill yes)
		(layer "In11.Cu")
		(net "M_J_DQS_DN<6>")
	)
	(gr_poly
		(pts
			(xy 117.519196 -52.808378) (xy 117.519196 -52.579778) (xy 117.326156 -52.490878) (xy 117.281706 -52.490878)
			(xy 117.281706 -52.897278) (xy 117.326156 -52.897278)
		)
		(stroke
			(width 0)
			(type solid)
		)
		(fill yes)
		(layer "In11.Cu")
		(net "M_J_DQS_DN<6>")
	)
	(gr_poly
		(pts
			(xy 117.519196 -51.817778) (xy 117.519196 -51.589178) (xy 117.326156 -51.500278) (xy 117.281706 -51.500278)
			(xy 117.281706 -51.906678) (xy 117.326156 -51.906678)
		)
		(stroke
			(width 0)
			(type solid)
		)
		(fill yes)
		(layer "In11.Cu")
		(net "M_J_DQS_DN<6>")
	)
	(gr_poly
		(pts
			(xy 117.564662 -99.04476) (xy 117.572536 -98.85299) (xy 117.381274 -98.7425) (xy 117.219222 -98.845624)
			(xy 117.197124 -98.883724) (xy 117.542564 -99.083368)
		)
		(stroke
			(width 0)
			(type solid)
		)
		(fill yes)
		(layer "In11.Cu")
		(net "M_M_DQS_DN<15>")
	)
	(gr_poly
		(pts
			(xy 117.564916 -98.054414) (xy 117.573044 -97.862644) (xy 117.381782 -97.752154) (xy 117.21973 -97.855024)
			(xy 117.197378 -97.893378) (xy 117.542818 -98.093022)
		)
		(stroke
			(width 0)
			(type solid)
		)
		(fill yes)
		(layer "In11.Cu")
		(net "M_M_DQS_DP<6>")
	)
	(gr_poly
		(pts
			(xy 117.564916 -97.063814) (xy 117.573044 -96.872044) (xy 117.381782 -96.761554) (xy 117.21973 -96.864424)
			(xy 117.197378 -96.902778) (xy 117.542818 -97.102422)
		)
		(stroke
			(width 0)
			(type solid)
		)
		(fill yes)
		(layer "In11.Cu")
		(net "M_M_DQ<55>")
	)
	(gr_poly
		(pts
			(xy 117.564916 -96.073214) (xy 117.573044 -95.881444) (xy 117.381782 -95.770954) (xy 117.21973 -95.873824)
			(xy 117.197378 -95.912178) (xy 117.542818 -96.111822)
		)
		(stroke
			(width 0)
			(type solid)
		)
		(fill yes)
		(layer "In11.Cu")
		(net "M_M_DQ<51>")
	)
	(gr_poly
		(pts
			(xy 117.56644 -95.083376) (xy 117.574568 -94.891606) (xy 117.383306 -94.781116) (xy 117.221254 -94.883986)
			(xy 117.198902 -94.922594) (xy 117.544342 -95.12173)
		)
		(stroke
			(width 0)
			(type solid)
		)
		(fill yes)
		(layer "In11.Cu")
		(net "M_M_DQ<61>")
	)
	(gr_poly
		(pts
			(xy 117.587522 -64.446404) (xy 117.587776 -64.225424) (xy 117.417342 -64.136778) (xy 117.373146 -64.136778)
			(xy 117.372892 -64.535304) (xy 117.417342 -64.535304)
		)
		(stroke
			(width 0)
			(type solid)
		)
		(fill yes)
		(layer "In11.Cu")
		(net "M_J_DQS_DN<6>")
	)
	(gr_poly
		(pts
			(xy 117.58803 -63.438278) (xy 117.58803 -63.217298) (xy 117.41785 -63.128398) (xy 117.3734 -63.128398)
			(xy 117.3734 -63.527178) (xy 117.41785 -63.527178)
		)
		(stroke
			(width 0)
			(type solid)
		)
		(fill yes)
		(layer "In11.Cu")
		(net "M_J_DQS_DN<6>")
	)
	(gr_poly
		(pts
			(xy 117.58803 -62.447678) (xy 117.58803 -62.226698) (xy 117.41785 -62.137798) (xy 117.3734 -62.137798)
			(xy 117.3734 -62.536578) (xy 117.41785 -62.536578)
		)
		(stroke
			(width 0)
			(type solid)
		)
		(fill yes)
		(layer "In11.Cu")
		(net "M_J_DQS_DN<6>")
	)
	(gr_poly
		(pts
			(xy 117.58803 -61.457078) (xy 117.58803 -61.236098) (xy 117.41785 -61.147198) (xy 117.3734 -61.147198)
			(xy 117.3734 -61.545978) (xy 117.41785 -61.545978)
		)
		(stroke
			(width 0)
			(type solid)
		)
		(fill yes)
		(layer "In11.Cu")
		(net "M_J_DQS_DN<6>")
	)
	(gr_poly
		(pts
			(xy 117.58803 -60.466478) (xy 117.58803 -60.245498) (xy 117.41785 -60.156598) (xy 117.3734 -60.156598)
			(xy 117.3734 -60.555378) (xy 117.41785 -60.555378)
		)
		(stroke
			(width 0)
			(type solid)
		)
		(fill yes)
		(layer "In11.Cu")
		(net "M_J_DQS_DN<6>")
	)
	(gr_poly
		(pts
			(xy 117.58803 -59.488324) (xy 117.58803 -59.267344) (xy 117.41785 -59.178444) (xy 117.3734 -59.178444)
			(xy 117.3734 -59.577224) (xy 117.41785 -59.577224)
		)
		(stroke
			(width 0)
			(type solid)
		)
		(fill yes)
		(layer "In11.Cu")
		(net "M_J_DQS_DN<6>")
	)
	(gr_poly
		(pts
			(xy 117.58803 -58.491628) (xy 117.58803 -58.270648) (xy 117.41785 -58.181748) (xy 117.3734 -58.181748)
			(xy 117.3734 -58.580528) (xy 117.41785 -58.580528)
		)
		(stroke
			(width 0)
			(type solid)
		)
		(fill yes)
		(layer "In11.Cu")
		(net "M_J_DQS_DN<6>")
	)
	(gr_poly
		(pts
			(xy 117.58803 -57.494678) (xy 117.58803 -57.273698) (xy 117.41785 -57.184798) (xy 117.3734 -57.184798)
			(xy 117.3734 -57.583578) (xy 117.41785 -57.583578)
		)
		(stroke
			(width 0)
			(type solid)
		)
		(fill yes)
		(layer "In11.Cu")
		(net "M_J_DQS_DN<6>")
	)
	(gr_poly
		(pts
			(xy 117.58803 -56.504078) (xy 117.58803 -56.283098) (xy 117.41785 -56.194198) (xy 117.3734 -56.194198)
			(xy 117.3734 -56.592978) (xy 117.41785 -56.592978)
		)
		(stroke
			(width 0)
			(type solid)
		)
		(fill yes)
		(layer "In11.Cu")
		(net "M_J_DQS_DN<6>")
	)
	(gr_poly
		(pts
			(xy 117.58803 -55.513478) (xy 117.58803 -55.292498) (xy 117.41785 -55.203598) (xy 117.3734 -55.203598)
			(xy 117.3734 -55.602378) (xy 117.41785 -55.602378)
		)
		(stroke
			(width 0)
			(type solid)
		)
		(fill yes)
		(layer "In11.Cu")
		(net "M_J_DQS_DN<6>")
	)
	(gr_poly
		(pts
			(xy 117.707664 -48.944276) (xy 117.634004 -48.74514) (xy 117.602508 -48.713644) (xy 117.315234 -49.000918)
			(xy 117.34673 -49.032414) (xy 117.545866 -49.106074)
		)
		(stroke
			(width 0)
			(type solid)
		)
		(fill yes)
		(layer "In11.Cu")
		(net "M_J_DQS_DN<6>")
	)
	(gr_poly
		(pts
			(xy 117.77091 -94.687136) (xy 117.793262 -94.648782) (xy 117.447568 -94.449392) (xy 117.425724 -94.487746)
			(xy 117.417596 -94.679516) (xy 117.608858 -94.790006)
		)
		(stroke
			(width 0)
			(type solid)
		)
		(fill yes)
		(layer "In11.Cu")
		(net "M_M_DQ<56>")
	)
	(gr_poly
		(pts
			(xy 117.772434 -98.650298) (xy 117.794786 -98.61169) (xy 117.449346 -98.412554) (xy 117.427248 -98.450908)
			(xy 117.41912 -98.642678) (xy 117.610382 -98.753168)
		)
		(stroke
			(width 0)
			(type solid)
		)
		(fill yes)
		(layer "In11.Cu")
		(net "M_M_DQS_DN<6>")
	)
	(gr_poly
		(pts
			(xy 117.772434 -97.659698) (xy 117.794786 -97.62109) (xy 117.449346 -97.421954) (xy 117.427248 -97.460308)
			(xy 117.41912 -97.652078) (xy 117.610382 -97.762568)
		)
		(stroke
			(width 0)
			(type solid)
		)
		(fill yes)
		(layer "In11.Cu")
		(net "M_M_DQ<54>")
	)
	(gr_poly
		(pts
			(xy 117.772434 -96.669098) (xy 117.794786 -96.63049) (xy 117.449346 -96.431354) (xy 117.427248 -96.469708)
			(xy 117.41912 -96.661478) (xy 117.610382 -96.771968)
		)
		(stroke
			(width 0)
			(type solid)
		)
		(fill yes)
		(layer "In11.Cu")
		(net "M_M_DQ<50>")
	)
	(gr_poly
		(pts
			(xy 117.77472 -95.679768) (xy 117.797072 -95.641414) (xy 117.451632 -95.44177) (xy 117.429534 -95.480378)
			(xy 117.421406 -95.672148) (xy 117.612668 -95.782638)
		)
		(stroke
			(width 0)
			(type solid)
		)
		(fill yes)
		(layer "In11.Cu")
		(net "M_M_DQ<60>")
	)
	(gr_poly
		(pts
			(xy 117.858286 -53.73751) (xy 117.813836 -53.73751) (xy 117.620796 -53.82641) (xy 117.620796 -54.05501)
			(xy 117.813836 -54.14391) (xy 117.858286 -54.14391)
		)
		(stroke
			(width 0)
			(type solid)
		)
		(fill yes)
		(layer "In11.Cu")
		(net "M_J_DQ<54>")
	)
	(gr_poly
		(pts
			(xy 117.858286 -52.74691) (xy 117.813836 -52.74691) (xy 117.620796 -52.83581) (xy 117.620796 -53.06441)
			(xy 117.813836 -53.15331) (xy 117.858286 -53.15331)
		)
		(stroke
			(width 0)
			(type solid)
		)
		(fill yes)
		(layer "In11.Cu")
		(net "M_J_DQ<54>")
	)
	(gr_poly
		(pts
			(xy 117.858286 -51.75631) (xy 117.813836 -51.75631) (xy 117.620796 -51.84521) (xy 117.620796 -52.07381)
			(xy 117.813836 -52.16271) (xy 117.858286 -52.16271)
		)
		(stroke
			(width 0)
			(type solid)
		)
		(fill yes)
		(layer "In11.Cu")
		(net "M_J_DQ<54>")
	)
	(gr_poly
		(pts
			(xy 117.87251 -105.553764) (xy 117.87251 -105.332784) (xy 117.70233 -105.243884) (xy 117.65788 -105.243884)
			(xy 117.65788 -105.642664) (xy 117.70233 -105.642664)
		)
		(stroke
			(width 0)
			(type solid)
		)
		(fill yes)
		(layer "In11.Cu")
		(net "M_M_DQS_DN<15>")
	)
	(gr_poly
		(pts
			(xy 117.87251 -104.563164) (xy 117.87251 -104.342184) (xy 117.70233 -104.253284) (xy 117.65788 -104.253284)
			(xy 117.65788 -104.652064) (xy 117.70233 -104.652064)
		)
		(stroke
			(width 0)
			(type solid)
		)
		(fill yes)
		(layer "In11.Cu")
		(net "M_M_DQS_DN<15>")
	)
	(gr_poly
		(pts
			(xy 117.87251 -103.572564) (xy 117.87251 -103.351584) (xy 117.70233 -103.262684) (xy 117.65788 -103.262684)
			(xy 117.65788 -103.661464) (xy 117.70233 -103.661464)
		)
		(stroke
			(width 0)
			(type solid)
		)
		(fill yes)
		(layer "In11.Cu")
		(net "M_M_DQS_DN<15>")
	)
	(gr_poly
		(pts
			(xy 117.87251 -102.57917) (xy 117.87251 -102.35819) (xy 117.70233 -102.26929) (xy 117.65788 -102.26929)
			(xy 117.65788 -102.66807) (xy 117.70233 -102.66807)
		)
		(stroke
			(width 0)
			(type solid)
		)
		(fill yes)
		(layer "In11.Cu")
		(net "M_M_DQS_DN<15>")
	)
	(gr_poly
		(pts
			(xy 117.87251 -101.58222) (xy 117.87251 -101.36124) (xy 117.70233 -101.27234) (xy 117.65788 -101.27234)
			(xy 117.65788 -101.67112) (xy 117.70233 -101.67112)
		)
		(stroke
			(width 0)
			(type solid)
		)
		(fill yes)
		(layer "In11.Cu")
		(net "M_M_DQS_DN<15>")
	)
	(gr_poly
		(pts
			(xy 117.87251 -100.58527) (xy 117.87251 -100.36429) (xy 117.70233 -100.27539) (xy 117.65788 -100.27539)
			(xy 117.65788 -100.67417) (xy 117.70233 -100.67417)
		)
		(stroke
			(width 0)
			(type solid)
		)
		(fill yes)
		(layer "In11.Cu")
		(net "M_M_DQS_DN<15>")
	)
	(gr_poly
		(pts
			(xy 117.87251 -99.59467) (xy 117.87251 -99.37369) (xy 117.70233 -99.28479) (xy 117.65788 -99.28479)
			(xy 117.65788 -99.68357) (xy 117.70233 -99.68357)
		)
		(stroke
			(width 0)
			(type solid)
		)
		(fill yes)
		(layer "In11.Cu")
		(net "M_M_DQS_DN<15>")
	)
	(gr_poly
		(pts
			(xy 117.87251 -93.664024) (xy 117.87251 -93.443044) (xy 117.70233 -93.354144) (xy 117.65788 -93.354144)
			(xy 117.65788 -93.752924) (xy 117.70233 -93.752924)
		)
		(stroke
			(width 0)
			(type solid)
		)
		(fill yes)
		(layer "In11.Cu")
		(net "M_M_DQ<57>")
	)
	(gr_poly
		(pts
			(xy 117.908324 -60.169298) (xy 117.863874 -60.169298) (xy 117.693694 -60.258198) (xy 117.693694 -60.479178)
			(xy 117.863874 -60.568078) (xy 117.908324 -60.568078)
		)
		(stroke
			(width 0)
			(type solid)
		)
		(fill yes)
		(layer "In11.Cu")
		(net "M_J_DQ<54>")
	)
	(gr_poly
		(pts
			(xy 117.908324 -59.178698) (xy 117.863874 -59.178698) (xy 117.693694 -59.267598) (xy 117.693694 -59.488578)
			(xy 117.863874 -59.577478) (xy 117.908324 -59.577478)
		)
		(stroke
			(width 0)
			(type solid)
		)
		(fill yes)
		(layer "In11.Cu")
		(net "M_J_DQ<54>")
	)
	(gr_poly
		(pts
			(xy 117.908324 -58.188098) (xy 117.863874 -58.188098) (xy 117.693694 -58.276998) (xy 117.693694 -58.497978)
			(xy 117.863874 -58.586878) (xy 117.908324 -58.586878)
		)
		(stroke
			(width 0)
			(type solid)
		)
		(fill yes)
		(layer "In11.Cu")
		(net "M_J_DQ<54>")
	)
	(gr_poly
		(pts
			(xy 117.908324 -57.191148) (xy 117.863874 -57.191148) (xy 117.693694 -57.280048) (xy 117.693694 -57.501028)
			(xy 117.863874 -57.589928) (xy 117.908324 -57.589928)
		)
		(stroke
			(width 0)
			(type solid)
		)
		(fill yes)
		(layer "In11.Cu")
		(net "M_J_DQ<54>")
	)
	(gr_poly
		(pts
			(xy 117.908324 -56.20004) (xy 117.863874 -56.20004) (xy 117.693694 -56.28894) (xy 117.693694 -56.50992)
			(xy 117.863874 -56.59882) (xy 117.908324 -56.59882)
		)
		(stroke
			(width 0)
			(type solid)
		)
		(fill yes)
		(layer "In11.Cu")
		(net "M_J_DQ<54>")
	)
	(gr_poly
		(pts
			(xy 117.908324 -55.203598) (xy 117.863874 -55.203598) (xy 117.693694 -55.292498) (xy 117.693694 -55.513478)
			(xy 117.863874 -55.602378) (xy 117.908324 -55.602378)
		)
		(stroke
			(width 0)
			(type solid)
		)
		(fill yes)
		(layer "In11.Cu")
		(net "M_J_DQ<54>")
	)
	(gr_poly
		(pts
			(xy 117.908578 -62.150498) (xy 117.864128 -62.150498) (xy 117.693948 -62.239398) (xy 117.693948 -62.460378)
			(xy 117.864128 -62.549278) (xy 117.908578 -62.549278)
		)
		(stroke
			(width 0)
			(type solid)
		)
		(fill yes)
		(layer "In11.Cu")
		(net "M_J_DQ<54>")
	)
	(gr_poly
		(pts
			(xy 117.908578 -61.159898) (xy 117.864128 -61.159898) (xy 117.693948 -61.248798) (xy 117.693948 -61.469778)
			(xy 117.864128 -61.558678) (xy 117.908578 -61.558678)
		)
		(stroke
			(width 0)
			(type solid)
		)
		(fill yes)
		(layer "In11.Cu")
		(net "M_J_DQ<54>")
	)
	(gr_poly
		(pts
			(xy 118.144036 -50.357786) (xy 118.099586 -50.357786) (xy 117.906546 -50.446686) (xy 117.906546 -50.675286)
			(xy 118.099586 -50.764186) (xy 118.144036 -50.764186)
		)
		(stroke
			(width 0)
			(type solid)
		)
		(fill yes)
		(layer "In11.Cu")
		(net "M_J_DQ<54>")
	)
	(gr_poly
		(pts
			(xy 118.144036 -49.367186) (xy 118.099586 -49.367186) (xy 117.906546 -49.456086) (xy 117.906546 -49.684686)
			(xy 118.099586 -49.773586) (xy 118.144036 -49.773586)
		)
		(stroke
			(width 0)
			(type solid)
		)
		(fill yes)
		(layer "In11.Cu")
		(net "M_J_DQ<54>")
	)
	(gr_poly
		(pts
			(xy 118.192804 -105.241344) (xy 118.148354 -105.241344) (xy 117.978174 -105.330244) (xy 117.978174 -105.551224)
			(xy 118.148354 -105.640124) (xy 118.192804 -105.640124)
		)
		(stroke
			(width 0)
			(type solid)
		)
		(fill yes)
		(layer "In11.Cu")
		(net "M_M_DQS_DN<6>")
	)
	(gr_poly
		(pts
			(xy 118.192804 -104.250744) (xy 118.148354 -104.250744) (xy 117.978174 -104.339644) (xy 117.978174 -104.560624)
			(xy 118.148354 -104.649524) (xy 118.192804 -104.649524)
		)
		(stroke
			(width 0)
			(type solid)
		)
		(fill yes)
		(layer "In11.Cu")
		(net "M_M_DQS_DN<6>")
	)
	(gr_poly
		(pts
			(xy 118.192804 -103.260144) (xy 118.148354 -103.260144) (xy 117.978174 -103.349044) (xy 117.978174 -103.570024)
			(xy 118.148354 -103.658924) (xy 118.192804 -103.658924)
		)
		(stroke
			(width 0)
			(type solid)
		)
		(fill yes)
		(layer "In11.Cu")
		(net "M_M_DQS_DN<6>")
	)
	(gr_poly
		(pts
			(xy 118.192804 -102.263194) (xy 118.148354 -102.263194) (xy 117.978174 -102.352094) (xy 117.978174 -102.573074)
			(xy 118.148354 -102.661974) (xy 118.192804 -102.661974)
		)
		(stroke
			(width 0)
			(type solid)
		)
		(fill yes)
		(layer "In11.Cu")
		(net "M_M_DQS_DN<6>")
	)
	(gr_poly
		(pts
			(xy 118.192804 -101.26345) (xy 118.148354 -101.26345) (xy 117.978174 -101.35235) (xy 117.978174 -101.57333)
			(xy 118.148354 -101.66223) (xy 118.192804 -101.66223)
		)
		(stroke
			(width 0)
			(type solid)
		)
		(fill yes)
		(layer "In11.Cu")
		(net "M_M_DQS_DN<6>")
	)
	(gr_poly
		(pts
			(xy 118.192804 -93.354144) (xy 118.148354 -93.354144) (xy 117.978174 -93.443044) (xy 117.978174 -93.664024)
			(xy 118.148354 -93.752924) (xy 118.192804 -93.752924)
		)
		(stroke
			(width 0)
			(type solid)
		)
		(fill yes)
		(layer "In11.Cu")
		(net "M_M_DQS_DP<16>")
	)
	(gr_poly
		(pts
			(xy 118.192804 -92.363544) (xy 118.148354 -92.363544) (xy 117.978174 -92.452444) (xy 117.978174 -92.673424)
			(xy 118.148354 -92.762324) (xy 118.192804 -92.762324)
		)
		(stroke
			(width 0)
			(type solid)
		)
		(fill yes)
		(layer "In11.Cu")
		(net "M_M_DQS_DP<16>")
	)
	(gr_poly
		(pts
			(xy 118.192804 -91.372944) (xy 118.148354 -91.372944) (xy 117.978174 -91.461844) (xy 117.978174 -91.682824)
			(xy 118.148354 -91.771724) (xy 118.192804 -91.771724)
		)
		(stroke
			(width 0)
			(type solid)
		)
		(fill yes)
		(layer "In11.Cu")
		(net "M_M_DQS_DP<16>")
	)
	(gr_poly
		(pts
			(xy 118.192804 -90.382344) (xy 118.148354 -90.382344) (xy 117.978174 -90.471244) (xy 117.978174 -90.692224)
			(xy 118.148354 -90.781124) (xy 118.192804 -90.781124)
		)
		(stroke
			(width 0)
			(type solid)
		)
		(fill yes)
		(layer "In11.Cu")
		(net "M_M_DQS_DP<16>")
	)
	(gr_poly
		(pts
			(xy 118.193058 -100.275644) (xy 118.148608 -100.275644) (xy 117.978428 -100.364544) (xy 117.978428 -100.585524)
			(xy 118.148608 -100.674424) (xy 118.193058 -100.674424)
		)
		(stroke
			(width 0)
			(type solid)
		)
		(fill yes)
		(layer "In11.Cu")
		(net "M_M_DQS_DN<6>")
	)
	(gr_poly
		(pts
			(xy 118.193058 -99.291394) (xy 118.148608 -99.291394) (xy 117.978428 -99.380294) (xy 117.978428 -99.601274)
			(xy 118.148608 -99.690174) (xy 118.193058 -99.690174)
		)
		(stroke
			(width 0)
			(type solid)
		)
		(fill yes)
		(layer "In11.Cu")
		(net "M_M_DQS_DN<6>")
	)
	(gr_poly
		(pts
			(xy 118.239032 -63.946024) (xy 118.24843 -63.725298) (xy 118.08206 -63.629286) (xy 118.03761 -63.627254)
			(xy 118.020846 -64.02578) (xy 118.065296 -64.027558)
		)
		(stroke
			(width 0)
			(type solid)
		)
		(fill yes)
		(layer "In11.Cu")
		(net "M_J_DQ<55>")
	)
	(gr_poly
		(pts
			(xy 118.249192 -106.357166) (xy 118.204742 -106.357166) (xy 118.011702 -106.446066) (xy 118.011702 -106.674666)
			(xy 118.204742 -106.763566) (xy 118.249192 -106.763566)
		)
		(stroke
			(width 0)
			(type solid)
		)
		(fill yes)
		(layer "In11.Cu")
		(net "M_M_DQS_DN<6>")
	)
	(gr_poly
		(pts
			(xy 118.286276 -54.05501) (xy 118.286276 -53.82641) (xy 118.093236 -53.73751) (xy 118.048786 -53.73751)
			(xy 118.048786 -54.14391) (xy 118.093236 -54.14391)
		)
		(stroke
			(width 0)
			(type solid)
		)
		(fill yes)
		(layer "In11.Cu")
		(net "M_J_DQ<55>")
	)
	(gr_poly
		(pts
			(xy 118.286276 -53.06441) (xy 118.286276 -52.83581) (xy 118.093236 -52.74691) (xy 118.048786 -52.74691)
			(xy 118.048786 -53.15331) (xy 118.093236 -53.15331)
		)
		(stroke
			(width 0)
			(type solid)
		)
		(fill yes)
		(layer "In11.Cu")
		(net "M_J_DQ<55>")
	)
	(gr_poly
		(pts
			(xy 118.286276 -52.07381) (xy 118.286276 -51.84521) (xy 118.093236 -51.75631) (xy 118.048786 -51.75631)
			(xy 118.048786 -52.16271) (xy 118.093236 -52.16271)
		)
		(stroke
			(width 0)
			(type solid)
		)
		(fill yes)
		(layer "In11.Cu")
		(net "M_J_DQ<55>")
	)
	(gr_poly
		(pts
			(xy 118.419626 -98.547174) (xy 118.427754 -98.355404) (xy 118.236238 -98.245168) (xy 118.07444 -98.348038)
			(xy 118.051834 -98.386392) (xy 118.397528 -98.585782)
		)
		(stroke
			(width 0)
			(type solid)
		)
		(fill yes)
		(layer "In11.Cu")
		(net "M_M_DQS_DP<6>")
	)
	(gr_poly
		(pts
			(xy 118.42115 -95.576644) (xy 118.429278 -95.384874) (xy 118.238016 -95.274384) (xy 118.075964 -95.377254)
			(xy 118.053612 -95.415862) (xy 118.399052 -95.614998)
		)
		(stroke
			(width 0)
			(type solid)
		)
		(fill yes)
		(layer "In11.Cu")
		(net "M_M_DQ<61>")
	)
	(gr_poly
		(pts
			(xy 118.423436 -94.587314) (xy 118.431564 -94.395544) (xy 118.240302 -94.285054) (xy 118.07825 -94.387924)
			(xy 118.055898 -94.426278) (xy 118.401338 -94.625922)
		)
		(stroke
			(width 0)
			(type solid)
		)
		(fill yes)
		(layer "In11.Cu")
		(net "M_M_DQ<57>")
	)
	(gr_poly
		(pts
			(xy 118.42496 -97.56013) (xy 118.433088 -97.36836) (xy 118.241826 -97.25787) (xy 118.079774 -97.36074)
			(xy 118.057422 -97.399094) (xy 118.402862 -97.598738)
		)
		(stroke
			(width 0)
			(type solid)
		)
		(fill yes)
		(layer "In11.Cu")
		(net "M_M_DQ<55>")
	)
	(gr_poly
		(pts
			(xy 118.42496 -96.56953) (xy 118.433088 -96.37776) (xy 118.241826 -96.26727) (xy 118.079774 -96.37014)
			(xy 118.057422 -96.408494) (xy 118.402862 -96.608138)
		)
		(stroke
			(width 0)
			(type solid)
		)
		(fill yes)
		(layer "In11.Cu")
		(net "M_M_DQ<51>")
	)
	(gr_poly
		(pts
			(xy 118.44655 -62.949328) (xy 118.44655 -62.728348) (xy 118.27637 -62.639448) (xy 118.23192 -62.639448)
			(xy 118.23192 -63.038228) (xy 118.27637 -63.038228)
		)
		(stroke
			(width 0)
			(type solid)
		)
		(fill yes)
		(layer "In11.Cu")
		(net "M_J_DQ<55>")
	)
	(gr_poly
		(pts
			(xy 118.44655 -61.958728) (xy 118.44655 -61.737748) (xy 118.27637 -61.648848) (xy 118.23192 -61.648848)
			(xy 118.23192 -62.047628) (xy 118.27637 -62.047628)
		)
		(stroke
			(width 0)
			(type solid)
		)
		(fill yes)
		(layer "In11.Cu")
		(net "M_J_DQ<55>")
	)
	(gr_poly
		(pts
			(xy 118.44655 -60.962032) (xy 118.44655 -60.741052) (xy 118.27637 -60.652152) (xy 118.23192 -60.652152)
			(xy 118.23192 -61.050932) (xy 118.27637 -61.050932)
		)
		(stroke
			(width 0)
			(type solid)
		)
		(fill yes)
		(layer "In11.Cu")
		(net "M_J_DQ<55>")
	)
	(gr_poly
		(pts
			(xy 118.44655 -59.971432) (xy 118.44655 -59.750452) (xy 118.27637 -59.661552) (xy 118.23192 -59.661552)
			(xy 118.23192 -60.060332) (xy 118.27637 -60.060332)
		)
		(stroke
			(width 0)
			(type solid)
		)
		(fill yes)
		(layer "In11.Cu")
		(net "M_J_DQ<55>")
	)
	(gr_poly
		(pts
			(xy 118.44655 -58.980832) (xy 118.44655 -58.759852) (xy 118.27637 -58.670952) (xy 118.23192 -58.670952)
			(xy 118.23192 -59.069732) (xy 118.27637 -59.069732)
		)
		(stroke
			(width 0)
			(type solid)
		)
		(fill yes)
		(layer "In11.Cu")
		(net "M_J_DQ<55>")
	)
	(gr_poly
		(pts
			(xy 118.44655 -57.990232) (xy 118.44655 -57.769252) (xy 118.27637 -57.680352) (xy 118.23192 -57.680352)
			(xy 118.23192 -58.079132) (xy 118.27637 -58.079132)
		)
		(stroke
			(width 0)
			(type solid)
		)
		(fill yes)
		(layer "In11.Cu")
		(net "M_J_DQ<55>")
	)
	(gr_poly
		(pts
			(xy 118.44655 -57.005474) (xy 118.44655 -56.784494) (xy 118.27637 -56.695594) (xy 118.23192 -56.695594)
			(xy 118.23192 -57.094374) (xy 118.27637 -57.094374)
		)
		(stroke
			(width 0)
			(type solid)
		)
		(fill yes)
		(layer "In11.Cu")
		(net "M_J_DQ<55>")
	)
	(gr_poly
		(pts
			(xy 118.44655 -56.014366) (xy 118.44655 -55.793386) (xy 118.27637 -55.704486) (xy 118.23192 -55.704486)
			(xy 118.23192 -56.103266) (xy 118.27637 -56.103266)
		)
		(stroke
			(width 0)
			(type solid)
		)
		(fill yes)
		(layer "In11.Cu")
		(net "M_J_DQ<55>")
	)
	(gr_poly
		(pts
			(xy 118.572026 -50.675286) (xy 118.572026 -50.446686) (xy 118.378986 -50.357786) (xy 118.334536 -50.357786)
			(xy 118.334536 -50.764186) (xy 118.378986 -50.764186)
		)
		(stroke
			(width 0)
			(type solid)
		)
		(fill yes)
		(layer "In11.Cu")
		(net "M_J_DQ<55>")
	)
	(gr_poly
		(pts
			(xy 118.572026 -49.684686) (xy 118.572026 -49.456086) (xy 118.378986 -49.367186) (xy 118.334536 -49.367186)
			(xy 118.334536 -49.773586) (xy 118.378986 -49.773586)
		)
		(stroke
			(width 0)
			(type solid)
		)
		(fill yes)
		(layer "In11.Cu")
		(net "M_J_DQ<55>")
	)
	(gr_poly
		(pts
			(xy 118.62943 -98.153982) (xy 118.651782 -98.115374) (xy 118.306342 -97.916238) (xy 118.284244 -97.954592)
			(xy 118.276116 -98.146362) (xy 118.467378 -98.256852)
		)
		(stroke
			(width 0)
			(type solid)
		)
		(fill yes)
		(layer "In11.Cu")
		(net "M_M_DQ<54>")
	)
	(gr_poly
		(pts
			(xy 118.62943 -97.163382) (xy 118.651782 -97.124774) (xy 118.306342 -96.925638) (xy 118.284244 -96.963992)
			(xy 118.276116 -97.155762) (xy 118.467378 -97.266252)
		)
		(stroke
			(width 0)
			(type solid)
		)
		(fill yes)
		(layer "In11.Cu")
		(net "M_M_DQ<50>")
	)
	(gr_poly
		(pts
			(xy 118.62943 -96.172782) (xy 118.651782 -96.134174) (xy 118.306342 -95.935038) (xy 118.284244 -95.973392)
			(xy 118.276116 -96.165162) (xy 118.467378 -96.275652)
		)
		(stroke
			(width 0)
			(type solid)
		)
		(fill yes)
		(layer "In11.Cu")
		(net "M_M_DQ<60>")
	)
	(gr_poly
		(pts
			(xy 118.630954 -95.183198) (xy 118.653306 -95.14459) (xy 118.307866 -94.945454) (xy 118.285768 -94.983808)
			(xy 118.27764 -95.175578) (xy 118.468902 -95.286068)
		)
		(stroke
			(width 0)
			(type solid)
		)
		(fill yes)
		(layer "In11.Cu")
		(net "M_M_DQ<56>")
	)
	(gr_poly
		(pts
			(xy 118.638828 -94.196916) (xy 118.660926 -94.158816) (xy 118.315486 -93.959172) (xy 118.293388 -93.99778)
			(xy 118.285514 -94.18955) (xy 118.476776 -94.30004)
		)
		(stroke
			(width 0)
			(type solid)
		)
		(fill yes)
		(layer "In11.Cu")
		(net "M_M_DQS_DP<16>")
	)
	(gr_poly
		(pts
			(xy 118.677182 -106.674666) (xy 118.677182 -106.446066) (xy 118.484142 -106.357166) (xy 118.439692 -106.357166)
			(xy 118.439692 -106.763566) (xy 118.484142 -106.763566)
		)
		(stroke
			(width 0)
			(type solid)
		)
		(fill yes)
		(layer "In11.Cu")
		(net "M_M_DQS_DP<6>")
	)
	(gr_poly
		(pts
			(xy 118.682262 -48.451516) (xy 118.650766 -48.420274) (xy 118.451376 -48.346614) (xy 118.289578 -48.508158)
			(xy 118.363238 -48.707548) (xy 118.394734 -48.739044)
		)
		(stroke
			(width 0)
			(type solid)
		)
		(fill yes)
		(layer "In11.Cu")
		(net "M_J_DQ<54>")
	)
	(gr_poly
		(pts
			(xy 118.73103 -106.034078) (xy 118.73103 -105.813098) (xy 118.56085 -105.724198) (xy 118.5164 -105.724198)
			(xy 118.5164 -106.122978) (xy 118.56085 -106.122978)
		)
		(stroke
			(width 0)
			(type solid)
		)
		(fill yes)
		(layer "In11.Cu")
		(net "M_M_DQS_DP<6>")
	)
	(gr_poly
		(pts
			(xy 118.73103 -105.043478) (xy 118.73103 -104.822498) (xy 118.56085 -104.733598) (xy 118.5164 -104.733598)
			(xy 118.5164 -105.132378) (xy 118.56085 -105.132378)
		)
		(stroke
			(width 0)
			(type solid)
		)
		(fill yes)
		(layer "In11.Cu")
		(net "M_M_DQS_DP<6>")
	)
	(gr_poly
		(pts
			(xy 118.73103 -104.052878) (xy 118.73103 -103.831898) (xy 118.56085 -103.742998) (xy 118.5164 -103.742998)
			(xy 118.5164 -104.141778) (xy 118.56085 -104.141778)
		)
		(stroke
			(width 0)
			(type solid)
		)
		(fill yes)
		(layer "In11.Cu")
		(net "M_M_DQS_DP<6>")
	)
	(gr_poly
		(pts
			(xy 118.73103 -103.062278) (xy 118.73103 -102.841298) (xy 118.56085 -102.752398) (xy 118.5164 -102.752398)
			(xy 118.5164 -103.151178) (xy 118.56085 -103.151178)
		)
		(stroke
			(width 0)
			(type solid)
		)
		(fill yes)
		(layer "In11.Cu")
		(net "M_M_DQS_DP<6>")
	)
	(gr_poly
		(pts
			(xy 118.73103 -102.08387) (xy 118.73103 -101.86289) (xy 118.56085 -101.77399) (xy 118.5164 -101.77399)
			(xy 118.5164 -102.17277) (xy 118.56085 -102.17277)
		)
		(stroke
			(width 0)
			(type solid)
		)
		(fill yes)
		(layer "In11.Cu")
		(net "M_M_DQS_DP<6>")
	)
	(gr_poly
		(pts
			(xy 118.73103 -101.093016) (xy 118.73103 -100.872036) (xy 118.56085 -100.783136) (xy 118.5164 -100.783136)
			(xy 118.5164 -101.181916) (xy 118.56085 -101.181916)
		)
		(stroke
			(width 0)
			(type solid)
		)
		(fill yes)
		(layer "In11.Cu")
		(net "M_M_DQS_DP<6>")
	)
	(gr_poly
		(pts
			(xy 118.73103 -100.10267) (xy 118.73103 -99.88169) (xy 118.56085 -99.79279) (xy 118.5164 -99.79279)
			(xy 118.5164 -100.19157) (xy 118.56085 -100.19157)
		)
		(stroke
			(width 0)
			(type solid)
		)
		(fill yes)
		(layer "In11.Cu")
		(net "M_M_DQS_DP<6>")
	)
	(gr_poly
		(pts
			(xy 118.73103 -99.11207) (xy 118.73103 -98.89109) (xy 118.56085 -98.80219) (xy 118.5164 -98.80219)
			(xy 118.5164 -99.20097) (xy 118.56085 -99.20097)
		)
		(stroke
			(width 0)
			(type solid)
		)
		(fill yes)
		(layer "In11.Cu")
		(net "M_M_DQS_DP<6>")
	)
	(gr_poly
		(pts
			(xy 118.73103 -93.156278) (xy 118.73103 -92.935298) (xy 118.56085 -92.846398) (xy 118.5164 -92.846398)
			(xy 118.5164 -93.245178) (xy 118.56085 -93.245178)
		)
		(stroke
			(width 0)
			(type solid)
		)
		(fill yes)
		(layer "In11.Cu")
		(net "M_M_DQS_DN<16>")
	)
	(gr_poly
		(pts
			(xy 118.73103 -92.165678) (xy 118.73103 -91.944698) (xy 118.56085 -91.855798) (xy 118.5164 -91.855798)
			(xy 118.5164 -92.254578) (xy 118.56085 -92.254578)
		)
		(stroke
			(width 0)
			(type solid)
		)
		(fill yes)
		(layer "In11.Cu")
		(net "M_M_DQS_DN<16>")
	)
	(gr_poly
		(pts
			(xy 118.73103 -91.175078) (xy 118.73103 -90.954098) (xy 118.56085 -90.865198) (xy 118.5164 -90.865198)
			(xy 118.5164 -91.263978) (xy 118.56085 -91.263978)
		)
		(stroke
			(width 0)
			(type solid)
		)
		(fill yes)
		(layer "In11.Cu")
		(net "M_M_DQS_DN<16>")
	)
	(gr_poly
		(pts
			(xy 118.766844 -62.645544) (xy 118.722394 -62.645544) (xy 118.552214 -62.734444) (xy 118.552214 -62.955424)
			(xy 118.722394 -63.044324) (xy 118.766844 -63.044324)
		)
		(stroke
			(width 0)
			(type solid)
		)
		(fill yes)
		(layer "In11.Cu")
		(net "M_J_DQ<50>")
	)
	(gr_poly
		(pts
			(xy 118.766844 -61.654944) (xy 118.722394 -61.654944) (xy 118.552214 -61.743844) (xy 118.552214 -61.964824)
			(xy 118.722394 -62.053724) (xy 118.766844 -62.053724)
		)
		(stroke
			(width 0)
			(type solid)
		)
		(fill yes)
		(layer "In11.Cu")
		(net "M_J_DQ<50>")
	)
	(gr_poly
		(pts
			(xy 118.766844 -60.664344) (xy 118.722394 -60.664344) (xy 118.552214 -60.753244) (xy 118.552214 -60.974224)
			(xy 118.722394 -61.063124) (xy 118.766844 -61.063124)
		)
		(stroke
			(width 0)
			(type solid)
		)
		(fill yes)
		(layer "In11.Cu")
		(net "M_J_DQ<50>")
	)
	(gr_poly
		(pts
			(xy 118.766844 -59.667394) (xy 118.722394 -59.667394) (xy 118.552214 -59.756294) (xy 118.552214 -59.977274)
			(xy 118.722394 -60.066174) (xy 118.766844 -60.066174)
		)
		(stroke
			(width 0)
			(type solid)
		)
		(fill yes)
		(layer "In11.Cu")
		(net "M_J_DQ<50>")
	)
	(gr_poly
		(pts
			(xy 118.766844 -58.670698) (xy 118.722394 -58.670698) (xy 118.552214 -58.759598) (xy 118.552214 -58.980578)
			(xy 118.722394 -59.069478) (xy 118.766844 -59.069478)
		)
		(stroke
			(width 0)
			(type solid)
		)
		(fill yes)
		(layer "In11.Cu")
		(net "M_J_DQ<50>")
	)
	(gr_poly
		(pts
			(xy 118.766844 -57.692544) (xy 118.722394 -57.692544) (xy 118.552214 -57.781444) (xy 118.552214 -58.002424)
			(xy 118.722394 -58.091324) (xy 118.766844 -58.091324)
		)
		(stroke
			(width 0)
			(type solid)
		)
		(fill yes)
		(layer "In11.Cu")
		(net "M_J_DQ<50>")
	)
	(gr_poly
		(pts
			(xy 118.766844 -56.701944) (xy 118.722394 -56.701944) (xy 118.552214 -56.790844) (xy 118.552214 -57.011824)
			(xy 118.722394 -57.100724) (xy 118.766844 -57.100724)
		)
		(stroke
			(width 0)
			(type solid)
		)
		(fill yes)
		(layer "In11.Cu")
		(net "M_J_DQ<50>")
	)
	(gr_poly
		(pts
			(xy 118.766844 -55.711344) (xy 118.722394 -55.711344) (xy 118.552214 -55.800244) (xy 118.552214 -56.021224)
			(xy 118.722394 -56.110124) (xy 118.766844 -56.110124)
		)
		(stroke
			(width 0)
			(type solid)
		)
		(fill yes)
		(layer "In11.Cu")
		(net "M_J_DQ<50>")
	)
	(gr_poly
		(pts
			(xy 118.767352 -54.209696) (xy 118.722902 -54.209696) (xy 118.529862 -54.298596) (xy 118.529862 -54.527196)
			(xy 118.722902 -54.616096) (xy 118.767352 -54.616096)
		)
		(stroke
			(width 0)
			(type solid)
		)
		(fill yes)
		(layer "In11.Cu")
		(net "M_J_DQ<50>")
	)
	(gr_poly
		(pts
			(xy 118.767352 -53.219096) (xy 118.722902 -53.219096) (xy 118.529862 -53.307996) (xy 118.529862 -53.536596)
			(xy 118.722902 -53.625496) (xy 118.767352 -53.625496)
		)
		(stroke
			(width 0)
			(type solid)
		)
		(fill yes)
		(layer "In11.Cu")
		(net "M_J_DQ<50>")
	)
	(gr_poly
		(pts
			(xy 118.9101 -48.82896) (xy 118.83644 -48.62957) (xy 118.805198 -48.598074) (xy 118.51767 -48.885602)
			(xy 118.549166 -48.917098) (xy 118.748556 -48.990504)
		)
		(stroke
			(width 0)
			(type solid)
		)
		(fill yes)
		(layer "In11.Cu")
		(net "M_J_DQ<55>")
	)
	(gr_poly
		(pts
			(xy 118.91264 -51.773582) (xy 118.86819 -51.773582) (xy 118.67515 -51.862482) (xy 118.67515 -52.091082)
			(xy 118.86819 -52.179982) (xy 118.91264 -52.179982)
		)
		(stroke
			(width 0)
			(type solid)
		)
		(fill yes)
		(layer "In11.Cu")
		(net "M_J_DQ<50>")
	)
	(gr_poly
		(pts
			(xy 118.91264 -50.859182) (xy 118.86819 -50.859182) (xy 118.67515 -50.948082) (xy 118.67515 -51.176682)
			(xy 118.86819 -51.265582) (xy 118.91264 -51.265582)
		)
		(stroke
			(width 0)
			(type solid)
		)
		(fill yes)
		(layer "In11.Cu")
		(net "M_J_DQ<50>")
	)
	(gr_poly
		(pts
			(xy 118.91264 -49.868582) (xy 118.86819 -49.868582) (xy 118.67515 -49.957482) (xy 118.67515 -50.186082)
			(xy 118.86819 -50.274982) (xy 118.91264 -50.274982)
		)
		(stroke
			(width 0)
			(type solid)
		)
		(fill yes)
		(layer "In11.Cu")
		(net "M_J_DQ<50>")
	)
	(gr_poly
		(pts
			(xy 119.051324 -105.724198) (xy 119.006874 -105.724198) (xy 118.836694 -105.813098) (xy 118.836694 -106.034078)
			(xy 119.006874 -106.122978) (xy 119.051324 -106.122978)
		)
		(stroke
			(width 0)
			(type solid)
		)
		(fill yes)
		(layer "In11.Cu")
		(net "M_M_DQ<54>")
	)
	(gr_poly
		(pts
			(xy 119.051324 -104.733598) (xy 119.006874 -104.733598) (xy 118.836694 -104.822498) (xy 118.836694 -105.043478)
			(xy 119.006874 -105.132378) (xy 119.051324 -105.132378)
		)
		(stroke
			(width 0)
			(type solid)
		)
		(fill yes)
		(layer "In11.Cu")
		(net "M_M_DQ<54>")
	)
	(gr_poly
		(pts
			(xy 119.051324 -103.742998) (xy 119.006874 -103.742998) (xy 118.836694 -103.831898) (xy 118.836694 -104.052878)
			(xy 119.006874 -104.141778) (xy 119.051324 -104.141778)
		)
		(stroke
			(width 0)
			(type solid)
		)
		(fill yes)
		(layer "In11.Cu")
		(net "M_M_DQ<54>")
	)
	(gr_poly
		(pts
			(xy 119.051324 -102.752398) (xy 119.006874 -102.752398) (xy 118.836694 -102.841298) (xy 118.836694 -103.062278)
			(xy 119.006874 -103.151178) (xy 119.051324 -103.151178)
		)
		(stroke
			(width 0)
			(type solid)
		)
		(fill yes)
		(layer "In11.Cu")
		(net "M_M_DQ<54>")
	)
	(gr_poly
		(pts
			(xy 119.051324 -101.761798) (xy 119.006874 -101.761798) (xy 118.836694 -101.850698) (xy 118.836694 -102.071678)
			(xy 119.006874 -102.160578) (xy 119.051324 -102.160578)
		)
		(stroke
			(width 0)
			(type solid)
		)
		(fill yes)
		(layer "In11.Cu")
		(net "M_M_DQ<54>")
	)
	(gr_poly
		(pts
			(xy 119.051324 -100.771198) (xy 119.006874 -100.771198) (xy 118.836694 -100.860098) (xy 118.836694 -101.081078)
			(xy 119.006874 -101.169978) (xy 119.051324 -101.169978)
		)
		(stroke
			(width 0)
			(type solid)
		)
		(fill yes)
		(layer "In11.Cu")
		(net "M_M_DQ<54>")
	)
	(gr_poly
		(pts
			(xy 119.051324 -99.780598) (xy 119.006874 -99.780598) (xy 118.836694 -99.869498) (xy 118.836694 -100.090478)
			(xy 119.006874 -100.179378) (xy 119.051324 -100.179378)
		)
		(stroke
			(width 0)
			(type solid)
		)
		(fill yes)
		(layer "In11.Cu")
		(net "M_M_DQ<54>")
	)
	(gr_poly
		(pts
			(xy 119.051324 -98.789998) (xy 119.006874 -98.789998) (xy 118.836694 -98.878898) (xy 118.836694 -99.099878)
			(xy 119.006874 -99.188778) (xy 119.051324 -99.188778)
		)
		(stroke
			(width 0)
			(type solid)
		)
		(fill yes)
		(layer "In11.Cu")
		(net "M_M_DQ<54>")
	)
	(gr_poly
		(pts
			(xy 119.195342 -54.527196) (xy 119.195342 -54.298596) (xy 119.002302 -54.209696) (xy 118.957852 -54.209696)
			(xy 118.957852 -54.616096) (xy 119.002302 -54.616096)
		)
		(stroke
			(width 0)
			(type solid)
		)
		(fill yes)
		(layer "In11.Cu")
		(net "M_J_DQ<51>")
	)
	(gr_poly
		(pts
			(xy 119.195342 -53.536596) (xy 119.195342 -53.307996) (xy 119.002302 -53.219096) (xy 118.957852 -53.219096)
			(xy 118.957852 -53.625496) (xy 119.002302 -53.625496)
		)
		(stroke
			(width 0)
			(type solid)
		)
		(fill yes)
		(layer "In11.Cu")
		(net "M_J_DQ<51>")
	)
	(gr_poly
		(pts
			(xy 119.242078 -90.866468) (xy 119.197628 -90.866468) (xy 119.027448 -90.955368) (xy 119.027448 -91.176348)
			(xy 119.197628 -91.265248) (xy 119.242078 -91.265248)
		)
		(stroke
			(width 0)
			(type solid)
		)
		(fill yes)
		(layer "In11.Cu")
		(net "M_M_DQ<62>")
	)
	(gr_poly
		(pts
			(xy 119.27967 -94.090744) (xy 119.287798 -93.898974) (xy 119.096536 -93.788484) (xy 118.934484 -93.891354)
			(xy 118.912132 -93.929962) (xy 119.257572 -94.129098)
		)
		(stroke
			(width 0)
			(type solid)
		)
		(fill yes)
		(layer "In11.Cu")
		(net "M_M_DQS_DN<16>")
	)
	(gr_poly
		(pts
			(xy 119.281702 -98.053906) (xy 119.28983 -97.862136) (xy 119.098568 -97.7519) (xy 118.936516 -97.85477)
			(xy 118.914164 -97.893124) (xy 119.259858 -98.092514)
		)
		(stroke
			(width 0)
			(type solid)
		)
		(fill yes)
		(layer "In11.Cu")
		(net "M_M_DQ<55>")
	)
	(gr_poly
		(pts
			(xy 119.281956 -97.063814) (xy 119.290084 -96.872044) (xy 119.098822 -96.761554) (xy 118.93677 -96.864424)
			(xy 118.914418 -96.902778) (xy 119.259858 -97.102422)
		)
		(stroke
			(width 0)
			(type solid)
		)
		(fill yes)
		(layer "In11.Cu")
		(net "M_M_DQ<51>")
	)
	(gr_poly
		(pts
			(xy 119.281956 -96.073214) (xy 119.290084 -95.881444) (xy 119.098822 -95.770954) (xy 118.93677 -95.873824)
			(xy 118.914418 -95.912178) (xy 119.259858 -96.111822)
		)
		(stroke
			(width 0)
			(type solid)
		)
		(fill yes)
		(layer "In11.Cu")
		(net "M_M_DQ<61>")
	)
	(gr_poly
		(pts
			(xy 119.28348 -95.083376) (xy 119.291608 -94.891606) (xy 119.100346 -94.781116) (xy 118.938294 -94.883986)
			(xy 118.915942 -94.922594) (xy 119.261382 -95.12173)
		)
		(stroke
			(width 0)
			(type solid)
		)
		(fill yes)
		(layer "In11.Cu")
		(net "M_M_DQ<57>")
	)
	(gr_poly
		(pts
			(xy 119.30507 -63.438278) (xy 119.30507 -63.217298) (xy 119.13489 -63.128398) (xy 119.09044 -63.128398)
			(xy 119.09044 -63.527178) (xy 119.13489 -63.527178)
		)
		(stroke
			(width 0)
			(type solid)
		)
		(fill yes)
		(layer "In11.Cu")
		(net "M_J_DQ<51>")
	)
	(gr_poly
		(pts
			(xy 119.30507 -62.447678) (xy 119.30507 -62.226698) (xy 119.13489 -62.137798) (xy 119.09044 -62.137798)
			(xy 119.09044 -62.536578) (xy 119.13489 -62.536578)
		)
		(stroke
			(width 0)
			(type solid)
		)
		(fill yes)
		(layer "In11.Cu")
		(net "M_J_DQ<51>")
	)
	(gr_poly
		(pts
			(xy 119.30507 -61.457078) (xy 119.30507 -61.236098) (xy 119.13489 -61.147198) (xy 119.09044 -61.147198)
			(xy 119.09044 -61.545978) (xy 119.13489 -61.545978)
		)
		(stroke
			(width 0)
			(type solid)
		)
		(fill yes)
		(layer "In11.Cu")
		(net "M_J_DQ<51>")
	)
	(gr_poly
		(pts
			(xy 119.30507 -60.466478) (xy 119.30507 -60.245498) (xy 119.13489 -60.156598) (xy 119.09044 -60.156598)
			(xy 119.09044 -60.555378) (xy 119.13489 -60.555378)
		)
		(stroke
			(width 0)
			(type solid)
		)
		(fill yes)
		(layer "In11.Cu")
		(net "M_J_DQ<51>")
	)
	(gr_poly
		(pts
			(xy 119.30507 -59.488324) (xy 119.30507 -59.267344) (xy 119.13489 -59.178444) (xy 119.09044 -59.178444)
			(xy 119.09044 -59.577224) (xy 119.13489 -59.577224)
		)
		(stroke
			(width 0)
			(type solid)
		)
		(fill yes)
		(layer "In11.Cu")
		(net "M_J_DQ<51>")
	)
	(gr_poly
		(pts
			(xy 119.30507 -58.491628) (xy 119.30507 -58.270648) (xy 119.13489 -58.181748) (xy 119.09044 -58.181748)
			(xy 119.09044 -58.580528) (xy 119.13489 -58.580528)
		)
		(stroke
			(width 0)
			(type solid)
		)
		(fill yes)
		(layer "In11.Cu")
		(net "M_J_DQ<51>")
	)
	(gr_poly
		(pts
			(xy 119.30507 -57.494678) (xy 119.30507 -57.273698) (xy 119.13489 -57.184798) (xy 119.09044 -57.184798)
			(xy 119.09044 -57.583578) (xy 119.13489 -57.583578)
		)
		(stroke
			(width 0)
			(type solid)
		)
		(fill yes)
		(layer "In11.Cu")
		(net "M_J_DQ<51>")
	)
	(gr_poly
		(pts
			(xy 119.30507 -56.504078) (xy 119.30507 -56.283098) (xy 119.13489 -56.194198) (xy 119.09044 -56.194198)
			(xy 119.09044 -56.592978) (xy 119.13489 -56.592978)
		)
		(stroke
			(width 0)
			(type solid)
		)
		(fill yes)
		(layer "In11.Cu")
		(net "M_J_DQ<51>")
	)
	(gr_poly
		(pts
			(xy 119.30507 -55.513478) (xy 119.30507 -55.292498) (xy 119.13489 -55.203598) (xy 119.09044 -55.203598)
			(xy 119.09044 -55.602378) (xy 119.13489 -55.602378)
		)
		(stroke
			(width 0)
			(type solid)
		)
		(fill yes)
		(layer "In11.Cu")
		(net "M_J_DQ<51>")
	)
	(gr_poly
		(pts
			(xy 119.34063 -52.167282) (xy 119.34063 -51.938682) (xy 119.14759 -51.849782) (xy 119.10314 -51.849782)
			(xy 119.10314 -52.256182) (xy 119.14759 -52.256182)
		)
		(stroke
			(width 0)
			(type solid)
		)
		(fill yes)
		(layer "In11.Cu")
		(net "M_J_DQ<51>")
	)
	(gr_poly
		(pts
			(xy 119.34063 -51.176682) (xy 119.34063 -50.948082) (xy 119.14759 -50.859182) (xy 119.10314 -50.859182)
			(xy 119.10314 -51.265582) (xy 119.14759 -51.265582)
		)
		(stroke
			(width 0)
			(type solid)
		)
		(fill yes)
		(layer "In11.Cu")
		(net "M_J_DQ<51>")
	)
	(gr_poly
		(pts
			(xy 119.34063 -50.186082) (xy 119.34063 -49.957482) (xy 119.14759 -49.868582) (xy 119.10314 -49.868582)
			(xy 119.10314 -50.274982) (xy 119.14759 -50.274982)
		)
		(stroke
			(width 0)
			(type solid)
		)
		(fill yes)
		(layer "In11.Cu")
		(net "M_J_DQ<51>")
	)
	(gr_poly
		(pts
			(xy 119.48795 -94.687136) (xy 119.510302 -94.648782) (xy 119.164862 -94.449138) (xy 119.142764 -94.487746)
			(xy 119.134636 -94.679516) (xy 119.325898 -94.790006)
		)
		(stroke
			(width 0)
			(type solid)
		)
		(fill yes)
		(layer "In11.Cu")
		(net "M_M_DQS_DP<16>")
	)
	(gr_poly
		(pts
			(xy 119.489474 -97.659698) (xy 119.511826 -97.62109) (xy 119.166386 -97.421954) (xy 119.144288 -97.460308)
			(xy 119.13616 -97.652078) (xy 119.327422 -97.762568)
		)
		(stroke
			(width 0)
			(type solid)
		)
		(fill yes)
		(layer "In11.Cu")
		(net "M_M_DQ<50>")
	)
	(gr_poly
		(pts
			(xy 119.489474 -96.669098) (xy 119.511826 -96.63049) (xy 119.166386 -96.431354) (xy 119.144288 -96.469708)
			(xy 119.13616 -96.661478) (xy 119.327422 -96.771968)
		)
		(stroke
			(width 0)
			(type solid)
		)
		(fill yes)
		(layer "In11.Cu")
		(net "M_M_DQ<60>")
	)
	(gr_poly
		(pts
			(xy 119.49176 -95.679768) (xy 119.514112 -95.641414) (xy 119.168672 -95.44177) (xy 119.146574 -95.480378)
			(xy 119.138446 -95.672148) (xy 119.329708 -95.782638)
		)
		(stroke
			(width 0)
			(type solid)
		)
		(fill yes)
		(layer "In11.Cu")
		(net "M_M_DQ<56>")
	)
	(gr_poly
		(pts
			(xy 119.49176 -93.698568) (xy 119.514112 -93.660214) (xy 119.168672 -93.46057) (xy 119.146574 -93.499178)
			(xy 119.138446 -93.690948) (xy 119.329708 -93.801438)
		)
		(stroke
			(width 0)
			(type solid)
		)
		(fill yes)
		(layer "In11.Cu")
		(net "M_M_DQS_DN<7>")
	)
	(gr_poly
		(pts
			(xy 119.58955 -105.551224) (xy 119.58955 -105.330244) (xy 119.41937 -105.241344) (xy 119.37492 -105.241344)
			(xy 119.37492 -105.640124) (xy 119.41937 -105.640124)
		)
		(stroke
			(width 0)
			(type solid)
		)
		(fill yes)
		(layer "In11.Cu")
		(net "M_M_DQ<55>")
	)
	(gr_poly
		(pts
			(xy 119.58955 -104.560624) (xy 119.58955 -104.339644) (xy 119.41937 -104.250744) (xy 119.37492 -104.250744)
			(xy 119.37492 -104.649524) (xy 119.41937 -104.649524)
		)
		(stroke
			(width 0)
			(type solid)
		)
		(fill yes)
		(layer "In11.Cu")
		(net "M_M_DQ<55>")
	)
	(gr_poly
		(pts
			(xy 119.58955 -103.570024) (xy 119.58955 -103.349044) (xy 119.41937 -103.260144) (xy 119.37492 -103.260144)
			(xy 119.37492 -103.658924) (xy 119.41937 -103.658924)
		)
		(stroke
			(width 0)
			(type solid)
		)
		(fill yes)
		(layer "In11.Cu")
		(net "M_M_DQ<55>")
	)
	(gr_poly
		(pts
			(xy 119.58955 -102.579424) (xy 119.58955 -102.358444) (xy 119.41937 -102.269544) (xy 119.37492 -102.269544)
			(xy 119.37492 -102.668324) (xy 119.41937 -102.668324)
		)
		(stroke
			(width 0)
			(type solid)
		)
		(fill yes)
		(layer "In11.Cu")
		(net "M_M_DQ<55>")
	)
	(gr_poly
		(pts
			(xy 119.58955 -101.588824) (xy 119.58955 -101.367844) (xy 119.41937 -101.278944) (xy 119.37492 -101.278944)
			(xy 119.37492 -101.677724) (xy 119.41937 -101.677724)
		)
		(stroke
			(width 0)
			(type solid)
		)
		(fill yes)
		(layer "In11.Cu")
		(net "M_M_DQ<55>")
	)
	(gr_poly
		(pts
			(xy 119.58955 -100.598224) (xy 119.58955 -100.377244) (xy 119.41937 -100.288344) (xy 119.37492 -100.288344)
			(xy 119.37492 -100.687124) (xy 119.41937 -100.687124)
		)
		(stroke
			(width 0)
			(type solid)
		)
		(fill yes)
		(layer "In11.Cu")
		(net "M_M_DQ<55>")
	)
	(gr_poly
		(pts
			(xy 119.58955 -99.607624) (xy 119.58955 -99.386644) (xy 119.41937 -99.297744) (xy 119.37492 -99.297744)
			(xy 119.37492 -99.696524) (xy 119.41937 -99.696524)
		)
		(stroke
			(width 0)
			(type solid)
		)
		(fill yes)
		(layer "In11.Cu")
		(net "M_M_DQ<55>")
	)
	(gr_poly
		(pts
			(xy 119.58955 -98.617024) (xy 119.58955 -98.396044) (xy 119.41937 -98.307144) (xy 119.37492 -98.307144)
			(xy 119.37492 -98.705924) (xy 119.41937 -98.705924)
		)
		(stroke
			(width 0)
			(type solid)
		)
		(fill yes)
		(layer "In11.Cu")
		(net "M_M_DQ<55>")
	)
	(gr_poly
		(pts
			(xy 119.58955 -91.682824) (xy 119.58955 -91.461844) (xy 119.41937 -91.372944) (xy 119.37492 -91.372944)
			(xy 119.37492 -91.771724) (xy 119.41937 -91.771724)
		)
		(stroke
			(width 0)
			(type solid)
		)
		(fill yes)
		(layer "In11.Cu")
		(net "M_M_DQ<62>")
	)
	(gr_poly
		(pts
			(xy 119.62511 -62.144148) (xy 119.58066 -62.144148) (xy 119.41048 -62.233048) (xy 119.41048 -62.454028)
			(xy 119.58066 -62.542928) (xy 119.62511 -62.542928)
		)
		(stroke
			(width 0)
			(type solid)
		)
		(fill yes)
		(layer "In11.Cu")
		(net "M_J_DQ<60>")
	)
	(gr_poly
		(pts
			(xy 119.62511 -61.153548) (xy 119.58066 -61.153548) (xy 119.41048 -61.242448) (xy 119.41048 -61.463428)
			(xy 119.58066 -61.552328) (xy 119.62511 -61.552328)
		)
		(stroke
			(width 0)
			(type solid)
		)
		(fill yes)
		(layer "In11.Cu")
		(net "M_J_DQ<60>")
	)
	(gr_poly
		(pts
			(xy 119.62511 -60.153804) (xy 119.58066 -60.153804) (xy 119.41048 -60.242704) (xy 119.41048 -60.463684)
			(xy 119.58066 -60.552584) (xy 119.62511 -60.552584)
		)
		(stroke
			(width 0)
			(type solid)
		)
		(fill yes)
		(layer "In11.Cu")
		(net "M_J_DQ<60>")
	)
	(gr_poly
		(pts
			(xy 119.62511 -59.178444) (xy 119.58066 -59.178444) (xy 119.41048 -59.267344) (xy 119.41048 -59.488324)
			(xy 119.58066 -59.577224) (xy 119.62511 -59.577224)
		)
		(stroke
			(width 0)
			(type solid)
		)
		(fill yes)
		(layer "In11.Cu")
		(net "M_J_DQ<60>")
	)
	(gr_poly
		(pts
			(xy 119.62511 -58.175398) (xy 119.58066 -58.175398) (xy 119.41048 -58.264298) (xy 119.41048 -58.485278)
			(xy 119.58066 -58.574178) (xy 119.62511 -58.574178)
		)
		(stroke
			(width 0)
			(type solid)
		)
		(fill yes)
		(layer "In11.Cu")
		(net "M_J_DQ<60>")
	)
	(gr_poly
		(pts
			(xy 119.62511 -57.182004) (xy 119.58066 -57.182004) (xy 119.41048 -57.270904) (xy 119.41048 -57.491884)
			(xy 119.58066 -57.580784) (xy 119.62511 -57.580784)
		)
		(stroke
			(width 0)
			(type solid)
		)
		(fill yes)
		(layer "In11.Cu")
		(net "M_J_DQ<60>")
	)
	(gr_poly
		(pts
			(xy 119.62511 -56.191404) (xy 119.58066 -56.191404) (xy 119.41048 -56.280304) (xy 119.41048 -56.501284)
			(xy 119.58066 -56.590184) (xy 119.62511 -56.590184)
		)
		(stroke
			(width 0)
			(type solid)
		)
		(fill yes)
		(layer "In11.Cu")
		(net "M_J_DQ<60>")
	)
	(gr_poly
		(pts
			(xy 119.62511 -55.200804) (xy 119.58066 -55.200804) (xy 119.41048 -55.289704) (xy 119.41048 -55.510684)
			(xy 119.58066 -55.599584) (xy 119.62511 -55.599584)
		)
		(stroke
			(width 0)
			(type solid)
		)
		(fill yes)
		(layer "In11.Cu")
		(net "M_J_DQ<60>")
	)
	(gr_poly
		(pts
			(xy 119.62511 -54.208426) (xy 119.58066 -54.208426) (xy 119.41048 -54.297326) (xy 119.41048 -54.518306)
			(xy 119.58066 -54.607206) (xy 119.62511 -54.607206)
		)
		(stroke
			(width 0)
			(type solid)
		)
		(fill yes)
		(layer "In11.Cu")
		(net "M_J_DQ<60>")
	)
	(gr_poly
		(pts
			(xy 119.711724 -48.50765) (xy 119.680228 -48.476408) (xy 119.480838 -48.402748) (xy 119.319294 -48.564292)
			(xy 119.392954 -48.763682) (xy 119.424196 -48.795178)
		)
		(stroke
			(width 0)
			(type solid)
		)
		(fill yes)
		(layer "In11.Cu")
		(net "M_J_DQ<50>")
	)
	(gr_poly
		(pts
			(xy 119.757952 -53.274722) (xy 119.713502 -53.274722) (xy 119.543322 -53.363622) (xy 119.543322 -53.584602)
			(xy 119.713502 -53.673502) (xy 119.757952 -53.673502)
		)
		(stroke
			(width 0)
			(type solid)
		)
		(fill yes)
		(layer "In11.Cu")
		(net "M_J_DQ<60>")
	)
	(gr_poly
		(pts
			(xy 119.80926 -51.556158) (xy 119.76481 -51.556158) (xy 119.57177 -51.645058) (xy 119.57177 -51.873658)
			(xy 119.76481 -51.962558) (xy 119.80926 -51.962558)
		)
		(stroke
			(width 0)
			(type solid)
		)
		(fill yes)
		(layer "In11.Cu")
		(net "M_J_DQ<60>")
	)
	(gr_poly
		(pts
			(xy 119.909844 -105.241344) (xy 119.865394 -105.241344) (xy 119.695214 -105.330244) (xy 119.695214 -105.551224)
			(xy 119.865394 -105.640124) (xy 119.909844 -105.640124)
		)
		(stroke
			(width 0)
			(type solid)
		)
		(fill yes)
		(layer "In11.Cu")
		(net "M_M_DQ<50>")
	)
	(gr_poly
		(pts
			(xy 119.909844 -104.250744) (xy 119.865394 -104.250744) (xy 119.695214 -104.339644) (xy 119.695214 -104.560624)
			(xy 119.865394 -104.649524) (xy 119.909844 -104.649524)
		)
		(stroke
			(width 0)
			(type solid)
		)
		(fill yes)
		(layer "In11.Cu")
		(net "M_M_DQ<50>")
	)
	(gr_poly
		(pts
			(xy 119.909844 -103.260144) (xy 119.865394 -103.260144) (xy 119.695214 -103.349044) (xy 119.695214 -103.570024)
			(xy 119.865394 -103.658924) (xy 119.909844 -103.658924)
		)
		(stroke
			(width 0)
			(type solid)
		)
		(fill yes)
		(layer "In11.Cu")
		(net "M_M_DQ<50>")
	)
	(gr_poly
		(pts
			(xy 119.909844 -102.269544) (xy 119.865394 -102.269544) (xy 119.695214 -102.358444) (xy 119.695214 -102.579424)
			(xy 119.865394 -102.668324) (xy 119.909844 -102.668324)
		)
		(stroke
			(width 0)
			(type solid)
		)
		(fill yes)
		(layer "In11.Cu")
		(net "M_M_DQ<50>")
	)
	(gr_poly
		(pts
			(xy 119.909844 -101.278944) (xy 119.865394 -101.278944) (xy 119.695214 -101.367844) (xy 119.695214 -101.588824)
			(xy 119.865394 -101.677724) (xy 119.909844 -101.677724)
		)
		(stroke
			(width 0)
			(type solid)
		)
		(fill yes)
		(layer "In11.Cu")
		(net "M_M_DQ<50>")
	)
	(gr_poly
		(pts
			(xy 119.909844 -100.288344) (xy 119.865394 -100.288344) (xy 119.695214 -100.377244) (xy 119.695214 -100.598224)
			(xy 119.865394 -100.687124) (xy 119.909844 -100.687124)
		)
		(stroke
			(width 0)
			(type solid)
		)
		(fill yes)
		(layer "In11.Cu")
		(net "M_M_DQ<50>")
	)
	(gr_poly
		(pts
			(xy 119.909844 -99.297744) (xy 119.865394 -99.297744) (xy 119.695214 -99.386644) (xy 119.695214 -99.607624)
			(xy 119.865394 -99.696524) (xy 119.909844 -99.696524)
		)
		(stroke
			(width 0)
			(type solid)
		)
		(fill yes)
		(layer "In11.Cu")
		(net "M_M_DQ<50>")
	)
	(gr_poly
		(pts
			(xy 119.909844 -98.307144) (xy 119.865394 -98.307144) (xy 119.695214 -98.396044) (xy 119.695214 -98.617024)
			(xy 119.865394 -98.705924) (xy 119.909844 -98.705924)
		)
		(stroke
			(width 0)
			(type solid)
		)
		(fill yes)
		(layer "In11.Cu")
		(net "M_M_DQ<50>")
	)
	(gr_poly
		(pts
			(xy 119.909844 -91.35745) (xy 119.865394 -91.35745) (xy 119.695214 -91.44635) (xy 119.695214 -91.667076)
			(xy 119.865394 -91.755976) (xy 119.910098 -91.755976)
		)
		(stroke
			(width 0)
			(type solid)
		)
		(fill yes)
		(layer "In11.Cu")
		(net "M_M_DQ<58>")
	)
	(gr_poly
		(pts
			(xy 119.9515 -48.873156) (xy 119.87784 -48.67402) (xy 119.846344 -48.642524) (xy 119.55907 -48.929798)
			(xy 119.590566 -48.961294) (xy 119.789702 -49.034954)
		)
		(stroke
			(width 0)
			(type solid)
		)
		(fill yes)
		(layer "In11.Cu")
		(net "M_J_DQ<51>")
	)
	(gr_poly
		(pts
			(xy 120.136666 -97.556574) (xy 120.144794 -97.364804) (xy 119.953278 -97.254568) (xy 119.79148 -97.357438)
			(xy 119.768874 -97.395792) (xy 120.114568 -97.595182)
		)
		(stroke
			(width 0)
			(type solid)
		)
		(fill yes)
		(layer "In11.Cu")
		(net "M_M_DQ<51>")
	)
	(gr_poly
		(pts
			(xy 120.13819 -95.576644) (xy 120.146318 -95.384874) (xy 119.955056 -95.274384) (xy 119.793004 -95.377254)
			(xy 119.770652 -95.415862) (xy 120.116092 -95.614998)
		)
		(stroke
			(width 0)
			(type solid)
		)
		(fill yes)
		(layer "In11.Cu")
		(net "M_M_DQ<57>")
	)
	(gr_poly
		(pts
			(xy 120.140476 -94.587314) (xy 120.148604 -94.395544) (xy 119.957342 -94.285054) (xy 119.79529 -94.387924)
			(xy 119.772938 -94.426278) (xy 120.118378 -94.625922)
		)
		(stroke
			(width 0)
			(type solid)
		)
		(fill yes)
		(layer "In11.Cu")
		(net "M_M_DQS_DN<16>")
	)
	(gr_poly
		(pts
			(xy 120.142 -96.56953) (xy 120.150128 -96.37776) (xy 119.958866 -96.26727) (xy 119.796814 -96.37014)
			(xy 119.774462 -96.408494) (xy 120.119902 -96.608138)
		)
		(stroke
			(width 0)
			(type solid)
		)
		(fill yes)
		(layer "In11.Cu")
		(net "M_M_DQ<61>")
	)
	(gr_poly
		(pts
			(xy 120.142 -93.59773) (xy 120.150128 -93.40596) (xy 119.958866 -93.29547) (xy 119.796814 -93.39834)
			(xy 119.774462 -93.436694) (xy 120.119902 -93.636338)
		)
		(stroke
			(width 0)
			(type solid)
		)
		(fill yes)
		(layer "In11.Cu")
		(net "M_M_DQS_DP<7>")
	)
	(gr_poly
		(pts
			(xy 120.16359 -61.958728) (xy 120.16359 -61.737748) (xy 119.99341 -61.648848) (xy 119.94896 -61.648848)
			(xy 119.94896 -62.047628) (xy 119.99341 -62.047628)
		)
		(stroke
			(width 0)
			(type solid)
		)
		(fill yes)
		(layer "In11.Cu")
		(net "M_J_DQ<61>")
	)
	(gr_poly
		(pts
			(xy 120.16359 -60.977018) (xy 120.16359 -60.756038) (xy 119.99341 -60.667138) (xy 119.94896 -60.667138)
			(xy 119.94896 -61.065918) (xy 119.99341 -61.065918)
		)
		(stroke
			(width 0)
			(type solid)
		)
		(fill yes)
		(layer "In11.Cu")
		(net "M_J_DQ<61>")
	)
	(gr_poly
		(pts
			(xy 120.16359 -59.983624) (xy 120.16359 -59.762644) (xy 119.99341 -59.673744) (xy 119.94896 -59.673744)
			(xy 119.94896 -60.072524) (xy 119.99341 -60.072524)
		)
		(stroke
			(width 0)
			(type solid)
		)
		(fill yes)
		(layer "In11.Cu")
		(net "M_J_DQ<61>")
	)
	(gr_poly
		(pts
			(xy 120.16359 -58.980578) (xy 120.16359 -58.759598) (xy 119.99341 -58.670698) (xy 119.94896 -58.670698)
			(xy 119.94896 -59.069478) (xy 119.99341 -59.069478)
		)
		(stroke
			(width 0)
			(type solid)
		)
		(fill yes)
		(layer "In11.Cu")
		(net "M_J_DQ<61>")
	)
	(gr_poly
		(pts
			(xy 120.16359 -58.005218) (xy 120.16359 -57.784238) (xy 119.99341 -57.695338) (xy 119.94896 -57.695338)
			(xy 119.94896 -58.094118) (xy 119.99341 -58.094118)
		)
		(stroke
			(width 0)
			(type solid)
		)
		(fill yes)
		(layer "In11.Cu")
		(net "M_J_DQ<61>")
	)
	(gr_poly
		(pts
			(xy 120.16359 -57.014618) (xy 120.16359 -56.793638) (xy 119.99341 -56.704738) (xy 119.94896 -56.704738)
			(xy 119.94896 -57.103518) (xy 119.99341 -57.103518)
		)
		(stroke
			(width 0)
			(type solid)
		)
		(fill yes)
		(layer "In11.Cu")
		(net "M_J_DQ<61>")
	)
	(gr_poly
		(pts
			(xy 120.16359 -56.024018) (xy 120.16359 -55.803038) (xy 119.99341 -55.714138) (xy 119.94896 -55.714138)
			(xy 119.94896 -56.112918) (xy 119.99341 -56.112918)
		)
		(stroke
			(width 0)
			(type solid)
		)
		(fill yes)
		(layer "In11.Cu")
		(net "M_J_DQ<61>")
	)
	(gr_poly
		(pts
			(xy 120.16359 -55.033418) (xy 120.16359 -54.812438) (xy 119.99341 -54.723538) (xy 119.94896 -54.723538)
			(xy 119.94896 -55.122318) (xy 119.99341 -55.122318)
		)
		(stroke
			(width 0)
			(type solid)
		)
		(fill yes)
		(layer "In11.Cu")
		(net "M_J_DQ<61>")
	)
	(gr_poly
		(pts
			(xy 120.163844 -53.689504) (xy 120.163844 -53.468524) (xy 119.993664 -53.379624) (xy 119.949214 -53.379624)
			(xy 119.949214 -53.778404) (xy 119.993664 -53.778404)
		)
		(stroke
			(width 0)
			(type solid)
		)
		(fill yes)
		(layer "In11.Cu")
		(net "M_J_DQ<61>")
	)
	(gr_poly
		(pts
			(xy 120.23725 -51.873658) (xy 120.23725 -51.645058) (xy 120.04421 -51.556158) (xy 119.99976 -51.556158)
			(xy 119.99976 -51.962558) (xy 120.04421 -51.962558)
		)
		(stroke
			(width 0)
			(type solid)
		)
		(fill yes)
		(layer "In11.Cu")
		(net "M_J_DQ<61>")
	)
	(gr_poly
		(pts
			(xy 120.311926 -50.080164) (xy 120.280684 -50.048668) (xy 120.081294 -49.975008) (xy 119.919496 -50.136552)
			(xy 119.993156 -50.335942) (xy 120.024652 -50.367438)
		)
		(stroke
			(width 0)
			(type solid)
		)
		(fill yes)
		(layer "In11.Cu")
		(net "M_J_DQ<60>")
	)
	(gr_poly
		(pts
			(xy 120.34647 -97.163382) (xy 120.368822 -97.124774) (xy 120.023382 -96.925638) (xy 120.001284 -96.963992)
			(xy 119.993156 -97.155762) (xy 120.184418 -97.266252)
		)
		(stroke
			(width 0)
			(type solid)
		)
		(fill yes)
		(layer "In11.Cu")
		(net "M_M_DQ<60>")
	)
	(gr_poly
		(pts
			(xy 120.34647 -96.172782) (xy 120.368822 -96.134174) (xy 120.023382 -95.935038) (xy 120.001284 -95.973392)
			(xy 119.993156 -96.165162) (xy 120.184418 -96.275652)
		)
		(stroke
			(width 0)
			(type solid)
		)
		(fill yes)
		(layer "In11.Cu")
		(net "M_M_DQ<56>")
	)
	(gr_poly
		(pts
			(xy 120.34647 -93.200982) (xy 120.368822 -93.162374) (xy 120.023382 -92.963238) (xy 120.001284 -93.001592)
			(xy 119.993156 -93.193362) (xy 120.184418 -93.303852)
		)
		(stroke
			(width 0)
			(type solid)
		)
		(fill yes)
		(layer "In11.Cu")
		(net "M_M_DQ<62>")
	)
	(gr_poly
		(pts
			(xy 120.34774 -92.211398) (xy 120.370092 -92.17279) (xy 120.024652 -91.973654) (xy 120.002554 -92.012008)
			(xy 119.994426 -92.203778) (xy 120.185688 -92.314268)
		)
		(stroke
			(width 0)
			(type solid)
		)
		(fill yes)
		(layer "In11.Cu")
		(net "M_M_DQ<58>")
	)
	(gr_poly
		(pts
			(xy 120.347994 -95.183198) (xy 120.370346 -95.14459) (xy 120.024906 -94.945454) (xy 120.002808 -94.983808)
			(xy 119.99468 -95.175578) (xy 120.185942 -95.286068)
		)
		(stroke
			(width 0)
			(type solid)
		)
		(fill yes)
		(layer "In11.Cu")
		(net "M_M_DQS_DP<16>")
	)
	(gr_poly
		(pts
			(xy 120.35028 -94.193868) (xy 120.372632 -94.155514) (xy 120.027192 -93.95587) (xy 120.005094 -93.994478)
			(xy 119.996966 -94.186248) (xy 120.188228 -94.296738)
		)
		(stroke
			(width 0)
			(type solid)
		)
		(fill yes)
		(layer "In11.Cu")
		(net "M_M_DQS_DN<7>")
	)
	(gr_poly
		(pts
			(xy 120.44807 -105.043478) (xy 120.44807 -104.822498) (xy 120.27789 -104.733598) (xy 120.23344 -104.733598)
			(xy 120.23344 -105.132378) (xy 120.27789 -105.132378)
		)
		(stroke
			(width 0)
			(type solid)
		)
		(fill yes)
		(layer "In11.Cu")
		(net "M_M_DQ<51>")
	)
	(gr_poly
		(pts
			(xy 120.44807 -104.052878) (xy 120.44807 -103.831898) (xy 120.27789 -103.742998) (xy 120.23344 -103.742998)
			(xy 120.23344 -104.141778) (xy 120.27789 -104.141778)
		)
		(stroke
			(width 0)
			(type solid)
		)
		(fill yes)
		(layer "In11.Cu")
		(net "M_M_DQ<51>")
	)
	(gr_poly
		(pts
			(xy 120.44807 -103.062278) (xy 120.44807 -102.841298) (xy 120.27789 -102.752398) (xy 120.23344 -102.752398)
			(xy 120.23344 -103.151178) (xy 120.27789 -103.151178)
		)
		(stroke
			(width 0)
			(type solid)
		)
		(fill yes)
		(layer "In11.Cu")
		(net "M_M_DQ<51>")
	)
	(gr_poly
		(pts
			(xy 120.44807 -102.071678) (xy 120.44807 -101.850698) (xy 120.27789 -101.761798) (xy 120.23344 -101.761798)
			(xy 120.23344 -102.160578) (xy 120.27789 -102.160578)
		)
		(stroke
			(width 0)
			(type solid)
		)
		(fill yes)
		(layer "In11.Cu")
		(net "M_M_DQ<51>")
	)
	(gr_poly
		(pts
			(xy 120.44807 -101.081078) (xy 120.44807 -100.860098) (xy 120.27789 -100.771198) (xy 120.23344 -100.771198)
			(xy 120.23344 -101.169978) (xy 120.27789 -101.169978)
		)
		(stroke
			(width 0)
			(type solid)
		)
		(fill yes)
		(layer "In11.Cu")
		(net "M_M_DQ<51>")
	)
	(gr_poly
		(pts
			(xy 120.44807 -100.090478) (xy 120.44807 -99.869498) (xy 120.27789 -99.780598) (xy 120.23344 -99.780598)
			(xy 120.23344 -100.179378) (xy 120.27789 -100.179378)
		)
		(stroke
			(width 0)
			(type solid)
		)
		(fill yes)
		(layer "In11.Cu")
		(net "M_M_DQ<51>")
	)
	(gr_poly
		(pts
			(xy 120.44807 -99.099878) (xy 120.44807 -98.878898) (xy 120.27789 -98.789998) (xy 120.23344 -98.789998)
			(xy 120.23344 -99.188778) (xy 120.27789 -99.188778)
		)
		(stroke
			(width 0)
			(type solid)
		)
		(fill yes)
		(layer "In11.Cu")
		(net "M_M_DQ<51>")
	)
	(gr_poly
		(pts
			(xy 120.44807 -98.109278) (xy 120.44807 -97.888298) (xy 120.27789 -97.799398) (xy 120.23344 -97.799398)
			(xy 120.23344 -98.198178) (xy 120.27789 -98.198178)
		)
		(stroke
			(width 0)
			(type solid)
		)
		(fill yes)
		(layer "In11.Cu")
		(net "M_M_DQ<51>")
	)
	(gr_poly
		(pts
			(xy 120.48363 -61.648848) (xy 120.43918 -61.648848) (xy 120.269 -61.737748) (xy 120.269 -61.958728)
			(xy 120.43918 -62.047628) (xy 120.48363 -62.047628)
		)
		(stroke
			(width 0)
			(type solid)
		)
		(fill yes)
		(layer "In11.Cu")
		(net "M_J_DQ<56>")
	)
	(gr_poly
		(pts
			(xy 120.48363 -60.664344) (xy 120.43918 -60.664344) (xy 120.269 -60.753244) (xy 120.269 -60.974224)
			(xy 120.43918 -61.063124) (xy 120.48363 -61.063124)
		)
		(stroke
			(width 0)
			(type solid)
		)
		(fill yes)
		(layer "In11.Cu")
		(net "M_J_DQ<56>")
	)
	(gr_poly
		(pts
			(xy 120.48363 -59.667394) (xy 120.43918 -59.667394) (xy 120.269 -59.756294) (xy 120.269 -59.977274)
			(xy 120.43918 -60.066174) (xy 120.48363 -60.066174)
		)
		(stroke
			(width 0)
			(type solid)
		)
		(fill yes)
		(layer "In11.Cu")
		(net "M_J_DQ<56>")
	)
	(gr_poly
		(pts
			(xy 120.48363 -58.670698) (xy 120.43918 -58.670698) (xy 120.269 -58.759598) (xy 120.269 -58.980578)
			(xy 120.43918 -59.069478) (xy 120.48363 -59.069478)
		)
		(stroke
			(width 0)
			(type solid)
		)
		(fill yes)
		(layer "In11.Cu")
		(net "M_J_DQ<56>")
	)
	(gr_poly
		(pts
			(xy 120.48363 -57.692544) (xy 120.43918 -57.692544) (xy 120.269 -57.781444) (xy 120.269 -58.002424)
			(xy 120.43918 -58.091324) (xy 120.48363 -58.091324)
		)
		(stroke
			(width 0)
			(type solid)
		)
		(fill yes)
		(layer "In11.Cu")
		(net "M_J_DQ<56>")
	)
	(gr_poly
		(pts
			(xy 120.48363 -56.701944) (xy 120.43918 -56.701944) (xy 120.269 -56.790844) (xy 120.269 -57.011824)
			(xy 120.43918 -57.100724) (xy 120.48363 -57.100724)
		)
		(stroke
			(width 0)
			(type solid)
		)
		(fill yes)
		(layer "In11.Cu")
		(net "M_J_DQ<56>")
	)
	(gr_poly
		(pts
			(xy 120.48363 -55.711344) (xy 120.43918 -55.711344) (xy 120.269 -55.800244) (xy 120.269 -56.021224)
			(xy 120.43918 -56.110124) (xy 120.48363 -56.110124)
		)
		(stroke
			(width 0)
			(type solid)
		)
		(fill yes)
		(layer "In11.Cu")
		(net "M_J_DQ<56>")
	)
	(gr_poly
		(pts
			(xy 120.48363 -54.720744) (xy 120.43918 -54.720744) (xy 120.269 -54.809644) (xy 120.269 -55.030624)
			(xy 120.43918 -55.119524) (xy 120.48363 -55.119524)
		)
		(stroke
			(width 0)
			(type solid)
		)
		(fill yes)
		(layer "In11.Cu")
		(net "M_J_DQ<56>")
	)
	(gr_poly
		(pts
			(xy 120.48363 -53.730144) (xy 120.43918 -53.730144) (xy 120.269 -53.819044) (xy 120.269 -54.040024)
			(xy 120.43918 -54.128924) (xy 120.48363 -54.128924)
		)
		(stroke
			(width 0)
			(type solid)
		)
		(fill yes)
		(layer "In11.Cu")
		(net "M_J_DQ<56>")
	)
	(gr_poly
		(pts
			(xy 120.551956 -50.44567) (xy 120.478296 -50.24628) (xy 120.4468 -50.214784) (xy 120.159526 -50.502058)
			(xy 120.190768 -50.533554) (xy 120.390158 -50.607214)
		)
		(stroke
			(width 0)
			(type solid)
		)
		(fill yes)
		(layer "In11.Cu")
		(net "M_J_DQ<61>")
	)
	(gr_poly
		(pts
			(xy 120.560846 -63.015622) (xy 120.582436 -62.824868) (xy 120.399302 -62.70117) (xy 120.230392 -62.792356)
			(xy 120.2055 -62.829186) (xy 120.535954 -63.052452)
		)
		(stroke
			(width 0)
			(type solid)
		)
		(fill yes)
		(layer "In11.Cu")
		(net "M_J_DQ<61>")
	)
	(gr_poly
		(pts
			(xy 120.576086 -53.06568) (xy 120.531636 -53.06568) (xy 120.338596 -53.15458) (xy 120.338596 -53.38318)
			(xy 120.531636 -53.47208) (xy 120.576086 -53.47208)
		)
		(stroke
			(width 0)
			(type solid)
		)
		(fill yes)
		(layer "In11.Cu")
		(net "M_J_DQ<56>")
	)
	(gr_poly
		(pts
			(xy 120.847612 -62.66688) (xy 120.88368 -62.641226) (xy 120.652794 -62.316106) (xy 120.616472 -62.34176)
			(xy 120.52935 -62.512956) (xy 120.657366 -62.693042)
		)
		(stroke
			(width 0)
			(type solid)
		)
		(fill yes)
		(layer "In11.Cu")
		(net "M_J_DQ<56>")
	)
	(gr_poly
		(pts
			(xy 120.93321 -64.49441) (xy 120.770904 -64.130174) (xy 120.730264 -64.148208) (xy 120.611138 -64.298576)
			(xy 120.701054 -64.500506) (xy 120.89257 -64.512444)
		)
		(stroke
			(width 0)
			(type solid)
		)
		(fill yes)
		(layer "In11.Cu")
		(net "M_J_DQ<57>")
	)
	(gr_poly
		(pts
			(xy 120.958102 -92.072714) (xy 121.041668 -91.89974) (xy 120.909842 -91.722448) (xy 120.720104 -91.752674)
			(xy 120.684544 -91.77909) (xy 120.922542 -92.099384)
		)
		(stroke
			(width 0)
			(type solid)
		)
		(fill yes)
		(layer "In11.Cu")
		(net "M_M_DQ<59>")
	)
	(gr_poly
		(pts
			(xy 120.99671 -94.090744) (xy 121.004838 -93.898974) (xy 120.813576 -93.788484) (xy 120.651524 -93.891354)
			(xy 120.629172 -93.929962) (xy 120.974612 -94.129098)
		)
		(stroke
			(width 0)
			(type solid)
		)
		(fill yes)
		(layer "In11.Cu")
		(net "M_M_DQS_DP<7>")
	)
	(gr_poly
		(pts
			(xy 120.998996 -97.063814) (xy 121.007124 -96.872044) (xy 120.815862 -96.761554) (xy 120.65381 -96.864424)
			(xy 120.631458 -96.902778) (xy 120.976898 -97.102422)
		)
		(stroke
			(width 0)
			(type solid)
		)
		(fill yes)
		(layer "In11.Cu")
		(net "M_M_DQ<61>")
	)
	(gr_poly
		(pts
			(xy 120.998996 -96.073214) (xy 121.007124 -95.881444) (xy 120.815862 -95.770954) (xy 120.65381 -95.873824)
			(xy 120.631458 -95.912178) (xy 120.976898 -96.111822)
		)
		(stroke
			(width 0)
			(type solid)
		)
		(fill yes)
		(layer "In11.Cu")
		(net "M_M_DQ<57>")
	)
	(gr_poly
		(pts
			(xy 120.998996 -93.101414) (xy 121.007124 -92.909644) (xy 120.815862 -92.799154) (xy 120.65381 -92.902024)
			(xy 120.631458 -92.940378) (xy 120.976898 -93.140022)
		)
		(stroke
			(width 0)
			(type solid)
		)
		(fill yes)
		(layer "In11.Cu")
		(net "M_M_DQ<63>")
	)
	(gr_poly
		(pts
			(xy 121.00052 -95.083376) (xy 121.008648 -94.891606) (xy 120.817386 -94.781116) (xy 120.655334 -94.883986)
			(xy 120.632982 -94.922594) (xy 120.978422 -95.12173)
		)
		(stroke
			(width 0)
			(type solid)
		)
		(fill yes)
		(layer "In11.Cu")
		(net "M_M_DQS_DN<16>")
	)
	(gr_poly
		(pts
			(xy 121.003822 -53.17998) (xy 121.003822 -52.95138) (xy 120.810782 -52.86248) (xy 120.766332 -52.86248)
			(xy 120.766332 -53.26888) (xy 120.810782 -53.26888)
		)
		(stroke
			(width 0)
			(type solid)
		)
		(fill yes)
		(layer "In11.Cu")
		(net "M_J_DQ<57>")
	)
	(gr_poly
		(pts
			(xy 121.012458 -49.379632) (xy 120.980962 -49.348136) (xy 120.781826 -49.274476) (xy 120.620028 -49.436274)
			(xy 120.693688 -49.63541) (xy 120.725184 -49.666906)
		)
		(stroke
			(width 0)
			(type solid)
		)
		(fill yes)
		(layer "In11.Cu")
		(net "M_J_DQ<60>")
	)
	(gr_poly
		(pts
			(xy 121.021602 -61.463428) (xy 121.021602 -61.242448) (xy 120.851422 -61.153548) (xy 120.806972 -61.153548)
			(xy 120.806972 -61.552328) (xy 120.851422 -61.552328)
		)
		(stroke
			(width 0)
			(type solid)
		)
		(fill yes)
		(layer "In11.Cu")
		(net "M_J_DQ<57>")
	)
	(gr_poly
		(pts
			(xy 121.021856 -60.466478) (xy 121.021856 -60.245498) (xy 120.851676 -60.156598) (xy 120.807226 -60.156598)
			(xy 120.807226 -60.555378) (xy 120.851676 -60.555378)
		)
		(stroke
			(width 0)
			(type solid)
		)
		(fill yes)
		(layer "In11.Cu")
		(net "M_J_DQ<57>")
	)
	(gr_poly
		(pts
			(xy 121.021856 -59.488324) (xy 121.021856 -59.267344) (xy 120.851676 -59.178444) (xy 120.807226 -59.178444)
			(xy 120.807226 -59.577224) (xy 120.851676 -59.577224)
		)
		(stroke
			(width 0)
			(type solid)
		)
		(fill yes)
		(layer "In11.Cu")
		(net "M_J_DQ<57>")
	)
	(gr_poly
		(pts
			(xy 121.021856 -58.491628) (xy 121.021856 -58.270648) (xy 120.851676 -58.181748) (xy 120.807226 -58.181748)
			(xy 120.807226 -58.580528) (xy 120.851676 -58.580528)
		)
		(stroke
			(width 0)
			(type solid)
		)
		(fill yes)
		(layer "In11.Cu")
		(net "M_J_DQ<57>")
	)
	(gr_poly
		(pts
			(xy 121.021856 -57.494678) (xy 121.021856 -57.273698) (xy 120.851676 -57.184798) (xy 120.807226 -57.184798)
			(xy 120.807226 -57.583578) (xy 120.851676 -57.583578)
		)
		(stroke
			(width 0)
			(type solid)
		)
		(fill yes)
		(layer "In11.Cu")
		(net "M_J_DQ<57>")
	)
	(gr_poly
		(pts
			(xy 121.021856 -56.504078) (xy 121.021856 -56.283098) (xy 120.851676 -56.194198) (xy 120.807226 -56.194198)
			(xy 120.807226 -56.592978) (xy 120.851676 -56.592978)
		)
		(stroke
			(width 0)
			(type solid)
		)
		(fill yes)
		(layer "In11.Cu")
		(net "M_J_DQ<57>")
	)
	(gr_poly
		(pts
			(xy 121.021856 -55.513478) (xy 121.021856 -55.292498) (xy 120.851676 -55.203598) (xy 120.807226 -55.203598)
			(xy 120.807226 -55.602378) (xy 120.851676 -55.602378)
		)
		(stroke
			(width 0)
			(type solid)
		)
		(fill yes)
		(layer "In11.Cu")
		(net "M_J_DQ<57>")
	)
	(gr_poly
		(pts
			(xy 121.021856 -54.522878) (xy 121.021856 -54.301898) (xy 120.851676 -54.212998) (xy 120.807226 -54.212998)
			(xy 120.807226 -54.611778) (xy 120.851676 -54.611778)
		)
		(stroke
			(width 0)
			(type solid)
		)
		(fill yes)
		(layer "In11.Cu")
		(net "M_J_DQ<57>")
	)
	(gr_poly
		(pts
			(xy 121.204736 -94.687136) (xy 121.227088 -94.648782) (xy 120.881648 -94.449138) (xy 120.85955 -94.487746)
			(xy 120.851422 -94.679516) (xy 121.042684 -94.790006)
		)
		(stroke
			(width 0)
			(type solid)
		)
		(fill yes)
		(layer "In11.Cu")
		(net "M_M_DQS_DN<7>")
	)
	(gr_poly
		(pts
			(xy 121.20626 -97.659698) (xy 121.228612 -97.62109) (xy 120.883172 -97.421954) (xy 120.861074 -97.460308)
			(xy 120.852946 -97.652078) (xy 121.044208 -97.762568)
		)
		(stroke
			(width 0)
			(type solid)
		)
		(fill yes)
		(layer "In11.Cu")
		(net "M_M_DQ<60>")
	)
	(gr_poly
		(pts
			(xy 121.20626 -96.669098) (xy 121.228612 -96.63049) (xy 120.883172 -96.431354) (xy 120.861074 -96.469708)
			(xy 120.852946 -96.661478) (xy 121.044208 -96.771968)
		)
		(stroke
			(width 0)
			(type solid)
		)
		(fill yes)
		(layer "In11.Cu")
		(net "M_M_DQ<56>")
	)
	(gr_poly
		(pts
			(xy 121.20626 -93.697298) (xy 121.228612 -93.65869) (xy 120.883172 -93.459554) (xy 120.861074 -93.497908)
			(xy 120.852946 -93.689678) (xy 121.044208 -93.800168)
		)
		(stroke
			(width 0)
			(type solid)
		)
		(fill yes)
		(layer "In11.Cu")
		(net "M_M_DQ<62>")
	)
	(gr_poly
		(pts
			(xy 121.20626 -92.706698) (xy 121.228612 -92.66809) (xy 120.883172 -92.468954) (xy 120.861074 -92.507308)
			(xy 120.852946 -92.699078) (xy 121.044208 -92.809568)
		)
		(stroke
			(width 0)
			(type solid)
		)
		(fill yes)
		(layer "In11.Cu")
		(net "M_M_DQ<58>")
	)
	(gr_poly
		(pts
			(xy 121.208546 -95.679768) (xy 121.230898 -95.641414) (xy 120.885458 -95.44177) (xy 120.86336 -95.480378)
			(xy 120.855232 -95.672148) (xy 121.046494 -95.782638)
		)
		(stroke
			(width 0)
			(type solid)
		)
		(fill yes)
		(layer "In11.Cu")
		(net "M_M_DQS_DP<16>")
	)
	(gr_poly
		(pts
			(xy 121.252234 -49.745138) (xy 121.178574 -49.545748) (xy 121.147332 -49.514252) (xy 120.859804 -49.80178)
			(xy 120.8913 -49.833022) (xy 121.09069 -49.906682)
		)
		(stroke
			(width 0)
			(type solid)
		)
		(fill yes)
		(layer "In11.Cu")
		(net "M_J_DQ<61>")
	)
	(gr_poly
		(pts
			(xy 121.34215 -61.153548) (xy 121.2977 -61.153548) (xy 121.12752 -61.242448) (xy 121.12752 -61.463428)
			(xy 121.2977 -61.552328) (xy 121.34215 -61.552328)
		)
		(stroke
			(width 0)
			(type solid)
		)
		(fill yes)
		(layer "In11.Cu")
		(net "M_J_DQS_DP<16>")
	)
	(gr_poly
		(pts
			(xy 121.34215 -60.156598) (xy 121.2977 -60.156598) (xy 121.12752 -60.245498) (xy 121.12752 -60.466478)
			(xy 121.2977 -60.555378) (xy 121.34215 -60.555378)
		)
		(stroke
			(width 0)
			(type solid)
		)
		(fill yes)
		(layer "In11.Cu")
		(net "M_J_DQS_DP<16>")
	)
	(gr_poly
		(pts
			(xy 121.34215 -59.178444) (xy 121.2977 -59.178444) (xy 121.12752 -59.267344) (xy 121.12752 -59.488324)
			(xy 121.2977 -59.577224) (xy 121.34215 -59.577224)
		)
		(stroke
			(width 0)
			(type solid)
		)
		(fill yes)
		(layer "In11.Cu")
		(net "M_J_DQS_DP<16>")
	)
	(gr_poly
		(pts
			(xy 121.34215 -58.181748) (xy 121.2977 -58.181748) (xy 121.12752 -58.270648) (xy 121.12752 -58.491628)
			(xy 121.2977 -58.580528) (xy 121.34215 -58.580528)
		)
		(stroke
			(width 0)
			(type solid)
		)
		(fill yes)
		(layer "In11.Cu")
		(net "M_J_DQS_DP<16>")
	)
	(gr_poly
		(pts
			(xy 121.34215 -57.184798) (xy 121.2977 -57.184798) (xy 121.12752 -57.273698) (xy 121.12752 -57.494678)
			(xy 121.2977 -57.583578) (xy 121.34215 -57.583578)
		)
		(stroke
			(width 0)
			(type solid)
		)
		(fill yes)
		(layer "In11.Cu")
		(net "M_J_DQS_DP<16>")
	)
	(gr_poly
		(pts
			(xy 121.34215 -56.194198) (xy 121.2977 -56.194198) (xy 121.12752 -56.283098) (xy 121.12752 -56.504078)
			(xy 121.2977 -56.592978) (xy 121.34215 -56.592978)
		)
		(stroke
			(width 0)
			(type solid)
		)
		(fill yes)
		(layer "In11.Cu")
		(net "M_J_DQS_DP<16>")
	)
	(gr_poly
		(pts
			(xy 121.34215 -55.203598) (xy 121.2977 -55.203598) (xy 121.12752 -55.292498) (xy 121.12752 -55.513478)
			(xy 121.2977 -55.602378) (xy 121.34215 -55.602378)
		)
		(stroke
			(width 0)
			(type solid)
		)
		(fill yes)
		(layer "In11.Cu")
		(net "M_J_DQS_DP<16>")
	)
	(gr_poly
		(pts
			(xy 121.34215 -54.212998) (xy 121.2977 -54.212998) (xy 121.12752 -54.301898) (xy 121.12752 -54.522878)
			(xy 121.2977 -54.611778) (xy 121.34215 -54.611778)
		)
		(stroke
			(width 0)
			(type solid)
		)
		(fill yes)
		(layer "In11.Cu")
		(net "M_J_DQS_DP<16>")
	)
	(gr_poly
		(pts
			(xy 121.342912 -53.090826) (xy 121.298462 -53.090826) (xy 121.128282 -53.179726) (xy 121.128282 -53.400706)
			(xy 121.298462 -53.489606) (xy 121.342912 -53.489606)
		)
		(stroke
			(width 0)
			(type solid)
		)
		(fill yes)
		(layer "In11.Cu")
		(net "M_J_DQS_DP<16>")
	)
	(gr_poly
		(pts
			(xy 121.342912 -52.152042) (xy 121.298462 -52.152042) (xy 121.105422 -52.240942) (xy 121.105422 -52.469542)
			(xy 121.298462 -52.558442) (xy 121.342912 -52.558442)
		)
		(stroke
			(width 0)
			(type solid)
		)
		(fill yes)
		(layer "In11.Cu")
		(net "M_J_DQS_DP<16>")
	)
	(gr_poly
		(pts
			(xy 121.445782 -63.368936) (xy 121.404634 -63.18123) (xy 121.375932 -63.147194) (xy 121.070624 -63.403734)
			(xy 121.099072 -63.43777) (xy 121.276618 -63.510922)
		)
		(stroke
			(width 0)
			(type solid)
		)
		(fill yes)
		(layer "In11.Cu")
		(net "M_J_DQ<57>")
	)
	(gr_poly
		(pts
			(xy 121.62663 -103.260144) (xy 121.58218 -103.260144) (xy 121.412 -103.349044) (xy 121.412 -103.570024)
			(xy 121.58218 -103.658924) (xy 121.62663 -103.658924)
		)
		(stroke
			(width 0)
			(type solid)
		)
		(fill yes)
		(layer "In11.Cu")
		(net "M_M_DQ<60>")
	)
	(gr_poly
		(pts
			(xy 121.62663 -102.269544) (xy 121.58218 -102.269544) (xy 121.412 -102.358444) (xy 121.412 -102.579424)
			(xy 121.58218 -102.668324) (xy 121.62663 -102.668324)
		)
		(stroke
			(width 0)
			(type solid)
		)
		(fill yes)
		(layer "In11.Cu")
		(net "M_M_DQ<60>")
	)
	(gr_poly
		(pts
			(xy 121.62663 -101.278944) (xy 121.58218 -101.278944) (xy 121.412 -101.367844) (xy 121.412 -101.588824)
			(xy 121.58218 -101.677724) (xy 121.62663 -101.677724)
		)
		(stroke
			(width 0)
			(type solid)
		)
		(fill yes)
		(layer "In11.Cu")
		(net "M_M_DQ<60>")
	)
	(gr_poly
		(pts
			(xy 121.62663 -100.288344) (xy 121.58218 -100.288344) (xy 121.412 -100.377244) (xy 121.412 -100.598224)
			(xy 121.58218 -100.687124) (xy 121.62663 -100.687124)
		)
		(stroke
			(width 0)
			(type solid)
		)
		(fill yes)
		(layer "In11.Cu")
		(net "M_M_DQ<60>")
	)
	(gr_poly
		(pts
			(xy 121.62663 -99.297744) (xy 121.58218 -99.297744) (xy 121.412 -99.386644) (xy 121.412 -99.607624)
			(xy 121.58218 -99.696524) (xy 121.62663 -99.696524)
		)
		(stroke
			(width 0)
			(type solid)
		)
		(fill yes)
		(layer "In11.Cu")
		(net "M_M_DQ<60>")
	)
	(gr_poly
		(pts
			(xy 121.62663 -98.301556) (xy 121.58218 -98.301556) (xy 121.412 -98.390456) (xy 121.412 -98.611436)
			(xy 121.58218 -98.700336) (xy 121.62663 -98.700336)
		)
		(stroke
			(width 0)
			(type solid)
		)
		(fill yes)
		(layer "In11.Cu")
		(net "M_M_DQ<60>")
	)
	(gr_poly
		(pts
			(xy 121.748042 -53.046122) (xy 121.748042 -52.825142) (xy 121.577862 -52.736242) (xy 121.533412 -52.736242)
			(xy 121.533412 -53.135022) (xy 121.577862 -53.135022)
		)
		(stroke
			(width 0)
			(type solid)
		)
		(fill yes)
		(layer "In11.Cu")
		(net "M_J_DQS_DN<16>")
	)
	(gr_poly
		(pts
			(xy 121.768108 -51.594766) (xy 121.736612 -51.563524) (xy 121.537222 -51.489864) (xy 121.375678 -51.651408)
			(xy 121.449084 -51.850798) (xy 121.48058 -51.882294)
		)
		(stroke
			(width 0)
			(type solid)
		)
		(fill yes)
		(layer "In11.Cu")
		(net "M_J_DQS_DP<16>")
	)
	(gr_poly
		(pts
			(xy 121.854976 -95.576644) (xy 121.863104 -95.384874) (xy 121.671842 -95.274384) (xy 121.50979 -95.377254)
			(xy 121.487438 -95.415862) (xy 121.832878 -95.614998)
		)
		(stroke
			(width 0)
			(type solid)
		)
		(fill yes)
		(layer "In11.Cu")
		(net "M_M_DQS_DN<16>")
	)
	(gr_poly
		(pts
			(xy 121.857262 -94.587314) (xy 121.86539 -94.395544) (xy 121.674128 -94.285054) (xy 121.512076 -94.387924)
			(xy 121.489724 -94.426278) (xy 121.835164 -94.625922)
		)
		(stroke
			(width 0)
			(type solid)
		)
		(fill yes)
		(layer "In11.Cu")
		(net "M_M_DQS_DP<7>")
	)
	(gr_poly
		(pts
			(xy 121.858786 -97.560384) (xy 121.866914 -97.368614) (xy 121.675652 -97.258124) (xy 121.5136 -97.360994)
			(xy 121.491248 -97.399348) (xy 121.836688 -97.598738)
		)
		(stroke
			(width 0)
			(type solid)
		)
		(fill yes)
		(layer "In11.Cu")
		(net "M_M_DQ<61>")
	)
	(gr_poly
		(pts
			(xy 121.858786 -96.56953) (xy 121.866914 -96.37776) (xy 121.675652 -96.26727) (xy 121.5136 -96.37014)
			(xy 121.491248 -96.408494) (xy 121.836688 -96.608138)
		)
		(stroke
			(width 0)
			(type solid)
		)
		(fill yes)
		(layer "In11.Cu")
		(net "M_M_DQ<57>")
	)
	(gr_poly
		(pts
			(xy 121.858786 -93.59773) (xy 121.866914 -93.40596) (xy 121.675652 -93.29547) (xy 121.5136 -93.39834)
			(xy 121.491248 -93.436694) (xy 121.836688 -93.636338)
		)
		(stroke
			(width 0)
			(type solid)
		)
		(fill yes)
		(layer "In11.Cu")
		(net "M_M_DQ<63>")
	)
	(gr_poly
		(pts
			(xy 121.858786 -92.60713) (xy 121.866914 -92.41536) (xy 121.675652 -92.30487) (xy 121.5136 -92.40774)
			(xy 121.491248 -92.446094) (xy 121.836688 -92.645738)
		)
		(stroke
			(width 0)
			(type solid)
		)
		(fill yes)
		(layer "In11.Cu")
		(net "M_M_DQ<59>")
	)
	(gr_poly
		(pts
			(xy 121.880122 -54.022498) (xy 121.880122 -53.801518) (xy 121.709942 -53.712618) (xy 121.665492 -53.712618)
			(xy 121.665492 -54.111398) (xy 121.709942 -54.111398)
		)
		(stroke
			(width 0)
			(type solid)
		)
		(fill yes)
		(layer "In11.Cu")
		(net "M_J_DQS_DN<16>")
	)
	(gr_poly
		(pts
			(xy 121.880376 -60.974224) (xy 121.880376 -60.753244) (xy 121.710196 -60.664344) (xy 121.665746 -60.664344)
			(xy 121.665746 -61.063124) (xy 121.710196 -61.063124)
		)
		(stroke
			(width 0)
			(type solid)
		)
		(fill yes)
		(layer "In11.Cu")
		(net "M_J_DQS_DN<16>")
	)
	(gr_poly
		(pts
			(xy 121.880376 -59.977274) (xy 121.880376 -59.756294) (xy 121.710196 -59.667394) (xy 121.665746 -59.667394)
			(xy 121.665746 -60.066174) (xy 121.710196 -60.066174)
		)
		(stroke
			(width 0)
			(type solid)
		)
		(fill yes)
		(layer "In11.Cu")
		(net "M_J_DQS_DN<16>")
	)
	(gr_poly
		(pts
			(xy 121.880376 -58.980578) (xy 121.880376 -58.759598) (xy 121.710196 -58.670698) (xy 121.665746 -58.670698)
			(xy 121.665746 -59.069478) (xy 121.710196 -59.069478)
		)
		(stroke
			(width 0)
			(type solid)
		)
		(fill yes)
		(layer "In11.Cu")
		(net "M_J_DQS_DN<16>")
	)
	(gr_poly
		(pts
			(xy 121.880376 -58.002424) (xy 121.880376 -57.781444) (xy 121.710196 -57.692544) (xy 121.665746 -57.692544)
			(xy 121.665746 -58.091324) (xy 121.710196 -58.091324)
		)
		(stroke
			(width 0)
			(type solid)
		)
		(fill yes)
		(layer "In11.Cu")
		(net "M_J_DQS_DN<16>")
	)
	(gr_poly
		(pts
			(xy 121.880376 -57.011824) (xy 121.880376 -56.790844) (xy 121.710196 -56.701944) (xy 121.665746 -56.701944)
			(xy 121.665746 -57.100724) (xy 121.710196 -57.100724)
		)
		(stroke
			(width 0)
			(type solid)
		)
		(fill yes)
		(layer "In11.Cu")
		(net "M_J_DQS_DN<16>")
	)
	(gr_poly
		(pts
			(xy 121.880376 -56.021224) (xy 121.880376 -55.800244) (xy 121.710196 -55.711344) (xy 121.665746 -55.711344)
			(xy 121.665746 -56.110124) (xy 121.710196 -56.110124)
		)
		(stroke
			(width 0)
			(type solid)
		)
		(fill yes)
		(layer "In11.Cu")
		(net "M_J_DQS_DN<16>")
	)
	(gr_poly
		(pts
			(xy 121.880376 -55.030624) (xy 121.880376 -54.809644) (xy 121.710196 -54.720744) (xy 121.665746 -54.720744)
			(xy 121.665746 -55.119524) (xy 121.710196 -55.119524)
		)
		(stroke
			(width 0)
			(type solid)
		)
		(fill yes)
		(layer "In11.Cu")
		(net "M_J_DQS_DN<16>")
	)
	(gr_poly
		(pts
			(xy 121.95556 -49.547018) (xy 121.924064 -49.515522) (xy 121.724928 -49.441862) (xy 121.56313 -49.60366)
			(xy 121.63679 -49.802796) (xy 121.668286 -49.834292)
		)
		(stroke
			(width 0)
			(type solid)
		)
		(fill yes)
		(layer "In11.Cu")
		(net "M_J_DQ<56>")
	)
	(gr_poly
		(pts
			(xy 122.063256 -97.163382) (xy 122.085608 -97.124774) (xy 121.740168 -96.925638) (xy 121.71807 -96.963992)
			(xy 121.709942 -97.155762) (xy 121.901204 -97.266252)
		)
		(stroke
			(width 0)
			(type solid)
		)
		(fill yes)
		(layer "In11.Cu")
		(net "M_M_DQ<56>")
	)
	(gr_poly
		(pts
			(xy 122.063256 -96.172782) (xy 122.085608 -96.134174) (xy 121.740168 -95.935038) (xy 121.71807 -95.973392)
			(xy 121.709942 -96.165162) (xy 121.901204 -96.275652)
		)
		(stroke
			(width 0)
			(type solid)
		)
		(fill yes)
		(layer "In11.Cu")
		(net "M_M_DQS_DP<16>")
	)
	(gr_poly
		(pts
			(xy 122.063256 -93.200982) (xy 122.085608 -93.162374) (xy 121.740168 -92.963238) (xy 121.71807 -93.001592)
			(xy 121.709942 -93.193362) (xy 121.901204 -93.303852)
		)
		(stroke
			(width 0)
			(type solid)
		)
		(fill yes)
		(layer "In11.Cu")
		(net "M_M_DQ<58>")
	)
	(gr_poly
		(pts
			(xy 122.06478 -95.183198) (xy 122.087132 -95.14459) (xy 121.741692 -94.945454) (xy 121.719594 -94.983808)
			(xy 121.711466 -95.175578) (xy 121.902728 -95.286068)
		)
		(stroke
			(width 0)
			(type solid)
		)
		(fill yes)
		(layer "In11.Cu")
		(net "M_M_DQS_DN<7>")
	)
	(gr_poly
		(pts
			(xy 122.067066 -94.193868) (xy 122.089418 -94.155514) (xy 121.743978 -93.95587) (xy 121.72188 -93.994478)
			(xy 121.713752 -94.186248) (xy 121.905014 -94.296738)
		)
		(stroke
			(width 0)
			(type solid)
		)
		(fill yes)
		(layer "In11.Cu")
		(net "M_M_DQ<62>")
	)
	(gr_poly
		(pts
			(xy 122.06859 -104.100884) (xy 122.090942 -104.06253) (xy 121.745756 -103.862886) (xy 121.723404 -103.901748)
			(xy 121.715276 -104.093518) (xy 121.906792 -104.203754)
		)
		(stroke
			(width 0)
			(type solid)
		)
		(fill yes)
		(layer "In11.Cu")
		(net "M_M_DQ<60>")
	)
	(gr_poly
		(pts
			(xy 122.164602 -99.107244) (xy 122.164602 -98.886264) (xy 121.994422 -98.797364) (xy 121.949972 -98.797364)
			(xy 121.949972 -99.196144) (xy 121.994422 -99.196144)
		)
		(stroke
			(width 0)
			(type solid)
		)
		(fill yes)
		(layer "In11.Cu")
		(net "M_M_DQ<61>")
	)
	(gr_poly
		(pts
			(xy 122.164856 -103.062278) (xy 122.164856 -102.841298) (xy 121.994676 -102.752398) (xy 121.950226 -102.752398)
			(xy 121.950226 -103.151178) (xy 121.994676 -103.151178)
		)
		(stroke
			(width 0)
			(type solid)
		)
		(fill yes)
		(layer "In11.Cu")
		(net "M_M_DQ<61>")
	)
	(gr_poly
		(pts
			(xy 122.164856 -102.071678) (xy 122.164856 -101.850698) (xy 121.994676 -101.761798) (xy 121.950226 -101.761798)
			(xy 121.950226 -102.160578) (xy 121.994676 -102.160578)
		)
		(stroke
			(width 0)
			(type solid)
		)
		(fill yes)
		(layer "In11.Cu")
		(net "M_M_DQ<61>")
	)
	(gr_poly
		(pts
			(xy 122.164856 -101.081078) (xy 122.164856 -100.860098) (xy 121.994676 -100.771198) (xy 121.950226 -100.771198)
			(xy 121.950226 -101.169978) (xy 121.994676 -101.169978)
		)
		(stroke
			(width 0)
			(type solid)
		)
		(fill yes)
		(layer "In11.Cu")
		(net "M_M_DQ<61>")
	)
	(gr_poly
		(pts
			(xy 122.164856 -100.090478) (xy 122.164856 -99.869498) (xy 121.994676 -99.780598) (xy 121.950226 -99.780598)
			(xy 121.950226 -100.179378) (xy 121.994676 -100.179378)
		)
		(stroke
			(width 0)
			(type solid)
		)
		(fill yes)
		(layer "In11.Cu")
		(net "M_M_DQ<61>")
	)
	(gr_poly
		(pts
			(xy 122.164856 -98.116136) (xy 122.164856 -97.895156) (xy 121.994676 -97.806256) (xy 121.950226 -97.806256)
			(xy 121.950226 -98.205036) (xy 121.994676 -98.205036)
		)
		(stroke
			(width 0)
			(type solid)
		)
		(fill yes)
		(layer "In11.Cu")
		(net "M_M_DQ<61>")
	)
	(gr_poly
		(pts
			(xy 122.195844 -49.913032) (xy 122.122184 -49.713642) (xy 122.090942 -49.682146) (xy 121.803414 -49.969674)
			(xy 121.83491 -50.000916) (xy 122.0343 -50.074576)
		)
		(stroke
			(width 0)
			(type solid)
		)
		(fill yes)
		(layer "In11.Cu")
		(net "M_J_DQ<57>")
	)
	(gr_poly
		(pts
			(xy 122.20067 -63.636144) (xy 122.15622 -63.636144) (xy 121.98604 -63.725044) (xy 121.98604 -63.946024)
			(xy 122.15622 -64.034924) (xy 122.20067 -64.034924)
		)
		(stroke
			(width 0)
			(type solid)
		)
		(fill yes)
		(layer "In11.Cu")
		(net "M_J_DQS_DP<7>")
	)
	(gr_poly
		(pts
			(xy 122.20067 -62.645544) (xy 122.15622 -62.645544) (xy 121.98604 -62.734444) (xy 121.98604 -62.955424)
			(xy 122.15622 -63.044324) (xy 122.20067 -63.044324)
		)
		(stroke
			(width 0)
			(type solid)
		)
		(fill yes)
		(layer "In11.Cu")
		(net "M_J_DQS_DP<7>")
	)
	(gr_poly
		(pts
			(xy 122.20067 -61.654944) (xy 122.15622 -61.654944) (xy 121.98604 -61.743844) (xy 121.98604 -61.964824)
			(xy 122.15622 -62.053724) (xy 122.20067 -62.053724)
		)
		(stroke
			(width 0)
			(type solid)
		)
		(fill yes)
		(layer "In11.Cu")
		(net "M_J_DQS_DP<7>")
	)
	(gr_poly
		(pts
			(xy 122.20067 -60.664344) (xy 122.15622 -60.664344) (xy 121.98604 -60.753244) (xy 121.98604 -60.974224)
			(xy 122.15622 -61.063124) (xy 122.20067 -61.063124)
		)
		(stroke
			(width 0)
			(type solid)
		)
		(fill yes)
		(layer "In11.Cu")
		(net "M_J_DQS_DP<7>")
	)
	(gr_poly
		(pts
			(xy 122.20067 -59.667394) (xy 122.15622 -59.667394) (xy 121.98604 -59.756294) (xy 121.98604 -59.977274)
			(xy 122.15622 -60.066174) (xy 122.20067 -60.066174)
		)
		(stroke
			(width 0)
			(type solid)
		)
		(fill yes)
		(layer "In11.Cu")
		(net "M_J_DQS_DP<7>")
	)
	(gr_poly
		(pts
			(xy 122.20067 -58.670698) (xy 122.15622 -58.670698) (xy 121.98604 -58.759598) (xy 121.98604 -58.980578)
			(xy 122.15622 -59.069478) (xy 122.20067 -59.069478)
		)
		(stroke
			(width 0)
			(type solid)
		)
		(fill yes)
		(layer "In11.Cu")
		(net "M_J_DQS_DP<7>")
	)
	(gr_poly
		(pts
			(xy 122.20067 -57.692544) (xy 122.15622 -57.692544) (xy 121.98604 -57.781444) (xy 121.98604 -58.002424)
			(xy 122.15622 -58.091324) (xy 122.20067 -58.091324)
		)
		(stroke
			(width 0)
			(type solid)
		)
		(fill yes)
		(layer "In11.Cu")
		(net "M_J_DQS_DP<7>")
	)
	(gr_poly
		(pts
			(xy 122.20067 -56.701944) (xy 122.15622 -56.701944) (xy 121.98604 -56.790844) (xy 121.98604 -57.011824)
			(xy 122.15622 -57.100724) (xy 122.20067 -57.100724)
		)
		(stroke
			(width 0)
			(type solid)
		)
		(fill yes)
		(layer "In11.Cu")
		(net "M_J_DQS_DP<7>")
	)
	(gr_poly
		(pts
			(xy 122.20067 -55.711344) (xy 122.15622 -55.711344) (xy 121.98604 -55.800244) (xy 121.98604 -56.021224)
			(xy 122.15622 -56.110124) (xy 122.20067 -56.110124)
		)
		(stroke
			(width 0)
			(type solid)
		)
		(fill yes)
		(layer "In11.Cu")
		(net "M_J_DQS_DP<7>")
	)
	(gr_poly
		(pts
			(xy 122.20067 -54.720744) (xy 122.15622 -54.720744) (xy 121.98604 -54.809644) (xy 121.98604 -55.030624)
			(xy 122.15622 -55.119524) (xy 122.20067 -55.119524)
		)
		(stroke
			(width 0)
			(type solid)
		)
		(fill yes)
		(layer "In11.Cu")
		(net "M_J_DQS_DP<7>")
	)
	(gr_poly
		(pts
			(xy 122.20067 -53.723794) (xy 122.15622 -53.723794) (xy 121.98604 -53.812694) (xy 121.98604 -54.033674)
			(xy 122.15622 -54.122574) (xy 122.20067 -54.122574)
		)
		(stroke
			(width 0)
			(type solid)
		)
		(fill yes)
		(layer "In11.Cu")
		(net "M_J_DQS_DP<7>")
	)
	(gr_poly
		(pts
			(xy 122.319796 -50.397918) (xy 122.2883 -50.366676) (xy 122.08891 -50.293016) (xy 121.927366 -50.45456)
			(xy 122.000772 -50.65395) (xy 122.032268 -50.685446)
		)
		(stroke
			(width 0)
			(type solid)
		)
		(fill yes)
		(layer "In11.Cu")
		(net "M_J_DQS_DP<16>")
	)
	(gr_poly
		(pts
			(xy 122.401838 -52.748688) (xy 122.357388 -52.748688) (xy 122.164348 -52.837588) (xy 122.164348 -53.066188)
			(xy 122.357388 -53.155088) (xy 122.401838 -53.155088)
		)
		(stroke
			(width 0)
			(type solid)
		)
		(fill yes)
		(layer "In11.Cu")
		(net "M_J_DQS_DP<7>")
	)
	(gr_poly
		(pts
			(xy 122.401838 -51.758088) (xy 122.357388 -51.758088) (xy 122.164348 -51.846988) (xy 122.164348 -52.075588)
			(xy 122.357388 -52.164488) (xy 122.401838 -52.164488)
		)
		(stroke
			(width 0)
			(type solid)
		)
		(fill yes)
		(layer "In11.Cu")
		(net "M_J_DQS_DP<7>")
	)
	(gr_poly
		(pts
			(xy 122.48515 -102.752398) (xy 122.4407 -102.752398) (xy 122.27052 -102.841298) (xy 122.27052 -103.062278)
			(xy 122.4407 -103.151178) (xy 122.48515 -103.151178)
		)
		(stroke
			(width 0)
			(type solid)
		)
		(fill yes)
		(layer "In11.Cu")
		(net "M_M_DQ<56>")
	)
	(gr_poly
		(pts
			(xy 122.48515 -101.761798) (xy 122.4407 -101.761798) (xy 122.27052 -101.850698) (xy 122.27052 -102.071678)
			(xy 122.4407 -102.160578) (xy 122.48515 -102.160578)
		)
		(stroke
			(width 0)
			(type solid)
		)
		(fill yes)
		(layer "In11.Cu")
		(net "M_M_DQ<56>")
	)
	(gr_poly
		(pts
			(xy 122.48515 -100.771198) (xy 122.4407 -100.771198) (xy 122.27052 -100.860098) (xy 122.27052 -101.081078)
			(xy 122.4407 -101.169978) (xy 122.48515 -101.169978)
		)
		(stroke
			(width 0)
			(type solid)
		)
		(fill yes)
		(layer "In11.Cu")
		(net "M_M_DQ<56>")
	)
	(gr_poly
		(pts
			(xy 122.48515 -99.780598) (xy 122.4407 -99.780598) (xy 122.27052 -99.869498) (xy 122.27052 -100.090478)
			(xy 122.4407 -100.179378) (xy 122.48515 -100.179378)
		)
		(stroke
			(width 0)
			(type solid)
		)
		(fill yes)
		(layer "In11.Cu")
		(net "M_M_DQ<56>")
	)
	(gr_poly
		(pts
			(xy 122.48515 -98.789998) (xy 122.4407 -98.789998) (xy 122.27052 -98.878898) (xy 122.27052 -99.099878)
			(xy 122.4407 -99.188778) (xy 122.48515 -99.188778)
		)
		(stroke
			(width 0)
			(type solid)
		)
		(fill yes)
		(layer "In11.Cu")
		(net "M_M_DQ<56>")
	)
	(gr_poly
		(pts
			(xy 122.48515 -97.806002) (xy 122.4407 -97.806002) (xy 122.27052 -97.894902) (xy 122.27052 -98.115882)
			(xy 122.4407 -98.204782) (xy 122.48515 -98.204782)
		)
		(stroke
			(width 0)
			(type solid)
		)
		(fill yes)
		(layer "In11.Cu")
		(net "M_M_DQ<56>")
	)
	(gr_poly
		(pts
			(xy 122.57659 -50.746406) (xy 122.503184 -50.547016) (xy 122.471688 -50.51552) (xy 122.18416 -50.803048)
			(xy 122.215656 -50.83429) (xy 122.415046 -50.90795)
		)
		(stroke
			(width 0)
			(type solid)
		)
		(fill yes)
		(layer "In11.Cu")
		(net "M_J_DQS_DN<16>")
	)
	(gr_poly
		(pts
			(xy 122.713496 -94.090744) (xy 122.721624 -93.898974) (xy 122.530362 -93.788484) (xy 122.36831 -93.891354)
			(xy 122.345958 -93.929962) (xy 122.691398 -94.129098)
		)
		(stroke
			(width 0)
			(type solid)
		)
		(fill yes)
		(layer "In11.Cu")
		(net "M_M_DQ<63>")
	)
	(gr_poly
		(pts
			(xy 122.715528 -103.997506) (xy 122.723656 -103.805736) (xy 122.532394 -103.6955) (xy 122.370342 -103.79837)
			(xy 122.348244 -103.836724) (xy 122.693684 -104.036114)
		)
		(stroke
			(width 0)
			(type solid)
		)
		(fill yes)
		(layer "In11.Cu")
		(net "M_M_DQ<61>")
	)
	(gr_poly
		(pts
			(xy 122.715528 -97.063306) (xy 122.723656 -96.871536) (xy 122.532394 -96.7613) (xy 122.370342 -96.86417)
			(xy 122.348244 -96.902524) (xy 122.693684 -97.101914)
		)
		(stroke
			(width 0)
			(type solid)
		)
		(fill yes)
		(layer "In11.Cu")
		(net "M_M_DQ<57>")
	)
	(gr_poly
		(pts
			(xy 122.715782 -96.073214) (xy 122.72391 -95.881444) (xy 122.532648 -95.770954) (xy 122.370596 -95.873824)
			(xy 122.348244 -95.912178) (xy 122.693684 -96.111822)
		)
		(stroke
			(width 0)
			(type solid)
		)
		(fill yes)
		(layer "In11.Cu")
		(net "M_M_DQS_DN<16>")
	)
	(gr_poly
		(pts
			(xy 122.715782 -93.101414) (xy 122.72391 -92.909644) (xy 122.532648 -92.799154) (xy 122.370596 -92.902024)
			(xy 122.348244 -92.940378) (xy 122.693684 -93.140022)
		)
		(stroke
			(width 0)
			(type solid)
		)
		(fill yes)
		(layer "In11.Cu")
		(net "M_M_DQ<59>")
	)
	(gr_poly
		(pts
			(xy 122.717306 -95.083376) (xy 122.725434 -94.891606) (xy 122.534172 -94.781116) (xy 122.37212 -94.883986)
			(xy 122.349768 -94.922594) (xy 122.695208 -95.12173)
		)
		(stroke
			(width 0)
			(type solid)
		)
		(fill yes)
		(layer "In11.Cu")
		(net "M_M_DQS_DP<7>")
	)
	(gr_poly
		(pts
			(xy 122.738388 -64.441324) (xy 122.738642 -64.220344) (xy 122.568208 -64.131698) (xy 122.524012 -64.131698)
			(xy 122.523758 -64.530224) (xy 122.568208 -64.530224)
		)
		(stroke
			(width 0)
			(type solid)
		)
		(fill yes)
		(layer "In11.Cu")
		(net "M_J_DQS_DN<7>")
	)
	(gr_poly
		(pts
			(xy 122.738896 -63.438278) (xy 122.738896 -63.217298) (xy 122.568716 -63.128398) (xy 122.524266 -63.128398)
			(xy 122.524266 -63.527178) (xy 122.568716 -63.527178)
		)
		(stroke
			(width 0)
			(type solid)
		)
		(fill yes)
		(layer "In11.Cu")
		(net "M_J_DQS_DN<7>")
	)
	(gr_poly
		(pts
			(xy 122.738896 -62.447678) (xy 122.738896 -62.226698) (xy 122.568716 -62.137798) (xy 122.524266 -62.137798)
			(xy 122.524266 -62.536578) (xy 122.568716 -62.536578)
		)
		(stroke
			(width 0)
			(type solid)
		)
		(fill yes)
		(layer "In11.Cu")
		(net "M_J_DQS_DN<7>")
	)
	(gr_poly
		(pts
			(xy 122.738896 -61.457078) (xy 122.738896 -61.236098) (xy 122.568716 -61.147198) (xy 122.524266 -61.147198)
			(xy 122.524266 -61.545978) (xy 122.568716 -61.545978)
		)
		(stroke
			(width 0)
			(type solid)
		)
		(fill yes)
		(layer "In11.Cu")
		(net "M_J_DQS_DN<7>")
	)
	(gr_poly
		(pts
			(xy 122.738896 -60.466478) (xy 122.738896 -60.245498) (xy 122.568716 -60.156598) (xy 122.524266 -60.156598)
			(xy 122.524266 -60.555378) (xy 122.568716 -60.555378)
		)
		(stroke
			(width 0)
			(type solid)
		)
		(fill yes)
		(layer "In11.Cu")
		(net "M_J_DQS_DN<7>")
	)
	(gr_poly
		(pts
			(xy 122.738896 -59.488324) (xy 122.738896 -59.267344) (xy 122.568716 -59.178444) (xy 122.524266 -59.178444)
			(xy 122.524266 -59.577224) (xy 122.568716 -59.577224)
		)
		(stroke
			(width 0)
			(type solid)
		)
		(fill yes)
		(layer "In11.Cu")
		(net "M_J_DQS_DN<7>")
	)
	(gr_poly
		(pts
			(xy 122.738896 -58.491628) (xy 122.738896 -58.270648) (xy 122.568716 -58.181748) (xy 122.524266 -58.181748)
			(xy 122.524266 -58.580528) (xy 122.568716 -58.580528)
		)
		(stroke
			(width 0)
			(type solid)
		)
		(fill yes)
		(layer "In11.Cu")
		(net "M_J_DQS_DN<7>")
	)
	(gr_poly
		(pts
			(xy 122.738896 -57.494678) (xy 122.738896 -57.273698) (xy 122.568716 -57.184798) (xy 122.524266 -57.184798)
			(xy 122.524266 -57.583578) (xy 122.568716 -57.583578)
		)
		(stroke
			(width 0)
			(type solid)
		)
		(fill yes)
		(layer "In11.Cu")
		(net "M_J_DQS_DN<7>")
	)
	(gr_poly
		(pts
			(xy 122.738896 -56.504078) (xy 122.738896 -56.283098) (xy 122.568716 -56.194198) (xy 122.524266 -56.194198)
			(xy 122.524266 -56.592978) (xy 122.568716 -56.592978)
		)
		(stroke
			(width 0)
			(type solid)
		)
		(fill yes)
		(layer "In11.Cu")
		(net "M_J_DQS_DN<7>")
	)
	(gr_poly
		(pts
			(xy 122.738896 -55.513478) (xy 122.738896 -55.292498) (xy 122.568716 -55.203598) (xy 122.524266 -55.203598)
			(xy 122.524266 -55.602378) (xy 122.568716 -55.602378)
		)
		(stroke
			(width 0)
			(type solid)
		)
		(fill yes)
		(layer "In11.Cu")
		(net "M_J_DQS_DN<7>")
	)
	(gr_poly
		(pts
			(xy 122.738896 -54.522878) (xy 122.738896 -54.301898) (xy 122.568716 -54.212998) (xy 122.524266 -54.212998)
			(xy 122.524266 -54.611778) (xy 122.568716 -54.611778)
		)
		(stroke
			(width 0)
			(type solid)
		)
		(fill yes)
		(layer "In11.Cu")
		(net "M_J_DQS_DN<7>")
	)
	(gr_poly
		(pts
			(xy 122.829828 -53.193188) (xy 122.829828 -52.964588) (xy 122.636788 -52.875688) (xy 122.592338 -52.875688)
			(xy 122.592338 -53.282088) (xy 122.636788 -53.282088)
		)
		(stroke
			(width 0)
			(type solid)
		)
		(fill yes)
		(layer "In11.Cu")
		(net "M_J_DQS_DN<7>")
	)
	(gr_poly
		(pts
			(xy 122.829828 -52.202588) (xy 122.829828 -51.973988) (xy 122.636788 -51.885088) (xy 122.592338 -51.885088)
			(xy 122.592338 -52.291488) (xy 122.636788 -52.291488)
		)
		(stroke
			(width 0)
			(type solid)
		)
		(fill yes)
		(layer "In11.Cu")
		(net "M_J_DQS_DN<7>")
	)
	(gr_poly
		(pts
			(xy 122.921776 -94.687136) (xy 122.944128 -94.648782) (xy 122.598688 -94.449138) (xy 122.57659 -94.487746)
			(xy 122.568462 -94.679516) (xy 122.759724 -94.790006)
		)
		(stroke
			(width 0)
			(type solid)
		)
		(fill yes)
		(layer "In11.Cu")
		(net "M_M_DQ<62>")
	)
	(gr_poly
		(pts
			(xy 122.9233 -96.669098) (xy 122.945652 -96.63049) (xy 122.600212 -96.431354) (xy 122.578114 -96.469708)
			(xy 122.569986 -96.661478) (xy 122.761248 -96.771968)
		)
		(stroke
			(width 0)
			(type solid)
		)
		(fill yes)
		(layer "In11.Cu")
		(net "M_M_DQS_DP<16>")
	)
	(gr_poly
		(pts
			(xy 122.9233 -93.697298) (xy 122.945652 -93.65869) (xy 122.600212 -93.459554) (xy 122.578114 -93.497908)
			(xy 122.569986 -93.689678) (xy 122.761248 -93.800168)
		)
		(stroke
			(width 0)
			(type solid)
		)
		(fill yes)
		(layer "In11.Cu")
		(net "M_M_DQ<58>")
	)
	(gr_poly
		(pts
			(xy 122.923554 -103.603552) (xy 122.945906 -103.565198) (xy 122.600466 -103.365554) (xy 122.578368 -103.404416)
			(xy 122.57024 -103.596186) (xy 122.761502 -103.706422)
		)
		(stroke
			(width 0)
			(type solid)
		)
		(fill yes)
		(layer "In11.Cu")
		(net "M_M_DQ<56>")
	)
	(gr_poly
		(pts
			(xy 122.925586 -95.679768) (xy 122.947938 -95.641414) (xy 122.602498 -95.44177) (xy 122.5804 -95.480378)
			(xy 122.572272 -95.672148) (xy 122.763534 -95.782638)
		)
		(stroke
			(width 0)
			(type solid)
		)
		(fill yes)
		(layer "In11.Cu")
		(net "M_M_DQS_DN<7>")
	)
	(gr_poly
		(pts
			(xy 123.023122 -98.610928) (xy 123.023122 -98.389948) (xy 122.852942 -98.301048) (xy 122.808492 -98.301048)
			(xy 122.808492 -98.699828) (xy 122.852942 -98.699828)
		)
		(stroke
			(width 0)
			(type solid)
		)
		(fill yes)
		(layer "In11.Cu")
		(net "M_M_DQ<57>")
	)
	(gr_poly
		(pts
			(xy 123.023122 -97.620328) (xy 123.023122 -97.399348) (xy 122.852942 -97.310448) (xy 122.808492 -97.310448)
			(xy 122.808492 -97.709228) (xy 122.852942 -97.709228)
		)
		(stroke
			(width 0)
			(type solid)
		)
		(fill yes)
		(layer "In11.Cu")
		(net "M_M_DQ<57>")
	)
	(gr_poly
		(pts
			(xy 123.023376 -104.560624) (xy 123.023376 -104.339644) (xy 122.853196 -104.250744) (xy 122.808746 -104.250744)
			(xy 122.808746 -104.649524) (xy 122.853196 -104.649524)
		)
		(stroke
			(width 0)
			(type solid)
		)
		(fill yes)
		(layer "In11.Cu")
		(net "M_M_DQ<61>")
	)
	(gr_poly
		(pts
			(xy 123.023376 -102.579424) (xy 123.023376 -102.358444) (xy 122.853196 -102.269544) (xy 122.808746 -102.269544)
			(xy 122.808746 -102.668324) (xy 122.853196 -102.668324)
		)
		(stroke
			(width 0)
			(type solid)
		)
		(fill yes)
		(layer "In11.Cu")
		(net "M_M_DQ<57>")
	)
	(gr_poly
		(pts
			(xy 123.023376 -101.588824) (xy 123.023376 -101.367844) (xy 122.853196 -101.278944) (xy 122.808746 -101.278944)
			(xy 122.808746 -101.677724) (xy 122.853196 -101.677724)
		)
		(stroke
			(width 0)
			(type solid)
		)
		(fill yes)
		(layer "In11.Cu")
		(net "M_M_DQ<57>")
	)
	(gr_poly
		(pts
			(xy 123.023376 -100.598224) (xy 123.023376 -100.377244) (xy 122.853196 -100.288344) (xy 122.808746 -100.288344)
			(xy 122.808746 -100.687124) (xy 122.853196 -100.687124)
		)
		(stroke
			(width 0)
			(type solid)
		)
		(fill yes)
		(layer "In11.Cu")
		(net "M_M_DQ<57>")
	)
	(gr_poly
		(pts
			(xy 123.023376 -99.607624) (xy 123.023376 -99.386644) (xy 122.853196 -99.297744) (xy 122.808746 -99.297744)
			(xy 122.808746 -99.696524) (xy 122.853196 -99.696524)
		)
		(stroke
			(width 0)
			(type solid)
		)
		(fill yes)
		(layer "In11.Cu")
		(net "M_M_DQ<57>")
	)
	(gr_poly
		(pts
			(xy 123.05919 -60.156598) (xy 123.01474 -60.156598) (xy 122.84456 -60.245498) (xy 122.84456 -60.466478)
			(xy 123.01474 -60.555378) (xy 123.05919 -60.555378)
		)
		(stroke
			(width 0)
			(type solid)
		)
		(fill yes)
		(layer "In11.Cu")
		(net "M_J_DQ<62>")
	)
	(gr_poly
		(pts
			(xy 123.05919 -59.178444) (xy 123.01474 -59.178444) (xy 122.84456 -59.267344) (xy 122.84456 -59.488324)
			(xy 123.01474 -59.577224) (xy 123.05919 -59.577224)
		)
		(stroke
			(width 0)
			(type solid)
		)
		(fill yes)
		(layer "In11.Cu")
		(net "M_J_DQ<62>")
	)
	(gr_poly
		(pts
			(xy 123.05919 -58.181748) (xy 123.01474 -58.181748) (xy 122.84456 -58.270648) (xy 122.84456 -58.491628)
			(xy 123.01474 -58.580528) (xy 123.05919 -58.580528)
		)
		(stroke
			(width 0)
			(type solid)
		)
		(fill yes)
		(layer "In11.Cu")
		(net "M_J_DQ<62>")
	)
	(gr_poly
		(pts
			(xy 123.05919 -57.184798) (xy 123.01474 -57.184798) (xy 122.84456 -57.273698) (xy 122.84456 -57.494678)
			(xy 123.01474 -57.583578) (xy 123.05919 -57.583578)
		)
		(stroke
			(width 0)
			(type solid)
		)
		(fill yes)
		(layer "In11.Cu")
		(net "M_J_DQ<62>")
	)
	(gr_poly
		(pts
			(xy 123.05919 -56.194198) (xy 123.01474 -56.194198) (xy 122.84456 -56.283098) (xy 122.84456 -56.504078)
			(xy 123.01474 -56.592978) (xy 123.05919 -56.592978)
		)
		(stroke
			(width 0)
			(type solid)
		)
		(fill yes)
		(layer "In11.Cu")
		(net "M_J_DQ<62>")
	)
	(gr_poly
		(pts
			(xy 123.05919 -55.203598) (xy 123.01474 -55.203598) (xy 122.84456 -55.292498) (xy 122.84456 -55.513478)
			(xy 123.01474 -55.602378) (xy 123.05919 -55.602378)
		)
		(stroke
			(width 0)
			(type solid)
		)
		(fill yes)
		(layer "In11.Cu")
		(net "M_J_DQ<62>")
	)
	(gr_poly
		(pts
			(xy 123.05919 -54.212998) (xy 123.01474 -54.212998) (xy 122.84456 -54.301898) (xy 122.84456 -54.522878)
			(xy 123.01474 -54.611778) (xy 123.05919 -54.611778)
		)
		(stroke
			(width 0)
			(type solid)
		)
		(fill yes)
		(layer "In11.Cu")
		(net "M_J_DQ<62>")
	)
	(gr_poly
		(pts
			(xy 123.059444 -62.144148) (xy 123.014994 -62.144148) (xy 122.844814 -62.233048) (xy 122.844814 -62.454028)
			(xy 123.014994 -62.542928) (xy 123.059444 -62.542928)
		)
		(stroke
			(width 0)
			(type solid)
		)
		(fill yes)
		(layer "In11.Cu")
		(net "M_J_DQ<62>")
	)
	(gr_poly
		(pts
			(xy 123.059444 -61.153548) (xy 123.014994 -61.153548) (xy 122.844814 -61.242448) (xy 122.844814 -61.463428)
			(xy 123.014994 -61.552328) (xy 123.059444 -61.552328)
		)
		(stroke
			(width 0)
			(type solid)
		)
		(fill yes)
		(layer "In11.Cu")
		(net "M_J_DQ<62>")
	)
	(gr_poly
		(pts
			(xy 123.059444 -53.233574) (xy 123.014994 -53.233574) (xy 122.844814 -53.322474) (xy 122.844814 -53.543454)
			(xy 123.014994 -53.632354) (xy 123.059444 -53.632354)
		)
		(stroke
			(width 0)
			(type solid)
		)
		(fill yes)
		(layer "In11.Cu")
		(net "M_J_DQ<62>")
	)
	(gr_poly
		(pts
			(xy 123.34367 -102.269544) (xy 123.29922 -102.269544) (xy 123.12904 -102.358444) (xy 123.12904 -102.579424)
			(xy 123.29922 -102.668324) (xy 123.34367 -102.668324)
		)
		(stroke
			(width 0)
			(type solid)
		)
		(fill yes)
		(layer "In11.Cu")
		(net "M_M_DQS_DP<16>")
	)
	(gr_poly
		(pts
			(xy 123.34367 -101.278944) (xy 123.29922 -101.278944) (xy 123.12904 -101.367844) (xy 123.12904 -101.588824)
			(xy 123.29922 -101.677724) (xy 123.34367 -101.677724)
		)
		(stroke
			(width 0)
			(type solid)
		)
		(fill yes)
		(layer "In11.Cu")
		(net "M_M_DQS_DP<16>")
	)
	(gr_poly
		(pts
			(xy 123.34367 -100.282248) (xy 123.29922 -100.282248) (xy 123.12904 -100.371148) (xy 123.12904 -100.592128)
			(xy 123.29922 -100.681028) (xy 123.34367 -100.681028)
		)
		(stroke
			(width 0)
			(type solid)
		)
		(fill yes)
		(layer "In11.Cu")
		(net "M_M_DQS_DP<16>")
	)
	(gr_poly
		(pts
			(xy 123.34367 -99.297744) (xy 123.29922 -99.297744) (xy 123.12904 -99.386644) (xy 123.12904 -99.607624)
			(xy 123.29922 -99.696524) (xy 123.34367 -99.696524)
		)
		(stroke
			(width 0)
			(type solid)
		)
		(fill yes)
		(layer "In11.Cu")
		(net "M_M_DQS_DP<16>")
	)
	(gr_poly
		(pts
			(xy 123.34367 -98.307144) (xy 123.29922 -98.307144) (xy 123.12904 -98.396044) (xy 123.12904 -98.617024)
			(xy 123.29922 -98.705924) (xy 123.34367 -98.705924)
		)
		(stroke
			(width 0)
			(type solid)
		)
		(fill yes)
		(layer "In11.Cu")
		(net "M_M_DQS_DP<16>")
	)
	(gr_poly
		(pts
			(xy 123.34367 -97.316544) (xy 123.29922 -97.316544) (xy 123.12904 -97.405444) (xy 123.12904 -97.626424)
			(xy 123.29922 -97.715324) (xy 123.34367 -97.715324)
		)
		(stroke
			(width 0)
			(type solid)
		)
		(fill yes)
		(layer "In11.Cu")
		(net "M_M_DQS_DP<16>")
	)
	(gr_poly
		(pts
			(xy 123.467114 -50.16627) (xy 123.393708 -49.96688) (xy 123.362212 -49.935384) (xy 123.074684 -50.222912)
			(xy 123.10618 -50.254154) (xy 123.30557 -50.327814)
		)
		(stroke
			(width 0)
			(type solid)
		)
		(fill yes)
		(layer "In11.Cu")
		(net "M_J_DQS_DN<16>")
	)
	(gr_poly
		(pts
			(xy 123.570492 -103.500174) (xy 123.57862 -103.308404) (xy 123.387104 -103.198168) (xy 123.225306 -103.301038)
			(xy 123.2027 -103.339392) (xy 123.54814 -103.539036)
		)
		(stroke
			(width 0)
			(type solid)
		)
		(fill yes)
		(layer "In11.Cu")
		(net "M_M_DQ<57>")
	)
	(gr_poly
		(pts
			(xy 123.570492 -96.565974) (xy 123.57862 -96.374204) (xy 123.387104 -96.263968) (xy 123.225306 -96.366838)
			(xy 123.2027 -96.405192) (xy 123.54814 -96.604836)
		)
		(stroke
			(width 0)
			(type solid)
		)
		(fill yes)
		(layer "In11.Cu")
		(net "M_M_DQS_DN<16>")
	)
	(gr_poly
		(pts
			(xy 123.572016 -95.576644) (xy 123.580144 -95.384874) (xy 123.388882 -95.274384) (xy 123.22683 -95.377254)
			(xy 123.204478 -95.415862) (xy 123.549918 -95.614998)
		)
		(stroke
			(width 0)
			(type solid)
		)
		(fill yes)
		(layer "In11.Cu")
		(net "M_M_DQS_DP<7>")
	)
	(gr_poly
		(pts
			(xy 123.574302 -94.587314) (xy 123.58243 -94.395544) (xy 123.391168 -94.285054) (xy 123.229116 -94.387924)
			(xy 123.206764 -94.426278) (xy 123.552204 -94.625922)
		)
		(stroke
			(width 0)
			(type solid)
		)
		(fill yes)
		(layer "In11.Cu")
		(net "M_M_DQ<63>")
	)
	(gr_poly
		(pts
			(xy 123.575826 -93.59773) (xy 123.583954 -93.40596) (xy 123.392692 -93.29547) (xy 123.23064 -93.39834)
			(xy 123.208288 -93.436694) (xy 123.553728 -93.636338)
		)
		(stroke
			(width 0)
			(type solid)
		)
		(fill yes)
		(layer "In11.Cu")
		(net "M_M_DQ<59>")
	)
	(gr_poly
		(pts
			(xy 123.597416 -62.949328) (xy 123.597416 -62.728348) (xy 123.427236 -62.639448) (xy 123.382786 -62.639448)
			(xy 123.382786 -63.038228) (xy 123.427236 -63.038228)
		)
		(stroke
			(width 0)
			(type solid)
		)
		(fill yes)
		(layer "In11.Cu")
		(net "M_J_DQ<63>")
	)
	(gr_poly
		(pts
			(xy 123.597416 -61.958728) (xy 123.597416 -61.737748) (xy 123.427236 -61.648848) (xy 123.382786 -61.648848)
			(xy 123.382786 -62.047628) (xy 123.427236 -62.047628)
		)
		(stroke
			(width 0)
			(type solid)
		)
		(fill yes)
		(layer "In11.Cu")
		(net "M_J_DQ<63>")
	)
	(gr_poly
		(pts
			(xy 123.597416 -60.974224) (xy 123.597416 -60.753244) (xy 123.427236 -60.664344) (xy 123.382786 -60.664344)
			(xy 123.382786 -61.063124) (xy 123.427236 -61.063124)
		)
		(stroke
			(width 0)
			(type solid)
		)
		(fill yes)
		(layer "In11.Cu")
		(net "M_J_DQ<63>")
	)
	(gr_poly
		(pts
			(xy 123.597416 -59.977274) (xy 123.597416 -59.756294) (xy 123.427236 -59.667394) (xy 123.382786 -59.667394)
			(xy 123.382786 -60.066174) (xy 123.427236 -60.066174)
		)
		(stroke
			(width 0)
			(type solid)
		)
		(fill yes)
		(layer "In11.Cu")
		(net "M_J_DQ<63>")
	)
	(gr_poly
		(pts
			(xy 123.597416 -58.980578) (xy 123.597416 -58.759598) (xy 123.427236 -58.670698) (xy 123.382786 -58.670698)
			(xy 123.382786 -59.069478) (xy 123.427236 -59.069478)
		)
		(stroke
			(width 0)
			(type solid)
		)
		(fill yes)
		(layer "In11.Cu")
		(net "M_J_DQ<63>")
	)
	(gr_poly
		(pts
			(xy 123.597416 -58.002424) (xy 123.597416 -57.781444) (xy 123.427236 -57.692544) (xy 123.382786 -57.692544)
			(xy 123.382786 -58.091324) (xy 123.427236 -58.091324)
		)
		(stroke
			(width 0)
			(type solid)
		)
		(fill yes)
		(layer "In11.Cu")
		(net "M_J_DQ<63>")
	)
	(gr_poly
		(pts
			(xy 123.597416 -57.011824) (xy 123.597416 -56.790844) (xy 123.427236 -56.701944) (xy 123.382786 -56.701944)
			(xy 123.382786 -57.100724) (xy 123.427236 -57.100724)
		)
		(stroke
			(width 0)
			(type solid)
		)
		(fill yes)
		(layer "In11.Cu")
		(net "M_J_DQ<63>")
	)
	(gr_poly
		(pts
			(xy 123.597416 -56.021224) (xy 123.597416 -55.800244) (xy 123.427236 -55.711344) (xy 123.382786 -55.711344)
			(xy 123.382786 -56.110124) (xy 123.427236 -56.110124)
		)
		(stroke
			(width 0)
			(type solid)
		)
		(fill yes)
		(layer "In11.Cu")
		(net "M_J_DQ<63>")
	)
	(gr_poly
		(pts
			(xy 123.597416 -55.030624) (xy 123.597416 -54.809644) (xy 123.427236 -54.720744) (xy 123.382786 -54.720744)
			(xy 123.382786 -55.119524) (xy 123.427236 -55.119524)
		)
		(stroke
			(width 0)
			(type solid)
		)
		(fill yes)
		(layer "In11.Cu")
		(net "M_J_DQ<63>")
	)
	(gr_poly
		(pts
			(xy 123.597416 -54.033674) (xy 123.597416 -53.812694) (xy 123.427236 -53.723794) (xy 123.382786 -53.723794)
			(xy 123.382786 -54.122574) (xy 123.427236 -54.122574)
		)
		(stroke
			(width 0)
			(type solid)
		)
		(fill yes)
		(layer "In11.Cu")
		(net "M_J_DQ<63>")
	)
	(gr_poly
		(pts
			(xy 123.607576 -104.008428) (xy 123.639072 -103.976932) (xy 123.356116 -103.695754) (xy 123.324874 -103.727504)
			(xy 123.267978 -103.910892) (xy 123.424696 -104.06634)
		)
		(stroke
			(width 0)
			(type solid)
		)
		(fill yes)
		(layer "In11.Cu")
		(net "M_M_DQ<56>")
	)
	(gr_poly
		(pts
			(xy 123.711716 -97.218246) (xy 123.881896 -97.129346) (xy 123.881642 -96.90862) (xy 123.711716 -96.81972)
			(xy 123.667012 -96.819466) (xy 123.667012 -97.2185)
		)
		(stroke
			(width 0)
			(type solid)
		)
		(fill yes)
		(layer "In11.Cu")
		(net "M_M_DQS_DN<16>")
	)
	(gr_poly
		(pts
			(xy 123.780296 -103.106982) (xy 123.802648 -103.068628) (xy 123.457208 -102.868984) (xy 123.43511 -102.907592)
			(xy 123.426982 -103.099362) (xy 123.618244 -103.209852)
		)
		(stroke
			(width 0)
			(type solid)
		)
		(fill yes)
		(layer "In11.Cu")
		(net "M_M_DQS_DP<16>")
	)
	(gr_poly
		(pts
			(xy 123.780296 -96.172782) (xy 123.802648 -96.134174) (xy 123.457208 -95.935038) (xy 123.43511 -95.973392)
			(xy 123.426982 -96.165162) (xy 123.618244 -96.275652)
		)
		(stroke
			(width 0)
			(type solid)
		)
		(fill yes)
		(layer "In11.Cu")
		(net "M_M_DQS_DN<7>")
	)
	(gr_poly
		(pts
			(xy 123.78182 -95.183198) (xy 123.804172 -95.14459) (xy 123.458732 -94.945454) (xy 123.436634 -94.983808)
			(xy 123.428506 -95.175578) (xy 123.619768 -95.286068)
		)
		(stroke
			(width 0)
			(type solid)
		)
		(fill yes)
		(layer "In11.Cu")
		(net "M_M_DQ<62>")
	)
	(gr_poly
		(pts
			(xy 123.784106 -94.193868) (xy 123.806458 -94.155514) (xy 123.461018 -93.95587) (xy 123.43892 -93.994478)
			(xy 123.430792 -94.186248) (xy 123.622054 -94.296738)
		)
		(stroke
			(width 0)
			(type solid)
		)
		(fill yes)
		(layer "In11.Cu")
		(net "M_M_DQ<58>")
	)
	(gr_poly
		(pts
			(xy 123.881896 -102.071678) (xy 123.881896 -101.850698) (xy 123.711716 -101.761798) (xy 123.667266 -101.761798)
			(xy 123.667266 -102.160578) (xy 123.711716 -102.160578)
		)
		(stroke
			(width 0)
			(type solid)
		)
		(fill yes)
		(layer "In11.Cu")
		(net "M_M_DQS_DN<16>")
	)
	(gr_poly
		(pts
			(xy 123.881896 -101.081078) (xy 123.881896 -100.860098) (xy 123.711716 -100.771198) (xy 123.667266 -100.771198)
			(xy 123.667266 -101.169978) (xy 123.711716 -101.169978)
		)
		(stroke
			(width 0)
			(type solid)
		)
		(fill yes)
		(layer "In11.Cu")
		(net "M_M_DQS_DN<16>")
	)
	(gr_poly
		(pts
			(xy 123.881896 -100.096828) (xy 123.881896 -99.875848) (xy 123.711716 -99.786948) (xy 123.667266 -99.786948)
			(xy 123.667266 -100.185728) (xy 123.711716 -100.185728)
		)
		(stroke
			(width 0)
			(type solid)
		)
		(fill yes)
		(layer "In11.Cu")
		(net "M_M_DQS_DN<16>")
	)
	(gr_poly
		(pts
			(xy 123.881896 -99.099878) (xy 123.881896 -98.878898) (xy 123.711716 -98.789998) (xy 123.667266 -98.789998)
			(xy 123.667266 -99.188778) (xy 123.711716 -99.188778)
		)
		(stroke
			(width 0)
			(type solid)
		)
		(fill yes)
		(layer "In11.Cu")
		(net "M_M_DQS_DN<16>")
	)
	(gr_poly
		(pts
			(xy 123.881896 -98.109278) (xy 123.881896 -97.888298) (xy 123.711716 -97.799398) (xy 123.667266 -97.799398)
			(xy 123.667266 -98.198178) (xy 123.711716 -98.198178)
		)
		(stroke
			(width 0)
			(type solid)
		)
		(fill yes)
		(layer "In11.Cu")
		(net "M_M_DQS_DN<16>")
	)
	(gr_poly
		(pts
			(xy 123.91771 -59.667394) (xy 123.87326 -59.667394) (xy 123.70308 -59.756294) (xy 123.70308 -59.977274)
			(xy 123.87326 -60.066174) (xy 123.91771 -60.066174)
		)
		(stroke
			(width 0)
			(type solid)
		)
		(fill yes)
		(layer "In11.Cu")
		(net "M_J_DQ<58>")
	)
	(gr_poly
		(pts
			(xy 123.91771 -58.670698) (xy 123.87326 -58.670698) (xy 123.70308 -58.759598) (xy 123.70308 -58.980578)
			(xy 123.87326 -59.069478) (xy 123.91771 -59.069478)
		)
		(stroke
			(width 0)
			(type solid)
		)
		(fill yes)
		(layer "In11.Cu")
		(net "M_J_DQ<58>")
	)
	(gr_poly
		(pts
			(xy 123.91771 -57.692544) (xy 123.87326 -57.692544) (xy 123.70308 -57.781444) (xy 123.70308 -58.002424)
			(xy 123.87326 -58.091324) (xy 123.91771 -58.091324)
		)
		(stroke
			(width 0)
			(type solid)
		)
		(fill yes)
		(layer "In11.Cu")
		(net "M_J_DQ<58>")
	)
	(gr_poly
		(pts
			(xy 123.91771 -56.701944) (xy 123.87326 -56.701944) (xy 123.70308 -56.790844) (xy 123.70308 -57.011824)
			(xy 123.87326 -57.100724) (xy 123.91771 -57.100724)
		)
		(stroke
			(width 0)
			(type solid)
		)
		(fill yes)
		(layer "In11.Cu")
		(net "M_J_DQ<58>")
	)
	(gr_poly
		(pts
			(xy 123.91771 -55.711344) (xy 123.87326 -55.711344) (xy 123.70308 -55.800244) (xy 123.70308 -56.021224)
			(xy 123.87326 -56.110124) (xy 123.91771 -56.110124)
		)
		(stroke
			(width 0)
			(type solid)
		)
		(fill yes)
		(layer "In11.Cu")
		(net "M_J_DQ<58>")
	)
	(gr_poly
		(pts
			(xy 123.91771 -54.720744) (xy 123.87326 -54.720744) (xy 123.70308 -54.809644) (xy 123.70308 -55.030624)
			(xy 123.87326 -55.119524) (xy 123.91771 -55.119524)
		)
		(stroke
			(width 0)
			(type solid)
		)
		(fill yes)
		(layer "In11.Cu")
		(net "M_J_DQ<58>")
	)
	(gr_poly
		(pts
			(xy 123.91771 -53.730144) (xy 123.87326 -53.730144) (xy 123.70308 -53.819044) (xy 123.70308 -54.040024)
			(xy 123.87326 -54.128924) (xy 123.91771 -54.128924)
		)
		(stroke
			(width 0)
			(type solid)
		)
		(fill yes)
		(layer "In11.Cu")
		(net "M_J_DQ<58>")
	)
	(gr_poly
		(pts
			(xy 123.92152 -62.63894) (xy 123.87707 -62.63894) (xy 123.70689 -62.72784) (xy 123.70689 -62.94882)
			(xy 123.87707 -63.03772) (xy 123.92152 -63.03772)
		)
		(stroke
			(width 0)
			(type solid)
		)
		(fill yes)
		(layer "In11.Cu")
		(net "M_J_DQ<58>")
	)
	(gr_poly
		(pts
			(xy 123.92152 -61.64834) (xy 123.87707 -61.64834) (xy 123.70689 -61.73724) (xy 123.70689 -61.95822)
			(xy 123.87707 -62.04712) (xy 123.92152 -62.04712)
		)
		(stroke
			(width 0)
			(type solid)
		)
		(fill yes)
		(layer "In11.Cu")
		(net "M_J_DQ<58>")
	)
	(gr_poly
		(pts
			(xy 123.922536 -60.664344) (xy 123.878086 -60.664344) (xy 123.707906 -60.753244) (xy 123.707906 -60.974224)
			(xy 123.878086 -61.063124) (xy 123.922536 -61.063124)
		)
		(stroke
			(width 0)
			(type solid)
		)
		(fill yes)
		(layer "In11.Cu")
		(net "M_J_DQ<58>")
	)
	(gr_poly
		(pts
			(xy 124.12091 -51.710844) (xy 124.089414 -51.679348) (xy 123.890278 -51.605688) (xy 123.72848 -51.767486)
			(xy 123.80214 -51.966622) (xy 123.833636 -51.998118)
		)
		(stroke
			(width 0)
			(type solid)
		)
		(fill yes)
		(layer "In11.Cu")
		(net "M_J_DQ<62>")
	)
	(gr_poly
		(pts
			(xy 124.142246 -104.732582) (xy 124.142246 -104.503982) (xy 123.949206 -104.415082) (xy 123.904756 -104.415082)
			(xy 123.904756 -104.821482) (xy 123.949206 -104.821482)
		)
		(stroke
			(width 0)
			(type solid)
		)
		(fill yes)
		(layer "In11.Cu")
		(net "M_M_DQ<57>")
	)
	(gr_poly
		(pts
			(xy 124.20219 -101.774244) (xy 124.15774 -101.774244) (xy 123.98756 -101.863144) (xy 123.98756 -102.084124)
			(xy 124.15774 -102.173024) (xy 124.20219 -102.173024)
		)
		(stroke
			(width 0)
			(type solid)
		)
		(fill yes)
		(layer "In11.Cu")
		(net "M_M_DQS_DN<7>")
	)
	(gr_poly
		(pts
			(xy 124.20219 -100.783644) (xy 124.15774 -100.783644) (xy 123.98756 -100.872544) (xy 123.98756 -101.093524)
			(xy 124.15774 -101.182424) (xy 124.20219 -101.182424)
		)
		(stroke
			(width 0)
			(type solid)
		)
		(fill yes)
		(layer "In11.Cu")
		(net "M_M_DQS_DN<7>")
	)
	(gr_poly
		(pts
			(xy 124.20219 -99.786948) (xy 124.15774 -99.786948) (xy 123.98756 -99.875848) (xy 123.98756 -100.096828)
			(xy 124.15774 -100.185728) (xy 124.20219 -100.185728)
		)
		(stroke
			(width 0)
			(type solid)
		)
		(fill yes)
		(layer "In11.Cu")
		(net "M_M_DQS_DN<7>")
	)
	(gr_poly
		(pts
			(xy 124.20219 -98.789998) (xy 124.15774 -98.789998) (xy 123.98756 -98.878898) (xy 123.98756 -99.099878)
			(xy 124.15774 -99.188778) (xy 124.20219 -99.188778)
		)
		(stroke
			(width 0)
			(type solid)
		)
		(fill yes)
		(layer "In11.Cu")
		(net "M_M_DQS_DN<7>")
	)
	(gr_poly
		(pts
			(xy 124.20219 -97.806256) (xy 124.15774 -97.806256) (xy 123.98756 -97.895156) (xy 123.98756 -98.116136)
			(xy 124.15774 -98.205036) (xy 124.20219 -98.205036)
		)
		(stroke
			(width 0)
			(type solid)
		)
		(fill yes)
		(layer "In11.Cu")
		(net "M_M_DQS_DN<7>")
	)
	(gr_poly
		(pts
			(xy 124.20219 -96.808798) (xy 124.15774 -96.808798) (xy 123.98756 -96.897698) (xy 123.98756 -97.118678)
			(xy 124.15774 -97.207578) (xy 124.20219 -97.207578)
		)
		(stroke
			(width 0)
			(type solid)
		)
		(fill yes)
		(layer "In11.Cu")
		(net "M_M_DQS_DN<7>")
	)
	(gr_poly
		(pts
			(xy 124.385578 -52.05349) (xy 124.311918 -51.854354) (xy 124.280422 -51.822858) (xy 123.993148 -52.110132)
			(xy 124.024644 -52.141628) (xy 124.22378 -52.215288)
		)
		(stroke
			(width 0)
			(type solid)
		)
		(fill yes)
		(layer "In11.Cu")
		(net "M_J_DQ<63>")
	)
	(gr_poly
		(pts
			(xy 124.430536 -94.090744) (xy 124.438664 -93.898974) (xy 124.247402 -93.788484) (xy 124.08535 -93.891354)
			(xy 124.062998 -93.929962) (xy 124.408438 -94.129098)
		)
		(stroke
			(width 0)
			(type solid)
		)
		(fill yes)
		(layer "In11.Cu")
		(net "M_M_DQ<59>")
	)
	(gr_poly
		(pts
			(xy 124.432568 -96.072706) (xy 124.440696 -95.880936) (xy 124.249434 -95.7707) (xy 124.087382 -95.87357)
			(xy 124.06503 -95.911924) (xy 124.41047 -96.111568)
		)
		(stroke
			(width 0)
			(type solid)
		)
		(fill yes)
		(layer "In11.Cu")
		(net "M_M_DQS_DP<7>")
	)
	(gr_poly
		(pts
			(xy 124.432822 -103.007414) (xy 124.44095 -102.815644) (xy 124.249688 -102.705154) (xy 124.087636 -102.808024)
			(xy 124.065284 -102.846378) (xy 124.410724 -103.046022)
		)
		(stroke
			(width 0)
			(type solid)
		)
		(fill yes)
		(layer "In11.Cu")
		(net "M_M_DQS_DN<16>")
	)
	(gr_poly
		(pts
			(xy 124.434346 -95.083376) (xy 124.442474 -94.891606) (xy 124.251212 -94.781116) (xy 124.08916 -94.883986)
			(xy 124.066808 -94.922594) (xy 124.412248 -95.12173)
		)
		(stroke
			(width 0)
			(type solid)
		)
		(fill yes)
		(layer "In11.Cu")
		(net "M_M_DQ<63>")
	)
	(gr_poly
		(pts
			(xy 124.455936 -60.466478) (xy 124.455936 -60.245498) (xy 124.285756 -60.156598) (xy 124.241306 -60.156598)
			(xy 124.241306 -60.555378) (xy 124.285756 -60.555378)
		)
		(stroke
			(width 0)
			(type solid)
		)
		(fill yes)
		(layer "In11.Cu")
		(net "M_J_DQ<59>")
	)
	(gr_poly
		(pts
			(xy 124.455936 -59.488324) (xy 124.455936 -59.267344) (xy 124.285756 -59.178444) (xy 124.241306 -59.178444)
			(xy 124.241306 -59.577224) (xy 124.285756 -59.577224)
		)
		(stroke
			(width 0)
			(type solid)
		)
		(fill yes)
		(layer "In11.Cu")
		(net "M_J_DQ<59>")
	)
	(gr_poly
		(pts
			(xy 124.455936 -58.491628) (xy 124.455936 -58.270648) (xy 124.285756 -58.181748) (xy 124.241306 -58.181748)
			(xy 124.241306 -58.580528) (xy 124.285756 -58.580528)
		)
		(stroke
			(width 0)
			(type solid)
		)
		(fill yes)
		(layer "In11.Cu")
		(net "M_J_DQ<59>")
	)
	(gr_poly
		(pts
			(xy 124.455936 -57.494678) (xy 124.455936 -57.273698) (xy 124.285756 -57.184798) (xy 124.241306 -57.184798)
			(xy 124.241306 -57.583578) (xy 124.285756 -57.583578)
		)
		(stroke
			(width 0)
			(type solid)
		)
		(fill yes)
		(layer "In11.Cu")
		(net "M_J_DQ<59>")
	)
	(gr_poly
		(pts
			(xy 124.455936 -56.504078) (xy 124.455936 -56.283098) (xy 124.285756 -56.194198) (xy 124.241306 -56.194198)
			(xy 124.241306 -56.592978) (xy 124.285756 -56.592978)
		)
		(stroke
			(width 0)
			(type solid)
		)
		(fill yes)
		(layer "In11.Cu")
		(net "M_J_DQ<59>")
	)
	(gr_poly
		(pts
			(xy 124.455936 -55.513478) (xy 124.455936 -55.292498) (xy 124.285756 -55.203598) (xy 124.241306 -55.203598)
			(xy 124.241306 -55.602378) (xy 124.285756 -55.602378)
		)
		(stroke
			(width 0)
			(type solid)
		)
		(fill yes)
		(layer "In11.Cu")
		(net "M_J_DQ<59>")
	)
	(gr_poly
		(pts
			(xy 124.455936 -54.522878) (xy 124.455936 -54.301898) (xy 124.285756 -54.212998) (xy 124.241306 -54.212998)
			(xy 124.241306 -54.611778) (xy 124.285756 -54.611778)
		)
		(stroke
			(width 0)
			(type solid)
		)
		(fill yes)
		(layer "In11.Cu")
		(net "M_J_DQ<59>")
	)
	(gr_poly
		(pts
			(xy 124.466096 -63.447422) (xy 124.466096 -63.226442) (xy 124.295916 -63.137542) (xy 124.251466 -63.137542)
			(xy 124.251466 -63.536322) (xy 124.295916 -63.536322)
		)
		(stroke
			(width 0)
			(type solid)
		)
		(fill yes)
		(layer "In11.Cu")
		(net "M_J_DQ<59>")
	)
	(gr_poly
		(pts
			(xy 124.466096 -62.456822) (xy 124.466096 -62.235842) (xy 124.295916 -62.146942) (xy 124.251466 -62.146942)
			(xy 124.251466 -62.545722) (xy 124.295916 -62.545722)
		)
		(stroke
			(width 0)
			(type solid)
		)
		(fill yes)
		(layer "In11.Cu")
		(net "M_J_DQ<59>")
	)
	(gr_poly
		(pts
			(xy 124.47778 -61.450982) (xy 124.47778 -61.230002) (xy 124.3076 -61.141102) (xy 124.26315 -61.141102)
			(xy 124.26315 -61.539882) (xy 124.3076 -61.539882)
		)
		(stroke
			(width 0)
			(type solid)
		)
		(fill yes)
		(layer "In11.Cu")
		(net "M_J_DQ<59>")
	)
	(gr_poly
		(pts
			(xy 124.638816 -94.687136) (xy 124.661168 -94.648782) (xy 124.315728 -94.449138) (xy 124.29363 -94.487746)
			(xy 124.285502 -94.679516) (xy 124.476764 -94.790006)
		)
		(stroke
			(width 0)
			(type solid)
		)
		(fill yes)
		(layer "In11.Cu")
		(net "M_M_DQ<58>")
	)
	(gr_poly
		(pts
			(xy 124.64034 -95.678752) (xy 124.662692 -95.640398) (xy 124.317252 -95.440754) (xy 124.295154 -95.479362)
			(xy 124.287026 -95.671132) (xy 124.478288 -95.781622)
		)
		(stroke
			(width 0)
			(type solid)
		)
		(fill yes)
		(layer "In11.Cu")
		(net "M_M_DQ<62>")
	)
	(gr_poly
		(pts
			(xy 124.640594 -102.612952) (xy 124.662692 -102.574598) (xy 124.317252 -102.375208) (xy 124.295408 -102.413816)
			(xy 124.28728 -102.605586) (xy 124.478542 -102.715822)
		)
		(stroke
			(width 0)
			(type solid)
		)
		(fill yes)
		(layer "In11.Cu")
		(net "M_M_DQS_DN<7>")
	)
	(gr_poly
		(pts
			(xy 124.740162 -98.610928) (xy 124.740162 -98.389948) (xy 124.569982 -98.301048) (xy 124.525532 -98.301048)
			(xy 124.525532 -98.699828) (xy 124.569982 -98.699828)
		)
		(stroke
			(width 0)
			(type solid)
		)
		(fill yes)
		(layer "In11.Cu")
		(net "M_M_DQS_DP<7>")
	)
	(gr_poly
		(pts
			(xy 124.740162 -97.620582) (xy 124.740162 -97.399602) (xy 124.569982 -97.310702) (xy 124.525532 -97.310702)
			(xy 124.525532 -97.709482) (xy 124.569982 -97.709482)
		)
		(stroke
			(width 0)
			(type solid)
		)
		(fill yes)
		(layer "In11.Cu")
		(net "M_M_DQS_DP<7>")
	)
	(gr_poly
		(pts
			(xy 124.740162 -96.629982) (xy 124.740162 -96.409002) (xy 124.569982 -96.320102) (xy 124.525532 -96.320102)
			(xy 124.525532 -96.718882) (xy 124.569982 -96.718882)
		)
		(stroke
			(width 0)
			(type solid)
		)
		(fill yes)
		(layer "In11.Cu")
		(net "M_M_DQS_DP<7>")
	)
	(gr_poly
		(pts
			(xy 124.740416 -101.582474) (xy 124.740416 -101.361494) (xy 124.570236 -101.272594) (xy 124.525786 -101.272594)
			(xy 124.525786 -101.671374) (xy 124.570236 -101.671374)
		)
		(stroke
			(width 0)
			(type solid)
		)
		(fill yes)
		(layer "In11.Cu")
		(net "M_M_DQS_DP<7>")
	)
	(gr_poly
		(pts
			(xy 124.740416 -100.585778) (xy 124.740416 -100.364798) (xy 124.570236 -100.275898) (xy 124.525786 -100.275898)
			(xy 124.525786 -100.674678) (xy 124.570236 -100.674678)
		)
		(stroke
			(width 0)
			(type solid)
		)
		(fill yes)
		(layer "In11.Cu")
		(net "M_M_DQS_DP<7>")
	)
	(gr_poly
		(pts
			(xy 124.740416 -99.607624) (xy 124.740416 -99.386644) (xy 124.570236 -99.297744) (xy 124.525786 -99.297744)
			(xy 124.525786 -99.696524) (xy 124.570236 -99.696524)
		)
		(stroke
			(width 0)
			(type solid)
		)
		(fill yes)
		(layer "In11.Cu")
		(net "M_M_DQS_DP<7>")
	)
	(gr_poly
		(pts
			(xy 124.922534 -52.599844) (xy 124.891038 -52.568602) (xy 124.691648 -52.494942) (xy 124.530104 -52.656486)
			(xy 124.603764 -52.855876) (xy 124.635006 -52.887372)
		)
		(stroke
			(width 0)
			(type solid)
		)
		(fill yes)
		(layer "In11.Cu")
		(net "M_J_DQ<58>")
	)
	(gr_poly
		(pts
			(xy 125.06071 -101.266498) (xy 125.01626 -101.266498) (xy 124.84608 -101.355398) (xy 124.84608 -101.576378)
			(xy 125.01626 -101.665278) (xy 125.06071 -101.665278)
		)
		(stroke
			(width 0)
			(type solid)
		)
		(fill yes)
		(layer "In11.Cu")
		(net "M_M_DQ<62>")
	)
	(gr_poly
		(pts
			(xy 125.06071 -100.275898) (xy 125.01626 -100.275898) (xy 124.84608 -100.364798) (xy 124.84608 -100.585778)
			(xy 125.01626 -100.674678) (xy 125.06071 -100.674678)
		)
		(stroke
			(width 0)
			(type solid)
		)
		(fill yes)
		(layer "In11.Cu")
		(net "M_M_DQ<62>")
	)
	(gr_poly
		(pts
			(xy 125.06071 -99.297744) (xy 125.01626 -99.297744) (xy 124.84608 -99.386644) (xy 124.84608 -99.607624)
			(xy 125.01626 -99.696524) (xy 125.06071 -99.696524)
		)
		(stroke
			(width 0)
			(type solid)
		)
		(fill yes)
		(layer "In11.Cu")
		(net "M_M_DQ<62>")
	)
	(gr_poly
		(pts
			(xy 125.06071 -98.307144) (xy 125.01626 -98.307144) (xy 124.84608 -98.396044) (xy 124.84608 -98.617024)
			(xy 125.01626 -98.705924) (xy 125.06071 -98.705924)
		)
		(stroke
			(width 0)
			(type solid)
		)
		(fill yes)
		(layer "In11.Cu")
		(net "M_M_DQ<62>")
	)
	(gr_poly
		(pts
			(xy 125.06071 -97.310956) (xy 125.01626 -97.310956) (xy 124.84608 -97.399856) (xy 124.84608 -97.620836)
			(xy 125.01626 -97.709736) (xy 125.06071 -97.709736)
		)
		(stroke
			(width 0)
			(type solid)
		)
		(fill yes)
		(layer "In11.Cu")
		(net "M_M_DQ<62>")
	)
	(gr_poly
		(pts
			(xy 125.06071 -96.313752) (xy 125.01626 -96.313752) (xy 124.84608 -96.402652) (xy 124.84608 -96.623632)
			(xy 125.01626 -96.712532) (xy 125.06071 -96.712532)
		)
		(stroke
			(width 0)
			(type solid)
		)
		(fill yes)
		(layer "In11.Cu")
		(net "M_M_DQ<62>")
	)
	(gr_poly
		(pts
			(xy 125.16231 -52.96535) (xy 125.08865 -52.766214) (xy 125.057154 -52.734718) (xy 124.76988 -53.021992)
			(xy 124.801376 -53.053488) (xy 125.000512 -53.127148)
		)
		(stroke
			(width 0)
			(type solid)
		)
		(fill yes)
		(layer "In11.Cu")
		(net "M_J_DQ<59>")
	)
	(gr_poly
		(pts
			(xy 125.291342 -94.587314) (xy 125.29947 -94.395544) (xy 125.108208 -94.285054) (xy 124.946156 -94.387924)
			(xy 124.923804 -94.426278) (xy 125.269244 -94.625922)
		)
		(stroke
			(width 0)
			(type solid)
		)
		(fill yes)
		(layer "In11.Cu")
		(net "M_M_DQ<59>")
	)
	(gr_poly
		(pts
			(xy 125.292866 -102.51313) (xy 125.300994 -102.32136) (xy 125.109732 -102.21087) (xy 124.94768 -102.31374)
			(xy 124.925328 -102.352094) (xy 125.270768 -102.551738)
		)
		(stroke
			(width 0)
			(type solid)
		)
		(fill yes)
		(layer "In11.Cu")
		(net "M_M_DQS_DP<7>")
	)
	(gr_poly
		(pts
			(xy 125.292866 -95.57893) (xy 125.300994 -95.38716) (xy 125.109732 -95.27667) (xy 124.94768 -95.37954)
			(xy 124.925582 -95.417894) (xy 125.270768 -95.617538)
		)
		(stroke
			(width 0)
			(type solid)
		)
		(fill yes)
		(layer "In11.Cu")
		(net "M_M_DQ<63>")
	)
	(gr_poly
		(pts
			(xy 125.497336 -103.106982) (xy 125.519688 -103.068628) (xy 125.174248 -102.868984) (xy 125.15215 -102.907592)
			(xy 125.144022 -103.099362) (xy 125.335284 -103.209852)
		)
		(stroke
			(width 0)
			(type solid)
		)
		(fill yes)
		(layer "In11.Cu")
		(net "M_M_DQS_DN<7>")
	)
	(gr_poly
		(pts
			(xy 125.497336 -102.116382) (xy 125.519434 -102.078028) (xy 125.174248 -101.878384) (xy 125.15215 -101.916992)
			(xy 125.144022 -102.108762) (xy 125.335284 -102.219252)
		)
		(stroke
			(width 0)
			(type solid)
		)
		(fill yes)
		(layer "In11.Cu")
		(net "M_M_DQ<62>")
	)
	(gr_poly
		(pts
			(xy 125.49886 -95.183198) (xy 125.521212 -95.14459) (xy 125.175772 -94.945454) (xy 125.153674 -94.983808)
			(xy 125.145546 -95.175578) (xy 125.336808 -95.286068)
		)
		(stroke
			(width 0)
			(type solid)
		)
		(fill yes)
		(layer "In11.Cu")
		(net "M_M_DQ<58>")
	)
	(gr_poly
		(pts
			(xy 125.598682 -98.115628) (xy 125.598682 -97.894648) (xy 125.428502 -97.805748) (xy 125.384052 -97.805748)
			(xy 125.384052 -98.204528) (xy 125.428502 -98.204528)
		)
		(stroke
			(width 0)
			(type solid)
		)
		(fill yes)
		(layer "In11.Cu")
		(net "M_M_DQ<63>")
	)
	(gr_poly
		(pts
			(xy 125.598936 -101.093524) (xy 125.598936 -100.872544) (xy 125.428756 -100.783644) (xy 125.384306 -100.783644)
			(xy 125.384306 -101.182424) (xy 125.428756 -101.182424)
		)
		(stroke
			(width 0)
			(type solid)
		)
		(fill yes)
		(layer "In11.Cu")
		(net "M_M_DQ<63>")
	)
	(gr_poly
		(pts
			(xy 125.598936 -100.096828) (xy 125.598936 -99.875848) (xy 125.428756 -99.786948) (xy 125.384306 -99.786948)
			(xy 125.384306 -100.185728) (xy 125.428756 -100.185728)
		)
		(stroke
			(width 0)
			(type solid)
		)
		(fill yes)
		(layer "In11.Cu")
		(net "M_M_DQ<63>")
	)
	(gr_poly
		(pts
			(xy 125.598936 -99.099878) (xy 125.598936 -98.878898) (xy 125.428756 -98.789998) (xy 125.384306 -98.789998)
			(xy 125.384306 -99.188778) (xy 125.428756 -99.188778)
		)
		(stroke
			(width 0)
			(type solid)
		)
		(fill yes)
		(layer "In11.Cu")
		(net "M_M_DQ<63>")
	)
	(gr_poly
		(pts
			(xy 125.598936 -97.131632) (xy 125.598936 -96.910652) (xy 125.428756 -96.821752) (xy 125.384306 -96.821752)
			(xy 125.384306 -97.220532) (xy 125.428756 -97.220532)
		)
		(stroke
			(width 0)
			(type solid)
		)
		(fill yes)
		(layer "In11.Cu")
		(net "M_M_DQ<63>")
	)
	(gr_poly
		(pts
			(xy 125.598936 -96.141032) (xy 125.598936 -95.920052) (xy 125.428756 -95.831152) (xy 125.384306 -95.831152)
			(xy 125.384306 -96.229932) (xy 125.428756 -96.229932)
		)
		(stroke
			(width 0)
			(type solid)
		)
		(fill yes)
		(layer "In11.Cu")
		(net "M_M_DQ<63>")
	)
	(gr_poly
		(pts
			(xy 125.768354 -103.290116) (xy 125.723904 -103.290116) (xy 125.530864 -103.379016) (xy 125.530864 -103.607616)
			(xy 125.723904 -103.696516) (xy 125.768354 -103.696516)
		)
		(stroke
			(width 0)
			(type solid)
		)
		(fill yes)
		(layer "In11.Cu")
		(net "M_M_DQS_DN<7>")
	)
	(gr_poly
		(pts
			(xy 125.91923 -100.777548) (xy 125.87478 -100.777548) (xy 125.7046 -100.866448) (xy 125.7046 -101.087428)
			(xy 125.87478 -101.176328) (xy 125.91923 -101.176328)
		)
		(stroke
			(width 0)
			(type solid)
		)
		(fill yes)
		(layer "In11.Cu")
		(net "M_M_DQ<58>")
	)
	(gr_poly
		(pts
			(xy 125.91923 -99.786948) (xy 125.87478 -99.786948) (xy 125.7046 -99.875848) (xy 125.7046 -100.096828)
			(xy 125.87478 -100.185728) (xy 125.91923 -100.185728)
		)
		(stroke
			(width 0)
			(type solid)
		)
		(fill yes)
		(layer "In11.Cu")
		(net "M_M_DQ<58>")
	)
	(gr_poly
		(pts
			(xy 125.91923 -97.806256) (xy 125.87478 -97.806256) (xy 125.7046 -97.895156) (xy 125.7046 -98.116136)
			(xy 125.87478 -98.205036) (xy 125.91923 -98.205036)
		)
		(stroke
			(width 0)
			(type solid)
		)
		(fill yes)
		(layer "In11.Cu")
		(net "M_M_DQ<58>")
	)
	(gr_poly
		(pts
			(xy 125.91923 -96.815656) (xy 125.87478 -96.815656) (xy 125.7046 -96.904556) (xy 125.7046 -97.125536)
			(xy 125.87478 -97.214436) (xy 125.91923 -97.214436)
		)
		(stroke
			(width 0)
			(type solid)
		)
		(fill yes)
		(layer "In11.Cu")
		(net "M_M_DQ<58>")
	)
	(gr_poly
		(pts
			(xy 125.91923 -95.818198) (xy 125.87478 -95.818198) (xy 125.7046 -95.907098) (xy 125.7046 -96.128078)
			(xy 125.87478 -96.216978) (xy 125.91923 -96.216978)
		)
		(stroke
			(width 0)
			(type solid)
		)
		(fill yes)
		(layer "In11.Cu")
		(net "M_M_DQ<58>")
	)
	(gr_poly
		(pts
			(xy 125.919484 -98.801428) (xy 125.875034 -98.801428) (xy 125.704854 -98.890328) (xy 125.704854 -99.111308)
			(xy 125.875034 -99.200208) (xy 125.919484 -99.200208)
		)
		(stroke
			(width 0)
			(type solid)
		)
		(fill yes)
		(layer "In11.Cu")
		(net "M_M_DQ<58>")
	)
	(gr_poly
		(pts
			(xy 126.002796 -103.055166) (xy 126.048008 -102.86873) (xy 125.881638 -102.723188) (xy 125.702822 -102.792784)
			(xy 125.673358 -102.826058) (xy 125.973586 -103.088948)
		)
		(stroke
			(width 0)
			(type solid)
		)
		(fill yes)
		(layer "In11.Cu")
		(net "M_M_DQS_DP<7>")
	)
	(gr_poly
		(pts
			(xy 126.00813 -103.593138) (xy 126.178056 -103.503984) (xy 126.177294 -103.283004) (xy 126.007114 -103.194612)
			(xy 125.962664 -103.194612) (xy 125.963426 -103.593646)
		)
		(stroke
			(width 0)
			(type solid)
		)
		(fill yes)
		(layer "In11.Cu")
		(net "M_M_DQS_DP<7>")
	)
	(gr_poly
		(pts
			(xy 126.151386 -102.017576) (xy 126.159514 -101.825806) (xy 125.968252 -101.715316) (xy 125.8062 -101.818186)
			(xy 125.783848 -101.856794) (xy 126.129288 -102.05593)
		)
		(stroke
			(width 0)
			(type solid)
		)
		(fill yes)
		(layer "In11.Cu")
		(net "M_M_DQ<63>")
	)
	(gr_poly
		(pts
			(xy 126.151386 -95.083376) (xy 126.159514 -94.891606) (xy 125.968252 -94.781116) (xy 125.8062 -94.883986)
			(xy 125.784102 -94.92234) (xy 126.129542 -95.12173)
		)
		(stroke
			(width 0)
			(type solid)
		)
		(fill yes)
		(layer "In11.Cu")
		(net "M_M_DQ<59>")
	)
	(gr_poly
		(pts
			(xy 126.355856 -102.611682) (xy 126.377954 -102.573328) (xy 126.032768 -102.373684) (xy 126.01067 -102.412292)
			(xy 126.002542 -102.604062) (xy 126.193804 -102.714552)
		)
		(stroke
			(width 0)
			(type solid)
		)
		(fill yes)
		(layer "In11.Cu")
		(net "M_M_DQ<62>")
	)
	(gr_poly
		(pts
			(xy 126.36119 -101.624384) (xy 126.383542 -101.58603) (xy 126.038356 -101.386386) (xy 126.016004 -101.425248)
			(xy 126.007876 -101.617018) (xy 126.199392 -101.727254)
		)
		(stroke
			(width 0)
			(type solid)
		)
		(fill yes)
		(layer "In11.Cu")
		(net "M_M_DQ<58>")
	)
	(gr_poly
		(pts
			(xy 126.457456 -100.585778) (xy 126.457456 -100.364798) (xy 126.287276 -100.275898) (xy 126.242826 -100.275898)
			(xy 126.242826 -100.674678) (xy 126.287276 -100.674678)
		)
		(stroke
			(width 0)
			(type solid)
		)
		(fill yes)
		(layer "In11.Cu")
		(net "M_M_DQ<59>")
	)
	(gr_poly
		(pts
			(xy 126.457456 -99.607624) (xy 126.457456 -99.386644) (xy 126.287276 -99.297744) (xy 126.242826 -99.297744)
			(xy 126.242826 -99.696524) (xy 126.287276 -99.696524)
		)
		(stroke
			(width 0)
			(type solid)
		)
		(fill yes)
		(layer "In11.Cu")
		(net "M_M_DQ<59>")
	)
	(gr_poly
		(pts
			(xy 126.457456 -98.611436) (xy 126.457456 -98.390456) (xy 126.287276 -98.301556) (xy 126.242826 -98.301556)
			(xy 126.242826 -98.700336) (xy 126.287276 -98.700336)
		)
		(stroke
			(width 0)
			(type solid)
		)
		(fill yes)
		(layer "In11.Cu")
		(net "M_M_DQ<59>")
	)
	(gr_poly
		(pts
			(xy 126.457456 -97.620836) (xy 126.457456 -97.399856) (xy 126.287276 -97.310956) (xy 126.242826 -97.310956)
			(xy 126.242826 -97.709736) (xy 126.287276 -97.709736)
		)
		(stroke
			(width 0)
			(type solid)
		)
		(fill yes)
		(layer "In11.Cu")
		(net "M_M_DQ<59>")
	)
	(gr_poly
		(pts
			(xy 126.457456 -96.636078) (xy 126.457456 -96.415098) (xy 126.287276 -96.326198) (xy 126.242826 -96.326198)
			(xy 126.242826 -96.724978) (xy 126.287276 -96.724978)
		)
		(stroke
			(width 0)
			(type solid)
		)
		(fill yes)
		(layer "In11.Cu")
		(net "M_M_DQ<59>")
	)
	(gr_poly
		(pts
			(xy 126.457456 -95.645478) (xy 126.457456 -95.424498) (xy 126.287276 -95.335598) (xy 126.242826 -95.335598)
			(xy 126.242826 -95.734378) (xy 126.287276 -95.734378)
		)
		(stroke
			(width 0)
			(type solid)
		)
		(fill yes)
		(layer "In11.Cu")
		(net "M_M_DQ<59>")
	)
	(gr_poly
		(pts
			(xy 126.677674 -103.05161) (xy 126.633224 -103.05161) (xy 126.440184 -103.14051) (xy 126.440184 -103.36911)
			(xy 126.633224 -103.45801) (xy 126.677674 -103.45801)
		)
		(stroke
			(width 0)
			(type solid)
		)
		(fill yes)
		(layer "In11.Cu")
		(net "M_M_DQ<62>")
	)
	(gr_poly
		(pts
			(xy 126.893066 -102.618794) (xy 126.950724 -102.435914) (xy 126.794768 -102.27945) (xy 126.611634 -102.3366)
			(xy 126.579884 -102.368096) (xy 126.86157 -102.65029)
		)
		(stroke
			(width 0)
			(type solid)
		)
		(fill yes)
		(layer "In11.Cu")
		(net "M_M_DQ<63>")
	)
	(gr_poly
		(pts
			(xy 127.008382 -101.521514) (xy 127.01651 -101.329744) (xy 126.825248 -101.219254) (xy 126.663196 -101.322124)
			(xy 126.640844 -101.360478) (xy 126.986284 -101.560122)
		)
		(stroke
			(width 0)
			(type solid)
		)
		(fill yes)
		(layer "In11.Cu")
		(net "M_M_DQ<59>")
	)
	(gr_poly
		(pts
			(xy 127.105664 -103.36911) (xy 127.105664 -103.14051) (xy 126.912624 -103.05161) (xy 126.868174 -103.05161)
			(xy 126.868174 -103.45801) (xy 126.912624 -103.45801)
		)
		(stroke
			(width 0)
			(type solid)
		)
		(fill yes)
		(layer "In11.Cu")
		(net "M_M_DQ<63>")
	)
	(gr_poly
		(pts
			(xy 127.21971 -102.119684) (xy 127.242062 -102.08133) (xy 126.896876 -101.881686) (xy 126.874524 -101.920548)
			(xy 126.866396 -102.112318) (xy 127.057912 -102.222554)
		)
		(stroke
			(width 0)
			(type solid)
		)
		(fill yes)
		(layer "In11.Cu")
		(net "M_M_DQ<58>")
	)
	(gr_poly
		(pts
			(xy 127.600202 -102.310946) (xy 127.555752 -102.310946) (xy 127.362712 -102.399846) (xy 127.362712 -102.628192)
			(xy 127.555752 -102.717092) (xy 127.600202 -102.717092)
		)
		(stroke
			(width 0)
			(type solid)
		)
		(fill yes)
		(layer "In11.Cu")
		(net "M_M_DQ<58>")
	)
	(gr_poly
		(pts
			(xy 128.028192 -102.501446) (xy 128.028192 -102.272846) (xy 127.835152 -102.183946) (xy 127.790702 -102.183946)
			(xy 127.790702 -102.590092) (xy 127.835152 -102.590092)
		)
		(stroke
			(width 0)
			(type solid)
		)
		(fill yes)
		(layer "In11.Cu")
		(net "M_M_DQ<59>")
	)
	(gr_poly
		(pts
			(xy 229.150672 -90.542364) (xy 229.061772 -90.349324) (xy 228.833172 -90.349324) (xy 228.744272 -90.542364)
			(xy 228.744272 -90.586814) (xy 229.150672 -90.586814)
		)
		(stroke
			(width 0)
			(type solid)
		)
		(fill yes)
		(layer "In11.Cu")
		(net "M_F_DQ<6>")
	)
	(gr_poly
		(pts
			(xy 229.191566 -92.116656) (xy 229.191566 -92.072206) (xy 228.785166 -92.072206) (xy 228.785166 -92.116656)
			(xy 228.874066 -92.309696) (xy 229.102666 -92.309696)
		)
		(stroke
			(width 0)
			(type solid)
		)
		(fill yes)
		(layer "In11.Cu")
		(net "M_F_DQ<3>")
	)
	(gr_poly
		(pts
			(xy 229.191566 -91.837764) (xy 229.102666 -91.644724) (xy 228.874066 -91.644724) (xy 228.785166 -91.837764)
			(xy 228.785166 -91.882214) (xy 229.191566 -91.882214)
		)
		(stroke
			(width 0)
			(type solid)
		)
		(fill yes)
		(layer "In11.Cu")
		(net "M_F_DQ<2>")
	)
	(gr_poly
		(pts
			(xy 229.226872 -90.821256) (xy 229.226872 -90.776806) (xy 228.820472 -90.776806) (xy 228.820472 -90.821256)
			(xy 228.909372 -91.014296) (xy 229.137972 -91.014296)
		)
		(stroke
			(width 0)
			(type solid)
		)
		(fill yes)
		(layer "In11.Cu")
		(net "M_F_DQ<7>")
	)
	(gr_poly
		(pts
			(xy 229.256844 -89.59723) (xy 229.257352 -89.552526) (xy 228.858318 -89.553034) (xy 228.858318 -89.59723)
			(xy 228.947218 -89.76741) (xy 229.168198 -89.76741)
		)
		(stroke
			(width 0)
			(type solid)
		)
		(fill yes)
		(layer "In11.Cu")
		(net "M_F_DQS_DP<0>")
	)
	(gr_poly
		(pts
			(xy 229.256844 -89.315798) (xy 229.168198 -89.145618) (xy 228.947218 -89.145618) (xy 228.858318 -89.315798)
			(xy 228.858318 -89.359994) (xy 229.257352 -89.360502)
		)
		(stroke
			(width 0)
			(type solid)
		)
		(fill yes)
		(layer "In11.Cu")
		(net "M_F_DQS_DN<0>")
	)
	(gr_poly
		(pts
			(xy 229.967282 -87.443056) (xy 229.967282 -87.398606) (xy 229.560882 -87.398606) (xy 229.560882 -87.443056)
			(xy 229.649782 -87.636096) (xy 229.878382 -87.636096)
		)
		(stroke
			(width 0)
			(type solid)
		)
		(fill yes)
		(layer "In11.Cu")
		(net "M_F_DQ<1>")
	)
	(gr_poly
		(pts
			(xy 230.058976 -95.076772) (xy 230.05923 -95.032322) (xy 229.652576 -95.032322) (xy 229.65283 -95.076772)
			(xy 229.74173 -95.269812) (xy 229.970076 -95.269812)
		)
		(stroke
			(width 0)
			(type solid)
		)
		(fill yes)
		(layer "In11.Cu")
		(net "M_F_DQ<9>")
	)
	(gr_poly
		(pts
			(xy 230.141272 -90.542364) (xy 230.052372 -90.349324) (xy 229.823772 -90.349324) (xy 229.734872 -90.542364)
			(xy 229.734872 -90.586814) (xy 230.141272 -90.586814)
		)
		(stroke
			(width 0)
			(type solid)
		)
		(fill yes)
		(layer "In11.Cu")
		(net "M_F_DQ<6>")
	)
	(gr_poly
		(pts
			(xy 230.182166 -92.116656) (xy 230.182166 -92.072206) (xy 229.775766 -92.072206) (xy 229.775766 -92.116656)
			(xy 229.864666 -92.309696) (xy 230.093266 -92.309696)
		)
		(stroke
			(width 0)
			(type solid)
		)
		(fill yes)
		(layer "In11.Cu")
		(net "M_F_DQ<3>")
	)
	(gr_poly
		(pts
			(xy 230.182166 -91.837764) (xy 230.093266 -91.644724) (xy 229.864666 -91.644724) (xy 229.775766 -91.837764)
			(xy 229.775766 -91.882214) (xy 230.182166 -91.882214)
		)
		(stroke
			(width 0)
			(type solid)
		)
		(fill yes)
		(layer "In11.Cu")
		(net "M_F_DQ<2>")
	)
	(gr_poly
		(pts
			(xy 230.192072 -97.468944) (xy 230.192072 -97.424494) (xy 229.785672 -97.424494) (xy 229.785672 -97.468944)
			(xy 229.874572 -97.661984) (xy 230.103172 -97.661984)
		)
		(stroke
			(width 0)
			(type solid)
		)
		(fill yes)
		(layer "In11.Cu")
		(net "M_F_DQS_DP<1>")
	)
	(gr_poly
		(pts
			(xy 230.192072 -97.189544) (xy 230.103172 -96.996504) (xy 229.874572 -96.996504) (xy 229.785672 -97.189544)
			(xy 229.785672 -97.233994) (xy 230.192072 -97.233994)
		)
		(stroke
			(width 0)
			(type solid)
		)
		(fill yes)
		(layer "In11.Cu")
		(net "M_F_DQS_DN<1>")
	)
	(gr_poly
		(pts
			(xy 230.217472 -90.821256) (xy 230.217472 -90.776806) (xy 229.811072 -90.776806) (xy 229.811072 -90.821256)
			(xy 229.899972 -91.014296) (xy 230.128572 -91.014296)
		)
		(stroke
			(width 0)
			(type solid)
		)
		(fill yes)
		(layer "In11.Cu")
		(net "M_F_DQ<7>")
	)
	(gr_poly
		(pts
			(xy 230.247444 -89.59723) (xy 230.247952 -89.552526) (xy 229.848918 -89.553034) (xy 229.848918 -89.59723)
			(xy 229.937818 -89.76741) (xy 230.158798 -89.76741)
		)
		(stroke
			(width 0)
			(type solid)
		)
		(fill yes)
		(layer "In11.Cu")
		(net "M_F_DQS_DP<0>")
	)
	(gr_poly
		(pts
			(xy 230.247444 -89.315798) (xy 230.158798 -89.145618) (xy 229.937818 -89.145618) (xy 229.848918 -89.315798)
			(xy 229.848918 -89.359994) (xy 230.247952 -89.360502)
		)
		(stroke
			(width 0)
			(type solid)
		)
		(fill yes)
		(layer "In11.Cu")
		(net "M_F_DQS_DN<0>")
	)
	(gr_poly
		(pts
			(xy 230.526844 -93.665802) (xy 230.527098 -93.621606) (xy 230.120444 -93.621606) (xy 230.120444 -93.665802)
			(xy 230.209598 -93.859096) (xy 230.437944 -93.859096)
		)
		(stroke
			(width 0)
			(type solid)
		)
		(fill yes)
		(layer "In11.Cu")
		(net "M_F_DQ<13>")
	)
	(gr_poly
		(pts
			(xy 230.830882 -87.443056) (xy 230.830882 -87.398606) (xy 230.424482 -87.398606) (xy 230.424482 -87.443056)
			(xy 230.513382 -87.636096) (xy 230.741982 -87.636096)
		)
		(stroke
			(width 0)
			(type solid)
		)
		(fill yes)
		(layer "In11.Cu")
		(net "M_F_DQ<1>")
	)
	(gr_poly
		(pts
			(xy 230.830882 -87.164164) (xy 230.741982 -86.971124) (xy 230.513382 -86.971124) (xy 230.424482 -87.164164)
			(xy 230.424482 -87.208614) (xy 230.830882 -87.208614)
		)
		(stroke
			(width 0)
			(type solid)
		)
		(fill yes)
		(layer "In11.Cu")
		(net "M_F_DQ<0>")
	)
	(gr_poly
		(pts
			(xy 230.846884 -98.974656) (xy 230.846884 -98.930206) (xy 230.440484 -98.930206) (xy 230.440484 -98.974656)
			(xy 230.529384 -99.167696) (xy 230.757984 -99.167696)
		)
		(stroke
			(width 0)
			(type solid)
		)
		(fill yes)
		(layer "In11.Cu")
		(net "M_F_DQ<15>")
	)
	(gr_poly
		(pts
			(xy 230.846884 -98.695764) (xy 230.757984 -98.502724) (xy 230.529384 -98.502724) (xy 230.440484 -98.695764)
			(xy 230.440484 -98.740214) (xy 230.846884 -98.740214)
		)
		(stroke
			(width 0)
			(type solid)
		)
		(fill yes)
		(layer "In11.Cu")
		(net "M_F_DQ<14>")
	)
	(gr_poly
		(pts
			(xy 230.97109 -94.387416) (xy 230.939594 -94.356174) (xy 230.740204 -94.282514) (xy 230.57866 -94.444058)
			(xy 230.65232 -94.643448) (xy 230.683562 -94.674944)
		)
		(stroke
			(width 0)
			(type solid)
		)
		(fill yes)
		(layer "In11.Cu")
		(net "M_F_DQ<8>")
	)
	(gr_poly
		(pts
			(xy 231.030526 -58.368184) (xy 230.941626 -58.175144) (xy 230.713026 -58.175144) (xy 230.624126 -58.368184)
			(xy 230.624126 -58.412634) (xy 231.030526 -58.412634)
		)
		(stroke
			(width 0)
			(type solid)
		)
		(fill yes)
		(layer "In11.Cu")
		(net "M_C_DQ<9>")
	)
	(gr_poly
		(pts
			(xy 231.034082 -58.647584) (xy 231.034082 -58.603134) (xy 230.627936 -58.603134) (xy 230.627936 -58.647584)
			(xy 230.716582 -58.840624) (xy 230.945436 -58.840624)
		)
		(stroke
			(width 0)
			(type solid)
		)
		(fill yes)
		(layer "In11.Cu")
		(net "M_C_DQ<8>")
	)
	(gr_poly
		(pts
			(xy 231.090978 -95.32366) (xy 231.059482 -95.292164) (xy 230.860346 -95.218504) (xy 230.698548 -95.380302)
			(xy 230.772208 -95.579438) (xy 230.803704 -95.610934)
		)
		(stroke
			(width 0)
			(type solid)
		)
		(fill yes)
		(layer "In11.Cu")
		(net "M_F_DQS_DP<10>")
	)
	(gr_poly
		(pts
			(xy 231.125014 -86.26983) (xy 231.212898 -86.099142) (xy 231.212898 -86.054692) (xy 230.814118 -86.056978)
			(xy 230.814372 -86.101174) (xy 230.904034 -86.270846)
		)
		(stroke
			(width 0)
			(type solid)
		)
		(fill yes)
		(layer "In11.Cu")
		(net "M_F_DQ<5>")
	)
	(gr_poly
		(pts
			(xy 231.131872 -90.542364) (xy 231.042972 -90.349324) (xy 230.814372 -90.349324) (xy 230.725472 -90.542364)
			(xy 230.725472 -90.586814) (xy 231.131872 -90.586814)
		)
		(stroke
			(width 0)
			(type solid)
		)
		(fill yes)
		(layer "In11.Cu")
		(net "M_F_DQ<6>")
	)
	(gr_poly
		(pts
			(xy 231.172766 -92.116656) (xy 231.172766 -92.072206) (xy 230.766366 -92.072206) (xy 230.766366 -92.116656)
			(xy 230.855266 -92.309696) (xy 231.083866 -92.309696)
		)
		(stroke
			(width 0)
			(type solid)
		)
		(fill yes)
		(layer "In11.Cu")
		(net "M_F_DQ<3>")
	)
	(gr_poly
		(pts
			(xy 231.172766 -91.837764) (xy 231.083866 -91.644724) (xy 230.855266 -91.644724) (xy 230.766366 -91.837764)
			(xy 230.766366 -91.882214) (xy 231.172766 -91.882214)
		)
		(stroke
			(width 0)
			(type solid)
		)
		(fill yes)
		(layer "In11.Cu")
		(net "M_F_DQ<2>")
	)
	(gr_poly
		(pts
			(xy 231.17683 -93.078808) (xy 231.145334 -93.047566) (xy 230.945944 -92.973906) (xy 230.7844 -93.13545)
			(xy 230.85806 -93.33484) (xy 230.889302 -93.366336)
		)
		(stroke
			(width 0)
			(type solid)
		)
		(fill yes)
		(layer "In11.Cu")
		(net "M_F_DQ<12>")
	)
	(gr_poly
		(pts
			(xy 231.182672 -97.468944) (xy 231.182672 -97.424494) (xy 230.776272 -97.424494) (xy 230.776272 -97.468944)
			(xy 230.865172 -97.661984) (xy 231.093772 -97.661984)
		)
		(stroke
			(width 0)
			(type solid)
		)
		(fill yes)
		(layer "In11.Cu")
		(net "M_F_DQS_DP<1>")
	)
	(gr_poly
		(pts
			(xy 231.182672 -97.189544) (xy 231.093772 -96.996504) (xy 230.865172 -96.996504) (xy 230.776272 -97.189544)
			(xy 230.776272 -97.233994) (xy 231.182672 -97.233994)
		)
		(stroke
			(width 0)
			(type solid)
		)
		(fill yes)
		(layer "In11.Cu")
		(net "M_F_DQS_DN<1>")
	)
	(gr_poly
		(pts
			(xy 231.208072 -90.821256) (xy 231.208072 -90.776806) (xy 230.801672 -90.776806) (xy 230.801672 -90.821256)
			(xy 230.890572 -91.014296) (xy 231.119172 -91.014296)
		)
		(stroke
			(width 0)
			(type solid)
		)
		(fill yes)
		(layer "In11.Cu")
		(net "M_F_DQ<7>")
	)
	(gr_poly
		(pts
			(xy 231.210358 -94.752668) (xy 231.136698 -94.553278) (xy 231.105456 -94.521782) (xy 230.817928 -94.80931)
			(xy 230.849424 -94.840552) (xy 231.048814 -94.914212)
		)
		(stroke
			(width 0)
			(type solid)
		)
		(fill yes)
		(layer "In11.Cu")
		(net "M_F_DQ<9>")
	)
	(gr_poly
		(pts
			(xy 231.238044 -89.59723) (xy 231.238552 -89.552526) (xy 230.839518 -89.553034) (xy 230.839518 -89.59723)
			(xy 230.928418 -89.76741) (xy 231.149398 -89.76741)
		)
		(stroke
			(width 0)
			(type solid)
		)
		(fill yes)
		(layer "In11.Cu")
		(net "M_F_DQS_DP<0>")
	)
	(gr_poly
		(pts
			(xy 231.238044 -89.315798) (xy 231.149398 -89.145618) (xy 230.928418 -89.145618) (xy 230.839518 -89.315798)
			(xy 230.839518 -89.359994) (xy 231.238552 -89.360502)
		)
		(stroke
			(width 0)
			(type solid)
		)
		(fill yes)
		(layer "In11.Cu")
		(net "M_F_DQS_DN<0>")
	)
	(gr_poly
		(pts
			(xy 231.330754 -95.689166) (xy 231.257094 -95.489776) (xy 231.225852 -95.45828) (xy 230.938324 -95.745808)
			(xy 230.96982 -95.77705) (xy 231.16921 -95.85071)
		)
		(stroke
			(width 0)
			(type solid)
		)
		(fill yes)
		(layer "In11.Cu")
		(net "M_F_DQS_DN<10>")
	)
	(gr_poly
		(pts
			(xy 231.416098 -93.44406) (xy 231.342438 -93.24467) (xy 231.311196 -93.213174) (xy 231.023668 -93.500702)
			(xy 231.055164 -93.531944) (xy 231.254554 -93.605604)
		)
		(stroke
			(width 0)
			(type solid)
		)
		(fill yes)
		(layer "In11.Cu")
		(net "M_F_DQ<13>")
	)
	(gr_poly
		(pts
			(xy 231.426004 -96.400366) (xy 231.381554 -96.400366) (xy 231.188514 -96.489266) (xy 231.188514 -96.717866)
			(xy 231.381554 -96.806766) (xy 231.426004 -96.806766)
		)
		(stroke
			(width 0)
			(type solid)
		)
		(fill yes)
		(layer "In11.Cu")
		(net "M_F_DQS_DN<1>")
	)
	(gr_poly
		(pts
			(xy 231.44353 -88.610186) (xy 231.44353 -88.565736) (xy 231.03713 -88.565736) (xy 231.03713 -88.610186)
			(xy 231.12603 -88.803226) (xy 231.35463 -88.803226)
		)
		(stroke
			(width 0)
			(type solid)
		)
		(fill yes)
		(layer "In11.Cu")
		(net "M_F_DQS_DN<9>")
	)
	(gr_poly
		(pts
			(xy 231.44353 -88.330786) (xy 231.35463 -88.137746) (xy 231.12603 -88.137746) (xy 231.03713 -88.330786)
			(xy 231.03713 -88.375236) (xy 231.44353 -88.375236)
		)
		(stroke
			(width 0)
			(type solid)
		)
		(fill yes)
		(layer "In11.Cu")
		(net "M_F_DQS_DP<9>")
	)
	(gr_poly
		(pts
			(xy 231.487218 -87.780114) (xy 231.518714 -87.748618) (xy 231.23144 -87.46109) (xy 231.199944 -87.492586)
			(xy 231.126284 -87.691976) (xy 231.288082 -87.85352)
		)
		(stroke
			(width 0)
			(type solid)
		)
		(fill yes)
		(layer "In11.Cu")
		(net "M_F_DQ<1>")
	)
	(gr_poly
		(pts
			(xy 231.660446 -57.21604) (xy 231.660446 -57.17159) (xy 231.254046 -57.17159) (xy 231.254046 -57.21604)
			(xy 231.342946 -57.40908) (xy 231.571546 -57.40908)
		)
		(stroke
			(width 0)
			(type solid)
		)
		(fill yes)
		(layer "In11.Cu")
		(net "M_C_DQS_DP<10>")
	)
	(gr_poly
		(pts
			(xy 231.660446 -56.93664) (xy 231.571546 -56.7436) (xy 231.342946 -56.7436) (xy 231.254046 -56.93664)
			(xy 231.254046 -56.98109) (xy 231.660446 -56.98109)
		)
		(stroke
			(width 0)
			(type solid)
		)
		(fill yes)
		(layer "In11.Cu")
		(net "M_C_DQS_DN<10>")
	)
	(gr_poly
		(pts
			(xy 231.670352 -56.201564) (xy 231.670352 -56.157114) (xy 231.263952 -56.157114) (xy 231.263952 -56.201564)
			(xy 231.352852 -56.394604) (xy 231.581452 -56.394604)
		)
		(stroke
			(width 0)
			(type solid)
		)
		(fill yes)
		(layer "In11.Cu")
		(net "M_C_DQS_DP<1>")
	)
	(gr_poly
		(pts
			(xy 231.670352 -55.922164) (xy 231.581452 -55.729124) (xy 231.352852 -55.729124) (xy 231.263952 -55.922164)
			(xy 231.263952 -55.966614) (xy 231.670352 -55.966614)
		)
		(stroke
			(width 0)
			(type solid)
		)
		(fill yes)
		(layer "In11.Cu")
		(net "M_C_DQS_DN<1>")
	)
	(gr_poly
		(pts
			(xy 231.671622 -93.686884) (xy 231.640126 -93.655642) (xy 231.440736 -93.581982) (xy 231.279192 -93.743526)
			(xy 231.352852 -93.942916) (xy 231.384094 -93.974412)
		)
		(stroke
			(width 0)
			(type solid)
		)
		(fill yes)
		(layer "In11.Cu")
		(net "M_F_DQ<8>")
	)
	(gr_poly
		(pts
			(xy 231.684576 -87.582756) (xy 231.758236 -87.383366) (xy 231.596438 -87.221822) (xy 231.397048 -87.295482)
			(xy 231.365806 -87.326978) (xy 231.65308 -87.614252)
		)
		(stroke
			(width 0)
			(type solid)
		)
		(fill yes)
		(layer "In11.Cu")
		(net "M_F_DQ<0>")
	)
	(gr_poly
		(pts
			(xy 231.72166 -86.132924) (xy 231.77881 -85.94979) (xy 231.6226 -85.793834) (xy 231.439466 -85.851238)
			(xy 231.40797 -85.882734) (xy 231.690418 -86.16442)
		)
		(stroke
			(width 0)
			(type solid)
		)
		(fill yes)
		(layer "In11.Cu")
		(net "M_F_DQ<4>")
	)
	(gr_poly
		(pts
			(xy 231.79151 -94.623128) (xy 231.760014 -94.591632) (xy 231.560624 -94.517972) (xy 231.39908 -94.67977)
			(xy 231.47274 -94.87916) (xy 231.504236 -94.910402)
		)
		(stroke
			(width 0)
			(type solid)
		)
		(fill yes)
		(layer "In11.Cu")
		(net "M_F_DQS_DP<10>")
	)
	(gr_poly
		(pts
			(xy 231.808782 -86.913974) (xy 231.840278 -86.882478) (xy 231.55656 -86.602062) (xy 231.525572 -86.633558)
			(xy 231.46893 -86.816946) (xy 231.625902 -86.972394)
		)
		(stroke
			(width 0)
			(type solid)
		)
		(fill yes)
		(layer "In11.Cu")
		(net "M_F_DQ<5>")
	)
	(gr_poly
		(pts
			(xy 231.812592 -65.14084) (xy 231.812592 -65.09639) (xy 231.406192 -65.09639) (xy 231.406192 -65.14084)
			(xy 231.495092 -65.33388) (xy 231.723692 -65.33388)
		)
		(stroke
			(width 0)
			(type solid)
		)
		(fill yes)
		(layer "In11.Cu")
		(net "M_C_DQS_DP<9>")
	)
	(gr_poly
		(pts
			(xy 231.812592 -64.86144) (xy 231.723692 -64.6684) (xy 231.495092 -64.6684) (xy 231.406192 -64.86144)
			(xy 231.406192 -64.90589) (xy 231.812592 -64.90589)
		)
		(stroke
			(width 0)
			(type solid)
		)
		(fill yes)
		(layer "In11.Cu")
		(net "M_C_DQS_DN<9>")
	)
	(gr_poly
		(pts
			(xy 231.837484 -98.974656) (xy 231.837484 -98.930206) (xy 231.431084 -98.930206) (xy 231.431084 -98.974656)
			(xy 231.519984 -99.167696) (xy 231.748584 -99.167696)
		)
		(stroke
			(width 0)
			(type solid)
		)
		(fill yes)
		(layer "In11.Cu")
		(net "M_F_DQ<15>")
	)
	(gr_poly
		(pts
			(xy 231.837484 -98.695764) (xy 231.748584 -98.502724) (xy 231.519984 -98.502724) (xy 231.431084 -98.695764)
			(xy 231.431084 -98.740214) (xy 231.837484 -98.740214)
		)
		(stroke
			(width 0)
			(type solid)
		)
		(fill yes)
		(layer "In11.Cu")
		(net "M_F_DQ<14>")
	)
	(gr_poly
		(pts
			(xy 231.850692 -60.011056) (xy 231.850692 -59.966606) (xy 231.444292 -59.966606) (xy 231.444292 -60.011056)
			(xy 231.533192 -60.204096) (xy 231.761792 -60.204096)
		)
		(stroke
			(width 0)
			(type solid)
		)
		(fill yes)
		(layer "In11.Cu")
		(net "M_C_DQ<12>")
	)
	(gr_poly
		(pts
			(xy 231.850692 -59.732164) (xy 231.761792 -59.539124) (xy 231.533192 -59.539124) (xy 231.444292 -59.732164)
			(xy 231.444292 -59.776614) (xy 231.850692 -59.776614)
		)
		(stroke
			(width 0)
			(type solid)
		)
		(fill yes)
		(layer "In11.Cu")
		(net "M_C_DQ<13>")
	)
	(gr_poly
		(pts
			(xy 231.853994 -96.717866) (xy 231.853994 -96.489266) (xy 231.660954 -96.400366) (xy 231.616504 -96.400366)
			(xy 231.616504 -96.806766) (xy 231.660954 -96.806766)
		)
		(stroke
			(width 0)
			(type solid)
		)
		(fill yes)
		(layer "In11.Cu")
		(net "M_F_DQS_DP<1>")
	)
	(gr_poly
		(pts
			(xy 231.877362 -92.378276) (xy 231.845866 -92.347034) (xy 231.646476 -92.273374) (xy 231.484932 -92.434918)
			(xy 231.558592 -92.634308) (xy 231.589834 -92.665804)
		)
		(stroke
			(width 0)
			(type solid)
		)
		(fill yes)
		(layer "In11.Cu")
		(net "M_F_DQ<12>")
	)
	(gr_poly
		(pts
			(xy 231.91089 -94.052136) (xy 231.83723 -93.852746) (xy 231.805988 -93.82125) (xy 231.51846 -94.108778)
			(xy 231.549956 -94.14002) (xy 231.749346 -94.21368)
		)
		(stroke
			(width 0)
			(type solid)
		)
		(fill yes)
		(layer "In11.Cu")
		(net "M_F_DQ<9>")
	)
	(gr_poly
		(pts
			(xy 232.021126 -58.368184) (xy 231.932226 -58.175144) (xy 231.703626 -58.175144) (xy 231.614726 -58.368184)
			(xy 231.614726 -58.412634) (xy 232.021126 -58.412634)
		)
		(stroke
			(width 0)
			(type solid)
		)
		(fill yes)
		(layer "In11.Cu")
		(net "M_C_DQ<9>")
	)
	(gr_poly
		(pts
			(xy 232.024682 -58.647584) (xy 232.024682 -58.603134) (xy 231.618536 -58.603134) (xy 231.618536 -58.647584)
			(xy 231.707182 -58.840624) (xy 231.936036 -58.840624)
		)
		(stroke
			(width 0)
			(type solid)
		)
		(fill yes)
		(layer "In11.Cu")
		(net "M_C_DQ<8>")
	)
	(gr_poly
		(pts
			(xy 232.031286 -94.988634) (xy 231.957626 -94.789244) (xy 231.92613 -94.758002) (xy 231.638856 -95.045276)
			(xy 231.670352 -95.076772) (xy 231.869742 -95.150432)
		)
		(stroke
			(width 0)
			(type solid)
		)
		(fill yes)
		(layer "In11.Cu")
		(net "M_F_DQS_DN<10>")
	)
	(gr_poly
		(pts
			(xy 232.113582 -95.43669) (xy 232.081832 -95.405448) (xy 231.882188 -95.332804) (xy 231.721406 -95.49511)
			(xy 231.795828 -95.693992) (xy 231.827324 -95.725488)
		)
		(stroke
			(width 0)
			(type solid)
		)
		(fill yes)
		(layer "In11.Cu")
		(net "M_F_DQS_DN<1>")
	)
	(gr_poly
		(pts
			(xy 232.11663 -92.743528) (xy 232.04297 -92.544138) (xy 232.011728 -92.512642) (xy 231.7242 -92.80017)
			(xy 231.755696 -92.831412) (xy 231.955086 -92.905072)
		)
		(stroke
			(width 0)
			(type solid)
		)
		(fill yes)
		(layer "In11.Cu")
		(net "M_F_DQ<13>")
	)
	(gr_poly
		(pts
			(xy 232.2703 -93.088206) (xy 232.239058 -93.05671) (xy 232.039668 -92.98305) (xy 231.87787 -93.144594)
			(xy 231.95153 -93.343984) (xy 231.983026 -93.37548)
		)
		(stroke
			(width 0)
			(type solid)
		)
		(fill yes)
		(layer "In11.Cu")
		(net "M_F_DQ<8>")
	)
	(gr_poly
		(pts
			(xy 232.290366 -91.664536) (xy 232.290366 -91.620086) (xy 231.883966 -91.620086) (xy 231.883966 -91.664536)
			(xy 231.972866 -91.857576) (xy 232.201466 -91.857576)
		)
		(stroke
			(width 0)
			(type solid)
		)
		(fill yes)
		(layer "In11.Cu")
		(net "M_F_DQ<3>")
	)
	(gr_poly
		(pts
			(xy 232.290366 -91.385644) (xy 232.201466 -91.192604) (xy 231.972866 -91.192604) (xy 231.883966 -91.385644)
			(xy 231.883966 -91.430094) (xy 232.290366 -91.430094)
		)
		(stroke
			(width 0)
			(type solid)
		)
		(fill yes)
		(layer "In11.Cu")
		(net "M_F_DQ<2>")
	)
	(gr_poly
		(pts
			(xy 232.297224 -97.980754) (xy 232.252774 -97.980754) (xy 232.059734 -98.069654) (xy 232.059734 -98.298254)
			(xy 232.252774 -98.387154) (xy 232.297224 -98.387154)
		)
		(stroke
			(width 0)
			(type solid)
		)
		(fill yes)
		(layer "In11.Cu")
		(net "M_F_DQ<14>")
	)
	(gr_poly
		(pts
			(xy 232.297224 -96.990154) (xy 232.252774 -96.990154) (xy 232.059734 -97.079054) (xy 232.059734 -97.307654)
			(xy 232.252774 -97.396554) (xy 232.297224 -97.396554)
		)
		(stroke
			(width 0)
			(type solid)
		)
		(fill yes)
		(layer "In11.Cu")
		(net "M_F_DQ<14>")
	)
	(gr_poly
		(pts
			(xy 232.354882 -95.80118) (xy 232.28046 -95.602298) (xy 232.248964 -95.570802) (xy 231.962706 -95.8596)
			(xy 231.994202 -95.890842) (xy 232.1941 -95.963486)
		)
		(stroke
			(width 0)
			(type solid)
		)
		(fill yes)
		(layer "In11.Cu")
		(net "M_F_DQS_DP<1>")
	)
	(gr_poly
		(pts
			(xy 232.36174 -100.346002) (xy 232.36174 -100.301552) (xy 231.95534 -100.301552) (xy 231.95534 -100.346002)
			(xy 232.04424 -100.539042) (xy 232.27284 -100.539042)
		)
		(stroke
			(width 0)
			(type solid)
		)
		(fill yes)
		(layer "In11.Cu")
		(net "M_F_DQ<11>")
	)
	(gr_poly
		(pts
			(xy 232.36174 -100.06711) (xy 232.27284 -99.87407) (xy 232.04424 -99.87407) (xy 231.95534 -100.06711)
			(xy 231.95534 -100.11156) (xy 232.36174 -100.11156)
		)
		(stroke
			(width 0)
			(type solid)
		)
		(fill yes)
		(layer "In11.Cu")
		(net "M_F_DQ<10>")
	)
	(gr_poly
		(pts
			(xy 232.509822 -93.453204) (xy 232.436162 -93.253814) (xy 232.404666 -93.222572) (xy 232.117392 -93.509846)
			(xy 232.148888 -93.541342) (xy 232.348278 -93.615002)
		)
		(stroke
			(width 0)
			(type solid)
		)
		(fill yes)
		(layer "In11.Cu")
		(net "M_F_DQ<9>")
	)
	(gr_poly
		(pts
			(xy 232.559606 -54.168548) (xy 232.591102 -54.137052) (xy 232.303828 -53.849778) (xy 232.272332 -53.881274)
			(xy 232.198672 -54.08041) (xy 232.36047 -54.242208)
		)
		(stroke
			(width 0)
			(type solid)
		)
		(fill yes)
		(layer "In11.Cu")
		(net "M_C_DQ<10>")
	)
	(gr_poly
		(pts
			(xy 232.656888 -96.04375) (xy 232.625392 -96.012508) (xy 232.426002 -95.938848) (xy 232.264458 -96.100392)
			(xy 232.338118 -96.299782) (xy 232.36936 -96.331278)
		)
		(stroke
			(width 0)
			(type solid)
		)
		(fill yes)
		(layer "In11.Cu")
		(net "M_F_DQ<14>")
	)
	(gr_poly
		(pts
			(xy 232.66273 -62.173358) (xy 232.651554 -61.981588) (xy 232.62844 -61.943488) (xy 232.28681 -62.149228)
			(xy 232.30967 -62.187328) (xy 232.4735 -62.28715)
		)
		(stroke
			(width 0)
			(type solid)
		)
		(fill yes)
		(layer "In11.Cu")
		(net "M_C_DQ<2>")
	)
	(gr_poly
		(pts
			(xy 232.678224 -94.225364) (xy 232.589324 -94.032324) (xy 232.360724 -94.032324) (xy 232.271824 -94.225364)
			(xy 232.271824 -94.269814) (xy 232.678224 -94.269814)
		)
		(stroke
			(width 0)
			(type solid)
		)
		(fill yes)
		(layer "In11.Cu")
		(net "M_F_DQS_DP<10>")
	)
	(gr_poly
		(pts
			(xy 232.682542 -89.909396) (xy 232.674414 -89.717626) (xy 232.652316 -89.679018) (xy 232.306876 -89.878662)
			(xy 232.329228 -89.917016) (xy 232.49128 -90.019886)
		)
		(stroke
			(width 0)
			(type solid)
		)
		(fill yes)
		(layer "In11.Cu")
		(net "M_F_DQS_DP<0>")
	)
	(gr_poly
		(pts
			(xy 232.682542 -88.918796) (xy 232.674414 -88.727026) (xy 232.652316 -88.688418) (xy 232.306876 -88.888062)
			(xy 232.329228 -88.926416) (xy 232.49128 -89.029286)
		)
		(stroke
			(width 0)
			(type solid)
		)
		(fill yes)
		(layer "In11.Cu")
		(net "M_F_DQS_DN<9>")
	)
	(gr_poly
		(pts
			(xy 232.682542 -65.144396) (xy 232.674414 -64.952626) (xy 232.652316 -64.914018) (xy 232.306876 -65.113408)
			(xy 232.329228 -65.152016) (xy 232.49128 -65.254886)
		)
		(stroke
			(width 0)
			(type solid)
		)
		(fill yes)
		(layer "In11.Cu")
		(net "M_C_DQS_DP<9>")
	)
	(gr_poly
		(pts
			(xy 232.682542 -64.153796) (xy 232.674414 -63.962026) (xy 232.652316 -63.923418) (xy 232.306876 -64.122808)
			(xy 232.329228 -64.161416) (xy 232.49128 -64.264286)
		)
		(stroke
			(width 0)
			(type solid)
		)
		(fill yes)
		(layer "In11.Cu")
		(net "M_C_DQS_DP<0>")
	)
	(gr_poly
		(pts
			(xy 232.68432 -87.92718) (xy 232.676192 -87.73541) (xy 232.654094 -87.696802) (xy 232.308654 -87.896446)
			(xy 232.331006 -87.9348) (xy 232.493058 -88.03767)
		)
		(stroke
			(width 0)
			(type solid)
		)
		(fill yes)
		(layer "In11.Cu")
		(net "M_F_DQ<1>")
	)
	(gr_poly
		(pts
			(xy 232.68432 -86.93658) (xy 232.676192 -86.74481) (xy 232.654094 -86.706202) (xy 232.308654 -86.905846)
			(xy 232.331006 -86.9442) (xy 232.493058 -87.04707)
		)
		(stroke
			(width 0)
			(type solid)
		)
		(fill yes)
		(layer "In11.Cu")
		(net "M_F_DQ<5>")
	)
	(gr_poly
		(pts
			(xy 232.68432 -67.12458) (xy 232.676192 -66.93281) (xy 232.654094 -66.894456) (xy 232.308654 -67.093592)
			(xy 232.331006 -67.1322) (xy 232.493058 -67.23507)
		)
		(stroke
			(width 0)
			(type solid)
		)
		(fill yes)
		(layer "In11.Cu")
		(net "M_C_DQ<4>")
	)
	(gr_poly
		(pts
			(xy 232.68432 -66.13398) (xy 232.676192 -65.94221) (xy 232.654094 -65.903602) (xy 232.308654 -66.102992)
			(xy 232.331006 -66.1416) (xy 232.493058 -66.24447)
		)
		(stroke
			(width 0)
			(type solid)
		)
		(fill yes)
		(layer "In11.Cu")
		(net "M_C_DQ<0>")
	)
	(gr_poly
		(pts
			(xy 232.68432 -63.16218) (xy 232.676192 -62.97041) (xy 232.654094 -62.931802) (xy 232.308654 -63.131192)
			(xy 232.331006 -63.1698) (xy 232.493058 -63.27267)
		)
		(stroke
			(width 0)
			(type solid)
		)
		(fill yes)
		(layer "In11.Cu")
		(net "M_C_DQ<6>")
	)
	(gr_poly
		(pts
			(xy 232.686352 -55.380128) (xy 232.717848 -55.348632) (xy 232.430574 -55.061358) (xy 232.399078 -55.092854)
			(xy 232.325418 -55.29199) (xy 232.487216 -55.453788)
		)
		(stroke
			(width 0)
			(type solid)
		)
		(fill yes)
		(layer "In11.Cu")
		(net "M_C_DQ<14>")
	)
	(gr_poly
		(pts
			(xy 232.724706 -98.298254) (xy 232.724706 -98.069654) (xy 232.531666 -97.980754) (xy 232.487216 -97.980754)
			(xy 232.487216 -98.387154) (xy 232.531666 -98.387154)
		)
		(stroke
			(width 0)
			(type solid)
		)
		(fill yes)
		(layer "In11.Cu")
		(net "M_F_DQ<15>")
	)
	(gr_poly
		(pts
			(xy 232.724706 -97.307654) (xy 232.724706 -97.079054) (xy 232.531666 -96.990154) (xy 232.487216 -96.990154)
			(xy 232.487216 -97.396554) (xy 232.531666 -97.396554)
		)
		(stroke
			(width 0)
			(type solid)
		)
		(fill yes)
		(layer "In11.Cu")
		(net "M_F_DQ<15>")
	)
	(gr_poly
		(pts
			(xy 232.767632 -53.982112) (xy 232.841292 -53.782722) (xy 232.679748 -53.620924) (xy 232.480358 -53.694584)
			(xy 232.448862 -53.72608) (xy 232.736136 -54.013354)
		)
		(stroke
			(width 0)
			(type solid)
		)
		(fill yes)
		(layer "In11.Cu")
		(net "M_C_DQ<11>")
	)
	(gr_poly
		(pts
			(xy 232.799636 -92.472256) (xy 232.799636 -92.427806) (xy 232.393236 -92.427806) (xy 232.393236 -92.472256)
			(xy 232.482136 -92.665296) (xy 232.710736 -92.665296)
		)
		(stroke
			(width 0)
			(type solid)
		)
		(fill yes)
		(layer "In11.Cu")
		(net "M_F_DQ<13>")
	)
	(gr_poly
		(pts
			(xy 232.799636 -92.193364) (xy 232.710736 -92.000324) (xy 232.482136 -92.000324) (xy 232.393236 -92.193364)
			(xy 232.393236 -92.237814) (xy 232.799636 -92.237814)
		)
		(stroke
			(width 0)
			(type solid)
		)
		(fill yes)
		(layer "In11.Cu")
		(net "M_F_DQ<12>")
	)
	(gr_poly
		(pts
			(xy 232.809034 -61.40069) (xy 232.780586 -61.366654) (xy 232.60304 -61.293502) (xy 232.433876 -61.435488)
			(xy 232.475024 -61.623194) (xy 232.503726 -61.65723)
		)
		(stroke
			(width 0)
			(type solid)
		)
		(fill yes)
		(layer "In11.Cu")
		(net "M_C_DQ<3>")
	)
	(gr_poly
		(pts
			(xy 232.86466 -57.728866) (xy 232.896156 -57.69737) (xy 232.608882 -57.410096) (xy 232.577386 -57.441592)
			(xy 232.503726 -57.640728) (xy 232.665524 -57.802526)
		)
		(stroke
			(width 0)
			(type solid)
		)
		(fill yes)
		(layer "In11.Cu")
		(net "M_C_DQS_DP<10>")
	)
	(gr_poly
		(pts
			(xy 232.881424 -94.504764) (xy 232.881424 -94.460314) (xy 232.475024 -94.460314) (xy 232.475024 -94.504764)
			(xy 232.563924 -94.697804) (xy 232.792524 -94.697804)
		)
		(stroke
			(width 0)
			(type solid)
		)
		(fill yes)
		(layer "In11.Cu")
		(net "M_F_DQS_DN<10>")
	)
	(gr_poly
		(pts
			(xy 232.883964 -55.182516) (xy 232.957624 -54.983126) (xy 232.79608 -54.821582) (xy 232.59669 -54.895242)
			(xy 232.565194 -54.926484) (xy 232.852722 -55.214012)
		)
		(stroke
			(width 0)
			(type solid)
		)
		(fill yes)
		(layer "In11.Cu")
		(net "M_C_DQ<15>")
	)
	(gr_poly
		(pts
			(xy 232.904538 -90.150696) (xy 232.882186 -90.112088) (xy 232.720134 -90.009218) (xy 232.528872 -90.119708)
			(xy 232.537 -90.311478) (xy 232.559098 -90.350086)
		)
		(stroke
			(width 0)
			(type solid)
		)
		(fill yes)
		(layer "In11.Cu")
		(net "M_F_DQ<6>")
	)
	(gr_poly
		(pts
			(xy 232.906062 -89.15908) (xy 232.88371 -89.120726) (xy 232.721658 -89.017856) (xy 232.530396 -89.128346)
			(xy 232.538524 -89.320116) (xy 232.560622 -89.35847)
		)
		(stroke
			(width 0)
			(type solid)
		)
		(fill yes)
		(layer "In11.Cu")
		(net "M_F_DQS_DN<0>")
	)
	(gr_poly
		(pts
			(xy 232.906062 -88.16848) (xy 232.88371 -88.130126) (xy 232.721658 -88.027256) (xy 232.530396 -88.137746)
			(xy 232.538524 -88.329516) (xy 232.560622 -88.36787)
		)
		(stroke
			(width 0)
			(type solid)
		)
		(fill yes)
		(layer "In11.Cu")
		(net "M_F_DQS_DP<9>")
	)
	(gr_poly
		(pts
			(xy 232.906062 -87.17788) (xy 232.88371 -87.139526) (xy 232.721658 -87.036656) (xy 232.530396 -87.147146)
			(xy 232.538524 -87.338916) (xy 232.560622 -87.37727)
		)
		(stroke
			(width 0)
			(type solid)
		)
		(fill yes)
		(layer "In11.Cu")
		(net "M_F_DQ<0>")
	)
	(gr_poly
		(pts
			(xy 232.906062 -86.18728) (xy 232.88371 -86.148926) (xy 232.721658 -86.046056) (xy 232.530396 -86.156546)
			(xy 232.538524 -86.348316) (xy 232.560622 -86.38667)
		)
		(stroke
			(width 0)
			(type solid)
		)
		(fill yes)
		(layer "In11.Cu")
		(net "M_F_DQ<4>")
	)
	(gr_poly
		(pts
			(xy 232.906062 -66.37528) (xy 232.88371 -66.336926) (xy 232.721658 -66.234056) (xy 232.530396 -66.344546)
			(xy 232.538524 -66.536316) (xy 232.560622 -66.574924)
		)
		(stroke
			(width 0)
			(type solid)
		)
		(fill yes)
		(layer "In11.Cu")
		(net "M_C_DQ<5>")
	)
	(gr_poly
		(pts
			(xy 232.906062 -65.38468) (xy 232.88371 -65.346326) (xy 232.721658 -65.243456) (xy 232.530396 -65.353946)
			(xy 232.538524 -65.545716) (xy 232.560622 -65.584324)
		)
		(stroke
			(width 0)
			(type solid)
		)
		(fill yes)
		(layer "In11.Cu")
		(net "M_C_DQ<1>")
	)
	(gr_poly
		(pts
			(xy 232.906062 -62.41288) (xy 232.88371 -62.374526) (xy 232.721658 -62.271656) (xy 232.530396 -62.382146)
			(xy 232.538524 -62.573916) (xy 232.560622 -62.612524)
		)
		(stroke
			(width 0)
			(type solid)
		)
		(fill yes)
		(layer "In11.Cu")
		(net "M_C_DQ<7>")
	)
	(gr_poly
		(pts
			(xy 232.911396 -90.594434) (xy 232.840276 -90.416126) (xy 232.806494 -90.387424) (xy 232.54716 -90.690446)
			(xy 232.580942 -90.719148) (xy 232.767886 -90.762328)
		)
		(stroke
			(width 0)
			(type solid)
		)
		(fill yes)
		(layer "In11.Cu")
		(net "M_F_DQ<7>")
	)
	(gr_poly
		(pts
			(xy 232.913428 -63.399416) (xy 232.891076 -63.360808) (xy 232.729024 -63.257938) (xy 232.537762 -63.368428)
			(xy 232.54589 -63.560198) (xy 232.567988 -63.598806)
		)
		(stroke
			(width 0)
			(type solid)
		)
		(fill yes)
		(layer "In11.Cu")
		(net "M_C_DQS_DN<0>")
	)
	(gr_poly
		(pts
			(xy 232.913682 -64.390016) (xy 232.89133 -64.351408) (xy 232.729278 -64.248538) (xy 232.538016 -64.359028)
			(xy 232.546144 -64.550798) (xy 232.568242 -64.589406)
		)
		(stroke
			(width 0)
			(type solid)
		)
		(fill yes)
		(layer "In11.Cu")
		(net "M_C_DQS_DN<9>")
	)
	(gr_poly
		(pts
			(xy 233.062272 -57.531254) (xy 233.135932 -57.331864) (xy 232.974388 -57.17032) (xy 232.774998 -57.24398)
			(xy 232.743502 -57.275222) (xy 233.03103 -57.56275)
		)
		(stroke
			(width 0)
			(type solid)
		)
		(fill yes)
		(layer "In11.Cu")
		(net "M_C_DQS_DN<10>")
	)
	(gr_poly
		(pts
			(xy 233.111802 -91.10218) (xy 233.023664 -90.931492) (xy 232.802938 -90.93073) (xy 232.713276 -91.100402)
			(xy 232.712768 -91.144852) (xy 233.111802 -91.14663)
		)
		(stroke
			(width 0)
			(type solid)
		)
		(fill yes)
		(layer "In11.Cu")
		(net "M_F_DQ<2>")
	)
	(gr_poly
		(pts
			(xy 233.147616 -95.266764) (xy 233.147616 -95.222314) (xy 232.741216 -95.222314) (xy 232.741216 -95.266764)
			(xy 232.830116 -95.459804) (xy 233.058716 -95.459804)
		)
		(stroke
			(width 0)
			(type solid)
		)
		(fill yes)
		(layer "In11.Cu")
		(net "M_F_DQS_DP<1>")
	)
	(gr_poly
		(pts
			(xy 233.147616 -94.987364) (xy 233.058716 -94.794324) (xy 232.830116 -94.794324) (xy 232.741216 -94.987364)
			(xy 232.741216 -95.031814) (xy 233.147616 -95.031814)
		)
		(stroke
			(width 0)
			(type solid)
		)
		(fill yes)
		(layer "In11.Cu")
		(net "M_F_DQS_DN<1>")
	)
	(gr_poly
		(pts
			(xy 233.160824 -92.917772) (xy 233.071924 -92.724732) (xy 232.843324 -92.724732) (xy 232.754424 -92.917772)
			(xy 232.754424 -92.962222) (xy 233.160824 -92.962222)
		)
		(stroke
			(width 0)
			(type solid)
		)
		(fill yes)
		(layer "In11.Cu")
		(net "M_F_DQ<8>")
	)
	(gr_poly
		(pts
			(xy 233.270806 -54.879748) (xy 233.302302 -54.848252) (xy 233.015028 -54.560978) (xy 232.983532 -54.592474)
			(xy 232.909872 -54.79161) (xy 233.07167 -54.953408)
		)
		(stroke
			(width 0)
			(type solid)
		)
		(fill yes)
		(layer "In11.Cu")
		(net "M_C_DQ<10>")
	)
	(gr_poly
		(pts
			(xy 233.27741 -59.300618) (xy 233.308906 -59.269122) (xy 233.021632 -58.981848) (xy 232.99039 -59.013344)
			(xy 232.916476 -59.21248) (xy 233.078274 -59.374278)
		)
		(stroke
			(width 0)
			(type solid)
		)
		(fill yes)
		(layer "In11.Cu")
		(net "M_C_DQ<8>")
	)
	(gr_poly
		(pts
			(xy 233.30408 -98.97745) (xy 233.25963 -98.97745) (xy 233.08945 -99.06635) (xy 233.08945 -99.28733)
			(xy 233.25963 -99.37623) (xy 233.30408 -99.37623)
		)
		(stroke
			(width 0)
			(type solid)
		)
		(fill yes)
		(layer "In11.Cu")
		(net "M_F_DQ<10>")
	)
	(gr_poly
		(pts
			(xy 233.30408 -97.9805) (xy 233.25963 -97.9805) (xy 233.08945 -98.0694) (xy 233.08945 -98.29038)
			(xy 233.25963 -98.37928) (xy 233.30408 -98.37928)
		)
		(stroke
			(width 0)
			(type solid)
		)
		(fill yes)
		(layer "In11.Cu")
		(net "M_F_DQ<10>")
	)
	(gr_poly
		(pts
			(xy 233.30408 -96.9899) (xy 233.25963 -96.9899) (xy 233.08945 -97.0788) (xy 233.08945 -97.29978)
			(xy 233.25963 -97.38868) (xy 233.30408 -97.38868)
		)
		(stroke
			(width 0)
			(type solid)
		)
		(fill yes)
		(layer "In11.Cu")
		(net "M_F_DQ<10>")
	)
	(gr_poly
		(pts
			(xy 233.36377 -57.142888) (xy 233.395266 -57.111392) (xy 233.107992 -56.824118) (xy 233.076496 -56.855614)
			(xy 233.002836 -57.05475) (xy 233.164634 -57.216548)
		)
		(stroke
			(width 0)
			(type solid)
		)
		(fill yes)
		(layer "In11.Cu")
		(net "M_C_DQS_DP<1>")
	)
	(gr_poly
		(pts
			(xy 233.374184 -95.825564) (xy 233.285284 -95.632524) (xy 233.056684 -95.632524) (xy 232.967784 -95.825564)
			(xy 232.967784 -95.870014) (xy 233.374184 -95.870014)
		)
		(stroke
			(width 0)
			(type solid)
		)
		(fill yes)
		(layer "In11.Cu")
		(net "M_F_DQ<14>")
	)
	(gr_poly
		(pts
			(xy 233.397552 -56.091328) (xy 233.429048 -56.059832) (xy 233.141774 -55.772558) (xy 233.110278 -55.804054)
			(xy 233.036618 -56.00319) (xy 233.198416 -56.164988)
		)
		(stroke
			(width 0)
			(type solid)
		)
		(fill yes)
		(layer "In11.Cu")
		(net "M_C_DQ<14>")
	)
	(gr_poly
		(pts
			(xy 233.414824 -93.196664) (xy 233.414824 -93.152214) (xy 233.008424 -93.152214) (xy 233.008424 -93.196664)
			(xy 233.097324 -93.389704) (xy 233.325924 -93.389704)
		)
		(stroke
			(width 0)
			(type solid)
		)
		(fill yes)
		(layer "In11.Cu")
		(net "M_F_DQ<9>")
	)
	(gr_poly
		(pts
			(xy 233.41965 -59.04738) (xy 233.49331 -58.84799) (xy 233.331766 -58.686446) (xy 233.132376 -58.760106)
			(xy 233.10088 -58.791348) (xy 233.388408 -59.078876)
		)
		(stroke
			(width 0)
			(type solid)
		)
		(fill yes)
		(layer "In11.Cu")
		(net "M_C_DQ<9>")
	)
	(gr_poly
		(pts
			(xy 233.468164 -54.68239) (xy 233.541824 -54.483254) (xy 233.380026 -54.321456) (xy 233.18089 -54.395116)
			(xy 233.149394 -54.426612) (xy 233.436668 -54.713886)
		)
		(stroke
			(width 0)
			(type solid)
		)
		(fill yes)
		(layer "In11.Cu")
		(net "M_C_DQ<11>")
	)
	(gr_poly
		(pts
			(xy 233.527346 -64.550798) (xy 233.535474 -64.359028) (xy 233.344212 -64.248538) (xy 233.18216 -64.351408)
			(xy 233.159808 -64.390016) (xy 233.505248 -64.589406)
		)
		(stroke
			(width 0)
			(type solid)
		)
		(fill yes)
		(layer "In11.Cu")
		(net "M_C_DQS_DN<9>")
	)
	(gr_poly
		(pts
			(xy 233.527346 -63.560198) (xy 233.535474 -63.368428) (xy 233.344212 -63.257938) (xy 233.18216 -63.360808)
			(xy 233.159808 -63.399416) (xy 233.505248 -63.598806)
		)
		(stroke
			(width 0)
			(type solid)
		)
		(fill yes)
		(layer "In11.Cu")
		(net "M_C_DQS_DN<0>")
	)
	(gr_poly
		(pts
			(xy 233.534712 -66.536316) (xy 233.54284 -66.344546) (xy 233.351578 -66.234056) (xy 233.189526 -66.336926)
			(xy 233.167174 -66.37528) (xy 233.512614 -66.574924)
		)
		(stroke
			(width 0)
			(type solid)
		)
		(fill yes)
		(layer "In11.Cu")
		(net "M_C_DQ<5>")
	)
	(gr_poly
		(pts
			(xy 233.534712 -65.545716) (xy 233.54284 -65.353946) (xy 233.351578 -65.243456) (xy 233.189526 -65.346326)
			(xy 233.167174 -65.38468) (xy 233.512614 -65.584324)
		)
		(stroke
			(width 0)
			(type solid)
		)
		(fill yes)
		(layer "In11.Cu")
		(net "M_C_DQ<1>")
	)
	(gr_poly
		(pts
			(xy 233.534712 -62.573916) (xy 233.54284 -62.382146) (xy 233.351578 -62.271656) (xy 233.189526 -62.374526)
			(xy 233.167174 -62.41288) (xy 233.512614 -62.612524)
		)
		(stroke
			(width 0)
			(type solid)
		)
		(fill yes)
		(layer "In11.Cu")
		(net "M_C_DQ<7>")
	)
	(gr_poly
		(pts
			(xy 233.534712 -61.583316) (xy 233.54284 -61.391546) (xy 233.351578 -61.281056) (xy 233.189526 -61.383926)
			(xy 233.167174 -61.42228) (xy 233.512614 -61.621924)
		)
		(stroke
			(width 0)
			(type solid)
		)
		(fill yes)
		(layer "In11.Cu")
		(net "M_C_DQ<3>")
	)
	(gr_poly
		(pts
			(xy 233.544364 -90.402664) (xy 233.536236 -90.210894) (xy 233.514138 -90.172286) (xy 233.168698 -90.37193)
			(xy 233.19105 -90.410284) (xy 233.353102 -90.513154)
		)
		(stroke
			(width 0)
			(type solid)
		)
		(fill yes)
		(layer "In11.Cu")
		(net "M_F_DQ<7>")
	)
	(gr_poly
		(pts
			(xy 233.544364 -89.412064) (xy 233.536236 -89.220294) (xy 233.514138 -89.181686) (xy 233.168698 -89.38133)
			(xy 233.19105 -89.419684) (xy 233.353102 -89.522554)
		)
		(stroke
			(width 0)
			(type solid)
		)
		(fill yes)
		(layer "In11.Cu")
		(net "M_F_DQS_DP<0>")
	)
	(gr_poly
		(pts
			(xy 233.544364 -88.421464) (xy 233.536236 -88.229694) (xy 233.514138 -88.191086) (xy 233.168698 -88.39073)
			(xy 233.19105 -88.429084) (xy 233.353102 -88.531954)
		)
		(stroke
			(width 0)
			(type solid)
		)
		(fill yes)
		(layer "In11.Cu")
		(net "M_F_DQS_DN<9>")
	)
	(gr_poly
		(pts
			(xy 233.544364 -87.430864) (xy 233.536236 -87.239094) (xy 233.514138 -87.200486) (xy 233.168698 -87.40013)
			(xy 233.19105 -87.438484) (xy 233.353102 -87.541354)
		)
		(stroke
			(width 0)
			(type solid)
		)
		(fill yes)
		(layer "In11.Cu")
		(net "M_F_DQ<1>")
	)
	(gr_poly
		(pts
			(xy 233.544364 -86.440264) (xy 233.536236 -86.248494) (xy 233.514138 -86.209886) (xy 233.168698 -86.40953)
			(xy 233.19105 -86.447884) (xy 233.353102 -86.550754)
		)
		(stroke
			(width 0)
			(type solid)
		)
		(fill yes)
		(layer "In11.Cu")
		(net "M_F_DQ<5>")
	)
	(gr_poly
		(pts
			(xy 233.561382 -56.945276) (xy 233.635042 -56.745886) (xy 233.473498 -56.584342) (xy 233.274108 -56.658002)
			(xy 233.242612 -56.689244) (xy 233.53014 -56.976772)
		)
		(stroke
			(width 0)
			(type solid)
		)
		(fill yes)
		(layer "In11.Cu")
		(net "M_C_DQS_DN<1>")
	)
	(gr_poly
		(pts
			(xy 233.57586 -58.440066) (xy 233.607356 -58.40857) (xy 233.320082 -58.121296) (xy 233.288586 -58.152792)
			(xy 233.214926 -58.351928) (xy 233.376724 -58.513726)
		)
		(stroke
			(width 0)
			(type solid)
		)
		(fill yes)
		(layer "In11.Cu")
		(net "M_C_DQS_DP<10>")
	)
	(gr_poly
		(pts
			(xy 233.577384 -96.104456) (xy 233.577384 -96.060006) (xy 233.170984 -96.060006) (xy 233.170984 -96.104456)
			(xy 233.259884 -96.297496) (xy 233.488484 -96.297496)
		)
		(stroke
			(width 0)
			(type solid)
		)
		(fill yes)
		(layer "In11.Cu")
		(net "M_F_DQ<15>")
	)
	(gr_poly
		(pts
			(xy 233.595164 -55.893716) (xy 233.668824 -55.694326) (xy 233.50728 -55.532782) (xy 233.30789 -55.606442)
			(xy 233.276394 -55.637684) (xy 233.563922 -55.925212)
		)
		(stroke
			(width 0)
			(type solid)
		)
		(fill yes)
		(layer "In11.Cu")
		(net "M_C_DQ<15>")
	)
	(gr_poly
		(pts
			(xy 233.740706 -53.262784) (xy 233.763058 -53.22443) (xy 233.417618 -53.024786) (xy 233.39552 -53.063394)
			(xy 233.387392 -53.255164) (xy 233.578654 -53.365654)
		)
		(stroke
			(width 0)
			(type solid)
		)
		(fill yes)
		(layer "In11.Cu")
		(net "M_C_DQ<20>")
	)
	(gr_poly
		(pts
			(xy 233.74223 -67.1322) (xy 233.764582 -67.093592) (xy 233.419142 -66.894456) (xy 233.397044 -66.93281)
			(xy 233.388916 -67.12458) (xy 233.580178 -67.23507)
		)
		(stroke
			(width 0)
			(type solid)
		)
		(fill yes)
		(layer "In11.Cu")
		(net "M_C_DQ<4>")
	)
	(gr_poly
		(pts
			(xy 233.74223 -66.1416) (xy 233.764582 -66.102992) (xy 233.419142 -65.903602) (xy 233.397044 -65.94221)
			(xy 233.388916 -66.13398) (xy 233.580178 -66.24447)
		)
		(stroke
			(width 0)
			(type solid)
		)
		(fill yes)
		(layer "In11.Cu")
		(net "M_C_DQ<0>")
	)
	(gr_poly
		(pts
			(xy 233.74223 -63.1698) (xy 233.764582 -63.131192) (xy 233.419142 -62.931802) (xy 233.397044 -62.97041)
			(xy 233.388916 -63.16218) (xy 233.580178 -63.27267)
		)
		(stroke
			(width 0)
			(type solid)
		)
		(fill yes)
		(layer "In11.Cu")
		(net "M_C_DQ<6>")
	)
	(gr_poly
		(pts
			(xy 233.74223 -62.1792) (xy 233.764582 -62.140592) (xy 233.419142 -61.941202) (xy 233.397044 -61.97981)
			(xy 233.388916 -62.17158) (xy 233.580178 -62.28207)
		)
		(stroke
			(width 0)
			(type solid)
		)
		(fill yes)
		(layer "In11.Cu")
		(net "M_C_DQ<2>")
	)
	(gr_poly
		(pts
			(xy 233.74223 -61.1886) (xy 233.764582 -61.149992) (xy 233.419142 -60.950602) (xy 233.397044 -60.98921)
			(xy 233.388916 -61.18098) (xy 233.580178 -61.29147)
		)
		(stroke
			(width 0)
			(type solid)
		)
		(fill yes)
		(layer "In11.Cu")
		(net "M_C_DQ<12>")
	)
	(gr_poly
		(pts
			(xy 233.749596 -65.155318) (xy 233.771948 -65.116964) (xy 233.426508 -64.91732) (xy 233.40441 -64.955928)
			(xy 233.396282 -65.147698) (xy 233.587544 -65.258188)
		)
		(stroke
			(width 0)
			(type solid)
		)
		(fill yes)
		(layer "In11.Cu")
		(net "M_C_DQS_DP<9>")
	)
	(gr_poly
		(pts
			(xy 233.749596 -64.164718) (xy 233.771948 -64.126364) (xy 233.426508 -63.92672) (xy 233.40441 -63.965328)
			(xy 233.396282 -64.157098) (xy 233.587544 -64.267588)
		)
		(stroke
			(width 0)
			(type solid)
		)
		(fill yes)
		(layer "In11.Cu")
		(net "M_C_DQS_DP<0>")
	)
	(gr_poly
		(pts
			(xy 233.755438 -96.555306) (xy 233.733086 -96.516952) (xy 233.571034 -96.414082) (xy 233.379772 -96.524318)
			(xy 233.387646 -96.716088) (xy 233.409744 -96.754696)
		)
		(stroke
			(width 0)
			(type solid)
		)
		(fill yes)
		(layer "In11.Cu")
		(net "M_F_DQ<10>")
	)
	(gr_poly
		(pts
			(xy 233.763058 -90.64625) (xy 233.740706 -90.607642) (xy 233.578654 -90.504772) (xy 233.387392 -90.615262)
			(xy 233.39552 -90.807032) (xy 233.417618 -90.84564)
		)
		(stroke
			(width 0)
			(type solid)
		)
		(fill yes)
		(layer "In11.Cu")
		(net "M_F_DQ<2>")
	)
	(gr_poly
		(pts
			(xy 233.763058 -89.65565) (xy 233.740706 -89.617042) (xy 233.578654 -89.514172) (xy 233.387392 -89.624662)
			(xy 233.39552 -89.816432) (xy 233.417618 -89.85504)
		)
		(stroke
			(width 0)
			(type solid)
		)
		(fill yes)
		(layer "In11.Cu")
		(net "M_F_DQ<6>")
	)
	(gr_poly
		(pts
			(xy 233.763058 -88.66505) (xy 233.740706 -88.626442) (xy 233.578654 -88.523572) (xy 233.387392 -88.634062)
			(xy 233.39552 -88.825832) (xy 233.417618 -88.86444)
		)
		(stroke
			(width 0)
			(type solid)
		)
		(fill yes)
		(layer "In11.Cu")
		(net "M_F_DQS_DN<0>")
	)
	(gr_poly
		(pts
			(xy 233.763058 -87.67445) (xy 233.740706 -87.635842) (xy 233.578654 -87.532972) (xy 233.387392 -87.643462)
			(xy 233.39552 -87.835232) (xy 233.417618 -87.87384)
		)
		(stroke
			(width 0)
			(type solid)
		)
		(fill yes)
		(layer "In11.Cu")
		(net "M_F_DQS_DP<9>")
	)
	(gr_poly
		(pts
			(xy 233.763058 -86.68385) (xy 233.740706 -86.645242) (xy 233.578654 -86.542372) (xy 233.387392 -86.652862)
			(xy 233.39552 -86.844632) (xy 233.417618 -86.88324)
		)
		(stroke
			(width 0)
			(type solid)
		)
		(fill yes)
		(layer "In11.Cu")
		(net "M_F_DQ<0>")
	)
	(gr_poly
		(pts
			(xy 233.763058 -85.69325) (xy 233.740706 -85.654642) (xy 233.578654 -85.551772) (xy 233.387392 -85.662262)
			(xy 233.39552 -85.854032) (xy 233.417618 -85.89264)
		)
		(stroke
			(width 0)
			(type solid)
		)
		(fill yes)
		(layer "In11.Cu")
		(net "M_F_DQ<4>")
	)
	(gr_poly
		(pts
			(xy 233.766868 -100.54971) (xy 233.744516 -100.511356) (xy 233.582464 -100.408486) (xy 233.391202 -100.518976)
			(xy 233.39933 -100.710746) (xy 233.421428 -100.749354)
		)
		(stroke
			(width 0)
			(type solid)
		)
		(fill yes)
		(layer "In11.Cu")
		(net "M_F_DQ<20>")
	)
	(gr_poly
		(pts
			(xy 233.77017 -91.157044) (xy 233.712766 -90.97391) (xy 233.681524 -90.942668) (xy 233.39933 -91.224354)
			(xy 233.43108 -91.25585) (xy 233.614214 -91.313508)
		)
		(stroke
			(width 0)
			(type solid)
		)
		(fill yes)
		(layer "In11.Cu")
		(net "M_F_DQ<3>")
	)
	(gr_poly
		(pts
			(xy 233.773472 -58.242454) (xy 233.847132 -58.043064) (xy 233.685588 -57.88152) (xy 233.486198 -57.95518)
			(xy 233.454702 -57.986422) (xy 233.74223 -58.27395)
		)
		(stroke
			(width 0)
			(type solid)
		)
		(fill yes)
		(layer "In11.Cu")
		(net "M_C_DQS_DN<10>")
	)
	(gr_poly
		(pts
			(xy 233.8324 -91.540838) (xy 233.800904 -91.509342) (xy 233.601768 -91.435682) (xy 233.43997 -91.59748)
			(xy 233.51363 -91.796616) (xy 233.545126 -91.828112)
		)
		(stroke
			(width 0)
			(type solid)
		)
		(fill yes)
		(layer "In11.Cu")
		(net "M_F_DQ<12>")
	)
	(gr_poly
		(pts
			(xy 233.842306 -99.77628) (xy 233.842306 -99.5553) (xy 233.672126 -99.4664) (xy 233.627676 -99.4664)
			(xy 233.627676 -99.86518) (xy 233.672126 -99.86518)
		)
		(stroke
			(width 0)
			(type solid)
		)
		(fill yes)
		(layer "In11.Cu")
		(net "M_F_DQ<11>")
	)
	(gr_poly
		(pts
			(xy 233.842306 -98.798126) (xy 233.842306 -98.577146) (xy 233.672126 -98.488246) (xy 233.627676 -98.488246)
			(xy 233.627676 -98.887026) (xy 233.672126 -98.887026)
		)
		(stroke
			(width 0)
			(type solid)
		)
		(fill yes)
		(layer "In11.Cu")
		(net "M_F_DQ<11>")
	)
	(gr_poly
		(pts
			(xy 233.842306 -97.807526) (xy 233.842306 -97.586546) (xy 233.672126 -97.497646) (xy 233.627676 -97.497646)
			(xy 233.627676 -97.896426) (xy 233.672126 -97.896426)
		)
		(stroke
			(width 0)
			(type solid)
		)
		(fill yes)
		(layer "In11.Cu")
		(net "M_F_DQ<11>")
	)
	(gr_poly
		(pts
			(xy 233.8832 -93.496638) (xy 233.851704 -93.465142) (xy 233.652568 -93.391482) (xy 233.49077 -93.55328)
			(xy 233.56443 -93.752416) (xy 233.595926 -93.783912)
		)
		(stroke
			(width 0)
			(type solid)
		)
		(fill yes)
		(layer "In11.Cu")
		(net "M_F_DQS_DP<10>")
	)
	(gr_poly
		(pts
			(xy 233.910124 -92.464382) (xy 233.878628 -92.43314) (xy 233.679238 -92.35948) (xy 233.517694 -92.521024)
			(xy 233.591354 -92.720414) (xy 233.622596 -92.75191)
		)
		(stroke
			(width 0)
			(type solid)
		)
		(fill yes)
		(layer "In11.Cu")
		(net "M_F_DQ<8>")
	)
	(gr_poly
		(pts
			(xy 233.969306 -94.436438) (xy 233.93781 -94.404942) (xy 233.738674 -94.331282) (xy 233.576876 -94.49308)
			(xy 233.650536 -94.692216) (xy 233.682032 -94.723712)
		)
		(stroke
			(width 0)
			(type solid)
		)
		(fill yes)
		(layer "In11.Cu")
		(net "M_F_DQS_DN<1>")
	)
	(gr_poly
		(pts
			(xy 233.982006 -55.590948) (xy 234.013502 -55.559452) (xy 233.726228 -55.272178) (xy 233.694732 -55.303674)
			(xy 233.621072 -55.50281) (xy 233.78287 -55.664608)
		)
		(stroke
			(width 0)
			(type solid)
		)
		(fill yes)
		(layer "In11.Cu")
		(net "M_C_DQ<10>")
	)
	(gr_poly
		(pts
			(xy 234.014264 -102.407974) (xy 233.982768 -102.376732) (xy 233.783378 -102.303072) (xy 233.621834 -102.464616)
			(xy 233.695494 -102.664006) (xy 233.726736 -102.695502)
		)
		(stroke
			(width 0)
			(type solid)
		)
		(fill yes)
		(layer "In11.Cu")
		(net "M_F_DQ<16>")
	)
	(gr_poly
		(pts
			(xy 234.072176 -91.906344) (xy 233.998516 -91.706954) (xy 233.967274 -91.675458) (xy 233.679746 -91.962986)
			(xy 233.711242 -91.994228) (xy 233.910632 -92.067888)
		)
		(stroke
			(width 0)
			(type solid)
		)
		(fill yes)
		(layer "In11.Cu")
		(net "M_F_DQ<13>")
	)
	(gr_poly
		(pts
			(xy 234.117134 -95.538798) (xy 234.085638 -95.507556) (xy 233.886248 -95.433896) (xy 233.724704 -95.59544)
			(xy 233.798364 -95.79483) (xy 233.829606 -95.826326)
		)
		(stroke
			(width 0)
			(type solid)
		)
		(fill yes)
		(layer "In11.Cu")
		(net "M_F_DQ<14>")
	)
	(gr_poly
		(pts
			(xy 234.122976 -93.862144) (xy 234.049316 -93.662754) (xy 234.018074 -93.631258) (xy 233.730546 -93.918786)
			(xy 233.762042 -93.950028) (xy 233.961432 -94.023688)
		)
		(stroke
			(width 0)
			(type solid)
		)
		(fill yes)
		(layer "In11.Cu")
		(net "M_F_DQS_DN<10>")
	)
	(gr_poly
		(pts
			(xy 234.149392 -92.829634) (xy 234.075732 -92.630244) (xy 234.04449 -92.598748) (xy 233.756962 -92.886276)
			(xy 233.788458 -92.917518) (xy 233.987848 -92.991178)
		)
		(stroke
			(width 0)
			(type solid)
		)
		(fill yes)
		(layer "In11.Cu")
		(net "M_F_DQ<9>")
	)
	(gr_poly
		(pts
			(xy 234.1626 -99.4664) (xy 234.11815 -99.4664) (xy 233.94797 -99.5553) (xy 233.94797 -99.77628) (xy 234.11815 -99.86518)
			(xy 234.1626 -99.86518)
		)
		(stroke
			(width 0)
			(type solid)
		)
		(fill yes)
		(layer "In11.Cu")
		(net "M_F_DQ<20>")
	)
	(gr_poly
		(pts
			(xy 234.1626 -98.48215) (xy 234.11815 -98.48215) (xy 233.94797 -98.57105) (xy 233.94797 -98.79203)
			(xy 234.11815 -98.88093) (xy 234.1626 -98.88093)
		)
		(stroke
			(width 0)
			(type solid)
		)
		(fill yes)
		(layer "In11.Cu")
		(net "M_F_DQ<20>")
	)
	(gr_poly
		(pts
			(xy 234.162854 -51.913028) (xy 234.118404 -51.913282) (xy 233.948224 -52.001928) (xy 233.948224 -52.222908)
			(xy 234.118404 -52.311808) (xy 234.162854 -52.312062)
		)
		(stroke
			(width 0)
			(type solid)
		)
		(fill yes)
		(layer "In11.Cu")
		(net "M_C_DQ<16>")
	)
	(gr_poly
		(pts
			(xy 234.179364 -55.39359) (xy 234.253024 -55.194454) (xy 234.091226 -55.032656) (xy 233.89209 -55.106316)
			(xy 233.860594 -55.137812) (xy 234.147868 -55.425086)
		)
		(stroke
			(width 0)
			(type solid)
		)
		(fill yes)
		(layer "In11.Cu")
		(net "M_C_DQ<11>")
	)
	(gr_poly
		(pts
			(xy 234.209082 -94.801944) (xy 234.135422 -94.602554) (xy 234.10418 -94.571058) (xy 233.816652 -94.858586)
			(xy 233.848148 -94.889828) (xy 234.047538 -94.963488)
		)
		(stroke
			(width 0)
			(type solid)
		)
		(fill yes)
		(layer "In11.Cu")
		(net "M_F_DQS_DP<1>")
	)
	(gr_poly
		(pts
			(xy 234.236514 -98.042476) (xy 234.13339 -97.657158) (xy 234.090464 -97.668842) (xy 233.948986 -97.79889)
			(xy 234.006136 -98.01225) (xy 234.193588 -98.053906)
		)
		(stroke
			(width 0)
			(type solid)
		)
		(fill yes)
		(layer "In11.Cu")
		(net "M_F_DQ<20>")
	)
	(gr_poly
		(pts
			(xy 234.253532 -102.773226) (xy 234.179872 -102.573836) (xy 234.14863 -102.54234) (xy 233.861102 -102.829868)
			(xy 233.892598 -102.86111) (xy 234.091988 -102.93477)
		)
		(stroke
			(width 0)
			(type solid)
		)
		(fill yes)
		(layer "In11.Cu")
		(net "M_F_DQ<17>")
	)
	(gr_poly
		(pts
			(xy 234.297728 -54.585108) (xy 234.336082 -54.56301) (xy 234.136692 -54.21757) (xy 234.098338 -54.239922)
			(xy 233.995468 -54.401974) (xy 234.105958 -54.593236)
		)
		(stroke
			(width 0)
			(type solid)
		)
		(fill yes)
		(layer "In11.Cu")
		(net "M_C_DQ<20>")
	)
	(gr_poly
		(pts
			(xy 234.36961 -90.926412) (xy 234.361482 -90.734642) (xy 234.339384 -90.696288) (xy 233.993944 -90.895424)
			(xy 234.016296 -90.934032) (xy 234.178348 -91.036902)
		)
		(stroke
			(width 0)
			(type solid)
		)
		(fill yes)
		(layer "In11.Cu")
		(net "M_F_DQ<3>")
	)
	(gr_poly
		(pts
			(xy 234.393232 -53.16347) (xy 234.40136 -52.9717) (xy 234.210098 -52.86121) (xy 234.048046 -52.96408)
			(xy 234.025694 -53.002434) (xy 234.371134 -53.202078)
		)
		(stroke
			(width 0)
			(type solid)
		)
		(fill yes)
		(layer "In11.Cu")
		(net "M_C_DQ<21>")
	)
	(gr_poly
		(pts
			(xy 234.393486 -100.809552) (xy 234.385612 -100.617782) (xy 234.36326 -100.579174) (xy 234.01782 -100.778564)
			(xy 234.040426 -100.816918) (xy 234.202224 -100.920042)
		)
		(stroke
			(width 0)
			(type solid)
		)
		(fill yes)
		(layer "In11.Cu")
		(net "M_F_DQ<21>")
	)
	(gr_poly
		(pts
			(xy 234.393994 -65.147698) (xy 234.385866 -64.955928) (xy 234.363768 -64.91732) (xy 234.018328 -65.116964)
			(xy 234.04068 -65.155318) (xy 234.202732 -65.258188)
		)
		(stroke
			(width 0)
			(type solid)
		)
		(fill yes)
		(layer "In11.Cu")
		(net "M_C_DQS_DP<9>")
	)
	(gr_poly
		(pts
			(xy 234.393994 -64.157098) (xy 234.385866 -63.965328) (xy 234.363768 -63.92672) (xy 234.018328 -64.126364)
			(xy 234.04068 -64.164718) (xy 234.202732 -64.267588)
		)
		(stroke
			(width 0)
			(type solid)
		)
		(fill yes)
		(layer "In11.Cu")
		(net "M_C_DQS_DP<0>")
	)
	(gr_poly
		(pts
			(xy 234.40136 -96.84258) (xy 234.393232 -96.65081) (xy 234.371134 -96.612202) (xy 234.025694 -96.811846)
			(xy 234.048046 -96.8502) (xy 234.210098 -96.95307)
		)
		(stroke
			(width 0)
			(type solid)
		)
		(fill yes)
		(layer "In11.Cu")
		(net "M_F_DQ<11>")
	)
	(gr_poly
		(pts
			(xy 234.40136 -89.90838) (xy 234.393232 -89.71661) (xy 234.371134 -89.678002) (xy 234.025694 -89.877646)
			(xy 234.048046 -89.916) (xy 234.210098 -90.01887)
		)
		(stroke
			(width 0)
			(type solid)
		)
		(fill yes)
		(layer "In11.Cu")
		(net "M_F_DQ<7>")
	)
	(gr_poly
		(pts
			(xy 234.40136 -88.91778) (xy 234.393232 -88.72601) (xy 234.371134 -88.687402) (xy 234.025694 -88.887046)
			(xy 234.048046 -88.9254) (xy 234.210098 -89.02827)
		)
		(stroke
			(width 0)
			(type solid)
		)
		(fill yes)
		(layer "In11.Cu")
		(net "M_F_DQS_DP<0>")
	)
	(gr_poly
		(pts
			(xy 234.40136 -87.92718) (xy 234.393232 -87.73541) (xy 234.371134 -87.696802) (xy 234.025694 -87.896446)
			(xy 234.048046 -87.9348) (xy 234.210098 -88.03767)
		)
		(stroke
			(width 0)
			(type solid)
		)
		(fill yes)
		(layer "In11.Cu")
		(net "M_F_DQS_DN<9>")
	)
	(gr_poly
		(pts
			(xy 234.40136 -86.93658) (xy 234.393232 -86.74481) (xy 234.371134 -86.706202) (xy 234.025694 -86.905846)
			(xy 234.048046 -86.9442) (xy 234.210098 -87.04707)
		)
		(stroke
			(width 0)
			(type solid)
		)
		(fill yes)
		(layer "In11.Cu")
		(net "M_F_DQ<1>")
	)
	(gr_poly
		(pts
			(xy 234.40136 -85.94598) (xy 234.393232 -85.75421) (xy 234.371134 -85.715602) (xy 234.025694 -85.915246)
			(xy 234.048046 -85.9536) (xy 234.210098 -86.05647)
		)
		(stroke
			(width 0)
			(type solid)
		)
		(fill yes)
		(layer "In11.Cu")
		(net "M_F_DQ<5>")
	)
	(gr_poly
		(pts
			(xy 234.40136 -67.12458) (xy 234.393232 -66.93281) (xy 234.371134 -66.894456) (xy 234.025694 -67.093592)
			(xy 234.048046 -67.1322) (xy 234.210098 -67.23507)
		)
		(stroke
			(width 0)
			(type solid)
		)
		(fill yes)
		(layer "In11.Cu")
		(net "M_C_DQ<4>")
	)
	(gr_poly
		(pts
			(xy 234.40136 -66.13398) (xy 234.393232 -65.94221) (xy 234.371134 -65.903602) (xy 234.025694 -66.102992)
			(xy 234.048046 -66.1416) (xy 234.210098 -66.24447)
		)
		(stroke
			(width 0)
			(type solid)
		)
		(fill yes)
		(layer "In11.Cu")
		(net "M_C_DQ<0>")
	)
	(gr_poly
		(pts
			(xy 234.40136 -63.16218) (xy 234.393232 -62.97041) (xy 234.371134 -62.931802) (xy 234.025694 -63.131192)
			(xy 234.048046 -63.1698) (xy 234.210098 -63.27267)
		)
		(stroke
			(width 0)
			(type solid)
		)
		(fill yes)
		(layer "In11.Cu")
		(net "M_C_DQ<6>")
	)
	(gr_poly
		(pts
			(xy 234.40136 -62.17158) (xy 234.393232 -61.97981) (xy 234.371134 -61.941202) (xy 234.025694 -62.140592)
			(xy 234.048046 -62.1792) (xy 234.210098 -62.28207)
		)
		(stroke
			(width 0)
			(type solid)
		)
		(fill yes)
		(layer "In11.Cu")
		(net "M_C_DQ<2>")
	)
	(gr_poly
		(pts
			(xy 234.40136 -61.18098) (xy 234.393232 -60.98921) (xy 234.371134 -60.950602) (xy 234.025694 -61.149992)
			(xy 234.048046 -61.1886) (xy 234.210098 -61.29147)
		)
		(stroke
			(width 0)
			(type solid)
		)
		(fill yes)
		(layer "In11.Cu")
		(net "M_C_DQ<12>")
	)
	(gr_poly
		(pts
			(xy 234.424474 -95.8469) (xy 234.350814 -95.64751) (xy 234.319572 -95.616014) (xy 234.032044 -95.903542)
			(xy 234.06354 -95.934784) (xy 234.26293 -96.008444)
		)
		(stroke
			(width 0)
			(type solid)
		)
		(fill yes)
		(layer "In11.Cu")
		(net "M_F_DQ<15>")
	)
	(gr_poly
		(pts
			(xy 234.42803 -96.21266) (xy 234.396534 -96.181418) (xy 234.2134 -96.124014) (xy 234.05719 -96.280224)
			(xy 234.114848 -96.463358) (xy 234.14609 -96.494854)
		)
		(stroke
			(width 0)
			(type solid)
		)
		(fill yes)
		(layer "In11.Cu")
		(net "M_F_DQ<10>")
	)
	(gr_poly
		(pts
			(xy 234.429554 -59.692286) (xy 234.429554 -59.647836) (xy 234.023154 -59.647836) (xy 234.023154 -59.692286)
			(xy 234.112054 -59.885326) (xy 234.340654 -59.885326)
		)
		(stroke
			(width 0)
			(type solid)
		)
		(fill yes)
		(layer "In11.Cu")
		(net "M_C_DQ<8>")
	)
	(gr_poly
		(pts
			(xy 234.429554 -59.412886) (xy 234.340654 -59.219846) (xy 234.112054 -59.219846) (xy 234.023154 -59.412886)
			(xy 234.023154 -59.457336) (xy 234.429554 -59.457336)
		)
		(stroke
			(width 0)
			(type solid)
		)
		(fill yes)
		(layer "In11.Cu")
		(net "M_C_DQ<9>")
	)
	(gr_poly
		(pts
			(xy 234.482132 -58.422286) (xy 234.393232 -58.229246) (xy 234.164886 -58.229246) (xy 234.075986 -58.422286)
			(xy 234.075732 -58.466736) (xy 234.482386 -58.466736)
		)
		(stroke
			(width 0)
			(type solid)
		)
		(fill yes)
		(layer "In11.Cu")
		(net "M_C_DQS_DN<10>")
	)
	(gr_poly
		(pts
			(xy 234.515406 -58.701686) (xy 234.515406 -58.657236) (xy 234.109006 -58.657236) (xy 234.109006 -58.701686)
			(xy 234.197906 -58.894726) (xy 234.426506 -58.894726)
		)
		(stroke
			(width 0)
			(type solid)
		)
		(fill yes)
		(layer "In11.Cu")
		(net "M_C_DQS_DP<10>")
	)
	(gr_poly
		(pts
			(xy 234.522518 -56.724804) (xy 234.522518 -56.6801) (xy 234.116118 -56.6801) (xy 234.116118 -56.724804)
			(xy 234.205018 -56.91759) (xy 234.433618 -56.91759)
		)
		(stroke
			(width 0)
			(type solid)
		)
		(fill yes)
		(layer "In11.Cu")
		(net "M_C_DQ<14>")
	)
	(gr_poly
		(pts
			(xy 234.522518 -56.44515) (xy 234.433618 -56.25211) (xy 234.205018 -56.25211) (xy 234.116118 -56.44515)
			(xy 234.116118 -56.4896) (xy 234.522518 -56.4896)
		)
		(stroke
			(width 0)
			(type solid)
		)
		(fill yes)
		(layer "In11.Cu")
		(net "M_C_DQ<15>")
	)
	(gr_poly
		(pts
			(xy 234.530392 -100.366322) (xy 234.700572 -100.277676) (xy 234.700572 -100.056696) (xy 234.530646 -99.967796)
			(xy 234.485942 -99.967796) (xy 234.485942 -100.366576)
		)
		(stroke
			(width 0)
			(type solid)
		)
		(fill yes)
		(layer "In11.Cu")
		(net "M_F_DQ<21>")
	)
	(gr_poly
		(pts
			(xy 234.599226 -52.767738) (xy 234.621578 -52.729384) (xy 234.276138 -52.52974) (xy 234.25404 -52.568348)
			(xy 234.245912 -52.760118) (xy 234.437174 -52.870608)
		)
		(stroke
			(width 0)
			(type solid)
		)
		(fill yes)
		(layer "In11.Cu")
		(net "M_C_DQ<16>")
	)
	(gr_poly
		(pts
			(xy 234.621578 -95.103442) (xy 234.599226 -95.065088) (xy 234.437174 -94.962218) (xy 234.245912 -95.072708)
			(xy 234.25404 -95.264478) (xy 234.276138 -95.303086)
		)
		(stroke
			(width 0)
			(type solid)
		)
		(fill yes)
		(layer "In11.Cu")
		(net "M_F_DQ<14>")
	)
	(gr_poly
		(pts
			(xy 234.623102 -101.04628) (xy 234.60075 -101.007926) (xy 234.438698 -100.905056) (xy 234.247436 -101.015546)
			(xy 234.255564 -101.207316) (xy 234.277662 -101.24567)
		)
		(stroke
			(width 0)
			(type solid)
		)
		(fill yes)
		(layer "In11.Cu")
		(net "M_F_DQ<16>")
	)
	(gr_poly
		(pts
			(xy 234.623102 -90.14968) (xy 234.60075 -90.111326) (xy 234.438698 -90.008456) (xy 234.247436 -90.118946)
			(xy 234.255564 -90.310716) (xy 234.277662 -90.34907)
		)
		(stroke
			(width 0)
			(type solid)
		)
		(fill yes)
		(layer "In11.Cu")
		(net "M_F_DQ<2>")
	)
	(gr_poly
		(pts
			(xy 234.623102 -89.15908) (xy 234.60075 -89.120726) (xy 234.438698 -89.017856) (xy 234.247436 -89.128346)
			(xy 234.255564 -89.320116) (xy 234.277662 -89.35847)
		)
		(stroke
			(width 0)
			(type solid)
		)
		(fill yes)
		(layer "In11.Cu")
		(net "M_F_DQ<6>")
	)
	(gr_poly
		(pts
			(xy 234.623102 -88.16848) (xy 234.60075 -88.130126) (xy 234.438698 -88.027256) (xy 234.247436 -88.137746)
			(xy 234.255564 -88.329516) (xy 234.277662 -88.36787)
		)
		(stroke
			(width 0)
			(type solid)
		)
		(fill yes)
		(layer "In11.Cu")
		(net "M_F_DQS_DN<0>")
	)
	(gr_poly
		(pts
			(xy 234.623102 -87.17788) (xy 234.60075 -87.139526) (xy 234.438698 -87.036656) (xy 234.247436 -87.147146)
			(xy 234.255564 -87.338916) (xy 234.277662 -87.37727)
		)
		(stroke
			(width 0)
			(type solid)
		)
		(fill yes)
		(layer "In11.Cu")
		(net "M_F_DQS_DP<9>")
	)
	(gr_poly
		(pts
			(xy 234.623102 -86.18728) (xy 234.60075 -86.148926) (xy 234.438698 -86.046056) (xy 234.247436 -86.156546)
			(xy 234.255564 -86.348316) (xy 234.277662 -86.38667)
		)
		(stroke
			(width 0)
			(type solid)
		)
		(fill yes)
		(layer "In11.Cu")
		(net "M_F_DQ<0>")
	)
	(gr_poly
		(pts
			(xy 234.623102 -85.19668) (xy 234.60075 -85.158326) (xy 234.438698 -85.055456) (xy 234.247436 -85.165946)
			(xy 234.255564 -85.357716) (xy 234.277662 -85.39607)
		)
		(stroke
			(width 0)
			(type solid)
		)
		(fill yes)
		(layer "In11.Cu")
		(net "M_F_DQ<4>")
	)
	(gr_poly
		(pts
			(xy 234.623102 -66.37528) (xy 234.60075 -66.336926) (xy 234.438698 -66.234056) (xy 234.247436 -66.344546)
			(xy 234.255564 -66.536316) (xy 234.277662 -66.574924)
		)
		(stroke
			(width 0)
			(type solid)
		)
		(fill yes)
		(layer "In11.Cu")
		(net "M_C_DQ<5>")
	)
	(gr_poly
		(pts
			(xy 234.623102 -65.38468) (xy 234.60075 -65.346326) (xy 234.438698 -65.243456) (xy 234.247436 -65.353946)
			(xy 234.255564 -65.545716) (xy 234.277662 -65.584324)
		)
		(stroke
			(width 0)
			(type solid)
		)
		(fill yes)
		(layer "In11.Cu")
		(net "M_C_DQ<1>")
	)
	(gr_poly
		(pts
			(xy 234.623102 -62.41288) (xy 234.60075 -62.374526) (xy 234.438698 -62.271656) (xy 234.247436 -62.382146)
			(xy 234.255564 -62.573916) (xy 234.277662 -62.612524)
		)
		(stroke
			(width 0)
			(type solid)
		)
		(fill yes)
		(layer "In11.Cu")
		(net "M_C_DQ<7>")
	)
	(gr_poly
		(pts
			(xy 234.623102 -61.42228) (xy 234.60075 -61.383926) (xy 234.438698 -61.281056) (xy 234.247436 -61.391546)
			(xy 234.255564 -61.583316) (xy 234.277662 -61.621924)
		)
		(stroke
			(width 0)
			(type solid)
		)
		(fill yes)
		(layer "In11.Cu")
		(net "M_C_DQ<3>")
	)
	(gr_poly
		(pts
			(xy 234.623102 -60.43168) (xy 234.60075 -60.393326) (xy 234.438698 -60.290456) (xy 234.247436 -60.400946)
			(xy 234.255564 -60.592716) (xy 234.277662 -60.631324)
		)
		(stroke
			(width 0)
			(type solid)
		)
		(fill yes)
		(layer "In11.Cu")
		(net "M_C_DQ<13>")
	)
	(gr_poly
		(pts
			(xy 234.625388 -97.082864) (xy 234.603036 -97.04451) (xy 234.440984 -96.941386) (xy 234.249468 -97.051876)
			(xy 234.25785 -97.243646) (xy 234.279948 -97.282254)
		)
		(stroke
			(width 0)
			(type solid)
		)
		(fill yes)
		(layer "In11.Cu")
		(net "M_F_DQ<20>")
	)
	(gr_poly
		(pts
			(xy 234.630722 -64.390016) (xy 234.60837 -64.351408) (xy 234.446318 -64.248538) (xy 234.255056 -64.359028)
			(xy 234.263184 -64.550798) (xy 234.285282 -64.589406)
		)
		(stroke
			(width 0)
			(type solid)
		)
		(fill yes)
		(layer "In11.Cu")
		(net "M_C_DQS_DN<9>")
	)
	(gr_poly
		(pts
			(xy 234.630722 -63.399416) (xy 234.60837 -63.360808) (xy 234.446318 -63.257938) (xy 234.255056 -63.368428)
			(xy 234.263184 -63.560198) (xy 234.285282 -63.598806)
		)
		(stroke
			(width 0)
			(type solid)
		)
		(fill yes)
		(layer "In11.Cu")
		(net "M_C_DQS_DN<0>")
	)
	(gr_poly
		(pts
			(xy 234.700318 -53.728874) (xy 234.700318 -53.507894) (xy 234.530392 -53.418994) (xy 234.485942 -53.418994)
			(xy 234.485688 -53.817774) (xy 234.530138 -53.817774)
		)
		(stroke
			(width 0)
			(type solid)
		)
		(fill yes)
		(layer "In11.Cu")
		(net "M_C_DQ<21>")
	)
	(gr_poly
		(pts
			(xy 234.700826 -99.28733) (xy 234.700826 -99.06635) (xy 234.530646 -98.97745) (xy 234.486196 -98.97745)
			(xy 234.486196 -99.37623) (xy 234.530646 -99.37623)
		)
		(stroke
			(width 0)
			(type solid)
		)
		(fill yes)
		(layer "In11.Cu")
		(net "M_F_DQ<21>")
	)
	(gr_poly
		(pts
			(xy 234.700826 -98.29673) (xy 234.700826 -98.07575) (xy 234.530646 -97.98685) (xy 234.486196 -97.98685)
			(xy 234.486196 -98.38563) (xy 234.530646 -98.38563)
		)
		(stroke
			(width 0)
			(type solid)
		)
		(fill yes)
		(layer "In11.Cu")
		(net "M_F_DQ<21>")
	)
	(gr_poly
		(pts
			(xy 234.700826 -51.73853) (xy 234.700826 -51.51755) (xy 234.530646 -51.42865) (xy 234.486196 -51.42865)
			(xy 234.486196 -51.82743) (xy 234.530646 -51.82743)
		)
		(stroke
			(width 0)
			(type solid)
		)
		(fill yes)
		(layer "In11.Cu")
		(net "M_C_DQ<17>")
	)
	(gr_poly
		(pts
			(xy 234.93603 -50.728118) (xy 234.974892 -50.705766) (xy 234.775248 -50.36058) (xy 234.736894 -50.382678)
			(xy 234.634024 -50.54473) (xy 234.744514 -50.736246)
		)
		(stroke
			(width 0)
			(type solid)
		)
		(fill yes)
		(layer "In11.Cu")
		(net "M_C_DQS_DP<11>")
	)
	(gr_poly
		(pts
			(xy 235.02112 -99.974146) (xy 234.97667 -99.974146) (xy 234.80649 -100.063046) (xy 234.80649 -100.284026)
			(xy 234.97667 -100.372926) (xy 235.02112 -100.372926)
		)
		(stroke
			(width 0)
			(type solid)
		)
		(fill yes)
		(layer "In11.Cu")
		(net "M_F_DQ<16>")
	)
	(gr_poly
		(pts
			(xy 235.02112 -98.97745) (xy 234.97667 -98.97745) (xy 234.80649 -99.06635) (xy 234.80649 -99.28733)
			(xy 234.97667 -99.37623) (xy 235.02112 -99.37623)
		)
		(stroke
			(width 0)
			(type solid)
		)
		(fill yes)
		(layer "In11.Cu")
		(net "M_F_DQ<16>")
	)
	(gr_poly
		(pts
			(xy 235.021374 -53.398928) (xy 234.976924 -53.399182) (xy 234.806744 -53.487828) (xy 234.806744 -53.708808)
			(xy 234.976924 -53.797708) (xy 235.021374 -53.797962)
		)
		(stroke
			(width 0)
			(type solid)
		)
		(fill yes)
		(layer "In11.Cu")
		(net "M_C_DQ<16>")
	)
	(gr_poly
		(pts
			(xy 235.021628 -51.421538) (xy 234.977178 -51.421538) (xy 234.806998 -51.510438) (xy 234.806998 -51.731418)
			(xy 234.976924 -51.820318) (xy 235.021628 -51.820318)
		)
		(stroke
			(width 0)
			(type solid)
		)
		(fill yes)
		(layer "In11.Cu")
		(net "M_C_DQS_DP<11>")
	)
	(gr_poly
		(pts
			(xy 235.194856 -97.727516) (xy 235.156248 -97.705418) (xy 234.964478 -97.69729) (xy 234.853988 -97.888552)
			(xy 234.956858 -98.050604) (xy 234.995212 -98.072956)
		)
		(stroke
			(width 0)
			(type solid)
		)
		(fill yes)
		(layer "In11.Cu")
		(net "M_F_DQ<16>")
	)
	(gr_poly
		(pts
			(xy 235.244386 -64.550798) (xy 235.252514 -64.359028) (xy 235.061252 -64.248538) (xy 234.8992 -64.351408)
			(xy 234.876848 -64.390016) (xy 235.222288 -64.589406)
		)
		(stroke
			(width 0)
			(type solid)
		)
		(fill yes)
		(layer "In11.Cu")
		(net "M_C_DQS_DN<9>")
	)
	(gr_poly
		(pts
			(xy 235.244386 -63.560198) (xy 235.252514 -63.368428) (xy 235.061252 -63.257938) (xy 234.8992 -63.360808)
			(xy 234.876848 -63.399416) (xy 235.222288 -63.598806)
		)
		(stroke
			(width 0)
			(type solid)
		)
		(fill yes)
		(layer "In11.Cu")
		(net "M_C_DQS_DN<0>")
	)
	(gr_poly
		(pts
			(xy 235.251752 -66.536316) (xy 235.25988 -66.344546) (xy 235.068618 -66.234056) (xy 234.906566 -66.336926)
			(xy 234.884214 -66.37528) (xy 235.229654 -66.574924)
		)
		(stroke
			(width 0)
			(type solid)
		)
		(fill yes)
		(layer "In11.Cu")
		(net "M_C_DQ<5>")
	)
	(gr_poly
		(pts
			(xy 235.251752 -65.545716) (xy 235.25988 -65.353946) (xy 235.068618 -65.243456) (xy 234.906566 -65.346326)
			(xy 234.884214 -65.38468) (xy 235.229654 -65.584324)
		)
		(stroke
			(width 0)
			(type solid)
		)
		(fill yes)
		(layer "In11.Cu")
		(net "M_C_DQ<1>")
	)
	(gr_poly
		(pts
			(xy 235.251752 -62.573916) (xy 235.25988 -62.382146) (xy 235.068618 -62.271656) (xy 234.906566 -62.374526)
			(xy 234.884214 -62.41288) (xy 235.229654 -62.612524)
		)
		(stroke
			(width 0)
			(type solid)
		)
		(fill yes)
		(layer "In11.Cu")
		(net "M_C_DQ<7>")
	)
	(gr_poly
		(pts
			(xy 235.251752 -61.583316) (xy 235.25988 -61.391546) (xy 235.068618 -61.281056) (xy 234.906566 -61.383926)
			(xy 234.884214 -61.42228) (xy 235.229654 -61.621924)
		)
		(stroke
			(width 0)
			(type solid)
		)
		(fill yes)
		(layer "In11.Cu")
		(net "M_C_DQ<3>")
	)
	(gr_poly
		(pts
			(xy 235.251752 -60.592716) (xy 235.25988 -60.400946) (xy 235.068618 -60.290456) (xy 234.906566 -60.393326)
			(xy 234.884214 -60.43168) (xy 235.229654 -60.631324)
		)
		(stroke
			(width 0)
			(type solid)
		)
		(fill yes)
		(layer "In11.Cu")
		(net "M_C_DQ<13>")
	)
	(gr_poly
		(pts
			(xy 235.251752 -59.602116) (xy 235.25988 -59.410346) (xy 235.068618 -59.299856) (xy 234.906566 -59.402726)
			(xy 234.884214 -59.44108) (xy 235.229654 -59.640724)
		)
		(stroke
			(width 0)
			(type solid)
		)
		(fill yes)
		(layer "In11.Cu")
		(net "M_C_DQ<9>")
	)
	(gr_poly
		(pts
			(xy 235.251752 -56.630316) (xy 235.25988 -56.438546) (xy 235.068618 -56.328056) (xy 234.906566 -56.430926)
			(xy 234.884214 -56.46928) (xy 235.229654 -56.668924)
		)
		(stroke
			(width 0)
			(type solid)
		)
		(fill yes)
		(layer "In11.Cu")
		(net "M_C_DQ<15>")
	)
	(gr_poly
		(pts
			(xy 235.251752 -55.639716) (xy 235.25988 -55.447946) (xy 235.068618 -55.337456) (xy 234.906566 -55.440326)
			(xy 234.884214 -55.47868) (xy 235.229654 -55.678324)
		)
		(stroke
			(width 0)
			(type solid)
		)
		(fill yes)
		(layer "In11.Cu")
		(net "M_C_DQ<11>")
	)
	(gr_poly
		(pts
			(xy 235.251752 -54.649116) (xy 235.25988 -54.457346) (xy 235.068618 -54.346856) (xy 234.906566 -54.449726)
			(xy 234.884214 -54.48808) (xy 235.229654 -54.687724)
		)
		(stroke
			(width 0)
			(type solid)
		)
		(fill yes)
		(layer "In11.Cu")
		(net "M_C_DQ<21>")
	)
	(gr_poly
		(pts
			(xy 235.253276 -58.612278) (xy 235.261404 -58.420508) (xy 235.070142 -58.310018) (xy 234.90809 -58.412888)
			(xy 234.885738 -58.451242) (xy 235.231178 -58.650632)
		)
		(stroke
			(width 0)
			(type solid)
		)
		(fill yes)
		(layer "In11.Cu")
		(net "M_C_DQS_DN<10>")
	)
	(gr_poly
		(pts
			(xy 235.253276 -57.621932) (xy 235.261404 -57.430162) (xy 235.070142 -57.319672) (xy 234.90809 -57.422542)
			(xy 234.885738 -57.460896) (xy 235.231178 -57.660286)
		)
		(stroke
			(width 0)
			(type solid)
		)
		(fill yes)
		(layer "In11.Cu")
		(net "M_C_DQS_DN<1>")
	)
	(gr_poly
		(pts
			(xy 235.253276 -52.668678) (xy 235.261404 -52.476908) (xy 235.070142 -52.366418) (xy 234.90809 -52.469288)
			(xy 234.885738 -52.507642) (xy 235.231178 -52.707286)
		)
		(stroke
			(width 0)
			(type solid)
		)
		(fill yes)
		(layer "In11.Cu")
		(net "M_C_DQ<17>")
	)
	(gr_poly
		(pts
			(xy 235.257594 -97.33915) (xy 235.249466 -97.14738) (xy 235.227368 -97.108772) (xy 234.881928 -97.308162)
			(xy 234.90428 -97.34677) (xy 235.066332 -97.44964)
		)
		(stroke
			(width 0)
			(type solid)
		)
		(fill yes)
		(layer "In11.Cu")
		(net "M_F_DQ<21>")
	)
	(gr_poly
		(pts
			(xy 235.257594 -93.37675) (xy 235.249466 -93.18498) (xy 235.227368 -93.146372) (xy 234.881928 -93.345762)
			(xy 234.90428 -93.38437) (xy 235.066332 -93.48724)
		)
		(stroke
			(width 0)
			(type solid)
		)
		(fill yes)
		(layer "In11.Cu")
		(net "M_F_DQS_DN<10>")
	)
	(gr_poly
		(pts
			(xy 235.25988 -95.35668) (xy 235.251752 -95.16491) (xy 235.229654 -95.126302) (xy 234.884214 -95.325946)
			(xy 234.906566 -95.3643) (xy 235.068618 -95.46717)
		)
		(stroke
			(width 0)
			(type solid)
		)
		(fill yes)
		(layer "In11.Cu")
		(net "M_F_DQ<15>")
	)
	(gr_poly
		(pts
			(xy 235.25988 -94.36608) (xy 235.251752 -94.17431) (xy 235.229654 -94.135702) (xy 234.884214 -94.335346)
			(xy 234.906566 -94.3737) (xy 235.068618 -94.47657)
		)
		(stroke
			(width 0)
			(type solid)
		)
		(fill yes)
		(layer "In11.Cu")
		(net "M_F_DQS_DP<1>")
	)
	(gr_poly
		(pts
			(xy 235.261404 -101.299264) (xy 235.25353 -101.107494) (xy 235.231432 -101.06914) (xy 234.885738 -101.26853)
			(xy 234.90809 -101.306884) (xy 235.070142 -101.409754)
		)
		(stroke
			(width 0)
			(type solid)
		)
		(fill yes)
		(layer "In11.Cu")
		(net "M_F_DQ<17>")
	)
	(gr_poly
		(pts
			(xy 235.261404 -96.346264) (xy 235.253276 -96.154494) (xy 235.231178 -96.115886) (xy 234.885738 -96.31553)
			(xy 234.90809 -96.353884) (xy 235.070142 -96.456754)
		)
		(stroke
			(width 0)
			(type solid)
		)
		(fill yes)
		(layer "In11.Cu")
		(net "M_F_DQ<11>")
	)
	(gr_poly
		(pts
			(xy 235.261404 -92.383864) (xy 235.253276 -92.192094) (xy 235.231178 -92.153486) (xy 234.885738 -92.35313)
			(xy 234.90809 -92.391484) (xy 235.070142 -92.494354)
		)
		(stroke
			(width 0)
			(type solid)
		)
		(fill yes)
		(layer "In11.Cu")
		(net "M_F_DQ<9>")
	)
	(gr_poly
		(pts
			(xy 235.261404 -91.393264) (xy 235.253276 -91.201494) (xy 235.231178 -91.162886) (xy 234.885738 -91.36253)
			(xy 234.90809 -91.400884) (xy 235.070142 -91.503754)
		)
		(stroke
			(width 0)
			(type solid)
		)
		(fill yes)
		(layer "In11.Cu")
		(net "M_F_DQ<13>")
	)
	(gr_poly
		(pts
			(xy 235.261404 -90.402664) (xy 235.253276 -90.210894) (xy 235.231178 -90.172286) (xy 234.885738 -90.37193)
			(xy 234.90809 -90.410284) (xy 235.070142 -90.513154)
		)
		(stroke
			(width 0)
			(type solid)
		)
		(fill yes)
		(layer "In11.Cu")
		(net "M_F_DQ<3>")
	)
	(gr_poly
		(pts
			(xy 235.261404 -89.412064) (xy 235.253276 -89.220294) (xy 235.231178 -89.181686) (xy 234.885738 -89.38133)
			(xy 234.90809 -89.419684) (xy 235.070142 -89.522554)
		)
		(stroke
			(width 0)
			(type solid)
		)
		(fill yes)
		(layer "In11.Cu")
		(net "M_F_DQ<7>")
	)
	(gr_poly
		(pts
			(xy 235.261404 -88.421464) (xy 235.253276 -88.229694) (xy 235.231178 -88.191086) (xy 234.885738 -88.39073)
			(xy 234.90809 -88.429084) (xy 235.070142 -88.531954)
		)
		(stroke
			(width 0)
			(type solid)
		)
		(fill yes)
		(layer "In11.Cu")
		(net "M_F_DQS_DP<0>")
	)
	(gr_poly
		(pts
			(xy 235.261404 -87.430864) (xy 235.253276 -87.239094) (xy 235.231178 -87.200486) (xy 234.885738 -87.40013)
			(xy 234.90809 -87.438484) (xy 235.070142 -87.541354)
		)
		(stroke
			(width 0)
			(type solid)
		)
		(fill yes)
		(layer "In11.Cu")
		(net "M_F_DQS_DN<9>")
	)
	(gr_poly
		(pts
			(xy 235.261404 -86.440264) (xy 235.253276 -86.248494) (xy 235.231178 -86.209886) (xy 234.885738 -86.40953)
			(xy 234.90809 -86.447884) (xy 235.070142 -86.550754)
		)
		(stroke
			(width 0)
			(type solid)
		)
		(fill yes)
		(layer "In11.Cu")
		(net "M_F_DQ<1>")
	)
	(gr_poly
		(pts
			(xy 235.261404 -85.449664) (xy 235.253276 -85.257894) (xy 235.231178 -85.219286) (xy 234.885738 -85.41893)
			(xy 234.90809 -85.457284) (xy 235.070142 -85.560154)
		)
		(stroke
			(width 0)
			(type solid)
		)
		(fill yes)
		(layer "In11.Cu")
		(net "M_F_DQ<5>")
	)
	(gr_poly
		(pts
			(xy 235.388912 -100.850954) (xy 235.559092 -100.762054) (xy 235.559092 -100.541074) (xy 235.388912 -100.452174)
			(xy 235.344716 -100.452174) (xy 235.344462 -100.851208)
		)
		(stroke
			(width 0)
			(type solid)
		)
		(fill yes)
		(layer "In11.Cu")
		(net "M_F_DQ<17>")
	)
	(gr_poly
		(pts
			(xy 235.388912 -53.323744) (xy 235.559092 -53.235098) (xy 235.559092 -53.014118) (xy 235.388912 -52.925218)
			(xy 235.344462 -52.924964) (xy 235.344462 -53.323998)
		)
		(stroke
			(width 0)
			(type solid)
		)
		(fill yes)
		(layer "In11.Cu")
		(net "M_C_DQ<17>")
	)
	(gr_poly
		(pts
			(xy 235.402882 -103.39832) (xy 235.329222 -103.19893) (xy 235.29798 -103.167434) (xy 235.010452 -103.454962)
			(xy 235.041948 -103.486204) (xy 235.241338 -103.559864)
		)
		(stroke
			(width 0)
			(type solid)
		)
		(fill yes)
		(layer "In11.Cu")
		(net "M_F_DQS_DN<11>")
	)
	(gr_poly
		(pts
			(xy 235.417106 -102.778814) (xy 235.38561 -102.747318) (xy 235.186474 -102.673658) (xy 235.024676 -102.835456)
			(xy 235.098336 -103.034592) (xy 235.129832 -103.066088)
		)
		(stroke
			(width 0)
			(type solid)
		)
		(fill yes)
		(layer "In11.Cu")
		(net "M_F_DQS_DP<11>")
	)
	(gr_poly
		(pts
			(xy 235.457746 -65.150238) (xy 235.480098 -65.111884) (xy 235.134658 -64.91224) (xy 235.11256 -64.950848)
			(xy 235.104432 -65.142618) (xy 235.295694 -65.253108)
		)
		(stroke
			(width 0)
			(type solid)
		)
		(fill yes)
		(layer "In11.Cu")
		(net "M_C_DQS_DP<9>")
	)
	(gr_poly
		(pts
			(xy 235.457746 -60.197238) (xy 235.480098 -60.158884) (xy 235.134658 -59.95924) (xy 235.11256 -59.997848)
			(xy 235.104432 -60.189618) (xy 235.295694 -60.300108)
		)
		(stroke
			(width 0)
			(type solid)
		)
		(fill yes)
		(layer "In11.Cu")
		(net "M_C_DQ<8>")
	)
	(gr_poly
		(pts
			(xy 235.457746 -58.216038) (xy 235.480098 -58.177684) (xy 235.134658 -57.97804) (xy 235.11256 -58.016648)
			(xy 235.104432 -58.208418) (xy 235.295694 -58.318908)
		)
		(stroke
			(width 0)
			(type solid)
		)
		(fill yes)
		(layer "In11.Cu")
		(net "M_C_DQS_DP<1>")
	)
	(gr_poly
		(pts
			(xy 235.457746 -54.253638) (xy 235.480098 -54.215284) (xy 235.134658 -54.01564) (xy 235.11256 -54.054248)
			(xy 235.104432 -54.246018) (xy 235.295694 -54.356508)
		)
		(stroke
			(width 0)
			(type solid)
		)
		(fill yes)
		(layer "In11.Cu")
		(net "M_C_DQ<16>")
	)
	(gr_poly
		(pts
			(xy 235.45927 -67.1322) (xy 235.481622 -67.093592) (xy 235.136182 -66.894456) (xy 235.114084 -66.93281)
			(xy 235.105956 -67.12458) (xy 235.297218 -67.23507)
		)
		(stroke
			(width 0)
			(type solid)
		)
		(fill yes)
		(layer "In11.Cu")
		(net "M_C_DQ<4>")
	)
	(gr_poly
		(pts
			(xy 235.45927 -66.1416) (xy 235.481622 -66.102992) (xy 235.136182 -65.903602) (xy 235.114084 -65.94221)
			(xy 235.105956 -66.13398) (xy 235.297218 -66.24447)
		)
		(stroke
			(width 0)
			(type solid)
		)
		(fill yes)
		(layer "In11.Cu")
		(net "M_C_DQ<0>")
	)
	(gr_poly
		(pts
			(xy 235.45927 -63.1698) (xy 235.481622 -63.131192) (xy 235.136182 -62.931802) (xy 235.114084 -62.97041)
			(xy 235.105956 -63.16218) (xy 235.297218 -63.27267)
		)
		(stroke
			(width 0)
			(type solid)
		)
		(fill yes)
		(layer "In11.Cu")
		(net "M_C_DQ<6>")
	)
	(gr_poly
		(pts
			(xy 235.45927 -62.1792) (xy 235.481622 -62.140592) (xy 235.136182 -61.941202) (xy 235.114084 -61.97981)
			(xy 235.105956 -62.17158) (xy 235.297218 -62.28207)
		)
		(stroke
			(width 0)
			(type solid)
		)
		(fill yes)
		(layer "In11.Cu")
		(net "M_C_DQ<2>")
	)
	(gr_poly
		(pts
			(xy 235.45927 -61.1886) (xy 235.481622 -61.149992) (xy 235.136182 -60.950602) (xy 235.114084 -60.98921)
			(xy 235.105956 -61.18098) (xy 235.297218 -61.29147)
		)
		(stroke
			(width 0)
			(type solid)
		)
		(fill yes)
		(layer "In11.Cu")
		(net "M_C_DQ<12>")
	)
	(gr_poly
		(pts
			(xy 235.45927 -57.2262) (xy 235.481622 -57.187592) (xy 235.136182 -56.988202) (xy 235.114084 -57.02681)
			(xy 235.105956 -57.21858) (xy 235.297218 -57.32907)
		)
		(stroke
			(width 0)
			(type solid)
		)
		(fill yes)
		(layer "In11.Cu")
		(net "M_C_DQ<14>")
	)
	(gr_poly
		(pts
			(xy 235.45927 -56.2356) (xy 235.481622 -56.196992) (xy 235.136182 -55.997602) (xy 235.114084 -56.03621)
			(xy 235.105956 -56.22798) (xy 235.297218 -56.33847)
		)
		(stroke
			(width 0)
			(type solid)
		)
		(fill yes)
		(layer "In11.Cu")
		(net "M_C_DQ<10>")
	)
	(gr_poly
		(pts
			(xy 235.45927 -55.245) (xy 235.481622 -55.206392) (xy 235.136182 -55.007002) (xy 235.114084 -55.04561)
			(xy 235.105956 -55.23738) (xy 235.297218 -55.34787)
		)
		(stroke
			(width 0)
			(type solid)
		)
		(fill yes)
		(layer "In11.Cu")
		(net "M_C_DQ<20>")
	)
	(gr_poly
		(pts
			(xy 235.461048 -52.274216) (xy 235.4834 -52.235608) (xy 235.13796 -52.036218) (xy 235.115862 -52.074826)
			(xy 235.107734 -52.266596) (xy 235.298996 -52.377086)
		)
		(stroke
			(width 0)
			(type solid)
		)
		(fill yes)
		(layer "In11.Cu")
		(net "M_C_DQS_DP<11>")
	)
	(gr_poly
		(pts
			(xy 235.461556 -59.20867) (xy 235.483908 -59.170316) (xy 235.138468 -58.970672) (xy 235.11637 -59.00928)
			(xy 235.108242 -59.20105) (xy 235.299504 -59.31154)
		)
		(stroke
			(width 0)
			(type solid)
		)
		(fill yes)
		(layer "In11.Cu")
		(net "M_C_DQS_DP<10>")
	)
	(gr_poly
		(pts
			(xy 235.480098 -96.58985) (xy 235.457746 -96.551242) (xy 235.295694 -96.448372) (xy 235.104432 -96.558862)
			(xy 235.11256 -96.750632) (xy 235.134658 -96.78924)
		)
		(stroke
			(width 0)
			(type solid)
		)
		(fill yes)
		(layer "In11.Cu")
		(net "M_F_DQ<20>")
	)
	(gr_poly
		(pts
			(xy 235.480098 -95.59925) (xy 235.457746 -95.560642) (xy 235.295694 -95.457772) (xy 235.104432 -95.568262)
			(xy 235.11256 -95.760032) (xy 235.134658 -95.79864)
		)
		(stroke
			(width 0)
			(type solid)
		)
		(fill yes)
		(layer "In11.Cu")
		(net "M_F_DQ<10>")
	)
	(gr_poly
		(pts
			(xy 235.480098 -92.62745) (xy 235.457746 -92.588842) (xy 235.295694 -92.485972) (xy 235.104432 -92.596462)
			(xy 235.11256 -92.788232) (xy 235.134658 -92.82684)
		)
		(stroke
			(width 0)
			(type solid)
		)
		(fill yes)
		(layer "In11.Cu")
		(net "M_F_DQS_DP<10>")
	)
	(gr_poly
		(pts
			(xy 235.480098 -91.63685) (xy 235.457746 -91.598242) (xy 235.295694 -91.495372) (xy 235.104432 -91.605862)
			(xy 235.11256 -91.797632) (xy 235.134658 -91.83624)
		)
		(stroke
			(width 0)
			(type solid)
		)
		(fill yes)
		(layer "In11.Cu")
		(net "M_F_DQ<8>")
	)
	(gr_poly
		(pts
			(xy 235.480098 -90.64625) (xy 235.457746 -90.607642) (xy 235.295694 -90.504772) (xy 235.104432 -90.615262)
			(xy 235.11256 -90.807032) (xy 235.134658 -90.84564)
		)
		(stroke
			(width 0)
			(type solid)
		)
		(fill yes)
		(layer "In11.Cu")
		(net "M_F_DQ<12>")
	)
	(gr_poly
		(pts
			(xy 235.480098 -89.65565) (xy 235.457746 -89.617042) (xy 235.295694 -89.514172) (xy 235.104432 -89.624662)
			(xy 235.11256 -89.816432) (xy 235.134658 -89.85504)
		)
		(stroke
			(width 0)
			(type solid)
		)
		(fill yes)
		(layer "In11.Cu")
		(net "M_F_DQ<2>")
	)
	(gr_poly
		(pts
			(xy 235.480098 -88.66505) (xy 235.457746 -88.626442) (xy 235.295694 -88.523572) (xy 235.104432 -88.634062)
			(xy 235.11256 -88.825832) (xy 235.134658 -88.86444)
		)
		(stroke
			(width 0)
			(type solid)
		)
		(fill yes)
		(layer "In11.Cu")
		(net "M_F_DQ<6>")
	)
	(gr_poly
		(pts
			(xy 235.480098 -87.67445) (xy 235.457746 -87.635842) (xy 235.295694 -87.532972) (xy 235.104432 -87.643462)
			(xy 235.11256 -87.835232) (xy 235.134658 -87.87384)
		)
		(stroke
			(width 0)
			(type solid)
		)
		(fill yes)
		(layer "In11.Cu")
		(net "M_F_DQS_DN<0>")
	)
	(gr_poly
		(pts
			(xy 235.480098 -86.68385) (xy 235.457746 -86.645242) (xy 235.295694 -86.542372) (xy 235.104432 -86.652862)
			(xy 235.11256 -86.844632) (xy 235.134658 -86.88324)
		)
		(stroke
			(width 0)
			(type solid)
		)
		(fill yes)
		(layer "In11.Cu")
		(net "M_F_DQS_DP<9>")
	)
	(gr_poly
		(pts
			(xy 235.480098 -85.69325) (xy 235.457746 -85.654642) (xy 235.295694 -85.551772) (xy 235.104432 -85.662262)
			(xy 235.11256 -85.854032) (xy 235.134658 -85.89264)
		)
		(stroke
			(width 0)
			(type solid)
		)
		(fill yes)
		(layer "In11.Cu")
		(net "M_F_DQ<0>")
	)
	(gr_poly
		(pts
			(xy 235.480098 -84.70265) (xy 235.457746 -84.664042) (xy 235.295694 -84.561172) (xy 235.104432 -84.671662)
			(xy 235.11256 -84.863432) (xy 235.134658 -84.90204)
		)
		(stroke
			(width 0)
			(type solid)
		)
		(fill yes)
		(layer "In11.Cu")
		(net "M_F_DQ<4>")
	)
	(gr_poly
		(pts
			(xy 235.481622 -93.61678) (xy 235.45927 -93.578426) (xy 235.297218 -93.475556) (xy 235.105956 -93.586046)
			(xy 235.114084 -93.777816) (xy 235.136182 -93.81617)
		)
		(stroke
			(width 0)
			(type solid)
		)
		(fill yes)
		(layer "In11.Cu")
		(net "M_F_DQS_DN<1>")
	)
	(gr_poly
		(pts
			(xy 235.483908 -94.60611) (xy 235.461556 -94.567756) (xy 235.299504 -94.464886) (xy 235.108242 -94.575376)
			(xy 235.11637 -94.767146) (xy 235.138468 -94.805754)
		)
		(stroke
			(width 0)
			(type solid)
		)
		(fill yes)
		(layer "In11.Cu")
		(net "M_F_DQ<14>")
	)
	(gr_poly
		(pts
			(xy 235.559092 -51.24958) (xy 235.559092 -51.0286) (xy 235.388912 -50.9397) (xy 235.344462 -50.9397)
			(xy 235.344462 -51.33848) (xy 235.388912 -51.33848)
		)
		(stroke
			(width 0)
			(type solid)
		)
		(fill yes)
		(layer "In11.Cu")
		(net "M_C_DQS_DN<11>")
	)
	(gr_poly
		(pts
			(xy 235.559346 -99.77628) (xy 235.559346 -99.5553) (xy 235.389166 -99.4664) (xy 235.344716 -99.4664)
			(xy 235.344716 -99.86518) (xy 235.389166 -99.86518)
		)
		(stroke
			(width 0)
			(type solid)
		)
		(fill yes)
		(layer "In11.Cu")
		(net "M_F_DQ<17>")
	)
	(gr_poly
		(pts
			(xy 235.559346 -98.79203) (xy 235.559346 -98.57105) (xy 235.389166 -98.48215) (xy 235.344716 -98.48215)
			(xy 235.344716 -98.88093) (xy 235.389166 -98.88093)
		)
		(stroke
			(width 0)
			(type solid)
		)
		(fill yes)
		(layer "In11.Cu")
		(net "M_F_DQ<17>")
	)
	(gr_poly
		(pts
			(xy 235.686092 -104.552242) (xy 235.612432 -104.352852) (xy 235.58119 -104.321356) (xy 235.293662 -104.608884)
			(xy 235.325158 -104.640126) (xy 235.524548 -104.713786)
		)
		(stroke
			(width 0)
			(type solid)
		)
		(fill yes)
		(layer "In11.Cu")
		(net "M_F_DQS_DP<2>")
	)
	(gr_poly
		(pts
			(xy 235.871004 -101.714554) (xy 235.826554 -101.714554) (xy 235.633514 -101.803454) (xy 235.633514 -102.032054)
			(xy 235.826554 -102.120954) (xy 235.871004 -102.120954)
		)
		(stroke
			(width 0)
			(type solid)
		)
		(fill yes)
		(layer "In11.Cu")
		(net "M_F_DQS_DP<11>")
	)
	(gr_poly
		(pts
			(xy 235.87964 -100.463096) (xy 235.83519 -100.463096) (xy 235.66501 -100.551996) (xy 235.66501 -100.772976)
			(xy 235.83519 -100.861876) (xy 235.87964 -100.861876)
		)
		(stroke
			(width 0)
			(type solid)
		)
		(fill yes)
		(layer "In11.Cu")
		(net "M_F_DQS_DP<11>")
	)
	(gr_poly
		(pts
			(xy 235.87964 -99.4664) (xy 235.83519 -99.4664) (xy 235.66501 -99.5553) (xy 235.66501 -99.77628)
			(xy 235.83519 -99.86518) (xy 235.87964 -99.86518)
		)
		(stroke
			(width 0)
			(type solid)
		)
		(fill yes)
		(layer "In11.Cu")
		(net "M_F_DQS_DP<11>")
	)
	(gr_poly
		(pts
			(xy 235.880148 -52.907184) (xy 235.835698 -52.907184) (xy 235.665518 -52.996084) (xy 235.665518 -53.217064)
			(xy 235.835444 -53.305964) (xy 235.880148 -53.305964)
		)
		(stroke
			(width 0)
			(type solid)
		)
		(fill yes)
		(layer "In11.Cu")
		(net "M_C_DQS_DP<11>")
	)
	(gr_poly
		(pts
			(xy 235.89742 -98.47326) (xy 235.85297 -98.473514) (xy 235.68279 -98.562414) (xy 235.68279 -98.78314)
			(xy 235.85297 -98.87204) (xy 235.897166 -98.872294)
		)
		(stroke
			(width 0)
			(type solid)
		)
		(fill yes)
		(layer "In11.Cu")
		(net "M_F_DQS_DP<11>")
	)
	(gr_poly
		(pts
			(xy 236.103414 -102.697788) (xy 236.029754 -102.498398) (xy 235.998512 -102.466902) (xy 235.710984 -102.75443)
			(xy 235.74248 -102.785672) (xy 235.94187 -102.859332)
		)
		(stroke
			(width 0)
			(type solid)
		)
		(fill yes)
		(layer "In11.Cu")
		(net "M_F_DQS_DN<11>")
	)
	(gr_poly
		(pts
			(xy 236.107986 -59.105546) (xy 236.116114 -58.913776) (xy 235.924852 -58.803286) (xy 235.7628 -58.906156)
			(xy 235.740448 -58.94451) (xy 236.085888 -59.1439)
		)
		(stroke
			(width 0)
			(type solid)
		)
		(fill yes)
		(layer "In11.Cu")
		(net "M_C_DQS_DN<10>")
	)
	(gr_poly
		(pts
			(xy 236.110272 -65.05067) (xy 236.1184 -64.8589) (xy 235.927138 -64.74841) (xy 235.765086 -64.85128)
			(xy 235.742734 -64.889634) (xy 236.088174 -65.089024)
		)
		(stroke
			(width 0)
			(type solid)
		)
		(fill yes)
		(layer "In11.Cu")
		(net "M_C_DQS_DN<9>")
	)
	(gr_poly
		(pts
			(xy 236.110272 -52.172616) (xy 236.1184 -51.980846) (xy 235.927138 -51.870356) (xy 235.765086 -51.973226)
			(xy 235.742734 -52.01158) (xy 236.088174 -52.211224)
		)
		(stroke
			(width 0)
			(type solid)
		)
		(fill yes)
		(layer "In11.Cu")
		(net "M_C_DQS_DN<11>")
	)
	(gr_poly
		(pts
			(xy 236.111796 -67.032632) (xy 236.119924 -66.840862) (xy 235.928662 -66.730372) (xy 235.76661 -66.833242)
			(xy 235.744258 -66.871596) (xy 236.089698 -67.07124)
		)
		(stroke
			(width 0)
			(type solid)
		)
		(fill yes)
		(layer "In11.Cu")
		(net "M_C_DQ<5>")
	)
	(gr_poly
		(pts
			(xy 236.111796 -66.042032) (xy 236.119924 -65.850262) (xy 235.928662 -65.739772) (xy 235.76661 -65.842642)
			(xy 235.744258 -65.880996) (xy 236.089698 -66.08064)
		)
		(stroke
			(width 0)
			(type solid)
		)
		(fill yes)
		(layer "In11.Cu")
		(net "M_C_DQ<1>")
	)
	(gr_poly
		(pts
			(xy 236.111796 -64.060832) (xy 236.119924 -63.869062) (xy 235.928662 -63.758572) (xy 235.76661 -63.861442)
			(xy 235.744258 -63.899796) (xy 236.089698 -64.09944)
		)
		(stroke
			(width 0)
			(type solid)
		)
		(fill yes)
		(layer "In11.Cu")
		(net "M_C_DQS_DN<0>")
	)
	(gr_poly
		(pts
			(xy 236.111796 -63.070232) (xy 236.119924 -62.878462) (xy 235.928662 -62.767972) (xy 235.76661 -62.870842)
			(xy 235.744258 -62.909196) (xy 236.089698 -63.10884)
		)
		(stroke
			(width 0)
			(type solid)
		)
		(fill yes)
		(layer "In11.Cu")
		(net "M_C_DQ<7>")
	)
	(gr_poly
		(pts
			(xy 236.111796 -62.079632) (xy 236.119924 -61.887862) (xy 235.928662 -61.777372) (xy 235.76661 -61.880242)
			(xy 235.744258 -61.918596) (xy 236.089698 -62.11824)
		)
		(stroke
			(width 0)
			(type solid)
		)
		(fill yes)
		(layer "In11.Cu")
		(net "M_C_DQ<3>")
	)
	(gr_poly
		(pts
			(xy 236.111796 -61.089032) (xy 236.119924 -60.897262) (xy 235.928662 -60.786772) (xy 235.76661 -60.889642)
			(xy 235.744258 -60.927996) (xy 236.089698 -61.12764)
		)
		(stroke
			(width 0)
			(type solid)
		)
		(fill yes)
		(layer "In11.Cu")
		(net "M_C_DQ<13>")
	)
	(gr_poly
		(pts
			(xy 236.111796 -60.098432) (xy 236.119924 -59.906662) (xy 235.928662 -59.796172) (xy 235.76661 -59.899042)
			(xy 235.744258 -59.937396) (xy 236.089698 -60.13704)
		)
		(stroke
			(width 0)
			(type solid)
		)
		(fill yes)
		(layer "In11.Cu")
		(net "M_C_DQ<9>")
	)
	(gr_poly
		(pts
			(xy 236.111796 -58.116978) (xy 236.119924 -57.925208) (xy 235.928662 -57.814718) (xy 235.76661 -57.917588)
			(xy 235.744258 -57.955942) (xy 236.089698 -58.155332)
		)
		(stroke
			(width 0)
			(type solid)
		)
		(fill yes)
		(layer "In11.Cu")
		(net "M_C_DQS_DN<1>")
	)
	(gr_poly
		(pts
			(xy 236.111796 -57.126632) (xy 236.119924 -56.934862) (xy 235.928662 -56.824372) (xy 235.76661 -56.927242)
			(xy 235.744258 -56.965596) (xy 236.089698 -57.16524)
		)
		(stroke
			(width 0)
			(type solid)
		)
		(fill yes)
		(layer "In11.Cu")
		(net "M_C_DQ<15>")
	)
	(gr_poly
		(pts
			(xy 236.111796 -56.136032) (xy 236.119924 -55.944262) (xy 235.928662 -55.833772) (xy 235.76661 -55.936642)
			(xy 235.744258 -55.974996) (xy 236.089698 -56.17464)
		)
		(stroke
			(width 0)
			(type solid)
		)
		(fill yes)
		(layer "In11.Cu")
		(net "M_C_DQ<11>")
	)
	(gr_poly
		(pts
			(xy 236.111796 -55.145432) (xy 236.119924 -54.953662) (xy 235.928662 -54.843172) (xy 235.76661 -54.946042)
			(xy 235.744258 -54.984396) (xy 236.089698 -55.18404)
		)
		(stroke
			(width 0)
			(type solid)
		)
		(fill yes)
		(layer "In11.Cu")
		(net "M_C_DQ<21>")
	)
	(gr_poly
		(pts
			(xy 236.111796 -54.154832) (xy 236.119924 -53.963062) (xy 235.928662 -53.852572) (xy 235.76661 -53.955442)
			(xy 235.744258 -53.993796) (xy 236.089698 -54.19344)
		)
		(stroke
			(width 0)
			(type solid)
		)
		(fill yes)
		(layer "In11.Cu")
		(net "M_C_DQ<17>")
	)
	(gr_poly
		(pts
			(xy 236.116114 -94.86265) (xy 236.107986 -94.67088) (xy 236.085888 -94.632272) (xy 235.740448 -94.831662)
			(xy 235.7628 -94.87027) (xy 235.924852 -94.97314)
		)
		(stroke
			(width 0)
			(type solid)
		)
		(fill yes)
		(layer "In11.Cu")
		(net "M_F_DQ<15>")
	)
	(gr_poly
		(pts
			(xy 236.1184 -97.83318) (xy 236.110272 -97.64141) (xy 236.088174 -97.602802) (xy 235.742734 -97.802446)
			(xy 235.765086 -97.8408) (xy 235.927138 -97.94367)
		)
		(stroke
			(width 0)
			(type solid)
		)
		(fill yes)
		(layer "In11.Cu")
		(net "M_F_DQ<17>")
	)
	(gr_poly
		(pts
			(xy 236.1184 -96.84258) (xy 236.110272 -96.65081) (xy 236.088174 -96.612202) (xy 235.742734 -96.811846)
			(xy 235.765086 -96.8502) (xy 235.927138 -96.95307)
		)
		(stroke
			(width 0)
			(type solid)
		)
		(fill yes)
		(layer "In11.Cu")
		(net "M_F_DQ<21>")
	)
	(gr_poly
		(pts
			(xy 236.1184 -95.85198) (xy 236.110272 -95.66021) (xy 236.088174 -95.621602) (xy 235.742734 -95.821246)
			(xy 235.765086 -95.8596) (xy 235.927138 -95.96247)
		)
		(stroke
			(width 0)
			(type solid)
		)
		(fill yes)
		(layer "In11.Cu")
		(net "M_F_DQ<11>")
	)
	(gr_poly
		(pts
			(xy 236.1184 -92.88018) (xy 236.110272 -92.68841) (xy 236.088174 -92.649802) (xy 235.742734 -92.849446)
			(xy 235.765086 -92.8878) (xy 235.927138 -92.99067)
		)
		(stroke
			(width 0)
			(type solid)
		)
		(fill yes)
		(layer "In11.Cu")
		(net "M_F_DQS_DN<10>")
	)
	(gr_poly
		(pts
			(xy 236.1184 -91.88958) (xy 236.110272 -91.69781) (xy 236.088174 -91.659202) (xy 235.742734 -91.858846)
			(xy 235.765086 -91.8972) (xy 235.927138 -92.00007)
		)
		(stroke
			(width 0)
			(type solid)
		)
		(fill yes)
		(layer "In11.Cu")
		(net "M_F_DQ<9>")
	)
	(gr_poly
		(pts
			(xy 236.1184 -90.89898) (xy 236.110272 -90.70721) (xy 236.088174 -90.668602) (xy 235.742734 -90.868246)
			(xy 235.765086 -90.9066) (xy 235.927138 -91.00947)
		)
		(stroke
			(width 0)
			(type solid)
		)
		(fill yes)
		(layer "In11.Cu")
		(net "M_F_DQ<13>")
	)
	(gr_poly
		(pts
			(xy 236.1184 -89.90838) (xy 236.110272 -89.71661) (xy 236.088174 -89.678002) (xy 235.742734 -89.877646)
			(xy 235.765086 -89.916) (xy 235.927138 -90.01887)
		)
		(stroke
			(width 0)
			(type solid)
		)
		(fill yes)
		(layer "In11.Cu")
		(net "M_F_DQ<3>")
	)
	(gr_poly
		(pts
			(xy 236.1184 -88.91778) (xy 236.110272 -88.72601) (xy 236.088174 -88.687402) (xy 235.742734 -88.887046)
			(xy 235.765086 -88.9254) (xy 235.927138 -89.02827)
		)
		(stroke
			(width 0)
			(type solid)
		)
		(fill yes)
		(layer "In11.Cu")
		(net "M_F_DQ<7>")
	)
	(gr_poly
		(pts
			(xy 236.1184 -87.92718) (xy 236.110272 -87.73541) (xy 236.088174 -87.696802) (xy 235.742734 -87.896446)
			(xy 235.765086 -87.9348) (xy 235.927138 -88.03767)
		)
		(stroke
			(width 0)
			(type solid)
		)
		(fill yes)
		(layer "In11.Cu")
		(net "M_F_DQS_DP<0>")
	)
	(gr_poly
		(pts
			(xy 236.1184 -86.93658) (xy 236.110272 -86.74481) (xy 236.088174 -86.706202) (xy 235.742734 -86.905846)
			(xy 235.765086 -86.9442) (xy 235.927138 -87.04707)
		)
		(stroke
			(width 0)
			(type solid)
		)
		(fill yes)
		(layer "In11.Cu")
		(net "M_F_DQS_DN<9>")
	)
	(gr_poly
		(pts
			(xy 236.1184 -85.94598) (xy 236.110272 -85.75421) (xy 236.088174 -85.715602) (xy 235.742734 -85.915246)
			(xy 235.765086 -85.9536) (xy 235.927138 -86.05647)
		)
		(stroke
			(width 0)
			(type solid)
		)
		(fill yes)
		(layer "In11.Cu")
		(net "M_F_DQ<1>")
	)
	(gr_poly
		(pts
			(xy 236.1184 -84.95538) (xy 236.110272 -84.76361) (xy 236.088174 -84.725002) (xy 235.742734 -84.924646)
			(xy 235.765086 -84.963) (xy 235.927138 -85.06587)
		)
		(stroke
			(width 0)
			(type solid)
		)
		(fill yes)
		(layer "In11.Cu")
		(net "M_F_DQ<5>")
	)
	(gr_poly
		(pts
			(xy 236.119924 -93.870018) (xy 236.111796 -93.678248) (xy 236.089698 -93.639894) (xy 235.744258 -93.83903)
			(xy 235.76661 -93.877638) (xy 235.928662 -93.980508)
		)
		(stroke
			(width 0)
			(type solid)
		)
		(fill yes)
		(layer "In11.Cu")
		(net "M_F_DQS_DP<1>")
	)
	(gr_poly
		(pts
			(xy 236.137958 -103.47706) (xy 236.106462 -103.445818) (xy 235.907072 -103.372158) (xy 235.745528 -103.533702)
			(xy 235.819188 -103.733092) (xy 235.85043 -103.764588)
		)
		(stroke
			(width 0)
			(type solid)
		)
		(fill yes)
		(layer "In11.Cu")
		(net "M_F_DQS_DN<2>")
	)
	(gr_poly
		(pts
			(xy 236.316266 -67.626484) (xy 236.338618 -67.587876) (xy 235.993178 -67.38874) (xy 235.97108 -67.427094)
			(xy 235.962952 -67.618864) (xy 236.154214 -67.729354)
		)
		(stroke
			(width 0)
			(type solid)
		)
		(fill yes)
		(layer "In11.Cu")
		(net "M_C_DQ<4>")
	)
	(gr_poly
		(pts
			(xy 236.316266 -66.635884) (xy 236.338618 -66.597276) (xy 235.993178 -66.397886) (xy 235.97108 -66.436494)
			(xy 235.962952 -66.628264) (xy 236.154214 -66.738754)
		)
		(stroke
			(width 0)
			(type solid)
		)
		(fill yes)
		(layer "In11.Cu")
		(net "M_C_DQ<0>")
	)
	(gr_poly
		(pts
			(xy 236.316266 -65.645284) (xy 236.338618 -65.60693) (xy 235.993178 -65.407286) (xy 235.97108 -65.445894)
			(xy 235.962952 -65.637664) (xy 236.154214 -65.748154)
		)
		(stroke
			(width 0)
			(type solid)
		)
		(fill yes)
		(layer "In11.Cu")
		(net "M_C_DQS_DP<9>")
	)
	(gr_poly
		(pts
			(xy 236.316266 -64.654684) (xy 236.338618 -64.61633) (xy 235.993178 -64.416686) (xy 235.97108 -64.455294)
			(xy 235.962952 -64.647064) (xy 236.154214 -64.757554)
		)
		(stroke
			(width 0)
			(type solid)
		)
		(fill yes)
		(layer "In11.Cu")
		(net "M_C_DQS_DP<0>")
	)
	(gr_poly
		(pts
			(xy 236.316266 -63.664084) (xy 236.338618 -63.62573) (xy 235.993178 -63.426086) (xy 235.97108 -63.464694)
			(xy 235.962952 -63.656464) (xy 236.154214 -63.766954)
		)
		(stroke
			(width 0)
			(type solid)
		)
		(fill yes)
		(layer "In11.Cu")
		(net "M_C_DQ<6>")
	)
	(gr_poly
		(pts
			(xy 236.316266 -62.673484) (xy 236.338618 -62.63513) (xy 235.993178 -62.435486) (xy 235.97108 -62.474094)
			(xy 235.962952 -62.665864) (xy 236.154214 -62.776354)
		)
		(stroke
			(width 0)
			(type solid)
		)
		(fill yes)
		(layer "In11.Cu")
		(net "M_C_DQ<2>")
	)
	(gr_poly
		(pts
			(xy 236.316266 -61.682884) (xy 236.338618 -61.64453) (xy 235.993178 -61.444886) (xy 235.97108 -61.483494)
			(xy 235.962952 -61.675264) (xy 236.154214 -61.785754)
		)
		(stroke
			(width 0)
			(type solid)
		)
		(fill yes)
		(layer "In11.Cu")
		(net "M_C_DQ<12>")
	)
	(gr_poly
		(pts
			(xy 236.316266 -60.692284) (xy 236.338618 -60.65393) (xy 235.993178 -60.454286) (xy 235.97108 -60.492894)
			(xy 235.962952 -60.684664) (xy 236.154214 -60.795154)
		)
		(stroke
			(width 0)
			(type solid)
		)
		(fill yes)
		(layer "In11.Cu")
		(net "M_C_DQ<8>")
	)
	(gr_poly
		(pts
			(xy 236.316266 -59.701684) (xy 236.338618 -59.66333) (xy 235.993178 -59.463686) (xy 235.97108 -59.502294)
			(xy 235.962952 -59.694064) (xy 236.154214 -59.804554)
		)
		(stroke
			(width 0)
			(type solid)
		)
		(fill yes)
		(layer "In11.Cu")
		(net "M_C_DQS_DP<10>")
	)
	(gr_poly
		(pts
			(xy 236.316266 -58.711338) (xy 236.338618 -58.672984) (xy 235.993178 -58.47334) (xy 235.97108 -58.511948)
			(xy 235.962952 -58.703718) (xy 236.154214 -58.814208)
		)
		(stroke
			(width 0)
			(type solid)
		)
		(fill yes)
		(layer "In11.Cu")
		(net "M_C_DQS_DP<1>")
	)
	(gr_poly
		(pts
			(xy 236.316266 -56.729884) (xy 236.338618 -56.69153) (xy 235.993178 -56.491886) (xy 235.97108 -56.530494)
			(xy 235.962952 -56.722264) (xy 236.154214 -56.832754)
		)
		(stroke
			(width 0)
			(type solid)
		)
		(fill yes)
		(layer "In11.Cu")
		(net "M_C_DQ<10>")
	)
	(gr_poly
		(pts
			(xy 236.316266 -55.739284) (xy 236.338618 -55.70093) (xy 235.993178 -55.501286) (xy 235.97108 -55.539894)
			(xy 235.962952 -55.731664) (xy 236.154214 -55.842154)
		)
		(stroke
			(width 0)
			(type solid)
		)
		(fill yes)
		(layer "In11.Cu")
		(net "M_C_DQ<20>")
	)
	(gr_poly
		(pts
			(xy 236.316266 -54.748684) (xy 236.338618 -54.71033) (xy 235.993178 -54.510686) (xy 235.97108 -54.549294)
			(xy 235.962952 -54.741064) (xy 236.154214 -54.851554)
		)
		(stroke
			(width 0)
			(type solid)
		)
		(fill yes)
		(layer "In11.Cu")
		(net "M_C_DQ<16>")
	)
	(gr_poly
		(pts
			(xy 236.319568 -53.759862) (xy 236.34192 -53.721254) (xy 235.99648 -53.521864) (xy 235.974382 -53.560472)
			(xy 235.966254 -53.752242) (xy 236.157516 -53.862732)
		)
		(stroke
			(width 0)
			(type solid)
		)
		(fill yes)
		(layer "In11.Cu")
		(net "M_C_DQS_DP<11>")
	)
	(gr_poly
		(pts
			(xy 236.320076 -57.72277) (xy 236.342428 -57.684416) (xy 235.996988 -57.484772) (xy 235.97489 -57.52338)
			(xy 235.966762 -57.71515) (xy 236.158024 -57.82564)
		)
		(stroke
			(width 0)
			(type solid)
		)
		(fill yes)
		(layer "In11.Cu")
		(net "M_C_DQ<14>")
	)
	(gr_poly
		(pts
			(xy 236.338618 -94.112842) (xy 236.316266 -94.074488) (xy 236.154214 -93.971618) (xy 235.962952 -94.082108)
			(xy 235.97108 -94.273878) (xy 235.993178 -94.312486)
		)
		(stroke
			(width 0)
			(type solid)
		)
		(fill yes)
		(layer "In11.Cu")
		(net "M_F_DQ<14>")
	)
	(gr_poly
		(pts
			(xy 236.340142 -97.08388) (xy 236.31779 -97.045526) (xy 236.155738 -96.942656) (xy 235.964476 -97.053146)
			(xy 235.972604 -97.244916) (xy 235.994702 -97.28327)
		)
		(stroke
			(width 0)
			(type solid)
		)
		(fill yes)
		(layer "In11.Cu")
		(net "M_F_DQ<16>")
	)
	(gr_poly
		(pts
			(xy 236.340142 -96.09328) (xy 236.31779 -96.054926) (xy 236.155738 -95.952056) (xy 235.964476 -96.062546)
			(xy 235.972604 -96.254316) (xy 235.994702 -96.29267)
		)
		(stroke
			(width 0)
			(type solid)
		)
		(fill yes)
		(layer "In11.Cu")
		(net "M_F_DQ<20>")
	)
	(gr_poly
		(pts
			(xy 236.340142 -95.10268) (xy 236.31779 -95.064326) (xy 236.155738 -94.961456) (xy 235.964476 -95.071946)
			(xy 235.972604 -95.263716) (xy 235.994702 -95.30207)
		)
		(stroke
			(width 0)
			(type solid)
		)
		(fill yes)
		(layer "In11.Cu")
		(net "M_F_DQ<10>")
	)
	(gr_poly
		(pts
			(xy 236.340142 -92.13088) (xy 236.31779 -92.092526) (xy 236.155738 -91.989656) (xy 235.964476 -92.100146)
			(xy 235.972604 -92.291916) (xy 235.994702 -92.33027)
		)
		(stroke
			(width 0)
			(type solid)
		)
		(fill yes)
		(layer "In11.Cu")
		(net "M_F_DQS_DP<10>")
	)
	(gr_poly
		(pts
			(xy 236.340142 -91.14028) (xy 236.31779 -91.101926) (xy 236.155738 -90.999056) (xy 235.964476 -91.109546)
			(xy 235.972604 -91.301316) (xy 235.994702 -91.33967)
		)
		(stroke
			(width 0)
			(type solid)
		)
		(fill yes)
		(layer "In11.Cu")
		(net "M_F_DQ<8>")
	)
	(gr_poly
		(pts
			(xy 236.340142 -90.14968) (xy 236.31779 -90.111326) (xy 236.155738 -90.008456) (xy 235.964476 -90.118946)
			(xy 235.972604 -90.310716) (xy 235.994702 -90.34907)
		)
		(stroke
			(width 0)
			(type solid)
		)
		(fill yes)
		(layer "In11.Cu")
		(net "M_F_DQ<12>")
	)
	(gr_poly
		(pts
			(xy 236.340142 -89.15908) (xy 236.31779 -89.120726) (xy 236.155738 -89.017856) (xy 235.964476 -89.128346)
			(xy 235.972604 -89.320116) (xy 235.994702 -89.35847)
		)
		(stroke
			(width 0)
			(type solid)
		)
		(fill yes)
		(layer "In11.Cu")
		(net "M_F_DQ<2>")
	)
	(gr_poly
		(pts
			(xy 236.340142 -88.16848) (xy 236.31779 -88.130126) (xy 236.155738 -88.027256) (xy 235.964476 -88.137746)
			(xy 235.972604 -88.329516) (xy 235.994702 -88.36787)
		)
		(stroke
			(width 0)
			(type solid)
		)
		(fill yes)
		(layer "In11.Cu")
		(net "M_F_DQ<6>")
	)
	(gr_poly
		(pts
			(xy 236.340142 -87.17788) (xy 236.31779 -87.139526) (xy 236.155738 -87.036656) (xy 235.964476 -87.147146)
			(xy 235.972604 -87.338916) (xy 235.994702 -87.37727)
		)
		(stroke
			(width 0)
			(type solid)
		)
		(fill yes)
		(layer "In11.Cu")
		(net "M_F_DQS_DN<0>")
	)
	(gr_poly
		(pts
			(xy 236.340142 -86.18728) (xy 236.31779 -86.148926) (xy 236.155738 -86.046056) (xy 235.964476 -86.156546)
			(xy 235.972604 -86.348316) (xy 235.994702 -86.38667)
		)
		(stroke
			(width 0)
			(type solid)
		)
		(fill yes)
		(layer "In11.Cu")
		(net "M_F_DQS_DP<9>")
	)
	(gr_poly
		(pts
			(xy 236.340142 -85.19668) (xy 236.31779 -85.158326) (xy 236.155738 -85.055456) (xy 235.964476 -85.165946)
			(xy 235.972604 -85.357716) (xy 235.994702 -85.39607)
		)
		(stroke
			(width 0)
			(type solid)
		)
		(fill yes)
		(layer "In11.Cu")
		(net "M_F_DQ<0>")
	)
	(gr_poly
		(pts
			(xy 236.340142 -84.20608) (xy 236.31779 -84.167726) (xy 236.155738 -84.064856) (xy 235.964476 -84.175346)
			(xy 235.972604 -84.367116) (xy 235.994702 -84.40547)
		)
		(stroke
			(width 0)
			(type solid)
		)
		(fill yes)
		(layer "In11.Cu")
		(net "M_F_DQ<4>")
	)
	(gr_poly
		(pts
			(xy 236.342428 -93.12021) (xy 236.320076 -93.081856) (xy 236.158024 -92.978986) (xy 235.966762 -93.089476)
			(xy 235.97489 -93.281246) (xy 235.996988 -93.319854)
		)
		(stroke
			(width 0)
			(type solid)
		)
		(fill yes)
		(layer "In11.Cu")
		(net "M_F_DQS_DN<1>")
	)
	(gr_poly
		(pts
			(xy 236.356398 -98.063558) (xy 236.333792 -98.025204) (xy 236.17174 -97.922334) (xy 235.980732 -98.03257)
			(xy 235.98886 -98.22434) (xy 236.010704 -98.262948)
		)
		(stroke
			(width 0)
			(type solid)
		)
		(fill yes)
		(layer "In11.Cu")
		(net "M_F_DQS_DP<11>")
	)
	(gr_poly
		(pts
			(xy 236.386624 -103.85171) (xy 236.312964 -103.65232) (xy 236.281722 -103.620824) (xy 235.994194 -103.908352)
			(xy 236.02569 -103.939594) (xy 236.22508 -104.013254)
		)
		(stroke
			(width 0)
			(type solid)
		)
		(fill yes)
		(layer "In11.Cu")
		(net "M_F_DQS_DP<2>")
	)
	(gr_poly
		(pts
			(xy 236.417358 -52.73802) (xy 236.417358 -52.51704) (xy 236.247432 -52.42814) (xy 236.202982 -52.42814)
			(xy 236.202728 -52.82692) (xy 236.247178 -52.82692)
		)
		(stroke
			(width 0)
			(type solid)
		)
		(fill yes)
		(layer "In11.Cu")
		(net "M_C_DQS_DN<11>")
	)
	(gr_poly
		(pts
			(xy 236.417866 -101.26218) (xy 236.417866 -101.0412) (xy 236.247686 -100.9523) (xy 236.203236 -100.9523)
			(xy 236.203236 -101.35108) (xy 236.247686 -101.35108)
		)
		(stroke
			(width 0)
			(type solid)
		)
		(fill yes)
		(layer "In11.Cu")
		(net "M_F_DQS_DN<11>")
	)
	(gr_poly
		(pts
			(xy 236.417866 -100.284026) (xy 236.417866 -100.063046) (xy 236.247686 -99.974146) (xy 236.203236 -99.974146)
			(xy 236.203236 -100.372926) (xy 236.247686 -100.372926)
		)
		(stroke
			(width 0)
			(type solid)
		)
		(fill yes)
		(layer "In11.Cu")
		(net "M_F_DQS_DN<11>")
	)
	(gr_poly
		(pts
			(xy 236.417866 -99.28733) (xy 236.417866 -99.06635) (xy 236.247686 -98.97745) (xy 236.203236 -98.97745)
			(xy 236.203236 -99.37623) (xy 236.247686 -99.37623)
		)
		(stroke
			(width 0)
			(type solid)
		)
		(fill yes)
		(layer "In11.Cu")
		(net "M_F_DQS_DN<11>")
	)
	(gr_poly
		(pts
			(xy 236.73816 -100.952554) (xy 236.69371 -100.952554) (xy 236.52353 -101.041454) (xy 236.52353 -101.262434)
			(xy 236.69371 -101.351334) (xy 236.73816 -101.351334)
		)
		(stroke
			(width 0)
			(type solid)
		)
		(fill yes)
		(layer "In11.Cu")
		(net "M_F_DQS_DN<2>")
	)
	(gr_poly
		(pts
			(xy 236.73816 -99.974146) (xy 236.69371 -99.974146) (xy 236.52353 -100.063046) (xy 236.52353 -100.284026)
			(xy 236.69371 -100.372926) (xy 236.73816 -100.372926)
		)
		(stroke
			(width 0)
			(type solid)
		)
		(fill yes)
		(layer "In11.Cu")
		(net "M_F_DQS_DN<2>")
	)
	(gr_poly
		(pts
			(xy 236.73816 -51.42865) (xy 236.69371 -51.42865) (xy 236.52353 -51.51755) (xy 236.52353 -51.73853)
			(xy 236.69371 -51.82743) (xy 236.73816 -51.82743)
		)
		(stroke
			(width 0)
			(type solid)
		)
		(fill yes)
		(layer "In11.Cu")
		(net "M_C_DQS_DP<2>")
	)
	(gr_poly
		(pts
			(xy 236.738414 -98.988118) (xy 236.693964 -98.988372) (xy 236.523784 -99.077272) (xy 236.523784 -99.298252)
			(xy 236.693964 -99.387152) (xy 236.73816 -99.387152)
		)
		(stroke
			(width 0)
			(type solid)
		)
		(fill yes)
		(layer "In11.Cu")
		(net "M_F_DQS_DN<2>")
	)
	(gr_poly
		(pts
			(xy 236.738414 -52.418996) (xy 236.69371 -52.418996) (xy 236.523784 -52.507896) (xy 236.523784 -52.728876)
			(xy 236.693964 -52.817522) (xy 236.73816 -52.817776)
		)
		(stroke
			(width 0)
			(type solid)
		)
		(fill yes)
		(layer "In11.Cu")
		(net "M_C_DQS_DP<2>")
	)
	(gr_poly
		(pts
			(xy 236.83849 -102.776528) (xy 236.806994 -102.745286) (xy 236.607604 -102.671626) (xy 236.44606 -102.83317)
			(xy 236.51972 -103.03256) (xy 236.550962 -103.064056)
		)
		(stroke
			(width 0)
			(type solid)
		)
		(fill yes)
		(layer "In11.Cu")
		(net "M_F_DQS_DN<2>")
	)
	(gr_poly
		(pts
			(xy 236.874304 -101.96576) (xy 236.829854 -101.96576) (xy 236.636814 -102.05466) (xy 236.636814 -102.28326)
			(xy 236.829854 -102.37216) (xy 236.874304 -102.37216)
		)
		(stroke
			(width 0)
			(type solid)
		)
		(fill yes)
		(layer "In11.Cu")
		(net "M_F_DQS_DN<2>")
	)
	(gr_poly
		(pts
			(xy 236.966506 -57.619646) (xy 236.974634 -57.427876) (xy 236.783372 -57.317386) (xy 236.62132 -57.420256)
			(xy 236.598968 -57.45861) (xy 236.944408 -57.658)
		)
		(stroke
			(width 0)
			(type solid)
		)
		(fill yes)
		(layer "In11.Cu")
		(net "M_C_DQ<15>")
	)
	(gr_poly
		(pts
			(xy 236.968792 -67.526916) (xy 236.97692 -67.335146) (xy 236.785658 -67.224656) (xy 236.623606 -67.327526)
			(xy 236.601254 -67.36588) (xy 236.946694 -67.565524)
		)
		(stroke
			(width 0)
			(type solid)
		)
		(fill yes)
		(layer "In11.Cu")
		(net "M_C_DQ<5>")
	)
	(gr_poly
		(pts
			(xy 236.968792 -66.536316) (xy 236.97692 -66.344546) (xy 236.785658 -66.234056) (xy 236.623606 -66.336926)
			(xy 236.601254 -66.37528) (xy 236.946694 -66.574924)
		)
		(stroke
			(width 0)
			(type solid)
		)
		(fill yes)
		(layer "In11.Cu")
		(net "M_C_DQ<1>")
	)
	(gr_poly
		(pts
			(xy 236.968792 -65.545716) (xy 236.97692 -65.353946) (xy 236.785658 -65.243456) (xy 236.623606 -65.346326)
			(xy 236.601254 -65.38468) (xy 236.946694 -65.58407)
		)
		(stroke
			(width 0)
			(type solid)
		)
		(fill yes)
		(layer "In11.Cu")
		(net "M_C_DQS_DN<9>")
	)
	(gr_poly
		(pts
			(xy 236.968792 -64.555116) (xy 236.97692 -64.363346) (xy 236.785658 -64.252856) (xy 236.623606 -64.355726)
			(xy 236.601254 -64.39408) (xy 236.946694 -64.593724)
		)
		(stroke
			(width 0)
			(type solid)
		)
		(fill yes)
		(layer "In11.Cu")
		(net "M_C_DQS_DN<0>")
	)
	(gr_poly
		(pts
			(xy 236.968792 -63.564516) (xy 236.97692 -63.372746) (xy 236.785658 -63.262256) (xy 236.623606 -63.365126)
			(xy 236.601254 -63.40348) (xy 236.946694 -63.603124)
		)
		(stroke
			(width 0)
			(type solid)
		)
		(fill yes)
		(layer "In11.Cu")
		(net "M_C_DQ<7>")
	)
	(gr_poly
		(pts
			(xy 236.968792 -62.573916) (xy 236.97692 -62.382146) (xy 236.785658 -62.271656) (xy 236.623606 -62.374526)
			(xy 236.601254 -62.41288) (xy 236.946694 -62.612524)
		)
		(stroke
			(width 0)
			(type solid)
		)
		(fill yes)
		(layer "In11.Cu")
		(net "M_C_DQ<3>")
	)
	(gr_poly
		(pts
			(xy 236.968792 -61.583316) (xy 236.97692 -61.391546) (xy 236.785658 -61.281056) (xy 236.623606 -61.383926)
			(xy 236.601254 -61.42228) (xy 236.946694 -61.621924)
		)
		(stroke
			(width 0)
			(type solid)
		)
		(fill yes)
		(layer "In11.Cu")
		(net "M_C_DQ<13>")
	)
	(gr_poly
		(pts
			(xy 236.968792 -60.592716) (xy 236.97692 -60.400946) (xy 236.785658 -60.290456) (xy 236.623606 -60.393326)
			(xy 236.601254 -60.43168) (xy 236.946694 -60.631324)
		)
		(stroke
			(width 0)
			(type solid)
		)
		(fill yes)
		(layer "In11.Cu")
		(net "M_C_DQ<9>")
	)
	(gr_poly
		(pts
			(xy 236.968792 -59.602116) (xy 236.97692 -59.410346) (xy 236.785658 -59.299856) (xy 236.623606 -59.402726)
			(xy 236.601254 -59.44108) (xy 236.946694 -59.640724)
		)
		(stroke
			(width 0)
			(type solid)
		)
		(fill yes)
		(layer "In11.Cu")
		(net "M_C_DQS_DN<10>")
	)
	(gr_poly
		(pts
			(xy 236.968792 -55.639716) (xy 236.97692 -55.447946) (xy 236.785658 -55.337456) (xy 236.623606 -55.440326)
			(xy 236.601254 -55.47868) (xy 236.946694 -55.678324)
		)
		(stroke
			(width 0)
			(type solid)
		)
		(fill yes)
		(layer "In11.Cu")
		(net "M_C_DQ<21>")
	)
	(gr_poly
		(pts
			(xy 236.968792 -54.649116) (xy 236.97692 -54.457346) (xy 236.785658 -54.346856) (xy 236.623606 -54.449726)
			(xy 236.601254 -54.48808) (xy 236.946694 -54.687724)
		)
		(stroke
			(width 0)
			(type solid)
		)
		(fill yes)
		(layer "In11.Cu")
		(net "M_C_DQ<17>")
	)
	(gr_poly
		(pts
			(xy 236.968792 -53.658516) (xy 236.97692 -53.466746) (xy 236.785658 -53.356256) (xy 236.623606 -53.459126)
			(xy 236.601254 -53.49748) (xy 236.946694 -53.697124)
		)
		(stroke
			(width 0)
			(type solid)
		)
		(fill yes)
		(layer "In11.Cu")
		(net "M_C_DQS_DN<11>")
	)
	(gr_poly
		(pts
			(xy 236.970316 -58.612278) (xy 236.978444 -58.420508) (xy 236.787182 -58.310018) (xy 236.62513 -58.412888)
			(xy 236.602778 -58.451242) (xy 236.948218 -58.650632)
		)
		(stroke
			(width 0)
			(type solid)
		)
		(fill yes)
		(layer "In11.Cu")
		(net "M_C_DQS_DN<1>")
	)
	(gr_poly
		(pts
			(xy 236.970316 -56.631078) (xy 236.978444 -56.439308) (xy 236.787182 -56.328818) (xy 236.62513 -56.431688)
			(xy 236.602778 -56.470042) (xy 236.948218 -56.669686)
		)
		(stroke
			(width 0)
			(type solid)
		)
		(fill yes)
		(layer "In11.Cu")
		(net "M_C_DQ<11>")
	)
	(gr_poly
		(pts
			(xy 236.974634 -93.37675) (xy 236.966506 -93.18498) (xy 236.944408 -93.146372) (xy 236.598968 -93.345762)
			(xy 236.62132 -93.38437) (xy 236.783372 -93.48724)
		)
		(stroke
			(width 0)
			(type solid)
		)
		(fill yes)
		(layer "In11.Cu")
		(net "M_F_DQS_DP<1>")
	)
	(gr_poly
		(pts
			(xy 236.97692 -94.36608) (xy 236.968792 -94.17431) (xy 236.946694 -94.135702) (xy 236.601254 -94.335346)
			(xy 236.623606 -94.3737) (xy 236.785658 -94.47657)
		)
		(stroke
			(width 0)
			(type solid)
		)
		(fill yes)
		(layer "In11.Cu")
		(net "M_F_DQ<15>")
	)
	(gr_poly
		(pts
			(xy 236.978444 -98.327464) (xy 236.970316 -98.135694) (xy 236.948218 -98.097086) (xy 236.602778 -98.29673)
			(xy 236.62513 -98.335084) (xy 236.787182 -98.437954)
		)
		(stroke
			(width 0)
			(type solid)
		)
		(fill yes)
		(layer "In11.Cu")
		(net "M_F_DQS_DN<11>")
	)
	(gr_poly
		(pts
			(xy 236.978444 -97.336864) (xy 236.970316 -97.145094) (xy 236.948218 -97.106486) (xy 236.602778 -97.30613)
			(xy 236.62513 -97.344484) (xy 236.787182 -97.447354)
		)
		(stroke
			(width 0)
			(type solid)
		)
		(fill yes)
		(layer "In11.Cu")
		(net "M_F_DQ<17>")
	)
	(gr_poly
		(pts
			(xy 236.978444 -96.346264) (xy 236.970316 -96.154494) (xy 236.948218 -96.115886) (xy 236.602778 -96.31553)
			(xy 236.62513 -96.353884) (xy 236.787182 -96.456754)
		)
		(stroke
			(width 0)
			(type solid)
		)
		(fill yes)
		(layer "In11.Cu")
		(net "M_F_DQ<21>")
	)
	(gr_poly
		(pts
			(xy 236.978444 -95.355664) (xy 236.970316 -95.163894) (xy 236.948218 -95.125286) (xy 236.602778 -95.32493)
			(xy 236.62513 -95.363284) (xy 236.787182 -95.466154)
		)
		(stroke
			(width 0)
			(type solid)
		)
		(fill yes)
		(layer "In11.Cu")
		(net "M_F_DQ<11>")
	)
	(gr_poly
		(pts
			(xy 236.978444 -92.383864) (xy 236.970316 -92.192094) (xy 236.948218 -92.153486) (xy 236.602778 -92.35313)
			(xy 236.62513 -92.391484) (xy 236.787182 -92.494354)
		)
		(stroke
			(width 0)
			(type solid)
		)
		(fill yes)
		(layer "In11.Cu")
		(net "M_F_DQS_DN<10>")
	)
	(gr_poly
		(pts
			(xy 236.978444 -91.393264) (xy 236.970316 -91.201494) (xy 236.948218 -91.162886) (xy 236.602778 -91.36253)
			(xy 236.62513 -91.400884) (xy 236.787182 -91.503754)
		)
		(stroke
			(width 0)
			(type solid)
		)
		(fill yes)
		(layer "In11.Cu")
		(net "M_F_DQ<9>")
	)
	(gr_poly
		(pts
			(xy 236.978444 -90.402664) (xy 236.970316 -90.210894) (xy 236.948218 -90.172286) (xy 236.602778 -90.37193)
			(xy 236.62513 -90.410284) (xy 236.787182 -90.513154)
		)
		(stroke
			(width 0)
			(type solid)
		)
		(fill yes)
		(layer "In11.Cu")
		(net "M_F_DQ<13>")
	)
	(gr_poly
		(pts
			(xy 236.978444 -89.412064) (xy 236.970316 -89.220294) (xy 236.948218 -89.181686) (xy 236.602778 -89.38133)
			(xy 236.62513 -89.419684) (xy 236.787182 -89.522554)
		)
		(stroke
			(width 0)
			(type solid)
		)
		(fill yes)
		(layer "In11.Cu")
		(net "M_F_DQ<3>")
	)
	(gr_poly
		(pts
			(xy 236.978444 -88.421464) (xy 236.970316 -88.229694) (xy 236.948218 -88.191086) (xy 236.602778 -88.39073)
			(xy 236.62513 -88.429084) (xy 236.787182 -88.531954)
		)
		(stroke
			(width 0)
			(type solid)
		)
		(fill yes)
		(layer "In11.Cu")
		(net "M_F_DQ<7>")
	)
	(gr_poly
		(pts
			(xy 236.978444 -87.430864) (xy 236.970316 -87.239094) (xy 236.948218 -87.200486) (xy 236.602778 -87.40013)
			(xy 236.62513 -87.438484) (xy 236.787182 -87.541354)
		)
		(stroke
			(width 0)
			(type solid)
		)
		(fill yes)
		(layer "In11.Cu")
		(net "M_F_DQS_DP<0>")
	)
	(gr_poly
		(pts
			(xy 236.978444 -86.440264) (xy 236.970316 -86.248494) (xy 236.948218 -86.209886) (xy 236.602778 -86.40953)
			(xy 236.62513 -86.447884) (xy 236.787182 -86.550754)
		)
		(stroke
			(width 0)
			(type solid)
		)
		(fill yes)
		(layer "In11.Cu")
		(net "M_F_DQS_DN<9>")
	)
	(gr_poly
		(pts
			(xy 236.978444 -85.449664) (xy 236.970316 -85.257894) (xy 236.948218 -85.219286) (xy 236.602778 -85.41893)
			(xy 236.62513 -85.457284) (xy 236.787182 -85.560154)
		)
		(stroke
			(width 0)
			(type solid)
		)
		(fill yes)
		(layer "In11.Cu")
		(net "M_F_DQ<1>")
	)
	(gr_poly
		(pts
			(xy 236.978444 -84.459064) (xy 236.970316 -84.267294) (xy 236.948218 -84.228686) (xy 236.602778 -84.42833)
			(xy 236.62513 -84.466684) (xy 236.787182 -84.569554)
		)
		(stroke
			(width 0)
			(type solid)
		)
		(fill yes)
		(layer "In11.Cu")
		(net "M_F_DQ<5>")
	)
	(gr_poly
		(pts
			(xy 237.087156 -103.151178) (xy 237.013496 -102.951788) (xy 236.982254 -102.920292) (xy 236.694726 -103.20782)
			(xy 236.726222 -103.239062) (xy 236.925612 -103.312722)
		)
		(stroke
			(width 0)
			(type solid)
		)
		(fill yes)
		(layer "In11.Cu")
		(net "M_F_DQS_DP<2>")
	)
	(gr_poly
		(pts
			(xy 237.174786 -60.197238) (xy 237.197138 -60.158884) (xy 236.851698 -59.95924) (xy 236.8296 -59.997848)
			(xy 236.821472 -60.189618) (xy 237.012734 -60.300108)
		)
		(stroke
			(width 0)
			(type solid)
		)
		(fill yes)
		(layer "In11.Cu")
		(net "M_C_DQS_DP<10>")
	)
	(gr_poly
		(pts
			(xy 237.174786 -58.216038) (xy 237.197138 -58.177684) (xy 236.851698 -57.97804) (xy 236.8296 -58.016648)
			(xy 236.821472 -58.208418) (xy 237.012734 -58.318908)
		)
		(stroke
			(width 0)
			(type solid)
		)
		(fill yes)
		(layer "In11.Cu")
		(net "M_C_DQ<14>")
	)
	(gr_poly
		(pts
			(xy 237.17631 -68.1228) (xy 237.198662 -68.084192) (xy 236.853222 -67.885056) (xy 236.831124 -67.92341)
			(xy 236.822996 -68.11518) (xy 237.014258 -68.22567)
		)
		(stroke
			(width 0)
			(type solid)
		)
		(fill yes)
		(layer "In11.Cu")
		(net "M_C_DQ<4>")
	)
	(gr_poly
		(pts
			(xy 237.17631 -67.1322) (xy 237.198662 -67.093592) (xy 236.853222 -66.894456) (xy 236.831124 -66.93281)
			(xy 236.822996 -67.12458) (xy 237.014258 -67.23507)
		)
		(stroke
			(width 0)
			(type solid)
		)
		(fill yes)
		(layer "In11.Cu")
		(net "M_C_DQ<0>")
	)
	(gr_poly
		(pts
			(xy 237.17631 -66.1416) (xy 237.198662 -66.102992) (xy 236.853222 -65.903602) (xy 236.831124 -65.94221)
			(xy 236.822996 -66.13398) (xy 237.014258 -66.24447)
		)
		(stroke
			(width 0)
			(type solid)
		)
		(fill yes)
		(layer "In11.Cu")
		(net "M_C_DQS_DP<9>")
	)
	(gr_poly
		(pts
			(xy 237.17631 -65.151) (xy 237.198662 -65.112392) (xy 236.853222 -64.913002) (xy 236.831124 -64.95161)
			(xy 236.822996 -65.14338) (xy 237.014258 -65.25387)
		)
		(stroke
			(width 0)
			(type solid)
		)
		(fill yes)
		(layer "In11.Cu")
		(net "M_C_DQS_DP<0>")
	)
	(gr_poly
		(pts
			(xy 237.17631 -64.1604) (xy 237.198662 -64.121792) (xy 236.853222 -63.922402) (xy 236.831124 -63.96101)
			(xy 236.822996 -64.15278) (xy 237.014258 -64.26327)
		)
		(stroke
			(width 0)
			(type solid)
		)
		(fill yes)
		(layer "In11.Cu")
		(net "M_C_DQ<6>")
	)
	(gr_poly
		(pts
			(xy 237.17631 -63.1698) (xy 237.198662 -63.131192) (xy 236.853222 -62.931802) (xy 236.831124 -62.97041)
			(xy 236.822996 -63.16218) (xy 237.014258 -63.27267)
		)
		(stroke
			(width 0)
			(type solid)
		)
		(fill yes)
		(layer "In11.Cu")
		(net "M_C_DQ<2>")
	)
	(gr_poly
		(pts
			(xy 237.17631 -62.1792) (xy 237.198662 -62.140592) (xy 236.853222 -61.941202) (xy 236.831124 -61.97981)
			(xy 236.822996 -62.17158) (xy 237.014258 -62.28207)
		)
		(stroke
			(width 0)
			(type solid)
		)
		(fill yes)
		(layer "In11.Cu")
		(net "M_C_DQ<12>")
	)
	(gr_poly
		(pts
			(xy 237.17631 -61.1886) (xy 237.198662 -61.149992) (xy 236.853222 -60.950602) (xy 236.831124 -60.98921)
			(xy 236.822996 -61.18098) (xy 237.014258 -61.29147)
		)
		(stroke
			(width 0)
			(type solid)
		)
		(fill yes)
		(layer "In11.Cu")
		(net "M_C_DQ<8>")
	)
	(gr_poly
		(pts
			(xy 237.17631 -57.2262) (xy 237.198662 -57.187592) (xy 236.853222 -56.988202) (xy 236.831124 -57.02681)
			(xy 236.822996 -57.21858) (xy 237.014258 -57.32907)
		)
		(stroke
			(width 0)
			(type solid)
		)
		(fill yes)
		(layer "In11.Cu")
		(net "M_C_DQ<10>")
	)
	(gr_poly
		(pts
			(xy 237.17631 -56.2356) (xy 237.198662 -56.196992) (xy 236.853222 -55.997602) (xy 236.831124 -56.03621)
			(xy 236.822996 -56.22798) (xy 237.014258 -56.33847)
		)
		(stroke
			(width 0)
			(type solid)
		)
		(fill yes)
		(layer "In11.Cu")
		(net "M_C_DQ<20>")
	)
	(gr_poly
		(pts
			(xy 237.17631 -55.245) (xy 237.198662 -55.206392) (xy 236.853222 -55.007002) (xy 236.831124 -55.04561)
			(xy 236.822996 -55.23738) (xy 237.014258 -55.34787)
		)
		(stroke
			(width 0)
			(type solid)
		)
		(fill yes)
		(layer "In11.Cu")
		(net "M_C_DQ<16>")
	)
	(gr_poly
		(pts
			(xy 237.178088 -54.255416) (xy 237.20044 -54.216808) (xy 236.855 -54.017418) (xy 236.832902 -54.056026)
			(xy 236.824774 -54.247796) (xy 237.016036 -54.358286)
		)
		(stroke
			(width 0)
			(type solid)
		)
		(fill yes)
		(layer "In11.Cu")
		(net "M_C_DQS_DP<11>")
	)
	(gr_poly
		(pts
			(xy 237.178596 -59.20867) (xy 237.200948 -59.170316) (xy 236.855508 -58.970672) (xy 236.83341 -59.00928)
			(xy 236.825282 -59.20105) (xy 237.016544 -59.31154)
		)
		(stroke
			(width 0)
			(type solid)
		)
		(fill yes)
		(layer "In11.Cu")
		(net "M_C_DQS_DP<1>")
	)
	(gr_poly
		(pts
			(xy 237.193582 -53.27015) (xy 237.215426 -53.231796) (xy 236.867192 -53.037232) (xy 236.845602 -53.076348)
			(xy 236.840268 -53.267864) (xy 237.033308 -53.37556)
		)
		(stroke
			(width 0)
			(type solid)
		)
		(fill yes)
		(layer "In11.Cu")
		(net "M_C_DQS_DP<2>")
	)
	(gr_poly
		(pts
			(xy 237.197138 -98.570796) (xy 237.174786 -98.532442) (xy 237.012734 -98.429572) (xy 236.821472 -98.540062)
			(xy 236.829346 -98.731832) (xy 236.851444 -98.770186)
		)
		(stroke
			(width 0)
			(type solid)
		)
		(fill yes)
		(layer "In11.Cu")
		(net "M_F_DQS_DN<2>")
	)
	(gr_poly
		(pts
			(xy 237.197138 -97.58045) (xy 237.174786 -97.541842) (xy 237.012734 -97.438972) (xy 236.821472 -97.549462)
			(xy 236.8296 -97.741232) (xy 236.851698 -97.77984)
		)
		(stroke
			(width 0)
			(type solid)
		)
		(fill yes)
		(layer "In11.Cu")
		(net "M_F_DQS_DP<11>")
	)
	(gr_poly
		(pts
			(xy 237.197138 -96.58985) (xy 237.174786 -96.551242) (xy 237.012734 -96.448372) (xy 236.821472 -96.558862)
			(xy 236.8296 -96.750632) (xy 236.851698 -96.78924)
		)
		(stroke
			(width 0)
			(type solid)
		)
		(fill yes)
		(layer "In11.Cu")
		(net "M_F_DQ<16>")
	)
	(gr_poly
		(pts
			(xy 237.197138 -95.59925) (xy 237.174786 -95.560642) (xy 237.012734 -95.457772) (xy 236.821472 -95.568262)
			(xy 236.8296 -95.760032) (xy 236.851698 -95.79864)
		)
		(stroke
			(width 0)
			(type solid)
		)
		(fill yes)
		(layer "In11.Cu")
		(net "M_F_DQ<20>")
	)
	(gr_poly
		(pts
			(xy 237.197138 -92.62745) (xy 237.174786 -92.588842) (xy 237.012734 -92.485972) (xy 236.821472 -92.596462)
			(xy 236.8296 -92.788232) (xy 236.851698 -92.82684)
		)
		(stroke
			(width 0)
			(type solid)
		)
		(fill yes)
		(layer "In11.Cu")
		(net "M_F_DQS_DN<1>")
	)
	(gr_poly
		(pts
			(xy 237.197138 -91.63685) (xy 237.174786 -91.598242) (xy 237.012734 -91.495372) (xy 236.821472 -91.605862)
			(xy 236.8296 -91.797632) (xy 236.851698 -91.83624)
		)
		(stroke
			(width 0)
			(type solid)
		)
		(fill yes)
		(layer "In11.Cu")
		(net "M_F_DQS_DP<10>")
	)
	(gr_poly
		(pts
			(xy 237.197138 -90.64625) (xy 237.174786 -90.607642) (xy 237.012734 -90.504772) (xy 236.821472 -90.615262)
			(xy 236.8296 -90.807032) (xy 236.851698 -90.84564)
		)
		(stroke
			(width 0)
			(type solid)
		)
		(fill yes)
		(layer "In11.Cu")
		(net "M_F_DQ<8>")
	)
	(gr_poly
		(pts
			(xy 237.197138 -89.65565) (xy 237.174786 -89.617042) (xy 237.012734 -89.514172) (xy 236.821472 -89.624662)
			(xy 236.8296 -89.816432) (xy 236.851698 -89.85504)
		)
		(stroke
			(width 0)
			(type solid)
		)
		(fill yes)
		(layer "In11.Cu")
		(net "M_F_DQ<12>")
	)
	(gr_poly
		(pts
			(xy 237.197138 -88.66505) (xy 237.174786 -88.626442) (xy 237.012734 -88.523572) (xy 236.821472 -88.634062)
			(xy 236.8296 -88.825832) (xy 236.851698 -88.86444)
		)
		(stroke
			(width 0)
			(type solid)
		)
		(fill yes)
		(layer "In11.Cu")
		(net "M_F_DQ<2>")
	)
	(gr_poly
		(pts
			(xy 237.197138 -87.67445) (xy 237.174786 -87.635842) (xy 237.012734 -87.532972) (xy 236.821472 -87.643462)
			(xy 236.8296 -87.835232) (xy 236.851698 -87.87384)
		)
		(stroke
			(width 0)
			(type solid)
		)
		(fill yes)
		(layer "In11.Cu")
		(net "M_F_DQ<6>")
	)
	(gr_poly
		(pts
			(xy 237.197138 -86.68385) (xy 237.174786 -86.645242) (xy 237.012734 -86.542372) (xy 236.821472 -86.652862)
			(xy 236.8296 -86.844632) (xy 236.851698 -86.88324)
		)
		(stroke
			(width 0)
			(type solid)
		)
		(fill yes)
		(layer "In11.Cu")
		(net "M_F_DQS_DN<0>")
	)
	(gr_poly
		(pts
			(xy 237.197138 -85.69325) (xy 237.174786 -85.654642) (xy 237.012734 -85.551772) (xy 236.821472 -85.662262)
			(xy 236.8296 -85.854032) (xy 236.851698 -85.89264)
		)
		(stroke
			(width 0)
			(type solid)
		)
		(fill yes)
		(layer "In11.Cu")
		(net "M_F_DQS_DP<9>")
	)
	(gr_poly
		(pts
			(xy 237.197138 -84.70265) (xy 237.174786 -84.664042) (xy 237.012734 -84.561172) (xy 236.821472 -84.671662)
			(xy 236.8296 -84.863432) (xy 236.851698 -84.90204)
		)
		(stroke
			(width 0)
			(type solid)
		)
		(fill yes)
		(layer "In11.Cu")
		(net "M_F_DQ<0>")
	)
	(gr_poly
		(pts
			(xy 237.197138 -83.71205) (xy 237.174786 -83.673442) (xy 237.012734 -83.570572) (xy 236.821472 -83.681062)
			(xy 236.8296 -83.872832) (xy 236.851698 -83.91144)
		)
		(stroke
			(width 0)
			(type solid)
		)
		(fill yes)
		(layer "In11.Cu")
		(net "M_F_DQ<4>")
	)
	(gr_poly
		(pts
			(xy 237.198662 -93.61678) (xy 237.17631 -93.578426) (xy 237.014258 -93.475556) (xy 236.822996 -93.586046)
			(xy 236.831124 -93.777816) (xy 236.853222 -93.81617)
		)
		(stroke
			(width 0)
			(type solid)
		)
		(fill yes)
		(layer "In11.Cu")
		(net "M_F_DQ<14>")
	)
	(gr_poly
		(pts
			(xy 237.200948 -94.60611) (xy 237.178596 -94.567756) (xy 237.016544 -94.464886) (xy 236.825282 -94.575376)
			(xy 236.83341 -94.767146) (xy 236.855508 -94.805754)
		)
		(stroke
			(width 0)
			(type solid)
		)
		(fill yes)
		(layer "In11.Cu")
		(net "M_F_DQ<10>")
	)
	(gr_poly
		(pts
			(xy 237.276386 -100.772976) (xy 237.276386 -100.551996) (xy 237.106206 -100.463096) (xy 237.061756 -100.463096)
			(xy 237.061756 -100.861876) (xy 237.106206 -100.861876)
		)
		(stroke
			(width 0)
			(type solid)
		)
		(fill yes)
		(layer "In11.Cu")
		(net "M_F_DQS_DP<2>")
	)
	(gr_poly
		(pts
			(xy 237.276386 -99.77628) (xy 237.276386 -99.5553) (xy 237.106206 -99.4664) (xy 237.061756 -99.4664)
			(xy 237.061756 -99.86518) (xy 237.106206 -99.86518)
		)
		(stroke
			(width 0)
			(type solid)
		)
		(fill yes)
		(layer "In11.Cu")
		(net "M_F_DQS_DP<2>")
	)
	(gr_poly
		(pts
			(xy 237.276386 -52.22748) (xy 237.276386 -52.0065) (xy 237.106206 -51.9176) (xy 237.061756 -51.9176)
			(xy 237.061756 -52.31638) (xy 237.106206 -52.31638)
		)
		(stroke
			(width 0)
			(type solid)
		)
		(fill yes)
		(layer "In11.Cu")
		(net "M_C_DQS_DN<2>")
	)
	(gr_poly
		(pts
			(xy 237.276386 -51.249326) (xy 237.276386 -51.028346) (xy 237.106206 -50.939446) (xy 237.061756 -50.939446)
			(xy 237.061756 -51.338226) (xy 237.106206 -51.338226)
		)
		(stroke
			(width 0)
			(type solid)
		)
		(fill yes)
		(layer "In11.Cu")
		(net "M_C_DQS_DN<2>")
	)
	(gr_poly
		(pts
			(xy 237.302294 -102.28326) (xy 237.302294 -102.05466) (xy 237.109254 -101.96576) (xy 237.064804 -101.96576)
			(xy 237.064804 -102.37216) (xy 237.109254 -102.37216)
		)
		(stroke
			(width 0)
			(type solid)
		)
		(fill yes)
		(layer "In11.Cu")
		(net "M_F_DQS_DP<2>")
	)
	(gr_poly
		(pts
			(xy 237.59668 -50.939446) (xy 237.55223 -50.939446) (xy 237.38205 -51.028346) (xy 237.38205 -51.249326)
			(xy 237.55223 -51.338226) (xy 237.59668 -51.338226)
		)
		(stroke
			(width 0)
			(type solid)
		)
		(fill yes)
		(layer "In11.Cu")
		(net "M_C_DQ<22>")
	)
	(gr_poly
		(pts
			(xy 237.597188 -51.916584) (xy 237.552738 -51.916584) (xy 237.382558 -52.00523) (xy 237.38205 -52.225956)
			(xy 237.551976 -52.31511) (xy 237.596426 -52.315364)
		)
		(stroke
			(width 0)
			(type solid)
		)
		(fill yes)
		(layer "In11.Cu")
		(net "M_C_DQ<22>")
	)
	(gr_poly
		(pts
			(xy 237.681262 -103.934514) (xy 237.649766 -103.903272) (xy 237.450376 -103.829612) (xy 237.288832 -103.991156)
			(xy 237.362492 -104.190546) (xy 237.393734 -104.222042)
		)
		(stroke
			(width 0)
			(type solid)
		)
		(fill yes)
		(layer "In11.Cu")
		(net "M_F_DQ<22>")
	)
	(gr_poly
		(pts
			(xy 237.729776 -49.642776) (xy 237.685326 -49.642776) (xy 237.492286 -49.731676) (xy 237.492286 -49.960276)
			(xy 237.685326 -50.049176) (xy 237.729776 -50.049176)
		)
		(stroke
			(width 0)
			(type solid)
		)
		(fill yes)
		(layer "In11.Cu")
		(net "M_C_DQ<22>")
	)
	(gr_poly
		(pts
			(xy 237.825026 -59.105546) (xy 237.833154 -58.913776) (xy 237.641892 -58.803286) (xy 237.47984 -58.906156)
			(xy 237.457488 -58.94451) (xy 237.802928 -59.1439)
		)
		(stroke
			(width 0)
			(type solid)
		)
		(fill yes)
		(layer "In11.Cu")
		(net "M_C_DQS_DN<1>")
	)
	(gr_poly
		(pts
			(xy 237.827312 -66.04127) (xy 237.83544 -65.8495) (xy 237.644178 -65.73901) (xy 237.482126 -65.84188)
			(xy 237.459774 -65.880234) (xy 237.805214 -66.079624)
		)
		(stroke
			(width 0)
			(type solid)
		)
		(fill yes)
		(layer "In11.Cu")
		(net "M_C_DQS_DN<9>")
	)
	(gr_poly
		(pts
			(xy 237.827312 -58.116216) (xy 237.83544 -57.924446) (xy 237.644178 -57.813956) (xy 237.482126 -57.916826)
			(xy 237.459774 -57.95518) (xy 237.805214 -58.154824)
		)
		(stroke
			(width 0)
			(type solid)
		)
		(fill yes)
		(layer "In11.Cu")
		(net "M_C_DQ<15>")
	)
	(gr_poly
		(pts
			(xy 237.827312 -53.16347) (xy 237.83544 -52.9717) (xy 237.644178 -52.86121) (xy 237.482126 -52.96408)
			(xy 237.459774 -53.002434) (xy 237.805214 -53.202078)
		)
		(stroke
			(width 0)
			(type solid)
		)
		(fill yes)
		(layer "In11.Cu")
		(net "M_C_DQS_DN<2>")
	)
	(gr_poly
		(pts
			(xy 237.828836 -68.023232) (xy 237.836964 -67.831462) (xy 237.645702 -67.720972) (xy 237.48365 -67.823842)
			(xy 237.461298 -67.862196) (xy 237.806738 -68.06184)
		)
		(stroke
			(width 0)
			(type solid)
		)
		(fill yes)
		(layer "In11.Cu")
		(net "M_C_DQ<5>")
	)
	(gr_poly
		(pts
			(xy 237.828836 -67.032632) (xy 237.836964 -66.840862) (xy 237.645702 -66.730372) (xy 237.48365 -66.833242)
			(xy 237.461298 -66.871596) (xy 237.806738 -67.07124)
		)
		(stroke
			(width 0)
			(type solid)
		)
		(fill yes)
		(layer "In11.Cu")
		(net "M_C_DQ<1>")
	)
	(gr_poly
		(pts
			(xy 237.828836 -65.051432) (xy 237.836964 -64.859662) (xy 237.645702 -64.749172) (xy 237.48365 -64.852042)
			(xy 237.461298 -64.890396) (xy 237.806738 -65.09004)
		)
		(stroke
			(width 0)
			(type solid)
		)
		(fill yes)
		(layer "In11.Cu")
		(net "M_C_DQS_DN<0>")
	)
	(gr_poly
		(pts
			(xy 237.828836 -64.060832) (xy 237.836964 -63.869062) (xy 237.645702 -63.758572) (xy 237.48365 -63.861442)
			(xy 237.461298 -63.899796) (xy 237.806738 -64.09944)
		)
		(stroke
			(width 0)
			(type solid)
		)
		(fill yes)
		(layer "In11.Cu")
		(net "M_C_DQ<7>")
	)
	(gr_poly
		(pts
			(xy 237.828836 -63.070232) (xy 237.836964 -62.878462) (xy 237.645702 -62.767972) (xy 237.48365 -62.870842)
			(xy 237.461298 -62.909196) (xy 237.806738 -63.10884)
		)
		(stroke
			(width 0)
			(type solid)
		)
		(fill yes)
		(layer "In11.Cu")
		(net "M_C_DQ<3>")
	)
	(gr_poly
		(pts
			(xy 237.828836 -62.079632) (xy 237.836964 -61.887862) (xy 237.645702 -61.777372) (xy 237.48365 -61.880242)
			(xy 237.461298 -61.918596) (xy 237.806738 -62.11824)
		)
		(stroke
			(width 0)
			(type solid)
		)
		(fill yes)
		(layer "In11.Cu")
		(net "M_C_DQ<13>")
	)
	(gr_poly
		(pts
			(xy 237.828836 -61.089032) (xy 237.836964 -60.897262) (xy 237.645702 -60.786772) (xy 237.48365 -60.889642)
			(xy 237.461298 -60.927996) (xy 237.806738 -61.12764)
		)
		(stroke
			(width 0)
			(type solid)
		)
		(fill yes)
		(layer "In11.Cu")
		(net "M_C_DQ<9>")
	)
	(gr_poly
		(pts
			(xy 237.828836 -60.098432) (xy 237.836964 -59.906662) (xy 237.645702 -59.796172) (xy 237.48365 -59.899042)
			(xy 237.461298 -59.937396) (xy 237.806738 -60.13704)
		)
		(stroke
			(width 0)
			(type solid)
		)
		(fill yes)
		(layer "In11.Cu")
		(net "M_C_DQS_DN<10>")
	)
	(gr_poly
		(pts
			(xy 237.828836 -57.126632) (xy 237.836964 -56.934862) (xy 237.645702 -56.824372) (xy 237.48365 -56.927242)
			(xy 237.461298 -56.965596) (xy 237.806738 -57.16524)
		)
		(stroke
			(width 0)
			(type solid)
		)
		(fill yes)
		(layer "In11.Cu")
		(net "M_C_DQ<11>")
	)
	(gr_poly
		(pts
			(xy 237.828836 -56.136032) (xy 237.836964 -55.944262) (xy 237.645702 -55.833772) (xy 237.48365 -55.936642)
			(xy 237.461298 -55.974996) (xy 237.806738 -56.17464)
		)
		(stroke
			(width 0)
			(type solid)
		)
		(fill yes)
		(layer "In11.Cu")
		(net "M_C_DQ<21>")
	)
	(gr_poly
		(pts
			(xy 237.828836 -55.145432) (xy 237.836964 -54.953662) (xy 237.645702 -54.843172) (xy 237.48365 -54.946042)
			(xy 237.461298 -54.984396) (xy 237.806738 -55.18404)
		)
		(stroke
			(width 0)
			(type solid)
		)
		(fill yes)
		(layer "In11.Cu")
		(net "M_C_DQ<17>")
	)
	(gr_poly
		(pts
			(xy 237.828836 -54.154832) (xy 237.836964 -53.963062) (xy 237.645702 -53.852572) (xy 237.48365 -53.955442)
			(xy 237.461298 -53.993796) (xy 237.806738 -54.19344)
		)
		(stroke
			(width 0)
			(type solid)
		)
		(fill yes)
		(layer "In11.Cu")
		(net "M_C_DQS_DN<11>")
	)
	(gr_poly
		(pts
			(xy 237.833154 -94.86265) (xy 237.825026 -94.67088) (xy 237.802928 -94.632272) (xy 237.457488 -94.831662)
			(xy 237.47984 -94.87027) (xy 237.641892 -94.97314)
		)
		(stroke
			(width 0)
			(type solid)
		)
		(fill yes)
		(layer "In11.Cu")
		(net "M_F_DQ<11>")
	)
	(gr_poly
		(pts
			(xy 237.83544 -98.82378) (xy 237.827312 -98.63201) (xy 237.805214 -98.593402) (xy 237.459774 -98.793046)
			(xy 237.482126 -98.8314) (xy 237.644178 -98.93427)
		)
		(stroke
			(width 0)
			(type solid)
		)
		(fill yes)
		(layer "In11.Cu")
		(net "M_F_DQS_DP<2>")
	)
	(gr_poly
		(pts
			(xy 237.83544 -97.83318) (xy 237.827312 -97.64141) (xy 237.805214 -97.602802) (xy 237.459774 -97.802446)
			(xy 237.482126 -97.8408) (xy 237.644178 -97.94367)
		)
		(stroke
			(width 0)
			(type solid)
		)
		(fill yes)
		(layer "In11.Cu")
		(net "M_F_DQS_DN<11>")
	)
	(gr_poly
		(pts
			(xy 237.83544 -96.84258) (xy 237.827312 -96.65081) (xy 237.805214 -96.612202) (xy 237.459774 -96.811846)
			(xy 237.482126 -96.8502) (xy 237.644178 -96.95307)
		)
		(stroke
			(width 0)
			(type solid)
		)
		(fill yes)
		(layer "In11.Cu")
		(net "M_F_DQ<17>")
	)
	(gr_poly
		(pts
			(xy 237.83544 -95.85198) (xy 237.827312 -95.66021) (xy 237.805214 -95.621602) (xy 237.459774 -95.821246)
			(xy 237.482126 -95.8596) (xy 237.644178 -95.96247)
		)
		(stroke
			(width 0)
			(type solid)
		)
		(fill yes)
		(layer "In11.Cu")
		(net "M_F_DQ<21>")
	)
	(gr_poly
		(pts
			(xy 237.83544 -92.88018) (xy 237.827312 -92.68841) (xy 237.805214 -92.649802) (xy 237.459774 -92.849446)
			(xy 237.482126 -92.8878) (xy 237.644178 -92.99067)
		)
		(stroke
			(width 0)
			(type solid)
		)
		(fill yes)
		(layer "In11.Cu")
		(net "M_F_DQS_DP<1>")
	)
	(gr_poly
		(pts
			(xy 237.83544 -91.88958) (xy 237.827312 -91.69781) (xy 237.805214 -91.659202) (xy 237.459774 -91.858846)
			(xy 237.482126 -91.8972) (xy 237.644178 -92.00007)
		)
		(stroke
			(width 0)
			(type solid)
		)
		(fill yes)
		(layer "In11.Cu")
		(net "M_F_DQS_DN<10>")
	)
	(gr_poly
		(pts
			(xy 237.83544 -90.89898) (xy 237.827312 -90.70721) (xy 237.805214 -90.668602) (xy 237.459774 -90.868246)
			(xy 237.482126 -90.9066) (xy 237.644178 -91.00947)
		)
		(stroke
			(width 0)
			(type solid)
		)
		(fill yes)
		(layer "In11.Cu")
		(net "M_F_DQ<9>")
	)
	(gr_poly
		(pts
			(xy 237.83544 -89.90838) (xy 237.827312 -89.71661) (xy 237.805214 -89.678002) (xy 237.459774 -89.877646)
			(xy 237.482126 -89.916) (xy 237.644178 -90.01887)
		)
		(stroke
			(width 0)
			(type solid)
		)
		(fill yes)
		(layer "In11.Cu")
		(net "M_F_DQ<13>")
	)
	(gr_poly
		(pts
			(xy 237.83544 -88.91778) (xy 237.827312 -88.72601) (xy 237.805214 -88.687402) (xy 237.459774 -88.887046)
			(xy 237.482126 -88.9254) (xy 237.644178 -89.02827)
		)
		(stroke
			(width 0)
			(type solid)
		)
		(fill yes)
		(layer "In11.Cu")
		(net "M_F_DQ<3>")
	)
	(gr_poly
		(pts
			(xy 237.83544 -87.92718) (xy 237.827312 -87.73541) (xy 237.805214 -87.696802) (xy 237.459774 -87.896446)
			(xy 237.482126 -87.9348) (xy 237.644178 -88.03767)
		)
		(stroke
			(width 0)
			(type solid)
		)
		(fill yes)
		(layer "In11.Cu")
		(net "M_F_DQ<7>")
	)
	(gr_poly
		(pts
			(xy 237.83544 -86.93658) (xy 237.827312 -86.74481) (xy 237.805214 -86.706202) (xy 237.459774 -86.905846)
			(xy 237.482126 -86.9442) (xy 237.644178 -87.04707)
		)
		(stroke
			(width 0)
			(type solid)
		)
		(fill yes)
		(layer "In11.Cu")
		(net "M_F_DQS_DP<0>")
	)
	(gr_poly
		(pts
			(xy 237.83544 -85.94598) (xy 237.827312 -85.75421) (xy 237.805214 -85.715602) (xy 237.459774 -85.915246)
			(xy 237.482126 -85.9536) (xy 237.644178 -86.05647)
		)
		(stroke
			(width 0)
			(type solid)
		)
		(fill yes)
		(layer "In11.Cu")
		(net "M_F_DQS_DN<9>")
	)
	(gr_poly
		(pts
			(xy 237.83544 -84.95538) (xy 237.827312 -84.76361) (xy 237.805214 -84.725002) (xy 237.459774 -84.924646)
			(xy 237.482126 -84.963) (xy 237.644178 -85.06587)
		)
		(stroke
			(width 0)
			(type solid)
		)
		(fill yes)
		(layer "In11.Cu")
		(net "M_F_DQ<1>")
	)
	(gr_poly
		(pts
			(xy 237.83544 -83.96478) (xy 237.827312 -83.77301) (xy 237.805214 -83.734402) (xy 237.459774 -83.934046)
			(xy 237.482126 -83.9724) (xy 237.644178 -84.07527)
		)
		(stroke
			(width 0)
			(type solid)
		)
		(fill yes)
		(layer "In11.Cu")
		(net "M_F_DQ<5>")
	)
	(gr_poly
		(pts
			(xy 237.836964 -93.870018) (xy 237.828836 -93.678248) (xy 237.806738 -93.639894) (xy 237.461298 -93.83903)
			(xy 237.48365 -93.877638) (xy 237.645702 -93.980508)
		)
		(stroke
			(width 0)
			(type solid)
		)
		(fill yes)
		(layer "In11.Cu")
		(net "M_F_DQ<15>")
	)
	(gr_poly
		(pts
			(xy 237.92053 -104.299766) (xy 237.84687 -104.100376) (xy 237.815628 -104.06888) (xy 237.5281 -104.356408)
			(xy 237.559596 -104.38765) (xy 237.758986 -104.46131)
		)
		(stroke
			(width 0)
			(type solid)
		)
		(fill yes)
		(layer "In11.Cu")
		(net "M_F_DQ<23>")
	)
	(gr_poly
		(pts
			(xy 238.033306 -68.617084) (xy 238.055658 -68.578476) (xy 237.710218 -68.37934) (xy 237.68812 -68.417694)
			(xy 237.679992 -68.609464) (xy 237.871254 -68.719954)
		)
		(stroke
			(width 0)
			(type solid)
		)
		(fill yes)
		(layer "In11.Cu")
		(net "M_C_DQ<4>")
	)
	(gr_poly
		(pts
			(xy 238.033306 -67.626484) (xy 238.055658 -67.587876) (xy 237.710218 -67.38874) (xy 237.68812 -67.427094)
			(xy 237.679992 -67.618864) (xy 237.871254 -67.729354)
		)
		(stroke
			(width 0)
			(type solid)
		)
		(fill yes)
		(layer "In11.Cu")
		(net "M_C_DQ<0>")
	)
	(gr_poly
		(pts
			(xy 238.033306 -66.635884) (xy 238.055658 -66.597276) (xy 237.710218 -66.397886) (xy 237.68812 -66.436494)
			(xy 237.679992 -66.628264) (xy 237.871254 -66.738754)
		)
		(stroke
			(width 0)
			(type solid)
		)
		(fill yes)
		(layer "In11.Cu")
		(net "M_C_DQS_DP<9>")
	)
	(gr_poly
		(pts
			(xy 238.033306 -65.645284) (xy 238.055658 -65.60693) (xy 237.710218 -65.407286) (xy 237.68812 -65.445894)
			(xy 237.679992 -65.637664) (xy 237.871254 -65.748154)
		)
		(stroke
			(width 0)
			(type solid)
		)
		(fill yes)
		(layer "In11.Cu")
		(net "M_C_DQS_DP<0>")
	)
	(gr_poly
		(pts
			(xy 238.033306 -64.654684) (xy 238.055658 -64.61633) (xy 237.710218 -64.416686) (xy 237.68812 -64.455294)
			(xy 237.679992 -64.647064) (xy 237.871254 -64.757554)
		)
		(stroke
			(width 0)
			(type solid)
		)
		(fill yes)
		(layer "In11.Cu")
		(net "M_C_DQ<6>")
	)
	(gr_poly
		(pts
			(xy 238.033306 -63.664084) (xy 238.055658 -63.62573) (xy 237.710218 -63.426086) (xy 237.68812 -63.464694)
			(xy 237.679992 -63.656464) (xy 237.871254 -63.766954)
		)
		(stroke
			(width 0)
			(type solid)
		)
		(fill yes)
		(layer "In11.Cu")
		(net "M_C_DQ<2>")
	)
	(gr_poly
		(pts
			(xy 238.033306 -62.673484) (xy 238.055658 -62.63513) (xy 237.710218 -62.435486) (xy 237.68812 -62.474094)
			(xy 237.679992 -62.665864) (xy 237.871254 -62.776354)
		)
		(stroke
			(width 0)
			(type solid)
		)
		(fill yes)
		(layer "In11.Cu")
		(net "M_C_DQ<12>")
	)
	(gr_poly
		(pts
			(xy 238.033306 -61.682884) (xy 238.055658 -61.64453) (xy 237.710218 -61.444886) (xy 237.68812 -61.483494)
			(xy 237.679992 -61.675264) (xy 237.871254 -61.785754)
		)
		(stroke
			(width 0)
			(type solid)
		)
		(fill yes)
		(layer "In11.Cu")
		(net "M_C_DQ<8>")
	)
	(gr_poly
		(pts
			(xy 238.033306 -60.692284) (xy 238.055658 -60.65393) (xy 237.710218 -60.454286) (xy 237.68812 -60.492894)
			(xy 237.679992 -60.684664) (xy 237.871254 -60.795154)
		)
		(stroke
			(width 0)
			(type solid)
		)
		(fill yes)
		(layer "In11.Cu")
		(net "M_C_DQS_DP<10>")
	)
	(gr_poly
		(pts
			(xy 238.033306 -59.701684) (xy 238.055658 -59.66333) (xy 237.710218 -59.463686) (xy 237.68812 -59.502294)
			(xy 237.679992 -59.694064) (xy 237.871254 -59.804554)
		)
		(stroke
			(width 0)
			(type solid)
		)
		(fill yes)
		(layer "In11.Cu")
		(net "M_C_DQS_DP<1>")
	)
	(gr_poly
		(pts
			(xy 238.033306 -58.711338) (xy 238.055658 -58.672984) (xy 237.710218 -58.47334) (xy 237.68812 -58.511948)
			(xy 237.679992 -58.703718) (xy 237.871254 -58.814208)
		)
		(stroke
			(width 0)
			(type solid)
		)
		(fill yes)
		(layer "In11.Cu")
		(net "M_C_DQ<14>")
	)
	(gr_poly
		(pts
			(xy 238.033306 -56.729884) (xy 238.055658 -56.69153) (xy 237.710218 -56.491886) (xy 237.68812 -56.530494)
			(xy 237.679992 -56.722264) (xy 237.871254 -56.832754)
		)
		(stroke
			(width 0)
			(type solid)
		)
		(fill yes)
		(layer "In11.Cu")
		(net "M_C_DQ<20>")
	)
	(gr_poly
		(pts
			(xy 238.033306 -55.739284) (xy 238.055658 -55.70093) (xy 237.710218 -55.501286) (xy 237.68812 -55.539894)
			(xy 237.679992 -55.731664) (xy 237.871254 -55.842154)
		)
		(stroke
			(width 0)
			(type solid)
		)
		(fill yes)
		(layer "In11.Cu")
		(net "M_C_DQ<16>")
	)
	(gr_poly
		(pts
			(xy 238.033306 -53.758084) (xy 238.055658 -53.71973) (xy 237.710218 -53.520086) (xy 237.68812 -53.558694)
			(xy 237.679992 -53.750464) (xy 237.871254 -53.860954)
		)
		(stroke
			(width 0)
			(type solid)
		)
		(fill yes)
		(layer "In11.Cu")
		(net "M_C_DQS_DP<2>")
	)
	(gr_poly
		(pts
			(xy 238.03483 -54.749446) (xy 238.057182 -54.711092) (xy 237.711742 -54.511448) (xy 237.689644 -54.550056)
			(xy 237.681516 -54.741826) (xy 237.872778 -54.852316)
		)
		(stroke
			(width 0)
			(type solid)
		)
		(fill yes)
		(layer "In11.Cu")
		(net "M_C_DQS_DP<11>")
	)
	(gr_poly
		(pts
			(xy 238.037116 -57.72277) (xy 238.059468 -57.684416) (xy 237.714028 -57.484772) (xy 237.69193 -57.52338)
			(xy 237.683802 -57.71515) (xy 237.875064 -57.82564)
		)
		(stroke
			(width 0)
			(type solid)
		)
		(fill yes)
		(layer "In11.Cu")
		(net "M_C_DQ<10>")
	)
	(gr_poly
		(pts
			(xy 238.037116 -52.770024) (xy 238.059468 -52.73167) (xy 237.714028 -52.532026) (xy 237.69193 -52.570634)
			(xy 237.683802 -52.762404) (xy 237.875064 -52.872894)
		)
		(stroke
			(width 0)
			(type solid)
		)
		(fill yes)
		(layer "In11.Cu")
		(net "M_C_DQ<22>")
	)
	(gr_poly
		(pts
			(xy 238.055658 -94.112842) (xy 238.033306 -94.074488) (xy 237.871254 -93.971618) (xy 237.679992 -94.082108)
			(xy 237.68812 -94.273878) (xy 237.710218 -94.312486)
		)
		(stroke
			(width 0)
			(type solid)
		)
		(fill yes)
		(layer "In11.Cu")
		(net "M_F_DQ<10>")
	)
	(gr_poly
		(pts
			(xy 238.057182 -98.07448) (xy 238.03483 -98.036126) (xy 237.872778 -97.933256) (xy 237.681516 -98.043746)
			(xy 237.689644 -98.235516) (xy 237.711742 -98.27387)
		)
		(stroke
			(width 0)
			(type solid)
		)
		(fill yes)
		(layer "In11.Cu")
		(net "M_F_DQS_DN<2>")
	)
	(gr_poly
		(pts
			(xy 238.057182 -97.08388) (xy 238.03483 -97.045526) (xy 237.872778 -96.942656) (xy 237.681516 -97.053146)
			(xy 237.689644 -97.244916) (xy 237.711742 -97.28327)
		)
		(stroke
			(width 0)
			(type solid)
		)
		(fill yes)
		(layer "In11.Cu")
		(net "M_F_DQS_DP<11>")
	)
	(gr_poly
		(pts
			(xy 238.057182 -96.09328) (xy 238.03483 -96.054926) (xy 237.872778 -95.952056) (xy 237.681516 -96.062546)
			(xy 237.689644 -96.254316) (xy 237.711742 -96.29267)
		)
		(stroke
			(width 0)
			(type solid)
		)
		(fill yes)
		(layer "In11.Cu")
		(net "M_F_DQ<16>")
	)
	(gr_poly
		(pts
			(xy 238.057182 -95.10268) (xy 238.03483 -95.064326) (xy 237.872778 -94.961456) (xy 237.681516 -95.071946)
			(xy 237.689644 -95.263716) (xy 237.711742 -95.30207)
		)
		(stroke
			(width 0)
			(type solid)
		)
		(fill yes)
		(layer "In11.Cu")
		(net "M_F_DQ<20>")
	)
	(gr_poly
		(pts
			(xy 238.057182 -92.13088) (xy 238.03483 -92.092526) (xy 237.872778 -91.989656) (xy 237.681516 -92.100146)
			(xy 237.689644 -92.291916) (xy 237.711742 -92.33027)
		)
		(stroke
			(width 0)
			(type solid)
		)
		(fill yes)
		(layer "In11.Cu")
		(net "M_F_DQS_DN<1>")
	)
	(gr_poly
		(pts
			(xy 238.057182 -91.14028) (xy 238.03483 -91.101926) (xy 237.872778 -90.999056) (xy 237.681516 -91.109546)
			(xy 237.689644 -91.301316) (xy 237.711742 -91.33967)
		)
		(stroke
			(width 0)
			(type solid)
		)
		(fill yes)
		(layer "In11.Cu")
		(net "M_F_DQS_DP<10>")
	)
	(gr_poly
		(pts
			(xy 238.057182 -90.14968) (xy 238.03483 -90.111326) (xy 237.872778 -90.008456) (xy 237.681516 -90.118946)
			(xy 237.689644 -90.310716) (xy 237.711742 -90.34907)
		)
		(stroke
			(width 0)
			(type solid)
		)
		(fill yes)
		(layer "In11.Cu")
		(net "M_F_DQ<8>")
	)
	(gr_poly
		(pts
			(xy 238.057182 -89.15908) (xy 238.03483 -89.120726) (xy 237.872778 -89.017856) (xy 237.681516 -89.128346)
			(xy 237.689644 -89.320116) (xy 237.711742 -89.35847)
		)
		(stroke
			(width 0)
			(type solid)
		)
		(fill yes)
		(layer "In11.Cu")
		(net "M_F_DQ<12>")
	)
	(gr_poly
		(pts
			(xy 238.057182 -88.16848) (xy 238.03483 -88.130126) (xy 237.872778 -88.027256) (xy 237.681516 -88.137746)
			(xy 237.689644 -88.329516) (xy 237.711742 -88.36787)
		)
		(stroke
			(width 0)
			(type solid)
		)
		(fill yes)
		(layer "In11.Cu")
		(net "M_F_DQ<2>")
	)
	(gr_poly
		(pts
			(xy 238.057182 -87.17788) (xy 238.03483 -87.139526) (xy 237.872778 -87.036656) (xy 237.681516 -87.147146)
			(xy 237.689644 -87.338916) (xy 237.711742 -87.37727)
		)
		(stroke
			(width 0)
			(type solid)
		)
		(fill yes)
		(layer "In11.Cu")
		(net "M_F_DQ<6>")
	)
	(gr_poly
		(pts
			(xy 238.057182 -86.18728) (xy 238.03483 -86.148926) (xy 237.872778 -86.046056) (xy 237.681516 -86.156546)
			(xy 237.689644 -86.348316) (xy 237.711742 -86.38667)
		)
		(stroke
			(width 0)
			(type solid)
		)
		(fill yes)
		(layer "In11.Cu")
		(net "M_F_DQS_DN<0>")
	)
	(gr_poly
		(pts
			(xy 238.057182 -85.19668) (xy 238.03483 -85.158326) (xy 237.872778 -85.055456) (xy 237.681516 -85.165946)
			(xy 237.689644 -85.357716) (xy 237.711742 -85.39607)
		)
		(stroke
			(width 0)
			(type solid)
		)
		(fill yes)
		(layer "In11.Cu")
		(net "M_F_DQS_DP<9>")
	)
	(gr_poly
		(pts
			(xy 238.057182 -84.20608) (xy 238.03483 -84.167726) (xy 237.872778 -84.064856) (xy 237.681516 -84.175346)
			(xy 237.689644 -84.367116) (xy 237.711742 -84.40547)
		)
		(stroke
			(width 0)
			(type solid)
		)
		(fill yes)
		(layer "In11.Cu")
		(net "M_F_DQ<0>")
	)
	(gr_poly
		(pts
			(xy 238.057182 -83.21548) (xy 238.03483 -83.177126) (xy 237.872778 -83.074256) (xy 237.681516 -83.184746)
			(xy 237.689644 -83.376516) (xy 237.711742 -83.41487)
		)
		(stroke
			(width 0)
			(type solid)
		)
		(fill yes)
		(layer "In11.Cu")
		(net "M_F_DQ<4>")
	)
	(gr_poly
		(pts
			(xy 238.059468 -93.12021) (xy 238.037116 -93.081856) (xy 237.875064 -92.978986) (xy 237.683802 -93.089476)
			(xy 237.69193 -93.281246) (xy 237.714028 -93.319854)
		)
		(stroke
			(width 0)
			(type solid)
		)
		(fill yes)
		(layer "In11.Cu")
		(net "M_F_DQ<14>")
	)
	(gr_poly
		(pts
			(xy 238.134906 -51.73853) (xy 238.134906 -51.51755) (xy 237.964726 -51.42865) (xy 237.920276 -51.42865)
			(xy 237.920276 -51.82743) (xy 237.964726 -51.82743)
		)
		(stroke
			(width 0)
			(type solid)
		)
		(fill yes)
		(layer "In11.Cu")
		(net "M_C_DQ<23>")
	)
	(gr_poly
		(pts
			(xy 238.157512 -49.960276) (xy 238.157512 -49.731676) (xy 237.964472 -49.642776) (xy 237.920022 -49.642776)
			(xy 237.920022 -50.049176) (xy 237.964472 -50.049176)
		)
		(stroke
			(width 0)
			(type solid)
		)
		(fill yes)
		(layer "In11.Cu")
		(net "M_C_DQ<23>")
	)
	(gr_poly
		(pts
			(xy 238.316262 -103.299514) (xy 238.284766 -103.268272) (xy 238.085376 -103.194612) (xy 237.923832 -103.356156)
			(xy 237.997492 -103.555546) (xy 238.028734 -103.587042)
		)
		(stroke
			(width 0)
			(type solid)
		)
		(fill yes)
		(layer "In11.Cu")
		(net "M_F_DQ<22>")
	)
	(gr_poly
		(pts
			(xy 238.4552 -100.9523) (xy 238.41075 -100.9523) (xy 238.24057 -101.0412) (xy 238.24057 -101.26218)
			(xy 238.41075 -101.35108) (xy 238.4552 -101.35108)
		)
		(stroke
			(width 0)
			(type solid)
		)
		(fill yes)
		(layer "In11.Cu")
		(net "M_F_DQ<22>")
	)
	(gr_poly
		(pts
			(xy 238.4552 -99.974146) (xy 238.41075 -99.974146) (xy 238.24057 -100.063046) (xy 238.24057 -100.284026)
			(xy 238.41075 -100.372926) (xy 238.4552 -100.372926)
		)
		(stroke
			(width 0)
			(type solid)
		)
		(fill yes)
		(layer "In11.Cu")
		(net "M_F_DQ<22>")
	)
	(gr_poly
		(pts
			(xy 238.455454 -98.988118) (xy 238.411004 -98.988372) (xy 238.240824 -99.077272) (xy 238.240824 -99.298252)
			(xy 238.411004 -99.387152) (xy 238.4552 -99.387152)
		)
		(stroke
			(width 0)
			(type solid)
		)
		(fill yes)
		(layer "In11.Cu")
		(net "M_F_DQ<22>")
	)
	(gr_poly
		(pts
			(xy 238.455454 -51.420014) (xy 238.411004 -51.420268) (xy 238.240824 -51.509422) (xy 238.241078 -51.730402)
			(xy 238.411258 -51.819048) (xy 238.455962 -51.819048)
		)
		(stroke
			(width 0)
			(type solid)
		)
		(fill yes)
		(layer "In11.Cu")
		(net "M_C_DQ<18>")
	)
	(gr_poly
		(pts
			(xy 238.455454 -50.429414) (xy 238.411004 -50.429668) (xy 238.240824 -50.518822) (xy 238.241078 -50.739802)
			(xy 238.411258 -50.828448) (xy 238.455962 -50.828448)
		)
		(stroke
			(width 0)
			(type solid)
		)
		(fill yes)
		(layer "In11.Cu")
		(net "M_C_DQ<18>")
	)
	(gr_poly
		(pts
			(xy 238.55553 -103.664766) (xy 238.48187 -103.465376) (xy 238.450628 -103.43388) (xy 238.1631 -103.721408)
			(xy 238.194596 -103.75265) (xy 238.393986 -103.82631)
		)
		(stroke
			(width 0)
			(type solid)
		)
		(fill yes)
		(layer "In11.Cu")
		(net "M_F_DQ<23>")
	)
	(gr_poly
		(pts
			(xy 238.6076 -102.1207) (xy 238.56315 -102.1207) (xy 238.39297 -102.2096) (xy 238.39297 -102.43058)
			(xy 238.56315 -102.51948) (xy 238.6076 -102.51948)
		)
		(stroke
			(width 0)
			(type solid)
		)
		(fill yes)
		(layer "In11.Cu")
		(net "M_F_DQ<22>")
	)
	(gr_poly
		(pts
			(xy 238.683546 -57.619646) (xy 238.691674 -57.427876) (xy 238.500412 -57.317386) (xy 238.33836 -57.420256)
			(xy 238.316008 -57.45861) (xy 238.661448 -57.658)
		)
		(stroke
			(width 0)
			(type solid)
		)
		(fill yes)
		(layer "In11.Cu")
		(net "M_C_DQ<11>")
	)
	(gr_poly
		(pts
			(xy 238.685832 -68.517516) (xy 238.69396 -68.325746) (xy 238.502698 -68.215256) (xy 238.340646 -68.318126)
			(xy 238.318294 -68.35648) (xy 238.663734 -68.556124)
		)
		(stroke
			(width 0)
			(type solid)
		)
		(fill yes)
		(layer "In11.Cu")
		(net "M_C_DQ<5>")
	)
	(gr_poly
		(pts
			(xy 238.685832 -67.526916) (xy 238.69396 -67.335146) (xy 238.502698 -67.224656) (xy 238.340646 -67.327526)
			(xy 238.318294 -67.36588) (xy 238.663734 -67.565524)
		)
		(stroke
			(width 0)
			(type solid)
		)
		(fill yes)
		(layer "In11.Cu")
		(net "M_C_DQ<1>")
	)
	(gr_poly
		(pts
			(xy 238.685832 -66.536316) (xy 238.69396 -66.344546) (xy 238.502698 -66.234056) (xy 238.340646 -66.336926)
			(xy 238.318294 -66.37528) (xy 238.663734 -66.57467)
		)
		(stroke
			(width 0)
			(type solid)
		)
		(fill yes)
		(layer "In11.Cu")
		(net "M_C_DQS_DN<9>")
	)
	(gr_poly
		(pts
			(xy 238.685832 -64.555116) (xy 238.69396 -64.363346) (xy 238.502698 -64.252856) (xy 238.340646 -64.355726)
			(xy 238.318294 -64.39408) (xy 238.663734 -64.593724)
		)
		(stroke
			(width 0)
			(type solid)
		)
		(fill yes)
		(layer "In11.Cu")
		(net "M_C_DQ<7>")
	)
	(gr_poly
		(pts
			(xy 238.685832 -63.564516) (xy 238.69396 -63.372746) (xy 238.502698 -63.262256) (xy 238.340646 -63.365126)
			(xy 238.318294 -63.40348) (xy 238.663734 -63.603124)
		)
		(stroke
			(width 0)
			(type solid)
		)
		(fill yes)
		(layer "In11.Cu")
		(net "M_C_DQ<3>")
	)
	(gr_poly
		(pts
			(xy 238.685832 -62.573916) (xy 238.69396 -62.382146) (xy 238.502698 -62.271656) (xy 238.340646 -62.374526)
			(xy 238.318294 -62.41288) (xy 238.663734 -62.612524)
		)
		(stroke
			(width 0)
			(type solid)
		)
		(fill yes)
		(layer "In11.Cu")
		(net "M_C_DQ<13>")
	)
	(gr_poly
		(pts
			(xy 238.685832 -61.583316) (xy 238.69396 -61.391546) (xy 238.502698 -61.281056) (xy 238.340646 -61.383926)
			(xy 238.318294 -61.42228) (xy 238.663734 -61.621924)
		)
		(stroke
			(width 0)
			(type solid)
		)
		(fill yes)
		(layer "In11.Cu")
		(net "M_C_DQ<9>")
	)
	(gr_poly
		(pts
			(xy 238.685832 -60.592716) (xy 238.69396 -60.400946) (xy 238.502698 -60.290456) (xy 238.340646 -60.393326)
			(xy 238.318294 -60.43168) (xy 238.663734 -60.631324)
		)
		(stroke
			(width 0)
			(type solid)
		)
		(fill yes)
		(layer "In11.Cu")
		(net "M_C_DQS_DN<10>")
	)
	(gr_poly
		(pts
			(xy 238.685832 -59.602116) (xy 238.69396 -59.410346) (xy 238.502698 -59.299856) (xy 238.340646 -59.402726)
			(xy 238.318294 -59.44108) (xy 238.663734 -59.640724)
		)
		(stroke
			(width 0)
			(type solid)
		)
		(fill yes)
		(layer "In11.Cu")
		(net "M_C_DQS_DN<1>")
	)
	(gr_poly
		(pts
			(xy 238.685832 -55.639716) (xy 238.69396 -55.447946) (xy 238.502698 -55.337456) (xy 238.340646 -55.440326)
			(xy 238.318294 -55.47868) (xy 238.663734 -55.678324)
		)
		(stroke
			(width 0)
			(type solid)
		)
		(fill yes)
		(layer "In11.Cu")
		(net "M_C_DQ<17>")
	)
	(gr_poly
		(pts
			(xy 238.685832 -54.649116) (xy 238.69396 -54.457346) (xy 238.502698 -54.346856) (xy 238.340646 -54.449726)
			(xy 238.318294 -54.48808) (xy 238.663734 -54.687724)
		)
		(stroke
			(width 0)
			(type solid)
		)
		(fill yes)
		(layer "In11.Cu")
		(net "M_C_DQS_DN<11>")
	)
	(gr_poly
		(pts
			(xy 238.685832 -53.658516) (xy 238.69396 -53.466746) (xy 238.502698 -53.356256) (xy 238.340646 -53.459126)
			(xy 238.318294 -53.49748) (xy 238.663734 -53.697124)
		)
		(stroke
			(width 0)
			(type solid)
		)
		(fill yes)
		(layer "In11.Cu")
		(net "M_C_DQS_DN<2>")
	)
	(gr_poly
		(pts
			(xy 238.687356 -65.546478) (xy 238.695484 -65.354708) (xy 238.504222 -65.244218) (xy 238.34217 -65.347088)
			(xy 238.319818 -65.385442) (xy 238.665258 -65.585086)
		)
		(stroke
			(width 0)
			(type solid)
		)
		(fill yes)
		(layer "In11.Cu")
		(net "M_C_DQS_DN<0>")
	)
	(gr_poly
		(pts
			(xy 238.687356 -58.612278) (xy 238.695484 -58.420508) (xy 238.504222 -58.310018) (xy 238.34217 -58.412888)
			(xy 238.319818 -58.451242) (xy 238.665258 -58.650632)
		)
		(stroke
			(width 0)
			(type solid)
		)
		(fill yes)
		(layer "In11.Cu")
		(net "M_C_DQ<15>")
	)
	(gr_poly
		(pts
			(xy 238.687356 -56.631078) (xy 238.695484 -56.439308) (xy 238.504222 -56.328818) (xy 238.34217 -56.431688)
			(xy 238.319818 -56.470042) (xy 238.665258 -56.669686)
		)
		(stroke
			(width 0)
			(type solid)
		)
		(fill yes)
		(layer "In11.Cu")
		(net "M_C_DQ<21>")
	)
	(gr_poly
		(pts
			(xy 238.687356 -52.668678) (xy 238.695484 -52.476908) (xy 238.504222 -52.366418) (xy 238.34217 -52.469288)
			(xy 238.319818 -52.507642) (xy 238.665258 -52.707032)
		)
		(stroke
			(width 0)
			(type solid)
		)
		(fill yes)
		(layer "In11.Cu")
		(net "M_C_DQ<23>")
	)
	(gr_poly
		(pts
			(xy 238.691674 -93.37675) (xy 238.683546 -93.18498) (xy 238.661448 -93.146372) (xy 238.316008 -93.345762)
			(xy 238.33836 -93.38437) (xy 238.500412 -93.48724)
		)
		(stroke
			(width 0)
			(type solid)
		)
		(fill yes)
		(layer "In11.Cu")
		(net "M_F_DQ<15>")
	)
	(gr_poly
		(pts
			(xy 238.69396 -94.36608) (xy 238.685832 -94.17431) (xy 238.663734 -94.135702) (xy 238.318294 -94.335346)
			(xy 238.340646 -94.3737) (xy 238.502698 -94.47657)
		)
		(stroke
			(width 0)
			(type solid)
		)
		(fill yes)
		(layer "In11.Cu")
		(net "M_F_DQ<11>")
	)
	(gr_poly
		(pts
			(xy 238.695484 -98.327464) (xy 238.687356 -98.135694) (xy 238.665258 -98.097086) (xy 238.319818 -98.29673)
			(xy 238.34217 -98.335084) (xy 238.504222 -98.437954)
		)
		(stroke
			(width 0)
			(type solid)
		)
		(fill yes)
		(layer "In11.Cu")
		(net "M_F_DQS_DP<2>")
	)
	(gr_poly
		(pts
			(xy 238.695484 -97.336864) (xy 238.687356 -97.145094) (xy 238.665258 -97.106486) (xy 238.319818 -97.30613)
			(xy 238.34217 -97.344484) (xy 238.504222 -97.447354)
		)
		(stroke
			(width 0)
			(type solid)
		)
		(fill yes)
		(layer "In11.Cu")
		(net "M_F_DQS_DN<11>")
	)
	(gr_poly
		(pts
			(xy 238.695484 -96.346264) (xy 238.687356 -96.154494) (xy 238.665258 -96.115886) (xy 238.319818 -96.31553)
			(xy 238.34217 -96.353884) (xy 238.504222 -96.456754)
		)
		(stroke
			(width 0)
			(type solid)
		)
		(fill yes)
		(layer "In11.Cu")
		(net "M_F_DQ<17>")
	)
	(gr_poly
		(pts
			(xy 238.695484 -95.355664) (xy 238.687356 -95.163894) (xy 238.665258 -95.125286) (xy 238.319818 -95.32493)
			(xy 238.34217 -95.363284) (xy 238.504222 -95.466154)
		)
		(stroke
			(width 0)
			(type solid)
		)
		(fill yes)
		(layer "In11.Cu")
		(net "M_F_DQ<21>")
	)
	(gr_poly
		(pts
			(xy 238.695484 -92.383864) (xy 238.687356 -92.192094) (xy 238.665258 -92.153486) (xy 238.319818 -92.35313)
			(xy 238.34217 -92.391484) (xy 238.504222 -92.494354)
		)
		(stroke
			(width 0)
			(type solid)
		)
		(fill yes)
		(layer "In11.Cu")
		(net "M_F_DQS_DP<1>")
	)
	(gr_poly
		(pts
			(xy 238.695484 -91.393264) (xy 238.687356 -91.201494) (xy 238.665258 -91.162886) (xy 238.319818 -91.36253)
			(xy 238.34217 -91.400884) (xy 238.504222 -91.503754)
		)
		(stroke
			(width 0)
			(type solid)
		)
		(fill yes)
		(layer "In11.Cu")
		(net "M_F_DQS_DN<10>")
	)
	(gr_poly
		(pts
			(xy 238.695484 -90.402664) (xy 238.687356 -90.210894) (xy 238.665258 -90.172286) (xy 238.319818 -90.37193)
			(xy 238.34217 -90.410284) (xy 238.504222 -90.513154)
		)
		(stroke
			(width 0)
			(type solid)
		)
		(fill yes)
		(layer "In11.Cu")
		(net "M_F_DQ<9>")
	)
	(gr_poly
		(pts
			(xy 238.695484 -89.412064) (xy 238.687356 -89.220294) (xy 238.665258 -89.181686) (xy 238.319818 -89.38133)
			(xy 238.34217 -89.419684) (xy 238.504222 -89.522554)
		)
		(stroke
			(width 0)
			(type solid)
		)
		(fill yes)
		(layer "In11.Cu")
		(net "M_F_DQ<13>")
	)
	(gr_poly
		(pts
			(xy 238.695484 -88.421464) (xy 238.687356 -88.229694) (xy 238.665258 -88.191086) (xy 238.319818 -88.39073)
			(xy 238.34217 -88.429084) (xy 238.504222 -88.531954)
		)
		(stroke
			(width 0)
			(type solid)
		)
		(fill yes)
		(layer "In11.Cu")
		(net "M_F_DQ<3>")
	)
	(gr_poly
		(pts
			(xy 238.695484 -87.430864) (xy 238.687356 -87.239094) (xy 238.665258 -87.200486) (xy 238.319818 -87.40013)
			(xy 238.34217 -87.438484) (xy 238.504222 -87.541354)
		)
		(stroke
			(width 0)
			(type solid)
		)
		(fill yes)
		(layer "In11.Cu")
		(net "M_F_DQ<7>")
	)
	(gr_poly
		(pts
			(xy 238.695484 -86.440264) (xy 238.687356 -86.248494) (xy 238.665258 -86.209886) (xy 238.319818 -86.40953)
			(xy 238.34217 -86.447884) (xy 238.504222 -86.550754)
		)
		(stroke
			(width 0)
			(type solid)
		)
		(fill yes)
		(layer "In11.Cu")
		(net "M_F_DQS_DP<0>")
	)
	(gr_poly
		(pts
			(xy 238.695484 -85.449664) (xy 238.687356 -85.257894) (xy 238.665258 -85.219286) (xy 238.319818 -85.41893)
			(xy 238.34217 -85.457284) (xy 238.504222 -85.560154)
		)
		(stroke
			(width 0)
			(type solid)
		)
		(fill yes)
		(layer "In11.Cu")
		(net "M_F_DQS_DN<9>")
	)
	(gr_poly
		(pts
			(xy 238.695484 -84.459064) (xy 238.687356 -84.267294) (xy 238.665258 -84.228686) (xy 238.319818 -84.42833)
			(xy 238.34217 -84.466684) (xy 238.504222 -84.569554)
		)
		(stroke
			(width 0)
			(type solid)
		)
		(fill yes)
		(layer "In11.Cu")
		(net "M_F_DQ<1>")
	)
	(gr_poly
		(pts
			(xy 238.695484 -83.468718) (xy 238.687356 -83.276948) (xy 238.665258 -83.238594) (xy 238.319818 -83.43773)
			(xy 238.34217 -83.476338) (xy 238.504222 -83.579208)
		)
		(stroke
			(width 0)
			(type solid)
		)
		(fill yes)
		(layer "In11.Cu")
		(net "M_F_DQ<5>")
	)
	(gr_poly
		(pts
			(xy 238.806482 -49.397666) (xy 238.762032 -49.397666) (xy 238.568992 -49.486566) (xy 238.568992 -49.715166)
			(xy 238.762032 -49.804066) (xy 238.806482 -49.804066)
		)
		(stroke
			(width 0)
			(type solid)
		)
		(fill yes)
		(layer "In11.Cu")
		(net "M_C_DQ<18>")
	)
	(gr_poly
		(pts
			(xy 238.891826 -60.197238) (xy 238.914178 -60.158884) (xy 238.568738 -59.95924) (xy 238.54664 -59.997848)
			(xy 238.538512 -60.189618) (xy 238.729774 -60.300108)
		)
		(stroke
			(width 0)
			(type solid)
		)
		(fill yes)
		(layer "In11.Cu")
		(net "M_C_DQS_DP<1>")
	)
	(gr_poly
		(pts
			(xy 238.891826 -58.216038) (xy 238.914178 -58.177684) (xy 238.568738 -57.97804) (xy 238.54664 -58.016648)
			(xy 238.538512 -58.208418) (xy 238.729774 -58.318908)
		)
		(stroke
			(width 0)
			(type solid)
		)
		(fill yes)
		(layer "In11.Cu")
		(net "M_C_DQ<10>")
	)
	(gr_poly
		(pts
			(xy 238.89335 -69.1134) (xy 238.915702 -69.074792) (xy 238.570262 -68.875656) (xy 238.548164 -68.91401)
			(xy 238.540036 -69.10578) (xy 238.731298 -69.21627)
		)
		(stroke
			(width 0)
			(type solid)
		)
		(fill yes)
		(layer "In11.Cu")
		(net "M_C_DQ<4>")
	)
	(gr_poly
		(pts
			(xy 238.89335 -68.1228) (xy 238.915702 -68.084192) (xy 238.570262 -67.885056) (xy 238.548164 -67.92341)
			(xy 238.540036 -68.11518) (xy 238.731298 -68.22567)
		)
		(stroke
			(width 0)
			(type solid)
		)
		(fill yes)
		(layer "In11.Cu")
		(net "M_C_DQ<0>")
	)
	(gr_poly
		(pts
			(xy 238.89335 -65.151) (xy 238.915702 -65.112392) (xy 238.570262 -64.913002) (xy 238.548164 -64.95161)
			(xy 238.540036 -65.14338) (xy 238.731298 -65.25387)
		)
		(stroke
			(width 0)
			(type solid)
		)
		(fill yes)
		(layer "In11.Cu")
		(net "M_C_DQ<6>")
	)
	(gr_poly
		(pts
			(xy 238.89335 -64.1604) (xy 238.915702 -64.121792) (xy 238.570262 -63.922402) (xy 238.548164 -63.96101)
			(xy 238.540036 -64.15278) (xy 238.731298 -64.26327)
		)
		(stroke
			(width 0)
			(type solid)
		)
		(fill yes)
		(layer "In11.Cu")
		(net "M_C_DQ<2>")
	)
	(gr_poly
		(pts
			(xy 238.89335 -63.1698) (xy 238.915702 -63.131192) (xy 238.570262 -62.931802) (xy 238.548164 -62.97041)
			(xy 238.540036 -63.16218) (xy 238.731298 -63.27267)
		)
		(stroke
			(width 0)
			(type solid)
		)
		(fill yes)
		(layer "In11.Cu")
		(net "M_C_DQ<12>")
	)
	(gr_poly
		(pts
			(xy 238.89335 -62.1792) (xy 238.915702 -62.140592) (xy 238.570262 -61.941202) (xy 238.548164 -61.97981)
			(xy 238.540036 -62.17158) (xy 238.731298 -62.28207)
		)
		(stroke
			(width 0)
			(type solid)
		)
		(fill yes)
		(layer "In11.Cu")
		(net "M_C_DQ<8>")
	)
	(gr_poly
		(pts
			(xy 238.89335 -61.1886) (xy 238.915702 -61.149992) (xy 238.570262 -60.950602) (xy 238.548164 -60.98921)
			(xy 238.540036 -61.18098) (xy 238.731298 -61.29147)
		)
		(stroke
			(width 0)
			(type solid)
		)
		(fill yes)
		(layer "In11.Cu")
		(net "M_C_DQS_DP<10>")
	)
	(gr_poly
		(pts
			(xy 238.89335 -57.2262) (xy 238.915702 -57.187592) (xy 238.570262 -56.988202) (xy 238.548164 -57.02681)
			(xy 238.540036 -57.21858) (xy 238.731298 -57.32907)
		)
		(stroke
			(width 0)
			(type solid)
		)
		(fill yes)
		(layer "In11.Cu")
		(net "M_C_DQ<20>")
	)
	(gr_poly
		(pts
			(xy 238.89335 -56.2356) (xy 238.915702 -56.196992) (xy 238.570262 -55.997602) (xy 238.548164 -56.03621)
			(xy 238.540036 -56.22798) (xy 238.731298 -56.33847)
		)
		(stroke
			(width 0)
			(type solid)
		)
		(fill yes)
		(layer "In11.Cu")
		(net "M_C_DQ<16>")
	)
	(gr_poly
		(pts
			(xy 238.89335 -54.2544) (xy 238.915702 -54.215792) (xy 238.570262 -54.016402) (xy 238.548164 -54.05501)
			(xy 238.540036 -54.24678) (xy 238.731298 -54.35727)
		)
		(stroke
			(width 0)
			(type solid)
		)
		(fill yes)
		(layer "In11.Cu")
		(net "M_C_DQS_DP<2>")
	)
	(gr_poly
		(pts
			(xy 238.89335 -52.2732) (xy 238.915702 -52.234592) (xy 238.570262 -52.035202) (xy 238.548164 -52.07381)
			(xy 238.540036 -52.26558) (xy 238.731298 -52.37607)
		)
		(stroke
			(width 0)
			(type solid)
		)
		(fill yes)
		(layer "In11.Cu")
		(net "M_C_DQ<18>")
	)
	(gr_poly
		(pts
			(xy 238.895128 -55.246016) (xy 238.91748 -55.207408) (xy 238.57204 -55.008018) (xy 238.549942 -55.046626)
			(xy 238.541814 -55.238396) (xy 238.733076 -55.348886)
		)
		(stroke
			(width 0)
			(type solid)
		)
		(fill yes)
		(layer "In11.Cu")
		(net "M_C_DQS_DP<11>")
	)
	(gr_poly
		(pts
			(xy 238.895636 -59.20867) (xy 238.917988 -59.170316) (xy 238.572548 -58.970672) (xy 238.55045 -59.00928)
			(xy 238.542322 -59.20105) (xy 238.733584 -59.31154)
		)
		(stroke
			(width 0)
			(type solid)
		)
		(fill yes)
		(layer "In11.Cu")
		(net "M_C_DQ<14>")
	)
	(gr_poly
		(pts
			(xy 238.895636 -53.26507) (xy 238.917988 -53.226716) (xy 238.572548 -53.027072) (xy 238.55045 -53.06568)
			(xy 238.542322 -53.25745) (xy 238.733584 -53.36794)
		)
		(stroke
			(width 0)
			(type solid)
		)
		(fill yes)
		(layer "In11.Cu")
		(net "M_C_DQ<22>")
	)
	(gr_poly
		(pts
			(xy 238.90097 -67.136518) (xy 238.923322 -67.098164) (xy 238.577882 -66.89852) (xy 238.555784 -66.937128)
			(xy 238.547656 -67.128898) (xy 238.738918 -67.239388)
		)
		(stroke
			(width 0)
			(type solid)
		)
		(fill yes)
		(layer "In11.Cu")
		(net "M_C_DQS_DP<9>")
	)
	(gr_poly
		(pts
			(xy 238.90097 -66.145918) (xy 238.923322 -66.107564) (xy 238.577882 -65.90792) (xy 238.555784 -65.946528)
			(xy 238.547656 -66.138298) (xy 238.738918 -66.248788)
		)
		(stroke
			(width 0)
			(type solid)
		)
		(fill yes)
		(layer "In11.Cu")
		(net "M_C_DQS_DP<0>")
	)
	(gr_poly
		(pts
			(xy 238.914178 -98.570796) (xy 238.891826 -98.532442) (xy 238.729774 -98.429572) (xy 238.538512 -98.540062)
			(xy 238.546386 -98.731832) (xy 238.568484 -98.770186)
		)
		(stroke
			(width 0)
			(type solid)
		)
		(fill yes)
		(layer "In11.Cu")
		(net "M_F_DQ<22>")
	)
	(gr_poly
		(pts
			(xy 238.914178 -97.58045) (xy 238.891826 -97.541842) (xy 238.729774 -97.438972) (xy 238.538512 -97.549462)
			(xy 238.54664 -97.741232) (xy 238.568738 -97.77984)
		)
		(stroke
			(width 0)
			(type solid)
		)
		(fill yes)
		(layer "In11.Cu")
		(net "M_F_DQS_DN<2>")
	)
	(gr_poly
		(pts
			(xy 238.914178 -96.58985) (xy 238.891826 -96.551242) (xy 238.729774 -96.448372) (xy 238.538512 -96.558862)
			(xy 238.54664 -96.750632) (xy 238.568738 -96.78924)
		)
		(stroke
			(width 0)
			(type solid)
		)
		(fill yes)
		(layer "In11.Cu")
		(net "M_F_DQS_DP<11>")
	)
	(gr_poly
		(pts
			(xy 238.914178 -95.59925) (xy 238.891826 -95.560642) (xy 238.729774 -95.457772) (xy 238.538512 -95.568262)
			(xy 238.54664 -95.760032) (xy 238.568738 -95.79864)
		)
		(stroke
			(width 0)
			(type solid)
		)
		(fill yes)
		(layer "In11.Cu")
		(net "M_F_DQ<16>")
	)
	(gr_poly
		(pts
			(xy 238.914178 -92.62745) (xy 238.891826 -92.588842) (xy 238.729774 -92.485972) (xy 238.538512 -92.596462)
			(xy 238.54664 -92.788232) (xy 238.568738 -92.82684)
		)
		(stroke
			(width 0)
			(type solid)
		)
		(fill yes)
		(layer "In11.Cu")
		(net "M_F_DQ<14>")
	)
	(gr_poly
		(pts
			(xy 238.914178 -91.63685) (xy 238.891826 -91.598242) (xy 238.729774 -91.495372) (xy 238.538512 -91.605862)
			(xy 238.54664 -91.797632) (xy 238.568738 -91.83624)
		)
		(stroke
			(width 0)
			(type solid)
		)
		(fill yes)
		(layer "In11.Cu")
		(net "M_F_DQS_DN<1>")
	)
	(gr_poly
		(pts
			(xy 238.914178 -90.64625) (xy 238.891826 -90.607642) (xy 238.729774 -90.504772) (xy 238.538512 -90.615262)
			(xy 238.54664 -90.807032) (xy 238.568738 -90.84564)
		)
		(stroke
			(width 0)
			(type solid)
		)
		(fill yes)
		(layer "In11.Cu")
		(net "M_F_DQS_DP<10>")
	)
	(gr_poly
		(pts
			(xy 238.914178 -89.65565) (xy 238.891826 -89.617042) (xy 238.729774 -89.514172) (xy 238.538512 -89.624662)
			(xy 238.54664 -89.816432) (xy 238.568738 -89.85504)
		)
		(stroke
			(width 0)
			(type solid)
		)
		(fill yes)
		(layer "In11.Cu")
		(net "M_F_DQ<8>")
	)
	(gr_poly
		(pts
			(xy 238.914178 -88.66505) (xy 238.891826 -88.626442) (xy 238.729774 -88.523572) (xy 238.538512 -88.634062)
			(xy 238.54664 -88.825832) (xy 238.568738 -88.86444)
		)
		(stroke
			(width 0)
			(type solid)
		)
		(fill yes)
		(layer "In11.Cu")
		(net "M_F_DQ<12>")
	)
	(gr_poly
		(pts
			(xy 238.914178 -87.67445) (xy 238.891826 -87.635842) (xy 238.729774 -87.532972) (xy 238.538512 -87.643462)
			(xy 238.54664 -87.835232) (xy 238.568738 -87.87384)
		)
		(stroke
			(width 0)
			(type solid)
		)
		(fill yes)
		(layer "In11.Cu")
		(net "M_F_DQ<2>")
	)
	(gr_poly
		(pts
			(xy 238.914178 -86.68385) (xy 238.891826 -86.645242) (xy 238.729774 -86.542372) (xy 238.538512 -86.652862)
			(xy 238.54664 -86.844632) (xy 238.568738 -86.88324)
		)
		(stroke
			(width 0)
			(type solid)
		)
		(fill yes)
		(layer "In11.Cu")
		(net "M_F_DQ<6>")
	)
	(gr_poly
		(pts
			(xy 238.914178 -85.69325) (xy 238.891826 -85.654642) (xy 238.729774 -85.551772) (xy 238.538512 -85.662262)
			(xy 238.54664 -85.854032) (xy 238.568738 -85.89264)
		)
		(stroke
			(width 0)
			(type solid)
		)
		(fill yes)
		(layer "In11.Cu")
		(net "M_F_DQS_DN<0>")
	)
	(gr_poly
		(pts
			(xy 238.914178 -84.70265) (xy 238.891826 -84.664042) (xy 238.729774 -84.561172) (xy 238.538512 -84.671662)
			(xy 238.54664 -84.863432) (xy 238.568738 -84.90204)
		)
		(stroke
			(width 0)
			(type solid)
		)
		(fill yes)
		(layer "In11.Cu")
		(net "M_F_DQS_DP<9>")
	)
	(gr_poly
		(pts
			(xy 238.914178 -83.71205) (xy 238.891826 -83.673442) (xy 238.729774 -83.570572) (xy 238.538512 -83.681062)
			(xy 238.54664 -83.872832) (xy 238.568738 -83.91144)
		)
		(stroke
			(width 0)
			(type solid)
		)
		(fill yes)
		(layer "In11.Cu")
		(net "M_F_DQ<0>")
	)
	(gr_poly
		(pts
			(xy 238.914178 -82.72145) (xy 238.891826 -82.682842) (xy 238.729774 -82.579972) (xy 238.538512 -82.690462)
			(xy 238.54664 -82.882232) (xy 238.568738 -82.92084)
		)
		(stroke
			(width 0)
			(type solid)
		)
		(fill yes)
		(layer "In11.Cu")
		(net "M_F_DQ<4>")
	)
	(gr_poly
		(pts
			(xy 238.915702 -93.61678) (xy 238.89335 -93.578426) (xy 238.731298 -93.475556) (xy 238.540036 -93.586046)
			(xy 238.548164 -93.777816) (xy 238.570262 -93.81617)
		)
		(stroke
			(width 0)
			(type solid)
		)
		(fill yes)
		(layer "In11.Cu")
		(net "M_F_DQ<10>")
	)
	(gr_poly
		(pts
			(xy 238.917988 -94.60611) (xy 238.895636 -94.567756) (xy 238.733584 -94.464886) (xy 238.542322 -94.575376)
			(xy 238.55045 -94.767146) (xy 238.572548 -94.805754)
		)
		(stroke
			(width 0)
			(type solid)
		)
		(fill yes)
		(layer "In11.Cu")
		(net "M_F_DQ<20>")
	)
	(gr_poly
		(pts
			(xy 238.97971 -105.362248) (xy 238.90605 -105.162858) (xy 238.874808 -105.131362) (xy 238.58728 -105.418636)
			(xy 238.618776 -105.450132) (xy 238.818166 -105.523792)
		)
		(stroke
			(width 0)
			(type solid)
		)
		(fill yes)
		(layer "In11.Cu")
		(net "M_F_DQ<19>")
	)
	(gr_poly
		(pts
			(xy 238.993426 -100.772976) (xy 238.993426 -100.551996) (xy 238.823246 -100.463096) (xy 238.778796 -100.463096)
			(xy 238.778796 -100.861876) (xy 238.823246 -100.861876)
		)
		(stroke
			(width 0)
			(type solid)
		)
		(fill yes)
		(layer "In11.Cu")
		(net "M_F_DQ<23>")
	)
	(gr_poly
		(pts
			(xy 238.993426 -99.77628) (xy 238.993426 -99.5553) (xy 238.823246 -99.4664) (xy 238.778796 -99.4664)
			(xy 238.778796 -99.86518) (xy 238.823246 -99.86518)
		)
		(stroke
			(width 0)
			(type solid)
		)
		(fill yes)
		(layer "In11.Cu")
		(net "M_F_DQ<23>")
	)
	(gr_poly
		(pts
			(xy 238.993426 -51.249326) (xy 238.993426 -51.028346) (xy 238.823246 -50.939446) (xy 238.778796 -50.939446)
			(xy 238.778796 -51.338226) (xy 238.823246 -51.338226)
		)
		(stroke
			(width 0)
			(type solid)
		)
		(fill yes)
		(layer "In11.Cu")
		(net "M_C_DQ<19>")
	)
	(gr_poly
		(pts
			(xy 239.024922 -102.979982) (xy 239.024922 -102.751382) (xy 238.831882 -102.662482) (xy 238.787432 -102.662482)
			(xy 238.787432 -103.068882) (xy 238.831882 -103.068882)
		)
		(stroke
			(width 0)
			(type solid)
		)
		(fill yes)
		(layer "In11.Cu")
		(net "M_F_DQ<23>")
	)
	(gr_poly
		(pts
			(xy 239.024922 -101.989382) (xy 239.024922 -101.760782) (xy 238.831882 -101.671882) (xy 238.787432 -101.671882)
			(xy 238.787432 -102.078282) (xy 238.831882 -102.078282)
		)
		(stroke
			(width 0)
			(type solid)
		)
		(fill yes)
		(layer "In11.Cu")
		(net "M_F_DQ<23>")
	)
	(gr_poly
		(pts
			(xy 239.075214 -104.66324) (xy 239.043972 -104.631744) (xy 238.844582 -104.558084) (xy 238.682784 -104.719628)
			(xy 238.756444 -104.919018) (xy 238.78794 -104.950514)
		)
		(stroke
			(width 0)
			(type solid)
		)
		(fill yes)
		(layer "In11.Cu")
		(net "M_F_DQ<18>")
	)
	(gr_poly
		(pts
			(xy 239.234472 -49.715166) (xy 239.234472 -49.486566) (xy 239.041432 -49.397666) (xy 238.996982 -49.397666)
			(xy 238.996982 -49.804066) (xy 239.041432 -49.804066)
		)
		(stroke
			(width 0)
			(type solid)
		)
		(fill yes)
		(layer "In11.Cu")
		(net "M_C_DQ<19>")
	)
	(gr_poly
		(pts
			(xy 239.542066 -59.105546) (xy 239.550194 -58.913776) (xy 239.358932 -58.803286) (xy 239.19688 -58.906156)
			(xy 239.174528 -58.94451) (xy 239.519968 -59.1439)
		)
		(stroke
			(width 0)
			(type solid)
		)
		(fill yes)
		(layer "In11.Cu")
		(net "M_C_DQ<15>")
	)
	(gr_poly
		(pts
			(xy 239.542066 -53.161946) (xy 239.550194 -52.970176) (xy 239.358932 -52.859686) (xy 239.19688 -52.962556)
			(xy 239.174528 -53.00091) (xy 239.519968 -53.2003)
		)
		(stroke
			(width 0)
			(type solid)
		)
		(fill yes)
		(layer "In11.Cu")
		(net "M_C_DQ<23>")
	)
	(gr_poly
		(pts
			(xy 239.544352 -58.116216) (xy 239.55248 -57.924446) (xy 239.361218 -57.813956) (xy 239.199166 -57.916826)
			(xy 239.176814 -57.95518) (xy 239.522254 -58.154824)
		)
		(stroke
			(width 0)
			(type solid)
		)
		(fill yes)
		(layer "In11.Cu")
		(net "M_C_DQ<11>")
	)
	(gr_poly
		(pts
			(xy 239.54486 -67.128898) (xy 239.536732 -66.937128) (xy 239.514634 -66.89852) (xy 239.169194 -67.098164)
			(xy 239.191546 -67.136518) (xy 239.353598 -67.239388)
		)
		(stroke
			(width 0)
			(type solid)
		)
		(fill yes)
		(layer "In11.Cu")
		(net "M_C_DQS_DP<9>")
	)
	(gr_poly
		(pts
			(xy 239.54486 -66.138298) (xy 239.536732 -65.946528) (xy 239.514634 -65.90792) (xy 239.169194 -66.107564)
			(xy 239.191546 -66.145918) (xy 239.353598 -66.248788)
		)
		(stroke
			(width 0)
			(type solid)
		)
		(fill yes)
		(layer "In11.Cu")
		(net "M_C_DQS_DP<0>")
	)
	(gr_poly
		(pts
			(xy 239.545876 -84.863432) (xy 239.554004 -84.671662) (xy 239.362742 -84.561172) (xy 239.20069 -84.664042)
			(xy 239.178338 -84.70265) (xy 239.523778 -84.90204)
		)
		(stroke
			(width 0)
			(type solid)
		)
		(fill yes)
		(layer "In11.Cu")
		(net "M_F_DQS_DP<9>")
	)
	(gr_poly
		(pts
			(xy 239.545876 -83.872832) (xy 239.554004 -83.681062) (xy 239.362742 -83.570572) (xy 239.20069 -83.673442)
			(xy 239.178338 -83.71205) (xy 239.523778 -83.91144)
		)
		(stroke
			(width 0)
			(type solid)
		)
		(fill yes)
		(layer "In11.Cu")
		(net "M_F_DQ<0>")
	)
	(gr_poly
		(pts
			(xy 239.545876 -82.882232) (xy 239.554004 -82.690462) (xy 239.362742 -82.579972) (xy 239.20069 -82.682842)
			(xy 239.178338 -82.72145) (xy 239.523778 -82.92084)
		)
		(stroke
			(width 0)
			(type solid)
		)
		(fill yes)
		(layer "In11.Cu")
		(net "M_F_DQ<4>")
	)
	(gr_poly
		(pts
			(xy 239.545876 -60.098432) (xy 239.554004 -59.906662) (xy 239.362742 -59.796172) (xy 239.20069 -59.899042)
			(xy 239.178338 -59.937396) (xy 239.523778 -60.13704)
		)
		(stroke
			(width 0)
			(type solid)
		)
		(fill yes)
		(layer "In11.Cu")
		(net "M_C_DQS_DN<1>")
	)
	(gr_poly
		(pts
			(xy 239.545876 -57.126632) (xy 239.554004 -56.934862) (xy 239.362742 -56.824372) (xy 239.20069 -56.927242)
			(xy 239.178338 -56.965596) (xy 239.523778 -57.16524)
		)
		(stroke
			(width 0)
			(type solid)
		)
		(fill yes)
		(layer "In11.Cu")
		(net "M_C_DQ<21>")
	)
	(gr_poly
		(pts
			(xy 239.545876 -56.136032) (xy 239.554004 -55.944262) (xy 239.362742 -55.833772) (xy 239.20069 -55.936642)
			(xy 239.178338 -55.974996) (xy 239.523778 -56.17464)
		)
		(stroke
			(width 0)
			(type solid)
		)
		(fill yes)
		(layer "In11.Cu")
		(net "M_C_DQ<17>")
	)
	(gr_poly
		(pts
			(xy 239.545876 -55.145432) (xy 239.554004 -54.953662) (xy 239.362742 -54.843172) (xy 239.20069 -54.946042)
			(xy 239.178338 -54.984396) (xy 239.523778 -55.18404)
		)
		(stroke
			(width 0)
			(type solid)
		)
		(fill yes)
		(layer "In11.Cu")
		(net "M_C_DQS_DN<11>")
	)
	(gr_poly
		(pts
			(xy 239.545876 -54.154832) (xy 239.554004 -53.963062) (xy 239.362742 -53.852572) (xy 239.20069 -53.955442)
			(xy 239.178338 -53.993796) (xy 239.523778 -54.19344)
		)
		(stroke
			(width 0)
			(type solid)
		)
		(fill yes)
		(layer "In11.Cu")
		(net "M_C_DQS_DN<2>")
	)
	(gr_poly
		(pts
			(xy 239.545876 -52.173632) (xy 239.554004 -51.981862) (xy 239.362742 -51.871372) (xy 239.20069 -51.974242)
			(xy 239.178338 -52.012596) (xy 239.523778 -52.211986)
		)
		(stroke
			(width 0)
			(type solid)
		)
		(fill yes)
		(layer "In11.Cu")
		(net "M_C_DQ<19>")
	)
	(gr_poly
		(pts
			(xy 239.550194 -94.86265) (xy 239.542066 -94.67088) (xy 239.519968 -94.632272) (xy 239.174528 -94.831662)
			(xy 239.19688 -94.87027) (xy 239.358932 -94.97314)
		)
		(stroke
			(width 0)
			(type solid)
		)
		(fill yes)
		(layer "In11.Cu")
		(net "M_F_DQ<21>")
	)
	(gr_poly
		(pts
			(xy 239.550702 -90.899996) (xy 239.542574 -90.708226) (xy 239.520476 -90.669618) (xy 239.175036 -90.869262)
			(xy 239.197388 -90.907616) (xy 239.35944 -91.010486)
		)
		(stroke
			(width 0)
			(type solid)
		)
		(fill yes)
		(layer "In11.Cu")
		(net "M_F_DQS_DN<10>")
	)
	(gr_poly
		(pts
			(xy 239.55248 -98.82378) (xy 239.544352 -98.63201) (xy 239.522254 -98.593402) (xy 239.176814 -98.793046)
			(xy 239.199166 -98.8314) (xy 239.361218 -98.93427)
		)
		(stroke
			(width 0)
			(type solid)
		)
		(fill yes)
		(layer "In11.Cu")
		(net "M_F_DQ<23>")
	)
	(gr_poly
		(pts
			(xy 239.55248 -97.83318) (xy 239.544352 -97.64141) (xy 239.522254 -97.602802) (xy 239.176814 -97.802446)
			(xy 239.199166 -97.8408) (xy 239.361218 -97.94367)
		)
		(stroke
			(width 0)
			(type solid)
		)
		(fill yes)
		(layer "In11.Cu")
		(net "M_F_DQS_DP<2>")
	)
	(gr_poly
		(pts
			(xy 239.55248 -96.84258) (xy 239.544352 -96.65081) (xy 239.522254 -96.612202) (xy 239.176814 -96.811846)
			(xy 239.199166 -96.8502) (xy 239.361218 -96.95307)
		)
		(stroke
			(width 0)
			(type solid)
		)
		(fill yes)
		(layer "In11.Cu")
		(net "M_F_DQS_DN<11>")
	)
	(gr_poly
		(pts
			(xy 239.55248 -95.85198) (xy 239.544352 -95.66021) (xy 239.522254 -95.621602) (xy 239.176814 -95.821246)
			(xy 239.199166 -95.8596) (xy 239.361218 -95.96247)
		)
		(stroke
			(width 0)
			(type solid)
		)
		(fill yes)
		(layer "In11.Cu")
		(net "M_F_DQ<17>")
	)
	(gr_poly
		(pts
			(xy 239.55248 -91.88958) (xy 239.544352 -91.69781) (xy 239.522254 -91.659202) (xy 239.176814 -91.858846)
			(xy 239.199166 -91.8972) (xy 239.361218 -92.00007)
		)
		(stroke
			(width 0)
			(type solid)
		)
		(fill yes)
		(layer "In11.Cu")
		(net "M_F_DQS_DP<1>")
	)
	(gr_poly
		(pts
			(xy 239.55248 -89.90838) (xy 239.544352 -89.71661) (xy 239.522254 -89.678002) (xy 239.176814 -89.877646)
			(xy 239.199166 -89.916) (xy 239.361218 -90.01887)
		)
		(stroke
			(width 0)
			(type solid)
		)
		(fill yes)
		(layer "In11.Cu")
		(net "M_F_DQ<9>")
	)
	(gr_poly
		(pts
			(xy 239.55248 -88.91778) (xy 239.544352 -88.72601) (xy 239.522254 -88.687402) (xy 239.176814 -88.887046)
			(xy 239.199166 -88.9254) (xy 239.361218 -89.02827)
		)
		(stroke
			(width 0)
			(type solid)
		)
		(fill yes)
		(layer "In11.Cu")
		(net "M_F_DQ<13>")
	)
	(gr_poly
		(pts
			(xy 239.55248 -69.10578) (xy 239.544352 -68.91401) (xy 239.522254 -68.875656) (xy 239.176814 -69.074792)
			(xy 239.199166 -69.1134) (xy 239.361218 -69.21627)
		)
		(stroke
			(width 0)
			(type solid)
		)
		(fill yes)
		(layer "In11.Cu")
		(net "M_C_DQ<4>")
	)
	(gr_poly
		(pts
			(xy 239.55248 -68.11518) (xy 239.544352 -67.92341) (xy 239.522254 -67.885056) (xy 239.176814 -68.084192)
			(xy 239.199166 -68.1228) (xy 239.361218 -68.22567)
		)
		(stroke
			(width 0)
			(type solid)
		)
		(fill yes)
		(layer "In11.Cu")
		(net "M_C_DQ<0>")
	)
	(gr_poly
		(pts
			(xy 239.554004 -93.870018) (xy 239.545876 -93.678248) (xy 239.523778 -93.639894) (xy 239.178338 -93.83903)
			(xy 239.20069 -93.877638) (xy 239.362742 -93.980508)
		)
		(stroke
			(width 0)
			(type solid)
		)
		(fill yes)
		(layer "In11.Cu")
		(net "M_F_DQ<11>")
	)
	(gr_poly
		(pts
			(xy 239.680242 -104.661716) (xy 239.606582 -104.462326) (xy 239.57534 -104.43083) (xy 239.287812 -104.718104)
			(xy 239.319308 -104.7496) (xy 239.518698 -104.82326)
		)
		(stroke
			(width 0)
			(type solid)
		)
		(fill yes)
		(layer "In11.Cu")
		(net "M_F_DQ<19>")
	)
	(gr_poly
		(pts
			(xy 239.750346 -85.457284) (xy 239.772698 -85.41893) (xy 239.427258 -85.219286) (xy 239.40516 -85.257894)
			(xy 239.397032 -85.449664) (xy 239.588294 -85.560154)
		)
		(stroke
			(width 0)
			(type solid)
		)
		(fill yes)
		(layer "In11.Cu")
		(net "M_F_DQS_DN<9>")
	)
	(gr_poly
		(pts
			(xy 239.750346 -84.466684) (xy 239.772698 -84.42833) (xy 239.427258 -84.228686) (xy 239.40516 -84.267294)
			(xy 239.397032 -84.459064) (xy 239.588294 -84.569554)
		)
		(stroke
			(width 0)
			(type solid)
		)
		(fill yes)
		(layer "In11.Cu")
		(net "M_F_DQ<1>")
	)
	(gr_poly
		(pts
			(xy 239.750346 -83.476338) (xy 239.772698 -83.43773) (xy 239.427258 -83.238594) (xy 239.40516 -83.276948)
			(xy 239.397032 -83.468718) (xy 239.588294 -83.579208)
		)
		(stroke
			(width 0)
			(type solid)
		)
		(fill yes)
		(layer "In11.Cu")
		(net "M_F_DQ<5>")
	)
	(gr_poly
		(pts
			(xy 239.750346 -60.692284) (xy 239.772698 -60.65393) (xy 239.427258 -60.454286) (xy 239.40516 -60.492894)
			(xy 239.397032 -60.684664) (xy 239.588294 -60.795154)
		)
		(stroke
			(width 0)
			(type solid)
		)
		(fill yes)
		(layer "In11.Cu")
		(net "M_C_DQS_DP<1>")
	)
	(gr_poly
		(pts
			(xy 239.750346 -56.729884) (xy 239.772698 -56.69153) (xy 239.427258 -56.491886) (xy 239.40516 -56.530494)
			(xy 239.397032 -56.722264) (xy 239.588294 -56.832754)
		)
		(stroke
			(width 0)
			(type solid)
		)
		(fill yes)
		(layer "In11.Cu")
		(net "M_C_DQ<16>")
	)
	(gr_poly
		(pts
			(xy 239.750346 -54.748684) (xy 239.772698 -54.71033) (xy 239.427258 -54.510686) (xy 239.40516 -54.549294)
			(xy 239.397032 -54.741064) (xy 239.588294 -54.851554)
		)
		(stroke
			(width 0)
			(type solid)
		)
		(fill yes)
		(layer "In11.Cu")
		(net "M_C_DQS_DP<2>")
	)
	(gr_poly
		(pts
			(xy 239.750346 -53.758084) (xy 239.772698 -53.71973) (xy 239.427258 -53.520086) (xy 239.40516 -53.558694)
			(xy 239.397032 -53.750464) (xy 239.588294 -53.860954)
		)
		(stroke
			(width 0)
			(type solid)
		)
		(fill yes)
		(layer "In11.Cu")
		(net "M_C_DQ<22>")
	)
	(gr_poly
		(pts
			(xy 239.75187 -55.740046) (xy 239.774222 -55.701692) (xy 239.428782 -55.502048) (xy 239.406684 -55.540656)
			(xy 239.398556 -55.732426) (xy 239.589818 -55.842916)
		)
		(stroke
			(width 0)
			(type solid)
		)
		(fill yes)
		(layer "In11.Cu")
		(net "M_C_DQS_DP<11>")
	)
	(gr_poly
		(pts
			(xy 239.75187 -52.7685) (xy 239.774222 -52.729892) (xy 239.428782 -52.530502) (xy 239.406684 -52.56911)
			(xy 239.398556 -52.76088) (xy 239.589818 -52.87137)
		)
		(stroke
			(width 0)
			(type solid)
		)
		(fill yes)
		(layer "In11.Cu")
		(net "M_C_DQ<18>")
	)
	(gr_poly
		(pts
			(xy 239.754156 -57.72277) (xy 239.776508 -57.684416) (xy 239.431068 -57.484772) (xy 239.40897 -57.52338)
			(xy 239.400842 -57.71515) (xy 239.592104 -57.82564)
		)
		(stroke
			(width 0)
			(type solid)
		)
		(fill yes)
		(layer "In11.Cu")
		(net "M_C_DQ<20>")
	)
	(gr_poly
		(pts
			(xy 239.772698 -94.112842) (xy 239.750346 -94.074488) (xy 239.588294 -93.971618) (xy 239.397032 -94.082108)
			(xy 239.40516 -94.273878) (xy 239.427258 -94.312486)
		)
		(stroke
			(width 0)
			(type solid)
		)
		(fill yes)
		(layer "In11.Cu")
		(net "M_F_DQ<20>")
	)
	(gr_poly
		(pts
			(xy 239.774222 -98.07448) (xy 239.75187 -98.036126) (xy 239.589818 -97.933256) (xy 239.398556 -98.043746)
			(xy 239.406684 -98.235516) (xy 239.428782 -98.27387)
		)
		(stroke
			(width 0)
			(type solid)
		)
		(fill yes)
		(layer "In11.Cu")
		(net "M_F_DQ<22>")
	)
	(gr_poly
		(pts
			(xy 239.774222 -97.08388) (xy 239.75187 -97.045526) (xy 239.589818 -96.942656) (xy 239.398556 -97.053146)
			(xy 239.406684 -97.244916) (xy 239.428782 -97.28327)
		)
		(stroke
			(width 0)
			(type solid)
		)
		(fill yes)
		(layer "In11.Cu")
		(net "M_F_DQS_DN<2>")
	)
	(gr_poly
		(pts
			(xy 239.774222 -96.09328) (xy 239.75187 -96.054926) (xy 239.589818 -95.952056) (xy 239.398556 -96.062546)
			(xy 239.406684 -96.254316) (xy 239.428782 -96.29267)
		)
		(stroke
			(width 0)
			(type solid)
		)
		(fill yes)
		(layer "In11.Cu")
		(net "M_F_DQS_DP<11>")
	)
	(gr_poly
		(pts
			(xy 239.774222 -95.10268) (xy 239.75187 -95.064326) (xy 239.589818 -94.961456) (xy 239.398556 -95.071946)
			(xy 239.406684 -95.263716) (xy 239.428782 -95.30207)
		)
		(stroke
			(width 0)
			(type solid)
		)
		(fill yes)
		(layer "In11.Cu")
		(net "M_F_DQ<16>")
	)
	(gr_poly
		(pts
			(xy 239.774222 -91.14028) (xy 239.75187 -91.101926) (xy 239.589818 -90.999056) (xy 239.398556 -91.109546)
			(xy 239.406684 -91.301316) (xy 239.428782 -91.33967)
		)
		(stroke
			(width 0)
			(type solid)
		)
		(fill yes)
		(layer "In11.Cu")
		(net "M_F_DQS_DN<1>")
	)
	(gr_poly
		(pts
			(xy 239.774222 -89.15908) (xy 239.75187 -89.120726) (xy 239.589818 -89.017856) (xy 239.398556 -89.128346)
			(xy 239.406684 -89.320116) (xy 239.428782 -89.35847)
		)
		(stroke
			(width 0)
			(type solid)
		)
		(fill yes)
		(layer "In11.Cu")
		(net "M_F_DQ<8>")
	)
	(gr_poly
		(pts
			(xy 239.774222 -88.16848) (xy 239.75187 -88.130126) (xy 239.589818 -88.027256) (xy 239.398556 -88.137746)
			(xy 239.406684 -88.329516) (xy 239.428782 -88.36787)
		)
		(stroke
			(width 0)
			(type solid)
		)
		(fill yes)
		(layer "In11.Cu")
		(net "M_F_DQ<12>")
	)
	(gr_poly
		(pts
			(xy 239.774222 -87.17788) (xy 239.75187 -87.139526) (xy 239.589818 -87.036656) (xy 239.398556 -87.147146)
			(xy 239.406684 -87.338916) (xy 239.428782 -87.37727)
		)
		(stroke
			(width 0)
			(type solid)
		)
		(fill yes)
		(layer "In11.Cu")
		(net "M_F_DQ<2>")
	)
	(gr_poly
		(pts
			(xy 239.774222 -68.35648) (xy 239.75187 -68.318126) (xy 239.589818 -68.215256) (xy 239.398556 -68.325746)
			(xy 239.406684 -68.517516) (xy 239.428782 -68.556124)
		)
		(stroke
			(width 0)
			(type solid)
		)
		(fill yes)
		(layer "In11.Cu")
		(net "M_C_DQ<5>")
	)
	(gr_poly
		(pts
			(xy 239.774222 -67.36588) (xy 239.75187 -67.327526) (xy 239.589818 -67.224656) (xy 239.398556 -67.335146)
			(xy 239.406684 -67.526916) (xy 239.428782 -67.565524)
		)
		(stroke
			(width 0)
			(type solid)
		)
		(fill yes)
		(layer "In11.Cu")
		(net "M_C_DQ<1>")
	)
	(gr_poly
		(pts
			(xy 239.774222 -64.39408) (xy 239.75187 -64.355726) (xy 239.589818 -64.252856) (xy 239.398556 -64.363346)
			(xy 239.406684 -64.555116) (xy 239.428782 -64.593724)
		)
		(stroke
			(width 0)
			(type solid)
		)
		(fill yes)
		(layer "In11.Cu")
		(net "M_C_DQ<7>")
	)
	(gr_poly
		(pts
			(xy 239.775746 -103.962708) (xy 239.744504 -103.931212) (xy 239.545114 -103.857552) (xy 239.383316 -104.019096)
			(xy 239.456976 -104.218486) (xy 239.488472 -104.249982)
		)
		(stroke
			(width 0)
			(type solid)
		)
		(fill yes)
		(layer "In11.Cu")
		(net "M_F_DQ<18>")
	)
	(gr_poly
		(pts
			(xy 239.776 -65.383664) (xy 239.753648 -65.34531) (xy 239.591596 -65.24244) (xy 239.400334 -65.35293)
			(xy 239.408462 -65.5447) (xy 239.43056 -65.583308)
		)
		(stroke
			(width 0)
			(type solid)
		)
		(fill yes)
		(layer "In11.Cu")
		(net "M_C_DQS_DN<0>")
	)
	(gr_poly
		(pts
			(xy 239.776508 -93.12021) (xy 239.754156 -93.081856) (xy 239.592104 -92.978986) (xy 239.400842 -93.089476)
			(xy 239.40897 -93.281246) (xy 239.431068 -93.319854)
		)
		(stroke
			(width 0)
			(type solid)
		)
		(fill yes)
		(layer "In11.Cu")
		(net "M_F_DQ<10>")
	)
	(gr_poly
		(pts
			(xy 239.781588 -90.145362) (xy 239.759236 -90.107008) (xy 239.597184 -90.004138) (xy 239.405922 -90.114628)
			(xy 239.41405 -90.306398) (xy 239.436148 -90.345006)
		)
		(stroke
			(width 0)
			(type solid)
		)
		(fill yes)
		(layer "In11.Cu")
		(net "M_F_DQS_DP<10>")
	)
	(gr_poly
		(pts
			(xy 240.17224 -100.9523) (xy 240.12779 -100.9523) (xy 239.95761 -101.0412) (xy 239.95761 -101.26218)
			(xy 240.12779 -101.35108) (xy 240.17224 -101.35108)
		)
		(stroke
			(width 0)
			(type solid)
		)
		(fill yes)
		(layer "In11.Cu")
		(net "M_F_DQ<18>")
	)
	(gr_poly
		(pts
			(xy 240.17224 -99.974146) (xy 240.12779 -99.974146) (xy 239.95761 -100.063046) (xy 239.95761 -100.284026)
			(xy 240.12779 -100.372926) (xy 240.17224 -100.372926)
		)
		(stroke
			(width 0)
			(type solid)
		)
		(fill yes)
		(layer "In11.Cu")
		(net "M_F_DQ<18>")
	)
	(gr_poly
		(pts
			(xy 240.172494 -98.988118) (xy 240.128044 -98.988372) (xy 239.957864 -99.077272) (xy 239.957864 -99.298252)
			(xy 240.128044 -99.387152) (xy 240.17224 -99.387152)
		)
		(stroke
			(width 0)
			(type solid)
		)
		(fill yes)
		(layer "In11.Cu")
		(net "M_F_DQ<18>")
	)
	(gr_poly
		(pts
			(xy 240.31448 -64.483742) (xy 240.306352 -64.291972) (xy 240.284254 -64.253364) (xy 239.938814 -64.453008)
			(xy 239.961166 -64.491362) (xy 240.123218 -64.594232)
		)
		(stroke
			(width 0)
			(type solid)
		)
		(fill yes)
		(layer "In11.Cu")
		(net "M_C_DQ<7>")
	)
	(gr_poly
		(pts
			(xy 240.350294 -102.869238) (xy 240.305844 -102.869238) (xy 240.112804 -102.958138) (xy 240.112804 -103.186738)
			(xy 240.305844 -103.275638) (xy 240.350294 -103.275638)
		)
		(stroke
			(width 0)
			(type solid)
		)
		(fill yes)
		(layer "In11.Cu")
		(net "M_F_DQ<18>")
	)
	(gr_poly
		(pts
			(xy 240.350294 -101.878638) (xy 240.305844 -101.878638) (xy 240.112804 -101.967538) (xy 240.112804 -102.196138)
			(xy 240.305844 -102.285038) (xy 240.350294 -102.285038)
		)
		(stroke
			(width 0)
			(type solid)
		)
		(fill yes)
		(layer "In11.Cu")
		(net "M_F_DQ<18>")
	)
	(gr_poly
		(pts
			(xy 240.380774 -103.961184) (xy 240.307114 -103.761794) (xy 240.275872 -103.730298) (xy 239.988344 -104.017572)
			(xy 240.01984 -104.049068) (xy 240.21923 -104.122728)
		)
		(stroke
			(width 0)
			(type solid)
		)
		(fill yes)
		(layer "In11.Cu")
		(net "M_F_DQ<19>")
	)
	(gr_poly
		(pts
			(xy 240.395506 -90.306398) (xy 240.403634 -90.114628) (xy 240.212372 -90.004138) (xy 240.05032 -90.107008)
			(xy 240.027968 -90.145362) (xy 240.373408 -90.345006)
		)
		(stroke
			(width 0)
			(type solid)
		)
		(fill yes)
		(layer "In11.Cu")
		(net "M_F_DQS_DP<10>")
	)
	(gr_poly
		(pts
			(xy 240.400586 -57.619646) (xy 240.408714 -57.427876) (xy 240.217452 -57.317386) (xy 240.0554 -57.420256)
			(xy 240.033048 -57.45861) (xy 240.378488 -57.658)
		)
		(stroke
			(width 0)
			(type solid)
		)
		(fill yes)
		(layer "In11.Cu")
		(net "M_C_DQ<21>")
	)
	(gr_poly
		(pts
			(xy 240.402872 -89.320116) (xy 240.411 -89.128346) (xy 240.219738 -89.017856) (xy 240.057686 -89.120726)
			(xy 240.035334 -89.15908) (xy 240.380774 -89.35847)
		)
		(stroke
			(width 0)
			(type solid)
		)
		(fill yes)
		(layer "In11.Cu")
		(net "M_F_DQ<8>")
	)
	(gr_poly
		(pts
			(xy 240.402872 -88.329516) (xy 240.411 -88.137746) (xy 240.219738 -88.027256) (xy 240.057686 -88.130126)
			(xy 240.035334 -88.16848) (xy 240.380774 -88.36787)
		)
		(stroke
			(width 0)
			(type solid)
		)
		(fill yes)
		(layer "In11.Cu")
		(net "M_F_DQ<12>")
	)
	(gr_poly
		(pts
			(xy 240.402872 -85.357716) (xy 240.411 -85.165946) (xy 240.219738 -85.055456) (xy 240.057686 -85.158326)
			(xy 240.035334 -85.19668) (xy 240.380774 -85.39607)
		)
		(stroke
			(width 0)
			(type solid)
		)
		(fill yes)
		(layer "In11.Cu")
		(net "M_F_DQS_DP<9>")
	)
	(gr_poly
		(pts
			(xy 240.402872 -84.367116) (xy 240.411 -84.175346) (xy 240.219738 -84.064856) (xy 240.057686 -84.167726)
			(xy 240.035334 -84.20608) (xy 240.380774 -84.40547)
		)
		(stroke
			(width 0)
			(type solid)
		)
		(fill yes)
		(layer "In11.Cu")
		(net "M_F_DQ<0>")
	)
	(gr_poly
		(pts
			(xy 240.402872 -83.376516) (xy 240.411 -83.184746) (xy 240.219738 -83.074256) (xy 240.057686 -83.177126)
			(xy 240.035334 -83.21548) (xy 240.380774 -83.41487)
		)
		(stroke
			(width 0)
			(type solid)
		)
		(fill yes)
		(layer "In11.Cu")
		(net "M_F_DQ<4>")
	)
	(gr_poly
		(pts
			(xy 240.402872 -55.639716) (xy 240.411 -55.447946) (xy 240.219738 -55.337456) (xy 240.057686 -55.440326)
			(xy 240.035334 -55.47868) (xy 240.380774 -55.678324)
		)
		(stroke
			(width 0)
			(type solid)
		)
		(fill yes)
		(layer "In11.Cu")
		(net "M_C_DQS_DN<11>")
	)
	(gr_poly
		(pts
			(xy 240.402872 -54.649116) (xy 240.411 -54.457346) (xy 240.219738 -54.346856) (xy 240.057686 -54.449726)
			(xy 240.035334 -54.48808) (xy 240.380774 -54.687724)
		)
		(stroke
			(width 0)
			(type solid)
		)
		(fill yes)
		(layer "In11.Cu")
		(net "M_C_DQS_DN<2>")
	)
	(gr_poly
		(pts
			(xy 240.402872 -53.658516) (xy 240.411 -53.466746) (xy 240.219738 -53.356256) (xy 240.057686 -53.459126)
			(xy 240.035334 -53.49748) (xy 240.380774 -53.697124)
		)
		(stroke
			(width 0)
			(type solid)
		)
		(fill yes)
		(layer "In11.Cu")
		(net "M_C_DQ<23>")
	)
	(gr_poly
		(pts
			(xy 240.404396 -56.631078) (xy 240.412524 -56.439308) (xy 240.221262 -56.328818) (xy 240.05921 -56.431688)
			(xy 240.036858 -56.470042) (xy 240.382298 -56.669686)
		)
		(stroke
			(width 0)
			(type solid)
		)
		(fill yes)
		(layer "In11.Cu")
		(net "M_C_DQ<17>")
	)
	(gr_poly
		(pts
			(xy 240.404396 -52.668678) (xy 240.412524 -52.476908) (xy 240.221262 -52.366418) (xy 240.05921 -52.469288)
			(xy 240.036858 -52.507642) (xy 240.382298 -52.707032)
		)
		(stroke
			(width 0)
			(type solid)
		)
		(fill yes)
		(layer "In11.Cu")
		(net "M_C_DQ<19>")
	)
	(gr_poly
		(pts
			(xy 240.411 -94.36608) (xy 240.402872 -94.17431) (xy 240.380774 -94.135702) (xy 240.035334 -94.335346)
			(xy 240.057686 -94.3737) (xy 240.219738 -94.47657)
		)
		(stroke
			(width 0)
			(type solid)
		)
		(fill yes)
		(layer "In11.Cu")
		(net "M_F_DQ<21>")
	)
	(gr_poly
		(pts
			(xy 240.412524 -98.327464) (xy 240.404396 -98.135694) (xy 240.382298 -98.097086) (xy 240.036858 -98.29673)
			(xy 240.05921 -98.335084) (xy 240.221262 -98.437954)
		)
		(stroke
			(width 0)
			(type solid)
		)
		(fill yes)
		(layer "In11.Cu")
		(net "M_F_DQ<23>")
	)
	(gr_poly
		(pts
			(xy 240.412524 -97.336864) (xy 240.404396 -97.145094) (xy 240.382298 -97.106486) (xy 240.036858 -97.30613)
			(xy 240.05921 -97.344484) (xy 240.221262 -97.447354)
		)
		(stroke
			(width 0)
			(type solid)
		)
		(fill yes)
		(layer "In11.Cu")
		(net "M_F_DQS_DP<2>")
	)
	(gr_poly
		(pts
			(xy 240.412524 -96.346264) (xy 240.404396 -96.154494) (xy 240.382298 -96.115886) (xy 240.036858 -96.31553)
			(xy 240.05921 -96.353884) (xy 240.221262 -96.456754)
		)
		(stroke
			(width 0)
			(type solid)
		)
		(fill yes)
		(layer "In11.Cu")
		(net "M_F_DQS_DN<11>")
	)
	(gr_poly
		(pts
			(xy 240.412524 -95.355664) (xy 240.404396 -95.163894) (xy 240.382298 -95.125286) (xy 240.036858 -95.32493)
			(xy 240.05921 -95.363284) (xy 240.221262 -95.466154)
		)
		(stroke
			(width 0)
			(type solid)
		)
		(fill yes)
		(layer "In11.Cu")
		(net "M_F_DQ<17>")
	)
	(gr_poly
		(pts
			(xy 240.412524 -68.609464) (xy 240.404396 -68.417694) (xy 240.382298 -68.37934) (xy 240.036858 -68.578476)
			(xy 240.05921 -68.617084) (xy 240.221262 -68.719954)
		)
		(stroke
			(width 0)
			(type solid)
		)
		(fill yes)
		(layer "In11.Cu")
		(net "M_C_DQ<4>")
	)
	(gr_poly
		(pts
			(xy 240.412524 -67.618864) (xy 240.404396 -67.427094) (xy 240.382298 -67.38874) (xy 240.036858 -67.587876)
			(xy 240.05921 -67.626484) (xy 240.221262 -67.729354)
		)
		(stroke
			(width 0)
			(type solid)
		)
		(fill yes)
		(layer "In11.Cu")
		(net "M_C_DQ<0>")
	)
	(gr_poly
		(pts
			(xy 240.412524 -65.637664) (xy 240.404396 -65.445894) (xy 240.382298 -65.407286) (xy 240.036858 -65.60693)
			(xy 240.05921 -65.645284) (xy 240.221262 -65.748154)
		)
		(stroke
			(width 0)
			(type solid)
		)
		(fill yes)
		(layer "In11.Cu")
		(net "M_C_DQS_DP<0>")
	)
	(gr_poly
		(pts
			(xy 240.412524 -62.665864) (xy 240.404396 -62.474094) (xy 240.382298 -62.435486) (xy 240.036858 -62.63513)
			(xy 240.05921 -62.673484) (xy 240.221262 -62.776354)
		)
		(stroke
			(width 0)
			(type solid)
		)
		(fill yes)
		(layer "In11.Cu")
		(net "M_C_DQ<13>")
	)
	(gr_poly
		(pts
			(xy 240.412524 -61.675264) (xy 240.404396 -61.483494) (xy 240.382298 -61.444886) (xy 240.036858 -61.64453)
			(xy 240.05921 -61.682884) (xy 240.221262 -61.785754)
		)
		(stroke
			(width 0)
			(type solid)
		)
		(fill yes)
		(layer "In11.Cu")
		(net "M_C_DQ<9>")
	)
	(gr_poly
		(pts
			(xy 240.412524 -60.684664) (xy 240.404396 -60.492894) (xy 240.382298 -60.454286) (xy 240.036858 -60.65393)
			(xy 240.05921 -60.692284) (xy 240.221262 -60.795154)
		)
		(stroke
			(width 0)
			(type solid)
		)
		(fill yes)
		(layer "In11.Cu")
		(net "M_C_DQS_DP<1>")
	)
	(gr_poly
		(pts
			(xy 240.608866 -58.216038) (xy 240.631218 -58.177684) (xy 240.285778 -57.97804) (xy 240.26368 -58.016648)
			(xy 240.255552 -58.208418) (xy 240.446814 -58.318908)
		)
		(stroke
			(width 0)
			(type solid)
		)
		(fill yes)
		(layer "In11.Cu")
		(net "M_C_DQ<20>")
	)
	(gr_poly
		(pts
			(xy 240.61039 -88.9254) (xy 240.632742 -88.887046) (xy 240.287302 -88.687402) (xy 240.265204 -88.72601)
			(xy 240.257076 -88.91778) (xy 240.448338 -89.02827)
		)
		(stroke
			(width 0)
			(type solid)
		)
		(fill yes)
		(layer "In11.Cu")
		(net "M_F_DQ<13>")
	)
	(gr_poly
		(pts
			(xy 240.61039 -85.9536) (xy 240.632742 -85.915246) (xy 240.287302 -85.715602) (xy 240.265204 -85.75421)
			(xy 240.257076 -85.94598) (xy 240.448338 -86.05647)
		)
		(stroke
			(width 0)
			(type solid)
		)
		(fill yes)
		(layer "In11.Cu")
		(net "M_F_DQS_DN<9>")
	)
	(gr_poly
		(pts
			(xy 240.61039 -83.9724) (xy 240.632742 -83.934046) (xy 240.287302 -83.734402) (xy 240.265204 -83.77301)
			(xy 240.257076 -83.96478) (xy 240.448338 -84.07527)
		)
		(stroke
			(width 0)
			(type solid)
		)
		(fill yes)
		(layer "In11.Cu")
		(net "M_F_DQ<5>")
	)
	(gr_poly
		(pts
			(xy 240.61039 -57.2262) (xy 240.632742 -57.187592) (xy 240.287302 -56.988202) (xy 240.265204 -57.02681)
			(xy 240.257076 -57.21858) (xy 240.448338 -57.32907)
		)
		(stroke
			(width 0)
			(type solid)
		)
		(fill yes)
		(layer "In11.Cu")
		(net "M_C_DQ<16>")
	)
	(gr_poly
		(pts
			(xy 240.61039 -56.2356) (xy 240.632742 -56.197246) (xy 240.287302 -55.997602) (xy 240.265204 -56.03621)
			(xy 240.257076 -56.22798) (xy 240.448338 -56.33847)
		)
		(stroke
			(width 0)
			(type solid)
		)
		(fill yes)
		(layer "In11.Cu")
		(net "M_C_DQS_DP<11>")
	)
	(gr_poly
		(pts
			(xy 240.61039 -55.245) (xy 240.632742 -55.206392) (xy 240.287302 -55.007002) (xy 240.265204 -55.04561)
			(xy 240.257076 -55.23738) (xy 240.448338 -55.34787)
		)
		(stroke
			(width 0)
			(type solid)
		)
		(fill yes)
		(layer "In11.Cu")
		(net "M_C_DQS_DP<2>")
	)
	(gr_poly
		(pts
			(xy 240.61039 -54.2544) (xy 240.632742 -54.215792) (xy 240.287302 -54.016402) (xy 240.265204 -54.05501)
			(xy 240.257076 -54.24678) (xy 240.448338 -54.35727)
		)
		(stroke
			(width 0)
			(type solid)
		)
		(fill yes)
		(layer "In11.Cu")
		(net "M_C_DQ<22>")
	)
	(gr_poly
		(pts
			(xy 240.612676 -53.26507) (xy 240.635028 -53.226716) (xy 240.289588 -53.027072) (xy 240.26749 -53.06568)
			(xy 240.259362 -53.25745) (xy 240.450624 -53.36794)
		)
		(stroke
			(width 0)
			(type solid)
		)
		(fill yes)
		(layer "In11.Cu")
		(net "M_C_DQ<18>")
	)
	(gr_poly
		(pts
			(xy 240.631218 -98.570796) (xy 240.608866 -98.532442) (xy 240.446814 -98.429572) (xy 240.255552 -98.540062)
			(xy 240.263426 -98.731832) (xy 240.285524 -98.770186)
		)
		(stroke
			(width 0)
			(type solid)
		)
		(fill yes)
		(layer "In11.Cu")
		(net "M_F_DQ<18>")
	)
	(gr_poly
		(pts
			(xy 240.631218 -97.58045) (xy 240.608866 -97.541842) (xy 240.446814 -97.438972) (xy 240.255552 -97.549462)
			(xy 240.26368 -97.741232) (xy 240.285778 -97.77984)
		)
		(stroke
			(width 0)
			(type solid)
		)
		(fill yes)
		(layer "In11.Cu")
		(net "M_F_DQ<22>")
	)
	(gr_poly
		(pts
			(xy 240.631218 -96.58985) (xy 240.608866 -96.551242) (xy 240.446814 -96.448372) (xy 240.255552 -96.558862)
			(xy 240.26368 -96.750632) (xy 240.285778 -96.78924)
		)
		(stroke
			(width 0)
			(type solid)
		)
		(fill yes)
		(layer "In11.Cu")
		(net "M_F_DQS_DN<2>")
	)
	(gr_poly
		(pts
			(xy 240.631218 -95.59925) (xy 240.608866 -95.560642) (xy 240.446814 -95.457772) (xy 240.255552 -95.568262)
			(xy 240.26368 -95.760032) (xy 240.285778 -95.79864)
		)
		(stroke
			(width 0)
			(type solid)
		)
		(fill yes)
		(layer "In11.Cu")
		(net "M_F_DQS_DP<11>")
	)
	(gr_poly
		(pts
			(xy 240.631218 -92.62745) (xy 240.608866 -92.588842) (xy 240.446814 -92.485972) (xy 240.255552 -92.596462)
			(xy 240.26368 -92.788232) (xy 240.285778 -92.82684)
		)
		(stroke
			(width 0)
			(type solid)
		)
		(fill yes)
		(layer "In11.Cu")
		(net "M_F_DQ<10>")
	)
	(gr_poly
		(pts
			(xy 240.631218 -67.862196) (xy 240.608866 -67.823842) (xy 240.446814 -67.720972) (xy 240.255552 -67.831462)
			(xy 240.26368 -68.023232) (xy 240.285778 -68.06184)
		)
		(stroke
			(width 0)
			(type solid)
		)
		(fill yes)
		(layer "In11.Cu")
		(net "M_C_DQ<5>")
	)
	(gr_poly
		(pts
			(xy 240.631218 -64.890396) (xy 240.608866 -64.852042) (xy 240.446814 -64.749172) (xy 240.255552 -64.859662)
			(xy 240.26368 -65.051432) (xy 240.285778 -65.09004)
		)
		(stroke
			(width 0)
			(type solid)
		)
		(fill yes)
		(layer "In11.Cu")
		(net "M_C_DQS_DN<0>")
	)
	(gr_poly
		(pts
			(xy 240.631218 -62.909196) (xy 240.608866 -62.870842) (xy 240.446814 -62.767972) (xy 240.255552 -62.878462)
			(xy 240.26368 -63.070232) (xy 240.285778 -63.10884)
		)
		(stroke
			(width 0)
			(type solid)
		)
		(fill yes)
		(layer "In11.Cu")
		(net "M_C_DQ<12>")
	)
	(gr_poly
		(pts
			(xy 240.631218 -59.937396) (xy 240.608866 -59.899042) (xy 240.446814 -59.796172) (xy 240.255552 -59.906662)
			(xy 240.26368 -60.098432) (xy 240.285778 -60.13704)
		)
		(stroke
			(width 0)
			(type solid)
		)
		(fill yes)
		(layer "In11.Cu")
		(net "M_C_DQS_DN<1>")
	)
	(gr_poly
		(pts
			(xy 240.632742 -93.61678) (xy 240.61039 -93.578426) (xy 240.448338 -93.475556) (xy 240.257076 -93.586046)
			(xy 240.265204 -93.777816) (xy 240.287302 -93.81617)
		)
		(stroke
			(width 0)
			(type solid)
		)
		(fill yes)
		(layer "In11.Cu")
		(net "M_F_DQ<20>")
	)
	(gr_poly
		(pts
			(xy 240.635028 -94.60611) (xy 240.612676 -94.567756) (xy 240.450624 -94.464886) (xy 240.259362 -94.575376)
			(xy 240.26749 -94.767146) (xy 240.289588 -94.805754)
		)
		(stroke
			(width 0)
			(type solid)
		)
		(fill yes)
		(layer "In11.Cu")
		(net "M_F_DQ<16>")
	)
	(gr_poly
		(pts
			(xy 240.710466 -100.772976) (xy 240.710466 -100.551996) (xy 240.540286 -100.463096) (xy 240.495836 -100.463096)
			(xy 240.495836 -100.861876) (xy 240.540286 -100.861876)
		)
		(stroke
			(width 0)
			(type solid)
		)
		(fill yes)
		(layer "In11.Cu")
		(net "M_F_DQ<19>")
	)
	(gr_poly
		(pts
			(xy 240.710466 -99.77628) (xy 240.710466 -99.5553) (xy 240.540286 -99.4664) (xy 240.495836 -99.4664)
			(xy 240.495836 -99.86518) (xy 240.540286 -99.86518)
		)
		(stroke
			(width 0)
			(type solid)
		)
		(fill yes)
		(layer "In11.Cu")
		(net "M_F_DQ<19>")
	)
	(gr_poly
		(pts
			(xy 240.751106 -86.738714) (xy 240.75136 -86.694518) (xy 240.352326 -86.694264) (xy 240.35258 -86.738714)
			(xy 240.441226 -86.908894) (xy 240.662206 -86.908894)
		)
		(stroke
			(width 0)
			(type solid)
		)
		(fill yes)
		(layer "In11.Cu")
		(net "M_F_DQ<6>")
	)
	(gr_poly
		(pts
			(xy 240.777776 -103.059738) (xy 240.777776 -102.831138) (xy 240.584736 -102.742238) (xy 240.540286 -102.742238)
			(xy 240.540286 -103.148638) (xy 240.584736 -103.148638)
		)
		(stroke
			(width 0)
			(type solid)
		)
		(fill yes)
		(layer "In11.Cu")
		(net "M_F_DQ<19>")
	)
	(gr_poly
		(pts
			(xy 240.777776 -102.069138) (xy 240.777776 -101.840538) (xy 240.584736 -101.751638) (xy 240.540286 -101.751638)
			(xy 240.540286 -102.158038) (xy 240.584736 -102.158038)
		)
		(stroke
			(width 0)
			(type solid)
		)
		(fill yes)
		(layer "In11.Cu")
		(net "M_F_DQ<19>")
	)
	(gr_poly
		(pts
			(xy 241.171222 -62.998858) (xy 241.163094 -62.807088) (xy 241.140996 -62.76848) (xy 240.795556 -62.968124)
			(xy 240.817908 -63.006478) (xy 240.97996 -63.109348)
		)
		(stroke
			(width 0)
			(type solid)
		)
		(fill yes)
		(layer "In11.Cu")
		(net "M_C_DQ<12>")
	)
	(gr_poly
		(pts
			(xy 241.261392 -58.116216) (xy 241.26952 -57.924446) (xy 241.078258 -57.813956) (xy 240.916206 -57.916826)
			(xy 240.893854 -57.95518) (xy 241.239294 -58.154824)
		)
		(stroke
			(width 0)
			(type solid)
		)
		(fill yes)
		(layer "In11.Cu")
		(net "M_C_DQ<21>")
	)
	(gr_poly
		(pts
			(xy 241.262916 -90.807032) (xy 241.271044 -90.615262) (xy 241.079782 -90.504772) (xy 240.91773 -90.607642)
			(xy 240.895378 -90.64625) (xy 241.240818 -90.84564)
		)
		(stroke
			(width 0)
			(type solid)
		)
		(fill yes)
		(layer "In11.Cu")
		(net "M_F_DQS_DP<10>")
	)
	(gr_poly
		(pts
			(xy 241.262916 -89.816432) (xy 241.271044 -89.624662) (xy 241.079782 -89.514172) (xy 240.91773 -89.617042)
			(xy 240.895378 -89.65565) (xy 241.240818 -89.85504)
		)
		(stroke
			(width 0)
			(type solid)
		)
		(fill yes)
		(layer "In11.Cu")
		(net "M_F_DQ<8>")
	)
	(gr_poly
		(pts
			(xy 241.262916 -88.825832) (xy 241.271044 -88.634062) (xy 241.079782 -88.523572) (xy 240.91773 -88.626442)
			(xy 240.895378 -88.66505) (xy 241.240818 -88.86444)
		)
		(stroke
			(width 0)
			(type solid)
		)
		(fill yes)
		(layer "In11.Cu")
		(net "M_F_DQ<12>")
	)
	(gr_poly
		(pts
			(xy 241.262916 -86.844632) (xy 241.271044 -86.652862) (xy 241.079782 -86.542372) (xy 240.91773 -86.645242)
			(xy 240.895378 -86.68385) (xy 241.240818 -86.88324)
		)
		(stroke
			(width 0)
			(type solid)
		)
		(fill yes)
		(layer "In11.Cu")
		(net "M_F_DQ<6>")
	)
	(gr_poly
		(pts
			(xy 241.262916 -85.854032) (xy 241.271044 -85.662262) (xy 241.079782 -85.551772) (xy 240.91773 -85.654642)
			(xy 240.895378 -85.69325) (xy 241.240818 -85.89264)
		)
		(stroke
			(width 0)
			(type solid)
		)
		(fill yes)
		(layer "In11.Cu")
		(net "M_F_DQS_DP<9>")
	)
	(gr_poly
		(pts
			(xy 241.262916 -84.863432) (xy 241.271044 -84.671662) (xy 241.079782 -84.561172) (xy 240.91773 -84.664042)
			(xy 240.895378 -84.70265) (xy 241.240818 -84.90204)
		)
		(stroke
			(width 0)
			(type solid)
		)
		(fill yes)
		(layer "In11.Cu")
		(net "M_F_DQ<0>")
	)
	(gr_poly
		(pts
			(xy 241.262916 -83.872832) (xy 241.271044 -83.681062) (xy 241.079782 -83.570572) (xy 240.91773 -83.673442)
			(xy 240.895378 -83.71205) (xy 241.240818 -83.91144)
		)
		(stroke
			(width 0)
			(type solid)
		)
		(fill yes)
		(layer "In11.Cu")
		(net "M_F_DQ<4>")
	)
	(gr_poly
		(pts
			(xy 241.262916 -57.126632) (xy 241.271044 -56.934862) (xy 241.079782 -56.824372) (xy 240.91773 -56.927242)
			(xy 240.895378 -56.965596) (xy 241.240818 -57.16524)
		)
		(stroke
			(width 0)
			(type solid)
		)
		(fill yes)
		(layer "In11.Cu")
		(net "M_C_DQ<17>")
	)
	(gr_poly
		(pts
			(xy 241.262916 -56.136032) (xy 241.271044 -55.944262) (xy 241.079782 -55.833772) (xy 240.91773 -55.936642)
			(xy 240.895378 -55.974996) (xy 241.240818 -56.17464)
		)
		(stroke
			(width 0)
			(type solid)
		)
		(fill yes)
		(layer "In11.Cu")
		(net "M_C_DQS_DN<11>")
	)
	(gr_poly
		(pts
			(xy 241.262916 -55.145432) (xy 241.271044 -54.953662) (xy 241.079782 -54.843172) (xy 240.91773 -54.946042)
			(xy 240.895378 -54.984396) (xy 241.240818 -55.18404)
		)
		(stroke
			(width 0)
			(type solid)
		)
		(fill yes)
		(layer "In11.Cu")
		(net "M_C_DQS_DN<2>")
	)
	(gr_poly
		(pts
			(xy 241.262916 -54.154832) (xy 241.271044 -53.963062) (xy 241.079782 -53.852572) (xy 240.91773 -53.955442)
			(xy 240.895378 -53.993796) (xy 241.240818 -54.19344)
		)
		(stroke
			(width 0)
			(type solid)
		)
		(fill yes)
		(layer "In11.Cu")
		(net "M_C_DQ<23>")
	)
	(gr_poly
		(pts
			(xy 241.262916 -53.164232) (xy 241.271044 -52.972462) (xy 241.079782 -52.861972) (xy 240.91773 -52.964842)
			(xy 240.895378 -53.003196) (xy 241.240818 -53.202586)
		)
		(stroke
			(width 0)
			(type solid)
		)
		(fill yes)
		(layer "In11.Cu")
		(net "M_C_DQ<19>")
	)
	(gr_poly
		(pts
			(xy 241.267234 -94.86265) (xy 241.259106 -94.67088) (xy 241.237008 -94.632272) (xy 240.891568 -94.831662)
			(xy 240.91392 -94.87027) (xy 241.075972 -94.97314)
		)
		(stroke
			(width 0)
			(type solid)
		)
		(fill yes)
		(layer "In11.Cu")
		(net "M_F_DQ<17>")
	)
	(gr_poly
		(pts
			(xy 241.26952 -98.82378) (xy 241.261392 -98.63201) (xy 241.239294 -98.593402) (xy 240.893854 -98.793046)
			(xy 240.916206 -98.8314) (xy 241.078258 -98.93427)
		)
		(stroke
			(width 0)
			(type solid)
		)
		(fill yes)
		(layer "In11.Cu")
		(net "M_F_DQ<19>")
	)
	(gr_poly
		(pts
			(xy 241.26952 -97.83318) (xy 241.261392 -97.64141) (xy 241.239294 -97.602802) (xy 240.893854 -97.802446)
			(xy 240.916206 -97.8408) (xy 241.078258 -97.94367)
		)
		(stroke
			(width 0)
			(type solid)
		)
		(fill yes)
		(layer "In11.Cu")
		(net "M_F_DQ<23>")
	)
	(gr_poly
		(pts
			(xy 241.26952 -96.84258) (xy 241.261392 -96.65081) (xy 241.239294 -96.612202) (xy 240.893854 -96.811846)
			(xy 240.916206 -96.8502) (xy 241.078258 -96.95307)
		)
		(stroke
			(width 0)
			(type solid)
		)
		(fill yes)
		(layer "In11.Cu")
		(net "M_F_DQS_DP<2>")
	)
	(gr_poly
		(pts
			(xy 241.26952 -95.85198) (xy 241.261392 -95.66021) (xy 241.239294 -95.621602) (xy 240.893854 -95.821246)
			(xy 240.916206 -95.8596) (xy 241.078258 -95.96247)
		)
		(stroke
			(width 0)
			(type solid)
		)
		(fill yes)
		(layer "In11.Cu")
		(net "M_F_DQS_DN<11>")
	)
	(gr_poly
		(pts
			(xy 241.26952 -65.14338) (xy 241.261392 -64.95161) (xy 241.239294 -64.913002) (xy 240.893854 -65.112392)
			(xy 240.916206 -65.151) (xy 241.078258 -65.25387)
		)
		(stroke
			(width 0)
			(type solid)
		)
		(fill yes)
		(layer "In11.Cu")
		(net "M_C_DQS_DP<0>")
	)
	(gr_poly
		(pts
			(xy 241.26952 -62.17158) (xy 241.261392 -61.97981) (xy 241.239294 -61.941202) (xy 240.893854 -62.140592)
			(xy 240.916206 -62.1792) (xy 241.078258 -62.28207)
		)
		(stroke
			(width 0)
			(type solid)
		)
		(fill yes)
		(layer "In11.Cu")
		(net "M_C_DQ<13>")
	)
	(gr_poly
		(pts
			(xy 241.26952 -60.19038) (xy 241.261392 -59.99861) (xy 241.239294 -59.960002) (xy 240.893854 -60.159392)
			(xy 240.916206 -60.198) (xy 241.078258 -60.30087)
		)
		(stroke
			(width 0)
			(type solid)
		)
		(fill yes)
		(layer "In11.Cu")
		(net "M_C_DQS_DP<1>")
	)
	(gr_poly
		(pts
			(xy 241.271044 -93.870018) (xy 241.262916 -93.678248) (xy 241.240818 -93.639894) (xy 240.895378 -93.83903)
			(xy 240.91773 -93.877638) (xy 241.079782 -93.980508)
		)
		(stroke
			(width 0)
			(type solid)
		)
		(fill yes)
		(layer "In11.Cu")
		(net "M_F_DQ<21>")
	)
	(gr_poly
		(pts
			(xy 241.467386 -91.400884) (xy 241.489738 -91.36253) (xy 241.144298 -91.162886) (xy 241.1222 -91.201494)
			(xy 241.114072 -91.393264) (xy 241.305334 -91.503754)
		)
		(stroke
			(width 0)
			(type solid)
		)
		(fill yes)
		(layer "In11.Cu")
		(net "M_F_DQS_DN<10>")
	)
	(gr_poly
		(pts
			(xy 241.467386 -86.447884) (xy 241.489738 -86.40953) (xy 241.144298 -86.209886) (xy 241.1222 -86.248494)
			(xy 241.114072 -86.440264) (xy 241.305334 -86.550754)
		)
		(stroke
			(width 0)
			(type solid)
		)
		(fill yes)
		(layer "In11.Cu")
		(net "M_F_DQS_DN<9>")
	)
	(gr_poly
		(pts
			(xy 241.467386 -55.739284) (xy 241.489738 -55.70093) (xy 241.144298 -55.501286) (xy 241.1222 -55.539894)
			(xy 241.114072 -55.731664) (xy 241.305334 -55.842154)
		)
		(stroke
			(width 0)
			(type solid)
		)
		(fill yes)
		(layer "In11.Cu")
		(net "M_C_DQS_DP<2>")
	)
	(gr_poly
		(pts
			(xy 241.467386 -54.748684) (xy 241.489738 -54.71033) (xy 241.144298 -54.510686) (xy 241.1222 -54.549294)
			(xy 241.114072 -54.741064) (xy 241.305334 -54.851554)
		)
		(stroke
			(width 0)
			(type solid)
		)
		(fill yes)
		(layer "In11.Cu")
		(net "M_C_DQ<22>")
	)
	(gr_poly
		(pts
			(xy 241.46891 -58.7121) (xy 241.491262 -58.673492) (xy 241.145822 -58.474102) (xy 241.123724 -58.51271)
			(xy 241.115596 -58.70448) (xy 241.306858 -58.81497)
		)
		(stroke
			(width 0)
			(type solid)
		)
		(fill yes)
		(layer "In11.Cu")
		(net "M_C_DQ<20>")
	)
	(gr_poly
		(pts
			(xy 241.46891 -56.730646) (xy 241.491262 -56.692292) (xy 241.145822 -56.492648) (xy 241.123724 -56.531256)
			(xy 241.115596 -56.723026) (xy 241.306858 -56.833516)
		)
		(stroke
			(width 0)
			(type solid)
		)
		(fill yes)
		(layer "In11.Cu")
		(net "M_C_DQS_DP<11>")
	)
	(gr_poly
		(pts
			(xy 241.46891 -53.758846) (xy 241.491262 -53.720238) (xy 241.145822 -53.520848) (xy 241.123724 -53.559456)
			(xy 241.115596 -53.751226) (xy 241.306858 -53.861716)
		)
		(stroke
			(width 0)
			(type solid)
		)
		(fill yes)
		(layer "In11.Cu")
		(net "M_C_DQ<18>")
	)
	(gr_poly
		(pts
			(xy 241.471196 -57.72277) (xy 241.493548 -57.684416) (xy 241.148108 -57.484772) (xy 241.12601 -57.52338)
			(xy 241.117882 -57.71515) (xy 241.309144 -57.82564)
		)
		(stroke
			(width 0)
			(type solid)
		)
		(fill yes)
		(layer "In11.Cu")
		(net "M_C_DQ<16>")
	)
	(gr_poly
		(pts
			(xy 241.489738 -94.112842) (xy 241.467386 -94.074488) (xy 241.305334 -93.971618) (xy 241.114072 -94.082108)
			(xy 241.1222 -94.273878) (xy 241.144298 -94.312486)
		)
		(stroke
			(width 0)
			(type solid)
		)
		(fill yes)
		(layer "In11.Cu")
		(net "M_F_DQ<16>")
	)
	(gr_poly
		(pts
			(xy 241.491262 -98.07448) (xy 241.46891 -98.036126) (xy 241.306858 -97.933256) (xy 241.115596 -98.043746)
			(xy 241.123724 -98.235516) (xy 241.145822 -98.27387)
		)
		(stroke
			(width 0)
			(type solid)
		)
		(fill yes)
		(layer "In11.Cu")
		(net "M_F_DQ<18>")
	)
	(gr_poly
		(pts
			(xy 241.491262 -97.08388) (xy 241.46891 -97.045526) (xy 241.306858 -96.942656) (xy 241.115596 -97.053146)
			(xy 241.123724 -97.244916) (xy 241.145822 -97.28327)
		)
		(stroke
			(width 0)
			(type solid)
		)
		(fill yes)
		(layer "In11.Cu")
		(net "M_F_DQ<22>")
	)
	(gr_poly
		(pts
			(xy 241.491262 -96.09328) (xy 241.46891 -96.054926) (xy 241.306858 -95.952056) (xy 241.115596 -96.062546)
			(xy 241.123724 -96.254316) (xy 241.145822 -96.29267)
		)
		(stroke
			(width 0)
			(type solid)
		)
		(fill yes)
		(layer "In11.Cu")
		(net "M_F_DQS_DN<2>")
	)
	(gr_poly
		(pts
			(xy 241.491262 -95.10268) (xy 241.46891 -95.064326) (xy 241.306858 -94.961456) (xy 241.115596 -95.071946)
			(xy 241.123724 -95.263716) (xy 241.145822 -95.30207)
		)
		(stroke
			(width 0)
			(type solid)
		)
		(fill yes)
		(layer "In11.Cu")
		(net "M_F_DQS_DP<11>")
	)
	(gr_poly
		(pts
			(xy 241.491262 -59.44108) (xy 241.46891 -59.402726) (xy 241.306858 -59.299856) (xy 241.115596 -59.410346)
			(xy 241.123724 -59.602116) (xy 241.145822 -59.640724)
		)
		(stroke
			(width 0)
			(type solid)
		)
		(fill yes)
		(layer "In11.Cu")
		(net "M_C_DQS_DN<1>")
	)
	(gr_poly
		(pts
			(xy 241.493548 -93.12021) (xy 241.471196 -93.081856) (xy 241.309144 -92.978986) (xy 241.117882 -93.089476)
			(xy 241.12601 -93.281246) (xy 241.148108 -93.319854)
		)
		(stroke
			(width 0)
			(type solid)
		)
		(fill yes)
		(layer "In11.Cu")
		(net "M_F_DQ<20>")
	)
	(gr_poly
		(pts
			(xy 242.10264 -86.342982) (xy 242.110514 -86.151212) (xy 241.919252 -86.040722) (xy 241.7572 -86.143592)
			(xy 241.735102 -86.181946) (xy 242.080542 -86.38159)
		)
		(stroke
			(width 0)
			(type solid)
		)
		(fill yes)
		(layer "In11.Cu")
		(net "M_F_DQS_DP<9>")
	)
	(gr_poly
		(pts
			(xy 242.110006 -91.304364) (xy 242.126008 -91.113102) (xy 241.939318 -90.994992) (xy 241.773202 -91.091258)
			(xy 241.749326 -91.128596) (xy 242.086384 -91.341956)
		)
		(stroke
			(width 0)
			(type solid)
		)
		(fill yes)
		(layer "In11.Cu")
		(net "M_F_DQS_DP<10>")
	)
	(gr_poly
		(pts
			(xy 242.117626 -57.619646) (xy 242.125754 -57.427876) (xy 241.934492 -57.317386) (xy 241.77244 -57.420256)
			(xy 241.750088 -57.45861) (xy 242.095528 -57.658)
		)
		(stroke
			(width 0)
			(type solid)
		)
		(fill yes)
		(layer "In11.Cu")
		(net "M_C_DQ<17>")
	)
	(gr_poly
		(pts
			(xy 242.119912 -89.320116) (xy 242.12804 -89.128346) (xy 241.936778 -89.017856) (xy 241.774726 -89.120726)
			(xy 241.752374 -89.15908) (xy 242.097814 -89.35847)
		)
		(stroke
			(width 0)
			(type solid)
		)
		(fill yes)
		(layer "In11.Cu")
		(net "M_F_DQ<12>")
	)
	(gr_poly
		(pts
			(xy 242.119912 -84.367116) (xy 242.12804 -84.175346) (xy 241.936778 -84.064856) (xy 241.774726 -84.167726)
			(xy 241.752374 -84.20608) (xy 242.097814 -84.40547)
		)
		(stroke
			(width 0)
			(type solid)
		)
		(fill yes)
		(layer "In11.Cu")
		(net "M_F_DQ<4>")
	)
	(gr_poly
		(pts
			(xy 242.119912 -55.639716) (xy 242.12804 -55.447946) (xy 241.936778 -55.337456) (xy 241.774726 -55.440326)
			(xy 241.752374 -55.47868) (xy 242.097814 -55.678324)
		)
		(stroke
			(width 0)
			(type solid)
		)
		(fill yes)
		(layer "In11.Cu")
		(net "M_C_DQS_DN<2>")
	)
	(gr_poly
		(pts
			(xy 242.119912 -54.649116) (xy 242.12804 -54.457346) (xy 241.936778 -54.346856) (xy 241.774726 -54.449726)
			(xy 241.752374 -54.48808) (xy 242.097814 -54.687724)
		)
		(stroke
			(width 0)
			(type solid)
		)
		(fill yes)
		(layer "In11.Cu")
		(net "M_C_DQ<23>")
	)
	(gr_poly
		(pts
			(xy 242.119912 -53.658516) (xy 242.12804 -53.466746) (xy 241.936778 -53.356256) (xy 241.774726 -53.459126)
			(xy 241.752374 -53.49748) (xy 242.097814 -53.697124)
		)
		(stroke
			(width 0)
			(type solid)
		)
		(fill yes)
		(layer "In11.Cu")
		(net "M_C_DQ<19>")
	)
	(gr_poly
		(pts
			(xy 242.121436 -58.612278) (xy 242.129564 -58.420508) (xy 241.938302 -58.310018) (xy 241.77625 -58.412888)
			(xy 241.753898 -58.451242) (xy 242.099338 -58.650632)
		)
		(stroke
			(width 0)
			(type solid)
		)
		(fill yes)
		(layer "In11.Cu")
		(net "M_C_DQ<21>")
	)
	(gr_poly
		(pts
			(xy 242.121436 -56.631078) (xy 242.129564 -56.439308) (xy 241.938302 -56.328818) (xy 241.77625 -56.431688)
			(xy 241.753898 -56.470042) (xy 242.099338 -56.669686)
		)
		(stroke
			(width 0)
			(type solid)
		)
		(fill yes)
		(layer "In11.Cu")
		(net "M_C_DQS_DN<11>")
	)
	(gr_poly
		(pts
			(xy 242.125754 -93.37675) (xy 242.117626 -93.18498) (xy 242.095528 -93.146372) (xy 241.750088 -93.345762)
			(xy 241.77244 -93.38437) (xy 241.934492 -93.48724)
		)
		(stroke
			(width 0)
			(type solid)
		)
		(fill yes)
		(layer "In11.Cu")
		(net "M_F_DQ<21>")
	)
	(gr_poly
		(pts
			(xy 242.12804 -94.36608) (xy 242.119912 -94.17431) (xy 242.097814 -94.135702) (xy 241.752374 -94.335346)
			(xy 241.774726 -94.3737) (xy 241.936778 -94.47657)
		)
		(stroke
			(width 0)
			(type solid)
		)
		(fill yes)
		(layer "In11.Cu")
		(net "M_F_DQ<17>")
	)
	(gr_poly
		(pts
			(xy 242.129564 -98.327464) (xy 242.121436 -98.135694) (xy 242.099338 -98.097086) (xy 241.753898 -98.29673)
			(xy 241.77625 -98.335084) (xy 241.938302 -98.437954)
		)
		(stroke
			(width 0)
			(type solid)
		)
		(fill yes)
		(layer "In11.Cu")
		(net "M_F_DQ<19>")
	)
	(gr_poly
		(pts
			(xy 242.129564 -97.336864) (xy 242.121436 -97.145094) (xy 242.099338 -97.106486) (xy 241.753898 -97.30613)
			(xy 241.77625 -97.344484) (xy 241.938302 -97.447354)
		)
		(stroke
			(width 0)
			(type solid)
		)
		(fill yes)
		(layer "In11.Cu")
		(net "M_F_DQ<23>")
	)
	(gr_poly
		(pts
			(xy 242.129564 -96.346264) (xy 242.121436 -96.154494) (xy 242.099338 -96.115886) (xy 241.753898 -96.31553)
			(xy 241.77625 -96.353884) (xy 241.938302 -96.456754)
		)
		(stroke
			(width 0)
			(type solid)
		)
		(fill yes)
		(layer "In11.Cu")
		(net "M_F_DQS_DP<2>")
	)
	(gr_poly
		(pts
			(xy 242.129564 -95.355664) (xy 242.121436 -95.163894) (xy 242.099338 -95.125286) (xy 241.753898 -95.32493)
			(xy 241.77625 -95.363284) (xy 241.938302 -95.466154)
		)
		(stroke
			(width 0)
			(type solid)
		)
		(fill yes)
		(layer "In11.Cu")
		(net "M_F_DQS_DN<11>")
	)
	(gr_poly
		(pts
			(xy 242.325906 -58.216038) (xy 242.348258 -58.177684) (xy 242.002818 -57.97804) (xy 241.98072 -58.016648)
			(xy 241.972592 -58.208418) (xy 242.163854 -58.318908)
		)
		(stroke
			(width 0)
			(type solid)
		)
		(fill yes)
		(layer "In11.Cu")
		(net "M_C_DQ<16>")
	)
	(gr_poly
		(pts
			(xy 242.325906 -56.234838) (xy 242.348258 -56.196484) (xy 242.002818 -55.99684) (xy 241.98072 -56.035448)
			(xy 241.972592 -56.227218) (xy 242.163854 -56.337708)
		)
		(stroke
			(width 0)
			(type solid)
		)
		(fill yes)
		(layer "In11.Cu")
		(net "M_C_DQS_DP<2>")
	)
	(gr_poly
		(pts
			(xy 242.32743 -57.2262) (xy 242.349782 -57.187846) (xy 242.004342 -56.988202) (xy 241.982244 -57.02681)
			(xy 241.974116 -57.21858) (xy 242.165378 -57.32907)
		)
		(stroke
			(width 0)
			(type solid)
		)
		(fill yes)
		(layer "In11.Cu")
		(net "M_C_DQS_DP<11>")
	)
	(gr_poly
		(pts
			(xy 242.32743 -55.245) (xy 242.349782 -55.206392) (xy 242.004342 -55.007002) (xy 241.982244 -55.04561)
			(xy 241.974116 -55.23738) (xy 242.165378 -55.34787)
		)
		(stroke
			(width 0)
			(type solid)
		)
		(fill yes)
		(layer "In11.Cu")
		(net "M_C_DQ<22>")
	)
	(gr_poly
		(pts
			(xy 242.32743 -54.254654) (xy 242.349782 -54.2163) (xy 242.004342 -54.016656) (xy 241.982244 -54.055264)
			(xy 241.974116 -54.247034) (xy 242.165378 -54.357524)
		)
		(stroke
			(width 0)
			(type solid)
		)
		(fill yes)
		(layer "In11.Cu")
		(net "M_C_DQ<18>")
	)
	(gr_poly
		(pts
			(xy 242.329716 -59.20867) (xy 242.352068 -59.170316) (xy 242.006628 -58.970672) (xy 241.98453 -59.00928)
			(xy 241.976402 -59.20105) (xy 242.167664 -59.31154)
		)
		(stroke
			(width 0)
			(type solid)
		)
		(fill yes)
		(layer "In11.Cu")
		(net "M_C_DQ<20>")
	)
	(gr_poly
		(pts
			(xy 242.348258 -97.58045) (xy 242.325906 -97.541842) (xy 242.163854 -97.438972) (xy 241.972592 -97.549462)
			(xy 241.98072 -97.741232) (xy 242.002818 -97.77984)
		)
		(stroke
			(width 0)
			(type solid)
		)
		(fill yes)
		(layer "In11.Cu")
		(net "M_F_DQ<18>")
	)
	(gr_poly
		(pts
			(xy 242.348258 -96.58985) (xy 242.325906 -96.551242) (xy 242.163854 -96.448372) (xy 241.972592 -96.558862)
			(xy 241.98072 -96.750632) (xy 242.002818 -96.78924)
		)
		(stroke
			(width 0)
			(type solid)
		)
		(fill yes)
		(layer "In11.Cu")
		(net "M_F_DQ<22>")
	)
	(gr_poly
		(pts
			(xy 242.348258 -95.59925) (xy 242.325906 -95.560642) (xy 242.163854 -95.457772) (xy 241.972592 -95.568262)
			(xy 241.98072 -95.760032) (xy 242.002818 -95.79864)
		)
		(stroke
			(width 0)
			(type solid)
		)
		(fill yes)
		(layer "In11.Cu")
		(net "M_F_DQS_DN<2>")
	)
	(gr_poly
		(pts
			(xy 242.348258 -92.62745) (xy 242.325906 -92.588842) (xy 242.163854 -92.485972) (xy 241.972592 -92.596462)
			(xy 241.98072 -92.788232) (xy 242.002818 -92.82684)
		)
		(stroke
			(width 0)
			(type solid)
		)
		(fill yes)
		(layer "In11.Cu")
		(net "M_F_DQ<20>")
	)
	(gr_poly
		(pts
			(xy 242.349782 -93.61678) (xy 242.32743 -93.578426) (xy 242.165378 -93.475556) (xy 241.974116 -93.586046)
			(xy 241.982244 -93.777816) (xy 242.004342 -93.81617)
		)
		(stroke
			(width 0)
			(type solid)
		)
		(fill yes)
		(layer "In11.Cu")
		(net "M_F_DQ<16>")
	)
	(gr_poly
		(pts
			(xy 242.352068 -94.60611) (xy 242.329716 -94.567756) (xy 242.167664 -94.464886) (xy 241.976402 -94.575376)
			(xy 241.98453 -94.767146) (xy 242.006628 -94.805754)
		)
		(stroke
			(width 0)
			(type solid)
		)
		(fill yes)
		(layer "In11.Cu")
		(net "M_F_DQS_DP<11>")
	)
	(gr_poly
		(pts
			(xy 242.533424 -101.759258) (xy 242.488974 -101.759258) (xy 242.295934 -101.848158) (xy 242.295934 -102.076758)
			(xy 242.488974 -102.165658) (xy 242.533424 -102.165658)
		)
		(stroke
			(width 0)
			(type solid)
		)
		(fill yes)
		(layer "In11.Cu")
		(net "M_F_DQ<28>")
	)
	(gr_poly
		(pts
			(xy 242.960906 -102.076758) (xy 242.960906 -101.848158) (xy 242.767866 -101.759258) (xy 242.723416 -101.759258)
			(xy 242.723416 -102.165658) (xy 242.767866 -102.165658)
		)
		(stroke
			(width 0)
			(type solid)
		)
		(fill yes)
		(layer "In11.Cu")
		(net "M_F_DQ<29>")
	)
	(gr_poly
		(pts
			(xy 242.970812 -100.663248) (xy 242.939316 -100.631752) (xy 242.739926 -100.558092) (xy 242.578382 -100.71989)
			(xy 242.652042 -100.919026) (xy 242.683538 -100.950522)
		)
		(stroke
			(width 0)
			(type solid)
		)
		(fill yes)
		(layer "In11.Cu")
		(net "M_F_DQ<28>")
	)
	(gr_poly
		(pts
			(xy 242.978178 -59.106562) (xy 242.986306 -58.914792) (xy 242.795044 -58.804302) (xy 242.632992 -58.907172)
			(xy 242.61064 -58.945526) (xy 242.95608 -59.144916)
		)
		(stroke
			(width 0)
			(type solid)
		)
		(fill yes)
		(layer "In11.Cu")
		(net "M_C_DQ<21>")
	)
	(gr_poly
		(pts
			(xy 242.978432 -56.13527) (xy 242.98656 -55.9435) (xy 242.795298 -55.83301) (xy 242.633246 -55.93588)
			(xy 242.610894 -55.974234) (xy 242.956334 -56.173878)
		)
		(stroke
			(width 0)
			(type solid)
		)
		(fill yes)
		(layer "In11.Cu")
		(net "M_C_DQS_DN<2>")
	)
	(gr_poly
		(pts
			(xy 242.978432 -55.14467) (xy 242.98656 -54.9529) (xy 242.795298 -54.84241) (xy 242.633246 -54.94528)
			(xy 242.610894 -54.983634) (xy 242.956334 -55.183278)
		)
		(stroke
			(width 0)
			(type solid)
		)
		(fill yes)
		(layer "In11.Cu")
		(net "M_C_DQ<23>")
	)
	(gr_poly
		(pts
			(xy 242.979956 -58.116978) (xy 242.988084 -57.925208) (xy 242.796822 -57.814718) (xy 242.63477 -57.917588)
			(xy 242.612418 -57.955942) (xy 242.957858 -58.155332)
		)
		(stroke
			(width 0)
			(type solid)
		)
		(fill yes)
		(layer "In11.Cu")
		(net "M_C_DQ<17>")
	)
	(gr_poly
		(pts
			(xy 242.979956 -57.126632) (xy 242.988084 -56.934862) (xy 242.796822 -56.824372) (xy 242.63477 -56.927242)
			(xy 242.612418 -56.965596) (xy 242.957858 -57.16524)
		)
		(stroke
			(width 0)
			(type solid)
		)
		(fill yes)
		(layer "In11.Cu")
		(net "M_C_DQS_DN<11>")
	)
	(gr_poly
		(pts
			(xy 242.979956 -54.154832) (xy 242.988084 -53.963062) (xy 242.796822 -53.852572) (xy 242.63477 -53.955442)
			(xy 242.612418 -53.993796) (xy 242.957858 -54.193186)
		)
		(stroke
			(width 0)
			(type solid)
		)
		(fill yes)
		(layer "In11.Cu")
		(net "M_C_DQ<19>")
	)
	(gr_poly
		(pts
			(xy 242.984274 -94.86265) (xy 242.976146 -94.67088) (xy 242.954048 -94.632272) (xy 242.608608 -94.831662)
			(xy 242.63096 -94.87027) (xy 242.793012 -94.97314)
		)
		(stroke
			(width 0)
			(type solid)
		)
		(fill yes)
		(layer "In11.Cu")
		(net "M_F_DQS_DN<11>")
	)
	(gr_poly
		(pts
			(xy 242.98656 -97.83318) (xy 242.978432 -97.64141) (xy 242.956334 -97.602802) (xy 242.610894 -97.802446)
			(xy 242.633246 -97.8408) (xy 242.795298 -97.94367)
		)
		(stroke
			(width 0)
			(type solid)
		)
		(fill yes)
		(layer "In11.Cu")
		(net "M_F_DQ<19>")
	)
	(gr_poly
		(pts
			(xy 242.98656 -96.84258) (xy 242.978432 -96.65081) (xy 242.956334 -96.612202) (xy 242.610894 -96.811846)
			(xy 242.633246 -96.8502) (xy 242.795298 -96.95307)
		)
		(stroke
			(width 0)
			(type solid)
		)
		(fill yes)
		(layer "In11.Cu")
		(net "M_F_DQ<23>")
	)
	(gr_poly
		(pts
			(xy 242.98656 -95.85198) (xy 242.978432 -95.66021) (xy 242.956334 -95.621602) (xy 242.610894 -95.821246)
			(xy 242.633246 -95.8596) (xy 242.795298 -95.96247)
		)
		(stroke
			(width 0)
			(type solid)
		)
		(fill yes)
		(layer "In11.Cu")
		(net "M_F_DQS_DP<2>")
	)
	(gr_poly
		(pts
			(xy 242.98656 -92.88018) (xy 242.978432 -92.68841) (xy 242.956334 -92.649802) (xy 242.610894 -92.849446)
			(xy 242.633246 -92.8878) (xy 242.795298 -92.99067)
		)
		(stroke
			(width 0)
			(type solid)
		)
		(fill yes)
		(layer "In11.Cu")
		(net "M_F_DQ<21>")
	)
	(gr_poly
		(pts
			(xy 242.988084 -93.870018) (xy 242.979956 -93.678248) (xy 242.957858 -93.639894) (xy 242.612418 -93.83903)
			(xy 242.63477 -93.877638) (xy 242.796822 -93.980508)
		)
		(stroke
			(width 0)
			(type solid)
		)
		(fill yes)
		(layer "In11.Cu")
		(net "M_F_DQ<17>")
	)
	(gr_poly
		(pts
			(xy 243.016786 -52.348384) (xy 243.048282 -52.316888) (xy 242.761008 -52.029614) (xy 242.729512 -52.06111)
			(xy 242.655852 -52.260246) (xy 242.81765 -52.422044)
		)
		(stroke
			(width 0)
			(type solid)
		)
		(fill yes)
		(layer "In11.Cu")
		(net "M_C_DQ<28>")
	)
	(gr_poly
		(pts
			(xy 243.185696 -58.7121) (xy 243.208048 -58.673492) (xy 242.862608 -58.474102) (xy 242.84051 -58.51271)
			(xy 242.832382 -58.70448) (xy 243.023644 -58.81497)
		)
		(stroke
			(width 0)
			(type solid)
		)
		(fill yes)
		(layer "In11.Cu")
		(net "M_C_DQ<16>")
	)
	(gr_poly
		(pts
			(xy 243.185696 -56.730646) (xy 243.208048 -56.692038) (xy 242.862608 -56.492648) (xy 242.84051 -56.531256)
			(xy 242.832382 -56.723026) (xy 243.023644 -56.833516)
		)
		(stroke
			(width 0)
			(type solid)
		)
		(fill yes)
		(layer "In11.Cu")
		(net "M_C_DQS_DP<2>")
	)
	(gr_poly
		(pts
			(xy 243.185696 -55.740046) (xy 243.208048 -55.701438) (xy 242.862608 -55.502048) (xy 242.84051 -55.540656)
			(xy 242.832382 -55.732426) (xy 243.023644 -55.842916)
		)
		(stroke
			(width 0)
			(type solid)
		)
		(fill yes)
		(layer "In11.Cu")
		(net "M_C_DQ<22>")
	)
	(gr_poly
		(pts
			(xy 243.185696 -54.749446) (xy 243.208048 -54.710838) (xy 242.862608 -54.511448) (xy 242.84051 -54.550056)
			(xy 242.832382 -54.741826) (xy 243.023644 -54.852316)
		)
		(stroke
			(width 0)
			(type solid)
		)
		(fill yes)
		(layer "In11.Cu")
		(net "M_C_DQ<18>")
	)
	(gr_poly
		(pts
			(xy 243.196618 -57.727596) (xy 243.21897 -57.689242) (xy 242.87353 -57.489852) (xy 242.851432 -57.528206)
			(xy 242.843304 -57.719976) (xy 243.034566 -57.830466)
		)
		(stroke
			(width 0)
			(type solid)
		)
		(fill yes)
		(layer "In11.Cu")
		(net "M_C_DQS_DP<11>")
	)
	(gr_poly
		(pts
			(xy 243.206524 -94.112842) (xy 243.184172 -94.074488) (xy 243.02212 -93.971618) (xy 242.830858 -94.082108)
			(xy 242.838986 -94.273878) (xy 242.861084 -94.312486)
		)
		(stroke
			(width 0)
			(type solid)
		)
		(fill yes)
		(layer "In11.Cu")
		(net "M_F_DQS_DP<11>")
	)
	(gr_poly
		(pts
			(xy 243.208048 -97.08388) (xy 243.185696 -97.045526) (xy 243.023644 -96.942656) (xy 242.832382 -97.053146)
			(xy 242.84051 -97.244916) (xy 242.862608 -97.28327)
		)
		(stroke
			(width 0)
			(type solid)
		)
		(fill yes)
		(layer "In11.Cu")
		(net "M_F_DQ<18>")
	)
	(gr_poly
		(pts
			(xy 243.208048 -96.09328) (xy 243.185696 -96.054926) (xy 243.023644 -95.952056) (xy 242.832382 -96.062546)
			(xy 242.84051 -96.254316) (xy 242.862608 -96.29267)
		)
		(stroke
			(width 0)
			(type solid)
		)
		(fill yes)
		(layer "In11.Cu")
		(net "M_F_DQ<22>")
	)
	(gr_poly
		(pts
			(xy 243.208048 -95.10268) (xy 243.185696 -95.064326) (xy 243.023644 -94.961456) (xy 242.832382 -95.071946)
			(xy 242.84051 -95.263716) (xy 242.862608 -95.30207)
		)
		(stroke
			(width 0)
			(type solid)
		)
		(fill yes)
		(layer "In11.Cu")
		(net "M_F_DQS_DN<2>")
	)
	(gr_poly
		(pts
			(xy 243.208048 -92.13088) (xy 243.185696 -92.092526) (xy 243.023644 -91.989656) (xy 242.832382 -92.100146)
			(xy 242.84051 -92.291916) (xy 242.862608 -92.33027)
		)
		(stroke
			(width 0)
			(type solid)
		)
		(fill yes)
		(layer "In11.Cu")
		(net "M_F_DQ<20>")
	)
	(gr_poly
		(pts
			(xy 243.210334 -101.028246) (xy 243.136674 -100.82911) (xy 243.105178 -100.797614) (xy 242.817904 -101.084888)
			(xy 242.849146 -101.116384) (xy 243.048536 -101.190044)
		)
		(stroke
			(width 0)
			(type solid)
		)
		(fill yes)
		(layer "In11.Cu")
		(net "M_F_DQ<29>")
	)
	(gr_poly
		(pts
			(xy 243.214906 -52.150264) (xy 243.288566 -51.951128) (xy 243.126768 -51.78933) (xy 242.927632 -51.86299)
			(xy 242.896136 -51.894486) (xy 243.18341 -52.18176)
		)
		(stroke
			(width 0)
			(type solid)
		)
		(fill yes)
		(layer "In11.Cu")
		(net "M_C_DQ<29>")
	)
	(gr_poly
		(pts
			(xy 243.220748 -93.118178) (xy 243.198396 -93.079824) (xy 243.036344 -92.976954) (xy 242.845082 -93.087444)
			(xy 242.85321 -93.279214) (xy 242.875308 -93.317822)
		)
		(stroke
			(width 0)
			(type solid)
		)
		(fill yes)
		(layer "In11.Cu")
		(net "M_F_DQ<16>")
	)
	(gr_poly
		(pts
			(xy 243.555012 -99.291648) (xy 243.523516 -99.260152) (xy 243.324126 -99.186492) (xy 243.162582 -99.34829)
			(xy 243.236242 -99.547426) (xy 243.267738 -99.578922)
		)
		(stroke
			(width 0)
			(type solid)
		)
		(fill yes)
		(layer "In11.Cu")
		(net "M_F_DQ<28>")
	)
	(gr_poly
		(pts
			(xy 243.60632 -97.991168) (xy 243.561616 -97.991422) (xy 243.39169 -98.080322) (xy 243.391436 -98.301048)
			(xy 243.561616 -98.389948) (xy 243.60632 -98.390202)
		)
		(stroke
			(width 0)
			(type solid)
		)
		(fill yes)
		(layer "In11.Cu")
		(net "M_F_DQ<28>")
	)
	(gr_poly
		(pts
			(xy 243.727986 -53.059584) (xy 243.759482 -53.028088) (xy 243.472208 -52.740814) (xy 243.440712 -52.77231)
			(xy 243.367052 -52.971446) (xy 243.52885 -53.133244)
		)
		(stroke
			(width 0)
			(type solid)
		)
		(fill yes)
		(layer "In11.Cu")
		(net "M_C_DQ<28>")
	)
	(gr_poly
		(pts
			(xy 243.794534 -99.656646) (xy 243.720874 -99.45751) (xy 243.689378 -99.426014) (xy 243.402104 -99.713288)
			(xy 243.433346 -99.744784) (xy 243.632736 -99.818444)
		)
		(stroke
			(width 0)
			(type solid)
		)
		(fill yes)
		(layer "In11.Cu")
		(net "M_F_DQ<29>")
	)
	(gr_poly
		(pts
			(xy 243.836698 -56.630316) (xy 243.844826 -56.438546) (xy 243.653564 -56.328056) (xy 243.491512 -56.430926)
			(xy 243.46916 -56.46928) (xy 243.8146 -56.668924)
		)
		(stroke
			(width 0)
			(type solid)
		)
		(fill yes)
		(layer "In11.Cu")
		(net "M_C_DQS_DN<2>")
	)
	(gr_poly
		(pts
			(xy 243.836698 -55.639716) (xy 243.844826 -55.447946) (xy 243.653564 -55.337456) (xy 243.491512 -55.440326)
			(xy 243.46916 -55.47868) (xy 243.8146 -55.678324)
		)
		(stroke
			(width 0)
			(type solid)
		)
		(fill yes)
		(layer "In11.Cu")
		(net "M_C_DQ<23>")
	)
	(gr_poly
		(pts
			(xy 243.838222 -54.649878) (xy 243.84635 -54.458108) (xy 243.655088 -54.347618) (xy 243.493036 -54.450488)
			(xy 243.470684 -54.488842) (xy 243.816124 -54.688232)
		)
		(stroke
			(width 0)
			(type solid)
		)
		(fill yes)
		(layer "In11.Cu")
		(net "M_C_DQ<19>")
	)
	(gr_poly
		(pts
			(xy 243.844826 -94.36608) (xy 243.836698 -94.17431) (xy 243.8146 -94.135702) (xy 243.46916 -94.335346)
			(xy 243.491512 -94.3737) (xy 243.653564 -94.47657)
		)
		(stroke
			(width 0)
			(type solid)
		)
		(fill yes)
		(layer "In11.Cu")
		(net "M_F_DQS_DN<11>")
	)
	(gr_poly
		(pts
			(xy 243.84635 -97.336864) (xy 243.838222 -97.145094) (xy 243.816124 -97.106486) (xy 243.470684 -97.30613)
			(xy 243.493036 -97.344484) (xy 243.655088 -97.447354)
		)
		(stroke
			(width 0)
			(type solid)
		)
		(fill yes)
		(layer "In11.Cu")
		(net "M_F_DQ<19>")
	)
	(gr_poly
		(pts
			(xy 243.84635 -96.346264) (xy 243.838222 -96.154494) (xy 243.816124 -96.115886) (xy 243.470684 -96.31553)
			(xy 243.493036 -96.353884) (xy 243.655088 -96.456754)
		)
		(stroke
			(width 0)
			(type solid)
		)
		(fill yes)
		(layer "In11.Cu")
		(net "M_F_DQ<23>")
	)
	(gr_poly
		(pts
			(xy 243.84635 -95.355664) (xy 243.838222 -95.163894) (xy 243.816124 -95.125286) (xy 243.470684 -95.32493)
			(xy 243.493036 -95.363284) (xy 243.655088 -95.466154)
		)
		(stroke
			(width 0)
			(type solid)
		)
		(fill yes)
		(layer "In11.Cu")
		(net "M_F_DQS_DP<2>")
	)
	(gr_poly
		(pts
			(xy 243.854224 -101.536246) (xy 243.809774 -101.536246) (xy 243.616734 -101.625146) (xy 243.616734 -101.853746)
			(xy 243.809774 -101.942646) (xy 243.854224 -101.942646)
		)
		(stroke
			(width 0)
			(type solid)
		)
		(fill yes)
		(layer "In11.Cu")
		(net "M_F_DQ<24>")
	)
	(gr_poly
		(pts
			(xy 243.854224 -100.545646) (xy 243.809774 -100.545646) (xy 243.616734 -100.634546) (xy 243.616734 -100.863146)
			(xy 243.809774 -100.952046) (xy 243.854224 -100.952046)
		)
		(stroke
			(width 0)
			(type solid)
		)
		(fill yes)
		(layer "In11.Cu")
		(net "M_F_DQ<24>")
	)
	(gr_poly
		(pts
			(xy 243.926106 -52.861464) (xy 243.999766 -52.662328) (xy 243.837968 -52.50053) (xy 243.638832 -52.57419)
			(xy 243.607336 -52.605686) (xy 243.89461 -52.89296)
		)
		(stroke
			(width 0)
			(type solid)
		)
		(fill yes)
		(layer "In11.Cu")
		(net "M_C_DQ<29>")
	)
	(gr_poly
		(pts
			(xy 244.044216 -57.2262) (xy 244.066568 -57.187592) (xy 243.721128 -56.988202) (xy 243.69903 -57.02681)
			(xy 243.690902 -57.21858) (xy 243.882164 -57.32907)
		)
		(stroke
			(width 0)
			(type solid)
		)
		(fill yes)
		(layer "In11.Cu")
		(net "M_C_DQS_DP<2>")
	)
	(gr_poly
		(pts
			(xy 244.044216 -56.2356) (xy 244.066568 -56.196992) (xy 243.721128 -55.997602) (xy 243.69903 -56.03621)
			(xy 243.690902 -56.22798) (xy 243.882164 -56.33847)
		)
		(stroke
			(width 0)
			(type solid)
		)
		(fill yes)
		(layer "In11.Cu")
		(net "M_C_DQ<22>")
	)
	(gr_poly
		(pts
			(xy 244.044216 -55.245) (xy 244.066568 -55.206392) (xy 243.721128 -55.007002) (xy 243.69903 -55.04561)
			(xy 243.690902 -55.23738) (xy 243.882164 -55.34787)
		)
		(stroke
			(width 0)
			(type solid)
		)
		(fill yes)
		(layer "In11.Cu")
		(net "M_C_DQ<18>")
	)
	(gr_poly
		(pts
			(xy 244.065044 -96.58985) (xy 244.042692 -96.551242) (xy 243.88064 -96.448372) (xy 243.689378 -96.558862)
			(xy 243.697506 -96.750632) (xy 243.719604 -96.78924)
		)
		(stroke
			(width 0)
			(type solid)
		)
		(fill yes)
		(layer "In11.Cu")
		(net "M_F_DQ<18>")
	)
	(gr_poly
		(pts
			(xy 244.065044 -95.59925) (xy 244.042692 -95.560642) (xy 243.88064 -95.457772) (xy 243.689378 -95.568262)
			(xy 243.697506 -95.760032) (xy 243.719604 -95.79864)
		)
		(stroke
			(width 0)
			(type solid)
		)
		(fill yes)
		(layer "In11.Cu")
		(net "M_F_DQ<22>")
	)
	(gr_poly
		(pts
			(xy 244.066568 -93.61678) (xy 244.044216 -93.578426) (xy 243.882164 -93.475556) (xy 243.690902 -93.586046)
			(xy 243.69903 -93.777816) (xy 243.721128 -93.81617)
		)
		(stroke
			(width 0)
			(type solid)
		)
		(fill yes)
		(layer "In11.Cu")
		(net "M_F_DQS_DP<11>")
	)
	(gr_poly
		(pts
			(xy 244.070632 -97.577148) (xy 244.048026 -97.53854) (xy 243.886228 -97.43567) (xy 243.694966 -97.545906)
			(xy 243.70284 -97.737676) (xy 243.725192 -97.776538)
		)
		(stroke
			(width 0)
			(type solid)
		)
		(fill yes)
		(layer "In11.Cu")
		(net "M_F_DQ<28>")
	)
	(gr_poly
		(pts
			(xy 244.163088 -92.790518) (xy 244.140736 -92.752164) (xy 243.978684 -92.649294) (xy 243.787422 -92.759784)
			(xy 243.79555 -92.951554) (xy 243.817648 -92.990162)
		)
		(stroke
			(width 0)
			(type solid)
		)
		(fill yes)
		(layer "In11.Cu")
		(net "M_F_DQ<16>")
	)
	(gr_poly
		(pts
			(xy 244.20703 -91.783408) (xy 244.118384 -91.612974) (xy 243.897658 -91.612466) (xy 243.80825 -91.782392)
			(xy 243.80825 -91.826842) (xy 244.206776 -91.828112)
		)
		(stroke
			(width 0)
			(type solid)
		)
		(fill yes)
		(layer "In11.Cu")
		(net "M_F_DQ<20>")
	)
	(gr_poly
		(pts
			(xy 244.214142 -98.958908) (xy 244.214142 -98.730054) (xy 244.021356 -98.641154) (xy 243.976906 -98.641154)
			(xy 243.976906 -99.047554) (xy 244.021102 -99.047808)
		)
		(stroke
			(width 0)
			(type solid)
		)
		(fill yes)
		(layer "In11.Cu")
		(net "M_F_DQ<29>")
	)
	(gr_poly
		(pts
			(xy 244.281706 -101.853746) (xy 244.281706 -101.625146) (xy 244.088666 -101.536246) (xy 244.044216 -101.536246)
			(xy 244.044216 -101.942646) (xy 244.088666 -101.942646)
		)
		(stroke
			(width 0)
			(type solid)
		)
		(fill yes)
		(layer "In11.Cu")
		(net "M_F_DQ<25>")
	)
	(gr_poly
		(pts
			(xy 244.281706 -100.863146) (xy 244.281706 -100.634546) (xy 244.088666 -100.545646) (xy 244.044216 -100.545646)
			(xy 244.044216 -100.952046) (xy 244.088666 -100.952046)
		)
		(stroke
			(width 0)
			(type solid)
		)
		(fill yes)
		(layer "In11.Cu")
		(net "M_F_DQ<25>")
	)
	(gr_poly
		(pts
			(xy 244.464586 -98.975926) (xy 244.420136 -98.975926) (xy 244.227096 -99.064826) (xy 244.227096 -99.293426)
			(xy 244.420136 -99.382326) (xy 244.464586 -99.382326)
		)
		(stroke
			(width 0)
			(type solid)
		)
		(fill yes)
		(layer "In11.Cu")
		(net "M_F_DQ<24>")
	)
	(gr_poly
		(pts
			(xy 244.696742 -57.126632) (xy 244.70487 -56.934862) (xy 244.513608 -56.824372) (xy 244.351556 -56.927242)
			(xy 244.329204 -56.965596) (xy 244.674644 -57.16524)
		)
		(stroke
			(width 0)
			(type solid)
		)
		(fill yes)
		(layer "In11.Cu")
		(net "M_C_DQS_DN<2>")
	)
	(gr_poly
		(pts
			(xy 244.696742 -56.136032) (xy 244.70487 -55.944262) (xy 244.513608 -55.833772) (xy 244.351556 -55.936642)
			(xy 244.329204 -55.974996) (xy 244.674644 -56.17464)
		)
		(stroke
			(width 0)
			(type solid)
		)
		(fill yes)
		(layer "In11.Cu")
		(net "M_C_DQ<23>")
	)
	(gr_poly
		(pts
			(xy 244.696742 -55.145432) (xy 244.70487 -54.953662) (xy 244.513608 -54.843172) (xy 244.351556 -54.946042)
			(xy 244.329204 -54.984396) (xy 244.674644 -55.18404)
		)
		(stroke
			(width 0)
			(type solid)
		)
		(fill yes)
		(layer "In11.Cu")
		(net "M_C_DQ<19>")
	)
	(gr_poly
		(pts
			(xy 244.703346 -97.83318) (xy 244.695218 -97.64141) (xy 244.67312 -97.602802) (xy 244.32768 -97.802446)
			(xy 244.350032 -97.8408) (xy 244.512084 -97.94367)
		)
		(stroke
			(width 0)
			(type solid)
		)
		(fill yes)
		(layer "In11.Cu")
		(net "M_F_DQ<29>")
	)
	(gr_poly
		(pts
			(xy 244.703346 -96.84258) (xy 244.695218 -96.65081) (xy 244.67312 -96.612202) (xy 244.32768 -96.811846)
			(xy 244.350032 -96.8502) (xy 244.512084 -96.95307)
		)
		(stroke
			(width 0)
			(type solid)
		)
		(fill yes)
		(layer "In11.Cu")
		(net "M_F_DQ<19>")
	)
	(gr_poly
		(pts
			(xy 244.703346 -95.85198) (xy 244.695218 -95.66021) (xy 244.67312 -95.621602) (xy 244.32768 -95.821246)
			(xy 244.350032 -95.8596) (xy 244.512084 -95.96247)
		)
		(stroke
			(width 0)
			(type solid)
		)
		(fill yes)
		(layer "In11.Cu")
		(net "M_F_DQ<23>")
	)
	(gr_poly
		(pts
			(xy 244.70487 -93.870018) (xy 244.696742 -93.678248) (xy 244.674644 -93.639894) (xy 244.329204 -93.83903)
			(xy 244.351556 -93.877638) (xy 244.513608 -93.980508)
		)
		(stroke
			(width 0)
			(type solid)
		)
		(fill yes)
		(layer "In11.Cu")
		(net "M_F_DQS_DN<11>")
	)
	(gr_poly
		(pts
			(xy 244.892576 -99.293426) (xy 244.892576 -99.064826) (xy 244.699536 -98.975926) (xy 244.655086 -98.975926)
			(xy 244.655086 -99.382326) (xy 244.699536 -99.382326)
		)
		(stroke
			(width 0)
			(type solid)
		)
		(fill yes)
		(layer "In11.Cu")
		(net "M_F_DQ<25>")
	)
	(gr_poly
		(pts
			(xy 244.901212 -55.739284) (xy 244.923564 -55.70093) (xy 244.578124 -55.501286) (xy 244.556026 -55.539894)
			(xy 244.547898 -55.731664) (xy 244.73916 -55.842154)
		)
		(stroke
			(width 0)
			(type solid)
		)
		(fill yes)
		(layer "In11.Cu")
		(net "M_C_DQ<18>")
	)
	(gr_poly
		(pts
			(xy 244.905022 -57.72277) (xy 244.927374 -57.684416) (xy 244.581934 -57.484772) (xy 244.559836 -57.52338)
			(xy 244.551708 -57.71515) (xy 244.74297 -57.82564)
		)
		(stroke
			(width 0)
			(type solid)
		)
		(fill yes)
		(layer "In11.Cu")
		(net "M_C_DQS_DP<2>")
	)
	(gr_poly
		(pts
			(xy 244.925088 -97.08388) (xy 244.902736 -97.045526) (xy 244.740684 -96.942656) (xy 244.549422 -97.053146)
			(xy 244.55755 -97.244916) (xy 244.579648 -97.28327)
		)
		(stroke
			(width 0)
			(type solid)
		)
		(fill yes)
		(layer "In11.Cu")
		(net "M_F_DQ<28>")
	)
	(gr_poly
		(pts
			(xy 244.925088 -96.09328) (xy 244.902736 -96.054926) (xy 244.740684 -95.952056) (xy 244.549422 -96.062546)
			(xy 244.55755 -96.254316) (xy 244.579648 -96.29267)
		)
		(stroke
			(width 0)
			(type solid)
		)
		(fill yes)
		(layer "In11.Cu")
		(net "M_F_DQ<18>")
	)
	(gr_poly
		(pts
			(xy 244.92712 -98.07321) (xy 244.905022 -98.034602) (xy 244.74297 -97.931732) (xy 244.551708 -98.042222)
			(xy 244.559582 -98.233992) (xy 244.581934 -98.272346)
		)
		(stroke
			(width 0)
			(type solid)
		)
		(fill yes)
		(layer "In11.Cu")
		(net "M_F_DQ<24>")
	)
	(gr_poly
		(pts
			(xy 244.927374 -93.12021) (xy 244.905022 -93.081856) (xy 244.74297 -92.978986) (xy 244.551708 -93.089476)
			(xy 244.559836 -93.281246) (xy 244.581934 -93.319854)
		)
		(stroke
			(width 0)
			(type solid)
		)
		(fill yes)
		(layer "In11.Cu")
		(net "M_F_DQS_DP<11>")
	)
	(gr_poly
		(pts
			(xy 245.020084 -95.353124) (xy 245.11127 -95.151956) (xy 244.992906 -95.000826) (xy 244.95252 -94.982284)
			(xy 244.787928 -95.345758) (xy 244.828568 -95.363792)
		)
		(stroke
			(width 0)
			(type solid)
		)
		(fill yes)
		(layer "In11.Cu")
		(net "M_F_DQ<23>")
	)
	(gr_poly
		(pts
			(xy 245.023386 -92.294202) (xy 245.001034 -92.255848) (xy 244.838982 -92.152978) (xy 244.64772 -92.263468)
			(xy 244.655848 -92.455238) (xy 244.677946 -92.493846)
		)
		(stroke
			(width 0)
			(type solid)
		)
		(fill yes)
		(layer "In11.Cu")
		(net "M_F_DQ<16>")
	)
	(gr_poly
		(pts
			(xy 245.086632 -101.718618) (xy 245.042182 -101.718618) (xy 244.849142 -101.807518) (xy 244.849142 -102.036118)
			(xy 245.042182 -102.125018) (xy 245.086632 -102.125018)
		)
		(stroke
			(width 0)
			(type solid)
		)
		(fill yes)
		(layer "In11.Cu")
		(net "M_F_DQS_DP<12>")
	)
	(gr_poly
		(pts
			(xy 245.086632 -100.728018) (xy 245.042182 -100.728018) (xy 244.849142 -100.816918) (xy 244.849142 -101.045518)
			(xy 245.042182 -101.134418) (xy 245.086632 -101.134418)
		)
		(stroke
			(width 0)
			(type solid)
		)
		(fill yes)
		(layer "In11.Cu")
		(net "M_F_DQS_DP<12>")
	)
	(gr_poly
		(pts
			(xy 245.514622 -102.036118) (xy 245.514622 -101.807518) (xy 245.321582 -101.718618) (xy 245.277132 -101.718618)
			(xy 245.277132 -102.125018) (xy 245.321582 -102.125018)
		)
		(stroke
			(width 0)
			(type solid)
		)
		(fill yes)
		(layer "In11.Cu")
		(net "M_F_DQS_DN<12>")
	)
	(gr_poly
		(pts
			(xy 245.514622 -101.045518) (xy 245.514622 -100.816918) (xy 245.321582 -100.728018) (xy 245.277132 -100.728018)
			(xy 245.277132 -101.134418) (xy 245.321582 -101.134418)
		)
		(stroke
			(width 0)
			(type solid)
		)
		(fill yes)
		(layer "In11.Cu")
		(net "M_F_DQS_DN<12>")
	)
	(gr_poly
		(pts
			(xy 245.551452 -57.619646) (xy 245.55958 -57.427876) (xy 245.368318 -57.317386) (xy 245.206266 -57.420256)
			(xy 245.183914 -57.45861) (xy 245.529354 -57.658)
		)
		(stroke
			(width 0)
			(type solid)
		)
		(fill yes)
		(layer "In11.Cu")
		(net "M_C_DQS_DN<2>")
	)
	(gr_poly
		(pts
			(xy 245.553738 -55.639716) (xy 245.561866 -55.447946) (xy 245.370604 -55.337456) (xy 245.208552 -55.440326)
			(xy 245.1862 -55.47868) (xy 245.53164 -55.678324)
		)
		(stroke
			(width 0)
			(type solid)
		)
		(fill yes)
		(layer "In11.Cu")
		(net "M_C_DQ<19>")
	)
	(gr_poly
		(pts
			(xy 245.555262 -56.631078) (xy 245.56339 -56.439308) (xy 245.372128 -56.328818) (xy 245.210076 -56.431688)
			(xy 245.187724 -56.470042) (xy 245.533164 -56.669686)
		)
		(stroke
			(width 0)
			(type solid)
		)
		(fill yes)
		(layer "In11.Cu")
		(net "M_C_DQ<23>")
	)
	(gr_poly
		(pts
			(xy 245.55958 -93.37675) (xy 245.551452 -93.18498) (xy 245.529354 -93.146372) (xy 245.183914 -93.345762)
			(xy 245.206266 -93.38437) (xy 245.368318 -93.48724)
		)
		(stroke
			(width 0)
			(type solid)
		)
		(fill yes)
		(layer "In11.Cu")
		(net "M_F_DQS_DN<11>")
	)
	(gr_poly
		(pts
			(xy 245.561866 -94.36608) (xy 245.553738 -94.17431) (xy 245.53164 -94.135702) (xy 245.1862 -94.335346)
			(xy 245.208552 -94.3737) (xy 245.370604 -94.47657)
		)
		(stroke
			(width 0)
			(type solid)
		)
		(fill yes)
		(layer "In11.Cu")
		(net "M_F_DQ<22>")
	)
	(gr_poly
		(pts
			(xy 245.56339 -98.327464) (xy 245.555262 -98.135694) (xy 245.533164 -98.097086) (xy 245.187724 -98.29673)
			(xy 245.210076 -98.335084) (xy 245.372128 -98.437954)
		)
		(stroke
			(width 0)
			(type solid)
		)
		(fill yes)
		(layer "In11.Cu")
		(net "M_F_DQ<25>")
	)
	(gr_poly
		(pts
			(xy 245.56339 -97.336864) (xy 245.555262 -97.145094) (xy 245.533164 -97.106486) (xy 245.187724 -97.30613)
			(xy 245.210076 -97.344484) (xy 245.372128 -97.447354)
		)
		(stroke
			(width 0)
			(type solid)
		)
		(fill yes)
		(layer "In11.Cu")
		(net "M_F_DQ<29>")
	)
	(gr_poly
		(pts
			(xy 245.56339 -96.346264) (xy 245.555262 -96.154494) (xy 245.533164 -96.115886) (xy 245.187724 -96.31553)
			(xy 245.210076 -96.353884) (xy 245.372128 -96.456754)
		)
		(stroke
			(width 0)
			(type solid)
		)
		(fill yes)
		(layer "In11.Cu")
		(net "M_F_DQ<19>")
	)
	(gr_poly
		(pts
			(xy 245.759732 -58.216038) (xy 245.782084 -58.177684) (xy 245.436644 -57.97804) (xy 245.414546 -58.016648)
			(xy 245.406418 -58.208418) (xy 245.59768 -58.318908)
		)
		(stroke
			(width 0)
			(type solid)
		)
		(fill yes)
		(layer "In11.Cu")
		(net "M_C_DQS_DP<2>")
	)
	(gr_poly
		(pts
			(xy 245.782084 -97.58045) (xy 245.759732 -97.541842) (xy 245.59768 -97.438972) (xy 245.406418 -97.549462)
			(xy 245.414546 -97.741232) (xy 245.436644 -97.77984)
		)
		(stroke
			(width 0)
			(type solid)
		)
		(fill yes)
		(layer "In11.Cu")
		(net "M_F_DQ<24>")
	)
	(gr_poly
		(pts
			(xy 245.782084 -96.58985) (xy 245.759732 -96.551242) (xy 245.59768 -96.448372) (xy 245.406418 -96.558862)
			(xy 245.414546 -96.750632) (xy 245.436644 -96.78924)
		)
		(stroke
			(width 0)
			(type solid)
		)
		(fill yes)
		(layer "In11.Cu")
		(net "M_F_DQ<28>")
	)
	(gr_poly
		(pts
			(xy 245.859554 -57.062878) (xy 245.881906 -57.024524) (xy 245.536466 -56.82488) (xy 245.514368 -56.863488)
			(xy 245.50624 -57.055258) (xy 245.697502 -57.165748)
		)
		(stroke
			(width 0)
			(type solid)
		)
		(fill yes)
		(layer "In11.Cu")
		(net "M_C_DQ<23>")
	)
	(gr_poly
		(pts
			(xy 245.873524 -101.991414) (xy 245.829074 -101.991414) (xy 245.636034 -102.080314) (xy 245.636034 -102.308914)
			(xy 245.829074 -102.397814) (xy 245.873524 -102.397814)
		)
		(stroke
			(width 0)
			(type solid)
		)
		(fill yes)
		(layer "In11.Cu")
		(net "M_F_DQS_DN<3>")
	)
	(gr_poly
		(pts
			(xy 245.873524 -101.000814) (xy 245.829074 -101.000814) (xy 245.636034 -101.089714) (xy 245.636034 -101.318314)
			(xy 245.829074 -101.407214) (xy 245.873524 -101.407214)
		)
		(stroke
			(width 0)
			(type solid)
		)
		(fill yes)
		(layer "In11.Cu")
		(net "M_F_DQS_DN<3>")
	)
	(gr_poly
		(pts
			(xy 245.878858 -93.78188) (xy 245.856506 -93.743526) (xy 245.694454 -93.640656) (xy 245.503192 -93.751146)
			(xy 245.51132 -93.942916) (xy 245.533418 -93.98127)
		)
		(stroke
			(width 0)
			(type solid)
		)
		(fill yes)
		(layer "In11.Cu")
		(net "M_F_DQ<22>")
	)
	(gr_poly
		(pts
			(xy 245.880128 -94.771718) (xy 245.857776 -94.733364) (xy 245.695724 -94.630494) (xy 245.504462 -94.740984)
			(xy 245.51259 -94.932754) (xy 245.534688 -94.971362)
		)
		(stroke
			(width 0)
			(type solid)
		)
		(fill yes)
		(layer "In11.Cu")
		(net "M_F_DQ<18>")
	)
	(gr_poly
		(pts
			(xy 245.89105 -53.906928) (xy 245.96471 -53.707792) (xy 245.802912 -53.545994) (xy 245.603776 -53.619654)
			(xy 245.57228 -53.65115) (xy 245.859554 -53.938424)
		)
		(stroke
			(width 0)
			(type solid)
		)
		(fill yes)
		(layer "In11.Cu")
		(net "M_C_DQ<29>")
	)
	(gr_poly
		(pts
			(xy 245.89232 -95.845884) (xy 245.980204 -95.643192) (xy 245.859554 -95.494094) (xy 245.81866 -95.47606)
			(xy 245.660164 -95.842328) (xy 245.701058 -95.859854)
		)
		(stroke
			(width 0)
			(type solid)
		)
		(fill yes)
		(layer "In11.Cu")
		(net "M_F_DQ<19>")
	)
	(gr_poly
		(pts
			(xy 246.098568 -54.860444) (xy 246.130064 -54.828948) (xy 245.84279 -54.541674) (xy 245.811294 -54.57317)
			(xy 245.737634 -54.772306) (xy 245.899432 -54.934104)
		)
		(stroke
			(width 0)
			(type solid)
		)
		(fill yes)
		(layer "In11.Cu")
		(net "M_C_DQ<28>")
	)
	(gr_poly
		(pts
			(xy 246.129048 -52.741576) (xy 246.160544 -52.710334) (xy 245.873016 -52.422806) (xy 245.841774 -52.454302)
			(xy 245.768114 -52.653692) (xy 245.929658 -52.815236)
		)
		(stroke
			(width 0)
			(type solid)
		)
		(fill yes)
		(layer "In11.Cu")
		(net "M_C_DQ<24>")
	)
	(gr_poly
		(pts
			(xy 246.161052 -102.924102) (xy 246.116602 -102.924102) (xy 245.923562 -103.013002) (xy 245.923562 -103.241602)
			(xy 246.116602 -103.330502) (xy 246.161052 -103.330502)
		)
		(stroke
			(width 0)
			(type solid)
		)
		(fill yes)
		(layer "In11.Cu")
		(net "M_F_DQS_DN<3>")
	)
	(gr_poly
		(pts
			(xy 246.296688 -54.662324) (xy 246.370348 -54.463188) (xy 246.20855 -54.30139) (xy 246.009414 -54.37505)
			(xy 245.977918 -54.406546) (xy 246.265192 -54.69382)
		)
		(stroke
			(width 0)
			(type solid)
		)
		(fill yes)
		(layer "In11.Cu")
		(net "M_C_DQ<29>")
	)
	(gr_poly
		(pts
			(xy 246.301514 -101.750114) (xy 246.301514 -101.521514) (xy 246.108474 -101.432614) (xy 246.064024 -101.432614)
			(xy 246.064024 -101.839014) (xy 246.108474 -101.839014)
		)
		(stroke
			(width 0)
			(type solid)
		)
		(fill yes)
		(layer "In11.Cu")
		(net "M_F_DQS_DP<3>")
	)
	(gr_poly
		(pts
			(xy 246.326152 -52.544472) (xy 246.399812 -52.345082) (xy 246.238268 -52.183538) (xy 246.038878 -52.257198)
			(xy 246.007382 -52.28844) (xy 246.29491 -52.575968)
		)
		(stroke
			(width 0)
			(type solid)
		)
		(fill yes)
		(layer "In11.Cu")
		(net "M_C_DQ<25>")
	)
	(gr_poly
		(pts
			(xy 246.409972 -56.143398) (xy 246.424704 -55.951882) (xy 246.237252 -55.834788) (xy 246.071644 -55.93207)
			(xy 246.048276 -55.969916) (xy 246.38635 -56.18099)
		)
		(stroke
			(width 0)
			(type solid)
		)
		(fill yes)
		(layer "In11.Cu")
		(net "M_C_DQ<19>")
	)
	(gr_poly
		(pts
			(xy 246.420132 -96.843088) (xy 246.412004 -96.651064) (xy 246.389906 -96.612456) (xy 246.04472 -96.8121)
			(xy 246.066818 -96.850454) (xy 246.22887 -96.953324)
		)
		(stroke
			(width 0)
			(type solid)
		)
		(fill yes)
		(layer "In11.Cu")
		(net "M_F_DQ<29>")
	)
	(gr_poly
		(pts
			(xy 246.420386 -97.83318) (xy 246.412258 -97.64141) (xy 246.39016 -97.602802) (xy 246.04472 -97.802446)
			(xy 246.067072 -97.8408) (xy 246.229124 -97.94367)
		)
		(stroke
			(width 0)
			(type solid)
		)
		(fill yes)
		(layer "In11.Cu")
		(net "M_F_DQ<25>")
	)
	(gr_poly
		(pts
			(xy 246.456962 -93.759782) (xy 246.45112 -93.715586) (xy 246.340884 -93.558614) (xy 246.121936 -93.587316)
			(xy 246.055896 -93.767402) (xy 246.061484 -93.811344)
		)
		(stroke
			(width 0)
			(type solid)
		)
		(fill yes)
		(layer "In11.Cu")
		(net "M_F_DQ<22>")
	)
	(gr_poly
		(pts
			(xy 246.462296 -51.064414) (xy 246.493792 -51.033172) (xy 246.206264 -50.745644) (xy 246.175022 -50.77714)
			(xy 246.101362 -50.97653) (xy 246.262906 -51.138074)
		)
		(stroke
			(width 0)
			(type solid)
		)
		(fill yes)
		(layer "In11.Cu")
		(net "M_C_DQS_DP<12>")
	)
	(gr_poly
		(pts
			(xy 246.589042 -103.241602) (xy 246.589042 -103.013002) (xy 246.396002 -102.924102) (xy 246.351552 -102.924102)
			(xy 246.351552 -103.330502) (xy 246.396002 -103.330502)
		)
		(stroke
			(width 0)
			(type solid)
		)
		(fill yes)
		(layer "In11.Cu")
		(net "M_F_DQS_DP<3>")
	)
	(gr_poly
		(pts
			(xy 246.638064 -56.759348) (xy 246.475758 -56.395366) (xy 246.435118 -56.4134) (xy 246.315738 -56.563768)
			(xy 246.405654 -56.765698) (xy 246.597424 -56.777636)
		)
		(stroke
			(width 0)
			(type solid)
		)
		(fill yes)
		(layer "In11.Cu")
		(net "M_C_DQ<19>")
	)
	(gr_poly
		(pts
			(xy 246.642128 -95.102426) (xy 246.62003 -95.064072) (xy 246.457978 -94.961202) (xy 246.266716 -95.071438)
			(xy 246.274844 -95.263208) (xy 246.296942 -95.30207)
		)
		(stroke
			(width 0)
			(type solid)
		)
		(fill yes)
		(layer "In11.Cu")
		(net "M_F_DQ<28>")
	)
	(gr_poly
		(pts
			(xy 246.650002 -97.079562) (xy 246.62765 -97.041208) (xy 246.465598 -96.938338) (xy 246.274336 -97.048828)
			(xy 246.282464 -97.240598) (xy 246.304562 -97.279206)
		)
		(stroke
			(width 0)
			(type solid)
		)
		(fill yes)
		(layer "In11.Cu")
		(net "M_F_DQ<24>")
	)
	(gr_poly
		(pts
			(xy 246.688356 -100.106988) (xy 246.65686 -100.075492) (xy 246.45747 -100.001832) (xy 246.295926 -100.16363)
			(xy 246.369586 -100.36302) (xy 246.401082 -100.394262)
		)
		(stroke
			(width 0)
			(type solid)
		)
		(fill yes)
		(layer "In11.Cu")
		(net "M_F_DQS_DN<3>")
	)
	(gr_poly
		(pts
			(xy 246.719598 -96.30664) (xy 246.719598 -96.085914) (xy 246.549418 -95.997014) (xy 246.504968 -95.99676)
			(xy 246.505222 -96.39554) (xy 246.549418 -96.39554)
		)
		(stroke
			(width 0)
			(type solid)
		)
		(fill yes)
		(layer "In11.Cu")
		(net "M_F_DQ<29>")
	)
	(gr_poly
		(pts
			(xy 246.786908 -50.993802) (xy 246.860568 -50.794666) (xy 246.69877 -50.632868) (xy 246.499634 -50.706528)
			(xy 246.468138 -50.738024) (xy 246.755412 -51.025298)
		)
		(stroke
			(width 0)
			(type solid)
		)
		(fill yes)
		(layer "In11.Cu")
		(net "M_C_DQS_DN<12>")
	)
	(gr_poly
		(pts
			(xy 246.809768 -55.571644) (xy 246.841264 -55.540148) (xy 246.55399 -55.252874) (xy 246.522494 -55.28437)
			(xy 246.448834 -55.483506) (xy 246.610632 -55.645304)
		)
		(stroke
			(width 0)
			(type solid)
		)
		(fill yes)
		(layer "In11.Cu")
		(net "M_C_DQ<28>")
	)
	(gr_poly
		(pts
			(xy 246.840248 -53.452776) (xy 246.871744 -53.421534) (xy 246.584216 -53.134006) (xy 246.552974 -53.165502)
			(xy 246.479314 -53.364892) (xy 246.640858 -53.526436)
		)
		(stroke
			(width 0)
			(type solid)
		)
		(fill yes)
		(layer "In11.Cu")
		(net "M_C_DQ<24>")
	)
	(gr_poly
		(pts
			(xy 246.928132 -100.472494) (xy 246.854472 -100.273104) (xy 246.822976 -100.241862) (xy 246.535702 -100.529136)
			(xy 246.567198 -100.560632) (xy 246.766588 -100.634292)
		)
		(stroke
			(width 0)
			(type solid)
		)
		(fill yes)
		(layer "In11.Cu")
		(net "M_F_DQS_DP<3>")
	)
	(gr_poly
		(pts
			(xy 247.007888 -55.373524) (xy 247.081548 -55.174388) (xy 246.91975 -55.01259) (xy 246.720614 -55.08625)
			(xy 246.689118 -55.117746) (xy 246.976392 -55.40502)
		)
		(stroke
			(width 0)
			(type solid)
		)
		(fill yes)
		(layer "In11.Cu")
		(net "M_C_DQ<29>")
	)
	(gr_poly
		(pts
			(xy 247.029224 -97.896934) (xy 246.997728 -97.865438) (xy 246.798338 -97.791778) (xy 246.636794 -97.953576)
			(xy 246.710454 -98.152966) (xy 246.74195 -98.184208)
		)
		(stroke
			(width 0)
			(type solid)
		)
		(fill yes)
		(layer "In11.Cu")
		(net "M_F_DQS_DP<12>")
	)
	(gr_poly
		(pts
			(xy 247.037352 -53.255672) (xy 247.111012 -53.056282) (xy 246.949468 -52.894738) (xy 246.750078 -52.968398)
			(xy 246.718582 -52.99964) (xy 247.00611 -53.287168)
		)
		(stroke
			(width 0)
			(type solid)
		)
		(fill yes)
		(layer "In11.Cu")
		(net "M_C_DQ<25>")
	)
	(gr_poly
		(pts
			(xy 247.040146 -96.010222) (xy 246.995696 -96.010222) (xy 246.82577 -96.099122) (xy 246.825516 -96.319848)
			(xy 246.995696 -96.408748) (xy 247.0404 -96.409002)
		)
		(stroke
			(width 0)
			(type solid)
		)
		(fill yes)
		(layer "In11.Cu")
		(net "M_F_DQ<24>")
	)
	(gr_poly
		(pts
			(xy 247.040146 -94.030546) (xy 246.995696 -94.030546) (xy 246.825516 -94.119446) (xy 246.825516 -94.340426)
			(xy 246.995696 -94.429326) (xy 247.040146 -94.429326)
		)
		(stroke
			(width 0)
			(type solid)
		)
		(fill yes)
		(layer "In11.Cu")
		(net "M_F_DQ<28>")
	)
	(gr_poly
		(pts
			(xy 247.040146 -93.03385) (xy 246.995696 -93.03385) (xy 246.825516 -93.12275) (xy 246.825516 -93.34373)
			(xy 246.995696 -93.43263) (xy 247.040146 -93.43263)
		)
		(stroke
			(width 0)
			(type solid)
		)
		(fill yes)
		(layer "In11.Cu")
		(net "M_F_DQ<28>")
	)
	(gr_poly
		(pts
			(xy 247.040146 -92.047822) (xy 246.995696 -92.047822) (xy 246.82577 -92.136722) (xy 246.825516 -92.357448)
			(xy 246.995696 -92.446348) (xy 247.0404 -92.446602)
		)
		(stroke
			(width 0)
			(type solid)
		)
		(fill yes)
		(layer "In11.Cu")
		(net "M_F_DQ<28>")
	)
	(gr_poly
		(pts
			(xy 247.040146 -64.3001) (xy 246.995696 -64.3001) (xy 246.825516 -64.389) (xy 246.825516 -64.60998)
			(xy 246.995696 -64.69888) (xy 247.040146 -64.69888)
		)
		(stroke
			(width 0)
			(type solid)
		)
		(fill yes)
		(layer "In11.Cu")
		(net "M_C_DQ<28>")
	)
	(gr_poly
		(pts
			(xy 247.040146 -63.3095) (xy 246.995696 -63.3095) (xy 246.825516 -63.3984) (xy 246.825516 -63.61938)
			(xy 246.995696 -63.70828) (xy 247.040146 -63.70828)
		)
		(stroke
			(width 0)
			(type solid)
		)
		(fill yes)
		(layer "In11.Cu")
		(net "M_C_DQ<28>")
	)
	(gr_poly
		(pts
			(xy 247.040146 -62.3189) (xy 246.995696 -62.3189) (xy 246.825516 -62.4078) (xy 246.825516 -62.62878)
			(xy 246.995696 -62.71768) (xy 247.040146 -62.71768)
		)
		(stroke
			(width 0)
			(type solid)
		)
		(fill yes)
		(layer "In11.Cu")
		(net "M_C_DQ<28>")
	)
	(gr_poly
		(pts
			(xy 247.040146 -61.3283) (xy 246.995696 -61.3283) (xy 246.825516 -61.4172) (xy 246.825516 -61.63818)
			(xy 246.995696 -61.72708) (xy 247.040146 -61.72708)
		)
		(stroke
			(width 0)
			(type solid)
		)
		(fill yes)
		(layer "In11.Cu")
		(net "M_C_DQ<28>")
	)
	(gr_poly
		(pts
			(xy 247.040146 -60.3377) (xy 246.995696 -60.3377) (xy 246.825516 -60.4266) (xy 246.825516 -60.64758)
			(xy 246.995696 -60.73648) (xy 247.040146 -60.73648)
		)
		(stroke
			(width 0)
			(type solid)
		)
		(fill yes)
		(layer "In11.Cu")
		(net "M_C_DQ<28>")
	)
	(gr_poly
		(pts
			(xy 247.040146 -59.3471) (xy 246.995696 -59.3471) (xy 246.825516 -59.436) (xy 246.825516 -59.65698)
			(xy 246.995696 -59.74588) (xy 247.040146 -59.74588)
		)
		(stroke
			(width 0)
			(type solid)
		)
		(fill yes)
		(layer "In11.Cu")
		(net "M_C_DQ<28>")
	)
	(gr_poly
		(pts
			(xy 247.040146 -58.368946) (xy 246.995696 -58.368946) (xy 246.825516 -58.457846) (xy 246.825516 -58.678826)
			(xy 246.995696 -58.767726) (xy 247.040146 -58.767726)
		)
		(stroke
			(width 0)
			(type solid)
		)
		(fill yes)
		(layer "In11.Cu")
		(net "M_C_DQ<28>")
	)
	(gr_poly
		(pts
			(xy 247.040146 -57.37225) (xy 246.995696 -57.37225) (xy 246.825516 -57.46115) (xy 246.825516 -57.68213)
			(xy 246.995696 -57.77103) (xy 247.040146 -57.77103)
		)
		(stroke
			(width 0)
			(type solid)
		)
		(fill yes)
		(layer "In11.Cu")
		(net "M_C_DQ<28>")
	)
	(gr_poly
		(pts
			(xy 247.040146 -56.3753) (xy 246.995696 -56.3753) (xy 246.825516 -56.4642) (xy 246.825516 -56.68518)
			(xy 246.995696 -56.77408) (xy 247.040146 -56.77408)
		)
		(stroke
			(width 0)
			(type solid)
		)
		(fill yes)
		(layer "In11.Cu")
		(net "M_C_DQ<28>")
	)
	(gr_poly
		(pts
			(xy 247.092216 -97.448624) (xy 247.133872 -97.261172) (xy 247.122696 -97.217992) (xy 246.737124 -97.32137)
			(xy 246.749062 -97.364296) (xy 246.878856 -97.50552)
		)
		(stroke
			(width 0)
			(type solid)
		)
		(fill yes)
		(layer "In11.Cu")
		(net "M_F_DQ<25>")
	)
	(gr_poly
		(pts
			(xy 247.18137 -52.440586) (xy 247.212866 -52.409344) (xy 246.925338 -52.121816) (xy 246.894096 -52.153312)
			(xy 246.820436 -52.352702) (xy 246.98198 -52.514246)
		)
		(stroke
			(width 0)
			(type solid)
		)
		(fill yes)
		(layer "In11.Cu")
		(net "M_C_DQS_DP<12>")
	)
	(gr_poly
		(pts
			(xy 247.26265 -54.3687) (xy 247.2182 -54.3687) (xy 247.02516 -54.4576) (xy 247.02516 -54.6862) (xy 247.2182 -54.7751)
			(xy 247.26265 -54.7751)
		)
		(stroke
			(width 0)
			(type solid)
		)
		(fill yes)
		(layer "In11.Cu")
		(net "M_C_DQ<24>")
	)
	(gr_poly
		(pts
			(xy 247.269 -98.26244) (xy 247.19534 -98.06305) (xy 247.163844 -98.031808) (xy 246.87657 -98.319082)
			(xy 246.908066 -98.350578) (xy 247.107456 -98.424238)
		)
		(stroke
			(width 0)
			(type solid)
		)
		(fill yes)
		(layer "In11.Cu")
		(net "M_F_DQS_DN<12>")
	)
	(gr_poly
		(pts
			(xy 247.28043 -95.355664) (xy 247.272556 -95.163894) (xy 247.250458 -95.12554) (xy 246.905018 -95.32493)
			(xy 246.927116 -95.363284) (xy 247.089168 -95.466154)
		)
		(stroke
			(width 0)
			(type solid)
		)
		(fill yes)
		(layer "In11.Cu")
		(net "M_F_DQ<29>")
	)
	(gr_poly
		(pts
			(xy 247.388888 -99.406456) (xy 247.357392 -99.375214) (xy 247.158002 -99.301554) (xy 246.996458 -99.463098)
			(xy 247.070118 -99.662488) (xy 247.10136 -99.693984)
		)
		(stroke
			(width 0)
			(type solid)
		)
		(fill yes)
		(layer "In11.Cu")
		(net "M_F_DQS_DN<3>")
	)
	(gr_poly
		(pts
			(xy 247.408192 -96.894904) (xy 247.578118 -96.806004) (xy 247.578372 -96.585278) (xy 247.408192 -96.496378)
			(xy 247.363488 -96.496124) (xy 247.363488 -96.895158)
		)
		(stroke
			(width 0)
			(type solid)
		)
		(fill yes)
		(layer "In11.Cu")
		(net "M_F_DQ<25>")
	)
	(gr_poly
		(pts
			(xy 247.504458 -95.595694) (xy 247.482106 -95.55734) (xy 247.320308 -95.45447) (xy 247.128792 -95.564706)
			(xy 247.13692 -95.756476) (xy 247.159272 -95.795338)
		)
		(stroke
			(width 0)
			(type solid)
		)
		(fill yes)
		(layer "In11.Cu")
		(net "M_F_DQ<24>")
	)
	(gr_poly
		(pts
			(xy 247.504458 -91.633294) (xy 247.482106 -91.59494) (xy 247.320308 -91.49207) (xy 247.128792 -91.602306)
			(xy 247.13692 -91.794076) (xy 247.159272 -91.832938)
		)
		(stroke
			(width 0)
			(type solid)
		)
		(fill yes)
		(layer "In11.Cu")
		(net "M_F_DQ<28>")
	)
	(gr_poly
		(pts
			(xy 247.531382 -52.395374) (xy 247.605042 -52.196238) (xy 247.443244 -52.03444) (xy 247.244108 -52.1081)
			(xy 247.212612 -52.139596) (xy 247.499886 -52.42687)
		)
		(stroke
			(width 0)
			(type solid)
		)
		(fill yes)
		(layer "In11.Cu")
		(net "M_C_DQS_DN<12>")
	)
	(gr_poly
		(pts
			(xy 247.578118 -94.818454) (xy 247.578118 -94.597474) (xy 247.407938 -94.508574) (xy 247.363742 -94.508574)
			(xy 247.363742 -94.907354) (xy 247.407938 -94.907354)
		)
		(stroke
			(width 0)
			(type solid)
		)
		(fill yes)
		(layer "In11.Cu")
		(net "M_F_DQ<29>")
	)
	(gr_poly
		(pts
			(xy 247.578372 -93.83268) (xy 247.578372 -93.6117) (xy 247.408192 -93.5228) (xy 247.363742 -93.5228)
			(xy 247.363742 -93.92158) (xy 247.408192 -93.92158)
		)
		(stroke
			(width 0)
			(type solid)
		)
		(fill yes)
		(layer "In11.Cu")
		(net "M_F_DQ<29>")
	)
	(gr_poly
		(pts
			(xy 247.578372 -92.854526) (xy 247.578372 -92.633546) (xy 247.408192 -92.544646) (xy 247.363742 -92.544646)
			(xy 247.363742 -92.943426) (xy 247.408192 -92.943426)
		)
		(stroke
			(width 0)
			(type solid)
		)
		(fill yes)
		(layer "In11.Cu")
		(net "M_F_DQ<29>")
	)
	(gr_poly
		(pts
			(xy 247.578372 -64.127126) (xy 247.578372 -63.906146) (xy 247.408192 -63.817246) (xy 247.363742 -63.817246)
			(xy 247.363742 -64.216026) (xy 247.408192 -64.216026)
		)
		(stroke
			(width 0)
			(type solid)
		)
		(fill yes)
		(layer "In11.Cu")
		(net "M_C_DQ<29>")
	)
	(gr_poly
		(pts
			(xy 247.578372 -63.136526) (xy 247.578372 -62.915546) (xy 247.408192 -62.826646) (xy 247.363742 -62.826646)
			(xy 247.363742 -63.225426) (xy 247.408192 -63.225426)
		)
		(stroke
			(width 0)
			(type solid)
		)
		(fill yes)
		(layer "In11.Cu")
		(net "M_C_DQ<29>")
	)
	(gr_poly
		(pts
			(xy 247.578372 -62.145926) (xy 247.578372 -61.924946) (xy 247.408192 -61.836046) (xy 247.363742 -61.836046)
			(xy 247.363742 -62.234826) (xy 247.408192 -62.234826)
		)
		(stroke
			(width 0)
			(type solid)
		)
		(fill yes)
		(layer "In11.Cu")
		(net "M_C_DQ<29>")
	)
	(gr_poly
		(pts
			(xy 247.578372 -61.155326) (xy 247.578372 -60.934346) (xy 247.408192 -60.845446) (xy 247.363742 -60.845446)
			(xy 247.363742 -61.244226) (xy 247.408192 -61.244226)
		)
		(stroke
			(width 0)
			(type solid)
		)
		(fill yes)
		(layer "In11.Cu")
		(net "M_C_DQ<29>")
	)
	(gr_poly
		(pts
			(xy 247.578372 -60.164726) (xy 247.578372 -59.943746) (xy 247.408192 -59.854846) (xy 247.363742 -59.854846)
			(xy 247.363742 -60.253626) (xy 247.408192 -60.253626)
		)
		(stroke
			(width 0)
			(type solid)
		)
		(fill yes)
		(layer "In11.Cu")
		(net "M_C_DQ<29>")
	)
	(gr_poly
		(pts
			(xy 247.578372 -59.167776) (xy 247.578372 -58.946796) (xy 247.408192 -58.857896) (xy 247.363742 -58.857896)
			(xy 247.363742 -59.256676) (xy 247.408192 -59.256676)
		)
		(stroke
			(width 0)
			(type solid)
		)
		(fill yes)
		(layer "In11.Cu")
		(net "M_C_DQ<29>")
	)
	(gr_poly
		(pts
			(xy 247.578372 -58.17108) (xy 247.578372 -57.9501) (xy 247.408192 -57.8612) (xy 247.363742 -57.8612)
			(xy 247.363742 -58.25998) (xy 247.408192 -58.25998)
		)
		(stroke
			(width 0)
			(type solid)
		)
		(fill yes)
		(layer "In11.Cu")
		(net "M_C_DQ<29>")
	)
	(gr_poly
		(pts
			(xy 247.578372 -57.192926) (xy 247.578372 -56.971946) (xy 247.408192 -56.883046) (xy 247.363742 -56.883046)
			(xy 247.363742 -57.281826) (xy 247.408192 -57.281826)
		)
		(stroke
			(width 0)
			(type solid)
		)
		(fill yes)
		(layer "In11.Cu")
		(net "M_C_DQ<29>")
	)
	(gr_poly
		(pts
			(xy 247.578372 -56.195976) (xy 247.578372 -55.974996) (xy 247.408192 -55.886096) (xy 247.363742 -55.886096)
			(xy 247.363742 -56.284876) (xy 247.408192 -56.284876)
		)
		(stroke
			(width 0)
			(type solid)
		)
		(fill yes)
		(layer "In11.Cu")
		(net "M_C_DQ<29>")
	)
	(gr_poly
		(pts
			(xy 247.628664 -99.771962) (xy 247.555004 -99.572826) (xy 247.523508 -99.54133) (xy 247.236234 -99.828604)
			(xy 247.26773 -99.8601) (xy 247.466866 -99.93376)
		)
		(stroke
			(width 0)
			(type solid)
		)
		(fill yes)
		(layer "In11.Cu")
		(net "M_F_DQS_DP<3>")
	)
	(gr_poly
		(pts
			(xy 247.69064 -54.651402) (xy 247.69064 -54.422802) (xy 247.497346 -54.333902) (xy 247.45315 -54.333648)
			(xy 247.45315 -54.740302) (xy 247.497346 -54.740302)
		)
		(stroke
			(width 0)
			(type solid)
		)
		(fill yes)
		(layer "In11.Cu")
		(net "M_C_DQ<25>")
	)
	(gr_poly
		(pts
			(xy 247.69191 -55.46725) (xy 247.723406 -55.435754) (xy 247.435878 -55.14848) (xy 247.404636 -55.179976)
			(xy 247.330976 -55.379112) (xy 247.49252 -55.54091)
		)
		(stroke
			(width 0)
			(type solid)
		)
		(fill yes)
		(layer "In11.Cu")
		(net "M_C_DQ<24>")
	)
	(gr_poly
		(pts
			(xy 247.712992 -102.044246) (xy 247.681496 -102.013004) (xy 247.482106 -101.939344) (xy 247.320562 -102.100888)
			(xy 247.394222 -102.300278) (xy 247.425464 -102.331774)
		)
		(stroke
			(width 0)
			(type solid)
		)
		(fill yes)
		(layer "In11.Cu")
		(net "M_F_DQ<30>")
	)
	(gr_poly
		(pts
			(xy 247.729756 -97.196402) (xy 247.69826 -97.16516) (xy 247.49887 -97.0915) (xy 247.337326 -97.253044)
			(xy 247.410986 -97.452434) (xy 247.442228 -97.48393)
		)
		(stroke
			(width 0)
			(type solid)
		)
		(fill yes)
		(layer "In11.Cu")
		(net "M_F_DQS_DP<12>")
	)
	(gr_poly
		(pts
			(xy 247.747536 -50.419762) (xy 247.703086 -50.420016) (xy 247.510046 -50.508916) (xy 247.510046 -50.737262)
			(xy 247.703086 -50.826162) (xy 247.747536 -50.826416)
		)
		(stroke
			(width 0)
			(type solid)
		)
		(fill yes)
		(layer "In11.Cu")
		(net "M_C_DQS_DP<3>")
	)
	(gr_poly
		(pts
			(xy 247.829832 -100.92944) (xy 247.785382 -100.92944) (xy 247.592342 -101.01834) (xy 247.592342 -101.24694)
			(xy 247.785382 -101.33584) (xy 247.829832 -101.33584)
		)
		(stroke
			(width 0)
			(type solid)
		)
		(fill yes)
		(layer "In11.Cu")
		(net "M_F_DQ<30>")
	)
	(gr_poly
		(pts
			(xy 247.894602 -55.70601) (xy 247.850152 -55.70601) (xy 247.679972 -55.79491) (xy 247.679972 -56.01589)
			(xy 247.850152 -56.10479) (xy 247.894602 -56.10479)
		)
		(stroke
			(width 0)
			(type solid)
		)
		(fill yes)
		(layer "In11.Cu")
		(net "M_C_DQ<24>")
	)
	(gr_poly
		(pts
			(xy 247.898666 -94.519496) (xy 247.854216 -94.519496) (xy 247.684036 -94.608396) (xy 247.684036 -94.829376)
			(xy 247.854216 -94.918276) (xy 247.898666 -94.918276)
		)
		(stroke
			(width 0)
			(type solid)
		)
		(fill yes)
		(layer "In11.Cu")
		(net "M_F_DQ<24>")
	)
	(gr_poly
		(pts
			(xy 247.898666 -93.5228) (xy 247.854216 -93.5228) (xy 247.684036 -93.6117) (xy 247.684036 -93.83268)
			(xy 247.854216 -93.92158) (xy 247.898666 -93.92158)
		)
		(stroke
			(width 0)
			(type solid)
		)
		(fill yes)
		(layer "In11.Cu")
		(net "M_F_DQ<24>")
	)
	(gr_poly
		(pts
			(xy 247.898666 -90.563446) (xy 247.854216 -90.563446) (xy 247.684036 -90.652346) (xy 247.684036 -90.873326)
			(xy 247.854216 -90.962226) (xy 247.898666 -90.962226)
		)
		(stroke
			(width 0)
			(type solid)
		)
		(fill yes)
		(layer "In11.Cu")
		(net "M_F_DQ<28>")
	)
	(gr_poly
		(pts
			(xy 247.898666 -89.572846) (xy 247.854216 -89.572846) (xy 247.684036 -89.661746) (xy 247.684036 -89.882726)
			(xy 247.854216 -89.971626) (xy 247.898666 -89.971626)
		)
		(stroke
			(width 0)
			(type solid)
		)
		(fill yes)
		(layer "In11.Cu")
		(net "M_F_DQ<28>")
	)
	(gr_poly
		(pts
			(xy 247.898666 -88.582246) (xy 247.854216 -88.582246) (xy 247.684036 -88.671146) (xy 247.684036 -88.892126)
			(xy 247.854216 -88.981026) (xy 247.898666 -88.981026)
		)
		(stroke
			(width 0)
			(type solid)
		)
		(fill yes)
		(layer "In11.Cu")
		(net "M_F_DQ<28>")
	)
	(gr_poly
		(pts
			(xy 247.898666 -87.591646) (xy 247.854216 -87.591646) (xy 247.684036 -87.680546) (xy 247.684036 -87.901526)
			(xy 247.854216 -87.990426) (xy 247.898666 -87.990426)
		)
		(stroke
			(width 0)
			(type solid)
		)
		(fill yes)
		(layer "In11.Cu")
		(net "M_F_DQ<28>")
	)
	(gr_poly
		(pts
			(xy 247.898666 -86.601046) (xy 247.854216 -86.601046) (xy 247.684036 -86.689946) (xy 247.684036 -86.910926)
			(xy 247.854216 -86.999826) (xy 247.898666 -86.999826)
		)
		(stroke
			(width 0)
			(type solid)
		)
		(fill yes)
		(layer "In11.Cu")
		(net "M_F_DQ<28>")
	)
	(gr_poly
		(pts
			(xy 247.898666 -63.81115) (xy 247.854216 -63.81115) (xy 247.684036 -63.90005) (xy 247.684036 -64.12103)
			(xy 247.854216 -64.20993) (xy 247.898666 -64.20993)
		)
		(stroke
			(width 0)
			(type solid)
		)
		(fill yes)
		(layer "In11.Cu")
		(net "M_C_DQ<24>")
	)
	(gr_poly
		(pts
			(xy 247.898666 -62.826646) (xy 247.854216 -62.826646) (xy 247.684036 -62.915546) (xy 247.684036 -63.136526)
			(xy 247.854216 -63.225426) (xy 247.898666 -63.225426)
		)
		(stroke
			(width 0)
			(type solid)
		)
		(fill yes)
		(layer "In11.Cu")
		(net "M_C_DQ<24>")
	)
	(gr_poly
		(pts
			(xy 247.898666 -61.836046) (xy 247.854216 -61.836046) (xy 247.684036 -61.924946) (xy 247.684036 -62.145926)
			(xy 247.854216 -62.234826) (xy 247.898666 -62.234826)
		)
		(stroke
			(width 0)
			(type solid)
		)
		(fill yes)
		(layer "In11.Cu")
		(net "M_C_DQ<24>")
	)
	(gr_poly
		(pts
			(xy 247.898666 -60.845446) (xy 247.854216 -60.845446) (xy 247.684036 -60.934346) (xy 247.684036 -61.155326)
			(xy 247.854216 -61.244226) (xy 247.898666 -61.244226)
		)
		(stroke
			(width 0)
			(type solid)
		)
		(fill yes)
		(layer "In11.Cu")
		(net "M_C_DQ<24>")
	)
	(gr_poly
		(pts
			(xy 247.898666 -59.854846) (xy 247.854216 -59.854846) (xy 247.684036 -59.943746) (xy 247.684036 -60.164726)
			(xy 247.854216 -60.253626) (xy 247.898666 -60.253626)
		)
		(stroke
			(width 0)
			(type solid)
		)
		(fill yes)
		(layer "In11.Cu")
		(net "M_C_DQ<24>")
	)
	(gr_poly
		(pts
			(xy 247.898666 -58.857896) (xy 247.854216 -58.857896) (xy 247.684036 -58.946796) (xy 247.684036 -59.167776)
			(xy 247.854216 -59.256676) (xy 247.898666 -59.256676)
		)
		(stroke
			(width 0)
			(type solid)
		)
		(fill yes)
		(layer "In11.Cu")
		(net "M_C_DQ<24>")
	)
	(gr_poly
		(pts
			(xy 247.898666 -57.8612) (xy 247.854216 -57.8612) (xy 247.684036 -57.9501) (xy 247.684036 -58.17108)
			(xy 247.854216 -58.25998) (xy 247.898666 -58.25998)
		)
		(stroke
			(width 0)
			(type solid)
		)
		(fill yes)
		(layer "In11.Cu")
		(net "M_C_DQ<24>")
	)
	(gr_poly
		(pts
			(xy 247.898666 -56.883046) (xy 247.854216 -56.883046) (xy 247.684036 -56.971946) (xy 247.684036 -57.192926)
			(xy 247.854216 -57.281826) (xy 247.898666 -57.281826)
		)
		(stroke
			(width 0)
			(type solid)
		)
		(fill yes)
		(layer "In11.Cu")
		(net "M_C_DQ<24>")
	)
	(gr_poly
		(pts
			(xy 247.89892 -92.53855) (xy 247.85447 -92.53855) (xy 247.68429 -92.62745) (xy 247.68429 -92.84843)
			(xy 247.85447 -92.93733) (xy 247.89892 -92.93733)
		)
		(stroke
			(width 0)
			(type solid)
		)
		(fill yes)
		(layer "In11.Cu")
		(net "M_F_DQ<24>")
	)
	(gr_poly
		(pts
			(xy 247.91797 -53.177186) (xy 247.949466 -53.145944) (xy 247.661938 -52.858416) (xy 247.630696 -52.889912)
			(xy 247.557036 -53.089302) (xy 247.71858 -53.250846)
		)
		(stroke
			(width 0)
			(type solid)
		)
		(fill yes)
		(layer "In11.Cu")
		(net "M_C_DQS_DP<12>")
	)
	(gr_poly
		(pts
			(xy 247.943878 -55.324502) (xy 248.017538 -55.125366) (xy 247.85574 -54.963568) (xy 247.656604 -55.037228)
			(xy 247.625108 -55.068724) (xy 247.912382 -55.355998)
		)
		(stroke
			(width 0)
			(type solid)
		)
		(fill yes)
		(layer "In11.Cu")
		(net "M_C_DQ<25>")
	)
	(gr_poly
		(pts
			(xy 247.969532 -97.561908) (xy 247.895872 -97.362772) (xy 247.864376 -97.331276) (xy 247.577102 -97.61855)
			(xy 247.608598 -97.650046) (xy 247.807734 -97.723706)
		)
		(stroke
			(width 0)
			(type solid)
		)
		(fill yes)
		(layer "In11.Cu")
		(net "M_F_DQS_DN<12>")
	)
	(gr_poly
		(pts
			(xy 247.982994 -102.389432) (xy 247.909334 -102.190042) (xy 247.878092 -102.158546) (xy 247.590564 -102.446074)
			(xy 247.62206 -102.477316) (xy 247.82145 -102.550976)
		)
		(stroke
			(width 0)
			(type solid)
		)
		(fill yes)
		(layer "In11.Cu")
		(net "M_F_DQ<31>")
	)
	(gr_poly
		(pts
			(xy 248.089166 -98.706178) (xy 248.057924 -98.674682) (xy 247.858534 -98.601022) (xy 247.696736 -98.762566)
			(xy 247.770396 -98.961956) (xy 247.801892 -98.993452)
		)
		(stroke
			(width 0)
			(type solid)
		)
		(fill yes)
		(layer "In11.Cu")
		(net "M_F_DQS_DN<3>")
	)
	(gr_poly
		(pts
			(xy 248.121424 -53.862224) (xy 248.076974 -53.862224) (xy 247.883934 -53.951124) (xy 247.883934 -54.179724)
			(xy 248.076974 -54.268624) (xy 248.121424 -54.268624)
		)
		(stroke
			(width 0)
			(type solid)
		)
		(fill yes)
		(layer "In11.Cu")
		(net "M_C_DQS_DP<12>")
	)
	(gr_poly
		(pts
			(xy 248.137172 -95.852488) (xy 248.129044 -95.660464) (xy 248.106946 -95.621856) (xy 247.76176 -95.8215)
			(xy 247.783858 -95.859854) (xy 247.94591 -95.962724)
		)
		(stroke
			(width 0)
			(type solid)
		)
		(fill yes)
		(layer "In11.Cu")
		(net "M_F_DQ<25>")
	)
	(gr_poly
		(pts
			(xy 248.137172 -91.890088) (xy 248.129044 -91.698064) (xy 248.106946 -91.659456) (xy 247.76176 -91.8591)
			(xy 247.783858 -91.897454) (xy 247.94591 -92.000324)
		)
		(stroke
			(width 0)
			(type solid)
		)
		(fill yes)
		(layer "In11.Cu")
		(net "M_F_DQ<29>")
	)
	(gr_poly
		(pts
			(xy 248.166636 -100.00107) (xy 248.13514 -99.969574) (xy 247.93575 -99.895914) (xy 247.774206 -100.057712)
			(xy 247.847866 -100.257102) (xy 247.879362 -100.288344)
		)
		(stroke
			(width 0)
			(type solid)
		)
		(fill yes)
		(layer "In11.Cu")
		(net "M_F_DQ<30>")
	)
	(gr_poly
		(pts
			(xy 248.175272 -51.307492) (xy 248.175272 -51.078638) (xy 247.982232 -50.989992) (xy 247.937782 -50.989992)
			(xy 247.937782 -51.396138) (xy 247.982232 -51.396138)
		)
		(stroke
			(width 0)
			(type solid)
		)
		(fill yes)
		(layer "In11.Cu")
		(net "M_C_DQS_DN<3>")
	)
	(gr_poly
		(pts
			(xy 248.242582 -53.106574) (xy 248.316242 -52.907438) (xy 248.154444 -52.74564) (xy 247.955308 -52.8193)
			(xy 247.923812 -52.850796) (xy 248.211086 -53.13807)
		)
		(stroke
			(width 0)
			(type solid)
		)
		(fill yes)
		(layer "In11.Cu")
		(net "M_C_DQS_DN<12>")
	)
	(gr_poly
		(pts
			(xy 248.257314 -101.24694) (xy 248.257314 -101.01834) (xy 248.064274 -100.92944) (xy 248.019824 -100.92944)
			(xy 248.019824 -101.33584) (xy 248.064274 -101.33584)
		)
		(stroke
			(width 0)
			(type solid)
		)
		(fill yes)
		(layer "In11.Cu")
		(net "M_F_DQ<31>")
	)
	(gr_poly
		(pts
			(xy 248.27611 -64.835278) (xy 248.312432 -64.809878) (xy 248.083832 -64.483234) (xy 248.047256 -64.508634)
			(xy 247.958864 -64.679068) (xy 248.08561 -64.86017)
		)
		(stroke
			(width 0)
			(type solid)
		)
		(fill yes)
		(layer "In11.Cu")
		(net "M_C_DQ<24>")
	)
	(gr_poly
		(pts
			(xy 248.329196 -99.071684) (xy 248.255536 -98.872294) (xy 248.22404 -98.840798) (xy 247.936766 -99.128072)
			(xy 247.968008 -99.159568) (xy 248.167398 -99.233228)
		)
		(stroke
			(width 0)
			(type solid)
		)
		(fill yes)
		(layer "In11.Cu")
		(net "M_F_DQS_DP<3>")
	)
	(gr_poly
		(pts
			(xy 248.357644 -66.682112) (xy 248.19737 -66.31686) (xy 248.15673 -66.33464) (xy 248.036588 -66.4845)
			(xy 248.125234 -66.686684) (xy 248.317004 -66.700146)
		)
		(stroke
			(width 0)
			(type solid)
		)
		(fill yes)
		(layer "In11.Cu")
		(net "M_C_DQ<25>")
	)
	(gr_poly
		(pts
			(xy 248.366788 -92.126562) (xy 248.344436 -92.087954) (xy 248.182384 -91.985084) (xy 247.991122 -92.095574)
			(xy 247.99925 -92.287344) (xy 248.021348 -92.325952)
		)
		(stroke
			(width 0)
			(type solid)
		)
		(fill yes)
		(layer "In11.Cu")
		(net "M_F_DQ<24>")
	)
	(gr_poly
		(pts
			(xy 248.406158 -100.366322) (xy 248.332498 -100.166932) (xy 248.301002 -100.135436) (xy 248.013728 -100.42271)
			(xy 248.04497 -100.454206) (xy 248.24436 -100.527866)
		)
		(stroke
			(width 0)
			(type solid)
		)
		(fill yes)
		(layer "In11.Cu")
		(net "M_F_DQ<31>")
	)
	(gr_poly
		(pts
			(xy 248.430034 -96.496124) (xy 248.398792 -96.464628) (xy 248.199402 -96.390968) (xy 248.037604 -96.552512)
			(xy 248.111264 -96.751902) (xy 248.14276 -96.783398)
		)
		(stroke
			(width 0)
			(type solid)
		)
		(fill yes)
		(layer "In11.Cu")
		(net "M_F_DQS_DP<12>")
	)
	(gr_poly
		(pts
			(xy 248.436638 -95.31604) (xy 248.436638 -95.095314) (xy 248.266458 -95.006414) (xy 248.222008 -95.00616)
			(xy 248.222262 -95.40494) (xy 248.266458 -95.40494)
		)
		(stroke
			(width 0)
			(type solid)
		)
		(fill yes)
		(layer "In11.Cu")
		(net "M_F_DQ<25>")
	)
	(gr_poly
		(pts
			(xy 248.436638 -93.343984) (xy 248.436638 -93.123004) (xy 248.266458 -93.034104) (xy 248.222008 -93.034104)
			(xy 248.222008 -93.432884) (xy 248.266458 -93.432884)
		)
		(stroke
			(width 0)
			(type solid)
		)
		(fill yes)
		(layer "In11.Cu")
		(net "M_F_DQ<25>")
	)
	(gr_poly
		(pts
			(xy 248.436638 -91.35364) (xy 248.436638 -91.132914) (xy 248.266458 -91.044014) (xy 248.222008 -91.04376)
			(xy 248.222262 -91.44254) (xy 248.266458 -91.44254)
		)
		(stroke
			(width 0)
			(type solid)
		)
		(fill yes)
		(layer "In11.Cu")
		(net "M_F_DQ<29>")
	)
	(gr_poly
		(pts
			(xy 248.436638 -63.62573) (xy 248.436638 -63.40475) (xy 248.266458 -63.31585) (xy 248.222008 -63.31585)
			(xy 248.222008 -63.71463) (xy 248.266458 -63.71463)
		)
		(stroke
			(width 0)
			(type solid)
		)
		(fill yes)
		(layer "In11.Cu")
		(net "M_C_DQ<25>")
	)
	(gr_poly
		(pts
			(xy 248.436892 -94.340426) (xy 248.436892 -94.119446) (xy 248.266712 -94.030546) (xy 248.222262 -94.030546)
			(xy 248.222262 -94.429326) (xy 248.266712 -94.429326)
		)
		(stroke
			(width 0)
			(type solid)
		)
		(fill yes)
		(layer "In11.Cu")
		(net "M_F_DQ<25>")
	)
	(gr_poly
		(pts
			(xy 248.436892 -90.36558) (xy 248.436892 -90.1446) (xy 248.266712 -90.0557) (xy 248.222262 -90.0557)
			(xy 248.222262 -90.45448) (xy 248.266712 -90.45448)
		)
		(stroke
			(width 0)
			(type solid)
		)
		(fill yes)
		(layer "In11.Cu")
		(net "M_F_DQ<29>")
	)
	(gr_poly
		(pts
			(xy 248.436892 -89.37498) (xy 248.436892 -89.154) (xy 248.266712 -89.0651) (xy 248.222262 -89.0651)
			(xy 248.222262 -89.46388) (xy 248.266712 -89.46388)
		)
		(stroke
			(width 0)
			(type solid)
		)
		(fill yes)
		(layer "In11.Cu")
		(net "M_F_DQ<29>")
	)
	(gr_poly
		(pts
			(xy 248.436892 -88.38438) (xy 248.436892 -88.1634) (xy 248.266712 -88.0745) (xy 248.222262 -88.0745)
			(xy 248.222262 -88.47328) (xy 248.266712 -88.47328)
		)
		(stroke
			(width 0)
			(type solid)
		)
		(fill yes)
		(layer "In11.Cu")
		(net "M_F_DQ<29>")
	)
	(gr_poly
		(pts
			(xy 248.436892 -62.62878) (xy 248.436892 -62.4078) (xy 248.266712 -62.3189) (xy 248.222262 -62.3189)
			(xy 248.222262 -62.71768) (xy 248.266712 -62.71768)
		)
		(stroke
			(width 0)
			(type solid)
		)
		(fill yes)
		(layer "In11.Cu")
		(net "M_C_DQ<25>")
	)
	(gr_poly
		(pts
			(xy 248.436892 -61.63818) (xy 248.436892 -61.4172) (xy 248.266712 -61.3283) (xy 248.222262 -61.3283)
			(xy 248.222262 -61.72708) (xy 248.266712 -61.72708)
		)
		(stroke
			(width 0)
			(type solid)
		)
		(fill yes)
		(layer "In11.Cu")
		(net "M_C_DQ<25>")
	)
	(gr_poly
		(pts
			(xy 248.436892 -60.64758) (xy 248.436892 -60.4266) (xy 248.266712 -60.3377) (xy 248.222262 -60.3377)
			(xy 248.222262 -60.73648) (xy 248.266712 -60.73648)
		)
		(stroke
			(width 0)
			(type solid)
		)
		(fill yes)
		(layer "In11.Cu")
		(net "M_C_DQ<25>")
	)
	(gr_poly
		(pts
			(xy 248.436892 -59.65698) (xy 248.436892 -59.436) (xy 248.266712 -59.3471) (xy 248.222262 -59.3471)
			(xy 248.222262 -59.74588) (xy 248.266712 -59.74588)
		)
		(stroke
			(width 0)
			(type solid)
		)
		(fill yes)
		(layer "In11.Cu")
		(net "M_C_DQ<25>")
	)
	(gr_poly
		(pts
			(xy 248.436892 -58.678826) (xy 248.436892 -58.457846) (xy 248.266712 -58.368946) (xy 248.222262 -58.368946)
			(xy 248.222262 -58.767726) (xy 248.266712 -58.767726)
		)
		(stroke
			(width 0)
			(type solid)
		)
		(fill yes)
		(layer "In11.Cu")
		(net "M_C_DQ<25>")
	)
	(gr_poly
		(pts
			(xy 248.436892 -57.68213) (xy 248.436892 -57.46115) (xy 248.266712 -57.37225) (xy 248.222262 -57.37225)
			(xy 248.222262 -57.77103) (xy 248.266712 -57.77103)
		)
		(stroke
			(width 0)
			(type solid)
		)
		(fill yes)
		(layer "In11.Cu")
		(net "M_C_DQ<25>")
	)
	(gr_poly
		(pts
			(xy 248.436892 -56.68518) (xy 248.436892 -56.4642) (xy 248.266712 -56.3753) (xy 248.222262 -56.3753)
			(xy 248.222262 -56.77408) (xy 248.266712 -56.77408)
		)
		(stroke
			(width 0)
			(type solid)
		)
		(fill yes)
		(layer "In11.Cu")
		(net "M_C_DQ<25>")
	)
	(gr_poly
		(pts
			(xy 248.471182 -50.56632) (xy 248.426732 -50.56632) (xy 248.233692 -50.654966) (xy 248.233692 -50.88382)
			(xy 248.426732 -50.972466) (xy 248.471182 -50.972466)
		)
		(stroke
			(width 0)
			(type solid)
		)
		(fill yes)
		(layer "In11.Cu")
		(net "M_C_DQ<30>")
	)
	(gr_poly
		(pts
			(xy 248.50598 -52.575968) (xy 248.537476 -52.544726) (xy 248.249948 -52.257198) (xy 248.218706 -52.288694)
			(xy 248.145046 -52.488084) (xy 248.30659 -52.649628)
		)
		(stroke
			(width 0)
			(type solid)
		)
		(fill yes)
		(layer "In11.Cu")
		(net "M_C_DQS_DP<3>")
	)
	(gr_poly
		(pts
			(xy 248.549414 -54.306724) (xy 248.549414 -54.078124) (xy 248.356374 -53.989224) (xy 248.311924 -53.989224)
			(xy 248.311924 -54.395624) (xy 248.356374 -54.395624)
		)
		(stroke
			(width 0)
			(type solid)
		)
		(fill yes)
		(layer "In11.Cu")
		(net "M_C_DQS_DN<12>")
	)
	(gr_poly
		(pts
			(xy 248.616724 -97.651062) (xy 248.572274 -97.651062) (xy 248.379234 -97.739962) (xy 248.379234 -97.968562)
			(xy 248.572274 -98.057462) (xy 248.616724 -98.057462)
		)
		(stroke
			(width 0)
			(type solid)
		)
		(fill yes)
		(layer "In11.Cu")
		(net "M_F_DQS_DN<3>")
	)
	(gr_poly
		(pts
			(xy 248.636282 -55.6133) (xy 248.67489 -55.590948) (xy 248.4755 -55.245762) (xy 248.436892 -55.26786)
			(xy 248.334022 -55.429912) (xy 248.444512 -55.621428)
		)
		(stroke
			(width 0)
			(type solid)
		)
		(fill yes)
		(layer "In11.Cu")
		(net "M_C_DQS_DP<12>")
	)
	(gr_poly
		(pts
			(xy 248.670064 -96.86163) (xy 248.596404 -96.66224) (xy 248.564908 -96.630744) (xy 248.277634 -96.918018)
			(xy 248.308876 -96.949514) (xy 248.508266 -97.023174)
		)
		(stroke
			(width 0)
			(type solid)
		)
		(fill yes)
		(layer "In11.Cu")
		(net "M_F_DQS_DN<12>")
	)
	(gr_poly
		(pts
			(xy 248.703592 -52.378356) (xy 248.777252 -52.17922) (xy 248.615454 -52.017422) (xy 248.416318 -52.091082)
			(xy 248.384822 -52.122578) (xy 248.672096 -52.409852)
		)
		(stroke
			(width 0)
			(type solid)
		)
		(fill yes)
		(layer "In11.Cu")
		(net "M_C_DQS_DN<3>")
	)
	(gr_poly
		(pts
			(xy 248.705624 -101.500432) (xy 248.661174 -101.500432) (xy 248.468134 -101.589332) (xy 248.468134 -101.817932)
			(xy 248.661174 -101.906832) (xy 248.705624 -101.906832)
		)
		(stroke
			(width 0)
			(type solid)
		)
		(fill yes)
		(layer "In11.Cu")
		(net "M_F_DQ<26>")
	)
	(gr_poly
		(pts
			(xy 248.757186 -95.0087) (xy 248.712736 -95.0087) (xy 248.542556 -95.0976) (xy 248.542556 -95.31858)
			(xy 248.712736 -95.40748) (xy 248.757186 -95.40748)
		)
		(stroke
			(width 0)
			(type solid)
		)
		(fill yes)
		(layer "In11.Cu")
		(net "M_F_DQS_DP<12>")
	)
	(gr_poly
		(pts
			(xy 248.757186 -94.030546) (xy 248.712736 -94.030546) (xy 248.542556 -94.119446) (xy 248.542556 -94.340426)
			(xy 248.712736 -94.429326) (xy 248.757186 -94.429326)
		)
		(stroke
			(width 0)
			(type solid)
		)
		(fill yes)
		(layer "In11.Cu")
		(net "M_F_DQS_DP<12>")
	)
	(gr_poly
		(pts
			(xy 248.757186 -93.044772) (xy 248.71299 -93.044772) (xy 248.54281 -93.133672) (xy 248.54281 -93.354652)
			(xy 248.71299 -93.443552) (xy 248.75744 -93.443552)
		)
		(stroke
			(width 0)
			(type solid)
		)
		(fill yes)
		(layer "In11.Cu")
		(net "M_F_DQS_DP<12>")
	)
	(gr_poly
		(pts
			(xy 248.757186 -91.052904) (xy 248.712736 -91.052904) (xy 248.542556 -91.141804) (xy 248.542556 -91.362784)
			(xy 248.712736 -91.451684) (xy 248.757186 -91.451684)
		)
		(stroke
			(width 0)
			(type solid)
		)
		(fill yes)
		(layer "In11.Cu")
		(net "M_F_DQ<24>")
	)
	(gr_poly
		(pts
			(xy 248.757186 -90.062304) (xy 248.712736 -90.062304) (xy 248.542556 -90.151204) (xy 248.542556 -90.372184)
			(xy 248.712736 -90.461084) (xy 248.757186 -90.461084)
		)
		(stroke
			(width 0)
			(type solid)
		)
		(fill yes)
		(layer "In11.Cu")
		(net "M_F_DQ<24>")
	)
	(gr_poly
		(pts
			(xy 248.757186 -89.071704) (xy 248.712736 -89.071704) (xy 248.542556 -89.160604) (xy 248.542556 -89.381584)
			(xy 248.712736 -89.470484) (xy 248.757186 -89.470484)
		)
		(stroke
			(width 0)
			(type solid)
		)
		(fill yes)
		(layer "In11.Cu")
		(net "M_F_DQ<24>")
	)
	(gr_poly
		(pts
			(xy 248.757186 -88.081104) (xy 248.712736 -88.081104) (xy 248.542556 -88.170004) (xy 248.542556 -88.390984)
			(xy 248.712736 -88.479884) (xy 248.757186 -88.479884)
		)
		(stroke
			(width 0)
			(type solid)
		)
		(fill yes)
		(layer "In11.Cu")
		(net "M_F_DQ<24>")
	)
	(gr_poly
		(pts
			(xy 248.757186 -87.090504) (xy 248.712736 -87.090504) (xy 248.542556 -87.179404) (xy 248.542556 -87.400384)
			(xy 248.712736 -87.489284) (xy 248.757186 -87.489284)
		)
		(stroke
			(width 0)
			(type solid)
		)
		(fill yes)
		(layer "In11.Cu")
		(net "M_F_DQ<24>")
	)
	(gr_poly
		(pts
			(xy 248.757186 -63.3095) (xy 248.712736 -63.3095) (xy 248.542556 -63.3984) (xy 248.542556 -63.61938)
			(xy 248.712736 -63.70828) (xy 248.757186 -63.70828)
		)
		(stroke
			(width 0)
			(type solid)
		)
		(fill yes)
		(layer "In11.Cu")
		(net "M_C_DQS_DP<12>")
	)
	(gr_poly
		(pts
			(xy 248.757186 -62.3189) (xy 248.712736 -62.3189) (xy 248.542556 -62.4078) (xy 248.542556 -62.62878)
			(xy 248.712736 -62.71768) (xy 248.757186 -62.71768)
		)
		(stroke
			(width 0)
			(type solid)
		)
		(fill yes)
		(layer "In11.Cu")
		(net "M_C_DQS_DP<12>")
	)
	(gr_poly
		(pts
			(xy 248.757186 -61.3283) (xy 248.712736 -61.3283) (xy 248.542556 -61.4172) (xy 248.542556 -61.63818)
			(xy 248.712736 -61.72708) (xy 248.757186 -61.72708)
		)
		(stroke
			(width 0)
			(type solid)
		)
		(fill yes)
		(layer "In11.Cu")
		(net "M_C_DQS_DP<12>")
	)
	(gr_poly
		(pts
			(xy 248.757186 -60.3377) (xy 248.712736 -60.3377) (xy 248.542556 -60.4266) (xy 248.542556 -60.64758)
			(xy 248.712736 -60.73648) (xy 248.757186 -60.73648)
		)
		(stroke
			(width 0)
			(type solid)
		)
		(fill yes)
		(layer "In11.Cu")
		(net "M_C_DQS_DP<12>")
	)
	(gr_poly
		(pts
			(xy 248.757186 -59.3471) (xy 248.712736 -59.3471) (xy 248.542556 -59.436) (xy 248.542556 -59.65698)
			(xy 248.712736 -59.74588) (xy 248.757186 -59.74588)
		)
		(stroke
			(width 0)
			(type solid)
		)
		(fill yes)
		(layer "In11.Cu")
		(net "M_C_DQS_DP<12>")
	)
	(gr_poly
		(pts
			(xy 248.757186 -58.368946) (xy 248.712736 -58.368946) (xy 248.542556 -58.457846) (xy 248.542556 -58.678826)
			(xy 248.712736 -58.767726) (xy 248.757186 -58.767726)
		)
		(stroke
			(width 0)
			(type solid)
		)
		(fill yes)
		(layer "In11.Cu")
		(net "M_C_DQS_DP<12>")
	)
	(gr_poly
		(pts
			(xy 248.757186 -57.37225) (xy 248.712736 -57.37225) (xy 248.542556 -57.46115) (xy 248.542556 -57.68213)
			(xy 248.712736 -57.77103) (xy 248.757186 -57.77103)
		)
		(stroke
			(width 0)
			(type solid)
		)
		(fill yes)
		(layer "In11.Cu")
		(net "M_C_DQS_DP<12>")
	)
	(gr_poly
		(pts
			(xy 248.757186 -56.3753) (xy 248.712736 -56.3753) (xy 248.542556 -56.4642) (xy 248.542556 -56.68518)
			(xy 248.712736 -56.77408) (xy 248.757186 -56.77408)
		)
		(stroke
			(width 0)
			(type solid)
		)
		(fill yes)
		(layer "In11.Cu")
		(net "M_C_DQS_DP<12>")
	)
	(gr_poly
		(pts
			(xy 248.833894 -51.821588) (xy 248.86539 -51.790092) (xy 248.578116 -51.502818) (xy 248.54662 -51.534314)
			(xy 248.47296 -51.73345) (xy 248.634758 -51.895248)
		)
		(stroke
			(width 0)
			(type solid)
		)
		(fill yes)
		(layer "In11.Cu")
		(net "M_C_DQ<30>")
	)
	(gr_poly
		(pts
			(xy 248.846594 -65.535048) (xy 248.805446 -65.347342) (xy 248.776744 -65.313306) (xy 248.471436 -65.569846)
			(xy 248.499884 -65.603882) (xy 248.67743 -65.677034)
		)
		(stroke
			(width 0)
			(type solid)
		)
		(fill yes)
		(layer "In11.Cu")
		(net "M_C_DQ<25>")
	)
	(gr_poly
		(pts
			(xy 248.867168 -99.300538) (xy 248.835672 -99.269296) (xy 248.636282 -99.195636) (xy 248.474738 -99.35718)
			(xy 248.548398 -99.55657) (xy 248.57964 -99.588066)
		)
		(stroke
			(width 0)
			(type solid)
		)
		(fill yes)
		(layer "In11.Cu")
		(net "M_F_DQ<30>")
	)
	(gr_poly
		(pts
			(xy 248.891806 -55.497222) (xy 248.994676 -55.334916) (xy 248.884186 -55.143654) (xy 248.692416 -55.151782)
			(xy 248.653808 -55.17388) (xy 248.853452 -55.51932)
		)
		(stroke
			(width 0)
			(type solid)
		)
		(fill yes)
		(layer "In11.Cu")
		(net "M_C_DQS_DN<12>")
	)
	(gr_poly
		(pts
			(xy 248.898918 -50.769266) (xy 248.898918 -50.540412) (xy 248.705878 -50.451512) (xy 248.661428 -50.451512)
			(xy 248.661428 -50.857912) (xy 248.705878 -50.857912)
		)
		(stroke
			(width 0)
			(type solid)
		)
		(fill yes)
		(layer "In11.Cu")
		(net "M_C_DQ<31>")
	)
	(gr_poly
		(pts
			(xy 248.928636 -53.279802) (xy 248.884186 -53.279802) (xy 248.691146 -53.368702) (xy 248.691146 -53.597302)
			(xy 248.884186 -53.686202) (xy 248.928636 -53.686202)
		)
		(stroke
			(width 0)
			(type solid)
		)
		(fill yes)
		(layer "In11.Cu")
		(net "M_C_DQS_DP<3>")
	)
	(gr_poly
		(pts
			(xy 248.988072 -92.389452) (xy 248.980198 -92.197682) (xy 248.9581 -92.159074) (xy 248.612406 -92.358464)
			(xy 248.634758 -92.396818) (xy 248.79681 -92.499942)
		)
		(stroke
			(width 0)
			(type solid)
		)
		(fill yes)
		(layer "In11.Cu")
		(net "M_F_DQ<25>")
	)
	(gr_poly
		(pts
			(xy 249.044714 -97.968562) (xy 249.044714 -97.739962) (xy 248.851674 -97.651062) (xy 248.807224 -97.651062)
			(xy 248.807224 -98.057462) (xy 248.851674 -98.057462)
		)
		(stroke
			(width 0)
			(type solid)
		)
		(fill yes)
		(layer "In11.Cu")
		(net "M_F_DQS_DP<3>")
	)
	(gr_poly
		(pts
			(xy 249.106436 -99.66579) (xy 249.032776 -99.4664) (xy 249.001534 -99.434904) (xy 248.714006 -99.722432)
			(xy 248.745502 -99.753674) (xy 248.944892 -99.827334)
		)
		(stroke
			(width 0)
			(type solid)
		)
		(fill yes)
		(layer "In11.Cu")
		(net "M_F_DQ<31>")
	)
	(gr_poly
		(pts
			(xy 249.124978 -91.946222) (xy 249.295158 -91.857576) (xy 249.295158 -91.636596) (xy 249.125232 -91.547696)
			(xy 249.080782 -91.547442) (xy 249.080528 -91.946476)
		)
		(stroke
			(width 0)
			(type solid)
		)
		(fill yes)
		(layer "In11.Cu")
		(net "M_F_DQ<25>")
	)
	(gr_poly
		(pts
			(xy 249.133106 -102.452932) (xy 249.133106 -102.224332) (xy 248.940066 -102.135432) (xy 248.895616 -102.135432)
			(xy 248.895616 -102.541832) (xy 248.940066 -102.541832)
		)
		(stroke
			(width 0)
			(type solid)
		)
		(fill yes)
		(layer "In11.Cu")
		(net "M_F_DQ<27>")
	)
	(gr_poly
		(pts
			(xy 249.133106 -101.462332) (xy 249.133106 -101.233732) (xy 248.940066 -101.144832) (xy 248.895616 -101.144832)
			(xy 248.895616 -101.551232) (xy 248.940066 -101.551232)
		)
		(stroke
			(width 0)
			(type solid)
		)
		(fill yes)
		(layer "In11.Cu")
		(net "M_F_DQ<27>")
	)
	(gr_poly
		(pts
			(xy 249.188224 -100.080318) (xy 249.156728 -100.048822) (xy 248.957338 -99.975162) (xy 248.795794 -100.13696)
			(xy 248.869454 -100.33635) (xy 248.90095 -100.367592)
		)
		(stroke
			(width 0)
			(type solid)
		)
		(fill yes)
		(layer "In11.Cu")
		(net "M_F_DQ<26>")
	)
	(gr_poly
		(pts
			(xy 249.21591 -92.627196) (xy 249.193812 -92.588842) (xy 249.03176 -92.485972) (xy 248.840498 -92.596462)
			(xy 248.848372 -92.788232) (xy 248.870724 -92.82684)
		)
		(stroke
			(width 0)
			(type solid)
		)
		(fill yes)
		(layer "In11.Cu")
		(net "M_F_DQS_DP<12>")
	)
	(gr_poly
		(pts
			(xy 249.26798 -96.878394) (xy 249.236484 -96.847152) (xy 249.037094 -96.773492) (xy 248.87555 -96.935036)
			(xy 248.94921 -97.134426) (xy 248.980452 -97.165922)
		)
		(stroke
			(width 0)
			(type solid)
		)
		(fill yes)
		(layer "In11.Cu")
		(net "M_F_DQS_DN<3>")
	)
	(gr_poly
		(pts
			(xy 249.295412 -95.826326) (xy 249.295412 -95.605346) (xy 249.125232 -95.516446) (xy 249.080782 -95.516446)
			(xy 249.080782 -95.915226) (xy 249.125232 -95.915226)
		)
		(stroke
			(width 0)
			(type solid)
		)
		(fill yes)
		(layer "In11.Cu")
		(net "M_F_DQS_DN<12>")
	)
	(gr_poly
		(pts
			(xy 249.295412 -94.829376) (xy 249.295412 -94.608396) (xy 249.125232 -94.519496) (xy 249.080782 -94.519496)
			(xy 249.080782 -94.918276) (xy 249.125232 -94.918276)
		)
		(stroke
			(width 0)
			(type solid)
		)
		(fill yes)
		(layer "In11.Cu")
		(net "M_F_DQS_DN<12>")
	)
	(gr_poly
		(pts
			(xy 249.295412 -93.83268) (xy 249.295412 -93.6117) (xy 249.125232 -93.5228) (xy 249.080782 -93.5228)
			(xy 249.080782 -93.92158) (xy 249.125232 -93.92158)
		)
		(stroke
			(width 0)
			(type solid)
		)
		(fill yes)
		(layer "In11.Cu")
		(net "M_F_DQS_DN<12>")
	)
	(gr_poly
		(pts
			(xy 249.295412 -90.867484) (xy 249.295412 -90.646504) (xy 249.125232 -90.557604) (xy 249.080782 -90.557604)
			(xy 249.080782 -90.956384) (xy 249.125232 -90.956384)
		)
		(stroke
			(width 0)
			(type solid)
		)
		(fill yes)
		(layer "In11.Cu")
		(net "M_F_DQ<25>")
	)
	(gr_poly
		(pts
			(xy 249.295412 -89.876884) (xy 249.295412 -89.655904) (xy 249.125232 -89.567004) (xy 249.080782 -89.567004)
			(xy 249.080782 -89.965784) (xy 249.125232 -89.965784)
		)
		(stroke
			(width 0)
			(type solid)
		)
		(fill yes)
		(layer "In11.Cu")
		(net "M_F_DQ<25>")
	)
	(gr_poly
		(pts
			(xy 249.295412 -88.886284) (xy 249.295412 -88.665304) (xy 249.125232 -88.576404) (xy 249.080782 -88.576404)
			(xy 249.080782 -88.975184) (xy 249.125232 -88.975184)
		)
		(stroke
			(width 0)
			(type solid)
		)
		(fill yes)
		(layer "In11.Cu")
		(net "M_F_DQ<25>")
	)
	(gr_poly
		(pts
			(xy 249.295412 -63.136526) (xy 249.295412 -62.915546) (xy 249.125232 -62.826646) (xy 249.080782 -62.826646)
			(xy 249.080782 -63.225426) (xy 249.125232 -63.225426)
		)
		(stroke
			(width 0)
			(type solid)
		)
		(fill yes)
		(layer "In11.Cu")
		(net "M_C_DQS_DN<12>")
	)
	(gr_poly
		(pts
			(xy 249.295412 -62.145926) (xy 249.295412 -61.924946) (xy 249.125232 -61.836046) (xy 249.080782 -61.836046)
			(xy 249.080782 -62.234826) (xy 249.125232 -62.234826)
		)
		(stroke
			(width 0)
			(type solid)
		)
		(fill yes)
		(layer "In11.Cu")
		(net "M_C_DQS_DN<12>")
	)
	(gr_poly
		(pts
			(xy 249.295412 -61.155326) (xy 249.295412 -60.934346) (xy 249.125232 -60.845446) (xy 249.080782 -60.845446)
			(xy 249.080782 -61.244226) (xy 249.125232 -61.244226)
		)
		(stroke
			(width 0)
			(type solid)
		)
		(fill yes)
		(layer "In11.Cu")
		(net "M_C_DQS_DN<12>")
	)
	(gr_poly
		(pts
			(xy 249.295412 -60.164726) (xy 249.295412 -59.943746) (xy 249.125232 -59.854846) (xy 249.080782 -59.854846)
			(xy 249.080782 -60.253626) (xy 249.125232 -60.253626)
		)
		(stroke
			(width 0)
			(type solid)
		)
		(fill yes)
		(layer "In11.Cu")
		(net "M_C_DQS_DN<12>")
	)
	(gr_poly
		(pts
			(xy 249.295412 -59.167776) (xy 249.295412 -58.946796) (xy 249.125232 -58.857896) (xy 249.080782 -58.857896)
			(xy 249.080782 -59.256676) (xy 249.125232 -59.256676)
		)
		(stroke
			(width 0)
			(type solid)
		)
		(fill yes)
		(layer "In11.Cu")
		(net "M_C_DQS_DN<12>")
	)
	(gr_poly
		(pts
			(xy 249.295412 -58.17108) (xy 249.295412 -57.9501) (xy 249.125232 -57.8612) (xy 249.080782 -57.8612)
			(xy 249.080782 -58.25998) (xy 249.125232 -58.25998)
		)
		(stroke
			(width 0)
			(type solid)
		)
		(fill yes)
		(layer "In11.Cu")
		(net "M_C_DQS_DN<12>")
	)
	(gr_poly
		(pts
			(xy 249.295412 -57.192926) (xy 249.295412 -56.971946) (xy 249.125232 -56.883046) (xy 249.080782 -56.883046)
			(xy 249.080782 -57.281826) (xy 249.125232 -57.281826)
		)
		(stroke
			(width 0)
			(type solid)
		)
		(fill yes)
		(layer "In11.Cu")
		(net "M_C_DQS_DN<12>")
	)
	(gr_poly
		(pts
			(xy 249.295412 -56.202326) (xy 249.295412 -55.981346) (xy 249.125232 -55.892446) (xy 249.080782 -55.892446)
			(xy 249.080782 -56.291226) (xy 249.125232 -56.291226)
		)
		(stroke
			(width 0)
			(type solid)
		)
		(fill yes)
		(layer "In11.Cu")
		(net "M_C_DQS_DN<12>")
	)
	(gr_poly
		(pts
			(xy 249.356626 -53.597302) (xy 249.356626 -53.368702) (xy 249.163586 -53.279802) (xy 249.119136 -53.279802)
			(xy 249.119136 -53.686202) (xy 249.163586 -53.686202)
		)
		(stroke
			(width 0)
			(type solid)
		)
		(fill yes)
		(layer "In11.Cu")
		(net "M_C_DQS_DN<3>")
	)
	(gr_poly
		(pts
			(xy 249.393964 -51.986434) (xy 249.467624 -51.787298) (xy 249.305826 -51.6255) (xy 249.10669 -51.69916)
			(xy 249.075194 -51.730656) (xy 249.362468 -52.01793)
		)
		(stroke
			(width 0)
			(type solid)
		)
		(fill yes)
		(layer "In11.Cu")
		(net "M_C_DQ<31>")
	)
	(gr_poly
		(pts
			(xy 249.507756 -97.2439) (xy 249.434096 -97.044764) (xy 249.4026 -97.013268) (xy 249.115326 -97.300542)
			(xy 249.146822 -97.332038) (xy 249.345958 -97.405698)
		)
		(stroke
			(width 0)
			(type solid)
		)
		(fill yes)
		(layer "In11.Cu")
		(net "M_F_DQS_DP<3>")
	)
	(gr_poly
		(pts
			(xy 249.545094 -52.532788) (xy 249.57659 -52.501292) (xy 249.289316 -52.214018) (xy 249.25782 -52.245514)
			(xy 249.18416 -52.44465) (xy 249.345958 -52.606448)
		)
		(stroke
			(width 0)
			(type solid)
		)
		(fill yes)
		(layer "In11.Cu")
		(net "M_C_DQ<30>")
	)
	(gr_poly
		(pts
			(xy 249.567446 -98.60026) (xy 249.536204 -98.568764) (xy 249.336814 -98.495104) (xy 249.175016 -98.656648)
			(xy 249.248676 -98.856038) (xy 249.280172 -98.887534)
		)
		(stroke
			(width 0)
			(type solid)
		)
		(fill yes)
		(layer "In11.Cu")
		(net "M_F_DQ<30>")
	)
	(gr_poly
		(pts
			(xy 249.615706 -95.516446) (xy 249.571256 -95.516446) (xy 249.401076 -95.605346) (xy 249.401076 -95.826326)
			(xy 249.571256 -95.915226) (xy 249.615706 -95.915226)
		)
		(stroke
			(width 0)
			(type solid)
		)
		(fill yes)
		(layer "In11.Cu")
		(net "M_F_DQS_DN<3>")
	)
	(gr_poly
		(pts
			(xy 249.615706 -94.519496) (xy 249.571256 -94.519496) (xy 249.401076 -94.608396) (xy 249.401076 -94.829376)
			(xy 249.571256 -94.918276) (xy 249.615706 -94.918276)
		)
		(stroke
			(width 0)
			(type solid)
		)
		(fill yes)
		(layer "In11.Cu")
		(net "M_F_DQS_DN<3>")
	)
	(gr_poly
		(pts
			(xy 249.615706 -91.554046) (xy 249.571256 -91.554046) (xy 249.401076 -91.642946) (xy 249.401076 -91.863926)
			(xy 249.571256 -91.952826) (xy 249.615706 -91.952826)
		)
		(stroke
			(width 0)
			(type solid)
		)
		(fill yes)
		(layer "In11.Cu")
		(net "M_F_DQS_DP<12>")
	)
	(gr_poly
		(pts
			(xy 249.615706 -90.563446) (xy 249.571256 -90.563446) (xy 249.401076 -90.652346) (xy 249.401076 -90.873326)
			(xy 249.571256 -90.962226) (xy 249.615706 -90.962226)
		)
		(stroke
			(width 0)
			(type solid)
		)
		(fill yes)
		(layer "In11.Cu")
		(net "M_F_DQS_DP<12>")
	)
	(gr_poly
		(pts
			(xy 249.615706 -89.572846) (xy 249.571256 -89.572846) (xy 249.401076 -89.661746) (xy 249.401076 -89.882726)
			(xy 249.571256 -89.971626) (xy 249.615706 -89.971626)
		)
		(stroke
			(width 0)
			(type solid)
		)
		(fill yes)
		(layer "In11.Cu")
		(net "M_F_DQS_DP<12>")
	)
	(gr_poly
		(pts
			(xy 249.615706 -88.582246) (xy 249.571256 -88.582246) (xy 249.401076 -88.671146) (xy 249.401076 -88.892126)
			(xy 249.571256 -88.981026) (xy 249.615706 -88.981026)
		)
		(stroke
			(width 0)
			(type solid)
		)
		(fill yes)
		(layer "In11.Cu")
		(net "M_F_DQS_DP<12>")
	)
	(gr_poly
		(pts
			(xy 249.615706 -87.591646) (xy 249.571256 -87.591646) (xy 249.401076 -87.680546) (xy 249.401076 -87.901526)
			(xy 249.571256 -87.990426) (xy 249.615706 -87.990426)
		)
		(stroke
			(width 0)
			(type solid)
		)
		(fill yes)
		(layer "In11.Cu")
		(net "M_F_DQS_DP<12>")
	)
	(gr_poly
		(pts
			(xy 249.615706 -86.601046) (xy 249.571256 -86.601046) (xy 249.401076 -86.689946) (xy 249.401076 -86.910926)
			(xy 249.571256 -86.999826) (xy 249.615706 -86.999826)
		)
		(stroke
			(width 0)
			(type solid)
		)
		(fill yes)
		(layer "In11.Cu")
		(net "M_F_DQS_DP<12>")
	)
	(gr_poly
		(pts
			(xy 249.615706 -85.610446) (xy 249.571256 -85.610446) (xy 249.401076 -85.699346) (xy 249.401076 -85.920326)
			(xy 249.571256 -86.009226) (xy 249.615706 -86.009226)
		)
		(stroke
			(width 0)
			(type solid)
		)
		(fill yes)
		(layer "In11.Cu")
		(net "M_F_DQS_DP<12>")
	)
	(gr_poly
		(pts
			(xy 249.615706 -65.798446) (xy 249.571256 -65.798446) (xy 249.401076 -65.887346) (xy 249.401076 -66.108326)
			(xy 249.571256 -66.197226) (xy 249.615706 -66.197226)
		)
		(stroke
			(width 0)
			(type solid)
		)
		(fill yes)
		(layer "In11.Cu")
		(net "M_C_DQS_DP<3>")
	)
	(gr_poly
		(pts
			(xy 249.615706 -64.807846) (xy 249.571256 -64.807846) (xy 249.401076 -64.896746) (xy 249.401076 -65.117726)
			(xy 249.571256 -65.206626) (xy 249.615706 -65.206626)
		)
		(stroke
			(width 0)
			(type solid)
		)
		(fill yes)
		(layer "In11.Cu")
		(net "M_C_DQS_DP<3>")
	)
	(gr_poly
		(pts
			(xy 249.615706 -63.817246) (xy 249.571256 -63.817246) (xy 249.401076 -63.906146) (xy 249.401076 -64.127126)
			(xy 249.571256 -64.216026) (xy 249.615706 -64.216026)
		)
		(stroke
			(width 0)
			(type solid)
		)
		(fill yes)
		(layer "In11.Cu")
		(net "M_C_DQS_DP<3>")
	)
	(gr_poly
		(pts
			(xy 249.615706 -62.826646) (xy 249.571256 -62.826646) (xy 249.401076 -62.915546) (xy 249.401076 -63.136526)
			(xy 249.571256 -63.225426) (xy 249.615706 -63.225426)
		)
		(stroke
			(width 0)
			(type solid)
		)
		(fill yes)
		(layer "In11.Cu")
		(net "M_C_DQS_DP<3>")
	)
	(gr_poly
		(pts
			(xy 249.615706 -61.836046) (xy 249.571256 -61.836046) (xy 249.401076 -61.924946) (xy 249.401076 -62.145926)
			(xy 249.571256 -62.234826) (xy 249.615706 -62.234826)
		)
		(stroke
			(width 0)
			(type solid)
		)
		(fill yes)
		(layer "In11.Cu")
		(net "M_C_DQS_DP<3>")
	)
	(gr_poly
		(pts
			(xy 249.615706 -60.845446) (xy 249.571256 -60.845446) (xy 249.401076 -60.934346) (xy 249.401076 -61.155326)
			(xy 249.571256 -61.244226) (xy 249.615706 -61.244226)
		)
		(stroke
			(width 0)
			(type solid)
		)
		(fill yes)
		(layer "In11.Cu")
		(net "M_C_DQS_DP<3>")
	)
	(gr_poly
		(pts
			(xy 249.615706 -59.854846) (xy 249.571256 -59.854846) (xy 249.401076 -59.943746) (xy 249.401076 -60.164726)
			(xy 249.571256 -60.253626) (xy 249.615706 -60.253626)
		)
		(stroke
			(width 0)
			(type solid)
		)
		(fill yes)
		(layer "In11.Cu")
		(net "M_C_DQS_DP<3>")
	)
	(gr_poly
		(pts
			(xy 249.615706 -58.857896) (xy 249.571256 -58.857896) (xy 249.401076 -58.946796) (xy 249.401076 -59.167776)
			(xy 249.571256 -59.256676) (xy 249.615706 -59.256676)
		)
		(stroke
			(width 0)
			(type solid)
		)
		(fill yes)
		(layer "In11.Cu")
		(net "M_C_DQS_DP<3>")
	)
	(gr_poly
		(pts
			(xy 249.615706 -57.8612) (xy 249.571256 -57.8612) (xy 249.401076 -57.9501) (xy 249.401076 -58.17108)
			(xy 249.571256 -58.25998) (xy 249.615706 -58.25998)
		)
		(stroke
			(width 0)
			(type solid)
		)
		(fill yes)
		(layer "In11.Cu")
		(net "M_C_DQS_DP<3>")
	)
	(gr_poly
		(pts
			(xy 249.615706 -56.883046) (xy 249.571256 -56.883046) (xy 249.401076 -56.971946) (xy 249.401076 -57.192926)
			(xy 249.571256 -57.281826) (xy 249.615706 -57.281826)
		)
		(stroke
			(width 0)
			(type solid)
		)
		(fill yes)
		(layer "In11.Cu")
		(net "M_C_DQS_DP<3>")
	)
	(gr_poly
		(pts
			(xy 249.615706 -55.892446) (xy 249.571256 -55.892446) (xy 249.401076 -55.981346) (xy 249.401076 -56.202326)
			(xy 249.571256 -56.291226) (xy 249.615706 -56.291226)
		)
		(stroke
			(width 0)
			(type solid)
		)
		(fill yes)
		(layer "In11.Cu")
		(net "M_C_DQS_DP<3>")
	)
	(gr_poly
		(pts
			(xy 249.61596 -93.52915) (xy 249.57151 -93.529404) (xy 249.40133 -93.61805) (xy 249.40133 -93.83903)
			(xy 249.571256 -93.92793) (xy 249.615706 -93.928184)
		)
		(stroke
			(width 0)
			(type solid)
		)
		(fill yes)
		(layer "In11.Cu")
		(net "M_F_DQS_DN<3>")
	)
	(gr_poly
		(pts
			(xy 249.616976 -97.795334) (xy 249.572526 -97.795334) (xy 249.379486 -97.884234) (xy 249.379486 -98.112834)
			(xy 249.572526 -98.201734) (xy 249.616976 -98.201734)
		)
		(stroke
			(width 0)
			(type solid)
		)
		(fill yes)
		(layer "In11.Cu")
		(net "M_F_DQ<30>")
	)
	(gr_poly
		(pts
			(xy 249.681746 -100.19157) (xy 249.608086 -99.99218) (xy 249.57659 -99.960684) (xy 249.289316 -100.247958)
			(xy 249.320558 -100.279454) (xy 249.519948 -100.353114)
		)
		(stroke
			(width 0)
			(type solid)
		)
		(fill yes)
		(layer "In11.Cu")
		(net "M_F_DQ<27>")
	)
	(gr_poly
		(pts
			(xy 249.69724 -53.116226) (xy 249.65279 -53.116226) (xy 249.45975 -53.205126) (xy 249.45975 -53.433726)
			(xy 249.65279 -53.522626) (xy 249.69724 -53.522626)
		)
		(stroke
			(width 0)
			(type solid)
		)
		(fill yes)
		(layer "In11.Cu")
		(net "M_C_DQ<30>")
	)
	(gr_poly
		(pts
			(xy 249.724164 -49.918874) (xy 249.692668 -49.887632) (xy 249.493278 -49.813972) (xy 249.331734 -49.975516)
			(xy 249.405394 -50.174906) (xy 249.436636 -50.206402)
		)
		(stroke
			(width 0)
			(type solid)
		)
		(fill yes)
		(layer "In11.Cu")
		(net "M_C_DQ<26>")
	)
	(gr_poly
		(pts
			(xy 249.806968 -98.965258) (xy 249.733308 -98.765868) (xy 249.701812 -98.734626) (xy 249.414538 -99.0219)
			(xy 249.446034 -99.053396) (xy 249.645424 -99.127056)
		)
		(stroke
			(width 0)
			(type solid)
		)
		(fill yes)
		(layer "In11.Cu")
		(net "M_F_DQ<31>")
	)
	(gr_poly
		(pts
			(xy 249.854212 -92.880688) (xy 249.846084 -92.688918) (xy 249.823986 -92.650056) (xy 249.4788 -92.8497)
			(xy 249.500898 -92.888054) (xy 249.66295 -92.990924)
		)
		(stroke
			(width 0)
			(type solid)
		)
		(fill yes)
		(layer "In11.Cu")
		(net "M_F_DQS_DN<12>")
	)
	(gr_poly
		(pts
			(xy 249.888756 -99.379786) (xy 249.85726 -99.348544) (xy 249.65787 -99.274884) (xy 249.496326 -99.436428)
			(xy 249.569986 -99.635818) (xy 249.601228 -99.667314)
		)
		(stroke
			(width 0)
			(type solid)
		)
		(fill yes)
		(layer "In11.Cu")
		(net "M_F_DQ<26>")
	)
	(gr_poly
		(pts
			(xy 250.001532 -51.55438) (xy 250.033028 -51.523138) (xy 249.7455 -51.23561) (xy 249.714258 -51.267106)
			(xy 249.640598 -51.466496) (xy 249.802142 -51.62804)
		)
		(stroke
			(width 0)
			(type solid)
		)
		(fill yes)
		(layer "In11.Cu")
		(net "M_C_DQ<26>")
	)
	(gr_poly
		(pts
			(xy 250.044458 -98.290634) (xy 250.044458 -98.062034) (xy 249.851418 -97.973134) (xy 249.806968 -97.973134)
			(xy 249.806968 -98.379534) (xy 249.851418 -98.379534)
		)
		(stroke
			(width 0)
			(type solid)
		)
		(fill yes)
		(layer "In11.Cu")
		(net "M_F_DQ<31>")
	)
	(gr_poly
		(pts
			(xy 250.084082 -93.117162) (xy 250.061476 -93.078808) (xy 249.899678 -92.975684) (xy 249.708416 -93.086174)
			(xy 249.71629 -93.277944) (xy 249.738388 -93.316552)
		)
		(stroke
			(width 0)
			(type solid)
		)
		(fill yes)
		(layer "In11.Cu")
		(net "M_F_DQS_DN<3>")
	)
	(gr_poly
		(pts
			(xy 250.12523 -53.433726) (xy 250.12523 -53.205126) (xy 249.93219 -53.116226) (xy 249.88774 -53.116226)
			(xy 249.88774 -53.522626) (xy 249.93219 -53.522626)
		)
		(stroke
			(width 0)
			(type solid)
		)
		(fill yes)
		(layer "In11.Cu")
		(net "M_C_DQ<31>")
	)
	(gr_poly
		(pts
			(xy 250.151392 -66.603626) (xy 250.154948 -66.3829) (xy 249.986038 -66.29146) (xy 249.941842 -66.290698)
			(xy 249.935238 -66.689224) (xy 249.979688 -66.689986)
		)
		(stroke
			(width 0)
			(type solid)
		)
		(fill yes)
		(layer "In11.Cu")
		(net "M_C_DQS_DN<3>")
	)
	(gr_poly
		(pts
			(xy 250.153678 -96.30918) (xy 250.153678 -96.0882) (xy 249.983498 -95.9993) (xy 249.939048 -95.9993)
			(xy 249.939048 -96.39808) (xy 249.983498 -96.39808)
		)
		(stroke
			(width 0)
			(type solid)
		)
		(fill yes)
		(layer "In11.Cu")
		(net "M_F_DQS_DP<3>")
	)
	(gr_poly
		(pts
			(xy 250.153678 -92.34424) (xy 250.153678 -92.123514) (xy 249.983752 -92.034614) (xy 249.939048 -92.03436)
			(xy 249.939302 -92.43314) (xy 249.983498 -92.43314)
		)
		(stroke
			(width 0)
			(type solid)
		)
		(fill yes)
		(layer "In11.Cu")
		(net "M_F_DQS_DN<12>")
	)
	(gr_poly
		(pts
			(xy 250.153932 -95.31858) (xy 250.153932 -95.0976) (xy 249.983752 -95.0087) (xy 249.939302 -95.0087)
			(xy 249.939302 -95.40748) (xy 249.983752 -95.40748)
		)
		(stroke
			(width 0)
			(type solid)
		)
		(fill yes)
		(layer "In11.Cu")
		(net "M_F_DQS_DP<3>")
	)
	(gr_poly
		(pts
			(xy 250.153932 -94.340426) (xy 250.153932 -94.119446) (xy 249.983752 -94.030546) (xy 249.939302 -94.030546)
			(xy 249.939302 -94.429326) (xy 249.983752 -94.429326)
		)
		(stroke
			(width 0)
			(type solid)
		)
		(fill yes)
		(layer "In11.Cu")
		(net "M_F_DQS_DP<3>")
	)
	(gr_poly
		(pts
			(xy 250.153932 -91.35618) (xy 250.153932 -91.1352) (xy 249.983752 -91.0463) (xy 249.939302 -91.0463)
			(xy 249.939302 -91.44508) (xy 249.983752 -91.44508)
		)
		(stroke
			(width 0)
			(type solid)
		)
		(fill yes)
		(layer "In11.Cu")
		(net "M_F_DQS_DN<12>")
	)
	(gr_poly
		(pts
			(xy 250.153932 -90.36558) (xy 250.153932 -90.1446) (xy 249.983752 -90.0557) (xy 249.939302 -90.0557)
			(xy 249.939302 -90.45448) (xy 249.983752 -90.45448)
		)
		(stroke
			(width 0)
			(type solid)
		)
		(fill yes)
		(layer "In11.Cu")
		(net "M_F_DQS_DN<12>")
	)
	(gr_poly
		(pts
			(xy 250.153932 -89.37498) (xy 250.153932 -89.154) (xy 249.983752 -89.0651) (xy 249.939302 -89.0651)
			(xy 249.939302 -89.46388) (xy 249.983752 -89.46388)
		)
		(stroke
			(width 0)
			(type solid)
		)
		(fill yes)
		(layer "In11.Cu")
		(net "M_F_DQS_DN<12>")
	)
	(gr_poly
		(pts
			(xy 250.153932 -88.38438) (xy 250.153932 -88.1634) (xy 249.983752 -88.0745) (xy 249.939302 -88.0745)
			(xy 249.939302 -88.47328) (xy 249.983752 -88.47328)
		)
		(stroke
			(width 0)
			(type solid)
		)
		(fill yes)
		(layer "In11.Cu")
		(net "M_F_DQS_DN<12>")
	)
	(gr_poly
		(pts
			(xy 250.153932 -87.39378) (xy 250.153932 -87.1728) (xy 249.983752 -87.0839) (xy 249.939302 -87.0839)
			(xy 249.939302 -87.48268) (xy 249.983752 -87.48268)
		)
		(stroke
			(width 0)
			(type solid)
		)
		(fill yes)
		(layer "In11.Cu")
		(net "M_F_DQS_DN<12>")
	)
	(gr_poly
		(pts
			(xy 250.153932 -86.40318) (xy 250.153932 -86.1822) (xy 249.983752 -86.0933) (xy 249.939302 -86.0933)
			(xy 249.939302 -86.49208) (xy 249.983752 -86.49208)
		)
		(stroke
			(width 0)
			(type solid)
		)
		(fill yes)
		(layer "In11.Cu")
		(net "M_F_DQS_DN<12>")
	)
	(gr_poly
		(pts
			(xy 250.153932 -65.60058) (xy 250.153932 -65.3796) (xy 249.983752 -65.2907) (xy 249.939302 -65.2907)
			(xy 249.939302 -65.68948) (xy 249.983752 -65.68948)
		)
		(stroke
			(width 0)
			(type solid)
		)
		(fill yes)
		(layer "In11.Cu")
		(net "M_C_DQS_DN<3>")
	)
	(gr_poly
		(pts
			(xy 250.153932 -64.60998) (xy 250.153932 -64.389) (xy 249.983752 -64.3001) (xy 249.939302 -64.3001)
			(xy 249.939302 -64.69888) (xy 249.983752 -64.69888)
		)
		(stroke
			(width 0)
			(type solid)
		)
		(fill yes)
		(layer "In11.Cu")
		(net "M_C_DQS_DN<3>")
	)
	(gr_poly
		(pts
			(xy 250.153932 -63.61938) (xy 250.153932 -63.3984) (xy 249.983752 -63.3095) (xy 249.939302 -63.3095)
			(xy 249.939302 -63.70828) (xy 249.983752 -63.70828)
		)
		(stroke
			(width 0)
			(type solid)
		)
		(fill yes)
		(layer "In11.Cu")
		(net "M_C_DQS_DN<3>")
	)
	(gr_poly
		(pts
			(xy 250.153932 -62.62878) (xy 250.153932 -62.4078) (xy 249.983752 -62.3189) (xy 249.939302 -62.3189)
			(xy 249.939302 -62.71768) (xy 249.983752 -62.71768)
		)
		(stroke
			(width 0)
			(type solid)
		)
		(fill yes)
		(layer "In11.Cu")
		(net "M_C_DQS_DN<3>")
	)
	(gr_poly
		(pts
			(xy 250.153932 -61.63818) (xy 250.153932 -61.4172) (xy 249.983752 -61.3283) (xy 249.939302 -61.3283)
			(xy 249.939302 -61.72708) (xy 249.983752 -61.72708)
		)
		(stroke
			(width 0)
			(type solid)
		)
		(fill yes)
		(layer "In11.Cu")
		(net "M_C_DQS_DN<3>")
	)
	(gr_poly
		(pts
			(xy 250.153932 -60.64758) (xy 250.153932 -60.4266) (xy 249.983752 -60.3377) (xy 249.939302 -60.3377)
			(xy 249.939302 -60.73648) (xy 249.983752 -60.73648)
		)
		(stroke
			(width 0)
			(type solid)
		)
		(fill yes)
		(layer "In11.Cu")
		(net "M_C_DQS_DN<3>")
	)
	(gr_poly
		(pts
			(xy 250.153932 -59.65698) (xy 250.153932 -59.436) (xy 249.983752 -59.3471) (xy 249.939302 -59.3471)
			(xy 249.939302 -59.74588) (xy 249.983752 -59.74588)
		)
		(stroke
			(width 0)
			(type solid)
		)
		(fill yes)
		(layer "In11.Cu")
		(net "M_C_DQS_DN<3>")
	)
	(gr_poly
		(pts
			(xy 250.153932 -58.678826) (xy 250.153932 -58.457846) (xy 249.983752 -58.368946) (xy 249.939302 -58.368946)
			(xy 249.939302 -58.767726) (xy 249.983752 -58.767726)
		)
		(stroke
			(width 0)
			(type solid)
		)
		(fill yes)
		(layer "In11.Cu")
		(net "M_C_DQS_DN<3>")
	)
	(gr_poly
		(pts
			(xy 250.153932 -57.68213) (xy 250.153932 -57.46115) (xy 249.983752 -57.37225) (xy 249.939302 -57.37225)
			(xy 249.939302 -57.77103) (xy 249.983752 -57.77103)
		)
		(stroke
			(width 0)
			(type solid)
		)
		(fill yes)
		(layer "In11.Cu")
		(net "M_C_DQS_DN<3>")
	)
	(gr_poly
		(pts
			(xy 250.153932 -56.68518) (xy 250.153932 -56.4642) (xy 249.983752 -56.3753) (xy 249.939302 -56.3753)
			(xy 249.939302 -56.77408) (xy 249.983752 -56.77408)
		)
		(stroke
			(width 0)
			(type solid)
		)
		(fill yes)
		(layer "In11.Cu")
		(net "M_C_DQS_DN<3>")
	)
	(gr_poly
		(pts
			(xy 250.153932 -55.69458) (xy 250.153932 -55.4736) (xy 249.983752 -55.3847) (xy 249.939302 -55.3847)
			(xy 249.939302 -55.78348) (xy 249.983752 -55.78348)
		)
		(stroke
			(width 0)
			(type solid)
		)
		(fill yes)
		(layer "In11.Cu")
		(net "M_C_DQS_DN<3>")
	)
	(gr_poly
		(pts
			(xy 250.19889 -51.357022) (xy 250.27255 -51.157632) (xy 250.111006 -50.996088) (xy 249.911616 -51.069748)
			(xy 249.88012 -51.10099) (xy 250.167648 -51.388518)
		)
		(stroke
			(width 0)
			(type solid)
		)
		(fill yes)
		(layer "In11.Cu")
		(net "M_C_DQ<27>")
	)
	(gr_poly
		(pts
			(xy 250.222258 -54.604412) (xy 250.253754 -54.572916) (xy 249.96648 -54.285642) (xy 249.934984 -54.317138)
			(xy 249.861324 -54.516274) (xy 250.023122 -54.678072)
		)
		(stroke
			(width 0)
			(type solid)
		)
		(fill yes)
		(layer "In11.Cu")
		(net "M_C_DQ<30>")
	)
	(gr_poly
		(pts
			(xy 250.382024 -99.491038) (xy 250.308364 -99.291648) (xy 250.277122 -99.260152) (xy 249.989594 -99.54768)
			(xy 250.02109 -99.578922) (xy 250.22048 -99.652582)
		)
		(stroke
			(width 0)
			(type solid)
		)
		(fill yes)
		(layer "In11.Cu")
		(net "M_F_DQ<27>")
	)
	(gr_poly
		(pts
			(xy 250.420124 -54.406546) (xy 250.493784 -54.20741) (xy 250.331986 -54.045612) (xy 250.13285 -54.119272)
			(xy 250.101354 -54.150768) (xy 250.388628 -54.438042)
		)
		(stroke
			(width 0)
			(type solid)
		)
		(fill yes)
		(layer "In11.Cu")
		(net "M_C_DQ<31>")
	)
	(gr_poly
		(pts
			(xy 250.465844 -53.285644) (xy 250.421394 -53.285644) (xy 250.228354 -53.374544) (xy 250.228354 -53.603144)
			(xy 250.421394 -53.692044) (xy 250.465844 -53.692044)
		)
		(stroke
			(width 0)
			(type solid)
		)
		(fill yes)
		(layer "In11.Cu")
		(net "M_C_DQ<26>")
	)
	(gr_poly
		(pts
			(xy 250.465844 -52.295044) (xy 250.421394 -52.295044) (xy 250.228354 -52.383944) (xy 250.228354 -52.612544)
			(xy 250.421394 -52.701444) (xy 250.465844 -52.701444)
		)
		(stroke
			(width 0)
			(type solid)
		)
		(fill yes)
		(layer "In11.Cu")
		(net "M_C_DQ<26>")
	)
	(gr_poly
		(pts
			(xy 250.474226 -95.9993) (xy 250.429776 -95.9993) (xy 250.259596 -96.0882) (xy 250.259596 -96.30918)
			(xy 250.429776 -96.39808) (xy 250.474226 -96.39808)
		)
		(stroke
			(width 0)
			(type solid)
		)
		(fill yes)
		(layer "In11.Cu")
		(net "M_F_DQ<30>")
	)
	(gr_poly
		(pts
			(xy 250.474226 -95.0087) (xy 250.429776 -95.0087) (xy 250.259596 -95.0976) (xy 250.259596 -95.31858)
			(xy 250.429776 -95.40748) (xy 250.474226 -95.40748)
		)
		(stroke
			(width 0)
			(type solid)
		)
		(fill yes)
		(layer "In11.Cu")
		(net "M_F_DQ<30>")
	)
	(gr_poly
		(pts
			(xy 250.474226 -94.033086) (xy 250.43003 -94.033086) (xy 250.25985 -94.121986) (xy 250.25985 -94.342712)
			(xy 250.43003 -94.431612) (xy 250.47448 -94.431866)
		)
		(stroke
			(width 0)
			(type solid)
		)
		(fill yes)
		(layer "In11.Cu")
		(net "M_F_DQ<30>")
	)
	(gr_poly
		(pts
			(xy 250.474226 -92.0369) (xy 250.429776 -92.0369) (xy 250.259596 -92.1258) (xy 250.259596 -92.34678)
			(xy 250.429776 -92.43568) (xy 250.474226 -92.43568)
		)
		(stroke
			(width 0)
			(type solid)
		)
		(fill yes)
		(layer "In11.Cu")
		(net "M_F_DQS_DN<3>")
	)
	(gr_poly
		(pts
			(xy 250.474226 -91.0463) (xy 250.429776 -91.0463) (xy 250.259596 -91.1352) (xy 250.259596 -91.35618)
			(xy 250.429776 -91.44508) (xy 250.474226 -91.44508)
		)
		(stroke
			(width 0)
			(type solid)
		)
		(fill yes)
		(layer "In11.Cu")
		(net "M_F_DQS_DN<3>")
	)
	(gr_poly
		(pts
			(xy 250.474226 -90.0557) (xy 250.429776 -90.0557) (xy 250.259596 -90.1446) (xy 250.259596 -90.36558)
			(xy 250.429776 -90.45448) (xy 250.474226 -90.45448)
		)
		(stroke
			(width 0)
			(type solid)
		)
		(fill yes)
		(layer "In11.Cu")
		(net "M_F_DQS_DN<3>")
	)
	(gr_poly
		(pts
			(xy 250.474226 -89.0651) (xy 250.429776 -89.0651) (xy 250.259596 -89.154) (xy 250.259596 -89.37498)
			(xy 250.429776 -89.46388) (xy 250.474226 -89.46388)
		)
		(stroke
			(width 0)
			(type solid)
		)
		(fill yes)
		(layer "In11.Cu")
		(net "M_F_DQS_DN<3>")
	)
	(gr_poly
		(pts
			(xy 250.474226 -62.3189) (xy 250.429776 -62.3189) (xy 250.259596 -62.4078) (xy 250.259596 -62.62878)
			(xy 250.429776 -62.71768) (xy 250.474226 -62.71768)
		)
		(stroke
			(width 0)
			(type solid)
		)
		(fill yes)
		(layer "In11.Cu")
		(net "M_C_DQ<30>")
	)
	(gr_poly
		(pts
			(xy 250.474226 -61.3283) (xy 250.429776 -61.3283) (xy 250.259596 -61.4172) (xy 250.259596 -61.63818)
			(xy 250.429776 -61.72708) (xy 250.474226 -61.72708)
		)
		(stroke
			(width 0)
			(type solid)
		)
		(fill yes)
		(layer "In11.Cu")
		(net "M_C_DQ<30>")
	)
	(gr_poly
		(pts
			(xy 250.474226 -60.3377) (xy 250.429776 -60.3377) (xy 250.259596 -60.4266) (xy 250.259596 -60.64758)
			(xy 250.429776 -60.73648) (xy 250.474226 -60.73648)
		)
		(stroke
			(width 0)
			(type solid)
		)
		(fill yes)
		(layer "In11.Cu")
		(net "M_C_DQ<30>")
	)
	(gr_poly
		(pts
			(xy 250.474226 -59.3471) (xy 250.429776 -59.3471) (xy 250.259596 -59.436) (xy 250.259596 -59.65698)
			(xy 250.429776 -59.74588) (xy 250.474226 -59.74588)
		)
		(stroke
			(width 0)
			(type solid)
		)
		(fill yes)
		(layer "In11.Cu")
		(net "M_C_DQ<30>")
	)
	(gr_poly
		(pts
			(xy 250.474226 -58.368946) (xy 250.429776 -58.368946) (xy 250.259596 -58.457846) (xy 250.259596 -58.678826)
			(xy 250.429776 -58.767726) (xy 250.474226 -58.767726)
		)
		(stroke
			(width 0)
			(type solid)
		)
		(fill yes)
		(layer "In11.Cu")
		(net "M_C_DQ<30>")
	)
	(gr_poly
		(pts
			(xy 250.474226 -57.37225) (xy 250.429776 -57.37225) (xy 250.259596 -57.46115) (xy 250.259596 -57.68213)
			(xy 250.429776 -57.77103) (xy 250.474226 -57.77103)
		)
		(stroke
			(width 0)
			(type solid)
		)
		(fill yes)
		(layer "In11.Cu")
		(net "M_C_DQ<30>")
	)
	(gr_poly
		(pts
			(xy 250.474226 -56.3753) (xy 250.429776 -56.3753) (xy 250.259596 -56.4642) (xy 250.259596 -56.68518)
			(xy 250.429776 -56.77408) (xy 250.474226 -56.77408)
		)
		(stroke
			(width 0)
			(type solid)
		)
		(fill yes)
		(layer "In11.Cu")
		(net "M_C_DQ<30>")
	)
	(gr_poly
		(pts
			(xy 250.474226 -55.397146) (xy 250.429776 -55.397146) (xy 250.259596 -55.486046) (xy 250.259596 -55.707026)
			(xy 250.429776 -55.795926) (xy 250.474226 -55.795926)
		)
		(stroke
			(width 0)
			(type solid)
		)
		(fill yes)
		(layer "In11.Cu")
		(net "M_C_DQ<30>")
	)
	(gr_poly
		(pts
			(xy 250.47448 -63.31585) (xy 250.43003 -63.31585) (xy 250.25985 -63.40475) (xy 250.25985 -63.62573)
			(xy 250.43003 -63.71463) (xy 250.47448 -63.71463)
		)
		(stroke
			(width 0)
			(type solid)
		)
		(fill yes)
		(layer "In11.Cu")
		(net "M_C_DQ<30>")
	)
	(gr_poly
		(pts
			(xy 250.589034 -98.679508) (xy 250.557792 -98.648012) (xy 250.358402 -98.574352) (xy 250.196604 -98.735896)
			(xy 250.270264 -98.935286) (xy 250.30176 -98.966782)
		)
		(stroke
			(width 0)
			(type solid)
		)
		(fill yes)
		(layer "In11.Cu")
		(net "M_F_DQ<26>")
	)
	(gr_poly
		(pts
			(xy 250.66498 -86.09457) (xy 250.62053 -86.09457) (xy 250.45035 -86.18347) (xy 250.45035 -86.40445)
			(xy 250.62053 -86.49335) (xy 250.66498 -86.49335)
		)
		(stroke
			(width 0)
			(type solid)
		)
		(fill yes)
		(layer "In11.Cu")
		(net "M_F_DQ<30>")
	)
	(gr_poly
		(pts
			(xy 250.705366 -93.380306) (xy 250.697492 -93.188536) (xy 250.675394 -93.149928) (xy 250.329954 -93.349318)
			(xy 250.352052 -93.387672) (xy 250.514104 -93.490542)
		)
		(stroke
			(width 0)
			(type solid)
		)
		(fill yes)
		(layer "In11.Cu")
		(net "M_F_DQS_DP<3>")
	)
	(gr_poly
		(pts
			(xy 250.709176 -97.34042) (xy 250.701048 -97.14865) (xy 250.67895 -97.110042) (xy 250.33351 -97.309432)
			(xy 250.355862 -97.347786) (xy 250.51766 -97.450656)
		)
		(stroke
			(width 0)
			(type solid)
		)
		(fill yes)
		(layer "In11.Cu")
		(net "M_F_DQ<31>")
	)
	(gr_poly
		(pts
			(xy 250.893834 -53.223922) (xy 250.893834 -52.995322) (xy 250.700794 -52.906422) (xy 250.656344 -52.906422)
			(xy 250.656344 -53.312822) (xy 250.700794 -53.312822)
		)
		(stroke
			(width 0)
			(type solid)
		)
		(fill yes)
		(layer "In11.Cu")
		(net "M_C_DQ<27>")
	)
	(gr_poly
		(pts
			(xy 250.893834 -52.233322) (xy 250.893834 -52.004722) (xy 250.700794 -51.915822) (xy 250.656344 -51.915822)
			(xy 250.656344 -52.322222) (xy 250.700794 -52.322222)
		)
		(stroke
			(width 0)
			(type solid)
		)
		(fill yes)
		(layer "In11.Cu")
		(net "M_C_DQ<27>")
	)
	(gr_poly
		(pts
			(xy 250.934728 -93.616526) (xy 250.91263 -93.578172) (xy 250.750578 -93.475302) (xy 250.559316 -93.585538)
			(xy 250.567444 -93.777562) (xy 250.589542 -93.81617)
		)
		(stroke
			(width 0)
			(type solid)
		)
		(fill yes)
		(layer "In11.Cu")
		(net "M_F_DQ<30>")
	)
	(gr_poly
		(pts
			(xy 251.012198 -96.806004) (xy 251.012452 -96.585278) (xy 250.842272 -96.496378) (xy 250.797822 -96.496124)
			(xy 250.797822 -96.894904) (xy 250.842272 -96.894904)
		)
		(stroke
			(width 0)
			(type solid)
		)
		(fill yes)
		(layer "In11.Cu")
		(net "M_F_DQ<31>")
	)
	(gr_poly
		(pts
			(xy 251.012452 -95.826326) (xy 251.012452 -95.605346) (xy 250.842272 -95.516446) (xy 250.797822 -95.516446)
			(xy 250.797822 -95.915226) (xy 250.842272 -95.915226)
		)
		(stroke
			(width 0)
			(type solid)
		)
		(fill yes)
		(layer "In11.Cu")
		(net "M_F_DQ<31>")
	)
	(gr_poly
		(pts
			(xy 251.012452 -94.829376) (xy 251.012452 -94.608396) (xy 250.842272 -94.519496) (xy 250.797822 -94.519496)
			(xy 250.797822 -94.918276) (xy 250.842272 -94.918276)
		)
		(stroke
			(width 0)
			(type solid)
		)
		(fill yes)
		(layer "In11.Cu")
		(net "M_F_DQ<31>")
	)
	(gr_poly
		(pts
			(xy 251.012452 -92.847922) (xy 251.012706 -92.627196) (xy 250.842526 -92.538042) (xy 250.798076 -92.538042)
			(xy 250.798076 -92.936822) (xy 250.842272 -92.936822)
		)
		(stroke
			(width 0)
			(type solid)
		)
		(fill yes)
		(layer "In11.Cu")
		(net "M_F_DQS_DP<3>")
	)
	(gr_poly
		(pts
			(xy 251.012452 -91.863926) (xy 251.012452 -91.642946) (xy 250.842272 -91.554046) (xy 250.797822 -91.554046)
			(xy 250.797822 -91.952826) (xy 250.842272 -91.952826)
		)
		(stroke
			(width 0)
			(type solid)
		)
		(fill yes)
		(layer "In11.Cu")
		(net "M_F_DQS_DP<3>")
	)
	(gr_poly
		(pts
			(xy 251.012452 -90.873326) (xy 251.012452 -90.652346) (xy 250.842272 -90.563446) (xy 250.797822 -90.563446)
			(xy 250.797822 -90.962226) (xy 250.842272 -90.962226)
		)
		(stroke
			(width 0)
			(type solid)
		)
		(fill yes)
		(layer "In11.Cu")
		(net "M_F_DQS_DP<3>")
	)
	(gr_poly
		(pts
			(xy 251.012452 -89.882726) (xy 251.012452 -89.661746) (xy 250.842272 -89.572846) (xy 250.797822 -89.572846)
			(xy 250.797822 -89.971626) (xy 250.842272 -89.971626)
		)
		(stroke
			(width 0)
			(type solid)
		)
		(fill yes)
		(layer "In11.Cu")
		(net "M_F_DQS_DP<3>")
	)
	(gr_poly
		(pts
			(xy 251.012452 -88.892126) (xy 251.012452 -88.671146) (xy 250.842272 -88.582246) (xy 250.797822 -88.582246)
			(xy 250.797822 -88.981026) (xy 250.842272 -88.981026)
		)
		(stroke
			(width 0)
			(type solid)
		)
		(fill yes)
		(layer "In11.Cu")
		(net "M_F_DQS_DP<3>")
	)
	(gr_poly
		(pts
			(xy 251.012452 -86.910926) (xy 251.012452 -86.689946) (xy 250.842272 -86.601046) (xy 250.797822 -86.601046)
			(xy 250.797822 -86.999826) (xy 250.842272 -86.999826)
		)
		(stroke
			(width 0)
			(type solid)
		)
		(fill yes)
		(layer "In11.Cu")
		(net "M_F_DQ<30>")
	)
	(gr_poly
		(pts
			(xy 251.012452 -65.11163) (xy 251.012452 -64.89065) (xy 250.842272 -64.80175) (xy 250.797822 -64.80175)
			(xy 250.797822 -65.20053) (xy 250.842272 -65.20053)
		)
		(stroke
			(width 0)
			(type solid)
		)
		(fill yes)
		(layer "In11.Cu")
		(net "M_C_DQ<31>")
	)
	(gr_poly
		(pts
			(xy 251.012452 -64.12103) (xy 251.012452 -63.90005) (xy 250.842272 -63.81115) (xy 250.797822 -63.81115)
			(xy 250.797822 -64.20993) (xy 250.842272 -64.20993)
		)
		(stroke
			(width 0)
			(type solid)
		)
		(fill yes)
		(layer "In11.Cu")
		(net "M_C_DQ<31>")
	)
	(gr_poly
		(pts
			(xy 251.012452 -63.136526) (xy 251.012452 -62.915546) (xy 250.842272 -62.826646) (xy 250.797822 -62.826646)
			(xy 250.797822 -63.225426) (xy 250.842272 -63.225426)
		)
		(stroke
			(width 0)
			(type solid)
		)
		(fill yes)
		(layer "In11.Cu")
		(net "M_C_DQ<31>")
	)
	(gr_poly
		(pts
			(xy 251.012452 -62.145926) (xy 251.012452 -61.924946) (xy 250.842272 -61.836046) (xy 250.797822 -61.836046)
			(xy 250.797822 -62.234826) (xy 250.842272 -62.234826)
		)
		(stroke
			(width 0)
			(type solid)
		)
		(fill yes)
		(layer "In11.Cu")
		(net "M_C_DQ<31>")
	)
	(gr_poly
		(pts
			(xy 251.012452 -61.155326) (xy 251.012452 -60.934346) (xy 250.842272 -60.845446) (xy 250.797822 -60.845446)
			(xy 250.797822 -61.244226) (xy 250.842272 -61.244226)
		)
		(stroke
			(width 0)
			(type solid)
		)
		(fill yes)
		(layer "In11.Cu")
		(net "M_C_DQ<31>")
	)
	(gr_poly
		(pts
			(xy 251.012452 -60.164726) (xy 251.012452 -59.943746) (xy 250.842272 -59.854846) (xy 250.797822 -59.854846)
			(xy 250.797822 -60.253626) (xy 250.842272 -60.253626)
		)
		(stroke
			(width 0)
			(type solid)
		)
		(fill yes)
		(layer "In11.Cu")
		(net "M_C_DQ<31>")
	)
	(gr_poly
		(pts
			(xy 251.012452 -59.167776) (xy 251.012452 -58.946796) (xy 250.842272 -58.857896) (xy 250.797822 -58.857896)
			(xy 250.797822 -59.256676) (xy 250.842272 -59.256676)
		)
		(stroke
			(width 0)
			(type solid)
		)
		(fill yes)
		(layer "In11.Cu")
		(net "M_C_DQ<31>")
	)
	(gr_poly
		(pts
			(xy 251.012452 -58.17108) (xy 251.012452 -57.9501) (xy 250.842272 -57.8612) (xy 250.797822 -57.8612)
			(xy 250.797822 -58.25998) (xy 250.842272 -58.25998)
		)
		(stroke
			(width 0)
			(type solid)
		)
		(fill yes)
		(layer "In11.Cu")
		(net "M_C_DQ<31>")
	)
	(gr_poly
		(pts
			(xy 251.012452 -57.192926) (xy 251.012452 -56.971946) (xy 250.842272 -56.883046) (xy 250.797822 -56.883046)
			(xy 250.797822 -57.281826) (xy 250.842272 -57.281826)
		)
		(stroke
			(width 0)
			(type solid)
		)
		(fill yes)
		(layer "In11.Cu")
		(net "M_C_DQ<31>")
	)
	(gr_poly
		(pts
			(xy 251.012452 -56.202326) (xy 251.012452 -55.981346) (xy 250.842272 -55.892446) (xy 250.797822 -55.892446)
			(xy 250.797822 -56.291226) (xy 250.842272 -56.291226)
		)
		(stroke
			(width 0)
			(type solid)
		)
		(fill yes)
		(layer "In11.Cu")
		(net "M_C_DQ<31>")
	)
	(gr_poly
		(pts
			(xy 251.012452 -55.211726) (xy 251.012452 -54.990746) (xy 250.842272 -54.901846) (xy 250.797822 -54.901846)
			(xy 250.797822 -55.300626) (xy 250.842272 -55.300626)
		)
		(stroke
			(width 0)
			(type solid)
		)
		(fill yes)
		(layer "In11.Cu")
		(net "M_C_DQ<31>")
	)
	(gr_poly
		(pts
			(xy 251.134118 -97.877376) (xy 251.095764 -97.855024) (xy 250.884182 -97.83572) (xy 250.769882 -98.033586)
			(xy 250.892818 -98.207068) (xy 250.931172 -98.22942)
		)
		(stroke
			(width 0)
			(type solid)
		)
		(fill yes)
		(layer "In11.Cu")
		(net "M_F_DQ<26>")
	)
	(gr_poly
		(pts
			(xy 251.332746 -96.507046) (xy 251.288296 -96.507046) (xy 251.118116 -96.595946) (xy 251.118116 -96.816926)
			(xy 251.288296 -96.905826) (xy 251.332746 -96.905826)
		)
		(stroke
			(width 0)
			(type solid)
		)
		(fill yes)
		(layer "In11.Cu")
		(net "M_F_DQ<26>")
	)
	(gr_poly
		(pts
			(xy 251.332746 -95.516446) (xy 251.288296 -95.516446) (xy 251.118116 -95.605346) (xy 251.118116 -95.826326)
			(xy 251.288296 -95.915226) (xy 251.332746 -95.915226)
		)
		(stroke
			(width 0)
			(type solid)
		)
		(fill yes)
		(layer "In11.Cu")
		(net "M_F_DQ<26>")
	)
	(gr_poly
		(pts
			(xy 251.332746 -92.544646) (xy 251.288296 -92.544646) (xy 251.118116 -92.633546) (xy 251.118116 -92.854526)
			(xy 251.288296 -92.943426) (xy 251.332746 -92.943426)
		)
		(stroke
			(width 0)
			(type solid)
		)
		(fill yes)
		(layer "In11.Cu")
		(net "M_F_DQ<30>")
	)
	(gr_poly
		(pts
			(xy 251.332746 -91.554046) (xy 251.288296 -91.554046) (xy 251.118116 -91.642946) (xy 251.118116 -91.863926)
			(xy 251.288296 -91.952826) (xy 251.332746 -91.952826)
		)
		(stroke
			(width 0)
			(type solid)
		)
		(fill yes)
		(layer "In11.Cu")
		(net "M_F_DQ<30>")
	)
	(gr_poly
		(pts
			(xy 251.332746 -90.563446) (xy 251.288296 -90.563446) (xy 251.118116 -90.652346) (xy 251.118116 -90.873326)
			(xy 251.288296 -90.962226) (xy 251.332746 -90.962226)
		)
		(stroke
			(width 0)
			(type solid)
		)
		(fill yes)
		(layer "In11.Cu")
		(net "M_F_DQ<30>")
	)
	(gr_poly
		(pts
			(xy 251.332746 -89.572846) (xy 251.288296 -89.572846) (xy 251.118116 -89.661746) (xy 251.118116 -89.882726)
			(xy 251.288296 -89.971626) (xy 251.332746 -89.971626)
		)
		(stroke
			(width 0)
			(type solid)
		)
		(fill yes)
		(layer "In11.Cu")
		(net "M_F_DQ<30>")
	)
	(gr_poly
		(pts
			(xy 251.332746 -88.582246) (xy 251.288296 -88.582246) (xy 251.118116 -88.671146) (xy 251.118116 -88.892126)
			(xy 251.288296 -88.981026) (xy 251.332746 -88.981026)
		)
		(stroke
			(width 0)
			(type solid)
		)
		(fill yes)
		(layer "In11.Cu")
		(net "M_F_DQ<30>")
	)
	(gr_poly
		(pts
			(xy 251.332746 -63.817246) (xy 251.288296 -63.817246) (xy 251.118116 -63.906146) (xy 251.118116 -64.127126)
			(xy 251.288296 -64.216026) (xy 251.332746 -64.216026)
		)
		(stroke
			(width 0)
			(type solid)
		)
		(fill yes)
		(layer "In11.Cu")
		(net "M_C_DQ<26>")
	)
	(gr_poly
		(pts
			(xy 251.332746 -62.826646) (xy 251.288296 -62.826646) (xy 251.118116 -62.915546) (xy 251.118116 -63.136526)
			(xy 251.288296 -63.225426) (xy 251.332746 -63.225426)
		)
		(stroke
			(width 0)
			(type solid)
		)
		(fill yes)
		(layer "In11.Cu")
		(net "M_C_DQ<26>")
	)
	(gr_poly
		(pts
			(xy 251.332746 -61.836046) (xy 251.288296 -61.836046) (xy 251.118116 -61.924946) (xy 251.118116 -62.145926)
			(xy 251.288296 -62.234826) (xy 251.332746 -62.234826)
		)
		(stroke
			(width 0)
			(type solid)
		)
		(fill yes)
		(layer "In11.Cu")
		(net "M_C_DQ<26>")
	)
	(gr_poly
		(pts
			(xy 251.332746 -60.845446) (xy 251.288296 -60.845446) (xy 251.118116 -60.934346) (xy 251.118116 -61.155326)
			(xy 251.288296 -61.244226) (xy 251.332746 -61.244226)
		)
		(stroke
			(width 0)
			(type solid)
		)
		(fill yes)
		(layer "In11.Cu")
		(net "M_C_DQ<26>")
	)
	(gr_poly
		(pts
			(xy 251.332746 -59.854846) (xy 251.288296 -59.854846) (xy 251.118116 -59.943746) (xy 251.118116 -60.164726)
			(xy 251.288296 -60.253626) (xy 251.332746 -60.253626)
		)
		(stroke
			(width 0)
			(type solid)
		)
		(fill yes)
		(layer "In11.Cu")
		(net "M_C_DQ<26>")
	)
	(gr_poly
		(pts
			(xy 251.332746 -58.857896) (xy 251.288296 -58.857896) (xy 251.118116 -58.946796) (xy 251.118116 -59.167776)
			(xy 251.288296 -59.256676) (xy 251.332746 -59.256676)
		)
		(stroke
			(width 0)
			(type solid)
		)
		(fill yes)
		(layer "In11.Cu")
		(net "M_C_DQ<26>")
	)
	(gr_poly
		(pts
			(xy 251.332746 -57.8612) (xy 251.288296 -57.8612) (xy 251.118116 -57.9501) (xy 251.118116 -58.17108)
			(xy 251.288296 -58.25998) (xy 251.332746 -58.25998)
		)
		(stroke
			(width 0)
			(type solid)
		)
		(fill yes)
		(layer "In11.Cu")
		(net "M_C_DQ<26>")
	)
	(gr_poly
		(pts
			(xy 251.332746 -56.883046) (xy 251.288296 -56.883046) (xy 251.118116 -56.971946) (xy 251.118116 -57.192926)
			(xy 251.288296 -57.281826) (xy 251.332746 -57.281826)
		)
		(stroke
			(width 0)
			(type solid)
		)
		(fill yes)
		(layer "In11.Cu")
		(net "M_C_DQ<26>")
	)
	(gr_poly
		(pts
			(xy 251.332746 -55.892446) (xy 251.288296 -55.892446) (xy 251.118116 -55.981346) (xy 251.118116 -56.202326)
			(xy 251.288296 -56.291226) (xy 251.332746 -56.291226)
		)
		(stroke
			(width 0)
			(type solid)
		)
		(fill yes)
		(layer "In11.Cu")
		(net "M_C_DQ<26>")
	)
	(gr_poly
		(pts
			(xy 251.332746 -54.901846) (xy 251.288296 -54.901846) (xy 251.118116 -54.990746) (xy 251.118116 -55.211726)
			(xy 251.288296 -55.300626) (xy 251.332746 -55.300626)
		)
		(stroke
			(width 0)
			(type solid)
		)
		(fill yes)
		(layer "In11.Cu")
		(net "M_C_DQ<26>")
	)
	(gr_poly
		(pts
			(xy 251.333 -94.530164) (xy 251.28855 -94.530418) (xy 251.11837 -94.619318) (xy 251.11837 -94.840298)
			(xy 251.28855 -94.929198) (xy 251.333 -94.929198)
		)
		(stroke
			(width 0)
			(type solid)
		)
		(fill yes)
		(layer "In11.Cu")
		(net "M_F_DQ<26>")
	)
	(gr_poly
		(pts
			(xy 251.460254 -98.167952) (xy 251.337572 -97.99447) (xy 251.298964 -97.972118) (xy 251.096018 -98.324416)
			(xy 251.134626 -98.346514) (xy 251.346208 -98.365818)
		)
		(stroke
			(width 0)
			(type solid)
		)
		(fill yes)
		(layer "In11.Cu")
		(net "M_F_DQ<27>")
	)
	(gr_poly
		(pts
			(xy 251.5235 -86.599776) (xy 251.47905 -86.599776) (xy 251.30887 -86.688676) (xy 251.30887 -86.909656)
			(xy 251.47905 -86.998556) (xy 251.5235 -86.998556)
		)
		(stroke
			(width 0)
			(type solid)
		)
		(fill yes)
		(layer "In11.Cu")
		(net "M_F_DQ<26>")
	)
	(gr_poly
		(pts
			(xy 251.57303 -93.870018) (xy 251.564902 -93.678248) (xy 251.543058 -93.639894) (xy 251.197618 -93.839284)
			(xy 251.219716 -93.877638) (xy 251.381768 -93.980508)
		)
		(stroke
			(width 0)
			(type solid)
		)
		(fill yes)
		(layer "In11.Cu")
		(net "M_F_DQ<31>")
	)
	(gr_poly
		(pts
			(xy 251.7013 -54.802024) (xy 251.871226 -54.712616) (xy 251.870464 -54.49189) (xy 251.700284 -54.403498)
			(xy 251.655834 -54.403498) (xy 251.656596 -54.802278)
		)
		(stroke
			(width 0)
			(type solid)
		)
		(fill yes)
		(layer "In11.Cu")
		(net "M_C_DQ<27>")
	)
	(gr_poly
		(pts
			(xy 251.791724 -94.112842) (xy 251.769372 -94.074488) (xy 251.60732 -93.971618) (xy 251.416058 -94.082108)
			(xy 251.423932 -94.273878) (xy 251.446284 -94.312486)
		)
		(stroke
			(width 0)
			(type solid)
		)
		(fill yes)
		(layer "In11.Cu")
		(net "M_F_DQ<26>")
	)
	(gr_poly
		(pts
			(xy 251.870718 -93.332808) (xy 251.870718 -93.111828) (xy 251.700538 -93.023182) (xy 251.656342 -93.022928)
			(xy 251.656342 -93.421708) (xy 251.700538 -93.421708)
		)
		(stroke
			(width 0)
			(type solid)
		)
		(fill yes)
		(layer "In11.Cu")
		(net "M_F_DQ<31>")
	)
	(gr_poly
		(pts
			(xy 251.870972 -97.29978) (xy 251.870972 -97.0788) (xy 251.700792 -96.9899) (xy 251.656342 -96.9899)
			(xy 251.656342 -97.38868) (xy 251.700792 -97.38868)
		)
		(stroke
			(width 0)
			(type solid)
		)
		(fill yes)
		(layer "In11.Cu")
		(net "M_F_DQ<27>")
	)
	(gr_poly
		(pts
			(xy 251.870972 -96.30918) (xy 251.870972 -96.0882) (xy 251.700792 -95.9993) (xy 251.656342 -95.9993)
			(xy 251.656342 -96.39808) (xy 251.700792 -96.39808)
		)
		(stroke
			(width 0)
			(type solid)
		)
		(fill yes)
		(layer "In11.Cu")
		(net "M_F_DQ<27>")
	)
	(gr_poly
		(pts
			(xy 251.870972 -95.31858) (xy 251.870972 -95.0976) (xy 251.700792 -95.0087) (xy 251.656342 -95.0087)
			(xy 251.656342 -95.40748) (xy 251.700792 -95.40748)
		)
		(stroke
			(width 0)
			(type solid)
		)
		(fill yes)
		(layer "In11.Cu")
		(net "M_F_DQ<27>")
	)
	(gr_poly
		(pts
			(xy 251.870972 -92.34678) (xy 251.870972 -92.1258) (xy 251.700792 -92.0369) (xy 251.656342 -92.0369)
			(xy 251.656342 -92.43568) (xy 251.700792 -92.43568)
		)
		(stroke
			(width 0)
			(type solid)
		)
		(fill yes)
		(layer "In11.Cu")
		(net "M_F_DQ<31>")
	)
	(gr_poly
		(pts
			(xy 251.870972 -91.35618) (xy 251.870972 -91.1352) (xy 251.700792 -91.0463) (xy 251.656342 -91.0463)
			(xy 251.656342 -91.44508) (xy 251.700792 -91.44508)
		)
		(stroke
			(width 0)
			(type solid)
		)
		(fill yes)
		(layer "In11.Cu")
		(net "M_F_DQ<31>")
	)
	(gr_poly
		(pts
			(xy 251.870972 -90.36558) (xy 251.870972 -90.1446) (xy 251.700792 -90.0557) (xy 251.656342 -90.0557)
			(xy 251.656342 -90.45448) (xy 251.700792 -90.45448)
		)
		(stroke
			(width 0)
			(type solid)
		)
		(fill yes)
		(layer "In11.Cu")
		(net "M_F_DQ<31>")
	)
	(gr_poly
		(pts
			(xy 251.870972 -89.37498) (xy 251.870972 -89.154) (xy 251.700792 -89.0651) (xy 251.656342 -89.0651)
			(xy 251.656342 -89.46388) (xy 251.700792 -89.46388)
		)
		(stroke
			(width 0)
			(type solid)
		)
		(fill yes)
		(layer "In11.Cu")
		(net "M_F_DQ<31>")
	)
	(gr_poly
		(pts
			(xy 251.870972 -88.38438) (xy 251.870972 -88.1634) (xy 251.700792 -88.0745) (xy 251.656342 -88.0745)
			(xy 251.656342 -88.47328) (xy 251.700792 -88.47328)
		)
		(stroke
			(width 0)
			(type solid)
		)
		(fill yes)
		(layer "In11.Cu")
		(net "M_F_DQ<31>")
	)
	(gr_poly
		(pts
			(xy 251.870972 -65.60058) (xy 251.870972 -65.3796) (xy 251.700792 -65.2907) (xy 251.656342 -65.2907)
			(xy 251.656342 -65.68948) (xy 251.700792 -65.68948)
		)
		(stroke
			(width 0)
			(type solid)
		)
		(fill yes)
		(layer "In11.Cu")
		(net "M_C_DQ<27>")
	)
	(gr_poly
		(pts
			(xy 251.870972 -64.60998) (xy 251.870972 -64.389) (xy 251.700792 -64.3001) (xy 251.656342 -64.3001)
			(xy 251.656342 -64.69888) (xy 251.700792 -64.69888)
		)
		(stroke
			(width 0)
			(type solid)
		)
		(fill yes)
		(layer "In11.Cu")
		(net "M_C_DQ<27>")
	)
	(gr_poly
		(pts
			(xy 251.870972 -63.61938) (xy 251.870972 -63.3984) (xy 251.700792 -63.3095) (xy 251.656342 -63.3095)
			(xy 251.656342 -63.70828) (xy 251.700792 -63.70828)
		)
		(stroke
			(width 0)
			(type solid)
		)
		(fill yes)
		(layer "In11.Cu")
		(net "M_C_DQ<27>")
	)
	(gr_poly
		(pts
			(xy 251.870972 -62.62878) (xy 251.870972 -62.4078) (xy 251.700792 -62.3189) (xy 251.656342 -62.3189)
			(xy 251.656342 -62.71768) (xy 251.700792 -62.71768)
		)
		(stroke
			(width 0)
			(type solid)
		)
		(fill yes)
		(layer "In11.Cu")
		(net "M_C_DQ<27>")
	)
	(gr_poly
		(pts
			(xy 251.870972 -61.63818) (xy 251.870972 -61.4172) (xy 251.700792 -61.3283) (xy 251.656342 -61.3283)
			(xy 251.656342 -61.72708) (xy 251.700792 -61.72708)
		)
		(stroke
			(width 0)
			(type solid)
		)
		(fill yes)
		(layer "In11.Cu")
		(net "M_C_DQ<27>")
	)
	(gr_poly
		(pts
			(xy 251.870972 -60.64758) (xy 251.870972 -60.4266) (xy 251.700792 -60.3377) (xy 251.656342 -60.3377)
			(xy 251.656342 -60.73648) (xy 251.700792 -60.73648)
		)
		(stroke
			(width 0)
			(type solid)
		)
		(fill yes)
		(layer "In11.Cu")
		(net "M_C_DQ<27>")
	)
	(gr_poly
		(pts
			(xy 251.870972 -59.65698) (xy 251.870972 -59.436) (xy 251.700792 -59.3471) (xy 251.656342 -59.3471)
			(xy 251.656342 -59.74588) (xy 251.700792 -59.74588)
		)
		(stroke
			(width 0)
			(type solid)
		)
		(fill yes)
		(layer "In11.Cu")
		(net "M_C_DQ<27>")
	)
	(gr_poly
		(pts
			(xy 251.870972 -58.678826) (xy 251.870972 -58.457846) (xy 251.700792 -58.368946) (xy 251.656342 -58.368946)
			(xy 251.656342 -58.767726) (xy 251.700792 -58.767726)
		)
		(stroke
			(width 0)
			(type solid)
		)
		(fill yes)
		(layer "In11.Cu")
		(net "M_C_DQ<27>")
	)
	(gr_poly
		(pts
			(xy 251.870972 -57.68213) (xy 251.870972 -57.46115) (xy 251.700792 -57.37225) (xy 251.656342 -57.37225)
			(xy 251.656342 -57.77103) (xy 251.700792 -57.77103)
		)
		(stroke
			(width 0)
			(type solid)
		)
		(fill yes)
		(layer "In11.Cu")
		(net "M_C_DQ<27>")
	)
	(gr_poly
		(pts
			(xy 251.870972 -56.68518) (xy 251.870972 -56.4642) (xy 251.700792 -56.3753) (xy 251.656342 -56.3753)
			(xy 251.656342 -56.77408) (xy 251.700792 -56.77408)
		)
		(stroke
			(width 0)
			(type solid)
		)
		(fill yes)
		(layer "In11.Cu")
		(net "M_C_DQ<27>")
	)
	(gr_poly
		(pts
			(xy 251.870972 -55.69458) (xy 251.870972 -55.4736) (xy 251.700792 -55.3847) (xy 251.656342 -55.3847)
			(xy 251.656342 -55.78348) (xy 251.700792 -55.78348)
		)
		(stroke
			(width 0)
			(type solid)
		)
		(fill yes)
		(layer "In11.Cu")
		(net "M_C_DQ<27>")
	)
	(gr_poly
		(pts
			(xy 252.191266 -93.03385) (xy 252.146816 -93.03385) (xy 251.976636 -93.12275) (xy 251.976636 -93.34373)
			(xy 252.146816 -93.43263) (xy 252.191266 -93.43263)
		)
		(stroke
			(width 0)
			(type solid)
		)
		(fill yes)
		(layer "In11.Cu")
		(net "M_F_DQ<26>")
	)
	(gr_poly
		(pts
			(xy 252.191266 -92.0369) (xy 252.146816 -92.0369) (xy 251.976636 -92.1258) (xy 251.976636 -92.34678)
			(xy 252.146816 -92.43568) (xy 252.191266 -92.43568)
		)
		(stroke
			(width 0)
			(type solid)
		)
		(fill yes)
		(layer "In11.Cu")
		(net "M_F_DQ<26>")
	)
	(gr_poly
		(pts
			(xy 252.191266 -91.0463) (xy 252.146816 -91.0463) (xy 251.976636 -91.1352) (xy 251.976636 -91.35618)
			(xy 252.146816 -91.44508) (xy 252.191266 -91.44508)
		)
		(stroke
			(width 0)
			(type solid)
		)
		(fill yes)
		(layer "In11.Cu")
		(net "M_F_DQ<26>")
	)
	(gr_poly
		(pts
			(xy 252.191266 -90.0557) (xy 252.146816 -90.0557) (xy 251.976636 -90.1446) (xy 251.976636 -90.36558)
			(xy 252.146816 -90.45448) (xy 252.191266 -90.45448)
		)
		(stroke
			(width 0)
			(type solid)
		)
		(fill yes)
		(layer "In11.Cu")
		(net "M_F_DQ<26>")
	)
	(gr_poly
		(pts
			(xy 252.191266 -89.0651) (xy 252.146816 -89.0651) (xy 251.976636 -89.154) (xy 251.976636 -89.37498)
			(xy 252.146816 -89.46388) (xy 252.191266 -89.46388)
		)
		(stroke
			(width 0)
			(type solid)
		)
		(fill yes)
		(layer "In11.Cu")
		(net "M_F_DQ<26>")
	)
	(gr_poly
		(pts
			(xy 252.191266 -88.0745) (xy 252.146816 -88.0745) (xy 251.976636 -88.1634) (xy 251.976636 -88.38438)
			(xy 252.146816 -88.47328) (xy 252.191266 -88.47328)
		)
		(stroke
			(width 0)
			(type solid)
		)
		(fill yes)
		(layer "In11.Cu")
		(net "M_F_DQ<26>")
	)
	(gr_poly
		(pts
			(xy 252.429772 -94.366588) (xy 252.421644 -94.174818) (xy 252.399546 -94.135956) (xy 252.05436 -94.3356)
			(xy 252.076458 -94.373954) (xy 252.23851 -94.476824)
		)
		(stroke
			(width 0)
			(type solid)
		)
		(fill yes)
		(layer "In11.Cu")
		(net "M_F_DQ<27>")
	)
	(gr_poly
		(pts
			(xy 252.729238 -93.83014) (xy 252.729238 -93.609414) (xy 252.559312 -93.520514) (xy 252.514608 -93.52026)
			(xy 252.514862 -93.91904) (xy 252.559058 -93.91904)
		)
		(stroke
			(width 0)
			(type solid)
		)
		(fill yes)
		(layer "In11.Cu")
		(net "M_F_DQ<27>")
	)
	(gr_poly
		(pts
			(xy 252.729492 -92.854526) (xy 252.729492 -92.633546) (xy 252.559312 -92.544646) (xy 252.514862 -92.544646)
			(xy 252.514862 -92.943426) (xy 252.559312 -92.943426)
		)
		(stroke
			(width 0)
			(type solid)
		)
		(fill yes)
		(layer "In11.Cu")
		(net "M_F_DQ<27>")
	)
	(gr_poly
		(pts
			(xy 252.729492 -91.863926) (xy 252.729492 -91.642946) (xy 252.559312 -91.554046) (xy 252.514862 -91.554046)
			(xy 252.514862 -91.952826) (xy 252.559312 -91.952826)
		)
		(stroke
			(width 0)
			(type solid)
		)
		(fill yes)
		(layer "In11.Cu")
		(net "M_F_DQ<27>")
	)
	(gr_poly
		(pts
			(xy 252.729492 -90.873326) (xy 252.729492 -90.652346) (xy 252.559312 -90.563446) (xy 252.514862 -90.563446)
			(xy 252.514862 -90.962226) (xy 252.559312 -90.962226)
		)
		(stroke
			(width 0)
			(type solid)
		)
		(fill yes)
		(layer "In11.Cu")
		(net "M_F_DQ<27>")
	)
	(gr_poly
		(pts
			(xy 252.729492 -89.882726) (xy 252.729492 -89.661746) (xy 252.559312 -89.572846) (xy 252.514862 -89.572846)
			(xy 252.514862 -89.971626) (xy 252.559312 -89.971626)
		)
		(stroke
			(width 0)
			(type solid)
		)
		(fill yes)
		(layer "In11.Cu")
		(net "M_F_DQ<27>")
	)
	(gr_poly
		(pts
			(xy 252.729492 -88.892126) (xy 252.729492 -88.671146) (xy 252.559312 -88.582246) (xy 252.514862 -88.582246)
			(xy 252.514862 -88.981026) (xy 252.559312 -88.981026)
		)
		(stroke
			(width 0)
			(type solid)
		)
		(fill yes)
		(layer "In11.Cu")
		(net "M_F_DQ<27>")
	)
	(gr_poly
		(pts
			(xy 252.729492 -87.901526) (xy 252.729492 -87.680546) (xy 252.559312 -87.591646) (xy 252.514862 -87.591646)
			(xy 252.514862 -87.990426) (xy 252.559312 -87.990426)
		)
		(stroke
			(width 0)
			(type solid)
		)
		(fill yes)
		(layer "In11.Cu")
		(net "M_F_DQ<27>")
	)
	(gr_poly
		(pts
			(xy 271.17421 -99.297744) (xy 271.12976 -99.297744) (xy 270.95958 -99.386644) (xy 270.95958 -99.607624)
			(xy 271.12976 -99.696524) (xy 271.17421 -99.696524)
		)
		(stroke
			(width 0)
			(type solid)
		)
		(fill yes)
		(layer "In11.Cu")
		(net "M_F_DQ<36>")
	)
	(gr_poly
		(pts
			(xy 271.17421 -98.307144) (xy 271.12976 -98.307144) (xy 270.95958 -98.396044) (xy 270.95958 -98.617024)
			(xy 271.12976 -98.705924) (xy 271.17421 -98.705924)
		)
		(stroke
			(width 0)
			(type solid)
		)
		(fill yes)
		(layer "In11.Cu")
		(net "M_F_DQ<36>")
	)
	(gr_poly
		(pts
			(xy 271.17421 -97.316544) (xy 271.12976 -97.316544) (xy 270.95958 -97.405444) (xy 270.95958 -97.626424)
			(xy 271.12976 -97.715324) (xy 271.17421 -97.715324)
		)
		(stroke
			(width 0)
			(type solid)
		)
		(fill yes)
		(layer "In11.Cu")
		(net "M_F_DQ<36>")
	)
	(gr_poly
		(pts
			(xy 271.17421 -96.325944) (xy 271.12976 -96.325944) (xy 270.95958 -96.414844) (xy 270.95958 -96.635824)
			(xy 271.12976 -96.724724) (xy 271.17421 -96.724724)
		)
		(stroke
			(width 0)
			(type solid)
		)
		(fill yes)
		(layer "In11.Cu")
		(net "M_F_DQ<36>")
	)
	(gr_poly
		(pts
			(xy 271.17421 -95.328994) (xy 271.12976 -95.328994) (xy 270.95958 -95.417894) (xy 270.95958 -95.638874)
			(xy 271.12976 -95.727774) (xy 271.17421 -95.727774)
		)
		(stroke
			(width 0)
			(type solid)
		)
		(fill yes)
		(layer "In11.Cu")
		(net "M_F_DQ<36>")
	)
	(gr_poly
		(pts
			(xy 271.17421 -94.332298) (xy 271.12976 -94.332298) (xy 270.95958 -94.421198) (xy 270.95958 -94.642178)
			(xy 271.12976 -94.731078) (xy 271.17421 -94.731078)
		)
		(stroke
			(width 0)
			(type solid)
		)
		(fill yes)
		(layer "In11.Cu")
		(net "M_F_DQ<36>")
	)
	(gr_poly
		(pts
			(xy 271.347692 -93.088714) (xy 271.309338 -93.066616) (xy 271.117568 -93.058488) (xy 271.007078 -93.24975)
			(xy 271.109948 -93.411802) (xy 271.148556 -93.434154)
		)
		(stroke
			(width 0)
			(type solid)
		)
		(fill yes)
		(layer "In11.Cu")
		(net "M_F_DQ<36>")
	)
	(gr_poly
		(pts
			(xy 271.712436 -99.099878) (xy 271.712436 -98.878898) (xy 271.542256 -98.789998) (xy 271.497806 -98.789998)
			(xy 271.497806 -99.188778) (xy 271.542256 -99.188778)
		)
		(stroke
			(width 0)
			(type solid)
		)
		(fill yes)
		(layer "In11.Cu")
		(net "M_F_DQ<37>")
	)
	(gr_poly
		(pts
			(xy 271.712436 -98.109278) (xy 271.712436 -97.888298) (xy 271.542256 -97.799398) (xy 271.497806 -97.799398)
			(xy 271.497806 -98.198178) (xy 271.542256 -98.198178)
		)
		(stroke
			(width 0)
			(type solid)
		)
		(fill yes)
		(layer "In11.Cu")
		(net "M_F_DQ<37>")
	)
	(gr_poly
		(pts
			(xy 271.712436 -97.118678) (xy 271.712436 -96.897698) (xy 271.542256 -96.808798) (xy 271.497806 -96.808798)
			(xy 271.497806 -97.207578) (xy 271.542256 -97.207578)
		)
		(stroke
			(width 0)
			(type solid)
		)
		(fill yes)
		(layer "In11.Cu")
		(net "M_F_DQ<37>")
	)
	(gr_poly
		(pts
			(xy 271.712436 -96.128078) (xy 271.712436 -95.907098) (xy 271.542256 -95.818198) (xy 271.497806 -95.818198)
			(xy 271.497806 -96.216978) (xy 271.542256 -96.216978)
		)
		(stroke
			(width 0)
			(type solid)
		)
		(fill yes)
		(layer "In11.Cu")
		(net "M_F_DQ<37>")
	)
	(gr_poly
		(pts
			(xy 271.712436 -95.149924) (xy 271.712436 -94.928944) (xy 271.542256 -94.840044) (xy 271.497806 -94.840044)
			(xy 271.497806 -95.238824) (xy 271.542256 -95.238824)
		)
		(stroke
			(width 0)
			(type solid)
		)
		(fill yes)
		(layer "In11.Cu")
		(net "M_F_DQ<37>")
	)
	(gr_poly
		(pts
			(xy 271.712436 -94.153228) (xy 271.712436 -93.932248) (xy 271.542256 -93.843348) (xy 271.497806 -93.843348)
			(xy 271.497806 -94.242128) (xy 271.542256 -94.242128)
		)
		(stroke
			(width 0)
			(type solid)
		)
		(fill yes)
		(layer "In11.Cu")
		(net "M_F_DQ<37>")
	)
	(gr_poly
		(pts
			(xy 271.736566 -100.989384) (xy 271.768062 -100.957888) (xy 271.480788 -100.670614) (xy 271.449292 -100.70211)
			(xy 271.375632 -100.901246) (xy 271.53743 -101.063044)
		)
		(stroke
			(width 0)
			(type solid)
		)
		(fill yes)
		(layer "In11.Cu")
		(net "M_F_DQ<36>")
	)
	(gr_poly
		(pts
			(xy 271.747996 -58.676794) (xy 271.703546 -58.676794) (xy 271.533366 -58.765694) (xy 271.533366 -58.986674)
			(xy 271.703546 -59.075574) (xy 271.747996 -59.075574)
		)
		(stroke
			(width 0)
			(type solid)
		)
		(fill yes)
		(layer "In11.Cu")
		(net "M_C_DQ<36>")
	)
	(gr_poly
		(pts
			(xy 271.74825 -57.692544) (xy 271.7038 -57.692544) (xy 271.53362 -57.781444) (xy 271.53362 -58.002424)
			(xy 271.7038 -58.091324) (xy 271.74825 -58.091324)
		)
		(stroke
			(width 0)
			(type solid)
		)
		(fill yes)
		(layer "In11.Cu")
		(net "M_C_DQ<36>")
	)
	(gr_poly
		(pts
			(xy 271.74825 -56.701944) (xy 271.7038 -56.701944) (xy 271.53362 -56.790844) (xy 271.53362 -57.011824)
			(xy 271.7038 -57.100724) (xy 271.74825 -57.100724)
		)
		(stroke
			(width 0)
			(type solid)
		)
		(fill yes)
		(layer "In11.Cu")
		(net "M_C_DQ<36>")
	)
	(gr_poly
		(pts
			(xy 271.74825 -55.711344) (xy 271.7038 -55.711344) (xy 271.53362 -55.800244) (xy 271.53362 -56.021224)
			(xy 271.7038 -56.110124) (xy 271.74825 -56.110124)
		)
		(stroke
			(width 0)
			(type solid)
		)
		(fill yes)
		(layer "In11.Cu")
		(net "M_C_DQ<36>")
	)
	(gr_poly
		(pts
			(xy 271.74825 -54.720744) (xy 271.7038 -54.720744) (xy 271.53362 -54.809644) (xy 271.53362 -55.030624)
			(xy 271.7038 -55.119524) (xy 271.74825 -55.119524)
		)
		(stroke
			(width 0)
			(type solid)
		)
		(fill yes)
		(layer "In11.Cu")
		(net "M_C_DQ<36>")
	)
	(gr_poly
		(pts
			(xy 271.822164 -52.942998) (xy 271.777714 -52.942998) (xy 271.584674 -53.031898) (xy 271.584674 -53.260498)
			(xy 271.777714 -53.349398) (xy 271.822164 -53.349398)
		)
		(stroke
			(width 0)
			(type solid)
		)
		(fill yes)
		(layer "In11.Cu")
		(net "M_C_DQ<36>")
	)
	(gr_poly
		(pts
			(xy 271.822164 -51.952398) (xy 271.777714 -51.952398) (xy 271.584674 -52.041298) (xy 271.584674 -52.269898)
			(xy 271.777714 -52.358798) (xy 271.822164 -52.358798)
		)
		(stroke
			(width 0)
			(type solid)
		)
		(fill yes)
		(layer "In11.Cu")
		(net "M_C_DQ<36>")
	)
	(gr_poly
		(pts
			(xy 271.934178 -100.791772) (xy 272.007838 -100.592382) (xy 271.846294 -100.430838) (xy 271.646904 -100.504498)
			(xy 271.615408 -100.53574) (xy 271.902936 -100.823268)
		)
		(stroke
			(width 0)
			(type solid)
		)
		(fill yes)
		(layer "In11.Cu")
		(net "M_F_DQ<37>")
	)
	(gr_poly
		(pts
			(xy 272.02892 -103.291386) (xy 271.98447 -103.291386) (xy 271.79143 -103.380286) (xy 271.79143 -103.608886)
			(xy 271.98447 -103.697786) (xy 272.02892 -103.697786)
		)
		(stroke
			(width 0)
			(type solid)
		)
		(fill yes)
		(layer "In11.Cu")
		(net "M_F_DQ<36>")
	)
	(gr_poly
		(pts
			(xy 272.02892 -102.300786) (xy 271.98447 -102.300786) (xy 271.79143 -102.389686) (xy 271.79143 -102.618286)
			(xy 271.98447 -102.707186) (xy 272.02892 -102.707186)
		)
		(stroke
			(width 0)
			(type solid)
		)
		(fill yes)
		(layer "In11.Cu")
		(net "M_F_DQ<36>")
	)
	(gr_poly
		(pts
			(xy 272.02892 -101.310186) (xy 271.98447 -101.310186) (xy 271.79143 -101.399086) (xy 271.79143 -101.627686)
			(xy 271.98447 -101.716586) (xy 272.02892 -101.716586)
		)
		(stroke
			(width 0)
			(type solid)
		)
		(fill yes)
		(layer "In11.Cu")
		(net "M_F_DQ<36>")
	)
	(gr_poly
		(pts
			(xy 272.03273 -99.780598) (xy 271.98828 -99.780598) (xy 271.8181 -99.869498) (xy 271.8181 -100.090478)
			(xy 271.98828 -100.179378) (xy 272.03273 -100.179378)
		)
		(stroke
			(width 0)
			(type solid)
		)
		(fill yes)
		(layer "In11.Cu")
		(net "M_F_DQ<32>")
	)
	(gr_poly
		(pts
			(xy 272.03273 -98.789998) (xy 271.98828 -98.789998) (xy 271.8181 -98.878898) (xy 271.8181 -99.099878)
			(xy 271.98828 -99.188778) (xy 272.03273 -99.188778)
		)
		(stroke
			(width 0)
			(type solid)
		)
		(fill yes)
		(layer "In11.Cu")
		(net "M_F_DQ<32>")
	)
	(gr_poly
		(pts
			(xy 272.03273 -97.799398) (xy 271.98828 -97.799398) (xy 271.8181 -97.888298) (xy 271.8181 -98.109278)
			(xy 271.98828 -98.198178) (xy 272.03273 -98.198178)
		)
		(stroke
			(width 0)
			(type solid)
		)
		(fill yes)
		(layer "In11.Cu")
		(net "M_F_DQ<32>")
	)
	(gr_poly
		(pts
			(xy 272.03273 -96.808798) (xy 271.98828 -96.808798) (xy 271.8181 -96.897698) (xy 271.8181 -97.118678)
			(xy 271.98828 -97.207578) (xy 272.03273 -97.207578)
		)
		(stroke
			(width 0)
			(type solid)
		)
		(fill yes)
		(layer "In11.Cu")
		(net "M_F_DQ<32>")
	)
	(gr_poly
		(pts
			(xy 272.03273 -95.818198) (xy 271.98828 -95.818198) (xy 271.8181 -95.907098) (xy 271.8181 -96.128078)
			(xy 271.98828 -96.216978) (xy 272.03273 -96.216978)
		)
		(stroke
			(width 0)
			(type solid)
		)
		(fill yes)
		(layer "In11.Cu")
		(net "M_F_DQ<32>")
	)
	(gr_poly
		(pts
			(xy 272.03273 -94.840044) (xy 271.98828 -94.840044) (xy 271.8181 -94.928944) (xy 271.8181 -95.149924)
			(xy 271.98828 -95.238824) (xy 272.03273 -95.238824)
		)
		(stroke
			(width 0)
			(type solid)
		)
		(fill yes)
		(layer "In11.Cu")
		(net "M_F_DQ<32>")
	)
	(gr_poly
		(pts
			(xy 272.03273 -93.849444) (xy 271.98828 -93.849444) (xy 271.8181 -93.938344) (xy 271.8181 -94.159324)
			(xy 271.98828 -94.248224) (xy 272.03273 -94.248224)
		)
		(stroke
			(width 0)
			(type solid)
		)
		(fill yes)
		(layer "In11.Cu")
		(net "M_F_DQ<32>")
	)
	(gr_poly
		(pts
			(xy 272.066258 -93.345508) (xy 272.139918 -93.168216) (xy 272.136108 -93.12402) (xy 271.738852 -93.158564)
			(xy 271.742662 -93.203014) (xy 271.84604 -93.364812)
		)
		(stroke
			(width 0)
			(type solid)
		)
		(fill yes)
		(layer "In11.Cu")
		(net "M_F_DQ<37>")
	)
	(gr_poly
		(pts
			(xy 272.180812 -91.61399) (xy 272.140426 -91.595194) (xy 271.948656 -91.60383) (xy 271.855184 -91.803982)
			(xy 271.972024 -91.956382) (xy 272.012156 -91.975178)
		)
		(stroke
			(width 0)
			(type solid)
		)
		(fill yes)
		(layer "In11.Cu")
		(net "M_F_DQ<36>")
	)
	(gr_poly
		(pts
			(xy 272.18386 -51.403758) (xy 272.152364 -51.372262) (xy 271.952974 -51.298602) (xy 271.79143 -51.4604)
			(xy 271.86509 -51.65979) (xy 271.896586 -51.691032)
		)
		(stroke
			(width 0)
			(type solid)
		)
		(fill yes)
		(layer "In11.Cu")
		(net "M_C_DQ<36>")
	)
	(gr_poly
		(pts
			(xy 272.2499 -53.260498) (xy 272.2499 -53.031898) (xy 272.05686 -52.942998) (xy 272.01241 -52.942998)
			(xy 272.01241 -53.349398) (xy 272.05686 -53.349398)
		)
		(stroke
			(width 0)
			(type solid)
		)
		(fill yes)
		(layer "In11.Cu")
		(net "M_C_DQ<37>")
	)
	(gr_poly
		(pts
			(xy 272.2499 -52.269898) (xy 272.2499 -52.041298) (xy 272.05686 -51.952398) (xy 272.01241 -51.952398)
			(xy 272.01241 -52.358798) (xy 272.05686 -52.358798)
		)
		(stroke
			(width 0)
			(type solid)
		)
		(fill yes)
		(layer "In11.Cu")
		(net "M_C_DQ<37>")
	)
	(gr_poly
		(pts
			(xy 272.286476 -58.491374) (xy 272.286476 -58.270394) (xy 272.116296 -58.181494) (xy 272.071846 -58.181494)
			(xy 272.071846 -58.580274) (xy 272.116296 -58.580274)
		)
		(stroke
			(width 0)
			(type solid)
		)
		(fill yes)
		(layer "In11.Cu")
		(net "M_C_DQ<37>")
	)
	(gr_poly
		(pts
			(xy 272.286476 -57.494678) (xy 272.286476 -57.273698) (xy 272.116296 -57.184798) (xy 272.071846 -57.184798)
			(xy 272.071846 -57.583578) (xy 272.116296 -57.583578)
		)
		(stroke
			(width 0)
			(type solid)
		)
		(fill yes)
		(layer "In11.Cu")
		(net "M_C_DQ<37>")
	)
	(gr_poly
		(pts
			(xy 272.286476 -56.504078) (xy 272.286476 -56.283098) (xy 272.116296 -56.194198) (xy 272.071846 -56.194198)
			(xy 272.071846 -56.592978) (xy 272.116296 -56.592978)
		)
		(stroke
			(width 0)
			(type solid)
		)
		(fill yes)
		(layer "In11.Cu")
		(net "M_C_DQ<37>")
	)
	(gr_poly
		(pts
			(xy 272.286476 -55.513478) (xy 272.286476 -55.292498) (xy 272.116296 -55.203598) (xy 272.071846 -55.203598)
			(xy 272.071846 -55.602378) (xy 272.116296 -55.602378)
		)
		(stroke
			(width 0)
			(type solid)
		)
		(fill yes)
		(layer "In11.Cu")
		(net "M_C_DQ<37>")
	)
	(gr_poly
		(pts
			(xy 272.387822 -49.244504) (xy 272.419318 -49.213008) (xy 272.132044 -48.925734) (xy 272.100548 -48.95723)
			(xy 272.026888 -49.156366) (xy 272.188686 -49.318164)
		)
		(stroke
			(width 0)
			(type solid)
		)
		(fill yes)
		(layer "In11.Cu")
		(net "M_C_DQ<36>")
	)
	(gr_poly
		(pts
			(xy 272.461228 -103.608886) (xy 272.461228 -103.380286) (xy 272.268188 -103.291386) (xy 272.223738 -103.291386)
			(xy 272.223738 -103.697786) (xy 272.268188 -103.697786)
		)
		(stroke
			(width 0)
			(type solid)
		)
		(fill yes)
		(layer "In11.Cu")
		(net "M_F_DQ<37>")
	)
	(gr_poly
		(pts
			(xy 272.461228 -102.618286) (xy 272.461228 -102.389686) (xy 272.268188 -102.300786) (xy 272.223738 -102.300786)
			(xy 272.223738 -102.707186) (xy 272.268188 -102.707186)
		)
		(stroke
			(width 0)
			(type solid)
		)
		(fill yes)
		(layer "In11.Cu")
		(net "M_F_DQ<37>")
	)
	(gr_poly
		(pts
			(xy 272.461228 -101.627686) (xy 272.461228 -101.399086) (xy 272.268188 -101.310186) (xy 272.223738 -101.310186)
			(xy 272.223738 -101.716586) (xy 272.268188 -101.716586)
		)
		(stroke
			(width 0)
			(type solid)
		)
		(fill yes)
		(layer "In11.Cu")
		(net "M_F_DQ<37>")
	)
	(gr_poly
		(pts
			(xy 272.477484 -100.635562) (xy 272.499582 -100.597208) (xy 272.154396 -100.397564) (xy 272.132044 -100.436172)
			(xy 272.12417 -100.627942) (xy 272.315432 -100.738432)
		)
		(stroke
			(width 0)
			(type solid)
		)
		(fill yes)
		(layer "In11.Cu")
		(net "M_F_DQ<32>")
	)
	(gr_poly
		(pts
			(xy 272.505932 -49.9872) (xy 272.461482 -49.9872) (xy 272.268442 -50.0761) (xy 272.268442 -50.3047)
			(xy 272.461482 -50.3936) (xy 272.505932 -50.3936)
		)
		(stroke
			(width 0)
			(type solid)
		)
		(fill yes)
		(layer "In11.Cu")
		(net "M_C_DQ<36>")
	)
	(gr_poly
		(pts
			(xy 272.570956 -99.607624) (xy 272.570956 -99.386644) (xy 272.400776 -99.297744) (xy 272.356326 -99.297744)
			(xy 272.356326 -99.696524) (xy 272.400776 -99.696524)
		)
		(stroke
			(width 0)
			(type solid)
		)
		(fill yes)
		(layer "In11.Cu")
		(net "M_F_DQ<33>")
	)
	(gr_poly
		(pts
			(xy 272.570956 -98.617024) (xy 272.570956 -98.396044) (xy 272.400776 -98.307144) (xy 272.356326 -98.307144)
			(xy 272.356326 -98.705924) (xy 272.400776 -98.705924)
		)
		(stroke
			(width 0)
			(type solid)
		)
		(fill yes)
		(layer "In11.Cu")
		(net "M_F_DQ<33>")
	)
	(gr_poly
		(pts
			(xy 272.570956 -97.626424) (xy 272.570956 -97.405444) (xy 272.400776 -97.316544) (xy 272.356326 -97.316544)
			(xy 272.356326 -97.715324) (xy 272.400776 -97.715324)
		)
		(stroke
			(width 0)
			(type solid)
		)
		(fill yes)
		(layer "In11.Cu")
		(net "M_F_DQ<33>")
	)
	(gr_poly
		(pts
			(xy 272.570956 -96.635824) (xy 272.570956 -96.414844) (xy 272.400776 -96.325944) (xy 272.356326 -96.325944)
			(xy 272.356326 -96.724724) (xy 272.400776 -96.724724)
		)
		(stroke
			(width 0)
			(type solid)
		)
		(fill yes)
		(layer "In11.Cu")
		(net "M_F_DQ<33>")
	)
	(gr_poly
		(pts
			(xy 272.570956 -95.638874) (xy 272.570956 -95.417894) (xy 272.400776 -95.328994) (xy 272.356326 -95.328994)
			(xy 272.356326 -95.727774) (xy 272.400776 -95.727774)
		)
		(stroke
			(width 0)
			(type solid)
		)
		(fill yes)
		(layer "In11.Cu")
		(net "M_F_DQ<33>")
	)
	(gr_poly
		(pts
			(xy 272.570956 -94.642178) (xy 272.570956 -94.421198) (xy 272.400776 -94.332298) (xy 272.356326 -94.332298)
			(xy 272.356326 -94.731078) (xy 272.400776 -94.731078)
		)
		(stroke
			(width 0)
			(type solid)
		)
		(fill yes)
		(layer "In11.Cu")
		(net "M_F_DQ<33>")
	)
	(gr_poly
		(pts
			(xy 272.585434 -49.046892) (xy 272.659094 -48.847502) (xy 272.49755 -48.685958) (xy 272.29816 -48.759618)
			(xy 272.266664 -48.79086) (xy 272.554192 -49.078388)
		)
		(stroke
			(width 0)
			(type solid)
		)
		(fill yes)
		(layer "In11.Cu")
		(net "M_C_DQ<37>")
	)
	(gr_poly
		(pts
			(xy 272.603214 -51.589432) (xy 272.529554 -51.390296) (xy 272.498058 -51.3588) (xy 272.210784 -51.646074)
			(xy 272.24228 -51.67757) (xy 272.441416 -51.75123)
		)
		(stroke
			(width 0)
			(type solid)
		)
		(fill yes)
		(layer "In11.Cu")
		(net "M_C_DQ<37>")
	)
	(gr_poly
		(pts
			(xy 272.606516 -58.181494) (xy 272.562066 -58.181494) (xy 272.391886 -58.270394) (xy 272.391886 -58.491374)
			(xy 272.562066 -58.580274) (xy 272.606516 -58.580274)
		)
		(stroke
			(width 0)
			(type solid)
		)
		(fill yes)
		(layer "In11.Cu")
		(net "M_C_DQ<32>")
	)
	(gr_poly
		(pts
			(xy 272.60677 -57.184798) (xy 272.56232 -57.184798) (xy 272.39214 -57.273698) (xy 272.39214 -57.494678)
			(xy 272.56232 -57.583578) (xy 272.60677 -57.583578)
		)
		(stroke
			(width 0)
			(type solid)
		)
		(fill yes)
		(layer "In11.Cu")
		(net "M_C_DQ<32>")
	)
	(gr_poly
		(pts
			(xy 272.60677 -56.194198) (xy 272.56232 -56.194198) (xy 272.39214 -56.283098) (xy 272.39214 -56.504078)
			(xy 272.56232 -56.592978) (xy 272.60677 -56.592978)
		)
		(stroke
			(width 0)
			(type solid)
		)
		(fill yes)
		(layer "In11.Cu")
		(net "M_C_DQ<32>")
	)
	(gr_poly
		(pts
			(xy 272.60677 -55.203598) (xy 272.56232 -55.203598) (xy 272.39214 -55.292498) (xy 272.39214 -55.513478)
			(xy 272.56232 -55.602378) (xy 272.60677 -55.602378)
		)
		(stroke
			(width 0)
			(type solid)
		)
		(fill yes)
		(layer "In11.Cu")
		(net "M_C_DQ<32>")
	)
	(gr_poly
		(pts
			(xy 272.647918 -54.102762) (xy 272.603468 -54.102762) (xy 272.410428 -54.191662) (xy 272.410428 -54.420262)
			(xy 272.603468 -54.509162) (xy 272.647918 -54.509162)
		)
		(stroke
			(width 0)
			(type solid)
		)
		(fill yes)
		(layer "In11.Cu")
		(net "M_C_DQ<32>")
	)
	(gr_poly
		(pts
			(xy 272.647918 -53.112162) (xy 272.603468 -53.112162) (xy 272.410428 -53.201062) (xy 272.410428 -53.429662)
			(xy 272.603468 -53.518562) (xy 272.647918 -53.518562)
		)
		(stroke
			(width 0)
			(type solid)
		)
		(fill yes)
		(layer "In11.Cu")
		(net "M_C_DQ<32>")
	)
	(gr_poly
		(pts
			(xy 272.678144 -59.550046) (xy 272.692114 -59.35853) (xy 272.504154 -59.242198) (xy 272.339054 -59.340242)
			(xy 272.315432 -59.377834) (xy 272.654776 -59.587892)
		)
		(stroke
			(width 0)
			(type solid)
		)
		(fill yes)
		(layer "In11.Cu")
		(net "M_C_DQ<37>")
	)
	(gr_poly
		(pts
			(xy 272.89125 -99.297744) (xy 272.8468 -99.297744) (xy 272.67662 -99.386644) (xy 272.67662 -99.607624)
			(xy 272.8468 -99.696524) (xy 272.89125 -99.696524)
		)
		(stroke
			(width 0)
			(type solid)
		)
		(fill yes)
		(layer "In11.Cu")
		(net "M_F_DQS_DP<13>")
	)
	(gr_poly
		(pts
			(xy 272.89125 -98.307144) (xy 272.8468 -98.307144) (xy 272.67662 -98.396044) (xy 272.67662 -98.617024)
			(xy 272.8468 -98.705924) (xy 272.89125 -98.705924)
		)
		(stroke
			(width 0)
			(type solid)
		)
		(fill yes)
		(layer "In11.Cu")
		(net "M_F_DQS_DP<13>")
	)
	(gr_poly
		(pts
			(xy 272.89125 -97.316544) (xy 272.8468 -97.316544) (xy 272.67662 -97.405444) (xy 272.67662 -97.626424)
			(xy 272.8468 -97.715324) (xy 272.89125 -97.715324)
		)
		(stroke
			(width 0)
			(type solid)
		)
		(fill yes)
		(layer "In11.Cu")
		(net "M_F_DQS_DP<13>")
	)
	(gr_poly
		(pts
			(xy 272.89125 -96.325944) (xy 272.8468 -96.325944) (xy 272.67662 -96.414844) (xy 272.67662 -96.635824)
			(xy 272.8468 -96.724724) (xy 272.89125 -96.724724)
		)
		(stroke
			(width 0)
			(type solid)
		)
		(fill yes)
		(layer "In11.Cu")
		(net "M_F_DQS_DP<13>")
	)
	(gr_poly
		(pts
			(xy 272.89125 -95.328994) (xy 272.8468 -95.328994) (xy 272.67662 -95.417894) (xy 272.67662 -95.638874)
			(xy 272.8468 -95.727774) (xy 272.89125 -95.727774)
		)
		(stroke
			(width 0)
			(type solid)
		)
		(fill yes)
		(layer "In11.Cu")
		(net "M_F_DQS_DP<13>")
	)
	(gr_poly
		(pts
			(xy 272.89125 -94.338394) (xy 272.8468 -94.338394) (xy 272.67662 -94.427294) (xy 272.67662 -94.648274)
			(xy 272.8468 -94.737174) (xy 272.89125 -94.737174)
		)
		(stroke
			(width 0)
			(type solid)
		)
		(fill yes)
		(layer "In11.Cu")
		(net "M_F_DQS_DP<13>")
	)
	(gr_poly
		(pts
			(xy 272.933922 -50.9397) (xy 272.933922 -50.7111) (xy 272.740882 -50.6222) (xy 272.696432 -50.6222)
			(xy 272.696432 -51.0286) (xy 272.740882 -51.0286)
		)
		(stroke
			(width 0)
			(type solid)
		)
		(fill yes)
		(layer "In11.Cu")
		(net "M_C_DQ<37>")
	)
	(gr_poly
		(pts
			(xy 272.933922 -49.9491) (xy 272.933922 -49.7205) (xy 272.740882 -49.6316) (xy 272.696432 -49.6316)
			(xy 272.696432 -50.038) (xy 272.740882 -50.038)
		)
		(stroke
			(width 0)
			(type solid)
		)
		(fill yes)
		(layer "In11.Cu")
		(net "M_C_DQ<37>")
	)
	(gr_poly
		(pts
			(xy 273.024092 -103.228394) (xy 272.979642 -103.228394) (xy 272.786602 -103.317294) (xy 272.786602 -103.545894)
			(xy 272.979642 -103.634794) (xy 273.024092 -103.634794)
		)
		(stroke
			(width 0)
			(type solid)
		)
		(fill yes)
		(layer "In11.Cu")
		(net "M_F_DQ<32>")
	)
	(gr_poly
		(pts
			(xy 273.024092 -102.237794) (xy 272.979642 -102.237794) (xy 272.786602 -102.326694) (xy 272.786602 -102.555294)
			(xy 272.979642 -102.644194) (xy 273.024092 -102.644194)
		)
		(stroke
			(width 0)
			(type solid)
		)
		(fill yes)
		(layer "In11.Cu")
		(net "M_F_DQ<32>")
	)
	(gr_poly
		(pts
			(xy 273.024092 -101.247194) (xy 272.979642 -101.247194) (xy 272.786602 -101.336094) (xy 272.786602 -101.564694)
			(xy 272.979642 -101.653594) (xy 273.024092 -101.653594)
		)
		(stroke
			(width 0)
			(type solid)
		)
		(fill yes)
		(layer "In11.Cu")
		(net "M_F_DQ<32>")
	)
	(gr_poly
		(pts
			(xy 273.031712 -93.526356) (xy 273.023584 -93.334586) (xy 273.001486 -93.295978) (xy 272.656046 -93.495622)
			(xy 272.678398 -93.533976) (xy 272.84045 -93.636846)
		)
		(stroke
			(width 0)
			(type solid)
		)
		(fill yes)
		(layer "In11.Cu")
		(net "M_F_DQ<32>")
	)
	(gr_poly
		(pts
			(xy 273.044158 -61.020706) (xy 272.885916 -60.654438) (xy 272.84553 -60.671964) (xy 272.724626 -60.821316)
			(xy 272.811748 -61.024008) (xy 273.003518 -61.038232)
		)
		(stroke
			(width 0)
			(type solid)
		)
		(fill yes)
		(layer "In11.Cu")
		(net "M_C_DQ<33>")
	)
	(gr_poly
		(pts
			(xy 273.075908 -54.420262) (xy 273.075908 -54.191662) (xy 272.882868 -54.102762) (xy 272.838418 -54.102762)
			(xy 272.838418 -54.509162) (xy 272.882868 -54.509162)
		)
		(stroke
			(width 0)
			(type solid)
		)
		(fill yes)
		(layer "In11.Cu")
		(net "M_C_DQ<33>")
	)
	(gr_poly
		(pts
			(xy 273.075908 -53.429662) (xy 273.075908 -53.201062) (xy 272.882868 -53.112162) (xy 272.838418 -53.112162)
			(xy 272.838418 -53.518562) (xy 272.882868 -53.518562)
		)
		(stroke
			(width 0)
			(type solid)
		)
		(fill yes)
		(layer "In11.Cu")
		(net "M_C_DQ<33>")
	)
	(gr_poly
		(pts
			(xy 273.114262 -100.526088) (xy 273.122136 -100.334318) (xy 272.930874 -100.224082) (xy 272.768822 -100.326952)
			(xy 272.746724 -100.365306) (xy 273.092164 -100.564696)
		)
		(stroke
			(width 0)
			(type solid)
		)
		(fill yes)
		(layer "In11.Cu")
		(net "M_F_DQ<33>")
	)
	(gr_poly
		(pts
			(xy 273.117564 -48.252888) (xy 273.073114 -48.252888) (xy 272.880074 -48.341788) (xy 272.880074 -48.570388)
			(xy 273.073114 -48.659288) (xy 273.117564 -48.659288)
		)
		(stroke
			(width 0)
			(type solid)
		)
		(fill yes)
		(layer "In11.Cu")
		(net "M_C_DQ<32>")
	)
	(gr_poly
		(pts
			(xy 273.131026 -51.540664) (xy 273.09953 -51.509168) (xy 272.900394 -51.435508) (xy 272.738596 -51.597306)
			(xy 272.812256 -51.796442) (xy 272.843752 -51.827938)
		)
		(stroke
			(width 0)
			(type solid)
		)
		(fill yes)
		(layer "In11.Cu")
		(net "M_C_DQ<32>")
	)
	(gr_poly
		(pts
			(xy 273.144742 -58.002424) (xy 273.144742 -57.781444) (xy 272.974562 -57.692544) (xy 272.930112 -57.692544)
			(xy 272.930112 -58.091324) (xy 272.974562 -58.091324)
		)
		(stroke
			(width 0)
			(type solid)
		)
		(fill yes)
		(layer "In11.Cu")
		(net "M_C_DQ<33>")
	)
	(gr_poly
		(pts
			(xy 273.144996 -57.011824) (xy 273.144996 -56.790844) (xy 272.974816 -56.701944) (xy 272.930366 -56.701944)
			(xy 272.930366 -57.100724) (xy 272.974816 -57.100724)
		)
		(stroke
			(width 0)
			(type solid)
		)
		(fill yes)
		(layer "In11.Cu")
		(net "M_C_DQ<33>")
	)
	(gr_poly
		(pts
			(xy 273.144996 -56.021224) (xy 273.144996 -55.800244) (xy 272.974816 -55.711344) (xy 272.930366 -55.711344)
			(xy 272.930366 -56.110124) (xy 272.974816 -56.110124)
		)
		(stroke
			(width 0)
			(type solid)
		)
		(fill yes)
		(layer "In11.Cu")
		(net "M_C_DQ<33>")
	)
	(gr_poly
		(pts
			(xy 273.273012 -50.748438) (xy 273.228562 -50.748438) (xy 273.035522 -50.837338) (xy 273.035522 -51.065938)
			(xy 273.228562 -51.154838) (xy 273.273012 -51.154838)
		)
		(stroke
			(width 0)
			(type solid)
		)
		(fill yes)
		(layer "In11.Cu")
		(net "M_C_DQ<32>")
	)
	(gr_poly
		(pts
			(xy 273.273012 -49.757838) (xy 273.228562 -49.757838) (xy 273.035522 -49.846738) (xy 273.035522 -50.075338)
			(xy 273.228562 -50.164238) (xy 273.273012 -50.164238)
		)
		(stroke
			(width 0)
			(type solid)
		)
		(fill yes)
		(layer "In11.Cu")
		(net "M_C_DQ<32>")
	)
	(gr_poly
		(pts
			(xy 273.337274 -100.140516) (xy 273.359626 -100.102162) (xy 273.013932 -99.902772) (xy 272.991834 -99.94138)
			(xy 272.98396 -100.13315) (xy 273.175222 -100.24364)
		)
		(stroke
			(width 0)
			(type solid)
		)
		(fill yes)
		(layer "In11.Cu")
		(net "M_F_DQS_DP<13>")
	)
	(gr_poly
		(pts
			(xy 273.359372 -93.926406) (xy 273.33702 -93.888052) (xy 273.174968 -93.785182) (xy 272.983706 -93.895418)
			(xy 272.99158 -94.087188) (xy 273.013932 -94.12605)
		)
		(stroke
			(width 0)
			(type solid)
		)
		(fill yes)
		(layer "In11.Cu")
		(net "M_F_DQS_DP<13>")
	)
	(gr_poly
		(pts
			(xy 273.370548 -51.905662) (xy 273.296888 -51.706526) (xy 273.265392 -51.67503) (xy 272.978118 -51.962304)
			(xy 273.009614 -51.9938) (xy 273.20875 -52.06746)
		)
		(stroke
			(width 0)
			(type solid)
		)
		(fill yes)
		(layer "In11.Cu")
		(net "M_C_DQ<33>")
	)
	(gr_poly
		(pts
			(xy 273.429476 -99.099878) (xy 273.429476 -98.878898) (xy 273.259296 -98.789998) (xy 273.214846 -98.789998)
			(xy 273.214846 -99.188778) (xy 273.259296 -99.188778)
		)
		(stroke
			(width 0)
			(type solid)
		)
		(fill yes)
		(layer "In11.Cu")
		(net "M_F_DQS_DN<13>")
	)
	(gr_poly
		(pts
			(xy 273.429476 -98.109278) (xy 273.429476 -97.888298) (xy 273.259296 -97.799398) (xy 273.214846 -97.799398)
			(xy 273.214846 -98.198178) (xy 273.259296 -98.198178)
		)
		(stroke
			(width 0)
			(type solid)
		)
		(fill yes)
		(layer "In11.Cu")
		(net "M_F_DQS_DN<13>")
	)
	(gr_poly
		(pts
			(xy 273.429476 -97.118678) (xy 273.429476 -96.897698) (xy 273.259296 -96.808798) (xy 273.214846 -96.808798)
			(xy 273.214846 -97.207578) (xy 273.259296 -97.207578)
		)
		(stroke
			(width 0)
			(type solid)
		)
		(fill yes)
		(layer "In11.Cu")
		(net "M_F_DQS_DN<13>")
	)
	(gr_poly
		(pts
			(xy 273.429476 -96.128078) (xy 273.429476 -95.907098) (xy 273.259296 -95.818198) (xy 273.214846 -95.818198)
			(xy 273.214846 -96.216978) (xy 273.259296 -96.216978)
		)
		(stroke
			(width 0)
			(type solid)
		)
		(fill yes)
		(layer "In11.Cu")
		(net "M_F_DQS_DN<13>")
	)
	(gr_poly
		(pts
			(xy 273.429476 -95.149924) (xy 273.429476 -94.928944) (xy 273.259296 -94.840044) (xy 273.214846 -94.840044)
			(xy 273.214846 -95.238824) (xy 273.259296 -95.238824)
		)
		(stroke
			(width 0)
			(type solid)
		)
		(fill yes)
		(layer "In11.Cu")
		(net "M_F_DQS_DN<13>")
	)
	(gr_poly
		(pts
			(xy 273.446494 -54.219348) (xy 273.402044 -54.219348) (xy 273.209004 -54.308248) (xy 273.209004 -54.536848)
			(xy 273.402044 -54.625748) (xy 273.446494 -54.625748)
		)
		(stroke
			(width 0)
			(type solid)
		)
		(fill yes)
		(layer "In11.Cu")
		(net "M_C_DQS_DP<13>")
	)
	(gr_poly
		(pts
			(xy 273.446494 -53.228748) (xy 273.402044 -53.228748) (xy 273.209004 -53.317648) (xy 273.209004 -53.546248)
			(xy 273.402044 -53.635148) (xy 273.446494 -53.635148)
		)
		(stroke
			(width 0)
			(type solid)
		)
		(fill yes)
		(layer "In11.Cu")
		(net "M_C_DQS_DP<13>")
	)
	(gr_poly
		(pts
			(xy 273.45259 -103.418894) (xy 273.45259 -103.190294) (xy 273.25955 -103.101394) (xy 273.2151 -103.101394)
			(xy 273.2151 -103.507794) (xy 273.25955 -103.507794)
		)
		(stroke
			(width 0)
			(type solid)
		)
		(fill yes)
		(layer "In11.Cu")
		(net "M_F_DQ<33>")
	)
	(gr_poly
		(pts
			(xy 273.45259 -102.428294) (xy 273.45259 -102.199694) (xy 273.25955 -102.110794) (xy 273.2151 -102.110794)
			(xy 273.2151 -102.517194) (xy 273.25955 -102.517194)
		)
		(stroke
			(width 0)
			(type solid)
		)
		(fill yes)
		(layer "In11.Cu")
		(net "M_F_DQ<33>")
	)
	(gr_poly
		(pts
			(xy 273.45259 -101.437694) (xy 273.45259 -101.209094) (xy 273.25955 -101.120194) (xy 273.2151 -101.120194)
			(xy 273.2151 -101.526594) (xy 273.25955 -101.526594)
		)
		(stroke
			(width 0)
			(type solid)
		)
		(fill yes)
		(layer "In11.Cu")
		(net "M_F_DQ<33>")
	)
	(gr_poly
		(pts
			(xy 273.46529 -57.680098) (xy 273.42084 -57.680098) (xy 273.25066 -57.768998) (xy 273.25066 -57.989978)
			(xy 273.42084 -58.078878) (xy 273.46529 -58.078878)
		)
		(stroke
			(width 0)
			(type solid)
		)
		(fill yes)
		(layer "In11.Cu")
		(net "M_C_DQS_DP<13>")
	)
	(gr_poly
		(pts
			(xy 273.46529 -56.689498) (xy 273.42084 -56.689498) (xy 273.25066 -56.778398) (xy 273.25066 -56.999378)
			(xy 273.42084 -57.088278) (xy 273.46529 -57.088278)
		)
		(stroke
			(width 0)
			(type solid)
		)
		(fill yes)
		(layer "In11.Cu")
		(net "M_C_DQS_DP<13>")
	)
	(gr_poly
		(pts
			(xy 273.46529 -55.698898) (xy 273.42084 -55.698898) (xy 273.25066 -55.787798) (xy 273.25066 -56.008778)
			(xy 273.42084 -56.097678) (xy 273.46529 -56.097678)
		)
		(stroke
			(width 0)
			(type solid)
		)
		(fill yes)
		(layer "In11.Cu")
		(net "M_C_DQS_DP<13>")
	)
	(gr_poly
		(pts
			(xy 273.545554 -48.570388) (xy 273.545554 -48.341788) (xy 273.352514 -48.252888) (xy 273.308064 -48.252888)
			(xy 273.308064 -48.659288) (xy 273.352514 -48.659288)
		)
		(stroke
			(width 0)
			(type solid)
		)
		(fill yes)
		(layer "In11.Cu")
		(net "M_C_DQ<33>")
	)
	(gr_poly
		(pts
			(xy 273.634708 -59.816746) (xy 273.57705 -59.633358) (xy 273.545808 -59.601862) (xy 273.263868 -59.884056)
			(xy 273.29511 -59.915298) (xy 273.478498 -59.972702)
		)
		(stroke
			(width 0)
			(type solid)
		)
		(fill yes)
		(layer "In11.Cu")
		(net "M_C_DQ<33>")
	)
	(gr_poly
		(pts
			(xy 273.701002 -51.065938) (xy 273.701002 -50.837338) (xy 273.507962 -50.748438) (xy 273.463512 -50.748438)
			(xy 273.463512 -51.154838) (xy 273.507962 -51.154838)
		)
		(stroke
			(width 0)
			(type solid)
		)
		(fill yes)
		(layer "In11.Cu")
		(net "M_C_DQ<33>")
	)
	(gr_poly
		(pts
			(xy 273.701002 -50.075338) (xy 273.701002 -49.846738) (xy 273.507962 -49.757838) (xy 273.463512 -49.757838)
			(xy 273.463512 -50.164238) (xy 273.507962 -50.164238)
		)
		(stroke
			(width 0)
			(type solid)
		)
		(fill yes)
		(layer "In11.Cu")
		(net "M_C_DQ<33>")
	)
	(gr_poly
		(pts
			(xy 273.74977 -98.789998) (xy 273.70532 -98.789998) (xy 273.53514 -98.878898) (xy 273.53514 -99.099878)
			(xy 273.70532 -99.188778) (xy 273.74977 -99.188778)
		)
		(stroke
			(width 0)
			(type solid)
		)
		(fill yes)
		(layer "In11.Cu")
		(net "M_F_DQS_DN<4>")
	)
	(gr_poly
		(pts
			(xy 273.74977 -97.799398) (xy 273.70532 -97.799398) (xy 273.53514 -97.888298) (xy 273.53514 -98.109278)
			(xy 273.70532 -98.198178) (xy 273.74977 -98.198178)
		)
		(stroke
			(width 0)
			(type solid)
		)
		(fill yes)
		(layer "In11.Cu")
		(net "M_F_DQS_DN<4>")
	)
	(gr_poly
		(pts
			(xy 273.74977 -96.808798) (xy 273.70532 -96.808798) (xy 273.53514 -96.897698) (xy 273.53514 -97.118678)
			(xy 273.70532 -97.207578) (xy 273.74977 -97.207578)
		)
		(stroke
			(width 0)
			(type solid)
		)
		(fill yes)
		(layer "In11.Cu")
		(net "M_F_DQS_DN<4>")
	)
	(gr_poly
		(pts
			(xy 273.74977 -95.818198) (xy 273.70532 -95.818198) (xy 273.53514 -95.907098) (xy 273.53514 -96.128078)
			(xy 273.70532 -96.216978) (xy 273.74977 -96.216978)
		)
		(stroke
			(width 0)
			(type solid)
		)
		(fill yes)
		(layer "In11.Cu")
		(net "M_F_DQS_DN<4>")
	)
	(gr_poly
		(pts
			(xy 273.750024 -94.838774) (xy 273.705574 -94.838774) (xy 273.535394 -94.927674) (xy 273.535394 -95.148654)
			(xy 273.705574 -95.237554) (xy 273.750024 -95.237554)
		)
		(stroke
			(width 0)
			(type solid)
		)
		(fill yes)
		(layer "In11.Cu")
		(net "M_F_DQS_DN<4>")
	)
	(gr_poly
		(pts
			(xy 273.750024 -92.845382) (xy 273.705574 -92.845382) (xy 273.535394 -92.934282) (xy 273.535394 -93.155262)
			(xy 273.705574 -93.244162) (xy 273.750024 -93.244162)
		)
		(stroke
			(width 0)
			(type solid)
		)
		(fill yes)
		(layer "In11.Cu")
		(net "M_F_DQS_DP<13>")
	)
	(gr_poly
		(pts
			(xy 273.874484 -54.536848) (xy 273.874484 -54.308248) (xy 273.681444 -54.219348) (xy 273.636994 -54.219348)
			(xy 273.636994 -54.625748) (xy 273.681444 -54.625748)
		)
		(stroke
			(width 0)
			(type solid)
		)
		(fill yes)
		(layer "In11.Cu")
		(net "M_C_DQS_DN<13>")
	)
	(gr_poly
		(pts
			(xy 273.874484 -53.546248) (xy 273.874484 -53.317648) (xy 273.681444 -53.228748) (xy 273.636994 -53.228748)
			(xy 273.636994 -53.635148) (xy 273.681444 -53.635148)
		)
		(stroke
			(width 0)
			(type solid)
		)
		(fill yes)
		(layer "In11.Cu")
		(net "M_C_DQS_DN<13>")
	)
	(gr_poly
		(pts
			(xy 273.978116 -100.034598) (xy 273.986244 -99.842828) (xy 273.794982 -99.732338) (xy 273.63293 -99.835208)
			(xy 273.610578 -99.873562) (xy 273.956018 -100.073206)
		)
		(stroke
			(width 0)
			(type solid)
		)
		(fill yes)
		(layer "In11.Cu")
		(net "M_F_DQS_DN<13>")
	)
	(gr_poly
		(pts
			(xy 273.980656 -94.18955) (xy 273.972782 -93.99778) (xy 273.950684 -93.959172) (xy 273.60499 -94.158562)
			(xy 273.627342 -94.196916) (xy 273.789394 -94.30004)
		)
		(stroke
			(width 0)
			(type solid)
		)
		(fill yes)
		(layer "In11.Cu")
		(net "M_F_DQS_DN<13>")
	)
	(gr_poly
		(pts
			(xy 274.003516 -57.507124) (xy 274.003516 -57.286144) (xy 273.833336 -57.197244) (xy 273.788886 -57.197244)
			(xy 273.788886 -57.596024) (xy 273.833336 -57.596024)
		)
		(stroke
			(width 0)
			(type solid)
		)
		(fill yes)
		(layer "In11.Cu")
		(net "M_C_DQS_DN<13>")
	)
	(gr_poly
		(pts
			(xy 274.003516 -56.510174) (xy 274.003516 -56.289194) (xy 273.833336 -56.200294) (xy 273.788886 -56.200294)
			(xy 273.788886 -56.599074) (xy 273.833336 -56.599074)
		)
		(stroke
			(width 0)
			(type solid)
		)
		(fill yes)
		(layer "In11.Cu")
		(net "M_C_DQS_DN<13>")
	)
	(gr_poly
		(pts
			(xy 274.003516 -55.513478) (xy 274.003516 -55.292498) (xy 273.833336 -55.203598) (xy 273.788886 -55.203598)
			(xy 273.788886 -55.602378) (xy 273.833336 -55.602378)
		)
		(stroke
			(width 0)
			(type solid)
		)
		(fill yes)
		(layer "In11.Cu")
		(net "M_C_DQS_DN<13>")
	)
	(gr_poly
		(pts
			(xy 274.040092 -51.163474) (xy 273.995642 -51.163474) (xy 273.802602 -51.252374) (xy 273.802602 -51.480974)
			(xy 273.995642 -51.569874) (xy 274.040092 -51.569874)
		)
		(stroke
			(width 0)
			(type solid)
		)
		(fill yes)
		(layer "In11.Cu")
		(net "M_C_DQS_DP<13>")
	)
	(gr_poly
		(pts
			(xy 274.040092 -50.172874) (xy 273.995642 -50.172874) (xy 273.802602 -50.261774) (xy 273.802602 -50.490374)
			(xy 273.995642 -50.579274) (xy 274.040092 -50.579274)
		)
		(stroke
			(width 0)
			(type solid)
		)
		(fill yes)
		(layer "In11.Cu")
		(net "M_C_DQS_DP<13>")
	)
	(gr_poly
		(pts
			(xy 274.040092 -49.182274) (xy 273.995642 -49.182274) (xy 273.802602 -49.271174) (xy 273.802602 -49.499774)
			(xy 273.995642 -49.588674) (xy 274.040092 -49.588674)
		)
		(stroke
			(width 0)
			(type solid)
		)
		(fill yes)
		(layer "In11.Cu")
		(net "M_C_DQS_DP<13>")
	)
	(gr_poly
		(pts
			(xy 274.040092 -48.191674) (xy 273.995642 -48.191674) (xy 273.802602 -48.280574) (xy 273.802602 -48.509174)
			(xy 273.995642 -48.598074) (xy 274.040092 -48.598074)
		)
		(stroke
			(width 0)
			(type solid)
		)
		(fill yes)
		(layer "In11.Cu")
		(net "M_C_DQS_DP<13>")
	)
	(gr_poly
		(pts
			(xy 274.07616 -52.657248) (xy 274.07616 -52.428648) (xy 273.88312 -52.339748) (xy 273.83867 -52.339748)
			(xy 273.83867 -52.746148) (xy 273.88312 -52.746148)
		)
		(stroke
			(width 0)
			(type solid)
		)
		(fill yes)
		(layer "In11.Cu")
		(net "M_C_DQS_DN<13>")
	)
	(gr_poly
		(pts
			(xy 274.117562 -93.74632) (xy 274.287742 -93.657674) (xy 274.287742 -93.436694) (xy 274.117816 -93.347794)
			(xy 274.073366 -93.34754) (xy 274.073112 -93.746574)
		)
		(stroke
			(width 0)
			(type solid)
		)
		(fill yes)
		(layer "In11.Cu")
		(net "M_F_DQS_DN<13>")
	)
	(gr_poly
		(pts
			(xy 274.188174 -99.641152) (xy 274.210272 -99.602798) (xy 273.865086 -99.403154) (xy 273.842988 -99.442016)
			(xy 273.83486 -99.633786) (xy 274.026122 -99.744022)
		)
		(stroke
			(width 0)
			(type solid)
		)
		(fill yes)
		(layer "In11.Cu")
		(net "M_F_DQS_DN<4>")
	)
	(gr_poly
		(pts
			(xy 274.287996 -98.617024) (xy 274.287996 -98.396044) (xy 274.117816 -98.307144) (xy 274.073366 -98.307144)
			(xy 274.073366 -98.705924) (xy 274.117816 -98.705924)
		)
		(stroke
			(width 0)
			(type solid)
		)
		(fill yes)
		(layer "In11.Cu")
		(net "M_F_DQS_DP<4>")
	)
	(gr_poly
		(pts
			(xy 274.287996 -97.626424) (xy 274.287996 -97.405444) (xy 274.117816 -97.316544) (xy 274.073366 -97.316544)
			(xy 274.073366 -97.715324) (xy 274.117816 -97.715324)
		)
		(stroke
			(width 0)
			(type solid)
		)
		(fill yes)
		(layer "In11.Cu")
		(net "M_F_DQS_DP<4>")
	)
	(gr_poly
		(pts
			(xy 274.287996 -96.635824) (xy 274.287996 -96.414844) (xy 274.117816 -96.325944) (xy 274.073366 -96.325944)
			(xy 274.073366 -96.724724) (xy 274.117816 -96.724724)
		)
		(stroke
			(width 0)
			(type solid)
		)
		(fill yes)
		(layer "In11.Cu")
		(net "M_F_DQS_DP<4>")
	)
	(gr_poly
		(pts
			(xy 274.287996 -95.638874) (xy 274.287996 -95.417894) (xy 274.117816 -95.328994) (xy 274.073366 -95.328994)
			(xy 274.073366 -95.727774) (xy 274.117816 -95.727774)
		)
		(stroke
			(width 0)
			(type solid)
		)
		(fill yes)
		(layer "In11.Cu")
		(net "M_F_DQS_DP<4>")
	)
	(gr_poly
		(pts
			(xy 274.323556 -60.153804) (xy 274.279106 -60.153804) (xy 274.108926 -60.242704) (xy 274.108926 -60.463684)
			(xy 274.279106 -60.552584) (xy 274.323556 -60.552584)
		)
		(stroke
			(width 0)
			(type solid)
		)
		(fill yes)
		(layer "In11.Cu")
		(net "M_C_DQS_DP<4>")
	)
	(gr_poly
		(pts
			(xy 274.323556 -59.178444) (xy 274.279106 -59.178444) (xy 274.108926 -59.267344) (xy 274.108926 -59.488324)
			(xy 274.279106 -59.577224) (xy 274.323556 -59.577224)
		)
		(stroke
			(width 0)
			(type solid)
		)
		(fill yes)
		(layer "In11.Cu")
		(net "M_C_DQS_DP<4>")
	)
	(gr_poly
		(pts
			(xy 274.323556 -58.175398) (xy 274.279106 -58.175398) (xy 274.108926 -58.264298) (xy 274.108926 -58.485278)
			(xy 274.279106 -58.574178) (xy 274.323556 -58.574178)
		)
		(stroke
			(width 0)
			(type solid)
		)
		(fill yes)
		(layer "In11.Cu")
		(net "M_C_DQS_DP<4>")
	)
	(gr_poly
		(pts
			(xy 274.323556 -57.182004) (xy 274.279106 -57.182004) (xy 274.108926 -57.270904) (xy 274.108926 -57.491884)
			(xy 274.279106 -57.580784) (xy 274.323556 -57.580784)
		)
		(stroke
			(width 0)
			(type solid)
		)
		(fill yes)
		(layer "In11.Cu")
		(net "M_C_DQS_DP<4>")
	)
	(gr_poly
		(pts
			(xy 274.323556 -56.191404) (xy 274.279106 -56.191404) (xy 274.108926 -56.280304) (xy 274.108926 -56.501284)
			(xy 274.279106 -56.590184) (xy 274.323556 -56.590184)
		)
		(stroke
			(width 0)
			(type solid)
		)
		(fill yes)
		(layer "In11.Cu")
		(net "M_C_DQS_DP<4>")
	)
	(gr_poly
		(pts
			(xy 274.323556 -55.200804) (xy 274.279106 -55.200804) (xy 274.108926 -55.289704) (xy 274.108926 -55.510684)
			(xy 274.279106 -55.599584) (xy 274.323556 -55.599584)
		)
		(stroke
			(width 0)
			(type solid)
		)
		(fill yes)
		(layer "In11.Cu")
		(net "M_C_DQS_DP<4>")
	)
	(gr_poly
		(pts
			(xy 274.323556 -54.212998) (xy 274.279106 -54.212998) (xy 274.108926 -54.301898) (xy 274.108926 -54.522878)
			(xy 274.279106 -54.611778) (xy 274.323556 -54.611778)
		)
		(stroke
			(width 0)
			(type solid)
		)
		(fill yes)
		(layer "In11.Cu")
		(net "M_C_DQS_DP<4>")
	)
	(gr_poly
		(pts
			(xy 274.323556 -53.236622) (xy 274.279106 -53.236622) (xy 274.108926 -53.325522) (xy 274.108926 -53.546502)
			(xy 274.279106 -53.635402) (xy 274.323556 -53.635402)
		)
		(stroke
			(width 0)
			(type solid)
		)
		(fill yes)
		(layer "In11.Cu")
		(net "M_C_DQS_DP<4>")
	)
	(gr_poly
		(pts
			(xy 274.467828 -51.607974) (xy 274.467828 -51.379374) (xy 274.274788 -51.290474) (xy 274.230338 -51.290474)
			(xy 274.230338 -51.696874) (xy 274.274788 -51.696874)
		)
		(stroke
			(width 0)
			(type solid)
		)
		(fill yes)
		(layer "In11.Cu")
		(net "M_C_DQS_DN<13>")
	)
	(gr_poly
		(pts
			(xy 274.467828 -50.617374) (xy 274.467828 -50.388774) (xy 274.274788 -50.299874) (xy 274.230338 -50.299874)
			(xy 274.230338 -50.706274) (xy 274.274788 -50.706274)
		)
		(stroke
			(width 0)
			(type solid)
		)
		(fill yes)
		(layer "In11.Cu")
		(net "M_C_DQS_DN<13>")
	)
	(gr_poly
		(pts
			(xy 274.467828 -49.626774) (xy 274.467828 -49.398174) (xy 274.274788 -49.309274) (xy 274.230338 -49.309274)
			(xy 274.230338 -49.715674) (xy 274.274788 -49.715674)
		)
		(stroke
			(width 0)
			(type solid)
		)
		(fill yes)
		(layer "In11.Cu")
		(net "M_C_DQS_DN<13>")
	)
	(gr_poly
		(pts
			(xy 274.467828 -48.636174) (xy 274.467828 -48.407574) (xy 274.274788 -48.318674) (xy 274.230338 -48.318674)
			(xy 274.230338 -48.725074) (xy 274.274788 -48.725074)
		)
		(stroke
			(width 0)
			(type solid)
		)
		(fill yes)
		(layer "In11.Cu")
		(net "M_C_DQS_DN<13>")
	)
	(gr_poly
		(pts
			(xy 274.60829 -98.307144) (xy 274.56384 -98.307144) (xy 274.39366 -98.396044) (xy 274.39366 -98.617024)
			(xy 274.56384 -98.705924) (xy 274.60829 -98.705924)
		)
		(stroke
			(width 0)
			(type solid)
		)
		(fill yes)
		(layer "In11.Cu")
		(net "M_F_DQ<38>")
	)
	(gr_poly
		(pts
			(xy 274.60829 -97.316544) (xy 274.56384 -97.316544) (xy 274.39366 -97.405444) (xy 274.39366 -97.626424)
			(xy 274.56384 -97.715324) (xy 274.60829 -97.715324)
		)
		(stroke
			(width 0)
			(type solid)
		)
		(fill yes)
		(layer "In11.Cu")
		(net "M_F_DQ<38>")
	)
	(gr_poly
		(pts
			(xy 274.60829 -96.325944) (xy 274.56384 -96.325944) (xy 274.39366 -96.414844) (xy 274.39366 -96.635824)
			(xy 274.56384 -96.724724) (xy 274.60829 -96.724724)
		)
		(stroke
			(width 0)
			(type solid)
		)
		(fill yes)
		(layer "In11.Cu")
		(net "M_F_DQ<38>")
	)
	(gr_poly
		(pts
			(xy 274.60829 -95.328994) (xy 274.56384 -95.328994) (xy 274.39366 -95.417894) (xy 274.39366 -95.638874)
			(xy 274.56384 -95.727774) (xy 274.60829 -95.727774)
		)
		(stroke
			(width 0)
			(type solid)
		)
		(fill yes)
		(layer "In11.Cu")
		(net "M_F_DQ<38>")
	)
	(gr_poly
		(pts
			(xy 274.60829 -93.354144) (xy 274.56384 -93.354144) (xy 274.39366 -93.443044) (xy 274.39366 -93.664024)
			(xy 274.56384 -93.752924) (xy 274.60829 -93.752924)
		)
		(stroke
			(width 0)
			(type solid)
		)
		(fill yes)
		(layer "In11.Cu")
		(net "M_F_DQ<38>")
	)
	(gr_poly
		(pts
			(xy 274.63496 -100.883974) (xy 274.70862 -100.684584) (xy 274.546822 -100.522786) (xy 274.347432 -100.596446)
			(xy 274.31619 -100.627942) (xy 274.603464 -100.91547)
		)
		(stroke
			(width 0)
			(type solid)
		)
		(fill yes)
		(layer "In11.Cu")
		(net "M_F_DQS_DN<13>")
	)
	(gr_poly
		(pts
			(xy 274.64512 -103.46182) (xy 274.60067 -103.46182) (xy 274.40763 -103.55072) (xy 274.40763 -103.77932)
			(xy 274.60067 -103.86822) (xy 274.64512 -103.86822)
		)
		(stroke
			(width 0)
			(type solid)
		)
		(fill yes)
		(layer "In11.Cu")
		(net "M_F_DQS_DP<13>")
	)
	(gr_poly
		(pts
			(xy 274.64512 -102.47122) (xy 274.60067 -102.47122) (xy 274.40763 -102.56012) (xy 274.40763 -102.78872)
			(xy 274.60067 -102.87762) (xy 274.64512 -102.87762)
		)
		(stroke
			(width 0)
			(type solid)
		)
		(fill yes)
		(layer "In11.Cu")
		(net "M_F_DQS_DP<13>")
	)
	(gr_poly
		(pts
			(xy 274.64512 -101.48062) (xy 274.60067 -101.48062) (xy 274.40763 -101.56952) (xy 274.40763 -101.79812)
			(xy 274.60067 -101.88702) (xy 274.64512 -101.88702)
		)
		(stroke
			(width 0)
			(type solid)
		)
		(fill yes)
		(layer "In11.Cu")
		(net "M_F_DQS_DP<13>")
	)
	(gr_poly
		(pts
			(xy 274.807172 -50.865278) (xy 274.762722 -50.865278) (xy 274.569682 -50.954178) (xy 274.569682 -51.182778)
			(xy 274.762722 -51.271678) (xy 274.807172 -51.271678)
		)
		(stroke
			(width 0)
			(type solid)
		)
		(fill yes)
		(layer "In11.Cu")
		(net "M_C_DQS_DP<4>")
	)
	(gr_poly
		(pts
			(xy 274.807172 -49.874678) (xy 274.762722 -49.874678) (xy 274.569682 -49.963578) (xy 274.569682 -50.192178)
			(xy 274.762722 -50.281078) (xy 274.807172 -50.281078)
		)
		(stroke
			(width 0)
			(type solid)
		)
		(fill yes)
		(layer "In11.Cu")
		(net "M_C_DQS_DP<4>")
	)
	(gr_poly
		(pts
			(xy 274.807172 -48.884078) (xy 274.762722 -48.884078) (xy 274.569682 -48.972978) (xy 274.569682 -49.201578)
			(xy 274.762722 -49.290478) (xy 274.807172 -49.290478)
		)
		(stroke
			(width 0)
			(type solid)
		)
		(fill yes)
		(layer "In11.Cu")
		(net "M_C_DQS_DP<4>")
	)
	(gr_poly
		(pts
			(xy 274.840446 -99.54133) (xy 274.848574 -99.34956) (xy 274.657312 -99.23907) (xy 274.49526 -99.34194)
			(xy 274.472908 -99.380294) (xy 274.818348 -99.579938)
		)
		(stroke
			(width 0)
			(type solid)
		)
		(fill yes)
		(layer "In11.Cu")
		(net "M_F_DQS_DP<4>")
	)
	(gr_poly
		(pts
			(xy 274.861528 -60.956952) (xy 274.861528 -60.735972) (xy 274.691348 -60.647072) (xy 274.646644 -60.647072)
			(xy 274.647152 -61.045852) (xy 274.691348 -61.045852)
		)
		(stroke
			(width 0)
			(type solid)
		)
		(fill yes)
		(layer "In11.Cu")
		(net "M_C_DQS_DN<4>")
	)
	(gr_poly
		(pts
			(xy 274.861782 -54.02453) (xy 274.861782 -53.80355) (xy 274.691602 -53.71465) (xy 274.647152 -53.71465)
			(xy 274.647152 -54.11343) (xy 274.691602 -54.11343)
		)
		(stroke
			(width 0)
			(type solid)
		)
		(fill yes)
		(layer "In11.Cu")
		(net "M_C_DQS_DN<4>")
	)
	(gr_poly
		(pts
			(xy 274.862036 -59.983624) (xy 274.862036 -59.762644) (xy 274.691856 -59.673744) (xy 274.647406 -59.673744)
			(xy 274.647406 -60.072524) (xy 274.691856 -60.072524)
		)
		(stroke
			(width 0)
			(type solid)
		)
		(fill yes)
		(layer "In11.Cu")
		(net "M_C_DQS_DN<4>")
	)
	(gr_poly
		(pts
			(xy 274.862036 -58.980578) (xy 274.862036 -58.759598) (xy 274.691856 -58.670698) (xy 274.647406 -58.670698)
			(xy 274.647406 -59.069478) (xy 274.691856 -59.069478)
		)
		(stroke
			(width 0)
			(type solid)
		)
		(fill yes)
		(layer "In11.Cu")
		(net "M_C_DQS_DN<4>")
	)
	(gr_poly
		(pts
			(xy 274.862036 -58.005218) (xy 274.862036 -57.784238) (xy 274.691856 -57.695338) (xy 274.647406 -57.695338)
			(xy 274.647406 -58.094118) (xy 274.691856 -58.094118)
		)
		(stroke
			(width 0)
			(type solid)
		)
		(fill yes)
		(layer "In11.Cu")
		(net "M_C_DQS_DN<4>")
	)
	(gr_poly
		(pts
			(xy 274.862036 -57.014618) (xy 274.862036 -56.793638) (xy 274.691856 -56.704738) (xy 274.647406 -56.704738)
			(xy 274.647406 -57.103518) (xy 274.691856 -57.103518)
		)
		(stroke
			(width 0)
			(type solid)
		)
		(fill yes)
		(layer "In11.Cu")
		(net "M_C_DQS_DN<4>")
	)
	(gr_poly
		(pts
			(xy 274.862036 -56.024018) (xy 274.862036 -55.803038) (xy 274.691856 -55.714138) (xy 274.647406 -55.714138)
			(xy 274.647406 -56.112918) (xy 274.691856 -56.112918)
		)
		(stroke
			(width 0)
			(type solid)
		)
		(fill yes)
		(layer "In11.Cu")
		(net "M_C_DQS_DN<4>")
	)
	(gr_poly
		(pts
			(xy 274.862036 -55.033418) (xy 274.862036 -54.812438) (xy 274.691856 -54.723538) (xy 274.647406 -54.723538)
			(xy 274.647406 -55.122318) (xy 274.691856 -55.122318)
		)
		(stroke
			(width 0)
			(type solid)
		)
		(fill yes)
		(layer "In11.Cu")
		(net "M_C_DQS_DN<4>")
	)
	(gr_poly
		(pts
			(xy 274.955762 -94.148148) (xy 274.955762 -93.927168) (xy 274.785582 -93.838268) (xy 274.741132 -93.838268)
			(xy 274.741132 -94.237048) (xy 274.785582 -94.237048)
		)
		(stroke
			(width 0)
			(type solid)
		)
		(fill yes)
		(layer "In11.Cu")
		(net "M_F_DQ<38>")
	)
	(gr_poly
		(pts
			(xy 275.05025 -99.147884) (xy 275.072856 -99.10953) (xy 274.727416 -98.909886) (xy 274.705064 -98.948748)
			(xy 274.696936 -99.140518) (xy 274.888452 -99.250754)
		)
		(stroke
			(width 0)
			(type solid)
		)
		(fill yes)
		(layer "In11.Cu")
		(net "M_F_DQ<38>")
	)
	(gr_poly
		(pts
			(xy 275.07311 -103.77932) (xy 275.07311 -103.55072) (xy 274.88007 -103.46182) (xy 274.83562 -103.46182)
			(xy 274.83562 -103.86822) (xy 274.88007 -103.86822)
		)
		(stroke
			(width 0)
			(type solid)
		)
		(fill yes)
		(layer "In11.Cu")
		(net "M_F_DQS_DN<13>")
	)
	(gr_poly
		(pts
			(xy 275.07311 -102.78872) (xy 275.07311 -102.56012) (xy 274.88007 -102.47122) (xy 274.83562 -102.47122)
			(xy 274.83562 -102.87762) (xy 274.88007 -102.87762)
		)
		(stroke
			(width 0)
			(type solid)
		)
		(fill yes)
		(layer "In11.Cu")
		(net "M_F_DQS_DN<13>")
	)
	(gr_poly
		(pts
			(xy 275.07311 -101.79812) (xy 275.07311 -101.56952) (xy 274.88007 -101.48062) (xy 274.83562 -101.48062)
			(xy 274.83562 -101.88702) (xy 274.88007 -101.88702)
		)
		(stroke
			(width 0)
			(type solid)
		)
		(fill yes)
		(layer "In11.Cu")
		(net "M_F_DQS_DN<13>")
	)
	(gr_poly
		(pts
			(xy 275.146516 -98.109278) (xy 275.146516 -97.888298) (xy 274.976336 -97.799398) (xy 274.931886 -97.799398)
			(xy 274.931886 -98.198178) (xy 274.976336 -98.198178)
		)
		(stroke
			(width 0)
			(type solid)
		)
		(fill yes)
		(layer "In11.Cu")
		(net "M_F_DQ<39>")
	)
	(gr_poly
		(pts
			(xy 275.146516 -97.118678) (xy 275.146516 -96.897698) (xy 274.976336 -96.808798) (xy 274.931886 -96.808798)
			(xy 274.931886 -97.207578) (xy 274.976336 -97.207578)
		)
		(stroke
			(width 0)
			(type solid)
		)
		(fill yes)
		(layer "In11.Cu")
		(net "M_F_DQ<39>")
	)
	(gr_poly
		(pts
			(xy 275.146516 -96.128078) (xy 275.146516 -95.907098) (xy 274.976336 -95.818198) (xy 274.931886 -95.818198)
			(xy 274.931886 -96.216978) (xy 274.976336 -96.216978)
		)
		(stroke
			(width 0)
			(type solid)
		)
		(fill yes)
		(layer "In11.Cu")
		(net "M_F_DQ<39>")
	)
	(gr_poly
		(pts
			(xy 275.146516 -95.149924) (xy 275.146516 -94.928944) (xy 274.976336 -94.840044) (xy 274.931886 -94.840044)
			(xy 274.931886 -95.238824) (xy 274.976336 -95.238824)
		)
		(stroke
			(width 0)
			(type solid)
		)
		(fill yes)
		(layer "In11.Cu")
		(net "M_F_DQ<39>")
	)
	(gr_poly
		(pts
			(xy 275.182076 -56.701944) (xy 275.137626 -56.701944) (xy 274.967446 -56.790844) (xy 274.967446 -57.011824)
			(xy 275.137626 -57.100724) (xy 275.182076 -57.100724)
		)
		(stroke
			(width 0)
			(type solid)
		)
		(fill yes)
		(layer "In11.Cu")
		(net "M_C_DQ<38>")
	)
	(gr_poly
		(pts
			(xy 275.182076 -55.711344) (xy 275.137626 -55.711344) (xy 274.967446 -55.800244) (xy 274.967446 -56.021224)
			(xy 275.137626 -56.110124) (xy 275.182076 -56.110124)
		)
		(stroke
			(width 0)
			(type solid)
		)
		(fill yes)
		(layer "In11.Cu")
		(net "M_C_DQ<38>")
	)
	(gr_poly
		(pts
			(xy 275.182076 -54.720744) (xy 275.137626 -54.720744) (xy 274.967446 -54.809644) (xy 274.967446 -55.030624)
			(xy 275.137626 -55.119524) (xy 275.182076 -55.119524)
		)
		(stroke
			(width 0)
			(type solid)
		)
		(fill yes)
		(layer "In11.Cu")
		(net "M_C_DQ<38>")
	)
	(gr_poly
		(pts
			(xy 275.18233 -58.683144) (xy 275.13788 -58.683144) (xy 274.9677 -58.772044) (xy 274.9677 -58.993024)
			(xy 275.13788 -59.081924) (xy 275.18233 -59.081924)
		)
		(stroke
			(width 0)
			(type solid)
		)
		(fill yes)
		(layer "In11.Cu")
		(net "M_C_DQ<38>")
	)
	(gr_poly
		(pts
			(xy 275.18233 -57.692544) (xy 275.13788 -57.692544) (xy 274.9677 -57.781444) (xy 274.9677 -58.002424)
			(xy 275.13788 -58.091324) (xy 275.18233 -58.091324)
		)
		(stroke
			(width 0)
			(type solid)
		)
		(fill yes)
		(layer "In11.Cu")
		(net "M_C_DQ<38>")
	)
	(gr_poly
		(pts
			(xy 275.182584 -52.940458) (xy 275.138134 -52.940458) (xy 274.945094 -53.029358) (xy 274.945094 -53.257958)
			(xy 275.138134 -53.346858) (xy 275.182584 -53.346858)
		)
		(stroke
			(width 0)
			(type solid)
		)
		(fill yes)
		(layer "In11.Cu")
		(net "M_C_DQ<38>")
	)
	(gr_poly
		(pts
			(xy 275.235162 -51.182778) (xy 275.235162 -50.954178) (xy 275.042122 -50.865278) (xy 274.997672 -50.865278)
			(xy 274.997672 -51.271678) (xy 275.042122 -51.271678)
		)
		(stroke
			(width 0)
			(type solid)
		)
		(fill yes)
		(layer "In11.Cu")
		(net "M_C_DQS_DN<4>")
	)
	(gr_poly
		(pts
			(xy 275.235162 -50.192178) (xy 275.235162 -49.963578) (xy 275.042122 -49.874678) (xy 274.997672 -49.874678)
			(xy 274.997672 -50.281078) (xy 275.042122 -50.281078)
		)
		(stroke
			(width 0)
			(type solid)
		)
		(fill yes)
		(layer "In11.Cu")
		(net "M_C_DQS_DN<4>")
	)
	(gr_poly
		(pts
			(xy 275.235162 -49.201578) (xy 275.235162 -48.972978) (xy 275.042122 -48.884078) (xy 274.997672 -48.884078)
			(xy 274.997672 -49.290478) (xy 275.042122 -49.290478)
		)
		(stroke
			(width 0)
			(type solid)
		)
		(fill yes)
		(layer "In11.Cu")
		(net "M_C_DQS_DN<4>")
	)
	(gr_poly
		(pts
			(xy 275.342604 -100.633022) (xy 275.3741 -100.601526) (xy 275.086826 -100.314252) (xy 275.05533 -100.345748)
			(xy 274.98167 -100.544884) (xy 275.143468 -100.706682)
		)
		(stroke
			(width 0)
			(type solid)
		)
		(fill yes)
		(layer "In11.Cu")
		(net "M_F_DQS_DN<4>")
	)
	(gr_poly
		(pts
			(xy 275.3487 -59.77382) (xy 275.305012 -59.7662) (xy 275.121878 -59.824112) (xy 275.083524 -60.04179)
			(xy 275.23567 -60.158884) (xy 275.279612 -60.166504)
		)
		(stroke
			(width 0)
			(type solid)
		)
		(fill yes)
		(layer "In11.Cu")
		(net "M_C_DQ<39>")
	)
	(gr_poly
		(pts
			(xy 275.466556 -97.796604) (xy 275.422106 -97.796604) (xy 275.251926 -97.885504) (xy 275.251926 -98.106484)
			(xy 275.422106 -98.195384) (xy 275.466556 -98.195384)
		)
		(stroke
			(width 0)
			(type solid)
		)
		(fill yes)
		(layer "In11.Cu")
		(net "M_F_DQ<34>")
	)
	(gr_poly
		(pts
			(xy 275.466556 -96.806004) (xy 275.422106 -96.806004) (xy 275.251926 -96.894904) (xy 275.251926 -97.115884)
			(xy 275.422106 -97.204784) (xy 275.466556 -97.204784)
		)
		(stroke
			(width 0)
			(type solid)
		)
		(fill yes)
		(layer "In11.Cu")
		(net "M_F_DQ<34>")
	)
	(gr_poly
		(pts
			(xy 275.466556 -95.815404) (xy 275.422106 -95.815404) (xy 275.251926 -95.904304) (xy 275.251926 -96.125284)
			(xy 275.422106 -96.214184) (xy 275.466556 -96.214184)
		)
		(stroke
			(width 0)
			(type solid)
		)
		(fill yes)
		(layer "In11.Cu")
		(net "M_F_DQ<34>")
	)
	(gr_poly
		(pts
			(xy 275.466556 -94.840044) (xy 275.422106 -94.840044) (xy 275.251926 -94.928944) (xy 275.251926 -95.149924)
			(xy 275.422106 -95.238824) (xy 275.466556 -95.238824)
		)
		(stroke
			(width 0)
			(type solid)
		)
		(fill yes)
		(layer "In11.Cu")
		(net "M_F_DQ<34>")
	)
	(gr_poly
		(pts
			(xy 275.466556 -93.849444) (xy 275.422106 -93.849444) (xy 275.251926 -93.938344) (xy 275.251926 -94.159324)
			(xy 275.422106 -94.248224) (xy 275.466556 -94.248224)
		)
		(stroke
			(width 0)
			(type solid)
		)
		(fill yes)
		(layer "In11.Cu")
		(net "M_F_DQ<34>")
	)
	(gr_poly
		(pts
			(xy 275.54047 -100.435156) (xy 275.61413 -100.23602) (xy 275.452332 -100.074222) (xy 275.253196 -100.147882)
			(xy 275.2217 -100.179378) (xy 275.508974 -100.466652)
		)
		(stroke
			(width 0)
			(type solid)
		)
		(fill yes)
		(layer "In11.Cu")
		(net "M_F_DQS_DP<4>")
	)
	(gr_poly
		(pts
			(xy 275.59762 -103.940356) (xy 275.55317 -103.940356) (xy 275.36013 -104.029256) (xy 275.36013 -104.257856)
			(xy 275.55317 -104.346756) (xy 275.59762 -104.346756)
		)
		(stroke
			(width 0)
			(type solid)
		)
		(fill yes)
		(layer "In11.Cu")
		(net "M_F_DQS_DN<4>")
	)
	(gr_poly
		(pts
			(xy 275.59762 -102.949756) (xy 275.55317 -102.949756) (xy 275.36013 -103.038656) (xy 275.36013 -103.267256)
			(xy 275.55317 -103.356156) (xy 275.59762 -103.356156)
		)
		(stroke
			(width 0)
			(type solid)
		)
		(fill yes)
		(layer "In11.Cu")
		(net "M_F_DQS_DN<4>")
	)
	(gr_poly
		(pts
			(xy 275.59762 -101.959156) (xy 275.55317 -101.959156) (xy 275.36013 -102.048056) (xy 275.36013 -102.276656)
			(xy 275.55317 -102.365556) (xy 275.59762 -102.365556)
		)
		(stroke
			(width 0)
			(type solid)
		)
		(fill yes)
		(layer "In11.Cu")
		(net "M_F_DQS_DN<4>")
	)
	(gr_poly
		(pts
			(xy 275.59762 -100.968556) (xy 275.55317 -100.968556) (xy 275.36013 -101.057456) (xy 275.36013 -101.286056)
			(xy 275.55317 -101.374956) (xy 275.59762 -101.374956)
		)
		(stroke
			(width 0)
			(type solid)
		)
		(fill yes)
		(layer "In11.Cu")
		(net "M_F_DQS_DN<4>")
	)
	(gr_poly
		(pts
			(xy 275.610574 -53.486558) (xy 275.610574 -53.257958) (xy 275.417534 -53.169058) (xy 275.373084 -53.169058)
			(xy 275.373084 -53.575458) (xy 275.417534 -53.575458)
		)
		(stroke
			(width 0)
			(type solid)
		)
		(fill yes)
		(layer "In11.Cu")
		(net "M_C_DQ<39>")
	)
	(gr_poly
		(pts
			(xy 275.683218 -52.24145) (xy 275.651722 -52.210208) (xy 275.452332 -52.136548) (xy 275.290788 -52.298092)
			(xy 275.364448 -52.497482) (xy 275.39569 -52.528978)
		)
		(stroke
			(width 0)
			(type solid)
		)
		(fill yes)
		(layer "In11.Cu")
		(net "M_C_DQ<38>")
	)
	(gr_poly
		(pts
			(xy 275.697442 -99.045014) (xy 275.70557 -98.853244) (xy 275.514308 -98.742754) (xy 275.352256 -98.845624)
			(xy 275.329904 -98.883978) (xy 275.675344 -99.083622)
		)
		(stroke
			(width 0)
			(type solid)
		)
		(fill yes)
		(layer "In11.Cu")
		(net "M_F_DQ<39>")
	)
	(gr_poly
		(pts
			(xy 275.720302 -58.491374) (xy 275.720302 -58.270394) (xy 275.550122 -58.181494) (xy 275.505672 -58.181494)
			(xy 275.505672 -58.580274) (xy 275.550122 -58.580274)
		)
		(stroke
			(width 0)
			(type solid)
		)
		(fill yes)
		(layer "In11.Cu")
		(net "M_C_DQ<39>")
	)
	(gr_poly
		(pts
			(xy 275.720302 -57.494678) (xy 275.720302 -57.273698) (xy 275.550122 -57.184798) (xy 275.505672 -57.184798)
			(xy 275.505672 -57.583578) (xy 275.550122 -57.583578)
		)
		(stroke
			(width 0)
			(type solid)
		)
		(fill yes)
		(layer "In11.Cu")
		(net "M_C_DQ<39>")
	)
	(gr_poly
		(pts
			(xy 275.720302 -56.504078) (xy 275.720302 -56.283098) (xy 275.550122 -56.194198) (xy 275.505672 -56.194198)
			(xy 275.505672 -56.592978) (xy 275.550122 -56.592978)
		)
		(stroke
			(width 0)
			(type solid)
		)
		(fill yes)
		(layer "In11.Cu")
		(net "M_C_DQ<39>")
	)
	(gr_poly
		(pts
			(xy 275.720302 -55.513478) (xy 275.720302 -55.292498) (xy 275.550122 -55.203598) (xy 275.505672 -55.203598)
			(xy 275.505672 -55.602378) (xy 275.550122 -55.602378)
		)
		(stroke
			(width 0)
			(type solid)
		)
		(fill yes)
		(layer "In11.Cu")
		(net "M_C_DQ<39>")
	)
	(gr_poly
		(pts
			(xy 275.720302 -54.522878) (xy 275.720302 -54.301898) (xy 275.550122 -54.212998) (xy 275.505672 -54.212998)
			(xy 275.505672 -54.611778) (xy 275.550122 -54.611778)
		)
		(stroke
			(width 0)
			(type solid)
		)
		(fill yes)
		(layer "In11.Cu")
		(net "M_C_DQ<39>")
	)
	(gr_poly
		(pts
			(xy 275.886164 -50.771552) (xy 275.841714 -50.771552) (xy 275.648674 -50.860452) (xy 275.648674 -51.089052)
			(xy 275.841714 -51.177952) (xy 275.886164 -51.177952)
		)
		(stroke
			(width 0)
			(type solid)
		)
		(fill yes)
		(layer "In11.Cu")
		(net "M_C_DQ<38>")
	)
	(gr_poly
		(pts
			(xy 275.886164 -49.780952) (xy 275.841714 -49.780952) (xy 275.648674 -49.869852) (xy 275.648674 -50.098452)
			(xy 275.841714 -50.187352) (xy 275.886164 -50.187352)
		)
		(stroke
			(width 0)
			(type solid)
		)
		(fill yes)
		(layer "In11.Cu")
		(net "M_C_DQ<38>")
	)
	(gr_poly
		(pts
			(xy 275.886164 -48.790352) (xy 275.841714 -48.790352) (xy 275.648674 -48.879252) (xy 275.648674 -49.107852)
			(xy 275.841714 -49.196752) (xy 275.886164 -49.196752)
		)
		(stroke
			(width 0)
			(type solid)
		)
		(fill yes)
		(layer "In11.Cu")
		(net "M_C_DQ<38>")
	)
	(gr_poly
		(pts
			(xy 275.904706 -99.640898) (xy 275.927058 -99.60229) (xy 275.581618 -99.403154) (xy 275.55952 -99.441508)
			(xy 275.551392 -99.633278) (xy 275.742654 -99.743768)
		)
		(stroke
			(width 0)
			(type solid)
		)
		(fill yes)
		(layer "In11.Cu")
		(net "M_F_DQ<38>")
	)
	(gr_poly
		(pts
			(xy 275.904706 -98.650298) (xy 275.927312 -98.611944) (xy 275.581618 -98.412554) (xy 275.55952 -98.451162)
			(xy 275.551392 -98.642932) (xy 275.742908 -98.753168)
		)
		(stroke
			(width 0)
			(type solid)
		)
		(fill yes)
		(layer "In11.Cu")
		(net "M_F_DQ<34>")
	)
	(gr_poly
		(pts
			(xy 275.928328 -93.428566) (xy 275.902928 -93.39199) (xy 275.732494 -93.303598) (xy 275.551392 -93.430344)
			(xy 275.576284 -93.62059) (xy 275.601684 -93.656912)
		)
		(stroke
			(width 0)
			(type solid)
		)
		(fill yes)
		(layer "In11.Cu")
		(net "M_F_DQ<34>")
	)
	(gr_poly
		(pts
			(xy 275.973286 -52.555902) (xy 275.899626 -52.356512) (xy 275.868384 -52.325016) (xy 275.580856 -52.612544)
			(xy 275.612352 -52.643786) (xy 275.811742 -52.717446)
		)
		(stroke
			(width 0)
			(type solid)
		)
		(fill yes)
		(layer "In11.Cu")
		(net "M_C_DQ<39>")
	)
	(gr_poly
		(pts
			(xy 276.005036 -97.629218) (xy 276.005036 -97.408238) (xy 275.834856 -97.319338) (xy 275.790406 -97.319338)
			(xy 275.790406 -97.718118) (xy 275.834856 -97.718118)
		)
		(stroke
			(width 0)
			(type solid)
		)
		(fill yes)
		(layer "In11.Cu")
		(net "M_F_DQ<35>")
	)
	(gr_poly
		(pts
			(xy 276.005036 -96.638618) (xy 276.005036 -96.417638) (xy 275.834856 -96.328738) (xy 275.790406 -96.328738)
			(xy 275.790406 -96.727518) (xy 275.834856 -96.727518)
		)
		(stroke
			(width 0)
			(type solid)
		)
		(fill yes)
		(layer "In11.Cu")
		(net "M_F_DQ<35>")
	)
	(gr_poly
		(pts
			(xy 276.005036 -95.645224) (xy 276.005036 -95.424244) (xy 275.834856 -95.335344) (xy 275.790406 -95.335344)
			(xy 275.790406 -95.734124) (xy 275.834856 -95.734124)
		)
		(stroke
			(width 0)
			(type solid)
		)
		(fill yes)
		(layer "In11.Cu")
		(net "M_F_DQ<35>")
	)
	(gr_poly
		(pts
			(xy 276.005036 -94.642178) (xy 276.005036 -94.421198) (xy 275.834856 -94.332298) (xy 275.790406 -94.332298)
			(xy 275.790406 -94.731078) (xy 275.834856 -94.731078)
		)
		(stroke
			(width 0)
			(type solid)
		)
		(fill yes)
		(layer "In11.Cu")
		(net "M_F_DQ<35>")
	)
	(gr_poly
		(pts
			(xy 276.02561 -104.257856) (xy 276.02561 -104.029256) (xy 275.83257 -103.940356) (xy 275.78812 -103.940356)
			(xy 275.78812 -104.346756) (xy 275.83257 -104.346756)
		)
		(stroke
			(width 0)
			(type solid)
		)
		(fill yes)
		(layer "In11.Cu")
		(net "M_F_DQS_DP<4>")
	)
	(gr_poly
		(pts
			(xy 276.02561 -103.267256) (xy 276.02561 -103.038656) (xy 275.83257 -102.949756) (xy 275.78812 -102.949756)
			(xy 275.78812 -103.356156) (xy 275.83257 -103.356156)
		)
		(stroke
			(width 0)
			(type solid)
		)
		(fill yes)
		(layer "In11.Cu")
		(net "M_F_DQS_DP<4>")
	)
	(gr_poly
		(pts
			(xy 276.02561 -102.276656) (xy 276.02561 -102.048056) (xy 275.83257 -101.959156) (xy 275.78812 -101.959156)
			(xy 275.78812 -102.365556) (xy 275.83257 -102.365556)
		)
		(stroke
			(width 0)
			(type solid)
		)
		(fill yes)
		(layer "In11.Cu")
		(net "M_F_DQS_DP<4>")
	)
	(gr_poly
		(pts
			(xy 276.02561 -101.286056) (xy 276.02561 -101.057456) (xy 275.83257 -100.968556) (xy 275.78812 -100.968556)
			(xy 275.78812 -101.374956) (xy 275.83257 -101.374956)
		)
		(stroke
			(width 0)
			(type solid)
		)
		(fill yes)
		(layer "In11.Cu")
		(net "M_F_DQS_DP<4>")
	)
	(gr_poly
		(pts
			(xy 276.040596 -58.181748) (xy 275.996146 -58.181748) (xy 275.825966 -58.270648) (xy 275.825966 -58.491628)
			(xy 275.996146 -58.580528) (xy 276.040596 -58.580528)
		)
		(stroke
			(width 0)
			(type solid)
		)
		(fill yes)
		(layer "In11.Cu")
		(net "M_C_DQ<34>")
	)
	(gr_poly
		(pts
			(xy 276.040596 -57.184798) (xy 275.996146 -57.184798) (xy 275.825966 -57.273698) (xy 275.825966 -57.494678)
			(xy 275.996146 -57.583578) (xy 276.040596 -57.583578)
		)
		(stroke
			(width 0)
			(type solid)
		)
		(fill yes)
		(layer "In11.Cu")
		(net "M_C_DQ<34>")
	)
	(gr_poly
		(pts
			(xy 276.040596 -56.194198) (xy 275.996146 -56.194198) (xy 275.825966 -56.283098) (xy 275.825966 -56.504078)
			(xy 275.996146 -56.592978) (xy 276.040596 -56.592978)
		)
		(stroke
			(width 0)
			(type solid)
		)
		(fill yes)
		(layer "In11.Cu")
		(net "M_C_DQ<34>")
	)
	(gr_poly
		(pts
			(xy 276.040596 -55.203598) (xy 275.996146 -55.203598) (xy 275.825966 -55.292498) (xy 275.825966 -55.513478)
			(xy 275.996146 -55.602378) (xy 276.040596 -55.602378)
		)
		(stroke
			(width 0)
			(type solid)
		)
		(fill yes)
		(layer "In11.Cu")
		(net "M_C_DQ<34>")
	)
	(gr_poly
		(pts
			(xy 276.040596 -54.212998) (xy 275.996146 -54.212998) (xy 275.825966 -54.301898) (xy 275.825966 -54.522878)
			(xy 275.996146 -54.611778) (xy 276.040596 -54.611778)
		)
		(stroke
			(width 0)
			(type solid)
		)
		(fill yes)
		(layer "In11.Cu")
		(net "M_C_DQ<34>")
	)
	(gr_poly
		(pts
			(xy 276.040596 -53.196998) (xy 275.996146 -53.196998) (xy 275.825966 -53.285898) (xy 275.825966 -53.506878)
			(xy 275.996146 -53.595778) (xy 276.040596 -53.595778)
		)
		(stroke
			(width 0)
			(type solid)
		)
		(fill yes)
		(layer "In11.Cu")
		(net "M_C_DQ<34>")
	)
	(gr_poly
		(pts
			(xy 276.313646 -51.724052) (xy 276.313646 -51.495452) (xy 276.120606 -51.406552) (xy 276.076156 -51.406552)
			(xy 276.076156 -51.812952) (xy 276.120606 -51.812952)
		)
		(stroke
			(width 0)
			(type solid)
		)
		(fill yes)
		(layer "In11.Cu")
		(net "M_C_DQ<39>")
	)
	(gr_poly
		(pts
			(xy 276.313646 -50.733452) (xy 276.313646 -50.504852) (xy 276.120606 -50.415952) (xy 276.076156 -50.415952)
			(xy 276.076156 -50.822352) (xy 276.120606 -50.822352)
		)
		(stroke
			(width 0)
			(type solid)
		)
		(fill yes)
		(layer "In11.Cu")
		(net "M_C_DQ<39>")
	)
	(gr_poly
		(pts
			(xy 276.313646 -49.742852) (xy 276.313646 -49.514252) (xy 276.120606 -49.425352) (xy 276.076156 -49.425352)
			(xy 276.076156 -49.831752) (xy 276.120606 -49.831752)
		)
		(stroke
			(width 0)
			(type solid)
		)
		(fill yes)
		(layer "In11.Cu")
		(net "M_C_DQ<39>")
	)
	(gr_poly
		(pts
			(xy 276.325076 -97.316544) (xy 276.280626 -97.316544) (xy 276.110446 -97.405444) (xy 276.110446 -97.626424)
			(xy 276.280626 -97.715324) (xy 276.325076 -97.715324)
		)
		(stroke
			(width 0)
			(type solid)
		)
		(fill yes)
		(layer "In11.Cu")
		(net "M_F_DQ<52>")
	)
	(gr_poly
		(pts
			(xy 276.325076 -96.325944) (xy 276.280626 -96.325944) (xy 276.110446 -96.414844) (xy 276.110446 -96.635824)
			(xy 276.280626 -96.724724) (xy 276.325076 -96.724724)
		)
		(stroke
			(width 0)
			(type solid)
		)
		(fill yes)
		(layer "In11.Cu")
		(net "M_F_DQ<52>")
	)
	(gr_poly
		(pts
			(xy 276.325076 -95.328994) (xy 276.280626 -95.328994) (xy 276.110446 -95.417894) (xy 276.110446 -95.638874)
			(xy 276.280626 -95.727774) (xy 276.325076 -95.727774)
		)
		(stroke
			(width 0)
			(type solid)
		)
		(fill yes)
		(layer "In11.Cu")
		(net "M_F_DQ<52>")
	)
	(gr_poly
		(pts
			(xy 276.325076 -94.332298) (xy 276.280626 -94.332298) (xy 276.110446 -94.421198) (xy 276.110446 -94.642178)
			(xy 276.280626 -94.731078) (xy 276.325076 -94.731078)
		)
		(stroke
			(width 0)
			(type solid)
		)
		(fill yes)
		(layer "In11.Cu")
		(net "M_F_DQ<52>")
	)
	(gr_poly
		(pts
			(xy 276.325076 -92.363544) (xy 276.280626 -92.363544) (xy 276.110446 -92.452444) (xy 276.110446 -92.673424)
			(xy 276.280626 -92.762324) (xy 276.325076 -92.762324)
		)
		(stroke
			(width 0)
			(type solid)
		)
		(fill yes)
		(layer "In11.Cu")
		(net "M_F_DQ<52>")
	)
	(gr_poly
		(pts
			(xy 276.325076 -91.372944) (xy 276.280626 -91.372944) (xy 276.110446 -91.461844) (xy 276.110446 -91.682824)
			(xy 276.280626 -91.771724) (xy 276.325076 -91.771724)
		)
		(stroke
			(width 0)
			(type solid)
		)
		(fill yes)
		(layer "In11.Cu")
		(net "M_F_DQ<52>")
	)
	(gr_poly
		(pts
			(xy 276.495002 -52.513992) (xy 276.463506 -52.48275) (xy 276.264116 -52.40909) (xy 276.102572 -52.570634)
			(xy 276.176232 -52.770024) (xy 276.207474 -52.80152)
		)
		(stroke
			(width 0)
			(type solid)
		)
		(fill yes)
		(layer "In11.Cu")
		(net "M_C_DQ<34>")
	)
	(gr_poly
		(pts
			(xy 276.557232 -99.54133) (xy 276.56536 -99.34956) (xy 276.374098 -99.23907) (xy 276.212046 -99.34194)
			(xy 276.189694 -99.380294) (xy 276.535134 -99.579938)
		)
		(stroke
			(width 0)
			(type solid)
		)
		(fill yes)
		(layer "In11.Cu")
		(net "M_F_DQ<39>")
	)
	(gr_poly
		(pts
			(xy 276.557232 -98.55073) (xy 276.56536 -98.35896) (xy 276.374098 -98.24847) (xy 276.212046 -98.35134)
			(xy 276.189694 -98.389694) (xy 276.535134 -98.589338)
		)
		(stroke
			(width 0)
			(type solid)
		)
		(fill yes)
		(layer "In11.Cu")
		(net "M_F_DQ<35>")
	)
	(gr_poly
		(pts
			(xy 276.578822 -59.977274) (xy 276.578822 -59.756294) (xy 276.408642 -59.667394) (xy 276.364192 -59.667394)
			(xy 276.364192 -60.066174) (xy 276.408642 -60.066174)
		)
		(stroke
			(width 0)
			(type solid)
		)
		(fill yes)
		(layer "In11.Cu")
		(net "M_C_DQ<35>")
	)
	(gr_poly
		(pts
			(xy 276.578822 -58.980578) (xy 276.578822 -58.759598) (xy 276.408642 -58.670698) (xy 276.364192 -58.670698)
			(xy 276.364192 -59.069478) (xy 276.408642 -59.069478)
		)
		(stroke
			(width 0)
			(type solid)
		)
		(fill yes)
		(layer "In11.Cu")
		(net "M_C_DQ<35>")
	)
	(gr_poly
		(pts
			(xy 276.578822 -58.002424) (xy 276.578822 -57.781444) (xy 276.408642 -57.692544) (xy 276.364192 -57.692544)
			(xy 276.364192 -58.091324) (xy 276.408642 -58.091324)
		)
		(stroke
			(width 0)
			(type solid)
		)
		(fill yes)
		(layer "In11.Cu")
		(net "M_C_DQ<35>")
	)
	(gr_poly
		(pts
			(xy 276.578822 -57.011824) (xy 276.578822 -56.790844) (xy 276.408642 -56.701944) (xy 276.364192 -56.701944)
			(xy 276.364192 -57.100724) (xy 276.408642 -57.100724)
		)
		(stroke
			(width 0)
			(type solid)
		)
		(fill yes)
		(layer "In11.Cu")
		(net "M_C_DQ<35>")
	)
	(gr_poly
		(pts
			(xy 276.578822 -56.021224) (xy 276.578822 -55.800244) (xy 276.408642 -55.711344) (xy 276.364192 -55.711344)
			(xy 276.364192 -56.110124) (xy 276.408642 -56.110124)
		)
		(stroke
			(width 0)
			(type solid)
		)
		(fill yes)
		(layer "In11.Cu")
		(net "M_C_DQ<35>")
	)
	(gr_poly
		(pts
			(xy 276.578822 -55.030624) (xy 276.578822 -54.809644) (xy 276.408642 -54.720744) (xy 276.364192 -54.720744)
			(xy 276.364192 -55.119524) (xy 276.408642 -55.119524)
		)
		(stroke
			(width 0)
			(type solid)
		)
		(fill yes)
		(layer "In11.Cu")
		(net "M_C_DQ<35>")
	)
	(gr_poly
		(pts
			(xy 276.578822 -54.033674) (xy 276.578822 -53.812694) (xy 276.408642 -53.723794) (xy 276.364192 -53.723794)
			(xy 276.364192 -54.122574) (xy 276.408642 -54.122574)
		)
		(stroke
			(width 0)
			(type solid)
		)
		(fill yes)
		(layer "In11.Cu")
		(net "M_C_DQ<35>")
	)
	(gr_poly
		(pts
			(xy 276.610064 -51.750722) (xy 276.565614 -51.750722) (xy 276.372574 -51.839622) (xy 276.372574 -52.068222)
			(xy 276.565614 -52.157122) (xy 276.610064 -52.157122)
		)
		(stroke
			(width 0)
			(type solid)
		)
		(fill yes)
		(layer "In11.Cu")
		(net "M_C_DQ<34>")
	)
	(gr_poly
		(pts
			(xy 276.610064 -50.760122) (xy 276.565614 -50.760122) (xy 276.372574 -50.849022) (xy 276.372574 -51.077622)
			(xy 276.565614 -51.166522) (xy 276.610064 -51.166522)
		)
		(stroke
			(width 0)
			(type solid)
		)
		(fill yes)
		(layer "In11.Cu")
		(net "M_C_DQ<34>")
	)
	(gr_poly
		(pts
			(xy 276.610064 -49.769522) (xy 276.565614 -49.769522) (xy 276.372574 -49.858422) (xy 276.372574 -50.087022)
			(xy 276.565614 -50.175922) (xy 276.610064 -50.175922)
		)
		(stroke
			(width 0)
			(type solid)
		)
		(fill yes)
		(layer "In11.Cu")
		(net "M_C_DQ<34>")
	)
	(gr_poly
		(pts
			(xy 276.761702 -100.135182) (xy 276.784054 -100.096574) (xy 276.438614 -99.897438) (xy 276.416516 -99.935792)
			(xy 276.408388 -100.127562) (xy 276.59965 -100.238052)
		)
		(stroke
			(width 0)
			(type solid)
		)
		(fill yes)
		(layer "In11.Cu")
		(net "M_F_DQ<38>")
	)
	(gr_poly
		(pts
			(xy 276.761702 -99.144582) (xy 276.784054 -99.105974) (xy 276.438614 -98.906838) (xy 276.416516 -98.945192)
			(xy 276.408388 -99.136962) (xy 276.59965 -99.247452)
		)
		(stroke
			(width 0)
			(type solid)
		)
		(fill yes)
		(layer "In11.Cu")
		(net "M_F_DQ<34>")
	)
	(gr_poly
		(pts
			(xy 276.767036 -98.157284) (xy 276.789642 -98.11893) (xy 276.443948 -97.91954) (xy 276.42185 -97.958148)
			(xy 276.413722 -98.149918) (xy 276.605238 -98.260154)
		)
		(stroke
			(width 0)
			(type solid)
		)
		(fill yes)
		(layer "In11.Cu")
		(net "M_F_DQ<52>")
	)
	(gr_poly
		(pts
			(xy 276.785832 -52.828952) (xy 276.712172 -52.629816) (xy 276.680676 -52.59832) (xy 276.393402 -52.885594)
			(xy 276.424898 -52.91709) (xy 276.624034 -52.99075)
		)
		(stroke
			(width 0)
			(type solid)
		)
		(fill yes)
		(layer "In11.Cu")
		(net "M_C_DQ<35>")
	)
	(gr_poly
		(pts
			(xy 276.863302 -97.118678) (xy 276.863302 -96.897698) (xy 276.693122 -96.808798) (xy 276.648672 -96.808798)
			(xy 276.648672 -97.207578) (xy 276.693122 -97.207578)
		)
		(stroke
			(width 0)
			(type solid)
		)
		(fill yes)
		(layer "In11.Cu")
		(net "M_F_DQ<53>")
	)
	(gr_poly
		(pts
			(xy 276.863302 -96.128078) (xy 276.863302 -95.907098) (xy 276.693122 -95.818198) (xy 276.648672 -95.818198)
			(xy 276.648672 -96.216978) (xy 276.693122 -96.216978)
		)
		(stroke
			(width 0)
			(type solid)
		)
		(fill yes)
		(layer "In11.Cu")
		(net "M_F_DQ<53>")
	)
	(gr_poly
		(pts
			(xy 276.863302 -95.149924) (xy 276.863302 -94.928944) (xy 276.693122 -94.840044) (xy 276.648672 -94.840044)
			(xy 276.648672 -95.238824) (xy 276.693122 -95.238824)
		)
		(stroke
			(width 0)
			(type solid)
		)
		(fill yes)
		(layer "In11.Cu")
		(net "M_F_DQ<53>")
	)
	(gr_poly
		(pts
			(xy 276.863302 -94.153228) (xy 276.863302 -93.932248) (xy 276.693122 -93.843348) (xy 276.648672 -93.843348)
			(xy 276.648672 -94.242128) (xy 276.693122 -94.242128)
		)
		(stroke
			(width 0)
			(type solid)
		)
		(fill yes)
		(layer "In11.Cu")
		(net "M_F_DQ<53>")
	)
	(gr_poly
		(pts
			(xy 276.863302 -93.156278) (xy 276.863302 -92.935298) (xy 276.693122 -92.846398) (xy 276.648672 -92.846398)
			(xy 276.648672 -93.245178) (xy 276.693122 -93.245178)
		)
		(stroke
			(width 0)
			(type solid)
		)
		(fill yes)
		(layer "In11.Cu")
		(net "M_F_DQ<53>")
	)
	(gr_poly
		(pts
			(xy 277.038054 -51.331622) (xy 277.038054 -51.103022) (xy 276.845014 -51.014122) (xy 276.800564 -51.014122)
			(xy 276.800564 -51.420522) (xy 276.845014 -51.420522)
		)
		(stroke
			(width 0)
			(type solid)
		)
		(fill yes)
		(layer "In11.Cu")
		(net "M_C_DQ<35>")
	)
	(gr_poly
		(pts
			(xy 277.038054 -50.341022) (xy 277.038054 -50.112422) (xy 276.845014 -50.023522) (xy 276.800564 -50.023522)
			(xy 276.800564 -50.429922) (xy 276.845014 -50.429922)
		)
		(stroke
			(width 0)
			(type solid)
		)
		(fill yes)
		(layer "In11.Cu")
		(net "M_C_DQ<35>")
	)
	(gr_poly
		(pts
			(xy 277.183596 -101.76764) (xy 277.139146 -101.76764) (xy 276.968966 -101.85654) (xy 276.968966 -102.07752)
			(xy 277.139146 -102.16642) (xy 277.183596 -102.16642)
		)
		(stroke
			(width 0)
			(type solid)
		)
		(fill yes)
		(layer "In11.Cu")
		(net "M_F_DQ<38>")
	)
	(gr_poly
		(pts
			(xy 277.183596 -100.783136) (xy 277.139146 -100.783136) (xy 276.968966 -100.872036) (xy 276.968966 -101.093016)
			(xy 277.139146 -101.181916) (xy 277.183596 -101.181916)
		)
		(stroke
			(width 0)
			(type solid)
		)
		(fill yes)
		(layer "In11.Cu")
		(net "M_F_DQ<38>")
	)
	(gr_poly
		(pts
			(xy 277.183596 -96.808798) (xy 277.139146 -96.808798) (xy 276.968966 -96.897698) (xy 276.968966 -97.118678)
			(xy 277.139146 -97.207578) (xy 277.183596 -97.207578)
		)
		(stroke
			(width 0)
			(type solid)
		)
		(fill yes)
		(layer "In11.Cu")
		(net "M_F_DQ<48>")
	)
	(gr_poly
		(pts
			(xy 277.183596 -95.818198) (xy 277.139146 -95.818198) (xy 276.968966 -95.907098) (xy 276.968966 -96.128078)
			(xy 277.139146 -96.216978) (xy 277.183596 -96.216978)
		)
		(stroke
			(width 0)
			(type solid)
		)
		(fill yes)
		(layer "In11.Cu")
		(net "M_F_DQ<48>")
	)
	(gr_poly
		(pts
			(xy 277.183596 -94.840044) (xy 277.139146 -94.840044) (xy 276.968966 -94.928944) (xy 276.968966 -95.149924)
			(xy 277.139146 -95.238824) (xy 277.183596 -95.238824)
		)
		(stroke
			(width 0)
			(type solid)
		)
		(fill yes)
		(layer "In11.Cu")
		(net "M_F_DQ<48>")
	)
	(gr_poly
		(pts
			(xy 277.183596 -93.843348) (xy 277.139146 -93.843348) (xy 276.968966 -93.932248) (xy 276.968966 -94.153228)
			(xy 277.139146 -94.242128) (xy 277.183596 -94.242128)
		)
		(stroke
			(width 0)
			(type solid)
		)
		(fill yes)
		(layer "In11.Cu")
		(net "M_F_DQ<48>")
	)
	(gr_poly
		(pts
			(xy 277.183596 -92.846398) (xy 277.139146 -92.846398) (xy 276.968966 -92.935298) (xy 276.968966 -93.156278)
			(xy 277.139146 -93.245178) (xy 277.183596 -93.245178)
		)
		(stroke
			(width 0)
			(type solid)
		)
		(fill yes)
		(layer "In11.Cu")
		(net "M_F_DQ<48>")
	)
	(gr_poly
		(pts
			(xy 277.183596 -91.855798) (xy 277.139146 -91.855798) (xy 276.968966 -91.944698) (xy 276.968966 -92.165678)
			(xy 277.139146 -92.254578) (xy 277.183596 -92.254578)
		)
		(stroke
			(width 0)
			(type solid)
		)
		(fill yes)
		(layer "In11.Cu")
		(net "M_F_DQ<48>")
	)
	(gr_poly
		(pts
			(xy 277.183596 -90.865198) (xy 277.139146 -90.865198) (xy 276.968966 -90.954098) (xy 276.968966 -91.175078)
			(xy 277.139146 -91.263978) (xy 277.183596 -91.263978)
		)
		(stroke
			(width 0)
			(type solid)
		)
		(fill yes)
		(layer "In11.Cu")
		(net "M_F_DQ<48>")
	)
	(gr_poly
		(pts
			(xy 277.353776 -48.65878) (xy 277.32228 -48.627538) (xy 277.12289 -48.553878) (xy 276.961346 -48.715422)
			(xy 277.035006 -48.914812) (xy 277.066248 -48.946308)
		)
		(stroke
			(width 0)
			(type solid)
		)
		(fill yes)
		(layer "In11.Cu")
		(net "M_C_DQ<34>")
	)
	(gr_poly
		(pts
			(xy 277.414228 -99.045014) (xy 277.422356 -98.853244) (xy 277.231094 -98.742754) (xy 277.069042 -98.845624)
			(xy 277.04669 -98.883978) (xy 277.39213 -99.083622)
		)
		(stroke
			(width 0)
			(type solid)
		)
		(fill yes)
		(layer "In11.Cu")
		(net "M_F_DQ<35>")
	)
	(gr_poly
		(pts
			(xy 277.414228 -98.054414) (xy 277.422356 -97.862644) (xy 277.231094 -97.752154) (xy 277.069042 -97.855024)
			(xy 277.04669 -97.893378) (xy 277.39213 -98.093022)
		)
		(stroke
			(width 0)
			(type solid)
		)
		(fill yes)
		(layer "In11.Cu")
		(net "M_F_DQ<53>")
	)
	(gr_poly
		(pts
			(xy 277.415752 -100.03663) (xy 277.42388 -99.84486) (xy 277.232618 -99.73437) (xy 277.070566 -99.83724)
			(xy 277.048214 -99.875594) (xy 277.393654 -100.075238)
		)
		(stroke
			(width 0)
			(type solid)
		)
		(fill yes)
		(layer "In11.Cu")
		(net "M_F_DQ<39>")
	)
	(gr_poly
		(pts
			(xy 277.593552 -49.02454) (xy 277.519892 -48.82515) (xy 277.48865 -48.793654) (xy 277.201122 -49.081182)
			(xy 277.232618 -49.112424) (xy 277.432008 -49.186084)
		)
		(stroke
			(width 0)
			(type solid)
		)
		(fill yes)
		(layer "In11.Cu")
		(net "M_C_DQ<35>")
	)
	(gr_poly
		(pts
			(xy 277.621746 -98.650298) (xy 277.644098 -98.61169) (xy 277.298658 -98.412554) (xy 277.27656 -98.450908)
			(xy 277.268432 -98.642678) (xy 277.459694 -98.753168)
		)
		(stroke
			(width 0)
			(type solid)
		)
		(fill yes)
		(layer "In11.Cu")
		(net "M_F_DQ<52>")
	)
	(gr_poly
		(pts
			(xy 277.622 -97.659952) (xy 277.644352 -97.621598) (xy 277.298658 -97.422208) (xy 277.276814 -97.460816)
			(xy 277.268686 -97.652586) (xy 277.459948 -97.762822)
		)
		(stroke
			(width 0)
			(type solid)
		)
		(fill yes)
		(layer "In11.Cu")
		(net "M_F_DQ<48>")
	)
	(gr_poly
		(pts
			(xy 277.628858 -99.63912) (xy 277.65121 -99.600766) (xy 277.30577 -99.401122) (xy 277.283672 -99.43973)
			(xy 277.275544 -99.6315) (xy 277.466806 -99.74199)
		)
		(stroke
			(width 0)
			(type solid)
		)
		(fill yes)
		(layer "In11.Cu")
		(net "M_F_DQ<34>")
	)
	(gr_poly
		(pts
			(xy 277.721822 -102.57917) (xy 277.721822 -102.35819) (xy 277.551642 -102.26929) (xy 277.507192 -102.26929)
			(xy 277.507192 -102.66807) (xy 277.551642 -102.66807)
		)
		(stroke
			(width 0)
			(type solid)
		)
		(fill yes)
		(layer "In11.Cu")
		(net "M_F_DQ<39>")
	)
	(gr_poly
		(pts
			(xy 277.721822 -101.58222) (xy 277.721822 -101.36124) (xy 277.551642 -101.27234) (xy 277.507192 -101.27234)
			(xy 277.507192 -101.67112) (xy 277.551642 -101.67112)
		)
		(stroke
			(width 0)
			(type solid)
		)
		(fill yes)
		(layer "In11.Cu")
		(net "M_F_DQ<39>")
	)
	(gr_poly
		(pts
			(xy 277.721822 -100.59162) (xy 277.721822 -100.37064) (xy 277.551642 -100.28174) (xy 277.507192 -100.28174)
			(xy 277.507192 -100.68052) (xy 277.551642 -100.68052)
		)
		(stroke
			(width 0)
			(type solid)
		)
		(fill yes)
		(layer "In11.Cu")
		(net "M_F_DQ<39>")
	)
	(gr_poly
		(pts
			(xy 277.721822 -96.635824) (xy 277.721822 -96.414844) (xy 277.551642 -96.325944) (xy 277.507192 -96.325944)
			(xy 277.507192 -96.724724) (xy 277.551642 -96.724724)
		)
		(stroke
			(width 0)
			(type solid)
		)
		(fill yes)
		(layer "In11.Cu")
		(net "M_F_DQ<49>")
	)
	(gr_poly
		(pts
			(xy 277.721822 -95.638874) (xy 277.721822 -95.417894) (xy 277.551642 -95.328994) (xy 277.507192 -95.328994)
			(xy 277.507192 -95.727774) (xy 277.551642 -95.727774)
		)
		(stroke
			(width 0)
			(type solid)
		)
		(fill yes)
		(layer "In11.Cu")
		(net "M_F_DQ<49>")
	)
	(gr_poly
		(pts
			(xy 277.721822 -94.642178) (xy 277.721822 -94.421198) (xy 277.551642 -94.332298) (xy 277.507192 -94.332298)
			(xy 277.507192 -94.731078) (xy 277.551642 -94.731078)
		)
		(stroke
			(width 0)
			(type solid)
		)
		(fill yes)
		(layer "In11.Cu")
		(net "M_F_DQ<49>")
	)
	(gr_poly
		(pts
			(xy 277.721822 -93.664024) (xy 277.721822 -93.443044) (xy 277.551642 -93.354144) (xy 277.507192 -93.354144)
			(xy 277.507192 -93.752924) (xy 277.551642 -93.752924)
		)
		(stroke
			(width 0)
			(type solid)
		)
		(fill yes)
		(layer "In11.Cu")
		(net "M_F_DQ<49>")
	)
	(gr_poly
		(pts
			(xy 278.042116 -102.273354) (xy 277.997666 -102.273354) (xy 277.827486 -102.362254) (xy 277.827486 -102.583234)
			(xy 277.997666 -102.672134) (xy 278.042116 -102.672134)
		)
		(stroke
			(width 0)
			(type solid)
		)
		(fill yes)
		(layer "In11.Cu")
		(net "M_F_DQ<34>")
	)
	(gr_poly
		(pts
			(xy 278.042116 -101.272086) (xy 277.997666 -101.272086) (xy 277.827486 -101.360986) (xy 277.827486 -101.581966)
			(xy 277.997666 -101.670866) (xy 278.042116 -101.670866)
		)
		(stroke
			(width 0)
			(type solid)
		)
		(fill yes)
		(layer "In11.Cu")
		(net "M_F_DQ<34>")
	)
	(gr_poly
		(pts
			(xy 278.042116 -100.27539) (xy 277.997666 -100.27539) (xy 277.827486 -100.36429) (xy 277.827486 -100.58527)
			(xy 277.997666 -100.67417) (xy 278.042116 -100.67417)
		)
		(stroke
			(width 0)
			(type solid)
		)
		(fill yes)
		(layer "In11.Cu")
		(net "M_F_DQ<34>")
	)
	(gr_poly
		(pts
			(xy 278.042116 -96.319594) (xy 277.997666 -96.319594) (xy 277.827486 -96.408494) (xy 277.827486 -96.629474)
			(xy 277.997666 -96.718374) (xy 278.042116 -96.718374)
		)
		(stroke
			(width 0)
			(type solid)
		)
		(fill yes)
		(layer "In11.Cu")
		(net "M_F_DQS_DP<15>")
	)
	(gr_poly
		(pts
			(xy 278.042116 -95.328994) (xy 277.997666 -95.328994) (xy 277.827486 -95.417894) (xy 277.827486 -95.638874)
			(xy 277.997666 -95.727774) (xy 278.042116 -95.727774)
		)
		(stroke
			(width 0)
			(type solid)
		)
		(fill yes)
		(layer "In11.Cu")
		(net "M_F_DQS_DP<15>")
	)
	(gr_poly
		(pts
			(xy 278.042116 -94.332298) (xy 277.997666 -94.332298) (xy 277.827486 -94.421198) (xy 277.827486 -94.642178)
			(xy 277.997666 -94.731078) (xy 278.042116 -94.731078)
		)
		(stroke
			(width 0)
			(type solid)
		)
		(fill yes)
		(layer "In11.Cu")
		(net "M_F_DQS_DP<15>")
	)
	(gr_poly
		(pts
			(xy 278.042116 -93.354144) (xy 277.997666 -93.354144) (xy 277.827486 -93.443044) (xy 277.827486 -93.664024)
			(xy 277.997666 -93.752924) (xy 278.042116 -93.752924)
		)
		(stroke
			(width 0)
			(type solid)
		)
		(fill yes)
		(layer "In11.Cu")
		(net "M_F_DQS_DP<15>")
	)
	(gr_poly
		(pts
			(xy 278.042116 -92.363544) (xy 277.997666 -92.363544) (xy 277.827486 -92.452444) (xy 277.827486 -92.673424)
			(xy 277.997666 -92.762324) (xy 278.042116 -92.762324)
		)
		(stroke
			(width 0)
			(type solid)
		)
		(fill yes)
		(layer "In11.Cu")
		(net "M_F_DQS_DP<15>")
	)
	(gr_poly
		(pts
			(xy 278.042116 -91.372944) (xy 277.997666 -91.372944) (xy 277.827486 -91.461844) (xy 277.827486 -91.682824)
			(xy 277.997666 -91.771724) (xy 278.042116 -91.771724)
		)
		(stroke
			(width 0)
			(type solid)
		)
		(fill yes)
		(layer "In11.Cu")
		(net "M_F_DQS_DP<15>")
	)
	(gr_poly
		(pts
			(xy 278.042116 -90.382344) (xy 277.997666 -90.382344) (xy 277.827486 -90.471244) (xy 277.827486 -90.692224)
			(xy 277.997666 -90.781124) (xy 278.042116 -90.781124)
		)
		(stroke
			(width 0)
			(type solid)
		)
		(fill yes)
		(layer "In11.Cu")
		(net "M_F_DQS_DP<15>")
	)
	(gr_poly
		(pts
			(xy 278.272748 -99.540314) (xy 278.280876 -99.348544) (xy 278.089614 -99.238054) (xy 277.927562 -99.340924)
			(xy 277.90521 -99.379278) (xy 278.25065 -99.578922)
		)
		(stroke
			(width 0)
			(type solid)
		)
		(fill yes)
		(layer "In11.Cu")
		(net "M_F_DQ<35>")
	)
	(gr_poly
		(pts
			(xy 278.274272 -98.55073) (xy 278.2824 -98.35896) (xy 278.091138 -98.24847) (xy 277.929086 -98.35134)
			(xy 277.906734 -98.389694) (xy 278.252174 -98.589338)
		)
		(stroke
			(width 0)
			(type solid)
		)
		(fill yes)
		(layer "In11.Cu")
		(net "M_F_DQ<53>")
	)
	(gr_poly
		(pts
			(xy 278.274272 -97.56013) (xy 278.2824 -97.36836) (xy 278.091138 -97.25787) (xy 277.929086 -97.36074)
			(xy 277.906734 -97.399094) (xy 278.252174 -97.598738)
		)
		(stroke
			(width 0)
			(type solid)
		)
		(fill yes)
		(layer "In11.Cu")
		(net "M_F_DQ<49>")
	)
	(gr_poly
		(pts
			(xy 278.478742 -99.144582) (xy 278.501094 -99.105974) (xy 278.155654 -98.906838) (xy 278.133556 -98.945192)
			(xy 278.125428 -99.136962) (xy 278.31669 -99.247452)
		)
		(stroke
			(width 0)
			(type solid)
		)
		(fill yes)
		(layer "In11.Cu")
		(net "M_F_DQ<52>")
	)
	(gr_poly
		(pts
			(xy 278.478742 -98.153982) (xy 278.501094 -98.115374) (xy 278.155654 -97.916238) (xy 278.133556 -97.954592)
			(xy 278.125428 -98.146362) (xy 278.31669 -98.256852)
		)
		(stroke
			(width 0)
			(type solid)
		)
		(fill yes)
		(layer "In11.Cu")
		(net "M_F_DQ<48>")
	)
	(gr_poly
		(pts
			(xy 278.484076 -97.166684) (xy 278.506682 -97.12833) (xy 278.160988 -96.92894) (xy 278.13889 -96.967548)
			(xy 278.130762 -97.159318) (xy 278.322278 -97.269554)
		)
		(stroke
			(width 0)
			(type solid)
		)
		(fill yes)
		(layer "In11.Cu")
		(net "M_F_DQS_DP<15>")
	)
	(gr_poly
		(pts
			(xy 278.580342 -102.07117) (xy 278.580342 -101.85019) (xy 278.410162 -101.76129) (xy 278.365712 -101.76129)
			(xy 278.365712 -102.16007) (xy 278.410162 -102.16007)
		)
		(stroke
			(width 0)
			(type solid)
		)
		(fill yes)
		(layer "In11.Cu")
		(net "M_F_DQ<35>")
	)
	(gr_poly
		(pts
			(xy 278.580342 -101.093016) (xy 278.580342 -100.872036) (xy 278.410162 -100.783136) (xy 278.365712 -100.783136)
			(xy 278.365712 -101.181916) (xy 278.410162 -101.181916)
		)
		(stroke
			(width 0)
			(type solid)
		)
		(fill yes)
		(layer "In11.Cu")
		(net "M_F_DQ<35>")
	)
	(gr_poly
		(pts
			(xy 278.580342 -100.102416) (xy 278.580342 -99.881436) (xy 278.410162 -99.792536) (xy 278.365712 -99.792536)
			(xy 278.365712 -100.191316) (xy 278.410162 -100.191316)
		)
		(stroke
			(width 0)
			(type solid)
		)
		(fill yes)
		(layer "In11.Cu")
		(net "M_F_DQ<35>")
	)
	(gr_poly
		(pts
			(xy 278.580342 -96.128078) (xy 278.580342 -95.907098) (xy 278.410162 -95.818198) (xy 278.365712 -95.818198)
			(xy 278.365712 -96.216978) (xy 278.410162 -96.216978)
		)
		(stroke
			(width 0)
			(type solid)
		)
		(fill yes)
		(layer "In11.Cu")
		(net "M_F_DQS_DN<15>")
	)
	(gr_poly
		(pts
			(xy 278.580342 -95.149924) (xy 278.580342 -94.928944) (xy 278.410162 -94.840044) (xy 278.365712 -94.840044)
			(xy 278.365712 -95.238824) (xy 278.410162 -95.238824)
		)
		(stroke
			(width 0)
			(type solid)
		)
		(fill yes)
		(layer "In11.Cu")
		(net "M_F_DQS_DN<15>")
	)
	(gr_poly
		(pts
			(xy 278.580342 -94.153228) (xy 278.580342 -93.932248) (xy 278.410162 -93.843348) (xy 278.365712 -93.843348)
			(xy 278.365712 -94.242128) (xy 278.410162 -94.242128)
		)
		(stroke
			(width 0)
			(type solid)
		)
		(fill yes)
		(layer "In11.Cu")
		(net "M_F_DQS_DN<15>")
	)
	(gr_poly
		(pts
			(xy 278.580342 -93.156278) (xy 278.580342 -92.935298) (xy 278.410162 -92.846398) (xy 278.365712 -92.846398)
			(xy 278.365712 -93.245178) (xy 278.410162 -93.245178)
		)
		(stroke
			(width 0)
			(type solid)
		)
		(fill yes)
		(layer "In11.Cu")
		(net "M_F_DQS_DN<15>")
	)
	(gr_poly
		(pts
			(xy 278.580342 -92.165678) (xy 278.580342 -91.944698) (xy 278.410162 -91.855798) (xy 278.365712 -91.855798)
			(xy 278.365712 -92.254578) (xy 278.410162 -92.254578)
		)
		(stroke
			(width 0)
			(type solid)
		)
		(fill yes)
		(layer "In11.Cu")
		(net "M_F_DQS_DN<15>")
	)
	(gr_poly
		(pts
			(xy 278.580342 -91.175078) (xy 278.580342 -90.954098) (xy 278.410162 -90.865198) (xy 278.365712 -90.865198)
			(xy 278.365712 -91.263978) (xy 278.410162 -91.263978)
		)
		(stroke
			(width 0)
			(type solid)
		)
		(fill yes)
		(layer "In11.Cu")
		(net "M_F_DQS_DN<15>")
	)
	(gr_poly
		(pts
			(xy 278.900636 -95.830644) (xy 278.856186 -95.830644) (xy 278.686006 -95.919544) (xy 278.686006 -96.140524)
			(xy 278.856186 -96.229424) (xy 278.900636 -96.229424)
		)
		(stroke
			(width 0)
			(type solid)
		)
		(fill yes)
		(layer "In11.Cu")
		(net "M_F_DQS_DN<6>")
	)
	(gr_poly
		(pts
			(xy 278.900636 -94.840044) (xy 278.856186 -94.840044) (xy 278.686006 -94.928944) (xy 278.686006 -95.149924)
			(xy 278.856186 -95.238824) (xy 278.900636 -95.238824)
		)
		(stroke
			(width 0)
			(type solid)
		)
		(fill yes)
		(layer "In11.Cu")
		(net "M_F_DQS_DN<6>")
	)
	(gr_poly
		(pts
			(xy 278.90089 -93.843348) (xy 278.85644 -93.843348) (xy 278.68626 -93.932248) (xy 278.68626 -94.153228)
			(xy 278.85644 -94.242128) (xy 278.90089 -94.242128)
		)
		(stroke
			(width 0)
			(type solid)
		)
		(fill yes)
		(layer "In11.Cu")
		(net "M_F_DQS_DN<6>")
	)
	(gr_poly
		(pts
			(xy 279.09139 -90.866468) (xy 279.04694 -90.866468) (xy 278.87676 -90.955368) (xy 278.87676 -91.176348)
			(xy 279.04694 -91.265248) (xy 279.09139 -91.265248)
		)
		(stroke
			(width 0)
			(type solid)
		)
		(fill yes)
		(layer "In11.Cu")
		(net "M_F_DQ<54>")
	)
	(gr_poly
		(pts
			(xy 279.131268 -99.045014) (xy 279.139396 -98.853244) (xy 278.948134 -98.742754) (xy 278.786082 -98.845624)
			(xy 278.76373 -98.883978) (xy 279.10917 -99.083622)
		)
		(stroke
			(width 0)
			(type solid)
		)
		(fill yes)
		(layer "In11.Cu")
		(net "M_F_DQ<53>")
	)
	(gr_poly
		(pts
			(xy 279.131268 -98.054414) (xy 279.139396 -97.862644) (xy 278.948134 -97.752154) (xy 278.786082 -97.855024)
			(xy 278.76373 -97.893378) (xy 279.10917 -98.093022)
		)
		(stroke
			(width 0)
			(type solid)
		)
		(fill yes)
		(layer "In11.Cu")
		(net "M_F_DQ<49>")
	)
	(gr_poly
		(pts
			(xy 279.131268 -97.063814) (xy 279.139396 -96.872044) (xy 278.948134 -96.761554) (xy 278.786082 -96.864424)
			(xy 278.76373 -96.902778) (xy 279.10917 -97.102422)
		)
		(stroke
			(width 0)
			(type solid)
		)
		(fill yes)
		(layer "In11.Cu")
		(net "M_F_DQS_DN<15>")
	)
	(gr_poly
		(pts
			(xy 279.279604 -52.091082) (xy 279.235154 -52.091082) (xy 279.042114 -52.179982) (xy 279.042114 -52.408582)
			(xy 279.235154 -52.497482) (xy 279.279604 -52.497482)
		)
		(stroke
			(width 0)
			(type solid)
		)
		(fill yes)
		(layer "In11.Cu")
		(net "M_C_DQ<52>")
	)
	(gr_poly
		(pts
			(xy 279.279604 -51.100482) (xy 279.235154 -51.100482) (xy 279.042114 -51.189382) (xy 279.042114 -51.417982)
			(xy 279.235154 -51.506882) (xy 279.279604 -51.506882)
		)
		(stroke
			(width 0)
			(type solid)
		)
		(fill yes)
		(layer "In11.Cu")
		(net "M_C_DQ<52>")
	)
	(gr_poly
		(pts
			(xy 279.279604 -50.109882) (xy 279.235154 -50.109882) (xy 279.042114 -50.198782) (xy 279.042114 -50.427382)
			(xy 279.235154 -50.516282) (xy 279.279604 -50.516282)
		)
		(stroke
			(width 0)
			(type solid)
		)
		(fill yes)
		(layer "In11.Cu")
		(net "M_C_DQ<52>")
	)
	(gr_poly
		(pts
			(xy 279.279604 -49.119282) (xy 279.235154 -49.119282) (xy 279.042114 -49.208182) (xy 279.042114 -49.436782)
			(xy 279.235154 -49.525682) (xy 279.279604 -49.525682)
		)
		(stroke
			(width 0)
			(type solid)
		)
		(fill yes)
		(layer "In11.Cu")
		(net "M_C_DQ<52>")
	)
	(gr_poly
		(pts
			(xy 279.279604 -48.128682) (xy 279.235154 -48.128682) (xy 279.042114 -48.217582) (xy 279.042114 -48.446182)
			(xy 279.235154 -48.535082) (xy 279.279604 -48.535082)
		)
		(stroke
			(width 0)
			(type solid)
		)
		(fill yes)
		(layer "In11.Cu")
		(net "M_C_DQ<52>")
	)
	(gr_poly
		(pts
			(xy 279.338786 -99.640898) (xy 279.361138 -99.60229) (xy 279.015698 -99.403154) (xy 278.9936 -99.441508)
			(xy 278.985472 -99.633278) (xy 279.176734 -99.743768)
		)
		(stroke
			(width 0)
			(type solid)
		)
		(fill yes)
		(layer "In11.Cu")
		(net "M_F_DQ<52>")
	)
	(gr_poly
		(pts
			(xy 279.338786 -98.650298) (xy 279.361138 -98.61169) (xy 279.015698 -98.412554) (xy 278.9936 -98.450908)
			(xy 278.985472 -98.642678) (xy 279.176734 -98.753168)
		)
		(stroke
			(width 0)
			(type solid)
		)
		(fill yes)
		(layer "In11.Cu")
		(net "M_F_DQ<48>")
	)
	(gr_poly
		(pts
			(xy 279.338786 -97.659698) (xy 279.361138 -97.62109) (xy 279.015698 -97.421954) (xy 278.9936 -97.460308)
			(xy 278.985472 -97.652078) (xy 279.176734 -97.762568)
		)
		(stroke
			(width 0)
			(type solid)
		)
		(fill yes)
		(layer "In11.Cu")
		(net "M_F_DQS_DP<15>")
	)
	(gr_poly
		(pts
			(xy 279.33904 -96.669352) (xy 279.361392 -96.630998) (xy 279.015698 -96.431608) (xy 278.993854 -96.470216)
			(xy 278.985726 -96.661986) (xy 279.176988 -96.772222)
		)
		(stroke
			(width 0)
			(type solid)
		)
		(fill yes)
		(layer "In11.Cu")
		(net "M_F_DQS_DN<6>")
	)
	(gr_poly
		(pts
			(xy 279.438862 -95.638874) (xy 279.438862 -95.417894) (xy 279.268682 -95.328994) (xy 279.224232 -95.328994)
			(xy 279.224232 -95.727774) (xy 279.268682 -95.727774)
		)
		(stroke
			(width 0)
			(type solid)
		)
		(fill yes)
		(layer "In11.Cu")
		(net "M_F_DQS_DP<6>")
	)
	(gr_poly
		(pts
			(xy 279.438862 -94.642178) (xy 279.438862 -94.421198) (xy 279.268682 -94.332298) (xy 279.224232 -94.332298)
			(xy 279.224232 -94.731078) (xy 279.268682 -94.731078)
		)
		(stroke
			(width 0)
			(type solid)
		)
		(fill yes)
		(layer "In11.Cu")
		(net "M_F_DQS_DP<6>")
	)
	(gr_poly
		(pts
			(xy 279.438862 -93.651578) (xy 279.438862 -93.430598) (xy 279.268682 -93.341698) (xy 279.224232 -93.341698)
			(xy 279.224232 -93.740478) (xy 279.268682 -93.740478)
		)
		(stroke
			(width 0)
			(type solid)
		)
		(fill yes)
		(layer "In11.Cu")
		(net "M_F_DQS_DP<6>")
	)
	(gr_poly
		(pts
			(xy 279.438862 -91.682824) (xy 279.438862 -91.461844) (xy 279.268682 -91.372944) (xy 279.224232 -91.372944)
			(xy 279.224232 -91.771724) (xy 279.268682 -91.771724)
		)
		(stroke
			(width 0)
			(type solid)
		)
		(fill yes)
		(layer "In11.Cu")
		(net "M_F_DQ<54>")
	)
	(gr_poly
		(pts
			(xy 279.474676 -62.137798) (xy 279.430226 -62.137798) (xy 279.260046 -62.226698) (xy 279.260046 -62.447678)
			(xy 279.430226 -62.536578) (xy 279.474676 -62.536578)
		)
		(stroke
			(width 0)
			(type solid)
		)
		(fill yes)
		(layer "In11.Cu")
		(net "M_C_DQ<52>")
	)
	(gr_poly
		(pts
			(xy 279.474676 -61.147198) (xy 279.430226 -61.147198) (xy 279.260046 -61.236098) (xy 279.260046 -61.457078)
			(xy 279.430226 -61.545978) (xy 279.474676 -61.545978)
		)
		(stroke
			(width 0)
			(type solid)
		)
		(fill yes)
		(layer "In11.Cu")
		(net "M_C_DQ<52>")
	)
	(gr_poly
		(pts
			(xy 279.474676 -60.156598) (xy 279.430226 -60.156598) (xy 279.260046 -60.245498) (xy 279.260046 -60.466478)
			(xy 279.430226 -60.555378) (xy 279.474676 -60.555378)
		)
		(stroke
			(width 0)
			(type solid)
		)
		(fill yes)
		(layer "In11.Cu")
		(net "M_C_DQ<52>")
	)
	(gr_poly
		(pts
			(xy 279.474676 -59.178444) (xy 279.430226 -59.178444) (xy 279.260046 -59.267344) (xy 279.260046 -59.488324)
			(xy 279.430226 -59.577224) (xy 279.474676 -59.577224)
		)
		(stroke
			(width 0)
			(type solid)
		)
		(fill yes)
		(layer "In11.Cu")
		(net "M_C_DQ<52>")
	)
	(gr_poly
		(pts
			(xy 279.474676 -58.181748) (xy 279.430226 -58.181748) (xy 279.260046 -58.270648) (xy 279.260046 -58.491628)
			(xy 279.430226 -58.580528) (xy 279.474676 -58.580528)
		)
		(stroke
			(width 0)
			(type solid)
		)
		(fill yes)
		(layer "In11.Cu")
		(net "M_C_DQ<52>")
	)
	(gr_poly
		(pts
			(xy 279.474676 -57.184798) (xy 279.430226 -57.184798) (xy 279.260046 -57.273698) (xy 279.260046 -57.494678)
			(xy 279.430226 -57.583578) (xy 279.474676 -57.583578)
		)
		(stroke
			(width 0)
			(type solid)
		)
		(fill yes)
		(layer "In11.Cu")
		(net "M_C_DQ<52>")
	)
	(gr_poly
		(pts
			(xy 279.474676 -56.194198) (xy 279.430226 -56.194198) (xy 279.260046 -56.283098) (xy 279.260046 -56.504078)
			(xy 279.430226 -56.592978) (xy 279.474676 -56.592978)
		)
		(stroke
			(width 0)
			(type solid)
		)
		(fill yes)
		(layer "In11.Cu")
		(net "M_C_DQ<52>")
	)
	(gr_poly
		(pts
			(xy 279.474676 -55.203598) (xy 279.430226 -55.203598) (xy 279.260046 -55.292498) (xy 279.260046 -55.513478)
			(xy 279.430226 -55.602378) (xy 279.474676 -55.602378)
		)
		(stroke
			(width 0)
			(type solid)
		)
		(fill yes)
		(layer "In11.Cu")
		(net "M_C_DQ<52>")
	)
	(gr_poly
		(pts
			(xy 279.474676 -54.212998) (xy 279.430226 -54.212998) (xy 279.260046 -54.301898) (xy 279.260046 -54.522878)
			(xy 279.430226 -54.611778) (xy 279.474676 -54.611778)
		)
		(stroke
			(width 0)
			(type solid)
		)
		(fill yes)
		(layer "In11.Cu")
		(net "M_C_DQ<52>")
	)
	(gr_poly
		(pts
			(xy 279.707594 -52.408582) (xy 279.707594 -52.179982) (xy 279.514554 -52.091082) (xy 279.470104 -52.091082)
			(xy 279.470104 -52.497482) (xy 279.514554 -52.497482)
		)
		(stroke
			(width 0)
			(type solid)
		)
		(fill yes)
		(layer "In11.Cu")
		(net "M_C_DQ<53>")
	)
	(gr_poly
		(pts
			(xy 279.707594 -51.417982) (xy 279.707594 -51.189382) (xy 279.514554 -51.100482) (xy 279.470104 -51.100482)
			(xy 279.470104 -51.506882) (xy 279.514554 -51.506882)
		)
		(stroke
			(width 0)
			(type solid)
		)
		(fill yes)
		(layer "In11.Cu")
		(net "M_C_DQ<53>")
	)
	(gr_poly
		(pts
			(xy 279.707594 -50.427382) (xy 279.707594 -50.198782) (xy 279.514554 -50.109882) (xy 279.470104 -50.109882)
			(xy 279.470104 -50.516282) (xy 279.514554 -50.516282)
		)
		(stroke
			(width 0)
			(type solid)
		)
		(fill yes)
		(layer "In11.Cu")
		(net "M_C_DQ<53>")
	)
	(gr_poly
		(pts
			(xy 279.707594 -49.436782) (xy 279.707594 -49.208182) (xy 279.514554 -49.119282) (xy 279.470104 -49.119282)
			(xy 279.470104 -49.525682) (xy 279.514554 -49.525682)
		)
		(stroke
			(width 0)
			(type solid)
		)
		(fill yes)
		(layer "In11.Cu")
		(net "M_C_DQ<53>")
	)
	(gr_poly
		(pts
			(xy 279.707594 -48.446182) (xy 279.707594 -48.217582) (xy 279.514554 -48.128682) (xy 279.470104 -48.128682)
			(xy 279.470104 -48.535082) (xy 279.514554 -48.535082)
		)
		(stroke
			(width 0)
			(type solid)
		)
		(fill yes)
		(layer "In11.Cu")
		(net "M_C_DQ<53>")
	)
	(gr_poly
		(pts
			(xy 279.759156 -95.322898) (xy 279.714706 -95.322898) (xy 279.544526 -95.411798) (xy 279.544526 -95.632778)
			(xy 279.714706 -95.721678) (xy 279.759156 -95.721678)
		)
		(stroke
			(width 0)
			(type solid)
		)
		(fill yes)
		(layer "In11.Cu")
		(net "M_F_DQ<54>")
	)
	(gr_poly
		(pts
			(xy 279.759156 -94.332298) (xy 279.714706 -94.332298) (xy 279.544526 -94.421198) (xy 279.544526 -94.642178)
			(xy 279.714706 -94.731078) (xy 279.759156 -94.731078)
		)
		(stroke
			(width 0)
			(type solid)
		)
		(fill yes)
		(layer "In11.Cu")
		(net "M_F_DQ<54>")
	)
	(gr_poly
		(pts
			(xy 279.759156 -93.354144) (xy 279.714706 -93.354144) (xy 279.544526 -93.443044) (xy 279.544526 -93.664024)
			(xy 279.714706 -93.752924) (xy 279.759156 -93.752924)
		)
		(stroke
			(width 0)
			(type solid)
		)
		(fill yes)
		(layer "In11.Cu")
		(net "M_F_DQ<54>")
	)
	(gr_poly
		(pts
			(xy 279.909524 -91.722448) (xy 279.908762 -91.323922) (xy 279.864312 -91.323922) (xy 279.694386 -91.413076)
			(xy 279.69464 -91.633802) (xy 279.865074 -91.722702)
		)
		(stroke
			(width 0)
			(type solid)
		)
		(fill yes)
		(layer "In11.Cu")
		(net "M_F_DQ<50>")
	)
	(gr_poly
		(pts
			(xy 279.991312 -99.54133) (xy 279.99944 -99.34956) (xy 279.808178 -99.23907) (xy 279.646126 -99.34194)
			(xy 279.623774 -99.380294) (xy 279.969214 -99.579938)
		)
		(stroke
			(width 0)
			(type solid)
		)
		(fill yes)
		(layer "In11.Cu")
		(net "M_F_DQ<53>")
	)
	(gr_poly
		(pts
			(xy 279.991312 -98.55073) (xy 279.99944 -98.35896) (xy 279.808178 -98.24847) (xy 279.646126 -98.35134)
			(xy 279.623774 -98.389694) (xy 279.969214 -98.589338)
		)
		(stroke
			(width 0)
			(type solid)
		)
		(fill yes)
		(layer "In11.Cu")
		(net "M_F_DQ<49>")
	)
	(gr_poly
		(pts
			(xy 279.991312 -97.56013) (xy 279.99944 -97.36836) (xy 279.808178 -97.25787) (xy 279.646126 -97.36074)
			(xy 279.623774 -97.399094) (xy 279.969214 -97.598738)
		)
		(stroke
			(width 0)
			(type solid)
		)
		(fill yes)
		(layer "In11.Cu")
		(net "M_F_DQS_DN<15>")
	)
	(gr_poly
		(pts
			(xy 279.991312 -96.56953) (xy 279.99944 -96.37776) (xy 279.808178 -96.26727) (xy 279.646126 -96.37014)
			(xy 279.623774 -96.408494) (xy 279.969214 -96.608138)
		)
		(stroke
			(width 0)
			(type solid)
		)
		(fill yes)
		(layer "In11.Cu")
		(net "M_F_DQS_DP<6>")
	)
	(gr_poly
		(pts
			(xy 280.012902 -61.964824) (xy 280.012902 -61.743844) (xy 279.842722 -61.654944) (xy 279.798272 -61.654944)
			(xy 279.798272 -62.053724) (xy 279.842722 -62.053724)
		)
		(stroke
			(width 0)
			(type solid)
		)
		(fill yes)
		(layer "In11.Cu")
		(net "M_C_DQ<53>")
	)
	(gr_poly
		(pts
			(xy 280.012902 -60.974224) (xy 280.012902 -60.753244) (xy 279.842722 -60.664344) (xy 279.798272 -60.664344)
			(xy 279.798272 -61.063124) (xy 279.842722 -61.063124)
		)
		(stroke
			(width 0)
			(type solid)
		)
		(fill yes)
		(layer "In11.Cu")
		(net "M_C_DQ<53>")
	)
	(gr_poly
		(pts
			(xy 280.012902 -59.977274) (xy 280.012902 -59.756294) (xy 279.842722 -59.667394) (xy 279.798272 -59.667394)
			(xy 279.798272 -60.066174) (xy 279.842722 -60.066174)
		)
		(stroke
			(width 0)
			(type solid)
		)
		(fill yes)
		(layer "In11.Cu")
		(net "M_C_DQ<53>")
	)
	(gr_poly
		(pts
			(xy 280.012902 -58.980578) (xy 280.012902 -58.759598) (xy 279.842722 -58.670698) (xy 279.798272 -58.670698)
			(xy 279.798272 -59.069478) (xy 279.842722 -59.069478)
		)
		(stroke
			(width 0)
			(type solid)
		)
		(fill yes)
		(layer "In11.Cu")
		(net "M_C_DQ<53>")
	)
	(gr_poly
		(pts
			(xy 280.012902 -58.002424) (xy 280.012902 -57.781444) (xy 279.842722 -57.692544) (xy 279.798272 -57.692544)
			(xy 279.798272 -58.091324) (xy 279.842722 -58.091324)
		)
		(stroke
			(width 0)
			(type solid)
		)
		(fill yes)
		(layer "In11.Cu")
		(net "M_C_DQ<53>")
	)
	(gr_poly
		(pts
			(xy 280.012902 -57.011824) (xy 280.012902 -56.790844) (xy 279.842722 -56.701944) (xy 279.798272 -56.701944)
			(xy 279.798272 -57.100724) (xy 279.842722 -57.100724)
		)
		(stroke
			(width 0)
			(type solid)
		)
		(fill yes)
		(layer "In11.Cu")
		(net "M_C_DQ<53>")
	)
	(gr_poly
		(pts
			(xy 280.012902 -56.021224) (xy 280.012902 -55.800244) (xy 279.842722 -55.711344) (xy 279.798272 -55.711344)
			(xy 279.798272 -56.110124) (xy 279.842722 -56.110124)
		)
		(stroke
			(width 0)
			(type solid)
		)
		(fill yes)
		(layer "In11.Cu")
		(net "M_C_DQ<53>")
	)
	(gr_poly
		(pts
			(xy 280.012902 -55.030624) (xy 280.012902 -54.809644) (xy 279.842722 -54.720744) (xy 279.798272 -54.720744)
			(xy 279.798272 -55.119524) (xy 279.842722 -55.119524)
		)
		(stroke
			(width 0)
			(type solid)
		)
		(fill yes)
		(layer "In11.Cu")
		(net "M_C_DQ<53>")
	)
	(gr_poly
		(pts
			(xy 280.046684 -52.628038) (xy 280.002234 -52.628038) (xy 279.809194 -52.716938) (xy 279.809194 -52.945538)
			(xy 280.002234 -53.034438) (xy 280.046684 -53.034438)
		)
		(stroke
			(width 0)
			(type solid)
		)
		(fill yes)
		(layer "In11.Cu")
		(net "M_C_DQ<48>")
	)
	(gr_poly
		(pts
			(xy 280.046684 -51.637438) (xy 280.002234 -51.637438) (xy 279.809194 -51.726338) (xy 279.809194 -51.954938)
			(xy 280.002234 -52.043838) (xy 280.046684 -52.043838)
		)
		(stroke
			(width 0)
			(type solid)
		)
		(fill yes)
		(layer "In11.Cu")
		(net "M_C_DQ<48>")
	)
	(gr_poly
		(pts
			(xy 280.046684 -50.646838) (xy 280.002234 -50.646838) (xy 279.809194 -50.735738) (xy 279.809194 -50.964338)
			(xy 280.002234 -51.053238) (xy 280.046684 -51.053238)
		)
		(stroke
			(width 0)
			(type solid)
		)
		(fill yes)
		(layer "In11.Cu")
		(net "M_C_DQ<48>")
	)
	(gr_poly
		(pts
			(xy 280.046684 -49.656238) (xy 280.002234 -49.656238) (xy 279.809194 -49.745138) (xy 279.809194 -49.973738)
			(xy 280.002234 -50.062638) (xy 280.046684 -50.062638)
		)
		(stroke
			(width 0)
			(type solid)
		)
		(fill yes)
		(layer "In11.Cu")
		(net "M_C_DQ<48>")
	)
	(gr_poly
		(pts
			(xy 280.046684 -48.665638) (xy 280.002234 -48.665638) (xy 279.809194 -48.754538) (xy 279.809194 -48.983138)
			(xy 280.002234 -49.072038) (xy 280.046684 -49.072038)
		)
		(stroke
			(width 0)
			(type solid)
		)
		(fill yes)
		(layer "In11.Cu")
		(net "M_C_DQ<48>")
	)
	(gr_poly
		(pts
			(xy 280.195782 -100.135182) (xy 280.218134 -100.096574) (xy 279.872694 -99.897438) (xy 279.850596 -99.935792)
			(xy 279.842468 -100.127562) (xy 280.03373 -100.238052)
		)
		(stroke
			(width 0)
			(type solid)
		)
		(fill yes)
		(layer "In11.Cu")
		(net "M_F_DQ<52>")
	)
	(gr_poly
		(pts
			(xy 280.195782 -99.144582) (xy 280.218134 -99.105974) (xy 279.872694 -98.906838) (xy 279.850596 -98.945192)
			(xy 279.842468 -99.136962) (xy 280.03373 -99.247452)
		)
		(stroke
			(width 0)
			(type solid)
		)
		(fill yes)
		(layer "In11.Cu")
		(net "M_F_DQ<48>")
	)
	(gr_poly
		(pts
			(xy 280.195782 -98.153982) (xy 280.218134 -98.115374) (xy 279.872694 -97.916238) (xy 279.850596 -97.954592)
			(xy 279.842468 -98.146362) (xy 280.03373 -98.256852)
		)
		(stroke
			(width 0)
			(type solid)
		)
		(fill yes)
		(layer "In11.Cu")
		(net "M_F_DQS_DP<15>")
	)
	(gr_poly
		(pts
			(xy 280.195782 -97.163382) (xy 280.218134 -97.124774) (xy 279.872694 -96.925638) (xy 279.850596 -96.963992)
			(xy 279.842468 -97.155762) (xy 280.03373 -97.266252)
		)
		(stroke
			(width 0)
			(type solid)
		)
		(fill yes)
		(layer "In11.Cu")
		(net "M_F_DQS_DN<6>")
	)
	(gr_poly
		(pts
			(xy 280.195782 -96.172782) (xy 280.218134 -96.134428) (xy 279.87244 -95.935038) (xy 279.850596 -95.973392)
			(xy 279.842468 -96.165162) (xy 280.03373 -96.275652)
		)
		(stroke
			(width 0)
			(type solid)
		)
		(fill yes)
		(layer "In11.Cu")
		(net "M_F_DQ<54>")
	)
	(gr_poly
		(pts
			(xy 280.287476 -92.174314) (xy 280.318718 -92.142818) (xy 280.035 -91.862402) (xy 280.003758 -91.894152)
			(xy 279.94737 -92.07754) (xy 280.104596 -92.232988)
		)
		(stroke
			(width 0)
			(type solid)
		)
		(fill yes)
		(layer "In11.Cu")
		(net "M_F_DQ<50>")
	)
	(gr_poly
		(pts
			(xy 280.297382 -95.149924) (xy 280.297382 -94.928944) (xy 280.127202 -94.840044) (xy 280.082752 -94.840044)
			(xy 280.082752 -95.238824) (xy 280.127202 -95.238824)
		)
		(stroke
			(width 0)
			(type solid)
		)
		(fill yes)
		(layer "In11.Cu")
		(net "M_F_DQ<55>")
	)
	(gr_poly
		(pts
			(xy 280.297382 -94.153228) (xy 280.297382 -93.932248) (xy 280.127202 -93.843348) (xy 280.082752 -93.843348)
			(xy 280.082752 -94.242128) (xy 280.127202 -94.242128)
		)
		(stroke
			(width 0)
			(type solid)
		)
		(fill yes)
		(layer "In11.Cu")
		(net "M_F_DQ<55>")
	)
	(gr_poly
		(pts
			(xy 280.297382 -93.156278) (xy 280.297382 -92.935298) (xy 280.127202 -92.846398) (xy 280.082752 -92.846398)
			(xy 280.082752 -93.245178) (xy 280.127202 -93.245178)
		)
		(stroke
			(width 0)
			(type solid)
		)
		(fill yes)
		(layer "In11.Cu")
		(net "M_F_DQ<55>")
	)
	(gr_poly
		(pts
			(xy 280.333196 -61.654944) (xy 280.288746 -61.654944) (xy 280.118566 -61.743844) (xy 280.118566 -61.964824)
			(xy 280.288746 -62.053724) (xy 280.333196 -62.053724)
		)
		(stroke
			(width 0)
			(type solid)
		)
		(fill yes)
		(layer "In11.Cu")
		(net "M_C_DQ<48>")
	)
	(gr_poly
		(pts
			(xy 280.333196 -60.664344) (xy 280.288746 -60.664344) (xy 280.118566 -60.753244) (xy 280.118566 -60.974224)
			(xy 280.288746 -61.063124) (xy 280.333196 -61.063124)
		)
		(stroke
			(width 0)
			(type solid)
		)
		(fill yes)
		(layer "In11.Cu")
		(net "M_C_DQ<48>")
	)
	(gr_poly
		(pts
			(xy 280.333196 -59.667394) (xy 280.288746 -59.667394) (xy 280.118566 -59.756294) (xy 280.118566 -59.977274)
			(xy 280.288746 -60.066174) (xy 280.333196 -60.066174)
		)
		(stroke
			(width 0)
			(type solid)
		)
		(fill yes)
		(layer "In11.Cu")
		(net "M_C_DQ<48>")
	)
	(gr_poly
		(pts
			(xy 280.333196 -58.670698) (xy 280.288746 -58.670698) (xy 280.118566 -58.759598) (xy 280.118566 -58.980578)
			(xy 280.288746 -59.069478) (xy 280.333196 -59.069478)
		)
		(stroke
			(width 0)
			(type solid)
		)
		(fill yes)
		(layer "In11.Cu")
		(net "M_C_DQ<48>")
	)
	(gr_poly
		(pts
			(xy 280.333196 -57.692544) (xy 280.288746 -57.692544) (xy 280.118566 -57.781444) (xy 280.118566 -58.002424)
			(xy 280.288746 -58.091324) (xy 280.333196 -58.091324)
		)
		(stroke
			(width 0)
			(type solid)
		)
		(fill yes)
		(layer "In11.Cu")
		(net "M_C_DQ<48>")
	)
	(gr_poly
		(pts
			(xy 280.333196 -56.701944) (xy 280.288746 -56.701944) (xy 280.118566 -56.790844) (xy 280.118566 -57.011824)
			(xy 280.288746 -57.100724) (xy 280.333196 -57.100724)
		)
		(stroke
			(width 0)
			(type solid)
		)
		(fill yes)
		(layer "In11.Cu")
		(net "M_C_DQ<48>")
	)
	(gr_poly
		(pts
			(xy 280.333196 -55.711344) (xy 280.288746 -55.711344) (xy 280.118566 -55.800244) (xy 280.118566 -56.021224)
			(xy 280.288746 -56.110124) (xy 280.333196 -56.110124)
		)
		(stroke
			(width 0)
			(type solid)
		)
		(fill yes)
		(layer "In11.Cu")
		(net "M_C_DQ<48>")
	)
	(gr_poly
		(pts
			(xy 280.333196 -54.720744) (xy 280.288746 -54.720744) (xy 280.118566 -54.809644) (xy 280.118566 -55.030624)
			(xy 280.288746 -55.119524) (xy 280.333196 -55.119524)
		)
		(stroke
			(width 0)
			(type solid)
		)
		(fill yes)
		(layer "In11.Cu")
		(net "M_C_DQ<48>")
	)
	(gr_poly
		(pts
			(xy 280.392124 -63.013336) (xy 280.42108 -62.823598) (xy 280.242772 -62.693042) (xy 280.07056 -62.777878)
			(xy 280.044144 -62.813692) (xy 280.365962 -63.04915)
		)
		(stroke
			(width 0)
			(type solid)
		)
		(fill yes)
		(layer "In11.Cu")
		(net "M_C_DQ<53>")
	)
	(gr_poly
		(pts
			(xy 280.474674 -52.945538) (xy 280.474674 -52.716938) (xy 280.281634 -52.628038) (xy 280.237184 -52.628038)
			(xy 280.237184 -53.034438) (xy 280.281634 -53.034438)
		)
		(stroke
			(width 0)
			(type solid)
		)
		(fill yes)
		(layer "In11.Cu")
		(net "M_C_DQ<49>")
	)
	(gr_poly
		(pts
			(xy 280.474674 -51.954938) (xy 280.474674 -51.726338) (xy 280.281634 -51.637438) (xy 280.237184 -51.637438)
			(xy 280.237184 -52.043838) (xy 280.281634 -52.043838)
		)
		(stroke
			(width 0)
			(type solid)
		)
		(fill yes)
		(layer "In11.Cu")
		(net "M_C_DQ<49>")
	)
	(gr_poly
		(pts
			(xy 280.474674 -50.964338) (xy 280.474674 -50.735738) (xy 280.281634 -50.646838) (xy 280.237184 -50.646838)
			(xy 280.237184 -51.053238) (xy 280.281634 -51.053238)
		)
		(stroke
			(width 0)
			(type solid)
		)
		(fill yes)
		(layer "In11.Cu")
		(net "M_C_DQ<49>")
	)
	(gr_poly
		(pts
			(xy 280.474674 -49.973738) (xy 280.474674 -49.745138) (xy 280.281634 -49.656238) (xy 280.237184 -49.656238)
			(xy 280.237184 -50.062638) (xy 280.281634 -50.062638)
		)
		(stroke
			(width 0)
			(type solid)
		)
		(fill yes)
		(layer "In11.Cu")
		(net "M_C_DQ<49>")
	)
	(gr_poly
		(pts
			(xy 280.474674 -48.983138) (xy 280.474674 -48.754538) (xy 280.281634 -48.665638) (xy 280.237184 -48.665638)
			(xy 280.237184 -49.072038) (xy 280.281634 -49.072038)
		)
		(stroke
			(width 0)
			(type solid)
		)
		(fill yes)
		(layer "In11.Cu")
		(net "M_C_DQ<49>")
	)
	(gr_poly
		(pts
			(xy 280.4795 -105.320338) (xy 280.448004 -105.288842) (xy 280.248868 -105.215182) (xy 280.08707 -105.37698)
			(xy 280.16073 -105.576116) (xy 280.192226 -105.607612)
		)
		(stroke
			(width 0)
			(type solid)
		)
		(fill yes)
		(layer "In11.Cu")
		(net "M_F_DQ<52>")
	)
	(gr_poly
		(pts
			(xy 280.617676 -103.742998) (xy 280.573226 -103.742998) (xy 280.403046 -103.831898) (xy 280.403046 -104.052878)
			(xy 280.573226 -104.141778) (xy 280.617676 -104.141778)
		)
		(stroke
			(width 0)
			(type solid)
		)
		(fill yes)
		(layer "In11.Cu")
		(net "M_F_DQ<52>")
	)
	(gr_poly
		(pts
			(xy 280.617676 -102.752398) (xy 280.573226 -102.752398) (xy 280.403046 -102.841298) (xy 280.403046 -103.062278)
			(xy 280.573226 -103.151178) (xy 280.617676 -103.151178)
		)
		(stroke
			(width 0)
			(type solid)
		)
		(fill yes)
		(layer "In11.Cu")
		(net "M_F_DQ<52>")
	)
	(gr_poly
		(pts
			(xy 280.617676 -101.761798) (xy 280.573226 -101.761798) (xy 280.403046 -101.850698) (xy 280.403046 -102.071678)
			(xy 280.573226 -102.160578) (xy 280.617676 -102.160578)
		)
		(stroke
			(width 0)
			(type solid)
		)
		(fill yes)
		(layer "In11.Cu")
		(net "M_F_DQ<52>")
	)
	(gr_poly
		(pts
			(xy 280.617676 -100.771198) (xy 280.573226 -100.771198) (xy 280.403046 -100.860098) (xy 280.403046 -101.081078)
			(xy 280.573226 -101.169978) (xy 280.617676 -101.169978)
		)
		(stroke
			(width 0)
			(type solid)
		)
		(fill yes)
		(layer "In11.Cu")
		(net "M_F_DQ<52>")
	)
	(gr_poly
		(pts
			(xy 280.617676 -94.833948) (xy 280.573226 -94.833948) (xy 280.403046 -94.922848) (xy 280.403046 -95.143828)
			(xy 280.573226 -95.232728) (xy 280.617676 -95.232728)
		)
		(stroke
			(width 0)
			(type solid)
		)
		(fill yes)
		(layer "In11.Cu")
		(net "M_F_DQ<50>")
	)
	(gr_poly
		(pts
			(xy 280.617676 -93.843348) (xy 280.573226 -93.843348) (xy 280.403046 -93.932248) (xy 280.403046 -94.153228)
			(xy 280.573226 -94.242128) (xy 280.617676 -94.242128)
		)
		(stroke
			(width 0)
			(type solid)
		)
		(fill yes)
		(layer "In11.Cu")
		(net "M_F_DQ<50>")
	)
	(gr_poly
		(pts
			(xy 280.617676 -92.846398) (xy 280.573226 -92.846398) (xy 280.403046 -92.935298) (xy 280.403046 -93.156278)
			(xy 280.573226 -93.245178) (xy 280.617676 -93.245178)
		)
		(stroke
			(width 0)
			(type solid)
		)
		(fill yes)
		(layer "In11.Cu")
		(net "M_F_DQ<50>")
	)
	(gr_poly
		(pts
			(xy 280.71953 -105.686098) (xy 280.64587 -105.486708) (xy 280.614628 -105.455212) (xy 280.3271 -105.74274)
			(xy 280.358596 -105.773982) (xy 280.557986 -105.847642)
		)
		(stroke
			(width 0)
			(type solid)
		)
		(fill yes)
		(layer "In11.Cu")
		(net "M_F_DQ<53>")
	)
	(gr_poly
		(pts
			(xy 280.848054 -100.035106) (xy 280.856182 -99.843336) (xy 280.66492 -99.7331) (xy 280.502868 -99.83597)
			(xy 280.480516 -99.874324) (xy 280.82621 -100.073714)
		)
		(stroke
			(width 0)
			(type solid)
		)
		(fill yes)
		(layer "In11.Cu")
		(net "M_F_DQ<53>")
	)
	(gr_poly
		(pts
			(xy 280.848308 -99.045014) (xy 280.856436 -98.853244) (xy 280.665174 -98.742754) (xy 280.503122 -98.845624)
			(xy 280.48077 -98.883978) (xy 280.82621 -99.083622)
		)
		(stroke
			(width 0)
			(type solid)
		)
		(fill yes)
		(layer "In11.Cu")
		(net "M_F_DQ<49>")
	)
	(gr_poly
		(pts
			(xy 280.848308 -98.054414) (xy 280.856436 -97.862644) (xy 280.665174 -97.752154) (xy 280.503122 -97.855024)
			(xy 280.48077 -97.893378) (xy 280.82621 -98.093022)
		)
		(stroke
			(width 0)
			(type solid)
		)
		(fill yes)
		(layer "In11.Cu")
		(net "M_F_DQS_DN<15>")
	)
	(gr_poly
		(pts
			(xy 280.848308 -97.063814) (xy 280.856436 -96.872044) (xy 280.665174 -96.761554) (xy 280.503122 -96.864424)
			(xy 280.48077 -96.902778) (xy 280.82621 -97.102422)
		)
		(stroke
			(width 0)
			(type solid)
		)
		(fill yes)
		(layer "In11.Cu")
		(net "M_F_DQS_DP<6>")
	)
	(gr_poly
		(pts
			(xy 280.848308 -96.073214) (xy 280.856436 -95.881444) (xy 280.665174 -95.770954) (xy 280.503122 -95.873824)
			(xy 280.48077 -95.912178) (xy 280.82621 -96.111822)
		)
		(stroke
			(width 0)
			(type solid)
		)
		(fill yes)
		(layer "In11.Cu")
		(net "M_F_DQ<55>")
	)
	(gr_poly
		(pts
			(xy 280.871422 -61.457078) (xy 280.871422 -61.236098) (xy 280.701242 -61.147198) (xy 280.656792 -61.147198)
			(xy 280.656792 -61.545978) (xy 280.701242 -61.545978)
		)
		(stroke
			(width 0)
			(type solid)
		)
		(fill yes)
		(layer "In11.Cu")
		(net "M_C_DQ<49>")
	)
	(gr_poly
		(pts
			(xy 280.871422 -60.466478) (xy 280.871422 -60.245498) (xy 280.701242 -60.156598) (xy 280.656792 -60.156598)
			(xy 280.656792 -60.555378) (xy 280.701242 -60.555378)
		)
		(stroke
			(width 0)
			(type solid)
		)
		(fill yes)
		(layer "In11.Cu")
		(net "M_C_DQ<49>")
	)
	(gr_poly
		(pts
			(xy 280.871422 -59.488324) (xy 280.871422 -59.267344) (xy 280.701242 -59.178444) (xy 280.656792 -59.178444)
			(xy 280.656792 -59.577224) (xy 280.701242 -59.577224)
		)
		(stroke
			(width 0)
			(type solid)
		)
		(fill yes)
		(layer "In11.Cu")
		(net "M_C_DQ<49>")
	)
	(gr_poly
		(pts
			(xy 280.871422 -58.491628) (xy 280.871422 -58.270648) (xy 280.701242 -58.181748) (xy 280.656792 -58.181748)
			(xy 280.656792 -58.580528) (xy 280.701242 -58.580528)
		)
		(stroke
			(width 0)
			(type solid)
		)
		(fill yes)
		(layer "In11.Cu")
		(net "M_C_DQ<49>")
	)
	(gr_poly
		(pts
			(xy 280.871422 -57.494678) (xy 280.871422 -57.273698) (xy 280.701242 -57.184798) (xy 280.656792 -57.184798)
			(xy 280.656792 -57.583578) (xy 280.701242 -57.583578)
		)
		(stroke
			(width 0)
			(type solid)
		)
		(fill yes)
		(layer "In11.Cu")
		(net "M_C_DQ<49>")
	)
	(gr_poly
		(pts
			(xy 280.871422 -56.504078) (xy 280.871422 -56.283098) (xy 280.701242 -56.194198) (xy 280.656792 -56.194198)
			(xy 280.656792 -56.592978) (xy 280.701242 -56.592978)
		)
		(stroke
			(width 0)
			(type solid)
		)
		(fill yes)
		(layer "In11.Cu")
		(net "M_C_DQ<49>")
	)
	(gr_poly
		(pts
			(xy 280.871422 -55.513478) (xy 280.871422 -55.292498) (xy 280.701242 -55.203598) (xy 280.656792 -55.203598)
			(xy 280.656792 -55.602378) (xy 280.701242 -55.602378)
		)
		(stroke
			(width 0)
			(type solid)
		)
		(fill yes)
		(layer "In11.Cu")
		(net "M_C_DQ<49>")
	)
	(gr_poly
		(pts
			(xy 280.871422 -54.522878) (xy 280.871422 -54.301898) (xy 280.701242 -54.212998) (xy 280.656792 -54.212998)
			(xy 280.656792 -54.611778) (xy 280.701242 -54.611778)
		)
		(stroke
			(width 0)
			(type solid)
		)
		(fill yes)
		(layer "In11.Cu")
		(net "M_C_DQ<49>")
	)
	(gr_poly
		(pts
			(xy 281.042364 -49.688242) (xy 280.997914 -49.688242) (xy 280.827734 -49.777142) (xy 280.827734 -49.998122)
			(xy 280.997914 -50.087022) (xy 281.042364 -50.087022)
		)
		(stroke
			(width 0)
			(type solid)
		)
		(fill yes)
		(layer "In11.Cu")
		(net "M_C_DQS_DP<15>")
	)
	(gr_poly
		(pts
			(xy 281.042364 -48.697642) (xy 280.997914 -48.697642) (xy 280.827734 -48.786542) (xy 280.827734 -49.007522)
			(xy 280.997914 -49.096422) (xy 281.042364 -49.096422)
		)
		(stroke
			(width 0)
			(type solid)
		)
		(fill yes)
		(layer "In11.Cu")
		(net "M_C_DQS_DP<15>")
	)
	(gr_poly
		(pts
			(xy 281.055826 -99.640898) (xy 281.078178 -99.60229) (xy 280.732738 -99.403154) (xy 280.71064 -99.441508)
			(xy 280.702512 -99.633278) (xy 280.893774 -99.743768)
		)
		(stroke
			(width 0)
			(type solid)
		)
		(fill yes)
		(layer "In11.Cu")
		(net "M_F_DQ<48>")
	)
	(gr_poly
		(pts
			(xy 281.055826 -98.650298) (xy 281.078178 -98.61169) (xy 280.732738 -98.412554) (xy 280.71064 -98.450908)
			(xy 280.702512 -98.642678) (xy 280.893774 -98.753168)
		)
		(stroke
			(width 0)
			(type solid)
		)
		(fill yes)
		(layer "In11.Cu")
		(net "M_F_DQS_DP<15>")
	)
	(gr_poly
		(pts
			(xy 281.055826 -97.659698) (xy 281.078178 -97.62109) (xy 280.732738 -97.421954) (xy 280.71064 -97.460308)
			(xy 280.702512 -97.652078) (xy 280.893774 -97.762568)
		)
		(stroke
			(width 0)
			(type solid)
		)
		(fill yes)
		(layer "In11.Cu")
		(net "M_F_DQS_DN<6>")
	)
	(gr_poly
		(pts
			(xy 281.055826 -96.669098) (xy 281.078178 -96.63049) (xy 280.732738 -96.431354) (xy 280.71064 -96.469708)
			(xy 280.702512 -96.661478) (xy 280.893774 -96.771968)
		)
		(stroke
			(width 0)
			(type solid)
		)
		(fill yes)
		(layer "In11.Cu")
		(net "M_F_DQ<54>")
	)
	(gr_poly
		(pts
			(xy 281.063446 -95.68307) (xy 281.085798 -95.644716) (xy 280.740104 -95.445326) (xy 280.718006 -95.483934)
			(xy 280.710132 -95.675704) (xy 280.901394 -95.78594)
		)
		(stroke
			(width 0)
			(type solid)
		)
		(fill yes)
		(layer "In11.Cu")
		(net "M_F_DQ<50>")
	)
	(gr_poly
		(pts
			(xy 281.155902 -104.560624) (xy 281.155902 -104.339644) (xy 280.985722 -104.250744) (xy 280.941272 -104.250744)
			(xy 280.941272 -104.649524) (xy 280.985722 -104.649524)
		)
		(stroke
			(width 0)
			(type solid)
		)
		(fill yes)
		(layer "In11.Cu")
		(net "M_F_DQ<53>")
	)
	(gr_poly
		(pts
			(xy 281.155902 -103.570024) (xy 281.155902 -103.349044) (xy 280.985722 -103.260144) (xy 280.941272 -103.260144)
			(xy 280.941272 -103.658924) (xy 280.985722 -103.658924)
		)
		(stroke
			(width 0)
			(type solid)
		)
		(fill yes)
		(layer "In11.Cu")
		(net "M_F_DQ<53>")
	)
	(gr_poly
		(pts
			(xy 281.155902 -102.579424) (xy 281.155902 -102.358444) (xy 280.985722 -102.269544) (xy 280.941272 -102.269544)
			(xy 280.941272 -102.668324) (xy 280.985722 -102.668324)
		)
		(stroke
			(width 0)
			(type solid)
		)
		(fill yes)
		(layer "In11.Cu")
		(net "M_F_DQ<53>")
	)
	(gr_poly
		(pts
			(xy 281.155902 -101.588824) (xy 281.155902 -101.367844) (xy 280.985722 -101.278944) (xy 280.941272 -101.278944)
			(xy 280.941272 -101.677724) (xy 280.985722 -101.677724)
		)
		(stroke
			(width 0)
			(type solid)
		)
		(fill yes)
		(layer "In11.Cu")
		(net "M_F_DQ<53>")
	)
	(gr_poly
		(pts
			(xy 281.155902 -100.598224) (xy 281.155902 -100.377244) (xy 280.985722 -100.288344) (xy 280.941272 -100.288344)
			(xy 280.941272 -100.687124) (xy 280.985722 -100.687124)
		)
		(stroke
			(width 0)
			(type solid)
		)
		(fill yes)
		(layer "In11.Cu")
		(net "M_F_DQ<53>")
	)
	(gr_poly
		(pts
			(xy 281.155902 -94.642178) (xy 281.155902 -94.421198) (xy 280.985722 -94.332298) (xy 280.941272 -94.332298)
			(xy 280.941272 -94.731078) (xy 280.985722 -94.731078)
		)
		(stroke
			(width 0)
			(type solid)
		)
		(fill yes)
		(layer "In11.Cu")
		(net "M_F_DQ<51>")
	)
	(gr_poly
		(pts
			(xy 281.155902 -93.664024) (xy 281.155902 -93.443044) (xy 280.985722 -93.354144) (xy 280.941272 -93.354144)
			(xy 280.941272 -93.752924) (xy 280.985722 -93.752924)
		)
		(stroke
			(width 0)
			(type solid)
		)
		(fill yes)
		(layer "In11.Cu")
		(net "M_F_DQ<51>")
	)
	(gr_poly
		(pts
			(xy 281.155902 -92.673424) (xy 281.155902 -92.452444) (xy 280.985722 -92.363544) (xy 280.941272 -92.363544)
			(xy 280.941272 -92.762324) (xy 280.985722 -92.762324)
		)
		(stroke
			(width 0)
			(type solid)
		)
		(fill yes)
		(layer "In11.Cu")
		(net "M_F_DQ<51>")
	)
	(gr_poly
		(pts
			(xy 281.191716 -61.153548) (xy 281.147266 -61.153548) (xy 280.977086 -61.242448) (xy 280.977086 -61.463428)
			(xy 281.147266 -61.552328) (xy 281.191716 -61.552328)
		)
		(stroke
			(width 0)
			(type solid)
		)
		(fill yes)
		(layer "In11.Cu")
		(net "M_C_DQS_DP<15>")
	)
	(gr_poly
		(pts
			(xy 281.191716 -60.156598) (xy 281.147266 -60.156598) (xy 280.977086 -60.245498) (xy 280.977086 -60.466478)
			(xy 281.147266 -60.555378) (xy 281.191716 -60.555378)
		)
		(stroke
			(width 0)
			(type solid)
		)
		(fill yes)
		(layer "In11.Cu")
		(net "M_C_DQS_DP<15>")
	)
	(gr_poly
		(pts
			(xy 281.191716 -59.165998) (xy 281.147266 -59.165998) (xy 280.977086 -59.254898) (xy 280.977086 -59.475878)
			(xy 281.147266 -59.564778) (xy 281.191716 -59.564778)
		)
		(stroke
			(width 0)
			(type solid)
		)
		(fill yes)
		(layer "In11.Cu")
		(net "M_C_DQS_DP<15>")
	)
	(gr_poly
		(pts
			(xy 281.191716 -58.181748) (xy 281.147266 -58.181748) (xy 280.977086 -58.270648) (xy 280.977086 -58.491628)
			(xy 281.147266 -58.580528) (xy 281.191716 -58.580528)
		)
		(stroke
			(width 0)
			(type solid)
		)
		(fill yes)
		(layer "In11.Cu")
		(net "M_C_DQS_DP<15>")
	)
	(gr_poly
		(pts
			(xy 281.191716 -57.184798) (xy 281.147266 -57.184798) (xy 280.977086 -57.273698) (xy 280.977086 -57.494678)
			(xy 281.147266 -57.583578) (xy 281.191716 -57.583578)
		)
		(stroke
			(width 0)
			(type solid)
		)
		(fill yes)
		(layer "In11.Cu")
		(net "M_C_DQS_DP<15>")
	)
	(gr_poly
		(pts
			(xy 281.191716 -56.194198) (xy 281.147266 -56.194198) (xy 280.977086 -56.283098) (xy 280.977086 -56.504078)
			(xy 281.147266 -56.592978) (xy 281.191716 -56.592978)
		)
		(stroke
			(width 0)
			(type solid)
		)
		(fill yes)
		(layer "In11.Cu")
		(net "M_C_DQS_DP<15>")
	)
	(gr_poly
		(pts
			(xy 281.191716 -55.203598) (xy 281.147266 -55.203598) (xy 280.977086 -55.292498) (xy 280.977086 -55.513478)
			(xy 281.147266 -55.602378) (xy 281.191716 -55.602378)
		)
		(stroke
			(width 0)
			(type solid)
		)
		(fill yes)
		(layer "In11.Cu")
		(net "M_C_DQS_DP<15>")
	)
	(gr_poly
		(pts
			(xy 281.191716 -54.212998) (xy 281.147266 -54.212998) (xy 280.977086 -54.301898) (xy 280.977086 -54.522878)
			(xy 281.147266 -54.611778) (xy 281.191716 -54.611778)
		)
		(stroke
			(width 0)
			(type solid)
		)
		(fill yes)
		(layer "In11.Cu")
		(net "M_C_DQS_DP<15>")
	)
	(gr_poly
		(pts
			(xy 281.220418 -51.591972) (xy 281.251914 -51.56073) (xy 280.964386 -51.273202) (xy 280.933144 -51.304698)
			(xy 280.859484 -51.504088) (xy 281.021028 -51.665632)
		)
		(stroke
			(width 0)
			(type solid)
		)
		(fill yes)
		(layer "In11.Cu")
		(net "M_C_DQS_DP<15>")
	)
	(gr_poly
		(pts
			(xy 281.307032 -63.3349) (xy 281.266392 -63.147194) (xy 281.237944 -63.113158) (xy 280.93162 -63.368428)
			(xy 280.960068 -63.402464) (xy 281.137106 -63.476378)
		)
		(stroke
			(width 0)
			(type solid)
		)
		(fill yes)
		(layer "In11.Cu")
		(net "M_C_DQ<49>")
	)
	(gr_poly
		(pts
			(xy 281.324558 -53.20919) (xy 281.280108 -53.20919) (xy 281.087068 -53.29809) (xy 281.087068 -53.52669)
			(xy 281.280108 -53.61559) (xy 281.324558 -53.61559)
		)
		(stroke
			(width 0)
			(type solid)
		)
		(fill yes)
		(layer "In11.Cu")
		(net "M_C_DQS_DP<15>")
	)
	(gr_poly
		(pts
			(xy 281.324558 -52.21859) (xy 281.280108 -52.21859) (xy 281.087068 -52.30749) (xy 281.087068 -52.53609)
			(xy 281.280108 -52.62499) (xy 281.324558 -52.62499)
		)
		(stroke
			(width 0)
			(type solid)
		)
		(fill yes)
		(layer "In11.Cu")
		(net "M_C_DQS_DP<15>")
	)
	(gr_poly
		(pts
			(xy 281.447494 -49.998122) (xy 281.447494 -49.777142) (xy 281.277314 -49.688242) (xy 281.232864 -49.688242)
			(xy 281.232864 -50.087022) (xy 281.277314 -50.087022)
		)
		(stroke
			(width 0)
			(type solid)
		)
		(fill yes)
		(layer "In11.Cu")
		(net "M_C_DQS_DN<15>")
	)
	(gr_poly
		(pts
			(xy 281.447494 -49.007522) (xy 281.447494 -48.786542) (xy 281.277314 -48.697642) (xy 281.232864 -48.697642)
			(xy 281.232864 -49.096422) (xy 281.277314 -49.096422)
		)
		(stroke
			(width 0)
			(type solid)
		)
		(fill yes)
		(layer "In11.Cu")
		(net "M_C_DQS_DN<15>")
	)
	(gr_poly
		(pts
			(xy 281.476196 -105.243884) (xy 281.431746 -105.243884) (xy 281.261566 -105.332784) (xy 281.261566 -105.553764)
			(xy 281.431746 -105.642664) (xy 281.476196 -105.642664)
		)
		(stroke
			(width 0)
			(type solid)
		)
		(fill yes)
		(layer "In11.Cu")
		(net "M_F_DQ<48>")
	)
	(gr_poly
		(pts
			(xy 281.476196 -104.253284) (xy 281.431746 -104.253284) (xy 281.261566 -104.342184) (xy 281.261566 -104.563164)
			(xy 281.431746 -104.652064) (xy 281.476196 -104.652064)
		)
		(stroke
			(width 0)
			(type solid)
		)
		(fill yes)
		(layer "In11.Cu")
		(net "M_F_DQ<48>")
	)
	(gr_poly
		(pts
			(xy 281.476196 -103.262684) (xy 281.431746 -103.262684) (xy 281.261566 -103.351584) (xy 281.261566 -103.572564)
			(xy 281.431746 -103.661464) (xy 281.476196 -103.661464)
		)
		(stroke
			(width 0)
			(type solid)
		)
		(fill yes)
		(layer "In11.Cu")
		(net "M_F_DQ<48>")
	)
	(gr_poly
		(pts
			(xy 281.476196 -102.272084) (xy 281.431746 -102.272084) (xy 281.261566 -102.360984) (xy 281.261566 -102.581964)
			(xy 281.431746 -102.670864) (xy 281.476196 -102.670864)
		)
		(stroke
			(width 0)
			(type solid)
		)
		(fill yes)
		(layer "In11.Cu")
		(net "M_F_DQ<48>")
	)
	(gr_poly
		(pts
			(xy 281.476196 -101.281484) (xy 281.431746 -101.281484) (xy 281.261566 -101.370384) (xy 281.261566 -101.591364)
			(xy 281.431746 -101.680264) (xy 281.476196 -101.680264)
		)
		(stroke
			(width 0)
			(type solid)
		)
		(fill yes)
		(layer "In11.Cu")
		(net "M_F_DQ<48>")
	)
	(gr_poly
		(pts
			(xy 281.476196 -100.290884) (xy 281.431746 -100.290884) (xy 281.261566 -100.379784) (xy 281.261566 -100.600764)
			(xy 281.431746 -100.689664) (xy 281.476196 -100.689664)
		)
		(stroke
			(width 0)
			(type solid)
		)
		(fill yes)
		(layer "In11.Cu")
		(net "M_F_DQ<48>")
	)
	(gr_poly
		(pts
			(xy 281.476196 -94.344744) (xy 281.431746 -94.344744) (xy 281.261566 -94.433644) (xy 281.261566 -94.654624)
			(xy 281.431746 -94.743524) (xy 281.476196 -94.743524)
		)
		(stroke
			(width 0)
			(type solid)
		)
		(fill yes)
		(layer "In11.Cu")
		(net "M_F_DQ<60>")
	)
	(gr_poly
		(pts
			(xy 281.476196 -93.354144) (xy 281.431746 -93.354144) (xy 281.261566 -93.443044) (xy 281.261566 -93.664024)
			(xy 281.431746 -93.752924) (xy 281.476196 -93.752924)
		)
		(stroke
			(width 0)
			(type solid)
		)
		(fill yes)
		(layer "In11.Cu")
		(net "M_F_DQ<60>")
	)
	(gr_poly
		(pts
			(xy 281.476196 -92.363544) (xy 281.431746 -92.363544) (xy 281.261566 -92.452444) (xy 281.261566 -92.673424)
			(xy 281.431746 -92.762324) (xy 281.476196 -92.762324)
		)
		(stroke
			(width 0)
			(type solid)
		)
		(fill yes)
		(layer "In11.Cu")
		(net "M_F_DQ<60>")
	)
	(gr_poly
		(pts
			(xy 281.476196 -91.372944) (xy 281.431746 -91.372944) (xy 281.261566 -91.461844) (xy 281.261566 -91.682824)
			(xy 281.431746 -91.771724) (xy 281.476196 -91.771724)
		)
		(stroke
			(width 0)
			(type solid)
		)
		(fill yes)
		(layer "In11.Cu")
		(net "M_F_DQ<60>")
	)
	(gr_poly
		(pts
			(xy 281.596846 -47.731426) (xy 281.56535 -47.69993) (xy 281.382216 -47.642526) (xy 281.226006 -47.798736)
			(xy 281.28341 -47.98187) (xy 281.314906 -48.013366)
		)
		(stroke
			(width 0)
			(type solid)
		)
		(fill yes)
		(layer "In11.Cu")
		(net "M_C_DQS_DP<15>")
	)
	(gr_poly
		(pts
			(xy 281.703018 -99.537774) (xy 281.711146 -99.346004) (xy 281.51963 -99.235768) (xy 281.357832 -99.338638)
			(xy 281.335226 -99.376992) (xy 281.68092 -99.576382)
		)
		(stroke
			(width 0)
			(type solid)
		)
		(fill yes)
		(layer "In11.Cu")
		(net "M_F_DQ<49>")
	)
	(gr_poly
		(pts
			(xy 281.704542 -95.576644) (xy 281.71267 -95.384874) (xy 281.521408 -95.274384) (xy 281.359356 -95.377254)
			(xy 281.337004 -95.415862) (xy 281.682444 -95.614998)
		)
		(stroke
			(width 0)
			(type solid)
		)
		(fill yes)
		(layer "In11.Cu")
		(net "M_F_DQ<51>")
	)
	(gr_poly
		(pts
			(xy 281.708352 -98.55073) (xy 281.71648 -98.35896) (xy 281.525218 -98.24847) (xy 281.363166 -98.35134)
			(xy 281.340814 -98.389694) (xy 281.686254 -98.589338)
		)
		(stroke
			(width 0)
			(type solid)
		)
		(fill yes)
		(layer "In11.Cu")
		(net "M_F_DQS_DN<15>")
	)
	(gr_poly
		(pts
			(xy 281.708352 -97.56013) (xy 281.71648 -97.36836) (xy 281.525218 -97.25787) (xy 281.363166 -97.36074)
			(xy 281.340814 -97.399094) (xy 281.686254 -97.598738)
		)
		(stroke
			(width 0)
			(type solid)
		)
		(fill yes)
		(layer "In11.Cu")
		(net "M_F_DQS_DP<6>")
	)
	(gr_poly
		(pts
			(xy 281.708352 -96.56953) (xy 281.71648 -96.37776) (xy 281.525218 -96.26727) (xy 281.363166 -96.37014)
			(xy 281.340814 -96.408494) (xy 281.686254 -96.608138)
		)
		(stroke
			(width 0)
			(type solid)
		)
		(fill yes)
		(layer "In11.Cu")
		(net "M_F_DQ<55>")
	)
	(gr_poly
		(pts
			(xy 281.729942 -60.974224) (xy 281.729942 -60.753244) (xy 281.559762 -60.664344) (xy 281.515312 -60.664344)
			(xy 281.515312 -61.063124) (xy 281.559762 -61.063124)
		)
		(stroke
			(width 0)
			(type solid)
		)
		(fill yes)
		(layer "In11.Cu")
		(net "M_C_DQS_DN<15>")
	)
	(gr_poly
		(pts
			(xy 281.729942 -59.977274) (xy 281.729942 -59.756294) (xy 281.559762 -59.667394) (xy 281.515312 -59.667394)
			(xy 281.515312 -60.066174) (xy 281.559762 -60.066174)
		)
		(stroke
			(width 0)
			(type solid)
		)
		(fill yes)
		(layer "In11.Cu")
		(net "M_C_DQS_DN<15>")
	)
	(gr_poly
		(pts
			(xy 281.729942 -58.980578) (xy 281.729942 -58.759598) (xy 281.559762 -58.670698) (xy 281.515312 -58.670698)
			(xy 281.515312 -59.069478) (xy 281.559762 -59.069478)
		)
		(stroke
			(width 0)
			(type solid)
		)
		(fill yes)
		(layer "In11.Cu")
		(net "M_C_DQS_DN<15>")
	)
	(gr_poly
		(pts
			(xy 281.729942 -58.002424) (xy 281.729942 -57.781444) (xy 281.559762 -57.692544) (xy 281.515312 -57.692544)
			(xy 281.515312 -58.091324) (xy 281.559762 -58.091324)
		)
		(stroke
			(width 0)
			(type solid)
		)
		(fill yes)
		(layer "In11.Cu")
		(net "M_C_DQS_DN<15>")
	)
	(gr_poly
		(pts
			(xy 281.729942 -57.011824) (xy 281.729942 -56.790844) (xy 281.559762 -56.701944) (xy 281.515312 -56.701944)
			(xy 281.515312 -57.100724) (xy 281.559762 -57.100724)
		)
		(stroke
			(width 0)
			(type solid)
		)
		(fill yes)
		(layer "In11.Cu")
		(net "M_C_DQS_DN<15>")
	)
	(gr_poly
		(pts
			(xy 281.729942 -56.021224) (xy 281.729942 -55.800244) (xy 281.559762 -55.711344) (xy 281.515312 -55.711344)
			(xy 281.515312 -56.110124) (xy 281.559762 -56.110124)
		)
		(stroke
			(width 0)
			(type solid)
		)
		(fill yes)
		(layer "In11.Cu")
		(net "M_C_DQS_DN<15>")
	)
	(gr_poly
		(pts
			(xy 281.729942 -55.030624) (xy 281.729942 -54.809644) (xy 281.559762 -54.720744) (xy 281.515312 -54.720744)
			(xy 281.515312 -55.119524) (xy 281.559762 -55.119524)
		)
		(stroke
			(width 0)
			(type solid)
		)
		(fill yes)
		(layer "In11.Cu")
		(net "M_C_DQS_DN<15>")
	)
	(gr_poly
		(pts
			(xy 281.752548 -53.88229) (xy 281.752548 -53.65369) (xy 281.559508 -53.56479) (xy 281.515058 -53.56479)
			(xy 281.515058 -53.97119) (xy 281.559508 -53.97119)
		)
		(stroke
			(width 0)
			(type solid)
		)
		(fill yes)
		(layer "In11.Cu")
		(net "M_C_DQS_DN<15>")
	)
	(gr_poly
		(pts
			(xy 281.752548 -52.89169) (xy 281.752548 -52.66309) (xy 281.559508 -52.57419) (xy 281.515058 -52.57419)
			(xy 281.515058 -52.98059) (xy 281.559508 -52.98059)
		)
		(stroke
			(width 0)
			(type solid)
		)
		(fill yes)
		(layer "In11.Cu")
		(net "M_C_DQS_DN<15>")
	)
	(gr_poly
		(pts
			(xy 281.752548 -51.90109) (xy 281.752548 -51.67249) (xy 281.559508 -51.58359) (xy 281.515058 -51.58359)
			(xy 281.515058 -51.98999) (xy 281.559508 -51.98999)
		)
		(stroke
			(width 0)
			(type solid)
		)
		(fill yes)
		(layer "In11.Cu")
		(net "M_C_DQS_DN<15>")
	)
	(gr_poly
		(pts
			(xy 281.763724 -49.727866) (xy 281.719274 -49.727866) (xy 281.549094 -49.816766) (xy 281.549094 -50.038)
			(xy 281.719274 -50.1269) (xy 281.763724 -50.1269)
		)
		(stroke
			(width 0)
			(type solid)
		)
		(fill yes)
		(layer "In11.Cu")
		(net "M_C_DQS_DP<6>")
	)
	(gr_poly
		(pts
			(xy 281.869134 -46.868588) (xy 281.824684 -46.868588) (xy 281.631644 -46.957488) (xy 281.631644 -47.186088)
			(xy 281.824684 -47.274988) (xy 281.869134 -47.274988)
		)
		(stroke
			(width 0)
			(type solid)
		)
		(fill yes)
		(layer "In11.Cu")
		(net "M_C_DQS_DP<15>")
	)
	(gr_poly
		(pts
			(xy 281.876246 -48.024796) (xy 281.818842 -47.841662) (xy 281.787346 -47.810166) (xy 281.505406 -48.092106)
			(xy 281.536902 -48.123602) (xy 281.720036 -48.181006)
		)
		(stroke
			(width 0)
			(type solid)
		)
		(fill yes)
		(layer "In11.Cu")
		(net "M_C_DQS_DN<15>")
	)
	(gr_poly
		(pts
			(xy 281.912822 -99.144582) (xy 281.935174 -99.105974) (xy 281.589734 -98.906838) (xy 281.567636 -98.945192)
			(xy 281.559508 -99.136962) (xy 281.75077 -99.247452)
		)
		(stroke
			(width 0)
			(type solid)
		)
		(fill yes)
		(layer "In11.Cu")
		(net "M_F_DQS_DP<15>")
	)
	(gr_poly
		(pts
			(xy 281.912822 -98.153982) (xy 281.935174 -98.115374) (xy 281.589734 -97.916238) (xy 281.567636 -97.954592)
			(xy 281.559508 -98.146362) (xy 281.75077 -98.256852)
		)
		(stroke
			(width 0)
			(type solid)
		)
		(fill yes)
		(layer "In11.Cu")
		(net "M_F_DQS_DN<6>")
	)
	(gr_poly
		(pts
			(xy 281.912822 -97.163382) (xy 281.935174 -97.124774) (xy 281.589734 -96.925638) (xy 281.567636 -96.963992)
			(xy 281.559508 -97.155762) (xy 281.75077 -97.266252)
		)
		(stroke
			(width 0)
			(type solid)
		)
		(fill yes)
		(layer "In11.Cu")
		(net "M_F_DQ<54>")
	)
	(gr_poly
		(pts
			(xy 281.912822 -96.172782) (xy 281.935174 -96.134174) (xy 281.589734 -95.935038) (xy 281.567636 -95.973392)
			(xy 281.559508 -96.165162) (xy 281.75077 -96.275652)
		)
		(stroke
			(width 0)
			(type solid)
		)
		(fill yes)
		(layer "In11.Cu")
		(net "M_F_DQ<50>")
	)
	(gr_poly
		(pts
			(xy 281.9146 -95.183452) (xy 281.936952 -95.145098) (xy 281.591258 -94.945708) (xy 281.569414 -94.984316)
			(xy 281.561286 -95.176086) (xy 281.752548 -95.286322)
		)
		(stroke
			(width 0)
			(type solid)
		)
		(fill yes)
		(layer "In11.Cu")
		(net "M_F_DQ<60>")
	)
	(gr_poly
		(pts
			(xy 282.014422 -106.031284) (xy 282.014422 -105.810304) (xy 281.844242 -105.721404) (xy 281.799792 -105.721404)
			(xy 281.799792 -106.120184) (xy 281.844242 -106.120184)
		)
		(stroke
			(width 0)
			(type solid)
		)
		(fill yes)
		(layer "In11.Cu")
		(net "M_F_DQ<49>")
	)
	(gr_poly
		(pts
			(xy 282.014422 -105.040684) (xy 282.014422 -104.819704) (xy 281.844242 -104.730804) (xy 281.799792 -104.730804)
			(xy 281.799792 -105.129584) (xy 281.844242 -105.129584)
		)
		(stroke
			(width 0)
			(type solid)
		)
		(fill yes)
		(layer "In11.Cu")
		(net "M_F_DQ<49>")
	)
	(gr_poly
		(pts
			(xy 282.014422 -104.050084) (xy 282.014422 -103.829104) (xy 281.844242 -103.740204) (xy 281.799792 -103.740204)
			(xy 281.799792 -104.138984) (xy 281.844242 -104.138984)
		)
		(stroke
			(width 0)
			(type solid)
		)
		(fill yes)
		(layer "In11.Cu")
		(net "M_F_DQ<49>")
	)
	(gr_poly
		(pts
			(xy 282.014422 -103.059484) (xy 282.014422 -102.838504) (xy 281.844242 -102.749604) (xy 281.799792 -102.749604)
			(xy 281.799792 -103.148384) (xy 281.844242 -103.148384)
		)
		(stroke
			(width 0)
			(type solid)
		)
		(fill yes)
		(layer "In11.Cu")
		(net "M_F_DQ<49>")
	)
	(gr_poly
		(pts
			(xy 282.014422 -102.068884) (xy 282.014422 -101.847904) (xy 281.844242 -101.759004) (xy 281.799792 -101.759004)
			(xy 281.799792 -102.157784) (xy 281.844242 -102.157784)
		)
		(stroke
			(width 0)
			(type solid)
		)
		(fill yes)
		(layer "In11.Cu")
		(net "M_F_DQ<49>")
	)
	(gr_poly
		(pts
			(xy 282.014422 -101.078284) (xy 282.014422 -100.857304) (xy 281.844242 -100.768404) (xy 281.799792 -100.768404)
			(xy 281.799792 -101.167184) (xy 281.844242 -101.167184)
		)
		(stroke
			(width 0)
			(type solid)
		)
		(fill yes)
		(layer "In11.Cu")
		(net "M_F_DQ<49>")
	)
	(gr_poly
		(pts
			(xy 282.014422 -100.087684) (xy 282.014422 -99.866704) (xy 281.844242 -99.777804) (xy 281.799792 -99.777804)
			(xy 281.799792 -100.176584) (xy 281.844242 -100.176584)
		)
		(stroke
			(width 0)
			(type solid)
		)
		(fill yes)
		(layer "In11.Cu")
		(net "M_F_DQ<49>")
	)
	(gr_poly
		(pts
			(xy 282.014422 -94.153228) (xy 282.014422 -93.932248) (xy 281.844242 -93.843348) (xy 281.799792 -93.843348)
			(xy 281.799792 -94.242128) (xy 281.844242 -94.242128)
		)
		(stroke
			(width 0)
			(type solid)
		)
		(fill yes)
		(layer "In11.Cu")
		(net "M_F_DQ<61>")
	)
	(gr_poly
		(pts
			(xy 282.014422 -93.156278) (xy 282.014422 -92.935298) (xy 281.844242 -92.846398) (xy 281.799792 -92.846398)
			(xy 281.799792 -93.245178) (xy 281.844242 -93.245178)
		)
		(stroke
			(width 0)
			(type solid)
		)
		(fill yes)
		(layer "In11.Cu")
		(net "M_F_DQ<61>")
	)
	(gr_poly
		(pts
			(xy 282.050236 -63.636144) (xy 282.005786 -63.636144) (xy 281.835606 -63.725044) (xy 281.835606 -63.946024)
			(xy 282.005786 -64.034924) (xy 282.050236 -64.034924)
		)
		(stroke
			(width 0)
			(type solid)
		)
		(fill yes)
		(layer "In11.Cu")
		(net "M_C_DQS_DP<6>")
	)
	(gr_poly
		(pts
			(xy 282.050236 -62.645544) (xy 282.005786 -62.645544) (xy 281.835606 -62.734444) (xy 281.835606 -62.955424)
			(xy 282.005786 -63.044324) (xy 282.050236 -63.044324)
		)
		(stroke
			(width 0)
			(type solid)
		)
		(fill yes)
		(layer "In11.Cu")
		(net "M_C_DQS_DP<6>")
	)
	(gr_poly
		(pts
			(xy 282.050236 -61.654944) (xy 282.005786 -61.654944) (xy 281.835606 -61.743844) (xy 281.835606 -61.964824)
			(xy 282.005786 -62.053724) (xy 282.050236 -62.053724)
		)
		(stroke
			(width 0)
			(type solid)
		)
		(fill yes)
		(layer "In11.Cu")
		(net "M_C_DQS_DP<6>")
	)
	(gr_poly
		(pts
			(xy 282.050236 -60.664344) (xy 282.005786 -60.664344) (xy 281.835606 -60.753244) (xy 281.835606 -60.974224)
			(xy 282.005786 -61.063124) (xy 282.050236 -61.063124)
		)
		(stroke
			(width 0)
			(type solid)
		)
		(fill yes)
		(layer "In11.Cu")
		(net "M_C_DQS_DP<6>")
	)
	(gr_poly
		(pts
			(xy 282.050236 -59.667394) (xy 282.005786 -59.667394) (xy 281.835606 -59.756294) (xy 281.835606 -59.977274)
			(xy 282.005786 -60.066174) (xy 282.050236 -60.066174)
		)
		(stroke
			(width 0)
			(type solid)
		)
		(fill yes)
		(layer "In11.Cu")
		(net "M_C_DQS_DP<6>")
	)
	(gr_poly
		(pts
			(xy 282.050236 -58.670698) (xy 282.005786 -58.670698) (xy 281.835606 -58.759598) (xy 281.835606 -58.980578)
			(xy 282.005786 -59.069478) (xy 282.050236 -59.069478)
		)
		(stroke
			(width 0)
			(type solid)
		)
		(fill yes)
		(layer "In11.Cu")
		(net "M_C_DQS_DP<6>")
	)
	(gr_poly
		(pts
			(xy 282.050236 -57.692544) (xy 282.005786 -57.692544) (xy 281.835606 -57.781444) (xy 281.835606 -58.002424)
			(xy 282.005786 -58.091324) (xy 282.050236 -58.091324)
		)
		(stroke
			(width 0)
			(type solid)
		)
		(fill yes)
		(layer "In11.Cu")
		(net "M_C_DQS_DP<6>")
	)
	(gr_poly
		(pts
			(xy 282.050236 -56.701944) (xy 282.005786 -56.701944) (xy 281.835606 -56.790844) (xy 281.835606 -57.011824)
			(xy 282.005786 -57.100724) (xy 282.050236 -57.100724)
		)
		(stroke
			(width 0)
			(type solid)
		)
		(fill yes)
		(layer "In11.Cu")
		(net "M_C_DQS_DP<6>")
	)
	(gr_poly
		(pts
			(xy 282.050236 -55.711344) (xy 282.005786 -55.711344) (xy 281.835606 -55.800244) (xy 281.835606 -56.021224)
			(xy 282.005786 -56.110124) (xy 282.050236 -56.110124)
		)
		(stroke
			(width 0)
			(type solid)
		)
		(fill yes)
		(layer "In11.Cu")
		(net "M_C_DQS_DP<6>")
	)
	(gr_poly
		(pts
			(xy 282.050236 -54.720744) (xy 282.005786 -54.720744) (xy 281.835606 -54.809644) (xy 281.835606 -55.030624)
			(xy 282.005786 -55.119524) (xy 282.050236 -55.119524)
		)
		(stroke
			(width 0)
			(type solid)
		)
		(fill yes)
		(layer "In11.Cu")
		(net "M_C_DQS_DP<6>")
	)
	(gr_poly
		(pts
			(xy 282.091638 -53.481478) (xy 282.047188 -53.481478) (xy 281.854148 -53.570378) (xy 281.854148 -53.798978)
			(xy 282.047188 -53.887878) (xy 282.091638 -53.887878)
		)
		(stroke
			(width 0)
			(type solid)
		)
		(fill yes)
		(layer "In11.Cu")
		(net "M_C_DQS_DP<6>")
	)
	(gr_poly
		(pts
			(xy 282.091638 -52.490878) (xy 282.047188 -52.490878) (xy 281.854148 -52.579778) (xy 281.854148 -52.808378)
			(xy 282.047188 -52.897278) (xy 282.091638 -52.897278)
		)
		(stroke
			(width 0)
			(type solid)
		)
		(fill yes)
		(layer "In11.Cu")
		(net "M_C_DQS_DP<6>")
	)
	(gr_poly
		(pts
			(xy 282.091638 -51.500278) (xy 282.047188 -51.500278) (xy 281.854148 -51.589178) (xy 281.854148 -51.817778)
			(xy 282.047188 -51.906678) (xy 282.091638 -51.906678)
		)
		(stroke
			(width 0)
			(type solid)
		)
		(fill yes)
		(layer "In11.Cu")
		(net "M_C_DQS_DP<6>")
	)
	(gr_poly
		(pts
			(xy 282.168854 -50.038) (xy 282.168854 -49.816766) (xy 281.998674 -49.727866) (xy 281.954224 -49.727866)
			(xy 281.954224 -50.1269) (xy 281.998674 -50.1269)
		)
		(stroke
			(width 0)
			(type solid)
		)
		(fill yes)
		(layer "In11.Cu")
		(net "M_C_DQS_DN<6>")
	)
	(gr_poly
		(pts
			(xy 282.297124 -47.236888) (xy 282.297124 -47.008288) (xy 282.104084 -46.919388) (xy 282.059634 -46.919388)
			(xy 282.059634 -47.325788) (xy 282.104084 -47.325788)
		)
		(stroke
			(width 0)
			(type solid)
		)
		(fill yes)
		(layer "In11.Cu")
		(net "M_C_DQS_DN<15>")
	)
	(gr_poly
		(pts
			(xy 282.334716 -104.730804) (xy 282.290266 -104.730804) (xy 282.120086 -104.819704) (xy 282.120086 -105.040684)
			(xy 282.290266 -105.129584) (xy 282.334716 -105.129584)
		)
		(stroke
			(width 0)
			(type solid)
		)
		(fill yes)
		(layer "In11.Cu")
		(net "M_F_DQS_DP<15>")
	)
	(gr_poly
		(pts
			(xy 282.334716 -103.740204) (xy 282.290266 -103.740204) (xy 282.120086 -103.829104) (xy 282.120086 -104.050084)
			(xy 282.290266 -104.138984) (xy 282.334716 -104.138984)
		)
		(stroke
			(width 0)
			(type solid)
		)
		(fill yes)
		(layer "In11.Cu")
		(net "M_F_DQS_DP<15>")
	)
	(gr_poly
		(pts
			(xy 282.334716 -102.749604) (xy 282.290266 -102.749604) (xy 282.120086 -102.838504) (xy 282.120086 -103.059484)
			(xy 282.290266 -103.148384) (xy 282.334716 -103.148384)
		)
		(stroke
			(width 0)
			(type solid)
		)
		(fill yes)
		(layer "In11.Cu")
		(net "M_F_DQS_DP<15>")
	)
	(gr_poly
		(pts
			(xy 282.334716 -101.76764) (xy 282.290266 -101.76764) (xy 282.120086 -101.85654) (xy 282.120086 -102.07752)
			(xy 282.290266 -102.16642) (xy 282.334716 -102.16642)
		)
		(stroke
			(width 0)
			(type solid)
		)
		(fill yes)
		(layer "In11.Cu")
		(net "M_F_DQS_DP<15>")
	)
	(gr_poly
		(pts
			(xy 282.334716 -100.783136) (xy 282.290266 -100.783136) (xy 282.120086 -100.872036) (xy 282.120086 -101.093016)
			(xy 282.290266 -101.181916) (xy 282.334716 -101.181916)
		)
		(stroke
			(width 0)
			(type solid)
		)
		(fill yes)
		(layer "In11.Cu")
		(net "M_F_DQS_DP<15>")
	)
	(gr_poly
		(pts
			(xy 282.334716 -99.79279) (xy 282.290266 -99.79279) (xy 282.120086 -99.88169) (xy 282.120086 -100.10267)
			(xy 282.290266 -100.19157) (xy 282.334716 -100.19157)
		)
		(stroke
			(width 0)
			(type solid)
		)
		(fill yes)
		(layer "In11.Cu")
		(net "M_F_DQS_DP<15>")
	)
	(gr_poly
		(pts
			(xy 282.334716 -93.836998) (xy 282.290266 -93.836998) (xy 282.120086 -93.925898) (xy 282.120086 -94.146878)
			(xy 282.290266 -94.235778) (xy 282.334716 -94.235778)
		)
		(stroke
			(width 0)
			(type solid)
		)
		(fill yes)
		(layer "In11.Cu")
		(net "M_F_DQ<56>")
	)
	(gr_poly
		(pts
			(xy 282.334716 -92.846398) (xy 282.290266 -92.846398) (xy 282.120086 -92.935298) (xy 282.120086 -93.156278)
			(xy 282.290266 -93.245178) (xy 282.334716 -93.245178)
		)
		(stroke
			(width 0)
			(type solid)
		)
		(fill yes)
		(layer "In11.Cu")
		(net "M_F_DQ<56>")
	)
	(gr_poly
		(pts
			(xy 282.334716 -91.855798) (xy 282.290266 -91.855798) (xy 282.120086 -91.944698) (xy 282.120086 -92.165678)
			(xy 282.290266 -92.254578) (xy 282.334716 -92.254578)
		)
		(stroke
			(width 0)
			(type solid)
		)
		(fill yes)
		(layer "In11.Cu")
		(net "M_F_DQ<56>")
	)
	(gr_poly
		(pts
			(xy 282.46832 -48.57877) (xy 282.436824 -48.547528) (xy 282.237434 -48.473868) (xy 282.07589 -48.635412)
			(xy 282.14955 -48.834802) (xy 282.180792 -48.866298)
		)
		(stroke
			(width 0)
			(type solid)
		)
		(fill yes)
		(layer "In11.Cu")
		(net "M_C_DQS_DP<6>")
	)
	(gr_poly
		(pts
			(xy 282.519628 -53.798978) (xy 282.519628 -53.570378) (xy 282.326588 -53.481478) (xy 282.282138 -53.481478)
			(xy 282.282138 -53.887878) (xy 282.326588 -53.887878)
		)
		(stroke
			(width 0)
			(type solid)
		)
		(fill yes)
		(layer "In11.Cu")
		(net "M_C_DQS_DN<6>")
	)
	(gr_poly
		(pts
			(xy 282.519628 -52.808378) (xy 282.519628 -52.579778) (xy 282.326588 -52.490878) (xy 282.282138 -52.490878)
			(xy 282.282138 -52.897278) (xy 282.326588 -52.897278)
		)
		(stroke
			(width 0)
			(type solid)
		)
		(fill yes)
		(layer "In11.Cu")
		(net "M_C_DQS_DN<6>")
	)
	(gr_poly
		(pts
			(xy 282.519628 -51.817778) (xy 282.519628 -51.589178) (xy 282.326588 -51.500278) (xy 282.282138 -51.500278)
			(xy 282.282138 -51.906678) (xy 282.326588 -51.906678)
		)
		(stroke
			(width 0)
			(type solid)
		)
		(fill yes)
		(layer "In11.Cu")
		(net "M_C_DQS_DN<6>")
	)
	(gr_poly
		(pts
			(xy 282.565094 -99.04476) (xy 282.572968 -98.85299) (xy 282.381706 -98.7425) (xy 282.219654 -98.845624)
			(xy 282.197556 -98.883724) (xy 282.542996 -99.083368)
		)
		(stroke
			(width 0)
			(type solid)
		)
		(fill yes)
		(layer "In11.Cu")
		(net "M_F_DQS_DN<15>")
	)
	(gr_poly
		(pts
			(xy 282.565348 -98.054414) (xy 282.573476 -97.862644) (xy 282.382214 -97.752154) (xy 282.220162 -97.855024)
			(xy 282.19781 -97.893378) (xy 282.54325 -98.093022)
		)
		(stroke
			(width 0)
			(type solid)
		)
		(fill yes)
		(layer "In11.Cu")
		(net "M_F_DQS_DP<6>")
	)
	(gr_poly
		(pts
			(xy 282.565348 -97.063814) (xy 282.573476 -96.872044) (xy 282.382214 -96.761554) (xy 282.220162 -96.864424)
			(xy 282.19781 -96.902778) (xy 282.54325 -97.102422)
		)
		(stroke
			(width 0)
			(type solid)
		)
		(fill yes)
		(layer "In11.Cu")
		(net "M_F_DQ<55>")
	)
	(gr_poly
		(pts
			(xy 282.565348 -96.073214) (xy 282.573476 -95.881444) (xy 282.382214 -95.770954) (xy 282.220162 -95.873824)
			(xy 282.19781 -95.912178) (xy 282.54325 -96.111822)
		)
		(stroke
			(width 0)
			(type solid)
		)
		(fill yes)
		(layer "In11.Cu")
		(net "M_F_DQ<51>")
	)
	(gr_poly
		(pts
			(xy 282.566872 -95.083376) (xy 282.575 -94.891606) (xy 282.383738 -94.781116) (xy 282.221686 -94.883986)
			(xy 282.199334 -94.922594) (xy 282.544774 -95.12173)
		)
		(stroke
			(width 0)
			(type solid)
		)
		(fill yes)
		(layer "In11.Cu")
		(net "M_F_DQ<61>")
	)
	(gr_poly
		(pts
			(xy 282.587954 -64.446404) (xy 282.588208 -64.225424) (xy 282.417774 -64.136778) (xy 282.373578 -64.136778)
			(xy 282.373324 -64.535304) (xy 282.417774 -64.535304)
		)
		(stroke
			(width 0)
			(type solid)
		)
		(fill yes)
		(layer "In11.Cu")
		(net "M_C_DQS_DN<6>")
	)
	(gr_poly
		(pts
			(xy 282.588462 -63.438278) (xy 282.588462 -63.217298) (xy 282.418282 -63.128398) (xy 282.373832 -63.128398)
			(xy 282.373832 -63.527178) (xy 282.418282 -63.527178)
		)
		(stroke
			(width 0)
			(type solid)
		)
		(fill yes)
		(layer "In11.Cu")
		(net "M_C_DQS_DN<6>")
	)
	(gr_poly
		(pts
			(xy 282.588462 -62.447678) (xy 282.588462 -62.226698) (xy 282.418282 -62.137798) (xy 282.373832 -62.137798)
			(xy 282.373832 -62.536578) (xy 282.418282 -62.536578)
		)
		(stroke
			(width 0)
			(type solid)
		)
		(fill yes)
		(layer "In11.Cu")
		(net "M_C_DQS_DN<6>")
	)
	(gr_poly
		(pts
			(xy 282.588462 -61.457078) (xy 282.588462 -61.236098) (xy 282.418282 -61.147198) (xy 282.373832 -61.147198)
			(xy 282.373832 -61.545978) (xy 282.418282 -61.545978)
		)
		(stroke
			(width 0)
			(type solid)
		)
		(fill yes)
		(layer "In11.Cu")
		(net "M_C_DQS_DN<6>")
	)
	(gr_poly
		(pts
			(xy 282.588462 -60.466478) (xy 282.588462 -60.245498) (xy 282.418282 -60.156598) (xy 282.373832 -60.156598)
			(xy 282.373832 -60.555378) (xy 282.418282 -60.555378)
		)
		(stroke
			(width 0)
			(type solid)
		)
		(fill yes)
		(layer "In11.Cu")
		(net "M_C_DQS_DN<6>")
	)
	(gr_poly
		(pts
			(xy 282.588462 -59.488324) (xy 282.588462 -59.267344) (xy 282.418282 -59.178444) (xy 282.373832 -59.178444)
			(xy 282.373832 -59.577224) (xy 282.418282 -59.577224)
		)
		(stroke
			(width 0)
			(type solid)
		)
		(fill yes)
		(layer "In11.Cu")
		(net "M_C_DQS_DN<6>")
	)
	(gr_poly
		(pts
			(xy 282.588462 -58.491628) (xy 282.588462 -58.270648) (xy 282.418282 -58.181748) (xy 282.373832 -58.181748)
			(xy 282.373832 -58.580528) (xy 282.418282 -58.580528)
		)
		(stroke
			(width 0)
			(type solid)
		)
		(fill yes)
		(layer "In11.Cu")
		(net "M_C_DQS_DN<6>")
	)
	(gr_poly
		(pts
			(xy 282.588462 -57.494678) (xy 282.588462 -57.273698) (xy 282.418282 -57.184798) (xy 282.373832 -57.184798)
			(xy 282.373832 -57.583578) (xy 282.418282 -57.583578)
		)
		(stroke
			(width 0)
			(type solid)
		)
		(fill yes)
		(layer "In11.Cu")
		(net "M_C_DQS_DN<6>")
	)
	(gr_poly
		(pts
			(xy 282.588462 -56.504078) (xy 282.588462 -56.283098) (xy 282.418282 -56.194198) (xy 282.373832 -56.194198)
			(xy 282.373832 -56.592978) (xy 282.418282 -56.592978)
		)
		(stroke
			(width 0)
			(type solid)
		)
		(fill yes)
		(layer "In11.Cu")
		(net "M_C_DQS_DN<6>")
	)
	(gr_poly
		(pts
			(xy 282.588462 -55.513478) (xy 282.588462 -55.292498) (xy 282.418282 -55.203598) (xy 282.373832 -55.203598)
			(xy 282.373832 -55.602378) (xy 282.418282 -55.602378)
		)
		(stroke
			(width 0)
			(type solid)
		)
		(fill yes)
		(layer "In11.Cu")
		(net "M_C_DQS_DN<6>")
	)
	(gr_poly
		(pts
			(xy 282.708096 -48.944276) (xy 282.634436 -48.74514) (xy 282.60294 -48.713644) (xy 282.315666 -49.000918)
			(xy 282.347162 -49.032414) (xy 282.546298 -49.106074)
		)
		(stroke
			(width 0)
			(type solid)
		)
		(fill yes)
		(layer "In11.Cu")
		(net "M_C_DQS_DN<6>")
	)
	(gr_poly
		(pts
			(xy 282.771342 -94.687136) (xy 282.793694 -94.648782) (xy 282.448 -94.449392) (xy 282.426156 -94.487746)
			(xy 282.418028 -94.679516) (xy 282.60929 -94.790006)
		)
		(stroke
			(width 0)
			(type solid)
		)
		(fill yes)
		(layer "In11.Cu")
		(net "M_F_DQ<56>")
	)
	(gr_poly
		(pts
			(xy 282.772866 -98.650298) (xy 282.795218 -98.61169) (xy 282.449778 -98.412554) (xy 282.42768 -98.450908)
			(xy 282.419552 -98.642678) (xy 282.610814 -98.753168)
		)
		(stroke
			(width 0)
			(type solid)
		)
		(fill yes)
		(layer "In11.Cu")
		(net "M_F_DQS_DN<6>")
	)
	(gr_poly
		(pts
			(xy 282.772866 -97.659698) (xy 282.795218 -97.62109) (xy 282.449778 -97.421954) (xy 282.42768 -97.460308)
			(xy 282.419552 -97.652078) (xy 282.610814 -97.762568)
		)
		(stroke
			(width 0)
			(type solid)
		)
		(fill yes)
		(layer "In11.Cu")
		(net "M_F_DQ<54>")
	)
	(gr_poly
		(pts
			(xy 282.772866 -96.669098) (xy 282.795218 -96.63049) (xy 282.449778 -96.431354) (xy 282.42768 -96.469708)
			(xy 282.419552 -96.661478) (xy 282.610814 -96.771968)
		)
		(stroke
			(width 0)
			(type solid)
		)
		(fill yes)
		(layer "In11.Cu")
		(net "M_F_DQ<50>")
	)
	(gr_poly
		(pts
			(xy 282.775152 -95.679768) (xy 282.797504 -95.641414) (xy 282.452064 -95.44177) (xy 282.429966 -95.480378)
			(xy 282.421838 -95.672148) (xy 282.6131 -95.782638)
		)
		(stroke
			(width 0)
			(type solid)
		)
		(fill yes)
		(layer "In11.Cu")
		(net "M_F_DQ<60>")
	)
	(gr_poly
		(pts
			(xy 282.858718 -53.73751) (xy 282.814268 -53.73751) (xy 282.621228 -53.82641) (xy 282.621228 -54.05501)
			(xy 282.814268 -54.14391) (xy 282.858718 -54.14391)
		)
		(stroke
			(width 0)
			(type solid)
		)
		(fill yes)
		(layer "In11.Cu")
		(net "M_C_DQ<54>")
	)
	(gr_poly
		(pts
			(xy 282.858718 -52.74691) (xy 282.814268 -52.74691) (xy 282.621228 -52.83581) (xy 282.621228 -53.06441)
			(xy 282.814268 -53.15331) (xy 282.858718 -53.15331)
		)
		(stroke
			(width 0)
			(type solid)
		)
		(fill yes)
		(layer "In11.Cu")
		(net "M_C_DQ<54>")
	)
	(gr_poly
		(pts
			(xy 282.858718 -51.75631) (xy 282.814268 -51.75631) (xy 282.621228 -51.84521) (xy 282.621228 -52.07381)
			(xy 282.814268 -52.16271) (xy 282.858718 -52.16271)
		)
		(stroke
			(width 0)
			(type solid)
		)
		(fill yes)
		(layer "In11.Cu")
		(net "M_C_DQ<54>")
	)
	(gr_poly
		(pts
			(xy 282.872942 -105.553764) (xy 282.872942 -105.332784) (xy 282.702762 -105.243884) (xy 282.658312 -105.243884)
			(xy 282.658312 -105.642664) (xy 282.702762 -105.642664)
		)
		(stroke
			(width 0)
			(type solid)
		)
		(fill yes)
		(layer "In11.Cu")
		(net "M_F_DQS_DN<15>")
	)
	(gr_poly
		(pts
			(xy 282.872942 -104.563164) (xy 282.872942 -104.342184) (xy 282.702762 -104.253284) (xy 282.658312 -104.253284)
			(xy 282.658312 -104.652064) (xy 282.702762 -104.652064)
		)
		(stroke
			(width 0)
			(type solid)
		)
		(fill yes)
		(layer "In11.Cu")
		(net "M_F_DQS_DN<15>")
	)
	(gr_poly
		(pts
			(xy 282.872942 -103.572564) (xy 282.872942 -103.351584) (xy 282.702762 -103.262684) (xy 282.658312 -103.262684)
			(xy 282.658312 -103.661464) (xy 282.702762 -103.661464)
		)
		(stroke
			(width 0)
			(type solid)
		)
		(fill yes)
		(layer "In11.Cu")
		(net "M_F_DQS_DN<15>")
	)
	(gr_poly
		(pts
			(xy 282.872942 -102.57917) (xy 282.872942 -102.35819) (xy 282.702762 -102.26929) (xy 282.658312 -102.26929)
			(xy 282.658312 -102.66807) (xy 282.702762 -102.66807)
		)
		(stroke
			(width 0)
			(type solid)
		)
		(fill yes)
		(layer "In11.Cu")
		(net "M_F_DQS_DN<15>")
	)
	(gr_poly
		(pts
			(xy 282.872942 -101.58222) (xy 282.872942 -101.36124) (xy 282.702762 -101.27234) (xy 282.658312 -101.27234)
			(xy 282.658312 -101.67112) (xy 282.702762 -101.67112)
		)
		(stroke
			(width 0)
			(type solid)
		)
		(fill yes)
		(layer "In11.Cu")
		(net "M_F_DQS_DN<15>")
	)
	(gr_poly
		(pts
			(xy 282.872942 -100.58527) (xy 282.872942 -100.36429) (xy 282.702762 -100.27539) (xy 282.658312 -100.27539)
			(xy 282.658312 -100.67417) (xy 282.702762 -100.67417)
		)
		(stroke
			(width 0)
			(type solid)
		)
		(fill yes)
		(layer "In11.Cu")
		(net "M_F_DQS_DN<15>")
	)
	(gr_poly
		(pts
			(xy 282.872942 -99.59467) (xy 282.872942 -99.37369) (xy 282.702762 -99.28479) (xy 282.658312 -99.28479)
			(xy 282.658312 -99.68357) (xy 282.702762 -99.68357)
		)
		(stroke
			(width 0)
			(type solid)
		)
		(fill yes)
		(layer "In11.Cu")
		(net "M_F_DQS_DN<15>")
	)
	(gr_poly
		(pts
			(xy 282.872942 -93.664024) (xy 282.872942 -93.443044) (xy 282.702762 -93.354144) (xy 282.658312 -93.354144)
			(xy 282.658312 -93.752924) (xy 282.702762 -93.752924)
		)
		(stroke
			(width 0)
			(type solid)
		)
		(fill yes)
		(layer "In11.Cu")
		(net "M_F_DQ<57>")
	)
	(gr_poly
		(pts
			(xy 282.908756 -60.169298) (xy 282.864306 -60.169298) (xy 282.694126 -60.258198) (xy 282.694126 -60.479178)
			(xy 282.864306 -60.568078) (xy 282.908756 -60.568078)
		)
		(stroke
			(width 0)
			(type solid)
		)
		(fill yes)
		(layer "In11.Cu")
		(net "M_C_DQ<54>")
	)
	(gr_poly
		(pts
			(xy 282.908756 -59.178698) (xy 282.864306 -59.178698) (xy 282.694126 -59.267598) (xy 282.694126 -59.488578)
			(xy 282.864306 -59.577478) (xy 282.908756 -59.577478)
		)
		(stroke
			(width 0)
			(type solid)
		)
		(fill yes)
		(layer "In11.Cu")
		(net "M_C_DQ<54>")
	)
	(gr_poly
		(pts
			(xy 282.908756 -58.188098) (xy 282.864306 -58.188098) (xy 282.694126 -58.276998) (xy 282.694126 -58.497978)
			(xy 282.864306 -58.586878) (xy 282.908756 -58.586878)
		)
		(stroke
			(width 0)
			(type solid)
		)
		(fill yes)
		(layer "In11.Cu")
		(net "M_C_DQ<54>")
	)
	(gr_poly
		(pts
			(xy 282.908756 -57.191148) (xy 282.864306 -57.191148) (xy 282.694126 -57.280048) (xy 282.694126 -57.501028)
			(xy 282.864306 -57.589928) (xy 282.908756 -57.589928)
		)
		(stroke
			(width 0)
			(type solid)
		)
		(fill yes)
		(layer "In11.Cu")
		(net "M_C_DQ<54>")
	)
	(gr_poly
		(pts
			(xy 282.908756 -56.20004) (xy 282.864306 -56.20004) (xy 282.694126 -56.28894) (xy 282.694126 -56.50992)
			(xy 282.864306 -56.59882) (xy 282.908756 -56.59882)
		)
		(stroke
			(width 0)
			(type solid)
		)
		(fill yes)
		(layer "In11.Cu")
		(net "M_C_DQ<54>")
	)
	(gr_poly
		(pts
			(xy 282.908756 -55.203598) (xy 282.864306 -55.203598) (xy 282.694126 -55.292498) (xy 282.694126 -55.513478)
			(xy 282.864306 -55.602378) (xy 282.908756 -55.602378)
		)
		(stroke
			(width 0)
			(type solid)
		)
		(fill yes)
		(layer "In11.Cu")
		(net "M_C_DQ<54>")
	)
	(gr_poly
		(pts
			(xy 282.90901 -62.150498) (xy 282.86456 -62.150498) (xy 282.69438 -62.239398) (xy 282.69438 -62.460378)
			(xy 282.86456 -62.549278) (xy 282.90901 -62.549278)
		)
		(stroke
			(width 0)
			(type solid)
		)
		(fill yes)
		(layer "In11.Cu")
		(net "M_C_DQ<54>")
	)
	(gr_poly
		(pts
			(xy 282.90901 -61.159898) (xy 282.86456 -61.159898) (xy 282.69438 -61.248798) (xy 282.69438 -61.469778)
			(xy 282.86456 -61.558678) (xy 282.90901 -61.558678)
		)
		(stroke
			(width 0)
			(type solid)
		)
		(fill yes)
		(layer "In11.Cu")
		(net "M_C_DQ<54>")
	)
	(gr_poly
		(pts
			(xy 283.144468 -50.357786) (xy 283.100018 -50.357786) (xy 282.906978 -50.446686) (xy 282.906978 -50.675286)
			(xy 283.100018 -50.764186) (xy 283.144468 -50.764186)
		)
		(stroke
			(width 0)
			(type solid)
		)
		(fill yes)
		(layer "In11.Cu")
		(net "M_C_DQ<54>")
	)
	(gr_poly
		(pts
			(xy 283.144468 -49.367186) (xy 283.100018 -49.367186) (xy 282.906978 -49.456086) (xy 282.906978 -49.684686)
			(xy 283.100018 -49.773586) (xy 283.144468 -49.773586)
		)
		(stroke
			(width 0)
			(type solid)
		)
		(fill yes)
		(layer "In11.Cu")
		(net "M_C_DQ<54>")
	)
	(gr_poly
		(pts
			(xy 283.193236 -105.241344) (xy 283.148786 -105.241344) (xy 282.978606 -105.330244) (xy 282.978606 -105.551224)
			(xy 283.148786 -105.640124) (xy 283.193236 -105.640124)
		)
		(stroke
			(width 0)
			(type solid)
		)
		(fill yes)
		(layer "In11.Cu")
		(net "M_F_DQS_DN<6>")
	)
	(gr_poly
		(pts
			(xy 283.193236 -104.250744) (xy 283.148786 -104.250744) (xy 282.978606 -104.339644) (xy 282.978606 -104.560624)
			(xy 283.148786 -104.649524) (xy 283.193236 -104.649524)
		)
		(stroke
			(width 0)
			(type solid)
		)
		(fill yes)
		(layer "In11.Cu")
		(net "M_F_DQS_DN<6>")
	)
	(gr_poly
		(pts
			(xy 283.193236 -103.260144) (xy 283.148786 -103.260144) (xy 282.978606 -103.349044) (xy 282.978606 -103.570024)
			(xy 283.148786 -103.658924) (xy 283.193236 -103.658924)
		)
		(stroke
			(width 0)
			(type solid)
		)
		(fill yes)
		(layer "In11.Cu")
		(net "M_F_DQS_DN<6>")
	)
	(gr_poly
		(pts
			(xy 283.193236 -102.263194) (xy 283.148786 -102.263194) (xy 282.978606 -102.352094) (xy 282.978606 -102.573074)
			(xy 283.148786 -102.661974) (xy 283.193236 -102.661974)
		)
		(stroke
			(width 0)
			(type solid)
		)
		(fill yes)
		(layer "In11.Cu")
		(net "M_F_DQS_DN<6>")
	)
	(gr_poly
		(pts
			(xy 283.193236 -101.26345) (xy 283.148786 -101.26345) (xy 282.978606 -101.35235) (xy 282.978606 -101.57333)
			(xy 283.148786 -101.66223) (xy 283.193236 -101.66223)
		)
		(stroke
			(width 0)
			(type solid)
		)
		(fill yes)
		(layer "In11.Cu")
		(net "M_F_DQS_DN<6>")
	)
	(gr_poly
		(pts
			(xy 283.193236 -93.354144) (xy 283.148786 -93.354144) (xy 282.978606 -93.443044) (xy 282.978606 -93.664024)
			(xy 283.148786 -93.752924) (xy 283.193236 -93.752924)
		)
		(stroke
			(width 0)
			(type solid)
		)
		(fill yes)
		(layer "In11.Cu")
		(net "M_F_DQS_DP<16>")
	)
	(gr_poly
		(pts
			(xy 283.193236 -92.363544) (xy 283.148786 -92.363544) (xy 282.978606 -92.452444) (xy 282.978606 -92.673424)
			(xy 283.148786 -92.762324) (xy 283.193236 -92.762324)
		)
		(stroke
			(width 0)
			(type solid)
		)
		(fill yes)
		(layer "In11.Cu")
		(net "M_F_DQS_DP<16>")
	)
	(gr_poly
		(pts
			(xy 283.193236 -91.372944) (xy 283.148786 -91.372944) (xy 282.978606 -91.461844) (xy 282.978606 -91.682824)
			(xy 283.148786 -91.771724) (xy 283.193236 -91.771724)
		)
		(stroke
			(width 0)
			(type solid)
		)
		(fill yes)
		(layer "In11.Cu")
		(net "M_F_DQS_DP<16>")
	)
	(gr_poly
		(pts
			(xy 283.193236 -90.382344) (xy 283.148786 -90.382344) (xy 282.978606 -90.471244) (xy 282.978606 -90.692224)
			(xy 283.148786 -90.781124) (xy 283.193236 -90.781124)
		)
		(stroke
			(width 0)
			(type solid)
		)
		(fill yes)
		(layer "In11.Cu")
		(net "M_F_DQS_DP<16>")
	)
	(gr_poly
		(pts
			(xy 283.19349 -100.275644) (xy 283.14904 -100.275644) (xy 282.97886 -100.364544) (xy 282.97886 -100.585524)
			(xy 283.14904 -100.674424) (xy 283.19349 -100.674424)
		)
		(stroke
			(width 0)
			(type solid)
		)
		(fill yes)
		(layer "In11.Cu")
		(net "M_F_DQS_DN<6>")
	)
	(gr_poly
		(pts
			(xy 283.19349 -99.291394) (xy 283.14904 -99.291394) (xy 282.97886 -99.380294) (xy 282.97886 -99.601274)
			(xy 283.14904 -99.690174) (xy 283.19349 -99.690174)
		)
		(stroke
			(width 0)
			(type solid)
		)
		(fill yes)
		(layer "In11.Cu")
		(net "M_F_DQS_DN<6>")
	)
	(gr_poly
		(pts
			(xy 283.239464 -63.946024) (xy 283.248862 -63.725298) (xy 283.082492 -63.629286) (xy 283.038042 -63.627254)
			(xy 283.021278 -64.02578) (xy 283.065728 -64.027558)
		)
		(stroke
			(width 0)
			(type solid)
		)
		(fill yes)
		(layer "In11.Cu")
		(net "M_C_DQ<55>")
	)
	(gr_poly
		(pts
			(xy 283.249624 -106.357166) (xy 283.205174 -106.357166) (xy 283.012134 -106.446066) (xy 283.012134 -106.674666)
			(xy 283.205174 -106.763566) (xy 283.249624 -106.763566)
		)
		(stroke
			(width 0)
			(type solid)
		)
		(fill yes)
		(layer "In11.Cu")
		(net "M_F_DQS_DN<6>")
	)
	(gr_poly
		(pts
			(xy 283.286708 -54.05501) (xy 283.286708 -53.82641) (xy 283.093668 -53.73751) (xy 283.049218 -53.73751)
			(xy 283.049218 -54.14391) (xy 283.093668 -54.14391)
		)
		(stroke
			(width 0)
			(type solid)
		)
		(fill yes)
		(layer "In11.Cu")
		(net "M_C_DQ<55>")
	)
	(gr_poly
		(pts
			(xy 283.286708 -53.06441) (xy 283.286708 -52.83581) (xy 283.093668 -52.74691) (xy 283.049218 -52.74691)
			(xy 283.049218 -53.15331) (xy 283.093668 -53.15331)
		)
		(stroke
			(width 0)
			(type solid)
		)
		(fill yes)
		(layer "In11.Cu")
		(net "M_C_DQ<55>")
	)
	(gr_poly
		(pts
			(xy 283.286708 -52.07381) (xy 283.286708 -51.84521) (xy 283.093668 -51.75631) (xy 283.049218 -51.75631)
			(xy 283.049218 -52.16271) (xy 283.093668 -52.16271)
		)
		(stroke
			(width 0)
			(type solid)
		)
		(fill yes)
		(layer "In11.Cu")
		(net "M_C_DQ<55>")
	)
	(gr_poly
		(pts
			(xy 283.420058 -98.547174) (xy 283.428186 -98.355404) (xy 283.23667 -98.245168) (xy 283.074872 -98.348038)
			(xy 283.052266 -98.386392) (xy 283.39796 -98.585782)
		)
		(stroke
			(width 0)
			(type solid)
		)
		(fill yes)
		(layer "In11.Cu")
		(net "M_F_DQS_DP<6>")
	)
	(gr_poly
		(pts
			(xy 283.421582 -95.576644) (xy 283.42971 -95.384874) (xy 283.238448 -95.274384) (xy 283.076396 -95.377254)
			(xy 283.054044 -95.415862) (xy 283.399484 -95.614998)
		)
		(stroke
			(width 0)
			(type solid)
		)
		(fill yes)
		(layer "In11.Cu")
		(net "M_F_DQ<61>")
	)
	(gr_poly
		(pts
			(xy 283.423868 -94.587314) (xy 283.431996 -94.395544) (xy 283.240734 -94.285054) (xy 283.078682 -94.387924)
			(xy 283.05633 -94.426278) (xy 283.40177 -94.625922)
		)
		(stroke
			(width 0)
			(type solid)
		)
		(fill yes)
		(layer "In11.Cu")
		(net "M_F_DQ<57>")
	)
	(gr_poly
		(pts
			(xy 283.425392 -97.56013) (xy 283.43352 -97.36836) (xy 283.242258 -97.25787) (xy 283.080206 -97.36074)
			(xy 283.057854 -97.399094) (xy 283.403294 -97.598738)
		)
		(stroke
			(width 0)
			(type solid)
		)
		(fill yes)
		(layer "In11.Cu")
		(net "M_F_DQ<55>")
	)
	(gr_poly
		(pts
			(xy 283.425392 -96.56953) (xy 283.43352 -96.37776) (xy 283.242258 -96.26727) (xy 283.080206 -96.37014)
			(xy 283.057854 -96.408494) (xy 283.403294 -96.608138)
		)
		(stroke
			(width 0)
			(type solid)
		)
		(fill yes)
		(layer "In11.Cu")
		(net "M_F_DQ<51>")
	)
	(gr_poly
		(pts
			(xy 283.446982 -62.949328) (xy 283.446982 -62.728348) (xy 283.276802 -62.639448) (xy 283.232352 -62.639448)
			(xy 283.232352 -63.038228) (xy 283.276802 -63.038228)
		)
		(stroke
			(width 0)
			(type solid)
		)
		(fill yes)
		(layer "In11.Cu")
		(net "M_C_DQ<55>")
	)
	(gr_poly
		(pts
			(xy 283.446982 -61.958728) (xy 283.446982 -61.737748) (xy 283.276802 -61.648848) (xy 283.232352 -61.648848)
			(xy 283.232352 -62.047628) (xy 283.276802 -62.047628)
		)
		(stroke
			(width 0)
			(type solid)
		)
		(fill yes)
		(layer "In11.Cu")
		(net "M_C_DQ<55>")
	)
	(gr_poly
		(pts
			(xy 283.446982 -60.962032) (xy 283.446982 -60.741052) (xy 283.276802 -60.652152) (xy 283.232352 -60.652152)
			(xy 283.232352 -61.050932) (xy 283.276802 -61.050932)
		)
		(stroke
			(width 0)
			(type solid)
		)
		(fill yes)
		(layer "In11.Cu")
		(net "M_C_DQ<55>")
	)
	(gr_poly
		(pts
			(xy 283.446982 -59.971432) (xy 283.446982 -59.750452) (xy 283.276802 -59.661552) (xy 283.232352 -59.661552)
			(xy 283.232352 -60.060332) (xy 283.276802 -60.060332)
		)
		(stroke
			(width 0)
			(type solid)
		)
		(fill yes)
		(layer "In11.Cu")
		(net "M_C_DQ<55>")
	)
	(gr_poly
		(pts
			(xy 283.446982 -58.980832) (xy 283.446982 -58.759852) (xy 283.276802 -58.670952) (xy 283.232352 -58.670952)
			(xy 283.232352 -59.069732) (xy 283.276802 -59.069732)
		)
		(stroke
			(width 0)
			(type solid)
		)
		(fill yes)
		(layer "In11.Cu")
		(net "M_C_DQ<55>")
	)
	(gr_poly
		(pts
			(xy 283.446982 -57.990232) (xy 283.446982 -57.769252) (xy 283.276802 -57.680352) (xy 283.232352 -57.680352)
			(xy 283.232352 -58.079132) (xy 283.276802 -58.079132)
		)
		(stroke
			(width 0)
			(type solid)
		)
		(fill yes)
		(layer "In11.Cu")
		(net "M_C_DQ<55>")
	)
	(gr_poly
		(pts
			(xy 283.446982 -57.005474) (xy 283.446982 -56.784494) (xy 283.276802 -56.695594) (xy 283.232352 -56.695594)
			(xy 283.232352 -57.094374) (xy 283.276802 -57.094374)
		)
		(stroke
			(width 0)
			(type solid)
		)
		(fill yes)
		(layer "In11.Cu")
		(net "M_C_DQ<55>")
	)
	(gr_poly
		(pts
			(xy 283.446982 -56.014366) (xy 283.446982 -55.793386) (xy 283.276802 -55.704486) (xy 283.232352 -55.704486)
			(xy 283.232352 -56.103266) (xy 283.276802 -56.103266)
		)
		(stroke
			(width 0)
			(type solid)
		)
		(fill yes)
		(layer "In11.Cu")
		(net "M_C_DQ<55>")
	)
	(gr_poly
		(pts
			(xy 283.572458 -50.675286) (xy 283.572458 -50.446686) (xy 283.379418 -50.357786) (xy 283.334968 -50.357786)
			(xy 283.334968 -50.764186) (xy 283.379418 -50.764186)
		)
		(stroke
			(width 0)
			(type solid)
		)
		(fill yes)
		(layer "In11.Cu")
		(net "M_C_DQ<55>")
	)
	(gr_poly
		(pts
			(xy 283.572458 -49.684686) (xy 283.572458 -49.456086) (xy 283.379418 -49.367186) (xy 283.334968 -49.367186)
			(xy 283.334968 -49.773586) (xy 283.379418 -49.773586)
		)
		(stroke
			(width 0)
			(type solid)
		)
		(fill yes)
		(layer "In11.Cu")
		(net "M_C_DQ<55>")
	)
	(gr_poly
		(pts
			(xy 283.629862 -98.153982) (xy 283.652214 -98.115374) (xy 283.306774 -97.916238) (xy 283.284676 -97.954592)
			(xy 283.276548 -98.146362) (xy 283.46781 -98.256852)
		)
		(stroke
			(width 0)
			(type solid)
		)
		(fill yes)
		(layer "In11.Cu")
		(net "M_F_DQ<54>")
	)
	(gr_poly
		(pts
			(xy 283.629862 -97.163382) (xy 283.652214 -97.124774) (xy 283.306774 -96.925638) (xy 283.284676 -96.963992)
			(xy 283.276548 -97.155762) (xy 283.46781 -97.266252)
		)
		(stroke
			(width 0)
			(type solid)
		)
		(fill yes)
		(layer "In11.Cu")
		(net "M_F_DQ<50>")
	)
	(gr_poly
		(pts
			(xy 283.629862 -96.172782) (xy 283.652214 -96.134174) (xy 283.306774 -95.935038) (xy 283.284676 -95.973392)
			(xy 283.276548 -96.165162) (xy 283.46781 -96.275652)
		)
		(stroke
			(width 0)
			(type solid)
		)
		(fill yes)
		(layer "In11.Cu")
		(net "M_F_DQ<60>")
	)
	(gr_poly
		(pts
			(xy 283.631386 -95.183198) (xy 283.653738 -95.14459) (xy 283.308298 -94.945454) (xy 283.2862 -94.983808)
			(xy 283.278072 -95.175578) (xy 283.469334 -95.286068)
		)
		(stroke
			(width 0)
			(type solid)
		)
		(fill yes)
		(layer "In11.Cu")
		(net "M_F_DQ<56>")
	)
	(gr_poly
		(pts
			(xy 283.63926 -94.196916) (xy 283.661358 -94.158816) (xy 283.315918 -93.959172) (xy 283.29382 -93.99778)
			(xy 283.285946 -94.18955) (xy 283.477208 -94.30004)
		)
		(stroke
			(width 0)
			(type solid)
		)
		(fill yes)
		(layer "In11.Cu")
		(net "M_F_DQS_DP<16>")
	)
	(gr_poly
		(pts
			(xy 283.677614 -106.674666) (xy 283.677614 -106.446066) (xy 283.484574 -106.357166) (xy 283.440124 -106.357166)
			(xy 283.440124 -106.763566) (xy 283.484574 -106.763566)
		)
		(stroke
			(width 0)
			(type solid)
		)
		(fill yes)
		(layer "In11.Cu")
		(net "M_F_DQS_DP<6>")
	)
	(gr_poly
		(pts
			(xy 283.682694 -48.451516) (xy 283.651198 -48.420274) (xy 283.451808 -48.346614) (xy 283.29001 -48.508158)
			(xy 283.36367 -48.707548) (xy 283.395166 -48.739044)
		)
		(stroke
			(width 0)
			(type solid)
		)
		(fill yes)
		(layer "In11.Cu")
		(net "M_C_DQ<54>")
	)
	(gr_poly
		(pts
			(xy 283.731462 -106.034078) (xy 283.731462 -105.813098) (xy 283.561282 -105.724198) (xy 283.516832 -105.724198)
			(xy 283.516832 -106.122978) (xy 283.561282 -106.122978)
		)
		(stroke
			(width 0)
			(type solid)
		)
		(fill yes)
		(layer "In11.Cu")
		(net "M_F_DQS_DP<6>")
	)
	(gr_poly
		(pts
			(xy 283.731462 -105.043478) (xy 283.731462 -104.822498) (xy 283.561282 -104.733598) (xy 283.516832 -104.733598)
			(xy 283.516832 -105.132378) (xy 283.561282 -105.132378)
		)
		(stroke
			(width 0)
			(type solid)
		)
		(fill yes)
		(layer "In11.Cu")
		(net "M_F_DQS_DP<6>")
	)
	(gr_poly
		(pts
			(xy 283.731462 -104.052878) (xy 283.731462 -103.831898) (xy 283.561282 -103.742998) (xy 283.516832 -103.742998)
			(xy 283.516832 -104.141778) (xy 283.561282 -104.141778)
		)
		(stroke
			(width 0)
			(type solid)
		)
		(fill yes)
		(layer "In11.Cu")
		(net "M_F_DQS_DP<6>")
	)
	(gr_poly
		(pts
			(xy 283.731462 -103.062278) (xy 283.731462 -102.841298) (xy 283.561282 -102.752398) (xy 283.516832 -102.752398)
			(xy 283.516832 -103.151178) (xy 283.561282 -103.151178)
		)
		(stroke
			(width 0)
			(type solid)
		)
		(fill yes)
		(layer "In11.Cu")
		(net "M_F_DQS_DP<6>")
	)
	(gr_poly
		(pts
			(xy 283.731462 -102.08387) (xy 283.731462 -101.86289) (xy 283.561282 -101.77399) (xy 283.516832 -101.77399)
			(xy 283.516832 -102.17277) (xy 283.561282 -102.17277)
		)
		(stroke
			(width 0)
			(type solid)
		)
		(fill yes)
		(layer "In11.Cu")
		(net "M_F_DQS_DP<6>")
	)
	(gr_poly
		(pts
			(xy 283.731462 -101.093016) (xy 283.731462 -100.872036) (xy 283.561282 -100.783136) (xy 283.516832 -100.783136)
			(xy 283.516832 -101.181916) (xy 283.561282 -101.181916)
		)
		(stroke
			(width 0)
			(type solid)
		)
		(fill yes)
		(layer "In11.Cu")
		(net "M_F_DQS_DP<6>")
	)
	(gr_poly
		(pts
			(xy 283.731462 -100.10267) (xy 283.731462 -99.88169) (xy 283.561282 -99.79279) (xy 283.516832 -99.79279)
			(xy 283.516832 -100.19157) (xy 283.561282 -100.19157)
		)
		(stroke
			(width 0)
			(type solid)
		)
		(fill yes)
		(layer "In11.Cu")
		(net "M_F_DQS_DP<6>")
	)
	(gr_poly
		(pts
			(xy 283.731462 -99.11207) (xy 283.731462 -98.89109) (xy 283.561282 -98.80219) (xy 283.516832 -98.80219)
			(xy 283.516832 -99.20097) (xy 283.561282 -99.20097)
		)
		(stroke
			(width 0)
			(type solid)
		)
		(fill yes)
		(layer "In11.Cu")
		(net "M_F_DQS_DP<6>")
	)
	(gr_poly
		(pts
			(xy 283.731462 -93.156278) (xy 283.731462 -92.935298) (xy 283.561282 -92.846398) (xy 283.516832 -92.846398)
			(xy 283.516832 -93.245178) (xy 283.561282 -93.245178)
		)
		(stroke
			(width 0)
			(type solid)
		)
		(fill yes)
		(layer "In11.Cu")
		(net "M_F_DQS_DN<16>")
	)
	(gr_poly
		(pts
			(xy 283.731462 -92.165678) (xy 283.731462 -91.944698) (xy 283.561282 -91.855798) (xy 283.516832 -91.855798)
			(xy 283.516832 -92.254578) (xy 283.561282 -92.254578)
		)
		(stroke
			(width 0)
			(type solid)
		)
		(fill yes)
		(layer "In11.Cu")
		(net "M_F_DQS_DN<16>")
	)
	(gr_poly
		(pts
			(xy 283.731462 -91.175078) (xy 283.731462 -90.954098) (xy 283.561282 -90.865198) (xy 283.516832 -90.865198)
			(xy 283.516832 -91.263978) (xy 283.561282 -91.263978)
		)
		(stroke
			(width 0)
			(type solid)
		)
		(fill yes)
		(layer "In11.Cu")
		(net "M_F_DQS_DN<16>")
	)
	(gr_poly
		(pts
			(xy 283.767276 -62.645544) (xy 283.722826 -62.645544) (xy 283.552646 -62.734444) (xy 283.552646 -62.955424)
			(xy 283.722826 -63.044324) (xy 283.767276 -63.044324)
		)
		(stroke
			(width 0)
			(type solid)
		)
		(fill yes)
		(layer "In11.Cu")
		(net "M_C_DQ<50>")
	)
	(gr_poly
		(pts
			(xy 283.767276 -61.654944) (xy 283.722826 -61.654944) (xy 283.552646 -61.743844) (xy 283.552646 -61.964824)
			(xy 283.722826 -62.053724) (xy 283.767276 -62.053724)
		)
		(stroke
			(width 0)
			(type solid)
		)
		(fill yes)
		(layer "In11.Cu")
		(net "M_C_DQ<50>")
	)
	(gr_poly
		(pts
			(xy 283.767276 -60.664344) (xy 283.722826 -60.664344) (xy 283.552646 -60.753244) (xy 283.552646 -60.974224)
			(xy 283.722826 -61.063124) (xy 283.767276 -61.063124)
		)
		(stroke
			(width 0)
			(type solid)
		)
		(fill yes)
		(layer "In11.Cu")
		(net "M_C_DQ<50>")
	)
	(gr_poly
		(pts
			(xy 283.767276 -59.667394) (xy 283.722826 -59.667394) (xy 283.552646 -59.756294) (xy 283.552646 -59.977274)
			(xy 283.722826 -60.066174) (xy 283.767276 -60.066174)
		)
		(stroke
			(width 0)
			(type solid)
		)
		(fill yes)
		(layer "In11.Cu")
		(net "M_C_DQ<50>")
	)
	(gr_poly
		(pts
			(xy 283.767276 -58.670698) (xy 283.722826 -58.670698) (xy 283.552646 -58.759598) (xy 283.552646 -58.980578)
			(xy 283.722826 -59.069478) (xy 283.767276 -59.069478)
		)
		(stroke
			(width 0)
			(type solid)
		)
		(fill yes)
		(layer "In11.Cu")
		(net "M_C_DQ<50>")
	)
	(gr_poly
		(pts
			(xy 283.767276 -57.692544) (xy 283.722826 -57.692544) (xy 283.552646 -57.781444) (xy 283.552646 -58.002424)
			(xy 283.722826 -58.091324) (xy 283.767276 -58.091324)
		)
		(stroke
			(width 0)
			(type solid)
		)
		(fill yes)
		(layer "In11.Cu")
		(net "M_C_DQ<50>")
	)
	(gr_poly
		(pts
			(xy 283.767276 -56.701944) (xy 283.722826 -56.701944) (xy 283.552646 -56.790844) (xy 283.552646 -57.011824)
			(xy 283.722826 -57.100724) (xy 283.767276 -57.100724)
		)
		(stroke
			(width 0)
			(type solid)
		)
		(fill yes)
		(layer "In11.Cu")
		(net "M_C_DQ<50>")
	)
	(gr_poly
		(pts
			(xy 283.767276 -55.711344) (xy 283.722826 -55.711344) (xy 283.552646 -55.800244) (xy 283.552646 -56.021224)
			(xy 283.722826 -56.110124) (xy 283.767276 -56.110124)
		)
		(stroke
			(width 0)
			(type solid)
		)
		(fill yes)
		(layer "In11.Cu")
		(net "M_C_DQ<50>")
	)
	(gr_poly
		(pts
			(xy 283.767784 -54.209696) (xy 283.723334 -54.209696) (xy 283.530294 -54.298596) (xy 283.530294 -54.527196)
			(xy 283.723334 -54.616096) (xy 283.767784 -54.616096)
		)
		(stroke
			(width 0)
			(type solid)
		)
		(fill yes)
		(layer "In11.Cu")
		(net "M_C_DQ<50>")
	)
	(gr_poly
		(pts
			(xy 283.767784 -53.219096) (xy 283.723334 -53.219096) (xy 283.530294 -53.307996) (xy 283.530294 -53.536596)
			(xy 283.723334 -53.625496) (xy 283.767784 -53.625496)
		)
		(stroke
			(width 0)
			(type solid)
		)
		(fill yes)
		(layer "In11.Cu")
		(net "M_C_DQ<50>")
	)
	(gr_poly
		(pts
			(xy 283.910532 -48.82896) (xy 283.836872 -48.62957) (xy 283.80563 -48.598074) (xy 283.518102 -48.885602)
			(xy 283.549598 -48.917098) (xy 283.748988 -48.990504)
		)
		(stroke
			(width 0)
			(type solid)
		)
		(fill yes)
		(layer "In11.Cu")
		(net "M_C_DQ<55>")
	)
	(gr_poly
		(pts
			(xy 283.913072 -51.773582) (xy 283.868622 -51.773582) (xy 283.675582 -51.862482) (xy 283.675582 -52.091082)
			(xy 283.868622 -52.179982) (xy 283.913072 -52.179982)
		)
		(stroke
			(width 0)
			(type solid)
		)
		(fill yes)
		(layer "In11.Cu")
		(net "M_C_DQ<50>")
	)
	(gr_poly
		(pts
			(xy 283.913072 -50.859182) (xy 283.868622 -50.859182) (xy 283.675582 -50.948082) (xy 283.675582 -51.176682)
			(xy 283.868622 -51.265582) (xy 283.913072 -51.265582)
		)
		(stroke
			(width 0)
			(type solid)
		)
		(fill yes)
		(layer "In11.Cu")
		(net "M_C_DQ<50>")
	)
	(gr_poly
		(pts
			(xy 283.913072 -49.868582) (xy 283.868622 -49.868582) (xy 283.675582 -49.957482) (xy 283.675582 -50.186082)
			(xy 283.868622 -50.274982) (xy 283.913072 -50.274982)
		)
		(stroke
			(width 0)
			(type solid)
		)
		(fill yes)
		(layer "In11.Cu")
		(net "M_C_DQ<50>")
	)
	(gr_poly
		(pts
			(xy 284.051756 -105.724198) (xy 284.007306 -105.724198) (xy 283.837126 -105.813098) (xy 283.837126 -106.034078)
			(xy 284.007306 -106.122978) (xy 284.051756 -106.122978)
		)
		(stroke
			(width 0)
			(type solid)
		)
		(fill yes)
		(layer "In11.Cu")
		(net "M_F_DQ<54>")
	)
	(gr_poly
		(pts
			(xy 284.051756 -104.733598) (xy 284.007306 -104.733598) (xy 283.837126 -104.822498) (xy 283.837126 -105.043478)
			(xy 284.007306 -105.132378) (xy 284.051756 -105.132378)
		)
		(stroke
			(width 0)
			(type solid)
		)
		(fill yes)
		(layer "In11.Cu")
		(net "M_F_DQ<54>")
	)
	(gr_poly
		(pts
			(xy 284.051756 -103.742998) (xy 284.007306 -103.742998) (xy 283.837126 -103.831898) (xy 283.837126 -104.052878)
			(xy 284.007306 -104.141778) (xy 284.051756 -104.141778)
		)
		(stroke
			(width 0)
			(type solid)
		)
		(fill yes)
		(layer "In11.Cu")
		(net "M_F_DQ<54>")
	)
	(gr_poly
		(pts
			(xy 284.051756 -102.752398) (xy 284.007306 -102.752398) (xy 283.837126 -102.841298) (xy 283.837126 -103.062278)
			(xy 284.007306 -103.151178) (xy 284.051756 -103.151178)
		)
		(stroke
			(width 0)
			(type solid)
		)
		(fill yes)
		(layer "In11.Cu")
		(net "M_F_DQ<54>")
	)
	(gr_poly
		(pts
			(xy 284.051756 -101.761798) (xy 284.007306 -101.761798) (xy 283.837126 -101.850698) (xy 283.837126 -102.071678)
			(xy 284.007306 -102.160578) (xy 284.051756 -102.160578)
		)
		(stroke
			(width 0)
			(type solid)
		)
		(fill yes)
		(layer "In11.Cu")
		(net "M_F_DQ<54>")
	)
	(gr_poly
		(pts
			(xy 284.051756 -100.771198) (xy 284.007306 -100.771198) (xy 283.837126 -100.860098) (xy 283.837126 -101.081078)
			(xy 284.007306 -101.169978) (xy 284.051756 -101.169978)
		)
		(stroke
			(width 0)
			(type solid)
		)
		(fill yes)
		(layer "In11.Cu")
		(net "M_F_DQ<54>")
	)
	(gr_poly
		(pts
			(xy 284.051756 -99.780598) (xy 284.007306 -99.780598) (xy 283.837126 -99.869498) (xy 283.837126 -100.090478)
			(xy 284.007306 -100.179378) (xy 284.051756 -100.179378)
		)
		(stroke
			(width 0)
			(type solid)
		)
		(fill yes)
		(layer "In11.Cu")
		(net "M_F_DQ<54>")
	)
	(gr_poly
		(pts
			(xy 284.051756 -98.789998) (xy 284.007306 -98.789998) (xy 283.837126 -98.878898) (xy 283.837126 -99.099878)
			(xy 284.007306 -99.188778) (xy 284.051756 -99.188778)
		)
		(stroke
			(width 0)
			(type solid)
		)
		(fill yes)
		(layer "In11.Cu")
		(net "M_F_DQ<54>")
	)
	(gr_poly
		(pts
			(xy 284.195774 -54.527196) (xy 284.195774 -54.298596) (xy 284.002734 -54.209696) (xy 283.958284 -54.209696)
			(xy 283.958284 -54.616096) (xy 284.002734 -54.616096)
		)
		(stroke
			(width 0)
			(type solid)
		)
		(fill yes)
		(layer "In11.Cu")
		(net "M_C_DQ<51>")
	)
	(gr_poly
		(pts
			(xy 284.195774 -53.536596) (xy 284.195774 -53.307996) (xy 284.002734 -53.219096) (xy 283.958284 -53.219096)
			(xy 283.958284 -53.625496) (xy 284.002734 -53.625496)
		)
		(stroke
			(width 0)
			(type solid)
		)
		(fill yes)
		(layer "In11.Cu")
		(net "M_C_DQ<51>")
	)
	(gr_poly
		(pts
			(xy 284.24251 -90.866468) (xy 284.19806 -90.866468) (xy 284.02788 -90.955368) (xy 284.02788 -91.176348)
			(xy 284.19806 -91.265248) (xy 284.24251 -91.265248)
		)
		(stroke
			(width 0)
			(type solid)
		)
		(fill yes)
		(layer "In11.Cu")
		(net "M_F_DQ<62>")
	)
	(gr_poly
		(pts
			(xy 284.280102 -94.090744) (xy 284.28823 -93.898974) (xy 284.096968 -93.788484) (xy 283.934916 -93.891354)
			(xy 283.912564 -93.929962) (xy 284.258004 -94.129098)
		)
		(stroke
			(width 0)
			(type solid)
		)
		(fill yes)
		(layer "In11.Cu")
		(net "M_F_DQS_DN<16>")
	)
	(gr_poly
		(pts
			(xy 284.282134 -98.053906) (xy 284.290262 -97.862136) (xy 284.099 -97.7519) (xy 283.936948 -97.85477)
			(xy 283.914596 -97.893124) (xy 284.26029 -98.092514)
		)
		(stroke
			(width 0)
			(type solid)
		)
		(fill yes)
		(layer "In11.Cu")
		(net "M_F_DQ<55>")
	)
	(gr_poly
		(pts
			(xy 284.282388 -97.063814) (xy 284.290516 -96.872044) (xy 284.099254 -96.761554) (xy 283.937202 -96.864424)
			(xy 283.91485 -96.902778) (xy 284.26029 -97.102422)
		)
		(stroke
			(width 0)
			(type solid)
		)
		(fill yes)
		(layer "In11.Cu")
		(net "M_F_DQ<51>")
	)
	(gr_poly
		(pts
			(xy 284.282388 -96.073214) (xy 284.290516 -95.881444) (xy 284.099254 -95.770954) (xy 283.937202 -95.873824)
			(xy 283.91485 -95.912178) (xy 284.26029 -96.111822)
		)
		(stroke
			(width 0)
			(type solid)
		)
		(fill yes)
		(layer "In11.Cu")
		(net "M_F_DQ<61>")
	)
	(gr_poly
		(pts
			(xy 284.283912 -95.083376) (xy 284.29204 -94.891606) (xy 284.100778 -94.781116) (xy 283.938726 -94.883986)
			(xy 283.916374 -94.922594) (xy 284.261814 -95.12173)
		)
		(stroke
			(width 0)
			(type solid)
		)
		(fill yes)
		(layer "In11.Cu")
		(net "M_F_DQ<57>")
	)
	(gr_poly
		(pts
			(xy 284.305502 -63.438278) (xy 284.305502 -63.217298) (xy 284.135322 -63.128398) (xy 284.090872 -63.128398)
			(xy 284.090872 -63.527178) (xy 284.135322 -63.527178)
		)
		(stroke
			(width 0)
			(type solid)
		)
		(fill yes)
		(layer "In11.Cu")
		(net "M_C_DQ<51>")
	)
	(gr_poly
		(pts
			(xy 284.305502 -62.447678) (xy 284.305502 -62.226698) (xy 284.135322 -62.137798) (xy 284.090872 -62.137798)
			(xy 284.090872 -62.536578) (xy 284.135322 -62.536578)
		)
		(stroke
			(width 0)
			(type solid)
		)
		(fill yes)
		(layer "In11.Cu")
		(net "M_C_DQ<51>")
	)
	(gr_poly
		(pts
			(xy 284.305502 -61.457078) (xy 284.305502 -61.236098) (xy 284.135322 -61.147198) (xy 284.090872 -61.147198)
			(xy 284.090872 -61.545978) (xy 284.135322 -61.545978)
		)
		(stroke
			(width 0)
			(type solid)
		)
		(fill yes)
		(layer "In11.Cu")
		(net "M_C_DQ<51>")
	)
	(gr_poly
		(pts
			(xy 284.305502 -60.466478) (xy 284.305502 -60.245498) (xy 284.135322 -60.156598) (xy 284.090872 -60.156598)
			(xy 284.090872 -60.555378) (xy 284.135322 -60.555378)
		)
		(stroke
			(width 0)
			(type solid)
		)
		(fill yes)
		(layer "In11.Cu")
		(net "M_C_DQ<51>")
	)
	(gr_poly
		(pts
			(xy 284.305502 -59.488324) (xy 284.305502 -59.267344) (xy 284.135322 -59.178444) (xy 284.090872 -59.178444)
			(xy 284.090872 -59.577224) (xy 284.135322 -59.577224)
		)
		(stroke
			(width 0)
			(type solid)
		)
		(fill yes)
		(layer "In11.Cu")
		(net "M_C_DQ<51>")
	)
	(gr_poly
		(pts
			(xy 284.305502 -58.491628) (xy 284.305502 -58.270648) (xy 284.135322 -58.181748) (xy 284.090872 -58.181748)
			(xy 284.090872 -58.580528) (xy 284.135322 -58.580528)
		)
		(stroke
			(width 0)
			(type solid)
		)
		(fill yes)
		(layer "In11.Cu")
		(net "M_C_DQ<51>")
	)
	(gr_poly
		(pts
			(xy 284.305502 -57.494678) (xy 284.305502 -57.273698) (xy 284.135322 -57.184798) (xy 284.090872 -57.184798)
			(xy 284.090872 -57.583578) (xy 284.135322 -57.583578)
		)
		(stroke
			(width 0)
			(type solid)
		)
		(fill yes)
		(layer "In11.Cu")
		(net "M_C_DQ<51>")
	)
	(gr_poly
		(pts
			(xy 284.305502 -56.504078) (xy 284.305502 -56.283098) (xy 284.135322 -56.194198) (xy 284.090872 -56.194198)
			(xy 284.090872 -56.592978) (xy 284.135322 -56.592978)
		)
		(stroke
			(width 0)
			(type solid)
		)
		(fill yes)
		(layer "In11.Cu")
		(net "M_C_DQ<51>")
	)
	(gr_poly
		(pts
			(xy 284.305502 -55.513478) (xy 284.305502 -55.292498) (xy 284.135322 -55.203598) (xy 284.090872 -55.203598)
			(xy 284.090872 -55.602378) (xy 284.135322 -55.602378)
		)
		(stroke
			(width 0)
			(type solid)
		)
		(fill yes)
		(layer "In11.Cu")
		(net "M_C_DQ<51>")
	)
	(gr_poly
		(pts
			(xy 284.341062 -52.167282) (xy 284.341062 -51.938682) (xy 284.148022 -51.849782) (xy 284.103572 -51.849782)
			(xy 284.103572 -52.256182) (xy 284.148022 -52.256182)
		)
		(stroke
			(width 0)
			(type solid)
		)
		(fill yes)
		(layer "In11.Cu")
		(net "M_C_DQ<51>")
	)
	(gr_poly
		(pts
			(xy 284.341062 -51.176682) (xy 284.341062 -50.948082) (xy 284.148022 -50.859182) (xy 284.103572 -50.859182)
			(xy 284.103572 -51.265582) (xy 284.148022 -51.265582)
		)
		(stroke
			(width 0)
			(type solid)
		)
		(fill yes)
		(layer "In11.Cu")
		(net "M_C_DQ<51>")
	)
	(gr_poly
		(pts
			(xy 284.341062 -50.186082) (xy 284.341062 -49.957482) (xy 284.148022 -49.868582) (xy 284.103572 -49.868582)
			(xy 284.103572 -50.274982) (xy 284.148022 -50.274982)
		)
		(stroke
			(width 0)
			(type solid)
		)
		(fill yes)
		(layer "In11.Cu")
		(net "M_C_DQ<51>")
	)
	(gr_poly
		(pts
			(xy 284.488382 -94.687136) (xy 284.510734 -94.648782) (xy 284.165294 -94.449138) (xy 284.143196 -94.487746)
			(xy 284.135068 -94.679516) (xy 284.32633 -94.790006)
		)
		(stroke
			(width 0)
			(type solid)
		)
		(fill yes)
		(layer "In11.Cu")
		(net "M_F_DQS_DP<16>")
	)
	(gr_poly
		(pts
			(xy 284.489906 -97.659698) (xy 284.512258 -97.62109) (xy 284.166818 -97.421954) (xy 284.14472 -97.460308)
			(xy 284.136592 -97.652078) (xy 284.327854 -97.762568)
		)
		(stroke
			(width 0)
			(type solid)
		)
		(fill yes)
		(layer "In11.Cu")
		(net "M_F_DQ<50>")
	)
	(gr_poly
		(pts
			(xy 284.489906 -96.669098) (xy 284.512258 -96.63049) (xy 284.166818 -96.431354) (xy 284.14472 -96.469708)
			(xy 284.136592 -96.661478) (xy 284.327854 -96.771968)
		)
		(stroke
			(width 0)
			(type solid)
		)
		(fill yes)
		(layer "In11.Cu")
		(net "M_F_DQ<60>")
	)
	(gr_poly
		(pts
			(xy 284.492192 -95.679768) (xy 284.514544 -95.641414) (xy 284.169104 -95.44177) (xy 284.147006 -95.480378)
			(xy 284.138878 -95.672148) (xy 284.33014 -95.782638)
		)
		(stroke
			(width 0)
			(type solid)
		)
		(fill yes)
		(layer "In11.Cu")
		(net "M_F_DQ<56>")
	)
	(gr_poly
		(pts
			(xy 284.492192 -93.698568) (xy 284.514544 -93.660214) (xy 284.169104 -93.46057) (xy 284.147006 -93.499178)
			(xy 284.138878 -93.690948) (xy 284.33014 -93.801438)
		)
		(stroke
			(width 0)
			(type solid)
		)
		(fill yes)
		(layer "In11.Cu")
		(net "M_F_DQS_DN<7>")
	)
	(gr_poly
		(pts
			(xy 284.589982 -105.551224) (xy 284.589982 -105.330244) (xy 284.419802 -105.241344) (xy 284.375352 -105.241344)
			(xy 284.375352 -105.640124) (xy 284.419802 -105.640124)
		)
		(stroke
			(width 0)
			(type solid)
		)
		(fill yes)
		(layer "In11.Cu")
		(net "M_F_DQ<55>")
	)
	(gr_poly
		(pts
			(xy 284.589982 -104.560624) (xy 284.589982 -104.339644) (xy 284.419802 -104.250744) (xy 284.375352 -104.250744)
			(xy 284.375352 -104.649524) (xy 284.419802 -104.649524)
		)
		(stroke
			(width 0)
			(type solid)
		)
		(fill yes)
		(layer "In11.Cu")
		(net "M_F_DQ<55>")
	)
	(gr_poly
		(pts
			(xy 284.589982 -103.570024) (xy 284.589982 -103.349044) (xy 284.419802 -103.260144) (xy 284.375352 -103.260144)
			(xy 284.375352 -103.658924) (xy 284.419802 -103.658924)
		)
		(stroke
			(width 0)
			(type solid)
		)
		(fill yes)
		(layer "In11.Cu")
		(net "M_F_DQ<55>")
	)
	(gr_poly
		(pts
			(xy 284.589982 -102.579424) (xy 284.589982 -102.358444) (xy 284.419802 -102.269544) (xy 284.375352 -102.269544)
			(xy 284.375352 -102.668324) (xy 284.419802 -102.668324)
		)
		(stroke
			(width 0)
			(type solid)
		)
		(fill yes)
		(layer "In11.Cu")
		(net "M_F_DQ<55>")
	)
	(gr_poly
		(pts
			(xy 284.589982 -101.588824) (xy 284.589982 -101.367844) (xy 284.419802 -101.278944) (xy 284.375352 -101.278944)
			(xy 284.375352 -101.677724) (xy 284.419802 -101.677724)
		)
		(stroke
			(width 0)
			(type solid)
		)
		(fill yes)
		(layer "In11.Cu")
		(net "M_F_DQ<55>")
	)
	(gr_poly
		(pts
			(xy 284.589982 -100.598224) (xy 284.589982 -100.377244) (xy 284.419802 -100.288344) (xy 284.375352 -100.288344)
			(xy 284.375352 -100.687124) (xy 284.419802 -100.687124)
		)
		(stroke
			(width 0)
			(type solid)
		)
		(fill yes)
		(layer "In11.Cu")
		(net "M_F_DQ<55>")
	)
	(gr_poly
		(pts
			(xy 284.589982 -99.607624) (xy 284.589982 -99.386644) (xy 284.419802 -99.297744) (xy 284.375352 -99.297744)
			(xy 284.375352 -99.696524) (xy 284.419802 -99.696524)
		)
		(stroke
			(width 0)
			(type solid)
		)
		(fill yes)
		(layer "In11.Cu")
		(net "M_F_DQ<55>")
	)
	(gr_poly
		(pts
			(xy 284.589982 -98.617024) (xy 284.589982 -98.396044) (xy 284.419802 -98.307144) (xy 284.375352 -98.307144)
			(xy 284.375352 -98.705924) (xy 284.419802 -98.705924)
		)
		(stroke
			(width 0)
			(type solid)
		)
		(fill yes)
		(layer "In11.Cu")
		(net "M_F_DQ<55>")
	)
	(gr_poly
		(pts
			(xy 284.589982 -91.682824) (xy 284.589982 -91.461844) (xy 284.419802 -91.372944) (xy 284.375352 -91.372944)
			(xy 284.375352 -91.771724) (xy 284.419802 -91.771724)
		)
		(stroke
			(width 0)
			(type solid)
		)
		(fill yes)
		(layer "In11.Cu")
		(net "M_F_DQ<62>")
	)
	(gr_poly
		(pts
			(xy 284.625542 -62.144148) (xy 284.581092 -62.144148) (xy 284.410912 -62.233048) (xy 284.410912 -62.454028)
			(xy 284.581092 -62.542928) (xy 284.625542 -62.542928)
		)
		(stroke
			(width 0)
			(type solid)
		)
		(fill yes)
		(layer "In11.Cu")
		(net "M_C_DQ<60>")
	)
	(gr_poly
		(pts
			(xy 284.625542 -61.153548) (xy 284.581092 -61.153548) (xy 284.410912 -61.242448) (xy 284.410912 -61.463428)
			(xy 284.581092 -61.552328) (xy 284.625542 -61.552328)
		)
		(stroke
			(width 0)
			(type solid)
		)
		(fill yes)
		(layer "In11.Cu")
		(net "M_C_DQ<60>")
	)
	(gr_poly
		(pts
			(xy 284.625542 -60.153804) (xy 284.581092 -60.153804) (xy 284.410912 -60.242704) (xy 284.410912 -60.463684)
			(xy 284.581092 -60.552584) (xy 284.625542 -60.552584)
		)
		(stroke
			(width 0)
			(type solid)
		)
		(fill yes)
		(layer "In11.Cu")
		(net "M_C_DQ<60>")
	)
	(gr_poly
		(pts
			(xy 284.625542 -59.178444) (xy 284.581092 -59.178444) (xy 284.410912 -59.267344) (xy 284.410912 -59.488324)
			(xy 284.581092 -59.577224) (xy 284.625542 -59.577224)
		)
		(stroke
			(width 0)
			(type solid)
		)
		(fill yes)
		(layer "In11.Cu")
		(net "M_C_DQ<60>")
	)
	(gr_poly
		(pts
			(xy 284.625542 -58.175398) (xy 284.581092 -58.175398) (xy 284.410912 -58.264298) (xy 284.410912 -58.485278)
			(xy 284.581092 -58.574178) (xy 284.625542 -58.574178)
		)
		(stroke
			(width 0)
			(type solid)
		)
		(fill yes)
		(layer "In11.Cu")
		(net "M_C_DQ<60>")
	)
	(gr_poly
		(pts
			(xy 284.625542 -57.182004) (xy 284.581092 -57.182004) (xy 284.410912 -57.270904) (xy 284.410912 -57.491884)
			(xy 284.581092 -57.580784) (xy 284.625542 -57.580784)
		)
		(stroke
			(width 0)
			(type solid)
		)
		(fill yes)
		(layer "In11.Cu")
		(net "M_C_DQ<60>")
	)
	(gr_poly
		(pts
			(xy 284.625542 -56.191404) (xy 284.581092 -56.191404) (xy 284.410912 -56.280304) (xy 284.410912 -56.501284)
			(xy 284.581092 -56.590184) (xy 284.625542 -56.590184)
		)
		(stroke
			(width 0)
			(type solid)
		)
		(fill yes)
		(layer "In11.Cu")
		(net "M_C_DQ<60>")
	)
	(gr_poly
		(pts
			(xy 284.625542 -55.200804) (xy 284.581092 -55.200804) (xy 284.410912 -55.289704) (xy 284.410912 -55.510684)
			(xy 284.581092 -55.599584) (xy 284.625542 -55.599584)
		)
		(stroke
			(width 0)
			(type solid)
		)
		(fill yes)
		(layer "In11.Cu")
		(net "M_C_DQ<60>")
	)
	(gr_poly
		(pts
			(xy 284.625542 -54.208426) (xy 284.581092 -54.208426) (xy 284.410912 -54.297326) (xy 284.410912 -54.518306)
			(xy 284.581092 -54.607206) (xy 284.625542 -54.607206)
		)
		(stroke
			(width 0)
			(type solid)
		)
		(fill yes)
		(layer "In11.Cu")
		(net "M_C_DQ<60>")
	)
	(gr_poly
		(pts
			(xy 284.712156 -48.50765) (xy 284.68066 -48.476408) (xy 284.48127 -48.402748) (xy 284.319726 -48.564292)
			(xy 284.393386 -48.763682) (xy 284.424628 -48.795178)
		)
		(stroke
			(width 0)
			(type solid)
		)
		(fill yes)
		(layer "In11.Cu")
		(net "M_C_DQ<50>")
	)
	(gr_poly
		(pts
			(xy 284.758384 -53.274722) (xy 284.713934 -53.274722) (xy 284.543754 -53.363622) (xy 284.543754 -53.584602)
			(xy 284.713934 -53.673502) (xy 284.758384 -53.673502)
		)
		(stroke
			(width 0)
			(type solid)
		)
		(fill yes)
		(layer "In11.Cu")
		(net "M_C_DQ<60>")
	)
	(gr_poly
		(pts
			(xy 284.809692 -51.556158) (xy 284.765242 -51.556158) (xy 284.572202 -51.645058) (xy 284.572202 -51.873658)
			(xy 284.765242 -51.962558) (xy 284.809692 -51.962558)
		)
		(stroke
			(width 0)
			(type solid)
		)
		(fill yes)
		(layer "In11.Cu")
		(net "M_C_DQ<60>")
	)
	(gr_poly
		(pts
			(xy 284.910276 -105.241344) (xy 284.865826 -105.241344) (xy 284.695646 -105.330244) (xy 284.695646 -105.551224)
			(xy 284.865826 -105.640124) (xy 284.910276 -105.640124)
		)
		(stroke
			(width 0)
			(type solid)
		)
		(fill yes)
		(layer "In11.Cu")
		(net "M_F_DQ<50>")
	)
	(gr_poly
		(pts
			(xy 284.910276 -104.250744) (xy 284.865826 -104.250744) (xy 284.695646 -104.339644) (xy 284.695646 -104.560624)
			(xy 284.865826 -104.649524) (xy 284.910276 -104.649524)
		)
		(stroke
			(width 0)
			(type solid)
		)
		(fill yes)
		(layer "In11.Cu")
		(net "M_F_DQ<50>")
	)
	(gr_poly
		(pts
			(xy 284.910276 -103.260144) (xy 284.865826 -103.260144) (xy 284.695646 -103.349044) (xy 284.695646 -103.570024)
			(xy 284.865826 -103.658924) (xy 284.910276 -103.658924)
		)
		(stroke
			(width 0)
			(type solid)
		)
		(fill yes)
		(layer "In11.Cu")
		(net "M_F_DQ<50>")
	)
	(gr_poly
		(pts
			(xy 284.910276 -102.269544) (xy 284.865826 -102.269544) (xy 284.695646 -102.358444) (xy 284.695646 -102.579424)
			(xy 284.865826 -102.668324) (xy 284.910276 -102.668324)
		)
		(stroke
			(width 0)
			(type solid)
		)
		(fill yes)
		(layer "In11.Cu")
		(net "M_F_DQ<50>")
	)
	(gr_poly
		(pts
			(xy 284.910276 -101.278944) (xy 284.865826 -101.278944) (xy 284.695646 -101.367844) (xy 284.695646 -101.588824)
			(xy 284.865826 -101.677724) (xy 284.910276 -101.677724)
		)
		(stroke
			(width 0)
			(type solid)
		)
		(fill yes)
		(layer "In11.Cu")
		(net "M_F_DQ<50>")
	)
	(gr_poly
		(pts
			(xy 284.910276 -100.288344) (xy 284.865826 -100.288344) (xy 284.695646 -100.377244) (xy 284.695646 -100.598224)
			(xy 284.865826 -100.687124) (xy 284.910276 -100.687124)
		)
		(stroke
			(width 0)
			(type solid)
		)
		(fill yes)
		(layer "In11.Cu")
		(net "M_F_DQ<50>")
	)
	(gr_poly
		(pts
			(xy 284.910276 -99.297744) (xy 284.865826 -99.297744) (xy 284.695646 -99.386644) (xy 284.695646 -99.607624)
			(xy 284.865826 -99.696524) (xy 284.910276 -99.696524)
		)
		(stroke
			(width 0)
			(type solid)
		)
		(fill yes)
		(layer "In11.Cu")
		(net "M_F_DQ<50>")
	)
	(gr_poly
		(pts
			(xy 284.910276 -98.307144) (xy 284.865826 -98.307144) (xy 284.695646 -98.396044) (xy 284.695646 -98.617024)
			(xy 284.865826 -98.705924) (xy 284.910276 -98.705924)
		)
		(stroke
			(width 0)
			(type solid)
		)
		(fill yes)
		(layer "In11.Cu")
		(net "M_F_DQ<50>")
	)
	(gr_poly
		(pts
			(xy 284.910276 -91.35745) (xy 284.865826 -91.35745) (xy 284.695646 -91.44635) (xy 284.695646 -91.667076)
			(xy 284.865826 -91.755976) (xy 284.91053 -91.755976)
		)
		(stroke
			(width 0)
			(type solid)
		)
		(fill yes)
		(layer "In11.Cu")
		(net "M_F_DQ<58>")
	)
	(gr_poly
		(pts
			(xy 284.951932 -48.873156) (xy 284.878272 -48.67402) (xy 284.846776 -48.642524) (xy 284.559502 -48.929798)
			(xy 284.590998 -48.961294) (xy 284.790134 -49.034954)
		)
		(stroke
			(width 0)
			(type solid)
		)
		(fill yes)
		(layer "In11.Cu")
		(net "M_C_DQ<51>")
	)
	(gr_poly
		(pts
			(xy 285.137098 -97.556574) (xy 285.145226 -97.364804) (xy 284.95371 -97.254568) (xy 284.791912 -97.357438)
			(xy 284.769306 -97.395792) (xy 285.115 -97.595182)
		)
		(stroke
			(width 0)
			(type solid)
		)
		(fill yes)
		(layer "In11.Cu")
		(net "M_F_DQ<51>")
	)
	(gr_poly
		(pts
			(xy 285.138622 -95.576644) (xy 285.14675 -95.384874) (xy 284.955488 -95.274384) (xy 284.793436 -95.377254)
			(xy 284.771084 -95.415862) (xy 285.116524 -95.614998)
		)
		(stroke
			(width 0)
			(type solid)
		)
		(fill yes)
		(layer "In11.Cu")
		(net "M_F_DQ<57>")
	)
	(gr_poly
		(pts
			(xy 285.140908 -94.587314) (xy 285.149036 -94.395544) (xy 284.957774 -94.285054) (xy 284.795722 -94.387924)
			(xy 284.77337 -94.426278) (xy 285.11881 -94.625922)
		)
		(stroke
			(width 0)
			(type solid)
		)
		(fill yes)
		(layer "In11.Cu")
		(net "M_F_DQS_DN<16>")
	)
	(gr_poly
		(pts
			(xy 285.142432 -96.56953) (xy 285.15056 -96.37776) (xy 284.959298 -96.26727) (xy 284.797246 -96.37014)
			(xy 284.774894 -96.408494) (xy 285.120334 -96.608138)
		)
		(stroke
			(width 0)
			(type solid)
		)
		(fill yes)
		(layer "In11.Cu")
		(net "M_F_DQ<61>")
	)
	(gr_poly
		(pts
			(xy 285.142432 -93.59773) (xy 285.15056 -93.40596) (xy 284.959298 -93.29547) (xy 284.797246 -93.39834)
			(xy 284.774894 -93.436694) (xy 285.120334 -93.636338)
		)
		(stroke
			(width 0)
			(type solid)
		)
		(fill yes)
		(layer "In11.Cu")
		(net "M_F_DQS_DP<7>")
	)
	(gr_poly
		(pts
			(xy 285.164022 -61.958728) (xy 285.164022 -61.737748) (xy 284.993842 -61.648848) (xy 284.949392 -61.648848)
			(xy 284.949392 -62.047628) (xy 284.993842 -62.047628)
		)
		(stroke
			(width 0)
			(type solid)
		)
		(fill yes)
		(layer "In11.Cu")
		(net "M_C_DQ<61>")
	)
	(gr_poly
		(pts
			(xy 285.164022 -60.977018) (xy 285.164022 -60.756038) (xy 284.993842 -60.667138) (xy 284.949392 -60.667138)
			(xy 284.949392 -61.065918) (xy 284.993842 -61.065918)
		)
		(stroke
			(width 0)
			(type solid)
		)
		(fill yes)
		(layer "In11.Cu")
		(net "M_C_DQ<61>")
	)
	(gr_poly
		(pts
			(xy 285.164022 -59.983624) (xy 285.164022 -59.762644) (xy 284.993842 -59.673744) (xy 284.949392 -59.673744)
			(xy 284.949392 -60.072524) (xy 284.993842 -60.072524)
		)
		(stroke
			(width 0)
			(type solid)
		)
		(fill yes)
		(layer "In11.Cu")
		(net "M_C_DQ<61>")
	)
	(gr_poly
		(pts
			(xy 285.164022 -58.980578) (xy 285.164022 -58.759598) (xy 284.993842 -58.670698) (xy 284.949392 -58.670698)
			(xy 284.949392 -59.069478) (xy 284.993842 -59.069478)
		)
		(stroke
			(width 0)
			(type solid)
		)
		(fill yes)
		(layer "In11.Cu")
		(net "M_C_DQ<61>")
	)
	(gr_poly
		(pts
			(xy 285.164022 -58.005218) (xy 285.164022 -57.784238) (xy 284.993842 -57.695338) (xy 284.949392 -57.695338)
			(xy 284.949392 -58.094118) (xy 284.993842 -58.094118)
		)
		(stroke
			(width 0)
			(type solid)
		)
		(fill yes)
		(layer "In11.Cu")
		(net "M_C_DQ<61>")
	)
	(gr_poly
		(pts
			(xy 285.164022 -57.014618) (xy 285.164022 -56.793638) (xy 284.993842 -56.704738) (xy 284.949392 -56.704738)
			(xy 284.949392 -57.103518) (xy 284.993842 -57.103518)
		)
		(stroke
			(width 0)
			(type solid)
		)
		(fill yes)
		(layer "In11.Cu")
		(net "M_C_DQ<61>")
	)
	(gr_poly
		(pts
			(xy 285.164022 -56.024018) (xy 285.164022 -55.803038) (xy 284.993842 -55.714138) (xy 284.949392 -55.714138)
			(xy 284.949392 -56.112918) (xy 284.993842 -56.112918)
		)
		(stroke
			(width 0)
			(type solid)
		)
		(fill yes)
		(layer "In11.Cu")
		(net "M_C_DQ<61>")
	)
	(gr_poly
		(pts
			(xy 285.164022 -55.033418) (xy 285.164022 -54.812438) (xy 284.993842 -54.723538) (xy 284.949392 -54.723538)
			(xy 284.949392 -55.122318) (xy 284.993842 -55.122318)
		)
		(stroke
			(width 0)
			(type solid)
		)
		(fill yes)
		(layer "In11.Cu")
		(net "M_C_DQ<61>")
	)
	(gr_poly
		(pts
			(xy 285.164276 -53.689504) (xy 285.164276 -53.468524) (xy 284.994096 -53.379624) (xy 284.949646 -53.379624)
			(xy 284.949646 -53.778404) (xy 284.994096 -53.778404)
		)
		(stroke
			(width 0)
			(type solid)
		)
		(fill yes)
		(layer "In11.Cu")
		(net "M_C_DQ<61>")
	)
	(gr_poly
		(pts
			(xy 285.237682 -51.873658) (xy 285.237682 -51.645058) (xy 285.044642 -51.556158) (xy 285.000192 -51.556158)
			(xy 285.000192 -51.962558) (xy 285.044642 -51.962558)
		)
		(stroke
			(width 0)
			(type solid)
		)
		(fill yes)
		(layer "In11.Cu")
		(net "M_C_DQ<61>")
	)
	(gr_poly
		(pts
			(xy 285.312358 -50.080164) (xy 285.281116 -50.048668) (xy 285.081726 -49.975008) (xy 284.919928 -50.136552)
			(xy 284.993588 -50.335942) (xy 285.025084 -50.367438)
		)
		(stroke
			(width 0)
			(type solid)
		)
		(fill yes)
		(layer "In11.Cu")
		(net "M_C_DQ<60>")
	)
	(gr_poly
		(pts
			(xy 285.346902 -97.163382) (xy 285.369254 -97.124774) (xy 285.023814 -96.925638) (xy 285.001716 -96.963992)
			(xy 284.993588 -97.155762) (xy 285.18485 -97.266252)
		)
		(stroke
			(width 0)
			(type solid)
		)
		(fill yes)
		(layer "In11.Cu")
		(net "M_F_DQ<60>")
	)
	(gr_poly
		(pts
			(xy 285.346902 -96.172782) (xy 285.369254 -96.134174) (xy 285.023814 -95.935038) (xy 285.001716 -95.973392)
			(xy 284.993588 -96.165162) (xy 285.18485 -96.275652)
		)
		(stroke
			(width 0)
			(type solid)
		)
		(fill yes)
		(layer "In11.Cu")
		(net "M_F_DQ<56>")
	)
	(gr_poly
		(pts
			(xy 285.346902 -93.200982) (xy 285.369254 -93.162374) (xy 285.023814 -92.963238) (xy 285.001716 -93.001592)
			(xy 284.993588 -93.193362) (xy 285.18485 -93.303852)
		)
		(stroke
			(width 0)
			(type solid)
		)
		(fill yes)
		(layer "In11.Cu")
		(net "M_F_DQ<62>")
	)
	(gr_poly
		(pts
			(xy 285.348172 -92.211398) (xy 285.370524 -92.17279) (xy 285.025084 -91.973654) (xy 285.002986 -92.012008)
			(xy 284.994858 -92.203778) (xy 285.18612 -92.314268)
		)
		(stroke
			(width 0)
			(type solid)
		)
		(fill yes)
		(layer "In11.Cu")
		(net "M_F_DQ<58>")
	)
	(gr_poly
		(pts
			(xy 285.348426 -95.183198) (xy 285.370778 -95.14459) (xy 285.025338 -94.945454) (xy 285.00324 -94.983808)
			(xy 284.995112 -95.175578) (xy 285.186374 -95.286068)
		)
		(stroke
			(width 0)
			(type solid)
		)
		(fill yes)
		(layer "In11.Cu")
		(net "M_F_DQS_DP<16>")
	)
	(gr_poly
		(pts
			(xy 285.350712 -94.193868) (xy 285.373064 -94.155514) (xy 285.027624 -93.95587) (xy 285.005526 -93.994478)
			(xy 284.997398 -94.186248) (xy 285.18866 -94.296738)
		)
		(stroke
			(width 0)
			(type solid)
		)
		(fill yes)
		(layer "In11.Cu")
		(net "M_F_DQS_DN<7>")
	)
	(gr_poly
		(pts
			(xy 285.448502 -105.043478) (xy 285.448502 -104.822498) (xy 285.278322 -104.733598) (xy 285.233872 -104.733598)
			(xy 285.233872 -105.132378) (xy 285.278322 -105.132378)
		)
		(stroke
			(width 0)
			(type solid)
		)
		(fill yes)
		(layer "In11.Cu")
		(net "M_F_DQ<51>")
	)
	(gr_poly
		(pts
			(xy 285.448502 -104.052878) (xy 285.448502 -103.831898) (xy 285.278322 -103.742998) (xy 285.233872 -103.742998)
			(xy 285.233872 -104.141778) (xy 285.278322 -104.141778)
		)
		(stroke
			(width 0)
			(type solid)
		)
		(fill yes)
		(layer "In11.Cu")
		(net "M_F_DQ<51>")
	)
	(gr_poly
		(pts
			(xy 285.448502 -103.062278) (xy 285.448502 -102.841298) (xy 285.278322 -102.752398) (xy 285.233872 -102.752398)
			(xy 285.233872 -103.151178) (xy 285.278322 -103.151178)
		)
		(stroke
			(width 0)
			(type solid)
		)
		(fill yes)
		(layer "In11.Cu")
		(net "M_F_DQ<51>")
	)
	(gr_poly
		(pts
			(xy 285.448502 -102.071678) (xy 285.448502 -101.850698) (xy 285.278322 -101.761798) (xy 285.233872 -101.761798)
			(xy 285.233872 -102.160578) (xy 285.278322 -102.160578)
		)
		(stroke
			(width 0)
			(type solid)
		)
		(fill yes)
		(layer "In11.Cu")
		(net "M_F_DQ<51>")
	)
	(gr_poly
		(pts
			(xy 285.448502 -101.081078) (xy 285.448502 -100.860098) (xy 285.278322 -100.771198) (xy 285.233872 -100.771198)
			(xy 285.233872 -101.169978) (xy 285.278322 -101.169978)
		)
		(stroke
			(width 0)
			(type solid)
		)
		(fill yes)
		(layer "In11.Cu")
		(net "M_F_DQ<51>")
	)
	(gr_poly
		(pts
			(xy 285.448502 -100.090478) (xy 285.448502 -99.869498) (xy 285.278322 -99.780598) (xy 285.233872 -99.780598)
			(xy 285.233872 -100.179378) (xy 285.278322 -100.179378)
		)
		(stroke
			(width 0)
			(type solid)
		)
		(fill yes)
		(layer "In11.Cu")
		(net "M_F_DQ<51>")
	)
	(gr_poly
		(pts
			(xy 285.448502 -99.099878) (xy 285.448502 -98.878898) (xy 285.278322 -98.789998) (xy 285.233872 -98.789998)
			(xy 285.233872 -99.188778) (xy 285.278322 -99.188778)
		)
		(stroke
			(width 0)
			(type solid)
		)
		(fill yes)
		(layer "In11.Cu")
		(net "M_F_DQ<51>")
	)
	(gr_poly
		(pts
			(xy 285.448502 -98.109278) (xy 285.448502 -97.888298) (xy 285.278322 -97.799398) (xy 285.233872 -97.799398)
			(xy 285.233872 -98.198178) (xy 285.278322 -98.198178)
		)
		(stroke
			(width 0)
			(type solid)
		)
		(fill yes)
		(layer "In11.Cu")
		(net "M_F_DQ<51>")
	)
	(gr_poly
		(pts
			(xy 285.484062 -61.648848) (xy 285.439612 -61.648848) (xy 285.269432 -61.737748) (xy 285.269432 -61.958728)
			(xy 285.439612 -62.047628) (xy 285.484062 -62.047628)
		)
		(stroke
			(width 0)
			(type solid)
		)
		(fill yes)
		(layer "In11.Cu")
		(net "M_C_DQ<56>")
	)
	(gr_poly
		(pts
			(xy 285.484062 -60.664344) (xy 285.439612 -60.664344) (xy 285.269432 -60.753244) (xy 285.269432 -60.974224)
			(xy 285.439612 -61.063124) (xy 285.484062 -61.063124)
		)
		(stroke
			(width 0)
			(type solid)
		)
		(fill yes)
		(layer "In11.Cu")
		(net "M_C_DQ<56>")
	)
	(gr_poly
		(pts
			(xy 285.484062 -59.667394) (xy 285.439612 -59.667394) (xy 285.269432 -59.756294) (xy 285.269432 -59.977274)
			(xy 285.439612 -60.066174) (xy 285.484062 -60.066174)
		)
		(stroke
			(width 0)
			(type solid)
		)
		(fill yes)
		(layer "In11.Cu")
		(net "M_C_DQ<56>")
	)
	(gr_poly
		(pts
			(xy 285.484062 -58.670698) (xy 285.439612 -58.670698) (xy 285.269432 -58.759598) (xy 285.269432 -58.980578)
			(xy 285.439612 -59.069478) (xy 285.484062 -59.069478)
		)
		(stroke
			(width 0)
			(type solid)
		)
		(fill yes)
		(layer "In11.Cu")
		(net "M_C_DQ<56>")
	)
	(gr_poly
		(pts
			(xy 285.484062 -57.692544) (xy 285.439612 -57.692544) (xy 285.269432 -57.781444) (xy 285.269432 -58.002424)
			(xy 285.439612 -58.091324) (xy 285.484062 -58.091324)
		)
		(stroke
			(width 0)
			(type solid)
		)
		(fill yes)
		(layer "In11.Cu")
		(net "M_C_DQ<56>")
	)
	(gr_poly
		(pts
			(xy 285.484062 -56.701944) (xy 285.439612 -56.701944) (xy 285.269432 -56.790844) (xy 285.269432 -57.011824)
			(xy 285.439612 -57.100724) (xy 285.484062 -57.100724)
		)
		(stroke
			(width 0)
			(type solid)
		)
		(fill yes)
		(layer "In11.Cu")
		(net "M_C_DQ<56>")
	)
	(gr_poly
		(pts
			(xy 285.484062 -55.711344) (xy 285.439612 -55.711344) (xy 285.269432 -55.800244) (xy 285.269432 -56.021224)
			(xy 285.439612 -56.110124) (xy 285.484062 -56.110124)
		)
		(stroke
			(width 0)
			(type solid)
		)
		(fill yes)
		(layer "In11.Cu")
		(net "M_C_DQ<56>")
	)
	(gr_poly
		(pts
			(xy 285.484062 -54.720744) (xy 285.439612 -54.720744) (xy 285.269432 -54.809644) (xy 285.269432 -55.030624)
			(xy 285.439612 -55.119524) (xy 285.484062 -55.119524)
		)
		(stroke
			(width 0)
			(type solid)
		)
		(fill yes)
		(layer "In11.Cu")
		(net "M_C_DQ<56>")
	)
	(gr_poly
		(pts
			(xy 285.484062 -53.730144) (xy 285.439612 -53.730144) (xy 285.269432 -53.819044) (xy 285.269432 -54.040024)
			(xy 285.439612 -54.128924) (xy 285.484062 -54.128924)
		)
		(stroke
			(width 0)
			(type solid)
		)
		(fill yes)
		(layer "In11.Cu")
		(net "M_C_DQ<56>")
	)
	(gr_poly
		(pts
			(xy 285.552388 -50.44567) (xy 285.478728 -50.24628) (xy 285.447232 -50.214784) (xy 285.159958 -50.502058)
			(xy 285.1912 -50.533554) (xy 285.39059 -50.607214)
		)
		(stroke
			(width 0)
			(type solid)
		)
		(fill yes)
		(layer "In11.Cu")
		(net "M_C_DQ<61>")
	)
	(gr_poly
		(pts
			(xy 285.561278 -63.015622) (xy 285.582868 -62.824868) (xy 285.399734 -62.70117) (xy 285.230824 -62.792356)
			(xy 285.205932 -62.829186) (xy 285.536386 -63.052452)
		)
		(stroke
			(width 0)
			(type solid)
		)
		(fill yes)
		(layer "In11.Cu")
		(net "M_C_DQ<61>")
	)
	(gr_poly
		(pts
			(xy 285.576518 -53.06568) (xy 285.532068 -53.06568) (xy 285.339028 -53.15458) (xy 285.339028 -53.38318)
			(xy 285.532068 -53.47208) (xy 285.576518 -53.47208)
		)
		(stroke
			(width 0)
			(type solid)
		)
		(fill yes)
		(layer "In11.Cu")
		(net "M_C_DQ<56>")
	)
	(gr_poly
		(pts
			(xy 285.848044 -62.66688) (xy 285.884112 -62.641226) (xy 285.653226 -62.316106) (xy 285.616904 -62.34176)
			(xy 285.529782 -62.512956) (xy 285.657798 -62.693042)
		)
		(stroke
			(width 0)
			(type solid)
		)
		(fill yes)
		(layer "In11.Cu")
		(net "M_C_DQ<56>")
	)
	(gr_poly
		(pts
			(xy 285.933642 -64.49441) (xy 285.771336 -64.130174) (xy 285.730696 -64.148208) (xy 285.61157 -64.298576)
			(xy 285.701486 -64.500506) (xy 285.893002 -64.512444)
		)
		(stroke
			(width 0)
			(type solid)
		)
		(fill yes)
		(layer "In11.Cu")
		(net "M_C_DQ<57>")
	)
	(gr_poly
		(pts
			(xy 285.958534 -92.072714) (xy 286.0421 -91.89974) (xy 285.910274 -91.722448) (xy 285.720536 -91.752674)
			(xy 285.684976 -91.77909) (xy 285.922974 -92.099384)
		)
		(stroke
			(width 0)
			(type solid)
		)
		(fill yes)
		(layer "In11.Cu")
		(net "M_F_DQ<59>")
	)
	(gr_poly
		(pts
			(xy 285.997142 -94.090744) (xy 286.00527 -93.898974) (xy 285.814008 -93.788484) (xy 285.651956 -93.891354)
			(xy 285.629604 -93.929962) (xy 285.975044 -94.129098)
		)
		(stroke
			(width 0)
			(type solid)
		)
		(fill yes)
		(layer "In11.Cu")
		(net "M_F_DQS_DP<7>")
	)
	(gr_poly
		(pts
			(xy 285.999428 -97.063814) (xy 286.007556 -96.872044) (xy 285.816294 -96.761554) (xy 285.654242 -96.864424)
			(xy 285.63189 -96.902778) (xy 285.97733 -97.102422)
		)
		(stroke
			(width 0)
			(type solid)
		)
		(fill yes)
		(layer "In11.Cu")
		(net "M_F_DQ<61>")
	)
	(gr_poly
		(pts
			(xy 285.999428 -96.073214) (xy 286.007556 -95.881444) (xy 285.816294 -95.770954) (xy 285.654242 -95.873824)
			(xy 285.63189 -95.912178) (xy 285.97733 -96.111822)
		)
		(stroke
			(width 0)
			(type solid)
		)
		(fill yes)
		(layer "In11.Cu")
		(net "M_F_DQ<57>")
	)
	(gr_poly
		(pts
			(xy 285.999428 -93.101414) (xy 286.007556 -92.909644) (xy 285.816294 -92.799154) (xy 285.654242 -92.902024)
			(xy 285.63189 -92.940378) (xy 285.97733 -93.140022)
		)
		(stroke
			(width 0)
			(type solid)
		)
		(fill yes)
		(layer "In11.Cu")
		(net "M_F_DQ<63>")
	)
	(gr_poly
		(pts
			(xy 286.000952 -95.083376) (xy 286.00908 -94.891606) (xy 285.817818 -94.781116) (xy 285.655766 -94.883986)
			(xy 285.633414 -94.922594) (xy 285.978854 -95.12173)
		)
		(stroke
			(width 0)
			(type solid)
		)
		(fill yes)
		(layer "In11.Cu")
		(net "M_F_DQS_DN<16>")
	)
	(gr_poly
		(pts
			(xy 286.004254 -53.17998) (xy 286.004254 -52.95138) (xy 285.811214 -52.86248) (xy 285.766764 -52.86248)
			(xy 285.766764 -53.26888) (xy 285.811214 -53.26888)
		)
		(stroke
			(width 0)
			(type solid)
		)
		(fill yes)
		(layer "In11.Cu")
		(net "M_C_DQ<57>")
	)
	(gr_poly
		(pts
			(xy 286.01289 -49.379632) (xy 285.981394 -49.348136) (xy 285.782258 -49.274476) (xy 285.62046 -49.436274)
			(xy 285.69412 -49.63541) (xy 285.725616 -49.666906)
		)
		(stroke
			(width 0)
			(type solid)
		)
		(fill yes)
		(layer "In11.Cu")
		(net "M_C_DQ<60>")
	)
	(gr_poly
		(pts
			(xy 286.022034 -61.463428) (xy 286.022034 -61.242448) (xy 285.851854 -61.153548) (xy 285.807404 -61.153548)
			(xy 285.807404 -61.552328) (xy 285.851854 -61.552328)
		)
		(stroke
			(width 0)
			(type solid)
		)
		(fill yes)
		(layer "In11.Cu")
		(net "M_C_DQ<57>")
	)
	(gr_poly
		(pts
			(xy 286.022288 -60.466478) (xy 286.022288 -60.245498) (xy 285.852108 -60.156598) (xy 285.807658 -60.156598)
			(xy 285.807658 -60.555378) (xy 285.852108 -60.555378)
		)
		(stroke
			(width 0)
			(type solid)
		)
		(fill yes)
		(layer "In11.Cu")
		(net "M_C_DQ<57>")
	)
	(gr_poly
		(pts
			(xy 286.022288 -59.488324) (xy 286.022288 -59.267344) (xy 285.852108 -59.178444) (xy 285.807658 -59.178444)
			(xy 285.807658 -59.577224) (xy 285.852108 -59.577224)
		)
		(stroke
			(width 0)
			(type solid)
		)
		(fill yes)
		(layer "In11.Cu")
		(net "M_C_DQ<57>")
	)
	(gr_poly
		(pts
			(xy 286.022288 -58.491628) (xy 286.022288 -58.270648) (xy 285.852108 -58.181748) (xy 285.807658 -58.181748)
			(xy 285.807658 -58.580528) (xy 285.852108 -58.580528)
		)
		(stroke
			(width 0)
			(type solid)
		)
		(fill yes)
		(layer "In11.Cu")
		(net "M_C_DQ<57>")
	)
	(gr_poly
		(pts
			(xy 286.022288 -57.494678) (xy 286.022288 -57.273698) (xy 285.852108 -57.184798) (xy 285.807658 -57.184798)
			(xy 285.807658 -57.583578) (xy 285.852108 -57.583578)
		)
		(stroke
			(width 0)
			(type solid)
		)
		(fill yes)
		(layer "In11.Cu")
		(net "M_C_DQ<57>")
	)
	(gr_poly
		(pts
			(xy 286.022288 -56.504078) (xy 286.022288 -56.283098) (xy 285.852108 -56.194198) (xy 285.807658 -56.194198)
			(xy 285.807658 -56.592978) (xy 285.852108 -56.592978)
		)
		(stroke
			(width 0)
			(type solid)
		)
		(fill yes)
		(layer "In11.Cu")
		(net "M_C_DQ<57>")
	)
	(gr_poly
		(pts
			(xy 286.022288 -55.513478) (xy 286.022288 -55.292498) (xy 285.852108 -55.203598) (xy 285.807658 -55.203598)
			(xy 285.807658 -55.602378) (xy 285.852108 -55.602378)
		)
		(stroke
			(width 0)
			(type solid)
		)
		(fill yes)
		(layer "In11.Cu")
		(net "M_C_DQ<57>")
	)
	(gr_poly
		(pts
			(xy 286.022288 -54.522878) (xy 286.022288 -54.301898) (xy 285.852108 -54.212998) (xy 285.807658 -54.212998)
			(xy 285.807658 -54.611778) (xy 285.852108 -54.611778)
		)
		(stroke
			(width 0)
			(type solid)
		)
		(fill yes)
		(layer "In11.Cu")
		(net "M_C_DQ<57>")
	)
	(gr_poly
		(pts
			(xy 286.205168 -94.687136) (xy 286.22752 -94.648782) (xy 285.88208 -94.449138) (xy 285.859982 -94.487746)
			(xy 285.851854 -94.679516) (xy 286.043116 -94.790006)
		)
		(stroke
			(width 0)
			(type solid)
		)
		(fill yes)
		(layer "In11.Cu")
		(net "M_F_DQS_DN<7>")
	)
	(gr_poly
		(pts
			(xy 286.206692 -97.659698) (xy 286.229044 -97.62109) (xy 285.883604 -97.421954) (xy 285.861506 -97.460308)
			(xy 285.853378 -97.652078) (xy 286.04464 -97.762568)
		)
		(stroke
			(width 0)
			(type solid)
		)
		(fill yes)
		(layer "In11.Cu")
		(net "M_F_DQ<60>")
	)
	(gr_poly
		(pts
			(xy 286.206692 -96.669098) (xy 286.229044 -96.63049) (xy 285.883604 -96.431354) (xy 285.861506 -96.469708)
			(xy 285.853378 -96.661478) (xy 286.04464 -96.771968)
		)
		(stroke
			(width 0)
			(type solid)
		)
		(fill yes)
		(layer "In11.Cu")
		(net "M_F_DQ<56>")
	)
	(gr_poly
		(pts
			(xy 286.206692 -93.697298) (xy 286.229044 -93.65869) (xy 285.883604 -93.459554) (xy 285.861506 -93.497908)
			(xy 285.853378 -93.689678) (xy 286.04464 -93.800168)
		)
		(stroke
			(width 0)
			(type solid)
		)
		(fill yes)
		(layer "In11.Cu")
		(net "M_F_DQ<62>")
	)
	(gr_poly
		(pts
			(xy 286.206692 -92.706698) (xy 286.229044 -92.66809) (xy 285.883604 -92.468954) (xy 285.861506 -92.507308)
			(xy 285.853378 -92.699078) (xy 286.04464 -92.809568)
		)
		(stroke
			(width 0)
			(type solid)
		)
		(fill yes)
		(layer "In11.Cu")
		(net "M_F_DQ<58>")
	)
	(gr_poly
		(pts
			(xy 286.208978 -95.679768) (xy 286.23133 -95.641414) (xy 285.88589 -95.44177) (xy 285.863792 -95.480378)
			(xy 285.855664 -95.672148) (xy 286.046926 -95.782638)
		)
		(stroke
			(width 0)
			(type solid)
		)
		(fill yes)
		(layer "In11.Cu")
		(net "M_F_DQS_DP<16>")
	)
	(gr_poly
		(pts
			(xy 286.252666 -49.745138) (xy 286.179006 -49.545748) (xy 286.147764 -49.514252) (xy 285.860236 -49.80178)
			(xy 285.891732 -49.833022) (xy 286.091122 -49.906682)
		)
		(stroke
			(width 0)
			(type solid)
		)
		(fill yes)
		(layer "In11.Cu")
		(net "M_C_DQ<61>")
	)
	(gr_poly
		(pts
			(xy 286.342582 -61.153548) (xy 286.298132 -61.153548) (xy 286.127952 -61.242448) (xy 286.127952 -61.463428)
			(xy 286.298132 -61.552328) (xy 286.342582 -61.552328)
		)
		(stroke
			(width 0)
			(type solid)
		)
		(fill yes)
		(layer "In11.Cu")
		(net "M_C_DQS_DP<16>")
	)
	(gr_poly
		(pts
			(xy 286.342582 -60.156598) (xy 286.298132 -60.156598) (xy 286.127952 -60.245498) (xy 286.127952 -60.466478)
			(xy 286.298132 -60.555378) (xy 286.342582 -60.555378)
		)
		(stroke
			(width 0)
			(type solid)
		)
		(fill yes)
		(layer "In11.Cu")
		(net "M_C_DQS_DP<16>")
	)
	(gr_poly
		(pts
			(xy 286.342582 -59.178444) (xy 286.298132 -59.178444) (xy 286.127952 -59.267344) (xy 286.127952 -59.488324)
			(xy 286.298132 -59.577224) (xy 286.342582 -59.577224)
		)
		(stroke
			(width 0)
			(type solid)
		)
		(fill yes)
		(layer "In11.Cu")
		(net "M_C_DQS_DP<16>")
	)
	(gr_poly
		(pts
			(xy 286.342582 -58.181748) (xy 286.298132 -58.181748) (xy 286.127952 -58.270648) (xy 286.127952 -58.491628)
			(xy 286.298132 -58.580528) (xy 286.342582 -58.580528)
		)
		(stroke
			(width 0)
			(type solid)
		)
		(fill yes)
		(layer "In11.Cu")
		(net "M_C_DQS_DP<16>")
	)
	(gr_poly
		(pts
			(xy 286.342582 -57.184798) (xy 286.298132 -57.184798) (xy 286.127952 -57.273698) (xy 286.127952 -57.494678)
			(xy 286.298132 -57.583578) (xy 286.342582 -57.583578)
		)
		(stroke
			(width 0)
			(type solid)
		)
		(fill yes)
		(layer "In11.Cu")
		(net "M_C_DQS_DP<16>")
	)
	(gr_poly
		(pts
			(xy 286.342582 -56.194198) (xy 286.298132 -56.194198) (xy 286.127952 -56.283098) (xy 286.127952 -56.504078)
			(xy 286.298132 -56.592978) (xy 286.342582 -56.592978)
		)
		(stroke
			(width 0)
			(type solid)
		)
		(fill yes)
		(layer "In11.Cu")
		(net "M_C_DQS_DP<16>")
	)
	(gr_poly
		(pts
			(xy 286.342582 -55.203598) (xy 286.298132 -55.203598) (xy 286.127952 -55.292498) (xy 286.127952 -55.513478)
			(xy 286.298132 -55.602378) (xy 286.342582 -55.602378)
		)
		(stroke
			(width 0)
			(type solid)
		)
		(fill yes)
		(layer "In11.Cu")
		(net "M_C_DQS_DP<16>")
	)
	(gr_poly
		(pts
			(xy 286.342582 -54.212998) (xy 286.298132 -54.212998) (xy 286.127952 -54.301898) (xy 286.127952 -54.522878)
			(xy 286.298132 -54.611778) (xy 286.342582 -54.611778)
		)
		(stroke
			(width 0)
			(type solid)
		)
		(fill yes)
		(layer "In11.Cu")
		(net "M_C_DQS_DP<16>")
	)
	(gr_poly
		(pts
			(xy 286.343344 -53.090826) (xy 286.298894 -53.090826) (xy 286.128714 -53.179726) (xy 286.128714 -53.400706)
			(xy 286.298894 -53.489606) (xy 286.343344 -53.489606)
		)
		(stroke
			(width 0)
			(type solid)
		)
		(fill yes)
		(layer "In11.Cu")
		(net "M_C_DQS_DP<16>")
	)
	(gr_poly
		(pts
			(xy 286.343344 -52.152042) (xy 286.298894 -52.152042) (xy 286.105854 -52.240942) (xy 286.105854 -52.469542)
			(xy 286.298894 -52.558442) (xy 286.343344 -52.558442)
		)
		(stroke
			(width 0)
			(type solid)
		)
		(fill yes)
		(layer "In11.Cu")
		(net "M_C_DQS_DP<16>")
	)
	(gr_poly
		(pts
			(xy 286.446214 -63.368936) (xy 286.405066 -63.18123) (xy 286.376364 -63.147194) (xy 286.071056 -63.403734)
			(xy 286.099504 -63.43777) (xy 286.27705 -63.510922)
		)
		(stroke
			(width 0)
			(type solid)
		)
		(fill yes)
		(layer "In11.Cu")
		(net "M_C_DQ<57>")
	)
	(gr_poly
		(pts
			(xy 286.627062 -103.260144) (xy 286.582612 -103.260144) (xy 286.412432 -103.349044) (xy 286.412432 -103.570024)
			(xy 286.582612 -103.658924) (xy 286.627062 -103.658924)
		)
		(stroke
			(width 0)
			(type solid)
		)
		(fill yes)
		(layer "In11.Cu")
		(net "M_F_DQ<60>")
	)
	(gr_poly
		(pts
			(xy 286.627062 -102.269544) (xy 286.582612 -102.269544) (xy 286.412432 -102.358444) (xy 286.412432 -102.579424)
			(xy 286.582612 -102.668324) (xy 286.627062 -102.668324)
		)
		(stroke
			(width 0)
			(type solid)
		)
		(fill yes)
		(layer "In11.Cu")
		(net "M_F_DQ<60>")
	)
	(gr_poly
		(pts
			(xy 286.627062 -101.278944) (xy 286.582612 -101.278944) (xy 286.412432 -101.367844) (xy 286.412432 -101.588824)
			(xy 286.582612 -101.677724) (xy 286.627062 -101.677724)
		)
		(stroke
			(width 0)
			(type solid)
		)
		(fill yes)
		(layer "In11.Cu")
		(net "M_F_DQ<60>")
	)
	(gr_poly
		(pts
			(xy 286.627062 -100.288344) (xy 286.582612 -100.288344) (xy 286.412432 -100.377244) (xy 286.412432 -100.598224)
			(xy 286.582612 -100.687124) (xy 286.627062 -100.687124)
		)
		(stroke
			(width 0)
			(type solid)
		)
		(fill yes)
		(layer "In11.Cu")
		(net "M_F_DQ<60>")
	)
	(gr_poly
		(pts
			(xy 286.627062 -99.297744) (xy 286.582612 -99.297744) (xy 286.412432 -99.386644) (xy 286.412432 -99.607624)
			(xy 286.582612 -99.696524) (xy 286.627062 -99.696524)
		)
		(stroke
			(width 0)
			(type solid)
		)
		(fill yes)
		(layer "In11.Cu")
		(net "M_F_DQ<60>")
	)
	(gr_poly
		(pts
			(xy 286.627062 -98.301556) (xy 286.582612 -98.301556) (xy 286.412432 -98.390456) (xy 286.412432 -98.611436)
			(xy 286.582612 -98.700336) (xy 286.627062 -98.700336)
		)
		(stroke
			(width 0)
			(type solid)
		)
		(fill yes)
		(layer "In11.Cu")
		(net "M_F_DQ<60>")
	)
	(gr_poly
		(pts
			(xy 286.748474 -53.046122) (xy 286.748474 -52.825142) (xy 286.578294 -52.736242) (xy 286.533844 -52.736242)
			(xy 286.533844 -53.135022) (xy 286.578294 -53.135022)
		)
		(stroke
			(width 0)
			(type solid)
		)
		(fill yes)
		(layer "In11.Cu")
		(net "M_C_DQS_DN<16>")
	)
	(gr_poly
		(pts
			(xy 286.76854 -51.594766) (xy 286.737044 -51.563524) (xy 286.537654 -51.489864) (xy 286.37611 -51.651408)
			(xy 286.449516 -51.850798) (xy 286.481012 -51.882294)
		)
		(stroke
			(width 0)
			(type solid)
		)
		(fill yes)
		(layer "In11.Cu")
		(net "M_C_DQS_DP<16>")
	)
	(gr_poly
		(pts
			(xy 286.855408 -95.576644) (xy 286.863536 -95.384874) (xy 286.672274 -95.274384) (xy 286.510222 -95.377254)
			(xy 286.48787 -95.415862) (xy 286.83331 -95.614998)
		)
		(stroke
			(width 0)
			(type solid)
		)
		(fill yes)
		(layer "In11.Cu")
		(net "M_F_DQS_DN<16>")
	)
	(gr_poly
		(pts
			(xy 286.857694 -94.587314) (xy 286.865822 -94.395544) (xy 286.67456 -94.285054) (xy 286.512508 -94.387924)
			(xy 286.490156 -94.426278) (xy 286.835596 -94.625922)
		)
		(stroke
			(width 0)
			(type solid)
		)
		(fill yes)
		(layer "In11.Cu")
		(net "M_F_DQS_DP<7>")
	)
	(gr_poly
		(pts
			(xy 286.859218 -97.560384) (xy 286.867346 -97.368614) (xy 286.676084 -97.258124) (xy 286.514032 -97.360994)
			(xy 286.49168 -97.399348) (xy 286.83712 -97.598738)
		)
		(stroke
			(width 0)
			(type solid)
		)
		(fill yes)
		(layer "In11.Cu")
		(net "M_F_DQ<61>")
	)
	(gr_poly
		(pts
			(xy 286.859218 -96.56953) (xy 286.867346 -96.37776) (xy 286.676084 -96.26727) (xy 286.514032 -96.37014)
			(xy 286.49168 -96.408494) (xy 286.83712 -96.608138)
		)
		(stroke
			(width 0)
			(type solid)
		)
		(fill yes)
		(layer "In11.Cu")
		(net "M_F_DQ<57>")
	)
	(gr_poly
		(pts
			(xy 286.859218 -93.59773) (xy 286.867346 -93.40596) (xy 286.676084 -93.29547) (xy 286.514032 -93.39834)
			(xy 286.49168 -93.436694) (xy 286.83712 -93.636338)
		)
		(stroke
			(width 0)
			(type solid)
		)
		(fill yes)
		(layer "In11.Cu")
		(net "M_F_DQ<63>")
	)
	(gr_poly
		(pts
			(xy 286.859218 -92.60713) (xy 286.867346 -92.41536) (xy 286.676084 -92.30487) (xy 286.514032 -92.40774)
			(xy 286.49168 -92.446094) (xy 286.83712 -92.645738)
		)
		(stroke
			(width 0)
			(type solid)
		)
		(fill yes)
		(layer "In11.Cu")
		(net "M_F_DQ<59>")
	)
	(gr_poly
		(pts
			(xy 286.880554 -54.022498) (xy 286.880554 -53.801518) (xy 286.710374 -53.712618) (xy 286.665924 -53.712618)
			(xy 286.665924 -54.111398) (xy 286.710374 -54.111398)
		)
		(stroke
			(width 0)
			(type solid)
		)
		(fill yes)
		(layer "In11.Cu")
		(net "M_C_DQS_DN<16>")
	)
	(gr_poly
		(pts
			(xy 286.880808 -60.974224) (xy 286.880808 -60.753244) (xy 286.710628 -60.664344) (xy 286.666178 -60.664344)
			(xy 286.666178 -61.063124) (xy 286.710628 -61.063124)
		)
		(stroke
			(width 0)
			(type solid)
		)
		(fill yes)
		(layer "In11.Cu")
		(net "M_C_DQS_DN<16>")
	)
	(gr_poly
		(pts
			(xy 286.880808 -59.977274) (xy 286.880808 -59.756294) (xy 286.710628 -59.667394) (xy 286.666178 -59.667394)
			(xy 286.666178 -60.066174) (xy 286.710628 -60.066174)
		)
		(stroke
			(width 0)
			(type solid)
		)
		(fill yes)
		(layer "In11.Cu")
		(net "M_C_DQS_DN<16>")
	)
	(gr_poly
		(pts
			(xy 286.880808 -58.980578) (xy 286.880808 -58.759598) (xy 286.710628 -58.670698) (xy 286.666178 -58.670698)
			(xy 286.666178 -59.069478) (xy 286.710628 -59.069478)
		)
		(stroke
			(width 0)
			(type solid)
		)
		(fill yes)
		(layer "In11.Cu")
		(net "M_C_DQS_DN<16>")
	)
	(gr_poly
		(pts
			(xy 286.880808 -58.002424) (xy 286.880808 -57.781444) (xy 286.710628 -57.692544) (xy 286.666178 -57.692544)
			(xy 286.666178 -58.091324) (xy 286.710628 -58.091324)
		)
		(stroke
			(width 0)
			(type solid)
		)
		(fill yes)
		(layer "In11.Cu")
		(net "M_C_DQS_DN<16>")
	)
	(gr_poly
		(pts
			(xy 286.880808 -57.011824) (xy 286.880808 -56.790844) (xy 286.710628 -56.701944) (xy 286.666178 -56.701944)
			(xy 286.666178 -57.100724) (xy 286.710628 -57.100724)
		)
		(stroke
			(width 0)
			(type solid)
		)
		(fill yes)
		(layer "In11.Cu")
		(net "M_C_DQS_DN<16>")
	)
	(gr_poly
		(pts
			(xy 286.880808 -56.021224) (xy 286.880808 -55.800244) (xy 286.710628 -55.711344) (xy 286.666178 -55.711344)
			(xy 286.666178 -56.110124) (xy 286.710628 -56.110124)
		)
		(stroke
			(width 0)
			(type solid)
		)
		(fill yes)
		(layer "In11.Cu")
		(net "M_C_DQS_DN<16>")
	)
	(gr_poly
		(pts
			(xy 286.880808 -55.030624) (xy 286.880808 -54.809644) (xy 286.710628 -54.720744) (xy 286.666178 -54.720744)
			(xy 286.666178 -55.119524) (xy 286.710628 -55.119524)
		)
		(stroke
			(width 0)
			(type solid)
		)
		(fill yes)
		(layer "In11.Cu")
		(net "M_C_DQS_DN<16>")
	)
	(gr_poly
		(pts
			(xy 286.955992 -49.547018) (xy 286.924496 -49.515522) (xy 286.72536 -49.441862) (xy 286.563562 -49.60366)
			(xy 286.637222 -49.802796) (xy 286.668718 -49.834292)
		)
		(stroke
			(width 0)
			(type solid)
		)
		(fill yes)
		(layer "In11.Cu")
		(net "M_C_DQ<56>")
	)
	(gr_poly
		(pts
			(xy 287.063688 -97.163382) (xy 287.08604 -97.124774) (xy 286.7406 -96.925638) (xy 286.718502 -96.963992)
			(xy 286.710374 -97.155762) (xy 286.901636 -97.266252)
		)
		(stroke
			(width 0)
			(type solid)
		)
		(fill yes)
		(layer "In11.Cu")
		(net "M_F_DQ<56>")
	)
	(gr_poly
		(pts
			(xy 287.063688 -96.172782) (xy 287.08604 -96.134174) (xy 286.7406 -95.935038) (xy 286.718502 -95.973392)
			(xy 286.710374 -96.165162) (xy 286.901636 -96.275652)
		)
		(stroke
			(width 0)
			(type solid)
		)
		(fill yes)
		(layer "In11.Cu")
		(net "M_F_DQS_DP<16>")
	)
	(gr_poly
		(pts
			(xy 287.063688 -93.200982) (xy 287.08604 -93.162374) (xy 286.7406 -92.963238) (xy 286.718502 -93.001592)
			(xy 286.710374 -93.193362) (xy 286.901636 -93.303852)
		)
		(stroke
			(width 0)
			(type solid)
		)
		(fill yes)
		(layer "In11.Cu")
		(net "M_F_DQ<58>")
	)
	(gr_poly
		(pts
			(xy 287.065212 -95.183198) (xy 287.087564 -95.14459) (xy 286.742124 -94.945454) (xy 286.720026 -94.983808)
			(xy 286.711898 -95.175578) (xy 286.90316 -95.286068)
		)
		(stroke
			(width 0)
			(type solid)
		)
		(fill yes)
		(layer "In11.Cu")
		(net "M_F_DQS_DN<7>")
	)
	(gr_poly
		(pts
			(xy 287.067498 -94.193868) (xy 287.08985 -94.155514) (xy 286.74441 -93.95587) (xy 286.722312 -93.994478)
			(xy 286.714184 -94.186248) (xy 286.905446 -94.296738)
		)
		(stroke
			(width 0)
			(type solid)
		)
		(fill yes)
		(layer "In11.Cu")
		(net "M_F_DQ<62>")
	)
	(gr_poly
		(pts
			(xy 287.069022 -104.100884) (xy 287.091374 -104.06253) (xy 286.746188 -103.862886) (xy 286.723836 -103.901748)
			(xy 286.715708 -104.093518) (xy 286.907224 -104.203754)
		)
		(stroke
			(width 0)
			(type solid)
		)
		(fill yes)
		(layer "In11.Cu")
		(net "M_F_DQ<60>")
	)
	(gr_poly
		(pts
			(xy 287.165034 -99.107244) (xy 287.165034 -98.886264) (xy 286.994854 -98.797364) (xy 286.950404 -98.797364)
			(xy 286.950404 -99.196144) (xy 286.994854 -99.196144)
		)
		(stroke
			(width 0)
			(type solid)
		)
		(fill yes)
		(layer "In11.Cu")
		(net "M_F_DQ<61>")
	)
	(gr_poly
		(pts
			(xy 287.165288 -103.062278) (xy 287.165288 -102.841298) (xy 286.995108 -102.752398) (xy 286.950658 -102.752398)
			(xy 286.950658 -103.151178) (xy 286.995108 -103.151178)
		)
		(stroke
			(width 0)
			(type solid)
		)
		(fill yes)
		(layer "In11.Cu")
		(net "M_F_DQ<61>")
	)
	(gr_poly
		(pts
			(xy 287.165288 -102.071678) (xy 287.165288 -101.850698) (xy 286.995108 -101.761798) (xy 286.950658 -101.761798)
			(xy 286.950658 -102.160578) (xy 286.995108 -102.160578)
		)
		(stroke
			(width 0)
			(type solid)
		)
		(fill yes)
		(layer "In11.Cu")
		(net "M_F_DQ<61>")
	)
	(gr_poly
		(pts
			(xy 287.165288 -101.081078) (xy 287.165288 -100.860098) (xy 286.995108 -100.771198) (xy 286.950658 -100.771198)
			(xy 286.950658 -101.169978) (xy 286.995108 -101.169978)
		)
		(stroke
			(width 0)
			(type solid)
		)
		(fill yes)
		(layer "In11.Cu")
		(net "M_F_DQ<61>")
	)
	(gr_poly
		(pts
			(xy 287.165288 -100.090478) (xy 287.165288 -99.869498) (xy 286.995108 -99.780598) (xy 286.950658 -99.780598)
			(xy 286.950658 -100.179378) (xy 286.995108 -100.179378)
		)
		(stroke
			(width 0)
			(type solid)
		)
		(fill yes)
		(layer "In11.Cu")
		(net "M_F_DQ<61>")
	)
	(gr_poly
		(pts
			(xy 287.165288 -98.116136) (xy 287.165288 -97.895156) (xy 286.995108 -97.806256) (xy 286.950658 -97.806256)
			(xy 286.950658 -98.205036) (xy 286.995108 -98.205036)
		)
		(stroke
			(width 0)
			(type solid)
		)
		(fill yes)
		(layer "In11.Cu")
		(net "M_F_DQ<61>")
	)
	(gr_poly
		(pts
			(xy 287.196276 -49.913032) (xy 287.122616 -49.713642) (xy 287.091374 -49.682146) (xy 286.803846 -49.969674)
			(xy 286.835342 -50.000916) (xy 287.034732 -50.074576)
		)
		(stroke
			(width 0)
			(type solid)
		)
		(fill yes)
		(layer "In11.Cu")
		(net "M_C_DQ<57>")
	)
	(gr_poly
		(pts
			(xy 287.201102 -63.636144) (xy 287.156652 -63.636144) (xy 286.986472 -63.725044) (xy 286.986472 -63.946024)
			(xy 287.156652 -64.034924) (xy 287.201102 -64.034924)
		)
		(stroke
			(width 0)
			(type solid)
		)
		(fill yes)
		(layer "In11.Cu")
		(net "M_C_DQS_DP<7>")
	)
	(gr_poly
		(pts
			(xy 287.201102 -62.645544) (xy 287.156652 -62.645544) (xy 286.986472 -62.734444) (xy 286.986472 -62.955424)
			(xy 287.156652 -63.044324) (xy 287.201102 -63.044324)
		)
		(stroke
			(width 0)
			(type solid)
		)
		(fill yes)
		(layer "In11.Cu")
		(net "M_C_DQS_DP<7>")
	)
	(gr_poly
		(pts
			(xy 287.201102 -61.654944) (xy 287.156652 -61.654944) (xy 286.986472 -61.743844) (xy 286.986472 -61.964824)
			(xy 287.156652 -62.053724) (xy 287.201102 -62.053724)
		)
		(stroke
			(width 0)
			(type solid)
		)
		(fill yes)
		(layer "In11.Cu")
		(net "M_C_DQS_DP<7>")
	)
	(gr_poly
		(pts
			(xy 287.201102 -60.664344) (xy 287.156652 -60.664344) (xy 286.986472 -60.753244) (xy 286.986472 -60.974224)
			(xy 287.156652 -61.063124) (xy 287.201102 -61.063124)
		)
		(stroke
			(width 0)
			(type solid)
		)
		(fill yes)
		(layer "In11.Cu")
		(net "M_C_DQS_DP<7>")
	)
	(gr_poly
		(pts
			(xy 287.201102 -59.667394) (xy 287.156652 -59.667394) (xy 286.986472 -59.756294) (xy 286.986472 -59.977274)
			(xy 287.156652 -60.066174) (xy 287.201102 -60.066174)
		)
		(stroke
			(width 0)
			(type solid)
		)
		(fill yes)
		(layer "In11.Cu")
		(net "M_C_DQS_DP<7>")
	)
	(gr_poly
		(pts
			(xy 287.201102 -58.670698) (xy 287.156652 -58.670698) (xy 286.986472 -58.759598) (xy 286.986472 -58.980578)
			(xy 287.156652 -59.069478) (xy 287.201102 -59.069478)
		)
		(stroke
			(width 0)
			(type solid)
		)
		(fill yes)
		(layer "In11.Cu")
		(net "M_C_DQS_DP<7>")
	)
	(gr_poly
		(pts
			(xy 287.201102 -57.692544) (xy 287.156652 -57.692544) (xy 286.986472 -57.781444) (xy 286.986472 -58.002424)
			(xy 287.156652 -58.091324) (xy 287.201102 -58.091324)
		)
		(stroke
			(width 0)
			(type solid)
		)
		(fill yes)
		(layer "In11.Cu")
		(net "M_C_DQS_DP<7>")
	)
	(gr_poly
		(pts
			(xy 287.201102 -56.701944) (xy 287.156652 -56.701944) (xy 286.986472 -56.790844) (xy 286.986472 -57.011824)
			(xy 287.156652 -57.100724) (xy 287.201102 -57.100724)
		)
		(stroke
			(width 0)
			(type solid)
		)
		(fill yes)
		(layer "In11.Cu")
		(net "M_C_DQS_DP<7>")
	)
	(gr_poly
		(pts
			(xy 287.201102 -55.711344) (xy 287.156652 -55.711344) (xy 286.986472 -55.800244) (xy 286.986472 -56.021224)
			(xy 287.156652 -56.110124) (xy 287.201102 -56.110124)
		)
		(stroke
			(width 0)
			(type solid)
		)
		(fill yes)
		(layer "In11.Cu")
		(net "M_C_DQS_DP<7>")
	)
	(gr_poly
		(pts
			(xy 287.201102 -54.720744) (xy 287.156652 -54.720744) (xy 286.986472 -54.809644) (xy 286.986472 -55.030624)
			(xy 287.156652 -55.119524) (xy 287.201102 -55.119524)
		)
		(stroke
			(width 0)
			(type solid)
		)
		(fill yes)
		(layer "In11.Cu")
		(net "M_C_DQS_DP<7>")
	)
	(gr_poly
		(pts
			(xy 287.201102 -53.723794) (xy 287.156652 -53.723794) (xy 286.986472 -53.812694) (xy 286.986472 -54.033674)
			(xy 287.156652 -54.122574) (xy 287.201102 -54.122574)
		)
		(stroke
			(width 0)
			(type solid)
		)
		(fill yes)
		(layer "In11.Cu")
		(net "M_C_DQS_DP<7>")
	)
	(gr_poly
		(pts
			(xy 287.320228 -50.397918) (xy 287.288732 -50.366676) (xy 287.089342 -50.293016) (xy 286.927798 -50.45456)
			(xy 287.001204 -50.65395) (xy 287.0327 -50.685446)
		)
		(stroke
			(width 0)
			(type solid)
		)
		(fill yes)
		(layer "In11.Cu")
		(net "M_C_DQS_DP<16>")
	)
	(gr_poly
		(pts
			(xy 287.40227 -52.748688) (xy 287.35782 -52.748688) (xy 287.16478 -52.837588) (xy 287.16478 -53.066188)
			(xy 287.35782 -53.155088) (xy 287.40227 -53.155088)
		)
		(stroke
			(width 0)
			(type solid)
		)
		(fill yes)
		(layer "In11.Cu")
		(net "M_C_DQS_DP<7>")
	)
	(gr_poly
		(pts
			(xy 287.40227 -51.758088) (xy 287.35782 -51.758088) (xy 287.16478 -51.846988) (xy 287.16478 -52.075588)
			(xy 287.35782 -52.164488) (xy 287.40227 -52.164488)
		)
		(stroke
			(width 0)
			(type solid)
		)
		(fill yes)
		(layer "In11.Cu")
		(net "M_C_DQS_DP<7>")
	)
	(gr_poly
		(pts
			(xy 287.485582 -102.752398) (xy 287.441132 -102.752398) (xy 287.270952 -102.841298) (xy 287.270952 -103.062278)
			(xy 287.441132 -103.151178) (xy 287.485582 -103.151178)
		)
		(stroke
			(width 0)
			(type solid)
		)
		(fill yes)
		(layer "In11.Cu")
		(net "M_F_DQ<56>")
	)
	(gr_poly
		(pts
			(xy 287.485582 -101.761798) (xy 287.441132 -101.761798) (xy 287.270952 -101.850698) (xy 287.270952 -102.071678)
			(xy 287.441132 -102.160578) (xy 287.485582 -102.160578)
		)
		(stroke
			(width 0)
			(type solid)
		)
		(fill yes)
		(layer "In11.Cu")
		(net "M_F_DQ<56>")
	)
	(gr_poly
		(pts
			(xy 287.485582 -100.771198) (xy 287.441132 -100.771198) (xy 287.270952 -100.860098) (xy 287.270952 -101.081078)
			(xy 287.441132 -101.169978) (xy 287.485582 -101.169978)
		)
		(stroke
			(width 0)
			(type solid)
		)
		(fill yes)
		(layer "In11.Cu")
		(net "M_F_DQ<56>")
	)
	(gr_poly
		(pts
			(xy 287.485582 -99.780598) (xy 287.441132 -99.780598) (xy 287.270952 -99.869498) (xy 287.270952 -100.090478)
			(xy 287.441132 -100.179378) (xy 287.485582 -100.179378)
		)
		(stroke
			(width 0)
			(type solid)
		)
		(fill yes)
		(layer "In11.Cu")
		(net "M_F_DQ<56>")
	)
	(gr_poly
		(pts
			(xy 287.485582 -98.789998) (xy 287.441132 -98.789998) (xy 287.270952 -98.878898) (xy 287.270952 -99.099878)
			(xy 287.441132 -99.188778) (xy 287.485582 -99.188778)
		)
		(stroke
			(width 0)
			(type solid)
		)
		(fill yes)
		(layer "In11.Cu")
		(net "M_F_DQ<56>")
	)
	(gr_poly
		(pts
			(xy 287.485582 -97.806002) (xy 287.441132 -97.806002) (xy 287.270952 -97.894902) (xy 287.270952 -98.115882)
			(xy 287.441132 -98.204782) (xy 287.485582 -98.204782)
		)
		(stroke
			(width 0)
			(type solid)
		)
		(fill yes)
		(layer "In11.Cu")
		(net "M_F_DQ<56>")
	)
	(gr_poly
		(pts
			(xy 287.577022 -50.746406) (xy 287.503616 -50.547016) (xy 287.47212 -50.51552) (xy 287.184592 -50.803048)
			(xy 287.216088 -50.83429) (xy 287.415478 -50.90795)
		)
		(stroke
			(width 0)
			(type solid)
		)
		(fill yes)
		(layer "In11.Cu")
		(net "M_C_DQS_DN<16>")
	)
	(gr_poly
		(pts
			(xy 287.713928 -94.090744) (xy 287.722056 -93.898974) (xy 287.530794 -93.788484) (xy 287.368742 -93.891354)
			(xy 287.34639 -93.929962) (xy 287.69183 -94.129098)
		)
		(stroke
			(width 0)
			(type solid)
		)
		(fill yes)
		(layer "In11.Cu")
		(net "M_F_DQ<63>")
	)
	(gr_poly
		(pts
			(xy 287.71596 -103.997506) (xy 287.724088 -103.805736) (xy 287.532826 -103.6955) (xy 287.370774 -103.79837)
			(xy 287.348676 -103.836724) (xy 287.694116 -104.036114)
		)
		(stroke
			(width 0)
			(type solid)
		)
		(fill yes)
		(layer "In11.Cu")
		(net "M_F_DQ<61>")
	)
	(gr_poly
		(pts
			(xy 287.71596 -97.063306) (xy 287.724088 -96.871536) (xy 287.532826 -96.7613) (xy 287.370774 -96.86417)
			(xy 287.348676 -96.902524) (xy 287.694116 -97.101914)
		)
		(stroke
			(width 0)
			(type solid)
		)
		(fill yes)
		(layer "In11.Cu")
		(net "M_F_DQ<57>")
	)
	(gr_poly
		(pts
			(xy 287.716214 -96.073214) (xy 287.724342 -95.881444) (xy 287.53308 -95.770954) (xy 287.371028 -95.873824)
			(xy 287.348676 -95.912178) (xy 287.694116 -96.111822)
		)
		(stroke
			(width 0)
			(type solid)
		)
		(fill yes)
		(layer "In11.Cu")
		(net "M_F_DQS_DN<16>")
	)
	(gr_poly
		(pts
			(xy 287.716214 -93.101414) (xy 287.724342 -92.909644) (xy 287.53308 -92.799154) (xy 287.371028 -92.902024)
			(xy 287.348676 -92.940378) (xy 287.694116 -93.140022)
		)
		(stroke
			(width 0)
			(type solid)
		)
		(fill yes)
		(layer "In11.Cu")
		(net "M_F_DQ<59>")
	)
	(gr_poly
		(pts
			(xy 287.717738 -95.083376) (xy 287.725866 -94.891606) (xy 287.534604 -94.781116) (xy 287.372552 -94.883986)
			(xy 287.3502 -94.922594) (xy 287.69564 -95.12173)
		)
		(stroke
			(width 0)
			(type solid)
		)
		(fill yes)
		(layer "In11.Cu")
		(net "M_F_DQS_DP<7>")
	)
	(gr_poly
		(pts
			(xy 287.73882 -64.441324) (xy 287.739074 -64.220344) (xy 287.56864 -64.131698) (xy 287.524444 -64.131698)
			(xy 287.52419 -64.530224) (xy 287.56864 -64.530224)
		)
		(stroke
			(width 0)
			(type solid)
		)
		(fill yes)
		(layer "In11.Cu")
		(net "M_C_DQS_DN<7>")
	)
	(gr_poly
		(pts
			(xy 287.739328 -63.438278) (xy 287.739328 -63.217298) (xy 287.569148 -63.128398) (xy 287.524698 -63.128398)
			(xy 287.524698 -63.527178) (xy 287.569148 -63.527178)
		)
		(stroke
			(width 0)
			(type solid)
		)
		(fill yes)
		(layer "In11.Cu")
		(net "M_C_DQS_DN<7>")
	)
	(gr_poly
		(pts
			(xy 287.739328 -62.447678) (xy 287.739328 -62.226698) (xy 287.569148 -62.137798) (xy 287.524698 -62.137798)
			(xy 287.524698 -62.536578) (xy 287.569148 -62.536578)
		)
		(stroke
			(width 0)
			(type solid)
		)
		(fill yes)
		(layer "In11.Cu")
		(net "M_C_DQS_DN<7>")
	)
	(gr_poly
		(pts
			(xy 287.739328 -61.457078) (xy 287.739328 -61.236098) (xy 287.569148 -61.147198) (xy 287.524698 -61.147198)
			(xy 287.524698 -61.545978) (xy 287.569148 -61.545978)
		)
		(stroke
			(width 0)
			(type solid)
		)
		(fill yes)
		(layer "In11.Cu")
		(net "M_C_DQS_DN<7>")
	)
	(gr_poly
		(pts
			(xy 287.739328 -60.466478) (xy 287.739328 -60.245498) (xy 287.569148 -60.156598) (xy 287.524698 -60.156598)
			(xy 287.524698 -60.555378) (xy 287.569148 -60.555378)
		)
		(stroke
			(width 0)
			(type solid)
		)
		(fill yes)
		(layer "In11.Cu")
		(net "M_C_DQS_DN<7>")
	)
	(gr_poly
		(pts
			(xy 287.739328 -59.488324) (xy 287.739328 -59.267344) (xy 287.569148 -59.178444) (xy 287.524698 -59.178444)
			(xy 287.524698 -59.577224) (xy 287.569148 -59.577224)
		)
		(stroke
			(width 0)
			(type solid)
		)
		(fill yes)
		(layer "In11.Cu")
		(net "M_C_DQS_DN<7>")
	)
	(gr_poly
		(pts
			(xy 287.739328 -58.491628) (xy 287.739328 -58.270648) (xy 287.569148 -58.181748) (xy 287.524698 -58.181748)
			(xy 287.524698 -58.580528) (xy 287.569148 -58.580528)
		)
		(stroke
			(width 0)
			(type solid)
		)
		(fill yes)
		(layer "In11.Cu")
		(net "M_C_DQS_DN<7>")
	)
	(gr_poly
		(pts
			(xy 287.739328 -57.494678) (xy 287.739328 -57.273698) (xy 287.569148 -57.184798) (xy 287.524698 -57.184798)
			(xy 287.524698 -57.583578) (xy 287.569148 -57.583578)
		)
		(stroke
			(width 0)
			(type solid)
		)
		(fill yes)
		(layer "In11.Cu")
		(net "M_C_DQS_DN<7>")
	)
	(gr_poly
		(pts
			(xy 287.739328 -56.504078) (xy 287.739328 -56.283098) (xy 287.569148 -56.194198) (xy 287.524698 -56.194198)
			(xy 287.524698 -56.592978) (xy 287.569148 -56.592978)
		)
		(stroke
			(width 0)
			(type solid)
		)
		(fill yes)
		(layer "In11.Cu")
		(net "M_C_DQS_DN<7>")
	)
	(gr_poly
		(pts
			(xy 287.739328 -55.513478) (xy 287.739328 -55.292498) (xy 287.569148 -55.203598) (xy 287.524698 -55.203598)
			(xy 287.524698 -55.602378) (xy 287.569148 -55.602378)
		)
		(stroke
			(width 0)
			(type solid)
		)
		(fill yes)
		(layer "In11.Cu")
		(net "M_C_DQS_DN<7>")
	)
	(gr_poly
		(pts
			(xy 287.739328 -54.522878) (xy 287.739328 -54.301898) (xy 287.569148 -54.212998) (xy 287.524698 -54.212998)
			(xy 287.524698 -54.611778) (xy 287.569148 -54.611778)
		)
		(stroke
			(width 0)
			(type solid)
		)
		(fill yes)
		(layer "In11.Cu")
		(net "M_C_DQS_DN<7>")
	)
	(gr_poly
		(pts
			(xy 287.83026 -53.193188) (xy 287.83026 -52.964588) (xy 287.63722 -52.875688) (xy 287.59277 -52.875688)
			(xy 287.59277 -53.282088) (xy 287.63722 -53.282088)
		)
		(stroke
			(width 0)
			(type solid)
		)
		(fill yes)
		(layer "In11.Cu")
		(net "M_C_DQS_DN<7>")
	)
	(gr_poly
		(pts
			(xy 287.83026 -52.202588) (xy 287.83026 -51.973988) (xy 287.63722 -51.885088) (xy 287.59277 -51.885088)
			(xy 287.59277 -52.291488) (xy 287.63722 -52.291488)
		)
		(stroke
			(width 0)
			(type solid)
		)
		(fill yes)
		(layer "In11.Cu")
		(net "M_C_DQS_DN<7>")
	)
	(gr_poly
		(pts
			(xy 287.922208 -94.687136) (xy 287.94456 -94.648782) (xy 287.59912 -94.449138) (xy 287.577022 -94.487746)
			(xy 287.568894 -94.679516) (xy 287.760156 -94.790006)
		)
		(stroke
			(width 0)
			(type solid)
		)
		(fill yes)
		(layer "In11.Cu")
		(net "M_F_DQ<62>")
	)
	(gr_poly
		(pts
			(xy 287.923732 -96.669098) (xy 287.946084 -96.63049) (xy 287.600644 -96.431354) (xy 287.578546 -96.469708)
			(xy 287.570418 -96.661478) (xy 287.76168 -96.771968)
		)
		(stroke
			(width 0)
			(type solid)
		)
		(fill yes)
		(layer "In11.Cu")
		(net "M_F_DQS_DP<16>")
	)
	(gr_poly
		(pts
			(xy 287.923732 -93.697298) (xy 287.946084 -93.65869) (xy 287.600644 -93.459554) (xy 287.578546 -93.497908)
			(xy 287.570418 -93.689678) (xy 287.76168 -93.800168)
		)
		(stroke
			(width 0)
			(type solid)
		)
		(fill yes)
		(layer "In11.Cu")
		(net "M_F_DQ<58>")
	)
	(gr_poly
		(pts
			(xy 287.923986 -103.603552) (xy 287.946338 -103.565198) (xy 287.600898 -103.365554) (xy 287.5788 -103.404416)
			(xy 287.570672 -103.596186) (xy 287.761934 -103.706422)
		)
		(stroke
			(width 0)
			(type solid)
		)
		(fill yes)
		(layer "In11.Cu")
		(net "M_F_DQ<56>")
	)
	(gr_poly
		(pts
			(xy 287.926018 -95.679768) (xy 287.94837 -95.641414) (xy 287.60293 -95.44177) (xy 287.580832 -95.480378)
			(xy 287.572704 -95.672148) (xy 287.763966 -95.782638)
		)
		(stroke
			(width 0)
			(type solid)
		)
		(fill yes)
		(layer "In11.Cu")
		(net "M_F_DQS_DN<7>")
	)
	(gr_poly
		(pts
			(xy 288.023554 -98.610928) (xy 288.023554 -98.389948) (xy 287.853374 -98.301048) (xy 287.808924 -98.301048)
			(xy 287.808924 -98.699828) (xy 287.853374 -98.699828)
		)
		(stroke
			(width 0)
			(type solid)
		)
		(fill yes)
		(layer "In11.Cu")
		(net "M_F_DQ<57>")
	)
	(gr_poly
		(pts
			(xy 288.023554 -97.620328) (xy 288.023554 -97.399348) (xy 287.853374 -97.310448) (xy 287.808924 -97.310448)
			(xy 287.808924 -97.709228) (xy 287.853374 -97.709228)
		)
		(stroke
			(width 0)
			(type solid)
		)
		(fill yes)
		(layer "In11.Cu")
		(net "M_F_DQ<57>")
	)
	(gr_poly
		(pts
			(xy 288.023808 -104.560624) (xy 288.023808 -104.339644) (xy 287.853628 -104.250744) (xy 287.809178 -104.250744)
			(xy 287.809178 -104.649524) (xy 287.853628 -104.649524)
		)
		(stroke
			(width 0)
			(type solid)
		)
		(fill yes)
		(layer "In11.Cu")
		(net "M_F_DQ<61>")
	)
	(gr_poly
		(pts
			(xy 288.023808 -102.579424) (xy 288.023808 -102.358444) (xy 287.853628 -102.269544) (xy 287.809178 -102.269544)
			(xy 287.809178 -102.668324) (xy 287.853628 -102.668324)
		)
		(stroke
			(width 0)
			(type solid)
		)
		(fill yes)
		(layer "In11.Cu")
		(net "M_F_DQ<57>")
	)
	(gr_poly
		(pts
			(xy 288.023808 -101.588824) (xy 288.023808 -101.367844) (xy 287.853628 -101.278944) (xy 287.809178 -101.278944)
			(xy 287.809178 -101.677724) (xy 287.853628 -101.677724)
		)
		(stroke
			(width 0)
			(type solid)
		)
		(fill yes)
		(layer "In11.Cu")
		(net "M_F_DQ<57>")
	)
	(gr_poly
		(pts
			(xy 288.023808 -100.598224) (xy 288.023808 -100.377244) (xy 287.853628 -100.288344) (xy 287.809178 -100.288344)
			(xy 287.809178 -100.687124) (xy 287.853628 -100.687124)
		)
		(stroke
			(width 0)
			(type solid)
		)
		(fill yes)
		(layer "In11.Cu")
		(net "M_F_DQ<57>")
	)
	(gr_poly
		(pts
			(xy 288.023808 -99.607624) (xy 288.023808 -99.386644) (xy 287.853628 -99.297744) (xy 287.809178 -99.297744)
			(xy 287.809178 -99.696524) (xy 287.853628 -99.696524)
		)
		(stroke
			(width 0)
			(type solid)
		)
		(fill yes)
		(layer "In11.Cu")
		(net "M_F_DQ<57>")
	)
	(gr_poly
		(pts
			(xy 288.059622 -60.156598) (xy 288.015172 -60.156598) (xy 287.844992 -60.245498) (xy 287.844992 -60.466478)
			(xy 288.015172 -60.555378) (xy 288.059622 -60.555378)
		)
		(stroke
			(width 0)
			(type solid)
		)
		(fill yes)
		(layer "In11.Cu")
		(net "M_C_DQ<62>")
	)
	(gr_poly
		(pts
			(xy 288.059622 -59.178444) (xy 288.015172 -59.178444) (xy 287.844992 -59.267344) (xy 287.844992 -59.488324)
			(xy 288.015172 -59.577224) (xy 288.059622 -59.577224)
		)
		(stroke
			(width 0)
			(type solid)
		)
		(fill yes)
		(layer "In11.Cu")
		(net "M_C_DQ<62>")
	)
	(gr_poly
		(pts
			(xy 288.059622 -58.181748) (xy 288.015172 -58.181748) (xy 287.844992 -58.270648) (xy 287.844992 -58.491628)
			(xy 288.015172 -58.580528) (xy 288.059622 -58.580528)
		)
		(stroke
			(width 0)
			(type solid)
		)
		(fill yes)
		(layer "In11.Cu")
		(net "M_C_DQ<62>")
	)
	(gr_poly
		(pts
			(xy 288.059622 -57.184798) (xy 288.015172 -57.184798) (xy 287.844992 -57.273698) (xy 287.844992 -57.494678)
			(xy 288.015172 -57.583578) (xy 288.059622 -57.583578)
		)
		(stroke
			(width 0)
			(type solid)
		)
		(fill yes)
		(layer "In11.Cu")
		(net "M_C_DQ<62>")
	)
	(gr_poly
		(pts
			(xy 288.059622 -56.194198) (xy 288.015172 -56.194198) (xy 287.844992 -56.283098) (xy 287.844992 -56.504078)
			(xy 288.015172 -56.592978) (xy 288.059622 -56.592978)
		)
		(stroke
			(width 0)
			(type solid)
		)
		(fill yes)
		(layer "In11.Cu")
		(net "M_C_DQ<62>")
	)
	(gr_poly
		(pts
			(xy 288.059622 -55.203598) (xy 288.015172 -55.203598) (xy 287.844992 -55.292498) (xy 287.844992 -55.513478)
			(xy 288.015172 -55.602378) (xy 288.059622 -55.602378)
		)
		(stroke
			(width 0)
			(type solid)
		)
		(fill yes)
		(layer "In11.Cu")
		(net "M_C_DQ<62>")
	)
	(gr_poly
		(pts
			(xy 288.059622 -54.212998) (xy 288.015172 -54.212998) (xy 287.844992 -54.301898) (xy 287.844992 -54.522878)
			(xy 288.015172 -54.611778) (xy 288.059622 -54.611778)
		)
		(stroke
			(width 0)
			(type solid)
		)
		(fill yes)
		(layer "In11.Cu")
		(net "M_C_DQ<62>")
	)
	(gr_poly
		(pts
			(xy 288.059876 -62.144148) (xy 288.015426 -62.144148) (xy 287.845246 -62.233048) (xy 287.845246 -62.454028)
			(xy 288.015426 -62.542928) (xy 288.059876 -62.542928)
		)
		(stroke
			(width 0)
			(type solid)
		)
		(fill yes)
		(layer "In11.Cu")
		(net "M_C_DQ<62>")
	)
	(gr_poly
		(pts
			(xy 288.059876 -61.153548) (xy 288.015426 -61.153548) (xy 287.845246 -61.242448) (xy 287.845246 -61.463428)
			(xy 288.015426 -61.552328) (xy 288.059876 -61.552328)
		)
		(stroke
			(width 0)
			(type solid)
		)
		(fill yes)
		(layer "In11.Cu")
		(net "M_C_DQ<62>")
	)
	(gr_poly
		(pts
			(xy 288.059876 -53.233574) (xy 288.015426 -53.233574) (xy 287.845246 -53.322474) (xy 287.845246 -53.543454)
			(xy 288.015426 -53.632354) (xy 288.059876 -53.632354)
		)
		(stroke
			(width 0)
			(type solid)
		)
		(fill yes)
		(layer "In11.Cu")
		(net "M_C_DQ<62>")
	)
	(gr_poly
		(pts
			(xy 288.344102 -102.269544) (xy 288.299652 -102.269544) (xy 288.129472 -102.358444) (xy 288.129472 -102.579424)
			(xy 288.299652 -102.668324) (xy 288.344102 -102.668324)
		)
		(stroke
			(width 0)
			(type solid)
		)
		(fill yes)
		(layer "In11.Cu")
		(net "M_F_DQS_DP<16>")
	)
	(gr_poly
		(pts
			(xy 288.344102 -101.278944) (xy 288.299652 -101.278944) (xy 288.129472 -101.367844) (xy 288.129472 -101.588824)
			(xy 288.299652 -101.677724) (xy 288.344102 -101.677724)
		)
		(stroke
			(width 0)
			(type solid)
		)
		(fill yes)
		(layer "In11.Cu")
		(net "M_F_DQS_DP<16>")
	)
	(gr_poly
		(pts
			(xy 288.344102 -100.282248) (xy 288.299652 -100.282248) (xy 288.129472 -100.371148) (xy 288.129472 -100.592128)
			(xy 288.299652 -100.681028) (xy 288.344102 -100.681028)
		)
		(stroke
			(width 0)
			(type solid)
		)
		(fill yes)
		(layer "In11.Cu")
		(net "M_F_DQS_DP<16>")
	)
	(gr_poly
		(pts
			(xy 288.344102 -99.297744) (xy 288.299652 -99.297744) (xy 288.129472 -99.386644) (xy 288.129472 -99.607624)
			(xy 288.299652 -99.696524) (xy 288.344102 -99.696524)
		)
		(stroke
			(width 0)
			(type solid)
		)
		(fill yes)
		(layer "In11.Cu")
		(net "M_F_DQS_DP<16>")
	)
	(gr_poly
		(pts
			(xy 288.344102 -98.307144) (xy 288.299652 -98.307144) (xy 288.129472 -98.396044) (xy 288.129472 -98.617024)
			(xy 288.299652 -98.705924) (xy 288.344102 -98.705924)
		)
		(stroke
			(width 0)
			(type solid)
		)
		(fill yes)
		(layer "In11.Cu")
		(net "M_F_DQS_DP<16>")
	)
	(gr_poly
		(pts
			(xy 288.344102 -97.316544) (xy 288.299652 -97.316544) (xy 288.129472 -97.405444) (xy 288.129472 -97.626424)
			(xy 288.299652 -97.715324) (xy 288.344102 -97.715324)
		)
		(stroke
			(width 0)
			(type solid)
		)
		(fill yes)
		(layer "In11.Cu")
		(net "M_F_DQS_DP<16>")
	)
	(gr_poly
		(pts
			(xy 288.467546 -50.16627) (xy 288.39414 -49.96688) (xy 288.362644 -49.935384) (xy 288.075116 -50.222912)
			(xy 288.106612 -50.254154) (xy 288.306002 -50.327814)
		)
		(stroke
			(width 0)
			(type solid)
		)
		(fill yes)
		(layer "In11.Cu")
		(net "M_C_DQS_DN<16>")
	)
	(gr_poly
		(pts
			(xy 288.570924 -103.500174) (xy 288.579052 -103.308404) (xy 288.387536 -103.198168) (xy 288.225738 -103.301038)
			(xy 288.203132 -103.339392) (xy 288.548572 -103.539036)
		)
		(stroke
			(width 0)
			(type solid)
		)
		(fill yes)
		(layer "In11.Cu")
		(net "M_F_DQ<57>")
	)
	(gr_poly
		(pts
			(xy 288.570924 -96.565974) (xy 288.579052 -96.374204) (xy 288.387536 -96.263968) (xy 288.225738 -96.366838)
			(xy 288.203132 -96.405192) (xy 288.548572 -96.604836)
		)
		(stroke
			(width 0)
			(type solid)
		)
		(fill yes)
		(layer "In11.Cu")
		(net "M_F_DQS_DN<16>")
	)
	(gr_poly
		(pts
			(xy 288.572448 -95.576644) (xy 288.580576 -95.384874) (xy 288.389314 -95.274384) (xy 288.227262 -95.377254)
			(xy 288.20491 -95.415862) (xy 288.55035 -95.614998)
		)
		(stroke
			(width 0)
			(type solid)
		)
		(fill yes)
		(layer "In11.Cu")
		(net "M_F_DQS_DP<7>")
	)
	(gr_poly
		(pts
			(xy 288.574734 -94.587314) (xy 288.582862 -94.395544) (xy 288.3916 -94.285054) (xy 288.229548 -94.387924)
			(xy 288.207196 -94.426278) (xy 288.552636 -94.625922)
		)
		(stroke
			(width 0)
			(type solid)
		)
		(fill yes)
		(layer "In11.Cu")
		(net "M_F_DQ<63>")
	)
	(gr_poly
		(pts
			(xy 288.576258 -93.59773) (xy 288.584386 -93.40596) (xy 288.393124 -93.29547) (xy 288.231072 -93.39834)
			(xy 288.20872 -93.436694) (xy 288.55416 -93.636338)
		)
		(stroke
			(width 0)
			(type solid)
		)
		(fill yes)
		(layer "In11.Cu")
		(net "M_F_DQ<59>")
	)
	(gr_poly
		(pts
			(xy 288.597848 -62.949328) (xy 288.597848 -62.728348) (xy 288.427668 -62.639448) (xy 288.383218 -62.639448)
			(xy 288.383218 -63.038228) (xy 288.427668 -63.038228)
		)
		(stroke
			(width 0)
			(type solid)
		)
		(fill yes)
		(layer "In11.Cu")
		(net "M_C_DQ<63>")
	)
	(gr_poly
		(pts
			(xy 288.597848 -61.958728) (xy 288.597848 -61.737748) (xy 288.427668 -61.648848) (xy 288.383218 -61.648848)
			(xy 288.383218 -62.047628) (xy 288.427668 -62.047628)
		)
		(stroke
			(width 0)
			(type solid)
		)
		(fill yes)
		(layer "In11.Cu")
		(net "M_C_DQ<63>")
	)
	(gr_poly
		(pts
			(xy 288.597848 -60.974224) (xy 288.597848 -60.753244) (xy 288.427668 -60.664344) (xy 288.383218 -60.664344)
			(xy 288.383218 -61.063124) (xy 288.427668 -61.063124)
		)
		(stroke
			(width 0)
			(type solid)
		)
		(fill yes)
		(layer "In11.Cu")
		(net "M_C_DQ<63>")
	)
	(gr_poly
		(pts
			(xy 288.597848 -59.977274) (xy 288.597848 -59.756294) (xy 288.427668 -59.667394) (xy 288.383218 -59.667394)
			(xy 288.383218 -60.066174) (xy 288.427668 -60.066174)
		)
		(stroke
			(width 0)
			(type solid)
		)
		(fill yes)
		(layer "In11.Cu")
		(net "M_C_DQ<63>")
	)
	(gr_poly
		(pts
			(xy 288.597848 -58.980578) (xy 288.597848 -58.759598) (xy 288.427668 -58.670698) (xy 288.383218 -58.670698)
			(xy 288.383218 -59.069478) (xy 288.427668 -59.069478)
		)
		(stroke
			(width 0)
			(type solid)
		)
		(fill yes)
		(layer "In11.Cu")
		(net "M_C_DQ<63>")
	)
	(gr_poly
		(pts
			(xy 288.597848 -58.002424) (xy 288.597848 -57.781444) (xy 288.427668 -57.692544) (xy 288.383218 -57.692544)
			(xy 288.383218 -58.091324) (xy 288.427668 -58.091324)
		)
		(stroke
			(width 0)
			(type solid)
		)
		(fill yes)
		(layer "In11.Cu")
		(net "M_C_DQ<63>")
	)
	(gr_poly
		(pts
			(xy 288.597848 -57.011824) (xy 288.597848 -56.790844) (xy 288.427668 -56.701944) (xy 288.383218 -56.701944)
			(xy 288.383218 -57.100724) (xy 288.427668 -57.100724)
		)
		(stroke
			(width 0)
			(type solid)
		)
		(fill yes)
		(layer "In11.Cu")
		(net "M_C_DQ<63>")
	)
	(gr_poly
		(pts
			(xy 288.597848 -56.021224) (xy 288.597848 -55.800244) (xy 288.427668 -55.711344) (xy 288.383218 -55.711344)
			(xy 288.383218 -56.110124) (xy 288.427668 -56.110124)
		)
		(stroke
			(width 0)
			(type solid)
		)
		(fill yes)
		(layer "In11.Cu")
		(net "M_C_DQ<63>")
	)
	(gr_poly
		(pts
			(xy 288.597848 -55.030624) (xy 288.597848 -54.809644) (xy 288.427668 -54.720744) (xy 288.383218 -54.720744)
			(xy 288.383218 -55.119524) (xy 288.427668 -55.119524)
		)
		(stroke
			(width 0)
			(type solid)
		)
		(fill yes)
		(layer "In11.Cu")
		(net "M_C_DQ<63>")
	)
	(gr_poly
		(pts
			(xy 288.597848 -54.033674) (xy 288.597848 -53.812694) (xy 288.427668 -53.723794) (xy 288.383218 -53.723794)
			(xy 288.383218 -54.122574) (xy 288.427668 -54.122574)
		)
		(stroke
			(width 0)
			(type solid)
		)
		(fill yes)
		(layer "In11.Cu")
		(net "M_C_DQ<63>")
	)
	(gr_poly
		(pts
			(xy 288.608008 -104.008428) (xy 288.639504 -103.976932) (xy 288.356548 -103.695754) (xy 288.325306 -103.727504)
			(xy 288.26841 -103.910892) (xy 288.425128 -104.06634)
		)
		(stroke
			(width 0)
			(type solid)
		)
		(fill yes)
		(layer "In11.Cu")
		(net "M_F_DQ<56>")
	)
	(gr_poly
		(pts
			(xy 288.712148 -97.218246) (xy 288.882328 -97.129346) (xy 288.882074 -96.90862) (xy 288.712148 -96.81972)
			(xy 288.667444 -96.819466) (xy 288.667444 -97.2185)
		)
		(stroke
			(width 0)
			(type solid)
		)
		(fill yes)
		(layer "In11.Cu")
		(net "M_F_DQS_DN<16>")
	)
	(gr_poly
		(pts
			(xy 288.780728 -103.106982) (xy 288.80308 -103.068628) (xy 288.45764 -102.868984) (xy 288.435542 -102.907592)
			(xy 288.427414 -103.099362) (xy 288.618676 -103.209852)
		)
		(stroke
			(width 0)
			(type solid)
		)
		(fill yes)
		(layer "In11.Cu")
		(net "M_F_DQS_DP<16>")
	)
	(gr_poly
		(pts
			(xy 288.780728 -96.172782) (xy 288.80308 -96.134174) (xy 288.45764 -95.935038) (xy 288.435542 -95.973392)
			(xy 288.427414 -96.165162) (xy 288.618676 -96.275652)
		)
		(stroke
			(width 0)
			(type solid)
		)
		(fill yes)
		(layer "In11.Cu")
		(net "M_F_DQS_DN<7>")
	)
	(gr_poly
		(pts
			(xy 288.782252 -95.183198) (xy 288.804604 -95.14459) (xy 288.459164 -94.945454) (xy 288.437066 -94.983808)
			(xy 288.428938 -95.175578) (xy 288.6202 -95.286068)
		)
		(stroke
			(width 0)
			(type solid)
		)
		(fill yes)
		(layer "In11.Cu")
		(net "M_F_DQ<62>")
	)
	(gr_poly
		(pts
			(xy 288.784538 -94.193868) (xy 288.80689 -94.155514) (xy 288.46145 -93.95587) (xy 288.439352 -93.994478)
			(xy 288.431224 -94.186248) (xy 288.622486 -94.296738)
		)
		(stroke
			(width 0)
			(type solid)
		)
		(fill yes)
		(layer "In11.Cu")
		(net "M_F_DQ<58>")
	)
	(gr_poly
		(pts
			(xy 288.882328 -102.071678) (xy 288.882328 -101.850698) (xy 288.712148 -101.761798) (xy 288.667698 -101.761798)
			(xy 288.667698 -102.160578) (xy 288.712148 -102.160578)
		)
		(stroke
			(width 0)
			(type solid)
		)
		(fill yes)
		(layer "In11.Cu")
		(net "M_F_DQS_DN<16>")
	)
	(gr_poly
		(pts
			(xy 288.882328 -101.081078) (xy 288.882328 -100.860098) (xy 288.712148 -100.771198) (xy 288.667698 -100.771198)
			(xy 288.667698 -101.169978) (xy 288.712148 -101.169978)
		)
		(stroke
			(width 0)
			(type solid)
		)
		(fill yes)
		(layer "In11.Cu")
		(net "M_F_DQS_DN<16>")
	)
	(gr_poly
		(pts
			(xy 288.882328 -100.096828) (xy 288.882328 -99.875848) (xy 288.712148 -99.786948) (xy 288.667698 -99.786948)
			(xy 288.667698 -100.185728) (xy 288.712148 -100.185728)
		)
		(stroke
			(width 0)
			(type solid)
		)
		(fill yes)
		(layer "In11.Cu")
		(net "M_F_DQS_DN<16>")
	)
	(gr_poly
		(pts
			(xy 288.882328 -99.099878) (xy 288.882328 -98.878898) (xy 288.712148 -98.789998) (xy 288.667698 -98.789998)
			(xy 288.667698 -99.188778) (xy 288.712148 -99.188778)
		)
		(stroke
			(width 0)
			(type solid)
		)
		(fill yes)
		(layer "In11.Cu")
		(net "M_F_DQS_DN<16>")
	)
	(gr_poly
		(pts
			(xy 288.882328 -98.109278) (xy 288.882328 -97.888298) (xy 288.712148 -97.799398) (xy 288.667698 -97.799398)
			(xy 288.667698 -98.198178) (xy 288.712148 -98.198178)
		)
		(stroke
			(width 0)
			(type solid)
		)
		(fill yes)
		(layer "In11.Cu")
		(net "M_F_DQS_DN<16>")
	)
	(gr_poly
		(pts
			(xy 288.918142 -59.667394) (xy 288.873692 -59.667394) (xy 288.703512 -59.756294) (xy 288.703512 -59.977274)
			(xy 288.873692 -60.066174) (xy 288.918142 -60.066174)
		)
		(stroke
			(width 0)
			(type solid)
		)
		(fill yes)
		(layer "In11.Cu")
		(net "M_C_DQ<58>")
	)
	(gr_poly
		(pts
			(xy 288.918142 -58.670698) (xy 288.873692 -58.670698) (xy 288.703512 -58.759598) (xy 288.703512 -58.980578)
			(xy 288.873692 -59.069478) (xy 288.918142 -59.069478)
		)
		(stroke
			(width 0)
			(type solid)
		)
		(fill yes)
		(layer "In11.Cu")
		(net "M_C_DQ<58>")
	)
	(gr_poly
		(pts
			(xy 288.918142 -57.692544) (xy 288.873692 -57.692544) (xy 288.703512 -57.781444) (xy 288.703512 -58.002424)
			(xy 288.873692 -58.091324) (xy 288.918142 -58.091324)
		)
		(stroke
			(width 0)
			(type solid)
		)
		(fill yes)
		(layer "In11.Cu")
		(net "M_C_DQ<58>")
	)
	(gr_poly
		(pts
			(xy 288.918142 -56.701944) (xy 288.873692 -56.701944) (xy 288.703512 -56.790844) (xy 288.703512 -57.011824)
			(xy 288.873692 -57.100724) (xy 288.918142 -57.100724)
		)
		(stroke
			(width 0)
			(type solid)
		)
		(fill yes)
		(layer "In11.Cu")
		(net "M_C_DQ<58>")
	)
	(gr_poly
		(pts
			(xy 288.918142 -55.711344) (xy 288.873692 -55.711344) (xy 288.703512 -55.800244) (xy 288.703512 -56.021224)
			(xy 288.873692 -56.110124) (xy 288.918142 -56.110124)
		)
		(stroke
			(width 0)
			(type solid)
		)
		(fill yes)
		(layer "In11.Cu")
		(net "M_C_DQ<58>")
	)
	(gr_poly
		(pts
			(xy 288.918142 -54.720744) (xy 288.873692 -54.720744) (xy 288.703512 -54.809644) (xy 288.703512 -55.030624)
			(xy 288.873692 -55.119524) (xy 288.918142 -55.119524)
		)
		(stroke
			(width 0)
			(type solid)
		)
		(fill yes)
		(layer "In11.Cu")
		(net "M_C_DQ<58>")
	)
	(gr_poly
		(pts
			(xy 288.918142 -53.730144) (xy 288.873692 -53.730144) (xy 288.703512 -53.819044) (xy 288.703512 -54.040024)
			(xy 288.873692 -54.128924) (xy 288.918142 -54.128924)
		)
		(stroke
			(width 0)
			(type solid)
		)
		(fill yes)
		(layer "In11.Cu")
		(net "M_C_DQ<58>")
	)
	(gr_poly
		(pts
			(xy 288.921952 -62.63894) (xy 288.877502 -62.63894) (xy 288.707322 -62.72784) (xy 288.707322 -62.94882)
			(xy 288.877502 -63.03772) (xy 288.921952 -63.03772)
		)
		(stroke
			(width 0)
			(type solid)
		)
		(fill yes)
		(layer "In11.Cu")
		(net "M_C_DQ<58>")
	)
	(gr_poly
		(pts
			(xy 288.921952 -61.64834) (xy 288.877502 -61.64834) (xy 288.707322 -61.73724) (xy 288.707322 -61.95822)
			(xy 288.877502 -62.04712) (xy 288.921952 -62.04712)
		)
		(stroke
			(width 0)
			(type solid)
		)
		(fill yes)
		(layer "In11.Cu")
		(net "M_C_DQ<58>")
	)
	(gr_poly
		(pts
			(xy 288.922968 -60.664344) (xy 288.878518 -60.664344) (xy 288.708338 -60.753244) (xy 288.708338 -60.974224)
			(xy 288.878518 -61.063124) (xy 288.922968 -61.063124)
		)
		(stroke
			(width 0)
			(type solid)
		)
		(fill yes)
		(layer "In11.Cu")
		(net "M_C_DQ<58>")
	)
	(gr_poly
		(pts
			(xy 289.121342 -51.710844) (xy 289.089846 -51.679348) (xy 288.89071 -51.605688) (xy 288.728912 -51.767486)
			(xy 288.802572 -51.966622) (xy 288.834068 -51.998118)
		)
		(stroke
			(width 0)
			(type solid)
		)
		(fill yes)
		(layer "In11.Cu")
		(net "M_C_DQ<62>")
	)
	(gr_poly
		(pts
			(xy 289.142678 -104.732582) (xy 289.142678 -104.503982) (xy 288.949638 -104.415082) (xy 288.905188 -104.415082)
			(xy 288.905188 -104.821482) (xy 288.949638 -104.821482)
		)
		(stroke
			(width 0)
			(type solid)
		)
		(fill yes)
		(layer "In11.Cu")
		(net "M_F_DQ<57>")
	)
	(gr_poly
		(pts
			(xy 289.202622 -101.774244) (xy 289.158172 -101.774244) (xy 288.987992 -101.863144) (xy 288.987992 -102.084124)
			(xy 289.158172 -102.173024) (xy 289.202622 -102.173024)
		)
		(stroke
			(width 0)
			(type solid)
		)
		(fill yes)
		(layer "In11.Cu")
		(net "M_F_DQS_DN<7>")
	)
	(gr_poly
		(pts
			(xy 289.202622 -100.783644) (xy 289.158172 -100.783644) (xy 288.987992 -100.872544) (xy 288.987992 -101.093524)
			(xy 289.158172 -101.182424) (xy 289.202622 -101.182424)
		)
		(stroke
			(width 0)
			(type solid)
		)
		(fill yes)
		(layer "In11.Cu")
		(net "M_F_DQS_DN<7>")
	)
	(gr_poly
		(pts
			(xy 289.202622 -99.786948) (xy 289.158172 -99.786948) (xy 288.987992 -99.875848) (xy 288.987992 -100.096828)
			(xy 289.158172 -100.185728) (xy 289.202622 -100.185728)
		)
		(stroke
			(width 0)
			(type solid)
		)
		(fill yes)
		(layer "In11.Cu")
		(net "M_F_DQS_DN<7>")
	)
	(gr_poly
		(pts
			(xy 289.202622 -98.789998) (xy 289.158172 -98.789998) (xy 288.987992 -98.878898) (xy 288.987992 -99.099878)
			(xy 289.158172 -99.188778) (xy 289.202622 -99.188778)
		)
		(stroke
			(width 0)
			(type solid)
		)
		(fill yes)
		(layer "In11.Cu")
		(net "M_F_DQS_DN<7>")
	)
	(gr_poly
		(pts
			(xy 289.202622 -97.806256) (xy 289.158172 -97.806256) (xy 288.987992 -97.895156) (xy 288.987992 -98.116136)
			(xy 289.158172 -98.205036) (xy 289.202622 -98.205036)
		)
		(stroke
			(width 0)
			(type solid)
		)
		(fill yes)
		(layer "In11.Cu")
		(net "M_F_DQS_DN<7>")
	)
	(gr_poly
		(pts
			(xy 289.202622 -96.808798) (xy 289.158172 -96.808798) (xy 288.987992 -96.897698) (xy 288.987992 -97.118678)
			(xy 289.158172 -97.207578) (xy 289.202622 -97.207578)
		)
		(stroke
			(width 0)
			(type solid)
		)
		(fill yes)
		(layer "In11.Cu")
		(net "M_F_DQS_DN<7>")
	)
	(gr_poly
		(pts
			(xy 289.38601 -52.05349) (xy 289.31235 -51.854354) (xy 289.280854 -51.822858) (xy 288.99358 -52.110132)
			(xy 289.025076 -52.141628) (xy 289.224212 -52.215288)
		)
		(stroke
			(width 0)
			(type solid)
		)
		(fill yes)
		(layer "In11.Cu")
		(net "M_C_DQ<63>")
	)
	(gr_poly
		(pts
			(xy 289.430968 -94.090744) (xy 289.439096 -93.898974) (xy 289.247834 -93.788484) (xy 289.085782 -93.891354)
			(xy 289.06343 -93.929962) (xy 289.40887 -94.129098)
		)
		(stroke
			(width 0)
			(type solid)
		)
		(fill yes)
		(layer "In11.Cu")
		(net "M_F_DQ<59>")
	)
	(gr_poly
		(pts
			(xy 289.433 -96.072706) (xy 289.441128 -95.880936) (xy 289.249866 -95.7707) (xy 289.087814 -95.87357)
			(xy 289.065462 -95.911924) (xy 289.410902 -96.111568)
		)
		(stroke
			(width 0)
			(type solid)
		)
		(fill yes)
		(layer "In11.Cu")
		(net "M_F_DQS_DP<7>")
	)
	(gr_poly
		(pts
			(xy 289.433254 -103.007414) (xy 289.441382 -102.815644) (xy 289.25012 -102.705154) (xy 289.088068 -102.808024)
			(xy 289.065716 -102.846378) (xy 289.411156 -103.046022)
		)
		(stroke
			(width 0)
			(type solid)
		)
		(fill yes)
		(layer "In11.Cu")
		(net "M_F_DQS_DN<16>")
	)
	(gr_poly
		(pts
			(xy 289.434778 -95.083376) (xy 289.442906 -94.891606) (xy 289.251644 -94.781116) (xy 289.089592 -94.883986)
			(xy 289.06724 -94.922594) (xy 289.41268 -95.12173)
		)
		(stroke
			(width 0)
			(type solid)
		)
		(fill yes)
		(layer "In11.Cu")
		(net "M_F_DQ<63>")
	)
	(gr_poly
		(pts
			(xy 289.456368 -60.466478) (xy 289.456368 -60.245498) (xy 289.286188 -60.156598) (xy 289.241738 -60.156598)
			(xy 289.241738 -60.555378) (xy 289.286188 -60.555378)
		)
		(stroke
			(width 0)
			(type solid)
		)
		(fill yes)
		(layer "In11.Cu")
		(net "M_C_DQ<59>")
	)
	(gr_poly
		(pts
			(xy 289.456368 -59.488324) (xy 289.456368 -59.267344) (xy 289.286188 -59.178444) (xy 289.241738 -59.178444)
			(xy 289.241738 -59.577224) (xy 289.286188 -59.577224)
		)
		(stroke
			(width 0)
			(type solid)
		)
		(fill yes)
		(layer "In11.Cu")
		(net "M_C_DQ<59>")
	)
	(gr_poly
		(pts
			(xy 289.456368 -58.491628) (xy 289.456368 -58.270648) (xy 289.286188 -58.181748) (xy 289.241738 -58.181748)
			(xy 289.241738 -58.580528) (xy 289.286188 -58.580528)
		)
		(stroke
			(width 0)
			(type solid)
		)
		(fill yes)
		(layer "In11.Cu")
		(net "M_C_DQ<59>")
	)
	(gr_poly
		(pts
			(xy 289.456368 -57.494678) (xy 289.456368 -57.273698) (xy 289.286188 -57.184798) (xy 289.241738 -57.184798)
			(xy 289.241738 -57.583578) (xy 289.286188 -57.583578)
		)
		(stroke
			(width 0)
			(type solid)
		)
		(fill yes)
		(layer "In11.Cu")
		(net "M_C_DQ<59>")
	)
	(gr_poly
		(pts
			(xy 289.456368 -56.504078) (xy 289.456368 -56.283098) (xy 289.286188 -56.194198) (xy 289.241738 -56.194198)
			(xy 289.241738 -56.592978) (xy 289.286188 -56.592978)
		)
		(stroke
			(width 0)
			(type solid)
		)
		(fill yes)
		(layer "In11.Cu")
		(net "M_C_DQ<59>")
	)
	(gr_poly
		(pts
			(xy 289.456368 -55.513478) (xy 289.456368 -55.292498) (xy 289.286188 -55.203598) (xy 289.241738 -55.203598)
			(xy 289.241738 -55.602378) (xy 289.286188 -55.602378)
		)
		(stroke
			(width 0)
			(type solid)
		)
		(fill yes)
		(layer "In11.Cu")
		(net "M_C_DQ<59>")
	)
	(gr_poly
		(pts
			(xy 289.456368 -54.522878) (xy 289.456368 -54.301898) (xy 289.286188 -54.212998) (xy 289.241738 -54.212998)
			(xy 289.241738 -54.611778) (xy 289.286188 -54.611778)
		)
		(stroke
			(width 0)
			(type solid)
		)
		(fill yes)
		(layer "In11.Cu")
		(net "M_C_DQ<59>")
	)
	(gr_poly
		(pts
			(xy 289.466528 -63.447422) (xy 289.466528 -63.226442) (xy 289.296348 -63.137542) (xy 289.251898 -63.137542)
			(xy 289.251898 -63.536322) (xy 289.296348 -63.536322)
		)
		(stroke
			(width 0)
			(type solid)
		)
		(fill yes)
		(layer "In11.Cu")
		(net "M_C_DQ<59>")
	)
	(gr_poly
		(pts
			(xy 289.466528 -62.456822) (xy 289.466528 -62.235842) (xy 289.296348 -62.146942) (xy 289.251898 -62.146942)
			(xy 289.251898 -62.545722) (xy 289.296348 -62.545722)
		)
		(stroke
			(width 0)
			(type solid)
		)
		(fill yes)
		(layer "In11.Cu")
		(net "M_C_DQ<59>")
	)
	(gr_poly
		(pts
			(xy 289.478212 -61.450982) (xy 289.478212 -61.230002) (xy 289.308032 -61.141102) (xy 289.263582 -61.141102)
			(xy 289.263582 -61.539882) (xy 289.308032 -61.539882)
		)
		(stroke
			(width 0)
			(type solid)
		)
		(fill yes)
		(layer "In11.Cu")
		(net "M_C_DQ<59>")
	)
	(gr_poly
		(pts
			(xy 289.639248 -94.687136) (xy 289.6616 -94.648782) (xy 289.31616 -94.449138) (xy 289.294062 -94.487746)
			(xy 289.285934 -94.679516) (xy 289.477196 -94.790006)
		)
		(stroke
			(width 0)
			(type solid)
		)
		(fill yes)
		(layer "In11.Cu")
		(net "M_F_DQ<58>")
	)
	(gr_poly
		(pts
			(xy 289.640772 -95.678752) (xy 289.663124 -95.640398) (xy 289.317684 -95.440754) (xy 289.295586 -95.479362)
			(xy 289.287458 -95.671132) (xy 289.47872 -95.781622)
		)
		(stroke
			(width 0)
			(type solid)
		)
		(fill yes)
		(layer "In11.Cu")
		(net "M_F_DQ<62>")
	)
	(gr_poly
		(pts
			(xy 289.641026 -102.612952) (xy 289.663124 -102.574598) (xy 289.317684 -102.375208) (xy 289.29584 -102.413816)
			(xy 289.287712 -102.605586) (xy 289.478974 -102.715822)
		)
		(stroke
			(width 0)
			(type solid)
		)
		(fill yes)
		(layer "In11.Cu")
		(net "M_F_DQS_DN<7>")
	)
	(gr_poly
		(pts
			(xy 289.740594 -98.610928) (xy 289.740594 -98.389948) (xy 289.570414 -98.301048) (xy 289.525964 -98.301048)
			(xy 289.525964 -98.699828) (xy 289.570414 -98.699828)
		)
		(stroke
			(width 0)
			(type solid)
		)
		(fill yes)
		(layer "In11.Cu")
		(net "M_F_DQS_DP<7>")
	)
	(gr_poly
		(pts
			(xy 289.740594 -97.620582) (xy 289.740594 -97.399602) (xy 289.570414 -97.310702) (xy 289.525964 -97.310702)
			(xy 289.525964 -97.709482) (xy 289.570414 -97.709482)
		)
		(stroke
			(width 0)
			(type solid)
		)
		(fill yes)
		(layer "In11.Cu")
		(net "M_F_DQS_DP<7>")
	)
	(gr_poly
		(pts
			(xy 289.740594 -96.629982) (xy 289.740594 -96.409002) (xy 289.570414 -96.320102) (xy 289.525964 -96.320102)
			(xy 289.525964 -96.718882) (xy 289.570414 -96.718882)
		)
		(stroke
			(width 0)
			(type solid)
		)
		(fill yes)
		(layer "In11.Cu")
		(net "M_F_DQS_DP<7>")
	)
	(gr_poly
		(pts
			(xy 289.740848 -101.582474) (xy 289.740848 -101.361494) (xy 289.570668 -101.272594) (xy 289.526218 -101.272594)
			(xy 289.526218 -101.671374) (xy 289.570668 -101.671374)
		)
		(stroke
			(width 0)
			(type solid)
		)
		(fill yes)
		(layer "In11.Cu")
		(net "M_F_DQS_DP<7>")
	)
	(gr_poly
		(pts
			(xy 289.740848 -100.585778) (xy 289.740848 -100.364798) (xy 289.570668 -100.275898) (xy 289.526218 -100.275898)
			(xy 289.526218 -100.674678) (xy 289.570668 -100.674678)
		)
		(stroke
			(width 0)
			(type solid)
		)
		(fill yes)
		(layer "In11.Cu")
		(net "M_F_DQS_DP<7>")
	)
	(gr_poly
		(pts
			(xy 289.740848 -99.607624) (xy 289.740848 -99.386644) (xy 289.570668 -99.297744) (xy 289.526218 -99.297744)
			(xy 289.526218 -99.696524) (xy 289.570668 -99.696524)
		)
		(stroke
			(width 0)
			(type solid)
		)
		(fill yes)
		(layer "In11.Cu")
		(net "M_F_DQS_DP<7>")
	)
	(gr_poly
		(pts
			(xy 289.922966 -52.599844) (xy 289.89147 -52.568602) (xy 289.69208 -52.494942) (xy 289.530536 -52.656486)
			(xy 289.604196 -52.855876) (xy 289.635438 -52.887372)
		)
		(stroke
			(width 0)
			(type solid)
		)
		(fill yes)
		(layer "In11.Cu")
		(net "M_C_DQ<58>")
	)
	(gr_poly
		(pts
			(xy 290.061142 -101.266498) (xy 290.016692 -101.266498) (xy 289.846512 -101.355398) (xy 289.846512 -101.576378)
			(xy 290.016692 -101.665278) (xy 290.061142 -101.665278)
		)
		(stroke
			(width 0)
			(type solid)
		)
		(fill yes)
		(layer "In11.Cu")
		(net "M_F_DQ<62>")
	)
	(gr_poly
		(pts
			(xy 290.061142 -100.275898) (xy 290.016692 -100.275898) (xy 289.846512 -100.364798) (xy 289.846512 -100.585778)
			(xy 290.016692 -100.674678) (xy 290.061142 -100.674678)
		)
		(stroke
			(width 0)
			(type solid)
		)
		(fill yes)
		(layer "In11.Cu")
		(net "M_F_DQ<62>")
	)
	(gr_poly
		(pts
			(xy 290.061142 -99.297744) (xy 290.016692 -99.297744) (xy 289.846512 -99.386644) (xy 289.846512 -99.607624)
			(xy 290.016692 -99.696524) (xy 290.061142 -99.696524)
		)
		(stroke
			(width 0)
			(type solid)
		)
		(fill yes)
		(layer "In11.Cu")
		(net "M_F_DQ<62>")
	)
	(gr_poly
		(pts
			(xy 290.061142 -98.307144) (xy 290.016692 -98.307144) (xy 289.846512 -98.396044) (xy 289.846512 -98.617024)
			(xy 290.016692 -98.705924) (xy 290.061142 -98.705924)
		)
		(stroke
			(width 0)
			(type solid)
		)
		(fill yes)
		(layer "In11.Cu")
		(net "M_F_DQ<62>")
	)
	(gr_poly
		(pts
			(xy 290.061142 -97.310956) (xy 290.016692 -97.310956) (xy 289.846512 -97.399856) (xy 289.846512 -97.620836)
			(xy 290.016692 -97.709736) (xy 290.061142 -97.709736)
		)
		(stroke
			(width 0)
			(type solid)
		)
		(fill yes)
		(layer "In11.Cu")
		(net "M_F_DQ<62>")
	)
	(gr_poly
		(pts
			(xy 290.061142 -96.313752) (xy 290.016692 -96.313752) (xy 289.846512 -96.402652) (xy 289.846512 -96.623632)
			(xy 290.016692 -96.712532) (xy 290.061142 -96.712532)
		)
		(stroke
			(width 0)
			(type solid)
		)
		(fill yes)
		(layer "In11.Cu")
		(net "M_F_DQ<62>")
	)
	(gr_poly
		(pts
			(xy 290.162742 -52.96535) (xy 290.089082 -52.766214) (xy 290.057586 -52.734718) (xy 289.770312 -53.021992)
			(xy 289.801808 -53.053488) (xy 290.000944 -53.127148)
		)
		(stroke
			(width 0)
			(type solid)
		)
		(fill yes)
		(layer "In11.Cu")
		(net "M_C_DQ<59>")
	)
	(gr_poly
		(pts
			(xy 290.291774 -94.587314) (xy 290.299902 -94.395544) (xy 290.10864 -94.285054) (xy 289.946588 -94.387924)
			(xy 289.924236 -94.426278) (xy 290.269676 -94.625922)
		)
		(stroke
			(width 0)
			(type solid)
		)
		(fill yes)
		(layer "In11.Cu")
		(net "M_F_DQ<59>")
	)
	(gr_poly
		(pts
			(xy 290.293298 -102.51313) (xy 290.301426 -102.32136) (xy 290.110164 -102.21087) (xy 289.948112 -102.31374)
			(xy 289.92576 -102.352094) (xy 290.2712 -102.551738)
		)
		(stroke
			(width 0)
			(type solid)
		)
		(fill yes)
		(layer "In11.Cu")
		(net "M_F_DQS_DP<7>")
	)
	(gr_poly
		(pts
			(xy 290.293298 -95.57893) (xy 290.301426 -95.38716) (xy 290.110164 -95.27667) (xy 289.948112 -95.37954)
			(xy 289.926014 -95.417894) (xy 290.2712 -95.617538)
		)
		(stroke
			(width 0)
			(type solid)
		)
		(fill yes)
		(layer "In11.Cu")
		(net "M_F_DQ<63>")
	)
	(gr_poly
		(pts
			(xy 290.497768 -103.106982) (xy 290.52012 -103.068628) (xy 290.17468 -102.868984) (xy 290.152582 -102.907592)
			(xy 290.144454 -103.099362) (xy 290.335716 -103.209852)
		)
		(stroke
			(width 0)
			(type solid)
		)
		(fill yes)
		(layer "In11.Cu")
		(net "M_F_DQS_DN<7>")
	)
	(gr_poly
		(pts
			(xy 290.497768 -102.116382) (xy 290.519866 -102.078028) (xy 290.17468 -101.878384) (xy 290.152582 -101.916992)
			(xy 290.144454 -102.108762) (xy 290.335716 -102.219252)
		)
		(stroke
			(width 0)
			(type solid)
		)
		(fill yes)
		(layer "In11.Cu")
		(net "M_F_DQ<62>")
	)
	(gr_poly
		(pts
			(xy 290.499292 -95.183198) (xy 290.521644 -95.14459) (xy 290.176204 -94.945454) (xy 290.154106 -94.983808)
			(xy 290.145978 -95.175578) (xy 290.33724 -95.286068)
		)
		(stroke
			(width 0)
			(type solid)
		)
		(fill yes)
		(layer "In11.Cu")
		(net "M_F_DQ<58>")
	)
	(gr_poly
		(pts
			(xy 290.599114 -98.115628) (xy 290.599114 -97.894648) (xy 290.428934 -97.805748) (xy 290.384484 -97.805748)
			(xy 290.384484 -98.204528) (xy 290.428934 -98.204528)
		)
		(stroke
			(width 0)
			(type solid)
		)
		(fill yes)
		(layer "In11.Cu")
		(net "M_F_DQ<63>")
	)
	(gr_poly
		(pts
			(xy 290.599368 -101.093524) (xy 290.599368 -100.872544) (xy 290.429188 -100.783644) (xy 290.384738 -100.783644)
			(xy 290.384738 -101.182424) (xy 290.429188 -101.182424)
		)
		(stroke
			(width 0)
			(type solid)
		)
		(fill yes)
		(layer "In11.Cu")
		(net "M_F_DQ<63>")
	)
	(gr_poly
		(pts
			(xy 290.599368 -100.096828) (xy 290.599368 -99.875848) (xy 290.429188 -99.786948) (xy 290.384738 -99.786948)
			(xy 290.384738 -100.185728) (xy 290.429188 -100.185728)
		)
		(stroke
			(width 0)
			(type solid)
		)
		(fill yes)
		(layer "In11.Cu")
		(net "M_F_DQ<63>")
	)
	(gr_poly
		(pts
			(xy 290.599368 -99.099878) (xy 290.599368 -98.878898) (xy 290.429188 -98.789998) (xy 290.384738 -98.789998)
			(xy 290.384738 -99.188778) (xy 290.429188 -99.188778)
		)
		(stroke
			(width 0)
			(type solid)
		)
		(fill yes)
		(layer "In11.Cu")
		(net "M_F_DQ<63>")
	)
	(gr_poly
		(pts
			(xy 290.599368 -97.131632) (xy 290.599368 -96.910652) (xy 290.429188 -96.821752) (xy 290.384738 -96.821752)
			(xy 290.384738 -97.220532) (xy 290.429188 -97.220532)
		)
		(stroke
			(width 0)
			(type solid)
		)
		(fill yes)
		(layer "In11.Cu")
		(net "M_F_DQ<63>")
	)
	(gr_poly
		(pts
			(xy 290.599368 -96.141032) (xy 290.599368 -95.920052) (xy 290.429188 -95.831152) (xy 290.384738 -95.831152)
			(xy 290.384738 -96.229932) (xy 290.429188 -96.229932)
		)
		(stroke
			(width 0)
			(type solid)
		)
		(fill yes)
		(layer "In11.Cu")
		(net "M_F_DQ<63>")
	)
	(gr_poly
		(pts
			(xy 290.768786 -103.290116) (xy 290.724336 -103.290116) (xy 290.531296 -103.379016) (xy 290.531296 -103.607616)
			(xy 290.724336 -103.696516) (xy 290.768786 -103.696516)
		)
		(stroke
			(width 0)
			(type solid)
		)
		(fill yes)
		(layer "In11.Cu")
		(net "M_F_DQS_DN<7>")
	)
	(gr_poly
		(pts
			(xy 290.919662 -100.777548) (xy 290.875212 -100.777548) (xy 290.705032 -100.866448) (xy 290.705032 -101.087428)
			(xy 290.875212 -101.176328) (xy 290.919662 -101.176328)
		)
		(stroke
			(width 0)
			(type solid)
		)
		(fill yes)
		(layer "In11.Cu")
		(net "M_F_DQ<58>")
	)
	(gr_poly
		(pts
			(xy 290.919662 -99.786948) (xy 290.875212 -99.786948) (xy 290.705032 -99.875848) (xy 290.705032 -100.096828)
			(xy 290.875212 -100.185728) (xy 290.919662 -100.185728)
		)
		(stroke
			(width 0)
			(type solid)
		)
		(fill yes)
		(layer "In11.Cu")
		(net "M_F_DQ<58>")
	)
	(gr_poly
		(pts
			(xy 290.919662 -97.806256) (xy 290.875212 -97.806256) (xy 290.705032 -97.895156) (xy 290.705032 -98.116136)
			(xy 290.875212 -98.205036) (xy 290.919662 -98.205036)
		)
		(stroke
			(width 0)
			(type solid)
		)
		(fill yes)
		(layer "In11.Cu")
		(net "M_F_DQ<58>")
	)
	(gr_poly
		(pts
			(xy 290.919662 -96.815656) (xy 290.875212 -96.815656) (xy 290.705032 -96.904556) (xy 290.705032 -97.125536)
			(xy 290.875212 -97.214436) (xy 290.919662 -97.214436)
		)
		(stroke
			(width 0)
			(type solid)
		)
		(fill yes)
		(layer "In11.Cu")
		(net "M_F_DQ<58>")
	)
	(gr_poly
		(pts
			(xy 290.919662 -95.818198) (xy 290.875212 -95.818198) (xy 290.705032 -95.907098) (xy 290.705032 -96.128078)
			(xy 290.875212 -96.216978) (xy 290.919662 -96.216978)
		)
		(stroke
			(width 0)
			(type solid)
		)
		(fill yes)
		(layer "In11.Cu")
		(net "M_F_DQ<58>")
	)
	(gr_poly
		(pts
			(xy 290.919916 -98.801428) (xy 290.875466 -98.801428) (xy 290.705286 -98.890328) (xy 290.705286 -99.111308)
			(xy 290.875466 -99.200208) (xy 290.919916 -99.200208)
		)
		(stroke
			(width 0)
			(type solid)
		)
		(fill yes)
		(layer "In11.Cu")
		(net "M_F_DQ<58>")
	)
	(gr_poly
		(pts
			(xy 291.003228 -103.055166) (xy 291.04844 -102.86873) (xy 290.88207 -102.723188) (xy 290.703254 -102.792784)
			(xy 290.67379 -102.826058) (xy 290.974018 -103.088948)
		)
		(stroke
			(width 0)
			(type solid)
		)
		(fill yes)
		(layer "In11.Cu")
		(net "M_F_DQS_DP<7>")
	)
	(gr_poly
		(pts
			(xy 291.008562 -103.593138) (xy 291.178488 -103.503984) (xy 291.177726 -103.283004) (xy 291.007546 -103.194612)
			(xy 290.963096 -103.194612) (xy 290.963858 -103.593646)
		)
		(stroke
			(width 0)
			(type solid)
		)
		(fill yes)
		(layer "In11.Cu")
		(net "M_F_DQS_DP<7>")
	)
	(gr_poly
		(pts
			(xy 291.151818 -102.017576) (xy 291.159946 -101.825806) (xy 290.968684 -101.715316) (xy 290.806632 -101.818186)
			(xy 290.78428 -101.856794) (xy 291.12972 -102.05593)
		)
		(stroke
			(width 0)
			(type solid)
		)
		(fill yes)
		(layer "In11.Cu")
		(net "M_F_DQ<63>")
	)
	(gr_poly
		(pts
			(xy 291.151818 -95.083376) (xy 291.159946 -94.891606) (xy 290.968684 -94.781116) (xy 290.806632 -94.883986)
			(xy 290.784534 -94.92234) (xy 291.129974 -95.12173)
		)
		(stroke
			(width 0)
			(type solid)
		)
		(fill yes)
		(layer "In11.Cu")
		(net "M_F_DQ<59>")
	)
	(gr_poly
		(pts
			(xy 291.356288 -102.611682) (xy 291.378386 -102.573328) (xy 291.0332 -102.373684) (xy 291.011102 -102.412292)
			(xy 291.002974 -102.604062) (xy 291.194236 -102.714552)
		)
		(stroke
			(width 0)
			(type solid)
		)
		(fill yes)
		(layer "In11.Cu")
		(net "M_F_DQ<62>")
	)
	(gr_poly
		(pts
			(xy 291.361622 -101.624384) (xy 291.383974 -101.58603) (xy 291.038788 -101.386386) (xy 291.016436 -101.425248)
			(xy 291.008308 -101.617018) (xy 291.199824 -101.727254)
		)
		(stroke
			(width 0)
			(type solid)
		)
		(fill yes)
		(layer "In11.Cu")
		(net "M_F_DQ<58>")
	)
	(gr_poly
		(pts
			(xy 291.457888 -100.585778) (xy 291.457888 -100.364798) (xy 291.287708 -100.275898) (xy 291.243258 -100.275898)
			(xy 291.243258 -100.674678) (xy 291.287708 -100.674678)
		)
		(stroke
			(width 0)
			(type solid)
		)
		(fill yes)
		(layer "In11.Cu")
		(net "M_F_DQ<59>")
	)
	(gr_poly
		(pts
			(xy 291.457888 -99.607624) (xy 291.457888 -99.386644) (xy 291.287708 -99.297744) (xy 291.243258 -99.297744)
			(xy 291.243258 -99.696524) (xy 291.287708 -99.696524)
		)
		(stroke
			(width 0)
			(type solid)
		)
		(fill yes)
		(layer "In11.Cu")
		(net "M_F_DQ<59>")
	)
	(gr_poly
		(pts
			(xy 291.457888 -98.611436) (xy 291.457888 -98.390456) (xy 291.287708 -98.301556) (xy 291.243258 -98.301556)
			(xy 291.243258 -98.700336) (xy 291.287708 -98.700336)
		)
		(stroke
			(width 0)
			(type solid)
		)
		(fill yes)
		(layer "In11.Cu")
		(net "M_F_DQ<59>")
	)
	(gr_poly
		(pts
			(xy 291.457888 -97.620836) (xy 291.457888 -97.399856) (xy 291.287708 -97.310956) (xy 291.243258 -97.310956)
			(xy 291.243258 -97.709736) (xy 291.287708 -97.709736)
		)
		(stroke
			(width 0)
			(type solid)
		)
		(fill yes)
		(layer "In11.Cu")
		(net "M_F_DQ<59>")
	)
	(gr_poly
		(pts
			(xy 291.457888 -96.636078) (xy 291.457888 -96.415098) (xy 291.287708 -96.326198) (xy 291.243258 -96.326198)
			(xy 291.243258 -96.724978) (xy 291.287708 -96.724978)
		)
		(stroke
			(width 0)
			(type solid)
		)
		(fill yes)
		(layer "In11.Cu")
		(net "M_F_DQ<59>")
	)
	(gr_poly
		(pts
			(xy 291.457888 -95.645478) (xy 291.457888 -95.424498) (xy 291.287708 -95.335598) (xy 291.243258 -95.335598)
			(xy 291.243258 -95.734378) (xy 291.287708 -95.734378)
		)
		(stroke
			(width 0)
			(type solid)
		)
		(fill yes)
		(layer "In11.Cu")
		(net "M_F_DQ<59>")
	)
	(gr_poly
		(pts
			(xy 291.678106 -103.05161) (xy 291.633656 -103.05161) (xy 291.440616 -103.14051) (xy 291.440616 -103.36911)
			(xy 291.633656 -103.45801) (xy 291.678106 -103.45801)
		)
		(stroke
			(width 0)
			(type solid)
		)
		(fill yes)
		(layer "In11.Cu")
		(net "M_F_DQ<62>")
	)
	(gr_poly
		(pts
			(xy 291.893498 -102.618794) (xy 291.951156 -102.435914) (xy 291.7952 -102.27945) (xy 291.612066 -102.3366)
			(xy 291.580316 -102.368096) (xy 291.862002 -102.65029)
		)
		(stroke
			(width 0)
			(type solid)
		)
		(fill yes)
		(layer "In11.Cu")
		(net "M_F_DQ<63>")
	)
	(gr_poly
		(pts
			(xy 292.008814 -101.521514) (xy 292.016942 -101.329744) (xy 291.82568 -101.219254) (xy 291.663628 -101.322124)
			(xy 291.641276 -101.360478) (xy 291.986716 -101.560122)
		)
		(stroke
			(width 0)
			(type solid)
		)
		(fill yes)
		(layer "In11.Cu")
		(net "M_F_DQ<59>")
	)
	(gr_poly
		(pts
			(xy 292.106096 -103.36911) (xy 292.106096 -103.14051) (xy 291.913056 -103.05161) (xy 291.868606 -103.05161)
			(xy 291.868606 -103.45801) (xy 291.913056 -103.45801)
		)
		(stroke
			(width 0)
			(type solid)
		)
		(fill yes)
		(layer "In11.Cu")
		(net "M_F_DQ<63>")
	)
	(gr_poly
		(pts
			(xy 292.220142 -102.119684) (xy 292.242494 -102.08133) (xy 291.897308 -101.881686) (xy 291.874956 -101.920548)
			(xy 291.866828 -102.112318) (xy 292.058344 -102.222554)
		)
		(stroke
			(width 0)
			(type solid)
		)
		(fill yes)
		(layer "In11.Cu")
		(net "M_F_DQ<58>")
	)
	(gr_poly
		(pts
			(xy 292.600634 -102.310946) (xy 292.556184 -102.310946) (xy 292.363144 -102.399846) (xy 292.363144 -102.628192)
			(xy 292.556184 -102.717092) (xy 292.600634 -102.717092)
		)
		(stroke
			(width 0)
			(type solid)
		)
		(fill yes)
		(layer "In11.Cu")
		(net "M_F_DQ<58>")
	)
	(gr_poly
		(pts
			(xy 293.028624 -102.501446) (xy 293.028624 -102.272846) (xy 292.835584 -102.183946) (xy 292.791134 -102.183946)
			(xy 292.791134 -102.590092) (xy 292.835584 -102.590092)
		)
		(stroke
			(width 0)
			(type solid)
		)
		(fill yes)
		(layer "In11.Cu")
		(net "M_F_DQ<59>")
	)
	(gr_poly
		(pts
			(arc
				(start -4.097782 -127.939038)
				(mid -4.384802 -127.939038)
				(end -4.097782 -127.939038)
			)
		)
		(stroke
			(width 0)
			(type solid)
		)
		(fill yes)
		(layer "In11.Cu")
		(net "GND")
	)
	(gr_poly
		(pts
			(arc
				(start 454.1774 -151.838914)
				(mid 453.8726 -151.838914)
				(end 454.1774 -151.838914)
			)
		)
		(stroke
			(width 0)
			(type solid)
		)
		(fill yes)
		(layer "In11.Cu")
		(net "GND")
	)
	(gr_poly
		(pts
			(arc
				(start 460.325216 -140.802614)
				(mid 460.020416 -140.802614)
				(end 460.325216 -140.802614)
			)
		)
		(stroke
			(width 0)
			(type solid)
		)
		(fill yes)
		(layer "In11.Cu")
		(net "GND")
	)
	(gr_line
		(start 4.499864 -27.71013)
		(end 4.900676 -27.71013)
		(stroke
			(width 0.05715)
			(type default)
		)
		(layer "In11.Cu")
	)
	(gr_line
		(start 4.900676 -27.71013)
		(end 4.960366 -27.76982)
		(stroke
			(width 0.05715)
			(type default)
		)
		(layer "In11.Cu")
	)
	(gr_line
		(start 5.37718 -27.76982)
		(end 5.43687 -27.71013)
		(stroke
			(width 0.05715)
			(type default)
		)
		(layer "In11.Cu")
	)
	(gr_line
		(start 5.43687 -27.71013)
		(end 5.899912 -27.71013)
		(stroke
			(width 0.05715)
			(type default)
		)
		(layer "In11.Cu")
	)
	(gr_line
		(start 5.80009 -29.710126)
		(end 6.164326 -29.710126)
		(stroke
			(width 0.05715)
			(type default)
		)
		(layer "In11.Cu")
	)
	(gr_line
		(start 5.80009 -25.710134)
		(end 6.0198 -25.710134)
		(stroke
			(width 0.05715)
			(type default)
		)
		(layer "In11.Cu")
	)
	(gr_line
		(start 6.0198 -25.710134)
		(end 6.25856 -25.471374)
		(stroke
			(width 0.05715)
			(type default)
		)
		(layer "In11.Cu")
	)
	(gr_line
		(start 6.164326 -29.710126)
		(end 6.29412 -29.83992)
		(stroke
			(width 0.05715)
			(type default)
		)
		(layer "In11.Cu")
	)
	(gr_line
		(start 6.675374 -25.471374)
		(end 6.914134 -25.710134)
		(stroke
			(width 0.05715)
			(type default)
		)
		(layer "In11.Cu")
	)
	(gr_line
		(start 6.71068 -29.83992)
		(end 6.840474 -29.710126)
		(stroke
			(width 0.05715)
			(type default)
		)
		(layer "In11.Cu")
	)
	(gr_line
		(start 6.840474 -29.710126)
		(end 7.199884 -29.710126)
		(stroke
			(width 0.05715)
			(type default)
		)
		(layer "In11.Cu")
	)
	(gr_line
		(start 6.914134 -25.710134)
		(end 7.199884 -25.710134)
		(stroke
			(width 0.05715)
			(type default)
		)
		(layer "In11.Cu")
	)
	(gr_line
		(start 7.89051 -28.561538)
		(end 8.05307 -28.398978)
		(stroke
			(width 0.05715)
			(type default)
		)
		(layer "In11.Cu")
	)
	(gr_line
		(start 8.05307 -28.398978)
		(end 8.39597 -28.398978)
		(stroke
			(width 0.05715)
			(type default)
		)
		(layer "In11.Cu")
	)
	(gr_line
		(start 8.18261 -28.856178)
		(end 8.26643 -28.856178)
		(stroke
			(width 0.05715)
			(type default)
		)
		(layer "In11.Cu")
	)
	(gr_line
		(start 8.39597 -28.398978)
		(end 8.55853 -28.561538)
		(stroke
			(width 0.05715)
			(type default)
		)
		(layer "In11.Cu")
	)
	(gr_line
		(start 8.683498 -27.237436)
		(end 8.925814 -27.480006)
		(stroke
			(width 0.05715)
			(type default)
		)
		(layer "In11.Cu")
	)
	(gr_line
		(start 8.683498 -27.007312)
		(end 8.683498 -27.237436)
		(stroke
			(width 0.05715)
			(type default)
		)
		(layer "In11.Cu")
	)
	(gr_line
		(start 8.815832 -33.00222)
		(end 8.87476 -33.061148)
		(stroke
			(width 0.05715)
			(type default)
		)
		(layer "In11.Cu")
	)
	(gr_line
		(start 8.817356 -32.587184)
		(end 9.04748 -32.587184)
		(stroke
			(width 0.05715)
			(type default)
		)
		(layer "In11.Cu")
	)
	(gr_line
		(start 8.925814 -27.480006)
		(end 9.156192 -27.480006)
		(stroke
			(width 0.05715)
			(type default)
		)
		(layer "In11.Cu")
	)
	(gr_line
		(start 9.04748 -32.587184)
		(end 9.289796 -32.8295)
		(stroke
			(width 0.05715)
			(type default)
		)
		(layer "In11.Cu")
	)
	(gr_line
		(start 9.098534 -27.005788)
		(end 9.157716 -27.06497)
		(stroke
			(width 0.05715)
			(type default)
		)
		(layer "In11.Cu")
	)
	(gr_line
		(start 9.230614 -30.206442)
		(end 9.230614 -30.290262)
		(stroke
			(width 0.05715)
			(type default)
		)
		(layer "In11.Cu")
	)
	(gr_line
		(start 9.289796 -32.8295)
		(end 9.289796 -33.059624)
		(stroke
			(width 0.05715)
			(type default)
		)
		(layer "In11.Cu")
	)
	(gr_line
		(start 9.325102 -25.474676)
		(end 9.567418 -25.717246)
		(stroke
			(width 0.05715)
			(type default)
		)
		(layer "In11.Cu")
	)
	(gr_line
		(start 9.325102 -25.244552)
		(end 9.325102 -25.474676)
		(stroke
			(width 0.05715)
			(type default)
		)
		(layer "In11.Cu")
	)
	(gr_line
		(start 9.40181 -27.955748)
		(end 9.64438 -28.198318)
		(stroke
			(width 0.05715)
			(type default)
		)
		(layer "In11.Cu")
	)
	(gr_line
		(start 9.40181 -27.725624)
		(end 9.40181 -27.955748)
		(stroke
			(width 0.05715)
			(type default)
		)
		(layer "In11.Cu")
	)
	(gr_line
		(start 9.525254 -30.582362)
		(end 9.687814 -30.419802)
		(stroke
			(width 0.05715)
			(type default)
		)
		(layer "In11.Cu")
	)
	(gr_line
		(start 9.525254 -29.914342)
		(end 9.687814 -30.076902)
		(stroke
			(width 0.05715)
			(type default)
		)
		(layer "In11.Cu")
	)
	(gr_line
		(start 9.567418 -25.717246)
		(end 9.797796 -25.717246)
		(stroke
			(width 0.05715)
			(type default)
		)
		(layer "In11.Cu")
	)
	(gr_line
		(start 9.64438 -28.198318)
		(end 9.874504 -28.198318)
		(stroke
			(width 0.05715)
			(type default)
		)
		(layer "In11.Cu")
	)
	(gr_line
		(start 9.687814 -30.076902)
		(end 9.687814 -30.419802)
		(stroke
			(width 0.05715)
			(type default)
		)
		(layer "In11.Cu")
	)
	(gr_line
		(start 9.740138 -25.243028)
		(end 9.79932 -25.30221)
		(stroke
			(width 0.05715)
			(type default)
		)
		(layer "In11.Cu")
	)
	(gr_line
		(start 9.816846 -27.7241)
		(end 9.876028 -27.783282)
		(stroke
			(width 0.05715)
			(type default)
		)
		(layer "In11.Cu")
	)
	(gr_line
		(start 9.8552 -34.55797)
		(end 9.8552 -34.64179)
		(stroke
			(width 0.05715)
			(type default)
		)
		(layer "In11.Cu")
	)
	(gr_line
		(start 10.043414 -26.192988)
		(end 10.285984 -26.435558)
		(stroke
			(width 0.05715)
			(type default)
		)
		(layer "In11.Cu")
	)
	(gr_line
		(start 10.043414 -25.962864)
		(end 10.043414 -26.192988)
		(stroke
			(width 0.05715)
			(type default)
		)
		(layer "In11.Cu")
	)
	(gr_line
		(start 10.120376 -28.674314)
		(end 10.362692 -28.91663)
		(stroke
			(width 0.05715)
			(type default)
		)
		(layer "In11.Cu")
	)
	(gr_line
		(start 10.120376 -28.44419)
		(end 10.120376 -28.674314)
		(stroke
			(width 0.05715)
			(type default)
		)
		(layer "In11.Cu")
	)
	(gr_line
		(start 10.14984 -34.93389)
		(end 10.3124 -34.77133)
		(stroke
			(width 0.05715)
			(type default)
		)
		(layer "In11.Cu")
	)
	(gr_line
		(start 10.14984 -34.26587)
		(end 10.3124 -34.42843)
		(stroke
			(width 0.05715)
			(type default)
		)
		(layer "In11.Cu")
	)
	(gr_line
		(start 10.285984 -26.435558)
		(end 10.516108 -26.435558)
		(stroke
			(width 0.05715)
			(type default)
		)
		(layer "In11.Cu")
	)
	(gr_line
		(start 10.301478 -32.119824)
		(end 10.360406 -32.178752)
		(stroke
			(width 0.05715)
			(type default)
		)
		(layer "In11.Cu")
	)
	(gr_line
		(start 10.303002 -31.704788)
		(end 10.533126 -31.704788)
		(stroke
			(width 0.05715)
			(type default)
		)
		(layer "In11.Cu")
	)
	(gr_line
		(start 10.3124 -34.42843)
		(end 10.3124 -34.77133)
		(stroke
			(width 0.05715)
			(type default)
		)
		(layer "In11.Cu")
	)
	(gr_line
		(start 10.362692 -28.91663)
		(end 10.592816 -28.91663)
		(stroke
			(width 0.05715)
			(type default)
		)
		(layer "In11.Cu")
	)
	(gr_line
		(start 10.45845 -25.96134)
		(end 10.517632 -26.020522)
		(stroke
			(width 0.05715)
			(type default)
		)
		(layer "In11.Cu")
	)
	(gr_line
		(start 10.533126 -31.704788)
		(end 10.775442 -31.947104)
		(stroke
			(width 0.05715)
			(type default)
		)
		(layer "In11.Cu")
	)
	(gr_line
		(start 10.535412 -28.442666)
		(end 10.59434 -28.501594)
		(stroke
			(width 0.05715)
			(type default)
		)
		(layer "In11.Cu")
	)
	(gr_line
		(start 10.76198 -26.911554)
		(end 11.004296 -27.15387)
		(stroke
			(width 0.05715)
			(type default)
		)
		(layer "In11.Cu")
	)
	(gr_line
		(start 10.76198 -26.68143)
		(end 10.76198 -26.911554)
		(stroke
			(width 0.05715)
			(type default)
		)
		(layer "In11.Cu")
	)
	(gr_line
		(start 10.775442 -31.947104)
		(end 10.775442 -32.177228)
		(stroke
			(width 0.05715)
			(type default)
		)
		(layer "In11.Cu")
	)
	(gr_line
		(start 11.004296 -27.15387)
		(end 11.23442 -27.15387)
		(stroke
			(width 0.05715)
			(type default)
		)
		(layer "In11.Cu")
	)
	(gr_line
		(start 11.177016 -26.679906)
		(end 11.235944 -26.738834)
		(stroke
			(width 0.05715)
			(type default)
		)
		(layer "In11.Cu")
	)
	(gr_line
		(start 11.7856 -32.77616)
		(end 11.9126 -32.90316)
		(stroke
			(width 0.05715)
			(type default)
		)
		(layer "In11.Cu")
	)
	(gr_line
		(start 11.7856 -32.3596)
		(end 11.9126 -32.2326)
		(stroke
			(width 0.05715)
			(type default)
		)
		(layer "In11.Cu")
	)
	(gr_line
		(start 11.816842 -36.378642)
		(end 11.9126 -36.4744)
		(stroke
			(width 0.05715)
			(type default)
		)
		(layer "In11.Cu")
	)
	(gr_line
		(start 11.816842 -35.962082)
		(end 11.9126 -35.866324)
		(stroke
			(width 0.05715)
			(type default)
		)
		(layer "In11.Cu")
	)
	(gr_line
		(start 11.84783 -29.22143)
		(end 11.9126 -29.2862)
		(stroke
			(width 0.05715)
			(type default)
		)
		(layer "In11.Cu")
	)
	(gr_line
		(start 11.84783 -28.80487)
		(end 11.9126 -28.7401)
		(stroke
			(width 0.05715)
			(type default)
		)
		(layer "In11.Cu")
	)
	(gr_line
		(start 11.9126 -36.4744)
		(end 11.9126 -36.7665)
		(stroke
			(width 0.05715)
			(type default)
		)
		(layer "In11.Cu")
	)
	(gr_line
		(start 11.9126 -35.4965)
		(end 11.9126 -35.866324)
		(stroke
			(width 0.05715)
			(type default)
		)
		(layer "In11.Cu")
	)
	(gr_line
		(start 11.9126 -32.90316)
		(end 11.9126 -33.2105)
		(stroke
			(width 0.05715)
			(type default)
		)
		(layer "In11.Cu")
	)
	(gr_line
		(start 11.9126 -31.9405)
		(end 11.9126 -32.2326)
		(stroke
			(width 0.05715)
			(type default)
		)
		(layer "In11.Cu")
	)
	(gr_line
		(start 11.9126 -29.2862)
		(end 11.9126 -29.6545)
		(stroke
			(width 0.05715)
			(type default)
		)
		(layer "In11.Cu")
	)
	(gr_line
		(start 11.9126 -28.3845)
		(end 11.9126 -28.7401)
		(stroke
			(width 0.05715)
			(type default)
		)
		(layer "In11.Cu")
	)
	(gr_line
		(start 12.95654 -27.45994)
		(end 13.050774 -27.554174)
		(stroke
			(width 0.05715)
			(type default)
		)
		(layer "In11.Cu")
	)
	(gr_line
		(start 12.95654 -27.04338)
		(end 13.050774 -26.949146)
		(stroke
			(width 0.05715)
			(type default)
		)
		(layer "In11.Cu")
	)
	(gr_line
		(start 13.050774 -27.554174)
		(end 13.050774 -27.8765)
		(stroke
			(width 0.05715)
			(type default)
		)
		(layer "In11.Cu")
	)
	(gr_line
		(start 13.050774 -26.6065)
		(end 13.050774 -26.949146)
		(stroke
			(width 0.05715)
			(type default)
		)
		(layer "In11.Cu")
	)
	(gr_line
		(start 129.085848 -78.688438)
		(end 129.378964 -78.857348)
		(stroke
			(width 0.04445)
			(type default)
		)
		(layer "In11.Cu")
	)
	(gr_line
		(start 129.378964 -78.857348)
		(end 129.393442 -78.911196)
		(stroke
			(width 0.04445)
			(type default)
		)
		(layer "In11.Cu")
	)
	(gr_line
		(start 129.394966 -78.9178)
		(end 129.40284 -78.946756)
		(stroke
			(width 0.04445)
			(type default)
		)
		(layer "In11.Cu")
	)
	(gr_line
		(start 129.426208 -81.449418)
		(end 129.432558 -81.460086)
		(stroke
			(width 0.04445)
			(type default)
		)
		(layer "In11.Cu")
	)
	(gr_line
		(start 129.426208 -80.458818)
		(end 129.432558 -80.469486)
		(stroke
			(width 0.04445)
			(type default)
		)
		(layer "In11.Cu")
	)
	(gr_line
		(start 129.426208 -79.468218)
		(end 129.432558 -79.478886)
		(stroke
			(width 0.04445)
			(type default)
		)
		(layer "In11.Cu")
	)
	(gr_line
		(start 129.432558 -80.469486)
		(end 129.437384 -80.478122)
		(stroke
			(width 0.04445)
			(type default)
		)
		(layer "In11.Cu")
	)
	(gr_line
		(start 129.432558 -79.478886)
		(end 129.437384 -79.487522)
		(stroke
			(width 0.04445)
			(type default)
		)
		(layer "In11.Cu")
	)
	(gr_line
		(start 129.572512 -79.036164)
		(end 129.59969 -79.028798)
		(stroke
			(width 0.04445)
			(type default)
		)
		(layer "In11.Cu")
	)
	(gr_line
		(start 129.592832 -81.3562)
		(end 129.597658 -81.364836)
		(stroke
			(width 0.04445)
			(type default)
		)
		(layer "In11.Cu")
	)
	(gr_line
		(start 129.592832 -80.3656)
		(end 129.597658 -80.374236)
		(stroke
			(width 0.04445)
			(type default)
		)
		(layer "In11.Cu")
	)
	(gr_line
		(start 129.597658 -81.364836)
		(end 129.604008 -81.375504)
		(stroke
			(width 0.04445)
			(type default)
		)
		(layer "In11.Cu")
	)
	(gr_line
		(start 129.597658 -80.374236)
		(end 129.604008 -80.384904)
		(stroke
			(width 0.04445)
			(type default)
		)
		(layer "In11.Cu")
	)
	(gr_line
		(start 129.597658 -79.383636)
		(end 129.604008 -79.394304)
		(stroke
			(width 0.04445)
			(type default)
		)
		(layer "In11.Cu")
	)
	(gr_line
		(start 129.60604 -79.02702)
		(end 129.651252 -79.014828)
		(stroke
			(width 0.04445)
			(type default)
		)
		(layer "In11.Cu")
	)
	(gr_line
		(start 129.651252 -79.014828)
		(end 129.944368 -79.183738)
		(stroke
			(width 0.04445)
			(type default)
		)
		(layer "In11.Cu")
	)
	(gr_line
		(start 129.931414 -82.746088)
		(end 129.959354 -82.746088)
		(stroke
			(width 0.04445)
			(type default)
		)
		(layer "In11.Cu")
	)
	(gr_line
		(start 129.933192 -82.555334)
		(end 129.957322 -82.555334)
		(stroke
			(width 0.04445)
			(type default)
		)
		(layer "In11.Cu")
	)
	(gr_line
		(start 130.781298 -83.241134)
		(end 130.814064 -83.241134)
		(stroke
			(width 0.04445)
			(type default)
		)
		(layer "In11.Cu")
	)
	(gr_line
		(start 130.787902 -83.050634)
		(end 130.820668 -83.050634)
		(stroke
			(width 0.04445)
			(type default)
		)
		(layer "In11.Cu")
	)
	(gr_line
		(start 131.643628 -83.736688)
		(end 131.661408 -83.736688)
		(stroke
			(width 0.04445)
			(type default)
		)
		(layer "In11.Cu")
	)
	(gr_line
		(start 131.650232 -83.546188)
		(end 131.6863 -83.546188)
		(stroke
			(width 0.04445)
			(type default)
		)
		(layer "In11.Cu")
	)
	(gr_line
		(start 132.004562 -83.930998)
		(end 132.007864 -83.93684)
		(stroke
			(width 0.04445)
			(type default)
		)
		(layer "In11.Cu")
	)
	(gr_line
		(start 132.173218 -83.841082)
		(end 132.17652 -83.846924)
		(stroke
			(width 0.04445)
			(type default)
		)
		(layer "In11.Cu")
	)
	(gr_line
		(start 132.494782 -84.231734)
		(end 132.53085 -84.231734)
		(stroke
			(width 0.04445)
			(type default)
		)
		(layer "In11.Cu")
	)
	(gr_line
		(start 132.519674 -84.041234)
		(end 132.537454 -84.041234)
		(stroke
			(width 0.04445)
			(type default)
		)
		(layer "In11.Cu")
	)
	(gr_line
		(start 133.360414 -84.727288)
		(end 133.39318 -84.727288)
		(stroke
			(width 0.04445)
			(type default)
		)
		(layer "In11.Cu")
	)
	(gr_line
		(start 133.367018 -84.536788)
		(end 133.399784 -84.536788)
		(stroke
			(width 0.04445)
			(type default)
		)
		(layer "In11.Cu")
	)
	(gr_line
		(start 134.215124 -85.222334)
		(end 134.24789 -85.222334)
		(stroke
			(width 0.04445)
			(type default)
		)
		(layer "In11.Cu")
	)
	(gr_line
		(start 134.221728 -85.031834)
		(end 134.254494 -85.031834)
		(stroke
			(width 0.04445)
			(type default)
		)
		(layer "In11.Cu")
	)
	(gr_line
		(start 135.077454 -85.717888)
		(end 135.11022 -85.717888)
		(stroke
			(width 0.04445)
			(type default)
		)
		(layer "In11.Cu")
	)
	(gr_line
		(start 135.084058 -85.527388)
		(end 135.116824 -85.527388)
		(stroke
			(width 0.04445)
			(type default)
		)
		(layer "In11.Cu")
	)
	(gr_line
		(start 135.932164 -86.212934)
		(end 135.96493 -86.212934)
		(stroke
			(width 0.04445)
			(type default)
		)
		(layer "In11.Cu")
	)
	(gr_line
		(start 135.938768 -86.022434)
		(end 135.971534 -86.022434)
		(stroke
			(width 0.04445)
			(type default)
		)
		(layer "In11.Cu")
	)
	(gr_line
		(start 136.794494 -86.708488)
		(end 136.82726 -86.708488)
		(stroke
			(width 0.04445)
			(type default)
		)
		(layer "In11.Cu")
	)
	(gr_line
		(start 136.801098 -86.517988)
		(end 136.833864 -86.517988)
		(stroke
			(width 0.04445)
			(type default)
		)
		(layer "In11.Cu")
	)
	(gr_line
		(start 137.649204 -87.203534)
		(end 137.68197 -87.203534)
		(stroke
			(width 0.04445)
			(type default)
		)
		(layer "In11.Cu")
	)
	(gr_line
		(start 137.655808 -87.013034)
		(end 137.688574 -87.013034)
		(stroke
			(width 0.04445)
			(type default)
		)
		(layer "In11.Cu")
	)
	(gr_line
		(start 138.511534 -87.699088)
		(end 138.5443 -87.699088)
		(stroke
			(width 0.04445)
			(type default)
		)
		(layer "In11.Cu")
	)
	(gr_line
		(start 138.518138 -87.508588)
		(end 138.550904 -87.508588)
		(stroke
			(width 0.04445)
			(type default)
		)
		(layer "In11.Cu")
	)
	(gr_line
		(start 139.366244 -88.194134)
		(end 139.39901 -88.194134)
		(stroke
			(width 0.04445)
			(type default)
		)
		(layer "In11.Cu")
	)
	(gr_line
		(start 139.372848 -88.003634)
		(end 139.405614 -88.003634)
		(stroke
			(width 0.04445)
			(type default)
		)
		(layer "In11.Cu")
	)
	(gr_line
		(start 140.228574 -88.689688)
		(end 140.26134 -88.689688)
		(stroke
			(width 0.04445)
			(type default)
		)
		(layer "In11.Cu")
	)
	(gr_line
		(start 140.235178 -88.499188)
		(end 140.267944 -88.499188)
		(stroke
			(width 0.04445)
			(type default)
		)
		(layer "In11.Cu")
	)
	(gr_line
		(start 141.083284 -89.184734)
		(end 141.11605 -89.184734)
		(stroke
			(width 0.04445)
			(type default)
		)
		(layer "In11.Cu")
	)
	(gr_line
		(start 141.089888 -88.994234)
		(end 141.122654 -88.994234)
		(stroke
			(width 0.04445)
			(type default)
		)
		(layer "In11.Cu")
	)
	(gr_line
		(start 141.945614 -89.680288)
		(end 142.130272 -89.680288)
		(stroke
			(width 0.04445)
			(type default)
		)
		(layer "In11.Cu")
	)
	(gr_line
		(start 141.952218 -89.489788)
		(end 142.166594 -89.489788)
		(stroke
			(width 0.04445)
			(type default)
		)
		(layer "In11.Cu")
	)
	(gr_line
		(start 142.808198 -90.20302)
		(end 143.066008 -90.162126)
		(stroke
			(width 0.04445)
			(type default)
		)
		(layer "In11.Cu")
	)
	(gr_line
		(start 142.810484 -90.009218)
		(end 143.03629 -89.973658)
		(stroke
			(width 0.04445)
			(type default)
		)
		(layer "In11.Cu")
	)
	(gr_line
		(start 143.03629 -89.973658)
		(end 143.04645 -89.959434)
		(stroke
			(width 0.04445)
			(type default)
		)
		(layer "In11.Cu")
	)
	(gr_line
		(start 143.04645 -89.959434)
		(end 143.046704 -89.959434)
		(stroke
			(width 0.04445)
			(type default)
		)
		(layer "In11.Cu")
	)
	(gr_line
		(start 143.046704 -89.959434)
		(end 143.098774 -89.951306)
		(stroke
			(width 0.04445)
			(type default)
		)
		(layer "In11.Cu")
	)
	(gr_line
		(start 143.066008 -90.162126)
		(end 143.080232 -90.172794)
		(stroke
			(width 0.04445)
			(type default)
		)
		(layer "In11.Cu")
	)
	(gr_line
		(start 143.080232 -90.172794)
		(end 143.13154 -90.164666)
		(stroke
			(width 0.04445)
			(type default)
		)
		(layer "In11.Cu")
	)
	(gr_line
		(start 143.204438 -90.153236)
		(end 143.260064 -90.153236)
		(stroke
			(width 0.04445)
			(type default)
		)
		(layer "In11.Cu")
	)
	(gr_line
		(start 145.115788 -91.548712)
		(end 145.131282 -91.564206)
		(stroke
			(width 0.04445)
			(type default)
		)
		(layer "In11.Cu")
	)
	(gr_line
		(start 145.115788 -91.521788)
		(end 145.115788 -91.548712)
		(stroke
			(width 0.04445)
			(type default)
		)
		(layer "In11.Cu")
	)
	(gr_line
		(start 145.268442 -91.36888)
		(end 145.295874 -91.36888)
		(stroke
			(width 0.04445)
			(type default)
		)
		(layer "In11.Cu")
	)
	(gr_line
		(start 145.295874 -91.36888)
		(end 145.311368 -91.384374)
		(stroke
			(width 0.04445)
			(type default)
		)
		(layer "In11.Cu")
	)
	(gr_line
		(start 145.963386 -92.036392)
		(end 146.012916 -92.085922)
		(stroke
			(width 0.0635)
			(type default)
		)
		(layer "In11.Cu")
	)
	(gr_line
		(start 172.719746 -109.389926)
		(end 172.7708 -109.44098)
		(stroke
			(width 0.0635)
			(type default)
		)
		(layer "In11.Cu")
	)
	(gr_line
		(start 172.719746 -109.027214)
		(end 172.81398 -108.93298)
		(stroke
			(width 0.0635)
			(type default)
		)
		(layer "In11.Cu")
	)
	(gr_line
		(start 172.7708 -109.44098)
		(end 172.7708 -109.7534)
		(stroke
			(width 0.0635)
			(type default)
		)
		(layer "In11.Cu")
	)
	(gr_line
		(start 172.81398 -108.65358)
		(end 172.81398 -108.93298)
		(stroke
			(width 0.0635)
			(type default)
		)
		(layer "In11.Cu")
	)
	(gr_line
		(start 212.667088 -99.42068)
		(end 212.965792 -99.121976)
		(stroke
			(width 0.0635)
			(type default)
		)
		(layer "In11.Cu")
	)
	(gr_line
		(start 212.96757 -99.120198)
		(end 213.0298 -99.057968)
		(stroke
			(width 0.0635)
			(type default)
		)
		(layer "In11.Cu")
	)
	(gr_line
		(start 213.2584 -99.087686)
		(end 213.290912 -99.120198)
		(stroke
			(width 0.0635)
			(type default)
		)
		(layer "In11.Cu")
	)
	(gr_line
		(start 213.29269 -99.121976)
		(end 213.581234 -99.41052)
		(stroke
			(width 0.0635)
			(type default)
		)
		(layer "In11.Cu")
	)
	(gr_line
		(start 231.0638 -84.91728)
		(end 231.20604 -84.91728)
		(stroke
			(width 0.0635)
			(type default)
		)
		(layer "In11.Cu")
	)
	(gr_line
		(start 231.20604 -84.91728)
		(end 231.21493 -84.90839)
		(stroke
			(width 0.04445)
			(type default)
		)
		(layer "In11.Cu")
	)
	(gr_line
		(start 231.24414 -84.68868)
		(end 231.27335 -84.71789)
		(stroke
			(width 0.04445)
			(type default)
		)
		(layer "In11.Cu")
	)
	(gr_line
		(start 231.27335 -84.71789)
		(end 231.41559 -84.71789)
		(stroke
			(width 0.04445)
			(type default)
		)
		(layer "In11.Cu")
	)
	(gr_line
		(start 240.695734 -81.933034)
		(end 240.73866 -81.97596)
		(stroke
			(width 0.04445)
			(type default)
		)
		(layer "In11.Cu")
	)
	(gr_line
		(start 240.703608 -81.741772)
		(end 240.73866 -81.70672)
		(stroke
			(width 0.04445)
			(type default)
		)
		(layer "In11.Cu")
	)
	(gr_line
		(start 240.740438 -81.977738)
		(end 240.763298 -82.000598)
		(stroke
			(width 0.04445)
			(type default)
		)
		(layer "In11.Cu")
	)
	(gr_line
		(start 240.740438 -81.704942)
		(end 240.763298 -81.682082)
		(stroke
			(width 0.04445)
			(type default)
		)
		(layer "In11.Cu")
	)
	(gr_line
		(start 240.763298 -82.000598)
		(end 240.763298 -82.33664)
		(stroke
			(width 0.04445)
			(type default)
		)
		(layer "In11.Cu")
	)
	(gr_line
		(start 240.763298 -81.34604)
		(end 240.763298 -81.682082)
		(stroke
			(width 0.04445)
			(type default)
		)
		(layer "In11.Cu")
	)
	(gr_line
		(start 294.08628 -78.688438)
		(end 294.379396 -78.857348)
		(stroke
			(width 0.04445)
			(type default)
		)
		(layer "In11.Cu")
	)
	(gr_line
		(start 294.379396 -78.857348)
		(end 294.43299 -78.84287)
		(stroke
			(width 0.04445)
			(type default)
		)
		(layer "In11.Cu")
	)
	(gr_line
		(start 294.43299 -95.328486)
		(end 294.437816 -95.337122)
		(stroke
			(width 0.04445)
			(type default)
		)
		(layer "In11.Cu")
	)
	(gr_line
		(start 294.439594 -78.841092)
		(end 294.468804 -78.833218)
		(stroke
			(width 0.04445)
			(type default)
		)
		(layer "In11.Cu")
	)
	(gr_line
		(start 294.593264 -94.234)
		(end 294.59809 -94.242636)
		(stroke
			(width 0.04445)
			(type default)
		)
		(layer "In11.Cu")
	)
	(gr_line
		(start 294.630602 -78.936088)
		(end 294.637968 -78.963266)
		(stroke
			(width 0.04445)
			(type default)
		)
		(layer "In11.Cu")
	)
	(gr_line
		(start 294.639492 -78.969362)
		(end 294.651684 -79.014828)
		(stroke
			(width 0.04445)
			(type default)
		)
		(layer "In11.Cu")
	)
	(gr_line
		(start 294.651684 -79.014828)
		(end 294.9448 -79.183738)
		(stroke
			(width 0.04445)
			(type default)
		)
		(layer "In11.Cu")
	)
	(gr_line
		(start 294.92321 -78.593188)
		(end 294.96639 -78.593188)
		(stroke
			(width 0.04445)
			(type default)
		)
		(layer "In11.Cu")
	)
	(gr_line
		(start 294.933624 -78.783688)
		(end 294.955976 -78.783688)
		(stroke
			(width 0.04445)
			(type default)
		)
		(layer "In11.Cu")
	)
	(gr_line
		(start 295.29151 -94.242636)
		(end 295.296336 -94.234)
		(stroke
			(width 0.04445)
			(type default)
		)
		(layer "In11.Cu")
	)
	(gr_line
		(start 295.451784 -95.337122)
		(end 295.45661 -95.328486)
		(stroke
			(width 0.04445)
			(type default)
		)
		(layer "In11.Cu")
	)
	(gr_line
		(start 295.78173 -79.278988)
		(end 295.821354 -79.278988)
		(stroke
			(width 0.04445)
			(type default)
		)
		(layer "In11.Cu")
	)
	(gr_line
		(start 295.785286 -79.088234)
		(end 295.8211 -79.088234)
		(stroke
			(width 0.04445)
			(type default)
		)
		(layer "In11.Cu")
	)
	(gr_line
		(start 296.15003 -95.328486)
		(end 296.154856 -95.337122)
		(stroke
			(width 0.04445)
			(type default)
		)
		(layer "In11.Cu")
	)
	(gr_line
		(start 296.310304 -100.1776)
		(end 296.31513 -100.186236)
		(stroke
			(width 0.04445)
			(type default)
		)
		(layer "In11.Cu")
	)
	(gr_line
		(start 296.64406 -79.774288)
		(end 296.67962 -79.774288)
		(stroke
			(width 0.04445)
			(type default)
		)
		(layer "In11.Cu")
	)
	(gr_line
		(start 296.650664 -79.583788)
		(end 296.66184 -79.583788)
		(stroke
			(width 0.04445)
			(type default)
		)
		(layer "In11.Cu")
	)
	(gr_line
		(start 297.004994 -79.389478)
		(end 297.008296 -79.383636)
		(stroke
			(width 0.04445)
			(type default)
		)
		(layer "In11.Cu")
	)
	(gr_line
		(start 297.17365 -100.28174)
		(end 297.18 -100.271072)
		(stroke
			(width 0.04445)
			(type default)
		)
		(layer "In11.Cu")
	)
	(gr_line
		(start 297.502326 -79.088234)
		(end 297.537886 -79.088234)
		(stroke
			(width 0.04445)
			(type default)
		)
		(layer "In11.Cu")
	)
	(gr_line
		(start 297.507914 -79.278988)
		(end 297.53814 -79.278988)
		(stroke
			(width 0.04445)
			(type default)
		)
		(layer "In11.Cu")
	)
	(gr_line
		(start 297.520106 -95.528384)
		(end 297.813222 -95.697548)
		(stroke
			(width 0.04445)
			(type default)
		)
		(layer "In11.Cu")
	)
	(gr_line
		(start 297.520106 -92.556584)
		(end 297.813222 -92.387674)
		(stroke
			(width 0.04445)
			(type default)
		)
		(layer "In11.Cu")
	)
	(gr_line
		(start 297.813222 -95.697548)
		(end 297.900598 -95.673926)
		(stroke
			(width 0.04445)
			(type default)
		)
		(layer "In11.Cu")
	)
	(gr_line
		(start 297.813222 -92.387674)
		(end 297.890438 -92.408502)
		(stroke
			(width 0.04445)
			(type default)
		)
		(layer "In11.Cu")
	)
	(gr_line
		(start 297.860466 -87.393018)
		(end 297.866816 -87.403686)
		(stroke
			(width 0.04445)
			(type default)
		)
		(layer "In11.Cu")
	)
	(gr_line
		(start 298.02709 -94.234)
		(end 298.031916 -94.242636)
		(stroke
			(width 0.04445)
			(type default)
		)
		(layer "In11.Cu")
	)
	(gr_line
		(start 298.062142 -92.317824)
		(end 298.08551 -92.230448)
		(stroke
			(width 0.04445)
			(type default)
		)
		(layer "In11.Cu")
	)
	(gr_line
		(start 298.064936 -95.777812)
		(end 298.08551 -95.854774)
		(stroke
			(width 0.04445)
			(type default)
		)
		(layer "In11.Cu")
	)
	(gr_line
		(start 298.08551 -95.854774)
		(end 298.378626 -96.023938)
		(stroke
			(width 0.04445)
			(type default)
		)
		(layer "In11.Cu")
	)
	(gr_line
		(start 298.08551 -92.230448)
		(end 298.378626 -92.061538)
		(stroke
			(width 0.04445)
			(type default)
		)
		(layer "In11.Cu")
	)
	(gr_line
		(start 298.360846 -79.774288)
		(end 298.396406 -79.774288)
		(stroke
			(width 0.04445)
			(type default)
		)
		(layer "In11.Cu")
	)
	(gr_line
		(start 298.36364 -95.623888)
		(end 298.393612 -95.623888)
		(stroke
			(width 0.04445)
			(type default)
		)
		(layer "In11.Cu")
	)
	(gr_line
		(start 298.36745 -79.583788)
		(end 298.389802 -79.583788)
		(stroke
			(width 0.04445)
			(type default)
		)
		(layer "In11.Cu")
	)
	(gr_line
		(start 298.378626 -95.033084)
		(end 298.671742 -94.864174)
		(stroke
			(width 0.04445)
			(type default)
		)
		(layer "In11.Cu")
	)
	(gr_line
		(start 298.378626 -93.704664)
		(end 298.378626 -94.042738)
		(stroke
			(width 0.04445)
			(type default)
		)
		(layer "In11.Cu")
	)
	(gr_line
		(start 298.378626 -93.704664)
		(end 298.399454 -93.683836)
		(stroke
			(width 0.04445)
			(type default)
		)
		(layer "In11.Cu")
	)
	(gr_line
		(start 298.378626 -93.390212)
		(end 298.399454 -93.41104)
		(stroke
			(width 0.04445)
			(type default)
		)
		(layer "In11.Cu")
	)
	(gr_line
		(start 298.378626 -93.052138)
		(end 298.378626 -93.390212)
		(stroke
			(width 0.04445)
			(type default)
		)
		(layer "In11.Cu")
	)
	(gr_line
		(start 298.378626 -91.070938)
		(end 298.671742 -91.239848)
		(stroke
			(width 0.04445)
			(type default)
		)
		(layer "In11.Cu")
	)
	(gr_line
		(start 298.378626 -88.099138)
		(end 298.671742 -87.929974)
		(stroke
			(width 0.04445)
			(type default)
		)
		(layer "In11.Cu")
	)
	(gr_line
		(start 298.401232 -93.682058)
		(end 298.443904 -93.639386)
		(stroke
			(width 0.04445)
			(type default)
		)
		(layer "In11.Cu")
	)
	(gr_line
		(start 298.401232 -93.412818)
		(end 298.436538 -93.448124)
		(stroke
			(width 0.04445)
			(type default)
		)
		(layer "In11.Cu")
	)
	(gr_line
		(start 298.671742 -94.864174)
		(end 298.759118 -94.887796)
		(stroke
			(width 0.04445)
			(type default)
		)
		(layer "In11.Cu")
	)
	(gr_line
		(start 298.671742 -91.239848)
		(end 298.692316 -91.31681)
		(stroke
			(width 0.04445)
			(type default)
		)
		(layer "In11.Cu")
	)
	(gr_line
		(start 298.671742 -87.929974)
		(end 298.692316 -87.853012)
		(stroke
			(width 0.04445)
			(type default)
		)
		(layer "In11.Cu")
	)
	(gr_line
		(start 298.856654 -91.420696)
		(end 298.94403 -91.397074)
		(stroke
			(width 0.04445)
			(type default)
		)
		(layer "In11.Cu")
	)
	(gr_line
		(start 298.856654 -87.749126)
		(end 298.94403 -87.772748)
		(stroke
			(width 0.04445)
			(type default)
		)
		(layer "In11.Cu")
	)
	(gr_line
		(start 298.923456 -94.78391)
		(end 298.94403 -94.706948)
		(stroke
			(width 0.04445)
			(type default)
		)
		(layer "In11.Cu")
	)
	(gr_line
		(start 298.94403 -94.706948)
		(end 298.958 -94.69882)
		(stroke
			(width 0.04445)
			(type default)
		)
		(layer "In11.Cu")
	)
	(gr_line
		(start 298.94403 -91.397074)
		(end 299.237146 -91.565984)
		(stroke
			(width 0.04445)
			(type default)
		)
		(layer "In11.Cu")
	)
	(gr_line
		(start 298.94403 -87.772748)
		(end 299.237146 -87.603584)
		(stroke
			(width 0.04445)
			(type default)
		)
		(layer "In11.Cu")
	)
	(gr_line
		(start 298.958 -94.69882)
		(end 298.9834 -94.684088)
		(stroke
			(width 0.04445)
			(type default)
		)
		(layer "In11.Cu")
	)
	(gr_line
		(start 298.98086 -102.8192)
		(end 298.99102 -102.83698)
		(stroke
			(width 0.04445)
			(type default)
		)
		(layer "In11.Cu")
	)
	(gr_line
		(start 298.9834 -94.684088)
		(end 299.237146 -94.538038)
		(stroke
			(width 0.04445)
			(type default)
		)
		(layer "In11.Cu")
	)
	(gr_line
		(start 299.181266 -103.559102)
		(end 299.222668 -103.600504)
		(stroke
			(width 0.04445)
			(type default)
		)
		(layer "In11.Cu")
	)
	(gr_line
		(start 299.183044 -103.28783)
		(end 299.305218 -103.28783)
		(stroke
			(width 0.04445)
			(type default)
		)
		(layer "In11.Cu")
	)
	(gr_line
		(start 299.219112 -79.278988)
		(end 299.25518 -79.278988)
		(stroke
			(width 0.04445)
			(type default)
		)
		(layer "In11.Cu")
	)
	(gr_line
		(start 299.219366 -79.088234)
		(end 299.254926 -79.088234)
		(stroke
			(width 0.04445)
			(type default)
		)
		(layer "In11.Cu")
	)
	(gr_line
		(start 299.237146 -93.547184)
		(end 299.530262 -93.716348)
		(stroke
			(width 0.04445)
			(type default)
		)
		(layer "In11.Cu")
	)
	(gr_line
		(start 299.237146 -90.575384)
		(end 299.530262 -90.406474)
		(stroke
			(width 0.04445)
			(type default)
		)
		(layer "In11.Cu")
	)
	(gr_line
		(start 299.237146 -89.24671)
		(end 299.237146 -89.584784)
		(stroke
			(width 0.04445)
			(type default)
		)
		(layer "In11.Cu")
	)
	(gr_line
		(start 299.237146 -89.24671)
		(end 299.257974 -89.225882)
		(stroke
			(width 0.04445)
			(type default)
		)
		(layer "In11.Cu")
	)
	(gr_line
		(start 299.237146 -88.932258)
		(end 299.257974 -88.953086)
		(stroke
			(width 0.04445)
			(type default)
		)
		(layer "In11.Cu")
	)
	(gr_line
		(start 299.237146 -88.594184)
		(end 299.237146 -88.932258)
		(stroke
			(width 0.04445)
			(type default)
		)
		(layer "In11.Cu")
	)
	(gr_line
		(start 299.237146 -86.612984)
		(end 299.530262 -86.782148)
		(stroke
			(width 0.04445)
			(type default)
		)
		(layer "In11.Cu")
	)
	(gr_line
		(start 299.259752 -89.224104)
		(end 299.30217 -89.181686)
		(stroke
			(width 0.04445)
			(type default)
		)
		(layer "In11.Cu")
	)
	(gr_line
		(start 299.259752 -88.954864)
		(end 299.295058 -88.99017)
		(stroke
			(width 0.04445)
			(type default)
		)
		(layer "In11.Cu")
	)
	(gr_line
		(start 299.305218 -103.28783)
		(end 299.49394 -103.476552)
		(stroke
			(width 0.04445)
			(type default)
		)
		(layer "In11.Cu")
	)
	(gr_line
		(start 299.49394 -103.476552)
		(end 299.49394 -103.598726)
		(stroke
			(width 0.04445)
			(type default)
		)
		(layer "In11.Cu")
	)
	(gr_line
		(start 299.530262 -93.716348)
		(end 299.617638 -93.692726)
		(stroke
			(width 0.04445)
			(type default)
		)
		(layer "In11.Cu")
	)
	(gr_line
		(start 299.530262 -90.406474)
		(end 299.607478 -90.427302)
		(stroke
			(width 0.04445)
			(type default)
		)
		(layer "In11.Cu")
	)
	(gr_line
		(start 299.530262 -86.782148)
		(end 299.617638 -86.758526)
		(stroke
			(width 0.04445)
			(type default)
		)
		(layer "In11.Cu")
	)
	(gr_line
		(start 299.684186 -104.062022)
		(end 299.725588 -104.103424)
		(stroke
			(width 0.04445)
			(type default)
		)
		(layer "In11.Cu")
	)
	(gr_line
		(start 299.685964 -103.79075)
		(end 299.808138 -103.79075)
		(stroke
			(width 0.04445)
			(type default)
		)
		(layer "In11.Cu")
	)
	(gr_line
		(start 299.779182 -90.336624)
		(end 299.80255 -90.249248)
		(stroke
			(width 0.04445)
			(type default)
		)
		(layer "In11.Cu")
	)
	(gr_line
		(start 299.781976 -93.796612)
		(end 299.80255 -93.873574)
		(stroke
			(width 0.04445)
			(type default)
		)
		(layer "In11.Cu")
	)
	(gr_line
		(start 299.781976 -86.862412)
		(end 299.80255 -86.939374)
		(stroke
			(width 0.04445)
			(type default)
		)
		(layer "In11.Cu")
	)
	(gr_line
		(start 299.80255 -93.873574)
		(end 300.095666 -94.042738)
		(stroke
			(width 0.04445)
			(type default)
		)
		(layer "In11.Cu")
	)
	(gr_line
		(start 299.80255 -90.249248)
		(end 300.095666 -90.080338)
		(stroke
			(width 0.04445)
			(type default)
		)
		(layer "In11.Cu")
	)
	(gr_line
		(start 299.80255 -86.939374)
		(end 300.095666 -87.108538)
		(stroke
			(width 0.04445)
			(type default)
		)
		(layer "In11.Cu")
	)
	(gr_line
		(start 299.808138 -103.79075)
		(end 299.99686 -103.979472)
		(stroke
			(width 0.04445)
			(type default)
		)
		(layer "In11.Cu")
	)
	(gr_line
		(start 299.99686 -103.979472)
		(end 299.99686 -104.101646)
		(stroke
			(width 0.04445)
			(type default)
		)
		(layer "In11.Cu")
	)
	(gr_line
		(start 300.077886 -79.774288)
		(end 300.113446 -79.774288)
		(stroke
			(width 0.04445)
			(type default)
		)
		(layer "In11.Cu")
	)
	(gr_arc
		(start 300.083474 -102.367334)
		(mid 300.083982 -102.367461)
		(end 300.08449 -102.367588)
		(stroke
			(width 0.04445)
			(type default)
		)
		(layer "In11.Cu")
	)
	(gr_line
		(start 300.08449 -79.583788)
		(end 300.106842 -79.583788)
		(stroke
			(width 0.04445)
			(type default)
		)
		(layer "In11.Cu")
	)
	(gr_line
		(start 300.095666 -89.089738)
		(end 300.388782 -89.258648)
		(stroke
			(width 0.04445)
			(type default)
		)
		(layer "In11.Cu")
	)
	(gr_line
		(start 300.095666 -86.117938)
		(end 300.346872 -85.972904)
		(stroke
			(width 0.04445)
			(type default)
		)
		(layer "In11.Cu")
	)
	(gr_line
		(start 300.262544 -104.712008)
		(end 300.278038 -104.727502)
		(stroke
			(width 0.04445)
			(type default)
		)
		(layer "In11.Cu")
	)
	(gr_line
		(start 300.262544 -104.698546)
		(end 300.262544 -104.712008)
		(stroke
			(width 0.04445)
			(type default)
		)
		(layer "In11.Cu")
	)
	(gr_line
		(start 300.262544 -104.64038)
		(end 300.262544 -104.696006)
		(stroke
			(width 0.04445)
			(type default)
		)
		(layer "In11.Cu")
	)
	(gr_line
		(start 300.346872 -85.972904)
		(end 300.476412 -85.972904)
		(stroke
			(width 0.04445)
			(type default)
		)
		(layer "In11.Cu")
	)
	(gr_line
		(start 300.388782 -89.258648)
		(end 300.409356 -89.33561)
		(stroke
			(width 0.04445)
			(type default)
		)
		(layer "In11.Cu")
	)
	(gr_line
		(start 300.397164 -104.505506)
		(end 300.453044 -104.505506)
		(stroke
			(width 0.04445)
			(type default)
		)
		(layer "In11.Cu")
	)
	(gr_line
		(start 300.455584 -104.505506)
		(end 300.4693 -104.505506)
		(stroke
			(width 0.04445)
			(type default)
		)
		(layer "In11.Cu")
	)
	(gr_line
		(start 300.4693 -104.505506)
		(end 300.484794 -104.521)
		(stroke
			(width 0.04445)
			(type default)
		)
		(layer "In11.Cu")
	)
	(gr_line
		(start 300.573694 -89.439496)
		(end 300.66107 -89.415874)
		(stroke
			(width 0.04445)
			(type default)
		)
		(layer "In11.Cu")
	)
	(gr_line
		(start 300.640496 -85.86851)
		(end 300.66107 -85.791548)
		(stroke
			(width 0.04445)
			(type default)
		)
		(layer "In11.Cu")
	)
	(gr_line
		(start 300.66107 -89.415874)
		(end 300.954186 -89.584784)
		(stroke
			(width 0.04445)
			(type default)
		)
		(layer "In11.Cu")
	)
	(gr_line
		(start 300.66107 -85.791548)
		(end 300.736 -85.748368)
		(stroke
			(width 0.04445)
			(type default)
		)
		(layer "In11.Cu")
	)
	(gr_line
		(start 300.736 -85.748368)
		(end 300.954186 -85.622384)
		(stroke
			(width 0.04445)
			(type default)
		)
		(layer "In11.Cu")
	)
	(gr_line
		(start 300.73854 -103.279702)
		(end 300.785784 -103.232458)
		(stroke
			(width 0.04445)
			(type default)
		)
		(layer "In11.Cu")
	)
	(gr_line
		(start 300.73854 -103.007414)
		(end 300.785784 -103.054658)
		(stroke
			(width 0.04445)
			(type default)
		)
		(layer "In11.Cu")
	)
	(gr_line
		(start 300.785784 -103.054658)
		(end 300.785784 -103.232458)
		(stroke
			(width 0.04445)
			(type default)
		)
		(layer "In11.Cu")
	)
	(gr_line
		(start 300.936152 -79.278988)
		(end 300.97222 -79.278988)
		(stroke
			(width 0.04445)
			(type default)
		)
		(layer "In11.Cu")
	)
	(gr_line
		(start 300.936406 -79.088234)
		(end 300.971966 -79.088234)
		(stroke
			(width 0.04445)
			(type default)
		)
		(layer "In11.Cu")
	)
	(gr_line
		(start 300.977046 -102.085902)
		(end 301.116492 -102.085902)
		(stroke
			(width 0.04445)
			(type default)
		)
		(layer "In11.Cu")
	)
	(gr_line
		(start 301.116492 -102.085902)
		(end 301.242222 -102.211632)
		(stroke
			(width 0.04445)
			(type default)
		)
		(layer "In11.Cu")
	)
	(gr_line
		(start 301.17923 -104.436164)
		(end 301.238666 -104.4956)
		(stroke
			(width 0.04445)
			(type default)
		)
		(layer "In11.Cu")
	)
	(gr_line
		(start 301.17923 -104.42321)
		(end 301.17923 -104.436164)
		(stroke
			(width 0.04445)
			(type default)
		)
		(layer "In11.Cu")
	)
	(gr_line
		(start 301.17923 -104.36479)
		(end 301.17923 -104.42067)
		(stroke
			(width 0.04445)
			(type default)
		)
		(layer "In11.Cu")
	)
	(gr_line
		(start 301.242222 -102.211632)
		(end 301.242222 -102.351078)
		(stroke
			(width 0.04445)
			(type default)
		)
		(layer "In11.Cu")
	)
	(gr_line
		(start 301.300896 -95.328486)
		(end 301.305722 -95.337122)
		(stroke
			(width 0.04445)
			(type default)
		)
		(layer "In11.Cu")
	)
	(gr_line
		(start 301.314104 -104.229916)
		(end 301.314358 -104.229916)
		(stroke
			(width 0.04445)
			(type default)
		)
		(layer "In11.Cu")
	)
	(gr_line
		(start 301.314612 -104.23017)
		(end 301.36973 -104.23017)
		(stroke
			(width 0.04445)
			(type default)
		)
		(layer "In11.Cu")
	)
	(gr_line
		(start 301.37227 -104.23017)
		(end 301.386494 -104.23017)
		(stroke
			(width 0.04445)
			(type default)
		)
		(layer "In11.Cu")
	)
	(gr_line
		(start 301.386494 -104.23017)
		(end 301.401988 -104.245664)
		(stroke
			(width 0.04445)
			(type default)
		)
		(layer "In11.Cu")
	)
	(gr_line
		(start 301.401988 -104.24541)
		(end 301.401988 -104.245664)
		(stroke
			(width 0.04445)
			(type default)
		)
		(layer "In11.Cu")
	)
	(gr_line
		(start 301.411132 -100.090986)
		(end 301.450756 -100.15982)
		(stroke
			(width 0.04445)
			(type default)
		)
		(layer "In11.Cu")
	)
	(gr_line
		(start 301.60595 -101.586284)
		(end 301.695866 -101.6762)
		(stroke
			(width 0.04445)
			(type default)
		)
		(layer "In11.Cu")
	)
	(gr_line
		(start 301.607728 -101.315012)
		(end 301.726346 -101.315012)
		(stroke
			(width 0.04445)
			(type default)
		)
		(layer "In11.Cu")
	)
	(gr_line
		(start 301.726346 -101.315012)
		(end 301.85233 -101.440996)
		(stroke
			(width 0.04445)
			(type default)
		)
		(layer "In11.Cu")
	)
	(gr_line
		(start 301.794926 -79.774288)
		(end 301.830486 -79.774288)
		(stroke
			(width 0.04445)
			(type default)
		)
		(layer "In11.Cu")
	)
	(gr_line
		(start 301.80153 -79.583788)
		(end 301.823882 -79.583788)
		(stroke
			(width 0.04445)
			(type default)
		)
		(layer "In11.Cu")
	)
	(gr_line
		(start 301.8028 -103.51516)
		(end 301.8028 -103.537258)
		(stroke
			(width 0.04445)
			(type default)
		)
		(layer "In11.Cu")
	)
	(gr_line
		(start 301.8028 -103.51516)
		(end 301.812452 -103.505508)
		(stroke
			(width 0.04445)
			(type default)
		)
		(layer "In11.Cu")
	)
	(gr_line
		(start 301.81423 -103.50373)
		(end 301.8536 -103.46436)
		(stroke
			(width 0.04445)
			(type default)
		)
		(layer "In11.Cu")
	)
	(gr_line
		(start 301.85233 -101.440996)
		(end 301.85233 -101.559614)
		(stroke
			(width 0.04445)
			(type default)
		)
		(layer "In11.Cu")
	)
	(gr_line
		(start 301.864522 -101.844856)
		(end 302.0695 -102.04958)
		(stroke
			(width 0.04445)
			(type default)
		)
		(layer "In11.Cu")
	)
	(gr_line
		(start 301.981108 -101.688392)
		(end 302.09998 -101.688392)
		(stroke
			(width 0.04445)
			(type default)
		)
		(layer "In11.Cu")
	)
	(gr_line
		(start 302.0441 -103.46436)
		(end 302.08347 -103.50373)
		(stroke
			(width 0.04445)
			(type default)
		)
		(layer "In11.Cu")
	)
	(gr_line
		(start 302.085248 -103.505508)
		(end 302.0949 -103.51516)
		(stroke
			(width 0.04445)
			(type default)
		)
		(layer "In11.Cu")
	)
	(gr_line
		(start 302.0949 -103.51516)
		(end 302.0949 -103.537258)
		(stroke
			(width 0.04445)
			(type default)
		)
		(layer "In11.Cu")
	)
	(gr_line
		(start 302.09998 -101.688392)
		(end 302.225964 -101.814376)
		(stroke
			(width 0.04445)
			(type default)
		)
		(layer "In11.Cu")
	)
	(gr_line
		(start 302.159416 -94.242636)
		(end 302.164242 -94.234)
		(stroke
			(width 0.04445)
			(type default)
		)
		(layer "In11.Cu")
	)
	(gr_line
		(start 302.225964 -101.814376)
		(end 302.225964 -101.933248)
		(stroke
			(width 0.04445)
			(type default)
		)
		(layer "In11.Cu")
	)
	(gr_line
		(start 302.274478 -99.759262)
		(end 302.281082 -99.762056)
		(stroke
			(width 0.04445)
			(type default)
		)
		(layer "In11.Cu")
	)
	(gr_line
		(start 302.316642 -98.89109)
		(end 302.442372 -99.01682)
		(stroke
			(width 0.04445)
			(type default)
		)
		(layer "In11.Cu")
	)
	(gr_line
		(start 302.316642 -98.771964)
		(end 302.316642 -98.89109)
		(stroke
			(width 0.04445)
			(type default)
		)
		(layer "In11.Cu")
	)
	(gr_line
		(start 302.31969 -95.337122)
		(end 302.324516 -95.328486)
		(stroke
			(width 0.04445)
			(type default)
		)
		(layer "In11.Cu")
	)
	(gr_line
		(start 302.35525 -102.33533)
		(end 302.428656 -102.408736)
		(stroke
			(width 0.04445)
			(type default)
		)
		(layer "In11.Cu")
	)
	(gr_line
		(start 302.356774 -102.064058)
		(end 302.459136 -102.064058)
		(stroke
			(width 0.04445)
			(type default)
		)
		(layer "In11.Cu")
	)
	(gr_line
		(start 302.442372 -99.01682)
		(end 302.561498 -99.01682)
		(stroke
			(width 0.04445)
			(type default)
		)
		(layer "In11.Cu")
	)
	(gr_line
		(start 302.453548 -104.663748)
		(end 302.473614 -104.67213)
		(stroke
			(width 0.05715)
			(type default)
		)
		(layer "In11.Cu")
	)
	(gr_line
		(start 302.459136 -102.064058)
		(end 302.58512 -102.190042)
		(stroke
			(width 0.04445)
			(type default)
		)
		(layer "In11.Cu")
	)
	(gr_line
		(start 302.58512 -102.190042)
		(end 302.58512 -102.292404)
		(stroke
			(width 0.04445)
			(type default)
		)
		(layer "In11.Cu")
	)
	(gr_line
		(start 302.653192 -79.278988)
		(end 302.692816 -79.278988)
		(stroke
			(width 0.04445)
			(type default)
		)
		(layer "In11.Cu")
	)
	(gr_line
		(start 302.653446 -79.088234)
		(end 302.68926 -79.088234)
		(stroke
			(width 0.04445)
			(type default)
		)
		(layer "In11.Cu")
	)
	(gr_line
		(start 302.811434 -99.2632)
		(end 302.817276 -99.26574)
		(stroke
			(width 0.04445)
			(type default)
		)
		(layer "In11.Cu")
	)
	(gr_line
		(start 302.834548 -98.379788)
		(end 302.858932 -98.503486)
		(stroke
			(width 0.04445)
			(type default)
		)
		(layer "In11.Cu")
	)
	(gr_line
		(start 302.858932 -98.503486)
		(end 303.007014 -98.602292)
		(stroke
			(width 0.04445)
			(type default)
		)
		(layer "In11.Cu")
	)
	(gr_line
		(start 302.965866 -98.235516)
		(end 303.21504 -98.40214)
		(stroke
			(width 0.04445)
			(type default)
		)
		(layer "In11.Cu")
	)
	(gr_line
		(start 302.97628 -99.33559)
		(end 303.020984 -99.445826)
		(stroke
			(width 0.04445)
			(type default)
		)
		(layer "In11.Cu")
	)
	(gr_arc
		(start 302.9839 -97.241106)
		(mid 302.830233 -96.878889)
		(end 302.671226 -96.518984)
		(stroke
			(width 0.04445)
			(type default)
		)
		(layer "In11.Cu")
	)
	(gr_line
		(start 303.007014 -98.602292)
		(end 303.130712 -98.577654)
		(stroke
			(width 0.04445)
			(type default)
		)
		(layer "In11.Cu")
	)
	(gr_line
		(start 303.014634 -99.142296)
		(end 303.052734 -99.158298)
		(stroke
			(width 0.04445)
			(type default)
		)
		(layer "In11.Cu")
	)
	(gr_line
		(start 303.020984 -99.445826)
		(end 303.184814 -99.515168)
		(stroke
			(width 0.04445)
			(type default)
		)
		(layer "In11.Cu")
	)
	(gr_line
		(start 303.078642 -99.169474)
		(end 303.344326 -99.281742)
		(stroke
			(width 0.04445)
			(type default)
		)
		(layer "In11.Cu")
	)
	(gr_line
		(start 303.082198 -100.09378)
		(end 303.287176 -100.178616)
		(stroke
			(width 0.04445)
			(type default)
		)
		(layer "In11.Cu")
	)
	(gr_line
		(start 303.129442 -99.90455)
		(end 303.195482 -99.877118)
		(stroke
			(width 0.04445)
			(type default)
		)
		(layer "In11.Cu")
	)
	(gr_line
		(start 303.141126 -101.179884)
		(end 303.266856 -101.305614)
		(stroke
			(width 0.04445)
			(type default)
		)
		(layer "In11.Cu")
	)
	(gr_line
		(start 303.141126 -101.077522)
		(end 303.141126 -101.179884)
		(stroke
			(width 0.04445)
			(type default)
		)
		(layer "In11.Cu")
	)
	(gr_line
		(start 303.165002 -104.958134)
		(end 303.182274 -104.9655)
		(stroke
			(width 0.05715)
			(type default)
		)
		(layer "In11.Cu")
	)
	(gr_line
		(start 303.178464 -102.88905)
		(end 303.2125 -102.923086)
		(stroke
			(width 0.04445)
			(type default)
		)
		(layer "In11.Cu")
	)
	(gr_line
		(start 303.184814 -99.515168)
		(end 303.294796 -99.470464)
		(stroke
			(width 0.04445)
			(type default)
		)
		(layer "In11.Cu")
	)
	(gr_line
		(start 303.195482 -99.877118)
		(end 303.360074 -99.94519)
		(stroke
			(width 0.04445)
			(type default)
		)
		(layer "In11.Cu")
	)
	(gr_line
		(start 303.266856 -101.305614)
		(end 303.369218 -101.305614)
		(stroke
			(width 0.04445)
			(type default)
		)
		(layer "In11.Cu")
	)
	(gr_line
		(start 303.299114 -98.690176)
		(end 303.320704 -98.799142)
		(stroke
			(width 0.04445)
			(type default)
		)
		(layer "In11.Cu")
	)
	(gr_line
		(start 303.320704 -98.799142)
		(end 303.468786 -98.897948)
		(stroke
			(width 0.04445)
			(type default)
		)
		(layer "In11.Cu")
	)
	(gr_line
		(start 303.360074 -99.94519)
		(end 303.387506 -100.011484)
		(stroke
			(width 0.04445)
			(type default)
		)
		(layer "In11.Cu")
	)
	(gr_line
		(start 303.429416 -98.545142)
		(end 303.661318 -98.700082)
		(stroke
			(width 0.04445)
			(type default)
		)
		(layer "In11.Cu")
	)
	(gr_line
		(start 303.433988 -99.526598)
		(end 303.461674 -99.538282)
		(stroke
			(width 0.04445)
			(type default)
		)
		(layer "In11.Cu")
	)
	(gr_line
		(start 303.462944 -99.541584)
		(end 303.507648 -99.65182)
		(stroke
			(width 0.04445)
			(type default)
		)
		(layer "In11.Cu")
	)
	(gr_line
		(start 303.468786 -98.897948)
		(end 303.577498 -98.876358)
		(stroke
			(width 0.04445)
			(type default)
		)
		(layer "In11.Cu")
	)
	(gr_line
		(start 303.507648 -99.65182)
		(end 303.671478 -99.721162)
		(stroke
			(width 0.04445)
			(type default)
		)
		(layer "In11.Cu")
	)
	(gr_line
		(start 303.508156 -78.593188)
		(end 303.551336 -78.593188)
		(stroke
			(width 0.04445)
			(type default)
		)
		(layer "In11.Cu")
	)
	(gr_line
		(start 303.51857 -78.783688)
		(end 303.540922 -78.783688)
		(stroke
			(width 0.04445)
			(type default)
		)
		(layer "In11.Cu")
	)
	(gr_line
		(start 303.519078 -99.355656)
		(end 303.539398 -99.364292)
		(stroke
			(width 0.04445)
			(type default)
		)
		(layer "In11.Cu")
	)
	(gr_line
		(start 303.527206 -101.570282)
		(end 303.652936 -101.696012)
		(stroke
			(width 0.04445)
			(type default)
		)
		(layer "In11.Cu")
	)
	(gr_line
		(start 303.527206 -101.463602)
		(end 303.527206 -101.570282)
		(stroke
			(width 0.04445)
			(type default)
		)
		(layer "In11.Cu")
	)
	(gr_arc
		(start 303.529746 -97.014538)
		(mid 303.417723 -96.754648)
		(end 303.15789 -96.86671)
		(stroke
			(width 0.04445)
			(type default)
		)
		(layer "In11.Cu")
	)
	(gr_line
		(start 303.529746 -96.023938)
		(end 303.822862 -95.854774)
		(stroke
			(width 0.04445)
			(type default)
		)
		(layer "In11.Cu")
	)
	(gr_line
		(start 303.529746 -94.69501)
		(end 303.529746 -95.033084)
		(stroke
			(width 0.04445)
			(type default)
		)
		(layer "In11.Cu")
	)
	(gr_line
		(start 303.529746 -94.69501)
		(end 303.550574 -94.674182)
		(stroke
			(width 0.04445)
			(type default)
		)
		(layer "In11.Cu")
	)
	(gr_line
		(start 303.529746 -94.380558)
		(end 303.550574 -94.401386)
		(stroke
			(width 0.04445)
			(type default)
		)
		(layer "In11.Cu")
	)
	(gr_line
		(start 303.529746 -94.042738)
		(end 303.529746 -94.380558)
		(stroke
			(width 0.04445)
			(type default)
		)
		(layer "In11.Cu")
	)
	(gr_line
		(start 303.529746 -92.061538)
		(end 303.60874 -92.052648)
		(stroke
			(width 0.04445)
			(type default)
		)
		(layer "In11.Cu")
	)
	(gr_line
		(start 303.552352 -94.672404)
		(end 303.595024 -94.629732)
		(stroke
			(width 0.04445)
			(type default)
		)
		(layer "In11.Cu")
	)
	(gr_line
		(start 303.552352 -94.403164)
		(end 303.587658 -94.43847)
		(stroke
			(width 0.04445)
			(type default)
		)
		(layer "In11.Cu")
	)
	(gr_line
		(start 303.565306 -99.375468)
		(end 303.831498 -99.48799)
		(stroke
			(width 0.04445)
			(type default)
		)
		(layer "In11.Cu")
	)
	(gr_line
		(start 303.60874 -92.052648)
		(end 304.260504 -91.97975)
		(stroke
			(width 0.04445)
			(type default)
		)
		(layer "In11.Cu")
	)
	(gr_line
		(start 303.652936 -101.696012)
		(end 303.759616 -101.696012)
		(stroke
			(width 0.04445)
			(type default)
		)
		(layer "In11.Cu")
	)
	(gr_line
		(start 303.671478 -99.721162)
		(end 303.781714 -99.676458)
		(stroke
			(width 0.04445)
			(type default)
		)
		(layer "In11.Cu")
	)
	(gr_line
		(start 303.822862 -95.854774)
		(end 303.84623 -95.767398)
		(stroke
			(width 0.04445)
			(type default)
		)
		(layer "In11.Cu")
	)
	(gr_line
		(start 303.894744 -101.950266)
		(end 304.020474 -102.075996)
		(stroke
			(width 0.04445)
			(type default)
		)
		(layer "In11.Cu")
	)
	(gr_line
		(start 303.894744 -101.83114)
		(end 303.894744 -101.950266)
		(stroke
			(width 0.04445)
			(type default)
		)
		(layer "In11.Cu")
	)
	(gr_line
		(start 303.949608 -99.747578)
		(end 303.994312 -99.857814)
		(stroke
			(width 0.04445)
			(type default)
		)
		(layer "In11.Cu")
	)
	(gr_line
		(start 303.954434 -97.939606)
		(end 303.957482 -97.94494)
		(stroke
			(width 0.04445)
			(type default)
		)
		(layer "In11.Cu")
	)
	(gr_line
		(start 303.957482 -97.94494)
		(end 303.962562 -97.94875)
		(stroke
			(width 0.04445)
			(type default)
		)
		(layer "In11.Cu")
	)
	(gr_line
		(start 303.994312 -99.857814)
		(end 304.158142 -99.927156)
		(stroke
			(width 0.04445)
			(type default)
		)
		(layer "In11.Cu")
	)
	(gr_line
		(start 304.014124 -81.124806)
		(end 304.054002 -81.055464)
		(stroke
			(width 0.04445)
			(type default)
		)
		(layer "In11.Cu")
	)
	(gr_line
		(start 304.018188 -95.67672)
		(end 304.09515 -95.697548)
		(stroke
			(width 0.04445)
			(type default)
		)
		(layer "In11.Cu")
	)
	(gr_line
		(start 304.020474 -102.075996)
		(end 304.1396 -102.075996)
		(stroke
			(width 0.04445)
			(type default)
		)
		(layer "In11.Cu")
	)
	(gr_line
		(start 304.029872 -92.378784)
		(end 304.066702 -92.451428)
		(stroke
			(width 0.04445)
			(type default)
		)
		(layer "In11.Cu")
	)
	(gr_line
		(start 304.03673 -95.337122)
		(end 304.041556 -95.328486)
		(stroke
			(width 0.04445)
			(type default)
		)
		(layer "In11.Cu")
	)
	(gr_line
		(start 304.051208 -99.580954)
		(end 304.31867 -99.693984)
		(stroke
			(width 0.04445)
			(type default)
		)
		(layer "In11.Cu")
	)
	(gr_line
		(start 304.066702 -92.451428)
		(end 304.388266 -92.556584)
		(stroke
			(width 0.04445)
			(type default)
		)
		(layer "In11.Cu")
	)
	(gr_arc
		(start 304.074068 -92.308934)
		(mid 304.050183 -92.342727)
		(end 304.029872 -92.378784)
		(stroke
			(width 0.04445)
			(type default)
		)
		(layer "In11.Cu")
	)
	(gr_line
		(start 304.09515 -95.697548)
		(end 304.388266 -95.528384)
		(stroke
			(width 0.04445)
			(type default)
		)
		(layer "In11.Cu")
	)
	(gr_line
		(start 304.132234 -98.07956)
		(end 304.159412 -98.100388)
		(stroke
			(width 0.04445)
			(type default)
		)
		(layer "In11.Cu")
	)
	(gr_line
		(start 304.158142 -99.927156)
		(end 304.268378 -99.882452)
		(stroke
			(width 0.04445)
			(type default)
		)
		(layer "In11.Cu")
	)
	(gr_line
		(start 304.330354 -96.91497)
		(end 304.388266 -96.857058)
		(stroke
			(width 0.04445)
			(type default)
		)
		(layer "In11.Cu")
	)
	(gr_line
		(start 304.366676 -79.278988)
		(end 304.986944 -79.278988)
		(stroke
			(width 0.04445)
			(type default)
		)
		(layer "In11.Cu")
	)
	(gr_line
		(start 304.370232 -79.088234)
		(end 304.987198 -79.088234)
		(stroke
			(width 0.04445)
			(type default)
		)
		(layer "In11.Cu")
	)
	(gr_arc
		(start 304.388266 -97.509584)
		(mid 304.250197 -97.220486)
		(end 304.029364 -96.988376)
		(stroke
			(width 0.04445)
			(type default)
		)
		(layer "In11.Cu")
	)
	(gr_line
		(start 304.388266 -96.518984)
		(end 304.388266 -96.857058)
		(stroke
			(width 0.04445)
			(type default)
		)
		(layer "In11.Cu")
	)
	(gr_line
		(start 304.388266 -94.538038)
		(end 304.54219 -94.642432)
		(stroke
			(width 0.04445)
			(type default)
		)
		(layer "In11.Cu")
	)
	(gr_line
		(start 304.388266 -91.565984)
		(end 305.100736 -91.654376)
		(stroke
			(width 0.04445)
			(type default)
		)
		(layer "In11.Cu")
	)
	(gr_line
		(start 304.388266 -90.274648)
		(end 304.388266 -90.575384)
		(stroke
			(width 0.04445)
			(type default)
		)
		(layer "In11.Cu")
	)
	(gr_line
		(start 304.388266 -90.274648)
		(end 304.449226 -90.213688)
		(stroke
			(width 0.04445)
			(type default)
		)
		(layer "In11.Cu")
	)
	(gr_line
		(start 304.388266 -89.879678)
		(end 304.449226 -89.940638)
		(stroke
			(width 0.04445)
			(type default)
		)
		(layer "In11.Cu")
	)
	(gr_line
		(start 304.388266 -89.584784)
		(end 304.388266 -89.879678)
		(stroke
			(width 0.04445)
			(type default)
		)
		(layer "In11.Cu")
	)
	(gr_line
		(start 304.388266 -87.603584)
		(end 304.665634 -87.763604)
		(stroke
			(width 0.04445)
			(type default)
		)
		(layer "In11.Cu")
	)
	(gr_line
		(start 304.388266 -84.631784)
		(end 304.681382 -84.462874)
		(stroke
			(width 0.04445)
			(type default)
		)
		(layer "In11.Cu")
	)
	(gr_line
		(start 304.436272 -99.953572)
		(end 304.480976 -100.063808)
		(stroke
			(width 0.04445)
			(type default)
		)
		(layer "In11.Cu")
	)
	(gr_line
		(start 304.451004 -90.21191)
		(end 304.48758 -90.175334)
		(stroke
			(width 0.04445)
			(type default)
		)
		(layer "In11.Cu")
	)
	(gr_line
		(start 304.451004 -89.942416)
		(end 304.493422 -89.984834)
		(stroke
			(width 0.04445)
			(type default)
		)
		(layer "In11.Cu")
	)
	(gr_line
		(start 304.455068 -100.456238)
		(end 304.461672 -100.459032)
		(stroke
			(width 0.04445)
			(type default)
		)
		(layer "In11.Cu")
	)
	(gr_line
		(start 304.480976 -100.063808)
		(end 304.64506 -100.13315)
		(stroke
			(width 0.04445)
			(type default)
		)
		(layer "In11.Cu")
	)
	(gr_line
		(start 304.53711 -99.78644)
		(end 304.804826 -99.899724)
		(stroke
			(width 0.04445)
			(type default)
		)
		(layer "In11.Cu")
	)
	(gr_line
		(start 304.54219 -94.642432)
		(end 304.671222 -94.617794)
		(stroke
			(width 0.04445)
			(type default)
		)
		(layer "In11.Cu")
	)
	(gr_line
		(start 304.64506 -100.13315)
		(end 304.755042 -100.088446)
		(stroke
			(width 0.04445)
			(type default)
		)
		(layer "In11.Cu")
	)
	(gr_line
		(start 304.659538 -100.99802)
		(end 304.659792 -100.930202)
		(stroke
			(width 0.04445)
			(type default)
		)
		(layer "In11.Cu")
	)
	(gr_line
		(start 304.659538 -100.99802)
		(end 304.675286 -101.013768)
		(stroke
			(width 0.04445)
			(type default)
		)
		(layer "In11.Cu")
	)
	(gr_line
		(start 304.665634 -87.763604)
		(end 304.738786 -87.743792)
		(stroke
			(width 0.04445)
			(type default)
		)
		(layer "In11.Cu")
	)
	(gr_line
		(start 304.671222 -94.617794)
		(end 304.801524 -94.548706)
		(stroke
			(width 0.04445)
			(type default)
		)
		(layer "In11.Cu")
	)
	(gr_line
		(start 304.681382 -84.462874)
		(end 304.768758 -84.486496)
		(stroke
			(width 0.04445)
			(type default)
		)
		(layer "In11.Cu")
	)
	(gr_line
		(start 304.738786 -87.743792)
		(end 304.76952 -87.713312)
		(stroke
			(width 0.04445)
			(type default)
		)
		(layer "In11.Cu")
	)
	(gr_line
		(start 304.740818 -81.248504)
		(end 304.827178 -81.334864)
		(stroke
			(width 0.04445)
			(type default)
		)
		(layer "In11.Cu")
	)
	(gr_line
		(start 304.797968 -100.791772)
		(end 304.866548 -100.791772)
		(stroke
			(width 0.04445)
			(type default)
		)
		(layer "In11.Cu")
	)
	(gr_line
		(start 304.827178 -81.334864)
		(end 305.093878 -81.334864)
		(stroke
			(width 0.04445)
			(type default)
		)
		(layer "In11.Cu")
	)
	(gr_line
		(start 304.866548 -100.791772)
		(end 304.882042 -100.807266)
		(stroke
			(width 0.04445)
			(type default)
		)
		(layer "In11.Cu")
	)
	(gr_line
		(start 304.882042 -100.807012)
		(end 304.882042 -100.807266)
		(stroke
			(width 0.04445)
			(type default)
		)
		(layer "In11.Cu")
	)
	(gr_line
		(start 304.888392 -91.249246)
		(end 304.925222 -91.176602)
		(stroke
			(width 0.04445)
			(type default)
		)
		(layer "In11.Cu")
	)
	(gr_arc
		(start 304.888392 -91.249246)
		(mid 304.908726 -91.285165)
		(end 304.932588 -91.318842)
		(stroke
			(width 0.04445)
			(type default)
		)
		(layer "In11.Cu")
	)
	(gr_line
		(start 304.925222 -91.176602)
		(end 305.246786 -91.070938)
		(stroke
			(width 0.04445)
			(type default)
		)
		(layer "In11.Cu")
	)
	(gr_line
		(start 304.926746 -87.829136)
		(end 304.95367 -87.929974)
		(stroke
			(width 0.04445)
			(type default)
		)
		(layer "In11.Cu")
	)
	(gr_line
		(start 304.931318 -81.055464)
		(end 304.989738 -81.055464)
		(stroke
			(width 0.04445)
			(type default)
		)
		(layer "In11.Cu")
	)
	(gr_arc
		(start 304.932588 -91.318842)
		(mid 305.065495 -91.427764)
		(end 305.2318 -91.470988)
		(stroke
			(width 0.04445)
			(type default)
		)
		(layer "In11.Cu")
	)
	(gr_line
		(start 304.933096 -84.38261)
		(end 304.95367 -84.305648)
		(stroke
			(width 0.04445)
			(type default)
		)
		(layer "In11.Cu")
	)
	(gr_line
		(start 304.95367 -87.929974)
		(end 305.246786 -88.099138)
		(stroke
			(width 0.04445)
			(type default)
		)
		(layer "In11.Cu")
	)
	(gr_line
		(start 304.95367 -84.305648)
		(end 305.246786 -84.136738)
		(stroke
			(width 0.04445)
			(type default)
		)
		(layer "In11.Cu")
	)
	(gr_line
		(start 304.955702 -104.1146)
		(end 304.995072 -104.15397)
		(stroke
			(width 0.04445)
			(type default)
		)
		(layer "In11.Cu")
	)
	(gr_line
		(start 304.955702 -103.9241)
		(end 304.995072 -103.88473)
		(stroke
			(width 0.04445)
			(type default)
		)
		(layer "In11.Cu")
	)
	(gr_line
		(start 304.978308 -94.756732)
		(end 305.016154 -94.89948)
		(stroke
			(width 0.04445)
			(type default)
		)
		(layer "In11.Cu")
	)
	(gr_line
		(start 304.978308 -94.756732)
		(end 305.020218 -94.603062)
		(stroke
			(width 0.04445)
			(type default)
		)
		(layer "In11.Cu")
	)
	(gr_line
		(start 304.986944 -79.278988)
		(end 305.018694 -79.310738)
		(stroke
			(width 0.04445)
			(type default)
		)
		(layer "In11.Cu")
	)
	(gr_line
		(start 304.987198 -79.088234)
		(end 305.018694 -79.056738)
		(stroke
			(width 0.04445)
			(type default)
		)
		(layer "In11.Cu")
	)
	(gr_line
		(start 304.99685 -104.155748)
		(end 305.006502 -104.1654)
		(stroke
			(width 0.04445)
			(type default)
		)
		(layer "In11.Cu")
	)
	(gr_line
		(start 304.99685 -103.882952)
		(end 305.006502 -103.8733)
		(stroke
			(width 0.04445)
			(type default)
		)
		(layer "In11.Cu")
	)
	(gr_line
		(start 305.006502 -104.1654)
		(end 305.0286 -104.1654)
		(stroke
			(width 0.04445)
			(type default)
		)
		(layer "In11.Cu")
	)
	(gr_line
		(start 305.006502 -103.8733)
		(end 305.0286 -103.8733)
		(stroke
			(width 0.04445)
			(type default)
		)
		(layer "In11.Cu")
	)
	(gr_line
		(start 305.016154 -94.89948)
		(end 305.246786 -95.033084)
		(stroke
			(width 0.04445)
			(type default)
		)
		(layer "In11.Cu")
	)
	(gr_line
		(start 305.018694 -79.310738)
		(end 305.040792 -79.310738)
		(stroke
			(width 0.04445)
			(type default)
		)
		(layer "In11.Cu")
	)
	(gr_line
		(start 305.018694 -79.056738)
		(end 305.040792 -79.056738)
		(stroke
			(width 0.04445)
			(type default)
		)
		(layer "In11.Cu")
	)
	(gr_line
		(start 305.040792 -79.310738)
		(end 305.219608 -79.310738)
		(stroke
			(width 0.0635)
			(type default)
		)
		(layer "In11.Cu")
	)
	(gr_line
		(start 305.040792 -79.056738)
		(end 305.219354 -79.056738)
		(stroke
			(width 0.0635)
			(type default)
		)
		(layer "In11.Cu")
	)
	(gr_line
		(start 305.07051 -100.012246)
		(end 305.076352 -100.014786)
		(stroke
			(width 0.04445)
			(type default)
		)
		(layer "In11.Cu")
	)
	(gr_line
		(start 305.087274 -100.367338)
		(end 305.102768 -100.382832)
		(stroke
			(width 0.04445)
			(type default)
		)
		(layer "In11.Cu")
	)
	(gr_line
		(start 305.087274 -100.353622)
		(end 305.087274 -100.367338)
		(stroke
			(width 0.04445)
			(type default)
		)
		(layer "In11.Cu")
	)
	(gr_line
		(start 305.087274 -100.295202)
		(end 305.087274 -100.351082)
		(stroke
			(width 0.04445)
			(type default)
		)
		(layer "In11.Cu")
	)
	(gr_line
		(start 305.093878 -81.334864)
		(end 305.180238 -81.248504)
		(stroke
			(width 0.04445)
			(type default)
		)
		(layer "In11.Cu")
	)
	(gr_arc
		(start 305.100736 -91.654376)
		(mid 305.16794 -91.65994)
		(end 305.235356 -91.661488)
		(stroke
			(width 0.04445)
			(type default)
		)
		(layer "In11.Cu")
	)
	(gr_line
		(start 305.222148 -100.160582)
		(end 305.277774 -100.160582)
		(stroke
			(width 0.04445)
			(type default)
		)
		(layer "In11.Cu")
	)
	(gr_line
		(start 305.237642 -94.385638)
		(end 305.377088 -94.385638)
		(stroke
			(width 0.04445)
			(type default)
		)
		(layer "In11.Cu")
	)
	(gr_line
		(start 305.246786 -87.108538)
		(end 305.539902 -86.939374)
		(stroke
			(width 0.04445)
			(type default)
		)
		(layer "In11.Cu")
	)
	(gr_line
		(start 305.246786 -85.806788)
		(end 305.246786 -86.117938)
		(stroke
			(width 0.04445)
			(type default)
		)
		(layer "In11.Cu")
	)
	(gr_line
		(start 305.246786 -85.806788)
		(end 305.294538 -85.759036)
		(stroke
			(width 0.04445)
			(type default)
		)
		(layer "In11.Cu")
	)
	(gr_line
		(start 305.246786 -85.438488)
		(end 305.294538 -85.48624)
		(stroke
			(width 0.04445)
			(type default)
		)
		(layer "In11.Cu")
	)
	(gr_line
		(start 305.246786 -85.127338)
		(end 305.246786 -85.438488)
		(stroke
			(width 0.04445)
			(type default)
		)
		(layer "In11.Cu")
	)
	(gr_line
		(start 305.263042 -93.202506)
		(end 305.269646 -93.199712)
		(stroke
			(width 0.04445)
			(type default)
		)
		(layer "In11.Cu")
	)
	(gr_line
		(start 305.280314 -100.160582)
		(end 305.29403 -100.160582)
		(stroke
			(width 0.04445)
			(type default)
		)
		(layer "In11.Cu")
	)
	(gr_line
		(start 305.29403 -100.160582)
		(end 305.309524 -100.176076)
		(stroke
			(width 0.04445)
			(type default)
		)
		(layer "In11.Cu")
	)
	(gr_line
		(start 305.296316 -85.757258)
		(end 305.335686 -85.717888)
		(stroke
			(width 0.04445)
			(type default)
		)
		(layer "In11.Cu")
	)
	(gr_line
		(start 305.296316 -85.488018)
		(end 305.335686 -85.527388)
		(stroke
			(width 0.04445)
			(type default)
		)
		(layer "In11.Cu")
	)
	(gr_line
		(start 305.377088 -94.385638)
		(end 305.502818 -94.259908)
		(stroke
			(width 0.04445)
			(type default)
		)
		(layer "In11.Cu")
	)
	(gr_line
		(start 305.410616 -83.738974)
		(end 305.467258 -83.795616)
		(stroke
			(width 0.04445)
			(type default)
		)
		(layer "In11.Cu")
	)
	(gr_line
		(start 305.452018 -81.248504)
		(end 305.538378 -81.334864)
		(stroke
			(width 0.04445)
			(type default)
		)
		(layer "In11.Cu")
	)
	(gr_line
		(start 305.467258 -83.795616)
		(end 305.733958 -83.795616)
		(stroke
			(width 0.04445)
			(type default)
		)
		(layer "In11.Cu")
	)
	(gr_line
		(start 305.502818 -94.120462)
		(end 305.502818 -94.259908)
		(stroke
			(width 0.04445)
			(type default)
		)
		(layer "In11.Cu")
	)
	(gr_line
		(start 305.520598 -101.85908)
		(end 305.540664 -101.867462)
		(stroke
			(width 0.05715)
			(type default)
		)
		(layer "In11.Cu")
	)
	(gr_line
		(start 305.538378 -81.334864)
		(end 305.805078 -81.334864)
		(stroke
			(width 0.04445)
			(type default)
		)
		(layer "In11.Cu")
	)
	(gr_line
		(start 305.539902 -86.939374)
		(end 305.56327 -86.851998)
		(stroke
			(width 0.04445)
			(type default)
		)
		(layer "In11.Cu")
	)
	(gr_line
		(start 305.548284 -93.801946)
		(end 305.554888 -93.799152)
		(stroke
			(width 0.04445)
			(type default)
		)
		(layer "In11.Cu")
	)
	(gr_line
		(start 305.562 -103.124)
		(end 305.60137 -103.16337)
		(stroke
			(width 0.04445)
			(type default)
		)
		(layer "In11.Cu")
	)
	(gr_line
		(start 305.562 -102.9335)
		(end 305.60137 -102.89413)
		(stroke
			(width 0.04445)
			(type default)
		)
		(layer "In11.Cu")
	)
	(gr_line
		(start 305.579526 -79.310738)
		(end 305.597814 -79.310738)
		(stroke
			(width 0.0635)
			(type default)
		)
		(layer "In11.Cu")
	)
	(gr_line
		(start 305.603148 -103.165148)
		(end 305.6128 -103.1748)
		(stroke
			(width 0.04445)
			(type default)
		)
		(layer "In11.Cu")
	)
	(gr_line
		(start 305.603148 -102.892352)
		(end 305.6128 -102.8827)
		(stroke
			(width 0.04445)
			(type default)
		)
		(layer "In11.Cu")
	)
	(gr_line
		(start 305.6128 -103.1748)
		(end 305.634898 -103.1748)
		(stroke
			(width 0.04445)
			(type default)
		)
		(layer "In11.Cu")
	)
	(gr_line
		(start 305.6128 -102.8827)
		(end 305.634898 -102.8827)
		(stroke
			(width 0.04445)
			(type default)
		)
		(layer "In11.Cu")
	)
	(gr_line
		(start 305.642518 -81.055464)
		(end 305.700938 -81.055464)
		(stroke
			(width 0.04445)
			(type default)
		)
		(layer "In11.Cu")
	)
	(gr_line
		(start 305.655726 -95.49003)
		(end 305.776122 -95.49003)
		(stroke
			(width 0.04445)
			(type default)
		)
		(layer "In11.Cu")
	)
	(gr_line
		(start 305.660298 -96.476312)
		(end 305.770534 -96.476312)
		(stroke
			(width 0.04445)
			(type default)
		)
		(layer "In11.Cu")
	)
	(gr_line
		(start 305.67122 -85.06206)
		(end 305.681634 -85.080094)
		(stroke
			(width 0.04445)
			(type default)
		)
		(layer "In11.Cu")
	)
	(gr_line
		(start 305.681634 -85.080094)
		(end 305.699668 -85.090508)
		(stroke
			(width 0.04445)
			(type default)
		)
		(layer "In11.Cu")
	)
	(gr_line
		(start 305.685444 -87.701628)
		(end 305.771804 -87.787988)
		(stroke
			(width 0.04445)
			(type default)
		)
		(layer "In11.Cu")
	)
	(gr_line
		(start 305.73218 -99.666806)
		(end 305.738784 -99.6696)
		(stroke
			(width 0.04445)
			(type default)
		)
		(layer "In11.Cu")
	)
	(gr_line
		(start 305.733958 -83.795616)
		(end 305.7906 -83.738974)
		(stroke
			(width 0.04445)
			(type default)
		)
		(layer "In11.Cu")
	)
	(gr_line
		(start 305.735228 -86.76132)
		(end 305.81219 -86.782148)
		(stroke
			(width 0.04445)
			(type default)
		)
		(layer "In11.Cu")
	)
	(gr_line
		(start 305.758342 -91.366594)
		(end 305.758342 -91.366848)
		(stroke
			(width 0.04445)
			(type default)
		)
		(layer "In11.Cu")
	)
	(gr_line
		(start 305.770534 -96.476312)
		(end 305.896264 -96.350582)
		(stroke
			(width 0.04445)
			(type default)
		)
		(layer "In11.Cu")
	)
	(gr_line
		(start 305.771804 -87.787988)
		(end 306.038504 -87.787988)
		(stroke
			(width 0.04445)
			(type default)
		)
		(layer "In11.Cu")
	)
	(gr_line
		(start 305.776122 -95.49003)
		(end 305.901852 -95.3643)
		(stroke
			(width 0.04445)
			(type default)
		)
		(layer "In11.Cu")
	)
	(gr_line
		(start 305.805078 -81.334864)
		(end 305.891438 -81.248504)
		(stroke
			(width 0.04445)
			(type default)
		)
		(layer "In11.Cu")
	)
	(gr_line
		(start 305.81219 -86.782148)
		(end 306.105306 -86.612984)
		(stroke
			(width 0.04445)
			(type default)
		)
		(layer "In11.Cu")
	)
	(gr_line
		(start 305.819556 -93.689424)
		(end 306.062126 -93.58884)
		(stroke
			(width 0.04445)
			(type default)
		)
		(layer "In11.Cu")
	)
	(gr_line
		(start 305.830986 -79.1845)
		(end 305.849274 -79.1845)
		(stroke
			(width 0.0635)
			(type default)
		)
		(layer "In11.Cu")
	)
	(gr_line
		(start 305.868832 -93.878146)
		(end 305.959764 -93.915738)
		(stroke
			(width 0.04445)
			(type default)
		)
		(layer "In11.Cu")
	)
	(gr_line
		(start 305.875944 -87.508588)
		(end 305.934364 -87.508588)
		(stroke
			(width 0.04445)
			(type default)
		)
		(layer "In11.Cu")
	)
	(gr_line
		(start 305.896264 -96.240346)
		(end 305.896264 -96.350582)
		(stroke
			(width 0.04445)
			(type default)
		)
		(layer "In11.Cu")
	)
	(gr_line
		(start 305.901852 -95.243904)
		(end 305.901852 -95.3643)
		(stroke
			(width 0.04445)
			(type default)
		)
		(layer "In11.Cu")
	)
	(gr_line
		(start 305.920902 -100.193348)
		(end 305.936396 -100.208842)
		(stroke
			(width 0.04445)
			(type default)
		)
		(layer "In11.Cu")
	)
	(gr_line
		(start 305.920902 -100.179378)
		(end 305.920902 -100.193348)
		(stroke
			(width 0.04445)
			(type default)
		)
		(layer "In11.Cu")
	)
	(gr_line
		(start 305.920902 -100.121212)
		(end 305.920902 -100.176838)
		(stroke
			(width 0.04445)
			(type default)
		)
		(layer "In11.Cu")
	)
	(gr_line
		(start 305.92268 -85.21954)
		(end 305.94046 -85.2297)
		(stroke
			(width 0.04445)
			(type default)
		)
		(layer "In11.Cu")
	)
	(gr_line
		(start 305.959764 -93.915738)
		(end 306.124102 -93.847666)
		(stroke
			(width 0.04445)
			(type default)
		)
		(layer "In11.Cu")
	)
	(gr_line
		(start 306.035456 -101.31552)
		(end 306.055522 -101.323902)
		(stroke
			(width 0.05715)
			(type default)
		)
		(layer "In11.Cu")
	)
	(gr_line
		(start 306.038504 -87.787988)
		(end 306.124864 -87.701628)
		(stroke
			(width 0.04445)
			(type default)
		)
		(layer "In11.Cu")
	)
	(gr_line
		(start 306.041552 -96.095058)
		(end 306.145438 -96.095058)
		(stroke
			(width 0.04445)
			(type default)
		)
		(layer "In11.Cu")
	)
	(gr_line
		(start 306.051458 -95.094298)
		(end 306.16779 -95.094298)
		(stroke
			(width 0.04445)
			(type default)
		)
		(layer "In11.Cu")
	)
	(gr_line
		(start 306.055522 -99.986338)
		(end 306.111402 -99.986338)
		(stroke
			(width 0.04445)
			(type default)
		)
		(layer "In11.Cu")
	)
	(gr_line
		(start 306.113942 -99.986338)
		(end 306.127658 -99.986338)
		(stroke
			(width 0.04445)
			(type default)
		)
		(layer "In11.Cu")
	)
	(gr_line
		(start 306.124102 -93.847666)
		(end 306.161948 -93.756734)
		(stroke
			(width 0.04445)
			(type default)
		)
		(layer "In11.Cu")
	)
	(gr_line
		(start 306.127658 -99.986338)
		(end 306.142898 -100.001578)
		(stroke
			(width 0.04445)
			(type default)
		)
		(layer "In11.Cu")
	)
	(gr_line
		(start 306.142898 -100.002086)
		(end 306.143152 -100.00234)
		(stroke
			(width 0.04445)
			(type default)
		)
		(layer "In11.Cu")
	)
	(gr_line
		(start 306.142898 -100.001578)
		(end 306.142898 -100.002086)
		(stroke
			(width 0.04445)
			(type default)
		)
		(layer "In11.Cu")
	)
	(gr_line
		(start 306.145438 -96.095058)
		(end 306.271168 -95.969328)
		(stroke
			(width 0.04445)
			(type default)
		)
		(layer "In11.Cu")
	)
	(gr_line
		(start 306.16779 -95.094298)
		(end 306.29352 -94.968568)
		(stroke
			(width 0.04445)
			(type default)
		)
		(layer "In11.Cu")
	)
	(gr_line
		(start 306.230782 -100.503482)
		(end 306.241704 -100.514404)
		(stroke
			(width 0.05715)
			(type default)
		)
		(layer "In11.Cu")
	)
	(gr_line
		(start 306.241704 -100.514404)
		(end 306.25542 -100.5205)
		(stroke
			(width 0.05715)
			(type default)
		)
		(layer "In11.Cu")
	)
	(gr_line
		(start 306.271168 -95.865442)
		(end 306.271168 -95.969328)
		(stroke
			(width 0.04445)
			(type default)
		)
		(layer "In11.Cu")
	)
	(gr_line
		(start 306.29352 -94.852236)
		(end 306.29352 -94.968568)
		(stroke
			(width 0.04445)
			(type default)
		)
		(layer "In11.Cu")
	)
	(gr_line
		(start 306.36337 -92.74683)
		(end 306.368958 -92.74429)
		(stroke
			(width 0.04445)
			(type default)
		)
		(layer "In11.Cu")
	)
	(gr_line
		(start 306.396644 -87.701628)
		(end 306.483004 -87.787988)
		(stroke
			(width 0.04445)
			(type default)
		)
		(layer "In11.Cu")
	)
	(gr_line
		(start 306.444396 -85.03666)
		(end 306.532788 -84.948268)
		(stroke
			(width 0.04445)
			(type default)
		)
		(layer "In11.Cu")
	)
	(gr_line
		(start 306.453032 -93.427296)
		(end 306.45862 -93.424756)
		(stroke
			(width 0.04445)
			(type default)
		)
		(layer "In11.Cu")
	)
	(gr_line
		(start 306.483004 -87.787988)
		(end 306.749704 -87.787988)
		(stroke
			(width 0.04445)
			(type default)
		)
		(layer "In11.Cu")
	)
	(gr_line
		(start 306.507896 -105.339896)
		(end 306.575968 -105.407968)
		(stroke
			(width 0.05715)
			(type default)
		)
		(layer "In11.Cu")
	)
	(gr_line
		(start 306.50942 -104.92486)
		(end 306.739544 -104.92486)
		(stroke
			(width 0.05715)
			(type default)
		)
		(layer "In11.Cu")
	)
	(gr_line
		(start 306.532788 -84.948268)
		(end 306.799488 -84.948268)
		(stroke
			(width 0.04445)
			(type default)
		)
		(layer "In11.Cu")
	)
	(gr_line
		(start 306.553616 -84.22894)
		(end 306.596288 -84.271612)
		(stroke
			(width 0.04445)
			(type default)
		)
		(layer "In11.Cu")
	)
	(gr_line
		(start 306.568094 -95.74784)
		(end 306.664614 -95.84436)
		(stroke
			(width 0.04445)
			(type default)
		)
		(layer "In11.Cu")
	)
	(gr_line
		(start 306.568602 -103.8733)
		(end 306.585874 -103.880666)
		(stroke
			(width 0.05715)
			(type default)
		)
		(layer "In11.Cu")
	)
	(gr_line
		(start 306.587144 -87.508588)
		(end 306.645564 -87.508588)
		(stroke
			(width 0.04445)
			(type default)
		)
		(layer "In11.Cu")
	)
	(gr_line
		(start 306.596288 -84.271866)
		(end 306.6415 -84.317078)
		(stroke
			(width 0.04445)
			(type default)
		)
		(layer "In11.Cu")
	)
	(gr_line
		(start 306.596288 -84.271612)
		(end 306.596288 -84.271866)
		(stroke
			(width 0.04445)
			(type default)
		)
		(layer "In11.Cu")
	)
	(gr_line
		(start 306.634896 -85.2297)
		(end 306.69738 -85.2297)
		(stroke
			(width 0.04445)
			(type default)
		)
		(layer "In11.Cu")
	)
	(gr_line
		(start 306.6415 -84.317078)
		(end 306.9082 -84.317078)
		(stroke
			(width 0.04445)
			(type default)
		)
		(layer "In11.Cu")
	)
	(gr_line
		(start 306.655724 -102.8827)
		(end 306.673504 -102.890066)
		(stroke
			(width 0.05715)
			(type default)
		)
		(layer "In11.Cu")
	)
	(gr_line
		(start 306.664614 -95.84436)
		(end 306.842414 -95.84436)
		(stroke
			(width 0.04445)
			(type default)
		)
		(layer "In11.Cu")
	)
	(gr_line
		(start 306.713636 -83.29676)
		(end 306.807616 -83.20278)
		(stroke
			(width 0.04445)
			(type default)
		)
		(layer "In11.Cu")
	)
	(gr_line
		(start 306.739544 -104.92486)
		(end 306.991004 -105.17632)
		(stroke
			(width 0.05715)
			(type default)
		)
		(layer "In11.Cu")
	)
	(gr_line
		(start 306.744116 -84.0359)
		(end 306.805584 -84.0359)
		(stroke
			(width 0.04445)
			(type default)
		)
		(layer "In11.Cu")
	)
	(gr_line
		(start 306.749704 -87.787988)
		(end 306.836064 -87.701628)
		(stroke
			(width 0.04445)
			(type default)
		)
		(layer "In11.Cu")
	)
	(gr_line
		(start 306.799488 -84.948268)
		(end 306.88788 -85.03666)
		(stroke
			(width 0.04445)
			(type default)
		)
		(layer "In11.Cu")
	)
	(gr_line
		(start 306.801774 -96.32188)
		(end 306.817014 -96.317054)
		(stroke
			(width 0.04445)
			(type default)
		)
		(layer "In11.Cu")
	)
	(gr_line
		(start 306.807616 -83.20278)
		(end 307.074316 -83.20278)
		(stroke
			(width 0.04445)
			(type default)
		)
		(layer "In11.Cu")
	)
	(gr_line
		(start 306.842414 -95.84436)
		(end 306.938934 -95.74784)
		(stroke
			(width 0.04445)
			(type default)
		)
		(layer "In11.Cu")
	)
	(gr_line
		(start 306.846224 -91.7956)
		(end 306.891182 -91.750642)
		(stroke
			(width 0.04445)
			(type default)
		)
		(layer "In11.Cu")
	)
	(gr_line
		(start 306.8574 -91.9861)
		(end 306.891182 -92.019882)
		(stroke
			(width 0.04445)
			(type default)
		)
		(layer "In11.Cu")
	)
	(gr_line
		(start 306.89296 -92.02166)
		(end 306.9082 -92.0369)
		(stroke
			(width 0.04445)
			(type default)
		)
		(layer "In11.Cu")
	)
	(gr_line
		(start 306.89296 -91.748864)
		(end 306.897024 -91.7448)
		(stroke
			(width 0.04445)
			(type default)
		)
		(layer "In11.Cu")
	)
	(gr_line
		(start 306.897024 -91.7448)
		(end 306.9082 -91.7448)
		(stroke
			(width 0.04445)
			(type default)
		)
		(layer "In11.Cu")
	)
	(gr_line
		(start 306.904136 -83.4898)
		(end 306.977796 -83.4898)
		(stroke
			(width 0.04445)
			(type default)
		)
		(layer "In11.Cu")
	)
	(gr_line
		(start 306.9082 -84.317078)
		(end 306.953412 -84.271866)
		(stroke
			(width 0.04445)
			(type default)
		)
		(layer "In11.Cu")
	)
	(gr_line
		(start 306.915566 -103.309166)
		(end 307.003704 -103.521764)
		(stroke
			(width 0.05715)
			(type default)
		)
		(layer "In11.Cu")
	)
	(gr_line
		(start 306.953412 -84.271612)
		(end 306.953412 -84.271866)
		(stroke
			(width 0.04445)
			(type default)
		)
		(layer "In11.Cu")
	)
	(gr_line
		(start 306.953412 -84.271612)
		(end 306.996084 -84.22894)
		(stroke
			(width 0.04445)
			(type default)
		)
		(layer "In11.Cu")
	)
	(gr_line
		(start 306.991004 -105.17632)
		(end 306.991004 -105.406444)
		(stroke
			(width 0.05715)
			(type default)
		)
		(layer "In11.Cu")
	)
	(gr_line
		(start 307.003704 -103.521764)
		(end 307.320442 -103.652828)
		(stroke
			(width 0.05715)
			(type default)
		)
		(layer "In11.Cu")
	)
	(gr_line
		(start 307.05298 -92.93479)
		(end 307.09235 -92.97416)
		(stroke
			(width 0.04445)
			(type default)
		)
		(layer "In11.Cu")
	)
	(gr_line
		(start 307.05298 -92.74429)
		(end 307.09235 -92.70492)
		(stroke
			(width 0.04445)
			(type default)
		)
		(layer "In11.Cu")
	)
	(gr_line
		(start 307.060092 -103.050086)
		(end 307.613558 -103.279194)
		(stroke
			(width 0.05715)
			(type default)
		)
		(layer "In11.Cu")
	)
	(gr_line
		(start 307.074316 -83.20278)
		(end 307.168296 -83.29676)
		(stroke
			(width 0.04445)
			(type default)
		)
		(layer "In11.Cu")
	)
	(gr_line
		(start 307.094128 -92.975938)
		(end 307.10378 -92.98559)
		(stroke
			(width 0.04445)
			(type default)
		)
		(layer "In11.Cu")
	)
	(gr_line
		(start 307.094128 -92.703142)
		(end 307.10378 -92.69349)
		(stroke
			(width 0.04445)
			(type default)
		)
		(layer "In11.Cu")
	)
	(gr_line
		(start 307.097938 -93.615256)
		(end 307.25237 -93.615256)
		(stroke
			(width 0.04445)
			(type default)
		)
		(layer "In11.Cu")
	)
	(gr_line
		(start 307.10378 -92.98559)
		(end 307.125878 -92.98559)
		(stroke
			(width 0.04445)
			(type default)
		)
		(layer "In11.Cu")
	)
	(gr_line
		(start 307.10378 -92.69349)
		(end 307.125878 -92.69349)
		(stroke
			(width 0.04445)
			(type default)
		)
		(layer "In11.Cu")
	)
	(gr_line
		(start 307.121814 -95.74784)
		(end 307.218334 -95.84436)
		(stroke
			(width 0.04445)
			(type default)
		)
		(layer "In11.Cu")
	)
	(gr_line
		(start 307.145436 -81.860644)
		(end 307.231796 -81.947004)
		(stroke
			(width 0.04445)
			(type default)
		)
		(layer "In11.Cu")
	)
	(gr_line
		(start 307.155088 -86.710774)
		(end 307.242972 -86.798658)
		(stroke
			(width 0.04445)
			(type default)
		)
		(layer "In11.Cu")
	)
	(gr_line
		(start 307.15966 -85.03666)
		(end 307.248052 -84.948268)
		(stroke
			(width 0.04445)
			(type default)
		)
		(layer "In11.Cu")
	)
	(gr_line
		(start 307.218334 -95.84436)
		(end 307.396134 -95.84436)
		(stroke
			(width 0.04445)
			(type default)
		)
		(layer "In11.Cu")
	)
	(gr_line
		(start 307.231796 -81.947004)
		(end 307.498496 -81.947004)
		(stroke
			(width 0.04445)
			(type default)
		)
		(layer "In11.Cu")
	)
	(gr_line
		(start 307.242972 -86.798658)
		(end 307.509672 -86.798658)
		(stroke
			(width 0.04445)
			(type default)
		)
		(layer "In11.Cu")
	)
	(gr_line
		(start 307.244242 -106.076242)
		(end 307.312314 -106.144314)
		(stroke
			(width 0.05715)
			(type default)
		)
		(layer "In11.Cu")
	)
	(gr_line
		(start 307.245766 -105.661206)
		(end 307.47589 -105.661206)
		(stroke
			(width 0.05715)
			(type default)
		)
		(layer "In11.Cu")
	)
	(gr_line
		(start 307.248052 -84.948268)
		(end 307.514752 -84.948268)
		(stroke
			(width 0.04445)
			(type default)
		)
		(layer "In11.Cu")
	)
	(gr_line
		(start 307.25237 -93.615256)
		(end 307.310028 -93.672914)
		(stroke
			(width 0.04445)
			(type default)
		)
		(layer "In11.Cu")
	)
	(gr_line
		(start 307.267864 -84.22894)
		(end 307.310536 -84.271612)
		(stroke
			(width 0.04445)
			(type default)
		)
		(layer "In11.Cu")
	)
	(gr_line
		(start 307.288692 -93.424756)
		(end 307.310028 -93.40342)
		(stroke
			(width 0.04445)
			(type default)
		)
		(layer "In11.Cu")
	)
	(gr_line
		(start 307.310536 -84.271866)
		(end 307.355748 -84.317078)
		(stroke
			(width 0.04445)
			(type default)
		)
		(layer "In11.Cu")
	)
	(gr_line
		(start 307.310536 -84.271612)
		(end 307.310536 -84.271866)
		(stroke
			(width 0.04445)
			(type default)
		)
		(layer "In11.Cu")
	)
	(gr_line
		(start 307.311806 -93.674692)
		(end 307.31587 -93.678756)
		(stroke
			(width 0.04445)
			(type default)
		)
		(layer "In11.Cu")
	)
	(gr_line
		(start 307.311806 -93.401642)
		(end 307.326792 -93.386656)
		(stroke
			(width 0.04445)
			(type default)
		)
		(layer "In11.Cu")
	)
	(gr_line
		(start 307.31587 -93.678756)
		(end 307.337968 -93.678756)
		(stroke
			(width 0.04445)
			(type default)
		)
		(layer "In11.Cu")
	)
	(gr_line
		(start 307.320442 -103.652828)
		(end 307.533294 -103.564944)
		(stroke
			(width 0.05715)
			(type default)
		)
		(layer "In11.Cu")
	)
	(gr_line
		(start 307.326792 -93.386656)
		(end 307.337968 -93.386656)
		(stroke
			(width 0.04445)
			(type default)
		)
		(layer "In11.Cu")
	)
	(gr_line
		(start 307.335936 -81.667604)
		(end 307.394356 -81.667604)
		(stroke
			(width 0.04445)
			(type default)
		)
		(layer "In11.Cu")
	)
	(gr_line
		(start 307.337968 -93.386656)
		(end 307.4924 -93.386656)
		(stroke
			(width 0.05715)
			(type default)
		)
		(layer "In11.Cu")
	)
	(gr_line
		(start 307.345588 -86.517734)
		(end 307.407056 -86.517734)
		(stroke
			(width 0.04445)
			(type default)
		)
		(layer "In11.Cu")
	)
	(gr_line
		(start 307.35016 -85.2297)
		(end 307.412644 -85.2297)
		(stroke
			(width 0.04445)
			(type default)
		)
		(layer "In11.Cu")
	)
	(gr_line
		(start 307.355748 -84.317078)
		(end 307.622448 -84.317078)
		(stroke
			(width 0.04445)
			(type default)
		)
		(layer "In11.Cu")
	)
	(gr_line
		(start 307.396134 -95.84436)
		(end 307.492654 -95.74784)
		(stroke
			(width 0.04445)
			(type default)
		)
		(layer "In11.Cu")
	)
	(gr_line
		(start 307.440076 -83.29676)
		(end 307.534056 -83.20278)
		(stroke
			(width 0.04445)
			(type default)
		)
		(layer "In11.Cu")
	)
	(gr_line
		(start 307.458364 -84.0359)
		(end 307.519832 -84.0359)
		(stroke
			(width 0.04445)
			(type default)
		)
		(layer "In11.Cu")
	)
	(gr_line
		(start 307.47589 -105.661206)
		(end 307.72735 -105.912666)
		(stroke
			(width 0.05715)
			(type default)
		)
		(layer "In11.Cu")
	)
	(gr_line
		(start 307.498496 -81.947004)
		(end 307.584856 -81.860644)
		(stroke
			(width 0.04445)
			(type default)
		)
		(layer "In11.Cu")
	)
	(gr_line
		(start 307.499512 -94.635574)
		(end 307.591968 -94.72803)
		(stroke
			(width 0.04445)
			(type default)
		)
		(layer "In11.Cu")
	)
	(gr_line
		(start 307.509672 -86.798658)
		(end 307.597556 -86.710774)
		(stroke
			(width 0.04445)
			(type default)
		)
		(layer "In11.Cu")
	)
	(gr_line
		(start 307.514752 -84.948268)
		(end 307.603144 -85.03666)
		(stroke
			(width 0.04445)
			(type default)
		)
		(layer "In11.Cu")
	)
	(gr_line
		(start 307.534056 -83.20278)
		(end 307.800756 -83.20278)
		(stroke
			(width 0.04445)
			(type default)
		)
		(layer "In11.Cu")
	)
	(gr_line
		(start 307.591968 -94.72803)
		(end 307.769768 -94.72803)
		(stroke
			(width 0.04445)
			(type default)
		)
		(layer "In11.Cu")
	)
	(gr_line
		(start 307.622448 -84.317078)
		(end 307.66766 -84.271866)
		(stroke
			(width 0.04445)
			(type default)
		)
		(layer "In11.Cu")
	)
	(gr_line
		(start 307.630576 -83.4898)
		(end 307.704236 -83.4898)
		(stroke
			(width 0.04445)
			(type default)
		)
		(layer "In11.Cu")
	)
	(gr_line
		(start 307.66766 -84.271612)
		(end 307.66766 -84.271866)
		(stroke
			(width 0.04445)
			(type default)
		)
		(layer "In11.Cu")
	)
	(gr_line
		(start 307.66766 -84.271612)
		(end 307.710332 -84.22894)
		(stroke
			(width 0.04445)
			(type default)
		)
		(layer "In11.Cu")
	)
	(gr_line
		(start 307.675534 -95.74784)
		(end 307.772054 -95.84436)
		(stroke
			(width 0.04445)
			(type default)
		)
		(layer "In11.Cu")
	)
	(gr_line
		(start 307.72735 -105.912666)
		(end 307.72735 -106.14279)
		(stroke
			(width 0.05715)
			(type default)
		)
		(layer "In11.Cu")
	)
	(gr_line
		(start 307.769768 -94.72803)
		(end 307.862224 -94.635574)
		(stroke
			(width 0.04445)
			(type default)
		)
		(layer "In11.Cu")
	)
	(gr_line
		(start 307.772054 -95.84436)
		(end 307.949854 -95.84436)
		(stroke
			(width 0.04445)
			(type default)
		)
		(layer "In11.Cu")
	)
	(gr_line
		(start 307.775864 -93.386656)
		(end 307.793136 -93.394022)
		(stroke
			(width 0.05715)
			(type default)
		)
		(layer "In11.Cu")
	)
	(gr_line
		(start 307.800756 -83.20278)
		(end 307.894736 -83.29676)
		(stroke
			(width 0.04445)
			(type default)
		)
		(layer "In11.Cu")
	)
	(gr_line
		(start 307.85435 -103.69804)
		(end 307.942488 -103.910384)
		(stroke
			(width 0.05715)
			(type default)
		)
		(layer "In11.Cu")
	)
	(gr_line
		(start 307.856636 -81.860644)
		(end 307.942996 -81.947004)
		(stroke
			(width 0.04445)
			(type default)
		)
		(layer "In11.Cu")
	)
	(gr_line
		(start 307.940456 -89.984834)
		(end 308.082442 -89.984834)
		(stroke
			(width 0.04445)
			(type default)
		)
		(layer "In11.Cu")
	)
	(gr_line
		(start 307.942488 -103.910384)
		(end 308.259226 -104.041702)
		(stroke
			(width 0.05715)
			(type default)
		)
		(layer "In11.Cu")
	)
	(gr_line
		(start 307.942996 -81.947004)
		(end 308.209696 -81.947004)
		(stroke
			(width 0.04445)
			(type default)
		)
		(layer "In11.Cu")
	)
	(gr_line
		(start 307.949854 -95.84436)
		(end 308.046374 -95.74784)
		(stroke
			(width 0.04445)
			(type default)
		)
		(layer "In11.Cu")
	)
	(gr_line
		(start 307.980588 -106.812588)
		(end 308.04866 -106.88066)
		(stroke
			(width 0.05715)
			(type default)
		)
		(layer "In11.Cu")
	)
	(gr_line
		(start 307.982112 -106.397552)
		(end 308.212236 -106.397552)
		(stroke
			(width 0.05715)
			(type default)
		)
		(layer "In11.Cu")
	)
	(gr_line
		(start 307.999384 -103.43896)
		(end 308.552088 -103.667814)
		(stroke
			(width 0.05715)
			(type default)
		)
		(layer "In11.Cu")
	)
	(gr_line
		(start 308.047136 -81.667604)
		(end 308.105556 -81.667604)
		(stroke
			(width 0.04445)
			(type default)
		)
		(layer "In11.Cu")
	)
	(gr_line
		(start 308.0512 -82.745834)
		(end 308.09057 -82.785204)
		(stroke
			(width 0.04445)
			(type default)
		)
		(layer "In11.Cu")
	)
	(gr_line
		(start 308.0512 -82.555334)
		(end 308.09057 -82.515964)
		(stroke
			(width 0.04445)
			(type default)
		)
		(layer "In11.Cu")
	)
	(gr_line
		(start 308.05755 -94.635574)
		(end 308.14772 -94.725744)
		(stroke
			(width 0.04445)
			(type default)
		)
		(layer "In11.Cu")
	)
	(gr_line
		(start 308.082442 -89.984834)
		(end 308.136544 -89.930732)
		(stroke
			(width 0.04445)
			(type default)
		)
		(layer "In11.Cu")
	)
	(gr_line
		(start 308.092348 -82.786982)
		(end 308.102 -82.796634)
		(stroke
			(width 0.04445)
			(type default)
		)
		(layer "In11.Cu")
	)
	(gr_line
		(start 308.092348 -82.514186)
		(end 308.102 -82.504534)
		(stroke
			(width 0.04445)
			(type default)
		)
		(layer "In11.Cu")
	)
	(gr_line
		(start 308.102 -82.796634)
		(end 308.124098 -82.796634)
		(stroke
			(width 0.04445)
			(type default)
		)
		(layer "In11.Cu")
	)
	(gr_line
		(start 308.102 -82.504534)
		(end 308.124098 -82.504534)
		(stroke
			(width 0.04445)
			(type default)
		)
		(layer "In11.Cu")
	)
	(gr_line
		(start 308.111652 -90.175334)
		(end 308.136544 -90.200226)
		(stroke
			(width 0.04445)
			(type default)
		)
		(layer "In11.Cu")
	)
	(gr_line
		(start 308.138322 -90.202004)
		(end 308.157118 -90.2208)
		(stroke
			(width 0.04445)
			(type default)
		)
		(layer "In11.Cu")
	)
	(gr_line
		(start 308.138322 -89.928954)
		(end 308.138576 -89.9287)
		(stroke
			(width 0.04445)
			(type default)
		)
		(layer "In11.Cu")
	)
	(gr_line
		(start 308.138576 -89.9287)
		(end 308.17439 -89.9287)
		(stroke
			(width 0.04445)
			(type default)
		)
		(layer "In11.Cu")
	)
	(gr_line
		(start 308.14772 -94.725744)
		(end 308.32552 -94.725744)
		(stroke
			(width 0.04445)
			(type default)
		)
		(layer "In11.Cu")
	)
	(gr_line
		(start 308.157118 -90.2208)
		(end 308.180486 -90.2208)
		(stroke
			(width 0.04445)
			(type default)
		)
		(layer "In11.Cu")
	)
	(gr_line
		(start 308.167532 -84.2264)
		(end 308.206902 -84.26577)
		(stroke
			(width 0.04445)
			(type default)
		)
		(layer "In11.Cu")
	)
	(gr_line
		(start 308.167532 -84.0359)
		(end 308.206902 -83.99653)
		(stroke
			(width 0.04445)
			(type default)
		)
		(layer "In11.Cu")
	)
	(gr_line
		(start 308.180486 -90.2208)
		(end 308.322472 -90.2208)
		(stroke
			(width 0.05715)
			(type default)
		)
		(layer "In11.Cu")
	)
	(gr_line
		(start 308.20868 -84.267548)
		(end 308.218332 -84.2772)
		(stroke
			(width 0.04445)
			(type default)
		)
		(layer "In11.Cu")
	)
	(gr_line
		(start 308.20868 -83.994752)
		(end 308.218332 -83.9851)
		(stroke
			(width 0.04445)
			(type default)
		)
		(layer "In11.Cu")
	)
	(gr_line
		(start 308.209696 -81.947004)
		(end 308.296056 -81.860644)
		(stroke
			(width 0.04445)
			(type default)
		)
		(layer "In11.Cu")
	)
	(gr_line
		(start 308.212236 -106.397552)
		(end 308.463696 -106.649012)
		(stroke
			(width 0.05715)
			(type default)
		)
		(layer "In11.Cu")
	)
	(gr_line
		(start 308.218332 -84.2772)
		(end 308.24043 -84.2772)
		(stroke
			(width 0.04445)
			(type default)
		)
		(layer "In11.Cu")
	)
	(gr_line
		(start 308.218332 -83.9851)
		(end 308.24043 -83.9851)
		(stroke
			(width 0.04445)
			(type default)
		)
		(layer "In11.Cu")
	)
	(gr_line
		(start 308.259226 -104.041702)
		(end 308.471824 -103.953564)
		(stroke
			(width 0.05715)
			(type default)
		)
		(layer "In11.Cu")
	)
	(gr_line
		(start 308.32552 -94.725744)
		(end 308.41569 -94.635574)
		(stroke
			(width 0.04445)
			(type default)
		)
		(layer "In11.Cu")
	)
	(gr_line
		(start 308.344062 -91.0336)
		(end 308.389528 -90.988134)
		(stroke
			(width 0.04445)
			(type default)
		)
		(layer "In11.Cu")
	)
	(gr_line
		(start 308.350158 -96.920558)
		(end 308.350158 -97.005648)
		(stroke
			(width 0.04445)
			(type default)
		)
		(layer "In11.Cu")
	)
	(gr_line
		(start 308.356 -91.2241)
		(end 308.389528 -91.257628)
		(stroke
			(width 0.04445)
			(type default)
		)
		(layer "In11.Cu")
	)
	(gr_line
		(start 308.374542 -83.4898)
		(end 308.413912 -83.52917)
		(stroke
			(width 0.04445)
			(type default)
		)
		(layer "In11.Cu")
	)
	(gr_line
		(start 308.374542 -83.2993)
		(end 308.413912 -83.25993)
		(stroke
			(width 0.04445)
			(type default)
		)
		(layer "In11.Cu")
	)
	(gr_line
		(start 308.391306 -91.259406)
		(end 308.4068 -91.2749)
		(stroke
			(width 0.04445)
			(type default)
		)
		(layer "In11.Cu")
	)
	(gr_line
		(start 308.391306 -90.986356)
		(end 308.394862 -90.9828)
		(stroke
			(width 0.04445)
			(type default)
		)
		(layer "In11.Cu")
	)
	(gr_line
		(start 308.394862 -90.9828)
		(end 308.40934 -90.9828)
		(stroke
			(width 0.04445)
			(type default)
		)
		(layer "In11.Cu")
	)
	(gr_line
		(start 308.4068 -91.2749)
		(end 308.40934 -91.2749)
		(stroke
			(width 0.04445)
			(type default)
		)
		(layer "In11.Cu")
	)
	(gr_line
		(start 308.410102 -88.3158)
		(end 308.449472 -88.35517)
		(stroke
			(width 0.04445)
			(type default)
		)
		(layer "In11.Cu")
	)
	(gr_line
		(start 308.410102 -88.1253)
		(end 308.449472 -88.08593)
		(stroke
			(width 0.04445)
			(type default)
		)
		(layer "In11.Cu")
	)
	(gr_line
		(start 308.41569 -83.530948)
		(end 308.425342 -83.5406)
		(stroke
			(width 0.04445)
			(type default)
		)
		(layer "In11.Cu")
	)
	(gr_line
		(start 308.41569 -83.258152)
		(end 308.425342 -83.2485)
		(stroke
			(width 0.04445)
			(type default)
		)
		(layer "In11.Cu")
	)
	(gr_line
		(start 308.425342 -83.5406)
		(end 308.44744 -83.5406)
		(stroke
			(width 0.04445)
			(type default)
		)
		(layer "In11.Cu")
	)
	(gr_line
		(start 308.425342 -83.2485)
		(end 308.44744 -83.2485)
		(stroke
			(width 0.04445)
			(type default)
		)
		(layer "In11.Cu")
	)
	(gr_line
		(start 308.45125 -88.356948)
		(end 308.460902 -88.3666)
		(stroke
			(width 0.04445)
			(type default)
		)
		(layer "In11.Cu")
	)
	(gr_line
		(start 308.45125 -88.084152)
		(end 308.460902 -88.0745)
		(stroke
			(width 0.04445)
			(type default)
		)
		(layer "In11.Cu")
	)
	(gr_line
		(start 308.460902 -88.3666)
		(end 308.483 -88.3666)
		(stroke
			(width 0.04445)
			(type default)
		)
		(layer "In11.Cu")
	)
	(gr_line
		(start 308.460902 -88.0745)
		(end 308.483 -88.0745)
		(stroke
			(width 0.04445)
			(type default)
		)
		(layer "In11.Cu")
	)
	(gr_line
		(start 308.463696 -106.649012)
		(end 308.463696 -106.879136)
		(stroke
			(width 0.05715)
			(type default)
		)
		(layer "In11.Cu")
	)
	(gr_line
		(start 308.468776 -87.157052)
		(end 308.512718 -87.200994)
		(stroke
			(width 0.04445)
			(type default)
		)
		(layer "In11.Cu")
	)
	(gr_line
		(start 308.512718 -87.201248)
		(end 308.5592 -87.24773)
		(stroke
			(width 0.04445)
			(type default)
		)
		(layer "In11.Cu")
	)
	(gr_line
		(start 308.512718 -87.200994)
		(end 308.512718 -87.201248)
		(stroke
			(width 0.04445)
			(type default)
		)
		(layer "In11.Cu")
	)
	(gr_line
		(start 308.520592 -96.821498)
		(end 308.540658 -96.821498)
		(stroke
			(width 0.04445)
			(type default)
		)
		(layer "In11.Cu")
	)
	(gr_line
		(start 308.543198 -96.821498)
		(end 308.57698 -96.821498)
		(stroke
			(width 0.04445)
			(type default)
		)
		(layer "In11.Cu")
	)
	(gr_line
		(start 308.55539 -96.035876)
		(end 308.68112 -96.161606)
		(stroke
			(width 0.04445)
			(type default)
		)
		(layer "In11.Cu")
	)
	(gr_line
		(start 308.55539 -95.896176)
		(end 308.55539 -96.035876)
		(stroke
			(width 0.04445)
			(type default)
		)
		(layer "In11.Cu")
	)
	(gr_line
		(start 308.5592 -87.24773)
		(end 308.8259 -87.24773)
		(stroke
			(width 0.04445)
			(type default)
		)
		(layer "In11.Cu")
	)
	(gr_line
		(start 308.567836 -81.860644)
		(end 308.654196 -81.947004)
		(stroke
			(width 0.04445)
			(type default)
		)
		(layer "In11.Cu")
	)
	(gr_line
		(start 308.586378 -85.932772)
		(end 308.625748 -85.972142)
		(stroke
			(width 0.04445)
			(type default)
		)
		(layer "In11.Cu")
	)
	(gr_line
		(start 308.586378 -85.742272)
		(end 308.625748 -85.702902)
		(stroke
			(width 0.04445)
			(type default)
		)
		(layer "In11.Cu")
	)
	(gr_line
		(start 308.627526 -85.97392)
		(end 308.637178 -85.983572)
		(stroke
			(width 0.04445)
			(type default)
		)
		(layer "In11.Cu")
	)
	(gr_line
		(start 308.627526 -85.701124)
		(end 308.637178 -85.691472)
		(stroke
			(width 0.04445)
			(type default)
		)
		(layer "In11.Cu")
	)
	(gr_line
		(start 308.637178 -85.983572)
		(end 308.659276 -85.983572)
		(stroke
			(width 0.04445)
			(type default)
		)
		(layer "In11.Cu")
	)
	(gr_line
		(start 308.637178 -85.691472)
		(end 308.659276 -85.691472)
		(stroke
			(width 0.04445)
			(type default)
		)
		(layer "In11.Cu")
	)
	(gr_line
		(start 308.654196 -81.947004)
		(end 308.920896 -81.947004)
		(stroke
			(width 0.04445)
			(type default)
		)
		(layer "In11.Cu")
	)
	(gr_line
		(start 308.659276 -86.964012)
		(end 308.725824 -86.964012)
		(stroke
			(width 0.04445)
			(type default)
		)
		(layer "In11.Cu")
	)
	(gr_line
		(start 308.677818 -94.901766)
		(end 308.803548 -95.027496)
		(stroke
			(width 0.04445)
			(type default)
		)
		(layer "In11.Cu")
	)
	(gr_line
		(start 308.677818 -94.762066)
		(end 308.677818 -94.901766)
		(stroke
			(width 0.04445)
			(type default)
		)
		(layer "In11.Cu")
	)
	(gr_line
		(start 308.68112 -96.161606)
		(end 308.82082 -96.161606)
		(stroke
			(width 0.04445)
			(type default)
		)
		(layer "In11.Cu")
	)
	(gr_line
		(start 308.716934 -107.548934)
		(end 308.78526 -107.61726)
		(stroke
			(width 0.05715)
			(type default)
		)
		(layer "In11.Cu")
	)
	(gr_line
		(start 308.718458 -107.133898)
		(end 308.948836 -107.133898)
		(stroke
			(width 0.05715)
			(type default)
		)
		(layer "In11.Cu")
	)
	(gr_line
		(start 308.758336 -81.667604)
		(end 308.816756 -81.667604)
		(stroke
			(width 0.04445)
			(type default)
		)
		(layer "In11.Cu")
	)
	(gr_line
		(start 308.791102 -85.2297)
		(end 308.830472 -85.26907)
		(stroke
			(width 0.04445)
			(type default)
		)
		(layer "In11.Cu")
	)
	(gr_line
		(start 308.791102 -85.0392)
		(end 308.830472 -84.99983)
		(stroke
			(width 0.04445)
			(type default)
		)
		(layer "In11.Cu")
	)
	(gr_line
		(start 308.803548 -95.027496)
		(end 308.943248 -95.027496)
		(stroke
			(width 0.04445)
			(type default)
		)
		(layer "In11.Cu")
	)
	(gr_line
		(start 308.8259 -87.24773)
		(end 308.872382 -87.201248)
		(stroke
			(width 0.04445)
			(type default)
		)
		(layer "In11.Cu")
	)
	(gr_line
		(start 308.83225 -85.270848)
		(end 308.841902 -85.2805)
		(stroke
			(width 0.04445)
			(type default)
		)
		(layer "In11.Cu")
	)
	(gr_line
		(start 308.83225 -84.998052)
		(end 308.841902 -84.9884)
		(stroke
			(width 0.04445)
			(type default)
		)
		(layer "In11.Cu")
	)
	(gr_line
		(start 308.841902 -85.2805)
		(end 308.864 -85.2805)
		(stroke
			(width 0.04445)
			(type default)
		)
		(layer "In11.Cu")
	)
	(gr_line
		(start 308.841902 -84.9884)
		(end 308.864 -84.9884)
		(stroke
			(width 0.04445)
			(type default)
		)
		(layer "In11.Cu")
	)
	(gr_line
		(start 308.872382 -87.200994)
		(end 308.872382 -87.201248)
		(stroke
			(width 0.04445)
			(type default)
		)
		(layer "In11.Cu")
	)
	(gr_line
		(start 308.872382 -87.200994)
		(end 308.916324 -87.157052)
		(stroke
			(width 0.04445)
			(type default)
		)
		(layer "In11.Cu")
	)
	(gr_line
		(start 308.920896 -81.947004)
		(end 309.007256 -81.860644)
		(stroke
			(width 0.04445)
			(type default)
		)
		(layer "In11.Cu")
	)
	(gr_line
		(start 308.948836 -107.133898)
		(end 309.200296 -107.385358)
		(stroke
			(width 0.05715)
			(type default)
		)
		(layer "In11.Cu")
	)
	(gr_line
		(start 308.949598 -96.430338)
		(end 309.075328 -96.556068)
		(stroke
			(width 0.04445)
			(type default)
		)
		(layer "In11.Cu")
	)
	(gr_line
		(start 308.949598 -96.290384)
		(end 308.949598 -96.430338)
		(stroke
			(width 0.04445)
			(type default)
		)
		(layer "In11.Cu")
	)
	(gr_line
		(start 309.07228 -95.296228)
		(end 309.19801 -95.421958)
		(stroke
			(width 0.04445)
			(type default)
		)
		(layer "In11.Cu")
	)
	(gr_line
		(start 309.07228 -95.156528)
		(end 309.07228 -95.296228)
		(stroke
			(width 0.04445)
			(type default)
		)
		(layer "In11.Cu")
	)
	(gr_line
		(start 309.075328 -96.556068)
		(end 309.215282 -96.556068)
		(stroke
			(width 0.04445)
			(type default)
		)
		(layer "In11.Cu")
	)
	(gr_line
		(start 309.188104 -87.157052)
		(end 309.232046 -87.200994)
		(stroke
			(width 0.04445)
			(type default)
		)
		(layer "In11.Cu")
	)
	(gr_line
		(start 309.19801 -95.421958)
		(end 309.33771 -95.421958)
		(stroke
			(width 0.04445)
			(type default)
		)
		(layer "In11.Cu")
	)
	(gr_line
		(start 309.200296 -107.385358)
		(end 309.200296 -107.615736)
		(stroke
			(width 0.05715)
			(type default)
		)
		(layer "In11.Cu")
	)
	(gr_line
		(start 309.232046 -87.201248)
		(end 309.278528 -87.24773)
		(stroke
			(width 0.04445)
			(type default)
		)
		(layer "In11.Cu")
	)
	(gr_line
		(start 309.232046 -87.200994)
		(end 309.232046 -87.201248)
		(stroke
			(width 0.04445)
			(type default)
		)
		(layer "In11.Cu")
	)
	(gr_line
		(start 309.278528 -87.24773)
		(end 309.545228 -87.24773)
		(stroke
			(width 0.04445)
			(type default)
		)
		(layer "In11.Cu")
	)
	(gr_line
		(start 309.279036 -81.860644)
		(end 309.365396 -81.947004)
		(stroke
			(width 0.04445)
			(type default)
		)
		(layer "In11.Cu")
	)
	(gr_line
		(start 309.34406 -96.8248)
		(end 309.46979 -96.95053)
		(stroke
			(width 0.04445)
			(type default)
		)
		(layer "In11.Cu")
	)
	(gr_line
		(start 309.34406 -96.684846)
		(end 309.34406 -96.8248)
		(stroke
			(width 0.04445)
			(type default)
		)
		(layer "In11.Cu")
	)
	(gr_line
		(start 309.365396 -81.947004)
		(end 309.632096 -81.947004)
		(stroke
			(width 0.04445)
			(type default)
		)
		(layer "In11.Cu")
	)
	(gr_line
		(start 309.378604 -86.964012)
		(end 309.445152 -86.964012)
		(stroke
			(width 0.04445)
			(type default)
		)
		(layer "In11.Cu")
	)
	(gr_line
		(start 309.438802 -94.075758)
		(end 309.45709 -94.083378)
		(stroke
			(width 0.05715)
			(type default)
		)
		(layer "In11.Cu")
	)
	(gr_line
		(start 309.466742 -95.69069)
		(end 309.592472 -95.81642)
		(stroke
			(width 0.04445)
			(type default)
		)
		(layer "In11.Cu")
	)
	(gr_line
		(start 309.466742 -95.55099)
		(end 309.466742 -95.69069)
		(stroke
			(width 0.04445)
			(type default)
		)
		(layer "In11.Cu")
	)
	(gr_line
		(start 309.469536 -81.667604)
		(end 309.527956 -81.667604)
		(stroke
			(width 0.04445)
			(type default)
		)
		(layer "In11.Cu")
	)
	(gr_line
		(start 309.46979 -96.95053)
		(end 309.609744 -96.95053)
		(stroke
			(width 0.04445)
			(type default)
		)
		(layer "In11.Cu")
	)
	(gr_line
		(start 309.545228 -87.24773)
		(end 309.59171 -87.201248)
		(stroke
			(width 0.04445)
			(type default)
		)
		(layer "In11.Cu")
	)
	(gr_line
		(start 309.59171 -87.200994)
		(end 309.59171 -87.201248)
		(stroke
			(width 0.04445)
			(type default)
		)
		(layer "In11.Cu")
	)
	(gr_line
		(start 309.59171 -87.200994)
		(end 309.635652 -87.157052)
		(stroke
			(width 0.04445)
			(type default)
		)
		(layer "In11.Cu")
	)
	(gr_line
		(start 309.592472 -95.81642)
		(end 309.732172 -95.81642)
		(stroke
			(width 0.04445)
			(type default)
		)
		(layer "In11.Cu")
	)
	(gr_line
		(start 309.632096 -81.947004)
		(end 309.718456 -81.860644)
		(stroke
			(width 0.04445)
			(type default)
		)
		(layer "In11.Cu")
	)
	(gr_line
		(start 309.636668 -105.145078)
		(end 309.655464 -105.152952)
		(stroke
			(width 0.05715)
			(type default)
		)
		(layer "In11.Cu")
	)
	(gr_line
		(start 309.655464 -105.152952)
		(end 309.669688 -105.167176)
		(stroke
			(width 0.05715)
			(type default)
		)
		(layer "In11.Cu")
	)
	(gr_line
		(start 309.700422 -104.143302)
		(end 309.720488 -104.151684)
		(stroke
			(width 0.05715)
			(type default)
		)
		(layer "In11.Cu")
	)
	(gr_line
		(start 309.720488 -104.151684)
		(end 309.735982 -104.167178)
		(stroke
			(width 0.05715)
			(type default)
		)
		(layer "In11.Cu")
	)
	(gr_line
		(start 309.746142 -97.155762)
		(end 309.756048 -97.165668)
		(stroke
			(width 0.04445)
			(type default)
		)
		(layer "In11.Cu")
	)
	(gr_line
		(start 309.746142 -97.143824)
		(end 309.746142 -97.155762)
		(stroke
			(width 0.04445)
			(type default)
		)
		(layer "In11.Cu")
	)
	(gr_line
		(start 309.746142 -97.083626)
		(end 309.746142 -97.141284)
		(stroke
			(width 0.04445)
			(type default)
		)
		(layer "In11.Cu")
	)
	(gr_line
		(start 309.883048 -96.950784)
		(end 309.936642 -96.950784)
		(stroke
			(width 0.04445)
			(type default)
		)
		(layer "In11.Cu")
	)
	(gr_line
		(start 309.907432 -87.157052)
		(end 309.951374 -87.200994)
		(stroke
			(width 0.04445)
			(type default)
		)
		(layer "In11.Cu")
	)
	(gr_line
		(start 309.939182 -96.950784)
		(end 309.954422 -96.950784)
		(stroke
			(width 0.04445)
			(type default)
		)
		(layer "In11.Cu")
	)
	(gr_line
		(start 309.951374 -87.201248)
		(end 309.997856 -87.24773)
		(stroke
			(width 0.04445)
			(type default)
		)
		(layer "In11.Cu")
	)
	(gr_line
		(start 309.951374 -87.200994)
		(end 309.951374 -87.201248)
		(stroke
			(width 0.04445)
			(type default)
		)
		(layer "In11.Cu")
	)
	(gr_line
		(start 309.954422 -96.950784)
		(end 309.96255 -96.958912)
		(stroke
			(width 0.04445)
			(type default)
		)
		(layer "In11.Cu")
	)
	(gr_line
		(start 309.99684 -96.14916)
		(end 310.004968 -96.157288)
		(stroke
			(width 0.04445)
			(type default)
		)
		(layer "In11.Cu")
	)
	(gr_line
		(start 309.99684 -96.128332)
		(end 309.99684 -96.14916)
		(stroke
			(width 0.04445)
			(type default)
		)
		(layer "In11.Cu")
	)
	(gr_line
		(start 309.99684 -96.077532)
		(end 309.99684 -96.125792)
		(stroke
			(width 0.04445)
			(type default)
		)
		(layer "In11.Cu")
	)
	(gr_line
		(start 309.997856 -87.24773)
		(end 310.264556 -87.24773)
		(stroke
			(width 0.04445)
			(type default)
		)
		(layer "In11.Cu")
	)
	(gr_line
		(start 310.097932 -86.964012)
		(end 310.16448 -86.964012)
		(stroke
			(width 0.04445)
			(type default)
		)
		(layer "In11.Cu")
	)
	(gr_line
		(start 310.124094 -95.935292)
		(end 310.18734 -95.935292)
		(stroke
			(width 0.04445)
			(type default)
		)
		(layer "In11.Cu")
	)
	(gr_line
		(start 310.18988 -95.935292)
		(end 310.19623 -95.935292)
		(stroke
			(width 0.04445)
			(type default)
		)
		(layer "In11.Cu")
	)
	(gr_line
		(start 310.19623 -95.935292)
		(end 310.211724 -95.950786)
		(stroke
			(width 0.04445)
			(type default)
		)
		(layer "In11.Cu")
	)
	(gr_line
		(start 310.238902 -81.858104)
		(end 310.278272 -81.897474)
		(stroke
			(width 0.04445)
			(type default)
		)
		(layer "In11.Cu")
	)
	(gr_line
		(start 310.238902 -81.667604)
		(end 310.278272 -81.628234)
		(stroke
			(width 0.04445)
			(type default)
		)
		(layer "In11.Cu")
	)
	(gr_line
		(start 310.243728 -103.499158)
		(end 310.263794 -103.50754)
		(stroke
			(width 0.05715)
			(type default)
		)
		(layer "In11.Cu")
	)
	(gr_line
		(start 310.263794 -103.50754)
		(end 310.279288 -103.523034)
		(stroke
			(width 0.05715)
			(type default)
		)
		(layer "In11.Cu")
	)
	(gr_line
		(start 310.264556 -87.24773)
		(end 310.311038 -87.201248)
		(stroke
			(width 0.04445)
			(type default)
		)
		(layer "In11.Cu")
	)
	(gr_line
		(start 310.28005 -81.899252)
		(end 310.289702 -81.908904)
		(stroke
			(width 0.04445)
			(type default)
		)
		(layer "In11.Cu")
	)
	(gr_line
		(start 310.28005 -81.626456)
		(end 310.289702 -81.616804)
		(stroke
			(width 0.04445)
			(type default)
		)
		(layer "In11.Cu")
	)
	(gr_line
		(start 310.311038 -87.200994)
		(end 310.311038 -87.201248)
		(stroke
			(width 0.04445)
			(type default)
		)
		(layer "In11.Cu")
	)
	(gr_line
		(start 310.311038 -87.200994)
		(end 310.35498 -87.157052)
		(stroke
			(width 0.04445)
			(type default)
		)
		(layer "In11.Cu")
	)
	(gr_line
		(start 310.614314 -97.610676)
		(end 310.615584 -97.612962)
		(stroke
			(width 0.05715)
			(type default)
		)
		(layer "In11.Cu")
	)
	(gr_line
		(start 310.62676 -87.157052)
		(end 310.670702 -87.200994)
		(stroke
			(width 0.04445)
			(type default)
		)
		(layer "In11.Cu")
	)
	(gr_line
		(start 310.670702 -87.201248)
		(end 310.717184 -87.24773)
		(stroke
			(width 0.04445)
			(type default)
		)
		(layer "In11.Cu")
	)
	(gr_line
		(start 310.670702 -87.200994)
		(end 310.670702 -87.201248)
		(stroke
			(width 0.04445)
			(type default)
		)
		(layer "In11.Cu")
	)
	(gr_line
		(start 310.717184 -87.24773)
		(end 310.983884 -87.24773)
		(stroke
			(width 0.04445)
			(type default)
		)
		(layer "In11.Cu")
	)
	(gr_line
		(start 310.81726 -86.964012)
		(end 310.883808 -86.964012)
		(stroke
			(width 0.04445)
			(type default)
		)
		(layer "In11.Cu")
	)
	(gr_line
		(start 310.931052 -83.9851)
		(end 310.933592 -83.98764)
		(stroke
			(width 0.05715)
			(type default)
		)
		(layer "In11.Cu")
	)
	(gr_line
		(start 310.983884 -87.24773)
		(end 311.030366 -87.201248)
		(stroke
			(width 0.04445)
			(type default)
		)
		(layer "In11.Cu")
	)
	(gr_line
		(start 311.030366 -87.200994)
		(end 311.030366 -87.201248)
		(stroke
			(width 0.04445)
			(type default)
		)
		(layer "In11.Cu")
	)
	(gr_line
		(start 311.030366 -87.200994)
		(end 311.074308 -87.157052)
		(stroke
			(width 0.04445)
			(type default)
		)
		(layer "In11.Cu")
	)
	(gr_line
		(start 311.076086 -103.086916)
		(end 311.096152 -103.095298)
		(stroke
			(width 0.05715)
			(type default)
		)
		(layer "In11.Cu")
	)
	(gr_line
		(start 311.096152 -103.095298)
		(end 311.111646 -103.110792)
		(stroke
			(width 0.05715)
			(type default)
		)
		(layer "In11.Cu")
	)
	(gr_line
		(start 311.18937 -82.504534)
		(end 311.19191 -82.507074)
		(stroke
			(width 0.05715)
			(type default)
		)
		(layer "In11.Cu")
	)
	(gr_line
		(start 311.242456 -96.981518)
		(end 311.247282 -96.99117)
		(stroke
			(width 0.05715)
			(type default)
		)
		(layer "In11.Cu")
	)
	(gr_line
		(start 311.382918 -83.2485)
		(end 311.385458 -83.25104)
		(stroke
			(width 0.05715)
			(type default)
		)
		(layer "In11.Cu")
	)
	(gr_line
		(start 311.469024 -87.154512)
		(end 311.508394 -87.193882)
		(stroke
			(width 0.04445)
			(type default)
		)
		(layer "In11.Cu")
	)
	(gr_line
		(start 311.469024 -86.964012)
		(end 311.508394 -86.924642)
		(stroke
			(width 0.04445)
			(type default)
		)
		(layer "In11.Cu")
	)
	(gr_line
		(start 311.510172 -87.19566)
		(end 311.519824 -87.205312)
		(stroke
			(width 0.04445)
			(type default)
		)
		(layer "In11.Cu")
	)
	(gr_line
		(start 311.510172 -86.922864)
		(end 311.519824 -86.913212)
		(stroke
			(width 0.04445)
			(type default)
		)
		(layer "In11.Cu")
	)
	(gr_line
		(start 311.519824 -87.205312)
		(end 311.541922 -87.205312)
		(stroke
			(width 0.04445)
			(type default)
		)
		(layer "In11.Cu")
	)
	(gr_line
		(start 311.519824 -86.913212)
		(end 311.541922 -86.913212)
		(stroke
			(width 0.04445)
			(type default)
		)
		(layer "In11.Cu")
	)
	(gr_line
		(start 311.713118 -102.656894)
		(end 311.728866 -102.664006)
		(stroke
			(width 0.05715)
			(type default)
		)
		(layer "In11.Cu")
	)
	(gr_line
		(start 311.728866 -102.664006)
		(end 311.741058 -102.676198)
		(stroke
			(width 0.05715)
			(type default)
		)
		(layer "In11.Cu")
	)
	(gr_line
		(start 311.79135 -96.417384)
		(end 311.79897 -96.425004)
		(stroke
			(width 0.05715)
			(type default)
		)
		(layer "In11.Cu")
	)
	(gr_line
		(start 311.79897 -96.425004)
		(end 311.803796 -96.434402)
		(stroke
			(width 0.05715)
			(type default)
		)
		(layer "In11.Cu")
	)
	(gr_line
		(start 313.26963 -88.0745)
		(end 313.272424 -88.077294)
		(stroke
			(width 0.05715)
			(type default)
		)
		(layer "In11.Cu")
	)
	(gr_line
		(start 313.471052 -86.913212)
		(end 313.473338 -86.915498)
		(stroke
			(width 0.05715)
			(type default)
		)
		(layer "In11.Cu")
	)
	(gr_line
		(start 314.316364 -104.35336)
		(end 314.339986 -104.38257)
		(stroke
			(width 0.05715)
			(type default)
		)
		(layer "In11.Cu")
	)
	(gr_line
		(start 314.339986 -104.38257)
		(end 314.374784 -104.397048)
		(stroke
			(width 0.05715)
			(type default)
		)
		(layer "In11.Cu")
	)
	(gr_line
		(start 314.761372 -103.631746)
		(end 314.784994 -103.660956)
		(stroke
			(width 0.05715)
			(type default)
		)
		(layer "In11.Cu")
	)
	(gr_line
		(start 314.784994 -103.660956)
		(end 314.819792 -103.675434)
		(stroke
			(width 0.05715)
			(type default)
		)
		(layer "In11.Cu")
	)
	(gr_line
		(start 315.368178 -103.127556)
		(end 315.3918 -103.156766)
		(stroke
			(width 0.05715)
			(type default)
		)
		(layer "In11.Cu")
	)
	(gr_line
		(start 315.3918 -103.156766)
		(end 315.426598 -103.171244)
		(stroke
			(width 0.05715)
			(type default)
		)
		(layer "In11.Cu")
	)
	(gr_line
		(start 315.540898 -102.265734)
		(end 315.56452 -102.294944)
		(stroke
			(width 0.05715)
			(type default)
		)
		(layer "In11.Cu")
	)
	(gr_line
		(start 315.56452 -102.294944)
		(end 315.599318 -102.309422)
		(stroke
			(width 0.05715)
			(type default)
		)
		(layer "In11.Cu")
	)
	(gr_line
		(start 316.31763 -103.54056)
		(end 316.871858 -103.77043)
		(stroke
			(width 0.05715)
			(type default)
		)
		(layer "In11.Cu")
	)
	(gr_line
		(start 316.400434 -103.25608)
		(end 316.613286 -103.167942)
		(stroke
			(width 0.05715)
			(type default)
		)
		(layer "In11.Cu")
	)
	(gr_line
		(start 316.613286 -103.167942)
		(end 316.930024 -103.29926)
		(stroke
			(width 0.05715)
			(type default)
		)
		(layer "In11.Cu")
	)
	(gr_line
		(start 316.67958 -112.59312)
		(end 316.738254 -112.651794)
		(stroke
			(width 0.05715)
			(type default)
		)
		(layer "In11.Cu")
	)
	(gr_line
		(start 316.927484 -105.455466)
		(end 317.482474 -105.685336)
		(stroke
			(width 0.05715)
			(type default)
		)
		(layer "In11.Cu")
	)
	(gr_line
		(start 316.930024 -103.29926)
		(end 317.017908 -103.512112)
		(stroke
			(width 0.05715)
			(type default)
		)
		(layer "In11.Cu")
	)
	(gr_line
		(start 317.00851 -105.16997)
		(end 317.221362 -105.081832)
		(stroke
			(width 0.05715)
			(type default)
		)
		(layer "In11.Cu")
	)
	(gr_line
		(start 317.221362 -105.081832)
		(end 317.5381 -105.21315)
		(stroke
			(width 0.05715)
			(type default)
		)
		(layer "In11.Cu")
	)
	(gr_line
		(start 317.2587 -103.930958)
		(end 317.81115 -104.159812)
		(stroke
			(width 0.05715)
			(type default)
		)
		(layer "In11.Cu")
	)
	(gr_line
		(start 317.338964 -103.645208)
		(end 317.551562 -103.557324)
		(stroke
			(width 0.05715)
			(type default)
		)
		(layer "In11.Cu")
	)
	(gr_line
		(start 317.429642 -111.0869)
		(end 317.48857 -111.145828)
		(stroke
			(width 0.05715)
			(type default)
		)
		(layer "In11.Cu")
	)
	(gr_line
		(start 317.5381 -105.21315)
		(end 317.625984 -105.426002)
		(stroke
			(width 0.05715)
			(type default)
		)
		(layer "In11.Cu")
	)
	(gr_line
		(start 317.551562 -103.557324)
		(end 317.8683 -103.688642)
		(stroke
			(width 0.05715)
			(type default)
		)
		(layer "In11.Cu")
	)
	(gr_line
		(start 317.728854 -110.141512)
		(end 317.787782 -110.20044)
		(stroke
			(width 0.05715)
			(type default)
		)
		(layer "In11.Cu")
	)
	(gr_line
		(start 317.864744 -105.843832)
		(end 318.420242 -106.07421)
		(stroke
			(width 0.05715)
			(type default)
		)
		(layer "In11.Cu")
	)
	(gr_line
		(start 317.8683 -103.688642)
		(end 317.956438 -103.90124)
		(stroke
			(width 0.05715)
			(type default)
		)
		(layer "In11.Cu")
	)
	(gr_line
		(start 317.89116 -109.239812)
		(end 317.950088 -109.29874)
		(stroke
			(width 0.05715)
			(type default)
		)
		(layer "In11.Cu")
	)
	(gr_line
		(start 317.946786 -105.558844)
		(end 318.159638 -105.47096)
		(stroke
			(width 0.05715)
			(type default)
		)
		(layer "In11.Cu")
	)
	(gr_line
		(start 318.159638 -105.47096)
		(end 318.47663 -105.602278)
		(stroke
			(width 0.05715)
			(type default)
		)
		(layer "In11.Cu")
	)
	(gr_line
		(start 318.47663 -105.602278)
		(end 318.564514 -105.81513)
		(stroke
			(width 0.05715)
			(type default)
		)
		(layer "In11.Cu")
	)
	(gr_line
		(start 319.029842 -89.568528)
		(end 319.051178 -89.572846)
		(stroke
			(width 0.05715)
			(type default)
		)
		(layer "In11.Cu")
	)
	(gr_line
		(start 319.051178 -89.572846)
		(end 319.072006 -89.568528)
		(stroke
			(width 0.05715)
			(type default)
		)
		(layer "In11.Cu")
	)
	(gr_line
		(start 319.733676 -95.627444)
		(end 319.76822 -95.641668)
		(stroke
			(width 0.05715)
			(type default)
		)
		(layer "In11.Cu")
	)
	(gr_line
		(start 319.76822 -95.641668)
		(end 319.791334 -95.671132)
		(stroke
			(width 0.05715)
			(type default)
		)
		(layer "In11.Cu")
	)
	(gr_line
		(start 320.49212 -88.580214)
		(end 320.511678 -88.584024)
		(stroke
			(width 0.05715)
			(type default)
		)
		(layer "In11.Cu")
	)
	(gr_line
		(start 320.511678 -88.584024)
		(end 320.531998 -88.57996)
		(stroke
			(width 0.05715)
			(type default)
		)
		(layer "In11.Cu")
	)
	(gr_line
		(start 320.61277 -95.211392)
		(end 320.649346 -95.226632)
		(stroke
			(width 0.05715)
			(type default)
		)
		(layer "In11.Cu")
	)
	(gr_line
		(start 320.649346 -95.226632)
		(end 320.673222 -95.256858)
		(stroke
			(width 0.05715)
			(type default)
		)
		(layer "In11.Cu")
	)
	(gr_line
		(start 320.67119 -87.8586)
		(end 320.690748 -87.86241)
		(stroke
			(width 0.05715)
			(type default)
		)
		(layer "In11.Cu")
	)
	(gr_line
		(start 320.690748 -87.86241)
		(end 320.711068 -87.858346)
		(stroke
			(width 0.05715)
			(type default)
		)
		(layer "In11.Cu")
	)
	(gr_line
		(start 320.787522 -87.147908)
		(end 320.806572 -87.151718)
		(stroke
			(width 0.05715)
			(type default)
		)
		(layer "In11.Cu")
	)
	(gr_line
		(start 320.806572 -87.151718)
		(end 320.825622 -87.147908)
		(stroke
			(width 0.05715)
			(type default)
		)
		(layer "In11.Cu")
	)
	(gr_line
		(start 320.975228 -86.296754)
		(end 320.994278 -86.300564)
		(stroke
			(width 0.05715)
			(type default)
		)
		(layer "In11.Cu")
	)
	(gr_line
		(start 320.994278 -86.300564)
		(end 321.013328 -86.296754)
		(stroke
			(width 0.05715)
			(type default)
		)
		(layer "In11.Cu")
	)
	(gr_line
		(start 321.140074 -94.40799)
		(end 321.17538 -94.422722)
		(stroke
			(width 0.05715)
			(type default)
		)
		(layer "In11.Cu")
	)
	(gr_line
		(start 321.149218 -84.798662)
		(end 321.168268 -84.802472)
		(stroke
			(width 0.05715)
			(type default)
		)
		(layer "In11.Cu")
	)
	(gr_line
		(start 321.168268 -84.802472)
		(end 321.187318 -84.798662)
		(stroke
			(width 0.05715)
			(type default)
		)
		(layer "In11.Cu")
	)
	(gr_line
		(start 321.17538 -94.422722)
		(end 321.198748 -94.45244)
		(stroke
			(width 0.05715)
			(type default)
		)
		(layer "In11.Cu")
	)
	(gr_line
		(start 321.298824 -85.533992)
		(end 321.317874 -85.537802)
		(stroke
			(width 0.05715)
			(type default)
		)
		(layer "In11.Cu")
	)
	(gr_line
		(start 321.317874 -85.537802)
		(end 321.336924 -85.533992)
		(stroke
			(width 0.05715)
			(type default)
		)
		(layer "In11.Cu")
	)
	(gr_line
		(start 321.384676 -83.965288)
		(end 321.403726 -83.969098)
		(stroke
			(width 0.05715)
			(type default)
		)
		(layer "In11.Cu")
	)
	(gr_line
		(start 321.403726 -83.969098)
		(end 321.422776 -83.965288)
		(stroke
			(width 0.05715)
			(type default)
		)
		(layer "In11.Cu")
	)
	(gr_line
		(start 321.426586 -93.502988)
		(end 321.463416 -93.518228)
		(stroke
			(width 0.05715)
			(type default)
		)
		(layer "In11.Cu")
	)
	(gr_line
		(start 321.463416 -93.518228)
		(end 321.487546 -93.549216)
		(stroke
			(width 0.05715)
			(type default)
		)
		(layer "In11.Cu")
	)
	(gr_line
		(start 322.522596 -124.381006)
		(end 322.523104 -124.381006)
		(stroke
			(width 0.05715)
			(type default)
		)
		(layer "In11.Cu")
	)
	(gr_line
		(start 322.720716 -99.87407)
		(end 322.744846 -99.905058)
		(stroke
			(width 0.05715)
			(type default)
		)
		(layer "In11.Cu")
	)
	(gr_line
		(start 322.744846 -99.905058)
		(end 322.781676 -99.920298)
		(stroke
			(width 0.05715)
			(type default)
		)
		(layer "In11.Cu")
	)
	(gr_line
		(start 322.812156 -124.2568)
		(end 322.812664 -124.2568)
		(stroke
			(width 0.05715)
			(type default)
		)
		(layer "In11.Cu")
	)
	(gr_line
		(start 323.008752 -97.232216)
		(end 323.032882 -97.262696)
		(stroke
			(width 0.05715)
			(type default)
		)
		(layer "In11.Cu")
	)
	(gr_line
		(start 323.032882 -97.262696)
		(end 323.068188 -97.277428)
		(stroke
			(width 0.05715)
			(type default)
		)
		(layer "In11.Cu")
	)
	(gr_line
		(start 323.469508 -124.2568)
		(end 323.471794 -124.2568)
		(stroke
			(width 0.05715)
			(type default)
		)
		(layer "In11.Cu")
	)
	(gr_line
		(start 323.532246 -96.626172)
		(end 323.556376 -96.65716)
		(stroke
			(width 0.05715)
			(type default)
		)
		(layer "In11.Cu")
	)
	(gr_line
		(start 323.556376 -96.65716)
		(end 323.593206 -96.6724)
		(stroke
			(width 0.05715)
			(type default)
		)
		(layer "In11.Cu")
	)
	(gr_line
		(start 323.642736 -99.511612)
		(end 323.666866 -99.5426)
		(stroke
			(width 0.05715)
			(type default)
		)
		(layer "In11.Cu")
	)
	(gr_line
		(start 323.666866 -99.5426)
		(end 323.703696 -99.55784)
		(stroke
			(width 0.05715)
			(type default)
		)
		(layer "In11.Cu")
	)
	(gr_line
		(start 323.759068 -124.382784)
		(end 323.761354 -124.382784)
		(stroke
			(width 0.05715)
			(type default)
		)
		(layer "In11.Cu")
	)
	(gr_line
		(start 326.409304 -122.977148)
		(end 326.651874 -123.219718)
		(stroke
			(width 0.05715)
			(type default)
		)
		(layer "In11.Cu")
	)
	(gr_line
		(start 326.409304 -122.747024)
		(end 326.409304 -122.977148)
		(stroke
			(width 0.05715)
			(type default)
		)
		(layer "In11.Cu")
	)
	(gr_line
		(start 326.651874 -123.219718)
		(end 326.881998 -123.219718)
		(stroke
			(width 0.05715)
			(type default)
		)
		(layer "In11.Cu")
	)
	(gr_line
		(start 326.82434 -122.7455)
		(end 326.883522 -122.804682)
		(stroke
			(width 0.05715)
			(type default)
		)
		(layer "In11.Cu")
	)
	(gr_line
		(start 326.919082 -109.281214)
		(end 327.00341 -109.316266)
		(stroke
			(width 0.05715)
			(type default)
		)
		(layer "In11.Cu")
	)
	(gr_line
		(start 327.00341 -109.316266)
		(end 327.03516 -109.401864)
		(stroke
			(width 0.05715)
			(type default)
		)
		(layer "In11.Cu")
	)
	(gr_line
		(start 327.12787 -123.695714)
		(end 327.370186 -123.93803)
		(stroke
			(width 0.05715)
			(type default)
		)
		(layer "In11.Cu")
	)
	(gr_line
		(start 327.12787 -123.46559)
		(end 327.12787 -123.695714)
		(stroke
			(width 0.05715)
			(type default)
		)
		(layer "In11.Cu")
	)
	(gr_line
		(start 327.310496 -109.04855)
		(end 327.51903 -109.61116)
		(stroke
			(width 0.05715)
			(type default)
		)
		(layer "In11.Cu")
	)
	(gr_line
		(start 327.368662 -108.556298)
		(end 327.452736 -108.591096)
		(stroke
			(width 0.05715)
			(type default)
		)
		(layer "In11.Cu")
	)
	(gr_line
		(start 327.370186 -123.93803)
		(end 327.60031 -123.93803)
		(stroke
			(width 0.05715)
			(type default)
		)
		(layer "In11.Cu")
	)
	(gr_line
		(start 327.452736 -108.591096)
		(end 327.484486 -108.676694)
		(stroke
			(width 0.05715)
			(type default)
		)
		(layer "In11.Cu")
	)
	(gr_line
		(start 327.542906 -123.464066)
		(end 327.601834 -123.522994)
		(stroke
			(width 0.05715)
			(type default)
		)
		(layer "In11.Cu")
	)
	(gr_line
		(start 327.574656 -108.91393)
		(end 327.783952 -109.010196)
		(stroke
			(width 0.05715)
			(type default)
		)
		(layer "In11.Cu")
	)
	(gr_line
		(start 327.724008 -112.103154)
		(end 327.727056 -112.111282)
		(stroke
			(width 0.05715)
			(type default)
		)
		(layer "In11.Cu")
	)
	(gr_line
		(start 327.727056 -112.111282)
		(end 327.732644 -112.118394)
		(stroke
			(width 0.05715)
			(type default)
		)
		(layer "In11.Cu")
	)
	(gr_line
		(start 327.783952 -109.010196)
		(end 327.903078 -109.33176)
		(stroke
			(width 0.05715)
			(type default)
		)
		(layer "In11.Cu")
	)
	(gr_line
		(start 327.807066 -109.541056)
		(end 327.903078 -109.33176)
		(stroke
			(width 0.05715)
			(type default)
		)
		(layer "In11.Cu")
	)
	(gr_line
		(start 327.846182 -124.1806)
		(end 327.89622 -124.190506)
		(stroke
			(width 0.05715)
			(type default)
		)
		(layer "In11.Cu")
	)
	(gr_line
		(start 328.151744 -108.131356)
		(end 328.22515 -108.161836)
		(stroke
			(width 0.05715)
			(type default)
		)
		(layer "In11.Cu")
	)
	(gr_line
		(start 328.22515 -108.161836)
		(end 328.257408 -108.234226)
		(stroke
			(width 0.05715)
			(type default)
		)
		(layer "In11.Cu")
	)
	(gr_line
		(start 328.318622 -111.769906)
		(end 328.32167 -111.778034)
		(stroke
			(width 0.05715)
			(type default)
		)
		(layer "In11.Cu")
	)
	(gr_line
		(start 328.32167 -111.778034)
		(end 328.327258 -111.785146)
		(stroke
			(width 0.05715)
			(type default)
		)
		(layer "In11.Cu")
	)
	(gr_line
		(start 328.54646 -113.150904)
		(end 328.570336 -113.18113)
		(stroke
			(width 0.05715)
			(type default)
		)
		(layer "In11.Cu")
	)
	(gr_line
		(start 328.570336 -113.18113)
		(end 328.606404 -113.196116)
		(stroke
			(width 0.05715)
			(type default)
		)
		(layer "In11.Cu")
	)
	(gr_line
		(start 328.60488 -109.736382)
		(end 328.623676 -109.778546)
		(stroke
			(width 0.05715)
			(type default)
		)
		(layer "In11.Cu")
	)
	(gr_line
		(start 328.623676 -109.778546)
		(end 328.66203 -109.8042)
		(stroke
			(width 0.05715)
			(type default)
		)
		(layer "In11.Cu")
	)
	(gr_line
		(start 329.00493 -112.64519)
		(end 329.028806 -112.675416)
		(stroke
			(width 0.05715)
			(type default)
		)
		(layer "In11.Cu")
	)
	(gr_line
		(start 329.028806 -112.675416)
		(end 329.064874 -112.690402)
		(stroke
			(width 0.05715)
			(type default)
		)
		(layer "In11.Cu")
	)
	(gr_line
		(start 329.410568 -108.031534)
		(end 329.42784 -108.0389)
		(stroke
			(width 0.05715)
			(type default)
		)
		(layer "In11.Cu")
	)
	(gr_line
		(start 329.811126 -82.287364)
		(end 329.830176 -82.283554)
		(stroke
			(width 0.05715)
			(type default)
		)
		(layer "In11.Cu")
	)
	(gr_line
		(start 329.830176 -82.283554)
		(end 329.846432 -82.272886)
		(stroke
			(width 0.05715)
			(type default)
		)
		(layer "In11.Cu")
	)
	(gr_line
		(start 330.23937 -127.490474)
		(end 330.298298 -127.549402)
		(stroke
			(width 0.05715)
			(type default)
		)
		(layer "In11.Cu")
	)
	(gr_line
		(start 330.38923 -82.958178)
		(end 330.40828 -82.954368)
		(stroke
			(width 0.05715)
			(type default)
		)
		(layer "In11.Cu")
	)
	(gr_line
		(start 330.40828 -82.954368)
		(end 330.424536 -82.9437)
		(stroke
			(width 0.05715)
			(type default)
		)
		(layer "In11.Cu")
	)
	(gr_line
		(start 330.450444 -126.793752)
		(end 330.509372 -126.85268)
		(stroke
			(width 0.05715)
			(type default)
		)
		(layer "In11.Cu")
	)
	(gr_line
		(start 330.72324 -83.656932)
		(end 330.74229 -83.653122)
		(stroke
			(width 0.05715)
			(type default)
		)
		(layer "In11.Cu")
	)
	(gr_line
		(start 330.74229 -83.653122)
		(end 330.758546 -83.642454)
		(stroke
			(width 0.05715)
			(type default)
		)
		(layer "In11.Cu")
	)
	(gr_line
		(start 330.813918 -119.85625)
		(end 330.872846 -119.915178)
		(stroke
			(width 0.05715)
			(type default)
		)
		(layer "In11.Cu")
	)
	(gr_line
		(start 330.883006 -113.289334)
		(end 330.908914 -113.294668)
		(stroke
			(width 0.05715)
			(type default)
		)
		(layer "In11.Cu")
	)
	(gr_line
		(start 330.896976 -113.978436)
		(end 330.922884 -113.98377)
		(stroke
			(width 0.05715)
			(type default)
		)
		(layer "In11.Cu")
	)
	(gr_line
		(start 330.908914 -113.294668)
		(end 330.935076 -113.288318)
		(stroke
			(width 0.05715)
			(type default)
		)
		(layer "In11.Cu")
	)
	(gr_line
		(start 330.922884 -113.98377)
		(end 330.949046 -113.97742)
		(stroke
			(width 0.05715)
			(type default)
		)
		(layer "In11.Cu")
	)
	(gr_line
		(start 331.409548 -80.879696)
		(end 331.908404 -80.54721)
		(stroke
			(width 0.05715)
			(type default)
		)
		(layer "In11.Cu")
	)
	(gr_line
		(start 331.446886 -121.479564)
		(end 331.505814 -121.538492)
		(stroke
			(width 0.05715)
			(type default)
		)
		(layer "In11.Cu")
	)
	(gr_line
		(start 331.543406 -81.144618)
		(end 331.769212 -81.18983)
		(stroke
			(width 0.05715)
			(type default)
		)
		(layer "In11.Cu")
	)
	(gr_line
		(start 331.573886 -129.238248)
		(end 331.58938 -129.253742)
		(stroke
			(width 0.05715)
			(type default)
		)
		(layer "In11.Cu")
	)
	(gr_line
		(start 331.58938 -129.253742)
		(end 331.609446 -129.262124)
		(stroke
			(width 0.05715)
			(type default)
		)
		(layer "In11.Cu")
	)
	(gr_line
		(start 331.721714 -111.851186)
		(end 331.763878 -111.87938)
		(stroke
			(width 0.05715)
			(type default)
		)
		(layer "In11.Cu")
	)
	(gr_line
		(start 331.769212 -81.18983)
		(end 332.054454 -80.999584)
		(stroke
			(width 0.05715)
			(type default)
		)
		(layer "In11.Cu")
	)
	(gr_line
		(start 331.949298 -128.70561)
		(end 331.964792 -128.721104)
		(stroke
			(width 0.05715)
			(type default)
		)
		(layer "In11.Cu")
	)
	(gr_line
		(start 331.964792 -128.721104)
		(end 331.984858 -128.729486)
		(stroke
			(width 0.05715)
			(type default)
		)
		(layer "In11.Cu")
	)
	(gr_line
		(start 332.054454 -80.999584)
		(end 332.09992 -80.773778)
		(stroke
			(width 0.05715)
			(type default)
		)
		(layer "In11.Cu")
	)
	(gr_line
		(start 332.119478 -112.700816)
		(end 332.14564 -112.694466)
		(stroke
			(width 0.05715)
			(type default)
		)
		(layer "In11.Cu")
	)
	(gr_line
		(start 332.133448 -113.389918)
		(end 332.15961 -113.383568)
		(stroke
			(width 0.05715)
			(type default)
		)
		(layer "In11.Cu")
	)
	(gr_line
		(start 332.14564 -112.694466)
		(end 332.171548 -112.6998)
		(stroke
			(width 0.05715)
			(type default)
		)
		(layer "In11.Cu")
	)
	(gr_line
		(start 332.15961 -113.383568)
		(end 332.185518 -113.388902)
		(stroke
			(width 0.05715)
			(type default)
		)
		(layer "In11.Cu")
	)
	(gr_line
		(start 332.255622 -80.315816)
		(end 332.753716 -79.983838)
		(stroke
			(width 0.05715)
			(type default)
		)
		(layer "In11.Cu")
	)
	(gr_line
		(start 332.320392 -86.620858)
		(end 332.339442 -86.617048)
		(stroke
			(width 0.05715)
			(type default)
		)
		(layer "In11.Cu")
	)
	(gr_line
		(start 332.339442 -86.617048)
		(end 332.358492 -86.620858)
		(stroke
			(width 0.05715)
			(type default)
		)
		(layer "In11.Cu")
	)
	(gr_line
		(start 332.388972 -80.580992)
		(end 332.614778 -80.626204)
		(stroke
			(width 0.05715)
			(type default)
		)
		(layer "In11.Cu")
	)
	(gr_line
		(start 332.602332 -85.867494)
		(end 332.621382 -85.863684)
		(stroke
			(width 0.05715)
			(type default)
		)
		(layer "In11.Cu")
	)
	(gr_line
		(start 332.614778 -80.626204)
		(end 332.90002 -80.435958)
		(stroke
			(width 0.05715)
			(type default)
		)
		(layer "In11.Cu")
	)
	(gr_line
		(start 332.621382 -85.863684)
		(end 332.640432 -85.867494)
		(stroke
			(width 0.05715)
			(type default)
		)
		(layer "In11.Cu")
	)
	(gr_line
		(start 332.90002 -80.435958)
		(end 332.945486 -80.210152)
		(stroke
			(width 0.05715)
			(type default)
		)
		(layer "In11.Cu")
	)
	(gr_line
		(start 333.00162 -128.24587)
		(end 333.041498 -128.277112)
		(stroke
			(width 0.05715)
			(type default)
		)
		(layer "In11.Cu")
	)
	(gr_line
		(start 333.041498 -128.277112)
		(end 333.092298 -128.28143)
		(stroke
			(width 0.05715)
			(type default)
		)
		(layer "In11.Cu")
	)
	(gr_line
		(start 333.099156 -79.75346)
		(end 333.598774 -79.420466)
		(stroke
			(width 0.05715)
			(type default)
		)
		(layer "In11.Cu")
	)
	(gr_line
		(start 333.234284 -80.017366)
		(end 333.46009 -80.062578)
		(stroke
			(width 0.05715)
			(type default)
		)
		(layer "In11.Cu")
	)
	(gr_line
		(start 333.46009 -80.062578)
		(end 333.745332 -79.872332)
		(stroke
			(width 0.05715)
			(type default)
		)
		(layer "In11.Cu")
	)
	(gr_line
		(start 333.56931 -101.133148)
		(end 333.580994 -101.13518)
		(stroke
			(width 0.05715)
			(type default)
		)
		(layer "In11.Cu")
	)
	(gr_line
		(start 333.57058 -100.321364)
		(end 333.582518 -100.323396)
		(stroke
			(width 0.05715)
			(type default)
		)
		(layer "In11.Cu")
	)
	(gr_line
		(start 333.580994 -101.13518)
		(end 333.592678 -101.133148)
		(stroke
			(width 0.05715)
			(type default)
		)
		(layer "In11.Cu")
	)
	(gr_line
		(start 333.582518 -100.323396)
		(end 333.594202 -100.321364)
		(stroke
			(width 0.05715)
			(type default)
		)
		(layer "In11.Cu")
	)
	(gr_line
		(start 333.66837 -124.113544)
		(end 333.727298 -124.172472)
		(stroke
			(width 0.05715)
			(type default)
		)
		(layer "In11.Cu")
	)
	(gr_line
		(start 333.745332 -79.872332)
		(end 333.790544 -79.64678)
		(stroke
			(width 0.05715)
			(type default)
		)
		(layer "In11.Cu")
	)
	(gr_line
		(start 333.945992 -79.189072)
		(end 334.444086 -78.857094)
		(stroke
			(width 0.05715)
			(type default)
		)
		(layer "In11.Cu")
	)
	(gr_line
		(start 334.022954 -123.477782)
		(end 334.082644 -123.537472)
		(stroke
			(width 0.05715)
			(type default)
		)
		(layer "In11.Cu")
	)
	(gr_line
		(start 334.07985 -79.453994)
		(end 334.305402 -79.499206)
		(stroke
			(width 0.05715)
			(type default)
		)
		(layer "In11.Cu")
	)
	(gr_line
		(start 334.102964 -114.070384)
		(end 334.122014 -114.074194)
		(stroke
			(width 0.05715)
			(type default)
		)
		(layer "In11.Cu")
	)
	(gr_line
		(start 334.102964 -113.383822)
		(end 334.122014 -113.387632)
		(stroke
			(width 0.05715)
			(type default)
		)
		(layer "In11.Cu")
	)
	(gr_line
		(start 334.120998 -125.942852)
		(end 334.12684 -125.94463)
		(stroke
			(width 0.05715)
			(type default)
		)
		(layer "In11.Cu")
	)
	(gr_line
		(start 334.122014 -114.074194)
		(end 334.141064 -114.070384)
		(stroke
			(width 0.05715)
			(type default)
		)
		(layer "In11.Cu")
	)
	(gr_line
		(start 334.122014 -113.387632)
		(end 334.141064 -113.383822)
		(stroke
			(width 0.05715)
			(type default)
		)
		(layer "In11.Cu")
	)
	(gr_line
		(start 334.305402 -79.499206)
		(end 334.590644 -79.30896)
		(stroke
			(width 0.05715)
			(type default)
		)
		(layer "In11.Cu")
	)
	(gr_line
		(start 334.590644 -79.30896)
		(end 334.63611 -79.083154)
		(stroke
			(width 0.05715)
			(type default)
		)
		(layer "In11.Cu")
	)
	(gr_line
		(start 334.783684 -76.087478)
		(end 335.101438 -76.405232)
		(stroke
			(width 0.0635)
			(type default)
		)
		(layer "In11.Cu")
	)
	(gr_line
		(start 334.783684 -75.724766)
		(end 335.101438 -75.407012)
		(stroke
			(width 0.0635)
			(type default)
		)
		(layer "In11.Cu")
	)
	(gr_line
		(start 334.791304 -78.6257)
		(end 335.289398 -78.293722)
		(stroke
			(width 0.05715)
			(type default)
		)
		(layer "In11.Cu")
	)
	(gr_line
		(start 334.925162 -78.890622)
		(end 335.150714 -78.935834)
		(stroke
			(width 0.05715)
			(type default)
		)
		(layer "In11.Cu")
	)
	(gr_line
		(start 335.101438 -76.40193)
		(end 335.101438 -76.405232)
		(stroke
			(width 0.0635)
			(type default)
		)
		(layer "In11.Cu")
	)
	(gr_line
		(start 335.101438 -76.40193)
		(end 335.10474 -76.40193)
		(stroke
			(width 0.0635)
			(type default)
		)
		(layer "In11.Cu")
	)
	(gr_line
		(start 335.150714 -78.935834)
		(end 335.435956 -78.745588)
		(stroke
			(width 0.05715)
			(type default)
		)
		(layer "In11.Cu")
	)
	(gr_line
		(start 335.16824 -86.67115)
		(end 335.21015 -86.679532)
		(stroke
			(width 0.05715)
			(type default)
		)
		(layer "In11.Cu")
	)
	(gr_line
		(start 335.21015 -86.679532)
		(end 335.250536 -86.665562)
		(stroke
			(width 0.05715)
			(type default)
		)
		(layer "In11.Cu")
	)
	(gr_line
		(start 335.435956 -78.745588)
		(end 335.481422 -78.519782)
		(stroke
			(width 0.05715)
			(type default)
		)
		(layer "In11.Cu")
	)
	(gr_line
		(start 335.477358 -113.505234)
		(end 335.496408 -113.501424)
		(stroke
			(width 0.05715)
			(type default)
		)
		(layer "In11.Cu")
	)
	(gr_line
		(start 335.496408 -113.501424)
		(end 335.515458 -113.505234)
		(stroke
			(width 0.05715)
			(type default)
		)
		(layer "In11.Cu")
	)
	(gr_line
		(start 335.53273 -128.48463)
		(end 335.533492 -128.48463)
		(stroke
			(width 0.05715)
			(type default)
		)
		(layer "In11.Cu")
	)
	(gr_line
		(start 335.533492 -128.48463)
		(end 335.534254 -128.48463)
		(stroke
			(width 0.05715)
			(type default)
		)
		(layer "In11.Cu")
	)
	(gr_line
		(start 335.748884 -78.33868)
		(end 335.767172 -78.326488)
		(stroke
			(width 0.05715)
			(type default)
		)
		(layer "In11.Cu")
	)
	(gr_line
		(start 335.767172 -78.326488)
		(end 335.779364 -78.3082)
		(stroke
			(width 0.05715)
			(type default)
		)
		(layer "In11.Cu")
	)
	(gr_line
		(start 335.909666 -79.287116)
		(end 335.927954 -79.274924)
		(stroke
			(width 0.05715)
			(type default)
		)
		(layer "In11.Cu")
	)
	(gr_line
		(start 335.92643 -99.632008)
		(end 335.93405 -99.630738)
		(stroke
			(width 0.05715)
			(type default)
		)
		(layer "In11.Cu")
	)
	(gr_line
		(start 335.927954 -79.274924)
		(end 335.940146 -79.256636)
		(stroke
			(width 0.05715)
			(type default)
		)
		(layer "In11.Cu")
	)
	(gr_line
		(start 335.93405 -99.630738)
		(end 335.94167 -99.631754)
		(stroke
			(width 0.05715)
			(type default)
		)
		(layer "In11.Cu")
	)
	(gr_line
		(start 335.982818 -112.71758)
		(end 336.001868 -112.71377)
		(stroke
			(width 0.05715)
			(type default)
		)
		(layer "In11.Cu")
	)
	(gr_line
		(start 336.001868 -112.71377)
		(end 336.020918 -112.71758)
		(stroke
			(width 0.05715)
			(type default)
		)
		(layer "In11.Cu")
	)
	(gr_line
		(start 336.036666 -100.424996)
		(end 336.044286 -100.423726)
		(stroke
			(width 0.05715)
			(type default)
		)
		(layer "In11.Cu")
	)
	(gr_line
		(start 336.044286 -100.423726)
		(end 336.051906 -100.424742)
		(stroke
			(width 0.05715)
			(type default)
		)
		(layer "In11.Cu")
	)
	(gr_line
		(start 336.29981 -104.428544)
		(end 336.31251 -104.430576)
		(stroke
			(width 0.05715)
			(type default)
		)
		(layer "In11.Cu")
	)
	(gr_line
		(start 336.309208 -105.111804)
		(end 336.321908 -105.113836)
		(stroke
			(width 0.05715)
			(type default)
		)
		(layer "In11.Cu")
	)
	(gr_line
		(start 336.31251 -104.430576)
		(end 336.325972 -104.428036)
		(stroke
			(width 0.05715)
			(type default)
		)
		(layer "In11.Cu")
	)
	(gr_line
		(start 336.321908 -105.113836)
		(end 336.33537 -105.111296)
		(stroke
			(width 0.05715)
			(type default)
		)
		(layer "In11.Cu")
	)
	(gr_line
		(start 336.440018 -130.945382)
		(end 336.502502 -130.97129)
		(stroke
			(width 0.05715)
			(type default)
		)
		(layer "In11.Cu")
	)
	(gr_line
		(start 336.46237 -79.840328)
		(end 336.480658 -79.828136)
		(stroke
			(width 0.05715)
			(type default)
		)
		(layer "In11.Cu")
	)
	(gr_line
		(start 336.480658 -79.828136)
		(end 336.49285 -79.809848)
		(stroke
			(width 0.05715)
			(type default)
		)
		(layer "In11.Cu")
	)
	(gr_line
		(start 336.502502 -130.97129)
		(end 336.534506 -131.032758)
		(stroke
			(width 0.05715)
			(type default)
		)
		(layer "In11.Cu")
	)
	(gr_line
		(start 336.869024 -87.821008)
		(end 336.920078 -87.831168)
		(stroke
			(width 0.05715)
			(type default)
		)
		(layer "In11.Cu")
	)
	(gr_line
		(start 336.905346 -130.449828)
		(end 336.968338 -130.47599)
		(stroke
			(width 0.05715)
			(type default)
		)
		(layer "In11.Cu")
	)
	(gr_line
		(start 336.920078 -87.831168)
		(end 336.96783 -87.81161)
		(stroke
			(width 0.05715)
			(type default)
		)
		(layer "In11.Cu")
	)
	(gr_line
		(start 336.968338 -130.47599)
		(end 336.999326 -130.536188)
		(stroke
			(width 0.05715)
			(type default)
		)
		(layer "In11.Cu")
	)
	(gr_line
		(start 337.138518 -100.088954)
		(end 337.14055 -100.089208)
		(stroke
			(width 0.05715)
			(type default)
		)
		(layer "In11.Cu")
	)
	(gr_line
		(start 337.14055 -100.089208)
		(end 337.142582 -100.088954)
		(stroke
			(width 0.05715)
			(type default)
		)
		(layer "In11.Cu")
	)
	(gr_line
		(start 337.2485 -100.881434)
		(end 337.250532 -100.881688)
		(stroke
			(width 0.05715)
			(type default)
		)
		(layer "In11.Cu")
	)
	(gr_line
		(start 337.250532 -100.881688)
		(end 337.252564 -100.881434)
		(stroke
			(width 0.05715)
			(type default)
		)
		(layer "In11.Cu")
	)
	(gr_line
		(start 337.382612 -133.300978)
		(end 337.420204 -133.373876)
		(stroke
			(width 0.05715)
			(type default)
		)
		(layer "In11.Cu")
	)
	(gr_line
		(start 337.420204 -133.373876)
		(end 337.499198 -133.399022)
		(stroke
			(width 0.05715)
			(type default)
		)
		(layer "In11.Cu")
	)
	(gr_line
		(start 337.75523 -85.487256)
		(end 337.795616 -85.473286)
		(stroke
			(width 0.05715)
			(type default)
		)
		(layer "In11.Cu")
	)
	(gr_line
		(start 337.795616 -85.473286)
		(end 337.837526 -85.481668)
		(stroke
			(width 0.05715)
			(type default)
		)
		(layer "In11.Cu")
	)
	(gr_line
		(start 337.80857 -132.730494)
		(end 337.84667 -132.8039)
		(stroke
			(width 0.05715)
			(type default)
		)
		(layer "In11.Cu")
	)
	(gr_line
		(start 337.824826 -103.845106)
		(end 337.838034 -103.842566)
		(stroke
			(width 0.05715)
			(type default)
		)
		(layer "In11.Cu")
	)
	(gr_line
		(start 337.830668 -104.528874)
		(end 337.8454 -104.52608)
		(stroke
			(width 0.05715)
			(type default)
		)
		(layer "In11.Cu")
	)
	(gr_line
		(start 337.838034 -103.842312)
		(end 337.838034 -103.842566)
		(stroke
			(width 0.05715)
			(type default)
		)
		(layer "In11.Cu")
	)
	(gr_line
		(start 337.838034 -103.842312)
		(end 337.853528 -103.844852)
		(stroke
			(width 0.05715)
			(type default)
		)
		(layer "In11.Cu")
	)
	(gr_line
		(start 337.8454 -104.52608)
		(end 337.860386 -104.52862)
		(stroke
			(width 0.05715)
			(type default)
		)
		(layer "In11.Cu")
	)
	(gr_line
		(start 337.84667 -132.8039)
		(end 337.925664 -132.829046)
		(stroke
			(width 0.05715)
			(type default)
		)
		(layer "In11.Cu")
	)
	(gr_line
		(start 338.10448 -75.48245)
		(end 338.132928 -75.439524)
		(stroke
			(width 0.05715)
			(type default)
		)
		(layer "In11.Cu")
	)
	(gr_line
		(start 338.132928 -75.439524)
		(end 338.180172 -75.419966)
		(stroke
			(width 0.05715)
			(type default)
		)
		(layer "In11.Cu")
	)
	(gr_line
		(start 338.21116 -73.615804)
		(end 338.229448 -73.575672)
		(stroke
			(width 0.05715)
			(type default)
		)
		(layer "In11.Cu")
	)
	(gr_line
		(start 338.229448 -73.575672)
		(end 338.26704 -73.550526)
		(stroke
			(width 0.05715)
			(type default)
		)
		(layer "In11.Cu")
	)
	(gr_line
		(start 338.290154 -100.452936)
		(end 338.333588 -100.447348)
		(stroke
			(width 0.05715)
			(type default)
		)
		(layer "In11.Cu")
	)
	(gr_line
		(start 338.333588 -100.447348)
		(end 338.37372 -100.464874)
		(stroke
			(width 0.05715)
			(type default)
		)
		(layer "In11.Cu")
	)
	(gr_line
		(start 338.407756 -99.630992)
		(end 338.450936 -99.625404)
		(stroke
			(width 0.05715)
			(type default)
		)
		(layer "In11.Cu")
	)
	(gr_line
		(start 338.450936 -99.625404)
		(end 338.491068 -99.64293)
		(stroke
			(width 0.05715)
			(type default)
		)
		(layer "In11.Cu")
	)
	(gr_line
		(start 338.65566 -73.291446)
		(end 338.67344 -73.279762)
		(stroke
			(width 0.05715)
			(type default)
		)
		(layer "In11.Cu")
	)
	(gr_line
		(start 338.67344 -73.279762)
		(end 338.694522 -73.275444)
		(stroke
			(width 0.05715)
			(type default)
		)
		(layer "In11.Cu")
	)
	(gr_line
		(start 338.696554 -75.977242)
		(end 338.72424 -75.935586)
		(stroke
			(width 0.05715)
			(type default)
		)
		(layer "In11.Cu")
	)
	(gr_line
		(start 338.72424 -75.935586)
		(end 338.770722 -75.916282)
		(stroke
			(width 0.05715)
			(type default)
		)
		(layer "In11.Cu")
	)
	(gr_line
		(start 339.182964 -86.585552)
		(end 339.230716 -86.565994)
		(stroke
			(width 0.05715)
			(type default)
		)
		(layer "In11.Cu")
	)
	(gr_line
		(start 339.230716 -86.565994)
		(end 339.28177 -86.576154)
		(stroke
			(width 0.05715)
			(type default)
		)
		(layer "In11.Cu")
	)
	(gr_line
		(start 339.539834 -127.463296)
		(end 339.556852 -127.459994)
		(stroke
			(width 0.05715)
			(type default)
		)
		(layer "In11.Cu")
	)
	(gr_line
		(start 339.556852 -127.459994)
		(end 339.55736 -127.459994)
		(stroke
			(width 0.05715)
			(type default)
		)
		(layer "In11.Cu")
	)
	(gr_line
		(start 339.55736 -127.459994)
		(end 339.57514 -127.46355)
		(stroke
			(width 0.05715)
			(type default)
		)
		(layer "In11.Cu")
	)
	(gr_line
		(start 339.688424 -73.076562)
		(end 339.707474 -73.072752)
		(stroke
			(width 0.05715)
			(type default)
		)
		(layer "In11.Cu")
	)
	(gr_line
		(start 339.693758 -101.0412)
		(end 339.723222 -101.054154)
		(stroke
			(width 0.05715)
			(type default)
		)
		(layer "In11.Cu")
	)
	(gr_line
		(start 339.707474 -73.072752)
		(end 339.726524 -73.076562)
		(stroke
			(width 0.05715)
			(type default)
		)
		(layer "In11.Cu")
	)
	(gr_line
		(start 339.723222 -101.054154)
		(end 339.743796 -101.079046)
		(stroke
			(width 0.05715)
			(type default)
		)
		(layer "In11.Cu")
	)
	(gr_line
		(start 339.748876 -104.845866)
		(end 339.778594 -104.850946)
		(stroke
			(width 0.05715)
			(type default)
		)
		(layer "In11.Cu")
	)
	(gr_line
		(start 339.778594 -104.850946)
		(end 339.802978 -104.868472)
		(stroke
			(width 0.05715)
			(type default)
		)
		(layer "In11.Cu")
	)
	(gr_line
		(start 339.987636 -104.2035)
		(end 340.017354 -104.20858)
		(stroke
			(width 0.05715)
			(type default)
		)
		(layer "In11.Cu")
	)
	(gr_line
		(start 340.017354 -104.20858)
		(end 340.041738 -104.226106)
		(stroke
			(width 0.05715)
			(type default)
		)
		(layer "In11.Cu")
	)
	(gr_line
		(start 340.022688 -100.311712)
		(end 340.05393 -100.325428)
		(stroke
			(width 0.05715)
			(type default)
		)
		(layer "In11.Cu")
	)
	(gr_line
		(start 340.05393 -100.325428)
		(end 340.07552 -100.35159)
		(stroke
			(width 0.05715)
			(type default)
		)
		(layer "In11.Cu")
	)
	(gr_line
		(start 340.221824 -83.65871)
		(end 340.240874 -83.6549)
		(stroke
			(width 0.05715)
			(type default)
		)
		(layer "In11.Cu")
	)
	(gr_line
		(start 340.240874 -83.6549)
		(end 340.259924 -83.65871)
		(stroke
			(width 0.05715)
			(type default)
		)
		(layer "In11.Cu")
	)
	(gr_line
		(start 340.36889 -101.838252)
		(end 340.372446 -101.84257)
		(stroke
			(width 0.05715)
			(type default)
		)
		(layer "In11.Cu")
	)
	(gr_line
		(start 340.372446 -101.84257)
		(end 340.374732 -101.847904)
		(stroke
			(width 0.05715)
			(type default)
		)
		(layer "In11.Cu")
	)
	(gr_line
		(start 340.393274 -82.937604)
		(end 340.412324 -82.933794)
		(stroke
			(width 0.05715)
			(type default)
		)
		(layer "In11.Cu")
	)
	(gr_line
		(start 340.406228 -105.303828)
		(end 340.425278 -105.31729)
		(stroke
			(width 0.05715)
			(type default)
		)
		(layer "In11.Cu")
	)
	(gr_line
		(start 340.412324 -82.933794)
		(end 340.431374 -82.937604)
		(stroke
			(width 0.05715)
			(type default)
		)
		(layer "In11.Cu")
	)
	(gr_line
		(start 340.425278 -105.31729)
		(end 340.437216 -105.33761)
		(stroke
			(width 0.05715)
			(type default)
		)
		(layer "In11.Cu")
	)
	(gr_line
		(start 340.450932 -114.15522)
		(end 340.468204 -114.162586)
		(stroke
			(width 0.05715)
			(type default)
		)
		(layer "In11.Cu")
	)
	(gr_line
		(start 340.467442 -112.8903)
		(end 340.484714 -112.897666)
		(stroke
			(width 0.05715)
			(type default)
		)
		(layer "In11.Cu")
	)
	(gr_line
		(start 340.555326 -82.09026)
		(end 340.574376 -82.08645)
		(stroke
			(width 0.05715)
			(type default)
		)
		(layer "In11.Cu")
	)
	(gr_line
		(start 340.574376 -82.08645)
		(end 340.593426 -82.09026)
		(stroke
			(width 0.05715)
			(type default)
		)
		(layer "In11.Cu")
	)
	(gr_line
		(start 340.74862 -73.578974)
		(end 340.76767 -73.582784)
		(stroke
			(width 0.05715)
			(type default)
		)
		(layer "In11.Cu")
	)
	(gr_line
		(start 340.76767 -73.582784)
		(end 340.78672 -73.578974)
		(stroke
			(width 0.05715)
			(type default)
		)
		(layer "In11.Cu")
	)
	(gr_line
		(start 340.856062 -91.533472)
		(end 340.856316 -91.533472)
		(stroke
			(width 0.0635)
			(type default)
		)
		(layer "In11.Cu")
	)
	(gr_line
		(start 340.856062 -91.533472)
		(end 341.122762 -91.800172)
		(stroke
			(width 0.0635)
			(type default)
		)
		(layer "In11.Cu")
	)
	(gr_line
		(start 340.859618 -101.303328)
		(end 340.863174 -101.307646)
		(stroke
			(width 0.05715)
			(type default)
		)
		(layer "In11.Cu")
	)
	(gr_line
		(start 340.863174 -101.307646)
		(end 340.86546 -101.31298)
		(stroke
			(width 0.05715)
			(type default)
		)
		(layer "In11.Cu")
	)
	(gr_line
		(start 340.930484 -104.867202)
		(end 340.949534 -104.880664)
		(stroke
			(width 0.05715)
			(type default)
		)
		(layer "In11.Cu")
	)
	(gr_line
		(start 340.949534 -104.880664)
		(end 340.961472 -104.900984)
		(stroke
			(width 0.05715)
			(type default)
		)
		(layer "In11.Cu")
	)
	(gr_line
		(start 340.997032 -114.381534)
		(end 341.01532 -114.389154)
		(stroke
			(width 0.05715)
			(type default)
		)
		(layer "In11.Cu")
	)
	(gr_line
		(start 341.141558 -104.464866)
		(end 341.159338 -104.507538)
		(stroke
			(width 0.05715)
			(type default)
		)
		(layer "In11.Cu")
	)
	(gr_line
		(start 341.159338 -104.507538)
		(end 341.196422 -104.534208)
		(stroke
			(width 0.05715)
			(type default)
		)
		(layer "In11.Cu")
	)
	(gr_line
		(start 341.447882 -91.44381)
		(end 341.447882 -91.798394)
		(stroke
			(width 0.0635)
			(type default)
		)
		(layer "In11.Cu")
	)
	(gr_line
		(start 341.447882 -91.44381)
		(end 341.561674 -91.330018)
		(stroke
			(width 0.0635)
			(type default)
		)
		(layer "In11.Cu")
	)
	(gr_line
		(start 341.574882 -103.790242)
		(end 341.592662 -103.833168)
		(stroke
			(width 0.05715)
			(type default)
		)
		(layer "In11.Cu")
	)
	(gr_line
		(start 341.592662 -103.833168)
		(end 341.63 -103.860092)
		(stroke
			(width 0.05715)
			(type default)
		)
		(layer "In11.Cu")
	)
	(gr_line
		(start 341.624158 -113.36909)
		(end 341.644224 -113.377472)
		(stroke
			(width 0.05715)
			(type default)
		)
		(layer "In11.Cu")
	)
	(gr_line
		(start 341.649304 -107.97032)
		(end 341.657686 -107.984798)
		(stroke
			(width 0.05715)
			(type default)
		)
		(layer "In11.Cu")
	)
	(gr_line
		(start 341.657686 -107.984798)
		(end 341.671148 -107.995466)
		(stroke
			(width 0.05715)
			(type default)
		)
		(layer "In11.Cu")
	)
	(gr_line
		(start 341.805006 -123.323858)
		(end 341.824818 -123.327922)
		(stroke
			(width 0.05715)
			(type default)
		)
		(layer "In11.Cu")
	)
	(gr_line
		(start 341.824818 -123.327922)
		(end 341.84463 -123.324112)
		(stroke
			(width 0.05715)
			(type default)
		)
		(layer "In11.Cu")
	)
	(gr_line
		(start 341.900764 -73.05802)
		(end 341.919814 -73.05421)
		(stroke
			(width 0.05715)
			(type default)
		)
		(layer "In11.Cu")
	)
	(gr_line
		(start 341.919814 -73.05421)
		(end 341.938864 -73.05802)
		(stroke
			(width 0.05715)
			(type default)
		)
		(layer "In11.Cu")
	)
	(gr_line
		(start 341.922608 -107.108498)
		(end 341.95766 -107.167934)
		(stroke
			(width 0.05715)
			(type default)
		)
		(layer "In11.Cu")
	)
	(gr_line
		(start 341.939626 -134.812278)
		(end 341.94623 -134.81431)
		(stroke
			(width 0.05715)
			(type default)
		)
		(layer "In11.Cu")
	)
	(gr_line
		(start 341.95766 -107.167934)
		(end 342.022684 -107.190794)
		(stroke
			(width 0.05715)
			(type default)
		)
		(layer "In11.Cu")
	)
	(gr_line
		(start 342.059006 -134.144512)
		(end 342.06561 -134.146544)
		(stroke
			(width 0.05715)
			(type default)
		)
		(layer "In11.Cu")
	)
	(gr_line
		(start 342.246712 -114.393472)
		(end 342.30564 -114.4524)
		(stroke
			(width 0.05715)
			(type default)
		)
		(layer "In11.Cu")
	)
	(gr_line
		(start 342.377522 -74.671174)
		(end 342.396572 -74.667364)
		(stroke
			(width 0.05715)
			(type default)
		)
		(layer "In11.Cu")
	)
	(gr_line
		(start 342.39073 -86.6902)
		(end 342.40978 -86.69401)
		(stroke
			(width 0.05715)
			(type default)
		)
		(layer "In11.Cu")
	)
	(gr_line
		(start 342.396572 -74.667364)
		(end 342.415622 -74.671174)
		(stroke
			(width 0.05715)
			(type default)
		)
		(layer "In11.Cu")
	)
	(gr_line
		(start 342.40978 -86.69401)
		(end 342.42883 -86.6902)
		(stroke
			(width 0.05715)
			(type default)
		)
		(layer "In11.Cu")
	)
	(gr_line
		(start 342.475312 -73.913746)
		(end 342.494362 -73.909936)
		(stroke
			(width 0.05715)
			(type default)
		)
		(layer "In11.Cu")
	)
	(gr_line
		(start 342.477598 -128.027684)
		(end 342.499696 -128.032002)
		(stroke
			(width 0.05715)
			(type default)
		)
		(layer "In11.Cu")
	)
	(gr_line
		(start 342.494362 -73.909936)
		(end 342.513412 -73.913746)
		(stroke
			(width 0.05715)
			(type default)
		)
		(layer "In11.Cu")
	)
	(gr_line
		(start 342.499696 -128.032002)
		(end 342.518238 -128.044448)
		(stroke
			(width 0.05715)
			(type default)
		)
		(layer "In11.Cu")
	)
	(gr_line
		(start 342.573356 -108.701078)
		(end 342.575134 -108.702348)
		(stroke
			(width 0.05715)
			(type default)
		)
		(layer "In11.Cu")
	)
	(gr_line
		(start 342.575134 -108.702348)
		(end 342.576658 -108.702856)
		(stroke
			(width 0.05715)
			(type default)
		)
		(layer "In11.Cu")
	)
	(gr_line
		(start 343.01684 -105.8418)
		(end 343.037414 -105.856532)
		(stroke
			(width 0.05715)
			(type default)
		)
		(layer "In11.Cu")
	)
	(gr_line
		(start 343.037414 -105.856532)
		(end 343.061544 -105.861104)
		(stroke
			(width 0.05715)
			(type default)
		)
		(layer "In11.Cu")
	)
	(gr_line
		(start 343.086182 -128.427988)
		(end 343.101422 -128.438402)
		(stroke
			(width 0.05715)
			(type default)
		)
		(layer "In11.Cu")
	)
	(gr_line
		(start 343.101422 -128.438402)
		(end 343.111582 -128.453642)
		(stroke
			(width 0.05715)
			(type default)
		)
		(layer "In11.Cu")
	)
	(gr_line
		(start 343.121996 -126.03607)
		(end 343.202768 -126.051818)
		(stroke
			(width 0.05715)
			(type default)
		)
		(layer "In11.Cu")
	)
	(gr_line
		(start 343.202768 -126.051818)
		(end 343.248996 -126.120144)
		(stroke
			(width 0.05715)
			(type default)
		)
		(layer "In11.Cu")
	)
	(gr_line
		(start 343.49309 -105.201466)
		(end 343.51468 -105.21696)
		(stroke
			(width 0.05715)
			(type default)
		)
		(layer "In11.Cu")
	)
	(gr_line
		(start 343.51468 -105.21696)
		(end 343.515442 -105.217214)
		(stroke
			(width 0.05715)
			(type default)
		)
		(layer "In11.Cu")
	)
	(gr_line
		(start 343.515442 -105.217214)
		(end 343.542112 -105.222548)
		(stroke
			(width 0.05715)
			(type default)
		)
		(layer "In11.Cu")
	)
	(gr_line
		(start 343.557098 -82.980784)
		(end 343.576148 -82.984594)
		(stroke
			(width 0.05715)
			(type default)
		)
		(layer "In11.Cu")
	)
	(gr_line
		(start 343.572592 -129.659126)
		(end 343.582752 -129.674366)
		(stroke
			(width 0.05715)
			(type default)
		)
		(layer "In11.Cu")
	)
	(gr_line
		(start 343.576148 -82.984594)
		(end 343.595198 -82.980784)
		(stroke
			(width 0.05715)
			(type default)
		)
		(layer "In11.Cu")
	)
	(gr_line
		(start 343.582752 -129.674366)
		(end 343.597992 -129.68478)
		(stroke
			(width 0.05715)
			(type default)
		)
		(layer "In11.Cu")
	)
	(gr_line
		(start 343.624916 -86.153244)
		(end 343.66073 -86.145878)
		(stroke
			(width 0.05715)
			(type default)
		)
		(layer "In11.Cu")
	)
	(gr_line
		(start 343.66073 -86.145878)
		(end 343.696544 -86.157054)
		(stroke
			(width 0.05715)
			(type default)
		)
		(layer "In11.Cu")
	)
	(gr_line
		(start 343.766394 -107.802934)
		(end 343.830402 -107.82554)
		(stroke
			(width 0.05715)
			(type default)
		)
		(layer "In11.Cu")
	)
	(gr_line
		(start 343.770204 -125.459236)
		(end 343.849452 -125.475238)
		(stroke
			(width 0.05715)
			(type default)
		)
		(layer "In11.Cu")
	)
	(gr_line
		(start 343.78646 -83.90763)
		(end 343.808558 -83.911948)
		(stroke
			(width 0.05715)
			(type default)
		)
		(layer "In11.Cu")
	)
	(gr_line
		(start 343.808558 -83.911948)
		(end 343.830148 -83.90763)
		(stroke
			(width 0.05715)
			(type default)
		)
		(layer "In11.Cu")
	)
	(gr_line
		(start 343.823544 -127.494284)
		(end 343.83472 -127.510794)
		(stroke
			(width 0.05715)
			(type default)
		)
		(layer "In11.Cu")
	)
	(gr_line
		(start 343.830402 -107.82554)
		(end 343.895934 -107.801156)
		(stroke
			(width 0.05715)
			(type default)
		)
		(layer "In11.Cu")
	)
	(gr_line
		(start 343.83472 -127.510794)
		(end 343.85123 -127.52197)
		(stroke
			(width 0.05715)
			(type default)
		)
		(layer "In11.Cu")
	)
	(gr_line
		(start 343.849452 -125.475238)
		(end 343.895172 -125.542802)
		(stroke
			(width 0.05715)
			(type default)
		)
		(layer "In11.Cu")
	)
	(gr_line
		(start 343.952576 -87.510874)
		(end 343.971626 -87.514684)
		(stroke
			(width 0.05715)
			(type default)
		)
		(layer "In11.Cu")
	)
	(gr_line
		(start 343.971626 -87.514684)
		(end 343.987882 -87.525352)
		(stroke
			(width 0.05715)
			(type default)
		)
		(layer "In11.Cu")
	)
	(gr_line
		(start 344.102182 -130.02514)
		(end 344.120724 -130.037586)
		(stroke
			(width 0.05715)
			(type default)
		)
		(layer "In11.Cu")
	)
	(gr_line
		(start 344.120724 -130.037586)
		(end 344.142822 -130.041904)
		(stroke
			(width 0.05715)
			(type default)
		)
		(layer "In11.Cu")
	)
	(gr_line
		(start 344.124534 -109.343698)
		(end 344.142314 -109.351064)
		(stroke
			(width 0.05715)
			(type default)
		)
		(layer "In11.Cu")
	)
	(gr_line
		(start 344.146632 -122.876818)
		(end 344.196924 -122.866912)
		(stroke
			(width 0.05715)
			(type default)
		)
		(layer "In11.Cu")
	)
	(gr_line
		(start 344.196924 -122.866912)
		(end 344.2335 -122.830336)
		(stroke
			(width 0.05715)
			(type default)
		)
		(layer "In11.Cu")
	)
	(gr_line
		(start 344.342974 -124.905262)
		(end 344.423746 -124.921518)
		(stroke
			(width 0.05715)
			(type default)
		)
		(layer "In11.Cu")
	)
	(gr_line
		(start 344.423746 -124.921518)
		(end 344.46972 -124.989844)
		(stroke
			(width 0.05715)
			(type default)
		)
		(layer "In11.Cu")
	)
	(gr_line
		(start 344.453972 -88.18753)
		(end 344.470228 -88.198198)
		(stroke
			(width 0.05715)
			(type default)
		)
		(layer "In11.Cu")
	)
	(gr_line
		(start 344.470228 -88.198198)
		(end 344.489278 -88.202008)
		(stroke
			(width 0.05715)
			(type default)
		)
		(layer "In11.Cu")
	)
	(gr_line
		(start 344.500708 -111.58728)
		(end 344.541856 -111.614966)
		(stroke
			(width 0.05715)
			(type default)
		)
		(layer "In11.Cu")
	)
	(gr_line
		(start 344.635836 -110.42015)
		(end 344.676984 -110.447836)
		(stroke
			(width 0.05715)
			(type default)
		)
		(layer "In11.Cu")
	)
	(gr_line
		(start 344.70975 -127.273558)
		(end 344.720926 -127.290068)
		(stroke
			(width 0.05715)
			(type default)
		)
		(layer "In11.Cu")
	)
	(gr_line
		(start 344.714068 -84.549996)
		(end 344.734134 -84.553806)
		(stroke
			(width 0.05715)
			(type default)
		)
		(layer "In11.Cu")
	)
	(gr_line
		(start 344.720926 -127.290068)
		(end 344.737436 -127.301244)
		(stroke
			(width 0.05715)
			(type default)
		)
		(layer "In11.Cu")
	)
	(gr_line
		(start 344.734134 -84.553806)
		(end 344.751406 -84.565236)
		(stroke
			(width 0.05715)
			(type default)
		)
		(layer "In11.Cu")
	)
	(gr_line
		(start 345.08186 -88.320626)
		(end 345.10091 -88.324436)
		(stroke
			(width 0.05715)
			(type default)
		)
		(layer "In11.Cu")
	)
	(gr_line
		(start 345.093544 -128.359916)
		(end 345.111324 -128.371854)
		(stroke
			(width 0.05715)
			(type default)
		)
		(layer "In11.Cu")
	)
	(gr_line
		(start 345.10091 -88.324436)
		(end 345.11996 -88.320626)
		(stroke
			(width 0.05715)
			(type default)
		)
		(layer "In11.Cu")
	)
	(gr_line
		(start 345.1098 -85.155024)
		(end 345.12631 -85.165946)
		(stroke
			(width 0.05715)
			(type default)
		)
		(layer "In11.Cu")
	)
	(gr_line
		(start 345.111324 -128.371854)
		(end 345.133168 -128.376172)
		(stroke
			(width 0.05715)
			(type default)
		)
		(layer "In11.Cu")
	)
	(gr_line
		(start 345.12631 -85.165946)
		(end 345.146376 -85.17001)
		(stroke
			(width 0.05715)
			(type default)
		)
		(layer "In11.Cu")
	)
	(gr_line
		(start 345.268042 -106.977942)
		(end 345.33078 -106.954574)
		(stroke
			(width 0.05715)
			(type default)
		)
		(layer "In11.Cu")
	)
	(gr_line
		(start 345.33078 -106.954574)
		(end 345.394534 -106.976418)
		(stroke
			(width 0.05715)
			(type default)
		)
		(layer "In11.Cu")
	)
	(gr_line
		(start 345.378278 -74.043794)
		(end 345.397328 -74.047604)
		(stroke
			(width 0.05715)
			(type default)
		)
		(layer "In11.Cu")
	)
	(gr_line
		(start 345.397328 -74.047604)
		(end 345.416378 -74.043794)
		(stroke
			(width 0.05715)
			(type default)
		)
		(layer "In11.Cu")
	)
	(gr_line
		(start 345.404186 -127.750824)
		(end 345.422728 -127.76327)
		(stroke
			(width 0.05715)
			(type default)
		)
		(layer "In11.Cu")
	)
	(gr_line
		(start 345.422728 -127.76327)
		(end 345.444572 -127.767334)
		(stroke
			(width 0.05715)
			(type default)
		)
		(layer "In11.Cu")
	)
	(gr_line
		(start 345.436698 -75.573382)
		(end 345.455748 -75.577192)
		(stroke
			(width 0.05715)
			(type default)
		)
		(layer "In11.Cu")
	)
	(gr_line
		(start 345.437206 -126.945644)
		(end 345.447366 -126.960884)
		(stroke
			(width 0.05715)
			(type default)
		)
		(layer "In11.Cu")
	)
	(gr_line
		(start 345.437968 -74.796396)
		(end 345.457018 -74.800206)
		(stroke
			(width 0.05715)
			(type default)
		)
		(layer "In11.Cu")
	)
	(gr_line
		(start 345.447366 -126.960884)
		(end 345.462606 -126.971298)
		(stroke
			(width 0.05715)
			(type default)
		)
		(layer "In11.Cu")
	)
	(gr_line
		(start 345.455748 -75.577192)
		(end 345.474798 -75.573382)
		(stroke
			(width 0.05715)
			(type default)
		)
		(layer "In11.Cu")
	)
	(gr_line
		(start 345.457018 -74.800206)
		(end 345.476068 -74.796396)
		(stroke
			(width 0.05715)
			(type default)
		)
		(layer "In11.Cu")
	)
	(gr_line
		(start 345.64066 -87.071962)
		(end 345.670886 -87.08136)
		(stroke
			(width 0.05715)
			(type default)
		)
		(layer "In11.Cu")
	)
	(gr_line
		(start 345.670886 -87.08136)
		(end 345.70162 -87.07628)
		(stroke
			(width 0.05715)
			(type default)
		)
		(layer "In11.Cu")
	)
	(gr_line
		(start 345.684602 -82.265266)
		(end 345.703652 -82.261456)
		(stroke
			(width 0.05715)
			(type default)
		)
		(layer "In11.Cu")
	)
	(gr_line
		(start 345.703652 -82.261456)
		(end 345.722702 -82.265266)
		(stroke
			(width 0.05715)
			(type default)
		)
		(layer "In11.Cu")
	)
	(gr_line
		(start 345.749626 -127.165354)
		(end 345.767152 -127.177038)
		(stroke
			(width 0.05715)
			(type default)
		)
		(layer "In11.Cu")
	)
	(gr_line
		(start 345.767152 -127.177038)
		(end 345.787726 -127.181102)
		(stroke
			(width 0.05715)
			(type default)
		)
		(layer "In11.Cu")
	)
	(gr_line
		(start 345.915742 -83.19262)
		(end 345.934792 -83.18881)
		(stroke
			(width 0.05715)
			(type default)
		)
		(layer "In11.Cu")
	)
	(gr_line
		(start 345.934792 -83.18881)
		(end 345.953842 -83.19262)
		(stroke
			(width 0.05715)
			(type default)
		)
		(layer "In11.Cu")
	)
	(gr_line
		(start 346.09405 -130.420872)
		(end 346.112846 -130.424428)
		(stroke
			(width 0.05715)
			(type default)
		)
		(layer "In11.Cu")
	)
	(gr_line
		(start 346.112846 -130.424428)
		(end 346.131642 -130.420872)
		(stroke
			(width 0.05715)
			(type default)
		)
		(layer "In11.Cu")
	)
	(gr_line
		(start 346.280232 -113.128298)
		(end 346.323412 -113.157)
		(stroke
			(width 0.05715)
			(type default)
		)
		(layer "In11.Cu")
	)
	(gr_line
		(start 346.290646 -111.877856)
		(end 346.33408 -111.906812)
		(stroke
			(width 0.05715)
			(type default)
		)
		(layer "In11.Cu")
	)
	(gr_line
		(start 346.881958 -87.670386)
		(end 346.901008 -87.666576)
		(stroke
			(width 0.05715)
			(type default)
		)
		(layer "In11.Cu")
	)
	(gr_line
		(start 346.901008 -87.666576)
		(end 346.920566 -87.67064)
		(stroke
			(width 0.05715)
			(type default)
		)
		(layer "In11.Cu")
	)
	(gr_line
		(start 346.953332 -109.058964)
		(end 346.954856 -109.059472)
		(stroke
			(width 0.05715)
			(type default)
		)
		(layer "In11.Cu")
	)
	(gr_line
		(start 347.029786 -85.545422)
		(end 347.049344 -85.549486)
		(stroke
			(width 0.05715)
			(type default)
		)
		(layer "In11.Cu")
	)
	(gr_line
		(start 347.049344 -85.549486)
		(end 347.068394 -85.545676)
		(stroke
			(width 0.05715)
			(type default)
		)
		(layer "In11.Cu")
	)
	(gr_line
		(start 347.077284 -83.715098)
		(end 347.096334 -83.718908)
		(stroke
			(width 0.05715)
			(type default)
		)
		(layer "In11.Cu")
	)
	(gr_line
		(start 347.080586 -127.43434)
		(end 347.121226 -127.442214)
		(stroke
			(width 0.05715)
			(type default)
		)
		(layer "In11.Cu")
	)
	(gr_line
		(start 347.096334 -83.718908)
		(end 347.115384 -83.715098)
		(stroke
			(width 0.05715)
			(type default)
		)
		(layer "In11.Cu")
	)
	(gr_line
		(start 347.121226 -127.442214)
		(end 347.160342 -127.428498)
		(stroke
			(width 0.05715)
			(type default)
		)
		(layer "In11.Cu")
	)
	(gr_line
		(start 347.133164 -128.09728)
		(end 347.174058 -128.105154)
		(stroke
			(width 0.05715)
			(type default)
		)
		(layer "In11.Cu")
	)
	(gr_line
		(start 347.152468 -128.768348)
		(end 347.190822 -128.775714)
		(stroke
			(width 0.05715)
			(type default)
		)
		(layer "In11.Cu")
	)
	(gr_line
		(start 347.174058 -128.105154)
		(end 347.213428 -128.091438)
		(stroke
			(width 0.05715)
			(type default)
		)
		(layer "In11.Cu")
	)
	(gr_line
		(start 347.190822 -128.775714)
		(end 347.22689 -128.763522)
		(stroke
			(width 0.05715)
			(type default)
		)
		(layer "In11.Cu")
	)
	(gr_line
		(start 347.258386 -82.870548)
		(end 347.277436 -82.874358)
		(stroke
			(width 0.05715)
			(type default)
		)
		(layer "In11.Cu")
	)
	(gr_line
		(start 347.277436 -82.874358)
		(end 347.296486 -82.870548)
		(stroke
			(width 0.05715)
			(type default)
		)
		(layer "In11.Cu")
	)
	(gr_line
		(start 347.775784 -86.451948)
		(end 347.787722 -86.45017)
		(stroke
			(width 0.05715)
			(type default)
		)
		(layer "In11.Cu")
	)
	(gr_line
		(start 347.787722 -86.45017)
		(end 347.798898 -86.452202)
		(stroke
			(width 0.05715)
			(type default)
		)
		(layer "In11.Cu")
	)
	(gr_line
		(start 347.911166 -88.165686)
		(end 347.930216 -88.169496)
		(stroke
			(width 0.05715)
			(type default)
		)
		(layer "In11.Cu")
	)
	(gr_line
		(start 347.930216 -88.169496)
		(end 347.949774 -88.165432)
		(stroke
			(width 0.05715)
			(type default)
		)
		(layer "In11.Cu")
	)
	(gr_line
		(start 347.962474 -85.069172)
		(end 348.01302 -85.059012)
		(stroke
			(width 0.05715)
			(type default)
		)
		(layer "In11.Cu")
	)
	(gr_line
		(start 348.01302 -85.059012)
		(end 348.060772 -85.078824)
		(stroke
			(width 0.05715)
			(type default)
		)
		(layer "In11.Cu")
	)
	(gr_line
		(start 348.06001 -83.22818)
		(end 348.07906 -83.22437)
		(stroke
			(width 0.05715)
			(type default)
		)
		(layer "In11.Cu")
	)
	(gr_line
		(start 348.060264 -130.046222)
		(end 348.143576 -130.029966)
		(stroke
			(width 0.05715)
			(type default)
		)
		(layer "In11.Cu")
	)
	(gr_line
		(start 348.07906 -83.22437)
		(end 348.09811 -83.22818)
		(stroke
			(width 0.05715)
			(type default)
		)
		(layer "In11.Cu")
	)
	(gr_line
		(start 348.079314 -82.415888)
		(end 348.098364 -82.412078)
		(stroke
			(width 0.05715)
			(type default)
		)
		(layer "In11.Cu")
	)
	(gr_line
		(start 348.098364 -82.412078)
		(end 348.117414 -82.415888)
		(stroke
			(width 0.05715)
			(type default)
		)
		(layer "In11.Cu")
	)
	(gr_line
		(start 348.143576 -130.029966)
		(end 348.191328 -129.959354)
		(stroke
			(width 0.05715)
			(type default)
		)
		(layer "In11.Cu")
	)
	(gr_line
		(start 348.24797 -88.105996)
		(end 348.267528 -88.101932)
		(stroke
			(width 0.05715)
			(type default)
		)
		(layer "In11.Cu")
	)
	(gr_line
		(start 348.267528 -88.101932)
		(end 348.284292 -88.09101)
		(stroke
			(width 0.05715)
			(type default)
		)
		(layer "In11.Cu")
	)
	(gr_line
		(start 348.27845 -74.714608)
		(end 348.2975 -74.710798)
		(stroke
			(width 0.05715)
			(type default)
		)
		(layer "In11.Cu")
	)
	(gr_line
		(start 348.2975 -74.710798)
		(end 348.31655 -74.714608)
		(stroke
			(width 0.05715)
			(type default)
		)
		(layer "In11.Cu")
	)
	(gr_line
		(start 348.321122 -86.84514)
		(end 348.337378 -86.848188)
		(stroke
			(width 0.05715)
			(type default)
		)
		(layer "In11.Cu")
	)
	(gr_line
		(start 348.326456 -127.391668)
		(end 348.365064 -127.378206)
		(stroke
			(width 0.05715)
			(type default)
		)
		(layer "In11.Cu")
	)
	(gr_line
		(start 348.337378 -86.848188)
		(end 348.353888 -86.844886)
		(stroke
			(width 0.05715)
			(type default)
		)
		(layer "In11.Cu")
	)
	(gr_line
		(start 348.34449 -128.080262)
		(end 348.382336 -128.067562)
		(stroke
			(width 0.05715)
			(type default)
		)
		(layer "In11.Cu")
	)
	(gr_line
		(start 348.365064 -127.378206)
		(end 348.405196 -127.385826)
		(stroke
			(width 0.05715)
			(type default)
		)
		(layer "In11.Cu")
	)
	(gr_line
		(start 348.370144 -126.69393)
		(end 348.407736 -126.680722)
		(stroke
			(width 0.05715)
			(type default)
		)
		(layer "In11.Cu")
	)
	(gr_line
		(start 348.382336 -128.067562)
		(end 348.421452 -128.074928)
		(stroke
			(width 0.05715)
			(type default)
		)
		(layer "In11.Cu")
	)
	(gr_line
		(start 348.400624 -129.125726)
		(end 348.448376 -129.055114)
		(stroke
			(width 0.05715)
			(type default)
		)
		(layer "In11.Cu")
	)
	(gr_line
		(start 348.407736 -126.680722)
		(end 348.447868 -126.688342)
		(stroke
			(width 0.05715)
			(type default)
		)
		(layer "In11.Cu")
	)
	(gr_line
		(start 348.441264 -73.140824)
		(end 348.460314 -73.137014)
		(stroke
			(width 0.05715)
			(type default)
		)
		(layer "In11.Cu")
	)
	(gr_line
		(start 348.448376 -129.055114)
		(end 348.531688 -129.038858)
		(stroke
			(width 0.05715)
			(type default)
		)
		(layer "In11.Cu")
	)
	(gr_line
		(start 348.457774 -73.901808)
		(end 348.476824 -73.897998)
		(stroke
			(width 0.05715)
			(type default)
		)
		(layer "In11.Cu")
	)
	(gr_line
		(start 348.460314 -73.137014)
		(end 348.479364 -73.140824)
		(stroke
			(width 0.05715)
			(type default)
		)
		(layer "In11.Cu")
	)
	(gr_line
		(start 348.476824 -73.897998)
		(end 348.495874 -73.901808)
		(stroke
			(width 0.05715)
			(type default)
		)
		(layer "In11.Cu")
	)
	(gr_line
		(start 348.495112 -116.36375)
		(end 348.869762 -116.36375)
		(stroke
			(width 0.05715)
			(type default)
		)
		(layer "In11.Cu")
	)
	(gr_line
		(start 348.794832 -85.700616)
		(end 348.843346 -85.720682)
		(stroke
			(width 0.05715)
			(type default)
		)
		(layer "In11.Cu")
	)
	(gr_line
		(start 348.843346 -85.720682)
		(end 348.894908 -85.710268)
		(stroke
			(width 0.05715)
			(type default)
		)
		(layer "In11.Cu")
	)
	(gr_line
		(start 348.869762 -116.36375)
		(end 348.914466 -116.408454)
		(stroke
			(width 0.05715)
			(type default)
		)
		(layer "In11.Cu")
	)
	(gr_line
		(start 348.991682 -86.717378)
		(end 349.010478 -86.713822)
		(stroke
			(width 0.05715)
			(type default)
		)
		(layer "In11.Cu")
	)
	(gr_line
		(start 349.010478 -86.713822)
		(end 349.026988 -86.7029)
		(stroke
			(width 0.05715)
			(type default)
		)
		(layer "In11.Cu")
	)
	(gr_line
		(start 349.06839 -122.197622)
		(end 349.087186 -122.201178)
		(stroke
			(width 0.05715)
			(type default)
		)
		(layer "In11.Cu")
	)
	(gr_line
		(start 349.087186 -122.201178)
		(end 349.105982 -122.197622)
		(stroke
			(width 0.05715)
			(type default)
		)
		(layer "In11.Cu")
	)
	(gr_line
		(start 349.15729 -128.917192)
		(end 349.176086 -128.913636)
		(stroke
			(width 0.05715)
			(type default)
		)
		(layer "In11.Cu")
	)
	(gr_line
		(start 349.176086 -128.913636)
		(end 349.194882 -128.917192)
		(stroke
			(width 0.05715)
			(type default)
		)
		(layer "In11.Cu")
	)
	(gr_line
		(start 349.345758 -116.408454)
		(end 349.390462 -116.36375)
		(stroke
			(width 0.05715)
			(type default)
		)
		(layer "In11.Cu")
	)
	(gr_line
		(start 349.390462 -116.36375)
		(end 349.765112 -116.36375)
		(stroke
			(width 0.05715)
			(type default)
		)
		(layer "In11.Cu")
	)
	(gr_line
		(start 349.691452 -85.912198)
		(end 349.707962 -85.901276)
		(stroke
			(width 0.05715)
			(type default)
		)
		(layer "In11.Cu")
	)
	(gr_line
		(start 349.707962 -85.901276)
		(end 349.72752 -85.897212)
		(stroke
			(width 0.05715)
			(type default)
		)
		(layer "In11.Cu")
	)
	(gr_line
		(start 350.223328 -86.457028)
		(end 350.23933 -86.446614)
		(stroke
			(width 0.05715)
			(type default)
		)
		(layer "In11.Cu")
	)
	(gr_line
		(start 350.23933 -86.446614)
		(end 350.258126 -86.442804)
		(stroke
			(width 0.05715)
			(type default)
		)
		(layer "In11.Cu")
	)
	(gr_line
		(start 350.84766 -83.25993)
		(end 350.86671 -83.26374)
		(stroke
			(width 0.05715)
			(type default)
		)
		(layer "In11.Cu")
	)
	(gr_line
		(start 350.86671 -83.26374)
		(end 350.88576 -83.25993)
		(stroke
			(width 0.05715)
			(type default)
		)
		(layer "In11.Cu")
	)
	(gr_line
		(start 350.920304 -84.091018)
		(end 350.939354 -84.094828)
		(stroke
			(width 0.05715)
			(type default)
		)
		(layer "In11.Cu")
	)
	(gr_line
		(start 350.939354 -84.094828)
		(end 350.958404 -84.091018)
		(stroke
			(width 0.05715)
			(type default)
		)
		(layer "In11.Cu")
	)
	(gr_line
		(start 350.97974 -116.849144)
		(end 351.13214 -116.696744)
		(stroke
			(width 0.05715)
			(type default)
		)
		(layer "In11.Cu")
	)
	(gr_line
		(start 351.052892 -124.774198)
		(end 351.071688 -124.777754)
		(stroke
			(width 0.05715)
			(type default)
		)
		(layer "In11.Cu")
	)
	(gr_line
		(start 351.071688 -124.777754)
		(end 351.090484 -124.774198)
		(stroke
			(width 0.05715)
			(type default)
		)
		(layer "In11.Cu")
	)
	(gr_line
		(start 351.13214 -116.696744)
		(end 351.47504 -116.696744)
		(stroke
			(width 0.05715)
			(type default)
		)
		(layer "In11.Cu")
	)
	(gr_line
		(start 351.27184 -117.153944)
		(end 351.33534 -117.153944)
		(stroke
			(width 0.05715)
			(type default)
		)
		(layer "In11.Cu")
	)
	(gr_line
		(start 351.276666 -83.181444)
		(end 351.295716 -83.177634)
		(stroke
			(width 0.05715)
			(type default)
		)
		(layer "In11.Cu")
	)
	(gr_line
		(start 351.295716 -83.177634)
		(end 351.31248 -83.166712)
		(stroke
			(width 0.05715)
			(type default)
		)
		(layer "In11.Cu")
	)
	(gr_line
		(start 351.412048 -110.631478)
		(end 351.414842 -110.63224)
		(stroke
			(width 0.05715)
			(type default)
		)
		(layer "In11.Cu")
	)
	(gr_line
		(start 351.415096 -109.353858)
		(end 351.425002 -109.35716)
		(stroke
			(width 0.05715)
			(type default)
		)
		(layer "In11.Cu")
	)
	(gr_line
		(start 351.47504 -116.696744)
		(end 351.62744 -116.849144)
		(stroke
			(width 0.05715)
			(type default)
		)
		(layer "In11.Cu")
	)
	(gr_line
		(start 351.550224 -83.9724)
		(end 351.569274 -83.96859)
		(stroke
			(width 0.05715)
			(type default)
		)
		(layer "In11.Cu")
	)
	(gr_line
		(start 351.569274 -83.96859)
		(end 351.58553 -83.957922)
		(stroke
			(width 0.05715)
			(type default)
		)
		(layer "In11.Cu")
	)
	(gr_line
		(start 351.75952 -124.346462)
		(end 351.778316 -124.342906)
		(stroke
			(width 0.05715)
			(type default)
		)
		(layer "In11.Cu")
	)
	(gr_line
		(start 351.778316 -124.342906)
		(end 351.797112 -124.346462)
		(stroke
			(width 0.05715)
			(type default)
		)
		(layer "In11.Cu")
	)
	(gr_line
		(start 351.99574 -116.849144)
		(end 352.14814 -116.696744)
		(stroke
			(width 0.05715)
			(type default)
		)
		(layer "In11.Cu")
	)
	(gr_line
		(start 352.062288 -75.761596)
		(end 352.081338 -75.765406)
		(stroke
			(width 0.05715)
			(type default)
		)
		(layer "In11.Cu")
	)
	(gr_line
		(start 352.081338 -75.765406)
		(end 352.100388 -75.761596)
		(stroke
			(width 0.05715)
			(type default)
		)
		(layer "In11.Cu")
	)
	(gr_line
		(start 352.14814 -116.696744)
		(end 352.49104 -116.696744)
		(stroke
			(width 0.05715)
			(type default)
		)
		(layer "In11.Cu")
	)
	(gr_line
		(start 352.181668 -128.402588)
		(end 352.208846 -128.407668)
		(stroke
			(width 0.05715)
			(type default)
		)
		(layer "In11.Cu")
	)
	(gr_line
		(start 352.206814 -127.701548)
		(end 352.233992 -127.706628)
		(stroke
			(width 0.05715)
			(type default)
		)
		(layer "In11.Cu")
	)
	(gr_line
		(start 352.208846 -128.407668)
		(end 352.235516 -128.401064)
		(stroke
			(width 0.05715)
			(type default)
		)
		(layer "In11.Cu")
	)
	(gr_line
		(start 352.21672 -129.095754)
		(end 352.242882 -129.100834)
		(stroke
			(width 0.05715)
			(type default)
		)
		(layer "In11.Cu")
	)
	(gr_line
		(start 352.233992 -127.706628)
		(end 352.260662 -127.700024)
		(stroke
			(width 0.05715)
			(type default)
		)
		(layer "In11.Cu")
	)
	(gr_line
		(start 352.242882 -129.100834)
		(end 352.26879 -129.09423)
		(stroke
			(width 0.05715)
			(type default)
		)
		(layer "In11.Cu")
	)
	(gr_line
		(start 352.28784 -117.153944)
		(end 352.35134 -117.153944)
		(stroke
			(width 0.05715)
			(type default)
		)
		(layer "In11.Cu")
	)
	(gr_line
		(start 352.288348 -74.95794)
		(end 352.307398 -74.96175)
		(stroke
			(width 0.05715)
			(type default)
		)
		(layer "In11.Cu")
	)
	(gr_line
		(start 352.307398 -74.96175)
		(end 352.326448 -74.95794)
		(stroke
			(width 0.05715)
			(type default)
		)
		(layer "In11.Cu")
	)
	(gr_line
		(start 352.30943 -74.20483)
		(end 352.32848 -74.20864)
		(stroke
			(width 0.05715)
			(type default)
		)
		(layer "In11.Cu")
	)
	(gr_line
		(start 352.366326 -129.831592)
		(end 352.385122 -129.835148)
		(stroke
			(width 0.05715)
			(type default)
		)
		(layer "In11.Cu")
	)
	(gr_line
		(start 352.385122 -129.835148)
		(end 352.403918 -129.831592)
		(stroke
			(width 0.05715)
			(type default)
		)
		(layer "In11.Cu")
	)
	(gr_line
		(start 352.457766 -124.772674)
		(end 352.476562 -124.77623)
		(stroke
			(width 0.05715)
			(type default)
		)
		(layer "In11.Cu")
	)
	(gr_line
		(start 352.459036 -82.05089)
		(end 352.475292 -82.040222)
		(stroke
			(width 0.05715)
			(type default)
		)
		(layer "In11.Cu")
	)
	(gr_line
		(start 352.475292 -82.040222)
		(end 352.494342 -82.036412)
		(stroke
			(width 0.05715)
			(type default)
		)
		(layer "In11.Cu")
	)
	(gr_line
		(start 352.476562 -124.77623)
		(end 352.495358 -124.772674)
		(stroke
			(width 0.05715)
			(type default)
		)
		(layer "In11.Cu")
	)
	(gr_line
		(start 352.49104 -116.696744)
		(end 352.64344 -116.849144)
		(stroke
			(width 0.05715)
			(type default)
		)
		(layer "In11.Cu")
	)
	(gr_line
		(start 352.644456 -82.900266)
		(end 352.661982 -82.888582)
		(stroke
			(width 0.05715)
			(type default)
		)
		(layer "In11.Cu")
	)
	(gr_line
		(start 352.661982 -82.888582)
		(end 352.682302 -82.884518)
		(stroke
			(width 0.05715)
			(type default)
		)
		(layer "In11.Cu")
	)
	(gr_line
		(start 352.737928 -121.775474)
		(end 352.759772 -121.779792)
		(stroke
			(width 0.05715)
			(type default)
		)
		(layer "In11.Cu")
	)
	(gr_line
		(start 352.759772 -121.779792)
		(end 352.777552 -121.79173)
		(stroke
			(width 0.05715)
			(type default)
		)
		(layer "In11.Cu")
	)
	(gr_line
		(start 352.842576 -85.918802)
		(end 352.863404 -85.914484)
		(stroke
			(width 0.05715)
			(type default)
		)
		(layer "In11.Cu")
	)
	(gr_line
		(start 352.863404 -85.914484)
		(end 352.884486 -85.918802)
		(stroke
			(width 0.05715)
			(type default)
		)
		(layer "In11.Cu")
	)
	(gr_line
		(start 353.088956 -85.21319)
		(end 353.109784 -85.208872)
		(stroke
			(width 0.05715)
			(type default)
		)
		(layer "In11.Cu")
	)
	(gr_line
		(start 353.109784 -85.208872)
		(end 353.130866 -85.21319)
		(stroke
			(width 0.05715)
			(type default)
		)
		(layer "In11.Cu")
	)
	(gr_line
		(start 353.228656 -84.530438)
		(end 353.250246 -84.52612)
		(stroke
			(width 0.05715)
			(type default)
		)
		(layer "In11.Cu")
	)
	(gr_line
		(start 353.250246 -84.52612)
		(end 353.271836 -84.530438)
		(stroke
			(width 0.05715)
			(type default)
		)
		(layer "In11.Cu")
	)
	(gr_line
		(start 353.357688 -124.307092)
		(end 353.376484 -124.303536)
		(stroke
			(width 0.05715)
			(type default)
		)
		(layer "In11.Cu")
	)
	(gr_line
		(start 353.376484 -124.303536)
		(end 353.39528 -124.307092)
		(stroke
			(width 0.05715)
			(type default)
		)
		(layer "In11.Cu")
	)
	(gr_line
		(start 353.459542 -115.7224)
		(end 353.520756 -115.7224)
		(stroke
			(width 0.05715)
			(type default)
		)
		(layer "In11.Cu")
	)
	(gr_line
		(start 353.52863 -88.96858)
		(end 353.52863 -89.014554)
		(stroke
			(width 0.0635)
			(type default)
		)
		(layer "In11.Cu")
	)
	(gr_line
		(start 353.52863 -88.47455)
		(end 353.52863 -88.96604)
		(stroke
			(width 0.0635)
			(type default)
		)
		(layer "In11.Cu")
	)
	(gr_line
		(start 353.595686 -81.81594)
		(end 353.614736 -81.81213)
		(stroke
			(width 0.05715)
			(type default)
		)
		(layer "In11.Cu")
	)
	(gr_line
		(start 353.614736 -81.81213)
		(end 353.633786 -81.81594)
		(stroke
			(width 0.05715)
			(type default)
		)
		(layer "In11.Cu")
	)
	(gr_line
		(start 353.637088 -86.073742)
		(end 353.65563 -86.077552)
		(stroke
			(width 0.05715)
			(type default)
		)
		(layer "In11.Cu")
	)
	(gr_line
		(start 353.65563 -86.077552)
		(end 353.671378 -86.087966)
		(stroke
			(width 0.05715)
			(type default)
		)
		(layer "In11.Cu")
	)
	(gr_line
		(start 353.666552 -107.192826)
		(end 353.68357 -107.196128)
		(stroke
			(width 0.05715)
			(type default)
		)
		(layer "In11.Cu")
	)
	(gr_line
		(start 353.669346 -89.19718)
		(end 353.75723 -89.19718)
		(stroke
			(width 0.0635)
			(type default)
		)
		(layer "In11.Cu")
	)
	(gr_line
		(start 353.68357 -107.196128)
		(end 353.700588 -107.192826)
		(stroke
			(width 0.05715)
			(type default)
		)
		(layer "In11.Cu")
	)
	(gr_line
		(start 353.747832 -82.672428)
		(end 353.766882 -82.668618)
		(stroke
			(width 0.05715)
			(type default)
		)
		(layer "In11.Cu")
	)
	(gr_line
		(start 353.749102 -115.537488)
		(end 353.810316 -115.537488)
		(stroke
			(width 0.05715)
			(type default)
		)
		(layer "In11.Cu")
	)
	(gr_line
		(start 353.75977 -89.19718)
		(end 354.14204 -89.19718)
		(stroke
			(width 0.0635)
			(type default)
		)
		(layer "In11.Cu")
	)
	(gr_line
		(start 353.766882 -82.668618)
		(end 353.78644 -82.672682)
		(stroke
			(width 0.05715)
			(type default)
		)
		(layer "In11.Cu")
	)
	(gr_line
		(start 353.840034 -129.254504)
		(end 353.921314 -129.238756)
		(stroke
			(width 0.05715)
			(type default)
		)
		(layer "In11.Cu")
	)
	(gr_line
		(start 353.840542 -85.358478)
		(end 353.857814 -85.362034)
		(stroke
			(width 0.05715)
			(type default)
		)
		(layer "In11.Cu")
	)
	(gr_line
		(start 353.857814 -85.362034)
		(end 353.873054 -85.37194)
		(stroke
			(width 0.05715)
			(type default)
		)
		(layer "In11.Cu")
	)
	(gr_line
		(start 353.920552 -93.928692)
		(end 353.930712 -93.979492)
		(stroke
			(width 0.05715)
			(type default)
		)
		(layer "In11.Cu")
	)
	(gr_line
		(start 353.920552 -93.928692)
		(end 353.94011 -93.881956)
		(stroke
			(width 0.05715)
			(type default)
		)
		(layer "In11.Cu")
	)
	(gr_line
		(start 353.921314 -129.238756)
		(end 353.989894 -129.284984)
		(stroke
			(width 0.05715)
			(type default)
		)
		(layer "In11.Cu")
	)
	(gr_line
		(start 353.997768 -84.67598)
		(end 354.016564 -84.679536)
		(stroke
			(width 0.05715)
			(type default)
		)
		(layer "In11.Cu")
	)
	(gr_line
		(start 354.016564 -84.679536)
		(end 354.033328 -84.690458)
		(stroke
			(width 0.05715)
			(type default)
		)
		(layer "In11.Cu")
	)
	(gr_line
		(start 354.181156 -124.46)
		(end 354.203 -124.464318)
		(stroke
			(width 0.05715)
			(type default)
		)
		(layer "In11.Cu")
	)
	(gr_line
		(start 354.19538 -73.537318)
		(end 354.21443 -73.533508)
		(stroke
			(width 0.05715)
			(type default)
		)
		(layer "In11.Cu")
	)
	(gr_line
		(start 354.203 -124.464318)
		(end 354.22078 -124.476256)
		(stroke
			(width 0.05715)
			(type default)
		)
		(layer "In11.Cu")
	)
	(gr_line
		(start 354.21443 -73.533508)
		(end 354.23348 -73.537318)
		(stroke
			(width 0.05715)
			(type default)
		)
		(layer "In11.Cu")
	)
	(gr_line
		(start 354.243894 -74.276458)
		(end 354.262944 -74.272648)
		(stroke
			(width 0.05715)
			(type default)
		)
		(layer "In11.Cu")
	)
	(gr_line
		(start 354.262944 -74.272648)
		(end 354.281994 -74.276458)
		(stroke
			(width 0.05715)
			(type default)
		)
		(layer "In11.Cu")
	)
	(gr_line
		(start 354.353114 -115.91163)
		(end 354.42525 -115.983766)
		(stroke
			(width 0.05715)
			(type default)
		)
		(layer "In11.Cu")
	)
	(gr_line
		(start 354.353114 -115.49507)
		(end 354.42525 -115.422934)
		(stroke
			(width 0.05715)
			(type default)
		)
		(layer "In11.Cu")
	)
	(gr_line
		(start 354.398834 -75.003914)
		(end 354.417884 -75.000104)
		(stroke
			(width 0.05715)
			(type default)
		)
		(layer "In11.Cu")
	)
	(gr_line
		(start 354.417884 -75.000104)
		(end 354.436934 -75.003914)
		(stroke
			(width 0.05715)
			(type default)
		)
		(layer "In11.Cu")
	)
	(gr_line
		(start 354.42525 -115.983766)
		(end 354.42525 -116.220494)
		(stroke
			(width 0.05715)
			(type default)
		)
		(layer "In11.Cu")
	)
	(gr_line
		(start 354.42525 -115.204494)
		(end 354.42525 -115.422934)
		(stroke
			(width 0.05715)
			(type default)
		)
		(layer "In11.Cu")
	)
	(gr_line
		(start 354.469954 -98.48596)
		(end 354.474018 -98.505772)
		(stroke
			(width 0.05715)
			(type default)
		)
		(layer "In11.Cu")
	)
	(gr_line
		(start 354.588064 -114.1603)
		(end 354.606606 -114.16792)
		(stroke
			(width 0.05715)
			(type default)
		)
		(layer "In11.Cu")
	)
	(gr_line
		(start 354.76434 -93.742256)
		(end 354.771452 -93.78696)
		(stroke
			(width 0.05715)
			(type default)
		)
		(layer "In11.Cu")
	)
	(gr_line
		(start 354.76434 -93.742256)
		(end 354.781358 -93.700854)
		(stroke
			(width 0.05715)
			(type default)
		)
		(layer "In11.Cu")
	)
	(gr_line
		(start 354.771198 -93.786452)
		(end 354.771452 -93.787468)
		(stroke
			(width 0.05715)
			(type default)
		)
		(layer "In11.Cu")
	)
	(gr_line
		(start 354.782374 -82.871818)
		(end 354.801424 -82.875628)
		(stroke
			(width 0.05715)
			(type default)
		)
		(layer "In11.Cu")
	)
	(gr_line
		(start 354.801424 -82.875628)
		(end 354.81768 -82.886296)
		(stroke
			(width 0.05715)
			(type default)
		)
		(layer "In11.Cu")
	)
	(gr_line
		(start 354.80879 -86.840822)
		(end 354.854256 -86.871048)
		(stroke
			(width 0.05715)
			(type default)
		)
		(layer "In11.Cu")
	)
	(gr_line
		(start 354.854256 -86.871048)
		(end 354.874576 -86.921086)
		(stroke
			(width 0.05715)
			(type default)
		)
		(layer "In11.Cu")
	)
	(gr_line
		(start 354.94468 -97.601532)
		(end 354.948744 -97.58172)
		(stroke
			(width 0.05715)
			(type default)
		)
		(layer "In11.Cu")
	)
	(gr_line
		(start 354.944934 -97.56267)
		(end 354.948744 -97.58172)
		(stroke
			(width 0.05715)
			(type default)
		)
		(layer "In11.Cu")
	)
	(gr_line
		(start 355.099112 -101.63048)
		(end 355.114352 -101.706172)
		(stroke
			(width 0.05715)
			(type default)
		)
		(layer "In11.Cu")
	)
	(gr_line
		(start 355.114352 -101.706172)
		(end 355.176074 -101.750368)
		(stroke
			(width 0.05715)
			(type default)
		)
		(layer "In11.Cu")
	)
	(gr_line
		(start 355.171248 -98.248216)
		(end 355.175058 -98.229166)
		(stroke
			(width 0.05715)
			(type default)
		)
		(layer "In11.Cu")
	)
	(gr_line
		(start 355.171248 -98.248216)
		(end 355.175312 -98.268282)
		(stroke
			(width 0.05715)
			(type default)
		)
		(layer "In11.Cu")
	)
	(gr_line
		(start 355.206808 -106.921808)
		(end 355.275896 -106.909362)
		(stroke
			(width 0.05715)
			(type default)
		)
		(layer "In11.Cu")
	)
	(gr_line
		(start 355.218746 -116.849144)
		(end 355.371146 -116.696744)
		(stroke
			(width 0.05715)
			(type default)
		)
		(layer "In11.Cu")
	)
	(gr_line
		(start 355.275896 -106.909362)
		(end 355.3206 -106.854244)
		(stroke
			(width 0.05715)
			(type default)
		)
		(layer "In11.Cu")
	)
	(gr_line
		(start 355.294184 -86.312756)
		(end 355.336602 -86.34095)
		(stroke
			(width 0.05715)
			(type default)
		)
		(layer "In11.Cu")
	)
	(gr_line
		(start 355.336602 -86.34095)
		(end 355.35616 -86.38794)
		(stroke
			(width 0.05715)
			(type default)
		)
		(layer "In11.Cu")
	)
	(gr_line
		(start 355.371146 -116.696744)
		(end 355.714046 -116.696744)
		(stroke
			(width 0.05715)
			(type default)
		)
		(layer "In11.Cu")
	)
	(gr_line
		(start 355.395276 -108.381546)
		(end 355.415342 -108.373164)
		(stroke
			(width 0.05715)
			(type default)
		)
		(layer "In11.Cu")
	)
	(gr_line
		(start 355.485446 -113.871502)
		(end 355.50094 -113.886996)
		(stroke
			(width 0.05715)
			(type default)
		)
		(layer "In11.Cu")
	)
	(gr_line
		(start 355.50094 -113.886996)
		(end 355.521006 -113.895378)
		(stroke
			(width 0.05715)
			(type default)
		)
		(layer "In11.Cu")
	)
	(gr_line
		(start 355.505004 -93.632528)
		(end 355.512116 -93.677232)
		(stroke
			(width 0.05715)
			(type default)
		)
		(layer "In11.Cu")
	)
	(gr_line
		(start 355.505004 -93.632528)
		(end 355.522022 -93.591888)
		(stroke
			(width 0.05715)
			(type default)
		)
		(layer "In11.Cu")
	)
	(gr_line
		(start 355.510846 -117.153944)
		(end 355.574346 -117.153944)
		(stroke
			(width 0.05715)
			(type default)
		)
		(layer "In11.Cu")
	)
	(gr_line
		(start 355.511862 -93.676724)
		(end 355.512116 -93.67774)
		(stroke
			(width 0.05715)
			(type default)
		)
		(layer "In11.Cu")
	)
	(gr_line
		(start 355.521514 -114.547396)
		(end 355.54031 -114.55527)
		(stroke
			(width 0.05715)
			(type default)
		)
		(layer "In11.Cu")
	)
	(gr_line
		(start 355.559614 -107.938824)
		(end 355.578156 -107.931204)
		(stroke
			(width 0.05715)
			(type default)
		)
		(layer "In11.Cu")
	)
	(gr_line
		(start 355.618288 -130.73634)
		(end 355.63683 -130.748786)
		(stroke
			(width 0.05715)
			(type default)
		)
		(layer "In11.Cu")
	)
	(gr_line
		(start 355.634544 -97.420176)
		(end 355.637338 -97.406714)
		(stroke
			(width 0.05715)
			(type default)
		)
		(layer "In11.Cu")
	)
	(gr_line
		(start 355.635306 -97.393252)
		(end 355.637338 -97.406714)
		(stroke
			(width 0.05715)
			(type default)
		)
		(layer "In11.Cu")
	)
	(gr_line
		(start 355.63683 -130.748786)
		(end 355.658928 -130.753104)
		(stroke
			(width 0.05715)
			(type default)
		)
		(layer "In11.Cu")
	)
	(gr_line
		(start 355.650292 -82.219292)
		(end 355.666294 -82.22996)
		(stroke
			(width 0.05715)
			(type default)
		)
		(layer "In11.Cu")
	)
	(gr_line
		(start 355.714046 -116.696744)
		(end 355.866446 -116.849144)
		(stroke
			(width 0.05715)
			(type default)
		)
		(layer "In11.Cu")
	)
	(gr_line
		(start 355.749606 -106.325162)
		(end 355.790754 -106.274362)
		(stroke
			(width 0.05715)
			(type default)
		)
		(layer "In11.Cu")
	)
	(gr_line
		(start 355.760528 -108.23067)
		(end 355.778308 -108.223304)
		(stroke
			(width 0.05715)
			(type default)
		)
		(layer "In11.Cu")
	)
	(gr_line
		(start 355.767386 -89.126568)
		(end 355.786182 -89.17305)
		(stroke
			(width 0.05715)
			(type default)
		)
		(layer "In11.Cu")
	)
	(gr_line
		(start 355.776276 -101.274118)
		(end 355.791008 -101.348794)
		(stroke
			(width 0.05715)
			(type default)
		)
		(layer "In11.Cu")
	)
	(gr_line
		(start 355.776276 -89.222072)
		(end 355.786182 -89.17305)
		(stroke
			(width 0.05715)
			(type default)
		)
		(layer "In11.Cu")
	)
	(gr_line
		(start 355.791008 -101.348794)
		(end 355.85273 -101.39299)
		(stroke
			(width 0.05715)
			(type default)
		)
		(layer "In11.Cu")
	)
	(gr_line
		(start 355.816662 -85.870542)
		(end 355.85908 -85.898736)
		(stroke
			(width 0.05715)
			(type default)
		)
		(layer "In11.Cu")
	)
	(gr_line
		(start 355.845618 -98.204274)
		(end 355.849428 -98.185224)
		(stroke
			(width 0.05715)
			(type default)
		)
		(layer "In11.Cu")
	)
	(gr_line
		(start 355.845618 -98.204274)
		(end 355.849682 -98.224086)
		(stroke
			(width 0.05715)
			(type default)
		)
		(layer "In11.Cu")
	)
	(gr_line
		(start 355.85908 -85.898736)
		(end 355.878638 -85.945726)
		(stroke
			(width 0.05715)
			(type default)
		)
		(layer "In11.Cu")
	)
	(gr_line
		(start 355.903022 -110.00613)
		(end 355.955092 -110.0582)
		(stroke
			(width 0.05715)
			(type default)
		)
		(layer "In11.Cu")
	)
	(gr_line
		(start 355.903022 -109.58957)
		(end 355.955092 -109.5375)
		(stroke
			(width 0.05715)
			(type default)
		)
		(layer "In11.Cu")
	)
	(gr_line
		(start 355.917754 -127.852424)
		(end 355.978714 -127.836676)
		(stroke
			(width 0.05715)
			(type default)
		)
		(layer "In11.Cu")
	)
	(gr_line
		(start 355.955092 -110.0582)
		(end 355.955092 -110.43285)
		(stroke
			(width 0.05715)
			(type default)
		)
		(layer "In11.Cu")
	)
	(gr_line
		(start 355.955092 -109.16285)
		(end 355.955092 -109.5375)
		(stroke
			(width 0.05715)
			(type default)
		)
		(layer "In11.Cu")
	)
	(gr_line
		(start 355.978714 -127.836676)
		(end 356.03688 -127.862584)
		(stroke
			(width 0.05715)
			(type default)
		)
		(layer "In11.Cu")
	)
	(gr_line
		(start 355.994716 -107.758484)
		(end 356.014274 -107.750356)
		(stroke
			(width 0.05715)
			(type default)
		)
		(layer "In11.Cu")
	)
	(gr_line
		(start 356.044754 -127.14859)
		(end 356.107238 -127.133096)
		(stroke
			(width 0.05715)
			(type default)
		)
		(layer "In11.Cu")
	)
	(gr_line
		(start 356.107238 -127.133096)
		(end 356.165912 -127.159258)
		(stroke
			(width 0.05715)
			(type default)
		)
		(layer "In11.Cu")
	)
	(gr_line
		(start 356.112572 -126.436882)
		(end 356.175056 -126.421388)
		(stroke
			(width 0.05715)
			(type default)
		)
		(layer "In11.Cu")
	)
	(gr_line
		(start 356.175056 -126.421388)
		(end 356.23373 -126.44755)
		(stroke
			(width 0.05715)
			(type default)
		)
		(layer "In11.Cu")
	)
	(gr_line
		(start 356.183692 -124.088398)
		(end 356.200202 -124.099574)
		(stroke
			(width 0.05715)
			(type default)
		)
		(layer "In11.Cu")
	)
	(gr_line
		(start 356.200202 -124.099574)
		(end 356.211378 -124.116084)
		(stroke
			(width 0.05715)
			(type default)
		)
		(layer "In11.Cu")
	)
	(gr_line
		(start 356.223824 -115.96243)
		(end 356.30485 -116.043456)
		(stroke
			(width 0.05715)
			(type default)
		)
		(layer "In11.Cu")
	)
	(gr_line
		(start 356.223824 -115.54587)
		(end 356.30485 -115.464844)
		(stroke
			(width 0.05715)
			(type default)
		)
		(layer "In11.Cu")
	)
	(gr_line
		(start 356.225602 -83.82508)
		(end 356.24389 -83.837272)
		(stroke
			(width 0.05715)
			(type default)
		)
		(layer "In11.Cu")
	)
	(gr_line
		(start 356.24389 -83.837272)
		(end 356.256082 -83.855306)
		(stroke
			(width 0.05715)
			(type default)
		)
		(layer "In11.Cu")
	)
	(gr_line
		(start 356.25659 -93.640656)
		(end 356.263702 -93.68536)
		(stroke
			(width 0.05715)
			(type default)
		)
		(layer "In11.Cu")
	)
	(gr_line
		(start 356.25659 -93.640656)
		(end 356.273608 -93.599254)
		(stroke
			(width 0.05715)
			(type default)
		)
		(layer "In11.Cu")
	)
	(gr_line
		(start 356.263448 -93.685106)
		(end 356.263702 -93.686122)
		(stroke
			(width 0.05715)
			(type default)
		)
		(layer "In11.Cu")
	)
	(gr_line
		(start 356.30485 -116.043456)
		(end 356.30485 -116.220494)
		(stroke
			(width 0.05715)
			(type default)
		)
		(layer "In11.Cu")
	)
	(gr_line
		(start 356.30485 -115.204494)
		(end 356.30485 -115.464844)
		(stroke
			(width 0.05715)
			(type default)
		)
		(layer "In11.Cu")
	)
	(gr_line
		(start 356.35184 -97.164144)
		(end 356.354888 -97.148904)
		(stroke
			(width 0.05715)
			(type default)
		)
		(layer "In11.Cu")
	)
	(gr_line
		(start 356.352602 -97.134172)
		(end 356.354888 -97.148904)
		(stroke
			(width 0.05715)
			(type default)
		)
		(layer "In11.Cu")
	)
	(gr_line
		(start 356.379526 -100.875592)
		(end 356.39502 -100.952046)
		(stroke
			(width 0.05715)
			(type default)
		)
		(layer "In11.Cu")
	)
	(gr_line
		(start 356.39502 -100.952046)
		(end 356.457504 -100.997004)
		(stroke
			(width 0.05715)
			(type default)
		)
		(layer "In11.Cu")
	)
	(gr_line
		(start 356.481126 -89.104978)
		(end 356.500176 -89.15019)
		(stroke
			(width 0.05715)
			(type default)
		)
		(layer "In11.Cu")
	)
	(gr_line
		(start 356.49027 -89.199974)
		(end 356.490524 -89.199212)
		(stroke
			(width 0.05715)
			(type default)
		)
		(layer "In11.Cu")
	)
	(gr_line
		(start 356.490524 -89.198958)
		(end 356.500176 -89.15019)
		(stroke
			(width 0.05715)
			(type default)
		)
		(layer "In11.Cu")
	)
	(gr_line
		(start 356.51821 -98.241358)
		(end 356.522528 -98.26371)
		(stroke
			(width 0.05715)
			(type default)
		)
		(layer "In11.Cu")
	)
	(gr_line
		(start 356.51821 -98.241358)
		(end 356.522528 -98.220276)
		(stroke
			(width 0.05715)
			(type default)
		)
		(layer "In11.Cu")
	)
	(gr_line
		(start 356.522528 -98.263456)
		(end 356.522782 -98.264218)
		(stroke
			(width 0.05715)
			(type default)
		)
		(layer "In11.Cu")
	)
	(gr_line
		(start 356.71887 -125.391926)
		(end 356.741222 -125.424946)
		(stroke
			(width 0.05715)
			(type default)
		)
		(layer "In11.Cu")
	)
	(gr_line
		(start 356.723442 -75.75931)
		(end 356.742492 -75.76312)
		(stroke
			(width 0.05715)
			(type default)
		)
		(layer "In11.Cu")
	)
	(gr_line
		(start 356.741222 -125.424946)
		(end 356.776782 -125.44298)
		(stroke
			(width 0.05715)
			(type default)
		)
		(layer "In11.Cu")
	)
	(gr_line
		(start 356.742492 -75.76312)
		(end 356.761542 -75.75931)
		(stroke
			(width 0.05715)
			(type default)
		)
		(layer "In11.Cu")
	)
	(gr_line
		(start 356.760526 -75.070462)
		(end 356.779576 -75.074272)
		(stroke
			(width 0.05715)
			(type default)
		)
		(layer "In11.Cu")
	)
	(gr_line
		(start 356.779576 -75.074272)
		(end 356.798626 -75.070462)
		(stroke
			(width 0.05715)
			(type default)
		)
		(layer "In11.Cu")
	)
	(gr_line
		(start 356.81412 -84.693506)
		(end 356.824788 -84.709254)
		(stroke
			(width 0.05715)
			(type default)
		)
		(layer "In11.Cu")
	)
	(gr_line
		(start 356.824788 -84.709254)
		(end 356.828598 -84.728304)
		(stroke
			(width 0.05715)
			(type default)
		)
		(layer "In11.Cu")
	)
	(gr_line
		(start 356.921816 -74.373232)
		(end 356.940866 -74.377042)
		(stroke
			(width 0.05715)
			(type default)
		)
		(layer "In11.Cu")
	)
	(gr_line
		(start 356.925372 -104.546654)
		(end 356.977442 -104.598724)
		(stroke
			(width 0.05715)
			(type default)
		)
		(layer "In11.Cu")
	)
	(gr_line
		(start 356.925372 -104.130094)
		(end 356.977442 -104.078024)
		(stroke
			(width 0.05715)
			(type default)
		)
		(layer "In11.Cu")
	)
	(gr_line
		(start 356.940866 -74.377042)
		(end 356.959916 -74.373232)
		(stroke
			(width 0.05715)
			(type default)
		)
		(layer "In11.Cu")
	)
	(gr_line
		(start 356.971346 -100.505768)
		(end 356.986332 -100.580444)
		(stroke
			(width 0.05715)
			(type default)
		)
		(layer "In11.Cu")
	)
	(gr_line
		(start 356.977442 -104.598724)
		(end 356.977442 -104.973374)
		(stroke
			(width 0.05715)
			(type default)
		)
		(layer "In11.Cu")
	)
	(gr_line
		(start 356.977442 -103.703374)
		(end 356.977442 -104.078024)
		(stroke
			(width 0.05715)
			(type default)
		)
		(layer "In11.Cu")
	)
	(gr_line
		(start 356.986332 -100.580444)
		(end 357.048054 -100.625402)
		(stroke
			(width 0.05715)
			(type default)
		)
		(layer "In11.Cu")
	)
	(gr_line
		(start 356.991412 -106.65333)
		(end 357.418132 -107.08005)
		(stroke
			(width 0.05715)
			(type default)
		)
		(layer "In11.Cu")
	)
	(gr_line
		(start 356.991412 -106.23677)
		(end 357.418132 -105.81005)
		(stroke
			(width 0.05715)
			(type default)
		)
		(layer "In11.Cu")
	)
	(gr_line
		(start 357.071168 -96.968056)
		(end 357.074216 -96.952816)
		(stroke
			(width 0.05715)
			(type default)
		)
		(layer "In11.Cu")
	)
	(gr_line
		(start 357.07193 -96.938084)
		(end 357.074216 -96.952816)
		(stroke
			(width 0.05715)
			(type default)
		)
		(layer "In11.Cu")
	)
	(gr_line
		(start 357.09733 -114.231928)
		(end 357.117396 -114.24031)
		(stroke
			(width 0.05715)
			(type default)
		)
		(layer "In11.Cu")
	)
	(gr_line
		(start 357.112316 -93.660722)
		(end 357.122476 -93.711014)
		(stroke
			(width 0.05715)
			(type default)
		)
		(layer "In11.Cu")
	)
	(gr_line
		(start 357.112316 -93.660722)
		(end 357.132128 -93.61297)
		(stroke
			(width 0.05715)
			(type default)
		)
		(layer "In11.Cu")
	)
	(gr_line
		(start 357.15956 -89.038938)
		(end 357.179118 -89.086436)
		(stroke
			(width 0.05715)
			(type default)
		)
		(layer "In11.Cu")
	)
	(gr_line
		(start 357.168958 -89.137236)
		(end 357.179118 -89.086436)
		(stroke
			(width 0.05715)
			(type default)
		)
		(layer "In11.Cu")
	)
	(gr_line
		(start 357.278178 -131.06781)
		(end 357.296974 -131.071366)
		(stroke
			(width 0.05715)
			(type default)
		)
		(layer "In11.Cu")
	)
	(gr_line
		(start 357.296974 -131.071366)
		(end 357.31577 -131.06781)
		(stroke
			(width 0.05715)
			(type default)
		)
		(layer "In11.Cu")
	)
	(gr_line
		(start 357.397812 -98.109532)
		(end 357.401622 -98.128582)
		(stroke
			(width 0.05715)
			(type default)
		)
		(layer "In11.Cu")
	)
	(gr_line
		(start 357.397812 -98.109532)
		(end 357.401876 -98.08972)
		(stroke
			(width 0.05715)
			(type default)
		)
		(layer "In11.Cu")
	)
	(gr_line
		(start 357.715312 -99.695)
		(end 357.724964 -99.744276)
		(stroke
			(width 0.05715)
			(type default)
		)
		(layer "In11.Cu")
	)
	(gr_line
		(start 357.91013 -110.00613)
		(end 357.9622 -110.0582)
		(stroke
			(width 0.05715)
			(type default)
		)
		(layer "In11.Cu")
	)
	(gr_line
		(start 357.91013 -109.58957)
		(end 357.9622 -109.5375)
		(stroke
			(width 0.05715)
			(type default)
		)
		(layer "In11.Cu")
	)
	(gr_line
		(start 357.955088 -88.387682)
		(end 357.974138 -88.434672)
		(stroke
			(width 0.05715)
			(type default)
		)
		(layer "In11.Cu")
	)
	(gr_line
		(start 357.959914 -131.298442)
		(end 357.978202 -131.290822)
		(stroke
			(width 0.05715)
			(type default)
		)
		(layer "In11.Cu")
	)
	(gr_line
		(start 357.9622 -110.0582)
		(end 357.9622 -110.43285)
		(stroke
			(width 0.05715)
			(type default)
		)
		(layer "In11.Cu")
	)
	(gr_line
		(start 357.9622 -109.16285)
		(end 357.9622 -109.5375)
		(stroke
			(width 0.05715)
			(type default)
		)
		(layer "In11.Cu")
	)
	(gr_line
		(start 357.964232 -88.484456)
		(end 357.974138 -88.434672)
		(stroke
			(width 0.05715)
			(type default)
		)
		(layer "In11.Cu")
	)
	(gr_line
		(start 357.99395 -96.57842)
		(end 357.998014 -96.598232)
		(stroke
			(width 0.05715)
			(type default)
		)
		(layer "In11.Cu")
	)
	(gr_line
		(start 358.099868 -115.907566)
		(end 358.26065 -116.068348)
		(stroke
			(width 0.05715)
			(type default)
		)
		(layer "In11.Cu")
	)
	(gr_line
		(start 358.099868 -115.490752)
		(end 358.26065 -115.32997)
		(stroke
			(width 0.05715)
			(type default)
		)
		(layer "In11.Cu")
	)
	(gr_line
		(start 358.229408 -83.940142)
		(end 358.246426 -83.951572)
		(stroke
			(width 0.05715)
			(type default)
		)
		(layer "In11.Cu")
	)
	(gr_line
		(start 358.238806 -94.123764)
		(end 358.242616 -94.142814)
		(stroke
			(width 0.05715)
			(type default)
		)
		(layer "In11.Cu")
	)
	(gr_line
		(start 358.238806 -94.123764)
		(end 358.24287 -94.103952)
		(stroke
			(width 0.05715)
			(type default)
		)
		(layer "In11.Cu")
	)
	(gr_line
		(start 358.246426 -83.951572)
		(end 358.257856 -83.96859)
		(stroke
			(width 0.05715)
			(type default)
		)
		(layer "In11.Cu")
	)
	(gr_line
		(start 358.26065 -116.068348)
		(end 358.26065 -116.220494)
		(stroke
			(width 0.05715)
			(type default)
		)
		(layer "In11.Cu")
	)
	(gr_line
		(start 358.26065 -115.204494)
		(end 358.26065 -115.32997)
		(stroke
			(width 0.05715)
			(type default)
		)
		(layer "In11.Cu")
	)
	(gr_line
		(start 358.40289 -93.304868)
		(end 358.4067 -93.285818)
		(stroke
			(width 0.05715)
			(type default)
		)
		(layer "In11.Cu")
	)
	(gr_line
		(start 358.4067 -93.285818)
		(end 358.417368 -93.269562)
		(stroke
			(width 0.05715)
			(type default)
		)
		(layer "In11.Cu")
	)
	(gr_line
		(start 358.45115 -75.123548)
		(end 358.4702 -75.119738)
		(stroke
			(width 0.05715)
			(type default)
		)
		(layer "In11.Cu")
	)
	(gr_line
		(start 358.4702 -75.119738)
		(end 358.48925 -75.123548)
		(stroke
			(width 0.05715)
			(type default)
		)
		(layer "In11.Cu")
	)
	(gr_line
		(start 358.479344 -131.776978)
		(end 358.497632 -131.769358)
		(stroke
			(width 0.05715)
			(type default)
		)
		(layer "In11.Cu")
	)
	(gr_line
		(start 358.52608 -100.098098)
		(end 359.08869 -100.660708)
		(stroke
			(width 0.05715)
			(type default)
		)
		(layer "In11.Cu")
	)
	(gr_line
		(start 358.601772 -129.327148)
		(end 358.623362 -129.3368)
		(stroke
			(width 0.05715)
			(type default)
		)
		(layer "In11.Cu")
	)
	(gr_line
		(start 358.622092 -74.40803)
		(end 358.641142 -74.40422)
		(stroke
			(width 0.05715)
			(type default)
		)
		(layer "In11.Cu")
	)
	(gr_line
		(start 358.641142 -74.40422)
		(end 358.660192 -74.40803)
		(stroke
			(width 0.05715)
			(type default)
		)
		(layer "In11.Cu")
	)
	(gr_line
		(start 358.667304 -73.733914)
		(end 358.686354 -73.730104)
		(stroke
			(width 0.05715)
			(type default)
		)
		(layer "In11.Cu")
	)
	(gr_line
		(start 358.67594 -99.803458)
		(end 359.08869 -99.390708)
		(stroke
			(width 0.05715)
			(type default)
		)
		(layer "In11.Cu")
	)
	(gr_line
		(start 358.686354 -73.730104)
		(end 358.705404 -73.733914)
		(stroke
			(width 0.05715)
			(type default)
		)
		(layer "In11.Cu")
	)
	(gr_line
		(start 358.82961 -128.670304)
		(end 358.851454 -128.679956)
		(stroke
			(width 0.05715)
			(type default)
		)
		(layer "In11.Cu")
	)
	(gr_line
		(start 358.90327 -84.937092)
		(end 358.913938 -84.953348)
		(stroke
			(width 0.05715)
			(type default)
		)
		(layer "In11.Cu")
	)
	(gr_line
		(start 358.913938 -84.953348)
		(end 358.917748 -84.972398)
		(stroke
			(width 0.05715)
			(type default)
		)
		(layer "In11.Cu")
	)
	(gr_line
		(start 359.023158 -116.849144)
		(end 359.175558 -116.696744)
		(stroke
			(width 0.05715)
			(type default)
		)
		(layer "In11.Cu")
	)
	(gr_line
		(start 359.03916 -92.33662)
		(end 359.05059 -92.319602)
		(stroke
			(width 0.05715)
			(type default)
		)
		(layer "In11.Cu")
	)
	(gr_line
		(start 359.05059 -92.319602)
		(end 359.067608 -92.308172)
		(stroke
			(width 0.05715)
			(type default)
		)
		(layer "In11.Cu")
	)
	(gr_line
		(start 359.063798 -128.033018)
		(end 359.08488 -128.04267)
		(stroke
			(width 0.05715)
			(type default)
		)
		(layer "In11.Cu")
	)
	(gr_line
		(start 359.072688 -98.290634)
		(end 359.076498 -98.309684)
		(stroke
			(width 0.05715)
			(type default)
		)
		(layer "In11.Cu")
	)
	(gr_line
		(start 359.076498 -98.309684)
		(end 359.087166 -98.32594)
		(stroke
			(width 0.05715)
			(type default)
		)
		(layer "In11.Cu")
	)
	(gr_line
		(start 359.168192 -127.378968)
		(end 359.190036 -127.38862)
		(stroke
			(width 0.05715)
			(type default)
		)
		(layer "In11.Cu")
	)
	(gr_line
		(start 359.175558 -116.696744)
		(end 359.518458 -116.696744)
		(stroke
			(width 0.05715)
			(type default)
		)
		(layer "In11.Cu")
	)
	(gr_line
		(start 359.300272 -126.718822)
		(end 359.328466 -126.733046)
		(stroke
			(width 0.05715)
			(type default)
		)
		(layer "In11.Cu")
	)
	(gr_line
		(start 359.31094 -86.938104)
		(end 359.315004 -86.957916)
		(stroke
			(width 0.05715)
			(type default)
		)
		(layer "In11.Cu")
	)
	(gr_line
		(start 359.311194 -86.976966)
		(end 359.315004 -86.957916)
		(stroke
			(width 0.05715)
			(type default)
		)
		(layer "In11.Cu")
	)
	(gr_line
		(start 359.315258 -117.153944)
		(end 359.378758 -117.153944)
		(stroke
			(width 0.05715)
			(type default)
		)
		(layer "In11.Cu")
	)
	(gr_line
		(start 359.3211 -93.63456)
		(end 359.32872 -93.653102)
		(stroke
			(width 0.05715)
			(type default)
		)
		(layer "In11.Cu")
	)
	(gr_line
		(start 359.3211 -93.079316)
		(end 359.380028 -93.020388)
		(stroke
			(width 0.05715)
			(type default)
		)
		(layer "In11.Cu")
	)
	(gr_line
		(start 359.34396 -106.760264)
		(end 359.447084 -106.863388)
		(stroke
			(width 0.05715)
			(type default)
		)
		(layer "In11.Cu")
	)
	(gr_line
		(start 359.34396 -106.343704)
		(end 359.405428 -106.282236)
		(stroke
			(width 0.05715)
			(type default)
		)
		(layer "In11.Cu")
	)
	(gr_line
		(start 359.396538 -93.816424)
		(end 359.396792 -93.816424)
		(stroke
			(width 0.05715)
			(type default)
		)
		(layer "In11.Cu")
	)
	(gr_line
		(start 359.405428 -105.92816)
		(end 359.405428 -106.282236)
		(stroke
			(width 0.05715)
			(type default)
		)
		(layer "In11.Cu")
	)
	(gr_line
		(start 359.429558 -129.989326)
		(end 359.447338 -129.98196)
		(stroke
			(width 0.05715)
			(type default)
		)
		(layer "In11.Cu")
	)
	(gr_line
		(start 359.447084 -106.863388)
		(end 359.447084 -107.174284)
		(stroke
			(width 0.05715)
			(type default)
		)
		(layer "In11.Cu")
	)
	(gr_line
		(start 359.464102 -93.97873)
		(end 359.472484 -93.998542)
		(stroke
			(width 0.05715)
			(type default)
		)
		(layer "In11.Cu")
	)
	(gr_line
		(start 359.518458 -116.696744)
		(end 359.670858 -116.849144)
		(stroke
			(width 0.05715)
			(type default)
		)
		(layer "In11.Cu")
	)
	(gr_line
		(start 359.55097 -130.639566)
		(end 359.568242 -130.6322)
		(stroke
			(width 0.05715)
			(type default)
		)
		(layer "In11.Cu")
	)
	(gr_line
		(start 359.6132 -93.526864)
		(end 359.6132 -93.575886)
		(stroke
			(width 0.05715)
			(type default)
		)
		(layer "In11.Cu")
	)
	(gr_line
		(start 359.668318 -131.284726)
		(end 359.68559 -131.27736)
		(stroke
			(width 0.05715)
			(type default)
		)
		(layer "In11.Cu")
	)
	(gr_line
		(start 359.704894 -109.287056)
		(end 359.708704 -109.268006)
		(stroke
			(width 0.05715)
			(type default)
		)
		(layer "In11.Cu")
	)
	(gr_line
		(start 359.704894 -109.287056)
		(end 359.708958 -109.306868)
		(stroke
			(width 0.05715)
			(type default)
		)
		(layer "In11.Cu")
	)
	(gr_line
		(start 359.814622 -92.585794)
		(end 359.851452 -92.548964)
		(stroke
			(width 0.05715)
			(type default)
		)
		(layer "In11.Cu")
	)
	(gr_line
		(start 359.851452 -92.548964)
		(end 359.901998 -92.538804)
		(stroke
			(width 0.05715)
			(type default)
		)
		(layer "In11.Cu")
	)
	(gr_line
		(start 359.875328 -92.119958)
		(end 359.892346 -92.108528)
		(stroke
			(width 0.05715)
			(type default)
		)
		(layer "In11.Cu")
	)
	(gr_line
		(start 359.892346 -92.108528)
		(end 359.903776 -92.09151)
		(stroke
			(width 0.05715)
			(type default)
		)
		(layer "In11.Cu")
	)
	(gr_line
		(start 359.940098 -104.810306)
		(end 359.97261 -104.833674)
		(stroke
			(width 0.05715)
			(type default)
		)
		(layer "In11.Cu")
	)
	(gr_line
		(start 359.97261 -104.833674)
		(end 359.989628 -104.870504)
		(stroke
			(width 0.05715)
			(type default)
		)
		(layer "In11.Cu")
	)
	(gr_line
		(start 360.039158 -116.849144)
		(end 360.191558 -116.696744)
		(stroke
			(width 0.05715)
			(type default)
		)
		(layer "In11.Cu")
	)
	(gr_line
		(start 360.189272 -82.80527)
		(end 360.193082 -82.82432)
		(stroke
			(width 0.05715)
			(type default)
		)
		(layer "In11.Cu")
	)
	(gr_line
		(start 360.189272 -82.80527)
		(end 360.193336 -82.785204)
		(stroke
			(width 0.05715)
			(type default)
		)
		(layer "In11.Cu")
	)
	(gr_line
		(start 360.191558 -116.696744)
		(end 360.534458 -116.696744)
		(stroke
			(width 0.05715)
			(type default)
		)
		(layer "In11.Cu")
	)
	(gr_line
		(start 360.24947 -92.767404)
		(end 360.331766 -92.750894)
		(stroke
			(width 0.05715)
			(type default)
		)
		(layer "In11.Cu")
	)
	(gr_line
		(start 360.318304 -112.353598)
		(end 360.32186 -112.371886)
		(stroke
			(width 0.05715)
			(type default)
		)
		(layer "In11.Cu")
	)
	(gr_line
		(start 360.32186 -112.371886)
		(end 360.333036 -112.388904)
		(stroke
			(width 0.05715)
			(type default)
		)
		(layer "In11.Cu")
	)
	(gr_line
		(start 360.331258 -117.153944)
		(end 360.394758 -117.153944)
		(stroke
			(width 0.05715)
			(type default)
		)
		(layer "In11.Cu")
	)
	(gr_line
		(start 360.331766 -92.750894)
		(end 360.378248 -92.681044)
		(stroke
			(width 0.05715)
			(type default)
		)
		(layer "In11.Cu")
	)
	(gr_line
		(start 360.39425 -84.847938)
		(end 360.39806 -84.866988)
		(stroke
			(width 0.05715)
			(type default)
		)
		(layer "In11.Cu")
	)
	(gr_line
		(start 360.39425 -84.847938)
		(end 360.398314 -84.828126)
		(stroke
			(width 0.05715)
			(type default)
		)
		(layer "In11.Cu")
	)
	(gr_line
		(start 360.446574 -109.316012)
		(end 360.450638 -109.335824)
		(stroke
			(width 0.05715)
			(type default)
		)
		(layer "In11.Cu")
	)
	(gr_line
		(start 360.446574 -109.316012)
		(end 360.450638 -109.295692)
		(stroke
			(width 0.05715)
			(type default)
		)
		(layer "In11.Cu")
	)
	(gr_line
		(start 360.502454 -104.370632)
		(end 360.534966 -104.394)
		(stroke
			(width 0.05715)
			(type default)
		)
		(layer "In11.Cu")
	)
	(gr_line
		(start 360.534458 -116.696744)
		(end 360.686858 -116.849144)
		(stroke
			(width 0.05715)
			(type default)
		)
		(layer "In11.Cu")
	)
	(gr_line
		(start 360.534966 -104.394)
		(end 360.551984 -104.43083)
		(stroke
			(width 0.05715)
			(type default)
		)
		(layer "In11.Cu")
	)
	(gr_line
		(start 360.566462 -75.538584)
		(end 360.648758 -75.555094)
		(stroke
			(width 0.05715)
			(type default)
		)
		(layer "In11.Cu")
	)
	(gr_line
		(start 360.590338 -106.182414)
		(end 360.613706 -106.23296)
		(stroke
			(width 0.05715)
			(type default)
		)
		(layer "In11.Cu")
	)
	(gr_line
		(start 360.60253 -106.288078)
		(end 360.613706 -106.23296)
		(stroke
			(width 0.05715)
			(type default)
		)
		(layer "In11.Cu")
	)
	(gr_line
		(start 360.621834 -99.50958)
		(end 360.69905 -99.586796)
		(stroke
			(width 0.05715)
			(type default)
		)
		(layer "In11.Cu")
	)
	(gr_line
		(start 360.621834 -99.092766)
		(end 360.69905 -99.01555)
		(stroke
			(width 0.05715)
			(type default)
		)
		(layer "In11.Cu")
	)
	(gr_line
		(start 360.648758 -75.555094)
		(end 360.694986 -75.624436)
		(stroke
			(width 0.05715)
			(type default)
		)
		(layer "In11.Cu")
	)
	(gr_line
		(start 360.692446 -94.467426)
		(end 360.81081 -94.58579)
		(stroke
			(width 0.05715)
			(type default)
		)
		(layer "In11.Cu")
	)
	(gr_line
		(start 360.692446 -94.050866)
		(end 360.81081 -93.932502)
		(stroke
			(width 0.05715)
			(type default)
		)
		(layer "In11.Cu")
	)
	(gr_line
		(start 360.69905 -99.586796)
		(end 360.69905 -99.924108)
		(stroke
			(width 0.05715)
			(type default)
		)
		(layer "In11.Cu")
	)
	(gr_line
		(start 360.69905 -98.654108)
		(end 360.69905 -99.01555)
		(stroke
			(width 0.05715)
			(type default)
		)
		(layer "In11.Cu")
	)
	(gr_line
		(start 360.69905 -97.1042)
		(end 360.69905 -97.37725)
		(stroke
			(width 0.05715)
			(type default)
		)
		(layer "In11.Cu")
	)
	(gr_line
		(start 360.69905 -97.1042)
		(end 360.77652 -97.02673)
		(stroke
			(width 0.05715)
			(type default)
		)
		(layer "In11.Cu")
	)
	(gr_line
		(start 360.69905 -96.5327)
		(end 360.77652 -96.61017)
		(stroke
			(width 0.05715)
			(type default)
		)
		(layer "In11.Cu")
	)
	(gr_line
		(start 360.69905 -96.10725)
		(end 360.69905 -96.5327)
		(stroke
			(width 0.05715)
			(type default)
		)
		(layer "In11.Cu")
	)
	(gr_line
		(start 360.789728 -84.319618)
		(end 360.793792 -84.339684)
		(stroke
			(width 0.05715)
			(type default)
		)
		(layer "In11.Cu")
	)
	(gr_line
		(start 360.789982 -84.358734)
		(end 360.793792 -84.339684)
		(stroke
			(width 0.05715)
			(type default)
		)
		(layer "In11.Cu")
	)
	(gr_line
		(start 360.81081 -94.58579)
		(end 360.81081 -94.89059)
		(stroke
			(width 0.05715)
			(type default)
		)
		(layer "In11.Cu")
	)
	(gr_line
		(start 360.81081 -93.62059)
		(end 360.81081 -93.932502)
		(stroke
			(width 0.05715)
			(type default)
		)
		(layer "In11.Cu")
	)
	(gr_line
		(start 360.853228 -82.72526)
		(end 360.857038 -82.74431)
		(stroke
			(width 0.05715)
			(type default)
		)
		(layer "In11.Cu")
	)
	(gr_line
		(start 360.853228 -82.72526)
		(end 360.857292 -82.705448)
		(stroke
			(width 0.05715)
			(type default)
		)
		(layer "In11.Cu")
	)
	(gr_line
		(start 360.899202 -74.855832)
		(end 360.981498 -74.872342)
		(stroke
			(width 0.05715)
			(type default)
		)
		(layer "In11.Cu")
	)
	(gr_line
		(start 360.91368 -90.576654)
		(end 360.924348 -90.560398)
		(stroke
			(width 0.05715)
			(type default)
		)
		(layer "In11.Cu")
	)
	(gr_line
		(start 360.91876 -111.678212)
		(end 360.92257 -111.697008)
		(stroke
			(width 0.05715)
			(type default)
		)
		(layer "In11.Cu")
	)
	(gr_line
		(start 360.92257 -111.697008)
		(end 360.933238 -111.713264)
		(stroke
			(width 0.05715)
			(type default)
		)
		(layer "In11.Cu")
	)
	(gr_line
		(start 360.924348 -90.560398)
		(end 360.928158 -90.541348)
		(stroke
			(width 0.05715)
			(type default)
		)
		(layer "In11.Cu")
	)
	(gr_line
		(start 360.966258 -131.27736)
		(end 361.003596 -131.30022)
		(stroke
			(width 0.05715)
			(type default)
		)
		(layer "In11.Cu")
	)
	(gr_line
		(start 360.981498 -74.872342)
		(end 361.027726 -74.941684)
		(stroke
			(width 0.05715)
			(type default)
		)
		(layer "In11.Cu")
	)
	(gr_line
		(start 360.98734 -103.889302)
		(end 361.01909 -103.912162)
		(stroke
			(width 0.05715)
			(type default)
		)
		(layer "In11.Cu")
	)
	(gr_line
		(start 361.01909 -103.912162)
		(end 361.0356 -103.947976)
		(stroke
			(width 0.05715)
			(type default)
		)
		(layer "In11.Cu")
	)
	(gr_line
		(start 361.053634 -84.873846)
		(end 361.057444 -84.892896)
		(stroke
			(width 0.05715)
			(type default)
		)
		(layer "In11.Cu")
	)
	(gr_line
		(start 361.053634 -84.873846)
		(end 361.057698 -84.854034)
		(stroke
			(width 0.05715)
			(type default)
		)
		(layer "In11.Cu")
	)
	(gr_line
		(start 361.055158 -116.849144)
		(end 361.207558 -116.696744)
		(stroke
			(width 0.05715)
			(type default)
		)
		(layer "In11.Cu")
	)
	(gr_line
		(start 361.16514 -129.0447)
		(end 361.18165 -129.051304)
		(stroke
			(width 0.05715)
			(type default)
		)
		(layer "In11.Cu")
	)
	(gr_line
		(start 361.184698 -76.359004)
		(end 361.196382 -76.37653)
		(stroke
			(width 0.05715)
			(type default)
		)
		(layer "In11.Cu")
	)
	(gr_line
		(start 361.196382 -76.37653)
		(end 361.200192 -76.396596)
		(stroke
			(width 0.05715)
			(type default)
		)
		(layer "In11.Cu")
	)
	(gr_line
		(start 361.207558 -116.696744)
		(end 361.550458 -116.696744)
		(stroke
			(width 0.05715)
			(type default)
		)
		(layer "In11.Cu")
	)
	(gr_line
		(start 361.218988 -109.034072)
		(end 361.222798 -109.015022)
		(stroke
			(width 0.05715)
			(type default)
		)
		(layer "In11.Cu")
	)
	(gr_line
		(start 361.218988 -109.034072)
		(end 361.223052 -109.053884)
		(stroke
			(width 0.05715)
			(type default)
		)
		(layer "In11.Cu")
	)
	(gr_line
		(start 361.342686 -106.156252)
		(end 361.366054 -106.207306)
		(stroke
			(width 0.05715)
			(type default)
		)
		(layer "In11.Cu")
	)
	(gr_line
		(start 361.347258 -117.153944)
		(end 361.410758 -117.153944)
		(stroke
			(width 0.05715)
			(type default)
		)
		(layer "In11.Cu")
	)
	(gr_line
		(start 361.375706 -88.267286)
		(end 361.37977 -88.287098)
		(stroke
			(width 0.05715)
			(type default)
		)
		(layer "In11.Cu")
	)
	(gr_line
		(start 361.37596 -88.306148)
		(end 361.37977 -88.287098)
		(stroke
			(width 0.05715)
			(type default)
		)
		(layer "In11.Cu")
	)
	(gr_line
		(start 361.409742 -74.274934)
		(end 361.492038 -74.291444)
		(stroke
			(width 0.05715)
			(type default)
		)
		(layer "In11.Cu")
	)
	(gr_line
		(start 361.422696 -128.387856)
		(end 361.439968 -128.395222)
		(stroke
			(width 0.05715)
			(type default)
		)
		(layer "In11.Cu")
	)
	(gr_line
		(start 361.46232 -84.282534)
		(end 361.466384 -84.302092)
		(stroke
			(width 0.05715)
			(type default)
		)
		(layer "In11.Cu")
	)
	(gr_line
		(start 361.462574 -84.320888)
		(end 361.466384 -84.302092)
		(stroke
			(width 0.05715)
			(type default)
		)
		(layer "In11.Cu")
	)
	(gr_line
		(start 361.480608 -77.799184)
		(end 361.484672 -77.81925)
		(stroke
			(width 0.05715)
			(type default)
		)
		(layer "In11.Cu")
	)
	(gr_line
		(start 361.480862 -77.8383)
		(end 361.484672 -77.81925)
		(stroke
			(width 0.05715)
			(type default)
		)
		(layer "In11.Cu")
	)
	(gr_line
		(start 361.492038 -74.291444)
		(end 361.538266 -74.360786)
		(stroke
			(width 0.05715)
			(type default)
		)
		(layer "In11.Cu")
	)
	(gr_line
		(start 361.536742 -82.660236)
		(end 361.540552 -82.679286)
		(stroke
			(width 0.05715)
			(type default)
		)
		(layer "In11.Cu")
	)
	(gr_line
		(start 361.536742 -82.660236)
		(end 361.540806 -82.640424)
		(stroke
			(width 0.05715)
			(type default)
		)
		(layer "In11.Cu")
	)
	(gr_line
		(start 361.550458 -116.696744)
		(end 361.702858 -116.849144)
		(stroke
			(width 0.05715)
			(type default)
		)
		(layer "In11.Cu")
	)
	(gr_line
		(start 361.586272 -90.870532)
		(end 361.597956 -90.853006)
		(stroke
			(width 0.05715)
			(type default)
		)
		(layer "In11.Cu")
	)
	(gr_line
		(start 361.588304 -130.6322)
		(end 361.605576 -130.639566)
		(stroke
			(width 0.05715)
			(type default)
		)
		(layer "In11.Cu")
	)
	(gr_line
		(start 361.597956 -90.853006)
		(end 361.601766 -90.83294)
		(stroke
			(width 0.05715)
			(type default)
		)
		(layer "In11.Cu")
	)
	(gr_line
		(start 361.607608 -103.552498)
		(end 361.640374 -103.57612)
		(stroke
			(width 0.05715)
			(type default)
		)
		(layer "In11.Cu")
	)
	(gr_line
		(start 361.62742 -111.075978)
		(end 361.63123 -111.095028)
		(stroke
			(width 0.05715)
			(type default)
		)
		(layer "In11.Cu")
	)
	(gr_line
		(start 361.628944 -127.75057)
		(end 361.646216 -127.757936)
		(stroke
			(width 0.05715)
			(type default)
		)
		(layer "In11.Cu")
	)
	(gr_line
		(start 361.63123 -111.095028)
		(end 361.641898 -111.111284)
		(stroke
			(width 0.05715)
			(type default)
		)
		(layer "In11.Cu")
	)
	(gr_line
		(start 361.640374 -103.57612)
		(end 361.6579 -103.61422)
		(stroke
			(width 0.05715)
			(type default)
		)
		(layer "In11.Cu")
	)
	(gr_line
		(start 361.640628 -114.350038)
		(end 361.686856 -114.41938)
		(stroke
			(width 0.05715)
			(type default)
		)
		(layer "In11.Cu")
	)
	(gr_line
		(start 361.686856 -114.41938)
		(end 361.769152 -114.43589)
		(stroke
			(width 0.05715)
			(type default)
		)
		(layer "In11.Cu")
	)
	(gr_line
		(start 361.720892 -127.09652)
		(end 361.738164 -127.103886)
		(stroke
			(width 0.05715)
			(type default)
		)
		(layer "In11.Cu")
	)
	(gr_line
		(start 361.729528 -92.208604)
		(end 361.733338 -92.227654)
		(stroke
			(width 0.05715)
			(type default)
		)
		(layer "In11.Cu")
	)
	(gr_line
		(start 361.729528 -92.208604)
		(end 361.733592 -92.188792)
		(stroke
			(width 0.05715)
			(type default)
		)
		(layer "In11.Cu")
	)
	(gr_line
		(start 361.731814 -131.74726)
		(end 361.77347 -131.772914)
		(stroke
			(width 0.05715)
			(type default)
		)
		(layer "In11.Cu")
	)
	(gr_line
		(start 361.745276 -112.931448)
		(end 361.791504 -113.00079)
		(stroke
			(width 0.05715)
			(type default)
		)
		(layer "In11.Cu")
	)
	(gr_line
		(start 361.773216 -129.98196)
		(end 361.790488 -129.989326)
		(stroke
			(width 0.05715)
			(type default)
		)
		(layer "In11.Cu")
	)
	(gr_line
		(start 361.77347 -131.772914)
		(end 361.794552 -131.817618)
		(stroke
			(width 0.05715)
			(type default)
		)
		(layer "In11.Cu")
	)
	(gr_line
		(start 361.791504 -113.00079)
		(end 361.8738 -113.0173)
		(stroke
			(width 0.05715)
			(type default)
		)
		(layer "In11.Cu")
	)
	(gr_line
		(start 361.794552 -76.091796)
		(end 361.80522 -76.108052)
		(stroke
			(width 0.05715)
			(type default)
		)
		(layer "In11.Cu")
	)
	(gr_line
		(start 361.80522 -76.108052)
		(end 361.80903 -76.127102)
		(stroke
			(width 0.05715)
			(type default)
		)
		(layer "In11.Cu")
	)
	(gr_line
		(start 361.869482 -126.440946)
		(end 361.886754 -126.448312)
		(stroke
			(width 0.05715)
			(type default)
		)
		(layer "In11.Cu")
	)
	(gr_line
		(start 362.054902 -106.173524)
		(end 362.0897 -106.249724)
		(stroke
			(width 0.05715)
			(type default)
		)
		(layer "In11.Cu")
	)
	(gr_line
		(start 362.06049 -106.328718)
		(end 362.0897 -106.249724)
		(stroke
			(width 0.05715)
			(type default)
		)
		(layer "In11.Cu")
	)
	(gr_line
		(start 362.068364 -88.45677)
		(end 362.072428 -88.476582)
		(stroke
			(width 0.05715)
			(type default)
		)
		(layer "In11.Cu")
	)
	(gr_line
		(start 362.068618 -88.495632)
		(end 362.072428 -88.476582)
		(stroke
			(width 0.05715)
			(type default)
		)
		(layer "In11.Cu")
	)
	(gr_line
		(start 362.071158 -116.849144)
		(end 362.223558 -116.696744)
		(stroke
			(width 0.05715)
			(type default)
		)
		(layer "In11.Cu")
	)
	(gr_line
		(start 362.134404 -77.817726)
		(end 362.13923 -77.814678)
		(stroke
			(width 0.05715)
			(type default)
		)
		(layer "In11.Cu")
	)
	(gr_line
		(start 362.135928 -77.761338)
		(end 362.139992 -77.78115)
		(stroke
			(width 0.05715)
			(type default)
		)
		(layer "In11.Cu")
	)
	(gr_line
		(start 362.136182 -77.800708)
		(end 362.13923 -77.814424)
		(stroke
			(width 0.05715)
			(type default)
		)
		(layer "In11.Cu")
	)
	(gr_line
		(start 362.136182 -77.800708)
		(end 362.139992 -77.78115)
		(stroke
			(width 0.05715)
			(type default)
		)
		(layer "In11.Cu")
	)
	(gr_line
		(start 362.13923 -77.814424)
		(end 362.13923 -77.814678)
		(stroke
			(width 0.05715)
			(type default)
		)
		(layer "In11.Cu")
	)
	(gr_line
		(start 362.223558 -116.696744)
		(end 362.566458 -116.696744)
		(stroke
			(width 0.05715)
			(type default)
		)
		(layer "In11.Cu")
	)
	(gr_line
		(start 362.335064 -75.555856)
		(end 362.345732 -75.572112)
		(stroke
			(width 0.05715)
			(type default)
		)
		(layer "In11.Cu")
	)
	(gr_line
		(start 362.345732 -75.572112)
		(end 362.349542 -75.591162)
		(stroke
			(width 0.05715)
			(type default)
		)
		(layer "In11.Cu")
	)
	(gr_line
		(start 362.363258 -117.153944)
		(end 362.426758 -117.153944)
		(stroke
			(width 0.05715)
			(type default)
		)
		(layer "In11.Cu")
	)
	(gr_line
		(start 362.566458 -116.696744)
		(end 362.718858 -116.849144)
		(stroke
			(width 0.05715)
			(type default)
		)
		(layer "In11.Cu")
	)
	(gr_line
		(start 362.61421 -95.444056)
		(end 362.660946 -95.373952)
		(stroke
			(width 0.05715)
			(type default)
		)
		(layer "In11.Cu")
	)
	(gr_line
		(start 362.644436 -95.291148)
		(end 362.660946 -95.373952)
		(stroke
			(width 0.05715)
			(type default)
		)
		(layer "In11.Cu")
	)
	(gr_line
		(start 362.787946 -133.979158)
		(end 362.83138 -134.04088)
		(stroke
			(width 0.05715)
			(type default)
		)
		(layer "In11.Cu")
	)
	(gr_line
		(start 362.795058 -77.81798)
		(end 362.799122 -77.837792)
		(stroke
			(width 0.05715)
			(type default)
		)
		(layer "In11.Cu")
	)
	(gr_line
		(start 362.795312 -77.856842)
		(end 362.799122 -77.837792)
		(stroke
			(width 0.05715)
			(type default)
		)
		(layer "In11.Cu")
	)
	(gr_line
		(start 362.83138 -134.04088)
		(end 362.90504 -134.057898)
		(stroke
			(width 0.05715)
			(type default)
		)
		(layer "In11.Cu")
	)
	(gr_line
		(start 362.881926 -87.896446)
		(end 362.88599 -87.916258)
		(stroke
			(width 0.05715)
			(type default)
		)
		(layer "In11.Cu")
	)
	(gr_line
		(start 362.88218 -87.935308)
		(end 362.88599 -87.916258)
		(stroke
			(width 0.05715)
			(type default)
		)
		(layer "In11.Cu")
	)
	(gr_line
		(start 363.7026 -115.189)
		(end 363.855 -115.0366)
		(stroke
			(width 0.05715)
			(type default)
		)
		(layer "In11.Cu")
	)
	(gr_line
		(start 363.7026 -113.792)
		(end 363.855 -113.9444)
		(stroke
			(width 0.05715)
			(type default)
		)
		(layer "In11.Cu")
	)
	(gr_line
		(start 363.7026 -112.4204)
		(end 363.855 -112.268)
		(stroke
			(width 0.05715)
			(type default)
		)
		(layer "In11.Cu")
	)
	(gr_line
		(start 363.7026 -111.0234)
		(end 363.855 -111.1758)
		(stroke
			(width 0.05715)
			(type default)
		)
		(layer "In11.Cu")
	)
	(gr_line
		(start 363.80293 -111.93018)
		(end 363.855 -111.98225)
		(stroke
			(width 0.05715)
			(type default)
		)
		(layer "In11.Cu")
	)
	(gr_line
		(start 363.80293 -111.51362)
		(end 363.855 -111.46155)
		(stroke
			(width 0.05715)
			(type default)
		)
		(layer "In11.Cu")
	)
	(gr_line
		(start 363.82198 -114.70513)
		(end 363.855 -114.73815)
		(stroke
			(width 0.05715)
			(type default)
		)
		(layer "In11.Cu")
	)
	(gr_line
		(start 363.82198 -114.28857)
		(end 363.855 -114.25555)
		(stroke
			(width 0.05715)
			(type default)
		)
		(layer "In11.Cu")
	)
	(gr_line
		(start 363.855 -114.73815)
		(end 363.855 -115.0366)
		(stroke
			(width 0.05715)
			(type default)
		)
		(layer "In11.Cu")
	)
	(gr_line
		(start 363.855 -113.9444)
		(end 363.855 -114.25555)
		(stroke
			(width 0.05715)
			(type default)
		)
		(layer "In11.Cu")
	)
	(gr_line
		(start 363.855 -111.98225)
		(end 363.855 -112.268)
		(stroke
			(width 0.05715)
			(type default)
		)
		(layer "In11.Cu")
	)
	(gr_line
		(start 363.855 -111.1758)
		(end 363.855 -111.46155)
		(stroke
			(width 0.05715)
			(type default)
		)
		(layer "In11.Cu")
	)
	(gr_line
		(start 363.909102 -133.988556)
		(end 363.97946 -134.004558)
		(stroke
			(width 0.05715)
			(type default)
		)
		(layer "In11.Cu")
	)
	(gr_line
		(start 363.97946 -134.004558)
		(end 364.02264 -134.063994)
		(stroke
			(width 0.05715)
			(type default)
		)
		(layer "In11.Cu")
	)
	(gr_line
		(start 364.086902 -109.619288)
		(end 364.106968 -109.662976)
		(stroke
			(width 0.05715)
			(type default)
		)
		(layer "In11.Cu")
	)
	(gr_line
		(start 364.106968 -109.662976)
		(end 364.1344 -109.680502)
		(stroke
			(width 0.05715)
			(type default)
		)
		(layer "In11.Cu")
	)
	(gr_line
		(start 364.1344 -109.680502)
		(end 364.147608 -109.689138)
		(stroke
			(width 0.05715)
			(type default)
		)
		(layer "In11.Cu")
	)
	(gr_line
		(start 364.23473 -131.727956)
		(end 364.254796 -131.736338)
		(stroke
			(width 0.05715)
			(type default)
		)
		(layer "In11.Cu")
	)
	(gr_line
		(start 364.237524 -138.177016)
		(end 364.256828 -138.112246)
		(stroke
			(width 0.05715)
			(type default)
		)
		(layer "In11.Cu")
	)
	(gr_line
		(start 364.237524 -138.177016)
		(end 364.263178 -138.238992)
		(stroke
			(width 0.05715)
			(type default)
		)
		(layer "In11.Cu")
	)
	(gr_line
		(start 364.689136 -131.189222)
		(end 364.709202 -131.197604)
		(stroke
			(width 0.05715)
			(type default)
		)
		(layer "In11.Cu")
	)
	(gr_line
		(start 364.709202 -131.197604)
		(end 364.724696 -131.213098)
		(stroke
			(width 0.05715)
			(type default)
		)
		(layer "In11.Cu")
	)
	(gr_line
		(start 364.870492 -135.234426)
		(end 364.873794 -135.238998)
		(stroke
			(width 0.05715)
			(type default)
		)
		(layer "In11.Cu")
	)
	(gr_line
		(start 364.873794 -135.238998)
		(end 364.875572 -135.244332)
		(stroke
			(width 0.05715)
			(type default)
		)
		(layer "In11.Cu")
	)
	(gr_line
		(start 364.992666 -130.57886)
		(end 365.014002 -130.587496)
		(stroke
			(width 0.05715)
			(type default)
		)
		(layer "In11.Cu")
	)
	(gr_line
		(start 365.014002 -130.587496)
		(end 365.031274 -130.604768)
		(stroke
			(width 0.05715)
			(type default)
		)
		(layer "In11.Cu")
	)
	(gr_line
		(start 365.13262 -140.337032)
		(end 365.173006 -140.435076)
		(stroke
			(width 0.05715)
			(type default)
		)
		(layer "In11.Cu")
	)
	(gr_line
		(start 365.150654 -136.03224)
		(end 365.16945 -136.085834)
		(stroke
			(width 0.05715)
			(type default)
		)
		(layer "In11.Cu")
	)
	(gr_line
		(start 365.153194 -136.14019)
		(end 365.16945 -136.085834)
		(stroke
			(width 0.05715)
			(type default)
		)
		(layer "In11.Cu")
	)
	(gr_line
		(start 365.173006 -140.435076)
		(end 365.27613 -140.463016)
		(stroke
			(width 0.05715)
			(type default)
		)
		(layer "In11.Cu")
	)
	(gr_line
		(start 365.286036 -110.419896)
		(end 365.326168 -110.44555)
		(stroke
			(width 0.05715)
			(type default)
		)
		(layer "In11.Cu")
	)
	(gr_line
		(start 365.992156 -133.473698)
		(end 366.000538 -133.493764)
		(stroke
			(width 0.05715)
			(type default)
		)
		(layer "In11.Cu")
	)
	(gr_line
		(start 365.996474 -110.15091)
		(end 366.075976 -110.071408)
		(stroke
			(width 0.05715)
			(type default)
		)
		(layer "In11.Cu")
	)
	(gr_line
		(start 366.075976 -110.071408)
		(end 366.418622 -110.071408)
		(stroke
			(width 0.05715)
			(type default)
		)
		(layer "In11.Cu")
	)
	(gr_line
		(start 366.189006 -130.361436)
		(end 366.209072 -130.369818)
		(stroke
			(width 0.05715)
			(type default)
		)
		(layer "In11.Cu")
	)
	(gr_line
		(start 366.209072 -130.369818)
		(end 366.224566 -130.385312)
		(stroke
			(width 0.05715)
			(type default)
		)
		(layer "In11.Cu")
	)
	(gr_line
		(start 366.3442 -138.307064)
		(end 366.351566 -138.324336)
		(stroke
			(width 0.05715)
			(type default)
		)
		(layer "In11.Cu")
	)
	(gr_line
		(start 366.418622 -110.071408)
		(end 366.498124 -110.15091)
		(stroke
			(width 0.05715)
			(type default)
		)
		(layer "In11.Cu")
	)
	(gr_line
		(start 366.572292 -129.79781)
		(end 366.592358 -129.806192)
		(stroke
			(width 0.05715)
			(type default)
		)
		(layer "In11.Cu")
	)
	(gr_line
		(start 366.592358 -129.806192)
		(end 366.607852 -129.821686)
		(stroke
			(width 0.05715)
			(type default)
		)
		(layer "In11.Cu")
	)
	(gr_line
		(start 366.628934 -135.011922)
		(end 366.6363 -135.029194)
		(stroke
			(width 0.05715)
			(type default)
		)
		(layer "In11.Cu")
	)
	(gr_line
		(start 366.759998 -139.310618)
		(end 366.77854 -139.355322)
		(stroke
			(width 0.05715)
			(type default)
		)
		(layer "In11.Cu")
	)
	(gr_line
		(start 366.77854 -139.355322)
		(end 366.818164 -139.383008)
		(stroke
			(width 0.05715)
			(type default)
		)
		(layer "In11.Cu")
	)
	(gr_line
		(start 366.830102 -133.318758)
		(end 366.845596 -133.334252)
		(stroke
			(width 0.05715)
			(type default)
		)
		(layer "In11.Cu")
	)
	(gr_line
		(start 366.845596 -133.334252)
		(end 366.853978 -133.354318)
		(stroke
			(width 0.05715)
			(type default)
		)
		(layer "In11.Cu")
	)
	(gr_line
		(start 366.965992 -140.920724)
		(end 366.992154 -140.927836)
		(stroke
			(width 0.05715)
			(type default)
		)
		(layer "In11.Cu")
	)
	(gr_line
		(start 366.992154 -140.927836)
		(end 367.019078 -140.923264)
		(stroke
			(width 0.05715)
			(type default)
		)
		(layer "In11.Cu")
	)
	(gr_line
		(start 367.026444 -129.29362)
		(end 367.045748 -129.301748)
		(stroke
			(width 0.05715)
			(type default)
		)
		(layer "In11.Cu")
	)
	(gr_line
		(start 367.18875 -139.640564)
		(end 367.207038 -139.653264)
		(stroke
			(width 0.05715)
			(type default)
		)
		(layer "In11.Cu")
	)
	(gr_line
		(start 367.207038 -139.653264)
		(end 367.229136 -139.657836)
		(stroke
			(width 0.05715)
			(type default)
		)
		(layer "In11.Cu")
	)
	(gr_line
		(start 367.409984 -132.983732)
		(end 367.418366 -133.003798)
		(stroke
			(width 0.05715)
			(type default)
		)
		(layer "In11.Cu")
	)
	(gr_line
		(start 367.46688 -128.761236)
		(end 367.485676 -128.76911)
		(stroke
			(width 0.05715)
			(type default)
		)
		(layer "In11.Cu")
	)
	(gr_line
		(start 367.65103 -113.31448)
		(end 367.665 -113.32845)
		(stroke
			(width 0.05715)
			(type default)
		)
		(layer "In11.Cu")
	)
	(gr_line
		(start 367.65103 -112.89792)
		(end 367.7158 -112.83315)
		(stroke
			(width 0.05715)
			(type default)
		)
		(layer "In11.Cu")
	)
	(gr_line
		(start 367.665 -113.32845)
		(end 367.665 -113.792)
		(stroke
			(width 0.05715)
			(type default)
		)
		(layer "In11.Cu")
	)
	(gr_line
		(start 367.7158 -112.395)
		(end 367.7158 -112.83315)
		(stroke
			(width 0.05715)
			(type default)
		)
		(layer "In11.Cu")
	)
	(gr_line
		(start 367.762282 -110.510828)
		(end 367.792 -110.540546)
		(stroke
			(width 0.05715)
			(type default)
		)
		(layer "In11.Cu")
	)
	(gr_line
		(start 367.762282 -110.094268)
		(end 367.792 -110.06455)
		(stroke
			(width 0.05715)
			(type default)
		)
		(layer "In11.Cu")
	)
	(gr_line
		(start 367.792 -110.540546)
		(end 367.792 -110.998)
		(stroke
			(width 0.05715)
			(type default)
		)
		(layer "In11.Cu")
	)
	(gr_line
		(start 367.792 -109.601)
		(end 367.792 -110.06455)
		(stroke
			(width 0.05715)
			(type default)
		)
		(layer "In11.Cu")
	)
	(gr_line
		(start 367.823242 -140.489178)
		(end 367.839244 -140.486384)
		(stroke
			(width 0.05715)
			(type default)
		)
		(layer "In11.Cu")
	)
	(gr_line
		(start 367.839244 -140.486384)
		(end 367.854992 -140.489686)
		(stroke
			(width 0.05715)
			(type default)
		)
		(layer "In11.Cu")
	)
	(gr_line
		(start 367.939574 -136.739122)
		(end 367.955576 -136.77773)
		(stroke
			(width 0.05715)
			(type default)
		)
		(layer "In11.Cu")
	)
	(gr_line
		(start 367.955576 -136.77773)
		(end 367.988596 -136.80313)
		(stroke
			(width 0.05715)
			(type default)
		)
		(layer "In11.Cu")
	)
	(gr_line
		(start 368.491516 -136.3599)
		(end 368.507772 -136.399016)
		(stroke
			(width 0.05715)
			(type default)
		)
		(layer "In11.Cu")
	)
	(gr_line
		(start 368.507772 -136.399016)
		(end 368.540792 -136.424416)
		(stroke
			(width 0.05715)
			(type default)
		)
		(layer "In11.Cu")
	)
	(gr_line
		(start 370.014246 -133.641592)
		(end 370.073174 -133.70052)
		(stroke
			(width 0.05715)
			(type default)
		)
		(layer "In11.Cu")
	)
	(gr_line
		(start 370.707412 -109.944154)
		(end 370.828824 -110.065566)
		(stroke
			(width 0.05715)
			(type default)
		)
		(layer "In11.Cu")
	)
	(gr_line
		(start 371.256052 -132.1689)
		(end 371.274594 -132.17652)
		(stroke
			(width 0.05715)
			(type default)
		)
		(layer "In11.Cu")
	)
	(gr_line
		(start 371.259862 -110.065566)
		(end 371.381274 -109.944154)
		(stroke
			(width 0.05715)
			(type default)
		)
		(layer "In11.Cu")
	)
	(gr_line
		(start 371.772942 -131.518914)
		(end 371.81409 -131.546346)
		(stroke
			(width 0.05715)
			(type default)
		)
		(layer "In11.Cu")
	)
	(gr_line
		(start 371.879876 -139.783058)
		(end 371.903752 -139.801346)
		(stroke
			(width 0.05715)
			(type default)
		)
		(layer "In11.Cu")
	)
	(gr_line
		(start 371.903752 -139.801346)
		(end 371.93347 -139.807442)
		(stroke
			(width 0.05715)
			(type default)
		)
		(layer "In11.Cu")
	)
	(gr_line
		(start 372.136924 -139.17803)
		(end 372.1608 -139.196318)
		(stroke
			(width 0.05715)
			(type default)
		)
		(layer "In11.Cu")
	)
	(gr_line
		(start 372.15318 -132.541264)
		(end 372.171976 -132.549138)
		(stroke
			(width 0.05715)
			(type default)
		)
		(layer "In11.Cu")
	)
	(gr_line
		(start 372.1608 -139.196318)
		(end 372.190518 -139.202414)
		(stroke
			(width 0.05715)
			(type default)
		)
		(layer "In11.Cu")
	)
	(gr_line
		(start 372.171976 -132.549138)
		(end 372.186454 -132.563616)
		(stroke
			(width 0.05715)
			(type default)
		)
		(layer "In11.Cu")
	)
	(gr_line
		(start 372.4275 -137.32383)
		(end 372.455186 -137.36574)
		(stroke
			(width 0.05715)
			(type default)
		)
		(layer "In11.Cu")
	)
	(gr_line
		(start 372.92407 -138.0744)
		(end 372.936516 -138.093196)
		(stroke
			(width 0.05715)
			(type default)
		)
		(layer "In11.Cu")
	)
	(gr_line
		(start 372.936516 -138.093196)
		(end 372.955312 -138.105642)
		(stroke
			(width 0.05715)
			(type default)
		)
		(layer "In11.Cu")
	)
	(gr_line
		(start 373.176292 -135.995918)
		(end 373.20474 -136.038336)
		(stroke
			(width 0.05715)
			(type default)
		)
		(layer "In11.Cu")
	)
	(gr_line
		(start 373.189754 -132.80771)
		(end 373.206264 -132.818632)
		(stroke
			(width 0.05715)
			(type default)
		)
		(layer "In11.Cu")
	)
	(gr_line
		(start 373.206264 -132.818632)
		(end 373.225568 -132.822696)
		(stroke
			(width 0.05715)
			(type default)
		)
		(layer "In11.Cu")
	)
	(gr_line
		(start 373.952008 -137.14603)
		(end 373.963184 -137.16254)
		(stroke
			(width 0.05715)
			(type default)
		)
		(layer "In11.Cu")
	)
	(gr_line
		(start 373.963184 -137.16254)
		(end 373.979694 -137.173716)
		(stroke
			(width 0.05715)
			(type default)
		)
		(layer "In11.Cu")
	)
	(gr_line
		(start 374.066054 -138.83894)
		(end 374.081548 -138.849354)
		(stroke
			(width 0.05715)
			(type default)
		)
		(layer "In11.Cu")
	)
	(gr_line
		(start 374.081548 -138.849354)
		(end 374.100344 -138.853164)
		(stroke
			(width 0.05715)
			(type default)
		)
		(layer "In11.Cu")
	)
	(gr_line
		(start 374.454928 -134.831582)
		(end 374.513602 -134.890256)
		(stroke
			(width 0.05715)
			(type default)
		)
		(layer "In11.Cu")
	)
	(gr_line
		(start 374.889014 -137.78738)
		(end 374.907556 -137.799826)
		(stroke
			(width 0.05715)
			(type default)
		)
		(layer "In11.Cu")
	)
	(gr_line
		(start 374.907556 -137.799826)
		(end 374.9294 -137.80389)
		(stroke
			(width 0.05715)
			(type default)
		)
		(layer "In11.Cu")
	)
	(gr_line
		(start 374.92178 -141.92758)
		(end 374.947688 -141.93266)
		(stroke
			(width 0.05715)
			(type default)
		)
		(layer "In11.Cu")
	)
	(gr_line
		(start 374.947688 -141.93266)
		(end 374.969532 -141.948916)
		(stroke
			(width 0.05715)
			(type default)
		)
		(layer "In11.Cu")
	)
	(gr_line
		(start 375.214642 -132.928614)
		(end 375.233946 -132.932678)
		(stroke
			(width 0.05715)
			(type default)
		)
		(layer "In11.Cu")
	)
	(gr_line
		(start 375.233946 -132.932678)
		(end 375.250456 -132.9436)
		(stroke
			(width 0.05715)
			(type default)
		)
		(layer "In11.Cu")
	)
	(gr_line
		(start 376.30227 -138.070844)
		(end 376.321066 -138.0744)
		(stroke
			(width 0.05715)
			(type default)
		)
		(layer "In11.Cu")
	)
	(gr_line
		(start 376.321066 -138.0744)
		(end 376.339862 -138.070844)
		(stroke
			(width 0.05715)
			(type default)
		)
		(layer "In11.Cu")
	)
	(gr_line
		(start 376.437652 -134.08025)
		(end 376.454162 -134.091172)
		(stroke
			(width 0.05715)
			(type default)
		)
		(layer "In11.Cu")
	)
	(gr_line
		(start 376.454162 -134.091172)
		(end 376.472958 -134.094728)
		(stroke
			(width 0.05715)
			(type default)
		)
		(layer "In11.Cu")
	)
	(gr_line
		(start 376.75185 -143.622268)
		(end 376.77725 -143.64081)
		(stroke
			(width 0.05715)
			(type default)
		)
		(layer "In11.Cu")
	)
	(gr_line
		(start 376.774964 -30.669484)
		(end 377.181872 -30.262576)
		(stroke
			(width 0.05715)
			(type default)
		)
		(layer "In11.Cu")
	)
	(gr_line
		(start 376.774964 -29.439108)
		(end 377.181872 -29.846016)
		(stroke
			(width 0.05715)
			(type default)
		)
		(layer "In11.Cu")
	)
	(gr_line
		(start 376.77725 -143.64081)
		(end 376.806968 -143.64589)
		(stroke
			(width 0.05715)
			(type default)
		)
		(layer "In11.Cu")
	)
	(gr_line
		(start 376.964702 -32.642302)
		(end 377.373388 -32.771842)
		(stroke
			(width 0.05715)
			(type default)
		)
		(layer "In11.Cu")
	)
	(gr_line
		(start 377.38177 -33.444434)
		(end 377.51131 -33.034986)
		(stroke
			(width 0.05715)
			(type default)
		)
		(layer "In11.Cu")
	)
	(gr_line
		(start 377.555506 -32.679894)
		(end 377.583954 -32.664908)
		(stroke
			(width 0.05715)
			(type default)
		)
		(layer "In11.Cu")
	)
	(gr_line
		(start 377.627134 -134.02818)
		(end 377.64593 -134.031736)
		(stroke
			(width 0.05715)
			(type default)
		)
		(layer "In11.Cu")
	)
	(gr_line
		(start 377.64593 -134.031736)
		(end 377.662694 -134.042658)
		(stroke
			(width 0.05715)
			(type default)
		)
		(layer "In11.Cu")
	)
	(gr_line
		(start 377.69292 -30.900878)
		(end 377.720352 -30.942026)
		(stroke
			(width 0.05715)
			(type default)
		)
		(layer "In11.Cu")
	)
	(gr_line
		(start 378.176282 -32.731964)
		(end 378.257308 -32.748474)
		(stroke
			(width 0.05715)
			(type default)
		)
		(layer "In11.Cu")
	)
	(gr_line
		(start 378.257308 -32.748474)
		(end 378.302266 -32.8168)
		(stroke
			(width 0.05715)
			(type default)
		)
		(layer "In11.Cu")
	)
	(gr_line
		(start 378.495306 -32.11322)
		(end 378.506736 -32.130492)
		(stroke
			(width 0.05715)
			(type default)
		)
		(layer "In11.Cu")
	)
	(gr_line
		(start 378.506736 -32.130492)
		(end 378.524008 -32.141922)
		(stroke
			(width 0.05715)
			(type default)
		)
		(layer "In11.Cu")
	)
	(gr_line
		(start 378.709428 -141.993112)
		(end 378.730764 -141.99743)
		(stroke
			(width 0.05715)
			(type default)
		)
		(layer "In11.Cu")
	)
	(gr_line
		(start 378.730764 -141.99743)
		(end 378.7521 -141.993112)
		(stroke
			(width 0.05715)
			(type default)
		)
		(layer "In11.Cu")
	)
	(gr_line
		(start 378.790708 -137.296906)
		(end 378.809504 -137.29335)
		(stroke
			(width 0.05715)
			(type default)
		)
		(layer "In11.Cu")
	)
	(gr_line
		(start 378.809504 -137.29335)
		(end 378.8283 -137.296906)
		(stroke
			(width 0.05715)
			(type default)
		)
		(layer "In11.Cu")
	)
	(gr_line
		(start 379.016006 -140.590524)
		(end 379.037342 -140.594842)
		(stroke
			(width 0.05715)
			(type default)
		)
		(layer "In11.Cu")
	)
	(gr_line
		(start 379.037342 -140.594842)
		(end 379.058678 -140.590524)
		(stroke
			(width 0.05715)
			(type default)
		)
		(layer "In11.Cu")
	)
	(gr_line
		(start 379.096778 -141.26464)
		(end 379.118114 -141.268958)
		(stroke
			(width 0.05715)
			(type default)
		)
		(layer "In11.Cu")
	)
	(gr_line
		(start 379.118114 -141.268958)
		(end 379.13945 -141.26464)
		(stroke
			(width 0.05715)
			(type default)
		)
		(layer "In11.Cu")
	)
	(gr_line
		(start 379.209046 -139.892024)
		(end 379.230382 -139.896342)
		(stroke
			(width 0.05715)
			(type default)
		)
		(layer "In11.Cu")
	)
	(gr_line
		(start 379.230382 -139.896342)
		(end 379.251718 -139.892024)
		(stroke
			(width 0.05715)
			(type default)
		)
		(layer "In11.Cu")
	)
	(gr_line
		(start 379.249432 -144.08023)
		(end 379.265688 -144.083024)
		(stroke
			(width 0.05715)
			(type default)
		)
		(layer "In11.Cu")
	)
	(gr_line
		(start 379.265688 -144.083024)
		(end 379.281944 -144.079976)
		(stroke
			(width 0.05715)
			(type default)
		)
		(layer "In11.Cu")
	)
	(gr_line
		(start 379.313948 -32.314642)
		(end 379.33122 -32.326072)
		(stroke
			(width 0.05715)
			(type default)
		)
		(layer "In11.Cu")
	)
	(gr_line
		(start 379.33122 -32.326072)
		(end 379.34265 -32.343344)
		(stroke
			(width 0.05715)
			(type default)
		)
		(layer "In11.Cu")
	)
	(gr_line
		(start 379.813566 -136.234678)
		(end 379.854714 -136.26211)
		(stroke
			(width 0.05715)
			(type default)
		)
		(layer "In11.Cu")
	)
	(gr_line
		(start 380.151132 -29.618178)
		(end 380.3142 -29.781246)
		(stroke
			(width 0.05715)
			(type default)
		)
		(layer "In11.Cu")
	)
	(gr_line
		(start 380.151132 -29.232352)
		(end 380.151132 -29.618178)
		(stroke
			(width 0.05715)
			(type default)
		)
		(layer "In11.Cu")
	)
	(gr_line
		(start 380.168404 -30.292294)
		(end 380.168404 -30.629352)
		(stroke
			(width 0.05715)
			(type default)
		)
		(layer "In11.Cu")
	)
	(gr_line
		(start 380.168404 -30.292294)
		(end 380.27483 -30.185868)
		(stroke
			(width 0.05715)
			(type default)
		)
		(layer "In11.Cu")
	)
	(gr_line
		(start 380.27483 -30.185868)
		(end 380.383034 -30.075886)
		(stroke
			(width 0.05715)
			(type default)
		)
		(layer "In11.Cu")
	)
	(gr_line
		(start 380.364238 -141.367002)
		(end 380.414276 -141.356842)
		(stroke
			(width 0.05715)
			(type default)
		)
		(layer "In11.Cu")
	)
	(gr_line
		(start 380.414276 -141.356842)
		(end 380.46152 -141.376146)
		(stroke
			(width 0.05715)
			(type default)
		)
		(layer "In11.Cu")
	)
	(gr_line
		(start 380.483872 -37.497766)
		(end 380.487936 -37.517324)
		(stroke
			(width 0.05715)
			(type default)
		)
		(layer "In11.Cu")
	)
	(gr_line
		(start 380.487936 -37.517324)
		(end 380.498858 -37.533834)
		(stroke
			(width 0.05715)
			(type default)
		)
		(layer "In11.Cu")
	)
	(gr_line
		(start 380.496318 -36.130738)
		(end 380.50724 -36.147248)
		(stroke
			(width 0.05715)
			(type default)
		)
		(layer "In11.Cu")
	)
	(gr_line
		(start 380.50724 -36.147248)
		(end 380.511304 -36.166806)
		(stroke
			(width 0.05715)
			(type default)
		)
		(layer "In11.Cu")
	)
	(gr_line
		(start 380.546356 -34.69005)
		(end 380.591314 -34.758376)
		(stroke
			(width 0.05715)
			(type default)
		)
		(layer "In11.Cu")
	)
	(gr_line
		(start 380.591314 -34.758376)
		(end 380.67234 -34.774886)
		(stroke
			(width 0.05715)
			(type default)
		)
		(layer "In11.Cu")
	)
	(gr_line
		(start 380.65964 -26.097484)
		(end 380.72822 -26.097484)
		(stroke
			(width 0.05715)
			(type default)
		)
		(layer "In11.Cu")
	)
	(gr_line
		(start 380.67107 -25.278588)
		(end 380.73203 -25.278588)
		(stroke
			(width 0.05715)
			(type default)
		)
		(layer "In11.Cu")
	)
	(gr_line
		(start 380.69393 -22.707854)
		(end 380.96825 -22.982174)
		(stroke
			(width 0.05715)
			(type default)
		)
		(layer "In11.Cu")
	)
	(gr_line
		(start 380.69393 -22.291294)
		(end 380.96825 -22.016974)
		(stroke
			(width 0.05715)
			(type default)
		)
		(layer "In11.Cu")
	)
	(gr_line
		(start 380.72822 -26.097484)
		(end 380.931166 -25.894538)
		(stroke
			(width 0.05715)
			(type default)
		)
		(layer "In11.Cu")
	)
	(gr_line
		(start 380.728474 -137.666222)
		(end 380.750318 -137.67054)
		(stroke
			(width 0.05715)
			(type default)
		)
		(layer "In11.Cu")
	)
	(gr_line
		(start 380.73203 -25.278588)
		(end 380.931166 -25.477724)
		(stroke
			(width 0.05715)
			(type default)
		)
		(layer "In11.Cu")
	)
	(gr_line
		(start 380.750318 -137.67054)
		(end 380.768098 -137.682478)
		(stroke
			(width 0.05715)
			(type default)
		)
		(layer "In11.Cu")
	)
	(gr_line
		(start 380.863856 -143.480536)
		(end 380.882652 -143.47698)
		(stroke
			(width 0.05715)
			(type default)
		)
		(layer "In11.Cu")
	)
	(gr_line
		(start 380.882652 -143.47698)
		(end 380.90094 -143.48079)
		(stroke
			(width 0.05715)
			(type default)
		)
		(layer "In11.Cu")
	)
	(gr_line
		(start 381.11557 -29.054552)
		(end 381.345948 -28.824174)
		(stroke
			(width 0.05715)
			(type default)
		)
		(layer "In11.Cu")
	)
	(gr_line
		(start 381.11557 -28.176982)
		(end 381.345948 -28.40736)
		(stroke
			(width 0.05715)
			(type default)
		)
		(layer "In11.Cu")
	)
	(gr_line
		(start 381.1778 -32.610806)
		(end 381.669798 -33.102804)
		(stroke
			(width 0.05715)
			(type default)
		)
		(layer "In11.Cu")
	)
	(gr_line
		(start 381.1778 -32.3215)
		(end 381.1778 -32.610806)
		(stroke
			(width 0.05715)
			(type default)
		)
		(layer "In11.Cu")
	)
	(gr_line
		(start 381.204724 -33.511744)
		(end 381.204724 -33.868106)
		(stroke
			(width 0.05715)
			(type default)
		)
		(layer "In11.Cu")
	)
	(gr_line
		(start 381.204724 -33.511744)
		(end 381.319024 -33.397444)
		(stroke
			(width 0.05715)
			(type default)
		)
		(layer "In11.Cu")
	)
	(gr_line
		(start 381.242316 -138.354816)
		(end 381.259334 -138.366246)
		(stroke
			(width 0.05715)
			(type default)
		)
		(layer "In11.Cu")
	)
	(gr_line
		(start 381.259334 -138.366246)
		(end 381.2794 -138.370056)
		(stroke
			(width 0.05715)
			(type default)
		)
		(layer "In11.Cu")
	)
	(gr_line
		(start 381.319024 -33.397444)
		(end 381.377698 -33.397444)
		(stroke
			(width 0.05715)
			(type default)
		)
		(layer "In11.Cu")
	)
	(gr_line
		(start 381.57023 -137.74801)
		(end 381.58674 -137.758932)
		(stroke
			(width 0.05715)
			(type default)
		)
		(layer "In11.Cu")
	)
	(gr_line
		(start 381.58674 -137.758932)
		(end 381.606298 -137.762996)
		(stroke
			(width 0.05715)
			(type default)
		)
		(layer "In11.Cu")
	)
	(gr_line
		(start 381.712978 -137.073894)
		(end 381.729488 -137.084816)
		(stroke
			(width 0.05715)
			(type default)
		)
		(layer "In11.Cu")
	)
	(gr_line
		(start 381.729488 -137.084816)
		(end 381.748792 -137.08888)
		(stroke
			(width 0.05715)
			(type default)
		)
		(layer "In11.Cu")
	)
	(gr_line
		(start 381.762508 -139.08278)
		(end 381.783844 -139.078462)
		(stroke
			(width 0.05715)
			(type default)
		)
		(layer "In11.Cu")
	)
	(gr_line
		(start 381.783844 -139.078462)
		(end 381.80518 -139.08278)
		(stroke
			(width 0.05715)
			(type default)
		)
		(layer "In11.Cu")
	)
	(gr_line
		(start 381.786638 -139.73683)
		(end 381.807974 -139.732512)
		(stroke
			(width 0.05715)
			(type default)
		)
		(layer "In11.Cu")
	)
	(gr_line
		(start 381.807974 -139.732512)
		(end 381.82931 -139.73683)
		(stroke
			(width 0.05715)
			(type default)
		)
		(layer "In11.Cu")
	)
	(gr_line
		(start 381.824738 -34.711132)
		(end 381.90805 -34.72815)
		(stroke
			(width 0.05715)
			(type default)
		)
		(layer "In11.Cu")
	)
	(gr_line
		(start 381.877824 -140.408914)
		(end 381.89916 -140.404596)
		(stroke
			(width 0.05715)
			(type default)
		)
		(layer "In11.Cu")
	)
	(gr_line
		(start 381.89916 -140.404596)
		(end 381.920496 -140.408914)
		(stroke
			(width 0.05715)
			(type default)
		)
		(layer "In11.Cu")
	)
	(gr_line
		(start 381.90805 -34.72815)
		(end 381.954786 -34.798762)
		(stroke
			(width 0.05715)
			(type default)
		)
		(layer "In11.Cu")
	)
	(gr_line
		(start 383.066036 -41.413176)
		(end 383.112772 -41.483788)
		(stroke
			(width 0.05715)
			(type default)
		)
		(layer "In11.Cu")
	)
	(gr_line
		(start 383.112772 -41.483788)
		(end 383.196084 -41.500806)
		(stroke
			(width 0.05715)
			(type default)
		)
		(layer "In11.Cu")
	)
	(gr_line
		(start 383.159762 -39.79926)
		(end 383.17678 -39.715694)
		(stroke
			(width 0.05715)
			(type default)
		)
		(layer "In11.Cu")
	)
	(gr_line
		(start 383.159762 -39.79926)
		(end 383.206498 -39.870126)
		(stroke
			(width 0.05715)
			(type default)
		)
		(layer "In11.Cu")
	)
	(gr_line
		(start 383.661666 -40.557958)
		(end 383.708656 -40.628824)
		(stroke
			(width 0.05715)
			(type default)
		)
		(layer "In11.Cu")
	)
	(gr_line
		(start 383.708656 -40.628824)
		(end 383.791714 -40.645842)
		(stroke
			(width 0.05715)
			(type default)
		)
		(layer "In11.Cu")
	)
	(gr_line
		(start 383.835656 -37.64026)
		(end 383.836164 -37.641276)
		(stroke
			(width 0.05715)
			(type default)
		)
		(layer "In11.Cu")
	)
	(gr_line
		(start 383.836164 -37.641784)
		(end 383.8829 -37.712142)
		(stroke
			(width 0.05715)
			(type default)
		)
		(layer "In11.Cu")
	)
	(gr_line
		(start 383.866136 -37.792406)
		(end 383.882646 -37.712142)
		(stroke
			(width 0.05715)
			(type default)
		)
		(layer "In11.Cu")
	)
	(gr_line
		(start 383.882646 -37.712142)
		(end 383.8829 -37.712142)
		(stroke
			(width 0.05715)
			(type default)
		)
		(layer "In11.Cu")
	)
	(gr_line
		(start 384.322828 -17.324578)
		(end 384.485388 -17.487138)
		(stroke
			(width 0.05715)
			(type default)
		)
		(layer "In11.Cu")
	)
	(gr_line
		(start 384.33375 -41.43375)
		(end 384.417062 -41.450768)
		(stroke
			(width 0.05715)
			(type default)
		)
		(layer "In11.Cu")
	)
	(gr_line
		(start 384.417062 -41.450768)
		(end 384.463798 -41.52138)
		(stroke
			(width 0.05715)
			(type default)
		)
		(layer "In11.Cu")
	)
	(gr_line
		(start 384.485388 -17.487138)
		(end 384.828288 -17.487138)
		(stroke
			(width 0.05715)
			(type default)
		)
		(layer "In11.Cu")
	)
	(gr_line
		(start 384.614928 -17.029938)
		(end 384.698748 -17.029938)
		(stroke
			(width 0.05715)
			(type default)
		)
		(layer "In11.Cu")
	)
	(gr_line
		(start 384.828288 -17.487138)
		(end 384.990848 -17.324578)
		(stroke
			(width 0.05715)
			(type default)
		)
		(layer "In11.Cu")
	)
	(gr_line
		(start 384.98526 -40.590216)
		(end 385.066032 -40.606726)
		(stroke
			(width 0.05715)
			(type default)
		)
		(layer "In11.Cu")
	)
	(gr_line
		(start 385.066032 -40.606726)
		(end 385.11099 -40.675052)
		(stroke
			(width 0.05715)
			(type default)
		)
		(layer "In11.Cu")
	)
	(gr_line
		(start 385.338828 -17.324578)
		(end 385.501388 -17.487138)
		(stroke
			(width 0.05715)
			(type default)
		)
		(layer "In11.Cu")
	)
	(gr_line
		(start 385.501388 -17.487138)
		(end 385.844288 -17.487138)
		(stroke
			(width 0.05715)
			(type default)
		)
		(layer "In11.Cu")
	)
	(gr_line
		(start 385.630928 -17.029938)
		(end 385.714748 -17.029938)
		(stroke
			(width 0.05715)
			(type default)
		)
		(layer "In11.Cu")
	)
	(gr_line
		(start 385.647946 -143.809212)
		(end 385.665472 -143.816324)
		(stroke
			(width 0.05715)
			(type default)
		)
		(layer "In11.Cu")
	)
	(gr_line
		(start 385.672584 -39.647368)
		(end 385.835144 -39.809928)
		(stroke
			(width 0.05715)
			(type default)
		)
		(layer "In11.Cu")
	)
	(gr_line
		(start 385.672584 -39.304468)
		(end 385.672584 -39.647368)
		(stroke
			(width 0.05715)
			(type default)
		)
		(layer "In11.Cu")
	)
	(gr_line
		(start 385.672584 -39.304468)
		(end 385.835144 -39.141908)
		(stroke
			(width 0.05715)
			(type default)
		)
		(layer "In11.Cu")
	)
	(gr_line
		(start 385.672584 -38.631368)
		(end 385.835144 -38.793928)
		(stroke
			(width 0.05715)
			(type default)
		)
		(layer "In11.Cu")
	)
	(gr_line
		(start 385.672584 -38.288468)
		(end 385.672584 -38.631368)
		(stroke
			(width 0.05715)
			(type default)
		)
		(layer "In11.Cu")
	)
	(gr_line
		(start 385.672584 -38.288468)
		(end 385.835144 -38.125908)
		(stroke
			(width 0.05715)
			(type default)
		)
		(layer "In11.Cu")
	)
	(gr_line
		(start 385.672584 -37.615368)
		(end 385.835144 -37.777928)
		(stroke
			(width 0.05715)
			(type default)
		)
		(layer "In11.Cu")
	)
	(gr_line
		(start 385.672584 -37.272468)
		(end 385.672584 -37.615368)
		(stroke
			(width 0.05715)
			(type default)
		)
		(layer "In11.Cu")
	)
	(gr_line
		(start 385.672584 -37.272468)
		(end 385.835144 -37.109908)
		(stroke
			(width 0.05715)
			(type default)
		)
		(layer "In11.Cu")
	)
	(gr_line
		(start 385.844288 -17.487138)
		(end 386.006848 -17.324578)
		(stroke
			(width 0.05715)
			(type default)
		)
		(layer "In11.Cu")
	)
	(gr_line
		(start 386.129784 -39.434008)
		(end 386.129784 -39.517828)
		(stroke
			(width 0.05715)
			(type default)
		)
		(layer "In11.Cu")
	)
	(gr_line
		(start 386.129784 -38.418008)
		(end 386.129784 -38.501828)
		(stroke
			(width 0.05715)
			(type default)
		)
		(layer "In11.Cu")
	)
	(gr_line
		(start 386.129784 -37.402008)
		(end 386.129784 -37.485828)
		(stroke
			(width 0.05715)
			(type default)
		)
		(layer "In11.Cu")
	)
	(gr_line
		(start 386.470906 -45.084238)
		(end 386.517642 -45.15485)
		(stroke
			(width 0.05715)
			(type default)
		)
		(layer "In11.Cu")
	)
	(gr_line
		(start 386.517642 -45.15485)
		(end 386.600954 -45.171868)
		(stroke
			(width 0.05715)
			(type default)
		)
		(layer "In11.Cu")
	)
	(gr_line
		(start 386.693918 -43.594274)
		(end 386.738876 -43.6626)
		(stroke
			(width 0.05715)
			(type default)
		)
		(layer "In11.Cu")
	)
	(gr_line
		(start 386.738876 -43.6626)
		(end 386.819648 -43.67911)
		(stroke
			(width 0.05715)
			(type default)
		)
		(layer "In11.Cu")
	)
	(gr_line
		(start 387.403594 -16.45158)
		(end 387.566154 -16.61414)
		(stroke
			(width 0.05715)
			(type default)
		)
		(layer "In11.Cu")
	)
	(gr_line
		(start 387.484366 -125.737112)
		(end 387.525768 -125.69571)
		(stroke
			(width 0.04445)
			(type default)
		)
		(layer "In11.Cu")
	)
	(gr_line
		(start 387.486144 -126.008384)
		(end 387.608318 -126.008384)
		(stroke
			(width 0.04445)
			(type default)
		)
		(layer "In11.Cu")
	)
	(gr_line
		(start 387.50875 -127.74295)
		(end 387.54812 -127.78232)
		(stroke
			(width 0.04445)
			(type default)
		)
		(layer "In11.Cu")
	)
	(gr_line
		(start 387.50875 -127.55245)
		(end 387.54812 -127.51308)
		(stroke
			(width 0.04445)
			(type default)
		)
		(layer "In11.Cu")
	)
	(gr_line
		(start 387.549898 -127.784098)
		(end 387.731 -127.9652)
		(stroke
			(width 0.04445)
			(type default)
		)
		(layer "In11.Cu")
	)
	(gr_line
		(start 387.549898 -127.511302)
		(end 387.731 -127.3302)
		(stroke
			(width 0.04445)
			(type default)
		)
		(layer "In11.Cu")
	)
	(gr_line
		(start 387.566154 -16.61414)
		(end 387.909054 -16.61414)
		(stroke
			(width 0.05715)
			(type default)
		)
		(layer "In11.Cu")
	)
	(gr_line
		(start 387.608318 -126.008384)
		(end 387.79704 -125.819662)
		(stroke
			(width 0.04445)
			(type default)
		)
		(layer "In11.Cu")
	)
	(gr_line
		(start 387.695694 -16.15694)
		(end 387.779514 -16.15694)
		(stroke
			(width 0.05715)
			(type default)
		)
		(layer "In11.Cu")
	)
	(gr_line
		(start 387.734302 -30.300676)
		(end 387.734302 -30.675326)
		(stroke
			(width 0.05715)
			(type default)
		)
		(layer "In11.Cu")
	)
	(gr_line
		(start 387.734302 -30.300676)
		(end 387.786372 -30.248606)
		(stroke
			(width 0.05715)
			(type default)
		)
		(layer "In11.Cu")
	)
	(gr_line
		(start 387.734302 -29.779976)
		(end 387.786372 -29.832046)
		(stroke
			(width 0.05715)
			(type default)
		)
		(layer "In11.Cu")
	)
	(gr_line
		(start 387.734302 -29.405326)
		(end 387.734302 -29.779976)
		(stroke
			(width 0.05715)
			(type default)
		)
		(layer "In11.Cu")
	)
	(gr_line
		(start 387.734302 -26.633678)
		(end 387.965188 -26.864564)
		(stroke
			(width 0.05715)
			(type default)
		)
		(layer "In11.Cu")
	)
	(gr_line
		(start 387.734302 -26.405332)
		(end 387.734302 -26.633678)
		(stroke
			(width 0.05715)
			(type default)
		)
		(layer "In11.Cu")
	)
	(gr_line
		(start 387.740906 -24.53259)
		(end 387.792976 -24.58466)
		(stroke
			(width 0.05715)
			(type default)
		)
		(layer "In11.Cu")
	)
	(gr_line
		(start 387.740906 -24.11603)
		(end 387.792976 -24.06396)
		(stroke
			(width 0.05715)
			(type default)
		)
		(layer "In11.Cu")
	)
	(gr_line
		(start 387.792976 -24.58466)
		(end 387.792976 -24.95931)
		(stroke
			(width 0.05715)
			(type default)
		)
		(layer "In11.Cu")
	)
	(gr_line
		(start 387.792976 -23.68931)
		(end 387.792976 -24.06396)
		(stroke
			(width 0.05715)
			(type default)
		)
		(layer "In11.Cu")
	)
	(gr_line
		(start 387.79704 -125.697488)
		(end 387.79704 -125.819662)
		(stroke
			(width 0.04445)
			(type default)
		)
		(layer "In11.Cu")
	)
	(gr_line
		(start 387.810502 -27.43581)
		(end 387.810502 -27.675332)
		(stroke
			(width 0.05715)
			(type default)
		)
		(layer "In11.Cu")
	)
	(gr_line
		(start 387.810502 -27.43581)
		(end 387.965188 -27.281124)
		(stroke
			(width 0.05715)
			(type default)
		)
		(layer "In11.Cu")
	)
	(gr_line
		(start 387.909054 -16.61414)
		(end 388.071614 -16.45158)
		(stroke
			(width 0.05715)
			(type default)
		)
		(layer "In11.Cu")
	)
	(gr_line
		(start 387.987286 -125.234192)
		(end 388.028688 -125.19279)
		(stroke
			(width 0.04445)
			(type default)
		)
		(layer "In11.Cu")
	)
	(gr_line
		(start 387.989064 -125.505464)
		(end 388.111238 -125.505464)
		(stroke
			(width 0.04445)
			(type default)
		)
		(layer "In11.Cu")
	)
	(gr_line
		(start 388.111238 -125.505464)
		(end 388.29996 -125.316742)
		(stroke
			(width 0.04445)
			(type default)
		)
		(layer "In11.Cu")
	)
	(gr_line
		(start 388.29996 -125.194568)
		(end 388.29996 -125.316742)
		(stroke
			(width 0.04445)
			(type default)
		)
		(layer "In11.Cu")
	)
	(gr_line
		(start 388.419594 -16.45158)
		(end 388.582154 -16.61414)
		(stroke
			(width 0.05715)
			(type default)
		)
		(layer "In11.Cu")
	)
	(gr_line
		(start 388.582154 -16.61414)
		(end 388.925054 -16.61414)
		(stroke
			(width 0.05715)
			(type default)
		)
		(layer "In11.Cu")
	)
	(gr_line
		(start 388.584694 -144.161256)
		(end 388.607808 -144.172178)
		(stroke
			(width 0.05715)
			(type default)
		)
		(layer "In11.Cu")
	)
	(gr_line
		(start 388.711694 -16.15694)
		(end 388.795514 -16.15694)
		(stroke
			(width 0.05715)
			(type default)
		)
		(layer "In11.Cu")
	)
	(gr_line
		(start 388.827772 -143.524224)
		(end 388.851902 -143.5354)
		(stroke
			(width 0.05715)
			(type default)
		)
		(layer "In11.Cu")
	)
	(gr_line
		(start 388.925054 -16.61414)
		(end 389.087614 -16.45158)
		(stroke
			(width 0.05715)
			(type default)
		)
		(layer "In11.Cu")
	)
	(gr_line
		(start 388.93877 -127.40894)
		(end 389.04799 -127.51816)
		(stroke
			(width 0.05715)
			(type default)
		)
		(layer "In11.Cu")
	)
	(gr_line
		(start 388.93877 -126.99238)
		(end 389.04799 -126.88316)
		(stroke
			(width 0.05715)
			(type default)
		)
		(layer "In11.Cu")
	)
	(gr_line
		(start 389.29437 -45.421296)
		(end 389.375142 -45.437806)
		(stroke
			(width 0.05715)
			(type default)
		)
		(layer "In11.Cu")
	)
	(gr_line
		(start 389.375142 -45.437806)
		(end 389.4201 -45.506132)
		(stroke
			(width 0.05715)
			(type default)
		)
		(layer "In11.Cu")
	)
	(gr_line
		(start 389.419592 -43.909742)
		(end 389.502904 -43.92676)
		(stroke
			(width 0.05715)
			(type default)
		)
		(layer "In11.Cu")
	)
	(gr_line
		(start 389.435594 -16.45158)
		(end 389.598154 -16.61414)
		(stroke
			(width 0.05715)
			(type default)
		)
		(layer "In11.Cu")
	)
	(gr_line
		(start 389.502904 -43.92676)
		(end 389.54964 -43.997372)
		(stroke
			(width 0.05715)
			(type default)
		)
		(layer "In11.Cu")
	)
	(gr_line
		(start 389.557514 -124.61494)
		(end 389.643874 -124.7013)
		(stroke
			(width 0.04445)
			(type default)
		)
		(layer "In11.Cu")
	)
	(gr_line
		(start 389.598154 -16.61414)
		(end 389.941054 -16.61414)
		(stroke
			(width 0.05715)
			(type default)
		)
		(layer "In11.Cu")
	)
	(gr_line
		(start 389.643874 -124.7013)
		(end 389.910574 -124.7013)
		(stroke
			(width 0.04445)
			(type default)
		)
		(layer "In11.Cu")
	)
	(gr_line
		(start 389.727694 -16.15694)
		(end 389.811514 -16.15694)
		(stroke
			(width 0.05715)
			(type default)
		)
		(layer "In11.Cu")
	)
	(gr_line
		(start 389.748014 -124.4219)
		(end 389.806434 -124.4219)
		(stroke
			(width 0.04445)
			(type default)
		)
		(layer "In11.Cu")
	)
	(gr_line
		(start 389.812784 -144.73428)
		(end 389.857996 -144.755362)
		(stroke
			(width 0.05715)
			(type default)
		)
		(layer "In11.Cu")
	)
	(gr_line
		(start 389.857996 -144.755362)
		(end 389.884158 -144.797526)
		(stroke
			(width 0.05715)
			(type default)
		)
		(layer "In11.Cu")
	)
	(gr_line
		(start 389.910574 -124.7013)
		(end 389.996934 -124.61494)
		(stroke
			(width 0.04445)
			(type default)
		)
		(layer "In11.Cu")
	)
	(gr_line
		(start 389.941054 -16.61414)
		(end 390.103614 -16.45158)
		(stroke
			(width 0.05715)
			(type default)
		)
		(layer "In11.Cu")
	)
	(gr_line
		(start 390.149334 -145.779744)
		(end 390.177528 -145.82521)
		(stroke
			(width 0.05715)
			(type default)
		)
		(layer "In11.Cu")
	)
	(gr_line
		(start 390.177528 -145.82521)
		(end 390.226042 -145.846292)
		(stroke
			(width 0.05715)
			(type default)
		)
		(layer "In11.Cu")
	)
	(gr_line
		(start 390.223502 -144.175988)
		(end 390.268714 -144.19707)
		(stroke
			(width 0.05715)
			(type default)
		)
		(layer "In11.Cu")
	)
	(gr_line
		(start 390.268714 -144.19707)
		(end 390.294876 -144.239234)
		(stroke
			(width 0.05715)
			(type default)
		)
		(layer "In11.Cu")
	)
	(gr_line
		(start 390.268714 -124.61494)
		(end 390.355074 -124.7013)
		(stroke
			(width 0.04445)
			(type default)
		)
		(layer "In11.Cu")
	)
	(gr_line
		(start 390.278874 -141.227556)
		(end 390.279382 -141.22781)
		(stroke
			(width 0.05715)
			(type default)
		)
		(layer "In11.Cu")
	)
	(gr_line
		(start 390.355074 -124.7013)
		(end 390.621774 -124.7013)
		(stroke
			(width 0.04445)
			(type default)
		)
		(layer "In11.Cu")
	)
	(gr_line
		(start 390.36498 -140.587476)
		(end 390.365488 -140.58773)
		(stroke
			(width 0.05715)
			(type default)
		)
		(layer "In11.Cu")
	)
	(gr_line
		(start 390.451086 -139.94511)
		(end 390.45134 -139.94511)
		(stroke
			(width 0.05715)
			(type default)
		)
		(layer "In11.Cu")
	)
	(gr_line
		(start 390.451594 -16.45158)
		(end 390.614154 -16.61414)
		(stroke
			(width 0.05715)
			(type default)
		)
		(layer "In11.Cu")
	)
	(gr_line
		(start 390.459214 -124.4219)
		(end 390.517634 -124.4219)
		(stroke
			(width 0.04445)
			(type default)
		)
		(layer "In11.Cu")
	)
	(gr_line
		(start 390.46531 -145.06829)
		(end 390.493504 -145.113756)
		(stroke
			(width 0.05715)
			(type default)
		)
		(layer "In11.Cu")
	)
	(gr_line
		(start 390.493504 -145.113756)
		(end 390.542526 -145.135092)
		(stroke
			(width 0.05715)
			(type default)
		)
		(layer "In11.Cu")
	)
	(gr_line
		(start 390.53643 -139.31011)
		(end 390.536684 -139.31011)
		(stroke
			(width 0.05715)
			(type default)
		)
		(layer "In11.Cu")
	)
	(gr_line
		(start 390.614154 -16.61414)
		(end 390.957054 -16.61414)
		(stroke
			(width 0.05715)
			(type default)
		)
		(layer "In11.Cu")
	)
	(gr_line
		(start 390.62152 -138.67511)
		(end 390.621774 -138.67511)
		(stroke
			(width 0.05715)
			(type default)
		)
		(layer "In11.Cu")
	)
	(gr_line
		(start 390.621774 -124.7013)
		(end 390.708134 -124.61494)
		(stroke
			(width 0.04445)
			(type default)
		)
		(layer "In11.Cu")
	)
	(gr_line
		(start 390.70661 -138.04011)
		(end 390.706864 -138.04011)
		(stroke
			(width 0.05715)
			(type default)
		)
		(layer "In11.Cu")
	)
	(gr_line
		(start 390.743694 -16.15694)
		(end 390.827514 -16.15694)
		(stroke
			(width 0.05715)
			(type default)
		)
		(layer "In11.Cu")
	)
	(gr_line
		(start 390.871202 -50.67046)
		(end 390.887712 -50.58918)
		(stroke
			(width 0.05715)
			(type default)
		)
		(layer "In11.Cu")
	)
	(gr_line
		(start 390.871202 -50.67046)
		(end 390.916922 -50.739294)
		(stroke
			(width 0.05715)
			(type default)
		)
		(layer "In11.Cu")
	)
	(gr_line
		(start 390.918192 -43.739562)
		(end 390.94537 -43.78071)
		(stroke
			(width 0.05715)
			(type default)
		)
		(layer "In11.Cu")
	)
	(gr_line
		(start 390.957054 -16.61414)
		(end 391.119614 -16.45158)
		(stroke
			(width 0.05715)
			(type default)
		)
		(layer "In11.Cu")
	)
	(gr_line
		(start 390.979914 -124.61494)
		(end 391.066274 -124.7013)
		(stroke
			(width 0.04445)
			(type default)
		)
		(layer "In11.Cu")
	)
	(gr_line
		(start 391.040874 -129.645918)
		(end 391.040874 -129.704338)
		(stroke
			(width 0.04445)
			(type default)
		)
		(layer "In11.Cu")
	)
	(gr_line
		(start 391.066274 -124.7013)
		(end 391.332974 -124.7013)
		(stroke
			(width 0.04445)
			(type default)
		)
		(layer "In11.Cu")
	)
	(gr_line
		(start 391.125456 -146.235928)
		(end 391.14476 -146.244564)
		(stroke
			(width 0.05715)
			(type default)
		)
		(layer "In11.Cu")
	)
	(gr_line
		(start 391.170414 -124.4219)
		(end 391.228834 -124.4219)
		(stroke
			(width 0.04445)
			(type default)
		)
		(layer "In11.Cu")
	)
	(gr_line
		(start 391.233914 -129.894838)
		(end 391.320274 -129.808478)
		(stroke
			(width 0.04445)
			(type default)
		)
		(layer "In11.Cu")
	)
	(gr_line
		(start 391.233914 -129.455418)
		(end 391.320274 -129.541778)
		(stroke
			(width 0.04445)
			(type default)
		)
		(layer "In11.Cu")
	)
	(gr_line
		(start 391.296906 -128.778)
		(end 391.78865 -128.778)
		(stroke
			(width 0.04445)
			(type default)
		)
		(layer "In11.Cu")
	)
	(gr_line
		(start 391.320274 -129.541778)
		(end 391.320274 -129.808478)
		(stroke
			(width 0.04445)
			(type default)
		)
		(layer "In11.Cu")
	)
	(gr_line
		(start 391.332974 -124.7013)
		(end 391.419334 -124.61494)
		(stroke
			(width 0.04445)
			(type default)
		)
		(layer "In11.Cu")
	)
	(gr_line
		(start 391.355326 -128.99263)
		(end 391.439654 -128.99263)
		(stroke
			(width 0.04445)
			(type default)
		)
		(layer "In11.Cu")
	)
	(gr_line
		(start 391.388854 -145.502376)
		(end 391.39241 -145.5039)
		(stroke
			(width 0.05715)
			(type default)
		)
		(layer "In11.Cu")
	)
	(gr_line
		(start 391.39241 -145.5039)
		(end 391.39622 -145.504408)
		(stroke
			(width 0.05715)
			(type default)
		)
		(layer "In11.Cu")
	)
	(gr_line
		(start 391.42162 -130.888994)
		(end 391.463022 -130.930396)
		(stroke
			(width 0.04445)
			(type default)
		)
		(layer "In11.Cu")
	)
	(gr_line
		(start 391.423398 -130.617722)
		(end 391.545572 -130.617722)
		(stroke
			(width 0.04445)
			(type default)
		)
		(layer "In11.Cu")
	)
	(gr_line
		(start 391.439654 -128.99263)
		(end 391.62355 -129.176526)
		(stroke
			(width 0.04445)
			(type default)
		)
		(layer "In11.Cu")
	)
	(gr_line
		(start 391.515854 -48.67148)
		(end 391.561828 -48.741076)
		(stroke
			(width 0.05715)
			(type default)
		)
		(layer "In11.Cu")
	)
	(gr_line
		(start 391.516108 -48.671734)
		(end 391.516108 -48.671988)
		(stroke
			(width 0.05715)
			(type default)
		)
		(layer "In11.Cu")
	)
	(gr_line
		(start 391.545318 -48.821848)
		(end 391.561828 -48.741076)
		(stroke
			(width 0.05715)
			(type default)
		)
		(layer "In11.Cu")
	)
	(gr_line
		(start 391.545572 -130.617722)
		(end 391.734294 -130.806444)
		(stroke
			(width 0.04445)
			(type default)
		)
		(layer "In11.Cu")
	)
	(gr_line
		(start 391.62355 -129.176526)
		(end 391.728706 -129.176526)
		(stroke
			(width 0.04445)
			(type default)
		)
		(layer "In11.Cu")
	)
	(gr_line
		(start 391.66165 -51.865276)
		(end 391.70864 -51.936142)
		(stroke
			(width 0.05715)
			(type default)
		)
		(layer "In11.Cu")
	)
	(gr_line
		(start 391.70864 -51.936142)
		(end 391.791952 -51.95316)
		(stroke
			(width 0.05715)
			(type default)
		)
		(layer "In11.Cu")
	)
	(gr_line
		(start 391.728706 -129.176526)
		(end 391.78865 -129.23647)
		(stroke
			(width 0.04445)
			(type default)
		)
		(layer "In11.Cu")
	)
	(gr_line
		(start 391.734294 -130.806444)
		(end 391.734294 -130.928618)
		(stroke
			(width 0.04445)
			(type default)
		)
		(layer "In11.Cu")
	)
	(gr_line
		(start 391.78865 -129.23647)
		(end 391.78865 -129.4384)
		(stroke
			(width 0.04445)
			(type default)
		)
		(layer "In11.Cu")
	)
	(gr_line
		(start 391.78865 -127.411226)
		(end 391.78865 -127.4826)
		(stroke
			(width 0.04445)
			(type default)
		)
		(layer "In11.Cu")
	)
	(gr_line
		(start 391.78865 -127.411226)
		(end 391.933938 -127.265938)
		(stroke
			(width 0.04445)
			(type default)
		)
		(layer "In11.Cu")
	)
	(gr_line
		(start 391.78865 -126.8476)
		(end 391.933938 -126.992888)
		(stroke
			(width 0.04445)
			(type default)
		)
		(layer "In11.Cu")
	)
	(gr_line
		(start 391.935716 -127.26416)
		(end 391.987786 -127.21209)
		(stroke
			(width 0.04445)
			(type default)
		)
		(layer "In11.Cu")
	)
	(gr_line
		(start 391.935716 -126.994666)
		(end 391.96264 -127.02159)
		(stroke
			(width 0.04445)
			(type default)
		)
		(layer "In11.Cu")
	)
	(gr_line
		(start 392.214608 -127.325374)
		(end 392.214608 -127.40386)
		(stroke
			(width 0.04445)
			(type default)
		)
		(layer "In11.Cu")
	)
	(gr_line
		(start 392.291062 -131.217162)
		(end 392.377422 -131.130802)
		(stroke
			(width 0.04445)
			(type default)
		)
		(layer "In11.Cu")
	)
	(gr_line
		(start 392.35507 -129.598166)
		(end 392.44143 -129.684526)
		(stroke
			(width 0.04445)
			(type default)
		)
		(layer "In11.Cu")
	)
	(gr_line
		(start 392.35507 -129.331466)
		(end 392.35507 -129.598166)
		(stroke
			(width 0.04445)
			(type default)
		)
		(layer "In11.Cu")
	)
	(gr_line
		(start 392.35507 -129.331466)
		(end 392.44143 -129.245106)
		(stroke
			(width 0.04445)
			(type default)
		)
		(layer "In11.Cu")
	)
	(gr_line
		(start 392.35507 -128.886966)
		(end 392.44143 -128.973326)
		(stroke
			(width 0.04445)
			(type default)
		)
		(layer "In11.Cu")
	)
	(gr_line
		(start 392.35507 -128.620266)
		(end 392.35507 -128.886966)
		(stroke
			(width 0.04445)
			(type default)
		)
		(layer "In11.Cu")
	)
	(gr_line
		(start 392.35507 -128.620266)
		(end 392.44143 -128.533906)
		(stroke
			(width 0.04445)
			(type default)
		)
		(layer "In11.Cu")
	)
	(gr_line
		(start 392.377422 -131.130802)
		(end 392.644122 -131.130802)
		(stroke
			(width 0.04445)
			(type default)
		)
		(layer "In11.Cu")
	)
	(gr_line
		(start 392.39317 -130.004566)
		(end 392.39317 -130.015742)
		(stroke
			(width 0.04445)
			(type default)
		)
		(layer "In11.Cu")
	)
	(gr_line
		(start 392.39317 -130.004566)
		(end 392.408156 -129.98958)
		(stroke
			(width 0.04445)
			(type default)
		)
		(layer "In11.Cu")
	)
	(gr_line
		(start 392.4046 -127.483362)
		(end 392.4046 -127.59436)
		(stroke
			(width 0.04445)
			(type default)
		)
		(layer "In11.Cu")
	)
	(gr_line
		(start 392.409934 -129.987802)
		(end 392.44397 -129.953766)
		(stroke
			(width 0.04445)
			(type default)
		)
		(layer "In11.Cu")
	)
	(gr_line
		(start 392.481562 -131.410202)
		(end 392.539982 -131.410202)
		(stroke
			(width 0.04445)
			(type default)
		)
		(layer "In11.Cu")
	)
	(gr_line
		(start 392.552174 -49.063402)
		(end 392.59891 -49.134014)
		(stroke
			(width 0.05715)
			(type default)
		)
		(layer "In11.Cu")
	)
	(gr_line
		(start 392.59891 -49.134014)
		(end 392.682222 -49.151032)
		(stroke
			(width 0.05715)
			(type default)
		)
		(layer "In11.Cu")
	)
	(gr_line
		(start 392.6078 -126.449582)
		(end 392.6078 -126.508002)
		(stroke
			(width 0.04445)
			(type default)
		)
		(layer "In11.Cu")
	)
	(gr_line
		(start 392.6078 -125.738382)
		(end 392.6078 -125.796802)
		(stroke
			(width 0.04445)
			(type default)
		)
		(layer "In11.Cu")
	)
	(gr_line
		(start 392.63447 -129.942844)
		(end 392.679428 -129.987802)
		(stroke
			(width 0.04445)
			(type default)
		)
		(layer "In11.Cu")
	)
	(gr_line
		(start 392.63447 -129.435606)
		(end 392.63447 -129.494026)
		(stroke
			(width 0.04445)
			(type default)
		)
		(layer "In11.Cu")
	)
	(gr_line
		(start 392.63447 -128.724406)
		(end 392.63447 -128.782826)
		(stroke
			(width 0.04445)
			(type default)
		)
		(layer "In11.Cu")
	)
	(gr_line
		(start 392.644122 -131.130802)
		(end 392.730482 -131.217162)
		(stroke
			(width 0.04445)
			(type default)
		)
		(layer "In11.Cu")
	)
	(gr_line
		(start 392.681206 -129.98958)
		(end 392.68527 -129.993644)
		(stroke
			(width 0.04445)
			(type default)
		)
		(layer "In11.Cu")
	)
	(gr_line
		(start 392.68527 -129.993644)
		(end 392.68527 -130.015742)
		(stroke
			(width 0.04445)
			(type default)
		)
		(layer "In11.Cu")
	)
	(gr_line
		(start 392.80084 -126.698502)
		(end 392.8872 -126.612142)
		(stroke
			(width 0.04445)
			(type default)
		)
		(layer "In11.Cu")
	)
	(gr_line
		(start 392.80084 -126.259082)
		(end 392.8872 -126.345442)
		(stroke
			(width 0.04445)
			(type default)
		)
		(layer "In11.Cu")
	)
	(gr_line
		(start 392.80084 -125.987302)
		(end 392.8872 -125.900942)
		(stroke
			(width 0.04445)
			(type default)
		)
		(layer "In11.Cu")
	)
	(gr_line
		(start 392.80084 -125.547882)
		(end 392.8872 -125.634242)
		(stroke
			(width 0.04445)
			(type default)
		)
		(layer "In11.Cu")
	)
	(gr_line
		(start 392.8872 -126.345442)
		(end 392.8872 -126.612142)
		(stroke
			(width 0.04445)
			(type default)
		)
		(layer "In11.Cu")
	)
	(gr_line
		(start 392.8872 -125.634242)
		(end 392.8872 -125.900942)
		(stroke
			(width 0.04445)
			(type default)
		)
		(layer "In11.Cu")
	)
	(gr_line
		(start 392.941556 -127.89408)
		(end 393.14628 -127.89408)
		(stroke
			(width 0.04445)
			(type default)
		)
		(layer "In11.Cu")
	)
	(gr_line
		(start 392.95324 -127.632714)
		(end 393.146026 -127.632714)
		(stroke
			(width 0.04445)
			(type default)
		)
		(layer "In11.Cu")
	)
	(gr_line
		(start 393.146026 -127.632714)
		(end 393.15009 -127.62865)
		(stroke
			(width 0.04445)
			(type default)
		)
		(layer "In11.Cu")
	)
	(gr_line
		(start 393.14628 -127.89408)
		(end 393.15009 -127.89789)
		(stroke
			(width 0.04445)
			(type default)
		)
		(layer "In11.Cu")
	)
	(gr_line
		(start 393.151868 -127.899668)
		(end 393.2682 -128.016)
		(stroke
			(width 0.04445)
			(type default)
		)
		(layer "In11.Cu")
	)
	(gr_line
		(start 393.151868 -127.626872)
		(end 393.2682 -127.51054)
		(stroke
			(width 0.04445)
			(type default)
		)
		(layer "In11.Cu")
	)
	(gr_line
		(start 393.16406 -131.410202)
		(end 393.20343 -131.449572)
		(stroke
			(width 0.04445)
			(type default)
		)
		(layer "In11.Cu")
	)
	(gr_line
		(start 393.16406 -131.219702)
		(end 393.20343 -131.180332)
		(stroke
			(width 0.04445)
			(type default)
		)
		(layer "In11.Cu")
	)
	(gr_line
		(start 393.205208 -131.45135)
		(end 393.21486 -131.461002)
		(stroke
			(width 0.04445)
			(type default)
		)
		(layer "In11.Cu")
	)
	(gr_line
		(start 393.205208 -131.178554)
		(end 393.21486 -131.168902)
		(stroke
			(width 0.04445)
			(type default)
		)
		(layer "In11.Cu")
	)
	(gr_line
		(start 393.21486 -131.461002)
		(end 393.236958 -131.461002)
		(stroke
			(width 0.04445)
			(type default)
		)
		(layer "In11.Cu")
	)
	(gr_line
		(start 393.21486 -131.168902)
		(end 393.236958 -131.168902)
		(stroke
			(width 0.04445)
			(type default)
		)
		(layer "In11.Cu")
	)
	(gr_line
		(start 393.2682 -129.9972)
		(end 393.462002 -129.803398)
		(stroke
			(width 0.04445)
			(type default)
		)
		(layer "In11.Cu")
	)
	(gr_line
		(start 393.2682 -129.3368)
		(end 393.462002 -129.530602)
		(stroke
			(width 0.04445)
			(type default)
		)
		(layer "In11.Cu")
	)
	(gr_line
		(start 393.2682 -127.381)
		(end 393.2682 -127.51054)
		(stroke
			(width 0.04445)
			(type default)
		)
		(layer "In11.Cu")
	)
	(gr_line
		(start 393.354052 -125.048518)
		(end 393.440412 -125.134878)
		(stroke
			(width 0.04445)
			(type default)
		)
		(layer "In11.Cu")
	)
	(gr_line
		(start 393.440412 -125.134878)
		(end 393.707112 -125.134878)
		(stroke
			(width 0.04445)
			(type default)
		)
		(layer "In11.Cu")
	)
	(gr_line
		(start 393.46378 -129.80162)
		(end 393.50315 -129.76225)
		(stroke
			(width 0.04445)
			(type default)
		)
		(layer "In11.Cu")
	)
	(gr_line
		(start 393.46378 -129.53238)
		(end 393.50315 -129.57175)
		(stroke
			(width 0.04445)
			(type default)
		)
		(layer "In11.Cu")
	)
	(gr_line
		(start 393.469114 -47.150528)
		(end 393.4714 -47.152814)
		(stroke
			(width 0.05715)
			(type default)
		)
		(layer "In11.Cu")
	)
	(gr_line
		(start 393.544552 -124.855478)
		(end 393.602972 -124.855478)
		(stroke
			(width 0.04445)
			(type default)
		)
		(layer "In11.Cu")
	)
	(gr_line
		(start 393.68095 -122.104404)
		(end 393.84986 -121.811288)
		(stroke
			(width 0.04445)
			(type default)
		)
		(layer "In11.Cu")
	)
	(gr_line
		(start 393.689078 -52.040536)
		(end 393.77239 -52.057554)
		(stroke
			(width 0.05715)
			(type default)
		)
		(layer "In11.Cu")
	)
	(gr_line
		(start 393.707112 -125.134878)
		(end 393.793472 -125.048518)
		(stroke
			(width 0.04445)
			(type default)
		)
		(layer "In11.Cu")
	)
	(gr_line
		(start 393.77239 -52.057554)
		(end 393.819126 -52.128166)
		(stroke
			(width 0.05715)
			(type default)
		)
		(layer "In11.Cu")
	)
	(gr_line
		(start 393.826238 -121.723658)
		(end 393.84986 -121.811288)
		(stroke
			(width 0.04445)
			(type default)
		)
		(layer "In11.Cu")
	)
	(gr_line
		(start 393.898882 -39.101268)
		(end 393.898882 -39.109904)
		(stroke
			(width 0.05715)
			(type default)
		)
		(layer "In11.Cu")
	)
	(gr_line
		(start 393.930378 -121.559574)
		(end 394.00734 -121.539)
		(stroke
			(width 0.04445)
			(type default)
		)
		(layer "In11.Cu")
	)
	(gr_line
		(start 394.00734 -121.539)
		(end 394.17625 -121.245884)
		(stroke
			(width 0.04445)
			(type default)
		)
		(layer "In11.Cu")
	)
	(gr_line
		(start 394.031216 -39.390828)
		(end 394.031216 -39.399464)
		(stroke
			(width 0.05715)
			(type default)
		)
		(layer "In11.Cu")
	)
	(gr_line
		(start 394.065252 -125.048518)
		(end 394.161772 -125.145038)
		(stroke
			(width 0.04445)
			(type default)
		)
		(layer "In11.Cu")
	)
	(gr_line
		(start 394.128498 -49.146714)
		(end 394.21181 -49.163732)
		(stroke
			(width 0.05715)
			(type default)
		)
		(layer "In11.Cu")
	)
	(gr_line
		(start 394.147548 -130.531362)
		(end 394.310108 -130.368802)
		(stroke
			(width 0.05715)
			(type default)
		)
		(layer "In11.Cu")
	)
	(gr_line
		(start 394.149326 -142.586202)
		(end 394.17752 -142.593822)
		(stroke
			(width 0.05715)
			(type default)
		)
		(layer "In11.Cu")
	)
	(gr_line
		(start 394.161772 -125.145038)
		(end 394.428472 -125.145038)
		(stroke
			(width 0.04445)
			(type default)
		)
		(layer "In11.Cu")
	)
	(gr_line
		(start 394.177266 -141.93012)
		(end 394.20546 -141.93774)
		(stroke
			(width 0.05715)
			(type default)
		)
		(layer "In11.Cu")
	)
	(gr_line
		(start 394.17752 -142.593822)
		(end 394.205714 -142.588488)
		(stroke
			(width 0.05715)
			(type default)
		)
		(layer "In11.Cu")
	)
	(gr_line
		(start 394.205206 -141.271752)
		(end 394.2334 -141.279372)
		(stroke
			(width 0.05715)
			(type default)
		)
		(layer "In11.Cu")
	)
	(gr_line
		(start 394.20546 -141.93774)
		(end 394.233654 -141.932406)
		(stroke
			(width 0.05715)
			(type default)
		)
		(layer "In11.Cu")
	)
	(gr_line
		(start 394.21181 -49.163732)
		(end 394.258546 -49.234344)
		(stroke
			(width 0.05715)
			(type default)
		)
		(layer "In11.Cu")
	)
	(gr_line
		(start 394.232892 -140.62075)
		(end 394.261086 -140.62837)
		(stroke
			(width 0.05715)
			(type default)
		)
		(layer "In11.Cu")
	)
	(gr_line
		(start 394.2334 -141.279372)
		(end 394.261594 -141.274038)
		(stroke
			(width 0.05715)
			(type default)
		)
		(layer "In11.Cu")
	)
	(gr_line
		(start 394.240766 -22.41804)
		(end 394.483082 -22.660356)
		(stroke
			(width 0.05715)
			(type default)
		)
		(layer "In11.Cu")
	)
	(gr_line
		(start 394.240766 -22.187916)
		(end 394.240766 -22.41804)
		(stroke
			(width 0.05715)
			(type default)
		)
		(layer "In11.Cu")
	)
	(gr_line
		(start 394.255752 -124.855478)
		(end 394.334492 -124.855478)
		(stroke
			(width 0.04445)
			(type default)
		)
		(layer "In11.Cu")
	)
	(gr_line
		(start 394.260578 -139.969748)
		(end 394.288772 -139.977368)
		(stroke
			(width 0.05715)
			(type default)
		)
		(layer "In11.Cu")
	)
	(gr_line
		(start 394.261086 -140.62837)
		(end 394.28928 -140.623036)
		(stroke
			(width 0.05715)
			(type default)
		)
		(layer "In11.Cu")
	)
	(gr_line
		(start 394.288264 -139.318746)
		(end 394.316458 -139.326366)
		(stroke
			(width 0.05715)
			(type default)
		)
		(layer "In11.Cu")
	)
	(gr_line
		(start 394.288772 -139.977368)
		(end 394.316966 -139.972034)
		(stroke
			(width 0.05715)
			(type default)
		)
		(layer "In11.Cu")
	)
	(gr_line
		(start 394.310108 -130.368802)
		(end 394.653008 -130.368802)
		(stroke
			(width 0.05715)
			(type default)
		)
		(layer "In11.Cu")
	)
	(gr_line
		(start 394.316458 -139.326366)
		(end 394.344906 -139.321032)
		(stroke
			(width 0.05715)
			(type default)
		)
		(layer "In11.Cu")
	)
	(gr_line
		(start 394.407898 -146.348958)
		(end 394.451078 -146.354292)
		(stroke
			(width 0.05715)
			(type default)
		)
		(layer "In11.Cu")
	)
	(gr_line
		(start 394.410692 -47.314358)
		(end 394.46962 -47.373286)
		(stroke
			(width 0.05715)
			(type default)
		)
		(layer "In11.Cu")
	)
	(gr_line
		(start 394.428472 -125.145038)
		(end 394.524992 -125.048518)
		(stroke
			(width 0.04445)
			(type default)
		)
		(layer "In11.Cu")
	)
	(gr_line
		(start 394.439648 -130.826002)
		(end 394.523468 -130.826002)
		(stroke
			(width 0.05715)
			(type default)
		)
		(layer "In11.Cu")
	)
	(gr_line
		(start 394.451078 -146.354292)
		(end 394.485622 -146.381216)
		(stroke
			(width 0.05715)
			(type default)
		)
		(layer "In11.Cu")
	)
	(gr_line
		(start 394.467842 -145.590006)
		(end 394.511022 -145.59534)
		(stroke
			(width 0.05715)
			(type default)
		)
		(layer "In11.Cu")
	)
	(gr_line
		(start 394.483082 -22.660356)
		(end 394.713206 -22.660356)
		(stroke
			(width 0.05715)
			(type default)
		)
		(layer "In11.Cu")
	)
	(gr_line
		(start 394.511022 -145.59534)
		(end 394.545566 -145.622264)
		(stroke
			(width 0.05715)
			(type default)
		)
		(layer "In11.Cu")
	)
	(gr_line
		(start 394.550646 -52.037996)
		(end 394.567156 -51.95697)
		(stroke
			(width 0.05715)
			(type default)
		)
		(layer "In11.Cu")
	)
	(gr_line
		(start 394.550646 -52.037996)
		(end 394.596366 -52.107338)
		(stroke
			(width 0.05715)
			(type default)
		)
		(layer "In11.Cu")
	)
	(gr_line
		(start 394.6525 -28.530042)
		(end 394.81506 -28.692602)
		(stroke
			(width 0.05715)
			(type default)
		)
		(layer "In11.Cu")
	)
	(gr_line
		(start 394.6525 -28.187142)
		(end 394.6525 -28.530042)
		(stroke
			(width 0.05715)
			(type default)
		)
		(layer "In11.Cu")
	)
	(gr_line
		(start 394.6525 -28.187142)
		(end 394.81506 -28.024582)
		(stroke
			(width 0.05715)
			(type default)
		)
		(layer "In11.Cu")
	)
	(gr_line
		(start 394.6525 -27.514042)
		(end 394.81506 -27.676602)
		(stroke
			(width 0.05715)
			(type default)
		)
		(layer "In11.Cu")
	)
	(gr_line
		(start 394.6525 -27.171142)
		(end 394.6525 -27.514042)
		(stroke
			(width 0.05715)
			(type default)
		)
		(layer "In11.Cu")
	)
	(gr_line
		(start 394.6525 -27.171142)
		(end 394.81506 -27.008582)
		(stroke
			(width 0.05715)
			(type default)
		)
		(layer "In11.Cu")
	)
	(gr_line
		(start 394.653008 -130.368802)
		(end 394.815568 -130.531362)
		(stroke
			(width 0.05715)
			(type default)
		)
		(layer "In11.Cu")
	)
	(gr_line
		(start 394.655802 -22.186392)
		(end 394.71473 -22.24532)
		(stroke
			(width 0.05715)
			(type default)
		)
		(layer "In11.Cu")
	)
	(gr_line
		(start 394.796772 -125.048518)
		(end 394.883132 -125.134878)
		(stroke
			(width 0.04445)
			(type default)
		)
		(layer "In11.Cu")
	)
	(gr_line
		(start 394.875258 -25.622758)
		(end 395.112494 -25.859994)
		(stroke
			(width 0.05715)
			(type default)
		)
		(layer "In11.Cu")
	)
	(gr_line
		(start 394.883132 -125.134878)
		(end 395.149832 -125.134878)
		(stroke
			(width 0.04445)
			(type default)
		)
		(layer "In11.Cu")
	)
	(gr_line
		(start 394.959078 -23.136352)
		(end 395.201394 -23.378922)
		(stroke
			(width 0.05715)
			(type default)
		)
		(layer "In11.Cu")
	)
	(gr_line
		(start 394.959078 -22.906228)
		(end 394.959078 -23.136352)
		(stroke
			(width 0.05715)
			(type default)
		)
		(layer "In11.Cu")
	)
	(gr_line
		(start 394.987272 -124.855478)
		(end 395.045692 -124.855478)
		(stroke
			(width 0.04445)
			(type default)
		)
		(layer "In11.Cu")
	)
	(gr_line
		(start 395.09954 -50.505106)
		(end 395.146276 -50.575464)
		(stroke
			(width 0.05715)
			(type default)
		)
		(layer "In11.Cu")
	)
	(gr_line
		(start 395.09954 -50.504598)
		(end 395.09954 -50.504852)
		(stroke
			(width 0.05715)
			(type default)
		)
		(layer "In11.Cu")
	)
	(gr_line
		(start 395.1097 -28.316682)
		(end 395.1097 -28.400502)
		(stroke
			(width 0.05715)
			(type default)
		)
		(layer "In11.Cu")
	)
	(gr_line
		(start 395.1097 -27.300682)
		(end 395.1097 -27.384502)
		(stroke
			(width 0.05715)
			(type default)
		)
		(layer "In11.Cu")
	)
	(gr_line
		(start 395.129512 -50.658268)
		(end 395.146276 -50.575464)
		(stroke
			(width 0.05715)
			(type default)
		)
		(layer "In11.Cu")
	)
	(gr_line
		(start 395.149832 -125.134878)
		(end 395.236192 -125.048518)
		(stroke
			(width 0.04445)
			(type default)
		)
		(layer "In11.Cu")
	)
	(gr_line
		(start 395.201394 -23.378922)
		(end 395.431772 -23.378922)
		(stroke
			(width 0.05715)
			(type default)
		)
		(layer "In11.Cu")
	)
	(gr_line
		(start 395.374114 -22.904704)
		(end 395.433296 -22.963886)
		(stroke
			(width 0.05715)
			(type default)
		)
		(layer "In11.Cu")
	)
	(gr_line
		(start 395.394434 -32.384238)
		(end 395.7574 -32.747204)
		(stroke
			(width 0.05715)
			(type default)
		)
		(layer "In11.Cu")
	)
	(gr_line
		(start 395.394434 -31.967424)
		(end 395.7574 -31.604458)
		(stroke
			(width 0.05715)
			(type default)
		)
		(layer "In11.Cu")
	)
	(gr_line
		(start 395.507972 -125.048518)
		(end 395.594332 -125.134878)
		(stroke
			(width 0.04445)
			(type default)
		)
		(layer "In11.Cu")
	)
	(gr_line
		(start 395.529308 -25.859994)
		(end 395.766544 -25.622758)
		(stroke
			(width 0.05715)
			(type default)
		)
		(layer "In11.Cu")
	)
	(gr_line
		(start 395.594332 -125.134878)
		(end 395.861032 -125.134878)
		(stroke
			(width 0.04445)
			(type default)
		)
		(layer "In11.Cu")
	)
	(gr_line
		(start 395.678152 -20.485862)
		(end 395.920468 -20.728178)
		(stroke
			(width 0.05715)
			(type default)
		)
		(layer "In11.Cu")
	)
	(gr_line
		(start 395.678152 -20.255738)
		(end 395.678152 -20.485862)
		(stroke
			(width 0.05715)
			(type default)
		)
		(layer "In11.Cu")
	)
	(gr_line
		(start 395.698472 -124.855478)
		(end 395.756892 -124.855478)
		(stroke
			(width 0.04445)
			(type default)
		)
		(layer "In11.Cu")
	)
	(gr_line
		(start 395.861032 -125.134878)
		(end 395.947392 -125.048518)
		(stroke
			(width 0.04445)
			(type default)
		)
		(layer "In11.Cu")
	)
	(gr_line
		(start 395.920468 -20.728178)
		(end 396.150592 -20.728178)
		(stroke
			(width 0.05715)
			(type default)
		)
		(layer "In11.Cu")
	)
	(gr_line
		(start 396.093188 -20.254214)
		(end 396.152116 -20.313142)
		(stroke
			(width 0.05715)
			(type default)
		)
		(layer "In11.Cu")
	)
	(gr_line
		(start 396.15745 -121.245884)
		(end 396.456154 -121.245884)
		(stroke
			(width 0.04445)
			(type default)
		)
		(layer "In11.Cu")
	)
	(gr_line
		(start 396.167356 -147.25396)
		(end 396.266162 -147.299426)
		(stroke
			(width 0.05715)
			(type default)
		)
		(layer "In11.Cu")
	)
	(gr_line
		(start 396.210282 -37.64788)
		(end 396.372842 -37.81044)
		(stroke
			(width 0.05715)
			(type default)
		)
		(layer "In11.Cu")
	)
	(gr_line
		(start 396.210282 -37.30498)
		(end 396.210282 -37.64788)
		(stroke
			(width 0.05715)
			(type default)
		)
		(layer "In11.Cu")
	)
	(gr_line
		(start 396.210282 -37.30498)
		(end 396.372842 -37.14242)
		(stroke
			(width 0.05715)
			(type default)
		)
		(layer "In11.Cu")
	)
	(gr_line
		(start 396.210282 -36.63188)
		(end 396.372842 -36.79444)
		(stroke
			(width 0.05715)
			(type default)
		)
		(layer "In11.Cu")
	)
	(gr_line
		(start 396.210282 -36.28898)
		(end 396.210282 -36.63188)
		(stroke
			(width 0.05715)
			(type default)
		)
		(layer "In11.Cu")
	)
	(gr_line
		(start 396.210282 -36.28898)
		(end 396.372842 -36.12642)
		(stroke
			(width 0.05715)
			(type default)
		)
		(layer "In11.Cu")
	)
	(gr_line
		(start 396.29842 -125.045978)
		(end 396.33779 -125.085348)
		(stroke
			(width 0.04445)
			(type default)
		)
		(layer "In11.Cu")
	)
	(gr_line
		(start 396.29842 -124.855478)
		(end 396.33779 -124.816108)
		(stroke
			(width 0.04445)
			(type default)
		)
		(layer "In11.Cu")
	)
	(gr_line
		(start 396.317978 -147.004532)
		(end 396.335504 -147.018248)
		(stroke
			(width 0.05715)
			(type default)
		)
		(layer "In11.Cu")
	)
	(gr_line
		(start 396.32255 -30.933644)
		(end 396.32255 -31.053278)
		(stroke
			(width 0.05715)
			(type default)
		)
		(layer "In11.Cu")
	)
	(gr_line
		(start 396.335504 -147.018248)
		(end 396.357348 -147.022566)
		(stroke
			(width 0.05715)
			(type default)
		)
		(layer "In11.Cu")
	)
	(gr_line
		(start 396.339568 -125.087126)
		(end 396.34922 -125.096778)
		(stroke
			(width 0.04445)
			(type default)
		)
		(layer "In11.Cu")
	)
	(gr_line
		(start 396.339568 -124.81433)
		(end 396.34922 -124.804678)
		(stroke
			(width 0.04445)
			(type default)
		)
		(layer "In11.Cu")
	)
	(gr_line
		(start 396.34922 -125.096778)
		(end 396.371318 -125.096778)
		(stroke
			(width 0.04445)
			(type default)
		)
		(layer "In11.Cu")
	)
	(gr_line
		(start 396.34922 -124.804678)
		(end 396.371318 -124.804678)
		(stroke
			(width 0.04445)
			(type default)
		)
		(layer "In11.Cu")
	)
	(gr_line
		(start 396.375382 -34.745676)
		(end 396.375382 -34.812478)
		(stroke
			(width 0.05715)
			(type default)
		)
		(layer "In11.Cu")
	)
	(gr_line
		(start 396.396464 -21.204174)
		(end 396.63878 -21.44649)
		(stroke
			(width 0.05715)
			(type default)
		)
		(layer "In11.Cu")
	)
	(gr_line
		(start 396.396464 -20.97405)
		(end 396.396464 -21.204174)
		(stroke
			(width 0.05715)
			(type default)
		)
		(layer "In11.Cu")
	)
	(gr_line
		(start 396.456154 -121.245884)
		(end 396.49654 -121.205498)
		(stroke
			(width 0.04445)
			(type default)
		)
		(layer "In11.Cu")
	)
	(gr_line
		(start 396.498318 -121.20372)
		(end 396.56766 -121.134378)
		(stroke
			(width 0.04445)
			(type default)
		)
		(layer "In11.Cu")
	)
	(gr_line
		(start 396.522702 -126.2888)
		(end 396.562072 -126.32817)
		(stroke
			(width 0.04445)
			(type default)
		)
		(layer "In11.Cu")
	)
	(gr_line
		(start 396.522702 -126.0983)
		(end 396.562072 -126.05893)
		(stroke
			(width 0.04445)
			(type default)
		)
		(layer "In11.Cu")
	)
	(gr_line
		(start 396.56385 -126.329948)
		(end 396.573502 -126.3396)
		(stroke
			(width 0.04445)
			(type default)
		)
		(layer "In11.Cu")
	)
	(gr_line
		(start 396.56385 -126.057152)
		(end 396.573502 -126.0475)
		(stroke
			(width 0.04445)
			(type default)
		)
		(layer "In11.Cu")
	)
	(gr_line
		(start 396.565882 -34.456116)
		(end 396.565882 -34.522918)
		(stroke
			(width 0.05715)
			(type default)
		)
		(layer "In11.Cu")
	)
	(gr_line
		(start 396.565882 -31.223204)
		(end 396.565882 -31.342838)
		(stroke
			(width 0.05715)
			(type default)
		)
		(layer "In11.Cu")
	)
	(gr_line
		(start 396.573502 -126.3396)
		(end 396.5956 -126.3396)
		(stroke
			(width 0.04445)
			(type default)
		)
		(layer "In11.Cu")
	)
	(gr_line
		(start 396.573502 -126.0475)
		(end 396.5956 -126.0475)
		(stroke
			(width 0.04445)
			(type default)
		)
		(layer "In11.Cu")
	)
	(gr_line
		(start 396.63878 -21.44649)
		(end 396.868904 -21.44649)
		(stroke
			(width 0.05715)
			(type default)
		)
		(layer "In11.Cu")
	)
	(gr_line
		(start 396.667482 -37.43452)
		(end 396.667482 -37.51834)
		(stroke
			(width 0.05715)
			(type default)
		)
		(layer "In11.Cu")
	)
	(gr_line
		(start 396.667482 -36.41852)
		(end 396.667482 -36.50234)
		(stroke
			(width 0.05715)
			(type default)
		)
		(layer "In11.Cu")
	)
	(gr_line
		(start 396.752064 -121.187972)
		(end 396.767812 -121.20372)
		(stroke
			(width 0.04445)
			(type default)
		)
		(layer "In11.Cu")
	)
	(gr_line
		(start 396.76959 -121.205498)
		(end 396.809976 -121.245884)
		(stroke
			(width 0.04445)
			(type default)
		)
		(layer "In11.Cu")
	)
	(gr_line
		(start 396.809976 -121.245884)
		(end 397.14805 -121.245884)
		(stroke
			(width 0.04445)
			(type default)
		)
		(layer "In11.Cu")
	)
	(gr_line
		(start 396.8115 -20.972526)
		(end 396.870428 -21.031454)
		(stroke
			(width 0.05715)
			(type default)
		)
		(layer "In11.Cu")
	)
	(gr_line
		(start 397.042894 -147.460462)
		(end 397.06677 -147.465288)
		(stroke
			(width 0.05715)
			(type default)
		)
		(layer "In11.Cu")
	)
	(gr_line
		(start 397.06677 -147.465288)
		(end 397.08963 -147.460208)
		(stroke
			(width 0.05715)
			(type default)
		)
		(layer "In11.Cu")
	)
	(gr_line
		(start 397.074898 -148.11502)
		(end 397.095726 -148.119338)
		(stroke
			(width 0.05715)
			(type default)
		)
		(layer "In11.Cu")
	)
	(gr_line
		(start 397.095726 -148.119338)
		(end 397.116808 -148.11502)
		(stroke
			(width 0.05715)
			(type default)
		)
		(layer "In11.Cu")
	)
	(gr_line
		(start 397.114776 -21.922486)
		(end 397.357092 -22.164802)
		(stroke
			(width 0.05715)
			(type default)
		)
		(layer "In11.Cu")
	)
	(gr_line
		(start 397.114776 -21.692362)
		(end 397.114776 -21.922486)
		(stroke
			(width 0.05715)
			(type default)
		)
		(layer "In11.Cu")
	)
	(gr_line
		(start 397.14805 -122.962924)
		(end 397.29283 -123.21413)
		(stroke
			(width 0.04445)
			(type default)
		)
		(layer "In11.Cu")
	)
	(gr_line
		(start 397.159226 -126.04496)
		(end 397.321786 -125.8824)
		(stroke
			(width 0.05715)
			(type default)
		)
		(layer "In11.Cu")
	)
	(gr_line
		(start 397.29283 -123.21413)
		(end 397.29283 -123.343924)
		(stroke
			(width 0.04445)
			(type default)
		)
		(layer "In11.Cu")
	)
	(gr_line
		(start 397.321786 -125.8824)
		(end 397.664686 -125.8824)
		(stroke
			(width 0.05715)
			(type default)
		)
		(layer "In11.Cu")
	)
	(gr_line
		(start 397.357092 -22.164802)
		(end 397.587216 -22.164802)
		(stroke
			(width 0.05715)
			(type default)
		)
		(layer "In11.Cu")
	)
	(gr_line
		(start 397.378174 -58.034428)
		(end 397.389604 -58.0517)
		(stroke
			(width 0.05715)
			(type default)
		)
		(layer "In11.Cu")
	)
	(gr_line
		(start 397.389604 -58.0517)
		(end 397.406876 -58.06313)
		(stroke
			(width 0.05715)
			(type default)
		)
		(layer "In11.Cu")
	)
	(gr_line
		(start 397.397478 -123.507754)
		(end 397.470376 -123.527312)
		(stroke
			(width 0.04445)
			(type default)
		)
		(layer "In11.Cu")
	)
	(gr_line
		(start 397.451326 -126.3396)
		(end 397.535146 -126.3396)
		(stroke
			(width 0.05715)
			(type default)
		)
		(layer "In11.Cu")
	)
	(gr_line
		(start 397.470376 -123.527312)
		(end 397.47444 -123.528328)
		(stroke
			(width 0.04445)
			(type default)
		)
		(layer "In11.Cu")
	)
	(gr_line
		(start 397.47444 -123.528328)
		(end 397.558768 -123.674632)
		(stroke
			(width 0.04445)
			(type default)
		)
		(layer "In11.Cu")
	)
	(gr_line
		(start 397.529812 -21.690838)
		(end 397.58874 -21.749766)
		(stroke
			(width 0.05715)
			(type default)
		)
		(layer "In11.Cu")
	)
	(gr_line
		(start 397.558768 -123.674632)
		(end 397.64335 -123.821444)
		(stroke
			(width 0.04445)
			(type default)
		)
		(layer "In11.Cu")
	)
	(gr_line
		(start 397.664686 -125.8824)
		(end 397.827246 -126.04496)
		(stroke
			(width 0.05715)
			(type default)
		)
		(layer "In11.Cu")
	)
	(gr_line
		(start 397.833088 -22.640798)
		(end 398.075404 -22.883114)
		(stroke
			(width 0.05715)
			(type default)
		)
		(layer "In11.Cu")
	)
	(gr_line
		(start 397.833088 -22.410674)
		(end 397.833088 -22.640798)
		(stroke
			(width 0.05715)
			(type default)
		)
		(layer "In11.Cu")
	)
	(gr_line
		(start 398.075404 -22.883114)
		(end 398.305528 -22.883114)
		(stroke
			(width 0.05715)
			(type default)
		)
		(layer "In11.Cu")
	)
	(gr_line
		(start 398.075658 -57.363868)
		(end 398.087088 -57.38114)
		(stroke
			(width 0.05715)
			(type default)
		)
		(layer "In11.Cu")
	)
	(gr_line
		(start 398.087088 -57.38114)
		(end 398.10436 -57.39257)
		(stroke
			(width 0.05715)
			(type default)
		)
		(layer "In11.Cu")
	)
	(gr_line
		(start 398.13865 -122.962924)
		(end 398.479518 -122.856752)
		(stroke
			(width 0.04445)
			(type default)
		)
		(layer "In11.Cu")
	)
	(gr_line
		(start 398.248124 -22.40915)
		(end 398.307052 -22.468078)
		(stroke
			(width 0.05715)
			(type default)
		)
		(layer "In11.Cu")
	)
	(gr_line
		(start 398.3863 -28.073858)
		(end 398.54886 -28.236418)
		(stroke
			(width 0.05715)
			(type default)
		)
		(layer "In11.Cu")
	)
	(gr_line
		(start 398.3863 -27.730958)
		(end 398.3863 -28.073858)
		(stroke
			(width 0.05715)
			(type default)
		)
		(layer "In11.Cu")
	)
	(gr_line
		(start 398.3863 -27.730958)
		(end 398.54886 -27.568398)
		(stroke
			(width 0.05715)
			(type default)
		)
		(layer "In11.Cu")
	)
	(gr_line
		(start 398.3863 -27.057858)
		(end 398.54886 -27.220418)
		(stroke
			(width 0.05715)
			(type default)
		)
		(layer "In11.Cu")
	)
	(gr_line
		(start 398.3863 -26.714958)
		(end 398.3863 -27.057858)
		(stroke
			(width 0.05715)
			(type default)
		)
		(layer "In11.Cu")
	)
	(gr_line
		(start 398.3863 -26.714958)
		(end 398.54886 -26.552398)
		(stroke
			(width 0.05715)
			(type default)
		)
		(layer "In11.Cu")
	)
	(gr_line
		(start 398.3863 -26.041858)
		(end 398.54886 -26.204418)
		(stroke
			(width 0.05715)
			(type default)
		)
		(layer "In11.Cu")
	)
	(gr_line
		(start 398.3863 -25.698958)
		(end 398.3863 -26.041858)
		(stroke
			(width 0.05715)
			(type default)
		)
		(layer "In11.Cu")
	)
	(gr_line
		(start 398.3863 -25.698958)
		(end 398.54886 -25.536398)
		(stroke
			(width 0.05715)
			(type default)
		)
		(layer "In11.Cu")
	)
	(gr_line
		(start 398.479518 -122.856752)
		(end 398.587722 -122.914156)
		(stroke
			(width 0.04445)
			(type default)
		)
		(layer "In11.Cu")
	)
	(gr_line
		(start 398.63395 -122.104404)
		(end 398.765268 -121.876566)
		(stroke
			(width 0.04445)
			(type default)
		)
		(layer "In11.Cu")
	)
	(gr_line
		(start 398.636744 -123.064016)
		(end 398.642078 -123.081034)
		(stroke
			(width 0.04445)
			(type default)
		)
		(layer "In11.Cu")
	)
	(gr_line
		(start 398.735042 -121.752868)
		(end 398.765268 -121.876566)
		(stroke
			(width 0.04445)
			(type default)
		)
		(layer "In11.Cu")
	)
	(gr_line
		(start 398.774412 -122.856498)
		(end 398.831308 -122.74804)
		(stroke
			(width 0.04445)
			(type default)
		)
		(layer "In11.Cu")
	)
	(gr_line
		(start 398.831308 -122.74804)
		(end 399.17243 -122.641868)
		(stroke
			(width 0.04445)
			(type default)
		)
		(layer "In11.Cu")
	)
	(gr_line
		(start 398.833848 -120.734074)
		(end 398.833848 -120.734328)
		(stroke
			(width 0.04445)
			(type default)
		)
		(layer "In11.Cu")
	)
	(gr_line
		(start 398.8435 -27.860498)
		(end 398.8435 -27.944318)
		(stroke
			(width 0.05715)
			(type default)
		)
		(layer "In11.Cu")
	)
	(gr_line
		(start 398.8435 -26.844498)
		(end 398.8435 -26.928318)
		(stroke
			(width 0.05715)
			(type default)
		)
		(layer "In11.Cu")
	)
	(gr_line
		(start 398.8435 -25.828498)
		(end 398.8435 -25.912318)
		(stroke
			(width 0.05715)
			(type default)
		)
		(layer "In11.Cu")
	)
	(gr_line
		(start 398.870932 -121.562876)
		(end 398.96034 -121.539)
		(stroke
			(width 0.04445)
			(type default)
		)
		(layer "In11.Cu")
	)
	(gr_line
		(start 398.90446 -55.696866)
		(end 399.146776 -55.939182)
		(stroke
			(width 0.05715)
			(type default)
		)
		(layer "In11.Cu")
	)
	(gr_line
		(start 398.90446 -55.466742)
		(end 398.90446 -55.696866)
		(stroke
			(width 0.05715)
			(type default)
		)
		(layer "In11.Cu")
	)
	(gr_line
		(start 398.945862 -117.290088)
		(end 399.102072 -117.133878)
		(stroke
			(width 0.04445)
			(type default)
		)
		(layer "In11.Cu")
	)
	(gr_line
		(start 398.94764 -117.56136)
		(end 399.069814 -117.56136)
		(stroke
			(width 0.04445)
			(type default)
		)
		(layer "In11.Cu")
	)
	(gr_line
		(start 398.96034 -121.539)
		(end 399.12925 -121.245884)
		(stroke
			(width 0.04445)
			(type default)
		)
		(layer "In11.Cu")
	)
	(gr_line
		(start 399.069814 -117.56136)
		(end 399.258536 -117.372638)
		(stroke
			(width 0.04445)
			(type default)
		)
		(layer "In11.Cu")
	)
	(gr_line
		(start 399.146776 -55.939182)
		(end 399.3769 -55.939182)
		(stroke
			(width 0.05715)
			(type default)
		)
		(layer "In11.Cu")
	)
	(gr_line
		(start 399.20418 -115.501674)
		(end 399.206974 -115.49888)
		(stroke
			(width 0.04445)
			(type default)
		)
		(layer "In11.Cu")
	)
	(gr_line
		(start 399.258536 -117.25021)
		(end 399.258536 -117.372638)
		(stroke
			(width 0.04445)
			(type default)
		)
		(layer "In11.Cu")
	)
	(gr_line
		(start 399.28038 -115.30838)
		(end 399.283174 -115.305586)
		(stroke
			(width 0.04445)
			(type default)
		)
		(layer "In11.Cu")
	)
	(gr_line
		(start 399.319496 -55.465218)
		(end 399.378424 -55.524146)
		(stroke
			(width 0.05715)
			(type default)
		)
		(layer "In11.Cu")
	)
	(gr_line
		(start 399.333974 -116.901976)
		(end 399.6055 -116.630196)
		(stroke
			(width 0.04445)
			(type default)
		)
		(layer "In11.Cu")
	)
	(gr_line
		(start 399.41373 -123.907804)
		(end 399.41373 -124.029978)
		(stroke
			(width 0.04445)
			(type default)
		)
		(layer "In11.Cu")
	)
	(gr_line
		(start 399.41373 -123.907804)
		(end 399.602452 -123.719082)
		(stroke
			(width 0.04445)
			(type default)
		)
		(layer "In11.Cu")
	)
	(gr_line
		(start 399.428462 -147.343114)
		(end 399.449798 -147.338796)
		(stroke
			(width 0.05715)
			(type default)
		)
		(layer "In11.Cu")
	)
	(gr_line
		(start 399.449798 -147.338796)
		(end 399.47088 -147.343114)
		(stroke
			(width 0.05715)
			(type default)
		)
		(layer "In11.Cu")
	)
	(gr_line
		(start 399.450306 -117.05844)
		(end 399.572734 -117.05844)
		(stroke
			(width 0.04445)
			(type default)
		)
		(layer "In11.Cu")
	)
	(gr_line
		(start 399.572734 -117.05844)
		(end 399.761456 -116.869718)
		(stroke
			(width 0.04445)
			(type default)
		)
		(layer "In11.Cu")
	)
	(gr_line
		(start 399.602452 -123.719082)
		(end 399.724626 -123.719082)
		(stroke
			(width 0.04445)
			(type default)
		)
		(layer "In11.Cu")
	)
	(gr_line
		(start 399.622772 -56.415178)
		(end 399.865342 -56.657748)
		(stroke
			(width 0.05715)
			(type default)
		)
		(layer "In11.Cu")
	)
	(gr_line
		(start 399.622772 -56.185054)
		(end 399.622772 -56.415178)
		(stroke
			(width 0.05715)
			(type default)
		)
		(layer "In11.Cu")
	)
	(gr_line
		(start 399.685002 -124.031756)
		(end 399.726404 -123.990354)
		(stroke
			(width 0.04445)
			(type default)
		)
		(layer "In11.Cu")
	)
	(gr_line
		(start 399.744946 -114.843814)
		(end 399.786348 -114.802412)
		(stroke
			(width 0.04445)
			(type default)
		)
		(layer "In11.Cu")
	)
	(gr_line
		(start 399.746724 -115.115086)
		(end 399.868898 -115.115086)
		(stroke
			(width 0.04445)
			(type default)
		)
		(layer "In11.Cu")
	)
	(gr_line
		(start 399.761456 -116.74729)
		(end 399.761456 -116.869718)
		(stroke
			(width 0.04445)
			(type default)
		)
		(layer "In11.Cu")
	)
	(gr_line
		(start 399.85315 -122.47372)
		(end 399.85315 -122.595894)
		(stroke
			(width 0.04445)
			(type default)
		)
		(layer "In11.Cu")
	)
	(gr_line
		(start 399.85315 -122.47372)
		(end 400.041872 -122.284998)
		(stroke
			(width 0.04445)
			(type default)
		)
		(layer "In11.Cu")
	)
	(gr_line
		(start 399.865342 -56.657748)
		(end 400.095466 -56.657748)
		(stroke
			(width 0.05715)
			(type default)
		)
		(layer "In11.Cu")
	)
	(gr_line
		(start 399.868898 -115.115086)
		(end 400.05762 -114.926364)
		(stroke
			(width 0.04445)
			(type default)
		)
		(layer "In11.Cu")
	)
	(gr_line
		(start 399.91665 -123.404884)
		(end 399.91665 -123.527058)
		(stroke
			(width 0.04445)
			(type default)
		)
		(layer "In11.Cu")
	)
	(gr_line
		(start 399.91665 -123.404884)
		(end 400.105372 -123.216162)
		(stroke
			(width 0.04445)
			(type default)
		)
		(layer "In11.Cu")
	)
	(gr_line
		(start 399.951448 -116.284248)
		(end 400.10842 -116.127276)
		(stroke
			(width 0.04445)
			(type default)
		)
		(layer "In11.Cu")
	)
	(gr_line
		(start 399.953226 -116.55552)
		(end 400.075654 -116.55552)
		(stroke
			(width 0.04445)
			(type default)
		)
		(layer "In11.Cu")
	)
	(gr_line
		(start 400.037808 -56.18353)
		(end 400.09699 -56.242712)
		(stroke
			(width 0.05715)
			(type default)
		)
		(layer "In11.Cu")
	)
	(gr_line
		(start 400.041872 -122.284998)
		(end 400.164046 -122.284998)
		(stroke
			(width 0.04445)
			(type default)
		)
		(layer "In11.Cu")
	)
	(gr_line
		(start 400.05762 -114.80419)
		(end 400.05762 -114.926364)
		(stroke
			(width 0.04445)
			(type default)
		)
		(layer "In11.Cu")
	)
	(gr_line
		(start 400.075654 -116.55552)
		(end 400.264376 -116.366798)
		(stroke
			(width 0.04445)
			(type default)
		)
		(layer "In11.Cu")
	)
	(gr_line
		(start 400.088608 -51.658266)
		(end 400.147536 -51.717194)
		(stroke
			(width 0.05715)
			(type default)
		)
		(layer "In11.Cu")
	)
	(gr_line
		(start 400.090132 -51.24323)
		(end 400.320256 -51.24323)
		(stroke
			(width 0.05715)
			(type default)
		)
		(layer "In11.Cu")
	)
	(gr_line
		(start 400.105372 -123.216162)
		(end 400.227546 -123.216162)
		(stroke
			(width 0.04445)
			(type default)
		)
		(layer "In11.Cu")
	)
	(gr_line
		(start 400.124422 -122.597672)
		(end 400.165824 -122.55627)
		(stroke
			(width 0.04445)
			(type default)
		)
		(layer "In11.Cu")
	)
	(gr_line
		(start 400.187922 -123.528836)
		(end 400.229324 -123.487434)
		(stroke
			(width 0.04445)
			(type default)
		)
		(layer "In11.Cu")
	)
	(gr_line
		(start 400.247866 -114.340894)
		(end 400.289268 -114.299492)
		(stroke
			(width 0.04445)
			(type default)
		)
		(layer "In11.Cu")
	)
	(gr_line
		(start 400.249644 -114.612166)
		(end 400.371818 -114.612166)
		(stroke
			(width 0.04445)
			(type default)
		)
		(layer "In11.Cu")
	)
	(gr_line
		(start 400.251422 -112.931448)
		(end 400.261074 -112.9411)
		(stroke
			(width 0.04445)
			(type default)
		)
		(layer "In11.Cu")
	)
	(gr_line
		(start 400.251422 -112.90935)
		(end 400.251422 -112.931448)
		(stroke
			(width 0.04445)
			(type default)
		)
		(layer "In11.Cu")
	)
	(gr_line
		(start 400.251422 -112.376966)
		(end 400.268186 -112.345724)
		(stroke
			(width 0.05715)
			(type default)
		)
		(layer "In11.Cu")
	)
	(gr_line
		(start 400.262852 -112.942878)
		(end 400.302222 -112.982248)
		(stroke
			(width 0.04445)
			(type default)
		)
		(layer "In11.Cu")
	)
	(gr_line
		(start 400.264376 -116.24437)
		(end 400.264376 -116.366798)
		(stroke
			(width 0.04445)
			(type default)
		)
		(layer "In11.Cu")
	)
	(gr_line
		(start 400.26717 -121.414286)
		(end 400.35353 -121.500646)
		(stroke
			(width 0.04445)
			(type default)
		)
		(layer "In11.Cu")
	)
	(gr_line
		(start 400.26717 -121.147586)
		(end 400.26717 -121.414286)
		(stroke
			(width 0.04445)
			(type default)
		)
		(layer "In11.Cu")
	)
	(gr_line
		(start 400.26717 -121.147586)
		(end 400.35353 -121.061226)
		(stroke
			(width 0.04445)
			(type default)
		)
		(layer "In11.Cu")
	)
	(gr_line
		(start 400.26717 -120.703086)
		(end 400.35353 -120.789446)
		(stroke
			(width 0.04445)
			(type default)
		)
		(layer "In11.Cu")
	)
	(gr_line
		(start 400.26717 -120.436386)
		(end 400.26717 -120.703086)
		(stroke
			(width 0.04445)
			(type default)
		)
		(layer "In11.Cu")
	)
	(gr_line
		(start 400.26717 -120.436386)
		(end 400.35353 -120.350026)
		(stroke
			(width 0.04445)
			(type default)
		)
		(layer "In11.Cu")
	)
	(gr_line
		(start 400.31797 -115.8621)
		(end 400.31797 -115.91798)
		(stroke
			(width 0.04445)
			(type default)
		)
		(layer "In11.Cu")
	)
	(gr_line
		(start 400.31797 -115.845844)
		(end 400.31797 -115.85956)
		(stroke
			(width 0.04445)
			(type default)
		)
		(layer "In11.Cu")
	)
	(gr_line
		(start 400.31797 -115.845844)
		(end 400.333464 -115.83035)
		(stroke
			(width 0.04445)
			(type default)
		)
		(layer "In11.Cu")
	)
	(gr_line
		(start 400.320256 -51.24323)
		(end 400.562572 -51.485546)
		(stroke
			(width 0.05715)
			(type default)
		)
		(layer "In11.Cu")
	)
	(gr_line
		(start 400.341338 -57.133744)
		(end 400.583654 -57.37606)
		(stroke
			(width 0.05715)
			(type default)
		)
		(layer "In11.Cu")
	)
	(gr_line
		(start 400.341338 -56.90362)
		(end 400.341338 -57.133744)
		(stroke
			(width 0.05715)
			(type default)
		)
		(layer "In11.Cu")
	)
	(gr_line
		(start 400.371818 -114.612166)
		(end 400.56054 -114.423444)
		(stroke
			(width 0.04445)
			(type default)
		)
		(layer "In11.Cu")
	)
	(gr_line
		(start 400.41957 -122.901964)
		(end 400.41957 -123.024138)
		(stroke
			(width 0.04445)
			(type default)
		)
		(layer "In11.Cu")
	)
	(gr_line
		(start 400.41957 -122.901964)
		(end 400.608292 -122.713242)
		(stroke
			(width 0.04445)
			(type default)
		)
		(layer "In11.Cu")
	)
	(gr_line
		(start 400.422364 -128.12141)
		(end 400.584924 -128.28397)
		(stroke
			(width 0.05715)
			(type default)
		)
		(layer "In11.Cu")
	)
	(gr_line
		(start 400.422364 -127.77851)
		(end 400.422364 -128.12141)
		(stroke
			(width 0.05715)
			(type default)
		)
		(layer "In11.Cu")
	)
	(gr_line
		(start 400.422364 -127.77851)
		(end 400.584924 -127.61595)
		(stroke
			(width 0.05715)
			(type default)
		)
		(layer "In11.Cu")
	)
	(gr_line
		(start 400.422364 -126.88824)
		(end 400.584924 -127.0508)
		(stroke
			(width 0.05715)
			(type default)
		)
		(layer "In11.Cu")
	)
	(gr_line
		(start 400.422364 -126.54534)
		(end 400.422364 -126.88824)
		(stroke
			(width 0.05715)
			(type default)
		)
		(layer "In11.Cu")
	)
	(gr_line
		(start 400.422364 -126.54534)
		(end 400.584924 -126.38278)
		(stroke
			(width 0.05715)
			(type default)
		)
		(layer "In11.Cu")
	)
	(gr_line
		(start 400.452844 -116.0526)
		(end 400.50847 -116.0526)
		(stroke
			(width 0.04445)
			(type default)
		)
		(layer "In11.Cu")
	)
	(gr_line
		(start 400.463004 -111.984536)
		(end 400.480022 -111.952532)
		(stroke
			(width 0.05715)
			(type default)
		)
		(layer "In11.Cu")
	)
	(gr_line
		(start 400.480022 -111.952532)
		(end 400.510756 -111.932212)
		(stroke
			(width 0.05715)
			(type default)
		)
		(layer "In11.Cu")
	)
	(gr_line
		(start 400.492722 -112.982248)
		(end 400.532092 -112.942878)
		(stroke
			(width 0.04445)
			(type default)
		)
		(layer "In11.Cu")
	)
	(gr_line
		(start 400.51101 -116.0526)
		(end 400.524472 -116.0526)
		(stroke
			(width 0.04445)
			(type default)
		)
		(layer "In11.Cu")
	)
	(gr_line
		(start 400.524472 -116.0526)
		(end 400.539966 -116.037106)
		(stroke
			(width 0.04445)
			(type default)
		)
		(layer "In11.Cu")
	)
	(gr_line
		(start 400.53387 -112.9411)
		(end 400.543522 -112.931448)
		(stroke
			(width 0.04445)
			(type default)
		)
		(layer "In11.Cu")
	)
	(gr_line
		(start 400.543522 -112.90935)
		(end 400.543522 -112.931448)
		(stroke
			(width 0.04445)
			(type default)
		)
		(layer "In11.Cu")
	)
	(gr_line
		(start 400.54657 -121.251726)
		(end 400.54657 -121.310146)
		(stroke
			(width 0.04445)
			(type default)
		)
		(layer "In11.Cu")
	)
	(gr_line
		(start 400.54657 -120.540526)
		(end 400.54657 -120.598946)
		(stroke
			(width 0.04445)
			(type default)
		)
		(layer "In11.Cu")
	)
	(gr_line
		(start 400.56054 -114.30127)
		(end 400.56054 -114.423444)
		(stroke
			(width 0.04445)
			(type default)
		)
		(layer "In11.Cu")
	)
	(gr_line
		(start 400.562572 -51.485546)
		(end 400.562572 -51.71567)
		(stroke
			(width 0.05715)
			(type default)
		)
		(layer "In11.Cu")
	)
	(gr_line
		(start 400.583654 -57.37606)
		(end 400.813778 -57.37606)
		(stroke
			(width 0.05715)
			(type default)
		)
		(layer "In11.Cu")
	)
	(gr_line
		(start 400.608292 -122.713242)
		(end 400.730466 -122.713242)
		(stroke
			(width 0.04445)
			(type default)
		)
		(layer "In11.Cu")
	)
	(gr_line
		(start 400.625056 -118.493286)
		(end 400.680682 -118.43766)
		(stroke
			(width 0.04445)
			(type default)
		)
		(layer "In11.Cu")
	)
	(gr_line
		(start 400.626834 -118.764558)
		(end 400.763486 -118.764558)
		(stroke
			(width 0.04445)
			(type default)
		)
		(layer "In11.Cu")
	)
	(gr_line
		(start 400.690842 -123.025916)
		(end 400.732244 -122.984514)
		(stroke
			(width 0.04445)
			(type default)
		)
		(layer "In11.Cu")
	)
	(gr_line
		(start 400.750786 -113.837974)
		(end 400.792188 -113.796572)
		(stroke
			(width 0.04445)
			(type default)
		)
		(layer "In11.Cu")
	)
	(gr_line
		(start 400.752564 -114.109246)
		(end 400.874738 -114.109246)
		(stroke
			(width 0.04445)
			(type default)
		)
		(layer "In11.Cu")
	)
	(gr_line
		(start 400.756374 -56.902096)
		(end 400.815302 -56.961024)
		(stroke
			(width 0.05715)
			(type default)
		)
		(layer "In11.Cu")
	)
	(gr_line
		(start 400.763486 -118.764558)
		(end 400.951954 -118.575836)
		(stroke
			(width 0.04445)
			(type default)
		)
		(layer "In11.Cu")
	)
	(gr_line
		(start 400.80692 -52.376578)
		(end 400.865848 -52.435506)
		(stroke
			(width 0.05715)
			(type default)
		)
		(layer "In11.Cu")
	)
	(gr_line
		(start 400.808444 -51.961542)
		(end 401.038568 -51.961542)
		(stroke
			(width 0.05715)
			(type default)
		)
		(layer "In11.Cu")
	)
	(gr_line
		(start 400.874738 -114.109246)
		(end 401.06346 -113.920524)
		(stroke
			(width 0.04445)
			(type default)
		)
		(layer "In11.Cu")
	)
	(gr_line
		(start 400.879564 -127.90805)
		(end 400.879564 -127.99187)
		(stroke
			(width 0.05715)
			(type default)
		)
		(layer "In11.Cu")
	)
	(gr_line
		(start 400.879564 -126.67488)
		(end 400.879564 -126.7587)
		(stroke
			(width 0.05715)
			(type default)
		)
		(layer "In11.Cu")
	)
	(gr_line
		(start 400.927824 -119.383302)
		(end 400.927824 -119.505476)
		(stroke
			(width 0.04445)
			(type default)
		)
		(layer "In11.Cu")
	)
	(gr_line
		(start 400.927824 -119.383302)
		(end 401.116546 -119.19458)
		(stroke
			(width 0.04445)
			(type default)
		)
		(layer "In11.Cu")
	)
	(gr_line
		(start 400.951954 -118.439438)
		(end 400.951954 -118.575836)
		(stroke
			(width 0.04445)
			(type default)
		)
		(layer "In11.Cu")
	)
	(gr_line
		(start 401.036282 -111.584994)
		(end 401.051776 -111.57458)
		(stroke
			(width 0.05715)
			(type default)
		)
		(layer "In11.Cu")
	)
	(gr_line
		(start 401.038568 -51.961542)
		(end 401.280884 -52.203858)
		(stroke
			(width 0.05715)
			(type default)
		)
		(layer "In11.Cu")
	)
	(gr_line
		(start 401.051776 -111.57458)
		(end 401.070572 -111.57077)
		(stroke
			(width 0.05715)
			(type default)
		)
		(layer "In11.Cu")
	)
	(gr_line
		(start 401.06346 -113.79835)
		(end 401.06346 -113.920524)
		(stroke
			(width 0.04445)
			(type default)
		)
		(layer "In11.Cu")
	)
	(gr_line
		(start 401.116546 -119.19458)
		(end 401.23872 -119.19458)
		(stroke
			(width 0.04445)
			(type default)
		)
		(layer "In11.Cu")
	)
	(gr_line
		(start 401.182586 -121.820178)
		(end 401.268946 -121.906538)
		(stroke
			(width 0.04445)
			(type default)
		)
		(layer "In11.Cu")
	)
	(gr_line
		(start 401.182586 -121.553478)
		(end 401.182586 -121.820178)
		(stroke
			(width 0.04445)
			(type default)
		)
		(layer "In11.Cu")
	)
	(gr_line
		(start 401.182586 -121.553478)
		(end 401.268946 -121.467118)
		(stroke
			(width 0.04445)
			(type default)
		)
		(layer "In11.Cu")
	)
	(gr_line
		(start 401.182586 -121.108978)
		(end 401.268946 -121.195338)
		(stroke
			(width 0.04445)
			(type default)
		)
		(layer "In11.Cu")
	)
	(gr_line
		(start 401.182586 -120.842278)
		(end 401.182586 -121.108978)
		(stroke
			(width 0.04445)
			(type default)
		)
		(layer "In11.Cu")
	)
	(gr_line
		(start 401.182586 -120.842278)
		(end 401.268946 -120.755918)
		(stroke
			(width 0.04445)
			(type default)
		)
		(layer "In11.Cu")
	)
	(gr_line
		(start 401.199096 -119.507254)
		(end 401.240498 -119.465852)
		(stroke
			(width 0.04445)
			(type default)
		)
		(layer "In11.Cu")
	)
	(gr_line
		(start 401.280884 -52.203858)
		(end 401.280884 -52.433982)
		(stroke
			(width 0.05715)
			(type default)
		)
		(layer "In11.Cu")
	)
	(gr_line
		(start 401.430744 -118.880382)
		(end 401.430744 -119.002556)
		(stroke
			(width 0.04445)
			(type default)
		)
		(layer "In11.Cu")
	)
	(gr_line
		(start 401.430744 -118.880382)
		(end 401.619466 -118.69166)
		(stroke
			(width 0.04445)
			(type default)
		)
		(layer "In11.Cu")
	)
	(gr_line
		(start 401.461986 -121.657618)
		(end 401.461986 -121.716038)
		(stroke
			(width 0.04445)
			(type default)
		)
		(layer "In11.Cu")
	)
	(gr_line
		(start 401.461986 -120.946418)
		(end 401.461986 -121.004838)
		(stroke
			(width 0.04445)
			(type default)
		)
		(layer "In11.Cu")
	)
	(gr_line
		(start 401.619466 -118.69166)
		(end 401.74164 -118.69166)
		(stroke
			(width 0.04445)
			(type default)
		)
		(layer "In11.Cu")
	)
	(gr_line
		(start 401.702016 -119.004334)
		(end 401.743418 -118.962932)
		(stroke
			(width 0.04445)
			(type default)
		)
		(layer "In11.Cu")
	)
	(gr_line
		(start 401.785836 -119.50573)
		(end 401.785836 -119.627904)
		(stroke
			(width 0.04445)
			(type default)
		)
		(layer "In11.Cu")
	)
	(gr_line
		(start 401.785836 -119.50573)
		(end 401.974304 -119.317262)
		(stroke
			(width 0.04445)
			(type default)
		)
		(layer "In11.Cu")
	)
	(gr_line
		(start 401.8534 -24.90724)
		(end 401.8534 -24.99106)
		(stroke
			(width 0.05715)
			(type default)
		)
		(layer "In11.Cu")
	)
	(gr_line
		(start 401.8534 -23.89124)
		(end 401.8534 -23.97506)
		(stroke
			(width 0.05715)
			(type default)
		)
		(layer "In11.Cu")
	)
	(gr_line
		(start 401.974304 -119.317262)
		(end 402.096478 -119.317262)
		(stroke
			(width 0.04445)
			(type default)
		)
		(layer "In11.Cu")
	)
	(gr_line
		(start 402.000212 -112.606074)
		(end 402.086572 -112.692434)
		(stroke
			(width 0.04445)
			(type default)
		)
		(layer "In11.Cu")
	)
	(gr_line
		(start 402.057108 -119.629682)
		(end 402.098256 -119.588534)
		(stroke
			(width 0.04445)
			(type default)
		)
		(layer "In11.Cu")
	)
	(gr_line
		(start 402.086572 -112.692434)
		(end 402.353272 -112.692434)
		(stroke
			(width 0.04445)
			(type default)
		)
		(layer "In11.Cu")
	)
	(gr_line
		(start 402.14804 -25.28316)
		(end 402.3106 -25.1206)
		(stroke
			(width 0.05715)
			(type default)
		)
		(layer "In11.Cu")
	)
	(gr_line
		(start 402.14804 -24.61514)
		(end 402.3106 -24.7777)
		(stroke
			(width 0.05715)
			(type default)
		)
		(layer "In11.Cu")
	)
	(gr_line
		(start 402.14804 -24.26716)
		(end 402.3106 -24.1046)
		(stroke
			(width 0.05715)
			(type default)
		)
		(layer "In11.Cu")
	)
	(gr_line
		(start 402.14804 -23.59914)
		(end 402.3106 -23.7617)
		(stroke
			(width 0.05715)
			(type default)
		)
		(layer "In11.Cu")
	)
	(gr_line
		(start 402.17979 -37.215572)
		(end 402.17979 -37.312092)
		(stroke
			(width 0.05715)
			(type default)
		)
		(layer "In11.Cu")
	)
	(gr_line
		(start 402.17979 -36.174172)
		(end 402.17979 -36.270692)
		(stroke
			(width 0.05715)
			(type default)
		)
		(layer "In11.Cu")
	)
	(gr_line
		(start 402.17979 -35.132772)
		(end 402.17979 -35.229292)
		(stroke
			(width 0.05715)
			(type default)
		)
		(layer "In11.Cu")
	)
	(gr_line
		(start 402.17979 -32.925512)
		(end 402.17979 -33.009332)
		(stroke
			(width 0.05715)
			(type default)
		)
		(layer "In11.Cu")
	)
	(gr_line
		(start 402.17979 -31.909512)
		(end 402.17979 -31.993332)
		(stroke
			(width 0.05715)
			(type default)
		)
		(layer "In11.Cu")
	)
	(gr_line
		(start 402.17979 -30.893512)
		(end 402.17979 -30.977332)
		(stroke
			(width 0.05715)
			(type default)
		)
		(layer "In11.Cu")
	)
	(gr_line
		(start 402.17979 -29.877512)
		(end 402.17979 -29.961332)
		(stroke
			(width 0.05715)
			(type default)
		)
		(layer "In11.Cu")
	)
	(gr_line
		(start 402.190712 -112.413034)
		(end 402.249132 -112.413034)
		(stroke
			(width 0.04445)
			(type default)
		)
		(layer "In11.Cu")
	)
	(gr_line
		(start 402.3106 -24.7777)
		(end 402.3106 -25.1206)
		(stroke
			(width 0.05715)
			(type default)
		)
		(layer "In11.Cu")
	)
	(gr_line
		(start 402.3106 -23.7617)
		(end 402.3106 -24.1046)
		(stroke
			(width 0.05715)
			(type default)
		)
		(layer "In11.Cu")
	)
	(gr_line
		(start 402.353272 -112.692434)
		(end 402.439632 -112.606074)
		(stroke
			(width 0.04445)
			(type default)
		)
		(layer "In11.Cu")
	)
	(gr_line
		(start 402.47443 -37.604192)
		(end 402.63699 -37.441632)
		(stroke
			(width 0.05715)
			(type default)
		)
		(layer "In11.Cu")
	)
	(gr_line
		(start 402.47443 -36.923472)
		(end 402.63699 -37.086032)
		(stroke
			(width 0.05715)
			(type default)
		)
		(layer "In11.Cu")
	)
	(gr_line
		(start 402.47443 -36.562792)
		(end 402.63699 -36.400232)
		(stroke
			(width 0.05715)
			(type default)
		)
		(layer "In11.Cu")
	)
	(gr_line
		(start 402.47443 -35.882072)
		(end 402.63699 -36.044632)
		(stroke
			(width 0.05715)
			(type default)
		)
		(layer "In11.Cu")
	)
	(gr_line
		(start 402.47443 -35.521392)
		(end 402.63699 -35.358832)
		(stroke
			(width 0.05715)
			(type default)
		)
		(layer "In11.Cu")
	)
	(gr_line
		(start 402.47443 -34.840672)
		(end 402.63699 -35.003232)
		(stroke
			(width 0.05715)
			(type default)
		)
		(layer "In11.Cu")
	)
	(gr_line
		(start 402.47443 -33.301432)
		(end 402.63699 -33.138872)
		(stroke
			(width 0.05715)
			(type default)
		)
		(layer "In11.Cu")
	)
	(gr_line
		(start 402.47443 -32.633412)
		(end 402.63699 -32.795972)
		(stroke
			(width 0.05715)
			(type default)
		)
		(layer "In11.Cu")
	)
	(gr_line
		(start 402.47443 -32.285432)
		(end 402.63699 -32.122872)
		(stroke
			(width 0.05715)
			(type default)
		)
		(layer "In11.Cu")
	)
	(gr_line
		(start 402.47443 -31.617412)
		(end 402.63699 -31.779972)
		(stroke
			(width 0.05715)
			(type default)
		)
		(layer "In11.Cu")
	)
	(gr_line
		(start 402.47443 -31.269432)
		(end 402.63699 -31.106872)
		(stroke
			(width 0.05715)
			(type default)
		)
		(layer "In11.Cu")
	)
	(gr_line
		(start 402.47443 -30.601412)
		(end 402.63699 -30.763972)
		(stroke
			(width 0.05715)
			(type default)
		)
		(layer "In11.Cu")
	)
	(gr_line
		(start 402.47443 -30.253432)
		(end 402.63699 -30.090872)
		(stroke
			(width 0.05715)
			(type default)
		)
		(layer "In11.Cu")
	)
	(gr_line
		(start 402.47443 -29.585412)
		(end 402.63699 -29.747972)
		(stroke
			(width 0.05715)
			(type default)
		)
		(layer "In11.Cu")
	)
	(gr_line
		(start 402.63699 -37.086032)
		(end 402.63699 -37.441632)
		(stroke
			(width 0.05715)
			(type default)
		)
		(layer "In11.Cu")
	)
	(gr_line
		(start 402.63699 -36.044632)
		(end 402.63699 -36.400232)
		(stroke
			(width 0.05715)
			(type default)
		)
		(layer "In11.Cu")
	)
	(gr_line
		(start 402.63699 -35.003232)
		(end 402.63699 -35.358832)
		(stroke
			(width 0.05715)
			(type default)
		)
		(layer "In11.Cu")
	)
	(gr_line
		(start 402.63699 -32.795972)
		(end 402.63699 -33.138872)
		(stroke
			(width 0.05715)
			(type default)
		)
		(layer "In11.Cu")
	)
	(gr_line
		(start 402.63699 -31.779972)
		(end 402.63699 -32.122872)
		(stroke
			(width 0.05715)
			(type default)
		)
		(layer "In11.Cu")
	)
	(gr_line
		(start 402.63699 -30.763972)
		(end 402.63699 -31.106872)
		(stroke
			(width 0.05715)
			(type default)
		)
		(layer "In11.Cu")
	)
	(gr_line
		(start 402.63699 -29.747972)
		(end 402.63699 -30.090872)
		(stroke
			(width 0.05715)
			(type default)
		)
		(layer "In11.Cu")
	)
	(gr_line
		(start 402.711412 -112.606074)
		(end 402.797772 -112.692434)
		(stroke
			(width 0.04445)
			(type default)
		)
		(layer "In11.Cu")
	)
	(gr_line
		(start 402.785326 -16.9418)
		(end 402.947886 -17.10436)
		(stroke
			(width 0.05715)
			(type default)
		)
		(layer "In11.Cu")
	)
	(gr_line
		(start 402.797772 -112.692434)
		(end 403.064472 -112.692434)
		(stroke
			(width 0.04445)
			(type default)
		)
		(layer "In11.Cu")
	)
	(gr_line
		(start 402.86305 -148.31949)
		(end 402.8821 -148.3233)
		(stroke
			(width 0.05715)
			(type default)
		)
		(layer "In11.Cu")
	)
	(gr_line
		(start 402.8821 -148.3233)
		(end 402.90115 -148.31949)
		(stroke
			(width 0.05715)
			(type default)
		)
		(layer "In11.Cu")
	)
	(gr_line
		(start 402.901912 -112.413034)
		(end 402.960332 -112.413034)
		(stroke
			(width 0.04445)
			(type default)
		)
		(layer "In11.Cu")
	)
	(gr_line
		(start 402.947124 -119.287798)
		(end 402.986494 -119.327168)
		(stroke
			(width 0.04445)
			(type default)
		)
		(layer "In11.Cu")
	)
	(gr_line
		(start 402.947124 -119.097298)
		(end 402.986494 -119.057928)
		(stroke
			(width 0.04445)
			(type default)
		)
		(layer "In11.Cu")
	)
	(gr_line
		(start 402.947886 -17.10436)
		(end 403.303486 -17.10436)
		(stroke
			(width 0.05715)
			(type default)
		)
		(layer "In11.Cu")
	)
	(gr_line
		(start 402.988272 -119.328946)
		(end 402.997924 -119.338598)
		(stroke
			(width 0.04445)
			(type default)
		)
		(layer "In11.Cu")
	)
	(gr_line
		(start 402.988272 -119.05615)
		(end 402.997924 -119.046498)
		(stroke
			(width 0.04445)
			(type default)
		)
		(layer "In11.Cu")
	)
	(gr_line
		(start 402.997924 -119.338598)
		(end 403.020022 -119.338598)
		(stroke
			(width 0.04445)
			(type default)
		)
		(layer "In11.Cu")
	)
	(gr_line
		(start 402.997924 -119.046498)
		(end 403.020022 -119.046498)
		(stroke
			(width 0.04445)
			(type default)
		)
		(layer "In11.Cu")
	)
	(gr_line
		(start 403.064472 -112.692434)
		(end 403.150832 -112.606074)
		(stroke
			(width 0.04445)
			(type default)
		)
		(layer "In11.Cu")
	)
	(gr_line
		(start 403.077426 -16.64716)
		(end 403.173946 -16.64716)
		(stroke
			(width 0.05715)
			(type default)
		)
		(layer "In11.Cu")
	)
	(gr_line
		(start 403.303486 -17.10436)
		(end 403.466046 -16.9418)
		(stroke
			(width 0.05715)
			(type default)
		)
		(layer "In11.Cu")
	)
	(gr_line
		(start 403.314154 -61.62294)
		(end 403.331426 -61.63437)
		(stroke
			(width 0.05715)
			(type default)
		)
		(layer "In11.Cu")
	)
	(gr_line
		(start 403.32279 -117.516656)
		(end 403.323044 -117.584728)
		(stroke
			(width 0.04445)
			(type default)
		)
		(layer "In11.Cu")
	)
	(gr_line
		(start 403.32279 -117.516656)
		(end 403.338284 -117.501162)
		(stroke
			(width 0.04445)
			(type default)
		)
		(layer "In11.Cu")
	)
	(gr_line
		(start 403.331426 -61.63437)
		(end 403.342856 -61.651642)
		(stroke
			(width 0.05715)
			(type default)
		)
		(layer "In11.Cu")
	)
	(gr_line
		(start 403.394672 -75.207876)
		(end 403.407626 -75.255628)
		(stroke
			(width 0.05715)
			(type default)
		)
		(layer "In11.Cu")
	)
	(gr_line
		(start 403.394672 -75.207876)
		(end 403.409912 -75.16114)
		(stroke
			(width 0.05715)
			(type default)
		)
		(layer "In11.Cu")
	)
	(gr_line
		(start 403.422612 -112.606074)
		(end 403.508972 -112.692434)
		(stroke
			(width 0.04445)
			(type default)
		)
		(layer "In11.Cu")
	)
	(gr_line
		(start 403.474428 -117.707918)
		(end 403.544786 -117.707918)
		(stroke
			(width 0.04445)
			(type default)
		)
		(layer "In11.Cu")
	)
	(gr_line
		(start 403.496526 -76.908914)
		(end 403.49932 -76.891896)
		(stroke
			(width 0.05715)
			(type default)
		)
		(layer "In11.Cu")
	)
	(gr_line
		(start 403.496526 -76.908914)
		(end 403.500082 -76.925424)
		(stroke
			(width 0.05715)
			(type default)
		)
		(layer "In11.Cu")
	)
	(gr_line
		(start 403.508972 -112.692434)
		(end 403.775672 -112.692434)
		(stroke
			(width 0.04445)
			(type default)
		)
		(layer "In11.Cu")
	)
	(gr_line
		(start 403.531578 -145.758154)
		(end 403.554184 -145.753328)
		(stroke
			(width 0.05715)
			(type default)
		)
		(layer "In11.Cu")
	)
	(gr_line
		(start 403.554184 -145.753328)
		(end 403.575774 -145.757646)
		(stroke
			(width 0.05715)
			(type default)
		)
		(layer "In11.Cu")
	)
	(gr_line
		(start 403.61235 -126.14021)
		(end 403.77618 -126.30404)
		(stroke
			(width 0.05715)
			(type default)
		)
		(layer "In11.Cu")
	)
	(gr_line
		(start 403.61235 -125.97765)
		(end 403.61235 -126.14021)
		(stroke
			(width 0.05715)
			(type default)
		)
		(layer "In11.Cu")
	)
	(gr_line
		(start 403.613112 -112.413034)
		(end 403.671532 -112.413034)
		(stroke
			(width 0.04445)
			(type default)
		)
		(layer "In11.Cu")
	)
	(gr_line
		(start 403.775672 -112.692434)
		(end 403.862032 -112.606074)
		(stroke
			(width 0.04445)
			(type default)
		)
		(layer "In11.Cu")
	)
	(gr_line
		(start 403.826726 -16.9418)
		(end 403.989286 -17.10436)
		(stroke
			(width 0.05715)
			(type default)
		)
		(layer "In11.Cu")
	)
	(gr_line
		(start 403.921722 -76.035662)
		(end 403.928326 -76.059538)
		(stroke
			(width 0.05715)
			(type default)
		)
		(layer "In11.Cu")
	)
	(gr_line
		(start 403.924516 -76.083414)
		(end 403.928326 -76.059538)
		(stroke
			(width 0.05715)
			(type default)
		)
		(layer "In11.Cu")
	)
	(gr_line
		(start 403.968712 -79.167736)
		(end 403.972522 -79.185516)
		(stroke
			(width 0.05715)
			(type default)
		)
		(layer "In11.Cu")
	)
	(gr_line
		(start 403.972522 -79.185516)
		(end 403.982428 -79.200502)
		(stroke
			(width 0.05715)
			(type default)
		)
		(layer "In11.Cu")
	)
	(gr_line
		(start 403.989286 -17.10436)
		(end 404.344886 -17.10436)
		(stroke
			(width 0.05715)
			(type default)
		)
		(layer "In11.Cu")
	)
	(gr_line
		(start 404.04161 -61.322458)
		(end 404.05812 -61.33338)
		(stroke
			(width 0.05715)
			(type default)
		)
		(layer "In11.Cu")
	)
	(gr_line
		(start 404.05812 -61.33338)
		(end 404.077424 -61.337444)
		(stroke
			(width 0.05715)
			(type default)
		)
		(layer "In11.Cu")
	)
	(gr_line
		(start 404.118826 -16.64716)
		(end 404.215346 -16.64716)
		(stroke
			(width 0.05715)
			(type default)
		)
		(layer "In11.Cu")
	)
	(gr_line
		(start 404.15972 -118.26748)
		(end 404.15972 -118.330218)
		(stroke
			(width 0.04445)
			(type default)
		)
		(layer "In11.Cu")
	)
	(gr_line
		(start 404.15972 -118.25859)
		(end 404.15972 -118.26494)
		(stroke
			(width 0.04445)
			(type default)
		)
		(layer "In11.Cu")
	)
	(gr_line
		(start 404.15972 -118.25859)
		(end 404.175214 -118.243096)
		(stroke
			(width 0.04445)
			(type default)
		)
		(layer "In11.Cu")
	)
	(gr_line
		(start 404.192994 -126.30404)
		(end 404.37435 -126.122684)
		(stroke
			(width 0.05715)
			(type default)
		)
		(layer "In11.Cu")
	)
	(gr_line
		(start 404.201122 -125.0442)
		(end 404.259542 -125.0442)
		(stroke
			(width 0.05715)
			(type default)
		)
		(layer "In11.Cu")
	)
	(gr_line
		(start 404.24989 -112.603534)
		(end 404.28926 -112.642904)
		(stroke
			(width 0.04445)
			(type default)
		)
		(layer "In11.Cu")
	)
	(gr_line
		(start 404.24989 -112.413034)
		(end 404.28926 -112.373664)
		(stroke
			(width 0.04445)
			(type default)
		)
		(layer "In11.Cu")
	)
	(gr_line
		(start 404.28418 -111.214916)
		(end 404.305262 -111.210598)
		(stroke
			(width 0.05715)
			(type default)
		)
		(layer "In11.Cu")
	)
	(gr_line
		(start 404.291038 -112.644682)
		(end 404.30069 -112.654334)
		(stroke
			(width 0.04445)
			(type default)
		)
		(layer "In11.Cu")
	)
	(gr_line
		(start 404.291038 -112.371886)
		(end 404.30069 -112.362234)
		(stroke
			(width 0.04445)
			(type default)
		)
		(layer "In11.Cu")
	)
	(gr_line
		(start 404.30069 -112.654334)
		(end 404.322788 -112.654334)
		(stroke
			(width 0.04445)
			(type default)
		)
		(layer "In11.Cu")
	)
	(gr_line
		(start 404.30069 -112.362234)
		(end 404.322788 -112.362234)
		(stroke
			(width 0.04445)
			(type default)
		)
		(layer "In11.Cu")
	)
	(gr_line
		(start 404.301452 -118.45798)
		(end 404.35022 -118.45798)
		(stroke
			(width 0.04445)
			(type default)
		)
		(layer "In11.Cu")
	)
	(gr_line
		(start 404.305262 -111.210598)
		(end 404.323296 -111.19866)
		(stroke
			(width 0.05715)
			(type default)
		)
		(layer "In11.Cu")
	)
	(gr_line
		(start 404.330408 -147.735544)
		(end 404.377906 -147.755102)
		(stroke
			(width 0.05715)
			(type default)
		)
		(layer "In11.Cu")
	)
	(gr_line
		(start 404.337774 -70.39737)
		(end 404.411434 -70.062344)
		(stroke
			(width 0.05715)
			(type default)
		)
		(layer "In11.Cu")
	)
	(gr_line
		(start 404.337774 -70.39737)
		(end 404.461726 -70.591172)
		(stroke
			(width 0.05715)
			(type default)
		)
		(layer "In11.Cu")
	)
	(gr_line
		(start 404.344886 -17.10436)
		(end 404.507446 -16.9418)
		(stroke
			(width 0.05715)
			(type default)
		)
		(layer "In11.Cu")
	)
	(gr_line
		(start 404.35276 -118.45798)
		(end 404.373588 -118.45798)
		(stroke
			(width 0.04445)
			(type default)
		)
		(layer "In11.Cu")
	)
	(gr_line
		(start 404.373588 -118.45798)
		(end 404.381716 -118.449852)
		(stroke
			(width 0.04445)
			(type default)
		)
		(layer "In11.Cu")
	)
	(gr_line
		(start 404.37435 -125.97765)
		(end 404.37435 -126.122684)
		(stroke
			(width 0.05715)
			(type default)
		)
		(layer "In11.Cu")
	)
	(gr_line
		(start 404.411434 -70.062344)
		(end 404.605236 -69.938392)
		(stroke
			(width 0.05715)
			(type default)
		)
		(layer "In11.Cu")
	)
	(gr_line
		(start 404.490682 -125.226318)
		(end 404.549102 -125.226318)
		(stroke
			(width 0.05715)
			(type default)
		)
		(layer "In11.Cu")
	)
	(gr_line
		(start 404.495762 -96.042988)
		(end 404.50008 -96.064324)
		(stroke
			(width 0.05715)
			(type default)
		)
		(layer "In11.Cu")
	)
	(gr_line
		(start 404.495762 -96.042988)
		(end 404.50008 -96.021652)
		(stroke
			(width 0.05715)
			(type default)
		)
		(layer "In11.Cu")
	)
	(gr_line
		(start 404.507954 -76.570586)
		(end 404.509478 -76.560426)
		(stroke
			(width 0.05715)
			(type default)
		)
		(layer "In11.Cu")
	)
	(gr_line
		(start 404.507954 -76.570586)
		(end 404.509732 -76.581)
		(stroke
			(width 0.05715)
			(type default)
		)
		(layer "In11.Cu")
	)
	(gr_line
		(start 404.509478 -76.560172)
		(end 404.509732 -76.55941)
		(stroke
			(width 0.05715)
			(type default)
		)
		(layer "In11.Cu")
	)
	(gr_line
		(start 404.55596 -69.404992)
		(end 404.62962 -69.07022)
		(stroke
			(width 0.05715)
			(type default)
		)
		(layer "In11.Cu")
	)
	(gr_line
		(start 404.55596 -69.404992)
		(end 404.679912 -69.599048)
		(stroke
			(width 0.05715)
			(type default)
		)
		(layer "In11.Cu")
	)
	(gr_line
		(start 404.62962 -69.07022)
		(end 404.823422 -68.946268)
		(stroke
			(width 0.05715)
			(type default)
		)
		(layer "In11.Cu")
	)
	(gr_line
		(start 404.710138 -79.769462)
		(end 404.72106 -79.785972)
		(stroke
			(width 0.05715)
			(type default)
		)
		(layer "In11.Cu")
	)
	(gr_line
		(start 404.72106 -79.785972)
		(end 404.725124 -79.805276)
		(stroke
			(width 0.05715)
			(type default)
		)
		(layer "In11.Cu")
	)
	(gr_line
		(start 404.757128 -70.619874)
		(end 404.885906 -70.034912)
		(stroke
			(width 0.05715)
			(type default)
		)
		(layer "In11.Cu")
	)
	(gr_line
		(start 404.761192 -112.654334)
		(end 404.802594 -112.627156)
		(stroke
			(width 0.05715)
			(type default)
		)
		(layer "In11.Cu")
	)
	(gr_line
		(start 404.7744 -68.412868)
		(end 404.84806 -68.077842)
		(stroke
			(width 0.05715)
			(type default)
		)
		(layer "In11.Cu")
	)
	(gr_line
		(start 404.7744 -68.412868)
		(end 404.898352 -68.60667)
		(stroke
			(width 0.05715)
			(type default)
		)
		(layer "In11.Cu")
	)
	(gr_line
		(start 404.84806 -68.077842)
		(end 405.041862 -67.95389)
		(stroke
			(width 0.05715)
			(type default)
		)
		(layer "In11.Cu")
	)
	(gr_line
		(start 404.871682 -78.657958)
		(end 404.875238 -78.679548)
		(stroke
			(width 0.05715)
			(type default)
		)
		(layer "In11.Cu")
	)
	(gr_line
		(start 404.875238 -78.679548)
		(end 404.887684 -78.69809)
		(stroke
			(width 0.05715)
			(type default)
		)
		(layer "In11.Cu")
	)
	(gr_line
		(start 404.97506 -69.629274)
		(end 405.103838 -69.044058)
		(stroke
			(width 0.05715)
			(type default)
		)
		(layer "In11.Cu")
	)
	(gr_line
		(start 404.992586 -67.42049)
		(end 405.066246 -67.085718)
		(stroke
			(width 0.05715)
			(type default)
		)
		(layer "In11.Cu")
	)
	(gr_line
		(start 404.992586 -67.42049)
		(end 405.116538 -67.614546)
		(stroke
			(width 0.05715)
			(type default)
		)
		(layer "In11.Cu")
	)
	(gr_line
		(start 405.00427 -100.655882)
		(end 405.008588 -100.677218)
		(stroke
			(width 0.05715)
			(type default)
		)
		(layer "In11.Cu")
	)
	(gr_line
		(start 405.00427 -100.655882)
		(end 405.008588 -100.634546)
		(stroke
			(width 0.05715)
			(type default)
		)
		(layer "In11.Cu")
	)
	(gr_line
		(start 405.066246 -67.085718)
		(end 405.260048 -66.961512)
		(stroke
			(width 0.05715)
			(type default)
		)
		(layer "In11.Cu")
	)
	(gr_line
		(start 405.111458 -93.017594)
		(end 405.128476 -92.934282)
		(stroke
			(width 0.05715)
			(type default)
		)
		(layer "In11.Cu")
	)
	(gr_line
		(start 405.128476 -92.934282)
		(end 405.199088 -92.887546)
		(stroke
			(width 0.05715)
			(type default)
		)
		(layer "In11.Cu")
	)
	(gr_line
		(start 405.193754 -68.635118)
		(end 405.322278 -68.050918)
		(stroke
			(width 0.05715)
			(type default)
		)
		(layer "In11.Cu")
	)
	(gr_line
		(start 405.19604 -64.450976)
		(end 405.206962 -64.467486)
		(stroke
			(width 0.05715)
			(type default)
		)
		(layer "In11.Cu")
	)
	(gr_line
		(start 405.203406 -101.636576)
		(end 405.20747 -101.65588)
		(stroke
			(width 0.05715)
			(type default)
		)
		(layer "In11.Cu")
	)
	(gr_line
		(start 405.206962 -64.467486)
		(end 405.211026 -64.48679)
		(stroke
			(width 0.05715)
			(type default)
		)
		(layer "In11.Cu")
	)
	(gr_line
		(start 405.20747 -101.65588)
		(end 405.218392 -101.67239)
		(stroke
			(width 0.05715)
			(type default)
		)
		(layer "In11.Cu")
	)
	(gr_line
		(start 405.26081 -72.844152)
		(end 405.26462 -72.825864)
		(stroke
			(width 0.05715)
			(type default)
		)
		(layer "In11.Cu")
	)
	(gr_line
		(start 405.26462 -72.825864)
		(end 405.27478 -72.81037)
		(stroke
			(width 0.05715)
			(type default)
		)
		(layer "In11.Cu")
	)
	(gr_line
		(start 405.277574 -118.570502)
		(end 405.277574 -118.800626)
		(stroke
			(width 0.05715)
			(type default)
		)
		(layer "In11.Cu")
	)
	(gr_line
		(start 405.277574 -118.570502)
		(end 405.51989 -118.328186)
		(stroke
			(width 0.05715)
			(type default)
		)
		(layer "In11.Cu")
	)
	(gr_line
		(start 405.290274 -112.30483)
		(end 405.308562 -112.292638)
		(stroke
			(width 0.05715)
			(type default)
		)
		(layer "In11.Cu")
	)
	(gr_line
		(start 405.296116 -110.554516)
		(end 405.313388 -110.543086)
		(stroke
			(width 0.05715)
			(type default)
		)
		(layer "In11.Cu")
	)
	(gr_line
		(start 405.308562 -112.292638)
		(end 405.321008 -112.27435)
		(stroke
			(width 0.05715)
			(type default)
		)
		(layer "In11.Cu")
	)
	(gr_line
		(start 405.313388 -110.543086)
		(end 405.324818 -110.525814)
		(stroke
			(width 0.05715)
			(type default)
		)
		(layer "In11.Cu")
	)
	(gr_line
		(start 405.363172 -107.333542)
		(end 405.36749 -107.354878)
		(stroke
			(width 0.05715)
			(type default)
		)
		(layer "In11.Cu")
	)
	(gr_line
		(start 405.363172 -107.333542)
		(end 405.36749 -107.312206)
		(stroke
			(width 0.05715)
			(type default)
		)
		(layer "In11.Cu")
	)
	(gr_line
		(start 405.407114 -72.311006)
		(end 405.453088 -72.536812)
		(stroke
			(width 0.05715)
			(type default)
		)
		(layer "In11.Cu")
	)
	(gr_line
		(start 405.407114 -72.311006)
		(end 405.596344 -72.025256)
		(stroke
			(width 0.05715)
			(type default)
		)
		(layer "In11.Cu")
	)
	(gr_line
		(start 405.41194 -67.642994)
		(end 405.539956 -67.060318)
		(stroke
			(width 0.05715)
			(type default)
		)
		(layer "In11.Cu")
	)
	(gr_line
		(start 405.513032 -99.620324)
		(end 405.51735 -99.598988)
		(stroke
			(width 0.05715)
			(type default)
		)
		(layer "In11.Cu")
	)
	(gr_line
		(start 405.513032 -99.577652)
		(end 405.51735 -99.598988)
		(stroke
			(width 0.05715)
			(type default)
		)
		(layer "In11.Cu")
	)
	(gr_line
		(start 405.51989 -118.328186)
		(end 405.750014 -118.328186)
		(stroke
			(width 0.05715)
			(type default)
		)
		(layer "In11.Cu")
	)
	(gr_line
		(start 405.548338 -79.167228)
		(end 405.55926 -79.183738)
		(stroke
			(width 0.05715)
			(type default)
		)
		(layer "In11.Cu")
	)
	(gr_line
		(start 405.55926 -79.183738)
		(end 405.563324 -79.203296)
		(stroke
			(width 0.05715)
			(type default)
		)
		(layer "In11.Cu")
	)
	(gr_line
		(start 405.573484 -110.150402)
		(end 405.584406 -110.133892)
		(stroke
			(width 0.05715)
			(type default)
		)
		(layer "In11.Cu")
	)
	(gr_line
		(start 405.584406 -110.133892)
		(end 405.58847 -110.114588)
		(stroke
			(width 0.05715)
			(type default)
		)
		(layer "In11.Cu")
	)
	(gr_line
		(start 405.596344 -72.025256)
		(end 405.82215 -71.979028)
		(stroke
			(width 0.05715)
			(type default)
		)
		(layer "In11.Cu")
	)
	(gr_line
		(start 405.605488 -116.579396)
		(end 405.605488 -116.80952)
		(stroke
			(width 0.05715)
			(type default)
		)
		(layer "In11.Cu")
	)
	(gr_line
		(start 405.605488 -116.579396)
		(end 405.848058 -116.336826)
		(stroke
			(width 0.05715)
			(type default)
		)
		(layer "In11.Cu")
	)
	(gr_line
		(start 405.635968 -66.6242)
		(end 405.641048 -66.601594)
		(stroke
			(width 0.05715)
			(type default)
		)
		(layer "In11.Cu")
	)
	(gr_line
		(start 405.636222 -66.577464)
		(end 405.641048 -66.601594)
		(stroke
			(width 0.05715)
			(type default)
		)
		(layer "In11.Cu")
	)
	(gr_line
		(start 405.638254 -105.981754)
		(end 405.654764 -105.900982)
		(stroke
			(width 0.05715)
			(type default)
		)
		(layer "In11.Cu")
	)
	(gr_line
		(start 405.654764 -105.900982)
		(end 405.723598 -105.855262)
		(stroke
			(width 0.05715)
			(type default)
		)
		(layer "In11.Cu")
	)
	(gr_line
		(start 405.69261 -118.80215)
		(end 405.751538 -118.743222)
		(stroke
			(width 0.05715)
			(type default)
		)
		(layer "In11.Cu")
	)
	(gr_line
		(start 405.717502 -72.671178)
		(end 406.04948 -72.169782)
		(stroke
			(width 0.05715)
			(type default)
		)
		(layer "In11.Cu")
	)
	(gr_line
		(start 405.73452 -77.949806)
		(end 405.747728 -77.976476)
		(stroke
			(width 0.05715)
			(type default)
		)
		(layer "In11.Cu")
	)
	(gr_line
		(start 405.73452 -76.060046)
		(end 405.740616 -76.044298)
		(stroke
			(width 0.05715)
			(type default)
		)
		(layer "In11.Cu")
	)
	(gr_line
		(start 405.848058 -116.336826)
		(end 406.078182 -116.336826)
		(stroke
			(width 0.05715)
			(type default)
		)
		(layer "In11.Cu")
	)
	(gr_line
		(start 405.90343 -108.56595)
		(end 405.907748 -108.544614)
		(stroke
			(width 0.05715)
			(type default)
		)
		(layer "In11.Cu")
	)
	(gr_line
		(start 405.90343 -108.523278)
		(end 405.907748 -108.544614)
		(stroke
			(width 0.05715)
			(type default)
		)
		(layer "In11.Cu")
	)
	(gr_line
		(start 405.967946 -71.463662)
		(end 406.01392 -71.689468)
		(stroke
			(width 0.05715)
			(type default)
		)
		(layer "In11.Cu")
	)
	(gr_line
		(start 405.967946 -71.463662)
		(end 406.157176 -71.177912)
		(stroke
			(width 0.05715)
			(type default)
		)
		(layer "In11.Cu")
	)
	(gr_line
		(start 405.995886 -117.85219)
		(end 405.995886 -118.082314)
		(stroke
			(width 0.05715)
			(type default)
		)
		(layer "In11.Cu")
	)
	(gr_line
		(start 405.995886 -117.85219)
		(end 406.238456 -117.60962)
		(stroke
			(width 0.05715)
			(type default)
		)
		(layer "In11.Cu")
	)
	(gr_line
		(start 406.020524 -116.811044)
		(end 406.079706 -116.751862)
		(stroke
			(width 0.05715)
			(type default)
		)
		(layer "In11.Cu")
	)
	(gr_line
		(start 406.033478 -92.686124)
		(end 406.104344 -92.639134)
		(stroke
			(width 0.05715)
			(type default)
		)
		(layer "In11.Cu")
	)
	(gr_line
		(start 406.073864 -148.773642)
		(end 406.091136 -148.781008)
		(stroke
			(width 0.05715)
			(type default)
		)
		(layer "In11.Cu")
	)
	(gr_line
		(start 406.104344 -92.639134)
		(end 406.121362 -92.555822)
		(stroke
			(width 0.05715)
			(type default)
		)
		(layer "In11.Cu")
	)
	(gr_line
		(start 406.157176 -71.177912)
		(end 406.382982 -71.131684)
		(stroke
			(width 0.05715)
			(type default)
		)
		(layer "In11.Cu")
	)
	(gr_line
		(start 406.238456 -117.60962)
		(end 406.46858 -117.60962)
		(stroke
			(width 0.05715)
			(type default)
		)
		(layer "In11.Cu")
	)
	(gr_line
		(start 406.277826 -71.824596)
		(end 406.610312 -71.322438)
		(stroke
			(width 0.05715)
			(type default)
		)
		(layer "In11.Cu")
	)
	(gr_line
		(start 406.318212 -79.130906)
		(end 406.323546 -79.141574)
		(stroke
			(width 0.05715)
			(type default)
		)
		(layer "In11.Cu")
	)
	(gr_line
		(start 406.3238 -115.86083)
		(end 406.3238 -116.091208)
		(stroke
			(width 0.05715)
			(type default)
		)
		(layer "In11.Cu")
	)
	(gr_line
		(start 406.3238 -115.86083)
		(end 406.56637 -115.618514)
		(stroke
			(width 0.05715)
			(type default)
		)
		(layer "In11.Cu")
	)
	(gr_line
		(start 406.330658 -74.546206)
		(end 406.339548 -74.5236)
		(stroke
			(width 0.05715)
			(type default)
		)
		(layer "In11.Cu")
	)
	(gr_line
		(start 406.339548 -74.5236)
		(end 406.35682 -74.506328)
		(stroke
			(width 0.05715)
			(type default)
		)
		(layer "In11.Cu")
	)
	(gr_line
		(start 406.347676 -107.431078)
		(end 406.351994 -107.452414)
		(stroke
			(width 0.05715)
			(type default)
		)
		(layer "In11.Cu")
	)
	(gr_line
		(start 406.347676 -107.431078)
		(end 406.351994 -107.409742)
		(stroke
			(width 0.05715)
			(type default)
		)
		(layer "In11.Cu")
	)
	(gr_line
		(start 406.356312 -146.608546)
		(end 406.40762 -146.618706)
		(stroke
			(width 0.05715)
			(type default)
		)
		(layer "In11.Cu")
	)
	(gr_line
		(start 406.39619 -105.760012)
		(end 406.464516 -105.715054)
		(stroke
			(width 0.05715)
			(type default)
		)
		(layer "In11.Cu")
	)
	(gr_line
		(start 406.40762 -146.618706)
		(end 406.454864 -146.599148)
		(stroke
			(width 0.05715)
			(type default)
		)
		(layer "In11.Cu")
	)
	(gr_line
		(start 406.410922 -118.083838)
		(end 406.470104 -118.024656)
		(stroke
			(width 0.05715)
			(type default)
		)
		(layer "In11.Cu")
	)
	(gr_line
		(start 406.452832 -106.91368)
		(end 406.469596 -106.831384)
		(stroke
			(width 0.05715)
			(type default)
		)
		(layer "In11.Cu")
	)
	(gr_line
		(start 406.464516 -105.715054)
		(end 406.481026 -105.634282)
		(stroke
			(width 0.05715)
			(type default)
		)
		(layer "In11.Cu")
	)
	(gr_line
		(start 406.469596 -106.831384)
		(end 406.539446 -106.785156)
		(stroke
			(width 0.05715)
			(type default)
		)
		(layer "In11.Cu")
	)
	(gr_line
		(start 406.470104 -103.033068)
		(end 406.481026 -103.049578)
		(stroke
			(width 0.05715)
			(type default)
		)
		(layer "In11.Cu")
	)
	(gr_line
		(start 406.481026 -103.049578)
		(end 406.48509 -103.068882)
		(stroke
			(width 0.05715)
			(type default)
		)
		(layer "In11.Cu")
	)
	(gr_line
		(start 406.509474 -110.51413)
		(end 406.520904 -110.497112)
		(stroke
			(width 0.05715)
			(type default)
		)
		(layer "In11.Cu")
	)
	(gr_line
		(start 406.520904 -110.497112)
		(end 406.525222 -110.476284)
		(stroke
			(width 0.05715)
			(type default)
		)
		(layer "In11.Cu")
	)
	(gr_line
		(start 406.528778 -70.616318)
		(end 406.574752 -70.842124)
		(stroke
			(width 0.05715)
			(type default)
		)
		(layer "In11.Cu")
	)
	(gr_line
		(start 406.528778 -70.616318)
		(end 406.718008 -70.330568)
		(stroke
			(width 0.05715)
			(type default)
		)
		(layer "In11.Cu")
	)
	(gr_line
		(start 406.564592 -61.544454)
		(end 406.64765 -61.561472)
		(stroke
			(width 0.05715)
			(type default)
		)
		(layer "In11.Cu")
	)
	(gr_line
		(start 406.56637 -115.618514)
		(end 406.796494 -115.618514)
		(stroke
			(width 0.05715)
			(type default)
		)
		(layer "In11.Cu")
	)
	(gr_line
		(start 406.592786 -108.677456)
		(end 406.595834 -108.66247)
		(stroke
			(width 0.05715)
			(type default)
		)
		(layer "In11.Cu")
	)
	(gr_line
		(start 406.64765 -61.561472)
		(end 406.694386 -61.632084)
		(stroke
			(width 0.05715)
			(type default)
		)
		(layer "In11.Cu")
	)
	(gr_line
		(start 406.714198 -117.133624)
		(end 406.714198 -117.364002)
		(stroke
			(width 0.05715)
			(type default)
		)
		(layer "In11.Cu")
	)
	(gr_line
		(start 406.714198 -117.133624)
		(end 406.956768 -116.891308)
		(stroke
			(width 0.05715)
			(type default)
		)
		(layer "In11.Cu")
	)
	(gr_line
		(start 406.715468 -89.633298)
		(end 406.719786 -89.61247)
		(stroke
			(width 0.05715)
			(type default)
		)
		(layer "In11.Cu")
	)
	(gr_line
		(start 406.715468 -89.59088)
		(end 406.719786 -89.61247)
		(stroke
			(width 0.05715)
			(type default)
		)
		(layer "In11.Cu")
	)
	(gr_line
		(start 406.718008 -70.330568)
		(end 406.943814 -70.28434)
		(stroke
			(width 0.05715)
			(type default)
		)
		(layer "In11.Cu")
	)
	(gr_line
		(start 406.738836 -116.092732)
		(end 406.798018 -116.03355)
		(stroke
			(width 0.05715)
			(type default)
		)
		(layer "In11.Cu")
	)
	(gr_line
		(start 406.739598 -104.364028)
		(end 406.743916 -104.342692)
		(stroke
			(width 0.05715)
			(type default)
		)
		(layer "In11.Cu")
	)
	(gr_line
		(start 406.739598 -104.321356)
		(end 406.743916 -104.342692)
		(stroke
			(width 0.05715)
			(type default)
		)
		(layer "In11.Cu")
	)
	(gr_line
		(start 406.838658 -70.977252)
		(end 407.170636 -70.475602)
		(stroke
			(width 0.05715)
			(type default)
		)
		(layer "In11.Cu")
	)
	(gr_line
		(start 406.875488 -108.766102)
		(end 406.907746 -108.71708)
		(stroke
			(width 0.05715)
			(type default)
		)
		(layer "In11.Cu")
	)
	(gr_line
		(start 406.890728 -108.633514)
		(end 406.890982 -108.634276)
		(stroke
			(width 0.05715)
			(type default)
		)
		(layer "In11.Cu")
	)
	(gr_line
		(start 406.890982 -108.634022)
		(end 406.907746 -108.71708)
		(stroke
			(width 0.05715)
			(type default)
		)
		(layer "In11.Cu")
	)
	(gr_line
		(start 406.956768 -116.891308)
		(end 407.186892 -116.891308)
		(stroke
			(width 0.05715)
			(type default)
		)
		(layer "In11.Cu")
	)
	(gr_line
		(start 407.018998 -113.820448)
		(end 407.092658 -113.746788)
		(stroke
			(width 0.05715)
			(type default)
		)
		(layer "In11.Cu")
	)
	(gr_line
		(start 407.020522 -114.235484)
		(end 407.265378 -114.235484)
		(stroke
			(width 0.05715)
			(type default)
		)
		(layer "In11.Cu")
	)
	(gr_line
		(start 407.042366 -115.142518)
		(end 407.042366 -115.372642)
		(stroke
			(width 0.05715)
			(type default)
		)
		(layer "In11.Cu")
	)
	(gr_line
		(start 407.042366 -115.142518)
		(end 407.284682 -114.899948)
		(stroke
			(width 0.05715)
			(type default)
		)
		(layer "In11.Cu")
	)
	(gr_line
		(start 407.085292 -63.576962)
		(end 407.153618 -63.91275)
		(stroke
			(width 0.05715)
			(type default)
		)
		(layer "In11.Cu")
	)
	(gr_line
		(start 407.085292 -63.576962)
		(end 407.212292 -63.384938)
		(stroke
			(width 0.05715)
			(type default)
		)
		(layer "In11.Cu")
	)
	(gr_line
		(start 407.08961 -69.768974)
		(end 407.135584 -69.99478)
		(stroke
			(width 0.05715)
			(type default)
		)
		(layer "In11.Cu")
	)
	(gr_line
		(start 407.08961 -69.768974)
		(end 407.27884 -69.483224)
		(stroke
			(width 0.05715)
			(type default)
		)
		(layer "In11.Cu")
	)
	(gr_line
		(start 407.110438 -146.011646)
		(end 407.128218 -146.00428)
		(stroke
			(width 0.05715)
			(type default)
		)
		(layer "In11.Cu")
	)
	(gr_line
		(start 407.129234 -117.365526)
		(end 407.188416 -117.306344)
		(stroke
			(width 0.05715)
			(type default)
		)
		(layer "In11.Cu")
	)
	(gr_line
		(start 407.153618 -63.91275)
		(end 407.345642 -64.040004)
		(stroke
			(width 0.05715)
			(type default)
		)
		(layer "In11.Cu")
	)
	(gr_line
		(start 407.265378 -114.235484)
		(end 407.507694 -113.992914)
		(stroke
			(width 0.05715)
			(type default)
		)
		(layer "In11.Cu")
	)
	(gr_line
		(start 407.27884 -69.483224)
		(end 407.504646 -69.43725)
		(stroke
			(width 0.05715)
			(type default)
		)
		(layer "In11.Cu")
	)
	(gr_line
		(start 407.284682 -114.899948)
		(end 407.51506 -114.899948)
		(stroke
			(width 0.05715)
			(type default)
		)
		(layer "In11.Cu")
	)
	(gr_line
		(start 407.28773 -64.572388)
		(end 407.356056 -64.90843)
		(stroke
			(width 0.05715)
			(type default)
		)
		(layer "In11.Cu")
	)
	(gr_line
		(start 407.28773 -64.572388)
		(end 407.41473 -64.380618)
		(stroke
			(width 0.05715)
			(type default)
		)
		(layer "In11.Cu")
	)
	(gr_line
		(start 407.350468 -62.623446)
		(end 407.36139 -62.639956)
		(stroke
			(width 0.05715)
			(type default)
		)
		(layer "In11.Cu")
	)
	(gr_line
		(start 407.356056 -64.90843)
		(end 407.54808 -65.035684)
		(stroke
			(width 0.05715)
			(type default)
		)
		(layer "In11.Cu")
	)
	(gr_line
		(start 407.36139 -62.639956)
		(end 407.365454 -62.659514)
		(stroke
			(width 0.05715)
			(type default)
		)
		(layer "In11.Cu")
	)
	(gr_line
		(start 407.399998 -70.128892)
		(end 407.731214 -69.628512)
		(stroke
			(width 0.05715)
			(type default)
		)
		(layer "In11.Cu")
	)
	(gr_line
		(start 407.42616 -96.790764)
		(end 407.485088 -96.849692)
		(stroke
			(width 0.05715)
			(type default)
		)
		(layer "In11.Cu")
	)
	(gr_line
		(start 407.432764 -116.415312)
		(end 407.432764 -116.645436)
		(stroke
			(width 0.05715)
			(type default)
		)
		(layer "In11.Cu")
	)
	(gr_line
		(start 407.432764 -116.415312)
		(end 407.67508 -116.172742)
		(stroke
			(width 0.05715)
			(type default)
		)
		(layer "In11.Cu")
	)
	(gr_line
		(start 407.457402 -115.374166)
		(end 407.516584 -115.314984)
		(stroke
			(width 0.05715)
			(type default)
		)
		(layer "In11.Cu")
	)
	(gr_line
		(start 407.507694 -113.748312)
		(end 407.507694 -113.992914)
		(stroke
			(width 0.05715)
			(type default)
		)
		(layer "In11.Cu")
	)
	(gr_line
		(start 407.507948 -63.360046)
		(end 407.627328 -63.947294)
		(stroke
			(width 0.05715)
			(type default)
		)
		(layer "In11.Cu")
	)
	(gr_line
		(start 407.67508 -116.172742)
		(end 407.905458 -116.172742)
		(stroke
			(width 0.05715)
			(type default)
		)
		(layer "In11.Cu")
	)
	(gr_line
		(start 407.71064 -64.35725)
		(end 407.829766 -64.942466)
		(stroke
			(width 0.05715)
			(type default)
		)
		(layer "In11.Cu")
	)
	(gr_line
		(start 407.730706 -122.20956)
		(end 407.893266 -122.047)
		(stroke
			(width 0.05715)
			(type default)
		)
		(layer "In11.Cu")
	)
	(gr_line
		(start 407.751788 -113.087658)
		(end 407.811224 -113.028222)
		(stroke
			(width 0.05715)
			(type default)
		)
		(layer "In11.Cu")
	)
	(gr_line
		(start 407.753312 -113.502694)
		(end 407.98369 -113.502694)
		(stroke
			(width 0.05715)
			(type default)
		)
		(layer "In11.Cu")
	)
	(gr_line
		(start 407.760678 -114.423952)
		(end 407.760678 -114.65433)
		(stroke
			(width 0.05715)
			(type default)
		)
		(layer "In11.Cu")
	)
	(gr_line
		(start 407.760678 -114.423952)
		(end 408.003248 -114.181636)
		(stroke
			(width 0.05715)
			(type default)
		)
		(layer "In11.Cu")
	)
	(gr_line
		(start 407.8478 -116.64696)
		(end 407.906982 -116.587778)
		(stroke
			(width 0.05715)
			(type default)
		)
		(layer "In11.Cu")
	)
	(gr_line
		(start 407.893266 -122.047)
		(end 408.236166 -122.047)
		(stroke
			(width 0.05715)
			(type default)
		)
		(layer "In11.Cu")
	)
	(gr_line
		(start 407.898092 -16.2687)
		(end 408.126438 -16.497046)
		(stroke
			(width 0.05715)
			(type default)
		)
		(layer "In11.Cu")
	)
	(gr_line
		(start 407.949146 -97.314004)
		(end 408.00782 -97.372678)
		(stroke
			(width 0.05715)
			(type default)
		)
		(layer "In11.Cu")
	)
	(gr_line
		(start 407.98369 -113.502694)
		(end 408.22626 -113.260124)
		(stroke
			(width 0.05715)
			(type default)
		)
		(layer "In11.Cu")
	)
	(gr_line
		(start 408.003248 -114.181636)
		(end 408.233372 -114.181636)
		(stroke
			(width 0.05715)
			(type default)
		)
		(layer "In11.Cu")
	)
	(gr_line
		(start 408.005788 -88.721946)
		(end 408.01544 -88.770206)
		(stroke
			(width 0.05715)
			(type default)
		)
		(layer "In11.Cu")
	)
	(gr_line
		(start 408.022806 -122.5042)
		(end 408.106626 -122.5042)
		(stroke
			(width 0.05715)
			(type default)
		)
		(layer "In11.Cu")
	)
	(gr_line
		(start 408.068272 -69.119242)
		(end 408.079194 -69.102732)
		(stroke
			(width 0.05715)
			(type default)
		)
		(layer "In11.Cu")
	)
	(gr_line
		(start 408.079194 -69.102732)
		(end 408.083258 -69.083428)
		(stroke
			(width 0.05715)
			(type default)
		)
		(layer "In11.Cu")
	)
	(gr_line
		(start 408.087576 -118.243858)
		(end 408.087576 -118.327678)
		(stroke
			(width 0.05715)
			(type default)
		)
		(layer "In11.Cu")
	)
	(gr_line
		(start 408.12085 -106.05135)
		(end 408.180032 -105.991914)
		(stroke
			(width 0.05715)
			(type default)
		)
		(layer "In11.Cu")
	)
	(gr_line
		(start 408.1653 -148.781008)
		(end 408.182572 -148.773642)
		(stroke
			(width 0.05715)
			(type default)
		)
		(layer "In11.Cu")
	)
	(gr_line
		(start 408.175714 -114.655854)
		(end 408.234896 -114.596672)
		(stroke
			(width 0.05715)
			(type default)
		)
		(layer "In11.Cu")
	)
	(gr_line
		(start 408.190192 -15.97406)
		(end 408.546808 -15.97406)
		(stroke
			(width 0.05715)
			(type default)
		)
		(layer "In11.Cu")
	)
	(gr_line
		(start 408.22626 -113.029746)
		(end 408.22626 -113.260124)
		(stroke
			(width 0.05715)
			(type default)
		)
		(layer "In11.Cu")
	)
	(gr_line
		(start 408.236166 -122.047)
		(end 408.398726 -122.20956)
		(stroke
			(width 0.05715)
			(type default)
		)
		(layer "In11.Cu")
	)
	(gr_line
		(start 408.368246 -115.102386)
		(end 408.427174 -115.043712)
		(stroke
			(width 0.05715)
			(type default)
		)
		(layer "In11.Cu")
	)
	(gr_line
		(start 408.373326 -67.656964)
		(end 408.377644 -67.635628)
		(stroke
			(width 0.05715)
			(type default)
		)
		(layer "In11.Cu")
	)
	(gr_line
		(start 408.373326 -67.614292)
		(end 408.377644 -67.635628)
		(stroke
			(width 0.05715)
			(type default)
		)
		(layer "In11.Cu")
	)
	(gr_line
		(start 408.382216 -118.619778)
		(end 408.544776 -118.457218)
		(stroke
			(width 0.05715)
			(type default)
		)
		(layer "In11.Cu")
	)
	(gr_line
		(start 408.382216 -117.951758)
		(end 408.544776 -118.114318)
		(stroke
			(width 0.05715)
			(type default)
		)
		(layer "In11.Cu")
	)
	(gr_line
		(start 408.544776 -118.114318)
		(end 408.544776 -118.457218)
		(stroke
			(width 0.05715)
			(type default)
		)
		(layer "In11.Cu")
	)
	(gr_line
		(start 408.827986 -126.037594)
		(end 408.990546 -126.200154)
		(stroke
			(width 0.05715)
			(type default)
		)
		(layer "In11.Cu")
	)
	(gr_line
		(start 408.851608 -114.619278)
		(end 408.910536 -114.56035)
		(stroke
			(width 0.05715)
			(type default)
		)
		(layer "In11.Cu")
	)
	(gr_line
		(start 408.868118 -72.409304)
		(end 408.929586 -72.347836)
		(stroke
			(width 0.05715)
			(type default)
		)
		(layer "In11.Cu")
	)
	(gr_line
		(start 408.990546 -126.200154)
		(end 409.333446 -126.200154)
		(stroke
			(width 0.05715)
			(type default)
		)
		(layer "In11.Cu")
	)
	(gr_line
		(start 409.120086 -125.742954)
		(end 409.203906 -125.742954)
		(stroke
			(width 0.05715)
			(type default)
		)
		(layer "In11.Cu")
	)
	(gr_line
		(start 409.333446 -126.200154)
		(end 409.496006 -126.037594)
		(stroke
			(width 0.05715)
			(type default)
		)
		(layer "In11.Cu")
	)
	(gr_line
		(start 409.818586 -52.3113)
		(end 409.87726 -52.369974)
		(stroke
			(width 0.05715)
			(type default)
		)
		(layer "In11.Cu")
	)
	(gr_line
		(start 409.956 -120.89638)
		(end 410.219144 -120.633236)
		(stroke
			(width 0.05715)
			(type default)
		)
		(layer "In11.Cu")
	)
	(gr_line
		(start 410.001466 -147.704556)
		(end 410.018738 -147.69719)
		(stroke
			(width 0.05715)
			(type default)
		)
		(layer "In11.Cu")
	)
	(gr_line
		(start 410.635958 -120.633236)
		(end 410.8958 -120.893078)
		(stroke
			(width 0.05715)
			(type default)
		)
		(layer "In11.Cu")
	)
	(gr_line
		(start 411.353 -46.975776)
		(end 411.508448 -47.131224)
		(stroke
			(width 0.05715)
			(type default)
		)
		(layer "In11.Cu")
	)
	(gr_line
		(start 411.85084 -140.024104)
		(end 411.874716 -140.019532)
		(stroke
			(width 0.05715)
			(type default)
		)
		(layer "In11.Cu")
	)
	(gr_line
		(start 411.860492 -139.373356)
		(end 411.884368 -139.368784)
		(stroke
			(width 0.05715)
			(type default)
		)
		(layer "In11.Cu")
	)
	(gr_line
		(start 411.872684 -138.722354)
		(end 411.89656 -138.717782)
		(stroke
			(width 0.05715)
			(type default)
		)
		(layer "In11.Cu")
	)
	(gr_line
		(start 411.874716 -140.019532)
		(end 411.898338 -140.024866)
		(stroke
			(width 0.05715)
			(type default)
		)
		(layer "In11.Cu")
	)
	(gr_line
		(start 411.882336 -138.07186)
		(end 411.906212 -138.067288)
		(stroke
			(width 0.05715)
			(type default)
		)
		(layer "In11.Cu")
	)
	(gr_line
		(start 411.884368 -139.368784)
		(end 411.88513 -139.368784)
		(stroke
			(width 0.05715)
			(type default)
		)
		(layer "In11.Cu")
	)
	(gr_line
		(start 411.88513 -139.368784)
		(end 411.909006 -139.374372)
		(stroke
			(width 0.05715)
			(type default)
		)
		(layer "In11.Cu")
	)
	(gr_line
		(start 411.893004 -137.421112)
		(end 411.916626 -137.416286)
		(stroke
			(width 0.05715)
			(type default)
		)
		(layer "In11.Cu")
	)
	(gr_line
		(start 411.89656 -138.717782)
		(end 411.920182 -138.723116)
		(stroke
			(width 0.05715)
			(type default)
		)
		(layer "In11.Cu")
	)
	(gr_line
		(start 411.906212 -138.067288)
		(end 411.929834 -138.072622)
		(stroke
			(width 0.05715)
			(type default)
		)
		(layer "In11.Cu")
	)
	(gr_line
		(start 411.916626 -137.416286)
		(end 411.917388 -137.416286)
		(stroke
			(width 0.05715)
			(type default)
		)
		(layer "In11.Cu")
	)
	(gr_line
		(start 411.917388 -137.416286)
		(end 411.94101 -137.42162)
		(stroke
			(width 0.05715)
			(type default)
		)
		(layer "In11.Cu")
	)
	(gr_line
		(start 411.925008 -47.131224)
		(end 412.050992 -47.00524)
		(stroke
			(width 0.05715)
			(type default)
		)
		(layer "In11.Cu")
	)
	(gr_line
		(start 411.947614 -136.761474)
		(end 411.97149 -136.756902)
		(stroke
			(width 0.05715)
			(type default)
		)
		(layer "In11.Cu")
	)
	(gr_line
		(start 412.115508 -64.94907)
		(end 412.278068 -65.11163)
		(stroke
			(width 0.05715)
			(type default)
		)
		(layer "In11.Cu")
	)
	(gr_line
		(start 412.115508 -64.60617)
		(end 412.115508 -64.94907)
		(stroke
			(width 0.05715)
			(type default)
		)
		(layer "In11.Cu")
	)
	(gr_line
		(start 412.115508 -64.60617)
		(end 412.278068 -64.44361)
		(stroke
			(width 0.05715)
			(type default)
		)
		(layer "In11.Cu")
	)
	(gr_line
		(start 412.115508 -63.93307)
		(end 412.278068 -64.09563)
		(stroke
			(width 0.05715)
			(type default)
		)
		(layer "In11.Cu")
	)
	(gr_line
		(start 412.115508 -63.59017)
		(end 412.115508 -63.93307)
		(stroke
			(width 0.05715)
			(type default)
		)
		(layer "In11.Cu")
	)
	(gr_line
		(start 412.115508 -63.59017)
		(end 412.278068 -63.42761)
		(stroke
			(width 0.05715)
			(type default)
		)
		(layer "In11.Cu")
	)
	(gr_line
		(start 412.42107 -118.632986)
		(end 412.42107 -118.83517)
		(stroke
			(width 0.05715)
			(type default)
		)
		(layer "In11.Cu")
	)
	(gr_line
		(start 412.42107 -118.632986)
		(end 412.49219 -118.561866)
		(stroke
			(width 0.05715)
			(type default)
		)
		(layer "In11.Cu")
	)
	(gr_line
		(start 412.432246 -118.085108)
		(end 412.49219 -118.145052)
		(stroke
			(width 0.05715)
			(type default)
		)
		(layer "In11.Cu")
	)
	(gr_line
		(start 412.432246 -117.910102)
		(end 412.432246 -118.085108)
		(stroke
			(width 0.05715)
			(type default)
		)
		(layer "In11.Cu")
	)
	(gr_line
		(start 412.572708 -64.73571)
		(end 412.572708 -64.81953)
		(stroke
			(width 0.05715)
			(type default)
		)
		(layer "In11.Cu")
	)
	(gr_line
		(start 412.572708 -63.71971)
		(end 412.572708 -63.80353)
		(stroke
			(width 0.05715)
			(type default)
		)
		(layer "In11.Cu")
	)
	(gr_line
		(start 412.642558 -68.020438)
		(end 412.903416 -68.281296)
		(stroke
			(width 0.05715)
			(type default)
		)
		(layer "In11.Cu")
	)
	(gr_line
		(start 412.642558 -67.916806)
		(end 412.642558 -68.020438)
		(stroke
			(width 0.05715)
			(type default)
		)
		(layer "In11.Cu")
	)
	(gr_line
		(start 412.642558 -67.916806)
		(end 412.643066 -67.916298)
		(stroke
			(width 0.05715)
			(type default)
		)
		(layer "In11.Cu")
	)
	(gr_line
		(start 412.643066 -67.815968)
		(end 412.643066 -67.916298)
		(stroke
			(width 0.05715)
			(type default)
		)
		(layer "In11.Cu")
	)
	(gr_line
		(start 412.673038 -55.166006)
		(end 412.731966 -55.224934)
		(stroke
			(width 0.05715)
			(type default)
		)
		(layer "In11.Cu")
	)
	(gr_line
		(start 412.701486 -80.990694)
		(end 412.701486 -81.220818)
		(stroke
			(width 0.05715)
			(type default)
		)
		(layer "In11.Cu")
	)
	(gr_line
		(start 412.701486 -80.990694)
		(end 412.943802 -80.748378)
		(stroke
			(width 0.05715)
			(type default)
		)
		(layer "In11.Cu")
	)
	(gr_line
		(start 412.903416 -68.281296)
		(end 413.007048 -68.281296)
		(stroke
			(width 0.05715)
			(type default)
		)
		(layer "In11.Cu")
	)
	(gr_line
		(start 412.943802 -80.748378)
		(end 413.173926 -80.748378)
		(stroke
			(width 0.05715)
			(type default)
		)
		(layer "In11.Cu")
	)
	(gr_line
		(start 413.007048 -68.281296)
		(end 413.007556 -68.280788)
		(stroke
			(width 0.05715)
			(type default)
		)
		(layer "In11.Cu")
	)
	(gr_line
		(start 413.007556 -68.280788)
		(end 413.107886 -68.280788)
		(stroke
			(width 0.05715)
			(type default)
		)
		(layer "In11.Cu")
	)
	(gr_line
		(start 413.058102 -67.814444)
		(end 413.10941 -67.865752)
		(stroke
			(width 0.05715)
			(type default)
		)
		(layer "In11.Cu")
	)
	(gr_line
		(start 413.116522 -81.222342)
		(end 413.17545 -81.163414)
		(stroke
			(width 0.05715)
			(type default)
		)
		(layer "In11.Cu")
	)
	(gr_line
		(start 413.419798 -80.272382)
		(end 413.419798 -80.502506)
		(stroke
			(width 0.05715)
			(type default)
		)
		(layer "In11.Cu")
	)
	(gr_line
		(start 413.419798 -80.272382)
		(end 413.662114 -80.030066)
		(stroke
			(width 0.05715)
			(type default)
		)
		(layer "In11.Cu")
	)
	(gr_line
		(start 413.662114 -80.030066)
		(end 413.892238 -80.030066)
		(stroke
			(width 0.05715)
			(type default)
		)
		(layer "In11.Cu")
	)
	(gr_line
		(start 413.7533 -49.617376)
		(end 414.0073 -49.363376)
		(stroke
			(width 0.05715)
			(type default)
		)
		(layer "In11.Cu")
	)
	(gr_line
		(start 413.834834 -80.50403)
		(end 413.893762 -80.445102)
		(stroke
			(width 0.05715)
			(type default)
		)
		(layer "In11.Cu")
	)
	(gr_line
		(start 414.3248 -65.132458)
		(end 414.3248 -65.216278)
		(stroke
			(width 0.05715)
			(type default)
		)
		(layer "In11.Cu")
	)
	(gr_line
		(start 414.42386 -49.363376)
		(end 414.67786 -49.617376)
		(stroke
			(width 0.05715)
			(type default)
		)
		(layer "In11.Cu")
	)
	(gr_line
		(start 414.61944 -65.508378)
		(end 414.782 -65.345818)
		(stroke
			(width 0.05715)
			(type default)
		)
		(layer "In11.Cu")
	)
	(gr_line
		(start 414.61944 -64.840358)
		(end 414.782 -65.002918)
		(stroke
			(width 0.05715)
			(type default)
		)
		(layer "In11.Cu")
	)
	(gr_line
		(start 414.755584 -83.056984)
		(end 414.755584 -83.074002)
		(stroke
			(width 0.05715)
			(type default)
		)
		(layer "In11.Cu")
	)
	(gr_line
		(start 414.782 -65.002918)
		(end 414.782 -65.345818)
		(stroke
			(width 0.05715)
			(type default)
		)
		(layer "In11.Cu")
	)
	(gr_line
		(start 414.8963 -82.767424)
		(end 414.8963 -82.784442)
		(stroke
			(width 0.05715)
			(type default)
		)
		(layer "In11.Cu")
	)
	(gr_line
		(start 415.109914 -141.066266)
		(end 415.137854 -141.072616)
		(stroke
			(width 0.05715)
			(type default)
		)
		(layer "In11.Cu")
	)
	(gr_line
		(start 415.111946 -140.413486)
		(end 415.139886 -140.419836)
		(stroke
			(width 0.05715)
			(type default)
		)
		(layer "In11.Cu")
	)
	(gr_line
		(start 415.113216 -139.760452)
		(end 415.141156 -139.766802)
		(stroke
			(width 0.05715)
			(type default)
		)
		(layer "In11.Cu")
	)
	(gr_line
		(start 415.113724 -139.107418)
		(end 415.141664 -139.113768)
		(stroke
			(width 0.05715)
			(type default)
		)
		(layer "In11.Cu")
	)
	(gr_line
		(start 415.11601 -138.454638)
		(end 415.143442 -138.460988)
		(stroke
			(width 0.05715)
			(type default)
		)
		(layer "In11.Cu")
	)
	(gr_line
		(start 415.137854 -141.072616)
		(end 415.166048 -141.066266)
		(stroke
			(width 0.05715)
			(type default)
		)
		(layer "In11.Cu")
	)
	(gr_line
		(start 415.139886 -140.419836)
		(end 415.16808 -140.413486)
		(stroke
			(width 0.05715)
			(type default)
		)
		(layer "In11.Cu")
	)
	(gr_line
		(start 415.141156 -139.766802)
		(end 415.16935 -139.760452)
		(stroke
			(width 0.05715)
			(type default)
		)
		(layer "In11.Cu")
	)
	(gr_line
		(start 415.141664 -139.113768)
		(end 415.142172 -139.113768)
		(stroke
			(width 0.05715)
			(type default)
		)
		(layer "In11.Cu")
	)
	(gr_line
		(start 415.142172 -139.113768)
		(end 415.17062 -139.107418)
		(stroke
			(width 0.05715)
			(type default)
		)
		(layer "In11.Cu")
	)
	(gr_line
		(start 415.143442 -138.460988)
		(end 415.171382 -138.454638)
		(stroke
			(width 0.05715)
			(type default)
		)
		(layer "In11.Cu")
	)
	(gr_line
		(start 415.158174 -137.792206)
		(end 415.186114 -137.798556)
		(stroke
			(width 0.05715)
			(type default)
		)
		(layer "In11.Cu")
	)
	(gr_line
		(start 415.186114 -137.798556)
		(end 415.214308 -137.792206)
		(stroke
			(width 0.05715)
			(type default)
		)
		(layer "In11.Cu")
	)
	(gr_line
		(start 415.379154 -47.102776)
		(end 415.644584 -46.837346)
		(stroke
			(width 0.05715)
			(type default)
		)
		(layer "In11.Cu")
	)
	(gr_line
		(start 415.811716 -119.590058)
		(end 415.811716 -119.820182)
		(stroke
			(width 0.05715)
			(type default)
		)
		(layer "In11.Cu")
	)
	(gr_line
		(start 415.811716 -119.590058)
		(end 416.054286 -119.347488)
		(stroke
			(width 0.05715)
			(type default)
		)
		(layer "In11.Cu")
	)
	(gr_line
		(start 416.054286 -119.347488)
		(end 416.28441 -119.347488)
		(stroke
			(width 0.05715)
			(type default)
		)
		(layer "In11.Cu")
	)
	(gr_line
		(start 416.061398 -46.837346)
		(end 416.371532 -47.14748)
		(stroke
			(width 0.05715)
			(type default)
		)
		(layer "In11.Cu")
	)
	(gr_line
		(start 416.226752 -119.821706)
		(end 416.285934 -119.762524)
		(stroke
			(width 0.05715)
			(type default)
		)
		(layer "In11.Cu")
	)
	(gr_line
		(start 416.530282 -118.871492)
		(end 416.530282 -119.101616)
		(stroke
			(width 0.05715)
			(type default)
		)
		(layer "In11.Cu")
	)
	(gr_line
		(start 416.530282 -118.871492)
		(end 416.772598 -118.629176)
		(stroke
			(width 0.05715)
			(type default)
		)
		(layer "In11.Cu")
	)
	(gr_line
		(start 416.562794 -140.450316)
		(end 416.591496 -140.443712)
		(stroke
			(width 0.05715)
			(type default)
		)
		(layer "In11.Cu")
	)
	(gr_line
		(start 416.566096 -139.79652)
		(end 416.595814 -139.789662)
		(stroke
			(width 0.05715)
			(type default)
		)
		(layer "In11.Cu")
	)
	(gr_line
		(start 416.569398 -139.142978)
		(end 416.598862 -139.136374)
		(stroke
			(width 0.05715)
			(type default)
		)
		(layer "In11.Cu")
	)
	(gr_line
		(start 416.574224 -138.489182)
		(end 416.60445 -138.482324)
		(stroke
			(width 0.05715)
			(type default)
		)
		(layer "In11.Cu")
	)
	(gr_line
		(start 416.57905 -137.83564)
		(end 416.608768 -137.828782)
		(stroke
			(width 0.05715)
			(type default)
		)
		(layer "In11.Cu")
	)
	(gr_line
		(start 416.58413 -137.182352)
		(end 416.612832 -137.175748)
		(stroke
			(width 0.05715)
			(type default)
		)
		(layer "In11.Cu")
	)
	(gr_line
		(start 416.591496 -140.443712)
		(end 416.620452 -140.45057)
		(stroke
			(width 0.05715)
			(type default)
		)
		(layer "In11.Cu")
	)
	(gr_line
		(start 416.595814 -139.789662)
		(end 416.626548 -139.797028)
		(stroke
			(width 0.05715)
			(type default)
		)
		(layer "In11.Cu")
	)
	(gr_line
		(start 416.598862 -139.136374)
		(end 416.599116 -139.13612)
		(stroke
			(width 0.05715)
			(type default)
		)
		(layer "In11.Cu")
	)
	(gr_line
		(start 416.599116 -139.13612)
		(end 416.59937 -139.13612)
		(stroke
			(width 0.05715)
			(type default)
		)
		(layer "In11.Cu")
	)
	(gr_line
		(start 416.59937 -139.13612)
		(end 416.630104 -139.143486)
		(stroke
			(width 0.05715)
			(type default)
		)
		(layer "In11.Cu")
	)
	(gr_line
		(start 416.60445 -138.482324)
		(end 416.635438 -138.48969)
		(stroke
			(width 0.05715)
			(type default)
		)
		(layer "In11.Cu")
	)
	(gr_line
		(start 416.608768 -137.828782)
		(end 416.639756 -137.836148)
		(stroke
			(width 0.05715)
			(type default)
		)
		(layer "In11.Cu")
	)
	(gr_line
		(start 416.612832 -137.175748)
		(end 416.641788 -137.182606)
		(stroke
			(width 0.05715)
			(type default)
		)
		(layer "In11.Cu")
	)
	(gr_line
		(start 416.772598 -118.629176)
		(end 417.002722 -118.629176)
		(stroke
			(width 0.05715)
			(type default)
		)
		(layer "In11.Cu")
	)
	(gr_line
		(start 416.945318 -119.10314)
		(end 417.004246 -119.044212)
		(stroke
			(width 0.05715)
			(type default)
		)
		(layer "In11.Cu")
	)
	(gr_line
		(start 416.983672 -50.547524)
		(end 417.225988 -50.78984)
		(stroke
			(width 0.05715)
			(type default)
		)
		(layer "In11.Cu")
	)
	(gr_line
		(start 416.983672 -50.3174)
		(end 416.983672 -50.547524)
		(stroke
			(width 0.05715)
			(type default)
		)
		(layer "In11.Cu")
	)
	(gr_line
		(start 417.02355 -94.262448)
		(end 417.081462 -94.204536)
		(stroke
			(width 0.05715)
			(type default)
		)
		(layer "In11.Cu")
	)
	(gr_line
		(start 417.0299 -112.20323)
		(end 417.19246 -112.36579)
		(stroke
			(width 0.05715)
			(type default)
		)
		(layer "In11.Cu")
	)
	(gr_line
		(start 417.0299 -111.86033)
		(end 417.0299 -112.20323)
		(stroke
			(width 0.05715)
			(type default)
		)
		(layer "In11.Cu")
	)
	(gr_line
		(start 417.0299 -111.86033)
		(end 417.19246 -111.69777)
		(stroke
			(width 0.05715)
			(type default)
		)
		(layer "In11.Cu")
	)
	(gr_line
		(start 417.088574 -137.59053)
		(end 417.14801 -137.604754)
		(stroke
			(width 0.05715)
			(type default)
		)
		(layer "In11.Cu")
	)
	(gr_line
		(start 417.14801 -137.604754)
		(end 417.148264 -137.604754)
		(stroke
			(width 0.05715)
			(type default)
		)
		(layer "In11.Cu")
	)
	(gr_line
		(start 417.148264 -137.604754)
		(end 417.20389 -137.580624)
		(stroke
			(width 0.05715)
			(type default)
		)
		(layer "In11.Cu")
	)
	(gr_line
		(start 417.153852 -138.260582)
		(end 417.213034 -138.274806)
		(stroke
			(width 0.05715)
			(type default)
		)
		(layer "In11.Cu")
	)
	(gr_line
		(start 417.213034 -138.274806)
		(end 417.26866 -138.250676)
		(stroke
			(width 0.05715)
			(type default)
		)
		(layer "In11.Cu")
	)
	(gr_line
		(start 417.213288 -138.929364)
		(end 417.271962 -138.943588)
		(stroke
			(width 0.05715)
			(type default)
		)
		(layer "In11.Cu")
	)
	(gr_line
		(start 417.225988 -50.78984)
		(end 417.456112 -50.78984)
		(stroke
			(width 0.05715)
			(type default)
		)
		(layer "In11.Cu")
	)
	(gr_line
		(start 417.248594 -118.15318)
		(end 417.248594 -118.383304)
		(stroke
			(width 0.05715)
			(type default)
		)
		(layer "In11.Cu")
	)
	(gr_line
		(start 417.248594 -118.15318)
		(end 417.49091 -117.910864)
		(stroke
			(width 0.05715)
			(type default)
		)
		(layer "In11.Cu")
	)
	(gr_line
		(start 417.271962 -139.598146)
		(end 417.330382 -139.61237)
		(stroke
			(width 0.05715)
			(type default)
		)
		(layer "In11.Cu")
	)
	(gr_line
		(start 417.271962 -138.943588)
		(end 417.327334 -138.919458)
		(stroke
			(width 0.05715)
			(type default)
		)
		(layer "In11.Cu")
	)
	(gr_line
		(start 417.330128 -140.267182)
		(end 417.388802 -140.281406)
		(stroke
			(width 0.05715)
			(type default)
		)
		(layer "In11.Cu")
	)
	(gr_line
		(start 417.330382 -139.61237)
		(end 417.386008 -139.58824)
		(stroke
			(width 0.05715)
			(type default)
		)
		(layer "In11.Cu")
	)
	(gr_line
		(start 417.388802 -140.281406)
		(end 417.444428 -140.257276)
		(stroke
			(width 0.05715)
			(type default)
		)
		(layer "In11.Cu")
	)
	(gr_line
		(start 417.398708 -50.315876)
		(end 417.457636 -50.374804)
		(stroke
			(width 0.05715)
			(type default)
		)
		(layer "In11.Cu")
	)
	(gr_line
		(start 417.414964 -116.612416)
		(end 417.414964 -116.842794)
		(stroke
			(width 0.05715)
			(type default)
		)
		(layer "In11.Cu")
	)
	(gr_line
		(start 417.414964 -116.612416)
		(end 417.657534 -116.3701)
		(stroke
			(width 0.05715)
			(type default)
		)
		(layer "In11.Cu")
	)
	(gr_line
		(start 417.467542 -150.083774)
		(end 417.484814 -150.076408)
		(stroke
			(width 0.05715)
			(type default)
		)
		(layer "In11.Cu")
	)
	(gr_line
		(start 417.483544 -119.511572)
		(end 417.483544 -119.741696)
		(stroke
			(width 0.05715)
			(type default)
		)
		(layer "In11.Cu")
	)
	(gr_line
		(start 417.483544 -119.511572)
		(end 417.726114 -119.269002)
		(stroke
			(width 0.05715)
			(type default)
		)
		(layer "In11.Cu")
	)
	(gr_line
		(start 417.4871 -111.98987)
		(end 417.4871 -112.07369)
		(stroke
			(width 0.05715)
			(type default)
		)
		(layer "In11.Cu")
	)
	(gr_line
		(start 417.49091 -117.910864)
		(end 417.721034 -117.910864)
		(stroke
			(width 0.05715)
			(type default)
		)
		(layer "In11.Cu")
	)
	(gr_line
		(start 417.5125 -102.63759)
		(end 417.67506 -102.80015)
		(stroke
			(width 0.05715)
			(type default)
		)
		(layer "In11.Cu")
	)
	(gr_line
		(start 417.5125 -102.29469)
		(end 417.5125 -102.63759)
		(stroke
			(width 0.05715)
			(type default)
		)
		(layer "In11.Cu")
	)
	(gr_line
		(start 417.5125 -102.29469)
		(end 417.67506 -102.13213)
		(stroke
			(width 0.05715)
			(type default)
		)
		(layer "In11.Cu")
	)
	(gr_line
		(start 417.5125 -101.62159)
		(end 417.67506 -101.78415)
		(stroke
			(width 0.05715)
			(type default)
		)
		(layer "In11.Cu")
	)
	(gr_line
		(start 417.5125 -101.27869)
		(end 417.5125 -101.62159)
		(stroke
			(width 0.05715)
			(type default)
		)
		(layer "In11.Cu")
	)
	(gr_line
		(start 417.5125 -101.27869)
		(end 417.67506 -101.11613)
		(stroke
			(width 0.05715)
			(type default)
		)
		(layer "In11.Cu")
	)
	(gr_line
		(start 417.5125 -100.60559)
		(end 417.67506 -100.76815)
		(stroke
			(width 0.05715)
			(type default)
		)
		(layer "In11.Cu")
	)
	(gr_line
		(start 417.5125 -100.26269)
		(end 417.5125 -100.60559)
		(stroke
			(width 0.05715)
			(type default)
		)
		(layer "In11.Cu")
	)
	(gr_line
		(start 417.5125 -100.26269)
		(end 417.67506 -100.10013)
		(stroke
			(width 0.05715)
			(type default)
		)
		(layer "In11.Cu")
	)
	(gr_line
		(start 417.5125 -99.58959)
		(end 417.67506 -99.75215)
		(stroke
			(width 0.05715)
			(type default)
		)
		(layer "In11.Cu")
	)
	(gr_line
		(start 417.5125 -99.24669)
		(end 417.5125 -99.58959)
		(stroke
			(width 0.05715)
			(type default)
		)
		(layer "In11.Cu")
	)
	(gr_line
		(start 417.5125 -99.24669)
		(end 417.67506 -99.08413)
		(stroke
			(width 0.05715)
			(type default)
		)
		(layer "In11.Cu")
	)
	(gr_line
		(start 417.596828 -146.29638)
		(end 417.615624 -146.28876)
		(stroke
			(width 0.05715)
			(type default)
		)
		(layer "In11.Cu")
	)
	(gr_line
		(start 417.657534 -116.3701)
		(end 417.887658 -116.3701)
		(stroke
			(width 0.05715)
			(type default)
		)
		(layer "In11.Cu")
	)
	(gr_line
		(start 417.66363 -118.384828)
		(end 417.722558 -118.3259)
		(stroke
			(width 0.05715)
			(type default)
		)
		(layer "In11.Cu")
	)
	(gr_line
		(start 417.701984 -51.265836)
		(end 417.9443 -51.508152)
		(stroke
			(width 0.05715)
			(type default)
		)
		(layer "In11.Cu")
	)
	(gr_line
		(start 417.701984 -51.035712)
		(end 417.701984 -51.265836)
		(stroke
			(width 0.05715)
			(type default)
		)
		(layer "In11.Cu")
	)
	(gr_line
		(start 417.726114 -119.269002)
		(end 417.956238 -119.269002)
		(stroke
			(width 0.05715)
			(type default)
		)
		(layer "In11.Cu")
	)
	(gr_line
		(start 417.797742 -93.900244)
		(end 417.855654 -93.842332)
		(stroke
			(width 0.05715)
			(type default)
		)
		(layer "In11.Cu")
	)
	(gr_line
		(start 417.83 -116.844318)
		(end 417.889182 -116.785136)
		(stroke
			(width 0.05715)
			(type default)
		)
		(layer "In11.Cu")
	)
	(gr_line
		(start 417.89858 -119.74322)
		(end 417.957762 -119.684038)
		(stroke
			(width 0.05715)
			(type default)
		)
		(layer "In11.Cu")
	)
	(gr_line
		(start 417.9443 -51.508152)
		(end 418.174424 -51.508152)
		(stroke
			(width 0.05715)
			(type default)
		)
		(layer "In11.Cu")
	)
	(gr_line
		(start 417.966906 -117.434868)
		(end 417.966906 -117.664992)
		(stroke
			(width 0.05715)
			(type default)
		)
		(layer "In11.Cu")
	)
	(gr_line
		(start 417.966906 -117.434868)
		(end 418.209222 -117.192552)
		(stroke
			(width 0.05715)
			(type default)
		)
		(layer "In11.Cu")
	)
	(gr_line
		(start 417.9697 -102.42423)
		(end 417.9697 -102.50805)
		(stroke
			(width 0.05715)
			(type default)
		)
		(layer "In11.Cu")
	)
	(gr_line
		(start 417.9697 -101.40823)
		(end 417.9697 -101.49205)
		(stroke
			(width 0.05715)
			(type default)
		)
		(layer "In11.Cu")
	)
	(gr_line
		(start 417.9697 -100.39223)
		(end 417.9697 -100.47605)
		(stroke
			(width 0.05715)
			(type default)
		)
		(layer "In11.Cu")
	)
	(gr_line
		(start 417.9697 -99.37623)
		(end 417.9697 -99.46005)
		(stroke
			(width 0.05715)
			(type default)
		)
		(layer "In11.Cu")
	)
	(gr_line
		(start 418.11702 -51.034188)
		(end 418.175948 -51.093116)
		(stroke
			(width 0.05715)
			(type default)
		)
		(layer "In11.Cu")
	)
	(gr_line
		(start 418.13353 -115.894104)
		(end 418.13353 -116.124228)
		(stroke
			(width 0.05715)
			(type default)
		)
		(layer "In11.Cu")
	)
	(gr_line
		(start 418.13353 -115.894104)
		(end 418.375846 -115.651788)
		(stroke
			(width 0.05715)
			(type default)
		)
		(layer "In11.Cu")
	)
	(gr_line
		(start 418.151056 -141.11986)
		(end 418.187124 -141.128496)
		(stroke
			(width 0.05715)
			(type default)
		)
		(layer "In11.Cu")
	)
	(gr_line
		(start 418.187124 -141.128496)
		(end 418.222684 -141.119098)
		(stroke
			(width 0.05715)
			(type default)
		)
		(layer "In11.Cu")
	)
	(gr_line
		(start 418.20211 -118.793006)
		(end 418.20211 -119.02313)
		(stroke
			(width 0.05715)
			(type default)
		)
		(layer "In11.Cu")
	)
	(gr_line
		(start 418.20211 -118.793006)
		(end 418.444426 -118.55069)
		(stroke
			(width 0.05715)
			(type default)
		)
		(layer "In11.Cu")
	)
	(gr_line
		(start 418.209222 -117.192552)
		(end 418.439346 -117.192552)
		(stroke
			(width 0.05715)
			(type default)
		)
		(layer "In11.Cu")
	)
	(gr_line
		(start 418.291264 -146.008598)
		(end 418.31133 -146.000216)
		(stroke
			(width 0.05715)
			(type default)
		)
		(layer "In11.Cu")
	)
	(gr_line
		(start 418.375846 -115.651788)
		(end 418.60597 -115.651788)
		(stroke
			(width 0.05715)
			(type default)
		)
		(layer "In11.Cu")
	)
	(gr_line
		(start 418.381942 -117.666516)
		(end 418.44087 -117.607588)
		(stroke
			(width 0.05715)
			(type default)
		)
		(layer "In11.Cu")
	)
	(gr_line
		(start 418.420296 -51.984148)
		(end 418.662612 -52.226464)
		(stroke
			(width 0.05715)
			(type default)
		)
		(layer "In11.Cu")
	)
	(gr_line
		(start 418.420296 -51.754024)
		(end 418.420296 -51.984148)
		(stroke
			(width 0.05715)
			(type default)
		)
		(layer "In11.Cu")
	)
	(gr_line
		(start 418.444426 -118.55069)
		(end 418.67455 -118.55069)
		(stroke
			(width 0.05715)
			(type default)
		)
		(layer "In11.Cu")
	)
	(gr_line
		(start 418.548566 -116.125752)
		(end 418.607494 -116.066824)
		(stroke
			(width 0.05715)
			(type default)
		)
		(layer "In11.Cu")
	)
	(gr_line
		(start 418.617146 -119.024654)
		(end 418.676074 -118.965726)
		(stroke
			(width 0.05715)
			(type default)
		)
		(layer "In11.Cu")
	)
	(gr_line
		(start 418.662612 -52.226464)
		(end 418.892736 -52.226464)
		(stroke
			(width 0.05715)
			(type default)
		)
		(layer "In11.Cu")
	)
	(gr_line
		(start 418.685218 -116.716556)
		(end 418.685218 -116.94668)
		(stroke
			(width 0.05715)
			(type default)
		)
		(layer "In11.Cu")
	)
	(gr_line
		(start 418.685218 -116.716556)
		(end 418.927534 -116.47424)
		(stroke
			(width 0.05715)
			(type default)
		)
		(layer "In11.Cu")
	)
	(gr_line
		(start 418.819838 -145.491708)
		(end 418.82822 -145.471642)
		(stroke
			(width 0.05715)
			(type default)
		)
		(layer "In11.Cu")
	)
	(gr_line
		(start 418.835332 -51.7525)
		(end 418.89426 -51.811428)
		(stroke
			(width 0.05715)
			(type default)
		)
		(layer "In11.Cu")
	)
	(gr_line
		(start 418.86251 -70.65772)
		(end 418.921438 -70.716648)
		(stroke
			(width 0.05715)
			(type default)
		)
		(layer "In11.Cu")
	)
	(gr_line
		(start 418.920422 -118.074694)
		(end 418.920422 -118.304818)
		(stroke
			(width 0.05715)
			(type default)
		)
		(layer "In11.Cu")
	)
	(gr_line
		(start 418.920422 -118.074694)
		(end 419.162992 -117.832124)
		(stroke
			(width 0.05715)
			(type default)
		)
		(layer "In11.Cu")
	)
	(gr_line
		(start 418.927534 -116.47424)
		(end 419.157658 -116.47424)
		(stroke
			(width 0.05715)
			(type default)
		)
		(layer "In11.Cu")
	)
	(gr_line
		(start 419.100254 -116.948204)
		(end 419.159182 -116.889276)
		(stroke
			(width 0.05715)
			(type default)
		)
		(layer "In11.Cu")
	)
	(gr_line
		(start 419.1254 -55.73141)
		(end 419.184074 -55.790084)
		(stroke
			(width 0.05715)
			(type default)
		)
		(layer "In11.Cu")
	)
	(gr_line
		(start 419.138608 -52.70246)
		(end 419.380924 -52.944776)
		(stroke
			(width 0.05715)
			(type default)
		)
		(layer "In11.Cu")
	)
	(gr_line
		(start 419.138608 -52.472336)
		(end 419.138608 -52.70246)
		(stroke
			(width 0.05715)
			(type default)
		)
		(layer "In11.Cu")
	)
	(gr_line
		(start 419.162992 -117.832124)
		(end 419.393116 -117.832124)
		(stroke
			(width 0.05715)
			(type default)
		)
		(layer "In11.Cu")
	)
	(gr_line
		(start 419.270434 -144.403826)
		(end 419.2778 -144.386554)
		(stroke
			(width 0.05715)
			(type default)
		)
		(layer "In11.Cu")
	)
	(gr_line
		(start 419.335458 -118.306342)
		(end 419.39464 -118.24716)
		(stroke
			(width 0.05715)
			(type default)
		)
		(layer "In11.Cu")
	)
	(gr_line
		(start 419.380924 -52.944776)
		(end 419.611048 -52.944776)
		(stroke
			(width 0.05715)
			(type default)
		)
		(layer "In11.Cu")
	)
	(gr_line
		(start 419.553644 -52.470812)
		(end 419.612572 -52.52974)
		(stroke
			(width 0.05715)
			(type default)
		)
		(layer "In11.Cu")
	)
	(gr_line
		(start 419.638988 -117.356128)
		(end 419.638988 -117.586252)
		(stroke
			(width 0.05715)
			(type default)
		)
		(layer "In11.Cu")
	)
	(gr_line
		(start 419.638988 -117.356128)
		(end 419.881304 -117.113812)
		(stroke
			(width 0.05715)
			(type default)
		)
		(layer "In11.Cu")
	)
	(gr_line
		(start 419.690804 -141.718538)
		(end 419.726364 -141.708124)
		(stroke
			(width 0.05715)
			(type default)
		)
		(layer "In11.Cu")
	)
	(gr_line
		(start 419.881304 -117.113812)
		(end 420.111428 -117.113812)
		(stroke
			(width 0.05715)
			(type default)
		)
		(layer "In11.Cu")
	)
	(gr_line
		(start 420.054024 -117.587776)
		(end 420.112952 -117.528848)
		(stroke
			(width 0.05715)
			(type default)
		)
		(layer "In11.Cu")
	)
	(gr_line
		(start 420.155878 -140.304774)
		(end 420.190676 -140.29563)
		(stroke
			(width 0.05715)
			(type default)
		)
		(layer "In11.Cu")
	)
	(gr_line
		(start 420.190676 -140.29563)
		(end 420.226236 -140.304266)
		(stroke
			(width 0.05715)
			(type default)
		)
		(layer "In11.Cu")
	)
	(gr_line
		(start 420.335964 -89.248742)
		(end 420.498524 -89.411302)
		(stroke
			(width 0.05715)
			(type default)
		)
		(layer "In11.Cu")
	)
	(gr_line
		(start 420.335964 -88.905842)
		(end 420.335964 -89.248742)
		(stroke
			(width 0.05715)
			(type default)
		)
		(layer "In11.Cu")
	)
	(gr_line
		(start 420.335964 -88.905842)
		(end 420.498524 -88.743282)
		(stroke
			(width 0.05715)
			(type default)
		)
		(layer "In11.Cu")
	)
	(gr_line
		(start 420.335964 -88.232742)
		(end 420.498524 -88.395302)
		(stroke
			(width 0.05715)
			(type default)
		)
		(layer "In11.Cu")
	)
	(gr_line
		(start 420.335964 -87.889842)
		(end 420.335964 -88.232742)
		(stroke
			(width 0.05715)
			(type default)
		)
		(layer "In11.Cu")
	)
	(gr_line
		(start 420.335964 -87.889842)
		(end 420.498524 -87.727282)
		(stroke
			(width 0.05715)
			(type default)
		)
		(layer "In11.Cu")
	)
	(gr_line
		(start 420.335964 -87.216742)
		(end 420.498524 -87.379302)
		(stroke
			(width 0.05715)
			(type default)
		)
		(layer "In11.Cu")
	)
	(gr_line
		(start 420.335964 -86.873842)
		(end 420.335964 -87.216742)
		(stroke
			(width 0.05715)
			(type default)
		)
		(layer "In11.Cu")
	)
	(gr_line
		(start 420.335964 -86.873842)
		(end 420.498524 -86.711282)
		(stroke
			(width 0.05715)
			(type default)
		)
		(layer "In11.Cu")
	)
	(gr_line
		(start 420.335964 -86.200742)
		(end 420.498524 -86.363302)
		(stroke
			(width 0.05715)
			(type default)
		)
		(layer "In11.Cu")
	)
	(gr_line
		(start 420.335964 -85.857842)
		(end 420.335964 -86.200742)
		(stroke
			(width 0.05715)
			(type default)
		)
		(layer "In11.Cu")
	)
	(gr_line
		(start 420.335964 -85.857842)
		(end 420.498524 -85.695282)
		(stroke
			(width 0.05715)
			(type default)
		)
		(layer "In11.Cu")
	)
	(gr_line
		(start 420.447216 -136.166352)
		(end 420.505382 -136.140952)
		(stroke
			(width 0.05715)
			(type default)
		)
		(layer "In11.Cu")
	)
	(gr_line
		(start 420.505382 -136.140952)
		(end 420.535608 -136.087612)
		(stroke
			(width 0.05715)
			(type default)
		)
		(layer "In11.Cu")
	)
	(gr_line
		(start 420.793164 -89.035382)
		(end 420.793164 -89.119202)
		(stroke
			(width 0.05715)
			(type default)
		)
		(layer "In11.Cu")
	)
	(gr_line
		(start 420.793164 -88.019382)
		(end 420.793164 -88.103202)
		(stroke
			(width 0.05715)
			(type default)
		)
		(layer "In11.Cu")
	)
	(gr_line
		(start 420.793164 -87.003382)
		(end 420.793164 -87.087202)
		(stroke
			(width 0.05715)
			(type default)
		)
		(layer "In11.Cu")
	)
	(gr_line
		(start 420.793164 -85.987382)
		(end 420.793164 -86.071202)
		(stroke
			(width 0.05715)
			(type default)
		)
		(layer "In11.Cu")
	)
	(gr_line
		(start 420.899082 -136.667494)
		(end 420.954962 -136.64311)
		(stroke
			(width 0.05715)
			(type default)
		)
		(layer "In11.Cu")
	)
	(gr_line
		(start 420.954962 -136.64311)
		(end 420.984426 -136.590532)
		(stroke
			(width 0.05715)
			(type default)
		)
		(layer "In11.Cu")
	)
	(gr_line
		(start 421.025574 -141.32433)
		(end 421.066214 -141.312138)
		(stroke
			(width 0.05715)
			(type default)
		)
		(layer "In11.Cu")
	)
	(gr_line
		(start 421.066214 -141.312138)
		(end 421.108124 -141.322552)
		(stroke
			(width 0.05715)
			(type default)
		)
		(layer "In11.Cu")
	)
	(gr_line
		(start 421.098726 -57.291224)
		(end 421.1574 -57.349898)
		(stroke
			(width 0.05715)
			(type default)
		)
		(layer "In11.Cu")
	)
	(gr_line
		(start 421.1447 -117.0559)
		(end 421.1447 -117.197632)
		(stroke
			(width 0.05715)
			(type default)
		)
		(layer "In11.Cu")
	)
	(gr_line
		(start 421.354504 -137.16254)
		(end 421.41013 -137.13841)
		(stroke
			(width 0.05715)
			(type default)
		)
		(layer "In11.Cu")
	)
	(gr_line
		(start 421.41013 -137.13841)
		(end 421.440864 -137.084054)
		(stroke
			(width 0.05715)
			(type default)
		)
		(layer "In11.Cu")
	)
	(gr_line
		(start 421.41013 -117.34546)
		(end 421.41013 -117.396768)
		(stroke
			(width 0.05715)
			(type default)
		)
		(layer "In11.Cu")
	)
	(gr_line
		(start 421.844216 -141.808962)
		(end 421.869108 -141.815312)
		(stroke
			(width 0.05715)
			(type default)
		)
		(layer "In11.Cu")
	)
	(gr_line
		(start 421.869108 -141.815312)
		(end 421.894 -141.810486)
		(stroke
			(width 0.05715)
			(type default)
		)
		(layer "In11.Cu")
	)
	(gr_line
		(start 422.162732 -141.078204)
		(end 422.187624 -141.0843)
		(stroke
			(width 0.05715)
			(type default)
		)
		(layer "In11.Cu")
	)
	(gr_line
		(start 422.187624 -141.0843)
		(end 422.213532 -141.079474)
		(stroke
			(width 0.05715)
			(type default)
		)
		(layer "In11.Cu")
	)
	(gr_line
		(start 422.455086 -132.086858)
		(end 422.472104 -132.056378)
		(stroke
			(width 0.05715)
			(type default)
		)
		(layer "In11.Cu")
	)
	(gr_line
		(start 422.472104 -132.056378)
		(end 422.501314 -132.037836)
		(stroke
			(width 0.05715)
			(type default)
		)
		(layer "In11.Cu")
	)
	(gr_line
		(start 422.93286 -132.538724)
		(end 422.949878 -132.508244)
		(stroke
			(width 0.05715)
			(type default)
		)
		(layer "In11.Cu")
	)
	(gr_line
		(start 422.949878 -132.508244)
		(end 422.979342 -132.489194)
		(stroke
			(width 0.05715)
			(type default)
		)
		(layer "In11.Cu")
	)
	(gr_line
		(start 423.412412 -132.992368)
		(end 423.42943 -132.961888)
		(stroke
			(width 0.05715)
			(type default)
		)
		(layer "In11.Cu")
	)
	(gr_line
		(start 423.42943 -132.961888)
		(end 423.458894 -132.942838)
		(stroke
			(width 0.05715)
			(type default)
		)
		(layer "In11.Cu")
	)
	(gr_line
		(start 423.79011 -131.211574)
		(end 423.800016 -131.205224)
		(stroke
			(width 0.05715)
			(type default)
		)
		(layer "In11.Cu")
	)
	(gr_line
		(start 423.800016 -131.205224)
		(end 423.811446 -131.20243)
		(stroke
			(width 0.05715)
			(type default)
		)
		(layer "In11.Cu")
	)
	(gr_line
		(start 423.991024 -131.840224)
		(end 424.001438 -131.83362)
		(stroke
			(width 0.05715)
			(type default)
		)
		(layer "In11.Cu")
	)
	(gr_line
		(start 424.001438 -131.83362)
		(end 424.013122 -131.830826)
		(stroke
			(width 0.05715)
			(type default)
		)
		(layer "In11.Cu")
	)
	(gr_line
		(start 424.239436 -132.442204)
		(end 424.249088 -132.435854)
		(stroke
			(width 0.05715)
			(type default)
		)
		(layer "In11.Cu")
	)
	(gr_line
		(start 424.249088 -132.435854)
		(end 424.260772 -132.43306)
		(stroke
			(width 0.05715)
			(type default)
		)
		(layer "In11.Cu")
	)
	(gr_line
		(start 424.751246 -140.30579)
		(end 424.76928 -140.302234)
		(stroke
			(width 0.05715)
			(type default)
		)
		(layer "In11.Cu")
	)
	(gr_line
		(start 424.76928 -140.302234)
		(end 424.787822 -140.306044)
		(stroke
			(width 0.05715)
			(type default)
		)
		(layer "In11.Cu")
	)
	(gr_line
		(start 424.802554 -140.966698)
		(end 424.823128 -140.962888)
		(stroke
			(width 0.05715)
			(type default)
		)
		(layer "In11.Cu")
	)
	(gr_line
		(start 424.822874 -135.609838)
		(end 424.843194 -135.605774)
		(stroke
			(width 0.05715)
			(type default)
		)
		(layer "In11.Cu")
	)
	(gr_line
		(start 424.823128 -140.962888)
		(end 424.842432 -140.966952)
		(stroke
			(width 0.05715)
			(type default)
		)
		(layer "In11.Cu")
	)
	(gr_line
		(start 425.461176 -136.508998)
		(end 425.491656 -136.503664)
		(stroke
			(width 0.05715)
			(type default)
		)
		(layer "In11.Cu")
	)
	(gr_line
		(start 425.491656 -136.503664)
		(end 425.521374 -136.5123)
		(stroke
			(width 0.05715)
			(type default)
		)
		(layer "In11.Cu")
	)
	(gr_line
		(start 425.974256 -135.678418)
		(end 425.994576 -135.674354)
		(stroke
			(width 0.05715)
			(type default)
		)
		(layer "In11.Cu")
	)
	(gr_line
		(start 425.994576 -135.674354)
		(end 426.012356 -135.66267)
		(stroke
			(width 0.05715)
			(type default)
		)
		(layer "In11.Cu")
	)
	(gr_line
		(start 426.151294 -140.884656)
		(end 426.17771 -140.88999)
		(stroke
			(width 0.05715)
			(type default)
		)
		(layer "In11.Cu")
	)
	(gr_line
		(start 426.160184 -141.53642)
		(end 426.1866 -141.541754)
		(stroke
			(width 0.05715)
			(type default)
		)
		(layer "In11.Cu")
	)
	(gr_line
		(start 426.17771 -140.88999)
		(end 426.203872 -140.883894)
		(stroke
			(width 0.05715)
			(type default)
		)
		(layer "In11.Cu")
	)
	(gr_line
		(start 426.1866 -141.541754)
		(end 426.212762 -141.535658)
		(stroke
			(width 0.05715)
			(type default)
		)
		(layer "In11.Cu")
	)
	(gr_line
		(start 426.962824 -141.059662)
		(end 426.994574 -141.052296)
		(stroke
			(width 0.05715)
			(type default)
		)
		(layer "In11.Cu")
	)
	(gr_line
		(start 426.965364 -140.405358)
		(end 426.997368 -140.397992)
		(stroke
			(width 0.05715)
			(type default)
		)
		(layer "In11.Cu")
	)
	(gr_line
		(start 426.994574 -141.052296)
		(end 427.026324 -141.059916)
		(stroke
			(width 0.05715)
			(type default)
		)
		(layer "In11.Cu")
	)
	(gr_line
		(start 426.997368 -140.397992)
		(end 427.029118 -140.405612)
		(stroke
			(width 0.05715)
			(type default)
		)
		(layer "In11.Cu")
	)
	(gr_line
		(start 427.322742 -134.437628)
		(end 427.338998 -134.42696)
		(stroke
			(width 0.05715)
			(type default)
		)
		(layer "In11.Cu")
	)
	(gr_line
		(start 427.338998 -134.42696)
		(end 427.358048 -134.42315)
		(stroke
			(width 0.05715)
			(type default)
		)
		(layer "In11.Cu")
	)
	(gr_line
		(start 427.41723 -130.65887)
		(end 427.433486 -130.65506)
		(stroke
			(width 0.05715)
			(type default)
		)
		(layer "In11.Cu")
	)
	(gr_line
		(start 427.433486 -130.65506)
		(end 427.447456 -130.645662)
		(stroke
			(width 0.05715)
			(type default)
		)
		(layer "In11.Cu")
	)
	(gr_line
		(start 427.632114 -131.284218)
		(end 427.64837 -131.280408)
		(stroke
			(width 0.05715)
			(type default)
		)
		(layer "In11.Cu")
	)
	(gr_line
		(start 427.888146 -131.884674)
		(end 427.904402 -131.880864)
		(stroke
			(width 0.05715)
			(type default)
		)
		(layer "In11.Cu")
	)
	(gr_line
		(start 428.225204 -141.650466)
		(end 428.248572 -141.656308)
		(stroke
			(width 0.05715)
			(type default)
		)
		(layer "In11.Cu")
	)
	(gr_line
		(start 428.239174 -140.999464)
		(end 428.265336 -141.005814)
		(stroke
			(width 0.05715)
			(type default)
		)
		(layer "In11.Cu")
	)
	(gr_line
		(start 428.248572 -141.656308)
		(end 428.272194 -141.651736)
		(stroke
			(width 0.05715)
			(type default)
		)
		(layer "In11.Cu")
	)
	(gr_line
		(start 428.265336 -141.005814)
		(end 428.29099 -141.000988)
		(stroke
			(width 0.05715)
			(type default)
		)
		(layer "In11.Cu")
	)
	(gr_line
		(start 430.413414 -138.239246)
		(end 430.442878 -138.247882)
		(stroke
			(width 0.05715)
			(type default)
		)
		(layer "In11.Cu")
	)
	(gr_line
		(start 430.427892 -140.950696)
		(end 430.454562 -140.945616)
		(stroke
			(width 0.05715)
			(type default)
		)
		(layer "In11.Cu")
	)
	(gr_line
		(start 430.442878 -138.247882)
		(end 430.473358 -138.24204)
		(stroke
			(width 0.05715)
			(type default)
		)
		(layer "In11.Cu")
	)
	(gr_line
		(start 430.449736 -140.298932)
		(end 430.476406 -140.293852)
		(stroke
			(width 0.05715)
			(type default)
		)
		(layer "In11.Cu")
	)
	(gr_line
		(start 430.453038 -145.372074)
		(end 430.482756 -145.366994)
		(stroke
			(width 0.05715)
			(type default)
		)
		(layer "In11.Cu")
	)
	(gr_line
		(start 430.454562 -140.945616)
		(end 430.481232 -140.952474)
		(stroke
			(width 0.05715)
			(type default)
		)
		(layer "In11.Cu")
	)
	(gr_line
		(start 430.476406 -140.293852)
		(end 430.503076 -140.30071)
		(stroke
			(width 0.05715)
			(type default)
		)
		(layer "In11.Cu")
	)
	(gr_line
		(start 430.578514 -128.946402)
		(end 430.586134 -128.941322)
		(stroke
			(width 0.05715)
			(type default)
		)
		(layer "In11.Cu")
	)
	(gr_line
		(start 430.586134 -128.941322)
		(end 430.595532 -128.938528)
		(stroke
			(width 0.05715)
			(type default)
		)
		(layer "In11.Cu")
	)
	(gr_line
		(start 430.864264 -129.527046)
		(end 430.871884 -129.521966)
		(stroke
			(width 0.05715)
			(type default)
		)
		(layer "In11.Cu")
	)
	(gr_line
		(start 430.871884 -129.521966)
		(end 430.881282 -129.519172)
		(stroke
			(width 0.05715)
			(type default)
		)
		(layer "In11.Cu")
	)
	(gr_line
		(start 431.029872 -128.224026)
		(end 431.07737 -128.191768)
		(stroke
			(width 0.05715)
			(type default)
		)
		(layer "In11.Cu")
	)
	(gr_line
		(start 431.07737 -128.191768)
		(end 431.097182 -128.137666)
		(stroke
			(width 0.05715)
			(type default)
		)
		(layer "In11.Cu")
	)
	(gr_line
		(start 431.658522 -140.901166)
		(end 431.699162 -140.91158)
		(stroke
			(width 0.05715)
			(type default)
		)
		(layer "In11.Cu")
	)
	(gr_line
		(start 431.699162 -140.91158)
		(end 431.739802 -140.90015)
		(stroke
			(width 0.05715)
			(type default)
		)
		(layer "In11.Cu")
	)
	(gr_line
		(start 431.738024 -141.578838)
		(end 431.77841 -141.589252)
		(stroke
			(width 0.05715)
			(type default)
		)
		(layer "In11.Cu")
	)
	(gr_line
		(start 431.77841 -141.589252)
		(end 431.818796 -141.577822)
		(stroke
			(width 0.05715)
			(type default)
		)
		(layer "In11.Cu")
	)
	(gr_line
		(start 431.865786 -133.819646)
		(end 431.896012 -133.81355)
		(stroke
			(width 0.05715)
			(type default)
		)
		(layer "In11.Cu")
	)
	(gr_line
		(start 431.896012 -133.81355)
		(end 431.92065 -133.7945)
		(stroke
			(width 0.05715)
			(type default)
		)
		(layer "In11.Cu")
	)
	(gr_line
		(start 432.122072 -124.461016)
		(end 432.15306 -124.375926)
		(stroke
			(width 0.05715)
			(type default)
		)
		(layer "In11.Cu")
	)
	(gr_line
		(start 432.15306 -124.375926)
		(end 432.23688 -124.341128)
		(stroke
			(width 0.05715)
			(type default)
		)
		(layer "In11.Cu")
	)
	(gr_line
		(start 432.499516 -137.565638)
		(end 432.52009 -137.561828)
		(stroke
			(width 0.05715)
			(type default)
		)
		(layer "In11.Cu")
	)
	(gr_line
		(start 432.52009 -137.561828)
		(end 432.539648 -137.565892)
		(stroke
			(width 0.05715)
			(type default)
		)
		(layer "In11.Cu")
	)
	(gr_line
		(start 432.590956 -133.28269)
		(end 432.62804 -133.254242)
		(stroke
			(width 0.05715)
			(type default)
		)
		(layer "In11.Cu")
	)
	(gr_line
		(start 432.62804 -133.254242)
		(end 432.64455 -133.210554)
		(stroke
			(width 0.05715)
			(type default)
		)
		(layer "In11.Cu")
	)
	(gr_line
		(start 433.122578 -146.453352)
		(end 433.145184 -146.459956)
		(stroke
			(width 0.05715)
			(type default)
		)
		(layer "In11.Cu")
	)
	(gr_line
		(start 433.145184 -146.459956)
		(end 433.168552 -146.456908)
		(stroke
			(width 0.05715)
			(type default)
		)
		(layer "In11.Cu")
	)
	(gr_line
		(start 433.258468 -140.166852)
		(end 433.371244 -139.965938)
		(stroke
			(width 0.05715)
			(type default)
		)
		(layer "In11.Cu")
	)
	(gr_line
		(start 433.371244 -139.965938)
		(end 433.701444 -139.872974)
		(stroke
			(width 0.05715)
			(type default)
		)
		(layer "In11.Cu")
	)
	(gr_line
		(start 433.371498 -140.441172)
		(end 433.949094 -140.278612)
		(stroke
			(width 0.05715)
			(type default)
		)
		(layer "In11.Cu")
	)
	(gr_line
		(start 433.598828 -128.38303)
		(end 433.690776 -128.356868)
		(stroke
			(width 0.05715)
			(type default)
		)
		(layer "In11.Cu")
	)
	(gr_line
		(start 433.63007 -129.756154)
		(end 433.651152 -129.700274)
		(stroke
			(width 0.05715)
			(type default)
		)
		(layer "In11.Cu")
	)
	(gr_line
		(start 433.651152 -129.700274)
		(end 433.70119 -129.668016)
		(stroke
			(width 0.05715)
			(type default)
		)
		(layer "In11.Cu")
	)
	(gr_line
		(start 433.690776 -128.356868)
		(end 433.73167 -128.27)
		(stroke
			(width 0.05715)
			(type default)
		)
		(layer "In11.Cu")
	)
	(gr_line
		(start 433.701444 -139.872974)
		(end 433.902104 -139.98575)
		(stroke
			(width 0.05715)
			(type default)
		)
		(layer "In11.Cu")
	)
	(gr_line
		(start 434.051964 -128.915922)
		(end 434.143912 -128.88976)
		(stroke
			(width 0.05715)
			(type default)
		)
		(layer "In11.Cu")
	)
	(gr_line
		(start 434.08727 -146.33702)
		(end 434.110384 -146.333972)
		(stroke
			(width 0.05715)
			(type default)
		)
		(layer "In11.Cu")
	)
	(gr_line
		(start 434.110384 -146.333972)
		(end 434.13045 -146.32178)
		(stroke
			(width 0.05715)
			(type default)
		)
		(layer "In11.Cu")
	)
	(gr_line
		(start 434.143912 -128.88976)
		(end 434.184806 -128.802892)
		(stroke
			(width 0.05715)
			(type default)
		)
		(layer "In11.Cu")
	)
	(gr_line
		(start 434.236876 -139.891516)
		(end 434.349398 -139.690856)
		(stroke
			(width 0.05715)
			(type default)
		)
		(layer "In11.Cu")
	)
	(gr_line
		(start 434.349398 -139.690856)
		(end 434.679344 -139.597892)
		(stroke
			(width 0.05715)
			(type default)
		)
		(layer "In11.Cu")
	)
	(gr_line
		(start 434.350414 -140.165836)
		(end 434.925978 -140.003784)
		(stroke
			(width 0.05715)
			(type default)
		)
		(layer "In11.Cu")
	)
	(gr_line
		(start 434.545994 -129.473452)
		(end 434.584348 -129.448814)
		(stroke
			(width 0.05715)
			(type default)
		)
		(layer "In11.Cu")
	)
	(gr_line
		(start 434.584348 -129.448814)
		(end 434.603906 -129.407412)
		(stroke
			(width 0.05715)
			(type default)
		)
		(layer "In11.Cu")
	)
	(gr_line
		(start 434.679344 -139.597892)
		(end 434.880004 -139.710668)
		(stroke
			(width 0.05715)
			(type default)
		)
		(layer "In11.Cu")
	)
	(gr_line
		(start 435.083712 -145.741644)
		(end 435.145688 -145.703798)
		(stroke
			(width 0.05715)
			(type default)
		)
		(layer "In11.Cu")
	)
	(gr_line
		(start 435.145688 -145.703798)
		(end 435.167532 -145.634456)
		(stroke
			(width 0.05715)
			(type default)
		)
		(layer "In11.Cu")
	)
	(gr_line
		(start 435.214522 -139.616434)
		(end 435.327298 -139.415774)
		(stroke
			(width 0.05715)
			(type default)
		)
		(layer "In11.Cu")
	)
	(gr_line
		(start 435.327298 -139.415774)
		(end 435.657498 -139.32281)
		(stroke
			(width 0.05715)
			(type default)
		)
		(layer "In11.Cu")
	)
	(gr_line
		(start 435.327552 -139.890754)
		(end 435.90337 -139.728702)
		(stroke
			(width 0.05715)
			(type default)
		)
		(layer "In11.Cu")
	)
	(gr_line
		(start 435.516274 -123.78817)
		(end 435.548532 -123.719336)
		(stroke
			(width 0.05715)
			(type default)
		)
		(layer "In11.Cu")
	)
	(gr_line
		(start 435.548532 -123.719336)
		(end 435.619398 -123.689872)
		(stroke
			(width 0.05715)
			(type default)
		)
		(layer "In11.Cu")
	)
	(gr_line
		(start 435.593998 -138.495278)
		(end 435.670706 -138.511026)
		(stroke
			(width 0.05715)
			(type default)
		)
		(layer "In11.Cu")
	)
	(gr_line
		(start 435.657498 -139.32281)
		(end 435.857904 -139.435332)
		(stroke
			(width 0.05715)
			(type default)
		)
		(layer "In11.Cu")
	)
	(gr_line
		(start 435.670706 -138.511026)
		(end 435.737 -138.470132)
		(stroke
			(width 0.05715)
			(type default)
		)
		(layer "In11.Cu")
	)
	(gr_line
		(start 435.980586 -124.296678)
		(end 436.012844 -124.227844)
		(stroke
			(width 0.05715)
			(type default)
		)
		(layer "In11.Cu")
	)
	(gr_line
		(start 436.012844 -124.227844)
		(end 436.013352 -124.22759)
		(stroke
			(width 0.05715)
			(type default)
		)
		(layer "In11.Cu")
	)
	(gr_line
		(start 436.013352 -124.227336)
		(end 436.013352 -124.22759)
		(stroke
			(width 0.05715)
			(type default)
		)
		(layer "In11.Cu")
	)
	(gr_line
		(start 436.013352 -124.227336)
		(end 436.085488 -124.197364)
		(stroke
			(width 0.05715)
			(type default)
		)
		(layer "In11.Cu")
	)
	(gr_line
		(start 436.306214 -139.615418)
		(end 436.358538 -139.600686)
		(stroke
			(width 0.05715)
			(type default)
		)
		(layer "In11.Cu")
	)
	(gr_line
		(start 436.358538 -139.600686)
		(end 436.393336 -139.558522)
		(stroke
			(width 0.05715)
			(type default)
		)
		(layer "In11.Cu")
	)
	(gr_line
		(start 436.437278 -124.821188)
		(end 436.470298 -124.751338)
		(stroke
			(width 0.05715)
			(type default)
		)
		(layer "In11.Cu")
	)
	(gr_line
		(start 436.470298 -124.751338)
		(end 436.550562 -124.718064)
		(stroke
			(width 0.05715)
			(type default)
		)
		(layer "In11.Cu")
	)
	(gr_line
		(start 436.639208 -140.213334)
		(end 436.690262 -140.198856)
		(stroke
			(width 0.05715)
			(type default)
		)
		(layer "In11.Cu")
	)
	(gr_line
		(start 436.690262 -140.198856)
		(end 436.723536 -140.158216)
		(stroke
			(width 0.05715)
			(type default)
		)
		(layer "In11.Cu")
	)
	(gr_line
		(start 436.711852 -141.345158)
		(end 436.742078 -141.294358)
		(stroke
			(width 0.05715)
			(type default)
		)
		(layer "In11.Cu")
	)
	(gr_line
		(start 436.742078 -141.294358)
		(end 436.796434 -141.271752)
		(stroke
			(width 0.05715)
			(type default)
		)
		(layer "In11.Cu")
	)
	(gr_line
		(start 436.92826 -124.5616)
		(end 437.506872 -124.321824)
		(stroke
			(width 0.05715)
			(type default)
		)
		(layer "In11.Cu")
	)
	(gr_line
		(start 437.015636 -124.844302)
		(end 437.230012 -124.932694)
		(stroke
			(width 0.05715)
			(type default)
		)
		(layer "In11.Cu")
	)
	(gr_line
		(start 437.11622 -137.622788)
		(end 437.164734 -137.592816)
		(stroke
			(width 0.05715)
			(type default)
		)
		(layer "In11.Cu")
	)
	(gr_line
		(start 437.164734 -137.592816)
		(end 437.186578 -137.540238)
		(stroke
			(width 0.05715)
			(type default)
		)
		(layer "In11.Cu")
	)
	(gr_line
		(start 437.230012 -124.932694)
		(end 437.558434 -124.796296)
		(stroke
			(width 0.05715)
			(type default)
		)
		(layer "In11.Cu")
	)
	(gr_line
		(start 437.558434 -124.796296)
		(end 437.646826 -124.582682)
		(stroke
			(width 0.05715)
			(type default)
		)
		(layer "In11.Cu")
	)
	(gr_line
		(start 437.616854 -141.247876)
		(end 437.670194 -141.226032)
		(stroke
			(width 0.05715)
			(type default)
		)
		(layer "In11.Cu")
	)
	(gr_line
		(start 437.670194 -141.226032)
		(end 437.70042 -141.175486)
		(stroke
			(width 0.05715)
			(type default)
		)
		(layer "In11.Cu")
	)
	(gr_line
		(start 437.894476 -124.161042)
		(end 438.463436 -123.92533)
		(stroke
			(width 0.05715)
			(type default)
		)
		(layer "In11.Cu")
	)
	(gr_line
		(start 437.978296 -124.445268)
		(end 438.191656 -124.533406)
		(stroke
			(width 0.05715)
			(type default)
		)
		(layer "In11.Cu")
	)
	(gr_line
		(start 438.191656 -124.533406)
		(end 438.520078 -124.397008)
		(stroke
			(width 0.05715)
			(type default)
		)
		(layer "In11.Cu")
	)
	(gr_line
		(start 438.385966 -133.880352)
		(end 438.394348 -133.860286)
		(stroke
			(width 0.05715)
			(type default)
		)
		(layer "In11.Cu")
	)
	(gr_line
		(start 438.394348 -133.860286)
		(end 438.409842 -133.844792)
		(stroke
			(width 0.05715)
			(type default)
		)
		(layer "In11.Cu")
	)
	(gr_line
		(start 438.480962 -137.025126)
		(end 438.49671 -137.005822)
		(stroke
			(width 0.05715)
			(type default)
		)
		(layer "In11.Cu")
	)
	(gr_line
		(start 438.49671 -137.005822)
		(end 438.503314 -136.9822)
		(stroke
			(width 0.05715)
			(type default)
		)
		(layer "In11.Cu")
	)
	(gr_line
		(start 438.520078 -124.397008)
		(end 438.607962 -124.184156)
		(stroke
			(width 0.05715)
			(type default)
		)
		(layer "In11.Cu")
	)
	(gr_line
		(start 438.964832 -134.239254)
		(end 438.976008 -134.199122)
		(stroke
			(width 0.05715)
			(type default)
		)
		(layer "In11.Cu")
	)
	(gr_line
		(start 438.976008 -134.199122)
		(end 439.005726 -134.169912)
		(stroke
			(width 0.05715)
			(type default)
		)
		(layer "In11.Cu")
	)
	(gr_line
		(start 439.14441 -137.220706)
		(end 439.145934 -137.218928)
		(stroke
			(width 0.05715)
			(type default)
		)
		(layer "In11.Cu")
	)
	(gr_line
		(start 439.145934 -137.218928)
		(end 439.147204 -137.216134)
		(stroke
			(width 0.05715)
			(type default)
		)
		(layer "In11.Cu")
	)
	(gr_line
		(start 440.250326 -134.064502)
		(end 440.278266 -134.00278)
		(stroke
			(width 0.05715)
			(type default)
		)
		(layer "In11.Cu")
	)
	(gr_line
		(start 440.278266 -134.00278)
		(end 440.338464 -133.972808)
		(stroke
			(width 0.05715)
			(type default)
		)
		(layer "In11.Cu")
	)
	(gr_line
		(start 440.649106 -123.019566)
		(end 440.666378 -123.0122)
		(stroke
			(width 0.05715)
			(type default)
		)
		(layer "In11.Cu")
	)
	(gr_line
		(start 440.76747 -134.64794)
		(end 440.79414 -134.587488)
		(stroke
			(width 0.05715)
			(type default)
		)
		(layer "In11.Cu")
	)
	(gr_line
		(start 440.79414 -134.587488)
		(end 440.852814 -134.557516)
		(stroke
			(width 0.05715)
			(type default)
		)
		(layer "In11.Cu")
	)
	(gr_line
		(start 441.1726 -123.88977)
		(end 441.537598 -123.88977)
		(stroke
			(width 0.05715)
			(type default)
		)
		(layer "In11.Cu")
	)
	(gr_line
		(start 441.537598 -123.88977)
		(end 441.594494 -123.832874)
		(stroke
			(width 0.05715)
			(type default)
		)
		(layer "In11.Cu")
	)
	(gr_line
		(start 441.751212 -122.489722)
		(end 441.914534 -122.65152)
		(stroke
			(width 0.05715)
			(type default)
		)
		(layer "In11.Cu")
	)
	(gr_line
		(start 441.785248 -122.194828)
		(end 442.38418 -122.192288)
		(stroke
			(width 0.05715)
			(type default)
		)
		(layer "In11.Cu")
	)
	(gr_line
		(start 441.914534 -122.65152)
		(end 442.257434 -122.65025)
		(stroke
			(width 0.05715)
			(type default)
		)
		(layer "In11.Cu")
	)
	(gr_line
		(start 442.011054 -123.832874)
		(end 442.06795 -123.88977)
		(stroke
			(width 0.05715)
			(type default)
		)
		(layer "In11.Cu")
	)
	(gr_line
		(start 442.06795 -123.88977)
		(end 442.4426 -123.88977)
		(stroke
			(width 0.05715)
			(type default)
		)
		(layer "In11.Cu")
	)
	(gr_line
		(start 442.257434 -122.65025)
		(end 442.419486 -122.486928)
		(stroke
			(width 0.05715)
			(type default)
		)
		(layer "In11.Cu")
	)
	(gr_line
		(start 442.767212 -122.485658)
		(end 442.930534 -122.64771)
		(stroke
			(width 0.05715)
			(type default)
		)
		(layer "In11.Cu")
	)
	(gr_line
		(start 442.801756 -122.190764)
		(end 443.398656 -122.188478)
		(stroke
			(width 0.05715)
			(type default)
		)
		(layer "In11.Cu")
	)
	(gr_line
		(start 442.930534 -122.64771)
		(end 443.273434 -122.64644)
		(stroke
			(width 0.05715)
			(type default)
		)
		(layer "In11.Cu")
	)
	(gr_line
		(start 443.13348 -121.047002)
		(end 443.15253 -121.043192)
		(stroke
			(width 0.05715)
			(type default)
		)
		(layer "In11.Cu")
	)
	(gr_line
		(start 443.15253 -121.043192)
		(end 443.17158 -121.047002)
		(stroke
			(width 0.05715)
			(type default)
		)
		(layer "In11.Cu")
	)
	(gr_line
		(start 443.273434 -122.64644)
		(end 443.435232 -122.483118)
		(stroke
			(width 0.05715)
			(type default)
		)
		(layer "In11.Cu")
	)
	(gr_line
		(start 444.3222 -123.91517)
		(end 444.57493 -123.91517)
		(stroke
			(width 0.05715)
			(type default)
		)
		(layer "In11.Cu")
	)
	(gr_line
		(start 444.57493 -123.91517)
		(end 444.758318 -123.731782)
		(stroke
			(width 0.05715)
			(type default)
		)
		(layer "In11.Cu")
	)
	(gr_line
		(start 444.595758 -122.337322)
		(end 444.647828 -122.347228)
		(stroke
			(width 0.05715)
			(type default)
		)
		(layer "In11.Cu")
	)
	(gr_line
		(start 444.89751 -119.805704)
		(end 445.371474 -119.71147)
		(stroke
			(width 0.05715)
			(type default)
		)
		(layer "In11.Cu")
	)
	(gr_line
		(start 444.92164 -120.10136)
		(end 445.044068 -120.183402)
		(stroke
			(width 0.05715)
			(type default)
		)
		(layer "In11.Cu")
	)
	(gr_line
		(start 445.044068 -120.183402)
		(end 445.381126 -120.116092)
		(stroke
			(width 0.05715)
			(type default)
		)
		(layer "In11.Cu")
	)
	(gr_line
		(start 445.174878 -123.731782)
		(end 445.358266 -123.91517)
		(stroke
			(width 0.05715)
			(type default)
		)
		(layer "In11.Cu")
	)
	(gr_line
		(start 445.358266 -123.91517)
		(end 445.5922 -123.91517)
		(stroke
			(width 0.05715)
			(type default)
		)
		(layer "In11.Cu")
	)
	(gr_line
		(start 445.381126 -120.116092)
		(end 445.462914 -119.993664)
		(stroke
			(width 0.05715)
			(type default)
		)
		(layer "In11.Cu")
	)
	(gr_line
		(start 445.78651 -119.628666)
		(end 446.27546 -119.531384)
		(stroke
			(width 0.05715)
			(type default)
		)
		(layer "In11.Cu")
	)
	(gr_line
		(start 445.81064 -119.924322)
		(end 445.942212 -120.012714)
		(stroke
			(width 0.05715)
			(type default)
		)
		(layer "In11.Cu")
	)
	(gr_line
		(start 445.942212 -120.012714)
		(end 446.27927 -119.945404)
		(stroke
			(width 0.05715)
			(type default)
		)
		(layer "In11.Cu")
	)
	(gr_line
		(start 446.27927 -119.945404)
		(end 446.367408 -119.813578)
		(stroke
			(width 0.05715)
			(type default)
		)
		(layer "In11.Cu")
	)
	(gr_line
		(start 447.070226 -122.123454)
		(end 447.088768 -122.127264)
		(stroke
			(width 0.05715)
			(type default)
		)
		(layer "In11.Cu")
	)
	(gr_line
		(start 447.088768 -122.127518)
		(end 447.108834 -122.123708)
		(stroke
			(width 0.05715)
			(type default)
		)
		(layer "In11.Cu")
	)
	(gr_line
		(start 447.088768 -122.127264)
		(end 447.088768 -122.127518)
		(stroke
			(width 0.05715)
			(type default)
		)
		(layer "In11.Cu")
	)
	(gr_line
		(start 447.420746 -121.766076)
		(end 448.006216 -121.653554)
		(stroke
			(width 0.05715)
			(type default)
		)
		(layer "In11.Cu")
	)
	(gr_line
		(start 447.44132 -122.06224)
		(end 447.631566 -122.191272)
		(stroke
			(width 0.05715)
			(type default)
		)
		(layer "In11.Cu")
	)
	(gr_line
		(start 447.4718 -120.81637)
		(end 447.771774 -120.81637)
		(stroke
			(width 0.05715)
			(type default)
		)
		(layer "In11.Cu")
	)
	(gr_line
		(start 447.631566 -122.191272)
		(end 447.96837 -122.126502)
		(stroke
			(width 0.05715)
			(type default)
		)
		(layer "In11.Cu")
	)
	(gr_line
		(start 447.771774 -120.81637)
		(end 447.936874 -120.65127)
		(stroke
			(width 0.05715)
			(type default)
		)
		(layer "In11.Cu")
	)
	(gr_line
		(start 447.96837 -122.126502)
		(end 448.097148 -121.936002)
		(stroke
			(width 0.05715)
			(type default)
		)
		(layer "In11.Cu")
	)
	(gr_line
		(start 448.353434 -120.65127)
		(end 448.518534 -120.81637)
		(stroke
			(width 0.05715)
			(type default)
		)
		(layer "In11.Cu")
	)
	(gr_line
		(start 448.518534 -120.81637)
		(end 448.7418 -120.81637)
		(stroke
			(width 0.05715)
			(type default)
		)
		(layer "In11.Cu")
	)
	(gr_line
		(start 448.601846 -130.201924)
		(end 448.63512 -129.974086)
		(stroke
			(width 0.05715)
			(type default)
		)
		(layer "In11.Cu")
	)
	(gr_line
		(start 448.63512 -129.974086)
		(end 448.910202 -129.769362)
		(stroke
			(width 0.05715)
			(type default)
		)
		(layer "In11.Cu")
	)
	(gr_line
		(start 448.805046 -130.417824)
		(end 449.286884 -130.059176)
		(stroke
			(width 0.05715)
			(type default)
		)
		(layer "In11.Cu")
	)
	(gr_line
		(start 448.910202 -129.769362)
		(end 449.13804 -129.802636)
		(stroke
			(width 0.05715)
			(type default)
		)
		(layer "In11.Cu")
	)
	(gr_line
		(start 449.172838 -121.72696)
		(end 449.224146 -121.717054)
		(stroke
			(width 0.05715)
			(type default)
		)
		(layer "In11.Cu")
	)
	(gr_line
		(start 449.224146 -121.717054)
		(end 449.261738 -121.679462)
		(stroke
			(width 0.05715)
			(type default)
		)
		(layer "In11.Cu")
	)
	(gr_line
		(start 449.636134 -121.305066)
		(end 449.695062 -121.246138)
		(stroke
			(width 0.05715)
			(type default)
		)
		(layer "In11.Cu")
	)
	(gr_line
		(start 449.697602 -120.707404)
		(end 449.805298 -120.599708)
		(stroke
			(width 0.05715)
			(type default)
		)
		(layer "In11.Cu")
	)
	(gr_line
		(start 449.697602 -120.149112)
		(end 449.805298 -120.256808)
		(stroke
			(width 0.05715)
			(type default)
		)
		(layer "In11.Cu")
	)
	(gr_line
		(start 449.805298 -120.256808)
		(end 449.805298 -120.599708)
		(stroke
			(width 0.05715)
			(type default)
		)
		(layer "In11.Cu")
	)
	(gr_line
		(start 450.007482 -125.586236)
		(end 450.058028 -125.555248)
		(stroke
			(width 0.05715)
			(type default)
		)
		(layer "In11.Cu")
	)
	(gr_line
		(start 450.058028 -125.555248)
		(end 450.080634 -125.500892)
		(stroke
			(width 0.05715)
			(type default)
		)
		(layer "In11.Cu")
	)
	(gr_line
		(start 450.591428 -123.503944)
		(end 450.59981 -123.483878)
		(stroke
			(width 0.05715)
			(type default)
		)
		(layer "In11.Cu")
	)
	(gr_line
		(start 450.59981 -123.483878)
		(end 450.615304 -123.468384)
		(stroke
			(width 0.05715)
			(type default)
		)
		(layer "In11.Cu")
	)
	(gr_line
		(start 450.632576 -126.084584)
		(end 450.684646 -126.053342)
		(stroke
			(width 0.05715)
			(type default)
		)
		(layer "In11.Cu")
	)
	(gr_line
		(start 450.6722 -120.66397)
		(end 450.993764 -120.66397)
		(stroke
			(width 0.05715)
			(type default)
		)
		(layer "In11.Cu")
	)
	(gr_line
		(start 450.684646 -126.053342)
		(end 450.70776 -125.997716)
		(stroke
			(width 0.05715)
			(type default)
		)
		(layer "In11.Cu")
	)
	(gr_line
		(start 450.734176 -127.87884)
		(end 450.768466 -127.85344)
		(stroke
			(width 0.05715)
			(type default)
		)
		(layer "In11.Cu")
	)
	(gr_line
		(start 450.768466 -127.85344)
		(end 450.78523 -127.813308)
		(stroke
			(width 0.05715)
			(type default)
		)
		(layer "In11.Cu")
	)
	(gr_line
		(start 450.984366 -128.43129)
		(end 451.007226 -128.414272)
		(stroke
			(width 0.05715)
			(type default)
		)
		(layer "In11.Cu")
	)
	(gr_line
		(start 450.993764 -120.66397)
		(end 451.076314 -120.58142)
		(stroke
			(width 0.05715)
			(type default)
		)
		(layer "In11.Cu")
	)
	(gr_line
		(start 451.007226 -128.414272)
		(end 451.035928 -128.40843)
		(stroke
			(width 0.05715)
			(type default)
		)
		(layer "In11.Cu")
	)
	(gr_line
		(start 451.276466 -123.860306)
		(end 451.284848 -123.84024)
		(stroke
			(width 0.05715)
			(type default)
		)
		(layer "In11.Cu")
	)
	(gr_line
		(start 451.284848 -123.84024)
		(end 451.300342 -123.824746)
		(stroke
			(width 0.05715)
			(type default)
		)
		(layer "In11.Cu")
	)
	(gr_line
		(start 451.492874 -120.58142)
		(end 451.575424 -120.66397)
		(stroke
			(width 0.05715)
			(type default)
		)
		(layer "In11.Cu")
	)
	(gr_line
		(start 451.575424 -120.66397)
		(end 451.9422 -120.66397)
		(stroke
			(width 0.05715)
			(type default)
		)
		(layer "In11.Cu")
	)
	(gr_line
		(start 451.993254 -124.134118)
		(end 452.001636 -124.114052)
		(stroke
			(width 0.05715)
			(type default)
		)
		(layer "In11.Cu")
	)
	(gr_line
		(start 452.001636 -124.114052)
		(end 452.01713 -124.098558)
		(stroke
			(width 0.05715)
			(type default)
		)
		(layer "In11.Cu")
	)
	(gr_line
		(start 452.620634 -121.463308)
		(end 452.790052 -121.29389)
		(stroke
			(width 0.05715)
			(type default)
		)
		(layer "In11.Cu")
	)
	(gr_line
		(start 452.622158 -121.878344)
		(end 452.780908 -121.878344)
		(stroke
			(width 0.05715)
			(type default)
		)
		(layer "In11.Cu")
	)
	(gr_line
		(start 452.780908 -121.878344)
		(end 453.023224 -121.636028)
		(stroke
			(width 0.05715)
			(type default)
		)
		(layer "In11.Cu")
	)
	(gr_line
		(start 452.80326 -123.312428)
		(end 452.862188 -123.2535)
		(stroke
			(width 0.05715)
			(type default)
		)
		(layer "In11.Cu")
	)
	(gr_line
		(start 453.023224 -121.477278)
		(end 453.023224 -121.636028)
		(stroke
			(width 0.05715)
			(type default)
		)
		(layer "In11.Cu")
	)
	(gr_line
		(start 453.267318 -120.816624)
		(end 453.436736 -120.647206)
		(stroke
			(width 0.05715)
			(type default)
		)
		(layer "In11.Cu")
	)
	(gr_line
		(start 453.268842 -121.23166)
		(end 453.427592 -121.23166)
		(stroke
			(width 0.05715)
			(type default)
		)
		(layer "In11.Cu")
	)
	(gr_line
		(start 453.427592 -121.23166)
		(end 453.669908 -120.989344)
		(stroke
			(width 0.05715)
			(type default)
		)
		(layer "In11.Cu")
	)
	(gr_line
		(start 453.669908 -120.830594)
		(end 453.669908 -120.989344)
		(stroke
			(width 0.05715)
			(type default)
		)
		(layer "In11.Cu")
	)
	(gr_line
		(start 454.65365 -121.7422)
		(end 455.0283 -121.7422)
		(stroke
			(width 0.05715)
			(type default)
		)
		(layer "In11.Cu")
	)
	(gr_line
		(start 455.0283 -121.7422)
		(end 455.08037 -121.69013)
		(stroke
			(width 0.05715)
			(type default)
		)
		(layer "In11.Cu")
	)
	(gr_line
		(start 455.461116 -127.526796)
		(end 455.589132 -127.335534)
		(stroke
			(width 0.05715)
			(type default)
		)
		(layer "In11.Cu")
	)
	(gr_line
		(start 455.49693 -121.69013)
		(end 455.549 -121.7422)
		(stroke
			(width 0.05715)
			(type default)
		)
		(layer "In11.Cu")
	)
	(gr_line
		(start 455.549 -121.7422)
		(end 455.92365 -121.7422)
		(stroke
			(width 0.05715)
			(type default)
		)
		(layer "In11.Cu")
	)
	(gr_line
		(start 455.554842 -127.808228)
		(end 456.139804 -127.69215)
		(stroke
			(width 0.05715)
			(type default)
		)
		(layer "In11.Cu")
	)
	(gr_line
		(start 455.589132 -127.335534)
		(end 455.925428 -127.268478)
		(stroke
			(width 0.05715)
			(type default)
		)
		(layer "In11.Cu")
	)
	(gr_line
		(start 455.925428 -127.268478)
		(end 456.116944 -127.396494)
		(stroke
			(width 0.05715)
			(type default)
		)
		(layer "In11.Cu")
	)
	(gr_line
		(start 455.989436 -122.7582)
		(end 456.006708 -122.750834)
		(stroke
			(width 0.05715)
			(type default)
		)
		(layer "In11.Cu")
	)
	(gr_line
		(start 456.23607 -123.5456)
		(end 456.253342 -123.538234)
		(stroke
			(width 0.05715)
			(type default)
		)
		(layer "In11.Cu")
	)
	(gr_line
		(start 456.457812 -127.328676)
		(end 456.585574 -127.137414)
		(stroke
			(width 0.05715)
			(type default)
		)
		(layer "In11.Cu")
	)
	(gr_line
		(start 456.551538 -127.610362)
		(end 457.135484 -127.494284)
		(stroke
			(width 0.05715)
			(type default)
		)
		(layer "In11.Cu")
	)
	(gr_line
		(start 456.585574 -127.137414)
		(end 456.92187 -127.070612)
		(stroke
			(width 0.05715)
			(type default)
		)
		(layer "In11.Cu")
	)
	(gr_line
		(start 456.92187 -127.070612)
		(end 457.113132 -127.198628)
		(stroke
			(width 0.05715)
			(type default)
		)
		(layer "In11.Cu")
	)
	(gr_line
		(start 457.086716 -122.876818)
		(end 457.640436 -122.647456)
		(stroke
			(width 0.05715)
			(type default)
		)
		(layer "In11.Cu")
	)
	(gr_line
		(start 457.16698 -123.162568)
		(end 457.379832 -123.250706)
		(stroke
			(width 0.05715)
			(type default)
		)
		(layer "In11.Cu")
	)
	(gr_line
		(start 457.379832 -123.250706)
		(end 457.69657 -123.119388)
		(stroke
			(width 0.05715)
			(type default)
		)
		(layer "In11.Cu")
	)
	(gr_line
		(start 457.40955 -122.17019)
		(end 457.429616 -122.161808)
		(stroke
			(width 0.05715)
			(type default)
		)
		(layer "In11.Cu")
	)
	(gr_line
		(start 457.429616 -122.161808)
		(end 457.44511 -122.146314)
		(stroke
			(width 0.05715)
			(type default)
		)
		(layer "In11.Cu")
	)
	(gr_line
		(start 457.454254 -127.13081)
		(end 457.582016 -126.939548)
		(stroke
			(width 0.05715)
			(type default)
		)
		(layer "In11.Cu")
	)
	(gr_line
		(start 457.547726 -127.412242)
		(end 458.132688 -127.296164)
		(stroke
			(width 0.05715)
			(type default)
		)
		(layer "In11.Cu")
	)
	(gr_line
		(start 457.582016 -126.939548)
		(end 457.918312 -126.872492)
		(stroke
			(width 0.05715)
			(type default)
		)
		(layer "In11.Cu")
	)
	(gr_line
		(start 457.58735 -120.38457)
		(end 457.962 -120.38457)
		(stroke
			(width 0.05715)
			(type default)
		)
		(layer "In11.Cu")
	)
	(gr_line
		(start 457.69657 -123.119388)
		(end 457.784708 -122.906536)
		(stroke
			(width 0.05715)
			(type default)
		)
		(layer "In11.Cu")
	)
	(gr_line
		(start 457.918312 -126.872492)
		(end 458.109574 -127.000508)
		(stroke
			(width 0.05715)
			(type default)
		)
		(layer "In11.Cu")
	)
	(gr_line
		(start 457.962 -120.38457)
		(end 458.01407 -120.43664)
		(stroke
			(width 0.05715)
			(type default)
		)
		(layer "In11.Cu")
	)
	(gr_line
		(start 458.08265 -122.780806)
		(end 458.102716 -122.772424)
		(stroke
			(width 0.05715)
			(type default)
		)
		(layer "In11.Cu")
	)
	(gr_line
		(start 458.102716 -122.772424)
		(end 458.11821 -122.75693)
		(stroke
			(width 0.05715)
			(type default)
		)
		(layer "In11.Cu")
	)
	(gr_line
		(start 458.309472 -121.281952)
		(end 458.3684 -121.223024)
		(stroke
			(width 0.05715)
			(type default)
		)
		(layer "In11.Cu")
	)
	(gr_line
		(start 458.402944 -122.058684)
		(end 458.57414 -121.887488)
		(stroke
			(width 0.05715)
			(type default)
		)
		(layer "In11.Cu")
	)
	(gr_line
		(start 458.404722 -122.47372)
		(end 458.564996 -122.47372)
		(stroke
			(width 0.05715)
			(type default)
		)
		(layer "In11.Cu")
	)
	(gr_line
		(start 458.43063 -120.43664)
		(end 458.4827 -120.38457)
		(stroke
			(width 0.05715)
			(type default)
		)
		(layer "In11.Cu")
	)
	(gr_line
		(start 458.4827 -120.38457)
		(end 458.85735 -120.38457)
		(stroke
			(width 0.05715)
			(type default)
		)
		(layer "In11.Cu")
	)
	(gr_line
		(start 458.54239 -127.214884)
		(end 458.56271 -127.21082)
		(stroke
			(width 0.05715)
			(type default)
		)
		(layer "In11.Cu")
	)
	(gr_line
		(start 458.56271 -127.21082)
		(end 458.580236 -127.199136)
		(stroke
			(width 0.05715)
			(type default)
		)
		(layer "In11.Cu")
	)
	(gr_line
		(start 458.564996 -122.47372)
		(end 458.807312 -122.231404)
		(stroke
			(width 0.05715)
			(type default)
		)
		(layer "In11.Cu")
	)
	(gr_line
		(start 458.734668 -126.741682)
		(end 458.779372 -126.51613)
		(stroke
			(width 0.05715)
			(type default)
		)
		(layer "In11.Cu")
	)
	(gr_line
		(start 458.779372 -126.51613)
		(end 459.064614 -126.32563)
		(stroke
			(width 0.05715)
			(type default)
		)
		(layer "In11.Cu")
	)
	(gr_line
		(start 458.807312 -122.07113)
		(end 458.807312 -122.231404)
		(stroke
			(width 0.05715)
			(type default)
		)
		(layer "In11.Cu")
	)
	(gr_line
		(start 458.873352 -121.588276)
		(end 459.206092 -121.25579)
		(stroke
			(width 0.05715)
			(type default)
		)
		(layer "In11.Cu")
	)
	(gr_line
		(start 458.9272 -126.967488)
		(end 459.424024 -126.63551)
		(stroke
			(width 0.05715)
			(type default)
		)
		(layer "In11.Cu")
	)
	(gr_line
		(start 459.056994 -121.821448)
		(end 459.196948 -121.821448)
		(stroke
			(width 0.05715)
			(type default)
		)
		(layer "In11.Cu")
	)
	(gr_line
		(start 459.064614 -126.32563)
		(end 459.290166 -126.370588)
		(stroke
			(width 0.05715)
			(type default)
		)
		(layer "In11.Cu")
	)
	(gr_line
		(start 459.196948 -121.821448)
		(end 459.439264 -121.579132)
		(stroke
			(width 0.05715)
			(type default)
		)
		(layer "In11.Cu")
	)
	(gr_line
		(start 459.439264 -121.439178)
		(end 459.439264 -121.579132)
		(stroke
			(width 0.05715)
			(type default)
		)
		(layer "In11.Cu")
	)
	(gr_line
		(start 459.579472 -126.177548)
		(end 459.624176 -125.951996)
		(stroke
			(width 0.05715)
			(type default)
		)
		(layer "In11.Cu")
	)
	(gr_line
		(start 459.624176 -125.951996)
		(end 459.909418 -125.761496)
		(stroke
			(width 0.05715)
			(type default)
		)
		(layer "In11.Cu")
	)
	(gr_line
		(start 459.772512 -126.402846)
		(end 460.26832 -126.07163)
		(stroke
			(width 0.05715)
			(type default)
		)
		(layer "In11.Cu")
	)
	(gr_line
		(start 459.909418 -125.761496)
		(end 460.134716 -125.806454)
		(stroke
			(width 0.05715)
			(type default)
		)
		(layer "In11.Cu")
	)
	(gr_line
		(start 460.34325 -121.49328)
		(end 460.70012 -121.49328)
		(stroke
			(width 0.05715)
			(type default)
		)
		(layer "In11.Cu")
	)
	(gr_line
		(start 460.70012 -121.49328)
		(end 460.77632 -121.41708)
		(stroke
			(width 0.05715)
			(type default)
		)
		(layer "In11.Cu")
	)
	(gr_line
		(start 461.19288 -121.41708)
		(end 461.26908 -121.49328)
		(stroke
			(width 0.05715)
			(type default)
		)
		(layer "In11.Cu")
	)
	(gr_line
		(start 461.204056 -125.44679)
		(end 461.3021 -125.381258)
		(stroke
			(width 0.05715)
			(type default)
		)
		(layer "In11.Cu")
	)
	(gr_line
		(start 461.26908 -121.49328)
		(end 461.61325 -121.49328)
		(stroke
			(width 0.05715)
			(type default)
		)
		(layer "In11.Cu")
	)
	(gr_line
		(start 463.625438 -121.139458)
		(end 463.871818 -121.139458)
		(stroke
			(width 0.05715)
			(type default)
		)
		(layer "In11.Cu")
	)
	(gr_line
		(start 463.871818 -121.139458)
		(end 463.97418 -121.24182)
		(stroke
			(width 0.05715)
			(type default)
		)
		(layer "In11.Cu")
	)
	(gr_line
		(start 464.39074 -121.24182)
		(end 464.493102 -121.139458)
		(stroke
			(width 0.05715)
			(type default)
		)
		(layer "In11.Cu")
	)
	(gr_line
		(start 464.493102 -121.139458)
		(end 464.811618 -121.139458)
		(stroke
			(width 0.05715)
			(type default)
		)
		(layer "In11.Cu")
	)
	(gr_line
		(start 479.861372 -15.116048)
		(end 479.861372 -15.50162)
		(stroke
			(width 0.051054)
			(type default)
		)
		(layer "In11.Cu")
	)
	(gr_line
		(start 479.861372 -15.116048)
		(end 479.949002 -15.028418)
		(stroke
			(width 0.051054)
			(type default)
		)
		(layer "In11.Cu")
	)
	(gr_line
		(start 479.861372 -14.36243)
		(end 479.949002 -14.45006)
		(stroke
			(width 0.051054)
			(type default)
		)
		(layer "In11.Cu")
	)
	(gr_line
		(start 479.861372 -14.23162)
		(end 479.861372 -14.36243)
		(stroke
			(width 0.051054)
			(type default)
		)
		(layer "In11.Cu")
	)
	(gr_line
		(start 479.861372 -12.63777)
		(end 479.861372 -12.96162)
		(stroke
			(width 0.051054)
			(type default)
		)
		(layer "In11.Cu")
	)
	(gr_line
		(start 479.861372 -12.63777)
		(end 479.877628 -12.621514)
		(stroke
			(width 0.051054)
			(type default)
		)
		(layer "In11.Cu")
	)
	(gr_line
		(start 479.861372 -12.027154)
		(end 479.877628 -12.04341)
		(stroke
			(width 0.051054)
			(type default)
		)
		(layer "In11.Cu")
	)
	(gr_line
		(start 479.861372 -11.69162)
		(end 479.861372 -12.027154)
		(stroke
			(width 0.051054)
			(type default)
		)
		(layer "In11.Cu")
	)
	(gr_line
		(start 482.430328 -16.40713)
		(end 482.64699 -16.623792)
		(stroke
			(width 0.051054)
			(type default)
		)
		(layer "In11.Cu")
	)
	(gr_line
		(start 482.430328 -15.998444)
		(end 482.430328 -16.40713)
		(stroke
			(width 0.051054)
			(type default)
		)
		(layer "In11.Cu")
	)
	(gr_line
		(start 482.64699 -16.623792)
		(end 483.035356 -16.623792)
		(stroke
			(width 0.051054)
			(type default)
		)
		(layer "In11.Cu")
	)
	(gr_line
		(start 483.006908 -15.996666)
		(end 483.057454 -16.047212)
		(stroke
			(width 0.051054)
			(type default)
		)
		(layer "In11.Cu")
	)
	(gr_line
		(start 483.040436 -16.623792)
		(end 483.059232 -16.623792)
		(stroke
			(width 0.051054)
			(type default)
		)
		(layer "In11.Cu")
	)
	(gr_line
		(start 483.444296 -16.434054)
		(end 483.463092 -16.434054)
		(stroke
			(width 0.051054)
			(type default)
		)
		(layer "In11.Cu")
	)
	(gr_line
		(start 483.67061 -36.274248)
		(end 484.105712 -36.274248)
		(stroke
			(width 0.051054)
			(type default)
		)
		(layer "In11.Cu")
	)
	(gr_line
		(start 484.105712 -36.274248)
		(end 484.13162 -36.24834)
		(stroke
			(width 0.051054)
			(type default)
		)
		(layer "In11.Cu")
	)
	(gr_line
		(start 484.709724 -36.24834)
		(end 484.735632 -36.274248)
		(stroke
			(width 0.051054)
			(type default)
		)
		(layer "In11.Cu")
	)
	(gr_line
		(start 484.715058 -37.935662)
		(end 485.04094 -37.937948)
		(stroke
			(width 0.051054)
			(type default)
		)
		(layer "In11.Cu")
	)
	(gr_line
		(start 484.735632 -36.274248)
		(end 484.940864 -36.274248)
		(stroke
			(width 0.051054)
			(type default)
		)
		(layer "In11.Cu")
	)
	(gr_line
		(start 484.98125 -29.544772)
		(end 484.98125 -29.59862)
		(stroke
			(width 0.051054)
			(type default)
		)
		(layer "In11.Cu")
	)
	(gr_line
		(start 485.04094 -37.937948)
		(end 485.172512 -37.807392)
		(stroke
			(width 0.051054)
			(type default)
		)
		(layer "In11.Cu")
	)
	(gr_line
		(start 485.20604 -29.948632)
		(end 485.20604 -30.00248)
		(stroke
			(width 0.051054)
			(type default)
		)
		(layer "In11.Cu")
	)
	(gr_line
		(start 485.583738 -37.815774)
		(end 485.708198 -37.940996)
		(stroke
			(width 0.051054)
			(type default)
		)
		(layer "In11.Cu")
	)
	(gr_line
		(start 485.601772 -30.398212)
		(end 485.65562 -30.398212)
		(stroke
			(width 0.051054)
			(type default)
		)
		(layer "In11.Cu")
	)
	(gr_line
		(start 485.708198 -37.940996)
		(end 486.001568 -37.942774)
		(stroke
			(width 0.051054)
			(type default)
		)
		(layer "In11.Cu")
	)
	(gr_line
		(start 486.005632 -30.623002)
		(end 486.05948 -30.623002)
		(stroke
			(width 0.051054)
			(type default)
		)
		(layer "In11.Cu")
	)
	(gr_line
		(start 486.682288 -31.24073)
		(end 486.682288 -31.24454)
		(stroke
			(width 0.051054)
			(type default)
		)
		(layer "In11.Cu")
	)
	(gr_line
		(start 486.85704 -30.83687)
		(end 486.85704 -30.84068)
		(stroke
			(width 0.051054)
			(type default)
		)
		(layer "In11.Cu")
	)
	(gr_line
		(start 487.499152 -30.578552)
		(end 487.788204 -30.867604)
		(stroke
			(width 0.051054)
			(type default)
		)
		(layer "In11.Cu")
	)
	(gr_line
		(start 487.499152 -30.272228)
		(end 487.499152 -30.578552)
		(stroke
			(width 0.051054)
			(type default)
		)
		(layer "In11.Cu")
	)
	(gr_line
		(start 487.499152 -30.272228)
		(end 487.773726 -29.997654)
		(stroke
			(width 0.051054)
			(type default)
		)
		(layer "In11.Cu")
	)
	(gr_line
		(start 488.197144 -30.389576)
		(end 488.197144 -30.461204)
		(stroke
			(width 0.051054)
			(type default)
		)
		(layer "In11.Cu")
	)
	(gr_line
		(start -5.999988 -158.100014)
		(end -5.999988 4.99999)
		(stroke
			(width 0.05)
			(type default)
		)
		(layer "Edge.Cuts")
	)
	(gr_arc
		(start -5.999988 -158.100014)
		(mid -5.707095 -158.807119)
		(end -4.99999 -159.100012)
		(stroke
			(width 0.05)
			(type default)
		)
		(layer "Edge.Cuts")
	)
	(gr_arc
		(start -4.99999 5.999988)
		(mid -5.707095 5.707095)
		(end -5.999988 4.99999)
		(stroke
			(width 0.05)
			(type default)
		)
		(layer "Edge.Cuts")
	)
	(gr_line
		(start -4.99999 5.999988)
		(end 501.000014 5.999988)
		(stroke
			(width 0.05)
			(type default)
		)
		(layer "Edge.Cuts")
	)
	(gr_arc
		(start -3.050032 -54.909974)
		(mid -1.999996 -55.96001)
		(end -0.94996 -54.909974)
		(stroke
			(width 0.05)
			(type default)
		)
		(layer "Edge.Cuts")
	)
	(gr_arc
		(start -0.94996 -54.909974)
		(mid -1.999996 -53.859938)
		(end -3.050032 -54.909974)
		(stroke
			(width 0.05)
			(type default)
		)
		(layer "Edge.Cuts")
	)
	(gr_line
		(start 0 -156.59989)
		(end 0.671576 -156.59989)
		(stroke
			(width 0.05)
			(type default)
		)
		(layer "Edge.Cuts")
	)
	(gr_arc
		(start 0 -153.599896)
		(mid -1.500124 -155.10002)
		(end 0 -156.59989)
		(stroke
			(width 0.05)
			(type default)
		)
		(layer "Edge.Cuts")
	)
	(gr_arc
		(start 0 -2.830068)
		(mid 2.830068 0)
		(end 0 2.830068)
		(stroke
			(width 0.05)
			(type default)
		)
		(layer "Edge.Cuts")
	)
	(gr_arc
		(start 0 2.830068)
		(mid -2.830068 0)
		(end 0 -2.830068)
		(stroke
			(width 0.05)
			(type default)
		)
		(layer "Edge.Cuts")
	)
	(gr_line
		(start 0.671576 -153.599896)
		(end 0 -153.599896)
		(stroke
			(width 0.05)
			(type default)
		)
		(layer "Edge.Cuts")
	)
	(gr_arc
		(start 0.671576 -153.599896)
		(mid 1.338217 -153.485632)
		(end 1.928622 -153.15565)
		(stroke
			(width 0.05)
			(type default)
		)
		(layer "Edge.Cuts")
	)
	(gr_arc
		(start 1.928622 -157.04439)
		(mid 1.338242 -156.714272)
		(end 0.671576 -156.59989)
		(stroke
			(width 0.05)
			(type default)
		)
		(layer "Edge.Cuts")
	)
	(gr_arc
		(start 1.928622 -157.04439)
		(mid 5.999742 -155.10002)
		(end 1.928622 -153.15565)
		(stroke
			(width 0.05)
			(type default)
		)
		(layer "Edge.Cuts")
	)
	(gr_arc
		(start 3.029966 -45.310044)
		(mid 4.630166 -46.910244)
		(end 6.230112 -45.310044)
		(stroke
			(width 0.05)
			(type default)
		)
		(layer "Edge.Cuts")
	)
	(gr_arc
		(start 6.230112 -45.310044)
		(mid 4.630166 -43.710098)
		(end 3.029966 -45.310044)
		(stroke
			(width 0.05)
			(type default)
		)
		(layer "Edge.Cuts")
	)
	(gr_arc
		(start 32.370014 -106.549952)
		(mid 33.920176 -108.100114)
		(end 35.470084 -106.549952)
		(stroke
			(width 0.05)
			(type default)
		)
		(layer "Edge.Cuts")
	)
	(gr_arc
		(start 32.370014 -46.550072)
		(mid 33.920176 -48.100234)
		(end 35.470084 -46.550072)
		(stroke
			(width 0.05)
			(type default)
		)
		(layer "Edge.Cuts")
	)
	(gr_arc
		(start 35.470084 -106.549952)
		(mid 33.920176 -105.000044)
		(end 32.370014 -106.549952)
		(stroke
			(width 0.05)
			(type default)
		)
		(layer "Edge.Cuts")
	)
	(gr_arc
		(start 35.470084 -46.550072)
		(mid 33.920176 -45.000164)
		(end 32.370014 -46.550072)
		(stroke
			(width 0.05)
			(type default)
		)
		(layer "Edge.Cuts")
	)
	(gr_arc
		(start 56.999886 -78.449932)
		(mid 58.899806 -76.550012)
		(end 56.999886 -74.650092)
		(stroke
			(width 0.05)
			(type default)
		)
		(layer "Edge.Cuts")
	)
	(gr_arc
		(start 56.999886 -74.650092)
		(mid 55.099966 -76.550012)
		(end 56.999886 -78.449932)
		(stroke
			(width 0.05)
			(type default)
		)
		(layer "Edge.Cuts")
	)
	(gr_arc
		(start 83.000088 -113.450116)
		(mid 84.900008 -111.550196)
		(end 83.000088 -109.650022)
		(stroke
			(width 0.05)
			(type default)
		)
		(layer "Edge.Cuts")
	)
	(gr_arc
		(start 83.000088 -109.650022)
		(mid 81.099914 -111.550196)
		(end 83.000088 -113.450116)
		(stroke
			(width 0.05)
			(type default)
		)
		(layer "Edge.Cuts")
	)
	(gr_arc
		(start 83.000088 -43.450002)
		(mid 84.900008 -41.550082)
		(end 83.000088 -39.649908)
		(stroke
			(width 0.05)
			(type default)
		)
		(layer "Edge.Cuts")
	)
	(gr_arc
		(start 83.000088 -39.649908)
		(mid 81.099914 -41.550082)
		(end 83.000088 -43.450002)
		(stroke
			(width 0.05)
			(type default)
		)
		(layer "Edge.Cuts")
	)
	(gr_arc
		(start 127 -113.450116)
		(mid 128.89992 -111.550196)
		(end 127 -109.650022)
		(stroke
			(width 0.05)
			(type default)
		)
		(layer "Edge.Cuts")
	)
	(gr_arc
		(start 127 -109.650022)
		(mid 125.099826 -111.550196)
		(end 127 -113.450116)
		(stroke
			(width 0.05)
			(type default)
		)
		(layer "Edge.Cuts")
	)
	(gr_arc
		(start 127 -43.450002)
		(mid 128.89992 -41.550082)
		(end 127 -39.649908)
		(stroke
			(width 0.05)
			(type default)
		)
		(layer "Edge.Cuts")
	)
	(gr_arc
		(start 127 -39.649908)
		(mid 125.099826 -41.550082)
		(end 127 -43.450002)
		(stroke
			(width 0.05)
			(type default)
		)
		(layer "Edge.Cuts")
	)
	(gr_arc
		(start 152.999948 -100.449888)
		(mid 154.899868 -98.549968)
		(end 152.999948 -96.650048)
		(stroke
			(width 0.05)
			(type default)
		)
		(layer "Edge.Cuts")
	)
	(gr_arc
		(start 152.999948 -96.650048)
		(mid 151.100028 -98.549968)
		(end 152.999948 -100.449888)
		(stroke
			(width 0.05)
			(type default)
		)
		(layer "Edge.Cuts")
	)
	(gr_arc
		(start 152.999948 -56.449976)
		(mid 154.899868 -54.550056)
		(end 152.999948 -52.649882)
		(stroke
			(width 0.05)
			(type default)
		)
		(layer "Edge.Cuts")
	)
	(gr_arc
		(start 152.999948 -52.649882)
		(mid 151.099774 -54.550056)
		(end 152.999948 -56.449976)
		(stroke
			(width 0.05)
			(type default)
		)
		(layer "Edge.Cuts")
	)
	(gr_line
		(start 171.99991 -156.59989)
		(end 172.671486 -156.59989)
		(stroke
			(width 0.05)
			(type default)
		)
		(layer "Edge.Cuts")
	)
	(gr_arc
		(start 171.99991 -153.599896)
		(mid 170.499786 -155.10002)
		(end 171.99991 -156.59989)
		(stroke
			(width 0.05)
			(type default)
		)
		(layer "Edge.Cuts")
	)
	(gr_line
		(start 171.99991 0.500126)
		(end 172.671486 0.500126)
		(stroke
			(width 0.05)
			(type default)
		)
		(layer "Edge.Cuts")
	)
	(gr_arc
		(start 171.99991 3.50012)
		(mid 170.50004 2.00025)
		(end 171.99991 0.500126)
		(stroke
			(width 0.05)
			(type default)
		)
		(layer "Edge.Cuts")
	)
	(gr_line
		(start 172.671486 -153.599896)
		(end 171.99991 -153.599896)
		(stroke
			(width 0.05)
			(type default)
		)
		(layer "Edge.Cuts")
	)
	(gr_arc
		(start 172.671486 -153.599896)
		(mid 173.33813 -153.485638)
		(end 173.928532 -153.15565)
		(stroke
			(width 0.05)
			(type default)
		)
		(layer "Edge.Cuts")
	)
	(gr_line
		(start 172.671486 3.50012)
		(end 171.99991 3.50012)
		(stroke
			(width 0.05)
			(type default)
		)
		(layer "Edge.Cuts")
	)
	(gr_arc
		(start 172.671486 3.50012)
		(mid 173.33813 3.614379)
		(end 173.928532 3.944366)
		(stroke
			(width 0.05)
			(type default)
		)
		(layer "Edge.Cuts")
	)
	(gr_arc
		(start 173.928532 -157.04439)
		(mid 173.338152 -156.714272)
		(end 172.671486 -156.59989)
		(stroke
			(width 0.05)
			(type default)
		)
		(layer "Edge.Cuts")
	)
	(gr_arc
		(start 173.928532 -157.04439)
		(mid 177.999652 -155.10002)
		(end 173.928532 -153.15565)
		(stroke
			(width 0.05)
			(type default)
		)
		(layer "Edge.Cuts")
	)
	(gr_arc
		(start 173.928532 0.055626)
		(mid 173.338152 0.385742)
		(end 172.671486 0.500126)
		(stroke
			(width 0.05)
			(type default)
		)
		(layer "Edge.Cuts")
	)
	(gr_arc
		(start 173.928532 0.055626)
		(mid 177.999652 1.999996)
		(end 173.928532 3.944366)
		(stroke
			(width 0.05)
			(type default)
		)
		(layer "Edge.Cuts")
	)
	(gr_arc
		(start 197.380098 -106.549952)
		(mid 198.930006 -108.09986)
		(end 200.479914 -106.549952)
		(stroke
			(width 0.05)
			(type default)
		)
		(layer "Edge.Cuts")
	)
	(gr_arc
		(start 197.380098 -46.550072)
		(mid 198.930006 -48.09998)
		(end 200.479914 -46.550072)
		(stroke
			(width 0.05)
			(type default)
		)
		(layer "Edge.Cuts")
	)
	(gr_arc
		(start 200.479914 -106.549952)
		(mid 198.930006 -105.000044)
		(end 197.380098 -106.549952)
		(stroke
			(width 0.05)
			(type default)
		)
		(layer "Edge.Cuts")
	)
	(gr_arc
		(start 200.479914 -46.550072)
		(mid 198.930006 -45.000164)
		(end 197.380098 -46.550072)
		(stroke
			(width 0.05)
			(type default)
		)
		(layer "Edge.Cuts")
	)
	(gr_arc
		(start 222.000064 -78.449932)
		(mid 223.899984 -76.550012)
		(end 222.000064 -74.650092)
		(stroke
			(width 0.05)
			(type default)
		)
		(layer "Edge.Cuts")
	)
	(gr_arc
		(start 222.000064 -74.650092)
		(mid 220.100144 -76.550012)
		(end 222.000064 -78.449932)
		(stroke
			(width 0.05)
			(type default)
		)
		(layer "Edge.Cuts")
	)
	(gr_arc
		(start 248.000012 -113.450116)
		(mid 249.899932 -111.550196)
		(end 248.000012 -109.650022)
		(stroke
			(width 0.05)
			(type default)
		)
		(layer "Edge.Cuts")
	)
	(gr_arc
		(start 248.000012 -109.650022)
		(mid 246.099838 -111.550196)
		(end 248.000012 -113.450116)
		(stroke
			(width 0.05)
			(type default)
		)
		(layer "Edge.Cuts")
	)
	(gr_arc
		(start 248.000012 -43.450002)
		(mid 249.899932 -41.550082)
		(end 248.000012 -39.649908)
		(stroke
			(width 0.05)
			(type default)
		)
		(layer "Edge.Cuts")
	)
	(gr_arc
		(start 248.000012 -39.649908)
		(mid 246.099838 -41.550082)
		(end 248.000012 -43.450002)
		(stroke
			(width 0.05)
			(type default)
		)
		(layer "Edge.Cuts")
	)
	(gr_arc
		(start 291.999924 -113.450116)
		(mid 293.899844 -111.550196)
		(end 291.999924 -109.650022)
		(stroke
			(width 0.05)
			(type default)
		)
		(layer "Edge.Cuts")
	)
	(gr_arc
		(start 291.999924 -109.650022)
		(mid 290.09975 -111.550196)
		(end 291.999924 -113.450116)
		(stroke
			(width 0.05)
			(type default)
		)
		(layer "Edge.Cuts")
	)
	(gr_arc
		(start 291.999924 -43.450002)
		(mid 293.899844 -41.550082)
		(end 291.999924 -39.649908)
		(stroke
			(width 0.05)
			(type default)
		)
		(layer "Edge.Cuts")
	)
	(gr_arc
		(start 291.999924 -39.649908)
		(mid 290.09975 -41.550082)
		(end 291.999924 -43.450002)
		(stroke
			(width 0.05)
			(type default)
		)
		(layer "Edge.Cuts")
	)
	(gr_arc
		(start 318.000126 -100.449888)
		(mid 319.900046 -98.549968)
		(end 318.000126 -96.650048)
		(stroke
			(width 0.05)
			(type default)
		)
		(layer "Edge.Cuts")
	)
	(gr_arc
		(start 318.000126 -96.650048)
		(mid 316.100206 -98.549968)
		(end 318.000126 -100.449888)
		(stroke
			(width 0.05)
			(type default)
		)
		(layer "Edge.Cuts")
	)
	(gr_arc
		(start 318.000126 -56.449976)
		(mid 319.900046 -54.550056)
		(end 318.000126 -52.649882)
		(stroke
			(width 0.05)
			(type default)
		)
		(layer "Edge.Cuts")
	)
	(gr_arc
		(start 318.000126 -52.649882)
		(mid 316.099952 -54.550056)
		(end 318.000126 -56.449976)
		(stroke
			(width 0.05)
			(type default)
		)
		(layer "Edge.Cuts")
	)
	(gr_line
		(start 357.000048 -156.59989)
		(end 357.671624 -156.59989)
		(stroke
			(width 0.05)
			(type default)
		)
		(layer "Edge.Cuts")
	)
	(gr_arc
		(start 357.000048 -153.599896)
		(mid 355.499924 -155.10002)
		(end 357.000048 -156.59989)
		(stroke
			(width 0.05)
			(type default)
		)
		(layer "Edge.Cuts")
	)
	(gr_line
		(start 357.000048 0.499872)
		(end 357.671624 0.499872)
		(stroke
			(width 0.05)
			(type default)
		)
		(layer "Edge.Cuts")
	)
	(gr_arc
		(start 357.000048 3.499866)
		(mid 355.500178 1.999996)
		(end 357.000048 0.499872)
		(stroke
			(width 0.05)
			(type default)
		)
		(layer "Edge.Cuts")
	)
	(gr_line
		(start 357.671624 -153.599896)
		(end 357.000048 -153.599896)
		(stroke
			(width 0.05)
			(type default)
		)
		(layer "Edge.Cuts")
	)
	(gr_arc
		(start 357.671624 -153.599896)
		(mid 358.338262 -153.485627)
		(end 358.92867 -153.15565)
		(stroke
			(width 0.05)
			(type default)
		)
		(layer "Edge.Cuts")
	)
	(gr_line
		(start 357.671624 3.499866)
		(end 357.000048 3.499866)
		(stroke
			(width 0.05)
			(type default)
		)
		(layer "Edge.Cuts")
	)
	(gr_arc
		(start 357.671624 3.499866)
		(mid 358.338275 3.614295)
		(end 358.92867 3.944366)
		(stroke
			(width 0.05)
			(type default)
		)
		(layer "Edge.Cuts")
	)
	(gr_arc
		(start 358.92867 -157.04439)
		(mid 358.338292 -156.714261)
		(end 357.671624 -156.59989)
		(stroke
			(width 0.05)
			(type default)
		)
		(layer "Edge.Cuts")
	)
	(gr_arc
		(start 358.92867 -157.04439)
		(mid 362.99979 -155.10002)
		(end 358.92867 -153.15565)
		(stroke
			(width 0.05)
			(type default)
		)
		(layer "Edge.Cuts")
	)
	(gr_arc
		(start 358.92867 0.055372)
		(mid 358.33829 0.385491)
		(end 357.671624 0.499872)
		(stroke
			(width 0.05)
			(type default)
		)
		(layer "Edge.Cuts")
	)
	(gr_arc
		(start 358.92867 0.055372)
		(mid 363.000402 2.000076)
		(end 358.92867 3.944366)
		(stroke
			(width 0.05)
			(type default)
		)
		(layer "Edge.Cuts")
	)
	(gr_arc
		(start 369.48999 -87.490046)
		(mid 371.08003 -85.900006)
		(end 369.48999 -84.309966)
		(stroke
			(width 0.05)
			(type default)
		)
		(layer "Edge.Cuts")
	)
	(gr_arc
		(start 369.48999 -84.309966)
		(mid 367.89995 -85.900006)
		(end 369.48999 -87.490046)
		(stroke
			(width 0.05)
			(type default)
		)
		(layer "Edge.Cuts")
	)
	(gr_arc
		(start 406.489916 -135.48995)
		(mid 408.079702 -133.900164)
		(end 406.489916 -132.310124)
		(stroke
			(width 0.05)
			(type default)
		)
		(layer "Edge.Cuts")
	)
	(gr_arc
		(start 406.489916 -132.310124)
		(mid 404.899876 -133.900164)
		(end 406.489916 -135.48995)
		(stroke
			(width 0.05)
			(type default)
		)
		(layer "Edge.Cuts")
	)
	(gr_arc
		(start 407.46934 -76.883768)
		(mid 409.719526 -79.133954)
		(end 411.969458 -76.883768)
		(stroke
			(width 0.05)
			(type default)
		)
		(layer "Edge.Cuts")
	)
	(gr_arc
		(start 411.969458 -76.883768)
		(mid 409.719526 -74.633836)
		(end 407.46934 -76.883768)
		(stroke
			(width 0.05)
			(type default)
		)
		(layer "Edge.Cuts")
	)
	(gr_arc
		(start 427.209966 -108.879894)
		(mid 427.502859 -109.586999)
		(end 428.209964 -109.879892)
		(stroke
			(width 0.05)
			(type default)
		)
		(layer "Edge.Cuts")
	)
	(gr_line
		(start 427.209966 -68.879974)
		(end 427.209966 -108.879894)
		(stroke
			(width 0.05)
			(type default)
		)
		(layer "Edge.Cuts")
	)
	(gr_line
		(start 428.209964 -109.879892)
		(end 501.000014 -109.879892)
		(stroke
			(width 0.05)
			(type default)
		)
		(layer "Edge.Cuts")
	)
	(gr_arc
		(start 428.209964 -67.879976)
		(mid 427.502859 -68.172869)
		(end 427.209966 -68.879974)
		(stroke
			(width 0.05)
			(type default)
		)
		(layer "Edge.Cuts")
	)
	(gr_arc
		(start 430.100486 -116.196872)
		(mid 431.700432 -117.796818)
		(end 433.300378 -116.196872)
		(stroke
			(width 0.05)
			(type default)
		)
		(layer "Edge.Cuts")
	)
	(gr_line
		(start 430.100486 -114.596926)
		(end 430.100486 -116.196872)
		(stroke
			(width 0.05)
			(type default)
		)
		(layer "Edge.Cuts")
	)
	(gr_arc
		(start 430.100486 -60.59678)
		(mid 431.700432 -62.196726)
		(end 433.300378 -60.59678)
		(stroke
			(width 0.05)
			(type default)
		)
		(layer "Edge.Cuts")
	)
	(gr_line
		(start 430.100486 -58.996834)
		(end 430.100486 -60.59678)
		(stroke
			(width 0.05)
			(type default)
		)
		(layer "Edge.Cuts")
	)
	(gr_line
		(start 433.300378 -116.196872)
		(end 433.300378 -114.596926)
		(stroke
			(width 0.05)
			(type default)
		)
		(layer "Edge.Cuts")
	)
	(gr_arc
		(start 433.300378 -114.596926)
		(mid 431.700432 -112.99698)
		(end 430.100486 -114.596926)
		(stroke
			(width 0.05)
			(type default)
		)
		(layer "Edge.Cuts")
	)
	(gr_line
		(start 433.300378 -60.59678)
		(end 433.300378 -58.996834)
		(stroke
			(width 0.05)
			(type default)
		)
		(layer "Edge.Cuts")
	)
	(gr_arc
		(start 433.300378 -58.996834)
		(mid 431.700432 -57.396888)
		(end 430.100486 -58.996834)
		(stroke
			(width 0.05)
			(type default)
		)
		(layer "Edge.Cuts")
	)
	(gr_line
		(start 465.719922 -32.120078)
		(end 467.320122 -32.120078)
		(stroke
			(width 0.05)
			(type default)
		)
		(layer "Edge.Cuts")
	)
	(gr_arc
		(start 465.719922 -28.919932)
		(mid 464.119722 -30.520132)
		(end 465.719922 -32.120078)
		(stroke
			(width 0.05)
			(type default)
		)
		(layer "Edge.Cuts")
	)
	(gr_arc
		(start 467.320122 -32.120078)
		(mid 468.920068 -30.520132)
		(end 467.320122 -28.919932)
		(stroke
			(width 0.05)
			(type default)
		)
		(layer "Edge.Cuts")
	)
	(gr_line
		(start 467.320122 -28.919932)
		(end 465.719922 -28.919932)
		(stroke
			(width 0.05)
			(type default)
		)
		(layer "Edge.Cuts")
	)
	(gr_line
		(start 471.000074 -156.59989)
		(end 471.67165 -156.59989)
		(stroke
			(width 0.05)
			(type default)
		)
		(layer "Edge.Cuts")
	)
	(gr_arc
		(start 471.000074 -153.599896)
		(mid 469.49995 -155.10002)
		(end 471.000074 -156.59989)
		(stroke
			(width 0.05)
			(type default)
		)
		(layer "Edge.Cuts")
	)
	(gr_line
		(start 471.000074 0.500126)
		(end 471.67165 0.500126)
		(stroke
			(width 0.05)
			(type default)
		)
		(layer "Edge.Cuts")
	)
	(gr_arc
		(start 471.000074 3.50012)
		(mid 469.500204 2.00025)
		(end 471.000074 0.500126)
		(stroke
			(width 0.05)
			(type default)
		)
		(layer "Edge.Cuts")
	)
	(gr_line
		(start 471.67165 -153.599896)
		(end 471.000074 -153.599896)
		(stroke
			(width 0.05)
			(type default)
		)
		(layer "Edge.Cuts")
	)
	(gr_arc
		(start 471.67165 -153.599896)
		(mid 472.338284 -153.485619)
		(end 472.928696 -153.15565)
		(stroke
			(width 0.05)
			(type default)
		)
		(layer "Edge.Cuts")
	)
	(gr_line
		(start 471.67165 3.50012)
		(end 471.000074 3.50012)
		(stroke
			(width 0.05)
			(type default)
		)
		(layer "Edge.Cuts")
	)
	(gr_arc
		(start 471.67165 3.50012)
		(mid 472.338283 3.614398)
		(end 472.928696 3.944366)
		(stroke
			(width 0.05)
			(type default)
		)
		(layer "Edge.Cuts")
	)
	(gr_arc
		(start 472.600528 -60.59678)
		(mid 474.200474 -62.196726)
		(end 475.80042 -60.59678)
		(stroke
			(width 0.05)
			(type default)
		)
		(layer "Edge.Cuts")
	)
	(gr_line
		(start 472.600528 -58.996834)
		(end 472.600528 -60.59678)
		(stroke
			(width 0.05)
			(type default)
		)
		(layer "Edge.Cuts")
	)
	(gr_arc
		(start 472.928696 -157.04439)
		(mid 472.338319 -156.714253)
		(end 471.67165 -156.59989)
		(stroke
			(width 0.05)
			(type default)
		)
		(layer "Edge.Cuts")
	)
	(gr_arc
		(start 472.928696 -157.04439)
		(mid 476.999816 -155.10002)
		(end 472.928696 -153.15565)
		(stroke
			(width 0.05)
			(type default)
		)
		(layer "Edge.Cuts")
	)
	(gr_arc
		(start 472.928696 0.055626)
		(mid 472.338319 0.385761)
		(end 471.67165 0.500126)
		(stroke
			(width 0.05)
			(type default)
		)
		(layer "Edge.Cuts")
	)
	(gr_arc
		(start 472.928696 0.055626)
		(mid 476.999816 1.999996)
		(end 472.928696 3.944366)
		(stroke
			(width 0.05)
			(type default)
		)
		(layer "Edge.Cuts")
	)
	(gr_line
		(start 475.80042 -60.59678)
		(end 475.80042 -58.996834)
		(stroke
			(width 0.05)
			(type default)
		)
		(layer "Edge.Cuts")
	)
	(gr_arc
		(start 475.80042 -58.996834)
		(mid 474.200474 -57.396888)
		(end 472.600528 -58.996834)
		(stroke
			(width 0.05)
			(type default)
		)
		(layer "Edge.Cuts")
	)
	(gr_line
		(start 478.48012 -67.879976)
		(end 428.209964 -67.879976)
		(stroke
			(width 0.05)
			(type default)
		)
		(layer "Edge.Cuts")
	)
	(gr_arc
		(start 478.48012 -67.879976)
		(mid 479.187205 -67.587075)
		(end 479.480118 -66.879978)
		(stroke
			(width 0.05)
			(type default)
		)
		(layer "Edge.Cuts")
	)
	(gr_line
		(start 479.480118 -63.680086)
		(end 479.480118 -66.879978)
		(stroke
			(width 0.05)
			(type default)
		)
		(layer "Edge.Cuts")
	)
	(gr_arc
		(start 480.480116 -62.680088)
		(mid 479.773011 -62.972981)
		(end 479.480118 -63.680086)
		(stroke
			(width 0.05)
			(type default)
		)
		(layer "Edge.Cuts")
	)
	(gr_arc
		(start 483.849934 -13.5001)
		(mid 483.996418 -13.853742)
		(end 484.35006 -13.999972)
		(stroke
			(width 0.05)
			(type default)
		)
		(layer "Edge.Cuts")
	)
	(gr_line
		(start 483.849934 2.500122)
		(end 483.849934 -13.5001)
		(stroke
			(width 0.05)
			(type default)
		)
		(layer "Edge.Cuts")
	)
	(gr_line
		(start 484.35006 -13.999972)
		(end 487.959908 -13.999972)
		(stroke
			(width 0.05)
			(type default)
		)
		(layer "Edge.Cuts")
	)
	(gr_arc
		(start 484.35006 2.999994)
		(mid 483.996597 2.853585)
		(end 483.849934 2.500122)
		(stroke
			(width 0.05)
			(type default)
		)
		(layer "Edge.Cuts")
	)
	(gr_arc
		(start 487.959908 -13.999972)
		(mid 488.313535 -13.853653)
		(end 488.460034 -13.5001)
		(stroke
			(width 0.05)
			(type default)
		)
		(layer "Edge.Cuts")
	)
	(gr_line
		(start 487.959908 2.999994)
		(end 484.35006 2.999994)
		(stroke
			(width 0.05)
			(type default)
		)
		(layer "Edge.Cuts")
	)
	(gr_line
		(start 488.460034 -13.5001)
		(end 488.460034 2.500122)
		(stroke
			(width 0.05)
			(type default)
		)
		(layer "Edge.Cuts")
	)
	(gr_arc
		(start 488.460034 2.500122)
		(mid 488.313535 2.853675)
		(end 487.959908 2.999994)
		(stroke
			(width 0.05)
			(type default)
		)
		(layer "Edge.Cuts")
	)
	(gr_arc
		(start 492.460026 -13.5001)
		(mid 492.606435 -13.853563)
		(end 492.959898 -13.999972)
		(stroke
			(width 0.05)
			(type default)
		)
		(layer "Edge.Cuts")
	)
	(gr_line
		(start 492.460026 -12.500102)
		(end 492.460026 -13.5001)
		(stroke
			(width 0.05)
			(type default)
		)
		(layer "Edge.Cuts")
	)
	(gr_arc
		(start 492.460026 1.500124)
		(mid 492.60642 1.146571)
		(end 492.959898 0.999998)
		(stroke
			(width 0.05)
			(type default)
		)
		(layer "Edge.Cuts")
	)
	(gr_line
		(start 492.460026 2.500122)
		(end 492.460026 1.500124)
		(stroke
			(width 0.05)
			(type default)
		)
		(layer "Edge.Cuts")
	)
	(gr_line
		(start 492.959898 -13.999972)
		(end 501.000014 -13.999972)
		(stroke
			(width 0.05)
			(type default)
		)
		(layer "Edge.Cuts")
	)
	(gr_arc
		(start 492.959898 -11.999976)
		(mid 492.60642 -12.146549)
		(end 492.460026 -12.500102)
		(stroke
			(width 0.05)
			(type default)
		)
		(layer "Edge.Cuts")
	)
	(gr_line
		(start 492.959898 0.999998)
		(end 501.000014 0.999998)
		(stroke
			(width 0.05)
			(type default)
		)
		(layer "Edge.Cuts")
	)
	(gr_arc
		(start 492.959898 2.999994)
		(mid 492.606435 2.853585)
		(end 492.460026 2.500122)
		(stroke
			(width 0.05)
			(type default)
		)
		(layer "Edge.Cuts")
	)
	(gr_arc
		(start 495.10061 -116.196872)
		(mid 496.700556 -117.796818)
		(end 498.300502 -116.196872)
		(stroke
			(width 0.05)
			(type default)
		)
		(layer "Edge.Cuts")
	)
	(gr_line
		(start 495.10061 -114.596926)
		(end 495.10061 -116.196872)
		(stroke
			(width 0.05)
			(type default)
		)
		(layer "Edge.Cuts")
	)
	(gr_line
		(start 495.720116 -32.120078)
		(end 497.320062 -32.120078)
		(stroke
			(width 0.05)
			(type default)
		)
		(layer "Edge.Cuts")
	)
	(gr_arc
		(start 495.720116 -28.919932)
		(mid 494.119916 -30.520132)
		(end 495.720116 -32.120078)
		(stroke
			(width 0.05)
			(type default)
		)
		(layer "Edge.Cuts")
	)
	(gr_arc
		(start 497.320062 -32.120078)
		(mid 498.920008 -30.520132)
		(end 497.320062 -28.919932)
		(stroke
			(width 0.05)
			(type default)
		)
		(layer "Edge.Cuts")
	)
	(gr_line
		(start 497.320062 -28.919932)
		(end 495.720116 -28.919932)
		(stroke
			(width 0.05)
			(type default)
		)
		(layer "Edge.Cuts")
	)
	(gr_line
		(start 498.300502 -116.196872)
		(end 498.300502 -114.596926)
		(stroke
			(width 0.05)
			(type default)
		)
		(layer "Edge.Cuts")
	)
	(gr_arc
		(start 498.300502 -114.596926)
		(mid 496.700556 -112.99698)
		(end 495.10061 -114.596926)
		(stroke
			(width 0.05)
			(type default)
		)
		(layer "Edge.Cuts")
	)
	(gr_line
		(start 501.000014 -159.100012)
		(end -4.99999 -159.100012)
		(stroke
			(width 0.05)
			(type default)
		)
		(layer "Edge.Cuts")
	)
	(gr_arc
		(start 501.000014 -159.100012)
		(mid 501.707115 -158.807115)
		(end 502.000012 -158.100014)
		(stroke
			(width 0.05)
			(type default)
		)
		(layer "Edge.Cuts")
	)
	(gr_line
		(start 501.000014 -62.680088)
		(end 480.480116 -62.680088)
		(stroke
			(width 0.05)
			(type default)
		)
		(layer "Edge.Cuts")
	)
	(gr_arc
		(start 501.000014 -62.680088)
		(mid 501.707107 -62.38719)
		(end 502.000012 -61.68009)
		(stroke
			(width 0.05)
			(type default)
		)
		(layer "Edge.Cuts")
	)
	(gr_line
		(start 501.000014 -11.999976)
		(end 492.959898 -11.999976)
		(stroke
			(width 0.05)
			(type default)
		)
		(layer "Edge.Cuts")
	)
	(gr_arc
		(start 501.000014 -11.999976)
		(mid 501.707103 -11.707077)
		(end 502.000012 -10.999978)
		(stroke
			(width 0.05)
			(type default)
		)
		(layer "Edge.Cuts")
	)
	(gr_line
		(start 501.000014 2.999994)
		(end 492.959898 2.999994)
		(stroke
			(width 0.05)
			(type default)
		)
		(layer "Edge.Cuts")
	)
	(gr_arc
		(start 501.000014 2.999994)
		(mid 501.707113 3.292891)
		(end 502.000012 3.999992)
		(stroke
			(width 0.05)
			(type default)
		)
		(layer "Edge.Cuts")
	)
	(gr_arc
		(start 502.000012 -110.87989)
		(mid 501.707117 -110.172786)
		(end 501.000014 -109.879892)
		(stroke
			(width 0.05)
			(type default)
		)
		(layer "Edge.Cuts")
	)
	(gr_line
		(start 502.000012 -110.87989)
		(end 502.000012 -158.100014)
		(stroke
			(width 0.05)
			(type default)
		)
		(layer "Edge.Cuts")
	)
	(gr_arc
		(start 502.000012 -14.99997)
		(mid 501.70711 -14.292879)
		(end 501.000014 -13.999972)
		(stroke
			(width 0.05)
			(type default)
		)
		(layer "Edge.Cuts")
	)
	(gr_line
		(start 502.000012 -14.99997)
		(end 502.000012 -61.68009)
		(stroke
			(width 0.05)
			(type default)
		)
		(layer "Edge.Cuts")
	)
	(gr_arc
		(start 502.000012 0)
		(mid 501.70712 0.70711)
		(end 501.000014 0.999998)
		(stroke
			(width 0.05)
			(type default)
		)
		(layer "Edge.Cuts")
	)
	(gr_line
		(start 502.000012 0)
		(end 502.000012 -10.999978)
		(stroke
			(width 0.05)
			(type default)
		)
		(layer "Edge.Cuts")
	)
	(gr_arc
		(start 502.000012 4.99999)
		(mid 501.707124 5.707107)
		(end 501.000014 5.999988)
		(stroke
			(width 0.05)
			(type default)
		)
		(layer "Edge.Cuts")
	)
	(gr_line
		(start 502.000012 4.99999)
		(end 502.000012 3.999992)
		(stroke
			(width 0.05)
			(type default)
		)
		(layer "Edge.Cuts")
	)
	(gr_line
		(start 1.1684 -67.0052)
		(end 2.8702 -68.707)
		(stroke
			(width 1.27)
			(type default)
		)
		(layer "In12.Cu")
	)
	(gr_line
		(start 1.1684 -60.1218)
		(end 1.1684 -67.0052)
		(stroke
			(width 1.27)
			(type default)
		)
		(layer "In12.Cu")
	)
	(gr_line
		(start 2.4384 -58.8518)
		(end 1.1684 -60.1218)
		(stroke
			(width 1.27)
			(type default)
		)
		(layer "In12.Cu")
	)
	(gr_line
		(start 2.4384 -50.0634)
		(end 2.4384 -58.8518)
		(stroke
			(width 1.27)
			(type default)
		)
		(layer "In12.Cu")
	)
	(gr_line
		(start 2.8702 -85.8266)
		(end 3.8608 -86.8172)
		(stroke
			(width 1.27)
			(type default)
		)
		(layer "In12.Cu")
	)
	(gr_line
		(start 2.8702 -68.707)
		(end 2.8702 -85.8266)
		(stroke
			(width 1.27)
			(type default)
		)
		(layer "In12.Cu")
	)
	(gr_line
		(start 3.0988 -49.403)
		(end 2.4384 -50.0634)
		(stroke
			(width 1.27)
			(type default)
		)
		(layer "In12.Cu")
	)
	(gr_line
		(start 3.8608 -86.8172)
		(end 10.107422 -86.8172)
		(stroke
			(width 1.27)
			(type default)
		)
		(layer "In12.Cu")
	)
	(gr_line
		(start 9.72185 -49.403)
		(end 3.0988 -49.403)
		(stroke
			(width 1.27)
			(type default)
		)
		(layer "In12.Cu")
	)
	(gr_line
		(start 10.107422 -86.8172)
		(end 10.727436 -86.197186)
		(stroke
			(width 1.27)
			(type default)
		)
		(layer "In12.Cu")
	)
	(gr_line
		(start 10.727436 -86.197186)
		(end 10.727436 -50.408586)
		(stroke
			(width 1.27)
			(type default)
		)
		(layer "In12.Cu")
	)
	(gr_line
		(start 10.727436 -50.408586)
		(end 9.72185 -49.403)
		(stroke
			(width 1.27)
			(type default)
		)
		(layer "In12.Cu")
	)
	(gr_line
		(start 12.611862 -65.975992)
		(end 14.99743 -68.36156)
		(stroke
			(width 1.016)
			(type default)
		)
		(layer "In12.Cu")
	)
	(gr_line
		(start 12.611862 -56.814466)
		(end 12.611862 -65.975992)
		(stroke
			(width 1.016)
			(type default)
		)
		(layer "In12.Cu")
	)
	(gr_line
		(start 13.243814 -56.182514)
		(end 12.611862 -56.814466)
		(stroke
			(width 1.016)
			(type default)
		)
		(layer "In12.Cu")
	)
	(gr_line
		(start 14.99743 -68.36156)
		(end 16.521684 -68.36156)
		(stroke
			(width 1.016)
			(type default)
		)
		(layer "In12.Cu")
	)
	(gr_line
		(start 16.521684 -68.36156)
		(end 18.74901 -68.36156)
		(stroke
			(width 1.016)
			(type default)
		)
		(layer "In12.Cu")
	)
	(gr_line
		(start 18.74901 -68.36156)
		(end 19.578066 -67.532504)
		(stroke
			(width 1.016)
			(type default)
		)
		(layer "In12.Cu")
	)
	(gr_line
		(start 18.906998 -56.182514)
		(end 13.243814 -56.182514)
		(stroke
			(width 1.016)
			(type default)
		)
		(layer "In12.Cu")
	)
	(gr_line
		(start 19.578066 -67.532504)
		(end 19.578066 -56.853582)
		(stroke
			(width 1.016)
			(type default)
		)
		(layer "In12.Cu")
	)
	(gr_line
		(start 19.578066 -56.853582)
		(end 18.906998 -56.182514)
		(stroke
			(width 1.016)
			(type default)
		)
		(layer "In12.Cu")
	)
	(gr_line
		(start 77.6986 -131.8006)
		(end 77.6986 -131.2926)
		(stroke
			(width 0.381)
			(type default)
		)
		(layer "In12.Cu")
	)
	(gr_line
		(start 77.6986 -131.2926)
		(end 78.5876 -130.4036)
		(stroke
			(width 0.381)
			(type default)
		)
		(layer "In12.Cu")
	)
	(gr_line
		(start 77.6986 -23.7744)
		(end 77.6986 -23.241)
		(stroke
			(width 0.381)
			(type default)
		)
		(layer "In12.Cu")
	)
	(gr_line
		(start 77.6986 -23.241)
		(end 78.5876 -22.352)
		(stroke
			(width 0.381)
			(type default)
		)
		(layer "In12.Cu")
	)
	(gr_line
		(start 77.978 -24.0538)
		(end 77.6986 -23.7744)
		(stroke
			(width 0.381)
			(type default)
		)
		(layer "In12.Cu")
	)
	(gr_circle
		(center 77.978 -24.053546)
		(end 77.978254 -24.053546)
		(stroke
			(width 0.381)
			(type default)
		)
		(fill no)
		(layer "In12.Cu")
	)
	(gr_line
		(start 78.0288 -132.1308)
		(end 77.6986 -131.8006)
		(stroke
			(width 0.381)
			(type default)
		)
		(layer "In12.Cu")
	)
	(gr_circle
		(center 78.0288 -132.130546)
		(end 78.029054 -132.130546)
		(stroke
			(width 0.381)
			(type default)
		)
		(fill no)
		(layer "In12.Cu")
	)
	(gr_line
		(start 78.5876 -130.4036)
		(end 78.5876 -129.3114)
		(stroke
			(width 0.381)
			(type default)
		)
		(layer "In12.Cu")
	)
	(gr_line
		(start 78.5876 -129.3114)
		(end 78.8416 -129.0574)
		(stroke
			(width 0.381)
			(type default)
		)
		(layer "In12.Cu")
	)
	(gr_line
		(start 78.5876 -22.352)
		(end 78.5876 -21.1836)
		(stroke
			(width 0.381)
			(type default)
		)
		(layer "In12.Cu")
	)
	(gr_line
		(start 78.5876 -21.1836)
		(end 78.8162 -20.955)
		(stroke
			(width 0.381)
			(type default)
		)
		(layer "In12.Cu")
	)
	(gr_line
		(start 78.8162 -20.955)
		(end 93.726 -20.955)
		(stroke
			(width 0.381)
			(type default)
		)
		(layer "In12.Cu")
	)
	(gr_line
		(start 78.8416 -129.0574)
		(end 93.6244 -129.0574)
		(stroke
			(width 0.381)
			(type default)
		)
		(layer "In12.Cu")
	)
	(gr_line
		(start 91.3384 -132.1308)
		(end 78.0288 -132.1308)
		(stroke
			(width 0.381)
			(type default)
		)
		(layer "In12.Cu")
	)
	(gr_line
		(start 92.5068 -24.0538)
		(end 77.978 -24.0538)
		(stroke
			(width 0.381)
			(type default)
		)
		(layer "In12.Cu")
	)
	(gr_line
		(start 93.6244 -132.1308)
		(end 78.0288 -132.1308)
		(stroke
			(width 0.381)
			(type default)
		)
		(layer "In12.Cu")
	)
	(gr_line
		(start 93.6244 -129.0574)
		(end 93.8276 -129.2606)
		(stroke
			(width 0.381)
			(type default)
		)
		(layer "In12.Cu")
	)
	(gr_line
		(start 93.6244 -24.0538)
		(end 77.978 -24.0538)
		(stroke
			(width 0.381)
			(type default)
		)
		(layer "In12.Cu")
	)
	(gr_line
		(start 93.726 -20.955)
		(end 93.8784 -21.1074)
		(stroke
			(width 0.381)
			(type default)
		)
		(layer "In12.Cu")
	)
	(gr_line
		(start 93.8276 -131.9276)
		(end 93.6244 -132.1308)
		(stroke
			(width 0.381)
			(type default)
		)
		(layer "In12.Cu")
	)
	(gr_line
		(start 93.8276 -129.2606)
		(end 93.8276 -131.9276)
		(stroke
			(width 0.381)
			(type default)
		)
		(layer "In12.Cu")
	)
	(gr_line
		(start 93.8784 -23.7998)
		(end 93.6244 -24.0538)
		(stroke
			(width 0.381)
			(type default)
		)
		(layer "In12.Cu")
	)
	(gr_line
		(start 93.8784 -21.1074)
		(end 93.8784 -23.7998)
		(stroke
			(width 0.381)
			(type default)
		)
		(layer "In12.Cu")
	)
	(gr_line
		(start 99.7712 -3.302)
		(end 100.0506 -3.5814)
		(stroke
			(width 0.381)
			(type default)
		)
		(layer "In12.Cu")
	)
	(gr_line
		(start 99.7712 -2.0828)
		(end 99.7712 -3.302)
		(stroke
			(width 0.381)
			(type default)
		)
		(layer "In12.Cu")
	)
	(gr_line
		(start 99.7966 -12.9286)
		(end 100.0252 -13.1572)
		(stroke
			(width 0.381)
			(type default)
		)
		(layer "In12.Cu")
	)
	(gr_line
		(start 99.7966 -11.5824)
		(end 99.7966 -12.9286)
		(stroke
			(width 0.381)
			(type default)
		)
		(layer "In12.Cu")
	)
	(gr_line
		(start 99.822 -149.479)
		(end 100.07346 -149.73046)
		(stroke
			(width 0.381)
			(type default)
		)
		(layer "In12.Cu")
	)
	(gr_line
		(start 99.822 -148.4884)
		(end 99.822 -149.479)
		(stroke
			(width 0.381)
			(type default)
		)
		(layer "In12.Cu")
	)
	(gr_line
		(start 99.8474 -139.9032)
		(end 100.0506 -140.1064)
		(stroke
			(width 0.381)
			(type default)
		)
		(layer "In12.Cu")
	)
	(gr_line
		(start 99.8474 -138.811)
		(end 99.8474 -139.9032)
		(stroke
			(width 0.381)
			(type default)
		)
		(layer "In12.Cu")
	)
	(gr_line
		(start 99.8474 -22.6822)
		(end 101.219 -24.0538)
		(stroke
			(width 0.381)
			(type default)
		)
		(layer "In12.Cu")
	)
	(gr_line
		(start 99.8474 -21.2852)
		(end 99.8474 -22.6822)
		(stroke
			(width 0.381)
			(type default)
		)
		(layer "In12.Cu")
	)
	(gr_circle
		(center 99.847654 -139.9032)
		(end 99.847908 -139.9032)
		(stroke
			(width 0.381)
			(type default)
		)
		(fill no)
		(layer "In12.Cu")
	)
	(gr_line
		(start 99.8982 -130.81)
		(end 99.8982 -129.2606)
		(stroke
			(width 0.381)
			(type default)
		)
		(layer "In12.Cu")
	)
	(gr_line
		(start 99.8982 -129.2606)
		(end 100.1776 -128.9812)
		(stroke
			(width 0.381)
			(type default)
		)
		(layer "In12.Cu")
	)
	(gr_circle
		(center 99.898454 -130.81)
		(end 99.898708 -130.81)
		(stroke
			(width 0.381)
			(type default)
		)
		(fill no)
		(layer "In12.Cu")
	)
	(gr_line
		(start 100.0252 -13.1572)
		(end 102.7938 -13.1572)
		(stroke
			(width 0.381)
			(type default)
		)
		(layer "In12.Cu")
	)
	(gr_circle
		(center 100.0252 -13.156946)
		(end 100.025454 -13.156946)
		(stroke
			(width 0.381)
			(type default)
		)
		(fill no)
		(layer "In12.Cu")
	)
	(gr_line
		(start 100.0506 -140.1064)
		(end 103.0986 -140.1064)
		(stroke
			(width 0.381)
			(type default)
		)
		(layer "In12.Cu")
	)
	(gr_circle
		(center 100.0506 -140.106146)
		(end 100.050854 -140.106146)
		(stroke
			(width 0.381)
			(type default)
		)
		(fill no)
		(layer "In12.Cu")
	)
	(gr_line
		(start 100.0506 -11.3284)
		(end 99.7966 -11.5824)
		(stroke
			(width 0.381)
			(type default)
		)
		(layer "In12.Cu")
	)
	(gr_line
		(start 100.0506 -3.5814)
		(end 102.7684 -3.5814)
		(stroke
			(width 0.381)
			(type default)
		)
		(layer "In12.Cu")
	)
	(gr_circle
		(center 100.0506 -3.581146)
		(end 100.050854 -3.581146)
		(stroke
			(width 0.381)
			(type default)
		)
		(fill no)
		(layer "In12.Cu")
	)
	(gr_line
		(start 100.07346 -149.73046)
		(end 103.084884 -149.73046)
		(stroke
			(width 0.381)
			(type default)
		)
		(layer "In12.Cu")
	)
	(gr_circle
		(center 100.07346 -149.730206)
		(end 100.073714 -149.730206)
		(stroke
			(width 0.381)
			(type default)
		)
		(fill no)
		(layer "In12.Cu")
	)
	(gr_line
		(start 100.076 -138.5824)
		(end 99.8474 -138.811)
		(stroke
			(width 0.381)
			(type default)
		)
		(layer "In12.Cu")
	)
	(gr_line
		(start 100.1014 -148.209)
		(end 99.822 -148.4884)
		(stroke
			(width 0.381)
			(type default)
		)
		(layer "In12.Cu")
	)
	(gr_line
		(start 100.1268 -1.7272)
		(end 99.7712 -2.0828)
		(stroke
			(width 0.381)
			(type default)
		)
		(layer "In12.Cu")
	)
	(gr_line
		(start 100.1776 -128.9812)
		(end 113.2078 -128.9812)
		(stroke
			(width 0.381)
			(type default)
		)
		(layer "In12.Cu")
	)
	(gr_line
		(start 100.203 -20.9296)
		(end 99.8474 -21.2852)
		(stroke
			(width 0.381)
			(type default)
		)
		(layer "In12.Cu")
	)
	(gr_line
		(start 100.4824 -131.8768)
		(end 100.4824 -131.3942)
		(stroke
			(width 0.381)
			(type default)
		)
		(layer "In12.Cu")
	)
	(gr_line
		(start 100.4824 -131.3942)
		(end 99.8982 -130.81)
		(stroke
			(width 0.381)
			(type default)
		)
		(layer "In12.Cu")
	)
	(gr_line
		(start 100.7618 -132.1562)
		(end 100.4824 -131.8768)
		(stroke
			(width 0.381)
			(type default)
		)
		(layer "In12.Cu")
	)
	(gr_line
		(start 101.219 -24.0538)
		(end 112.4458 -24.0538)
		(stroke
			(width 0.381)
			(type default)
		)
		(layer "In12.Cu")
	)
	(gr_circle
		(center 101.219 -24.053546)
		(end 101.219254 -24.053546)
		(stroke
			(width 0.381)
			(type default)
		)
		(fill no)
		(layer "In12.Cu")
	)
	(gr_line
		(start 102.7684 -3.5814)
		(end 103.4288 -2.921)
		(stroke
			(width 0.381)
			(type default)
		)
		(layer "In12.Cu")
	)
	(gr_line
		(start 102.7938 -13.1572)
		(end 103.4288 -12.5222)
		(stroke
			(width 0.381)
			(type default)
		)
		(layer "In12.Cu")
	)
	(gr_line
		(start 103.084884 -149.73046)
		(end 103.463344 -149.352)
		(stroke
			(width 0.381)
			(type default)
		)
		(layer "In12.Cu")
	)
	(gr_line
		(start 103.0986 -140.1064)
		(end 103.4288 -139.7762)
		(stroke
			(width 0.381)
			(type default)
		)
		(layer "In12.Cu")
	)
	(gr_line
		(start 103.4288 -139.7762)
		(end 103.886 -139.7762)
		(stroke
			(width 0.381)
			(type default)
		)
		(layer "In12.Cu")
	)
	(gr_line
		(start 103.4288 -12.5222)
		(end 103.9114 -12.5222)
		(stroke
			(width 0.381)
			(type default)
		)
		(layer "In12.Cu")
	)
	(gr_line
		(start 103.4288 -2.921)
		(end 103.886 -2.921)
		(stroke
			(width 0.381)
			(type default)
		)
		(layer "In12.Cu")
	)
	(gr_line
		(start 103.463344 -149.352)
		(end 103.886 -149.352)
		(stroke
			(width 0.381)
			(type default)
		)
		(layer "In12.Cu")
	)
	(gr_line
		(start 103.7844 -138.5824)
		(end 100.076 -138.5824)
		(stroke
			(width 0.381)
			(type default)
		)
		(layer "In12.Cu")
	)
	(gr_line
		(start 103.7844 -1.7272)
		(end 100.1268 -1.7272)
		(stroke
			(width 0.381)
			(type default)
		)
		(layer "In12.Cu")
	)
	(gr_line
		(start 103.8098 -148.209)
		(end 100.1014 -148.209)
		(stroke
			(width 0.381)
			(type default)
		)
		(layer "In12.Cu")
	)
	(gr_line
		(start 103.8352 -11.3284)
		(end 100.0506 -11.3284)
		(stroke
			(width 0.381)
			(type default)
		)
		(layer "In12.Cu")
	)
	(gr_line
		(start 103.886 -149.352)
		(end 104.0892 -149.1488)
		(stroke
			(width 0.381)
			(type default)
		)
		(layer "In12.Cu")
	)
	(gr_line
		(start 103.886 -139.7762)
		(end 104.14 -139.5222)
		(stroke
			(width 0.381)
			(type default)
		)
		(layer "In12.Cu")
	)
	(gr_line
		(start 103.886 -2.921)
		(end 104.1146 -2.6924)
		(stroke
			(width 0.381)
			(type default)
		)
		(layer "In12.Cu")
	)
	(gr_line
		(start 103.9114 -12.5222)
		(end 104.14 -12.2936)
		(stroke
			(width 0.381)
			(type default)
		)
		(layer "In12.Cu")
	)
	(gr_line
		(start 104.0892 -149.1488)
		(end 104.0892 -148.4884)
		(stroke
			(width 0.381)
			(type default)
		)
		(layer "In12.Cu")
	)
	(gr_line
		(start 104.0892 -148.4884)
		(end 103.8098 -148.209)
		(stroke
			(width 0.381)
			(type default)
		)
		(layer "In12.Cu")
	)
	(gr_line
		(start 104.1146 -2.6924)
		(end 104.1146 -2.0574)
		(stroke
			(width 0.381)
			(type default)
		)
		(layer "In12.Cu")
	)
	(gr_line
		(start 104.1146 -2.0574)
		(end 103.7844 -1.7272)
		(stroke
			(width 0.381)
			(type default)
		)
		(layer "In12.Cu")
	)
	(gr_line
		(start 104.14 -139.5222)
		(end 104.14 -138.938)
		(stroke
			(width 0.381)
			(type default)
		)
		(layer "In12.Cu")
	)
	(gr_line
		(start 104.14 -138.938)
		(end 103.7844 -138.5824)
		(stroke
			(width 0.381)
			(type default)
		)
		(layer "In12.Cu")
	)
	(gr_line
		(start 104.14 -12.2936)
		(end 104.14 -11.6332)
		(stroke
			(width 0.381)
			(type default)
		)
		(layer "In12.Cu")
	)
	(gr_line
		(start 104.14 -11.6332)
		(end 103.8352 -11.3284)
		(stroke
			(width 0.381)
			(type default)
		)
		(layer "In12.Cu")
	)
	(gr_line
		(start 111.5568 -20.9296)
		(end 100.203 -20.9296)
		(stroke
			(width 0.381)
			(type default)
		)
		(layer "In12.Cu")
	)
	(gr_line
		(start 112.4458 -24.0538)
		(end 112.6998 -23.7998)
		(stroke
			(width 0.381)
			(type default)
		)
		(layer "In12.Cu")
	)
	(gr_line
		(start 112.4458 -23.1394)
		(end 112.4458 -22.5806)
		(stroke
			(width 0.381)
			(type default)
		)
		(layer "In12.Cu")
	)
	(gr_line
		(start 112.4458 -22.5806)
		(end 112.5982 -22.4282)
		(stroke
			(width 0.381)
			(type default)
		)
		(layer "In12.Cu")
	)
	(gr_line
		(start 112.5982 -22.4282)
		(end 112.5982 -21.971)
		(stroke
			(width 0.381)
			(type default)
		)
		(layer "In12.Cu")
	)
	(gr_line
		(start 112.5982 -21.971)
		(end 111.5568 -20.9296)
		(stroke
			(width 0.381)
			(type default)
		)
		(layer "In12.Cu")
	)
	(gr_line
		(start 112.6998 -23.7998)
		(end 112.6998 -23.3934)
		(stroke
			(width 0.381)
			(type default)
		)
		(layer "In12.Cu")
	)
	(gr_line
		(start 112.6998 -23.3934)
		(end 112.4458 -23.1394)
		(stroke
			(width 0.381)
			(type default)
		)
		(layer "In12.Cu")
	)
	(gr_line
		(start 113.2078 -132.1562)
		(end 100.7618 -132.1562)
		(stroke
			(width 0.381)
			(type default)
		)
		(layer "In12.Cu")
	)
	(gr_line
		(start 113.2078 -128.9812)
		(end 113.5126 -129.286)
		(stroke
			(width 0.381)
			(type default)
		)
		(layer "In12.Cu")
	)
	(gr_line
		(start 113.3094 -130.429)
		(end 113.5634 -130.683)
		(stroke
			(width 0.381)
			(type default)
		)
		(layer "In12.Cu")
	)
	(gr_line
		(start 113.3094 -130.0226)
		(end 113.3094 -130.429)
		(stroke
			(width 0.381)
			(type default)
		)
		(layer "In12.Cu")
	)
	(gr_line
		(start 113.5126 -129.8194)
		(end 113.3094 -130.0226)
		(stroke
			(width 0.381)
			(type default)
		)
		(layer "In12.Cu")
	)
	(gr_line
		(start 113.5126 -129.286)
		(end 113.5126 -129.8194)
		(stroke
			(width 0.381)
			(type default)
		)
		(layer "In12.Cu")
	)
	(gr_line
		(start 113.5634 -131.8006)
		(end 113.2078 -132.1562)
		(stroke
			(width 0.381)
			(type default)
		)
		(layer "In12.Cu")
	)
	(gr_line
		(start 113.5634 -130.683)
		(end 113.5634 -131.8006)
		(stroke
			(width 0.381)
			(type default)
		)
		(layer "In12.Cu")
	)
	(gr_line
		(start 170.434 -133.731)
		(end 170.434 -131.8514)
		(stroke
			(width 0.508)
			(type default)
		)
		(layer "In12.Cu")
	)
	(gr_line
		(start 170.434 -131.8514)
		(end 170.688 -131.5974)
		(stroke
			(width 0.508)
			(type default)
		)
		(layer "In12.Cu")
	)
	(gr_line
		(start 170.688 -131.5974)
		(end 171.1198 -131.5974)
		(stroke
			(width 0.508)
			(type default)
		)
		(layer "In12.Cu")
	)
	(gr_line
		(start 170.815 -12.065)
		(end 171.323 -12.573)
		(stroke
			(width 0.508)
			(type default)
		)
		(layer "In12.Cu")
	)
	(gr_line
		(start 170.815 -10.033)
		(end 170.815 -12.065)
		(stroke
			(width 0.508)
			(type default)
		)
		(layer "In12.Cu")
	)
	(gr_line
		(start 171.1198 -131.5974)
		(end 171.2722 -131.445)
		(stroke
			(width 0.508)
			(type default)
		)
		(layer "In12.Cu")
	)
	(gr_line
		(start 171.2214 -134.5184)
		(end 170.434 -133.731)
		(stroke
			(width 0.508)
			(type default)
		)
		(layer "In12.Cu")
	)
	(gr_line
		(start 171.2722 -131.445)
		(end 171.2722 -129.413)
		(stroke
			(width 0.508)
			(type default)
		)
		(layer "In12.Cu")
	)
	(gr_line
		(start 171.2722 -129.413)
		(end 171.4246 -129.2606)
		(stroke
			(width 0.508)
			(type default)
		)
		(layer "In12.Cu")
	)
	(gr_line
		(start 171.323 -12.573)
		(end 173.228 -12.573)
		(stroke
			(width 0.508)
			(type default)
		)
		(layer "In12.Cu")
	)
	(gr_line
		(start 171.4246 -129.2606)
		(end 172.339 -129.2606)
		(stroke
			(width 0.508)
			(type default)
		)
		(layer "In12.Cu")
	)
	(gr_line
		(start 171.958 -8.89)
		(end 170.815 -10.033)
		(stroke
			(width 0.508)
			(type default)
		)
		(layer "In12.Cu")
	)
	(gr_line
		(start 171.958 -7.62)
		(end 171.958 -8.89)
		(stroke
			(width 0.508)
			(type default)
		)
		(layer "In12.Cu")
	)
	(gr_line
		(start 172.339 -129.2606)
		(end 172.5676 -129.4892)
		(stroke
			(width 0.508)
			(type default)
		)
		(layer "In12.Cu")
	)
	(gr_line
		(start 172.5676 -129.4892)
		(end 178.2064 -129.4892)
		(stroke
			(width 0.508)
			(type default)
		)
		(layer "In12.Cu")
	)
	(gr_line
		(start 172.974 -6.604)
		(end 171.958 -7.62)
		(stroke
			(width 0.508)
			(type default)
		)
		(layer "In12.Cu")
	)
	(gr_line
		(start 173.228 -12.573)
		(end 173.99 -13.335)
		(stroke
			(width 0.508)
			(type default)
		)
		(layer "In12.Cu")
	)
	(gr_line
		(start 173.99 -13.335)
		(end 174.752 -13.335)
		(stroke
			(width 0.508)
			(type default)
		)
		(layer "In12.Cu")
	)
	(gr_line
		(start 174.752 -13.335)
		(end 175.26 -12.827)
		(stroke
			(width 0.508)
			(type default)
		)
		(layer "In12.Cu")
	)
	(gr_line
		(start 174.752 -6.604)
		(end 172.974 -6.604)
		(stroke
			(width 0.508)
			(type default)
		)
		(layer "In12.Cu")
	)
	(gr_line
		(start 175.133 -6.223)
		(end 174.752 -6.604)
		(stroke
			(width 0.508)
			(type default)
		)
		(layer "In12.Cu")
	)
	(gr_line
		(start 175.26 -12.827)
		(end 175.26 -11.176)
		(stroke
			(width 0.508)
			(type default)
		)
		(layer "In12.Cu")
	)
	(gr_line
		(start 175.26 -11.176)
		(end 175.514 -10.922)
		(stroke
			(width 0.508)
			(type default)
		)
		(layer "In12.Cu")
	)
	(gr_line
		(start 175.514 -10.922)
		(end 178.181 -10.922)
		(stroke
			(width 0.508)
			(type default)
		)
		(layer "In12.Cu")
	)
	(gr_line
		(start 177.8 -134.5184)
		(end 171.2214 -134.5184)
		(stroke
			(width 0.508)
			(type default)
		)
		(layer "In12.Cu")
	)
	(gr_line
		(start 178.054 -6.223)
		(end 175.133 -6.223)
		(stroke
			(width 0.508)
			(type default)
		)
		(layer "In12.Cu")
	)
	(gr_line
		(start 178.181 -10.922)
		(end 178.435 -10.668)
		(stroke
			(width 0.508)
			(type default)
		)
		(layer "In12.Cu")
	)
	(gr_line
		(start 178.2064 -129.4892)
		(end 178.4096 -129.6924)
		(stroke
			(width 0.508)
			(type default)
		)
		(layer "In12.Cu")
	)
	(gr_line
		(start 178.4096 -131.9276)
		(end 178.562 -132.08)
		(stroke
			(width 0.508)
			(type default)
		)
		(layer "In12.Cu")
	)
	(gr_line
		(start 178.4096 -129.6924)
		(end 178.4096 -131.9276)
		(stroke
			(width 0.508)
			(type default)
		)
		(layer "In12.Cu")
	)
	(gr_line
		(start 178.435 -10.668)
		(end 178.435 -9.906)
		(stroke
			(width 0.508)
			(type default)
		)
		(layer "In12.Cu")
	)
	(gr_line
		(start 178.435 -9.906)
		(end 178.689 -9.652)
		(stroke
			(width 0.508)
			(type default)
		)
		(layer "In12.Cu")
	)
	(gr_line
		(start 178.435 -8.001)
		(end 178.435 -6.604)
		(stroke
			(width 0.508)
			(type default)
		)
		(layer "In12.Cu")
	)
	(gr_line
		(start 178.435 -6.604)
		(end 178.054 -6.223)
		(stroke
			(width 0.508)
			(type default)
		)
		(layer "In12.Cu")
	)
	(gr_line
		(start 178.562 -133.7564)
		(end 177.8 -134.5184)
		(stroke
			(width 0.508)
			(type default)
		)
		(layer "In12.Cu")
	)
	(gr_line
		(start 178.562 -132.08)
		(end 178.562 -133.7564)
		(stroke
			(width 0.508)
			(type default)
		)
		(layer "In12.Cu")
	)
	(gr_line
		(start 178.689 -9.652)
		(end 178.689 -8.255)
		(stroke
			(width 0.508)
			(type default)
		)
		(layer "In12.Cu")
	)
	(gr_line
		(start 178.689 -8.255)
		(end 178.435 -8.001)
		(stroke
			(width 0.508)
			(type default)
		)
		(layer "In12.Cu")
	)
	(gr_line
		(start 242.697 -131.9276)
		(end 242.697 -131.2926)
		(stroke
			(width 0.381)
			(type default)
		)
		(layer "In12.Cu")
	)
	(gr_line
		(start 242.697 -131.2926)
		(end 243.586 -130.4036)
		(stroke
			(width 0.381)
			(type default)
		)
		(layer "In12.Cu")
	)
	(gr_line
		(start 242.697 -23.749)
		(end 243.0526 -24.1046)
		(stroke
			(width 0.381)
			(type default)
		)
		(layer "In12.Cu")
	)
	(gr_line
		(start 242.697 -23.2156)
		(end 242.697 -23.749)
		(stroke
			(width 0.381)
			(type default)
		)
		(layer "In12.Cu")
	)
	(gr_line
		(start 242.951 -132.1816)
		(end 242.697 -131.9276)
		(stroke
			(width 0.381)
			(type default)
		)
		(layer "In12.Cu")
	)
	(gr_line
		(start 243.0526 -24.1046)
		(end 243.078 -24.13)
		(stroke
			(width 0.381)
			(type default)
		)
		(layer "In12.Cu")
	)
	(gr_line
		(start 243.0526 -24.1046)
		(end 258.572 -24.1046)
		(stroke
			(width 0.381)
			(type default)
		)
		(layer "In12.Cu")
	)
	(gr_circle
		(center 243.0526 -24.104346)
		(end 243.052854 -24.104346)
		(stroke
			(width 0.381)
			(type default)
		)
		(fill no)
		(layer "In12.Cu")
	)
	(gr_circle
		(center 243.585746 -130.4036)
		(end 243.586 -130.4036)
		(stroke
			(width 0.381)
			(type default)
		)
		(fill no)
		(layer "In12.Cu")
	)
	(gr_line
		(start 243.586 -130.4036)
		(end 243.586 -129.3114)
		(stroke
			(width 0.381)
			(type default)
		)
		(layer "In12.Cu")
	)
	(gr_line
		(start 243.586 -129.3114)
		(end 243.9416 -128.9558)
		(stroke
			(width 0.381)
			(type default)
		)
		(layer "In12.Cu")
	)
	(gr_line
		(start 243.6114 -22.3012)
		(end 242.697 -23.2156)
		(stroke
			(width 0.381)
			(type default)
		)
		(layer "In12.Cu")
	)
	(gr_line
		(start 243.6114 -21.1836)
		(end 243.6114 -22.3012)
		(stroke
			(width 0.381)
			(type default)
		)
		(layer "In12.Cu")
	)
	(gr_line
		(start 243.84 -20.955)
		(end 243.6114 -21.1836)
		(stroke
			(width 0.381)
			(type default)
		)
		(layer "In12.Cu")
	)
	(gr_circle
		(center 243.9416 -128.956054)
		(end 243.941854 -128.956054)
		(stroke
			(width 0.381)
			(type default)
		)
		(fill no)
		(layer "In12.Cu")
	)
	(gr_line
		(start 243.9416 -128.9558)
		(end 258.3942 -128.9558)
		(stroke
			(width 0.381)
			(type default)
		)
		(layer "In12.Cu")
	)
	(gr_line
		(start 258.3942 -128.9558)
		(end 258.9022 -129.4638)
		(stroke
			(width 0.381)
			(type default)
		)
		(layer "In12.Cu")
	)
	(gr_line
		(start 258.4958 -20.955)
		(end 243.84 -20.955)
		(stroke
			(width 0.381)
			(type default)
		)
		(layer "In12.Cu")
	)
	(gr_line
		(start 258.5212 -132.1816)
		(end 242.951 -132.1816)
		(stroke
			(width 0.381)
			(type default)
		)
		(layer "In12.Cu")
	)
	(gr_line
		(start 258.572 -24.1046)
		(end 258.9022 -23.7744)
		(stroke
			(width 0.381)
			(type default)
		)
		(layer "In12.Cu")
	)
	(gr_line
		(start 258.9022 -131.8006)
		(end 258.5212 -132.1816)
		(stroke
			(width 0.381)
			(type default)
		)
		(layer "In12.Cu")
	)
	(gr_line
		(start 258.9022 -129.4638)
		(end 258.9022 -131.8006)
		(stroke
			(width 0.381)
			(type default)
		)
		(layer "In12.Cu")
	)
	(gr_line
		(start 258.9022 -23.7744)
		(end 258.9022 -21.3614)
		(stroke
			(width 0.381)
			(type default)
		)
		(layer "In12.Cu")
	)
	(gr_line
		(start 258.9022 -21.3614)
		(end 258.4958 -20.955)
		(stroke
			(width 0.381)
			(type default)
		)
		(layer "In12.Cu")
	)
	(gr_line
		(start 264.7696 -149.5044)
		(end 265.049 -149.7838)
		(stroke
			(width 0.381)
			(type default)
		)
		(layer "In12.Cu")
	)
	(gr_line
		(start 264.7696 -148.4884)
		(end 264.7696 -149.5044)
		(stroke
			(width 0.381)
			(type default)
		)
		(layer "In12.Cu")
	)
	(gr_line
		(start 264.7696 -12.9286)
		(end 265.0998 -13.2588)
		(stroke
			(width 0.381)
			(type default)
		)
		(layer "In12.Cu")
	)
	(gr_line
		(start 264.7696 -11.6586)
		(end 264.7696 -12.9286)
		(stroke
			(width 0.381)
			(type default)
		)
		(layer "In12.Cu")
	)
	(gr_line
		(start 264.7696 -3.3782)
		(end 264.9982 -3.6068)
		(stroke
			(width 0.381)
			(type default)
		)
		(layer "In12.Cu")
	)
	(gr_line
		(start 264.7696 -2.0828)
		(end 264.7696 -3.3782)
		(stroke
			(width 0.381)
			(type default)
		)
		(layer "In12.Cu")
	)
	(gr_line
		(start 264.8204 -139.8778)
		(end 265.1252 -140.1826)
		(stroke
			(width 0.381)
			(type default)
		)
		(layer "In12.Cu")
	)
	(gr_line
		(start 264.8204 -138.9888)
		(end 264.8204 -139.8778)
		(stroke
			(width 0.381)
			(type default)
		)
		(layer "In12.Cu")
	)
	(gr_line
		(start 264.8458 -130.7338)
		(end 266.2936 -132.1816)
		(stroke
			(width 0.381)
			(type default)
		)
		(layer "In12.Cu")
	)
	(gr_line
		(start 264.8458 -129.286)
		(end 264.8458 -130.7338)
		(stroke
			(width 0.381)
			(type default)
		)
		(layer "In12.Cu")
	)
	(gr_line
		(start 264.8712 -22.733)
		(end 264.8712 -21.336)
		(stroke
			(width 0.381)
			(type default)
		)
		(layer "In12.Cu")
	)
	(gr_line
		(start 264.8712 -21.336)
		(end 265.2776 -20.9296)
		(stroke
			(width 0.381)
			(type default)
		)
		(layer "In12.Cu")
	)
	(gr_circle
		(center 264.871454 -22.733)
		(end 264.871708 -22.733)
		(stroke
			(width 0.381)
			(type default)
		)
		(fill no)
		(layer "In12.Cu")
	)
	(gr_line
		(start 264.9982 -3.6068)
		(end 267.7668 -3.6068)
		(stroke
			(width 0.381)
			(type default)
		)
		(layer "In12.Cu")
	)
	(gr_circle
		(center 264.9982 -3.606546)
		(end 264.998454 -3.606546)
		(stroke
			(width 0.381)
			(type default)
		)
		(fill no)
		(layer "In12.Cu")
	)
	(gr_line
		(start 265.049 -149.7838)
		(end 268.0716 -149.7838)
		(stroke
			(width 0.381)
			(type default)
		)
		(layer "In12.Cu")
	)
	(gr_circle
		(center 265.049 -149.783546)
		(end 265.049254 -149.783546)
		(stroke
			(width 0.381)
			(type default)
		)
		(fill no)
		(layer "In12.Cu")
	)
	(gr_line
		(start 265.049 -1.8034)
		(end 264.7696 -2.0828)
		(stroke
			(width 0.381)
			(type default)
		)
		(layer "In12.Cu")
	)
	(gr_line
		(start 265.0744 -148.1836)
		(end 264.7696 -148.4884)
		(stroke
			(width 0.381)
			(type default)
		)
		(layer "In12.Cu")
	)
	(gr_line
		(start 265.0744 -11.3538)
		(end 264.7696 -11.6586)
		(stroke
			(width 0.381)
			(type default)
		)
		(layer "In12.Cu")
	)
	(gr_line
		(start 265.0998 -13.2588)
		(end 267.716 -13.2588)
		(stroke
			(width 0.381)
			(type default)
		)
		(layer "In12.Cu")
	)
	(gr_circle
		(center 265.0998 -13.258546)
		(end 265.100054 -13.258546)
		(stroke
			(width 0.381)
			(type default)
		)
		(fill no)
		(layer "In12.Cu")
	)
	(gr_line
		(start 265.1252 -140.1826)
		(end 268.0462 -140.1826)
		(stroke
			(width 0.381)
			(type default)
		)
		(layer "In12.Cu")
	)
	(gr_circle
		(center 265.1252 -140.182346)
		(end 265.125454 -140.182346)
		(stroke
			(width 0.381)
			(type default)
		)
		(fill no)
		(layer "In12.Cu")
	)
	(gr_line
		(start 265.1506 -128.9812)
		(end 264.8458 -129.286)
		(stroke
			(width 0.381)
			(type default)
		)
		(layer "In12.Cu")
	)
	(gr_line
		(start 265.176 -138.6332)
		(end 264.8204 -138.9888)
		(stroke
			(width 0.381)
			(type default)
		)
		(layer "In12.Cu")
	)
	(gr_line
		(start 265.2776 -20.9296)
		(end 278.1808 -20.9296)
		(stroke
			(width 0.381)
			(type default)
		)
		(layer "In12.Cu")
	)
	(gr_line
		(start 265.4808 -23.7744)
		(end 265.4808 -23.3426)
		(stroke
			(width 0.381)
			(type default)
		)
		(layer "In12.Cu")
	)
	(gr_line
		(start 265.4808 -23.3426)
		(end 264.8712 -22.733)
		(stroke
			(width 0.381)
			(type default)
		)
		(layer "In12.Cu")
	)
	(gr_line
		(start 265.811 -24.1046)
		(end 265.4808 -23.7744)
		(stroke
			(width 0.381)
			(type default)
		)
		(layer "In12.Cu")
	)
	(gr_line
		(start 266.2936 -132.1816)
		(end 278.2062 -132.1816)
		(stroke
			(width 0.381)
			(type default)
		)
		(layer "In12.Cu")
	)
	(gr_circle
		(center 266.2936 -132.181346)
		(end 266.293854 -132.181346)
		(stroke
			(width 0.381)
			(type default)
		)
		(fill no)
		(layer "In12.Cu")
	)
	(gr_line
		(start 267.716 -13.2588)
		(end 268.4526 -12.5222)
		(stroke
			(width 0.381)
			(type default)
		)
		(layer "In12.Cu")
	)
	(gr_line
		(start 267.7668 -3.6068)
		(end 268.4526 -2.921)
		(stroke
			(width 0.381)
			(type default)
		)
		(layer "In12.Cu")
	)
	(gr_line
		(start 268.0462 -140.1826)
		(end 268.4526 -139.7762)
		(stroke
			(width 0.381)
			(type default)
		)
		(layer "In12.Cu")
	)
	(gr_line
		(start 268.0716 -149.7838)
		(end 268.478 -149.3774)
		(stroke
			(width 0.381)
			(type default)
		)
		(layer "In12.Cu")
	)
	(gr_line
		(start 268.4526 -139.7762)
		(end 268.8844 -139.7762)
		(stroke
			(width 0.381)
			(type default)
		)
		(layer "In12.Cu")
	)
	(gr_line
		(start 268.4526 -12.5222)
		(end 268.8844 -12.5222)
		(stroke
			(width 0.381)
			(type default)
		)
		(layer "In12.Cu")
	)
	(gr_line
		(start 268.4526 -2.921)
		(end 268.8844 -2.921)
		(stroke
			(width 0.381)
			(type default)
		)
		(layer "In12.Cu")
	)
	(gr_line
		(start 268.478 -149.3774)
		(end 268.9098 -149.3774)
		(stroke
			(width 0.381)
			(type default)
		)
		(layer "In12.Cu")
	)
	(gr_line
		(start 268.7066 -148.1836)
		(end 265.0744 -148.1836)
		(stroke
			(width 0.381)
			(type default)
		)
		(layer "In12.Cu")
	)
	(gr_line
		(start 268.7574 -138.6332)
		(end 265.176 -138.6332)
		(stroke
			(width 0.381)
			(type default)
		)
		(layer "In12.Cu")
	)
	(gr_line
		(start 268.8336 -11.3538)
		(end 265.0744 -11.3538)
		(stroke
			(width 0.381)
			(type default)
		)
		(layer "In12.Cu")
	)
	(gr_line
		(start 268.8844 -139.7762)
		(end 269.113 -139.5476)
		(stroke
			(width 0.381)
			(type default)
		)
		(layer "In12.Cu")
	)
	(gr_line
		(start 268.8844 -12.5222)
		(end 269.1638 -12.2428)
		(stroke
			(width 0.381)
			(type default)
		)
		(layer "In12.Cu")
	)
	(gr_line
		(start 268.8844 -2.921)
		(end 269.1384 -2.667)
		(stroke
			(width 0.381)
			(type default)
		)
		(layer "In12.Cu")
	)
	(gr_line
		(start 268.9098 -149.3774)
		(end 269.0876 -149.1996)
		(stroke
			(width 0.381)
			(type default)
		)
		(layer "In12.Cu")
	)
	(gr_line
		(start 268.9098 -1.8034)
		(end 265.049 -1.8034)
		(stroke
			(width 0.381)
			(type default)
		)
		(layer "In12.Cu")
	)
	(gr_line
		(start 269.0876 -149.1996)
		(end 269.0876 -148.5646)
		(stroke
			(width 0.381)
			(type default)
		)
		(layer "In12.Cu")
	)
	(gr_line
		(start 269.0876 -148.5646)
		(end 268.7066 -148.1836)
		(stroke
			(width 0.381)
			(type default)
		)
		(layer "In12.Cu")
	)
	(gr_line
		(start 269.113 -139.5476)
		(end 269.113 -138.9888)
		(stroke
			(width 0.381)
			(type default)
		)
		(layer "In12.Cu")
	)
	(gr_line
		(start 269.113 -138.9888)
		(end 268.7574 -138.6332)
		(stroke
			(width 0.381)
			(type default)
		)
		(layer "In12.Cu")
	)
	(gr_line
		(start 269.1384 -2.667)
		(end 269.1384 -2.032)
		(stroke
			(width 0.381)
			(type default)
		)
		(layer "In12.Cu")
	)
	(gr_line
		(start 269.1384 -2.032)
		(end 268.9098 -1.8034)
		(stroke
			(width 0.381)
			(type default)
		)
		(layer "In12.Cu")
	)
	(gr_line
		(start 269.1638 -12.2428)
		(end 269.1638 -11.684)
		(stroke
			(width 0.381)
			(type default)
		)
		(layer "In12.Cu")
	)
	(gr_line
		(start 269.1638 -11.684)
		(end 268.8336 -11.3538)
		(stroke
			(width 0.381)
			(type default)
		)
		(layer "In12.Cu")
	)
	(gr_line
		(start 278.1554 -128.9812)
		(end 265.1506 -128.9812)
		(stroke
			(width 0.381)
			(type default)
		)
		(layer "In12.Cu")
	)
	(gr_line
		(start 278.1808 -20.9296)
		(end 278.5618 -21.3106)
		(stroke
			(width 0.381)
			(type default)
		)
		(layer "In12.Cu")
	)
	(gr_line
		(start 278.2062 -132.1816)
		(end 278.5618 -131.826)
		(stroke
			(width 0.381)
			(type default)
		)
		(layer "In12.Cu")
	)
	(gr_line
		(start 278.2062 -24.1046)
		(end 265.811 -24.1046)
		(stroke
			(width 0.381)
			(type default)
		)
		(layer "In12.Cu")
	)
	(gr_line
		(start 278.3332 -130.4544)
		(end 278.3332 -130.0226)
		(stroke
			(width 0.381)
			(type default)
		)
		(layer "In12.Cu")
	)
	(gr_line
		(start 278.3332 -130.0226)
		(end 278.511 -129.8448)
		(stroke
			(width 0.381)
			(type default)
		)
		(layer "In12.Cu")
	)
	(gr_line
		(start 278.511 -129.8448)
		(end 278.511 -129.3368)
		(stroke
			(width 0.381)
			(type default)
		)
		(layer "In12.Cu")
	)
	(gr_line
		(start 278.511 -129.3368)
		(end 278.1554 -128.9812)
		(stroke
			(width 0.381)
			(type default)
		)
		(layer "In12.Cu")
	)
	(gr_line
		(start 278.5618 -131.826)
		(end 278.5618 -130.683)
		(stroke
			(width 0.381)
			(type default)
		)
		(layer "In12.Cu")
	)
	(gr_line
		(start 278.5618 -130.683)
		(end 278.3332 -130.4544)
		(stroke
			(width 0.381)
			(type default)
		)
		(layer "In12.Cu")
	)
	(gr_line
		(start 278.5618 -23.749)
		(end 278.2062 -24.1046)
		(stroke
			(width 0.381)
			(type default)
		)
		(layer "In12.Cu")
	)
	(gr_line
		(start 278.5618 -21.3106)
		(end 278.5618 -23.749)
		(stroke
			(width 0.381)
			(type default)
		)
		(layer "In12.Cu")
	)
	(gr_line
		(start 336.296 -25.146)
		(end 337.693 -26.543)
		(stroke
			(width 0.508)
			(type default)
		)
		(layer "In12.Cu")
	)
	(gr_line
		(start 336.296 -22.86)
		(end 336.296 -25.146)
		(stroke
			(width 0.508)
			(type default)
		)
		(layer "In12.Cu")
	)
	(gr_line
		(start 337.693 -26.543)
		(end 340.36 -26.543)
		(stroke
			(width 0.508)
			(type default)
		)
		(layer "In12.Cu")
	)
	(gr_line
		(start 337.82 -22.86)
		(end 336.296 -22.86)
		(stroke
			(width 0.508)
			(type default)
		)
		(layer "In12.Cu")
	)
	(gr_line
		(start 338.455 -23.368)
		(end 337.82 -22.86)
		(stroke
			(width 0.508)
			(type default)
		)
		(layer "In12.Cu")
	)
	(gr_line
		(start 339.979 -22.225)
		(end 340.233 -22.479)
		(stroke
			(width 0.508)
			(type default)
		)
		(layer "In12.Cu")
	)
	(gr_line
		(start 339.979 -21.59)
		(end 339.979 -22.225)
		(stroke
			(width 0.508)
			(type default)
		)
		(layer "In12.Cu")
	)
	(gr_line
		(start 340.233 -22.479)
		(end 340.487 -22.479)
		(stroke
			(width 0.508)
			(type default)
		)
		(layer "In12.Cu")
	)
	(gr_line
		(start 340.233 -21.336)
		(end 339.979 -21.59)
		(stroke
			(width 0.508)
			(type default)
		)
		(layer "In12.Cu")
	)
	(gr_line
		(start 340.36 -26.543)
		(end 340.741 -26.162)
		(stroke
			(width 0.508)
			(type default)
		)
		(layer "In12.Cu")
	)
	(gr_line
		(start 340.487 -22.479)
		(end 340.741 -22.733)
		(stroke
			(width 0.508)
			(type default)
		)
		(layer "In12.Cu")
	)
	(gr_line
		(start 340.614 -23.368)
		(end 338.455 -23.368)
		(stroke
			(width 0.508)
			(type default)
		)
		(layer "In12.Cu")
	)
	(gr_line
		(start 340.741 -26.162)
		(end 345.313 -26.162)
		(stroke
			(width 0.508)
			(type default)
		)
		(layer "In12.Cu")
	)
	(gr_line
		(start 340.741 -23.241)
		(end 340.614 -23.368)
		(stroke
			(width 0.508)
			(type default)
		)
		(layer "In12.Cu")
	)
	(gr_line
		(start 340.741 -22.733)
		(end 340.741 -23.241)
		(stroke
			(width 0.508)
			(type default)
		)
		(layer "In12.Cu")
	)
	(gr_line
		(start 340.995 -21.336)
		(end 340.233 -21.336)
		(stroke
			(width 0.508)
			(type default)
		)
		(layer "In12.Cu")
	)
	(gr_line
		(start 341.376 -21.717)
		(end 340.995 -21.336)
		(stroke
			(width 0.508)
			(type default)
		)
		(layer "In12.Cu")
	)
	(gr_line
		(start 342.646 -21.717)
		(end 341.376 -21.717)
		(stroke
			(width 0.508)
			(type default)
		)
		(layer "In12.Cu")
	)
	(gr_line
		(start 343.281 -22.352)
		(end 342.646 -21.717)
		(stroke
			(width 0.508)
			(type default)
		)
		(layer "In12.Cu")
	)
	(gr_line
		(start 345.059 -22.352)
		(end 343.281 -22.352)
		(stroke
			(width 0.508)
			(type default)
		)
		(layer "In12.Cu")
	)
	(gr_line
		(start 345.186 -22.225)
		(end 345.059 -22.352)
		(stroke
			(width 0.508)
			(type default)
		)
		(layer "In12.Cu")
	)
	(gr_line
		(start 345.186 -21.59)
		(end 345.186 -22.225)
		(stroke
			(width 0.508)
			(type default)
		)
		(layer "In12.Cu")
	)
	(gr_line
		(start 345.313 -26.162)
		(end 346.329 -25.146)
		(stroke
			(width 0.508)
			(type default)
		)
		(layer "In12.Cu")
	)
	(gr_line
		(start 345.313 -21.463)
		(end 345.186 -21.59)
		(stroke
			(width 0.508)
			(type default)
		)
		(layer "In12.Cu")
	)
	(gr_line
		(start 345.821 -21.463)
		(end 345.313 -21.463)
		(stroke
			(width 0.508)
			(type default)
		)
		(layer "In12.Cu")
	)
	(gr_line
		(start 346.202 -23.495)
		(end 346.202 -21.844)
		(stroke
			(width 0.508)
			(type default)
		)
		(layer "In12.Cu")
	)
	(gr_line
		(start 346.202 -21.844)
		(end 345.821 -21.463)
		(stroke
			(width 0.508)
			(type default)
		)
		(layer "In12.Cu")
	)
	(gr_line
		(start 346.329 -25.146)
		(end 346.329 -23.622)
		(stroke
			(width 0.508)
			(type default)
		)
		(layer "In12.Cu")
	)
	(gr_line
		(start 346.329 -23.622)
		(end 346.202 -23.495)
		(stroke
			(width 0.508)
			(type default)
		)
		(layer "In12.Cu")
	)
	(gr_rect
		(start 401.00377 -127.405384)
		(end 402.40077 -127.913384)
		(stroke
			(width 0)
			(type default)
		)
		(fill no)
		(layer "In12.Cu")
	)
	(gr_rect
		(start 401.00377 -126.135384)
		(end 402.40077 -126.643384)
		(stroke
			(width 0)
			(type default)
		)
		(fill no)
		(layer "In12.Cu")
	)
	(gr_line
		(start 429.82007 -137.109454)
		(end 431.09007 -137.109454)
		(stroke
			(width 0.2)
			(type default)
		)
		(layer "In12.Cu")
	)
	(gr_arc
		(start 429.82007 -135.580374)
		(mid 429.05553 -136.344914)
		(end 429.82007 -137.109454)
		(stroke
			(width 0.2)
			(type default)
		)
		(layer "In12.Cu")
	)
	(gr_arc
		(start 431.09007 -137.109454)
		(mid 431.629783 -136.886423)
		(end 431.85461 -136.347454)
		(stroke
			(width 0.2)
			(type default)
		)
		(layer "In12.Cu")
	)
	(gr_line
		(start 431.09007 -135.580374)
		(end 429.82007 -135.580374)
		(stroke
			(width 0.2)
			(type default)
		)
		(layer "In12.Cu")
	)
	(gr_line
		(start 431.666142 -136.347454)
		(end 431.666142 -136.344914)
		(stroke
			(width 0.2)
			(type default)
		)
		(layer "In12.Cu")
	)
	(gr_line
		(start 431.666142 -136.344914)
		(end 431.85461 -136.344914)
		(stroke
			(width 0.2)
			(type default)
		)
		(layer "In12.Cu")
	)
	(gr_line
		(start 431.85461 -136.347454)
		(end 431.666142 -136.347454)
		(stroke
			(width 0.2)
			(type default)
		)
		(layer "In12.Cu")
	)
	(gr_arc
		(start 431.85461 -136.344914)
		(mid 431.630681 -135.804303)
		(end 431.09007 -135.580374)
		(stroke
			(width 0.2)
			(type default)
		)
		(layer "In12.Cu")
	)
	(gr_line
		(start 433.63007 -137.109454)
		(end 434.90007 -137.109454)
		(stroke
			(width 0.2)
			(type default)
		)
		(layer "In12.Cu")
	)
	(gr_arc
		(start 433.63007 -135.580374)
		(mid 432.86553 -136.344914)
		(end 433.63007 -137.109454)
		(stroke
			(width 0.2)
			(type default)
		)
		(layer "In12.Cu")
	)
	(gr_arc
		(start 434.90007 -137.109454)
		(mid 435.439783 -136.886423)
		(end 435.66461 -136.347454)
		(stroke
			(width 0.2)
			(type default)
		)
		(layer "In12.Cu")
	)
	(gr_line
		(start 434.90007 -135.580374)
		(end 433.63007 -135.580374)
		(stroke
			(width 0.2)
			(type default)
		)
		(layer "In12.Cu")
	)
	(gr_line
		(start 435.473856 -136.347454)
		(end 435.473856 -136.344914)
		(stroke
			(width 0.2)
			(type default)
		)
		(layer "In12.Cu")
	)
	(gr_line
		(start 435.473856 -136.344914)
		(end 435.66461 -136.344914)
		(stroke
			(width 0.2)
			(type default)
		)
		(layer "In12.Cu")
	)
	(gr_line
		(start 435.66461 -136.347454)
		(end 435.473856 -136.347454)
		(stroke
			(width 0.2)
			(type default)
		)
		(layer "In12.Cu")
	)
	(gr_arc
		(start 435.66461 -136.344914)
		(mid 435.440681 -135.804303)
		(end 434.90007 -135.580374)
		(stroke
			(width 0.2)
			(type default)
		)
		(layer "In12.Cu")
	)
	(gr_rect
		(start 460.265272 -60.94222)
		(end 461.662272 -62.33922)
		(stroke
			(width 0)
			(type default)
		)
		(fill no)
		(layer "In12.Cu")
	)
	(segment
		(start 379.31725 -103.615236)
		(end 378.82195 -103.84536)
		(width 0.10795)
		(layer "F.Cu")
		(net "Net_1")
	)
	(via
		(at 379.31725 -103.615236)
		(size 0.508)
		(drill 0.254)
		(layers "F.Cu" "B.Cu")
		(net "Net_1")
	)
	(segment
		(start 377.83135 -103.84536)
		(end 378.32665 -103.615236)
		(width 0.10795)
		(layer "F.Cu")
		(net "Net_2")
	)
	(via
		(at 378.32665 -103.615236)
		(size 0.508)
		(drill 0.254)
		(layers "F.Cu" "B.Cu")
		(net "Net_2")
	)
	(segment
		(start 374.102122 -104.6226)
		(end 374.062752 -104.66197)
		(width 0.0889)
		(layer "F.Cu")
		(net "Net_3")
	)
	(segment
		(start 375.504964 -103.855012)
		(end 374.977406 -104.007158)
		(width 0.0889)
		(layer "F.Cu")
		(net "Net_3")
	)
	(segment
		(start 374.361964 -104.6226)
		(end 374.102122 -104.6226)
		(width 0.0889)
		(layer "F.Cu")
		(net "Net_3")
	)
	(segment
		(start 374.977406 -104.007158)
		(end 374.361964 -104.6226)
		(width 0.0889)
		(layer "F.Cu")
		(net "Net_3")
	)
	(via
		(at 374.062752 -104.66197)
		(size 0.508)
		(drill 0.254)
		(layers "F.Cu" "B.Cu")
		(net "Net_3")
	)
	(segment
		(start 374.674892 -103.855012)
		(end 374.674892 -104.00919)
		(width 0.0889)
		(layer "F.Cu")
		(net "Net_4")
	)
	(segment
		(start 374.674892 -104.00919)
		(end 374.429782 -104.2543)
		(width 0.0889)
		(layer "F.Cu")
		(net "Net_4")
	)
	(segment
		(start 374.429782 -104.2543)
		(end 373.839232 -104.2543)
		(width 0.0889)
		(layer "F.Cu")
		(net "Net_4")
	)
	(segment
		(start 373.839232 -104.2543)
		(end 373.406924 -104.686608)
		(width 0.0889)
		(layer "F.Cu")
		(net "Net_4")
	)
	(via
		(at 373.406924 -104.686608)
		(size 0.508)
		(drill 0.254)
		(layers "F.Cu" "B.Cu")
		(net "Net_4")
	)
	(segment
		(start 357.485188 -4.389882)
		(end 357.485188 -3.337306)
		(width 0.10795)
		(layer "F.Cu")
		(net "JTAG_RISER_TRST")
	)
	(via
		(at 357.485188 -3.337306)
		(size 0.508)
		(drill 0.254)
		(layers "F.Cu" "B.Cu")
		(net "JTAG_RISER_TRST")
	)
	(segment
		(start 357.485188 -3.337306)
		(end 357.485188 -4.019042)
		(width 0.10795)
		(layer "B.Cu")
		(net "JTAG_RISER_TRST")
	)
	(segment
		(start 357.485188 -4.019042)
		(end 357.707946 -4.2418)
		(width 0.10795)
		(layer "B.Cu")
		(net "JTAG_RISER_TRST")
	)
	(segment
		(start 357.707946 -4.2418)
		(end 358.3432 -4.2418)
		(width 0.10795)
		(layer "B.Cu")
		(net "JTAG_RISER_TRST")
	)
	(segment
		(start 359.885234 -4.389882)
		(end 359.885234 -3.337306)
		(width 0.10795)
		(layer "F.Cu")
		(net "JTAG_RISER_TMS")
	)
	(via
		(at 359.885234 -3.337306)
		(size 0.508)
		(drill 0.254)
		(layers "F.Cu" "B.Cu")
		(net "JTAG_RISER_TMS")
	)
	(via
		(at 361.0356 -4.2418)
		(size 0.6604)
		(drill 0.3302)
		(layers "F.Cu" "B.Cu")
		(net "JTAG_RISER_TMS")
	)
	(segment
		(start 359.8672 -4.2418)
		(end 361.0356 -4.2418)
		(width 0.10795)
		(layer "B.Cu")
		(net "JTAG_RISER_TMS")
	)
	(segment
		(start 359.59415 -3.62839)
		(end 359.59415 -3.96875)
		(width 0.10795)
		(layer "B.Cu")
		(net "JTAG_RISER_TMS")
	)
	(segment
		(start 359.59415 -3.96875)
		(end 359.8672 -4.2418)
		(width 0.10795)
		(layer "B.Cu")
		(net "JTAG_RISER_TMS")
	)
	(segment
		(start 359.885234 -3.337306)
		(end 359.59415 -3.62839)
		(width 0.10795)
		(layer "B.Cu")
		(net "JTAG_RISER_TMS")
	)
	(segment
		(start 359.876598 -10.916158)
		(end 359.876598 -11.551158)
		(width 0.10795)
		(layer "F.Cu")
		(net "JTAG_RISER_TDO_R")
	)
	(via
		(at 359.179114 -11.788648)
		(size 0.6604)
		(drill 0.3302)
		(layers "F.Cu" "B.Cu")
		(net "JTAG_RISER_TDO_R")
	)
	(via
		(at 359.876598 -11.551158)
		(size 0.508)
		(drill 0.254)
		(layers "F.Cu" "B.Cu")
		(net "JTAG_RISER_TDO_R")
	)
	(via
		(at 384.4798 -1.798828)
		(size 0.508)
		(drill 0.254)
		(layers "F.Cu" "B.Cu")
		(net "JTAG_RISER_TDO_R")
	)
	(segment
		(start 359.639108 -11.788648)
		(end 359.876598 -11.551158)
		(width 0.10795)
		(layer "B.Cu")
		(net "JTAG_RISER_TDO_R")
	)
	(segment
		(start 359.179114 -11.788648)
		(end 359.639108 -11.788648)
		(width 0.10795)
		(layer "B.Cu")
		(net "JTAG_RISER_TDO_R")
	)
	(segment
		(start 385.3688 -1.798828)
		(end 384.4798 -1.798828)
		(width 0.10795)
		(layer "B.Cu")
		(net "JTAG_RISER_TDO_R")
	)
	(segment
		(start 359.876598 -11.551158)
		(end 360.3244 -11.103356)
		(width 0.089408)
		(layer "In11.Cu")
		(net "JTAG_RISER_TDO_R")
	)
	(segment
		(start 360.3244 -10.905744)
		(end 361.184952 -10.045192)
		(width 0.089408)
		(layer "In11.Cu")
		(net "JTAG_RISER_TDO_R")
	)
	(segment
		(start 367.788952 -3.923792)
		(end 380.209552 -3.923792)
		(width 0.089408)
		(layer "In11.Cu")
		(net "JTAG_RISER_TDO_R")
	)
	(segment
		(start 361.667552 -10.045192)
		(end 367.788952 -3.923792)
		(width 0.089408)
		(layer "In11.Cu")
		(net "JTAG_RISER_TDO_R")
	)
	(segment
		(start 380.209552 -3.923792)
		(end 382.334516 -1.798828)
		(width 0.089408)
		(layer "In11.Cu")
		(net "JTAG_RISER_TDO_R")
	)
	(segment
		(start 360.3244 -11.103356)
		(end 360.3244 -10.905744)
		(width 0.089408)
		(layer "In11.Cu")
		(net "JTAG_RISER_TDO_R")
	)
	(segment
		(start 382.334516 -1.798828)
		(end 384.4798 -1.798828)
		(width 0.089408)
		(layer "In11.Cu")
		(net "JTAG_RISER_TDO_R")
	)
	(segment
		(start 361.184952 -10.045192)
		(end 361.667552 -10.045192)
		(width 0.089408)
		(layer "In11.Cu")
		(net "JTAG_RISER_TDO_R")
	)
	(segment
		(start 359.885234 -8.597646)
		(end 359.885234 -7.789926)
		(width 0.10795)
		(layer "F.Cu")
		(net "JTAG_RISER_TDO")
	)
	(segment
		(start 360.200448 -8.91286)
		(end 359.885234 -8.597646)
		(width 0.1143)
		(layer "F.Cu")
		(net "JTAG_RISER_TDO")
	)
	(segment
		(start 359.876598 -10.027158)
		(end 360.200448 -9.703308)
		(width 0.1143)
		(layer "F.Cu")
		(net "JTAG_RISER_TDO")
	)
	(segment
		(start 360.200448 -9.703308)
		(end 360.200448 -8.91286)
		(width 0.1143)
		(layer "F.Cu")
		(net "JTAG_RISER_TDO")
	)
	(segment
		(start 360.765598 -10.916158)
		(end 360.765598 -11.551158)
		(width 0.10795)
		(layer "F.Cu")
		(net "JTAG_RISER_TDI_R")
	)
	(via
		(at 360.765598 -11.551158)
		(size 0.508)
		(drill 0.254)
		(layers "F.Cu" "B.Cu")
		(net "JTAG_RISER_TDI_R")
	)
	(via
		(at 386.2578 -1.8034)
		(size 0.508)
		(drill 0.254)
		(layers "F.Cu" "B.Cu")
		(net "JTAG_RISER_TDI_R")
	)
	(via
		(at 360.765598 -12.287758)
		(size 0.6604)
		(drill 0.3302)
		(layers "F.Cu" "B.Cu")
		(net "JTAG_RISER_TDI_R")
	)
	(segment
		(start 387.1468 -1.8034)
		(end 386.2578 -1.8034)
		(width 0.10795)
		(layer "B.Cu")
		(net "JTAG_RISER_TDI_R")
	)
	(segment
		(start 360.765598 -11.551158)
		(end 360.765598 -12.287758)
		(width 0.10795)
		(layer "B.Cu")
		(net "JTAG_RISER_TDI_R")
	)
	(segment
		(start 380.2888 -4.1148)
		(end 382.1684 -2.2352)
		(width 0.089408)
		(layer "In11.Cu")
		(net "JTAG_RISER_TDI_R")
	)
	(segment
		(start 382.1684 -2.2352)
		(end 384.7846 -2.2352)
		(width 0.089408)
		(layer "In11.Cu")
		(net "JTAG_RISER_TDI_R")
	)
	(segment
		(start 367.8682 -4.1148)
		(end 380.2888 -4.1148)
		(width 0.089408)
		(layer "In11.Cu")
		(net "JTAG_RISER_TDI_R")
	)
	(segment
		(start 360.515408 -10.984992)
		(end 361.2642 -10.2362)
		(width 0.089408)
		(layer "In11.Cu")
		(net "JTAG_RISER_TDI_R")
	)
	(segment
		(start 385.2164 -1.8034)
		(end 386.2578 -1.8034)
		(width 0.089408)
		(layer "In11.Cu")
		(net "JTAG_RISER_TDI_R")
	)
	(segment
		(start 361.7468 -10.2362)
		(end 367.8682 -4.1148)
		(width 0.089408)
		(layer "In11.Cu")
		(net "JTAG_RISER_TDI_R")
	)
	(segment
		(start 361.2642 -10.2362)
		(end 361.7468 -10.2362)
		(width 0.089408)
		(layer "In11.Cu")
		(net "JTAG_RISER_TDI_R")
	)
	(segment
		(start 360.765598 -11.551158)
		(end 360.515408 -11.300968)
		(width 0.089408)
		(layer "In11.Cu")
		(net "JTAG_RISER_TDI_R")
	)
	(segment
		(start 384.7846 -2.2352)
		(end 385.2164 -1.8034)
		(width 0.089408)
		(layer "In11.Cu")
		(net "JTAG_RISER_TDI_R")
	)
	(segment
		(start 360.515408 -11.300968)
		(end 360.515408 -10.984992)
		(width 0.089408)
		(layer "In11.Cu")
		(net "JTAG_RISER_TDI_R")
	)
	(segment
		(start 360.441748 -8.841232)
		(end 360.68508 -8.5979)
		(width 0.1143)
		(layer "F.Cu")
		(net "JTAG_RISER_TDI")
	)
	(segment
		(start 360.68508 -8.5979)
		(end 360.68508 -7.789926)
		(width 0.1143)
		(layer "F.Cu")
		(net "JTAG_RISER_TDI")
	)
	(segment
		(start 360.765598 -10.027158)
		(end 360.441748 -9.703308)
		(width 0.1143)
		(layer "F.Cu")
		(net "JTAG_RISER_TDI")
	)
	(segment
		(start 360.441748 -9.703308)
		(end 360.441748 -8.841232)
		(width 0.1143)
		(layer "F.Cu")
		(net "JTAG_RISER_TDI")
	)
	(segment
		(start 359.085134 -4.389882)
		(end 359.085134 -3.337306)
		(width 0.10795)
		(layer "F.Cu")
		(net "JTAG_RISER_TCK")
	)
	(via
		(at 359.085134 -3.337306)
		(size 0.508)
		(drill 0.254)
		(layers "F.Cu" "B.Cu")
		(net "JTAG_RISER_TCK")
	)
	(segment
		(start 359.3846 -3.636772)
		(end 359.3846 -3.9624)
		(width 0.10795)
		(layer "B.Cu")
		(net "JTAG_RISER_TCK")
	)
	(segment
		(start 359.3846 -3.9624)
		(end 359.1052 -4.2418)
		(width 0.10795)
		(layer "B.Cu")
		(net "JTAG_RISER_TCK")
	)
	(segment
		(start 359.085134 -3.337306)
		(end 359.3846 -3.636772)
		(width 0.10795)
		(layer "B.Cu")
		(net "JTAG_RISER_TCK")
	)
	(segment
		(start 405.01951 -37.77488)
		(end 405.86152 -37.77488)
		(width 0.089408)
		(layer "F.Cu")
		(net "JTAG_RISER_N")
	)
	(segment
		(start 407.512266 -37.3126)
		(end 407.890218 -36.934648)
		(width 0.089408)
		(layer "F.Cu")
		(net "JTAG_RISER_N")
	)
	(segment
		(start 405.86152 -37.77488)
		(end 406.3238 -37.3126)
		(width 0.089408)
		(layer "F.Cu")
		(net "JTAG_RISER_N")
	)
	(segment
		(start 406.3238 -37.3126)
		(end 407.512266 -37.3126)
		(width 0.089408)
		(layer "F.Cu")
		(net "JTAG_RISER_N")
	)
	(via
		(at 403.596348 -19.285204)
		(size 0.508)
		(drill 0.254)
		(layers "F.Cu" "B.Cu")
		(net "JTAG_RISER_N")
	)
	(via
		(at 402.147024 -7.4676)
		(size 0.6604)
		(drill 0.3302)
		(layers "F.Cu" "B.Cu")
		(net "JTAG_RISER_N")
	)
	(via
		(at 405.01951 -37.77488)
		(size 0.4572)
		(drill 0.2032)
		(layers "F.Cu" "B.Cu")
		(net "JTAG_RISER_N")
	)
	(segment
		(start 400.154902 -4.699)
		(end 402.147024 -6.691122)
		(width 0.10795)
		(layer "B.Cu")
		(net "JTAG_RISER_N")
	)
	(segment
		(start 387.096 -4.2418)
		(end 383.8194 -4.2418)
		(width 0.10795)
		(layer "B.Cu")
		(net "JTAG_RISER_N")
	)
	(segment
		(start 382.905 -3.0988)
		(end 383.5908 -3.0988)
		(width 0.10795)
		(layer "B.Cu")
		(net "JTAG_RISER_N")
	)
	(segment
		(start 402.147024 -8.091424)
		(end 402.5138 -8.4582)
		(width 0.10795)
		(layer "B.Cu")
		(net "JTAG_RISER_N")
	)
	(segment
		(start 400.5326 -17.959832)
		(end 400.5326 -19.7612)
		(width 0.10795)
		(layer "B.Cu")
		(net "JTAG_RISER_N")
	)
	(segment
		(start 388.9248 -3.103372)
		(end 389.536432 -3.103372)
		(width 0.10795)
		(layer "B.Cu")
		(net "JTAG_RISER_N")
	)
	(segment
		(start 402.147024 -6.691122)
		(end 402.147024 -7.4676)
		(width 0.10795)
		(layer "B.Cu")
		(net "JTAG_RISER_N")
	)
	(segment
		(start 400.389598 -16.511778)
		(end 400.389598 -17.81683)
		(width 0.10795)
		(layer "B.Cu")
		(net "JTAG_RISER_N")
	)
	(segment
		(start 389.536432 -3.103372)
		(end 391.13206 -4.699)
		(width 0.10795)
		(layer "B.Cu")
		(net "JTAG_RISER_N")
	)
	(segment
		(start 402.8948 -19.986752)
		(end 403.596348 -19.285204)
		(width 0.10795)
		(layer "B.Cu")
		(net "JTAG_RISER_N")
	)
	(segment
		(start 402.8948 -20.8788)
		(end 402.8948 -19.986752)
		(width 0.10795)
		(layer "B.Cu")
		(net "JTAG_RISER_N")
	)
	(segment
		(start 402.5138 -8.4582)
		(end 402.5138 -14.387576)
		(width 0.10795)
		(layer "B.Cu")
		(net "JTAG_RISER_N")
	)
	(segment
		(start 402.147024 -7.4676)
		(end 402.147024 -8.091424)
		(width 0.10795)
		(layer "B.Cu")
		(net "JTAG_RISER_N")
	)
	(segment
		(start 383.5908 -4.0132)
		(end 383.5908 -3.0988)
		(width 0.10795)
		(layer "B.Cu")
		(net "JTAG_RISER_N")
	)
	(segment
		(start 401.9296 -21.1582)
		(end 402.6154 -21.1582)
		(width 0.10795)
		(layer "B.Cu")
		(net "JTAG_RISER_N")
	)
	(segment
		(start 400.389598 -17.81683)
		(end 400.5326 -17.959832)
		(width 0.10795)
		(layer "B.Cu")
		(net "JTAG_RISER_N")
	)
	(segment
		(start 400.5326 -19.7612)
		(end 401.9296 -21.1582)
		(width 0.10795)
		(layer "B.Cu")
		(net "JTAG_RISER_N")
	)
	(segment
		(start 382.3716 -3.185414)
		(end 382.818386 -3.185414)
		(width 0.10795)
		(layer "B.Cu")
		(net "JTAG_RISER_N")
	)
	(segment
		(start 383.8194 -4.2418)
		(end 383.5908 -4.0132)
		(width 0.10795)
		(layer "B.Cu")
		(net "JTAG_RISER_N")
	)
	(segment
		(start 388.234428 -3.103372)
		(end 387.096 -4.2418)
		(width 0.10795)
		(layer "B.Cu")
		(net "JTAG_RISER_N")
	)
	(segment
		(start 382.818386 -3.185414)
		(end 382.905 -3.0988)
		(width 0.10795)
		(layer "B.Cu")
		(net "JTAG_RISER_N")
	)
	(segment
		(start 402.6154 -21.1582)
		(end 402.8948 -20.8788)
		(width 0.10795)
		(layer "B.Cu")
		(net "JTAG_RISER_N")
	)
	(segment
		(start 402.5138 -14.387576)
		(end 400.389598 -16.511778)
		(width 0.10795)
		(layer "B.Cu")
		(net "JTAG_RISER_N")
	)
	(segment
		(start 391.13206 -4.699)
		(end 400.154902 -4.699)
		(width 0.10795)
		(layer "B.Cu")
		(net "JTAG_RISER_N")
	)
	(segment
		(start 388.9248 -3.103372)
		(end 388.234428 -3.103372)
		(width 0.10795)
		(layer "B.Cu")
		(net "JTAG_RISER_N")
	)
	(segment
		(start 403.387052 -19.826732)
		(end 403.387052 -19.4945)
		(width 0.089408)
		(layer "In11.Cu")
		(net "JTAG_RISER_N")
	)
	(segment
		(start 405.01951 -36.600892)
		(end 405.404828 -36.215574)
		(width 0.089408)
		(layer "In11.Cu")
		(net "JTAG_RISER_N")
	)
	(segment
		(start 404.7744 -26.854912)
		(end 404.7744 -23.241)
		(width 0.089408)
		(layer "In11.Cu")
		(net "JTAG_RISER_N")
	)
	(segment
		(start 404.7744 -23.241)
		(end 404.467822 -22.934422)
		(width 0.089408)
		(layer "In11.Cu")
		(net "JTAG_RISER_N")
	)
	(segment
		(start 403.633686 -20.312126)
		(end 403.633686 -20.073366)
		(width 0.089408)
		(layer "In11.Cu")
		(net "JTAG_RISER_N")
	)
	(segment
		(start 405.01951 -37.77488)
		(end 405.01951 -36.600892)
		(width 0.089408)
		(layer "In11.Cu")
		(net "JTAG_RISER_N")
	)
	(segment
		(start 404.467822 -22.934422)
		(end 404.467822 -21.146262)
		(width 0.089408)
		(layer "In11.Cu")
		(net "JTAG_RISER_N")
	)
	(segment
		(start 405.404828 -33.04286)
		(end 405.723344 -32.724344)
		(width 0.089408)
		(layer "In11.Cu")
		(net "JTAG_RISER_N")
	)
	(segment
		(start 405.723344 -30.95625)
		(end 404.231602 -29.464508)
		(width 0.089408)
		(layer "In11.Cu")
		(net "JTAG_RISER_N")
	)
	(segment
		(start 404.231602 -27.39771)
		(end 404.7744 -26.854912)
		(width 0.089408)
		(layer "In11.Cu")
		(net "JTAG_RISER_N")
	)
	(segment
		(start 405.404828 -36.215574)
		(end 405.404828 -33.04286)
		(width 0.089408)
		(layer "In11.Cu")
		(net "JTAG_RISER_N")
	)
	(segment
		(start 403.387052 -19.4945)
		(end 403.596348 -19.285204)
		(width 0.089408)
		(layer "In11.Cu")
		(net "JTAG_RISER_N")
	)
	(segment
		(start 403.633686 -20.073366)
		(end 403.387052 -19.826732)
		(width 0.089408)
		(layer "In11.Cu")
		(net "JTAG_RISER_N")
	)
	(segment
		(start 404.231602 -29.464508)
		(end 404.231602 -27.39771)
		(width 0.089408)
		(layer "In11.Cu")
		(net "JTAG_RISER_N")
	)
	(segment
		(start 405.723344 -32.724344)
		(end 405.723344 -30.95625)
		(width 0.089408)
		(layer "In11.Cu")
		(net "JTAG_RISER_N")
	)
	(segment
		(start 404.467822 -21.146262)
		(end 403.633686 -20.312126)
		(width 0.089408)
		(layer "In11.Cu")
		(net "JTAG_RISER_N")
	)
	(segment
		(start 384.0226 -2.0066)
		(end 384.2893 -2.2733)
		(width 0.10795)
		(layer "F.Cu")
		(net "JTAG_PLD_TDO_MUX_R")
	)
	(segment
		(start 384.0226 -0.889)
		(end 384.0226 -2.0066)
		(width 0.10795)
		(layer "F.Cu")
		(net "JTAG_PLD_TDO_MUX_R")
	)
	(segment
		(start 398.157192 -2.2606)
		(end 399.419318 -0.998474)
		(width 0.10795)
		(layer "F.Cu")
		(net "JTAG_PLD_TDO_MUX_R")
	)
	(segment
		(start 384.2893 -2.2733)
		(end 384.302 -2.2606)
		(width 0.10795)
		(layer "F.Cu")
		(net "JTAG_PLD_TDO_MUX_R")
	)
	(segment
		(start 384.302 -2.2606)
		(end 398.157192 -2.2606)
		(width 0.10795)
		(layer "F.Cu")
		(net "JTAG_PLD_TDO_MUX_R")
	)
	(segment
		(start 399.419318 -0.998474)
		(end 399.770092 -0.998474)
		(width 0.10795)
		(layer "F.Cu")
		(net "JTAG_PLD_TDO_MUX_R")
	)
	(via
		(at 384.0226 -0.889)
		(size 0.508)
		(drill 0.254)
		(layers "F.Cu" "B.Cu")
		(net "JTAG_PLD_TDO_MUX_R")
	)
	(via
		(at 383.667 0.0762)
		(size 0.6604)
		(drill 0.3302)
		(layers "F.Cu" "B.Cu")
		(net "JTAG_PLD_TDO_MUX_R")
	)
	(segment
		(start 384.0226 -0.889)
		(end 384.0226 -0.2794)
		(width 0.10795)
		(layer "B.Cu")
		(net "JTAG_PLD_TDO_MUX_R")
	)
	(segment
		(start 384.0226 -0.889)
		(end 383.5908 -1.3208)
		(width 0.10795)
		(layer "B.Cu")
		(net "JTAG_PLD_TDO_MUX_R")
	)
	(segment
		(start 384.0226 -0.2794)
		(end 383.667 0.0762)
		(width 0.10795)
		(layer "B.Cu")
		(net "JTAG_PLD_TDO_MUX_R")
	)
	(segment
		(start 383.5908 -1.3208)
		(end 383.5908 -1.798828)
		(width 0.10795)
		(layer "B.Cu")
		(net "JTAG_PLD_TDO_MUX_R")
	)
	(segment
		(start 438.912 -143.383)
		(end 438.326276 -143.968724)
		(width 0.10795)
		(layer "F.Cu")
		(net "JTAG_BMC_TCK_BUF")
	)
	(segment
		(start 440.3598 -143.8148)
		(end 440.3598 -144.8816)
		(width 0.10795)
		(layer "F.Cu")
		(net "JTAG_BMC_TCK_BUF")
	)
	(segment
		(start 439.3438 -143.383)
		(end 439.928 -143.383)
		(width 0.10795)
		(layer "F.Cu")
		(net "JTAG_BMC_TCK_BUF")
	)
	(segment
		(start 439.3438 -143.383)
		(end 438.912 -143.383)
		(width 0.10795)
		(layer "F.Cu")
		(net "JTAG_BMC_TCK_BUF")
	)
	(segment
		(start 440.655456 -145.177256)
		(end 441.404756 -145.177256)
		(width 0.10795)
		(layer "F.Cu")
		(net "JTAG_BMC_TCK_BUF")
	)
	(segment
		(start 440.3598 -144.8816)
		(end 440.655456 -145.177256)
		(width 0.10795)
		(layer "F.Cu")
		(net "JTAG_BMC_TCK_BUF")
	)
	(segment
		(start 438.326276 -143.968724)
		(end 438.326276 -144.478756)
		(width 0.10795)
		(layer "F.Cu")
		(net "JTAG_BMC_TCK_BUF")
	)
	(segment
		(start 439.928 -143.383)
		(end 440.3598 -143.8148)
		(width 0.10795)
		(layer "F.Cu")
		(net "JTAG_BMC_TCK_BUF")
	)
	(via
		(at 438.326276 -144.478756)
		(size 0.508)
		(drill 0.254)
		(layers "F.Cu" "B.Cu")
		(net "JTAG_BMC_TCK_BUF")
	)
	(via
		(at 439.3438 -143.383)
		(size 0.6604)
		(drill 0.3302)
		(layers "F.Cu" "B.Cu")
		(net "JTAG_BMC_TCK_BUF")
	)
	(segment
		(start 438.326276 -143.589756)
		(end 438.326276 -144.478756)
		(width 0.10795)
		(layer "B.Cu")
		(net "JTAG_BMC_TCK_BUF")
	)
	(segment
		(start 414.8836 -93.8276)
		(end 414.45942 -93.40342)
		(width 0.10795)
		(layer "F.Cu")
		(net "IRQ_SML1_PMBUS_ALERT_R1_N")
	)
	(segment
		(start 414.45942 -93.40342)
		(end 414.0708 -93.40342)
		(width 0.10795)
		(layer "F.Cu")
		(net "IRQ_SML1_PMBUS_ALERT_R1_N")
	)
	(segment
		(start 389.22325 -96.11868)
		(end 389.71855 -95.888556)
		(width 0.10795)
		(layer "F.Cu")
		(net "IRQ_SML1_PMBUS_ALERT_R1_N")
	)
	(via
		(at 389.71855 -95.888556)
		(size 0.508)
		(drill 0.254)
		(layers "F.Cu" "B.Cu")
		(net "IRQ_SML1_PMBUS_ALERT_R1_N")
	)
	(via
		(at 414.0708 -93.40342)
		(size 0.508)
		(drill 0.254)
		(layers "F.Cu" "B.Cu")
		(net "IRQ_SML1_PMBUS_ALERT_R1_N")
	)
	(segment
		(start 397.04518 -93.5609)
		(end 396.19682 -94.40926)
		(width 0.089408)
		(layer "In4.Cu")
		(net "IRQ_SML1_PMBUS_ALERT_R1_N")
	)
	(segment
		(start 397.04518 -91.63558)
		(end 397.04518 -93.5609)
		(width 0.089408)
		(layer "In4.Cu")
		(net "IRQ_SML1_PMBUS_ALERT_R1_N")
	)
	(segment
		(start 396.19682 -94.40926)
		(end 391.197846 -94.40926)
		(width 0.089408)
		(layer "In4.Cu")
		(net "IRQ_SML1_PMBUS_ALERT_R1_N")
	)
	(segment
		(start 407.37028 -91.47302)
		(end 404.91156 -91.47302)
		(width 0.089408)
		(layer "In4.Cu")
		(net "IRQ_SML1_PMBUS_ALERT_R1_N")
	)
	(segment
		(start 391.197846 -94.40926)
		(end 389.71855 -95.888556)
		(width 0.089408)
		(layer "In4.Cu")
		(net "IRQ_SML1_PMBUS_ALERT_R1_N")
	)
	(segment
		(start 404.91156 -91.47302)
		(end 403.7965 -92.58808)
		(width 0.089408)
		(layer "In4.Cu")
		(net "IRQ_SML1_PMBUS_ALERT_R1_N")
	)
	(segment
		(start 413.55772 -93.40342)
		(end 412.5722 -92.4179)
		(width 0.089408)
		(layer "In4.Cu")
		(net "IRQ_SML1_PMBUS_ALERT_R1_N")
	)
	(segment
		(start 401.04822 -90.85834)
		(end 397.82242 -90.85834)
		(width 0.089408)
		(layer "In4.Cu")
		(net "IRQ_SML1_PMBUS_ALERT_R1_N")
	)
	(segment
		(start 412.5722 -92.4179)
		(end 408.31516 -92.4179)
		(width 0.089408)
		(layer "In4.Cu")
		(net "IRQ_SML1_PMBUS_ALERT_R1_N")
	)
	(segment
		(start 403.7965 -92.58808)
		(end 402.77796 -92.58808)
		(width 0.089408)
		(layer "In4.Cu")
		(net "IRQ_SML1_PMBUS_ALERT_R1_N")
	)
	(segment
		(start 414.0708 -93.40342)
		(end 413.55772 -93.40342)
		(width 0.089408)
		(layer "In4.Cu")
		(net "IRQ_SML1_PMBUS_ALERT_R1_N")
	)
	(segment
		(start 408.31516 -92.4179)
		(end 407.37028 -91.47302)
		(width 0.089408)
		(layer "In4.Cu")
		(net "IRQ_SML1_PMBUS_ALERT_R1_N")
	)
	(segment
		(start 397.82242 -90.85834)
		(end 397.04518 -91.63558)
		(width 0.089408)
		(layer "In4.Cu")
		(net "IRQ_SML1_PMBUS_ALERT_R1_N")
	)
	(segment
		(start 402.77796 -92.58808)
		(end 401.04822 -90.85834)
		(width 0.089408)
		(layer "In4.Cu")
		(net "IRQ_SML1_PMBUS_ALERT_R1_N")
	)
	(segment
		(start 400.971258 -101.72827)
		(end 401.14093 -101.558598)
		(width 0.0889)
		(layer "F.Cu")
		(net "IRQ_DIMM_SAVE_LVT3_R_N")
	)
	(segment
		(start 403.449028 -101.682804)
		(end 403.889464 -101.682804)
		(width 0.0889)
		(layer "F.Cu")
		(net "IRQ_DIMM_SAVE_LVT3_R_N")
	)
	(segment
		(start 407.559002 -101.964998)
		(end 409.321 -101.964998)
		(width 0.10795)
		(layer "F.Cu")
		(net "IRQ_DIMM_SAVE_LVT3_R_N")
	)
	(segment
		(start 404.87346 -102.6668)
		(end 406.8572 -102.6668)
		(width 0.10795)
		(layer "F.Cu")
		(net "IRQ_DIMM_SAVE_LVT3_R_N")
	)
	(segment
		(start 403.324822 -101.558598)
		(end 403.449028 -101.682804)
		(width 0.0889)
		(layer "F.Cu")
		(net "IRQ_DIMM_SAVE_LVT3_R_N")
	)
	(segment
		(start 406.8572 -102.6668)
		(end 407.559002 -101.964998)
		(width 0.10795)
		(layer "F.Cu")
		(net "IRQ_DIMM_SAVE_LVT3_R_N")
	)
	(segment
		(start 404.573232 -102.366572)
		(end 404.87346 -102.6668)
		(width 0.10795)
		(layer "F.Cu")
		(net "IRQ_DIMM_SAVE_LVT3_R_N")
	)
	(segment
		(start 401.14093 -101.558598)
		(end 403.324822 -101.558598)
		(width 0.0889)
		(layer "F.Cu")
		(net "IRQ_DIMM_SAVE_LVT3_R_N")
	)
	(segment
		(start 403.889464 -101.682804)
		(end 404.573232 -102.366572)
		(width 0.0889)
		(layer "F.Cu")
		(net "IRQ_DIMM_SAVE_LVT3_R_N")
	)
	(segment
		(start 400.465036 -101.855016)
		(end 400.591782 -101.72827)
		(width 0.0889)
		(layer "F.Cu")
		(net "IRQ_DIMM_SAVE_LVT3_R_N")
	)
	(segment
		(start 410.69006 -101.49332)
		(end 410.218382 -101.964998)
		(width 0.10795)
		(layer "F.Cu")
		(net "IRQ_DIMM_SAVE_LVT3_R_N")
	)
	(segment
		(start 400.591782 -101.72827)
		(end 400.971258 -101.72827)
		(width 0.0889)
		(layer "F.Cu")
		(net "IRQ_DIMM_SAVE_LVT3_R_N")
	)
	(segment
		(start 410.218382 -101.964998)
		(end 409.321 -101.964998)
		(width 0.10795)
		(layer "F.Cu")
		(net "IRQ_DIMM_SAVE_LVT3_R_N")
	)
	(via
		(at 409.321 -101.964998)
		(size 0.6604)
		(drill 0.3302)
		(layers "F.Cu" "B.Cu")
		(net "IRQ_DIMM_SAVE_LVT3_R_N")
	)
	(segment
		(start 402.495512 -111.255048)
		(end 402.021294 -111.255048)
		(width 0.0889)
		(layer "F.Cu")
		(net "FM_THROTTLE_R2_N")
	)
	(segment
		(start 401.621244 -110.854998)
		(end 401.295108 -110.854998)
		(width 0.0889)
		(layer "F.Cu")
		(net "FM_THROTTLE_R2_N")
	)
	(segment
		(start 404.409148 -111.255048)
		(end 402.495512 -111.255048)
		(width 0.10795)
		(layer "F.Cu")
		(net "FM_THROTTLE_R2_N")
	)
	(segment
		(start 402.021294 -111.255048)
		(end 401.621244 -110.854998)
		(width 0.0889)
		(layer "F.Cu")
		(net "FM_THROTTLE_R2_N")
	)
	(segment
		(start 406.002998 -112.848898)
		(end 404.409148 -111.255048)
		(width 0.10795)
		(layer "F.Cu")
		(net "FM_THROTTLE_R2_N")
	)
	(segment
		(start 407.73604 -112.32642)
		(end 406.94356 -112.32642)
		(width 0.10795)
		(layer "F.Cu")
		(net "FM_THROTTLE_R2_N")
	)
	(segment
		(start 406.421082 -112.848898)
		(end 406.002998 -112.848898)
		(width 0.10795)
		(layer "F.Cu")
		(net "FM_THROTTLE_R2_N")
	)
	(segment
		(start 406.94356 -112.32642)
		(end 406.421082 -112.848898)
		(width 0.10795)
		(layer "F.Cu")
		(net "FM_THROTTLE_R2_N")
	)
	(segment
		(start 385.572 -92.4814)
		(end 385.39166 -92.66174)
		(width 0.0889)
		(layer "F.Cu")
		(net "FM_OCP_MEZZA_PRES_R")
	)
	(segment
		(start 385.485132 -93.250004)
		(end 385.485132 -93.95968)
		(width 0.0889)
		(layer "F.Cu")
		(net "FM_OCP_MEZZA_PRES_R")
	)
	(segment
		(start 385.600194 -91.68638)
		(end 385.600194 -92.443046)
		(width 0.10795)
		(layer "F.Cu")
		(net "FM_OCP_MEZZA_PRES_R")
	)
	(segment
		(start 385.39166 -92.66174)
		(end 385.39166 -93.156532)
		(width 0.0889)
		(layer "F.Cu")
		(net "FM_OCP_MEZZA_PRES_R")
	)
	(segment
		(start 385.572 -92.47124)
		(end 385.572 -92.4814)
		(width 0.0889)
		(layer "F.Cu")
		(net "FM_OCP_MEZZA_PRES_R")
	)
	(segment
		(start 385.30784 -90.44432)
		(end 385.30784 -91.394026)
		(width 0.10795)
		(layer "F.Cu")
		(net "FM_OCP_MEZZA_PRES_R")
	)
	(segment
		(start 385.600194 -92.443046)
		(end 385.572 -92.47124)
		(width 0.10795)
		(layer "F.Cu")
		(net "FM_OCP_MEZZA_PRES_R")
	)
	(segment
		(start 385.485132 -93.95968)
		(end 385.484878 -93.959934)
		(width 0.0889)
		(layer "F.Cu")
		(net "FM_OCP_MEZZA_PRES_R")
	)
	(segment
		(start 385.39166 -93.156532)
		(end 385.485132 -93.250004)
		(width 0.0889)
		(layer "F.Cu")
		(net "FM_OCP_MEZZA_PRES_R")
	)
	(segment
		(start 385.30784 -91.394026)
		(end 385.600194 -91.68638)
		(width 0.10795)
		(layer "F.Cu")
		(net "FM_OCP_MEZZA_PRES_R")
	)
	(segment
		(start 381.985012 -92.638118)
		(end 381.985012 -93.544898)
		(width 0.10795)
		(layer "F.Cu")
		(net "FM_BMC_READY_R_N")
	)
	(via
		(at 381.985012 -92.638118)
		(size 0.508)
		(drill 0.254)
		(layers "F.Cu" "B.Cu")
		(net "FM_BMC_READY_R_N")
	)
	(segment
		(start 381.985012 -92.246958)
		(end 381.7112 -91.973146)
		(width 0.10795)
		(layer "B.Cu")
		(net "FM_BMC_READY_R_N")
	)
	(segment
		(start 381.7112 -91.973146)
		(end 381.7112 -91.41968)
		(width 0.10795)
		(layer "B.Cu")
		(net "FM_BMC_READY_R_N")
	)
	(segment
		(start 381.985012 -92.638118)
		(end 381.985012 -92.246958)
		(width 0.10795)
		(layer "B.Cu")
		(net "FM_BMC_READY_R_N")
	)
	(segment
		(start 387.24205 -98.464116)
		(end 386.74675 -98.69424)
		(width 0.10795)
		(layer "F.Cu")
		(net "FM_BMC_READY_R1_N")
	)
	(segment
		(start 385.29514 -83.16976)
		(end 385.34721 -83.22183)
		(width 0.10795)
		(layer "F.Cu")
		(net "FM_BMC_READY_R1_N")
	)
	(segment
		(start 385.34721 -83.22183)
		(end 385.34721 -83.82127)
		(width 0.10795)
		(layer "F.Cu")
		(net "FM_BMC_READY_R1_N")
	)
	(via
		(at 385.34721 -83.82127)
		(size 0.508)
		(drill 0.254)
		(layers "F.Cu" "B.Cu")
		(net "FM_BMC_READY_R1_N")
	)
	(via
		(at 387.24205 -98.464116)
		(size 0.508)
		(drill 0.254)
		(layers "F.Cu" "B.Cu")
		(net "FM_BMC_READY_R1_N")
	)
	(segment
		(start 385.210812 -83.957668)
		(end 385.34721 -83.82127)
		(width 0.089408)
		(layer "In11.Cu")
		(net "FM_BMC_READY_R1_N")
	)
	(segment
		(start 384.30962 -86.94928)
		(end 385.210812 -86.048088)
		(width 0.089408)
		(layer "In11.Cu")
		(net "FM_BMC_READY_R1_N")
	)
	(segment
		(start 385.210812 -86.048088)
		(end 385.210812 -83.957668)
		(width 0.089408)
		(layer "In11.Cu")
		(net "FM_BMC_READY_R1_N")
	)
	(segment
		(start 385.1656 -95.885)
		(end 385.1656 -95.107506)
		(width 0.089408)
		(layer "In11.Cu")
		(net "FM_BMC_READY_R1_N")
	)
	(segment
		(start 387.24205 -98.464116)
		(end 386.909818 -98.131884)
		(width 0.089408)
		(layer "In11.Cu")
		(net "FM_BMC_READY_R1_N")
	)
	(segment
		(start 385.6736 -96.774)
		(end 385.6736 -96.393)
		(width 0.089408)
		(layer "In11.Cu")
		(net "FM_BMC_READY_R1_N")
	)
	(segment
		(start 385.6736 -96.393)
		(end 385.1656 -95.885)
		(width 0.089408)
		(layer "In11.Cu")
		(net "FM_BMC_READY_R1_N")
	)
	(segment
		(start 385.1656 -95.107506)
		(end 383.3368 -93.278706)
		(width 0.089408)
		(layer "In11.Cu")
		(net "FM_BMC_READY_R1_N")
	)
	(segment
		(start 386.1816 -97.282)
		(end 385.6736 -96.774)
		(width 0.089408)
		(layer "In11.Cu")
		(net "FM_BMC_READY_R1_N")
	)
	(segment
		(start 386.650484 -98.131884)
		(end 386.1816 -97.663)
		(width 0.089408)
		(layer "In11.Cu")
		(net "FM_BMC_READY_R1_N")
	)
	(segment
		(start 383.3368 -93.278706)
		(end 383.3368 -90.30716)
		(width 0.089408)
		(layer "In11.Cu")
		(net "FM_BMC_READY_R1_N")
	)
	(segment
		(start 384.30962 -89.33434)
		(end 384.30962 -86.94928)
		(width 0.089408)
		(layer "In11.Cu")
		(net "FM_BMC_READY_R1_N")
	)
	(segment
		(start 383.3368 -90.30716)
		(end 384.30962 -89.33434)
		(width 0.089408)
		(layer "In11.Cu")
		(net "FM_BMC_READY_R1_N")
	)
	(segment
		(start 386.909818 -98.131884)
		(end 386.650484 -98.131884)
		(width 0.089408)
		(layer "In11.Cu")
		(net "FM_BMC_READY_R1_N")
	)
	(segment
		(start 386.1816 -97.663)
		(end 386.1816 -97.282)
		(width 0.089408)
		(layer "In11.Cu")
		(net "FM_BMC_READY_R1_N")
	)
	(segment
		(start 445.5922 -154.253946)
		(end 445.5922 -153.738072)
		(width 0.10795)
		(layer "F.Cu")
		(net "JTAG_BMC_BUF_TDO_R")
	)
	(segment
		(start 448.35572 -153.54046)
		(end 448.35572 -154.10942)
		(width 0.10795)
		(layer "F.Cu")
		(net "JTAG_BMC_BUF_TDO_R")
	)
	(segment
		(start 445.5922 -151.1935)
		(end 445.5922 -153.738072)
		(width 0.10795)
		(layer "F.Cu")
		(net "JTAG_BMC_BUF_TDO_R")
	)
	(segment
		(start 448.35572 -154.10942)
		(end 447.876676 -154.588464)
		(width 0.10795)
		(layer "F.Cu")
		(net "JTAG_BMC_BUF_TDO_R")
	)
	(segment
		(start 447.876676 -154.588464)
		(end 445.926718 -154.588464)
		(width 0.10795)
		(layer "F.Cu")
		(net "JTAG_BMC_BUF_TDO_R")
	)
	(segment
		(start 445.926718 -154.588464)
		(end 445.5922 -154.253946)
		(width 0.10795)
		(layer "F.Cu")
		(net "JTAG_BMC_BUF_TDO_R")
	)
	(segment
		(start 444.1952 -151.0157)
		(end 445.4144 -151.0157)
		(width 0.10795)
		(layer "F.Cu")
		(net "JTAG_BMC_BUF_TDO_R")
	)
	(segment
		(start 445.4144 -151.0157)
		(end 445.5922 -151.1935)
		(width 0.10795)
		(layer "F.Cu")
		(net "JTAG_BMC_BUF_TDO_R")
	)
	(via
		(at 445.5922 -153.738072)
		(size 0.762)
		(drill 0.381)
		(layers "F.Cu" "B.Cu")
		(net "JTAG_BMC_BUF_TDO_R")
	)
	(segment
		(start 442.569092 -59.608974)
		(end 442.569092 -59.068462)
		(width 0.10795)
		(layer "F.Cu")
		(net "EXT_MDIO_I2C_SEL")
	)
	(segment
		(start 442.149992 -58.649362)
		(end 442.149992 -57.596024)
		(width 0.10795)
		(layer "F.Cu")
		(net "EXT_MDIO_I2C_SEL")
	)
	(segment
		(start 442.569092 -59.068462)
		(end 442.149992 -58.649362)
		(width 0.10795)
		(layer "F.Cu")
		(net "EXT_MDIO_I2C_SEL")
	)
	(via
		(at 442.569092 -59.608974)
		(size 0.508)
		(drill 0.254)
		(layers "F.Cu" "B.Cu")
		(net "EXT_MDIO_I2C_SEL")
	)
	(segment
		(start 442.57468 -58.01614)
		(end 442.57468 -59.603386)
		(width 0.10795)
		(layer "B.Cu")
		(net "EXT_MDIO_I2C_SEL")
	)
	(segment
		(start 442.57468 -58.01614)
		(end 441.56884 -58.01614)
		(width 0.10795)
		(layer "B.Cu")
		(net "EXT_MDIO_I2C_SEL")
	)
	(segment
		(start 441.56884 -58.01614)
		(end 441.56122 -58.02376)
		(width 0.10795)
		(layer "B.Cu")
		(net "EXT_MDIO_I2C_SEL")
	)
	(segment
		(start 442.57468 -59.603386)
		(end 442.569092 -59.608974)
		(width 0.10795)
		(layer "B.Cu")
		(net "EXT_MDIO_I2C_SEL")
	)
	(segment
		(start 395.16685 -116.72316)
		(end 395.66215 -116.953284)
		(width 0.10795)
		(layer "F.Cu")
		(net "FM_POST_CARD_PRES_BMC_R1_N")
	)
	(via
		(at 401.41398 -117.37086)
		(size 0.508)
		(drill 0.254)
		(layers "F.Cu" "B.Cu")
		(net "FM_POST_CARD_PRES_BMC_R1_N")
	)
	(via
		(at 395.66215 -116.953284)
		(size 0.508)
		(drill 0.254)
		(layers "F.Cu" "B.Cu")
		(net "FM_POST_CARD_PRES_BMC_R1_N")
	)
	(segment
		(start 400.3294 -117.094)
		(end 400.3294 -116.398294)
		(width 0.10795)
		(layer "B.Cu")
		(net "FM_POST_CARD_PRES_BMC_R1_N")
	)
	(segment
		(start 401.41398 -116.767864)
		(end 401.41398 -117.37086)
		(width 0.10795)
		(layer "B.Cu")
		(net "FM_POST_CARD_PRES_BMC_R1_N")
	)
	(segment
		(start 400.3294 -116.398294)
		(end 400.43735 -116.290344)
		(width 0.10795)
		(layer "B.Cu")
		(net "FM_POST_CARD_PRES_BMC_R1_N")
	)
	(segment
		(start 400.756628 -116.290344)
		(end 400.93646 -116.290344)
		(width 0.10795)
		(layer "B.Cu")
		(net "FM_POST_CARD_PRES_BMC_R1_N")
	)
	(segment
		(start 400.93646 -116.290344)
		(end 401.41398 -116.767864)
		(width 0.10795)
		(layer "B.Cu")
		(net "FM_POST_CARD_PRES_BMC_R1_N")
	)
	(segment
		(start 400.43735 -116.290344)
		(end 400.756628 -116.290344)
		(width 0.10795)
		(layer "B.Cu")
		(net "FM_POST_CARD_PRES_BMC_R1_N")
	)
	(segment
		(start 399.891758 -117.206014)
		(end 400.217386 -117.206014)
		(width 0.10795)
		(layer "B.Cu")
		(net "FM_POST_CARD_PRES_BMC_R1_N")
	)
	(segment
		(start 400.217386 -117.206014)
		(end 400.3294 -117.094)
		(width 0.10795)
		(layer "B.Cu")
		(net "FM_POST_CARD_PRES_BMC_R1_N")
	)
	(segment
		(start 395.51737 -116.702078)
		(end 395.66215 -116.953284)
		(width 0.0889)
		(layer "In2.Cu")
		(net "FM_POST_CARD_PRES_BMC_R1_N")
	)
	(segment
		(start 400.9517 -115.438682)
		(end 399.622518 -114.1095)
		(width 0.089408)
		(layer "In2.Cu")
		(net "FM_POST_CARD_PRES_BMC_R1_N")
	)
	(segment
		(start 395.7574 -116.083588)
		(end 395.7574 -116.116354)
		(width 0.0889)
		(layer "In2.Cu")
		(net "FM_POST_CARD_PRES_BMC_R1_N")
	)
	(segment
		(start 396.729966 -115.155472)
		(end 396.729458 -115.15598)
		(width 0.0889)
		(layer "In2.Cu")
		(net "FM_POST_CARD_PRES_BMC_R1_N")
	)
	(segment
		(start 400.9517 -116.90858)
		(end 400.9517 -115.438682)
		(width 0.089408)
		(layer "In2.Cu")
		(net "FM_POST_CARD_PRES_BMC_R1_N")
	)
	(segment
		(start 395.51737 -116.57076)
		(end 395.51737 -116.702078)
		(width 0.0889)
		(layer "In2.Cu")
		(net "FM_POST_CARD_PRES_BMC_R1_N")
	)
	(segment
		(start 401.41398 -117.37086)
		(end 400.9517 -116.90858)
		(width 0.089408)
		(layer "In2.Cu")
		(net "FM_POST_CARD_PRES_BMC_R1_N")
	)
	(segment
		(start 396.748 -114.366548)
		(end 396.748 -114.399314)
		(width 0.0889)
		(layer "In2.Cu")
		(net "FM_POST_CARD_PRES_BMC_R1_N")
	)
	(segment
		(start 396.729966 -114.524028)
		(end 396.729966 -115.155472)
		(width 0.0889)
		(layer "In2.Cu")
		(net "FM_POST_CARD_PRES_BMC_R1_N")
	)
	(arc
		(start 397.347948 -114.031014)
		(mid 396.952701 -114.028431)
		(end 396.748 -114.366548)
		(width 0.0889)
		(layer "In2.Cu")
		(net "FM_POST_CARD_PRES_BMC_R1_N")
	)
	(arc
		(start 396.729458 -115.15598)
		(mid 396.362948 -115.477367)
		(end 395.957552 -115.748054)
		(width 0.0889)
		(layer "In2.Cu")
		(net "FM_POST_CARD_PRES_BMC_R1_N")
	)
	(arc
		(start 397.938752 -114.031014)
		(mid 397.64335 -114.110145)
		(end 397.347948 -114.031014)
		(width 0.0889)
		(layer "In2.Cu")
		(net "FM_POST_CARD_PRES_BMC_R1_N")
	)
	(arc
		(start 395.957552 -115.748054)
		(mid 395.813748 -115.889737)
		(end 395.7574 -116.083588)
		(width 0.0889)
		(layer "In2.Cu")
		(net "FM_POST_CARD_PRES_BMC_R1_N")
	)
	(arc
		(start 396.748 -114.399314)
		(mid 396.742305 -114.462151)
		(end 396.729966 -114.524028)
		(width 0.0889)
		(layer "In2.Cu")
		(net "FM_POST_CARD_PRES_BMC_R1_N")
	)
	(arc
		(start 398.929352 -114.031014)
		(mid 398.63395 -114.110145)
		(end 398.338548 -114.031014)
		(width 0.0889)
		(layer "In2.Cu")
		(net "FM_POST_CARD_PRES_BMC_R1_N")
	)
	(arc
		(start 398.338548 -114.031014)
		(mid 398.13865 -113.977515)
		(end 397.938752 -114.031014)
		(width 0.0889)
		(layer "In2.Cu")
		(net "FM_POST_CARD_PRES_BMC_R1_N")
	)
	(arc
		(start 395.7574 -116.116354)
		(mid 395.689371 -116.371019)
		(end 395.51737 -116.57076)
		(width 0.0889)
		(layer "In2.Cu")
		(net "FM_POST_CARD_PRES_BMC_R1_N")
	)
	(arc
		(start 399.622518 -114.1095)
		(mid 399.470679 -114.089531)
		(end 399.329148 -114.031014)
		(width 0.0889)
		(layer "In2.Cu")
		(net "FM_POST_CARD_PRES_BMC_R1_N")
	)
	(arc
		(start 399.329148 -114.031014)
		(mid 399.12925 -113.977515)
		(end 398.929352 -114.031014)
		(width 0.0889)
		(layer "In2.Cu")
		(net "FM_POST_CARD_PRES_BMC_R1_N")
	)
	(segment
		(start 410.6926 -103.771192)
		(end 410.524198 -103.939594)
		(width 0.10795)
		(layer "F.Cu")
		(net "FM_CPU1_RC_ERROR_R_N")
	)
	(segment
		(start 401.031456 -103.043736)
		(end 400.73326 -103.043736)
		(width 0.0889)
		(layer "F.Cu")
		(net "FM_CPU1_RC_ERROR_R_N")
	)
	(segment
		(start 404.392384 -103.589582)
		(end 404.054056 -103.589582)
		(width 0.10795)
		(layer "F.Cu")
		(net "FM_CPU1_RC_ERROR_R_N")
	)
	(segment
		(start 409.8798 -104.5972)
		(end 409.575 -104.5972)
		(width 0.10795)
		(layer "F.Cu")
		(net "FM_CPU1_RC_ERROR_R_N")
	)
	(segment
		(start 410.524198 -103.939594)
		(end 410.524198 -103.952802)
		(width 0.10795)
		(layer "F.Cu")
		(net "FM_CPU1_RC_ERROR_R_N")
	)
	(segment
		(start 405.1808 -104.377998)
		(end 404.392384 -103.589582)
		(width 0.10795)
		(layer "F.Cu")
		(net "FM_CPU1_RC_ERROR_R_N")
	)
	(segment
		(start 404.051008 -103.59263)
		(end 403.196806 -103.59263)
		(width 0.10795)
		(layer "F.Cu")
		(net "FM_CPU1_RC_ERROR_R_N")
	)
	(segment
		(start 402.861272 -103.257096)
		(end 402.32203 -103.257096)
		(width 0.10795)
		(layer "F.Cu")
		(net "FM_CPU1_RC_ERROR_R_N")
	)
	(segment
		(start 401.151344 -103.163624)
		(end 401.031456 -103.043736)
		(width 0.0889)
		(layer "F.Cu")
		(net "FM_CPU1_RC_ERROR_R_N")
	)
	(segment
		(start 405.1808 -104.8258)
		(end 405.1808 -104.377998)
		(width 0.10795)
		(layer "F.Cu")
		(net "FM_CPU1_RC_ERROR_R_N")
	)
	(segment
		(start 400.42211 -103.354886)
		(end 400.05 -103.354886)
		(width 0.0889)
		(layer "F.Cu")
		(net "FM_CPU1_RC_ERROR_R_N")
	)
	(segment
		(start 401.747228 -103.257096)
		(end 401.653756 -103.163624)
		(width 0.0889)
		(layer "F.Cu")
		(net "FM_CPU1_RC_ERROR_R_N")
	)
	(segment
		(start 400.73326 -103.043736)
		(end 400.42211 -103.354886)
		(width 0.0889)
		(layer "F.Cu")
		(net "FM_CPU1_RC_ERROR_R_N")
	)
	(segment
		(start 410.524198 -103.952802)
		(end 409.8798 -104.5972)
		(width 0.10795)
		(layer "F.Cu")
		(net "FM_CPU1_RC_ERROR_R_N")
	)
	(segment
		(start 404.054056 -103.589582)
		(end 404.051008 -103.59263)
		(width 0.10795)
		(layer "F.Cu")
		(net "FM_CPU1_RC_ERROR_R_N")
	)
	(segment
		(start 402.32203 -103.257096)
		(end 401.747228 -103.257096)
		(width 0.0889)
		(layer "F.Cu")
		(net "FM_CPU1_RC_ERROR_R_N")
	)
	(segment
		(start 401.653756 -103.163624)
		(end 401.151344 -103.163624)
		(width 0.0889)
		(layer "F.Cu")
		(net "FM_CPU1_RC_ERROR_R_N")
	)
	(segment
		(start 410.6926 -103.3526)
		(end 410.6926 -103.771192)
		(width 0.10795)
		(layer "F.Cu")
		(net "FM_CPU1_RC_ERROR_R_N")
	)
	(segment
		(start 403.196806 -103.59263)
		(end 402.861272 -103.257096)
		(width 0.10795)
		(layer "F.Cu")
		(net "FM_CPU1_RC_ERROR_R_N")
	)
	(via
		(at 409.575 -104.5972)
		(size 0.508)
		(drill 0.254)
		(layers "F.Cu" "B.Cu")
		(net "FM_CPU1_RC_ERROR_R_N")
	)
	(via
		(at 405.1808 -104.8258)
		(size 0.508)
		(drill 0.254)
		(layers "F.Cu" "B.Cu")
		(net "FM_CPU1_RC_ERROR_R_N")
	)
	(via
		(at 409.575 -105.3338)
		(size 0.6604)
		(drill 0.3302)
		(layers "F.Cu" "B.Cu")
		(net "FM_CPU1_RC_ERROR_R_N")
	)
	(segment
		(start 409.575 -104.5972)
		(end 409.575 -105.3338)
		(width 0.10795)
		(layer "B.Cu")
		(net "FM_CPU1_RC_ERROR_R_N")
	)
	(segment
		(start 409.067 -105.1052)
		(end 409.575 -104.5972)
		(width 0.089408)
		(layer "In4.Cu")
		(net "FM_CPU1_RC_ERROR_R_N")
	)
	(segment
		(start 405.4602 -105.1052)
		(end 409.067 -105.1052)
		(width 0.089408)
		(layer "In4.Cu")
		(net "FM_CPU1_RC_ERROR_R_N")
	)
	(segment
		(start 405.1808 -104.8258)
		(end 405.4602 -105.1052)
		(width 0.089408)
		(layer "In4.Cu")
		(net "FM_CPU1_RC_ERROR_R_N")
	)
	(segment
		(start 411.6578 -103.3526)
		(end 411.6578 -103.4034)
		(width 0.10795)
		(layer "F.Cu")
		(net "FM_CPU1_RC_ERROR_R1_N")
	)
	(segment
		(start 392.19505 -116.72316)
		(end 392.69035 -116.953284)
		(width 0.10795)
		(layer "F.Cu")
		(net "FM_CPU1_RC_ERROR_R1_N")
	)
	(segment
		(start 411.6578 -103.4034)
		(end 410.9466 -104.1146)
		(width 0.10795)
		(layer "F.Cu")
		(net "FM_CPU1_RC_ERROR_R1_N")
	)
	(via
		(at 410.9466 -104.1146)
		(size 0.508)
		(drill 0.254)
		(layers "F.Cu" "B.Cu")
		(net "FM_CPU1_RC_ERROR_R1_N")
	)
	(via
		(at 392.69035 -116.953284)
		(size 0.508)
		(drill 0.254)
		(layers "F.Cu" "B.Cu")
		(net "FM_CPU1_RC_ERROR_R1_N")
	)
	(segment
		(start 404.355046 -117.9957)
		(end 400.239992 -117.9957)
		(width 0.089408)
		(layer "In4.Cu")
		(net "FM_CPU1_RC_ERROR_R1_N")
	)
	(segment
		(start 392.78687 -116.856764)
		(end 392.69035 -116.953284)
		(width 0.089408)
		(layer "In4.Cu")
		(net "FM_CPU1_RC_ERROR_R1_N")
	)
	(segment
		(start 396.0114 -115.6716)
		(end 393.04468 -115.6716)
		(width 0.089408)
		(layer "In4.Cu")
		(net "FM_CPU1_RC_ERROR_R1_N")
	)
	(segment
		(start 400.239992 -117.9957)
		(end 399.39976 -117.155468)
		(width 0.089408)
		(layer "In4.Cu")
		(net "FM_CPU1_RC_ERROR_R1_N")
	)
	(segment
		(start 392.78687 -115.92941)
		(end 392.78687 -116.856764)
		(width 0.089408)
		(layer "In4.Cu")
		(net "FM_CPU1_RC_ERROR_R1_N")
	)
	(segment
		(start 397.87322 -116.531644)
		(end 397.671798 -116.330222)
		(width 0.0889)
		(layer "In4.Cu")
		(net "FM_CPU1_RC_ERROR_R1_N")
	)
	(segment
		(start 410.9466 -104.1146)
		(end 410.9466 -104.9274)
		(width 0.089408)
		(layer "In4.Cu")
		(net "FM_CPU1_RC_ERROR_R1_N")
	)
	(segment
		(start 393.04468 -115.6716)
		(end 392.78687 -115.92941)
		(width 0.089408)
		(layer "In4.Cu")
		(net "FM_CPU1_RC_ERROR_R1_N")
	)
	(segment
		(start 399.39976 -117.155468)
		(end 398.775936 -116.531644)
		(width 0.0889)
		(layer "In4.Cu")
		(net "FM_CPU1_RC_ERROR_R1_N")
	)
	(segment
		(start 407.0604 -106.2482)
		(end 406.5651 -106.7435)
		(width 0.089408)
		(layer "In4.Cu")
		(net "FM_CPU1_RC_ERROR_R1_N")
	)
	(segment
		(start 407.327608 -111.351314)
		(end 409.75788 -111.351314)
		(width 0.0889)
		(layer "In4.Cu")
		(net "FM_CPU1_RC_ERROR_R1_N")
	)
	(segment
		(start 397.671798 -115.998752)
		(end 397.344646 -115.6716)
		(width 0.0889)
		(layer "In4.Cu")
		(net "FM_CPU1_RC_ERROR_R1_N")
	)
	(segment
		(start 406.5651 -106.7435)
		(end 406.5651 -110.588806)
		(width 0.089408)
		(layer "In4.Cu")
		(net "FM_CPU1_RC_ERROR_R1_N")
	)
	(segment
		(start 410.218382 -113.40084)
		(end 408.938222 -114.681)
		(width 0.0889)
		(layer "In4.Cu")
		(net "FM_CPU1_RC_ERROR_R1_N")
	)
	(segment
		(start 406.5651 -110.588806)
		(end 407.327608 -111.351314)
		(width 0.089408)
		(layer "In4.Cu")
		(net "FM_CPU1_RC_ERROR_R1_N")
	)
	(segment
		(start 409.6258 -106.2482)
		(end 407.0604 -106.2482)
		(width 0.089408)
		(layer "In4.Cu")
		(net "FM_CPU1_RC_ERROR_R1_N")
	)
	(segment
		(start 410.218382 -111.811816)
		(end 410.218382 -113.40084)
		(width 0.0889)
		(layer "In4.Cu")
		(net "FM_CPU1_RC_ERROR_R1_N")
	)
	(segment
		(start 398.775936 -116.531644)
		(end 397.87322 -116.531644)
		(width 0.0889)
		(layer "In4.Cu")
		(net "FM_CPU1_RC_ERROR_R1_N")
	)
	(segment
		(start 408.938222 -114.681)
		(end 407.669746 -114.681)
		(width 0.0889)
		(layer "In4.Cu")
		(net "FM_CPU1_RC_ERROR_R1_N")
	)
	(segment
		(start 397.671798 -116.330222)
		(end 397.671798 -115.998752)
		(width 0.0889)
		(layer "In4.Cu")
		(net "FM_CPU1_RC_ERROR_R1_N")
	)
	(segment
		(start 409.75788 -111.351314)
		(end 410.218382 -111.811816)
		(width 0.0889)
		(layer "In4.Cu")
		(net "FM_CPU1_RC_ERROR_R1_N")
	)
	(segment
		(start 407.669746 -114.681)
		(end 404.355046 -117.9957)
		(width 0.089408)
		(layer "In4.Cu")
		(net "FM_CPU1_RC_ERROR_R1_N")
	)
	(segment
		(start 410.9466 -104.9274)
		(end 409.6258 -106.2482)
		(width 0.089408)
		(layer "In4.Cu")
		(net "FM_CPU1_RC_ERROR_R1_N")
	)
	(segment
		(start 397.344646 -115.6716)
		(end 396.0114 -115.6716)
		(width 0.0889)
		(layer "In4.Cu")
		(net "FM_CPU1_RC_ERROR_R1_N")
	)
	(segment
		(start 372.8466 -99.187)
		(end 374.015 -99.187)
		(width 0.0889)
		(layer "F.Cu")
		(net "FM_CPU0_RC_ERROR_R_N")
	)
	(segment
		(start 370.967 -98.806)
		(end 372.4656 -98.806)
		(width 0.0889)
		(layer "F.Cu")
		(net "FM_CPU0_RC_ERROR_R_N")
	)
	(segment
		(start 374.015 -99.187)
		(end 374.182894 -99.354894)
		(width 0.0889)
		(layer "F.Cu")
		(net "FM_CPU0_RC_ERROR_R_N")
	)
	(segment
		(start 372.4656 -98.806)
		(end 372.8466 -99.187)
		(width 0.0889)
		(layer "F.Cu")
		(net "FM_CPU0_RC_ERROR_R_N")
	)
	(segment
		(start 374.182894 -99.354894)
		(end 375.089928 -99.354894)
		(width 0.0889)
		(layer "F.Cu")
		(net "FM_CPU0_RC_ERROR_R_N")
	)
	(segment
		(start 412.4452 -114.2492)
		(end 412.2928 -114.2492)
		(width 0.10795)
		(layer "F.Cu")
		(net "FM_CPU0_RC_ERROR_R1_N")
	)
	(segment
		(start 412.2928 -114.2492)
		(end 411.734 -114.808)
		(width 0.10795)
		(layer "F.Cu")
		(net "FM_CPU0_RC_ERROR_R1_N")
	)
	(segment
		(start 395.66215 -115.86464)
		(end 396.15745 -116.094764)
		(width 0.10795)
		(layer "F.Cu")
		(net "FM_CPU0_RC_ERROR_R1_N")
	)
	(via
		(at 396.15745 -116.094764)
		(size 0.508)
		(drill 0.254)
		(layers "F.Cu" "B.Cu")
		(net "FM_CPU0_RC_ERROR_R1_N")
	)
	(via
		(at 411.734 -114.808)
		(size 0.508)
		(drill 0.254)
		(layers "F.Cu" "B.Cu")
		(net "FM_CPU0_RC_ERROR_R1_N")
	)
	(via
		(at 412.375858 -115.29441)
		(size 0.6604)
		(drill 0.3302)
		(layers "F.Cu" "B.Cu")
		(net "FM_CPU0_RC_ERROR_R1_N")
	)
	(segment
		(start 411.889448 -114.808)
		(end 412.375858 -115.29441)
		(width 0.10795)
		(layer "B.Cu")
		(net "FM_CPU0_RC_ERROR_R1_N")
	)
	(segment
		(start 411.734 -114.808)
		(end 411.889448 -114.808)
		(width 0.10795)
		(layer "B.Cu")
		(net "FM_CPU0_RC_ERROR_R1_N")
	)
	(segment
		(start 407.029158 -117.339872)
		(end 405.841454 -118.527576)
		(width 0.089408)
		(layer "In9.Cu")
		(net "FM_CPU0_RC_ERROR_R1_N")
	)
	(segment
		(start 411.734 -114.808)
		(end 411.734 -116.44376)
		(width 0.089408)
		(layer "In9.Cu")
		(net "FM_CPU0_RC_ERROR_R1_N")
	)
	(segment
		(start 409.554426 -117.724174)
		(end 408.40279 -117.724174)
		(width 0.089408)
		(layer "In9.Cu")
		(net "FM_CPU0_RC_ERROR_R1_N")
	)
	(segment
		(start 410.98978 -117.18798)
		(end 410.09062 -117.18798)
		(width 0.089408)
		(layer "In9.Cu")
		(net "FM_CPU0_RC_ERROR_R1_N")
	)
	(segment
		(start 405.841454 -118.527576)
		(end 401.385278 -118.527576)
		(width 0.089408)
		(layer "In9.Cu")
		(net "FM_CPU0_RC_ERROR_R1_N")
	)
	(segment
		(start 411.734 -116.44376)
		(end 410.98978 -117.18798)
		(width 0.089408)
		(layer "In9.Cu")
		(net "FM_CPU0_RC_ERROR_R1_N")
	)
	(segment
		(start 399.7706 -115.795298)
		(end 399.558256 -115.582954)
		(width 0.089408)
		(layer "In9.Cu")
		(net "FM_CPU0_RC_ERROR_R1_N")
	)
	(segment
		(start 399.558256 -115.582954)
		(end 398.833848 -115.582954)
		(width 0.089408)
		(layer "In9.Cu")
		(net "FM_CPU0_RC_ERROR_R1_N")
	)
	(segment
		(start 408.40279 -117.724174)
		(end 408.018488 -117.339872)
		(width 0.089408)
		(layer "In9.Cu")
		(net "FM_CPU0_RC_ERROR_R1_N")
	)
	(segment
		(start 399.7706 -116.912898)
		(end 399.7706 -115.795298)
		(width 0.089408)
		(layer "In9.Cu")
		(net "FM_CPU0_RC_ERROR_R1_N")
	)
	(segment
		(start 396.852648 -115.582954)
		(end 396.800578 -115.612926)
		(width 0.0889)
		(layer "In9.Cu")
		(net "FM_CPU0_RC_ERROR_R1_N")
	)
	(segment
		(start 408.018488 -117.339872)
		(end 407.029158 -117.339872)
		(width 0.089408)
		(layer "In9.Cu")
		(net "FM_CPU0_RC_ERROR_R1_N")
	)
	(segment
		(start 410.09062 -117.18798)
		(end 409.554426 -117.724174)
		(width 0.089408)
		(layer "In9.Cu")
		(net "FM_CPU0_RC_ERROR_R1_N")
	)
	(segment
		(start 396.495524 -116.094764)
		(end 396.15745 -116.094764)
		(width 0.0889)
		(layer "In9.Cu")
		(net "FM_CPU0_RC_ERROR_R1_N")
	)
	(segment
		(start 401.385278 -118.527576)
		(end 399.7706 -116.912898)
		(width 0.089408)
		(layer "In9.Cu")
		(net "FM_CPU0_RC_ERROR_R1_N")
	)
	(segment
		(start 396.567152 -115.97005)
		(end 396.495524 -116.094764)
		(width 0.0889)
		(layer "In9.Cu")
		(net "FM_CPU0_RC_ERROR_R1_N")
	)
	(arc
		(start 396.800578 -115.612926)
		(mid 396.641203 -115.763615)
		(end 396.567152 -115.97005)
		(width 0.0889)
		(layer "In9.Cu")
		(net "FM_CPU0_RC_ERROR_R1_N")
	)
	(arc
		(start 398.833848 -115.582954)
		(mid 398.63395 -115.636453)
		(end 398.434052 -115.582954)
		(width 0.0889)
		(layer "In9.Cu")
		(net "FM_CPU0_RC_ERROR_R1_N")
	)
	(arc
		(start 397.495776 -115.6081)
		(mid 397.350592 -115.550687)
		(end 397.2052 -115.4938)
		(width 0.0889)
		(layer "In9.Cu")
		(net "FM_CPU0_RC_ERROR_R1_N")
	)
	(arc
		(start 397.2052 -115.4938)
		(mid 397.022719 -115.513835)
		(end 396.852648 -115.582954)
		(width 0.0889)
		(layer "In9.Cu")
		(net "FM_CPU0_RC_ERROR_R1_N")
	)
	(arc
		(start 397.843248 -115.582954)
		(mid 397.672399 -115.635288)
		(end 397.495776 -115.6081)
		(width 0.0889)
		(layer "In9.Cu")
		(net "FM_CPU0_RC_ERROR_R1_N")
	)
	(arc
		(start 398.434052 -115.582954)
		(mid 398.13865 -115.503823)
		(end 397.843248 -115.582954)
		(width 0.0889)
		(layer "In9.Cu")
		(net "FM_CPU0_RC_ERROR_R1_N")
	)
	(segment
		(start 377.83135 -96.9772)
		(end 378.32665 -96.747076)
		(width 0.10795)
		(layer "F.Cu")
		(net "FM_BATTERY_SENSE_EN_R_N")
	)
	(via
		(at 387.284976 -33.948624)
		(size 0.508)
		(drill 0.254)
		(layers "F.Cu" "B.Cu")
		(net "FM_BATTERY_SENSE_EN_R_N")
	)
	(via
		(at 378.32665 -96.747076)
		(size 0.508)
		(drill 0.254)
		(layers "F.Cu" "B.Cu")
		(net "FM_BATTERY_SENSE_EN_R_N")
	)
	(segment
		(start 375.73077 -95.568516)
		(end 376.086116 -95.568516)
		(width 0.10795)
		(layer "B.Cu")
		(net "FM_BATTERY_SENSE_EN_R_N")
	)
	(segment
		(start 386.800598 -34.655506)
		(end 386.800598 -34.433002)
		(width 0.10795)
		(layer "B.Cu")
		(net "FM_BATTERY_SENSE_EN_R_N")
	)
	(segment
		(start 386.800598 -34.433002)
		(end 387.284976 -33.948624)
		(width 0.10795)
		(layer "B.Cu")
		(net "FM_BATTERY_SENSE_EN_R_N")
	)
	(segment
		(start 376.086116 -95.568516)
		(end 377.264676 -96.747076)
		(width 0.10795)
		(layer "B.Cu")
		(net "FM_BATTERY_SENSE_EN_R_N")
	)
	(segment
		(start 377.264676 -96.747076)
		(end 378.32665 -96.747076)
		(width 0.10795)
		(layer "B.Cu")
		(net "FM_BATTERY_SENSE_EN_R_N")
	)
	(segment
		(start 377.9266 -87.77478)
		(end 378.84354 -86.85784)
		(width 0.089408)
		(layer "In9.Cu")
		(net "FM_BATTERY_SENSE_EN_R_N")
	)
	(segment
		(start 385.953254 -45.216318)
		(end 385.953254 -35.280346)
		(width 0.089408)
		(layer "In9.Cu")
		(net "FM_BATTERY_SENSE_EN_R_N")
	)
	(segment
		(start 387.895084 -54.258972)
		(end 387.326886 -53.690774)
		(width 0.089408)
		(layer "In9.Cu")
		(net "FM_BATTERY_SENSE_EN_R_N")
	)
	(segment
		(start 386.310632 -62.51956)
		(end 386.310632 -61.279786)
		(width 0.089408)
		(layer "In9.Cu")
		(net "FM_BATTERY_SENSE_EN_R_N")
	)
	(segment
		(start 387.326886 -52.78628)
		(end 387.067044 -52.526438)
		(width 0.089408)
		(layer "In9.Cu")
		(net "FM_BATTERY_SENSE_EN_R_N")
	)
	(segment
		(start 378.60224 -90.67038)
		(end 377.9266 -89.99474)
		(width 0.089408)
		(layer "In9.Cu")
		(net "FM_BATTERY_SENSE_EN_R_N")
	)
	(segment
		(start 385.814062 -69.151246)
		(end 385.814062 -63.01613)
		(width 0.089408)
		(layer "In9.Cu")
		(net "FM_BATTERY_SENSE_EN_R_N")
	)
	(segment
		(start 378.32665 -94.464124)
		(end 378.60224 -94.188534)
		(width 0.089408)
		(layer "In9.Cu")
		(net "FM_BATTERY_SENSE_EN_R_N")
	)
	(segment
		(start 387.067044 -46.330108)
		(end 385.953254 -45.216318)
		(width 0.089408)
		(layer "In9.Cu")
		(net "FM_BATTERY_SENSE_EN_R_N")
	)
	(segment
		(start 382.40462 -81.24698)
		(end 382.40462 -80.456786)
		(width 0.089408)
		(layer "In9.Cu")
		(net "FM_BATTERY_SENSE_EN_R_N")
	)
	(segment
		(start 385.953254 -35.280346)
		(end 387.284976 -33.948624)
		(width 0.089408)
		(layer "In9.Cu")
		(net "FM_BATTERY_SENSE_EN_R_N")
	)
	(segment
		(start 386.58546 -61.004958)
		(end 386.58546 -59.489086)
		(width 0.089408)
		(layer "In9.Cu")
		(net "FM_BATTERY_SENSE_EN_R_N")
	)
	(segment
		(start 387.326886 -53.690774)
		(end 387.326886 -52.78628)
		(width 0.089408)
		(layer "In9.Cu")
		(net "FM_BATTERY_SENSE_EN_R_N")
	)
	(segment
		(start 383.723896 -70.915276)
		(end 384.161284 -70.477888)
		(width 0.089408)
		(layer "In9.Cu")
		(net "FM_BATTERY_SENSE_EN_R_N")
	)
	(segment
		(start 381.683006 -79.735172)
		(end 381.683006 -77.41158)
		(width 0.089408)
		(layer "In9.Cu")
		(net "FM_BATTERY_SENSE_EN_R_N")
	)
	(segment
		(start 383.07645 -73.990962)
		(end 383.622296 -73.445116)
		(width 0.089408)
		(layer "In9.Cu")
		(net "FM_BATTERY_SENSE_EN_R_N")
	)
	(segment
		(start 383.622296 -72.542908)
		(end 383.723896 -72.441308)
		(width 0.089408)
		(layer "In9.Cu")
		(net "FM_BATTERY_SENSE_EN_R_N")
	)
	(segment
		(start 383.723896 -72.441308)
		(end 383.723896 -70.915276)
		(width 0.089408)
		(layer "In9.Cu")
		(net "FM_BATTERY_SENSE_EN_R_N")
	)
	(segment
		(start 377.9266 -89.99474)
		(end 377.9266 -87.77478)
		(width 0.089408)
		(layer "In9.Cu")
		(net "FM_BATTERY_SENSE_EN_R_N")
	)
	(segment
		(start 378.60224 -94.188534)
		(end 378.60224 -90.67038)
		(width 0.089408)
		(layer "In9.Cu")
		(net "FM_BATTERY_SENSE_EN_R_N")
	)
	(segment
		(start 380.18212 -83.725512)
		(end 380.18212 -83.46948)
		(width 0.089408)
		(layer "In9.Cu")
		(net "FM_BATTERY_SENSE_EN_R_N")
	)
	(segment
		(start 383.07645 -76.018136)
		(end 383.07645 -73.990962)
		(width 0.089408)
		(layer "In9.Cu")
		(net "FM_BATTERY_SENSE_EN_R_N")
	)
	(segment
		(start 386.310632 -61.279786)
		(end 386.58546 -61.004958)
		(width 0.089408)
		(layer "In9.Cu")
		(net "FM_BATTERY_SENSE_EN_R_N")
	)
	(segment
		(start 387.895084 -55.922926)
		(end 387.895084 -54.258972)
		(width 0.089408)
		(layer "In9.Cu")
		(net "FM_BATTERY_SENSE_EN_R_N")
	)
	(segment
		(start 387.067044 -52.526438)
		(end 387.067044 -46.330108)
		(width 0.089408)
		(layer "In9.Cu")
		(net "FM_BATTERY_SENSE_EN_R_N")
	)
	(segment
		(start 387.344158 -56.473852)
		(end 387.895084 -55.922926)
		(width 0.089408)
		(layer "In9.Cu")
		(net "FM_BATTERY_SENSE_EN_R_N")
	)
	(segment
		(start 378.32665 -96.747076)
		(end 378.32665 -94.464124)
		(width 0.089408)
		(layer "In9.Cu")
		(net "FM_BATTERY_SENSE_EN_R_N")
	)
	(segment
		(start 383.622296 -73.445116)
		(end 383.622296 -72.542908)
		(width 0.089408)
		(layer "In9.Cu")
		(net "FM_BATTERY_SENSE_EN_R_N")
	)
	(segment
		(start 387.344158 -58.730388)
		(end 387.344158 -56.473852)
		(width 0.089408)
		(layer "In9.Cu")
		(net "FM_BATTERY_SENSE_EN_R_N")
	)
	(segment
		(start 378.84354 -86.85784)
		(end 378.84354 -85.064092)
		(width 0.089408)
		(layer "In9.Cu")
		(net "FM_BATTERY_SENSE_EN_R_N")
	)
	(segment
		(start 381.683006 -77.41158)
		(end 383.07645 -76.018136)
		(width 0.089408)
		(layer "In9.Cu")
		(net "FM_BATTERY_SENSE_EN_R_N")
	)
	(segment
		(start 380.18212 -83.46948)
		(end 382.40462 -81.24698)
		(width 0.089408)
		(layer "In9.Cu")
		(net "FM_BATTERY_SENSE_EN_R_N")
	)
	(segment
		(start 386.58546 -59.489086)
		(end 387.344158 -58.730388)
		(width 0.089408)
		(layer "In9.Cu")
		(net "FM_BATTERY_SENSE_EN_R_N")
	)
	(segment
		(start 384.161284 -70.477888)
		(end 384.48742 -70.477888)
		(width 0.089408)
		(layer "In9.Cu")
		(net "FM_BATTERY_SENSE_EN_R_N")
	)
	(segment
		(start 378.84354 -85.064092)
		(end 380.18212 -83.725512)
		(width 0.089408)
		(layer "In9.Cu")
		(net "FM_BATTERY_SENSE_EN_R_N")
	)
	(segment
		(start 382.40462 -80.456786)
		(end 381.683006 -79.735172)
		(width 0.089408)
		(layer "In9.Cu")
		(net "FM_BATTERY_SENSE_EN_R_N")
	)
	(segment
		(start 385.814062 -63.01613)
		(end 386.310632 -62.51956)
		(width 0.089408)
		(layer "In9.Cu")
		(net "FM_BATTERY_SENSE_EN_R_N")
	)
	(segment
		(start 384.48742 -70.477888)
		(end 385.814062 -69.151246)
		(width 0.089408)
		(layer "In9.Cu")
		(net "FM_BATTERY_SENSE_EN_R_N")
	)
	(segment
		(start 346.329 11.607292)
		(end 296.9768 11.607292)
		(width 0.102108)
		(layer "In11.Cu")
		(net "L12_95OHM_6INCH_DN")
	)
	(segment
		(start 293.518082 13.28039)
		(end 294.584882 12.21359)
		(width 0.102108)
		(layer "In11.Cu")
		(net "L12_95OHM_6INCH_DN")
	)
	(segment
		(start 295.853358 13.0556)
		(end 346.329 13.0556)
		(width 0.102108)
		(layer "In11.Cu")
		(net "L12_95OHM_6INCH_DN")
	)
	(segment
		(start 296.9768 10.971784)
		(end 346.738702 10.971784)
		(width 0.102108)
		(layer "In11.Cu")
		(net "L12_95OHM_6INCH_DN")
	)
	(segment
		(start 294.584882 12.21359)
		(end 295.011348 12.21359)
		(width 0.102108)
		(layer "In11.Cu")
		(net "L12_95OHM_6INCH_DN")
	)
	(segment
		(start 295.011348 12.21359)
		(end 295.853358 13.0556)
		(width 0.102108)
		(layer "In11.Cu")
		(net "L12_95OHM_6INCH_DN")
	)
	(arc
		(start 346.329 13.0556)
		(mid 347.053154 12.331446)
		(end 346.329 11.607292)
		(width 0.102108)
		(layer "In11.Cu")
		(net "L12_95OHM_6INCH_DN")
	)
	(arc
		(start 296.9768 11.607292)
		(mid 296.659046 11.289538)
		(end 296.9768 10.971784)
		(width 0.102108)
		(layer "In11.Cu")
		(net "L12_95OHM_6INCH_DN")
	)
	(segment
		(start 231.1019 12.6873)
		(end 230.221028 11.806428)
		(width 0.1143)
		(layer "In4.Cu")
		(net "L5_85OHM_6INCH_DP")
	)
	(segment
		(start 230.221028 11.806428)
		(end 214.225886 11.806428)
		(width 0.1143)
		(layer "In4.Cu")
		(net "L5_85OHM_6INCH_DP")
	)
	(segment
		(start 281.722068 10.8077)
		(end 232.283 10.8077)
		(width 0.1143)
		(layer "In4.Cu")
		(net "L5_85OHM_6INCH_DP")
	)
	(segment
		(start 232.283 12.0396)
		(end 281.696668 12.0396)
		(width 0.1143)
		(layer "In4.Cu")
		(net "L5_85OHM_6INCH_DP")
	)
	(segment
		(start 281.696668 12.6873)
		(end 231.1019 12.6873)
		(width 0.1143)
		(layer "In4.Cu")
		(net "L5_85OHM_6INCH_DP")
	)
	(segment
		(start 214.225886 11.806428)
		(end 213.101936 10.682478)
		(width 0.1143)
		(layer "In4.Cu")
		(net "L5_85OHM_6INCH_DP")
	)
	(arc
		(start 232.283 10.8077)
		(mid 231.66705 11.42365)
		(end 232.283 12.0396)
		(width 0.1143)
		(layer "In4.Cu")
		(net "L5_85OHM_6INCH_DP")
	)
	(arc
		(start 281.696668 12.0396)
		(mid 282.020518 12.36345)
		(end 281.696668 12.6873)
		(width 0.1143)
		(layer "In4.Cu")
		(net "L5_85OHM_6INCH_DP")
	)
	(segment
		(start 214.225886 12.098528)
		(end 213.101936 13.222478)
		(width 0.1143)
		(layer "In4.Cu")
		(net "L5_85OHM_6INCH_DN")
	)
	(segment
		(start 281.722068 11.0998)
		(end 232.283 11.0998)
		(width 0.1143)
		(layer "In4.Cu")
		(net "L5_85OHM_6INCH_DN")
	)
	(segment
		(start 230.09987 12.098528)
		(end 214.225886 12.098528)
		(width 0.1143)
		(layer "In4.Cu")
		(net "L5_85OHM_6INCH_DN")
	)
	(segment
		(start 230.980742 12.9794)
		(end 230.09987 12.098528)
		(width 0.1143)
		(layer "In4.Cu")
		(net "L5_85OHM_6INCH_DN")
	)
	(segment
		(start 281.696668 12.9794)
		(end 230.980742 12.9794)
		(width 0.1143)
		(layer "In4.Cu")
		(net "L5_85OHM_6INCH_DN")
	)
	(segment
		(start 232.283 11.7475)
		(end 281.696668 11.7475)
		(width 0.1143)
		(layer "In4.Cu")
		(net "L5_85OHM_6INCH_DN")
	)
	(arc
		(start 281.696668 11.7475)
		(mid 282.312618 12.36345)
		(end 281.696668 12.9794)
		(width 0.1143)
		(layer "In4.Cu")
		(net "L5_85OHM_6INCH_DN")
	)
	(arc
		(start 232.283 11.0998)
		(mid 231.95915 11.42365)
		(end 232.283 11.7475)
		(width 0.1143)
		(layer "In4.Cu")
		(net "L5_85OHM_6INCH_DN")
	)
	(via
		(at 146.543014 -165.668452)
		(size 0.5588)
		(drill 0.3048)
		(layers "F.Cu" "B.Cu")
		(net "L5_85OHM_5INCH_DP")
	)
	(via
		(at 111.424974 -165.738556)
		(size 0.5588)
		(drill 0.3048)
		(layers "F.Cu" "B.Cu")
		(net "L5_85OHM_5INCH_DP")
	)
	(segment
		(start 147.395438 -165.052502)
		(end 147.763738 -165.420802)
		(width 0.1143)
		(layer "B.Cu")
		(net "L5_85OHM_5INCH_DP")
	)
	(segment
		(start 110.551214 -165.122606)
		(end 110.809024 -165.122606)
		(width 0.1143)
		(layer "B.Cu")
		(net "L5_85OHM_5INCH_DP")
	)
	(segment
		(start 110.809024 -165.122606)
		(end 111.424974 -165.738556)
		(width 0.1143)
		(layer "B.Cu")
		(net "L5_85OHM_5INCH_DP")
	)
	(segment
		(start 110.203996 -165.469824)
		(end 110.551214 -165.122606)
		(width 0.1143)
		(layer "B.Cu")
		(net "L5_85OHM_5INCH_DP")
	)
	(segment
		(start 146.543014 -165.668452)
		(end 147.158964 -165.052502)
		(width 0.1143)
		(layer "B.Cu")
		(net "L5_85OHM_5INCH_DP")
	)
	(segment
		(start 147.158964 -165.052502)
		(end 147.395438 -165.052502)
		(width 0.1143)
		(layer "B.Cu")
		(net "L5_85OHM_5INCH_DP")
	)
	(segment
		(start 131.721098 -166.014654)
		(end 131.489704 -166.34587)
		(width 0.1143)
		(layer "In4.Cu")
		(net "L5_85OHM_5INCH_DP")
	)
	(segment
		(start 133.430518 -163.792662)
		(end 133.298184 -163.700206)
		(width 0.1143)
		(layer "In4.Cu")
		(net "L5_85OHM_5INCH_DP")
	)
	(segment
		(start 121.909078 -166.431722)
		(end 121.407682 -166.520368)
		(width 0.1143)
		(layer "In4.Cu")
		(net "L5_85OHM_5INCH_DP")
	)
	(segment
		(start 125.313694 -163.766246)
		(end 125.050804 -163.812474)
		(width 0.1143)
		(layer "In4.Cu")
		(net "L5_85OHM_5INCH_DP")
	)
	(segment
		(start 133.036056 -163.746434)
		(end 132.943346 -163.879022)
		(width 0.1143)
		(layer "In4.Cu")
		(net "L5_85OHM_5INCH_DP")
	)
	(segment
		(start 121.07672 -166.287704)
		(end 120.64746 -163.85413)
		(width 0.1143)
		(layer "In4.Cu")
		(net "L5_85OHM_5INCH_DP")
	)
	(segment
		(start 120.160288 -163.940236)
		(end 120.541288 -166.10203)
		(width 0.1143)
		(layer "In4.Cu")
		(net "L5_85OHM_5INCH_DP")
	)
	(segment
		(start 129.05867 -166.202614)
		(end 128.642618 -163.850574)
		(width 0.1143)
		(layer "In4.Cu")
		(net "L5_85OHM_5INCH_DP")
	)
	(segment
		(start 136.624314 -163.764976)
		(end 136.491472 -163.671504)
		(width 0.1143)
		(layer "In4.Cu")
		(net "L5_85OHM_5INCH_DP")
	)
	(segment
		(start 120.64746 -163.85413)
		(end 120.51538 -163.761674)
		(width 0.1143)
		(layer "In4.Cu")
		(net "L5_85OHM_5INCH_DP")
	)
	(segment
		(start 142.536672 -163.871402)
		(end 142.913608 -166.00678)
		(width 0.1143)
		(layer "In4.Cu")
		(net "L5_85OHM_5INCH_DP")
	)
	(segment
		(start 143.109696 -164.270436)
		(end 143.024352 -163.785296)
		(width 0.1143)
		(layer "In4.Cu")
		(net "L5_85OHM_5INCH_DP")
	)
	(segment
		(start 125.050804 -163.812474)
		(end 124.958094 -163.945062)
		(width 0.1143)
		(layer "In4.Cu")
		(net "L5_85OHM_5INCH_DP")
	)
	(segment
		(start 115.719098 -163.76523)
		(end 115.456462 -163.811712)
		(width 0.1143)
		(layer "In4.Cu")
		(net "L5_85OHM_5INCH_DP")
	)
	(segment
		(start 134.185406 -166.425372)
		(end 133.854444 -166.194486)
		(width 0.1143)
		(layer "In4.Cu")
		(net "L5_85OHM_5INCH_DP")
	)
	(segment
		(start 118.562374 -163.948618)
		(end 118.941088 -166.096442)
		(width 0.1143)
		(layer "In4.Cu")
		(net "L5_85OHM_5INCH_DP")
	)
	(segment
		(start 140.581126 -166.421816)
		(end 140.24991 -166.190676)
		(width 0.1143)
		(layer "In4.Cu")
		(net "L5_85OHM_5INCH_DP")
	)
	(segment
		(start 118.941088 -166.096442)
		(end 118.70944 -166.427658)
		(width 0.1143)
		(layer "In4.Cu")
		(net "L5_85OHM_5INCH_DP")
	)
	(segment
		(start 138.223498 -163.764214)
		(end 138.09091 -163.671758)
		(width 0.1143)
		(layer "In4.Cu")
		(net "L5_85OHM_5INCH_DP")
	)
	(segment
		(start 130.988308 -166.433754)
		(end 130.657346 -166.202868)
		(width 0.1143)
		(layer "In4.Cu")
		(net "L5_85OHM_5INCH_DP")
	)
	(segment
		(start 138.116564 -166.011098)
		(end 137.885424 -166.34206)
		(width 0.1143)
		(layer "In4.Cu")
		(net "L5_85OHM_5INCH_DP")
	)
	(segment
		(start 112.495076 -165.122606)
		(end 112.040924 -165.122606)
		(width 0.1143)
		(layer "In4.Cu")
		(net "L5_85OHM_5INCH_DP")
	)
	(segment
		(start 139.823444 -163.76904)
		(end 139.690856 -163.67633)
		(width 0.1143)
		(layer "In4.Cu")
		(net "L5_85OHM_5INCH_DP")
	)
	(segment
		(start 117.342158 -166.095426)
		(end 117.111272 -166.426896)
		(width 0.1143)
		(layer "In4.Cu")
		(net "L5_85OHM_5INCH_DP")
	)
	(segment
		(start 134.686548 -166.337742)
		(end 134.185406 -166.425372)
		(width 0.1143)
		(layer "In4.Cu")
		(net "L5_85OHM_5INCH_DP")
	)
	(segment
		(start 133.854444 -166.194486)
		(end 133.430518 -163.792662)
		(width 0.1143)
		(layer "In4.Cu")
		(net "L5_85OHM_5INCH_DP")
	)
	(segment
		(start 123.503182 -166.403528)
		(end 123.001786 -166.491412)
		(width 0.1143)
		(layer "In4.Cu")
		(net "L5_85OHM_5INCH_DP")
	)
	(segment
		(start 118.65483 -163.816284)
		(end 118.562374 -163.948618)
		(width 0.1143)
		(layer "In4.Cu")
		(net "L5_85OHM_5INCH_DP")
	)
	(segment
		(start 131.489704 -166.34587)
		(end 130.988308 -166.433754)
		(width 0.1143)
		(layer "In4.Cu")
		(net "L5_85OHM_5INCH_DP")
	)
	(segment
		(start 120.252744 -163.807902)
		(end 120.160288 -163.940236)
		(width 0.1143)
		(layer "In4.Cu")
		(net "L5_85OHM_5INCH_DP")
	)
	(segment
		(start 114.572288 -165.67404)
		(end 114.52733 -165.497256)
		(width 0.1143)
		(layer "In4.Cu")
		(net "L5_85OHM_5INCH_DP")
	)
	(segment
		(start 138.981942 -166.421562)
		(end 138.650726 -166.190422)
		(width 0.1143)
		(layer "In4.Cu")
		(net "L5_85OHM_5INCH_DP")
	)
	(segment
		(start 118.917466 -163.770056)
		(end 118.65483 -163.816284)
		(width 0.1143)
		(layer "In4.Cu")
		(net "L5_85OHM_5INCH_DP")
	)
	(segment
		(start 119.808752 -166.51986)
		(end 119.47779 -166.288974)
		(width 0.1143)
		(layer "In4.Cu")
		(net "L5_85OHM_5INCH_DP")
	)
	(segment
		(start 122.670824 -166.259256)
		(end 122.247152 -163.85413)
		(width 0.1143)
		(layer "In4.Cu")
		(net "L5_85OHM_5INCH_DP")
	)
	(segment
		(start 125.102112 -166.403528)
		(end 124.601478 -166.491666)
		(width 0.1143)
		(layer "In4.Cu")
		(net "L5_85OHM_5INCH_DP")
	)
	(segment
		(start 121.759726 -163.94049)
		(end 122.140726 -166.101268)
		(width 0.1143)
		(layer "In4.Cu")
		(net "L5_85OHM_5INCH_DP")
	)
	(segment
		(start 120.51538 -163.761674)
		(end 120.252744 -163.807902)
		(width 0.1143)
		(layer "In4.Cu")
		(net "L5_85OHM_5INCH_DP")
	)
	(segment
		(start 134.897368 -163.70046)
		(end 134.634986 -163.746434)
		(width 0.1143)
		(layer "In4.Cu")
		(net "L5_85OHM_5INCH_DP")
	)
	(segment
		(start 139.483338 -166.333678)
		(end 138.981942 -166.421562)
		(width 0.1143)
		(layer "In4.Cu")
		(net "L5_85OHM_5INCH_DP")
	)
	(segment
		(start 128.292098 -166.40556)
		(end 127.807466 -166.49065)
		(width 0.1143)
		(layer "In4.Cu")
		(net "L5_85OHM_5INCH_DP")
	)
	(segment
		(start 125.333506 -166.072312)
		(end 125.102112 -166.403528)
		(width 0.1143)
		(layer "In4.Cu")
		(net "L5_85OHM_5INCH_DP")
	)
	(segment
		(start 130.657346 -166.202868)
		(end 130.234182 -163.80079)
		(width 0.1143)
		(layer "In4.Cu")
		(net "L5_85OHM_5INCH_DP")
	)
	(segment
		(start 124.958094 -163.945062)
		(end 125.333506 -166.072312)
		(width 0.1143)
		(layer "In4.Cu")
		(net "L5_85OHM_5INCH_DP")
	)
	(segment
		(start 136.517126 -166.011352)
		(end 136.28624 -166.341806)
		(width 0.1143)
		(layer "In4.Cu")
		(net "L5_85OHM_5INCH_DP")
	)
	(segment
		(start 115.456462 -163.811712)
		(end 115.363244 -163.944808)
		(width 0.1143)
		(layer "In4.Cu")
		(net "L5_85OHM_5INCH_DP")
	)
	(segment
		(start 118.70944 -166.427658)
		(end 118.208552 -166.515288)
		(width 0.1143)
		(layer "In4.Cu")
		(net "L5_85OHM_5INCH_DP")
	)
	(segment
		(start 127.043942 -163.85032)
		(end 126.911354 -163.757864)
		(width 0.1143)
		(layer "In4.Cu")
		(net "L5_85OHM_5INCH_DP")
	)
	(segment
		(start 122.114564 -163.76142)
		(end 121.851928 -163.807902)
		(width 0.1143)
		(layer "In4.Cu")
		(net "L5_85OHM_5INCH_DP")
	)
	(segment
		(start 114.369342 -165.286436)
		(end 113.580926 -165.035738)
		(width 0.1143)
		(layer "In4.Cu")
		(net "L5_85OHM_5INCH_DP")
	)
	(segment
		(start 117.111272 -166.426896)
		(end 116.609876 -166.515288)
		(width 0.1143)
		(layer "In4.Cu")
		(net "L5_85OHM_5INCH_DP")
	)
	(segment
		(start 143.024352 -163.785296)
		(end 142.892018 -163.692586)
		(width 0.1143)
		(layer "In4.Cu")
		(net "L5_85OHM_5INCH_DP")
	)
	(segment
		(start 129.890774 -166.345616)
		(end 129.389632 -166.433754)
		(width 0.1143)
		(layer "In4.Cu")
		(net "L5_85OHM_5INCH_DP")
	)
	(segment
		(start 120.308878 -166.43223)
		(end 119.808752 -166.51986)
		(width 0.1143)
		(layer "In4.Cu")
		(net "L5_85OHM_5INCH_DP")
	)
	(segment
		(start 131.831588 -163.788598)
		(end 131.698492 -163.695888)
		(width 0.1143)
		(layer "In4.Cu")
		(net "L5_85OHM_5INCH_DP")
	)
	(segment
		(start 145.48485 -165.052502)
		(end 144.35328 -165.14318)
		(width 0.1143)
		(layer "In4.Cu")
		(net "L5_85OHM_5INCH_DP")
	)
	(segment
		(start 141.02715 -163.722812)
		(end 140.934694 -163.855654)
		(width 0.1143)
		(layer "In4.Cu")
		(net "L5_85OHM_5INCH_DP")
	)
	(segment
		(start 122.247152 -163.85413)
		(end 122.114564 -163.76142)
		(width 0.1143)
		(layer "In4.Cu")
		(net "L5_85OHM_5INCH_DP")
	)
	(segment
		(start 117.87759 -166.284148)
		(end 117.451378 -163.862512)
		(width 0.1143)
		(layer "In4.Cu")
		(net "L5_85OHM_5INCH_DP")
	)
	(segment
		(start 145.927064 -165.052502)
		(end 145.48485 -165.052502)
		(width 0.1143)
		(layer "In4.Cu")
		(net "L5_85OHM_5INCH_DP")
	)
	(segment
		(start 139.714478 -166.002716)
		(end 139.483338 -166.333678)
		(width 0.1143)
		(layer "In4.Cu")
		(net "L5_85OHM_5INCH_DP")
	)
	(segment
		(start 129.389632 -166.433754)
		(end 129.05867 -166.202614)
		(width 0.1143)
		(layer "In4.Cu")
		(net "L5_85OHM_5INCH_DP")
	)
	(segment
		(start 115.00739 -166.499286)
		(end 114.676682 -166.267638)
		(width 0.1143)
		(layer "In4.Cu")
		(net "L5_85OHM_5INCH_DP")
	)
	(segment
		(start 123.734322 -166.072058)
		(end 123.503182 -166.403528)
		(width 0.1143)
		(layer "In4.Cu")
		(net "L5_85OHM_5INCH_DP")
	)
	(segment
		(start 117.318536 -163.769802)
		(end 117.055646 -163.81603)
		(width 0.1143)
		(layer "In4.Cu")
		(net "L5_85OHM_5INCH_DP")
	)
	(segment
		(start 142.180564 -166.426642)
		(end 141.850364 -166.195502)
		(width 0.1143)
		(layer "In4.Cu")
		(net "L5_85OHM_5INCH_DP")
	)
	(segment
		(start 129.746756 -163.886642)
		(end 130.121914 -166.014654)
		(width 0.1143)
		(layer "In4.Cu")
		(net "L5_85OHM_5INCH_DP")
	)
	(segment
		(start 119.050308 -163.862766)
		(end 118.917466 -163.770056)
		(width 0.1143)
		(layer "In4.Cu")
		(net "L5_85OHM_5INCH_DP")
	)
	(segment
		(start 140.934694 -163.855654)
		(end 141.313662 -166.00297)
		(width 0.1143)
		(layer "In4.Cu")
		(net "L5_85OHM_5INCH_DP")
	)
	(segment
		(start 115.74018 -166.079932)
		(end 115.508786 -166.411148)
		(width 0.1143)
		(layer "In4.Cu")
		(net "L5_85OHM_5INCH_DP")
	)
	(segment
		(start 121.407682 -166.520368)
		(end 121.07672 -166.287704)
		(width 0.1143)
		(layer "In4.Cu")
		(net "L5_85OHM_5INCH_DP")
	)
	(segment
		(start 139.690856 -163.67633)
		(end 139.428474 -163.722304)
		(width 0.1143)
		(layer "In4.Cu")
		(net "L5_85OHM_5INCH_DP")
	)
	(segment
		(start 134.634986 -163.746434)
		(end 134.54253 -163.879022)
		(width 0.1143)
		(layer "In4.Cu")
		(net "L5_85OHM_5INCH_DP")
	)
	(segment
		(start 130.091942 -163.701222)
		(end 129.84607 -163.744402)
		(width 0.1143)
		(layer "In4.Cu")
		(net "L5_85OHM_5INCH_DP")
	)
	(segment
		(start 141.082522 -166.333932)
		(end 140.581126 -166.421816)
		(width 0.1143)
		(layer "In4.Cu")
		(net "L5_85OHM_5INCH_DP")
	)
	(segment
		(start 146.543014 -165.668452)
		(end 145.927064 -165.052502)
		(width 0.1143)
		(layer "In4.Cu")
		(net "L5_85OHM_5INCH_DP")
	)
	(segment
		(start 134.917688 -166.00678)
		(end 134.686548 -166.337742)
		(width 0.1143)
		(layer "In4.Cu")
		(net "L5_85OHM_5INCH_DP")
	)
	(segment
		(start 123.846844 -163.858702)
		(end 123.714256 -163.766246)
		(width 0.1143)
		(layer "In4.Cu")
		(net "L5_85OHM_5INCH_DP")
	)
	(segment
		(start 131.698492 -163.695888)
		(end 131.436364 -163.741608)
		(width 0.1143)
		(layer "In4.Cu")
		(net "L5_85OHM_5INCH_DP")
	)
	(segment
		(start 133.318758 -166.006272)
		(end 133.087364 -166.337488)
		(width 0.1143)
		(layer "In4.Cu")
		(net "L5_85OHM_5INCH_DP")
	)
	(segment
		(start 138.650726 -166.190422)
		(end 138.223498 -163.764214)
		(width 0.1143)
		(layer "In4.Cu")
		(net "L5_85OHM_5INCH_DP")
	)
	(segment
		(start 128.530096 -166.064692)
		(end 128.292098 -166.40556)
		(width 0.1143)
		(layer "In4.Cu")
		(net "L5_85OHM_5INCH_DP")
	)
	(segment
		(start 115.363244 -163.944808)
		(end 115.74018 -166.079932)
		(width 0.1143)
		(layer "In4.Cu")
		(net "L5_85OHM_5INCH_DP")
	)
	(segment
		(start 136.28624 -166.341806)
		(end 135.785098 -166.430198)
		(width 0.1143)
		(layer "In4.Cu")
		(net "L5_85OHM_5INCH_DP")
	)
	(segment
		(start 137.735564 -163.849812)
		(end 138.116564 -166.011098)
		(width 0.1143)
		(layer "In4.Cu")
		(net "L5_85OHM_5INCH_DP")
	)
	(segment
		(start 114.52733 -165.497256)
		(end 114.369342 -165.286436)
		(width 0.1143)
		(layer "In4.Cu")
		(net "L5_85OHM_5INCH_DP")
	)
	(segment
		(start 127.467106 -166.252144)
		(end 127.043942 -163.85032)
		(width 0.1143)
		(layer "In4.Cu")
		(net "L5_85OHM_5INCH_DP")
	)
	(segment
		(start 136.136126 -163.85032)
		(end 136.517126 -166.011352)
		(width 0.1143)
		(layer "In4.Cu")
		(net "L5_85OHM_5INCH_DP")
	)
	(segment
		(start 113.580926 -165.035738)
		(end 112.495076 -165.122606)
		(width 0.1143)
		(layer "In4.Cu")
		(net "L5_85OHM_5INCH_DP")
	)
	(segment
		(start 142.681706 -166.337996)
		(end 142.180564 -166.426642)
		(width 0.1143)
		(layer "In4.Cu")
		(net "L5_85OHM_5INCH_DP")
	)
	(segment
		(start 132.585968 -166.425372)
		(end 132.255006 -166.194486)
		(width 0.1143)
		(layer "In4.Cu")
		(net "L5_85OHM_5INCH_DP")
	)
	(segment
		(start 126.20117 -166.49573)
		(end 125.869446 -166.264844)
		(width 0.1143)
		(layer "In4.Cu")
		(net "L5_85OHM_5INCH_DP")
	)
	(segment
		(start 126.648464 -163.804092)
		(end 126.555754 -163.93668)
		(width 0.1143)
		(layer "In4.Cu")
		(net "L5_85OHM_5INCH_DP")
	)
	(segment
		(start 143.171672 -164.51453)
		(end 143.109696 -164.270436)
		(width 0.1143)
		(layer "In4.Cu")
		(net "L5_85OHM_5INCH_DP")
	)
	(segment
		(start 139.335764 -163.854892)
		(end 139.714478 -166.002716)
		(width 0.1143)
		(layer "In4.Cu")
		(net "L5_85OHM_5INCH_DP")
	)
	(segment
		(start 125.869446 -166.264844)
		(end 125.446282 -163.858702)
		(width 0.1143)
		(layer "In4.Cu")
		(net "L5_85OHM_5INCH_DP")
	)
	(segment
		(start 128.154938 -163.93668)
		(end 128.530096 -166.064692)
		(width 0.1143)
		(layer "In4.Cu")
		(net "L5_85OHM_5INCH_DP")
	)
	(segment
		(start 116.96319 -163.948364)
		(end 117.342158 -166.095426)
		(width 0.1143)
		(layer "In4.Cu")
		(net "L5_85OHM_5INCH_DP")
	)
	(segment
		(start 137.053828 -166.198804)
		(end 136.624314 -163.764976)
		(width 0.1143)
		(layer "In4.Cu")
		(net "L5_85OHM_5INCH_DP")
	)
	(segment
		(start 126.701804 -166.408354)
		(end 126.20117 -166.49573)
		(width 0.1143)
		(layer "In4.Cu")
		(net "L5_85OHM_5INCH_DP")
	)
	(segment
		(start 123.359164 -163.944554)
		(end 123.734322 -166.072058)
		(width 0.1143)
		(layer "In4.Cu")
		(net "L5_85OHM_5INCH_DP")
	)
	(segment
		(start 133.087364 -166.337488)
		(end 132.585968 -166.425372)
		(width 0.1143)
		(layer "In4.Cu")
		(net "L5_85OHM_5INCH_DP")
	)
	(segment
		(start 142.913608 -166.00678)
		(end 142.681706 -166.337996)
		(width 0.1143)
		(layer "In4.Cu")
		(net "L5_85OHM_5INCH_DP")
	)
	(segment
		(start 126.911354 -163.757864)
		(end 126.648464 -163.804092)
		(width 0.1143)
		(layer "In4.Cu")
		(net "L5_85OHM_5INCH_DP")
	)
	(segment
		(start 135.785098 -166.430198)
		(end 135.454136 -166.199058)
		(width 0.1143)
		(layer "In4.Cu")
		(net "L5_85OHM_5INCH_DP")
	)
	(segment
		(start 123.001786 -166.491412)
		(end 122.670824 -166.259256)
		(width 0.1143)
		(layer "In4.Cu")
		(net "L5_85OHM_5INCH_DP")
	)
	(segment
		(start 141.850364 -166.195502)
		(end 141.422374 -163.769802)
		(width 0.1143)
		(layer "In4.Cu")
		(net "L5_85OHM_5INCH_DP")
	)
	(segment
		(start 135.454136 -166.199058)
		(end 135.03021 -163.793678)
		(width 0.1143)
		(layer "In4.Cu")
		(net "L5_85OHM_5INCH_DP")
	)
	(segment
		(start 132.943346 -163.879022)
		(end 133.318758 -166.006272)
		(width 0.1143)
		(layer "In4.Cu")
		(net "L5_85OHM_5INCH_DP")
	)
	(segment
		(start 128.51003 -163.757864)
		(end 128.247394 -163.804092)
		(width 0.1143)
		(layer "In4.Cu")
		(net "L5_85OHM_5INCH_DP")
	)
	(segment
		(start 126.933198 -166.076376)
		(end 126.701804 -166.408354)
		(width 0.1143)
		(layer "In4.Cu")
		(net "L5_85OHM_5INCH_DP")
	)
	(segment
		(start 126.555754 -163.93668)
		(end 126.933198 -166.076376)
		(width 0.1143)
		(layer "In4.Cu")
		(net "L5_85OHM_5INCH_DP")
	)
	(segment
		(start 137.885424 -166.34206)
		(end 137.384028 -166.430198)
		(width 0.1143)
		(layer "In4.Cu")
		(net "L5_85OHM_5INCH_DP")
	)
	(segment
		(start 119.47779 -166.288974)
		(end 119.050308 -163.862766)
		(width 0.1143)
		(layer "In4.Cu")
		(net "L5_85OHM_5INCH_DP")
	)
	(segment
		(start 129.84607 -163.744402)
		(end 129.746756 -163.886642)
		(width 0.1143)
		(layer "In4.Cu")
		(net "L5_85OHM_5INCH_DP")
	)
	(segment
		(start 140.24991 -166.190676)
		(end 139.823444 -163.76904)
		(width 0.1143)
		(layer "In4.Cu")
		(net "L5_85OHM_5INCH_DP")
	)
	(segment
		(start 143.420846 -164.846762)
		(end 143.171672 -164.51453)
		(width 0.1143)
		(layer "In4.Cu")
		(net "L5_85OHM_5INCH_DP")
	)
	(segment
		(start 114.676682 -166.267638)
		(end 114.572288 -165.67404)
		(width 0.1143)
		(layer "In4.Cu")
		(net "L5_85OHM_5INCH_DP")
	)
	(segment
		(start 141.313662 -166.00297)
		(end 141.082522 -166.333932)
		(width 0.1143)
		(layer "In4.Cu")
		(net "L5_85OHM_5INCH_DP")
	)
	(segment
		(start 123.714256 -163.766246)
		(end 123.45162 -163.81222)
		(width 0.1143)
		(layer "In4.Cu")
		(net "L5_85OHM_5INCH_DP")
	)
	(segment
		(start 124.601478 -166.491666)
		(end 124.27077 -166.260526)
		(width 0.1143)
		(layer "In4.Cu")
		(net "L5_85OHM_5INCH_DP")
	)
	(segment
		(start 141.422374 -163.769802)
		(end 141.289532 -163.676584)
		(width 0.1143)
		(layer "In4.Cu")
		(net "L5_85OHM_5INCH_DP")
	)
	(segment
		(start 136.491472 -163.671504)
		(end 136.228836 -163.717986)
		(width 0.1143)
		(layer "In4.Cu")
		(net "L5_85OHM_5INCH_DP")
	)
	(segment
		(start 118.208552 -166.515288)
		(end 117.87759 -166.284148)
		(width 0.1143)
		(layer "In4.Cu")
		(net "L5_85OHM_5INCH_DP")
	)
	(segment
		(start 122.140726 -166.101268)
		(end 121.909078 -166.431722)
		(width 0.1143)
		(layer "In4.Cu")
		(net "L5_85OHM_5INCH_DP")
	)
	(segment
		(start 142.629382 -163.738814)
		(end 142.536672 -163.871402)
		(width 0.1143)
		(layer "In4.Cu")
		(net "L5_85OHM_5INCH_DP")
	)
	(segment
		(start 142.892018 -163.692586)
		(end 142.629382 -163.738814)
		(width 0.1143)
		(layer "In4.Cu")
		(net "L5_85OHM_5INCH_DP")
	)
	(segment
		(start 133.298184 -163.700206)
		(end 133.036056 -163.746434)
		(width 0.1143)
		(layer "In4.Cu")
		(net "L5_85OHM_5INCH_DP")
	)
	(segment
		(start 117.451378 -163.862512)
		(end 117.318536 -163.769802)
		(width 0.1143)
		(layer "In4.Cu")
		(net "L5_85OHM_5INCH_DP")
	)
	(segment
		(start 116.609876 -166.515288)
		(end 116.27866 -166.283132)
		(width 0.1143)
		(layer "In4.Cu")
		(net "L5_85OHM_5INCH_DP")
	)
	(segment
		(start 130.234182 -163.80079)
		(end 130.091942 -163.701222)
		(width 0.1143)
		(layer "In4.Cu")
		(net "L5_85OHM_5INCH_DP")
	)
	(segment
		(start 137.384028 -166.430198)
		(end 137.053828 -166.198804)
		(width 0.1143)
		(layer "In4.Cu")
		(net "L5_85OHM_5INCH_DP")
	)
	(segment
		(start 144.35328 -165.14318)
		(end 143.420846 -164.846762)
		(width 0.1143)
		(layer "In4.Cu")
		(net "L5_85OHM_5INCH_DP")
	)
	(segment
		(start 115.850924 -163.857432)
		(end 115.719098 -163.76523)
		(width 0.1143)
		(layer "In4.Cu")
		(net "L5_85OHM_5INCH_DP")
	)
	(segment
		(start 115.508786 -166.411148)
		(end 115.00739 -166.499286)
		(width 0.1143)
		(layer "In4.Cu")
		(net "L5_85OHM_5INCH_DP")
	)
	(segment
		(start 135.03021 -163.793678)
		(end 134.897368 -163.70046)
		(width 0.1143)
		(layer "In4.Cu")
		(net "L5_85OHM_5INCH_DP")
	)
	(segment
		(start 137.828528 -163.717732)
		(end 137.735564 -163.849812)
		(width 0.1143)
		(layer "In4.Cu")
		(net "L5_85OHM_5INCH_DP")
	)
	(segment
		(start 128.642618 -163.850574)
		(end 128.51003 -163.757864)
		(width 0.1143)
		(layer "In4.Cu")
		(net "L5_85OHM_5INCH_DP")
	)
	(segment
		(start 130.121914 -166.014654)
		(end 129.890774 -166.345616)
		(width 0.1143)
		(layer "In4.Cu")
		(net "L5_85OHM_5INCH_DP")
	)
	(segment
		(start 132.255006 -166.194486)
		(end 131.831588 -163.788598)
		(width 0.1143)
		(layer "In4.Cu")
		(net "L5_85OHM_5INCH_DP")
	)
	(segment
		(start 138.09091 -163.671758)
		(end 137.828528 -163.717732)
		(width 0.1143)
		(layer "In4.Cu")
		(net "L5_85OHM_5INCH_DP")
	)
	(segment
		(start 127.807466 -166.49065)
		(end 127.467106 -166.252144)
		(width 0.1143)
		(layer "In4.Cu")
		(net "L5_85OHM_5INCH_DP")
	)
	(segment
		(start 141.289532 -163.676584)
		(end 141.02715 -163.722812)
		(width 0.1143)
		(layer "In4.Cu")
		(net "L5_85OHM_5INCH_DP")
	)
	(segment
		(start 123.45162 -163.81222)
		(end 123.359164 -163.944554)
		(width 0.1143)
		(layer "In4.Cu")
		(net "L5_85OHM_5INCH_DP")
	)
	(segment
		(start 134.54253 -163.879022)
		(end 134.917688 -166.00678)
		(width 0.1143)
		(layer "In4.Cu")
		(net "L5_85OHM_5INCH_DP")
	)
	(segment
		(start 131.343654 -163.874704)
		(end 131.721098 -166.014654)
		(width 0.1143)
		(layer "In4.Cu")
		(net "L5_85OHM_5INCH_DP")
	)
	(segment
		(start 116.27866 -166.283132)
		(end 115.850924 -163.857432)
		(width 0.1143)
		(layer "In4.Cu")
		(net "L5_85OHM_5INCH_DP")
	)
	(segment
		(start 124.27077 -166.260526)
		(end 123.846844 -163.858702)
		(width 0.1143)
		(layer "In4.Cu")
		(net "L5_85OHM_5INCH_DP")
	)
	(segment
		(start 136.228836 -163.717986)
		(end 136.136126 -163.85032)
		(width 0.1143)
		(layer "In4.Cu")
		(net "L5_85OHM_5INCH_DP")
	)
	(segment
		(start 112.040924 -165.122606)
		(end 111.424974 -165.738556)
		(width 0.1143)
		(layer "In4.Cu")
		(net "L5_85OHM_5INCH_DP")
	)
	(segment
		(start 117.055646 -163.81603)
		(end 116.96319 -163.948364)
		(width 0.1143)
		(layer "In4.Cu")
		(net "L5_85OHM_5INCH_DP")
	)
	(segment
		(start 120.541288 -166.10203)
		(end 120.308878 -166.43223)
		(width 0.1143)
		(layer "In4.Cu")
		(net "L5_85OHM_5INCH_DP")
	)
	(segment
		(start 128.247394 -163.804092)
		(end 128.154938 -163.93668)
		(width 0.1143)
		(layer "In4.Cu")
		(net "L5_85OHM_5INCH_DP")
	)
	(segment
		(start 131.436364 -163.741608)
		(end 131.343654 -163.874704)
		(width 0.1143)
		(layer "In4.Cu")
		(net "L5_85OHM_5INCH_DP")
	)
	(segment
		(start 125.446282 -163.858702)
		(end 125.313694 -163.766246)
		(width 0.1143)
		(layer "In4.Cu")
		(net "L5_85OHM_5INCH_DP")
	)
	(segment
		(start 121.851928 -163.807902)
		(end 121.759726 -163.94049)
		(width 0.1143)
		(layer "In4.Cu")
		(net "L5_85OHM_5INCH_DP")
	)
	(segment
		(start 139.428474 -163.722304)
		(end 139.335764 -163.854892)
		(width 0.1143)
		(layer "In4.Cu")
		(net "L5_85OHM_5INCH_DP")
	)
	(via
		(at 146.543014 -164.144452)
		(size 0.5588)
		(drill 0.3048)
		(layers "F.Cu" "B.Cu")
		(net "L5_85OHM_5INCH_DN")
	)
	(via
		(at 111.424974 -164.214556)
		(size 0.5588)
		(drill 0.3048)
		(layers "F.Cu" "B.Cu")
		(net "L5_85OHM_5INCH_DN")
	)
	(segment
		(start 110.203996 -164.469064)
		(end 110.565438 -164.830506)
		(width 0.1143)
		(layer "B.Cu")
		(net "L5_85OHM_5INCH_DN")
	)
	(segment
		(start 110.565438 -164.830506)
		(end 110.809024 -164.830506)
		(width 0.1143)
		(layer "B.Cu")
		(net "L5_85OHM_5INCH_DN")
	)
	(segment
		(start 147.763738 -164.420042)
		(end 147.423378 -164.760402)
		(width 0.1143)
		(layer "B.Cu")
		(net "L5_85OHM_5INCH_DN")
	)
	(segment
		(start 147.423378 -164.760402)
		(end 147.158964 -164.760402)
		(width 0.1143)
		(layer "B.Cu")
		(net "L5_85OHM_5INCH_DN")
	)
	(segment
		(start 147.158964 -164.760402)
		(end 146.543014 -164.144452)
		(width 0.1143)
		(layer "B.Cu")
		(net "L5_85OHM_5INCH_DN")
	)
	(segment
		(start 110.809024 -164.830506)
		(end 111.424974 -164.214556)
		(width 0.1143)
		(layer "B.Cu")
		(net "L5_85OHM_5INCH_DN")
	)
	(segment
		(start 123.782582 -163.457636)
		(end 123.28144 -163.545266)
		(width 0.1143)
		(layer "In4.Cu")
		(net "L5_85OHM_5INCH_DN")
	)
	(segment
		(start 139.759436 -163.36772)
		(end 139.258548 -163.45535)
		(width 0.1143)
		(layer "In4.Cu")
		(net "L5_85OHM_5INCH_DN")
	)
	(segment
		(start 114.547142 -165.036246)
		(end 113.614708 -164.739828)
		(width 0.1143)
		(layer "In4.Cu")
		(net "L5_85OHM_5INCH_DN")
	)
	(segment
		(start 126.1364 -166.09441)
		(end 125.712982 -163.688522)
		(width 0.1143)
		(layer "In4.Cu")
		(net "L5_85OHM_5INCH_DN")
	)
	(segment
		(start 132.865876 -163.47948)
		(end 132.634482 -163.810696)
		(width 0.1143)
		(layer "In4.Cu")
		(net "L5_85OHM_5INCH_DN")
	)
	(segment
		(start 121.831862 -166.032688)
		(end 121.739152 -166.165022)
		(width 0.1143)
		(layer "In4.Cu")
		(net "L5_85OHM_5INCH_DN")
	)
	(segment
		(start 142.459202 -163.47186)
		(end 142.227808 -163.803076)
		(width 0.1143)
		(layer "In4.Cu")
		(net "L5_85OHM_5INCH_DN")
	)
	(segment
		(start 118.48465 -163.54933)
		(end 118.25351 -163.880292)
		(width 0.1143)
		(layer "In4.Cu")
		(net "L5_85OHM_5INCH_DN")
	)
	(segment
		(start 138.490198 -163.594034)
		(end 138.159236 -163.363148)
		(width 0.1143)
		(layer "In4.Cu")
		(net "L5_85OHM_5INCH_DN")
	)
	(segment
		(start 145.927064 -164.760402)
		(end 145.472912 -164.760402)
		(width 0.1143)
		(layer "In4.Cu")
		(net "L5_85OHM_5INCH_DN")
	)
	(segment
		(start 141.689328 -163.599876)
		(end 141.358112 -163.36772)
		(width 0.1143)
		(layer "In4.Cu")
		(net "L5_85OHM_5INCH_DN")
	)
	(segment
		(start 143.3957 -164.208968)
		(end 143.291306 -163.61537)
		(width 0.1143)
		(layer "In4.Cu")
		(net "L5_85OHM_5INCH_DN")
	)
	(segment
		(start 114.858292 -165.612572)
		(end 114.796316 -165.368478)
		(width 0.1143)
		(layer "In4.Cu")
		(net "L5_85OHM_5INCH_DN")
	)
	(segment
		(start 119.317262 -163.692586)
		(end 118.986046 -163.461446)
		(width 0.1143)
		(layer "In4.Cu")
		(net "L5_85OHM_5INCH_DN")
	)
	(segment
		(start 138.159236 -163.363148)
		(end 137.65911 -163.450778)
		(width 0.1143)
		(layer "In4.Cu")
		(net "L5_85OHM_5INCH_DN")
	)
	(segment
		(start 124.880624 -163.54552)
		(end 124.64923 -163.876736)
		(width 0.1143)
		(layer "In4.Cu")
		(net "L5_85OHM_5INCH_DN")
	)
	(segment
		(start 129.67589 -163.477448)
		(end 129.437892 -163.818316)
		(width 0.1143)
		(layer "In4.Cu")
		(net "L5_85OHM_5INCH_DN")
	)
	(segment
		(start 121.739152 -166.165022)
		(end 121.476516 -166.211504)
		(width 0.1143)
		(layer "In4.Cu")
		(net "L5_85OHM_5INCH_DN")
	)
	(segment
		(start 134.516368 -166.070788)
		(end 134.253732 -166.116762)
		(width 0.1143)
		(layer "In4.Cu")
		(net "L5_85OHM_5INCH_DN")
	)
	(segment
		(start 115.431316 -166.011606)
		(end 115.338606 -166.144194)
		(width 0.1143)
		(layer "In4.Cu")
		(net "L5_85OHM_5INCH_DN")
	)
	(segment
		(start 121.681748 -163.541202)
		(end 121.450862 -163.871656)
		(width 0.1143)
		(layer "In4.Cu")
		(net "L5_85OHM_5INCH_DN")
	)
	(segment
		(start 122.937778 -166.08933)
		(end 122.513852 -163.68395)
		(width 0.1143)
		(layer "In4.Cu")
		(net "L5_85OHM_5INCH_DN")
	)
	(segment
		(start 137.452608 -166.121334)
		(end 137.320528 -166.028878)
		(width 0.1143)
		(layer "In4.Cu")
		(net "L5_85OHM_5INCH_DN")
	)
	(segment
		(start 128.909318 -163.680394)
		(end 128.578356 -163.449254)
		(width 0.1143)
		(layer "In4.Cu")
		(net "L5_85OHM_5INCH_DN")
	)
	(segment
		(start 137.4267 -163.780978)
		(end 137.8077 -165.942772)
		(width 0.1143)
		(layer "In4.Cu")
		(net "L5_85OHM_5INCH_DN")
	)
	(segment
		(start 137.8077 -165.942772)
		(end 137.715244 -166.075106)
		(width 0.1143)
		(layer "In4.Cu")
		(net "L5_85OHM_5INCH_DN")
	)
	(segment
		(start 143.598646 -164.596572)
		(end 143.440658 -164.385752)
		(width 0.1143)
		(layer "In4.Cu")
		(net "L5_85OHM_5INCH_DN")
	)
	(segment
		(start 115.286282 -163.545012)
		(end 115.05438 -163.876228)
		(width 0.1143)
		(layer "In4.Cu")
		(net "L5_85OHM_5INCH_DN")
	)
	(segment
		(start 126.531624 -166.1414)
		(end 126.269496 -166.18712)
		(width 0.1143)
		(layer "In4.Cu")
		(net "L5_85OHM_5INCH_DN")
	)
	(segment
		(start 128.077214 -163.537392)
		(end 127.846074 -163.868354)
		(width 0.1143)
		(layer "In4.Cu")
		(net "L5_85OHM_5INCH_DN")
	)
	(segment
		(start 138.91768 -166.020242)
		(end 138.490198 -163.594034)
		(width 0.1143)
		(layer "In4.Cu")
		(net "L5_85OHM_5INCH_DN")
	)
	(segment
		(start 129.720594 -166.078916)
		(end 129.457958 -166.125144)
		(width 0.1143)
		(layer "In4.Cu")
		(net "L5_85OHM_5INCH_DN")
	)
	(segment
		(start 116.885466 -163.549076)
		(end 116.654326 -163.880038)
		(width 0.1143)
		(layer "In4.Cu")
		(net "L5_85OHM_5INCH_DN")
	)
	(segment
		(start 127.846074 -163.868354)
		(end 128.221232 -165.996366)
		(width 0.1143)
		(layer "In4.Cu")
		(net "L5_85OHM_5INCH_DN")
	)
	(segment
		(start 140.090398 -163.59886)
		(end 139.759436 -163.36772)
		(width 0.1143)
		(layer "In4.Cu")
		(net "L5_85OHM_5INCH_DN")
	)
	(segment
		(start 123.0503 -163.876228)
		(end 123.425458 -166.003986)
		(width 0.1143)
		(layer "In4.Cu")
		(net "L5_85OHM_5INCH_DN")
	)
	(segment
		(start 131.266184 -163.474654)
		(end 131.03479 -163.806632)
		(width 0.1143)
		(layer "In4.Cu")
		(net "L5_85OHM_5INCH_DN")
	)
	(segment
		(start 120.13946 -166.165276)
		(end 119.877078 -166.21125)
		(width 0.1143)
		(layer "In4.Cu")
		(net "L5_85OHM_5INCH_DN")
	)
	(segment
		(start 118.277132 -166.206678)
		(end 118.144544 -166.113968)
		(width 0.1143)
		(layer "In4.Cu")
		(net "L5_85OHM_5INCH_DN")
	)
	(segment
		(start 126.478284 -163.537138)
		(end 126.24689 -163.868354)
		(width 0.1143)
		(layer "In4.Cu")
		(net "L5_85OHM_5INCH_DN")
	)
	(segment
		(start 127.733806 -166.082218)
		(end 127.310642 -163.68014)
		(width 0.1143)
		(layer "In4.Cu")
		(net "L5_85OHM_5INCH_DN")
	)
	(segment
		(start 124.53747 -166.090346)
		(end 124.113544 -163.688522)
		(width 0.1143)
		(layer "In4.Cu")
		(net "L5_85OHM_5INCH_DN")
	)
	(segment
		(start 131.056634 -166.125144)
		(end 130.924046 -166.032688)
		(width 0.1143)
		(layer "In4.Cu")
		(net "L5_85OHM_5INCH_DN")
	)
	(segment
		(start 116.678456 -166.206424)
		(end 116.545614 -166.113206)
		(width 0.1143)
		(layer "In4.Cu")
		(net "L5_85OHM_5INCH_DN")
	)
	(segment
		(start 143.440658 -164.385752)
		(end 143.3957 -164.208968)
		(width 0.1143)
		(layer "In4.Cu")
		(net "L5_85OHM_5INCH_DN")
	)
	(segment
		(start 117.033294 -166.027354)
		(end 116.940838 -166.160196)
		(width 0.1143)
		(layer "In4.Cu")
		(net "L5_85OHM_5INCH_DN")
	)
	(segment
		(start 135.297164 -163.623752)
		(end 134.966202 -163.391596)
		(width 0.1143)
		(layer "In4.Cu")
		(net "L5_85OHM_5INCH_DN")
	)
	(segment
		(start 119.851424 -163.87191)
		(end 120.232424 -166.033196)
		(width 0.1143)
		(layer "In4.Cu")
		(net "L5_85OHM_5INCH_DN")
	)
	(segment
		(start 121.450862 -163.871656)
		(end 121.831862 -166.032688)
		(width 0.1143)
		(layer "In4.Cu")
		(net "L5_85OHM_5INCH_DN")
	)
	(segment
		(start 144.387062 -164.84727)
		(end 143.598646 -164.596572)
		(width 0.1143)
		(layer "In4.Cu")
		(net "L5_85OHM_5INCH_DN")
	)
	(segment
		(start 131.412234 -165.946328)
		(end 131.319524 -166.078916)
		(width 0.1143)
		(layer "In4.Cu")
		(net "L5_85OHM_5INCH_DN")
	)
	(segment
		(start 134.464806 -163.47948)
		(end 134.233666 -163.81095)
		(width 0.1143)
		(layer "In4.Cu")
		(net "L5_85OHM_5INCH_DN")
	)
	(segment
		(start 142.511526 -166.071296)
		(end 142.24889 -166.117778)
		(width 0.1143)
		(layer "In4.Cu")
		(net "L5_85OHM_5INCH_DN")
	)
	(segment
		(start 146.543014 -164.144452)
		(end 145.927064 -164.760402)
		(width 0.1143)
		(layer "In4.Cu")
		(net "L5_85OHM_5INCH_DN")
	)
	(segment
		(start 136.891268 -163.595304)
		(end 136.560306 -163.36264)
		(width 0.1143)
		(layer "In4.Cu")
		(net "L5_85OHM_5INCH_DN")
	)
	(segment
		(start 123.425458 -166.003986)
		(end 123.333002 -166.136574)
		(width 0.1143)
		(layer "In4.Cu")
		(net "L5_85OHM_5INCH_DN")
	)
	(segment
		(start 140.912342 -166.066978)
		(end 140.649452 -166.113206)
		(width 0.1143)
		(layer "In4.Cu")
		(net "L5_85OHM_5INCH_DN")
	)
	(segment
		(start 135.827262 -163.78174)
		(end 136.208262 -165.942518)
		(width 0.1143)
		(layer "In4.Cu")
		(net "L5_85OHM_5INCH_DN")
	)
	(segment
		(start 129.32537 -166.032434)
		(end 128.909318 -163.680394)
		(width 0.1143)
		(layer "In4.Cu")
		(net "L5_85OHM_5INCH_DN")
	)
	(segment
		(start 120.082564 -163.540948)
		(end 119.851424 -163.87191)
		(width 0.1143)
		(layer "In4.Cu")
		(net "L5_85OHM_5INCH_DN")
	)
	(segment
		(start 140.62583 -163.787582)
		(end 141.004798 -165.934644)
		(width 0.1143)
		(layer "In4.Cu")
		(net "L5_85OHM_5INCH_DN")
	)
	(segment
		(start 136.11606 -166.075106)
		(end 135.853424 -166.121588)
		(width 0.1143)
		(layer "In4.Cu")
		(net "L5_85OHM_5INCH_DN")
	)
	(segment
		(start 120.91416 -163.684204)
		(end 120.58396 -163.45281)
		(width 0.1143)
		(layer "In4.Cu")
		(net "L5_85OHM_5INCH_DN")
	)
	(segment
		(start 145.472912 -164.760402)
		(end 144.387062 -164.84727)
		(width 0.1143)
		(layer "In4.Cu")
		(net "L5_85OHM_5INCH_DN")
	)
	(segment
		(start 139.0269 -163.786566)
		(end 139.405614 -165.93439)
		(width 0.1143)
		(layer "In4.Cu")
		(net "L5_85OHM_5INCH_DN")
	)
	(segment
		(start 124.931932 -166.136574)
		(end 124.669804 -166.182802)
		(width 0.1143)
		(layer "In4.Cu")
		(net "L5_85OHM_5INCH_DN")
	)
	(segment
		(start 118.986046 -163.461446)
		(end 118.48465 -163.54933)
		(width 0.1143)
		(layer "In4.Cu")
		(net "L5_85OHM_5INCH_DN")
	)
	(segment
		(start 120.232424 -166.033196)
		(end 120.13946 -166.165276)
		(width 0.1143)
		(layer "In4.Cu")
		(net "L5_85OHM_5INCH_DN")
	)
	(segment
		(start 120.58396 -163.45281)
		(end 120.082564 -163.540948)
		(width 0.1143)
		(layer "In4.Cu")
		(net "L5_85OHM_5INCH_DN")
	)
	(segment
		(start 133.36651 -163.391342)
		(end 132.865876 -163.47948)
		(width 0.1143)
		(layer "In4.Cu")
		(net "L5_85OHM_5INCH_DN")
	)
	(segment
		(start 141.358112 -163.36772)
		(end 140.856716 -163.456112)
		(width 0.1143)
		(layer "In4.Cu")
		(net "L5_85OHM_5INCH_DN")
	)
	(segment
		(start 134.608824 -165.938454)
		(end 134.516368 -166.070788)
		(width 0.1143)
		(layer "In4.Cu")
		(net "L5_85OHM_5INCH_DN")
	)
	(segment
		(start 128.121918 -166.138606)
		(end 127.876046 -166.181786)
		(width 0.1143)
		(layer "In4.Cu")
		(net "L5_85OHM_5INCH_DN")
	)
	(segment
		(start 115.338606 -166.144194)
		(end 115.07597 -166.190422)
		(width 0.1143)
		(layer "In4.Cu")
		(net "L5_85OHM_5INCH_DN")
	)
	(segment
		(start 116.654326 -163.880038)
		(end 117.033294 -166.027354)
		(width 0.1143)
		(layer "In4.Cu")
		(net "L5_85OHM_5INCH_DN")
	)
	(segment
		(start 139.050522 -166.112952)
		(end 138.91768 -166.020242)
		(width 0.1143)
		(layer "In4.Cu")
		(net "L5_85OHM_5INCH_DN")
	)
	(segment
		(start 140.856716 -163.456112)
		(end 140.62583 -163.787582)
		(width 0.1143)
		(layer "In4.Cu")
		(net "L5_85OHM_5INCH_DN")
	)
	(segment
		(start 128.578356 -163.449254)
		(end 128.077214 -163.537392)
		(width 0.1143)
		(layer "In4.Cu")
		(net "L5_85OHM_5INCH_DN")
	)
	(segment
		(start 137.320528 -166.028878)
		(end 136.891268 -163.595304)
		(width 0.1143)
		(layer "In4.Cu")
		(net "L5_85OHM_5INCH_DN")
	)
	(segment
		(start 136.05891 -163.451286)
		(end 135.827262 -163.78174)
		(width 0.1143)
		(layer "In4.Cu")
		(net "L5_85OHM_5INCH_DN")
	)
	(segment
		(start 139.405614 -165.93439)
		(end 139.313158 -166.066724)
		(width 0.1143)
		(layer "In4.Cu")
		(net "L5_85OHM_5INCH_DN")
	)
	(segment
		(start 124.113544 -163.688522)
		(end 123.782582 -163.457636)
		(width 0.1143)
		(layer "In4.Cu")
		(net "L5_85OHM_5INCH_DN")
	)
	(segment
		(start 139.258548 -163.45535)
		(end 139.0269 -163.786566)
		(width 0.1143)
		(layer "In4.Cu")
		(net "L5_85OHM_5INCH_DN")
	)
	(segment
		(start 121.476516 -166.211504)
		(end 121.343674 -166.118032)
		(width 0.1143)
		(layer "In4.Cu")
		(net "L5_85OHM_5INCH_DN")
	)
	(segment
		(start 125.024642 -166.003986)
		(end 124.931932 -166.136574)
		(width 0.1143)
		(layer "In4.Cu")
		(net "L5_85OHM_5INCH_DN")
	)
	(segment
		(start 118.25351 -163.880292)
		(end 118.632224 -166.028116)
		(width 0.1143)
		(layer "In4.Cu")
		(net "L5_85OHM_5INCH_DN")
	)
	(segment
		(start 126.24689 -163.868354)
		(end 126.624334 -166.008304)
		(width 0.1143)
		(layer "In4.Cu")
		(net "L5_85OHM_5INCH_DN")
	)
	(segment
		(start 134.253732 -166.116762)
		(end 134.121144 -166.024306)
		(width 0.1143)
		(layer "In4.Cu")
		(net "L5_85OHM_5INCH_DN")
	)
	(segment
		(start 123.07062 -166.182548)
		(end 122.937778 -166.08933)
		(width 0.1143)
		(layer "In4.Cu")
		(net "L5_85OHM_5INCH_DN")
	)
	(segment
		(start 124.669804 -166.182802)
		(end 124.53747 -166.090346)
		(width 0.1143)
		(layer "In4.Cu")
		(net "L5_85OHM_5INCH_DN")
	)
	(segment
		(start 132.521706 -166.024306)
		(end 132.098542 -163.618164)
		(width 0.1143)
		(layer "In4.Cu")
		(net "L5_85OHM_5INCH_DN")
	)
	(segment
		(start 126.624334 -166.008304)
		(end 126.531624 -166.1414)
		(width 0.1143)
		(layer "In4.Cu")
		(net "L5_85OHM_5INCH_DN")
	)
	(segment
		(start 134.121144 -166.024306)
		(end 133.697218 -163.622482)
		(width 0.1143)
		(layer "In4.Cu")
		(net "L5_85OHM_5INCH_DN")
	)
	(segment
		(start 113.614708 -164.739828)
		(end 112.483138 -164.830506)
		(width 0.1143)
		(layer "In4.Cu")
		(net "L5_85OHM_5INCH_DN")
	)
	(segment
		(start 117.386862 -163.461192)
		(end 116.885466 -163.549076)
		(width 0.1143)
		(layer "In4.Cu")
		(net "L5_85OHM_5INCH_DN")
	)
	(segment
		(start 118.632224 -166.028116)
		(end 118.539514 -166.160704)
		(width 0.1143)
		(layer "In4.Cu")
		(net "L5_85OHM_5INCH_DN")
	)
	(segment
		(start 123.28144 -163.545266)
		(end 123.0503 -163.876228)
		(width 0.1143)
		(layer "In4.Cu")
		(net "L5_85OHM_5INCH_DN")
	)
	(segment
		(start 126.97968 -163.449254)
		(end 126.478284 -163.537138)
		(width 0.1143)
		(layer "In4.Cu")
		(net "L5_85OHM_5INCH_DN")
	)
	(segment
		(start 127.876046 -166.181786)
		(end 127.733806 -166.082218)
		(width 0.1143)
		(layer "In4.Cu")
		(net "L5_85OHM_5INCH_DN")
	)
	(segment
		(start 125.38202 -163.457636)
		(end 124.880624 -163.54552)
		(width 0.1143)
		(layer "In4.Cu")
		(net "L5_85OHM_5INCH_DN")
	)
	(segment
		(start 135.853424 -166.121588)
		(end 135.720836 -166.028878)
		(width 0.1143)
		(layer "In4.Cu")
		(net "L5_85OHM_5INCH_DN")
	)
	(segment
		(start 139.313158 -166.066724)
		(end 139.050522 -166.112952)
		(width 0.1143)
		(layer "In4.Cu")
		(net "L5_85OHM_5INCH_DN")
	)
	(segment
		(start 116.117624 -163.687506)
		(end 115.787424 -163.456366)
		(width 0.1143)
		(layer "In4.Cu")
		(net "L5_85OHM_5INCH_DN")
	)
	(segment
		(start 130.160522 -163.392358)
		(end 129.67589 -163.477448)
		(width 0.1143)
		(layer "In4.Cu")
		(net "L5_85OHM_5INCH_DN")
	)
	(segment
		(start 119.877078 -166.21125)
		(end 119.74449 -166.118794)
		(width 0.1143)
		(layer "In4.Cu")
		(net "L5_85OHM_5INCH_DN")
	)
	(segment
		(start 140.649452 -166.113206)
		(end 140.51661 -166.020496)
		(width 0.1143)
		(layer "In4.Cu")
		(net "L5_85OHM_5INCH_DN")
	)
	(segment
		(start 112.483138 -164.830506)
		(end 112.040924 -164.830506)
		(width 0.1143)
		(layer "In4.Cu")
		(net "L5_85OHM_5INCH_DN")
	)
	(segment
		(start 134.966202 -163.391596)
		(end 134.464806 -163.47948)
		(width 0.1143)
		(layer "In4.Cu")
		(net "L5_85OHM_5INCH_DN")
	)
	(segment
		(start 123.333002 -166.136574)
		(end 123.07062 -166.182548)
		(width 0.1143)
		(layer "In4.Cu")
		(net "L5_85OHM_5INCH_DN")
	)
	(segment
		(start 128.221232 -165.996366)
		(end 128.121918 -166.138606)
		(width 0.1143)
		(layer "In4.Cu")
		(net "L5_85OHM_5INCH_DN")
	)
	(segment
		(start 140.51661 -166.020496)
		(end 140.090398 -163.59886)
		(width 0.1143)
		(layer "In4.Cu")
		(net "L5_85OHM_5INCH_DN")
	)
	(segment
		(start 122.18289 -163.45281)
		(end 121.681748 -163.541202)
		(width 0.1143)
		(layer "In4.Cu")
		(net "L5_85OHM_5INCH_DN")
	)
	(segment
		(start 142.604744 -165.9382)
		(end 142.511526 -166.071296)
		(width 0.1143)
		(layer "In4.Cu")
		(net "L5_85OHM_5INCH_DN")
	)
	(segment
		(start 143.291306 -163.61537)
		(end 142.960598 -163.383722)
		(width 0.1143)
		(layer "In4.Cu")
		(net "L5_85OHM_5INCH_DN")
	)
	(segment
		(start 142.960598 -163.383722)
		(end 142.459202 -163.47186)
		(width 0.1143)
		(layer "In4.Cu")
		(net "L5_85OHM_5INCH_DN")
	)
	(segment
		(start 112.040924 -164.830506)
		(end 111.424974 -164.214556)
		(width 0.1143)
		(layer "In4.Cu")
		(net "L5_85OHM_5INCH_DN")
	)
	(segment
		(start 142.117064 -166.025576)
		(end 141.689328 -163.599876)
		(width 0.1143)
		(layer "In4.Cu")
		(net "L5_85OHM_5INCH_DN")
	)
	(segment
		(start 126.269496 -166.18712)
		(end 126.1364 -166.09441)
		(width 0.1143)
		(layer "In4.Cu")
		(net "L5_85OHM_5INCH_DN")
	)
	(segment
		(start 133.009894 -165.937946)
		(end 132.917184 -166.070534)
		(width 0.1143)
		(layer "In4.Cu")
		(net "L5_85OHM_5INCH_DN")
	)
	(segment
		(start 131.766818 -163.387278)
		(end 131.266184 -163.474654)
		(width 0.1143)
		(layer "In4.Cu")
		(net "L5_85OHM_5INCH_DN")
	)
	(segment
		(start 115.07597 -166.190422)
		(end 114.943636 -166.097712)
		(width 0.1143)
		(layer "In4.Cu")
		(net "L5_85OHM_5INCH_DN")
	)
	(segment
		(start 137.715244 -166.075106)
		(end 137.452608 -166.121334)
		(width 0.1143)
		(layer "In4.Cu")
		(net "L5_85OHM_5INCH_DN")
	)
	(segment
		(start 116.940838 -166.160196)
		(end 116.678456 -166.206424)
		(width 0.1143)
		(layer "In4.Cu")
		(net "L5_85OHM_5INCH_DN")
	)
	(segment
		(start 132.917184 -166.070534)
		(end 132.654294 -166.116762)
		(width 0.1143)
		(layer "In4.Cu")
		(net "L5_85OHM_5INCH_DN")
	)
	(segment
		(start 125.712982 -163.688522)
		(end 125.38202 -163.457636)
		(width 0.1143)
		(layer "In4.Cu")
		(net "L5_85OHM_5INCH_DN")
	)
	(segment
		(start 116.545614 -166.113206)
		(end 116.117624 -163.687506)
		(width 0.1143)
		(layer "In4.Cu")
		(net "L5_85OHM_5INCH_DN")
	)
	(segment
		(start 142.24889 -166.117778)
		(end 142.117064 -166.025576)
		(width 0.1143)
		(layer "In4.Cu")
		(net "L5_85OHM_5INCH_DN")
	)
	(segment
		(start 134.233666 -163.81095)
		(end 134.608824 -165.938454)
		(width 0.1143)
		(layer "In4.Cu")
		(net "L5_85OHM_5INCH_DN")
	)
	(segment
		(start 142.227808 -163.803076)
		(end 142.604744 -165.9382)
		(width 0.1143)
		(layer "In4.Cu")
		(net "L5_85OHM_5INCH_DN")
	)
	(segment
		(start 124.64923 -163.876736)
		(end 125.024642 -166.003986)
		(width 0.1143)
		(layer "In4.Cu")
		(net "L5_85OHM_5INCH_DN")
	)
	(segment
		(start 114.796316 -165.368478)
		(end 114.547142 -165.036246)
		(width 0.1143)
		(layer "In4.Cu")
		(net "L5_85OHM_5INCH_DN")
	)
	(segment
		(start 133.697218 -163.622482)
		(end 133.36651 -163.391342)
		(width 0.1143)
		(layer "In4.Cu")
		(net "L5_85OHM_5INCH_DN")
	)
	(segment
		(start 122.513852 -163.68395)
		(end 122.18289 -163.45281)
		(width 0.1143)
		(layer "In4.Cu")
		(net "L5_85OHM_5INCH_DN")
	)
	(segment
		(start 119.74449 -166.118794)
		(end 119.317262 -163.692586)
		(width 0.1143)
		(layer "In4.Cu")
		(net "L5_85OHM_5INCH_DN")
	)
	(segment
		(start 141.004798 -165.934644)
		(end 140.912342 -166.066978)
		(width 0.1143)
		(layer "In4.Cu")
		(net "L5_85OHM_5INCH_DN")
	)
	(segment
		(start 129.81305 -165.946328)
		(end 129.720594 -166.078916)
		(width 0.1143)
		(layer "In4.Cu")
		(net "L5_85OHM_5INCH_DN")
	)
	(segment
		(start 115.05438 -163.876228)
		(end 115.431316 -166.011606)
		(width 0.1143)
		(layer "In4.Cu")
		(net "L5_85OHM_5INCH_DN")
	)
	(segment
		(start 132.654294 -166.116762)
		(end 132.521706 -166.024306)
		(width 0.1143)
		(layer "In4.Cu")
		(net "L5_85OHM_5INCH_DN")
	)
	(segment
		(start 117.718078 -163.692332)
		(end 117.386862 -163.461192)
		(width 0.1143)
		(layer "In4.Cu")
		(net "L5_85OHM_5INCH_DN")
	)
	(segment
		(start 136.208262 -165.942518)
		(end 136.11606 -166.075106)
		(width 0.1143)
		(layer "In4.Cu")
		(net "L5_85OHM_5INCH_DN")
	)
	(segment
		(start 130.500882 -163.630864)
		(end 130.160522 -163.392358)
		(width 0.1143)
		(layer "In4.Cu")
		(net "L5_85OHM_5INCH_DN")
	)
	(segment
		(start 118.539514 -166.160704)
		(end 118.277132 -166.206678)
		(width 0.1143)
		(layer "In4.Cu")
		(net "L5_85OHM_5INCH_DN")
	)
	(segment
		(start 118.144544 -166.113968)
		(end 117.718078 -163.692332)
		(width 0.1143)
		(layer "In4.Cu")
		(net "L5_85OHM_5INCH_DN")
	)
	(segment
		(start 115.787424 -163.456366)
		(end 115.286282 -163.545012)
		(width 0.1143)
		(layer "In4.Cu")
		(net "L5_85OHM_5INCH_DN")
	)
	(segment
		(start 132.634482 -163.810696)
		(end 133.009894 -165.937946)
		(width 0.1143)
		(layer "In4.Cu")
		(net "L5_85OHM_5INCH_DN")
	)
	(segment
		(start 131.319524 -166.078916)
		(end 131.056634 -166.125144)
		(width 0.1143)
		(layer "In4.Cu")
		(net "L5_85OHM_5INCH_DN")
	)
	(segment
		(start 114.943636 -166.097712)
		(end 114.858292 -165.612572)
		(width 0.1143)
		(layer "In4.Cu")
		(net "L5_85OHM_5INCH_DN")
	)
	(segment
		(start 132.098542 -163.618164)
		(end 131.766818 -163.387278)
		(width 0.1143)
		(layer "In4.Cu")
		(net "L5_85OHM_5INCH_DN")
	)
	(segment
		(start 129.437892 -163.818316)
		(end 129.81305 -165.946328)
		(width 0.1143)
		(layer "In4.Cu")
		(net "L5_85OHM_5INCH_DN")
	)
	(segment
		(start 136.560306 -163.36264)
		(end 136.05891 -163.451286)
		(width 0.1143)
		(layer "In4.Cu")
		(net "L5_85OHM_5INCH_DN")
	)
	(segment
		(start 131.03479 -163.806632)
		(end 131.412234 -165.946328)
		(width 0.1143)
		(layer "In4.Cu")
		(net "L5_85OHM_5INCH_DN")
	)
	(segment
		(start 127.310642 -163.68014)
		(end 126.97968 -163.449254)
		(width 0.1143)
		(layer "In4.Cu")
		(net "L5_85OHM_5INCH_DN")
	)
	(segment
		(start 129.457958 -166.125144)
		(end 129.32537 -166.032434)
		(width 0.1143)
		(layer "In4.Cu")
		(net "L5_85OHM_5INCH_DN")
	)
	(segment
		(start 121.343674 -166.118032)
		(end 120.91416 -163.684204)
		(width 0.1143)
		(layer "In4.Cu")
		(net "L5_85OHM_5INCH_DN")
	)
	(segment
		(start 130.924046 -166.032688)
		(end 130.500882 -163.630864)
		(width 0.1143)
		(layer "In4.Cu")
		(net "L5_85OHM_5INCH_DN")
	)
	(segment
		(start 135.720836 -166.028878)
		(end 135.297164 -163.623752)
		(width 0.1143)
		(layer "In4.Cu")
		(net "L5_85OHM_5INCH_DN")
	)
	(segment
		(start 137.65911 -163.450778)
		(end 137.4267 -163.780978)
		(width 0.1143)
		(layer "In4.Cu")
		(net "L5_85OHM_5INCH_DN")
	)
	(via
		(at 318.866774 -165.675056)
		(size 0.5588)
		(drill 0.3048)
		(layers "F.Cu" "B.Cu")
		(net "L5_85OHM_10INCH_DP")
	)
	(via
		(at 385.980432 -165.667944)
		(size 0.5588)
		(drill 0.3048)
		(layers "F.Cu" "B.Cu")
		(net "L5_85OHM_10INCH_DP")
	)
	(segment
		(start 317.993014 -165.059106)
		(end 318.250824 -165.059106)
		(width 0.1143)
		(layer "B.Cu")
		(net "L5_85OHM_10INCH_DP")
	)
	(segment
		(start 317.645796 -165.406324)
		(end 317.993014 -165.059106)
		(width 0.1143)
		(layer "B.Cu")
		(net "L5_85OHM_10INCH_DP")
	)
	(segment
		(start 386.596382 -165.051994)
		(end 385.980432 -165.667944)
		(width 0.1143)
		(layer "B.Cu")
		(net "L5_85OHM_10INCH_DP")
	)
	(segment
		(start 318.250824 -165.059106)
		(end 318.866774 -165.675056)
		(width 0.1143)
		(layer "B.Cu")
		(net "L5_85OHM_10INCH_DP")
	)
	(segment
		(start 386.832856 -165.051994)
		(end 386.596382 -165.051994)
		(width 0.1143)
		(layer "B.Cu")
		(net "L5_85OHM_10INCH_DP")
	)
	(segment
		(start 387.20141 -165.420548)
		(end 386.832856 -165.051994)
		(width 0.1143)
		(layer "B.Cu")
		(net "L5_85OHM_10INCH_DP")
	)
	(segment
		(start 332.888082 -163.795202)
		(end 332.755494 -163.702746)
		(width 0.1143)
		(layer "In4.Cu")
		(net "L5_85OHM_10INCH_DP")
	)
	(segment
		(start 361.545632 -165.923976)
		(end 361.314492 -166.254938)
		(width 0.1143)
		(layer "In4.Cu")
		(net "L5_85OHM_10INCH_DP")
	)
	(segment
		(start 374.334786 -163.699952)
		(end 374.072404 -163.745926)
		(width 0.1143)
		(layer "In4.Cu")
		(net "L5_85OHM_10INCH_DP")
	)
	(segment
		(start 321.96913 -165.433756)
		(end 321.811142 -165.222936)
		(width 0.1143)
		(layer "In4.Cu")
		(net "L5_85OHM_10INCH_DP")
	)
	(segment
		(start 329.350878 -166.368222)
		(end 328.849482 -166.456868)
		(width 0.1143)
		(layer "In4.Cu")
		(net "L5_85OHM_10INCH_DP")
	)
	(segment
		(start 369.558824 -166.012876)
		(end 369.328192 -166.344346)
		(width 0.1143)
		(layer "In4.Cu")
		(net "L5_85OHM_10INCH_DP")
	)
	(segment
		(start 356.478078 -163.737544)
		(end 356.385368 -163.869878)
		(width 0.1143)
		(layer "In4.Cu")
		(net "L5_85OHM_10INCH_DP")
	)
	(segment
		(start 375.666254 -163.717478)
		(end 375.573544 -163.849812)
		(width 0.1143)
		(layer "In4.Cu")
		(net "L5_85OHM_10INCH_DP")
	)
	(segment
		(start 370.781072 -163.874196)
		(end 371.158516 -166.014146)
		(width 0.1143)
		(layer "In4.Cu")
		(net "L5_85OHM_10INCH_DP")
	)
	(segment
		(start 345.68257 -163.799266)
		(end 345.549982 -163.70681)
		(width 0.1143)
		(layer "In4.Cu")
		(net "L5_85OHM_10INCH_DP")
	)
	(segment
		(start 355.275134 -163.788598)
		(end 355.142292 -163.69538)
		(width 0.1143)
		(layer "In4.Cu")
		(net "L5_85OHM_10INCH_DP")
	)
	(segment
		(start 329.201526 -163.87699)
		(end 329.582526 -166.037768)
		(width 0.1143)
		(layer "In4.Cu")
		(net "L5_85OHM_10INCH_DP")
	)
	(segment
		(start 332.399894 -163.881562)
		(end 332.775306 -166.008812)
		(width 0.1143)
		(layer "In4.Cu")
		(net "L5_85OHM_10INCH_DP")
	)
	(segment
		(start 328.51852 -166.224204)
		(end 328.08926 -163.79063)
		(width 0.1143)
		(layer "In4.Cu")
		(net "L5_85OHM_10INCH_DP")
	)
	(segment
		(start 323.292724 -163.793932)
		(end 323.160898 -163.70173)
		(width 0.1143)
		(layer "In4.Cu")
		(net "L5_85OHM_10INCH_DP")
	)
	(segment
		(start 370.425726 -166.433246)
		(end 370.094764 -166.20236)
		(width 0.1143)
		(layer "In4.Cu")
		(net "L5_85OHM_10INCH_DP")
	)
	(segment
		(start 354.87991 -163.741354)
		(end 354.787454 -163.873942)
		(width 0.1143)
		(layer "In4.Cu")
		(net "L5_85OHM_10INCH_DP")
	)
	(segment
		(start 366.117632 -166.28999)
		(end 365.61649 -166.378636)
		(width 0.1143)
		(layer "In4.Cu")
		(net "L5_85OHM_10INCH_DP")
	)
	(segment
		(start 356.385368 -163.869878)
		(end 356.749096 -165.932358)
		(width 0.1143)
		(layer "In4.Cu")
		(net "L5_85OHM_10INCH_DP")
	)
	(segment
		(start 343.958926 -165.947852)
		(end 343.72804 -166.278306)
		(width 0.1143)
		(layer "In4.Cu")
		(net "L5_85OHM_10INCH_DP")
	)
	(segment
		(start 356.749096 -165.932358)
		(end 356.51821 -166.262812)
		(width 0.1143)
		(layer "In4.Cu")
		(net "L5_85OHM_10INCH_DP")
	)
	(segment
		(start 349.622364 -166.363142)
		(end 349.292164 -166.132002)
		(width 0.1143)
		(layer "In4.Cu")
		(net "L5_85OHM_10INCH_DP")
	)
	(segment
		(start 355.142292 -163.69538)
		(end 354.87991 -163.741354)
		(width 0.1143)
		(layer "In4.Cu")
		(net "L5_85OHM_10INCH_DP")
	)
	(segment
		(start 381.287782 -166.194994)
		(end 380.859792 -163.769294)
		(width 0.1143)
		(layer "In4.Cu")
		(net "L5_85OHM_10INCH_DP")
	)
	(segment
		(start 367.68024 -163.780216)
		(end 367.58753 -163.912804)
		(width 0.1143)
		(layer "In4.Cu")
		(net "L5_85OHM_10INCH_DP")
	)
	(segment
		(start 368.07521 -163.826698)
		(end 367.942876 -163.733988)
		(width 0.1143)
		(layer "In4.Cu")
		(net "L5_85OHM_10INCH_DP")
	)
	(segment
		(start 334.485742 -163.78682)
		(end 334.353154 -163.694364)
		(width 0.1143)
		(layer "In4.Cu")
		(net "L5_85OHM_10INCH_DP")
	)
	(segment
		(start 372.867936 -163.792154)
		(end 372.735602 -163.699698)
		(width 0.1143)
		(layer "In4.Cu")
		(net "L5_85OHM_10INCH_DP")
	)
	(segment
		(start 350.123506 -166.274496)
		(end 349.622364 -166.363142)
		(width 0.1143)
		(layer "In4.Cu")
		(net "L5_85OHM_10INCH_DP")
	)
	(segment
		(start 347.156278 -165.939216)
		(end 346.925138 -166.270178)
		(width 0.1143)
		(layer "In4.Cu")
		(net "L5_85OHM_10INCH_DP")
	)
	(segment
		(start 351.953068 -165.93566)
		(end 351.721674 -166.266876)
		(width 0.1143)
		(layer "In4.Cu")
		(net "L5_85OHM_10INCH_DP")
	)
	(segment
		(start 350.346772 -163.703)
		(end 350.084136 -163.749228)
		(width 0.1143)
		(layer "In4.Cu")
		(net "L5_85OHM_10INCH_DP")
	)
	(segment
		(start 364.388654 -163.910772)
		(end 364.747556 -165.94328)
		(width 0.1143)
		(layer "In4.Cu")
		(net "L5_85OHM_10INCH_DP")
	)
	(segment
		(start 332.543912 -166.340028)
		(end 332.043278 -166.428166)
		(width 0.1143)
		(layer "In4.Cu")
		(net "L5_85OHM_10INCH_DP")
	)
	(segment
		(start 369.328192 -166.344346)
		(end 368.826542 -166.432738)
		(width 0.1143)
		(layer "In4.Cu")
		(net "L5_85OHM_10INCH_DP")
	)
	(segment
		(start 360.48188 -166.111682)
		(end 360.073448 -163.792916)
		(width 0.1143)
		(layer "In4.Cu")
		(net "L5_85OHM_10INCH_DP")
	)
	(segment
		(start 364.515654 -166.274496)
		(end 364.014512 -166.363142)
		(width 0.1143)
		(layer "In4.Cu")
		(net "L5_85OHM_10INCH_DP")
	)
	(segment
		(start 345.549982 -163.70681)
		(end 345.2876 -163.752784)
		(width 0.1143)
		(layer "In4.Cu")
		(net "L5_85OHM_10INCH_DP")
	)
	(segment
		(start 375.573544 -163.849812)
		(end 375.954544 -166.010844)
		(width 0.1143)
		(layer "In4.Cu")
		(net "L5_85OHM_10INCH_DP")
	)
	(segment
		(start 332.755494 -163.702746)
		(end 332.492604 -163.748974)
		(width 0.1143)
		(layer "In4.Cu")
		(net "L5_85OHM_10INCH_DP")
	)
	(segment
		(start 348.8817 -163.804854)
		(end 348.748604 -163.711636)
		(width 0.1143)
		(layer "In4.Cu")
		(net "L5_85OHM_10INCH_DP")
	)
	(segment
		(start 353.675442 -163.787582)
		(end 353.543108 -163.695126)
		(width 0.1143)
		(layer "In4.Cu")
		(net "L5_85OHM_10INCH_DP")
	)
	(segment
		(start 329.688952 -163.79063)
		(end 329.556364 -163.69792)
		(width 0.1143)
		(layer "In4.Cu")
		(net "L5_85OHM_10INCH_DP")
	)
	(segment
		(start 345.327224 -166.27856)
		(end 344.825828 -166.366698)
		(width 0.1143)
		(layer "In4.Cu")
		(net "L5_85OHM_10INCH_DP")
	)
	(segment
		(start 342.359488 -165.94328)
		(end 342.128348 -166.274242)
		(width 0.1143)
		(layer "In4.Cu")
		(net "L5_85OHM_10INCH_DP")
	)
	(segment
		(start 372.524782 -166.33698)
		(end 372.023386 -166.424864)
		(width 0.1143)
		(layer "In4.Cu")
		(net "L5_85OHM_10INCH_DP")
	)
	(segment
		(start 362.878878 -163.758118)
		(end 362.786168 -163.89096)
		(width 0.1143)
		(layer "In4.Cu")
		(net "L5_85OHM_10INCH_DP")
	)
	(segment
		(start 322.014088 -165.61054)
		(end 321.96913 -165.433756)
		(width 0.1143)
		(layer "In4.Cu")
		(net "L5_85OHM_10INCH_DP")
	)
	(segment
		(start 334.143604 -166.344854)
		(end 333.64297 -166.43223)
		(width 0.1143)
		(layer "In4.Cu")
		(net "L5_85OHM_10INCH_DP")
	)
	(segment
		(start 346.925138 -166.270178)
		(end 346.423742 -166.358062)
		(width 0.1143)
		(layer "In4.Cu")
		(net "L5_85OHM_10INCH_DP")
	)
	(segment
		(start 348.755462 -165.93947)
		(end 348.524322 -166.270432)
		(width 0.1143)
		(layer "In4.Cu")
		(net "L5_85OHM_10INCH_DP")
	)
	(segment
		(start 377.172982 -163.849304)
		(end 377.553982 -166.01059)
		(width 0.1143)
		(layer "In4.Cu")
		(net "L5_85OHM_10INCH_DP")
	)
	(segment
		(start 379.151896 -166.002208)
		(end 378.920756 -166.33317)
		(width 0.1143)
		(layer "In4.Cu")
		(net "L5_85OHM_10INCH_DP")
	)
	(segment
		(start 324.40499 -163.884864)
		(end 324.783958 -166.031926)
		(width 0.1143)
		(layer "In4.Cu")
		(net "L5_85OHM_10INCH_DP")
	)
	(segment
		(start 363.684312 -166.132002)
		(end 363.273848 -163.804854)
		(width 0.1143)
		(layer "In4.Cu")
		(net "L5_85OHM_10INCH_DP")
	)
	(segment
		(start 339.287104 -163.80333)
		(end 339.154008 -163.71062)
		(width 0.1143)
		(layer "In4.Cu")
		(net "L5_85OHM_10INCH_DP")
	)
	(segment
		(start 374.467628 -163.79317)
		(end 374.334786 -163.699952)
		(width 0.1143)
		(layer "In4.Cu")
		(net "L5_85OHM_10INCH_DP")
	)
	(segment
		(start 344.07983 -163.779708)
		(end 343.946988 -163.686236)
		(width 0.1143)
		(layer "In4.Cu")
		(net "L5_85OHM_10INCH_DP")
	)
	(segment
		(start 332.492604 -163.748974)
		(end 332.399894 -163.881562)
		(width 0.1143)
		(layer "In4.Cu")
		(net "L5_85OHM_10INCH_DP")
	)
	(segment
		(start 381.97409 -163.870894)
		(end 382.351026 -166.006272)
		(width 0.1143)
		(layer "In4.Cu")
		(net "L5_85OHM_10INCH_DP")
	)
	(segment
		(start 379.128274 -163.675822)
		(end 378.865892 -163.721796)
		(width 0.1143)
		(layer "In4.Cu")
		(net "L5_85OHM_10INCH_DP")
	)
	(segment
		(start 369.52936 -163.700714)
		(end 369.283488 -163.743894)
		(width 0.1143)
		(layer "In4.Cu")
		(net "L5_85OHM_10INCH_DP")
	)
	(segment
		(start 367.218468 -166.39413)
		(end 366.888268 -166.16299)
		(width 0.1143)
		(layer "In4.Cu")
		(net "L5_85OHM_10INCH_DP")
	)
	(segment
		(start 343.72804 -166.278306)
		(end 343.226898 -166.366698)
		(width 0.1143)
		(layer "In4.Cu")
		(net "L5_85OHM_10INCH_DP")
	)
	(segment
		(start 374.072404 -163.745926)
		(end 373.979948 -163.878514)
		(width 0.1143)
		(layer "In4.Cu")
		(net "L5_85OHM_10INCH_DP")
	)
	(segment
		(start 340.885272 -163.803076)
		(end 340.752938 -163.71062)
		(width 0.1143)
		(layer "In4.Cu")
		(net "L5_85OHM_10INCH_DP")
	)
	(segment
		(start 323.18198 -166.016432)
		(end 322.950586 -166.347648)
		(width 0.1143)
		(layer "In4.Cu")
		(net "L5_85OHM_10INCH_DP")
	)
	(segment
		(start 350.889316 -166.123874)
		(end 350.479106 -163.79571)
		(width 0.1143)
		(layer "In4.Cu")
		(net "L5_85OHM_10INCH_DP")
	)
	(segment
		(start 345.194636 -163.884864)
		(end 345.558364 -165.947598)
		(width 0.1143)
		(layer "In4.Cu")
		(net "L5_85OHM_10INCH_DP")
	)
	(segment
		(start 373.979948 -163.878514)
		(end 374.355106 -166.006272)
		(width 0.1143)
		(layer "In4.Cu")
		(net "L5_85OHM_10INCH_DP")
	)
	(segment
		(start 343.591642 -163.865052)
		(end 343.958926 -165.947852)
		(width 0.1143)
		(layer "In4.Cu")
		(net "L5_85OHM_10INCH_DP")
	)
	(segment
		(start 350.355408 -165.94328)
		(end 350.123506 -166.274496)
		(width 0.1143)
		(layer "In4.Cu")
		(net "L5_85OHM_10INCH_DP")
	)
	(segment
		(start 330.89342 -163.74872)
		(end 330.800964 -163.881054)
		(width 0.1143)
		(layer "In4.Cu")
		(net "L5_85OHM_10INCH_DP")
	)
	(segment
		(start 372.380764 -163.878514)
		(end 372.756176 -166.005764)
		(width 0.1143)
		(layer "In4.Cu")
		(net "L5_85OHM_10INCH_DP")
	)
	(segment
		(start 356.51821 -166.262812)
		(end 356.017068 -166.351204)
		(width 0.1143)
		(layer "In4.Cu")
		(net "L5_85OHM_10INCH_DP")
	)
	(segment
		(start 354.086414 -166.115492)
		(end 353.675442 -163.787582)
		(width 0.1143)
		(layer "In4.Cu")
		(net "L5_85OHM_10INCH_DP")
	)
	(segment
		(start 354.417376 -166.346378)
		(end 354.086414 -166.115492)
		(width 0.1143)
		(layer "In4.Cu")
		(net "L5_85OHM_10INCH_DP")
	)
	(segment
		(start 359.585768 -163.878768)
		(end 359.946448 -165.923722)
		(width 0.1143)
		(layer "In4.Cu")
		(net "L5_85OHM_10INCH_DP")
	)
	(segment
		(start 367.58753 -163.912804)
		(end 367.951512 -165.974268)
		(width 0.1143)
		(layer "In4.Cu")
		(net "L5_85OHM_10INCH_DP")
	)
	(segment
		(start 340.529164 -166.273988)
		(end 340.027768 -166.361872)
		(width 0.1143)
		(layer "In4.Cu")
		(net "L5_85OHM_10INCH_DP")
	)
	(segment
		(start 334.908906 -166.188644)
		(end 334.485742 -163.78682)
		(width 0.1143)
		(layer "In4.Cu")
		(net "L5_85OHM_10INCH_DP")
	)
	(segment
		(start 358.340152 -163.691316)
		(end 358.07777 -163.73729)
		(width 0.1143)
		(layer "In4.Cu")
		(net "L5_85OHM_10INCH_DP")
	)
	(segment
		(start 382.46177 -163.784788)
		(end 382.329436 -163.692078)
		(width 0.1143)
		(layer "In4.Cu")
		(net "L5_85OHM_10INCH_DP")
	)
	(segment
		(start 374.891554 -166.19855)
		(end 374.467628 -163.79317)
		(width 0.1143)
		(layer "In4.Cu")
		(net "L5_85OHM_10INCH_DP")
	)
	(segment
		(start 351.220278 -166.35476)
		(end 350.889316 -166.123874)
		(width 0.1143)
		(layer "In4.Cu")
		(net "L5_85OHM_10INCH_DP")
	)
	(segment
		(start 352.486976 -166.115492)
		(end 352.077274 -163.787836)
		(width 0.1143)
		(layer "In4.Cu")
		(net "L5_85OHM_10INCH_DP")
	)
	(segment
		(start 345.2876 -163.752784)
		(end 345.194636 -163.884864)
		(width 0.1143)
		(layer "In4.Cu")
		(net "L5_85OHM_10INCH_DP")
	)
	(segment
		(start 324.783958 -166.031926)
		(end 324.553072 -166.363396)
		(width 0.1143)
		(layer "In4.Cu")
		(net "L5_85OHM_10INCH_DP")
	)
	(segment
		(start 338.099146 -166.139368)
		(end 337.688936 -163.811204)
		(width 0.1143)
		(layer "In4.Cu")
		(net "L5_85OHM_10INCH_DP")
	)
	(segment
		(start 342.128348 -166.274242)
		(end 341.627206 -166.361872)
		(width 0.1143)
		(layer "In4.Cu")
		(net "L5_85OHM_10INCH_DP")
	)
	(segment
		(start 380.859792 -163.769294)
		(end 380.72695 -163.676076)
		(width 0.1143)
		(layer "In4.Cu")
		(net "L5_85OHM_10INCH_DP")
	)
	(segment
		(start 331.156056 -163.702746)
		(end 330.89342 -163.74872)
		(width 0.1143)
		(layer "In4.Cu")
		(net "L5_85OHM_10INCH_DP")
	)
	(segment
		(start 337.300824 -163.754816)
		(end 337.20151 -163.897056)
		(width 0.1143)
		(layer "In4.Cu")
		(net "L5_85OHM_10INCH_DP")
	)
	(segment
		(start 366.888268 -166.16299)
		(end 366.473232 -163.811204)
		(width 0.1143)
		(layer "In4.Cu")
		(net "L5_85OHM_10INCH_DP")
	)
	(segment
		(start 357.615998 -166.351204)
		(end 357.285798 -166.11981)
		(width 0.1143)
		(layer "In4.Cu")
		(net "L5_85OHM_10INCH_DP")
	)
	(segment
		(start 329.556364 -163.69792)
		(end 329.293728 -163.744402)
		(width 0.1143)
		(layer "In4.Cu")
		(net "L5_85OHM_10INCH_DP")
	)
	(segment
		(start 327.602088 -163.876736)
		(end 327.983088 -166.03853)
		(width 0.1143)
		(layer "In4.Cu")
		(net "L5_85OHM_10INCH_DP")
	)
	(segment
		(start 368.826542 -166.432738)
		(end 368.495072 -166.200328)
		(width 0.1143)
		(layer "In4.Cu")
		(net "L5_85OHM_10INCH_DP")
	)
	(segment
		(start 341.296244 -166.130986)
		(end 340.885272 -163.803076)
		(width 0.1143)
		(layer "In4.Cu")
		(net "L5_85OHM_10INCH_DP")
	)
	(segment
		(start 333.64297 -166.43223)
		(end 333.311246 -166.201344)
		(width 0.1143)
		(layer "In4.Cu")
		(net "L5_85OHM_10INCH_DP")
	)
	(segment
		(start 366.078262 -163.764722)
		(end 365.985552 -163.89731)
		(width 0.1143)
		(layer "In4.Cu")
		(net "L5_85OHM_10INCH_DP")
	)
	(segment
		(start 324.497446 -163.75253)
		(end 324.40499 -163.884864)
		(width 0.1143)
		(layer "In4.Cu")
		(net "L5_85OHM_10INCH_DP")
	)
	(segment
		(start 330.944982 -166.340028)
		(end 330.443586 -166.427912)
		(width 0.1143)
		(layer "In4.Cu")
		(net "L5_85OHM_10INCH_DP")
	)
	(segment
		(start 382.119124 -166.337488)
		(end 381.617982 -166.426134)
		(width 0.1143)
		(layer "In4.Cu")
		(net "L5_85OHM_10INCH_DP")
	)
	(segment
		(start 353.18827 -163.873942)
		(end 353.550728 -165.927278)
		(width 0.1143)
		(layer "In4.Cu")
		(net "L5_85OHM_10INCH_DP")
	)
	(segment
		(start 343.946988 -163.686236)
		(end 343.684352 -163.732718)
		(width 0.1143)
		(layer "In4.Cu")
		(net "L5_85OHM_10INCH_DP")
	)
	(segment
		(start 365.61649 -166.378636)
		(end 365.28629 -166.147496)
		(width 0.1143)
		(layer "In4.Cu")
		(net "L5_85OHM_10INCH_DP")
	)
	(segment
		(start 363.273848 -163.804854)
		(end 363.14126 -163.712144)
		(width 0.1143)
		(layer "In4.Cu")
		(net "L5_85OHM_10INCH_DP")
	)
	(segment
		(start 338.430108 -166.370254)
		(end 338.099146 -166.139368)
		(width 0.1143)
		(layer "In4.Cu")
		(net "L5_85OHM_10INCH_DP")
	)
	(segment
		(start 330.112624 -166.195756)
		(end 329.688952 -163.79063)
		(width 0.1143)
		(layer "In4.Cu")
		(net "L5_85OHM_10INCH_DP")
	)
	(segment
		(start 371.269006 -163.78809)
		(end 371.13591 -163.69538)
		(width 0.1143)
		(layer "In4.Cu")
		(net "L5_85OHM_10INCH_DP")
	)
	(segment
		(start 341.627206 -166.361872)
		(end 341.296244 -166.130986)
		(width 0.1143)
		(layer "In4.Cu")
		(net "L5_85OHM_10INCH_DP")
	)
	(segment
		(start 346.092526 -166.126922)
		(end 345.68257 -163.799266)
		(width 0.1143)
		(layer "In4.Cu")
		(net "L5_85OHM_10INCH_DP")
	)
	(segment
		(start 364.014512 -166.363142)
		(end 363.684312 -166.132002)
		(width 0.1143)
		(layer "In4.Cu")
		(net "L5_85OHM_10INCH_DP")
	)
	(segment
		(start 337.20151 -163.897056)
		(end 337.563714 -165.951154)
		(width 0.1143)
		(layer "In4.Cu")
		(net "L5_85OHM_10INCH_DP")
	)
	(segment
		(start 337.688936 -163.811204)
		(end 337.546696 -163.711636)
		(width 0.1143)
		(layer "In4.Cu")
		(net "L5_85OHM_10INCH_DP")
	)
	(segment
		(start 382.351026 -166.006272)
		(end 382.119124 -166.337488)
		(width 0.1143)
		(layer "In4.Cu")
		(net "L5_85OHM_10INCH_DP")
	)
	(segment
		(start 323.160898 -163.70173)
		(end 322.898262 -163.748212)
		(width 0.1143)
		(layer "In4.Cu")
		(net "L5_85OHM_10INCH_DP")
	)
	(segment
		(start 321.022726 -164.972238)
		(end 319.936876 -165.059106)
		(width 0.1143)
		(layer "In4.Cu")
		(net "L5_85OHM_10INCH_DP")
	)
	(segment
		(start 326.359266 -163.706556)
		(end 326.09663 -163.752784)
		(width 0.1143)
		(layer "In4.Cu")
		(net "L5_85OHM_10INCH_DP")
	)
	(segment
		(start 348.486476 -163.75761)
		(end 348.393766 -163.890452)
		(width 0.1143)
		(layer "In4.Cu")
		(net "L5_85OHM_10INCH_DP")
	)
	(segment
		(start 382.60909 -164.514022)
		(end 382.547114 -164.269928)
		(width 0.1143)
		(layer "In4.Cu")
		(net "L5_85OHM_10INCH_DP")
	)
	(segment
		(start 328.08926 -163.79063)
		(end 327.95718 -163.698174)
		(width 0.1143)
		(layer "In4.Cu")
		(net "L5_85OHM_10INCH_DP")
	)
	(segment
		(start 358.882696 -166.111428)
		(end 358.47274 -163.783772)
		(width 0.1143)
		(layer "In4.Cu")
		(net "L5_85OHM_10INCH_DP")
	)
	(segment
		(start 347.149928 -163.711382)
		(end 346.887546 -163.757356)
		(width 0.1143)
		(layer "In4.Cu")
		(net "L5_85OHM_10INCH_DP")
	)
	(segment
		(start 373.291862 -166.193978)
		(end 372.867936 -163.792154)
		(width 0.1143)
		(layer "In4.Cu")
		(net "L5_85OHM_10INCH_DP")
	)
	(segment
		(start 335.689194 -163.740592)
		(end 335.596738 -163.87318)
		(width 0.1143)
		(layer "In4.Cu")
		(net "L5_85OHM_10INCH_DP")
	)
	(segment
		(start 327.250552 -166.45636)
		(end 326.91959 -166.225474)
		(width 0.1143)
		(layer "In4.Cu")
		(net "L5_85OHM_10INCH_DP")
	)
	(segment
		(start 364.744 -163.731956)
		(end 364.481364 -163.778184)
		(width 0.1143)
		(layer "In4.Cu")
		(net "L5_85OHM_10INCH_DP")
	)
	(segment
		(start 382.0668 -163.738306)
		(end 381.97409 -163.870894)
		(width 0.1143)
		(layer "In4.Cu")
		(net "L5_85OHM_10INCH_DP")
	)
	(segment
		(start 351.944178 -163.695126)
		(end 351.68205 -163.740846)
		(width 0.1143)
		(layer "In4.Cu")
		(net "L5_85OHM_10INCH_DP")
	)
	(segment
		(start 376.061732 -163.764468)
		(end 375.92889 -163.670996)
		(width 0.1143)
		(layer "In4.Cu")
		(net "L5_85OHM_10INCH_DP")
	)
	(segment
		(start 331.176122 -166.008558)
		(end 330.944982 -166.340028)
		(width 0.1143)
		(layer "In4.Cu")
		(net "L5_85OHM_10INCH_DP")
	)
	(segment
		(start 354.918518 -166.258748)
		(end 354.417376 -166.346378)
		(width 0.1143)
		(layer "In4.Cu")
		(net "L5_85OHM_10INCH_DP")
	)
	(segment
		(start 374.123966 -166.337234)
		(end 373.622824 -166.424864)
		(width 0.1143)
		(layer "In4.Cu")
		(net "L5_85OHM_10INCH_DP")
	)
	(segment
		(start 375.723658 -166.341298)
		(end 375.222516 -166.42969)
		(width 0.1143)
		(layer "In4.Cu")
		(net "L5_85OHM_10INCH_DP")
	)
	(segment
		(start 343.684352 -163.732718)
		(end 343.591642 -163.865052)
		(width 0.1143)
		(layer "In4.Cu")
		(net "L5_85OHM_10INCH_DP")
	)
	(segment
		(start 337.546696 -163.711636)
		(end 337.300824 -163.754816)
		(width 0.1143)
		(layer "In4.Cu")
		(net "L5_85OHM_10INCH_DP")
	)
	(segment
		(start 380.018544 -166.421308)
		(end 379.687328 -166.190168)
		(width 0.1143)
		(layer "In4.Cu")
		(net "L5_85OHM_10INCH_DP")
	)
	(segment
		(start 361.538774 -163.696142)
		(end 361.276646 -163.742116)
		(width 0.1143)
		(layer "In4.Cu")
		(net "L5_85OHM_10INCH_DP")
	)
	(segment
		(start 328.849482 -166.456868)
		(end 328.51852 -166.224204)
		(width 0.1143)
		(layer "In4.Cu")
		(net "L5_85OHM_10INCH_DP")
	)
	(segment
		(start 361.183936 -163.874958)
		(end 361.545632 -165.923976)
		(width 0.1143)
		(layer "In4.Cu")
		(net "L5_85OHM_10INCH_DP")
	)
	(segment
		(start 379.260862 -163.768532)
		(end 379.128274 -163.675822)
		(width 0.1143)
		(layer "In4.Cu")
		(net "L5_85OHM_10INCH_DP")
	)
	(segment
		(start 362.913676 -166.259002)
		(end 362.412534 -166.347648)
		(width 0.1143)
		(layer "In4.Cu")
		(net "L5_85OHM_10INCH_DP")
	)
	(segment
		(start 364.876334 -163.824666)
		(end 364.744 -163.731956)
		(width 0.1143)
		(layer "In4.Cu")
		(net "L5_85OHM_10INCH_DP")
	)
	(segment
		(start 358.47274 -163.783772)
		(end 358.340152 -163.691316)
		(width 0.1143)
		(layer "In4.Cu")
		(net "L5_85OHM_10INCH_DP")
	)
	(segment
		(start 348.393766 -163.890452)
		(end 348.755462 -165.93947)
		(width 0.1143)
		(layer "In4.Cu")
		(net "L5_85OHM_10INCH_DP")
	)
	(segment
		(start 363.14126 -163.712144)
		(end 362.878878 -163.758118)
		(width 0.1143)
		(layer "In4.Cu")
		(net "L5_85OHM_10INCH_DP")
	)
	(segment
		(start 341.997284 -163.889436)
		(end 342.359488 -165.94328)
		(width 0.1143)
		(layer "In4.Cu")
		(net "L5_85OHM_10INCH_DP")
	)
	(segment
		(start 374.355106 -166.006272)
		(end 374.123966 -166.337234)
		(width 0.1143)
		(layer "In4.Cu")
		(net "L5_85OHM_10INCH_DP")
	)
	(segment
		(start 319.936876 -165.059106)
		(end 319.482724 -165.059106)
		(width 0.1143)
		(layer "In4.Cu")
		(net "L5_85OHM_10INCH_DP")
	)
	(segment
		(start 376.821446 -166.42969)
		(end 376.491246 -166.198296)
		(width 0.1143)
		(layer "In4.Cu")
		(net "L5_85OHM_10INCH_DP")
	)
	(segment
		(start 370.873782 -163.7411)
		(end 370.781072 -163.874196)
		(width 0.1143)
		(layer "In4.Cu")
		(net "L5_85OHM_10INCH_DP")
	)
	(segment
		(start 338.89188 -163.75634)
		(end 338.79917 -163.889436)
		(width 0.1143)
		(layer "In4.Cu")
		(net "L5_85OHM_10INCH_DP")
	)
	(segment
		(start 364.747556 -165.94328)
		(end 364.515654 -166.274496)
		(width 0.1143)
		(layer "In4.Cu")
		(net "L5_85OHM_10INCH_DP")
	)
	(segment
		(start 351.68205 -163.740846)
		(end 351.58934 -163.873942)
		(width 0.1143)
		(layer "In4.Cu")
		(net "L5_85OHM_10INCH_DP")
	)
	(segment
		(start 383.790698 -165.142672)
		(end 382.858264 -164.846254)
		(width 0.1143)
		(layer "In4.Cu")
		(net "L5_85OHM_10INCH_DP")
	)
	(segment
		(start 378.865892 -163.721796)
		(end 378.773182 -163.854384)
		(width 0.1143)
		(layer "In4.Cu")
		(net "L5_85OHM_10INCH_DP")
	)
	(segment
		(start 377.660916 -163.763706)
		(end 377.528328 -163.67125)
		(width 0.1143)
		(layer "In4.Cu")
		(net "L5_85OHM_10INCH_DP")
	)
	(segment
		(start 339.696806 -166.130986)
		(end 339.287104 -163.80333)
		(width 0.1143)
		(layer "In4.Cu")
		(net "L5_85OHM_10INCH_DP")
	)
	(segment
		(start 362.082334 -166.116508)
		(end 361.67187 -163.78936)
		(width 0.1143)
		(layer "In4.Cu")
		(net "L5_85OHM_10INCH_DP")
	)
	(segment
		(start 322.805044 -163.881308)
		(end 323.18198 -166.016432)
		(width 0.1143)
		(layer "In4.Cu")
		(net "L5_85OHM_10INCH_DP")
	)
	(segment
		(start 369.283488 -163.743894)
		(end 369.184174 -163.886134)
		(width 0.1143)
		(layer "In4.Cu")
		(net "L5_85OHM_10INCH_DP")
	)
	(segment
		(start 359.678478 -163.74618)
		(end 359.585768 -163.878768)
		(width 0.1143)
		(layer "In4.Cu")
		(net "L5_85OHM_10INCH_DP")
	)
	(segment
		(start 362.786168 -163.89096)
		(end 363.145578 -165.927786)
		(width 0.1143)
		(layer "In4.Cu")
		(net "L5_85OHM_10INCH_DP")
	)
	(segment
		(start 349.292164 -166.132002)
		(end 348.8817 -163.804854)
		(width 0.1143)
		(layer "In4.Cu")
		(net "L5_85OHM_10INCH_DP")
	)
	(segment
		(start 322.118482 -166.204138)
		(end 322.014088 -165.61054)
		(width 0.1143)
		(layer "In4.Cu")
		(net "L5_85OHM_10INCH_DP")
	)
	(segment
		(start 329.582526 -166.037768)
		(end 329.350878 -166.368222)
		(width 0.1143)
		(layer "In4.Cu")
		(net "L5_85OHM_10INCH_DP")
	)
	(segment
		(start 375.954544 -166.010844)
		(end 375.723658 -166.341298)
		(width 0.1143)
		(layer "In4.Cu")
		(net "L5_85OHM_10INCH_DP")
	)
	(segment
		(start 322.898262 -163.748212)
		(end 322.805044 -163.881308)
		(width 0.1143)
		(layer "In4.Cu")
		(net "L5_85OHM_10INCH_DP")
	)
	(segment
		(start 385.980432 -165.667944)
		(end 385.364482 -165.051994)
		(width 0.1143)
		(layer "In4.Cu")
		(net "L5_85OHM_10INCH_DP")
	)
	(segment
		(start 372.756176 -166.005764)
		(end 372.524782 -166.33698)
		(width 0.1143)
		(layer "In4.Cu")
		(net "L5_85OHM_10INCH_DP")
	)
	(segment
		(start 370.927122 -166.345362)
		(end 370.425726 -166.433246)
		(width 0.1143)
		(layer "In4.Cu")
		(net "L5_85OHM_10INCH_DP")
	)
	(segment
		(start 335.971896 -166.001192)
		(end 335.733898 -166.34206)
		(width 0.1143)
		(layer "In4.Cu")
		(net "L5_85OHM_10INCH_DP")
	)
	(segment
		(start 330.443586 -166.427912)
		(end 330.112624 -166.195756)
		(width 0.1143)
		(layer "In4.Cu")
		(net "L5_85OHM_10INCH_DP")
	)
	(segment
		(start 327.750678 -166.36873)
		(end 327.250552 -166.45636)
		(width 0.1143)
		(layer "In4.Cu")
		(net "L5_85OHM_10INCH_DP")
	)
	(segment
		(start 376.491246 -166.198296)
		(end 376.061732 -163.764468)
		(width 0.1143)
		(layer "In4.Cu")
		(net "L5_85OHM_10INCH_DP")
	)
	(segment
		(start 364.481364 -163.778184)
		(end 364.388654 -163.910772)
		(width 0.1143)
		(layer "In4.Cu")
		(net "L5_85OHM_10INCH_DP")
	)
	(segment
		(start 331.288644 -163.795202)
		(end 331.156056 -163.702746)
		(width 0.1143)
		(layer "In4.Cu")
		(net "L5_85OHM_10INCH_DP")
	)
	(segment
		(start 347.69171 -166.127176)
		(end 347.282516 -163.804092)
		(width 0.1143)
		(layer "In4.Cu")
		(net "L5_85OHM_10INCH_DP")
	)
	(segment
		(start 367.951512 -165.974268)
		(end 367.71961 -166.305484)
		(width 0.1143)
		(layer "In4.Cu")
		(net "L5_85OHM_10INCH_DP")
	)
	(segment
		(start 369.6716 -163.800282)
		(end 369.52936 -163.700714)
		(width 0.1143)
		(layer "In4.Cu")
		(net "L5_85OHM_10INCH_DP")
	)
	(segment
		(start 326.15124 -166.364158)
		(end 325.650352 -166.451788)
		(width 0.1143)
		(layer "In4.Cu")
		(net "L5_85OHM_10INCH_DP")
	)
	(segment
		(start 338.79917 -163.889436)
		(end 339.162898 -165.951154)
		(width 0.1143)
		(layer "In4.Cu")
		(net "L5_85OHM_10INCH_DP")
	)
	(segment
		(start 351.721674 -166.266876)
		(end 351.220278 -166.35476)
		(width 0.1143)
		(layer "In4.Cu")
		(net "L5_85OHM_10INCH_DP")
	)
	(segment
		(start 360.813096 -166.342822)
		(end 360.48188 -166.111682)
		(width 0.1143)
		(layer "In4.Cu")
		(net "L5_85OHM_10INCH_DP")
	)
	(segment
		(start 362.412534 -166.347648)
		(end 362.082334 -166.116508)
		(width 0.1143)
		(layer "In4.Cu")
		(net "L5_85OHM_10INCH_DP")
	)
	(segment
		(start 338.931504 -166.28237)
		(end 338.430108 -166.370254)
		(width 0.1143)
		(layer "In4.Cu")
		(net "L5_85OHM_10INCH_DP")
	)
	(segment
		(start 336.084418 -163.787074)
		(end 335.95183 -163.694364)
		(width 0.1143)
		(layer "In4.Cu")
		(net "L5_85OHM_10INCH_DP")
	)
	(segment
		(start 375.92889 -163.670996)
		(end 375.666254 -163.717478)
		(width 0.1143)
		(layer "In4.Cu")
		(net "L5_85OHM_10INCH_DP")
	)
	(segment
		(start 326.004174 -163.885118)
		(end 326.382888 -166.032942)
		(width 0.1143)
		(layer "In4.Cu")
		(net "L5_85OHM_10INCH_DP")
	)
	(segment
		(start 380.51994 -166.333424)
		(end 380.018544 -166.421308)
		(width 0.1143)
		(layer "In4.Cu")
		(net "L5_85OHM_10INCH_DP")
	)
	(segment
		(start 324.893178 -163.799012)
		(end 324.760336 -163.706302)
		(width 0.1143)
		(layer "In4.Cu")
		(net "L5_85OHM_10INCH_DP")
	)
	(segment
		(start 334.090264 -163.740592)
		(end 333.997554 -163.87318)
		(width 0.1143)
		(layer "In4.Cu")
		(net "L5_85OHM_10INCH_DP")
	)
	(segment
		(start 348.022926 -166.358316)
		(end 347.69171 -166.127176)
		(width 0.1143)
		(layer "In4.Cu")
		(net "L5_85OHM_10INCH_DP")
	)
	(segment
		(start 366.473232 -163.811204)
		(end 366.340898 -163.718494)
		(width 0.1143)
		(layer "In4.Cu")
		(net "L5_85OHM_10INCH_DP")
	)
	(segment
		(start 322.950586 -166.347648)
		(end 322.44919 -166.435786)
		(width 0.1143)
		(layer "In4.Cu")
		(net "L5_85OHM_10INCH_DP")
	)
	(segment
		(start 333.311246 -166.201344)
		(end 332.888082 -163.795202)
		(width 0.1143)
		(layer "In4.Cu")
		(net "L5_85OHM_10INCH_DP")
	)
	(segment
		(start 368.495072 -166.200328)
		(end 368.07521 -163.826698)
		(width 0.1143)
		(layer "In4.Cu")
		(net "L5_85OHM_10INCH_DP")
	)
	(segment
		(start 334.353154 -163.694364)
		(end 334.090264 -163.740592)
		(width 0.1143)
		(layer "In4.Cu")
		(net "L5_85OHM_10INCH_DP")
	)
	(segment
		(start 377.322842 -166.341552)
		(end 376.821446 -166.42969)
		(width 0.1143)
		(layer "In4.Cu")
		(net "L5_85OHM_10INCH_DP")
	)
	(segment
		(start 372.735602 -163.699698)
		(end 372.473474 -163.745926)
		(width 0.1143)
		(layer "In4.Cu")
		(net "L5_85OHM_10INCH_DP")
	)
	(segment
		(start 361.276646 -163.742116)
		(end 361.183936 -163.874958)
		(width 0.1143)
		(layer "In4.Cu")
		(net "L5_85OHM_10INCH_DP")
	)
	(segment
		(start 348.524322 -166.270432)
		(end 348.022926 -166.358316)
		(width 0.1143)
		(layer "In4.Cu")
		(net "L5_85OHM_10INCH_DP")
	)
	(segment
		(start 379.687328 -166.190168)
		(end 379.260862 -163.768532)
		(width 0.1143)
		(layer "In4.Cu")
		(net "L5_85OHM_10INCH_DP")
	)
	(segment
		(start 358.07777 -163.73729)
		(end 357.984806 -163.86937)
		(width 0.1143)
		(layer "In4.Cu")
		(net "L5_85OHM_10INCH_DP")
	)
	(segment
		(start 358.117394 -166.263066)
		(end 357.615998 -166.351204)
		(width 0.1143)
		(layer "In4.Cu")
		(net "L5_85OHM_10INCH_DP")
	)
	(segment
		(start 377.553982 -166.01059)
		(end 377.322842 -166.341552)
		(width 0.1143)
		(layer "In4.Cu")
		(net "L5_85OHM_10INCH_DP")
	)
	(segment
		(start 385.364482 -165.051994)
		(end 384.922268 -165.051994)
		(width 0.1143)
		(layer "In4.Cu")
		(net "L5_85OHM_10INCH_DP")
	)
	(segment
		(start 365.985552 -163.89731)
		(end 366.349534 -165.958774)
		(width 0.1143)
		(layer "In4.Cu")
		(net "L5_85OHM_10INCH_DP")
	)
	(segment
		(start 325.650352 -166.451788)
		(end 325.31939 -166.220648)
		(width 0.1143)
		(layer "In4.Cu")
		(net "L5_85OHM_10INCH_DP")
	)
	(segment
		(start 380.72695 -163.676076)
		(end 380.464568 -163.722304)
		(width 0.1143)
		(layer "In4.Cu")
		(net "L5_85OHM_10INCH_DP")
	)
	(segment
		(start 353.550728 -165.927278)
		(end 353.319334 -166.258494)
		(width 0.1143)
		(layer "In4.Cu")
		(net "L5_85OHM_10INCH_DP")
	)
	(segment
		(start 326.492108 -163.799266)
		(end 326.359266 -163.706556)
		(width 0.1143)
		(layer "In4.Cu")
		(net "L5_85OHM_10INCH_DP")
	)
	(segment
		(start 366.349534 -165.958774)
		(end 366.117632 -166.28999)
		(width 0.1143)
		(layer "In4.Cu")
		(net "L5_85OHM_10INCH_DP")
	)
	(segment
		(start 350.084136 -163.749228)
		(end 349.991426 -163.881816)
		(width 0.1143)
		(layer "In4.Cu")
		(net "L5_85OHM_10INCH_DP")
	)
	(segment
		(start 324.760336 -163.706302)
		(end 324.497446 -163.75253)
		(width 0.1143)
		(layer "In4.Cu")
		(net "L5_85OHM_10INCH_DP")
	)
	(segment
		(start 370.094764 -166.20236)
		(end 369.6716 -163.800282)
		(width 0.1143)
		(layer "In4.Cu")
		(net "L5_85OHM_10INCH_DP")
	)
	(segment
		(start 322.44919 -166.435786)
		(end 322.118482 -166.204138)
		(width 0.1143)
		(layer "In4.Cu")
		(net "L5_85OHM_10INCH_DP")
	)
	(segment
		(start 324.553072 -166.363396)
		(end 324.051676 -166.451788)
		(width 0.1143)
		(layer "In4.Cu")
		(net "L5_85OHM_10INCH_DP")
	)
	(segment
		(start 345.558364 -165.947598)
		(end 345.327224 -166.27856)
		(width 0.1143)
		(layer "In4.Cu")
		(net "L5_85OHM_10INCH_DP")
	)
	(segment
		(start 377.528328 -163.67125)
		(end 377.265946 -163.717224)
		(width 0.1143)
		(layer "In4.Cu")
		(net "L5_85OHM_10INCH_DP")
	)
	(segment
		(start 366.340898 -163.718494)
		(end 366.078262 -163.764722)
		(width 0.1143)
		(layer "In4.Cu")
		(net "L5_85OHM_10INCH_DP")
	)
	(segment
		(start 346.423742 -166.358062)
		(end 346.092526 -166.126922)
		(width 0.1143)
		(layer "In4.Cu")
		(net "L5_85OHM_10INCH_DP")
	)
	(segment
		(start 371.692424 -166.193978)
		(end 371.269006 -163.78809)
		(width 0.1143)
		(layer "In4.Cu")
		(net "L5_85OHM_10INCH_DP")
	)
	(segment
		(start 371.13591 -163.69538)
		(end 370.873782 -163.7411)
		(width 0.1143)
		(layer "In4.Cu")
		(net "L5_85OHM_10INCH_DP")
	)
	(segment
		(start 321.811142 -165.222936)
		(end 321.022726 -164.972238)
		(width 0.1143)
		(layer "In4.Cu")
		(net "L5_85OHM_10INCH_DP")
	)
	(segment
		(start 352.077274 -163.787836)
		(end 351.944178 -163.695126)
		(width 0.1143)
		(layer "In4.Cu")
		(net "L5_85OHM_10INCH_DP")
	)
	(segment
		(start 356.740714 -163.691062)
		(end 356.478078 -163.737544)
		(width 0.1143)
		(layer "In4.Cu")
		(net "L5_85OHM_10INCH_DP")
	)
	(segment
		(start 344.825828 -166.366698)
		(end 344.495628 -166.135304)
		(width 0.1143)
		(layer "In4.Cu")
		(net "L5_85OHM_10INCH_DP")
	)
	(segment
		(start 361.67187 -163.78936)
		(end 361.538774 -163.696142)
		(width 0.1143)
		(layer "In4.Cu")
		(net "L5_85OHM_10INCH_DP")
	)
	(segment
		(start 372.023386 -166.424864)
		(end 371.692424 -166.193978)
		(width 0.1143)
		(layer "In4.Cu")
		(net "L5_85OHM_10INCH_DP")
	)
	(segment
		(start 365.28629 -166.147496)
		(end 364.876334 -163.824666)
		(width 0.1143)
		(layer "In4.Cu")
		(net "L5_85OHM_10INCH_DP")
	)
	(segment
		(start 340.752938 -163.71062)
		(end 340.49081 -163.756848)
		(width 0.1143)
		(layer "In4.Cu")
		(net "L5_85OHM_10INCH_DP")
	)
	(segment
		(start 384.922268 -165.051994)
		(end 383.790698 -165.142672)
		(width 0.1143)
		(layer "In4.Cu")
		(net "L5_85OHM_10INCH_DP")
	)
	(segment
		(start 355.686106 -166.120064)
		(end 355.275134 -163.788598)
		(width 0.1143)
		(layer "In4.Cu")
		(net "L5_85OHM_10INCH_DP")
	)
	(segment
		(start 342.484964 -163.804092)
		(end 342.352122 -163.710874)
		(width 0.1143)
		(layer "In4.Cu")
		(net "L5_85OHM_10INCH_DP")
	)
	(segment
		(start 326.09663 -163.752784)
		(end 326.004174 -163.885118)
		(width 0.1143)
		(layer "In4.Cu")
		(net "L5_85OHM_10INCH_DP")
	)
	(segment
		(start 342.352122 -163.710874)
		(end 342.08974 -163.756848)
		(width 0.1143)
		(layer "In4.Cu")
		(net "L5_85OHM_10INCH_DP")
	)
	(segment
		(start 350.479106 -163.79571)
		(end 350.346772 -163.703)
		(width 0.1143)
		(layer "In4.Cu")
		(net "L5_85OHM_10INCH_DP")
	)
	(segment
		(start 378.41936 -166.421054)
		(end 378.088144 -166.189914)
		(width 0.1143)
		(layer "In4.Cu")
		(net "L5_85OHM_10INCH_DP")
	)
	(segment
		(start 346.887546 -163.757356)
		(end 346.794836 -163.889944)
		(width 0.1143)
		(layer "In4.Cu")
		(net "L5_85OHM_10INCH_DP")
	)
	(segment
		(start 326.91959 -166.225474)
		(end 326.492108 -163.799266)
		(width 0.1143)
		(layer "In4.Cu")
		(net "L5_85OHM_10INCH_DP")
	)
	(segment
		(start 327.694544 -163.744402)
		(end 327.602088 -163.876736)
		(width 0.1143)
		(layer "In4.Cu")
		(net "L5_85OHM_10INCH_DP")
	)
	(segment
		(start 342.08974 -163.756848)
		(end 341.997284 -163.889436)
		(width 0.1143)
		(layer "In4.Cu")
		(net "L5_85OHM_10INCH_DP")
	)
	(segment
		(start 360.073448 -163.792916)
		(end 359.94086 -163.700206)
		(width 0.1143)
		(layer "In4.Cu")
		(net "L5_85OHM_10INCH_DP")
	)
	(segment
		(start 347.282516 -163.804092)
		(end 347.149928 -163.711382)
		(width 0.1143)
		(layer "In4.Cu")
		(net "L5_85OHM_10INCH_DP")
	)
	(segment
		(start 382.858264 -164.846254)
		(end 382.60909 -164.514022)
		(width 0.1143)
		(layer "In4.Cu")
		(net "L5_85OHM_10INCH_DP")
	)
	(segment
		(start 353.319334 -166.258494)
		(end 352.817938 -166.346378)
		(width 0.1143)
		(layer "In4.Cu")
		(net "L5_85OHM_10INCH_DP")
	)
	(segment
		(start 377.265946 -163.717224)
		(end 377.172982 -163.849304)
		(width 0.1143)
		(layer "In4.Cu")
		(net "L5_85OHM_10INCH_DP")
	)
	(segment
		(start 342.895936 -166.135558)
		(end 342.484964 -163.804092)
		(width 0.1143)
		(layer "In4.Cu")
		(net "L5_85OHM_10INCH_DP")
	)
	(segment
		(start 344.495628 -166.135304)
		(end 344.07983 -163.779708)
		(width 0.1143)
		(layer "In4.Cu")
		(net "L5_85OHM_10INCH_DP")
	)
	(segment
		(start 367.71961 -166.305484)
		(end 367.218468 -166.39413)
		(width 0.1143)
		(layer "In4.Cu")
		(net "L5_85OHM_10INCH_DP")
	)
	(segment
		(start 356.017068 -166.351204)
		(end 355.686106 -166.120064)
		(width 0.1143)
		(layer "In4.Cu")
		(net "L5_85OHM_10INCH_DP")
	)
	(segment
		(start 325.31939 -166.220648)
		(end 324.893178 -163.799012)
		(width 0.1143)
		(layer "In4.Cu")
		(net "L5_85OHM_10INCH_DP")
	)
	(segment
		(start 353.28098 -163.741354)
		(end 353.18827 -163.873942)
		(width 0.1143)
		(layer "In4.Cu")
		(net "L5_85OHM_10INCH_DP")
	)
	(segment
		(start 335.596738 -163.87318)
		(end 335.971896 -166.001192)
		(width 0.1143)
		(layer "In4.Cu")
		(net "L5_85OHM_10INCH_DP")
	)
	(segment
		(start 337.332574 -166.282116)
		(end 336.831432 -166.370254)
		(width 0.1143)
		(layer "In4.Cu")
		(net "L5_85OHM_10INCH_DP")
	)
	(segment
		(start 339.154008 -163.71062)
		(end 338.89188 -163.75634)
		(width 0.1143)
		(layer "In4.Cu")
		(net "L5_85OHM_10INCH_DP")
	)
	(segment
		(start 329.293728 -163.744402)
		(end 329.201526 -163.87699)
		(width 0.1143)
		(layer "In4.Cu")
		(net "L5_85OHM_10INCH_DP")
	)
	(segment
		(start 378.773182 -163.854384)
		(end 379.151896 -166.002208)
		(width 0.1143)
		(layer "In4.Cu")
		(net "L5_85OHM_10INCH_DP")
	)
	(segment
		(start 359.213912 -166.342568)
		(end 358.882696 -166.111428)
		(width 0.1143)
		(layer "In4.Cu")
		(net "L5_85OHM_10INCH_DP")
	)
	(segment
		(start 327.983088 -166.03853)
		(end 327.750678 -166.36873)
		(width 0.1143)
		(layer "In4.Cu")
		(net "L5_85OHM_10INCH_DP")
	)
	(segment
		(start 337.563714 -165.951154)
		(end 337.332574 -166.282116)
		(width 0.1143)
		(layer "In4.Cu")
		(net "L5_85OHM_10INCH_DP")
	)
	(segment
		(start 367.942876 -163.733988)
		(end 367.68024 -163.780216)
		(width 0.1143)
		(layer "In4.Cu")
		(net "L5_85OHM_10INCH_DP")
	)
	(segment
		(start 319.482724 -165.059106)
		(end 318.866774 -165.675056)
		(width 0.1143)
		(layer "In4.Cu")
		(net "L5_85OHM_10INCH_DP")
	)
	(segment
		(start 372.473474 -163.745926)
		(end 372.380764 -163.878514)
		(width 0.1143)
		(layer "In4.Cu")
		(net "L5_85OHM_10INCH_DP")
	)
	(segment
		(start 381.617982 -166.426134)
		(end 381.287782 -166.194994)
		(width 0.1143)
		(layer "In4.Cu")
		(net "L5_85OHM_10INCH_DP")
	)
	(segment
		(start 335.733898 -166.34206)
		(end 335.249266 -166.42715)
		(width 0.1143)
		(layer "In4.Cu")
		(net "L5_85OHM_10INCH_DP")
	)
	(segment
		(start 324.051676 -166.451788)
		(end 323.72046 -166.219632)
		(width 0.1143)
		(layer "In4.Cu")
		(net "L5_85OHM_10INCH_DP")
	)
	(segment
		(start 351.58934 -163.873942)
		(end 351.953068 -165.93566)
		(width 0.1143)
		(layer "In4.Cu")
		(net "L5_85OHM_10INCH_DP")
	)
	(segment
		(start 369.184174 -163.886134)
		(end 369.558824 -166.012876)
		(width 0.1143)
		(layer "In4.Cu")
		(net "L5_85OHM_10INCH_DP")
	)
	(segment
		(start 343.226898 -166.366698)
		(end 342.895936 -166.135558)
		(width 0.1143)
		(layer "In4.Cu")
		(net "L5_85OHM_10INCH_DP")
	)
	(segment
		(start 378.920756 -166.33317)
		(end 378.41936 -166.421054)
		(width 0.1143)
		(layer "In4.Cu")
		(net "L5_85OHM_10INCH_DP")
	)
	(segment
		(start 335.95183 -163.694364)
		(end 335.689194 -163.740592)
		(width 0.1143)
		(layer "In4.Cu")
		(net "L5_85OHM_10INCH_DP")
	)
	(segment
		(start 331.71257 -166.197026)
		(end 331.288644 -163.795202)
		(width 0.1143)
		(layer "In4.Cu")
		(net "L5_85OHM_10INCH_DP")
	)
	(segment
		(start 359.94086 -163.700206)
		(end 359.678478 -163.74618)
		(width 0.1143)
		(layer "In4.Cu")
		(net "L5_85OHM_10INCH_DP")
	)
	(segment
		(start 326.382888 -166.032942)
		(end 326.15124 -166.364158)
		(width 0.1143)
		(layer "In4.Cu")
		(net "L5_85OHM_10INCH_DP")
	)
	(segment
		(start 332.043278 -166.428166)
		(end 331.71257 -166.197026)
		(width 0.1143)
		(layer "In4.Cu")
		(net "L5_85OHM_10INCH_DP")
	)
	(segment
		(start 382.329436 -163.692078)
		(end 382.0668 -163.738306)
		(width 0.1143)
		(layer "In4.Cu")
		(net "L5_85OHM_10INCH_DP")
	)
	(segment
		(start 361.314492 -166.254938)
		(end 360.813096 -166.342822)
		(width 0.1143)
		(layer "In4.Cu")
		(net "L5_85OHM_10INCH_DP")
	)
	(segment
		(start 363.145578 -165.927786)
		(end 362.913676 -166.259002)
		(width 0.1143)
		(layer "In4.Cu")
		(net "L5_85OHM_10INCH_DP")
	)
	(segment
		(start 375.222516 -166.42969)
		(end 374.891554 -166.19855)
		(width 0.1143)
		(layer "In4.Cu")
		(net "L5_85OHM_10INCH_DP")
	)
	(segment
		(start 340.49081 -163.756848)
		(end 340.3981 -163.889436)
		(width 0.1143)
		(layer "In4.Cu")
		(net "L5_85OHM_10INCH_DP")
	)
	(segment
		(start 356.87381 -163.784534)
		(end 356.740714 -163.691062)
		(width 0.1143)
		(layer "In4.Cu")
		(net "L5_85OHM_10INCH_DP")
	)
	(segment
		(start 359.715308 -166.254684)
		(end 359.213912 -166.342568)
		(width 0.1143)
		(layer "In4.Cu")
		(net "L5_85OHM_10INCH_DP")
	)
	(segment
		(start 346.794836 -163.889944)
		(end 347.156278 -165.939216)
		(width 0.1143)
		(layer "In4.Cu")
		(net "L5_85OHM_10INCH_DP")
	)
	(segment
		(start 335.249266 -166.42715)
		(end 334.908906 -166.188644)
		(width 0.1143)
		(layer "In4.Cu")
		(net "L5_85OHM_10INCH_DP")
	)
	(segment
		(start 355.149658 -165.927786)
		(end 354.918518 -166.258748)
		(width 0.1143)
		(layer "In4.Cu")
		(net "L5_85OHM_10INCH_DP")
	)
	(segment
		(start 357.285798 -166.11981)
		(end 356.87381 -163.784534)
		(width 0.1143)
		(layer "In4.Cu")
		(net "L5_85OHM_10INCH_DP")
	)
	(segment
		(start 380.372112 -163.855146)
		(end 380.75108 -166.002462)
		(width 0.1143)
		(layer "In4.Cu")
		(net "L5_85OHM_10INCH_DP")
	)
	(segment
		(start 339.162898 -165.951154)
		(end 338.931504 -166.28237)
		(width 0.1143)
		(layer "In4.Cu")
		(net "L5_85OHM_10INCH_DP")
	)
	(segment
		(start 353.543108 -163.695126)
		(end 353.28098 -163.741354)
		(width 0.1143)
		(layer "In4.Cu")
		(net "L5_85OHM_10INCH_DP")
	)
	(segment
		(start 340.3981 -163.889436)
		(end 340.760558 -165.942772)
		(width 0.1143)
		(layer "In4.Cu")
		(net "L5_85OHM_10INCH_DP")
	)
	(segment
		(start 354.787454 -163.873942)
		(end 355.149658 -165.927786)
		(width 0.1143)
		(layer "In4.Cu")
		(net "L5_85OHM_10INCH_DP")
	)
	(segment
		(start 357.984806 -163.86937)
		(end 358.348534 -165.932104)
		(width 0.1143)
		(layer "In4.Cu")
		(net "L5_85OHM_10INCH_DP")
	)
	(segment
		(start 380.75108 -166.002462)
		(end 380.51994 -166.333424)
		(width 0.1143)
		(layer "In4.Cu")
		(net "L5_85OHM_10INCH_DP")
	)
	(segment
		(start 327.95718 -163.698174)
		(end 327.694544 -163.744402)
		(width 0.1143)
		(layer "In4.Cu")
		(net "L5_85OHM_10INCH_DP")
	)
	(segment
		(start 371.158516 -166.014146)
		(end 370.927122 -166.345362)
		(width 0.1143)
		(layer "In4.Cu")
		(net "L5_85OHM_10INCH_DP")
	)
	(segment
		(start 332.775306 -166.008812)
		(end 332.543912 -166.340028)
		(width 0.1143)
		(layer "In4.Cu")
		(net "L5_85OHM_10INCH_DP")
	)
	(segment
		(start 323.72046 -166.219632)
		(end 323.292724 -163.793932)
		(width 0.1143)
		(layer "In4.Cu")
		(net "L5_85OHM_10INCH_DP")
	)
	(segment
		(start 336.831432 -166.370254)
		(end 336.50047 -166.139114)
		(width 0.1143)
		(layer "In4.Cu")
		(net "L5_85OHM_10INCH_DP")
	)
	(segment
		(start 334.374998 -166.012876)
		(end 334.143604 -166.344854)
		(width 0.1143)
		(layer "In4.Cu")
		(net "L5_85OHM_10INCH_DP")
	)
	(segment
		(start 382.547114 -164.269928)
		(end 382.46177 -163.784788)
		(width 0.1143)
		(layer "In4.Cu")
		(net "L5_85OHM_10INCH_DP")
	)
	(segment
		(start 378.088144 -166.189914)
		(end 377.660916 -163.763706)
		(width 0.1143)
		(layer "In4.Cu")
		(net "L5_85OHM_10INCH_DP")
	)
	(segment
		(start 340.760558 -165.942772)
		(end 340.529164 -166.273988)
		(width 0.1143)
		(layer "In4.Cu")
		(net "L5_85OHM_10INCH_DP")
	)
	(segment
		(start 340.027768 -166.361872)
		(end 339.696806 -166.130986)
		(width 0.1143)
		(layer "In4.Cu")
		(net "L5_85OHM_10INCH_DP")
	)
	(segment
		(start 333.997554 -163.87318)
		(end 334.374998 -166.012876)
		(width 0.1143)
		(layer "In4.Cu")
		(net "L5_85OHM_10INCH_DP")
	)
	(segment
		(start 358.348534 -165.932104)
		(end 358.117394 -166.263066)
		(width 0.1143)
		(layer "In4.Cu")
		(net "L5_85OHM_10INCH_DP")
	)
	(segment
		(start 336.50047 -166.139114)
		(end 336.084418 -163.787074)
		(width 0.1143)
		(layer "In4.Cu")
		(net "L5_85OHM_10INCH_DP")
	)
	(segment
		(start 359.946448 -165.923722)
		(end 359.715308 -166.254684)
		(width 0.1143)
		(layer "In4.Cu")
		(net "L5_85OHM_10INCH_DP")
	)
	(segment
		(start 373.622824 -166.424864)
		(end 373.291862 -166.193978)
		(width 0.1143)
		(layer "In4.Cu")
		(net "L5_85OHM_10INCH_DP")
	)
	(segment
		(start 348.748604 -163.711636)
		(end 348.486476 -163.75761)
		(width 0.1143)
		(layer "In4.Cu")
		(net "L5_85OHM_10INCH_DP")
	)
	(segment
		(start 330.800964 -163.881054)
		(end 331.176122 -166.008558)
		(width 0.1143)
		(layer "In4.Cu")
		(net "L5_85OHM_10INCH_DP")
	)
	(segment
		(start 380.464568 -163.722304)
		(end 380.372112 -163.855146)
		(width 0.1143)
		(layer "In4.Cu")
		(net "L5_85OHM_10INCH_DP")
	)
	(segment
		(start 352.817938 -166.346378)
		(end 352.486976 -166.115492)
		(width 0.1143)
		(layer "In4.Cu")
		(net "L5_85OHM_10INCH_DP")
	)
	(segment
		(start 349.991426 -163.881816)
		(end 350.355408 -165.94328)
		(width 0.1143)
		(layer "In4.Cu")
		(net "L5_85OHM_10INCH_DP")
	)
	(via
		(at 385.980432 -164.143944)
		(size 0.5588)
		(drill 0.3048)
		(layers "F.Cu" "B.Cu")
		(net "L5_85OHM_10INCH_DN")
	)
	(via
		(at 318.866774 -164.151056)
		(size 0.5588)
		(drill 0.3048)
		(layers "F.Cu" "B.Cu")
		(net "L5_85OHM_10INCH_DN")
	)
	(segment
		(start 386.861304 -164.759894)
		(end 386.596382 -164.759894)
		(width 0.1143)
		(layer "B.Cu")
		(net "L5_85OHM_10INCH_DN")
	)
	(segment
		(start 318.007238 -164.767006)
		(end 318.250824 -164.767006)
		(width 0.1143)
		(layer "B.Cu")
		(net "L5_85OHM_10INCH_DN")
	)
	(segment
		(start 318.250824 -164.767006)
		(end 318.866774 -164.151056)
		(width 0.1143)
		(layer "B.Cu")
		(net "L5_85OHM_10INCH_DN")
	)
	(segment
		(start 386.596382 -164.759894)
		(end 385.980432 -164.143944)
		(width 0.1143)
		(layer "B.Cu")
		(net "L5_85OHM_10INCH_DN")
	)
	(segment
		(start 387.20141 -164.419788)
		(end 386.861304 -164.759894)
		(width 0.1143)
		(layer "B.Cu")
		(net "L5_85OHM_10INCH_DN")
	)
	(segment
		(start 317.645796 -164.405564)
		(end 318.007238 -164.767006)
		(width 0.1143)
		(layer "B.Cu")
		(net "L5_85OHM_10INCH_DN")
	)
	(segment
		(start 367.278666 -163.844478)
		(end 367.642648 -165.905688)
		(width 0.1143)
		(layer "In4.Cu")
		(net "L5_85OHM_10INCH_DN")
	)
	(segment
		(start 375.64568 -165.94201)
		(end 375.553478 -166.074598)
		(width 0.1143)
		(layer "In4.Cu")
		(net "L5_85OHM_10INCH_DN")
	)
	(segment
		(start 351.288604 -166.04615)
		(end 351.156016 -165.953694)
		(width 0.1143)
		(layer "In4.Cu")
		(net "L5_85OHM_10INCH_DN")
	)
	(segment
		(start 361.105958 -163.47567)
		(end 360.875072 -163.806886)
		(width 0.1143)
		(layer "In4.Cu")
		(net "L5_85OHM_10INCH_DN")
	)
	(segment
		(start 379.527816 -163.598352)
		(end 379.196854 -163.367212)
		(width 0.1143)
		(layer "In4.Cu")
		(net "L5_85OHM_10INCH_DN")
	)
	(segment
		(start 353.149154 -165.99154)
		(end 352.886264 -166.037768)
		(width 0.1143)
		(layer "In4.Cu")
		(net "L5_85OHM_10INCH_DN")
	)
	(segment
		(start 323.229224 -163.392866)
		(end 322.728082 -163.481512)
		(width 0.1143)
		(layer "In4.Cu")
		(net "L5_85OHM_10INCH_DN")
	)
	(segment
		(start 331.224382 -163.394136)
		(end 330.72324 -163.481766)
		(width 0.1143)
		(layer "In4.Cu")
		(net "L5_85OHM_10INCH_DN")
	)
	(segment
		(start 380.34976 -166.06647)
		(end 380.08687 -166.112698)
		(width 0.1143)
		(layer "In4.Cu")
		(net "L5_85OHM_10INCH_DN")
	)
	(segment
		(start 377.096528 -163.45027)
		(end 376.864118 -163.78047)
		(width 0.1143)
		(layer "In4.Cu")
		(net "L5_85OHM_10INCH_DN")
	)
	(segment
		(start 325.586344 -166.050468)
		(end 325.159878 -163.628832)
		(width 0.1143)
		(layer "In4.Cu")
		(net "L5_85OHM_10INCH_DN")
	)
	(segment
		(start 352.753676 -165.945312)
		(end 352.344228 -163.617402)
		(width 0.1143)
		(layer "In4.Cu")
		(net "L5_85OHM_10INCH_DN")
	)
	(segment
		(start 348.446598 -165.871144)
		(end 348.354142 -166.003478)
		(width 0.1143)
		(layer "In4.Cu")
		(net "L5_85OHM_10INCH_DN")
	)
	(segment
		(start 347.95841 -165.956996)
		(end 347.54947 -163.633912)
		(width 0.1143)
		(layer "In4.Cu")
		(net "L5_85OHM_10INCH_DN")
	)
	(segment
		(start 351.644204 -165.867334)
		(end 351.551494 -165.999922)
		(width 0.1143)
		(layer "In4.Cu")
		(net "L5_85OHM_10INCH_DN")
	)
	(segment
		(start 324.828662 -163.397692)
		(end 324.327266 -163.485576)
		(width 0.1143)
		(layer "In4.Cu")
		(net "L5_85OHM_10INCH_DN")
	)
	(segment
		(start 338.854034 -165.882828)
		(end 338.761324 -166.015416)
		(width 0.1143)
		(layer "In4.Cu")
		(net "L5_85OHM_10INCH_DN")
	)
	(segment
		(start 346.847414 -165.87089)
		(end 346.754958 -166.003224)
		(width 0.1143)
		(layer "In4.Cu")
		(net "L5_85OHM_10INCH_DN")
	)
	(segment
		(start 371.959124 -166.023798)
		(end 371.53596 -163.617656)
		(width 0.1143)
		(layer "In4.Cu")
		(net "L5_85OHM_10INCH_DN")
	)
	(segment
		(start 375.553478 -166.074598)
		(end 375.290842 -166.12108)
		(width 0.1143)
		(layer "In4.Cu")
		(net "L5_85OHM_10INCH_DN")
	)
	(segment
		(start 352.886264 -166.037768)
		(end 352.753676 -165.945312)
		(width 0.1143)
		(layer "In4.Cu")
		(net "L5_85OHM_10INCH_DN")
	)
	(segment
		(start 330.867258 -165.940486)
		(end 330.774802 -166.073074)
		(width 0.1143)
		(layer "In4.Cu")
		(net "L5_85OHM_10INCH_DN")
	)
	(segment
		(start 335.287874 -163.804854)
		(end 335.663032 -165.932866)
		(width 0.1143)
		(layer "In4.Cu")
		(net "L5_85OHM_10INCH_DN")
	)
	(segment
		(start 334.066134 -165.944804)
		(end 333.973424 -166.0779)
		(width 0.1143)
		(layer "In4.Cu")
		(net "L5_85OHM_10INCH_DN")
	)
	(segment
		(start 345.157044 -166.011606)
		(end 344.894408 -166.057834)
		(width 0.1143)
		(layer "In4.Cu")
		(net "L5_85OHM_10INCH_DN")
	)
	(segment
		(start 370.472208 -163.806124)
		(end 370.849652 -165.94582)
		(width 0.1143)
		(layer "In4.Cu")
		(net "L5_85OHM_10INCH_DN")
	)
	(segment
		(start 365.684816 -166.069772)
		(end 365.55299 -165.97757)
		(width 0.1143)
		(layer "In4.Cu")
		(net "L5_85OHM_10INCH_DN")
	)
	(segment
		(start 353.942142 -163.617402)
		(end 353.611434 -163.386262)
		(width 0.1143)
		(layer "In4.Cu")
		(net "L5_85OHM_10INCH_DN")
	)
	(segment
		(start 375.997724 -163.362132)
		(end 375.496328 -163.450778)
		(width 0.1143)
		(layer "In4.Cu")
		(net "L5_85OHM_10INCH_DN")
	)
	(segment
		(start 370.494052 -166.124636)
		(end 370.361464 -166.03218)
		(width 0.1143)
		(layer "In4.Cu")
		(net "L5_85OHM_10INCH_DN")
	)
	(segment
		(start 344.894408 -166.057834)
		(end 344.762328 -165.965378)
		(width 0.1143)
		(layer "In4.Cu")
		(net "L5_85OHM_10INCH_DN")
	)
	(segment
		(start 329.123548 -163.477702)
		(end 328.892662 -163.808156)
		(width 0.1143)
		(layer "In4.Cu")
		(net "L5_85OHM_10INCH_DN")
	)
	(segment
		(start 377.152662 -166.074598)
		(end 376.890026 -166.120826)
		(width 0.1143)
		(layer "In4.Cu")
		(net "L5_85OHM_10INCH_DN")
	)
	(segment
		(start 353.241864 -165.858952)
		(end 353.149154 -165.99154)
		(width 0.1143)
		(layer "In4.Cu")
		(net "L5_85OHM_10INCH_DN")
	)
	(segment
		(start 373.69115 -166.116254)
		(end 373.558562 -166.023798)
		(width 0.1143)
		(layer "In4.Cu")
		(net "L5_85OHM_10INCH_DN")
	)
	(segment
		(start 362.836714 -165.859206)
		(end 362.743496 -165.992302)
		(width 0.1143)
		(layer "In4.Cu")
		(net "L5_85OHM_10INCH_DN")
	)
	(segment
		(start 383.036064 -164.596064)
		(end 382.878076 -164.385244)
		(width 0.1143)
		(layer "In4.Cu")
		(net "L5_85OHM_10INCH_DN")
	)
	(segment
		(start 357.140764 -163.614862)
		(end 356.809548 -163.382198)
		(width 0.1143)
		(layer "In4.Cu")
		(net "L5_85OHM_10INCH_DN")
	)
	(segment
		(start 333.920084 -163.473638)
		(end 333.68869 -163.804854)
		(width 0.1143)
		(layer "In4.Cu")
		(net "L5_85OHM_10INCH_DN")
	)
	(segment
		(start 363.951012 -165.962076)
		(end 363.540548 -163.634928)
		(width 0.1143)
		(layer "In4.Cu")
		(net "L5_85OHM_10INCH_DN")
	)
	(segment
		(start 330.379578 -166.02583)
		(end 329.955652 -163.62045)
		(width 0.1143)
		(layer "In4.Cu")
		(net "L5_85OHM_10INCH_DN")
	)
	(segment
		(start 337.25485 -165.882828)
		(end 337.162394 -166.015416)
		(width 0.1143)
		(layer "In4.Cu")
		(net "L5_85OHM_10INCH_DN")
	)
	(segment
		(start 332.466442 -165.940486)
		(end 332.373732 -166.073074)
		(width 0.1143)
		(layer "In4.Cu")
		(net "L5_85OHM_10INCH_DN")
	)
	(segment
		(start 324.382638 -166.096696)
		(end 324.120256 -166.142924)
		(width 0.1143)
		(layer "In4.Cu")
		(net "L5_85OHM_10INCH_DN")
	)
	(segment
		(start 349.1484 -163.634928)
		(end 348.817184 -163.402772)
		(width 0.1143)
		(layer "In4.Cu")
		(net "L5_85OHM_10INCH_DN")
	)
	(segment
		(start 323.987414 -166.049706)
		(end 323.559424 -163.624006)
		(width 0.1143)
		(layer "In4.Cu")
		(net "L5_85OHM_10INCH_DN")
	)
	(segment
		(start 339.963506 -165.960806)
		(end 339.554058 -163.632896)
		(width 0.1143)
		(layer "In4.Cu")
		(net "L5_85OHM_10INCH_DN")
	)
	(segment
		(start 347.54947 -163.633912)
		(end 347.218508 -163.402772)
		(width 0.1143)
		(layer "In4.Cu")
		(net "L5_85OHM_10INCH_DN")
	)
	(segment
		(start 370.361464 -166.03218)
		(end 369.9383 -163.630356)
		(width 0.1143)
		(layer "In4.Cu")
		(net "L5_85OHM_10INCH_DN")
	)
	(segment
		(start 369.157758 -166.077646)
		(end 368.895122 -166.123874)
		(width 0.1143)
		(layer "In4.Cu")
		(net "L5_85OHM_10INCH_DN")
	)
	(segment
		(start 328.785474 -166.054532)
		(end 328.35596 -163.620704)
		(width 0.1143)
		(layer "In4.Cu")
		(net "L5_85OHM_10INCH_DN")
	)
	(segment
		(start 335.317846 -166.118286)
		(end 335.175606 -166.018718)
		(width 0.1143)
		(layer "In4.Cu")
		(net "L5_85OHM_10INCH_DN")
	)
	(segment
		(start 367.154968 -165.993064)
		(end 366.740186 -163.641278)
		(width 0.1143)
		(layer "In4.Cu")
		(net "L5_85OHM_10INCH_DN")
	)
	(segment
		(start 361.144312 -165.987984)
		(end 360.881422 -166.034212)
		(width 0.1143)
		(layer "In4.Cu")
		(net "L5_85OHM_10INCH_DN")
	)
	(segment
		(start 359.545128 -165.98773)
		(end 359.282492 -166.033958)
		(width 0.1143)
		(layer "In4.Cu")
		(net "L5_85OHM_10INCH_DN")
	)
	(segment
		(start 356.085394 -166.042594)
		(end 355.952806 -165.949884)
		(width 0.1143)
		(layer "In4.Cu")
		(net "L5_85OHM_10INCH_DN")
	)
	(segment
		(start 379.196854 -163.367212)
		(end 378.695966 -163.454842)
		(width 0.1143)
		(layer "In4.Cu")
		(net "L5_85OHM_10INCH_DN")
	)
	(segment
		(start 341.91956 -163.489894)
		(end 341.68842 -163.821364)
		(width 0.1143)
		(layer "In4.Cu")
		(net "L5_85OHM_10INCH_DN")
	)
	(segment
		(start 325.159878 -163.628832)
		(end 324.828662 -163.397692)
		(width 0.1143)
		(layer "In4.Cu")
		(net "L5_85OHM_10INCH_DN")
	)
	(segment
		(start 367.54943 -166.038784)
		(end 367.286794 -166.085266)
		(width 0.1143)
		(layer "In4.Cu")
		(net "L5_85OHM_10INCH_DN")
	)
	(segment
		(start 354.748338 -165.991794)
		(end 354.485702 -166.037768)
		(width 0.1143)
		(layer "In4.Cu")
		(net "L5_85OHM_10INCH_DN")
	)
	(segment
		(start 365.947452 -166.02329)
		(end 365.684816 -166.069772)
		(width 0.1143)
		(layer "In4.Cu")
		(net "L5_85OHM_10INCH_DN")
	)
	(segment
		(start 331.97927 -166.026846)
		(end 331.555344 -163.625022)
		(width 0.1143)
		(layer "In4.Cu")
		(net "L5_85OHM_10INCH_DN")
	)
	(segment
		(start 380.79553 -163.367212)
		(end 380.294134 -163.455604)
		(width 0.1143)
		(layer "In4.Cu")
		(net "L5_85OHM_10INCH_DN")
	)
	(segment
		(start 367.286794 -166.085266)
		(end 367.154968 -165.993064)
		(width 0.1143)
		(layer "In4.Cu")
		(net "L5_85OHM_10INCH_DN")
	)
	(segment
		(start 346.754958 -166.003224)
		(end 346.492322 -166.049452)
		(width 0.1143)
		(layer "In4.Cu")
		(net "L5_85OHM_10INCH_DN")
	)
	(segment
		(start 327.318878 -166.14775)
		(end 327.18629 -166.055294)
		(width 0.1143)
		(layer "In4.Cu")
		(net "L5_85OHM_10INCH_DN")
	)
	(segment
		(start 379.954028 -166.019988)
		(end 379.527816 -163.598352)
		(width 0.1143)
		(layer "In4.Cu")
		(net "L5_85OHM_10INCH_DN")
	)
	(segment
		(start 319.482724 -164.767006)
		(end 318.866774 -164.151056)
		(width 0.1143)
		(layer "In4.Cu")
		(net "L5_85OHM_10INCH_DN")
	)
	(segment
		(start 350.415352 -163.394136)
		(end 349.913956 -163.482274)
		(width 0.1143)
		(layer "In4.Cu")
		(net "L5_85OHM_10INCH_DN")
	)
	(segment
		(start 372.354602 -166.070026)
		(end 372.091712 -166.116254)
		(width 0.1143)
		(layer "In4.Cu")
		(net "L5_85OHM_10INCH_DN")
	)
	(segment
		(start 327.293224 -163.80841)
		(end 327.674224 -165.969696)
		(width 0.1143)
		(layer "In4.Cu")
		(net "L5_85OHM_10INCH_DN")
	)
	(segment
		(start 330.4921 -163.812728)
		(end 330.867258 -165.940486)
		(width 0.1143)
		(layer "In4.Cu")
		(net "L5_85OHM_10INCH_DN")
	)
	(segment
		(start 362.47705 -163.82238)
		(end 362.836714 -165.859206)
		(width 0.1143)
		(layer "In4.Cu")
		(net "L5_85OHM_10INCH_DN")
	)
	(segment
		(start 355.952806 -165.949884)
		(end 355.542088 -163.618672)
		(width 0.1143)
		(layer "In4.Cu")
		(net "L5_85OHM_10INCH_DN")
	)
	(segment
		(start 380.442216 -165.934136)
		(end 380.34976 -166.06647)
		(width 0.1143)
		(layer "In4.Cu")
		(net "L5_85OHM_10INCH_DN")
	)
	(segment
		(start 324.120256 -166.142924)
		(end 323.987414 -166.049706)
		(width 0.1143)
		(layer "In4.Cu")
		(net "L5_85OHM_10INCH_DN")
	)
	(segment
		(start 364.311184 -163.51123)
		(end 364.07979 -163.842446)
		(width 0.1143)
		(layer "In4.Cu")
		(net "L5_85OHM_10INCH_DN")
	)
	(segment
		(start 349.953326 -166.007796)
		(end 349.69069 -166.054278)
		(width 0.1143)
		(layer "In4.Cu")
		(net "L5_85OHM_10INCH_DN")
	)
	(segment
		(start 376.757946 -166.02837)
		(end 376.328686 -163.594796)
		(width 0.1143)
		(layer "In4.Cu")
		(net "L5_85OHM_10INCH_DN")
	)
	(segment
		(start 328.918316 -166.148004)
		(end 328.785474 -166.054532)
		(width 0.1143)
		(layer "In4.Cu")
		(net "L5_85OHM_10INCH_DN")
	)
	(segment
		(start 329.62469 -163.38931)
		(end 329.123548 -163.477702)
		(width 0.1143)
		(layer "In4.Cu")
		(net "L5_85OHM_10INCH_DN")
	)
	(segment
		(start 363.540548 -163.634928)
		(end 363.20984 -163.40328)
		(width 0.1143)
		(layer "In4.Cu")
		(net "L5_85OHM_10INCH_DN")
	)
	(segment
		(start 327.524364 -163.477448)
		(end 327.293224 -163.80841)
		(width 0.1143)
		(layer "In4.Cu")
		(net "L5_85OHM_10INCH_DN")
	)
	(segment
		(start 376.328686 -163.594796)
		(end 375.997724 -163.362132)
		(width 0.1143)
		(layer "In4.Cu")
		(net "L5_85OHM_10INCH_DN")
	)
	(segment
		(start 346.492322 -166.049452)
		(end 346.35948 -165.956742)
		(width 0.1143)
		(layer "In4.Cu")
		(net "L5_85OHM_10INCH_DN")
	)
	(segment
		(start 343.162636 -165.965378)
		(end 342.751918 -163.634166)
		(width 0.1143)
		(layer "In4.Cu")
		(net "L5_85OHM_10INCH_DN")
	)
	(segment
		(start 376.864118 -163.78047)
		(end 377.245118 -165.942264)
		(width 0.1143)
		(layer "In4.Cu")
		(net "L5_85OHM_10INCH_DN")
	)
	(segment
		(start 365.676688 -163.828984)
		(end 366.04067 -165.890194)
		(width 0.1143)
		(layer "In4.Cu")
		(net "L5_85OHM_10INCH_DN")
	)
	(segment
		(start 338.490306 -163.821364)
		(end 338.854034 -165.882828)
		(width 0.1143)
		(layer "In4.Cu")
		(net "L5_85OHM_10INCH_DN")
	)
	(segment
		(start 322.300092 -165.549072)
		(end 322.238116 -165.304978)
		(width 0.1143)
		(layer "In4.Cu")
		(net "L5_85OHM_10INCH_DN")
	)
	(segment
		(start 377.927616 -163.593526)
		(end 377.596654 -163.36264)
		(width 0.1143)
		(layer "In4.Cu")
		(net "L5_85OHM_10INCH_DN")
	)
	(segment
		(start 357.947214 -165.996112)
		(end 357.684578 -166.04234)
		(width 0.1143)
		(layer "In4.Cu")
		(net "L5_85OHM_10INCH_DN")
	)
	(segment
		(start 354.70973 -163.4744)
		(end 354.47859 -163.80587)
		(width 0.1143)
		(layer "In4.Cu")
		(net "L5_85OHM_10INCH_DN")
	)
	(segment
		(start 339.554058 -163.632896)
		(end 339.222334 -163.40201)
		(width 0.1143)
		(layer "In4.Cu")
		(net "L5_85OHM_10INCH_DN")
	)
	(segment
		(start 332.82382 -163.394136)
		(end 332.322424 -163.48202)
		(width 0.1143)
		(layer "In4.Cu")
		(net "L5_85OHM_10INCH_DN")
	)
	(segment
		(start 382.398016 -163.383214)
		(end 381.89662 -163.471352)
		(width 0.1143)
		(layer "In4.Cu")
		(net "L5_85OHM_10INCH_DN")
	)
	(segment
		(start 336.351118 -163.616894)
		(end 336.020156 -163.385754)
		(width 0.1143)
		(layer "In4.Cu")
		(net "L5_85OHM_10INCH_DN")
	)
	(segment
		(start 375.158254 -166.02837)
		(end 374.734582 -163.623244)
		(width 0.1143)
		(layer "In4.Cu")
		(net "L5_85OHM_10INCH_DN")
	)
	(segment
		(start 322.51777 -166.126922)
		(end 322.385436 -166.034212)
		(width 0.1143)
		(layer "In4.Cu")
		(net "L5_85OHM_10INCH_DN")
	)
	(segment
		(start 351.551494 -165.999922)
		(end 351.288604 -166.04615)
		(width 0.1143)
		(layer "In4.Cu")
		(net "L5_85OHM_10INCH_DN")
	)
	(segment
		(start 331.555344 -163.625022)
		(end 331.224382 -163.394136)
		(width 0.1143)
		(layer "In4.Cu")
		(net "L5_85OHM_10INCH_DN")
	)
	(segment
		(start 365.908082 -163.497768)
		(end 365.676688 -163.828984)
		(width 0.1143)
		(layer "In4.Cu")
		(net "L5_85OHM_10INCH_DN")
	)
	(segment
		(start 342.420956 -163.40201)
		(end 341.91956 -163.489894)
		(width 0.1143)
		(layer "In4.Cu")
		(net "L5_85OHM_10INCH_DN")
	)
	(segment
		(start 328.02576 -163.38931)
		(end 327.524364 -163.477448)
		(width 0.1143)
		(layer "In4.Cu")
		(net "L5_85OHM_10INCH_DN")
	)
	(segment
		(start 343.650062 -165.879018)
		(end 343.55786 -166.011606)
		(width 0.1143)
		(layer "In4.Cu")
		(net "L5_85OHM_10INCH_DN")
	)
	(segment
		(start 336.899758 -166.061644)
		(end 336.76717 -165.968934)
		(width 0.1143)
		(layer "In4.Cu")
		(net "L5_85OHM_10INCH_DN")
	)
	(segment
		(start 332.373732 -166.073074)
		(end 332.111604 -166.119302)
		(width 0.1143)
		(layer "In4.Cu")
		(net "L5_85OHM_10INCH_DN")
	)
	(segment
		(start 341.68842 -163.821364)
		(end 342.050624 -165.874954)
		(width 0.1143)
		(layer "In4.Cu")
		(net "L5_85OHM_10INCH_DN")
	)
	(segment
		(start 348.084902 -163.82238)
		(end 348.446598 -165.871144)
		(width 0.1143)
		(layer "In4.Cu")
		(net "L5_85OHM_10INCH_DN")
	)
	(segment
		(start 322.385436 -166.034212)
		(end 322.300092 -165.549072)
		(width 0.1143)
		(layer "In4.Cu")
		(net "L5_85OHM_10INCH_DN")
	)
	(segment
		(start 326.759062 -163.629086)
		(end 326.427846 -163.397946)
		(width 0.1143)
		(layer "In4.Cu")
		(net "L5_85OHM_10INCH_DN")
	)
	(segment
		(start 336.892646 -163.82873)
		(end 337.25485 -165.882828)
		(width 0.1143)
		(layer "In4.Cu")
		(net "L5_85OHM_10INCH_DN")
	)
	(segment
		(start 373.558562 -166.023798)
		(end 373.134636 -163.621974)
		(width 0.1143)
		(layer "In4.Cu")
		(net "L5_85OHM_10INCH_DN")
	)
	(segment
		(start 364.81258 -163.423092)
		(end 364.311184 -163.51123)
		(width 0.1143)
		(layer "In4.Cu")
		(net "L5_85OHM_10INCH_DN")
	)
	(segment
		(start 368.87531 -163.817808)
		(end 369.250214 -165.944804)
		(width 0.1143)
		(layer "In4.Cu")
		(net "L5_85OHM_10INCH_DN")
	)
	(segment
		(start 345.2495 -165.879272)
		(end 345.157044 -166.011606)
		(width 0.1143)
		(layer "In4.Cu")
		(net "L5_85OHM_10INCH_DN")
	)
	(segment
		(start 368.895122 -166.123874)
		(end 368.761772 -166.030402)
		(width 0.1143)
		(layer "In4.Cu")
		(net "L5_85OHM_10INCH_DN")
	)
	(segment
		(start 341.958168 -166.007288)
		(end 341.695532 -166.053262)
		(width 0.1143)
		(layer "In4.Cu")
		(net "L5_85OHM_10INCH_DN")
	)
	(segment
		(start 325.92645 -163.48583)
		(end 325.69531 -163.816792)
		(width 0.1143)
		(layer "In4.Cu")
		(net "L5_85OHM_10INCH_DN")
	)
	(segment
		(start 340.32063 -163.489894)
		(end 340.089236 -163.82111)
		(width 0.1143)
		(layer "In4.Cu")
		(net "L5_85OHM_10INCH_DN")
	)
	(segment
		(start 349.558864 -165.962076)
		(end 349.1484 -163.634928)
		(width 0.1143)
		(layer "In4.Cu")
		(net "L5_85OHM_10INCH_DN")
	)
	(segment
		(start 377.596654 -163.36264)
		(end 377.096528 -163.45027)
		(width 0.1143)
		(layer "In4.Cu")
		(net "L5_85OHM_10INCH_DN")
	)
	(segment
		(start 334.42148 -163.385754)
		(end 333.920084 -163.473638)
		(width 0.1143)
		(layer "In4.Cu")
		(net "L5_85OHM_10INCH_DN")
	)
	(segment
		(start 369.59794 -163.39185)
		(end 369.113308 -163.47694)
		(width 0.1143)
		(layer "In4.Cu")
		(net "L5_85OHM_10INCH_DN")
	)
	(segment
		(start 342.050624 -165.874954)
		(end 341.958168 -166.007288)
		(width 0.1143)
		(layer "In4.Cu")
		(net "L5_85OHM_10INCH_DN")
	)
	(segment
		(start 348.315788 -163.491164)
		(end 348.084902 -163.82238)
		(width 0.1143)
		(layer "In4.Cu")
		(net "L5_85OHM_10INCH_DN")
	)
	(segment
		(start 346.35948 -165.956742)
		(end 345.94927 -163.629086)
		(width 0.1143)
		(layer "In4.Cu")
		(net "L5_85OHM_10INCH_DN")
	)
	(segment
		(start 373.902224 -163.478972)
		(end 373.671084 -163.810442)
		(width 0.1143)
		(layer "In4.Cu")
		(net "L5_85OHM_10INCH_DN")
	)
	(segment
		(start 351.280476 -163.80587)
		(end 351.644204 -165.867334)
		(width 0.1143)
		(layer "In4.Cu")
		(net "L5_85OHM_10INCH_DN")
	)
	(segment
		(start 385.364482 -164.759894)
		(end 384.91033 -164.759894)
		(width 0.1143)
		(layer "In4.Cu")
		(net "L5_85OHM_10INCH_DN")
	)
	(segment
		(start 360.00944 -163.391596)
		(end 359.508552 -163.479226)
		(width 0.1143)
		(layer "In4.Cu")
		(net "L5_85OHM_10INCH_DN")
	)
	(segment
		(start 371.204236 -163.38677)
		(end 370.703602 -163.474146)
		(width 0.1143)
		(layer "In4.Cu")
		(net "L5_85OHM_10INCH_DN")
	)
	(segment
		(start 359.276904 -163.810442)
		(end 359.637584 -165.855396)
		(width 0.1143)
		(layer "In4.Cu")
		(net "L5_85OHM_10INCH_DN")
	)
	(segment
		(start 383.82448 -164.846762)
		(end 383.036064 -164.596064)
		(width 0.1143)
		(layer "In4.Cu")
		(net "L5_85OHM_10INCH_DN")
	)
	(segment
		(start 330.72324 -163.481766)
		(end 330.4921 -163.812728)
		(width 0.1143)
		(layer "In4.Cu")
		(net "L5_85OHM_10INCH_DN")
	)
	(segment
		(start 337.955636 -163.641278)
		(end 337.615276 -163.402772)
		(width 0.1143)
		(layer "In4.Cu")
		(net "L5_85OHM_10INCH_DN")
	)
	(segment
		(start 345.618308 -163.3982)
		(end 345.118182 -163.48583)
		(width 0.1143)
		(layer "In4.Cu")
		(net "L5_85OHM_10INCH_DN")
	)
	(segment
		(start 369.113308 -163.47694)
		(end 368.87531 -163.817808)
		(width 0.1143)
		(layer "In4.Cu")
		(net "L5_85OHM_10INCH_DN")
	)
	(segment
		(start 344.346784 -163.610036)
		(end 344.015822 -163.377372)
		(width 0.1143)
		(layer "In4.Cu")
		(net "L5_85OHM_10INCH_DN")
	)
	(segment
		(start 329.273662 -165.969188)
		(end 329.180952 -166.101522)
		(width 0.1143)
		(layer "In4.Cu")
		(net "L5_85OHM_10INCH_DN")
	)
	(segment
		(start 343.514426 -163.466018)
		(end 343.282778 -163.796472)
		(width 0.1143)
		(layer "In4.Cu")
		(net "L5_85OHM_10INCH_DN")
	)
	(segment
		(start 360.881422 -166.034212)
		(end 360.74858 -165.941502)
		(width 0.1143)
		(layer "In4.Cu")
		(net "L5_85OHM_10INCH_DN")
	)
	(segment
		(start 373.134636 -163.621974)
		(end 372.803928 -163.390834)
		(width 0.1143)
		(layer "In4.Cu")
		(net "L5_85OHM_10INCH_DN")
	)
	(segment
		(start 344.015822 -163.377372)
		(end 343.514426 -163.466018)
		(width 0.1143)
		(layer "In4.Cu")
		(net "L5_85OHM_10INCH_DN")
	)
	(segment
		(start 338.7217 -163.489386)
		(end 338.490306 -163.821364)
		(width 0.1143)
		(layer "In4.Cu")
		(net "L5_85OHM_10INCH_DN")
	)
	(segment
		(start 325.69531 -163.816792)
		(end 326.074024 -165.964616)
		(width 0.1143)
		(layer "In4.Cu")
		(net "L5_85OHM_10INCH_DN")
	)
	(segment
		(start 322.238116 -165.304978)
		(end 321.988942 -164.972746)
		(width 0.1143)
		(layer "In4.Cu")
		(net "L5_85OHM_10INCH_DN")
	)
	(segment
		(start 373.671084 -163.810442)
		(end 374.046242 -165.937946)
		(width 0.1143)
		(layer "In4.Cu")
		(net "L5_85OHM_10INCH_DN")
	)
	(segment
		(start 337.130644 -163.487862)
		(end 336.892646 -163.82873)
		(width 0.1143)
		(layer "In4.Cu")
		(net "L5_85OHM_10INCH_DN")
	)
	(segment
		(start 337.162394 -166.015416)
		(end 336.899758 -166.061644)
		(width 0.1143)
		(layer "In4.Cu")
		(net "L5_85OHM_10INCH_DN")
	)
	(segment
		(start 341.562944 -165.960806)
		(end 341.151972 -163.632896)
		(width 0.1143)
		(layer "In4.Cu")
		(net "L5_85OHM_10INCH_DN")
	)
	(segment
		(start 333.5782 -166.03091)
		(end 333.154782 -163.625022)
		(width 0.1143)
		(layer "In4.Cu")
		(net "L5_85OHM_10INCH_DN")
	)
	(segment
		(start 382.833118 -164.20846)
		(end 382.728724 -163.614862)
		(width 0.1143)
		(layer "In4.Cu")
		(net "L5_85OHM_10INCH_DN")
	)
	(segment
		(start 372.803928 -163.390834)
		(end 372.303294 -163.478972)
		(width 0.1143)
		(layer "In4.Cu")
		(net "L5_85OHM_10INCH_DN")
	)
	(segment
		(start 381.948944 -166.070788)
		(end 381.686308 -166.11727)
		(width 0.1143)
		(layer "In4.Cu")
		(net "L5_85OHM_10INCH_DN")
	)
	(segment
		(start 322.49618 -163.812728)
		(end 322.873116 -165.948106)
		(width 0.1143)
		(layer "In4.Cu")
		(net "L5_85OHM_10INCH_DN")
	)
	(segment
		(start 329.180952 -166.101522)
		(end 328.918316 -166.148004)
		(width 0.1143)
		(layer "In4.Cu")
		(net "L5_85OHM_10INCH_DN")
	)
	(segment
		(start 334.752442 -163.61664)
		(end 334.42148 -163.385754)
		(width 0.1143)
		(layer "In4.Cu")
		(net "L5_85OHM_10INCH_DN")
	)
	(segment
		(start 367.642648 -165.905688)
		(end 367.54943 -166.038784)
		(width 0.1143)
		(layer "In4.Cu")
		(net "L5_85OHM_10INCH_DN")
	)
	(segment
		(start 339.222334 -163.40201)
		(end 338.7217 -163.489386)
		(width 0.1143)
		(layer "In4.Cu")
		(net "L5_85OHM_10INCH_DN")
	)
	(segment
		(start 359.508552 -163.479226)
		(end 359.276904 -163.810442)
		(width 0.1143)
		(layer "In4.Cu")
		(net "L5_85OHM_10INCH_DN")
	)
	(segment
		(start 346.485972 -163.821618)
		(end 346.847414 -165.87089)
		(width 0.1143)
		(layer "In4.Cu")
		(net "L5_85OHM_10INCH_DN")
	)
	(segment
		(start 324.475094 -165.963854)
		(end 324.382638 -166.096696)
		(width 0.1143)
		(layer "In4.Cu")
		(net "L5_85OHM_10INCH_DN")
	)
	(segment
		(start 333.68869 -163.804854)
		(end 334.066134 -165.944804)
		(width 0.1143)
		(layer "In4.Cu")
		(net "L5_85OHM_10INCH_DN")
	)
	(segment
		(start 319.924938 -164.767006)
		(end 319.482724 -164.767006)
		(width 0.1143)
		(layer "In4.Cu")
		(net "L5_85OHM_10INCH_DN")
	)
	(segment
		(start 328.892662 -163.808156)
		(end 329.273662 -165.969188)
		(width 0.1143)
		(layer "In4.Cu")
		(net "L5_85OHM_10INCH_DN")
	)
	(segment
		(start 366.409478 -163.40963)
		(end 365.908082 -163.497768)
		(width 0.1143)
		(layer "In4.Cu")
		(net "L5_85OHM_10INCH_DN")
	)
	(segment
		(start 356.440232 -165.863524)
		(end 356.34803 -165.996112)
		(width 0.1143)
		(layer "In4.Cu")
		(net "L5_85OHM_10INCH_DN")
	)
	(segment
		(start 385.980432 -164.143944)
		(end 385.364482 -164.759894)
		(width 0.1143)
		(layer "In4.Cu")
		(net "L5_85OHM_10INCH_DN")
	)
	(segment
		(start 378.48794 -166.112444)
		(end 378.355098 -166.019734)
		(width 0.1143)
		(layer "In4.Cu")
		(net "L5_85OHM_10INCH_DN")
	)
	(segment
		(start 326.427846 -163.397946)
		(end 325.92645 -163.48583)
		(width 0.1143)
		(layer "In4.Cu")
		(net "L5_85OHM_10INCH_DN")
	)
	(segment
		(start 359.282492 -166.033958)
		(end 359.14965 -165.941248)
		(width 0.1143)
		(layer "In4.Cu")
		(net "L5_85OHM_10INCH_DN")
	)
	(segment
		(start 350.046544 -165.8747)
		(end 349.953326 -166.007796)
		(width 0.1143)
		(layer "In4.Cu")
		(net "L5_85OHM_10INCH_DN")
	)
	(segment
		(start 359.14965 -165.941248)
		(end 358.73944 -163.613592)
		(width 0.1143)
		(layer "In4.Cu")
		(net "L5_85OHM_10INCH_DN")
	)
	(segment
		(start 330.51242 -166.119048)
		(end 330.379578 -166.02583)
		(width 0.1143)
		(layer "In4.Cu")
		(net "L5_85OHM_10INCH_DN")
	)
	(segment
		(start 351.51187 -163.473892)
		(end 351.280476 -163.80587)
		(width 0.1143)
		(layer "In4.Cu")
		(net "L5_85OHM_10INCH_DN")
	)
	(segment
		(start 360.74858 -165.941502)
		(end 360.340402 -163.622736)
		(width 0.1143)
		(layer "In4.Cu")
		(net "L5_85OHM_10INCH_DN")
	)
	(segment
		(start 364.082838 -166.054278)
		(end 363.951012 -165.962076)
		(width 0.1143)
		(layer "In4.Cu")
		(net "L5_85OHM_10INCH_DN")
	)
	(segment
		(start 321.988942 -164.972746)
		(end 321.056508 -164.676328)
		(width 0.1143)
		(layer "In4.Cu")
		(net "L5_85OHM_10INCH_DN")
	)
	(segment
		(start 327.18629 -166.055294)
		(end 326.759062 -163.629086)
		(width 0.1143)
		(layer "In4.Cu")
		(net "L5_85OHM_10INCH_DN")
	)
	(segment
		(start 340.358984 -166.007034)
		(end 340.096094 -166.053262)
		(width 0.1143)
		(layer "In4.Cu")
		(net "L5_85OHM_10INCH_DN")
	)
	(segment
		(start 382.878076 -164.385244)
		(end 382.833118 -164.20846)
		(width 0.1143)
		(layer "In4.Cu")
		(net "L5_85OHM_10INCH_DN")
	)
	(segment
		(start 340.451694 -165.874446)
		(end 340.358984 -166.007034)
		(width 0.1143)
		(layer "In4.Cu")
		(net "L5_85OHM_10INCH_DN")
	)
	(segment
		(start 364.345474 -166.007796)
		(end 364.082838 -166.054278)
		(width 0.1143)
		(layer "In4.Cu")
		(net "L5_85OHM_10INCH_DN")
	)
	(segment
		(start 343.295224 -166.058088)
		(end 343.162636 -165.965378)
		(width 0.1143)
		(layer "In4.Cu")
		(net "L5_85OHM_10INCH_DN")
	)
	(segment
		(start 359.637584 -165.855396)
		(end 359.545128 -165.98773)
		(width 0.1143)
		(layer "In4.Cu")
		(net "L5_85OHM_10INCH_DN")
	)
	(segment
		(start 354.840794 -165.85946)
		(end 354.748338 -165.991794)
		(width 0.1143)
		(layer "In4.Cu")
		(net "L5_85OHM_10INCH_DN")
	)
	(segment
		(start 338.498434 -166.061644)
		(end 338.365846 -165.969188)
		(width 0.1143)
		(layer "In4.Cu")
		(net "L5_85OHM_10INCH_DN")
	)
	(segment
		(start 364.438692 -165.8747)
		(end 364.345474 -166.007796)
		(width 0.1143)
		(layer "In4.Cu")
		(net "L5_85OHM_10INCH_DN")
	)
	(segment
		(start 332.09103 -163.813236)
		(end 332.466442 -165.940486)
		(width 0.1143)
		(layer "In4.Cu")
		(net "L5_85OHM_10INCH_DN")
	)
	(segment
		(start 382.728724 -163.614862)
		(end 382.398016 -163.383214)
		(width 0.1143)
		(layer "In4.Cu")
		(net "L5_85OHM_10INCH_DN")
	)
	(segment
		(start 349.682562 -163.81349)
		(end 350.046544 -165.8747)
		(width 0.1143)
		(layer "In4.Cu")
		(net "L5_85OHM_10INCH_DN")
	)
	(segment
		(start 321.056508 -164.676328)
		(end 319.924938 -164.767006)
		(width 0.1143)
		(layer "In4.Cu")
		(net "L5_85OHM_10INCH_DN")
	)
	(segment
		(start 376.890026 -166.120826)
		(end 376.757946 -166.02837)
		(width 0.1143)
		(layer "In4.Cu")
		(net "L5_85OHM_10INCH_DN")
	)
	(segment
		(start 327.58126 -166.101776)
		(end 327.318878 -166.14775)
		(width 0.1143)
		(layer "In4.Cu")
		(net "L5_85OHM_10INCH_DN")
	)
	(segment
		(start 335.519014 -163.473892)
		(end 335.287874 -163.804854)
		(width 0.1143)
		(layer "In4.Cu")
		(net "L5_85OHM_10INCH_DN")
	)
	(segment
		(start 336.020156 -163.385754)
		(end 335.519014 -163.473892)
		(width 0.1143)
		(layer "In4.Cu")
		(net "L5_85OHM_10INCH_DN")
	)
	(segment
		(start 332.111604 -166.119302)
		(end 331.97927 -166.026846)
		(width 0.1143)
		(layer "In4.Cu")
		(net "L5_85OHM_10INCH_DN")
	)
	(segment
		(start 354.485702 -166.037768)
		(end 354.353114 -165.945312)
		(width 0.1143)
		(layer "In4.Cu")
		(net "L5_85OHM_10INCH_DN")
	)
	(segment
		(start 338.761324 -166.015416)
		(end 338.498434 -166.061644)
		(width 0.1143)
		(layer "In4.Cu")
		(net "L5_85OHM_10INCH_DN")
	)
	(segment
		(start 358.03967 -165.863778)
		(end 357.947214 -165.996112)
		(width 0.1143)
		(layer "In4.Cu")
		(net "L5_85OHM_10INCH_DN")
	)
	(segment
		(start 353.611434 -163.386262)
		(end 353.1108 -163.4744)
		(width 0.1143)
		(layer "In4.Cu")
		(net "L5_85OHM_10INCH_DN")
	)
	(segment
		(start 341.151972 -163.632896)
		(end 340.821264 -163.401756)
		(width 0.1143)
		(layer "In4.Cu")
		(net "L5_85OHM_10INCH_DN")
	)
	(segment
		(start 357.684578 -166.04234)
		(end 357.552498 -165.949884)
		(width 0.1143)
		(layer "In4.Cu")
		(net "L5_85OHM_10INCH_DN")
	)
	(segment
		(start 352.344228 -163.617402)
		(end 352.012504 -163.386516)
		(width 0.1143)
		(layer "In4.Cu")
		(net "L5_85OHM_10INCH_DN")
	)
	(segment
		(start 333.973424 -166.0779)
		(end 333.711296 -166.12362)
		(width 0.1143)
		(layer "In4.Cu")
		(net "L5_85OHM_10INCH_DN")
	)
	(segment
		(start 384.91033 -164.759894)
		(end 383.82448 -164.846762)
		(width 0.1143)
		(layer "In4.Cu")
		(net "L5_85OHM_10INCH_DN")
	)
	(segment
		(start 380.294134 -163.455604)
		(end 380.063248 -163.787074)
		(width 0.1143)
		(layer "In4.Cu")
		(net "L5_85OHM_10INCH_DN")
	)
	(segment
		(start 362.48086 -166.038784)
		(end 362.349034 -165.946582)
		(width 0.1143)
		(layer "In4.Cu")
		(net "L5_85OHM_10INCH_DN")
	)
	(segment
		(start 355.542088 -163.618672)
		(end 355.211126 -163.386516)
		(width 0.1143)
		(layer "In4.Cu")
		(net "L5_85OHM_10INCH_DN")
	)
	(segment
		(start 375.26468 -163.781232)
		(end 375.64568 -165.94201)
		(width 0.1143)
		(layer "In4.Cu")
		(net "L5_85OHM_10INCH_DN")
	)
	(segment
		(start 344.762328 -165.965378)
		(end 344.346784 -163.610036)
		(width 0.1143)
		(layer "In4.Cu")
		(net "L5_85OHM_10INCH_DN")
	)
	(segment
		(start 343.282778 -163.796472)
		(end 343.650062 -165.879018)
		(width 0.1143)
		(layer "In4.Cu")
		(net "L5_85OHM_10INCH_DN")
	)
	(segment
		(start 356.308152 -163.470844)
		(end 356.076504 -163.801298)
		(width 0.1143)
		(layer "In4.Cu")
		(net "L5_85OHM_10INCH_DN")
	)
	(segment
		(start 357.908352 -163.470336)
		(end 357.675942 -163.800536)
		(width 0.1143)
		(layer "In4.Cu")
		(net "L5_85OHM_10INCH_DN")
	)
	(segment
		(start 328.35596 -163.620704)
		(end 328.02576 -163.38931)
		(width 0.1143)
		(layer "In4.Cu")
		(net "L5_85OHM_10INCH_DN")
	)
	(segment
		(start 343.55786 -166.011606)
		(end 343.295224 -166.058088)
		(width 0.1143)
		(layer "In4.Cu")
		(net "L5_85OHM_10INCH_DN")
	)
	(segment
		(start 372.0719 -163.810188)
		(end 372.447312 -165.937438)
		(width 0.1143)
		(layer "In4.Cu")
		(net "L5_85OHM_10INCH_DN")
	)
	(segment
		(start 378.355098 -166.019734)
		(end 377.927616 -163.593526)
		(width 0.1143)
		(layer "In4.Cu")
		(net "L5_85OHM_10INCH_DN")
	)
	(segment
		(start 349.913956 -163.482274)
		(end 349.682562 -163.81349)
		(width 0.1143)
		(layer "In4.Cu")
		(net "L5_85OHM_10INCH_DN")
	)
	(segment
		(start 360.340402 -163.622736)
		(end 360.00944 -163.391596)
		(width 0.1143)
		(layer "In4.Cu")
		(net "L5_85OHM_10INCH_DN")
	)
	(segment
		(start 335.663032 -165.932866)
		(end 335.563718 -166.075106)
		(width 0.1143)
		(layer "In4.Cu")
		(net "L5_85OHM_10INCH_DN")
	)
	(segment
		(start 366.04067 -165.890194)
		(end 365.947452 -166.02329)
		(width 0.1143)
		(layer "In4.Cu")
		(net "L5_85OHM_10INCH_DN")
	)
	(segment
		(start 337.615276 -163.402772)
		(end 337.130644 -163.487862)
		(width 0.1143)
		(layer "In4.Cu")
		(net "L5_85OHM_10INCH_DN")
	)
	(segment
		(start 323.559424 -163.624006)
		(end 323.229224 -163.392866)
		(width 0.1143)
		(layer "In4.Cu")
		(net "L5_85OHM_10INCH_DN")
	)
	(segment
		(start 338.365846 -165.969188)
		(end 337.955636 -163.641278)
		(width 0.1143)
		(layer "In4.Cu")
		(net "L5_85OHM_10INCH_DN")
	)
	(segment
		(start 357.675942 -163.800536)
		(end 358.03967 -165.863778)
		(width 0.1143)
		(layer "In4.Cu")
		(net "L5_85OHM_10INCH_DN")
	)
	(segment
		(start 345.118182 -163.48583)
		(end 344.885772 -163.81603)
		(width 0.1143)
		(layer "In4.Cu")
		(net "L5_85OHM_10INCH_DN")
	)
	(segment
		(start 358.408478 -163.382706)
		(end 357.908352 -163.470336)
		(width 0.1143)
		(layer "In4.Cu")
		(net "L5_85OHM_10INCH_DN")
	)
	(segment
		(start 345.94927 -163.629086)
		(end 345.618308 -163.3982)
		(width 0.1143)
		(layer "In4.Cu")
		(net "L5_85OHM_10INCH_DN")
	)
	(segment
		(start 368.761772 -166.030402)
		(end 368.34191 -163.656518)
		(width 0.1143)
		(layer "In4.Cu")
		(net "L5_85OHM_10INCH_DN")
	)
	(segment
		(start 374.40362 -163.391088)
		(end 373.902224 -163.478972)
		(width 0.1143)
		(layer "In4.Cu")
		(net "L5_85OHM_10INCH_DN")
	)
	(segment
		(start 369.9383 -163.630356)
		(end 369.59794 -163.39185)
		(width 0.1143)
		(layer "In4.Cu")
		(net "L5_85OHM_10INCH_DN")
	)
	(segment
		(start 356.809548 -163.382198)
		(end 356.308152 -163.470844)
		(width 0.1143)
		(layer "In4.Cu")
		(net "L5_85OHM_10INCH_DN")
	)
	(segment
		(start 360.875072 -163.806886)
		(end 361.236768 -165.85565)
		(width 0.1143)
		(layer "In4.Cu")
		(net "L5_85OHM_10INCH_DN")
	)
	(segment
		(start 364.07979 -163.842446)
		(end 364.438692 -165.8747)
		(width 0.1143)
		(layer "In4.Cu")
		(net "L5_85OHM_10INCH_DN")
	)
	(segment
		(start 375.290842 -166.12108)
		(end 375.158254 -166.02837)
		(width 0.1143)
		(layer "In4.Cu")
		(net "L5_85OHM_10INCH_DN")
	)
	(segment
		(start 340.089236 -163.82111)
		(end 340.451694 -165.874446)
		(width 0.1143)
		(layer "In4.Cu")
		(net "L5_85OHM_10INCH_DN")
	)
	(segment
		(start 342.751918 -163.634166)
		(end 342.420956 -163.40201)
		(width 0.1143)
		(layer "In4.Cu")
		(net "L5_85OHM_10INCH_DN")
	)
	(segment
		(start 361.93857 -163.619434)
		(end 361.607354 -163.387278)
		(width 0.1143)
		(layer "In4.Cu")
		(net "L5_85OHM_10INCH_DN")
	)
	(segment
		(start 333.154782 -163.625022)
		(end 332.82382 -163.394136)
		(width 0.1143)
		(layer "In4.Cu")
		(net "L5_85OHM_10INCH_DN")
	)
	(segment
		(start 329.955652 -163.62045)
		(end 329.62469 -163.38931)
		(width 0.1143)
		(layer "In4.Cu")
		(net "L5_85OHM_10INCH_DN")
	)
	(segment
		(start 335.563718 -166.075106)
		(end 335.317846 -166.118286)
		(width 0.1143)
		(layer "In4.Cu")
		(net "L5_85OHM_10INCH_DN")
	)
	(segment
		(start 353.1108 -163.4744)
		(end 352.879406 -163.805616)
		(width 0.1143)
		(layer "In4.Cu")
		(net "L5_85OHM_10INCH_DN")
	)
	(segment
		(start 370.849652 -165.94582)
		(end 370.756942 -166.078408)
		(width 0.1143)
		(layer "In4.Cu")
		(net "L5_85OHM_10INCH_DN")
	)
	(segment
		(start 368.34191 -163.656518)
		(end 368.011456 -163.425124)
		(width 0.1143)
		(layer "In4.Cu")
		(net "L5_85OHM_10INCH_DN")
	)
	(segment
		(start 332.322424 -163.48202)
		(end 332.09103 -163.813236)
		(width 0.1143)
		(layer "In4.Cu")
		(net "L5_85OHM_10INCH_DN")
	)
	(segment
		(start 372.303294 -163.478972)
		(end 372.0719 -163.810188)
		(width 0.1143)
		(layer "In4.Cu")
		(net "L5_85OHM_10INCH_DN")
	)
	(segment
		(start 378.843032 -165.933882)
		(end 378.750576 -166.066216)
		(width 0.1143)
		(layer "In4.Cu")
		(net "L5_85OHM_10INCH_DN")
	)
	(segment
		(start 324.096126 -163.816538)
		(end 324.475094 -165.963854)
		(width 0.1143)
		(layer "In4.Cu")
		(net "L5_85OHM_10INCH_DN")
	)
	(segment
		(start 365.143288 -163.65474)
		(end 364.81258 -163.423092)
		(width 0.1143)
		(layer "In4.Cu")
		(net "L5_85OHM_10INCH_DN")
	)
	(segment
		(start 381.686308 -166.11727)
		(end 381.554482 -166.025068)
		(width 0.1143)
		(layer "In4.Cu")
		(net "L5_85OHM_10INCH_DN")
	)
	(segment
		(start 366.740186 -163.641278)
		(end 366.409478 -163.40963)
		(width 0.1143)
		(layer "In4.Cu")
		(net "L5_85OHM_10INCH_DN")
	)
	(segment
		(start 348.354142 -166.003478)
		(end 348.091252 -166.049706)
		(width 0.1143)
		(layer "In4.Cu")
		(net "L5_85OHM_10INCH_DN")
	)
	(segment
		(start 340.821264 -163.401756)
		(end 340.32063 -163.489894)
		(width 0.1143)
		(layer "In4.Cu")
		(net "L5_85OHM_10INCH_DN")
	)
	(segment
		(start 370.703602 -163.474146)
		(end 370.472208 -163.806124)
		(width 0.1143)
		(layer "In4.Cu")
		(net "L5_85OHM_10INCH_DN")
	)
	(segment
		(start 356.076504 -163.801298)
		(end 356.440232 -165.863524)
		(width 0.1143)
		(layer "In4.Cu")
		(net "L5_85OHM_10INCH_DN")
	)
	(segment
		(start 372.091712 -166.116254)
		(end 371.959124 -166.023798)
		(width 0.1143)
		(layer "In4.Cu")
		(net "L5_85OHM_10INCH_DN")
	)
	(segment
		(start 340.096094 -166.053262)
		(end 339.963506 -165.960806)
		(width 0.1143)
		(layer "In4.Cu")
		(net "L5_85OHM_10INCH_DN")
	)
	(segment
		(start 381.126746 -163.599368)
		(end 380.79553 -163.367212)
		(width 0.1143)
		(layer "In4.Cu")
		(net "L5_85OHM_10INCH_DN")
	)
	(segment
		(start 371.53596 -163.617656)
		(end 371.204236 -163.38677)
		(width 0.1143)
		(layer "In4.Cu")
		(net "L5_85OHM_10INCH_DN")
	)
	(segment
		(start 348.091252 -166.049706)
		(end 347.95841 -165.956996)
		(width 0.1143)
		(layer "In4.Cu")
		(net "L5_85OHM_10INCH_DN")
	)
	(segment
		(start 351.156016 -165.953694)
		(end 350.745806 -163.625784)
		(width 0.1143)
		(layer "In4.Cu")
		(net "L5_85OHM_10INCH_DN")
	)
	(segment
		(start 335.175606 -166.018718)
		(end 334.752442 -163.61664)
		(width 0.1143)
		(layer "In4.Cu")
		(net "L5_85OHM_10INCH_DN")
	)
	(segment
		(start 382.042162 -165.937692)
		(end 381.948944 -166.070788)
		(width 0.1143)
		(layer "In4.Cu")
		(net "L5_85OHM_10INCH_DN")
	)
	(segment
		(start 381.554482 -166.025068)
		(end 381.126746 -163.599368)
		(width 0.1143)
		(layer "In4.Cu")
		(net "L5_85OHM_10INCH_DN")
	)
	(segment
		(start 346.71762 -163.490402)
		(end 346.485972 -163.821618)
		(width 0.1143)
		(layer "In4.Cu")
		(net "L5_85OHM_10INCH_DN")
	)
	(segment
		(start 361.607354 -163.387278)
		(end 361.105958 -163.47567)
		(width 0.1143)
		(layer "In4.Cu")
		(net "L5_85OHM_10INCH_DN")
	)
	(segment
		(start 354.353114 -165.945312)
		(end 353.942142 -163.617402)
		(width 0.1143)
		(layer "In4.Cu")
		(net "L5_85OHM_10INCH_DN")
	)
	(segment
		(start 356.34803 -165.996112)
		(end 356.085394 -166.042594)
		(width 0.1143)
		(layer "In4.Cu")
		(net "L5_85OHM_10INCH_DN")
	)
	(segment
		(start 361.236768 -165.85565)
		(end 361.144312 -165.987984)
		(width 0.1143)
		(layer "In4.Cu")
		(net "L5_85OHM_10INCH_DN")
	)
	(segment
		(start 341.695532 -166.053262)
		(end 341.562944 -165.960806)
		(width 0.1143)
		(layer "In4.Cu")
		(net "L5_85OHM_10INCH_DN")
	)
	(segment
		(start 380.08687 -166.112698)
		(end 379.954028 -166.019988)
		(width 0.1143)
		(layer "In4.Cu")
		(net "L5_85OHM_10INCH_DN")
	)
	(segment
		(start 333.711296 -166.12362)
		(end 333.5782 -166.03091)
		(width 0.1143)
		(layer "In4.Cu")
		(net "L5_85OHM_10INCH_DN")
	)
	(segment
		(start 372.447312 -165.937438)
		(end 372.354602 -166.070026)
		(width 0.1143)
		(layer "In4.Cu")
		(net "L5_85OHM_10INCH_DN")
	)
	(segment
		(start 378.464318 -163.786058)
		(end 378.843032 -165.933882)
		(width 0.1143)
		(layer "In4.Cu")
		(net "L5_85OHM_10INCH_DN")
	)
	(segment
		(start 326.074024 -165.964616)
		(end 325.981314 -166.097204)
		(width 0.1143)
		(layer "In4.Cu")
		(net "L5_85OHM_10INCH_DN")
	)
	(segment
		(start 352.012504 -163.386516)
		(end 351.51187 -163.473892)
		(width 0.1143)
		(layer "In4.Cu")
		(net "L5_85OHM_10INCH_DN")
	)
	(segment
		(start 381.665226 -163.802568)
		(end 382.042162 -165.937692)
		(width 0.1143)
		(layer "In4.Cu")
		(net "L5_85OHM_10INCH_DN")
	)
	(segment
		(start 324.327266 -163.485576)
		(end 324.096126 -163.816538)
		(width 0.1143)
		(layer "In4.Cu")
		(net "L5_85OHM_10INCH_DN")
	)
	(segment
		(start 369.250214 -165.944804)
		(end 369.157758 -166.077646)
		(width 0.1143)
		(layer "In4.Cu")
		(net "L5_85OHM_10INCH_DN")
	)
	(segment
		(start 322.728082 -163.481512)
		(end 322.49618 -163.812728)
		(width 0.1143)
		(layer "In4.Cu")
		(net "L5_85OHM_10INCH_DN")
	)
	(segment
		(start 380.063248 -163.787074)
		(end 380.442216 -165.934136)
		(width 0.1143)
		(layer "In4.Cu")
		(net "L5_85OHM_10INCH_DN")
	)
	(segment
		(start 325.981314 -166.097204)
		(end 325.718932 -166.143178)
		(width 0.1143)
		(layer "In4.Cu")
		(net "L5_85OHM_10INCH_DN")
	)
	(segment
		(start 358.73944 -163.613592)
		(end 358.408478 -163.382706)
		(width 0.1143)
		(layer "In4.Cu")
		(net "L5_85OHM_10INCH_DN")
	)
	(segment
		(start 365.55299 -165.97757)
		(end 365.143288 -163.65474)
		(width 0.1143)
		(layer "In4.Cu")
		(net "L5_85OHM_10INCH_DN")
	)
	(segment
		(start 327.674224 -165.969696)
		(end 327.58126 -166.101776)
		(width 0.1143)
		(layer "In4.Cu")
		(net "L5_85OHM_10INCH_DN")
	)
	(segment
		(start 378.750576 -166.066216)
		(end 378.48794 -166.112444)
		(width 0.1143)
		(layer "In4.Cu")
		(net "L5_85OHM_10INCH_DN")
	)
	(segment
		(start 347.218508 -163.402772)
		(end 346.71762 -163.490402)
		(width 0.1143)
		(layer "In4.Cu")
		(net "L5_85OHM_10INCH_DN")
	)
	(segment
		(start 355.211126 -163.386516)
		(end 354.70973 -163.4744)
		(width 0.1143)
		(layer "In4.Cu")
		(net "L5_85OHM_10INCH_DN")
	)
	(segment
		(start 370.756942 -166.078408)
		(end 370.494052 -166.124636)
		(width 0.1143)
		(layer "In4.Cu")
		(net "L5_85OHM_10INCH_DN")
	)
	(segment
		(start 378.695966 -163.454842)
		(end 378.464318 -163.786058)
		(width 0.1143)
		(layer "In4.Cu")
		(net "L5_85OHM_10INCH_DN")
	)
	(segment
		(start 322.873116 -165.948106)
		(end 322.780406 -166.080694)
		(width 0.1143)
		(layer "In4.Cu")
		(net "L5_85OHM_10INCH_DN")
	)
	(segment
		(start 377.245118 -165.942264)
		(end 377.152662 -166.074598)
		(width 0.1143)
		(layer "In4.Cu")
		(net "L5_85OHM_10INCH_DN")
	)
	(segment
		(start 381.89662 -163.471352)
		(end 381.665226 -163.802568)
		(width 0.1143)
		(layer "In4.Cu")
		(net "L5_85OHM_10INCH_DN")
	)
	(segment
		(start 336.76717 -165.968934)
		(end 336.351118 -163.616894)
		(width 0.1143)
		(layer "In4.Cu")
		(net "L5_85OHM_10INCH_DN")
	)
	(segment
		(start 373.953786 -166.07028)
		(end 373.69115 -166.116254)
		(width 0.1143)
		(layer "In4.Cu")
		(net "L5_85OHM_10INCH_DN")
	)
	(segment
		(start 348.817184 -163.402772)
		(end 348.315788 -163.491164)
		(width 0.1143)
		(layer "In4.Cu")
		(net "L5_85OHM_10INCH_DN")
	)
	(segment
		(start 354.47859 -163.80587)
		(end 354.840794 -165.85946)
		(width 0.1143)
		(layer "In4.Cu")
		(net "L5_85OHM_10INCH_DN")
	)
	(segment
		(start 367.51006 -163.513262)
		(end 367.278666 -163.844478)
		(width 0.1143)
		(layer "In4.Cu")
		(net "L5_85OHM_10INCH_DN")
	)
	(segment
		(start 322.780406 -166.080694)
		(end 322.51777 -166.126922)
		(width 0.1143)
		(layer "In4.Cu")
		(net "L5_85OHM_10INCH_DN")
	)
	(segment
		(start 362.743496 -165.992302)
		(end 362.48086 -166.038784)
		(width 0.1143)
		(layer "In4.Cu")
		(net "L5_85OHM_10INCH_DN")
	)
	(segment
		(start 350.745806 -163.625784)
		(end 350.415352 -163.394136)
		(width 0.1143)
		(layer "In4.Cu")
		(net "L5_85OHM_10INCH_DN")
	)
	(segment
		(start 362.708444 -163.491418)
		(end 362.47705 -163.82238)
		(width 0.1143)
		(layer "In4.Cu")
		(net "L5_85OHM_10INCH_DN")
	)
	(segment
		(start 330.774802 -166.073074)
		(end 330.51242 -166.119048)
		(width 0.1143)
		(layer "In4.Cu")
		(net "L5_85OHM_10INCH_DN")
	)
	(segment
		(start 362.349034 -165.946582)
		(end 361.93857 -163.619434)
		(width 0.1143)
		(layer "In4.Cu")
		(net "L5_85OHM_10INCH_DN")
	)
	(segment
		(start 352.879406 -163.805616)
		(end 353.241864 -165.858952)
		(width 0.1143)
		(layer "In4.Cu")
		(net "L5_85OHM_10INCH_DN")
	)
	(segment
		(start 344.885772 -163.81603)
		(end 345.2495 -165.879272)
		(width 0.1143)
		(layer "In4.Cu")
		(net "L5_85OHM_10INCH_DN")
	)
	(segment
		(start 349.69069 -166.054278)
		(end 349.558864 -165.962076)
		(width 0.1143)
		(layer "In4.Cu")
		(net "L5_85OHM_10INCH_DN")
	)
	(segment
		(start 374.046242 -165.937946)
		(end 373.953786 -166.07028)
		(width 0.1143)
		(layer "In4.Cu")
		(net "L5_85OHM_10INCH_DN")
	)
	(segment
		(start 374.734582 -163.623244)
		(end 374.40362 -163.391088)
		(width 0.1143)
		(layer "In4.Cu")
		(net "L5_85OHM_10INCH_DN")
	)
	(segment
		(start 363.20984 -163.40328)
		(end 362.708444 -163.491418)
		(width 0.1143)
		(layer "In4.Cu")
		(net "L5_85OHM_10INCH_DN")
	)
	(segment
		(start 325.718932 -166.143178)
		(end 325.586344 -166.050468)
		(width 0.1143)
		(layer "In4.Cu")
		(net "L5_85OHM_10INCH_DN")
	)
	(segment
		(start 357.552498 -165.949884)
		(end 357.140764 -163.614862)
		(width 0.1143)
		(layer "In4.Cu")
		(net "L5_85OHM_10INCH_DN")
	)
	(segment
		(start 368.011456 -163.425124)
		(end 367.51006 -163.513262)
		(width 0.1143)
		(layer "In4.Cu")
		(net "L5_85OHM_10INCH_DN")
	)
	(segment
		(start 375.496328 -163.450778)
		(end 375.26468 -163.781232)
		(width 0.1143)
		(layer "In4.Cu")
		(net "L5_85OHM_10INCH_DN")
	)
	(segment
		(start 148.22424 12.04976)
		(end 197.401688 12.04976)
		(width 0.14224)
		(layer "In4.Cu")
		(net "L5_73OHM_6INCH_DP")
	)
	(segment
		(start 197.401688 12.7254)
		(end 146.42592 12.7254)
		(width 0.14224)
		(layer "In4.Cu")
		(net "L5_73OHM_6INCH_DP")
	)
	(segment
		(start 129.975864 11.879834)
		(end 128.840484 10.744454)
		(width 0.14224)
		(layer "In4.Cu")
		(net "L5_73OHM_6INCH_DP")
	)
	(segment
		(start 197.502526 10.83564)
		(end 148.22424 10.83564)
		(width 0.14224)
		(layer "In4.Cu")
		(net "L5_73OHM_6INCH_DP")
	)
	(segment
		(start 146.42592 12.7254)
		(end 145.580354 11.879834)
		(width 0.14224)
		(layer "In4.Cu")
		(net "L5_73OHM_6INCH_DP")
	)
	(segment
		(start 145.580354 11.879834)
		(end 129.975864 11.879834)
		(width 0.14224)
		(layer "In4.Cu")
		(net "L5_73OHM_6INCH_DP")
	)
	(arc
		(start 148.22424 10.83564)
		(mid 147.61718 11.4427)
		(end 148.22424 12.04976)
		(width 0.14224)
		(layer "In4.Cu")
		(net "L5_73OHM_6INCH_DP")
	)
	(arc
		(start 197.401688 12.04976)
		(mid 197.739508 12.38758)
		(end 197.401688 12.7254)
		(width 0.14224)
		(layer "In4.Cu")
		(net "L5_73OHM_6INCH_DP")
	)
	(segment
		(start 197.401688 12.99464)
		(end 146.31416 12.99464)
		(width 0.14224)
		(layer "In4.Cu")
		(net "L5_73OHM_6INCH_DN")
	)
	(segment
		(start 197.502526 11.10488)
		(end 148.22424 11.10488)
		(width 0.14224)
		(layer "In4.Cu")
		(net "L5_73OHM_6INCH_DN")
	)
	(segment
		(start 148.22424 11.78052)
		(end 197.401688 11.78052)
		(width 0.14224)
		(layer "In4.Cu")
		(net "L5_73OHM_6INCH_DN")
	)
	(segment
		(start 129.975864 12.149074)
		(end 128.840484 13.284454)
		(width 0.14224)
		(layer "In4.Cu")
		(net "L5_73OHM_6INCH_DN")
	)
	(segment
		(start 145.468594 12.149074)
		(end 129.975864 12.149074)
		(width 0.14224)
		(layer "In4.Cu")
		(net "L5_73OHM_6INCH_DN")
	)
	(segment
		(start 146.31416 12.99464)
		(end 145.468594 12.149074)
		(width 0.14224)
		(layer "In4.Cu")
		(net "L5_73OHM_6INCH_DN")
	)
	(arc
		(start 197.401688 11.78052)
		(mid 198.008748 12.38758)
		(end 197.401688 12.99464)
		(width 0.14224)
		(layer "In4.Cu")
		(net "L5_73OHM_6INCH_DN")
	)
	(arc
		(start 148.22424 11.10488)
		(mid 147.88642 11.4427)
		(end 148.22424 11.78052)
		(width 0.14224)
		(layer "In4.Cu")
		(net "L5_73OHM_6INCH_DN")
	)
	(segment
		(start 36.83762 14.2748)
		(end 21.4503 14.2748)
		(width 0.089408)
		(layer "In4.Cu")
		(net "L5_50OHM_6INCH")
	)
	(segment
		(start 37.435028 13.677392)
		(end 36.83762 14.2748)
		(width 0.089408)
		(layer "In4.Cu")
		(net "L5_50OHM_6INCH")
	)
	(segment
		(start 113.159286 13.677392)
		(end 37.435028 13.677392)
		(width 0.089408)
		(layer "In4.Cu")
		(net "L5_50OHM_6INCH")
	)
	(segment
		(start 21.4503 14.2748)
		(end 20.447 13.2715)
		(width 0.089408)
		(layer "In4.Cu")
		(net "L5_50OHM_6INCH")
	)
	(segment
		(start 37.820854 12.825984)
		(end 113.159286 12.825984)
		(width 0.089408)
		(layer "In4.Cu")
		(net "L5_50OHM_6INCH")
	)
	(arc
		(start 113.159286 12.825984)
		(mid 113.58499 13.251688)
		(end 113.159286 13.677392)
		(width 0.089408)
		(layer "In4.Cu")
		(net "L5_50OHM_6INCH")
	)
	(segment
		(start 36.97859 11.66241)
		(end 36.6268 12.0142)
		(width 0.14224)
		(layer "In4.Cu")
		(net "L5_40OHM_6INCH")
	)
	(segment
		(start 36.6268 12.0142)
		(end 21.7297 12.0142)
		(width 0.14224)
		(layer "In4.Cu")
		(net "L5_40OHM_6INCH")
	)
	(segment
		(start 37.159946 10.75817)
		(end 112.559084 10.75817)
		(width 0.14224)
		(layer "In4.Cu")
		(net "L5_40OHM_6INCH")
	)
	(segment
		(start 21.7297 12.0142)
		(end 20.447 10.7315)
		(width 0.14224)
		(layer "In4.Cu")
		(net "L5_40OHM_6INCH")
	)
	(segment
		(start 112.559084 11.66241)
		(end 36.97859 11.66241)
		(width 0.14224)
		(layer "In4.Cu")
		(net "L5_40OHM_6INCH")
	)
	(arc
		(start 112.559084 10.75817)
		(mid 113.011204 11.21029)
		(end 112.559084 11.66241)
		(width 0.14224)
		(layer "In4.Cu")
		(net "L5_40OHM_6INCH")
	)
	(segment
		(start 297.474132 12.30122)
		(end 346.312998 12.30122)
		(width 0.11684)
		(layer "F.Cu")
		(net "L1_95OHM_6INCH_DP")
	)
	(segment
		(start 295.040558 11.78052)
		(end 289.478212 11.78052)
		(width 0.11684)
		(layer "F.Cu")
		(net "L1_95OHM_6INCH_DP")
	)
	(segment
		(start 289.478212 11.78052)
		(end 288.438082 10.74039)
		(width 0.11684)
		(layer "F.Cu")
		(net "L1_95OHM_6INCH_DP")
	)
	(segment
		(start 346.79382 10.4267)
		(end 297.474132 10.4267)
		(width 0.11684)
		(layer "F.Cu")
		(net "L1_95OHM_6INCH_DP")
	)
	(segment
		(start 346.312998 13.25626)
		(end 296.516298 13.25626)
		(width 0.11684)
		(layer "F.Cu")
		(net "L1_95OHM_6INCH_DP")
	)
	(segment
		(start 296.516298 13.25626)
		(end 295.040558 11.78052)
		(width 0.11684)
		(layer "F.Cu")
		(net "L1_95OHM_6INCH_DP")
	)
	(arc
		(start 297.474132 10.4267)
		(mid 296.536872 11.36396)
		(end 297.474132 12.30122)
		(width 0.11684)
		(layer "F.Cu")
		(net "L1_95OHM_6INCH_DP")
	)
	(arc
		(start 346.312998 12.30122)
		(mid 346.790518 12.77874)
		(end 346.312998 13.25626)
		(width 0.11684)
		(layer "F.Cu")
		(net "L1_95OHM_6INCH_DP")
	)
	(segment
		(start 296.325798 13.716)
		(end 294.850058 12.24026)
		(width 0.11684)
		(layer "F.Cu")
		(net "L1_95OHM_6INCH_DN")
	)
	(segment
		(start 346.79382 10.88644)
		(end 297.474132 10.88644)
		(width 0.11684)
		(layer "F.Cu")
		(net "L1_95OHM_6INCH_DN")
	)
	(segment
		(start 346.312998 13.716)
		(end 296.325798 13.716)
		(width 0.11684)
		(layer "F.Cu")
		(net "L1_95OHM_6INCH_DN")
	)
	(segment
		(start 297.474132 11.84148)
		(end 346.312998 11.84148)
		(width 0.11684)
		(layer "F.Cu")
		(net "L1_95OHM_6INCH_DN")
	)
	(segment
		(start 289.478212 12.24026)
		(end 288.438082 13.28039)
		(width 0.11684)
		(layer "F.Cu")
		(net "L1_95OHM_6INCH_DN")
	)
	(segment
		(start 294.850058 12.24026)
		(end 289.478212 12.24026)
		(width 0.11684)
		(layer "F.Cu")
		(net "L1_95OHM_6INCH_DN")
	)
	(arc
		(start 346.312998 11.84148)
		(mid 347.250258 12.77874)
		(end 346.312998 13.716)
		(width 0.11684)
		(layer "F.Cu")
		(net "L1_95OHM_6INCH_DN")
	)
	(arc
		(start 297.474132 10.88644)
		(mid 296.996612 11.36396)
		(end 297.474132 11.84148)
		(width 0.11684)
		(layer "F.Cu")
		(net "L1_95OHM_6INCH_DN")
	)
	(segment
		(start 230.221028 11.806428)
		(end 209.145886 11.806428)
		(width 0.1143)
		(layer "In2.Cu")
		(net "L3_85OHM_6INCH_DP")
	)
	(segment
		(start 281.722068 10.8077)
		(end 232.283 10.8077)
		(width 0.1143)
		(layer "In2.Cu")
		(net "L3_85OHM_6INCH_DP")
	)
	(segment
		(start 232.283 12.0396)
		(end 281.696668 12.0396)
		(width 0.1143)
		(layer "In2.Cu")
		(net "L3_85OHM_6INCH_DP")
	)
	(segment
		(start 231.1019 12.6873)
		(end 230.221028 11.806428)
		(width 0.1143)
		(layer "In2.Cu")
		(net "L3_85OHM_6INCH_DP")
	)
	(segment
		(start 281.696668 12.6873)
		(end 231.1019 12.6873)
		(width 0.1143)
		(layer "In2.Cu")
		(net "L3_85OHM_6INCH_DP")
	)
	(segment
		(start 209.145886 11.806428)
		(end 208.021936 10.682478)
		(width 0.1143)
		(layer "In2.Cu")
		(net "L3_85OHM_6INCH_DP")
	)
	(arc
		(start 232.283 10.8077)
		(mid 231.66705 11.42365)
		(end 232.283 12.0396)
		(width 0.1143)
		(layer "In2.Cu")
		(net "L3_85OHM_6INCH_DP")
	)
	(arc
		(start 281.696668 12.0396)
		(mid 282.020518 12.36345)
		(end 281.696668 12.6873)
		(width 0.1143)
		(layer "In2.Cu")
		(net "L3_85OHM_6INCH_DP")
	)
	(segment
		(start 281.722068 11.0998)
		(end 232.283 11.0998)
		(width 0.1143)
		(layer "In2.Cu")
		(net "L3_85OHM_6INCH_DN")
	)
	(segment
		(start 281.696668 12.9794)
		(end 230.980742 12.9794)
		(width 0.1143)
		(layer "In2.Cu")
		(net "L3_85OHM_6INCH_DN")
	)
	(segment
		(start 232.283 11.7475)
		(end 281.696668 11.7475)
		(width 0.1143)
		(layer "In2.Cu")
		(net "L3_85OHM_6INCH_DN")
	)
	(segment
		(start 209.145886 12.098528)
		(end 208.021936 13.222478)
		(width 0.1143)
		(layer "In2.Cu")
		(net "L3_85OHM_6INCH_DN")
	)
	(segment
		(start 230.980742 12.9794)
		(end 230.09987 12.098528)
		(width 0.1143)
		(layer "In2.Cu")
		(net "L3_85OHM_6INCH_DN")
	)
	(segment
		(start 230.09987 12.098528)
		(end 209.145886 12.098528)
		(width 0.1143)
		(layer "In2.Cu")
		(net "L3_85OHM_6INCH_DN")
	)
	(arc
		(start 232.283 11.0998)
		(mid 231.95915 11.42365)
		(end 232.283 11.7475)
		(width 0.1143)
		(layer "In2.Cu")
		(net "L3_85OHM_6INCH_DN")
	)
	(arc
		(start 281.696668 11.7475)
		(mid 282.312618 12.36345)
		(end 281.696668 12.9794)
		(width 0.1143)
		(layer "In2.Cu")
		(net "L3_85OHM_6INCH_DN")
	)
	(via
		(at 66.32575 -165.807136)
		(size 0.5588)
		(drill 0.3048)
		(layers "F.Cu" "B.Cu")
		(net "L3_85OHM_5INCH_DP")
	)
	(via
		(at 96.408494 -165.737032)
		(size 0.5588)
		(drill 0.3048)
		(layers "F.Cu" "B.Cu")
		(net "L3_85OHM_5INCH_DP")
	)
	(segment
		(start 100.14712 -165.489636)
		(end 99.778566 -165.121082)
		(width 0.1143)
		(layer "B.Cu")
		(net "L3_85OHM_5INCH_DP")
	)
	(segment
		(start 97.024444 -165.121082)
		(end 96.408494 -165.737032)
		(width 0.1143)
		(layer "B.Cu")
		(net "L3_85OHM_5INCH_DP")
	)
	(segment
		(start 65.7098 -165.191186)
		(end 66.32575 -165.807136)
		(width 0.1143)
		(layer "B.Cu")
		(net "L3_85OHM_5INCH_DP")
	)
	(segment
		(start 62.934342 -165.191186)
		(end 65.7098 -165.191186)
		(width 0.1143)
		(layer "B.Cu")
		(net "L3_85OHM_5INCH_DP")
	)
	(segment
		(start 99.778566 -165.121082)
		(end 97.024444 -165.121082)
		(width 0.1143)
		(layer "B.Cu")
		(net "L3_85OHM_5INCH_DP")
	)
	(segment
		(start 62.587124 -165.538404)
		(end 62.934342 -165.191186)
		(width 0.1143)
		(layer "B.Cu")
		(net "L3_85OHM_5INCH_DP")
	)
	(segment
		(start 66.43751 -165.193726)
		(end 66.558922 -165.193726)
		(width 0.1143)
		(layer "In2.Cu")
		(net "L3_85OHM_5INCH_DP")
	)
	(segment
		(start 82.129884 -163.955222)
		(end 82.229198 -163.812982)
		(width 0.1143)
		(layer "In2.Cu")
		(net "L3_85OHM_5INCH_DP")
	)
	(segment
		(start 67.060064 -166.336218)
		(end 67.390518 -166.567866)
		(width 0.1143)
		(layer "In2.Cu")
		(net "L3_85OHM_5INCH_DP")
	)
	(segment
		(start 85.326474 -163.947602)
		(end 85.419184 -163.815014)
		(width 0.1143)
		(layer "In2.Cu")
		(net "L3_85OHM_5INCH_DP")
	)
	(segment
		(start 83.726782 -163.943284)
		(end 83.819492 -163.810188)
		(width 0.1143)
		(layer "In2.Cu")
		(net "L3_85OHM_5INCH_DP")
	)
	(segment
		(start 82.505042 -166.083234)
		(end 82.129884 -163.955222)
		(width 0.1143)
		(layer "In2.Cu")
		(net "L3_85OHM_5INCH_DP")
	)
	(segment
		(start 74.292206 -166.500302)
		(end 74.523854 -166.169848)
		(width 0.1143)
		(layer "In2.Cu")
		(net "L3_85OHM_5INCH_DP")
	)
	(segment
		(start 90.118692 -163.918392)
		(end 90.211656 -163.786312)
		(width 0.1143)
		(layer "In2.Cu")
		(net "L3_85OHM_5INCH_DP")
	)
	(segment
		(start 83.872832 -166.41445)
		(end 84.104226 -166.083234)
		(width 0.1143)
		(layer "In2.Cu")
		(net "L3_85OHM_5INCH_DP")
	)
	(segment
		(start 76.653898 -166.329106)
		(end 76.984606 -166.560246)
		(width 0.1143)
		(layer "In2.Cu")
		(net "L3_85OHM_5INCH_DP")
	)
	(segment
		(start 66.558922 -165.193726)
		(end 66.718942 -165.315392)
		(width 0.1143)
		(layer "In2.Cu")
		(net "L3_85OHM_5INCH_DP")
	)
	(segment
		(start 73.459848 -166.356284)
		(end 73.79081 -166.588948)
		(width 0.1143)
		(layer "In2.Cu")
		(net "L3_85OHM_5INCH_DP")
	)
	(segment
		(start 69.4944 -166.495476)
		(end 69.725286 -166.164006)
		(width 0.1143)
		(layer "In2.Cu")
		(net "L3_85OHM_5INCH_DP")
	)
	(segment
		(start 86.925658 -163.947602)
		(end 87.018114 -163.815014)
		(width 0.1143)
		(layer "In2.Cu")
		(net "L3_85OHM_5INCH_DP")
	)
	(segment
		(start 68.661788 -166.351712)
		(end 68.993004 -166.583868)
		(width 0.1143)
		(layer "In2.Cu")
		(net "L3_85OHM_5INCH_DP")
	)
	(segment
		(start 83.040474 -166.271448)
		(end 83.371436 -166.502334)
		(width 0.1143)
		(layer "In2.Cu")
		(net "L3_85OHM_5INCH_DP")
	)
	(segment
		(start 66.32575 -165.807136)
		(end 66.32575 -165.305486)
		(width 0.1143)
		(layer "In2.Cu")
		(net "L3_85OHM_5INCH_DP")
	)
	(segment
		(start 75.834748 -163.8808)
		(end 76.097384 -163.834826)
		(width 0.1143)
		(layer "In2.Cu")
		(net "L3_85OHM_5INCH_DP")
	)
	(segment
		(start 88.669368 -166.410386)
		(end 88.900254 -166.079932)
		(width 0.1143)
		(layer "In2.Cu")
		(net "L3_85OHM_5INCH_DP")
	)
	(segment
		(start 90.606626 -163.832794)
		(end 91.033854 -166.259002)
		(width 0.1143)
		(layer "In2.Cu")
		(net "L3_85OHM_5INCH_DP")
	)
	(segment
		(start 91.811602 -163.790884)
		(end 92.073984 -163.74491)
		(width 0.1143)
		(layer "In2.Cu")
		(net "L3_85OHM_5INCH_DP")
	)
	(segment
		(start 67.83959 -163.880292)
		(end 68.102226 -163.83381)
		(width 0.1143)
		(layer "In2.Cu")
		(net "L3_85OHM_5INCH_DP")
	)
	(segment
		(start 75.88631 -166.472108)
		(end 76.11745 -166.140638)
		(width 0.1143)
		(layer "In2.Cu")
		(net "L3_85OHM_5INCH_DP")
	)
	(segment
		(start 80.675226 -166.47414)
		(end 80.913224 -166.133272)
		(width 0.1143)
		(layer "In2.Cu")
		(net "L3_85OHM_5INCH_DP")
	)
	(segment
		(start 79.316326 -166.144956)
		(end 78.938882 -164.00526)
		(width 0.1143)
		(layer "In2.Cu")
		(net "L3_85OHM_5INCH_DP")
	)
	(segment
		(start 88.8746 -163.740084)
		(end 89.007442 -163.833556)
		(width 0.1143)
		(layer "In2.Cu")
		(net "L3_85OHM_5INCH_DP")
	)
	(segment
		(start 84.638134 -166.263066)
		(end 84.969096 -166.493952)
		(width 0.1143)
		(layer "In2.Cu")
		(net "L3_85OHM_5INCH_DP")
	)
	(segment
		(start 90.474038 -163.740338)
		(end 90.606626 -163.832794)
		(width 0.1143)
		(layer "In2.Cu")
		(net "L3_85OHM_5INCH_DP")
	)
	(segment
		(start 69.834506 -163.931092)
		(end 70.260718 -166.352728)
		(width 0.1143)
		(layer "In2.Cu")
		(net "L3_85OHM_5INCH_DP")
	)
	(segment
		(start 70.945502 -164.017198)
		(end 71.037958 -163.884864)
		(width 0.1143)
		(layer "In2.Cu")
		(net "L3_85OHM_5INCH_DP")
	)
	(segment
		(start 77.433932 -163.881054)
		(end 77.696822 -163.834826)
		(width 0.1143)
		(layer "In2.Cu")
		(net "L3_85OHM_5INCH_DP")
	)
	(segment
		(start 88.519254 -163.9189)
		(end 88.611964 -163.786566)
		(width 0.1143)
		(layer "In2.Cu")
		(net "L3_85OHM_5INCH_DP")
	)
	(segment
		(start 95.01251 -163.807394)
		(end 95.275146 -163.761166)
		(width 0.1143)
		(layer "In2.Cu")
		(net "L3_85OHM_5INCH_DP")
	)
	(segment
		(start 91.866466 -166.402258)
		(end 92.097606 -166.071296)
		(width 0.1143)
		(layer "In2.Cu")
		(net "L3_85OHM_5INCH_DP")
	)
	(segment
		(start 82.229198 -163.812982)
		(end 82.47507 -163.769802)
		(width 0.1143)
		(layer "In2.Cu")
		(net "L3_85OHM_5INCH_DP")
	)
	(segment
		(start 69.725286 -166.164006)
		(end 69.346318 -164.016944)
		(width 0.1143)
		(layer "In2.Cu")
		(net "L3_85OHM_5INCH_DP")
	)
	(segment
		(start 91.033854 -166.259002)
		(end 91.36507 -166.490142)
		(width 0.1143)
		(layer "In2.Cu")
		(net "L3_85OHM_5INCH_DP")
	)
	(segment
		(start 74.523854 -166.169848)
		(end 74.142854 -164.00907)
		(width 0.1143)
		(layer "In2.Cu")
		(net "L3_85OHM_5INCH_DP")
	)
	(segment
		(start 95.588074 -164.714174)
		(end 95.734632 -164.9095)
		(width 0.1143)
		(layer "In2.Cu")
		(net "L3_85OHM_5INCH_DP")
	)
	(segment
		(start 71.433436 -163.931346)
		(end 71.860918 -166.357554)
		(width 0.1143)
		(layer "In2.Cu")
		(net "L3_85OHM_5INCH_DP")
	)
	(segment
		(start 87.018114 -163.815014)
		(end 87.280496 -163.76904)
		(width 0.1143)
		(layer "In2.Cu")
		(net "L3_85OHM_5INCH_DP")
	)
	(segment
		(start 94.563692 -166.495222)
		(end 95.064834 -166.406576)
		(width 0.1143)
		(layer "In2.Cu")
		(net "L3_85OHM_5INCH_DP")
	)
	(segment
		(start 78.938882 -164.00526)
		(end 79.031592 -163.872672)
		(width 0.1143)
		(layer "In2.Cu")
		(net "L3_85OHM_5INCH_DP")
	)
	(segment
		(start 83.371436 -166.502334)
		(end 83.872832 -166.41445)
		(width 0.1143)
		(layer "In2.Cu")
		(net "L3_85OHM_5INCH_DP")
	)
	(segment
		(start 72.543416 -164.008816)
		(end 72.635872 -163.876482)
		(width 0.1143)
		(layer "In2.Cu")
		(net "L3_85OHM_5INCH_DP")
	)
	(segment
		(start 74.235056 -163.876482)
		(end 74.497692 -163.83)
		(width 0.1143)
		(layer "In2.Cu")
		(net "L3_85OHM_5INCH_DP")
	)
	(segment
		(start 75.742292 -164.013134)
		(end 75.834748 -163.8808)
		(width 0.1143)
		(layer "In2.Cu")
		(net "L3_85OHM_5INCH_DP")
	)
	(segment
		(start 89.007442 -163.833556)
		(end 89.436956 -166.267384)
		(width 0.1143)
		(layer "In2.Cu")
		(net "L3_85OHM_5INCH_DP")
	)
	(segment
		(start 87.280496 -163.76904)
		(end 87.413338 -163.862258)
		(width 0.1143)
		(layer "In2.Cu")
		(net "L3_85OHM_5INCH_DP")
	)
	(segment
		(start 72.19188 -166.58844)
		(end 72.692006 -166.50081)
		(width 0.1143)
		(layer "In2.Cu")
		(net "L3_85OHM_5INCH_DP")
	)
	(segment
		(start 79.850234 -166.320724)
		(end 80.190594 -166.55923)
		(width 0.1143)
		(layer "In2.Cu")
		(net "L3_85OHM_5INCH_DP")
	)
	(segment
		(start 95.275146 -163.761166)
		(end 95.407734 -163.853876)
		(width 0.1143)
		(layer "In2.Cu")
		(net "L3_85OHM_5INCH_DP")
	)
	(segment
		(start 95.734632 -164.9095)
		(end 96.021144 -165.145974)
		(width 0.1143)
		(layer "In2.Cu")
		(net "L3_85OHM_5INCH_DP")
	)
	(segment
		(start 86.568534 -166.493952)
		(end 87.069676 -166.406322)
		(width 0.1143)
		(layer "In2.Cu")
		(net "L3_85OHM_5INCH_DP")
	)
	(segment
		(start 71.300594 -163.838636)
		(end 71.433436 -163.931346)
		(width 0.1143)
		(layer "In2.Cu")
		(net "L3_85OHM_5INCH_DP")
	)
	(segment
		(start 68.993004 -166.583868)
		(end 69.4944 -166.495476)
		(width 0.1143)
		(layer "In2.Cu")
		(net "L3_85OHM_5INCH_DP")
	)
	(segment
		(start 93.410278 -163.791392)
		(end 93.67266 -163.745164)
		(width 0.1143)
		(layer "In2.Cu")
		(net "L3_85OHM_5INCH_DP")
	)
	(segment
		(start 70.260718 -166.352728)
		(end 70.59168 -166.583868)
		(width 0.1143)
		(layer "In2.Cu")
		(net "L3_85OHM_5INCH_DP")
	)
	(segment
		(start 76.11745 -166.140638)
		(end 75.742292 -164.013134)
		(width 0.1143)
		(layer "In2.Cu")
		(net "L3_85OHM_5INCH_DP")
	)
	(segment
		(start 93.46565 -166.402512)
		(end 93.69679 -166.07155)
		(width 0.1143)
		(layer "In2.Cu")
		(net "L3_85OHM_5INCH_DP")
	)
	(segment
		(start 95.492824 -164.339016)
		(end 95.588074 -164.714174)
		(width 0.1143)
		(layer "In2.Cu")
		(net "L3_85OHM_5INCH_DP")
	)
	(segment
		(start 76.097384 -163.834826)
		(end 76.229972 -163.927282)
		(width 0.1143)
		(layer "In2.Cu")
		(net "L3_85OHM_5INCH_DP")
	)
	(segment
		(start 92.206572 -163.83762)
		(end 92.633038 -166.259256)
		(width 0.1143)
		(layer "In2.Cu")
		(net "L3_85OHM_5INCH_DP")
	)
	(segment
		(start 66.91249 -165.573456)
		(end 66.955416 -165.74262)
		(width 0.1143)
		(layer "In2.Cu")
		(net "L3_85OHM_5INCH_DP")
	)
	(segment
		(start 92.097606 -166.071296)
		(end 91.718892 -163.923472)
		(width 0.1143)
		(layer "In2.Cu")
		(net "L3_85OHM_5INCH_DP")
	)
	(segment
		(start 70.59168 -166.583868)
		(end 71.092568 -166.496238)
		(width 0.1143)
		(layer "In2.Cu")
		(net "L3_85OHM_5INCH_DP")
	)
	(segment
		(start 79.084932 -166.476934)
		(end 79.316326 -166.144956)
		(width 0.1143)
		(layer "In2.Cu")
		(net "L3_85OHM_5INCH_DP")
	)
	(segment
		(start 72.692006 -166.50081)
		(end 72.924416 -166.17061)
		(width 0.1143)
		(layer "In2.Cu")
		(net "L3_85OHM_5INCH_DP")
	)
	(segment
		(start 85.470492 -166.406068)
		(end 85.701886 -166.074852)
		(width 0.1143)
		(layer "In2.Cu")
		(net "L3_85OHM_5INCH_DP")
	)
	(segment
		(start 96.305624 -165.132766)
		(end 96.408494 -165.235382)
		(width 0.1143)
		(layer "In2.Cu")
		(net "L3_85OHM_5INCH_DP")
	)
	(segment
		(start 88.611964 -163.786566)
		(end 88.8746 -163.740084)
		(width 0.1143)
		(layer "In2.Cu")
		(net "L3_85OHM_5INCH_DP")
	)
	(segment
		(start 75.053952 -166.327836)
		(end 75.384914 -166.559992)
		(width 0.1143)
		(layer "In2.Cu")
		(net "L3_85OHM_5INCH_DP")
	)
	(segment
		(start 96.408494 -165.235382)
		(end 96.408494 -165.737032)
		(width 0.1143)
		(layer "In2.Cu")
		(net "L3_85OHM_5INCH_DP")
	)
	(segment
		(start 80.893158 -163.826444)
		(end 81.025746 -163.919154)
		(width 0.1143)
		(layer "In2.Cu")
		(net "L3_85OHM_5INCH_DP")
	)
	(segment
		(start 92.073984 -163.74491)
		(end 92.206572 -163.83762)
		(width 0.1143)
		(layer "In2.Cu")
		(net "L3_85OHM_5INCH_DP")
	)
	(segment
		(start 67.891914 -166.479728)
		(end 68.123308 -166.148512)
		(width 0.1143)
		(layer "In2.Cu")
		(net "L3_85OHM_5INCH_DP")
	)
	(segment
		(start 72.635872 -163.876482)
		(end 72.898508 -163.830254)
		(width 0.1143)
		(layer "In2.Cu")
		(net "L3_85OHM_5INCH_DP")
	)
	(segment
		(start 80.538066 -164.00526)
		(end 80.630522 -163.872672)
		(width 0.1143)
		(layer "In2.Cu")
		(net "L3_85OHM_5INCH_DP")
	)
	(segment
		(start 73.030588 -163.92271)
		(end 73.459848 -166.356284)
		(width 0.1143)
		(layer "In2.Cu")
		(net "L3_85OHM_5INCH_DP")
	)
	(segment
		(start 85.813646 -163.861242)
		(end 86.237572 -166.263066)
		(width 0.1143)
		(layer "In2.Cu")
		(net "L3_85OHM_5INCH_DP")
	)
	(segment
		(start 81.77276 -166.502334)
		(end 82.273902 -166.414196)
		(width 0.1143)
		(layer "In2.Cu")
		(net "L3_85OHM_5INCH_DP")
	)
	(segment
		(start 77.341222 -164.013642)
		(end 77.433932 -163.881054)
		(width 0.1143)
		(layer "In2.Cu")
		(net "L3_85OHM_5INCH_DP")
	)
	(segment
		(start 77.48524 -166.472108)
		(end 77.716634 -166.140892)
		(width 0.1143)
		(layer "In2.Cu")
		(net "L3_85OHM_5INCH_DP")
	)
	(segment
		(start 92.633038 -166.259256)
		(end 92.964254 -166.490396)
		(width 0.1143)
		(layer "In2.Cu")
		(net "L3_85OHM_5INCH_DP")
	)
	(segment
		(start 87.069676 -166.406322)
		(end 87.300816 -166.07536)
		(width 0.1143)
		(layer "In2.Cu")
		(net "L3_85OHM_5INCH_DP")
	)
	(segment
		(start 94.9198 -163.939982)
		(end 95.01251 -163.807394)
		(width 0.1143)
		(layer "In2.Cu")
		(net "L3_85OHM_5INCH_DP")
	)
	(segment
		(start 71.092568 -166.496238)
		(end 71.324216 -166.165022)
		(width 0.1143)
		(layer "In2.Cu")
		(net "L3_85OHM_5INCH_DP")
	)
	(segment
		(start 88.900254 -166.079932)
		(end 88.519254 -163.9189)
		(width 0.1143)
		(layer "In2.Cu")
		(net "L3_85OHM_5INCH_DP")
	)
	(segment
		(start 91.718892 -163.923472)
		(end 91.811602 -163.790884)
		(width 0.1143)
		(layer "In2.Cu")
		(net "L3_85OHM_5INCH_DP")
	)
	(segment
		(start 94.233492 -166.264082)
		(end 94.563692 -166.495222)
		(width 0.1143)
		(layer "In2.Cu")
		(net "L3_85OHM_5INCH_DP")
	)
	(segment
		(start 85.701886 -166.074852)
		(end 85.326474 -163.947602)
		(width 0.1143)
		(layer "In2.Cu")
		(net "L3_85OHM_5INCH_DP")
	)
	(segment
		(start 79.294482 -163.826444)
		(end 79.42707 -163.9189)
		(width 0.1143)
		(layer "In2.Cu")
		(net "L3_85OHM_5INCH_DP")
	)
	(segment
		(start 90.499692 -166.079678)
		(end 90.118692 -163.918392)
		(width 0.1143)
		(layer "In2.Cu")
		(net "L3_85OHM_5INCH_DP")
	)
	(segment
		(start 72.898508 -163.830254)
		(end 73.030588 -163.92271)
		(width 0.1143)
		(layer "In2.Cu")
		(net "L3_85OHM_5INCH_DP")
	)
	(segment
		(start 84.969096 -166.493952)
		(end 85.470492 -166.406068)
		(width 0.1143)
		(layer "In2.Cu")
		(net "L3_85OHM_5INCH_DP")
	)
	(segment
		(start 93.317822 -163.924234)
		(end 93.410278 -163.791392)
		(width 0.1143)
		(layer "In2.Cu")
		(net "L3_85OHM_5INCH_DP")
	)
	(segment
		(start 80.630522 -163.872672)
		(end 80.893158 -163.826444)
		(width 0.1143)
		(layer "In2.Cu")
		(net "L3_85OHM_5INCH_DP")
	)
	(segment
		(start 83.819492 -163.810188)
		(end 84.08162 -163.764468)
		(width 0.1143)
		(layer "In2.Cu")
		(net "L3_85OHM_5INCH_DP")
	)
	(segment
		(start 95.064834 -166.406576)
		(end 95.296736 -166.07536)
		(width 0.1143)
		(layer "In2.Cu")
		(net "L3_85OHM_5INCH_DP")
	)
	(segment
		(start 77.716634 -166.140892)
		(end 77.341222 -164.013642)
		(width 0.1143)
		(layer "In2.Cu")
		(net "L3_85OHM_5INCH_DP")
	)
	(segment
		(start 74.63028 -163.92271)
		(end 75.053952 -166.327836)
		(width 0.1143)
		(layer "In2.Cu")
		(net "L3_85OHM_5INCH_DP")
	)
	(segment
		(start 90.211656 -163.786312)
		(end 90.474038 -163.740338)
		(width 0.1143)
		(layer "In2.Cu")
		(net "L3_85OHM_5INCH_DP")
	)
	(segment
		(start 81.441798 -166.271194)
		(end 81.77276 -166.502334)
		(width 0.1143)
		(layer "In2.Cu")
		(net "L3_85OHM_5INCH_DP")
	)
	(segment
		(start 82.47507 -163.769802)
		(end 82.61731 -163.86937)
		(width 0.1143)
		(layer "In2.Cu")
		(net "L3_85OHM_5INCH_DP")
	)
	(segment
		(start 89.436956 -166.267384)
		(end 89.767156 -166.498778)
		(width 0.1143)
		(layer "In2.Cu")
		(net "L3_85OHM_5INCH_DP")
	)
	(segment
		(start 66.955416 -165.74262)
		(end 67.060064 -166.336218)
		(width 0.1143)
		(layer "In2.Cu")
		(net "L3_85OHM_5INCH_DP")
	)
	(segment
		(start 92.964254 -166.490396)
		(end 93.46565 -166.402512)
		(width 0.1143)
		(layer "In2.Cu")
		(net "L3_85OHM_5INCH_DP")
	)
	(segment
		(start 79.42707 -163.9189)
		(end 79.850234 -166.320724)
		(width 0.1143)
		(layer "In2.Cu")
		(net "L3_85OHM_5INCH_DP")
	)
	(segment
		(start 72.924416 -166.17061)
		(end 72.543416 -164.008816)
		(width 0.1143)
		(layer "In2.Cu")
		(net "L3_85OHM_5INCH_DP")
	)
	(segment
		(start 74.497692 -163.83)
		(end 74.63028 -163.92271)
		(width 0.1143)
		(layer "In2.Cu")
		(net "L3_85OHM_5INCH_DP")
	)
	(segment
		(start 95.296736 -166.07536)
		(end 94.9198 -163.939982)
		(width 0.1143)
		(layer "In2.Cu")
		(net "L3_85OHM_5INCH_DP")
	)
	(segment
		(start 87.413338 -163.862258)
		(end 87.837264 -166.267638)
		(width 0.1143)
		(layer "In2.Cu")
		(net "L3_85OHM_5INCH_DP")
	)
	(segment
		(start 87.300816 -166.07536)
		(end 86.925658 -163.947602)
		(width 0.1143)
		(layer "In2.Cu")
		(net "L3_85OHM_5INCH_DP")
	)
	(segment
		(start 82.61731 -163.86937)
		(end 83.040474 -166.271448)
		(width 0.1143)
		(layer "In2.Cu")
		(net "L3_85OHM_5INCH_DP")
	)
	(segment
		(start 90.268552 -166.41064)
		(end 90.499692 -166.079678)
		(width 0.1143)
		(layer "In2.Cu")
		(net "L3_85OHM_5INCH_DP")
	)
	(segment
		(start 82.273902 -166.414196)
		(end 82.505042 -166.083234)
		(width 0.1143)
		(layer "In2.Cu")
		(net "L3_85OHM_5INCH_DP")
	)
	(segment
		(start 87.837264 -166.267638)
		(end 88.168226 -166.498778)
		(width 0.1143)
		(layer "In2.Cu")
		(net "L3_85OHM_5INCH_DP")
	)
	(segment
		(start 71.037958 -163.884864)
		(end 71.300594 -163.838636)
		(width 0.1143)
		(layer "In2.Cu")
		(net "L3_85OHM_5INCH_DP")
	)
	(segment
		(start 84.104226 -166.083234)
		(end 83.726782 -163.943284)
		(width 0.1143)
		(layer "In2.Cu")
		(net "L3_85OHM_5INCH_DP")
	)
	(segment
		(start 76.984606 -166.560246)
		(end 77.48524 -166.472108)
		(width 0.1143)
		(layer "In2.Cu")
		(net "L3_85OHM_5INCH_DP")
	)
	(segment
		(start 68.123308 -166.148512)
		(end 67.746372 -164.013388)
		(width 0.1143)
		(layer "In2.Cu")
		(net "L3_85OHM_5INCH_DP")
	)
	(segment
		(start 84.08162 -163.764468)
		(end 84.214716 -163.857178)
		(width 0.1143)
		(layer "In2.Cu")
		(net "L3_85OHM_5INCH_DP")
	)
	(segment
		(start 93.67266 -163.745164)
		(end 93.805502 -163.838382)
		(width 0.1143)
		(layer "In2.Cu")
		(net "L3_85OHM_5INCH_DP")
	)
	(segment
		(start 85.681312 -163.768786)
		(end 85.813646 -163.861242)
		(width 0.1143)
		(layer "In2.Cu")
		(net "L3_85OHM_5INCH_DP")
	)
	(segment
		(start 69.438774 -163.88461)
		(end 69.701664 -163.838382)
		(width 0.1143)
		(layer "In2.Cu")
		(net "L3_85OHM_5INCH_DP")
	)
	(segment
		(start 86.237572 -166.263066)
		(end 86.568534 -166.493952)
		(width 0.1143)
		(layer "In2.Cu")
		(net "L3_85OHM_5INCH_DP")
	)
	(segment
		(start 66.718942 -165.315392)
		(end 66.91249 -165.573456)
		(width 0.1143)
		(layer "In2.Cu")
		(net "L3_85OHM_5INCH_DP")
	)
	(segment
		(start 96.021144 -165.145974)
		(end 96.305624 -165.132766)
		(width 0.1143)
		(layer "In2.Cu")
		(net "L3_85OHM_5INCH_DP")
	)
	(segment
		(start 68.102226 -163.83381)
		(end 68.234052 -163.926012)
		(width 0.1143)
		(layer "In2.Cu")
		(net "L3_85OHM_5INCH_DP")
	)
	(segment
		(start 78.252574 -166.333424)
		(end 78.584298 -166.56431)
		(width 0.1143)
		(layer "In2.Cu")
		(net "L3_85OHM_5INCH_DP")
	)
	(segment
		(start 73.79081 -166.588948)
		(end 74.292206 -166.500302)
		(width 0.1143)
		(layer "In2.Cu")
		(net "L3_85OHM_5INCH_DP")
	)
	(segment
		(start 77.696822 -163.834826)
		(end 77.82941 -163.927282)
		(width 0.1143)
		(layer "In2.Cu")
		(net "L3_85OHM_5INCH_DP")
	)
	(segment
		(start 66.32575 -165.305486)
		(end 66.43751 -165.193726)
		(width 0.1143)
		(layer "In2.Cu")
		(net "L3_85OHM_5INCH_DP")
	)
	(segment
		(start 79.031592 -163.872672)
		(end 79.294482 -163.826444)
		(width 0.1143)
		(layer "In2.Cu")
		(net "L3_85OHM_5INCH_DP")
	)
	(segment
		(start 88.168226 -166.498778)
		(end 88.669368 -166.410386)
		(width 0.1143)
		(layer "In2.Cu")
		(net "L3_85OHM_5INCH_DP")
	)
	(segment
		(start 68.234052 -163.926012)
		(end 68.661788 -166.351712)
		(width 0.1143)
		(layer "In2.Cu")
		(net "L3_85OHM_5INCH_DP")
	)
	(segment
		(start 69.346318 -164.016944)
		(end 69.438774 -163.88461)
		(width 0.1143)
		(layer "In2.Cu")
		(net "L3_85OHM_5INCH_DP")
	)
	(segment
		(start 67.390518 -166.567866)
		(end 67.891914 -166.479728)
		(width 0.1143)
		(layer "In2.Cu")
		(net "L3_85OHM_5INCH_DP")
	)
	(segment
		(start 85.419184 -163.815014)
		(end 85.681312 -163.768786)
		(width 0.1143)
		(layer "In2.Cu")
		(net "L3_85OHM_5INCH_DP")
	)
	(segment
		(start 77.82941 -163.927282)
		(end 78.252574 -166.333424)
		(width 0.1143)
		(layer "In2.Cu")
		(net "L3_85OHM_5INCH_DP")
	)
	(segment
		(start 74.142854 -164.00907)
		(end 74.235056 -163.876482)
		(width 0.1143)
		(layer "In2.Cu")
		(net "L3_85OHM_5INCH_DP")
	)
	(segment
		(start 84.214716 -163.857178)
		(end 84.638134 -166.263066)
		(width 0.1143)
		(layer "In2.Cu")
		(net "L3_85OHM_5INCH_DP")
	)
	(segment
		(start 81.025746 -163.919154)
		(end 81.218786 -165.014402)
		(width 0.1143)
		(layer "In2.Cu")
		(net "L3_85OHM_5INCH_DP")
	)
	(segment
		(start 78.584298 -166.56431)
		(end 79.084932 -166.476934)
		(width 0.1143)
		(layer "In2.Cu")
		(net "L3_85OHM_5INCH_DP")
	)
	(segment
		(start 89.767156 -166.498778)
		(end 90.268552 -166.41064)
		(width 0.1143)
		(layer "In2.Cu")
		(net "L3_85OHM_5INCH_DP")
	)
	(segment
		(start 71.860918 -166.357554)
		(end 72.19188 -166.58844)
		(width 0.1143)
		(layer "In2.Cu")
		(net "L3_85OHM_5INCH_DP")
	)
	(segment
		(start 95.407734 -163.853876)
		(end 95.492824 -164.339016)
		(width 0.1143)
		(layer "In2.Cu")
		(net "L3_85OHM_5INCH_DP")
	)
	(segment
		(start 69.701664 -163.838382)
		(end 69.834506 -163.931092)
		(width 0.1143)
		(layer "In2.Cu")
		(net "L3_85OHM_5INCH_DP")
	)
	(segment
		(start 91.36507 -166.490142)
		(end 91.866466 -166.402258)
		(width 0.1143)
		(layer "In2.Cu")
		(net "L3_85OHM_5INCH_DP")
	)
	(segment
		(start 93.69679 -166.07155)
		(end 93.317822 -163.924234)
		(width 0.1143)
		(layer "In2.Cu")
		(net "L3_85OHM_5INCH_DP")
	)
	(segment
		(start 76.229972 -163.927282)
		(end 76.653898 -166.329106)
		(width 0.1143)
		(layer "In2.Cu")
		(net "L3_85OHM_5INCH_DP")
	)
	(segment
		(start 67.746372 -164.013388)
		(end 67.83959 -163.880292)
		(width 0.1143)
		(layer "In2.Cu")
		(net "L3_85OHM_5INCH_DP")
	)
	(segment
		(start 93.805502 -163.838382)
		(end 94.233492 -166.264082)
		(width 0.1143)
		(layer "In2.Cu")
		(net "L3_85OHM_5INCH_DP")
	)
	(segment
		(start 80.190594 -166.55923)
		(end 80.675226 -166.47414)
		(width 0.1143)
		(layer "In2.Cu")
		(net "L3_85OHM_5INCH_DP")
	)
	(segment
		(start 81.218786 -165.014402)
		(end 81.441798 -166.271194)
		(width 0.1143)
		(layer "In2.Cu")
		(net "L3_85OHM_5INCH_DP")
	)
	(segment
		(start 71.324216 -166.165022)
		(end 70.945502 -164.017198)
		(width 0.1143)
		(layer "In2.Cu")
		(net "L3_85OHM_5INCH_DP")
	)
	(segment
		(start 75.384914 -166.559992)
		(end 75.88631 -166.472108)
		(width 0.1143)
		(layer "In2.Cu")
		(net "L3_85OHM_5INCH_DP")
	)
	(segment
		(start 80.913224 -166.133272)
		(end 80.538066 -164.00526)
		(width 0.1143)
		(layer "In2.Cu")
		(net "L3_85OHM_5INCH_DP")
	)
	(via
		(at 96.408494 -164.213032)
		(size 0.5588)
		(drill 0.3048)
		(layers "F.Cu" "B.Cu")
		(net "L3_85OHM_5INCH_DN")
	)
	(via
		(at 66.32575 -164.283136)
		(size 0.5588)
		(drill 0.3048)
		(layers "F.Cu" "B.Cu")
		(net "L3_85OHM_5INCH_DN")
	)
	(segment
		(start 62.948566 -164.899086)
		(end 65.7098 -164.899086)
		(width 0.1143)
		(layer "B.Cu")
		(net "L3_85OHM_5INCH_DN")
	)
	(segment
		(start 97.024444 -164.828982)
		(end 96.408494 -164.213032)
		(width 0.1143)
		(layer "B.Cu")
		(net "L3_85OHM_5INCH_DN")
	)
	(segment
		(start 100.14712 -164.488876)
		(end 99.807014 -164.828982)
		(width 0.1143)
		(layer "B.Cu")
		(net "L3_85OHM_5INCH_DN")
	)
	(segment
		(start 62.587124 -164.537644)
		(end 62.948566 -164.899086)
		(width 0.1143)
		(layer "B.Cu")
		(net "L3_85OHM_5INCH_DN")
	)
	(segment
		(start 65.7098 -164.899086)
		(end 66.32575 -164.283136)
		(width 0.1143)
		(layer "B.Cu")
		(net "L3_85OHM_5INCH_DN")
	)
	(segment
		(start 99.807014 -164.828982)
		(end 97.024444 -164.828982)
		(width 0.1143)
		(layer "B.Cu")
		(net "L3_85OHM_5INCH_DN")
	)
	(segment
		(start 70.636638 -163.948872)
		(end 70.867778 -163.61791)
		(width 0.1143)
		(layer "In2.Cu")
		(net "L3_85OHM_5INCH_DN")
	)
	(segment
		(start 67.437508 -163.944808)
		(end 67.66941 -163.613592)
		(width 0.1143)
		(layer "In2.Cu")
		(net "L3_85OHM_5INCH_DN")
	)
	(segment
		(start 89.274396 -163.663884)
		(end 89.703656 -166.097458)
		(width 0.1143)
		(layer "In2.Cu")
		(net "L3_85OHM_5INCH_DN")
	)
	(segment
		(start 72.465692 -163.609528)
		(end 72.967088 -163.52139)
		(width 0.1143)
		(layer "In2.Cu")
		(net "L3_85OHM_5INCH_DN")
	)
	(segment
		(start 76.496672 -163.757102)
		(end 76.920598 -166.158926)
		(width 0.1143)
		(layer "In2.Cu")
		(net "L3_85OHM_5INCH_DN")
	)
	(segment
		(start 73.726802 -166.186612)
		(end 73.859644 -166.280084)
		(width 0.1143)
		(layer "In2.Cu")
		(net "L3_85OHM_5INCH_DN")
	)
	(segment
		(start 78.914752 -166.20998)
		(end 79.007462 -166.076884)
		(width 0.1143)
		(layer "In2.Cu")
		(net "L3_85OHM_5INCH_DN")
	)
	(segment
		(start 75.320906 -166.15791)
		(end 75.453748 -166.251128)
		(width 0.1143)
		(layer "In2.Cu")
		(net "L3_85OHM_5INCH_DN")
	)
	(segment
		(start 88.21039 -163.85032)
		(end 88.442038 -163.519866)
		(width 0.1143)
		(layer "In2.Cu")
		(net "L3_85OHM_5INCH_DN")
	)
	(segment
		(start 71.369174 -163.530026)
		(end 71.70039 -163.761166)
		(width 0.1143)
		(layer "In2.Cu")
		(net "L3_85OHM_5INCH_DN")
	)
	(segment
		(start 90.542364 -163.431728)
		(end 90.873326 -163.662614)
		(width 0.1143)
		(layer "In2.Cu")
		(net "L3_85OHM_5INCH_DN")
	)
	(segment
		(start 91.43365 -166.181532)
		(end 91.696286 -166.135304)
		(width 0.1143)
		(layer "In2.Cu")
		(net "L3_85OHM_5INCH_DN")
	)
	(segment
		(start 66.32575 -164.784786)
		(end 66.44259 -164.901626)
		(width 0.1143)
		(layer "In2.Cu")
		(net "L3_85OHM_5INCH_DN")
	)
	(segment
		(start 67.24142 -165.681152)
		(end 67.326764 -166.166292)
		(width 0.1143)
		(layer "In2.Cu")
		(net "L3_85OHM_5INCH_DN")
	)
	(segment
		(start 90.190828 -166.011352)
		(end 89.809828 -163.849558)
		(width 0.1143)
		(layer "In2.Cu")
		(net "L3_85OHM_5INCH_DN")
	)
	(segment
		(start 81.82102 -163.886896)
		(end 82.059018 -163.546028)
		(width 0.1143)
		(layer "In2.Cu")
		(net "L3_85OHM_5INCH_DN")
	)
	(segment
		(start 78.861412 -163.605718)
		(end 79.362808 -163.517834)
		(width 0.1143)
		(layer "In2.Cu")
		(net "L3_85OHM_5INCH_DN")
	)
	(segment
		(start 72.260206 -166.27983)
		(end 72.522588 -166.233856)
		(width 0.1143)
		(layer "In2.Cu")
		(net "L3_85OHM_5INCH_DN")
	)
	(segment
		(start 77.263752 -163.6141)
		(end 77.765148 -163.526216)
		(width 0.1143)
		(layer "In2.Cu")
		(net "L3_85OHM_5INCH_DN")
	)
	(segment
		(start 67.459098 -166.259002)
		(end 67.721734 -166.212774)
		(width 0.1143)
		(layer "In2.Cu")
		(net "L3_85OHM_5INCH_DN")
	)
	(segment
		(start 67.721734 -166.212774)
		(end 67.814444 -166.080186)
		(width 0.1143)
		(layer "In2.Cu")
		(net "L3_85OHM_5INCH_DN")
	)
	(segment
		(start 81.292446 -163.748974)
		(end 81.510632 -164.986462)
		(width 0.1143)
		(layer "In2.Cu")
		(net "L3_85OHM_5INCH_DN")
	)
	(segment
		(start 83.307174 -166.101268)
		(end 83.439762 -166.193724)
		(width 0.1143)
		(layer "In2.Cu")
		(net "L3_85OHM_5INCH_DN")
	)
	(segment
		(start 83.795362 -166.014908)
		(end 83.417918 -163.875212)
		(width 0.1143)
		(layer "In2.Cu")
		(net "L3_85OHM_5INCH_DN")
	)
	(segment
		(start 76.920598 -166.158926)
		(end 77.052932 -166.251382)
		(width 0.1143)
		(layer "In2.Cu")
		(net "L3_85OHM_5INCH_DN")
	)
	(segment
		(start 69.061584 -166.275004)
		(end 69.323966 -166.228776)
		(width 0.1143)
		(layer "In2.Cu")
		(net "L3_85OHM_5INCH_DN")
	)
	(segment
		(start 74.064876 -163.609782)
		(end 74.566018 -163.52139)
		(width 0.1143)
		(layer "In2.Cu")
		(net "L3_85OHM_5INCH_DN")
	)
	(segment
		(start 71.015352 -166.096696)
		(end 70.636638 -163.948872)
		(width 0.1143)
		(layer "In2.Cu")
		(net "L3_85OHM_5INCH_DN")
	)
	(segment
		(start 78.519528 -166.16299)
		(end 78.652624 -166.2557)
		(width 0.1143)
		(layer "In2.Cu")
		(net "L3_85OHM_5INCH_DN")
	)
	(segment
		(start 90.042238 -163.519358)
		(end 90.542364 -163.431728)
		(width 0.1143)
		(layer "In2.Cu")
		(net "L3_85OHM_5INCH_DN")
	)
	(segment
		(start 92.142564 -163.4363)
		(end 92.473526 -163.66744)
		(width 0.1143)
		(layer "In2.Cu")
		(net "L3_85OHM_5INCH_DN")
	)
	(segment
		(start 75.453748 -166.251128)
		(end 75.71613 -166.205154)
		(width 0.1143)
		(layer "In2.Cu")
		(net "L3_85OHM_5INCH_DN")
	)
	(segment
		(start 82.54365 -163.460938)
		(end 82.88401 -163.699444)
		(width 0.1143)
		(layer "In2.Cu")
		(net "L3_85OHM_5INCH_DN")
	)
	(segment
		(start 90.873326 -163.662614)
		(end 91.300808 -166.088822)
		(width 0.1143)
		(layer "In2.Cu")
		(net "L3_85OHM_5INCH_DN")
	)
	(segment
		(start 73.83399 -163.940236)
		(end 74.064876 -163.609782)
		(width 0.1143)
		(layer "In2.Cu")
		(net "L3_85OHM_5INCH_DN")
	)
	(segment
		(start 86.847934 -163.54806)
		(end 87.34933 -163.460176)
		(width 0.1143)
		(layer "In2.Cu")
		(net "L3_85OHM_5INCH_DN")
	)
	(segment
		(start 80.116934 -166.150798)
		(end 80.259174 -166.250366)
		(width 0.1143)
		(layer "In2.Cu")
		(net "L3_85OHM_5INCH_DN")
	)
	(segment
		(start 85.037422 -166.185342)
		(end 85.300312 -166.139114)
		(width 0.1143)
		(layer "In2.Cu")
		(net "L3_85OHM_5INCH_DN")
	)
	(segment
		(start 66.928238 -165.107366)
		(end 67.181476 -165.444932)
		(width 0.1143)
		(layer "In2.Cu")
		(net "L3_85OHM_5INCH_DN")
	)
	(segment
		(start 82.88401 -163.699444)
		(end 83.307174 -166.101268)
		(width 0.1143)
		(layer "In2.Cu")
		(net "L3_85OHM_5INCH_DN")
	)
	(segment
		(start 68.928742 -166.181786)
		(end 69.061584 -166.275004)
		(width 0.1143)
		(layer "In2.Cu")
		(net "L3_85OHM_5INCH_DN")
	)
	(segment
		(start 75.433428 -163.944808)
		(end 75.664568 -163.613846)
		(width 0.1143)
		(layer "In2.Cu")
		(net "L3_85OHM_5INCH_DN")
	)
	(segment
		(start 96.408494 -164.714682)
		(end 96.408494 -164.213032)
		(width 0.1143)
		(layer "In2.Cu")
		(net "L3_85OHM_5INCH_DN")
	)
	(segment
		(start 84.149946 -163.455858)
		(end 84.48167 -163.686744)
		(width 0.1143)
		(layer "In2.Cu")
		(net "L3_85OHM_5INCH_DN")
	)
	(segment
		(start 84.904834 -166.092886)
		(end 85.037422 -166.185342)
		(width 0.1143)
		(layer "In2.Cu")
		(net "L3_85OHM_5INCH_DN")
	)
	(segment
		(start 67.326764 -166.166292)
		(end 67.459098 -166.259002)
		(width 0.1143)
		(layer "In2.Cu")
		(net "L3_85OHM_5INCH_DN")
	)
	(segment
		(start 72.234552 -163.94049)
		(end 72.465692 -163.609528)
		(width 0.1143)
		(layer "In2.Cu")
		(net "L3_85OHM_5INCH_DN")
	)
	(segment
		(start 79.69377 -163.74872)
		(end 80.116934 -166.150798)
		(width 0.1143)
		(layer "In2.Cu")
		(net "L3_85OHM_5INCH_DN")
	)
	(segment
		(start 95.674434 -163.68395)
		(end 95.778828 -164.277548)
		(width 0.1143)
		(layer "In2.Cu")
		(net "L3_85OHM_5INCH_DN")
	)
	(segment
		(start 86.991952 -166.007034)
		(end 86.616794 -163.87953)
		(width 0.1143)
		(layer "In2.Cu")
		(net "L3_85OHM_5INCH_DN")
	)
	(segment
		(start 80.259174 -166.250366)
		(end 80.505046 -166.207186)
		(width 0.1143)
		(layer "In2.Cu")
		(net "L3_85OHM_5INCH_DN")
	)
	(segment
		(start 80.505046 -166.207186)
		(end 80.60436 -166.064946)
		(width 0.1143)
		(layer "In2.Cu")
		(net "L3_85OHM_5INCH_DN")
	)
	(segment
		(start 93.03258 -166.181786)
		(end 93.29547 -166.135558)
		(width 0.1143)
		(layer "In2.Cu")
		(net "L3_85OHM_5INCH_DN")
	)
	(segment
		(start 77.032358 -163.945316)
		(end 77.263752 -163.6141)
		(width 0.1143)
		(layer "In2.Cu")
		(net "L3_85OHM_5INCH_DN")
	)
	(segment
		(start 94.500192 -166.094156)
		(end 94.632018 -166.186358)
		(width 0.1143)
		(layer "In2.Cu")
		(net "L3_85OHM_5INCH_DN")
	)
	(segment
		(start 80.460342 -163.605972)
		(end 80.961484 -163.517834)
		(width 0.1143)
		(layer "In2.Cu")
		(net "L3_85OHM_5INCH_DN")
	)
	(segment
		(start 81.510632 -164.986462)
		(end 81.708498 -166.101014)
		(width 0.1143)
		(layer "In2.Cu")
		(net "L3_85OHM_5INCH_DN")
	)
	(segment
		(start 67.814444 -166.080186)
		(end 67.437508 -163.944808)
		(width 0.1143)
		(layer "In2.Cu")
		(net "L3_85OHM_5INCH_DN")
	)
	(segment
		(start 82.196178 -166.014908)
		(end 81.82102 -163.886896)
		(width 0.1143)
		(layer "In2.Cu")
		(net "L3_85OHM_5INCH_DN")
	)
	(segment
		(start 74.21499 -166.101268)
		(end 73.83399 -163.940236)
		(width 0.1143)
		(layer "In2.Cu")
		(net "L3_85OHM_5INCH_DN")
	)
	(segment
		(start 88.943434 -163.43122)
		(end 89.274396 -163.663884)
		(width 0.1143)
		(layer "In2.Cu")
		(net "L3_85OHM_5INCH_DN")
	)
	(segment
		(start 91.300808 -166.088822)
		(end 91.43365 -166.181532)
		(width 0.1143)
		(layer "In2.Cu")
		(net "L3_85OHM_5INCH_DN")
	)
	(segment
		(start 68.170552 -163.524946)
		(end 68.500752 -163.756086)
		(width 0.1143)
		(layer "In2.Cu")
		(net "L3_85OHM_5INCH_DN")
	)
	(segment
		(start 94.632018 -166.186358)
		(end 94.894654 -166.139876)
		(width 0.1143)
		(layer "In2.Cu")
		(net "L3_85OHM_5INCH_DN")
	)
	(segment
		(start 69.268594 -163.617656)
		(end 69.76999 -163.529772)
		(width 0.1143)
		(layer "In2.Cu")
		(net "L3_85OHM_5INCH_DN")
	)
	(segment
		(start 77.052932 -166.251382)
		(end 77.31506 -166.205154)
		(width 0.1143)
		(layer "In2.Cu")
		(net "L3_85OHM_5INCH_DN")
	)
	(segment
		(start 78.652624 -166.2557)
		(end 78.914752 -166.20998)
		(width 0.1143)
		(layer "In2.Cu")
		(net "L3_85OHM_5INCH_DN")
	)
	(segment
		(start 69.323966 -166.228776)
		(end 69.416422 -166.095934)
		(width 0.1143)
		(layer "In2.Cu")
		(net "L3_85OHM_5INCH_DN")
	)
	(segment
		(start 86.63686 -166.185342)
		(end 86.899496 -166.139368)
		(width 0.1143)
		(layer "In2.Cu")
		(net "L3_85OHM_5INCH_DN")
	)
	(segment
		(start 75.808586 -166.072566)
		(end 75.433428 -163.944808)
		(width 0.1143)
		(layer "In2.Cu")
		(net "L3_85OHM_5INCH_DN")
	)
	(segment
		(start 67.66941 -163.613592)
		(end 68.170552 -163.524946)
		(width 0.1143)
		(layer "In2.Cu")
		(net "L3_85OHM_5INCH_DN")
	)
	(segment
		(start 66.44259 -164.901626)
		(end 66.657474 -164.901626)
		(width 0.1143)
		(layer "In2.Cu")
		(net "L3_85OHM_5INCH_DN")
	)
	(segment
		(start 85.749638 -163.459922)
		(end 86.080346 -163.691062)
		(width 0.1143)
		(layer "In2.Cu")
		(net "L3_85OHM_5INCH_DN")
	)
	(segment
		(start 94.84233 -163.54044)
		(end 95.343726 -163.452302)
		(width 0.1143)
		(layer "In2.Cu")
		(net "L3_85OHM_5INCH_DN")
	)
	(segment
		(start 79.362808 -163.517834)
		(end 79.69377 -163.74872)
		(width 0.1143)
		(layer "In2.Cu")
		(net "L3_85OHM_5INCH_DN")
	)
	(segment
		(start 66.32575 -164.283136)
		(end 66.32575 -164.784786)
		(width 0.1143)
		(layer "In2.Cu")
		(net "L3_85OHM_5INCH_DN")
	)
	(segment
		(start 94.894654 -166.139876)
		(end 94.987872 -166.00678)
		(width 0.1143)
		(layer "In2.Cu")
		(net "L3_85OHM_5INCH_DN")
	)
	(segment
		(start 88.442038 -163.519866)
		(end 88.943434 -163.43122)
		(width 0.1143)
		(layer "In2.Cu")
		(net "L3_85OHM_5INCH_DN")
	)
	(segment
		(start 82.103722 -166.147496)
		(end 82.196178 -166.014908)
		(width 0.1143)
		(layer "In2.Cu")
		(net "L3_85OHM_5INCH_DN")
	)
	(segment
		(start 87.34933 -163.460176)
		(end 87.680292 -163.692332)
		(width 0.1143)
		(layer "In2.Cu")
		(net "L3_85OHM_5INCH_DN")
	)
	(segment
		(start 69.037454 -163.948618)
		(end 69.268594 -163.617656)
		(width 0.1143)
		(layer "In2.Cu")
		(net "L3_85OHM_5INCH_DN")
	)
	(segment
		(start 84.48167 -163.686744)
		(end 84.904834 -166.092886)
		(width 0.1143)
		(layer "In2.Cu")
		(net "L3_85OHM_5INCH_DN")
	)
	(segment
		(start 85.01761 -163.879276)
		(end 85.249004 -163.54806)
		(width 0.1143)
		(layer "In2.Cu")
		(net "L3_85OHM_5INCH_DN")
	)
	(segment
		(start 83.649312 -163.543234)
		(end 84.149946 -163.455858)
		(width 0.1143)
		(layer "In2.Cu")
		(net "L3_85OHM_5INCH_DN")
	)
	(segment
		(start 77.40777 -166.072566)
		(end 77.032358 -163.945316)
		(width 0.1143)
		(layer "In2.Cu")
		(net "L3_85OHM_5INCH_DN")
	)
	(segment
		(start 69.76999 -163.529772)
		(end 70.101206 -163.760912)
		(width 0.1143)
		(layer "In2.Cu")
		(net "L3_85OHM_5INCH_DN")
	)
	(segment
		(start 91.696286 -166.135304)
		(end 91.788742 -166.00297)
		(width 0.1143)
		(layer "In2.Cu")
		(net "L3_85OHM_5INCH_DN")
	)
	(segment
		(start 91.410028 -163.855146)
		(end 91.641676 -163.52393)
		(width 0.1143)
		(layer "In2.Cu")
		(net "L3_85OHM_5INCH_DN")
	)
	(segment
		(start 93.29547 -166.135558)
		(end 93.387926 -166.003224)
		(width 0.1143)
		(layer "In2.Cu")
		(net "L3_85OHM_5INCH_DN")
	)
	(segment
		(start 67.181476 -165.444932)
		(end 67.24142 -165.681152)
		(width 0.1143)
		(layer "In2.Cu")
		(net "L3_85OHM_5INCH_DN")
	)
	(segment
		(start 77.765148 -163.526216)
		(end 78.09611 -163.757102)
		(width 0.1143)
		(layer "In2.Cu")
		(net "L3_85OHM_5INCH_DN")
	)
	(segment
		(start 94.072456 -163.668456)
		(end 94.500192 -166.094156)
		(width 0.1143)
		(layer "In2.Cu")
		(net "L3_85OHM_5INCH_DN")
	)
	(segment
		(start 92.473526 -163.66744)
		(end 92.899738 -166.089076)
		(width 0.1143)
		(layer "In2.Cu")
		(net "L3_85OHM_5INCH_DN")
	)
	(segment
		(start 74.89698 -163.75253)
		(end 75.320906 -166.15791)
		(width 0.1143)
		(layer "In2.Cu")
		(net "L3_85OHM_5INCH_DN")
	)
	(segment
		(start 94.987872 -166.00678)
		(end 94.610936 -163.871656)
		(width 0.1143)
		(layer "In2.Cu")
		(net "L3_85OHM_5INCH_DN")
	)
	(segment
		(start 70.922642 -166.229284)
		(end 71.015352 -166.096696)
		(width 0.1143)
		(layer "In2.Cu")
		(net "L3_85OHM_5INCH_DN")
	)
	(segment
		(start 70.867778 -163.61791)
		(end 71.369174 -163.530026)
		(width 0.1143)
		(layer "In2.Cu")
		(net "L3_85OHM_5INCH_DN")
	)
	(segment
		(start 75.664568 -163.613846)
		(end 76.16571 -163.526216)
		(width 0.1143)
		(layer "In2.Cu")
		(net "L3_85OHM_5INCH_DN")
	)
	(segment
		(start 86.080346 -163.691062)
		(end 86.504272 -166.092886)
		(width 0.1143)
		(layer "In2.Cu")
		(net "L3_85OHM_5INCH_DN")
	)
	(segment
		(start 80.229202 -163.936934)
		(end 80.460342 -163.605972)
		(width 0.1143)
		(layer "In2.Cu")
		(net "L3_85OHM_5INCH_DN")
	)
	(segment
		(start 93.387926 -166.003224)
		(end 93.008958 -163.856162)
		(width 0.1143)
		(layer "In2.Cu")
		(net "L3_85OHM_5INCH_DN")
	)
	(segment
		(start 96.282002 -164.841174)
		(end 96.408494 -164.714682)
		(width 0.1143)
		(layer "In2.Cu")
		(net "L3_85OHM_5INCH_DN")
	)
	(segment
		(start 69.416422 -166.095934)
		(end 69.037454 -163.948618)
		(width 0.1143)
		(layer "In2.Cu")
		(net "L3_85OHM_5INCH_DN")
	)
	(segment
		(start 72.615552 -166.101776)
		(end 72.234552 -163.94049)
		(width 0.1143)
		(layer "In2.Cu")
		(net "L3_85OHM_5INCH_DN")
	)
	(segment
		(start 86.899496 -166.139368)
		(end 86.991952 -166.007034)
		(width 0.1143)
		(layer "In2.Cu")
		(net "L3_85OHM_5INCH_DN")
	)
	(segment
		(start 72.967088 -163.52139)
		(end 73.297288 -163.752784)
		(width 0.1143)
		(layer "In2.Cu")
		(net "L3_85OHM_5INCH_DN")
	)
	(segment
		(start 83.417918 -163.875212)
		(end 83.649312 -163.543234)
		(width 0.1143)
		(layer "In2.Cu")
		(net "L3_85OHM_5INCH_DN")
	)
	(segment
		(start 83.702652 -166.147496)
		(end 83.795362 -166.014908)
		(width 0.1143)
		(layer "In2.Cu")
		(net "L3_85OHM_5INCH_DN")
	)
	(segment
		(start 82.059018 -163.546028)
		(end 82.54365 -163.460938)
		(width 0.1143)
		(layer "In2.Cu")
		(net "L3_85OHM_5INCH_DN")
	)
	(segment
		(start 81.841086 -166.193724)
		(end 82.103722 -166.147496)
		(width 0.1143)
		(layer "In2.Cu")
		(net "L3_85OHM_5INCH_DN")
	)
	(segment
		(start 96.120204 -164.848794)
		(end 96.282002 -164.841174)
		(width 0.1143)
		(layer "In2.Cu")
		(net "L3_85OHM_5INCH_DN")
	)
	(segment
		(start 88.103964 -166.097458)
		(end 88.236552 -166.190168)
		(width 0.1143)
		(layer "In2.Cu")
		(net "L3_85OHM_5INCH_DN")
	)
	(segment
		(start 70.101206 -163.760912)
		(end 70.527672 -166.182548)
		(width 0.1143)
		(layer "In2.Cu")
		(net "L3_85OHM_5INCH_DN")
	)
	(segment
		(start 68.500752 -163.756086)
		(end 68.928742 -166.181786)
		(width 0.1143)
		(layer "In2.Cu")
		(net "L3_85OHM_5INCH_DN")
	)
	(segment
		(start 74.12228 -166.233602)
		(end 74.21499 -166.101268)
		(width 0.1143)
		(layer "In2.Cu")
		(net "L3_85OHM_5INCH_DN")
	)
	(segment
		(start 85.249004 -163.54806)
		(end 85.749638 -163.459922)
		(width 0.1143)
		(layer "In2.Cu")
		(net "L3_85OHM_5INCH_DN")
	)
	(segment
		(start 91.641676 -163.52393)
		(end 92.142564 -163.4363)
		(width 0.1143)
		(layer "In2.Cu")
		(net "L3_85OHM_5INCH_DN")
	)
	(segment
		(start 80.961484 -163.517834)
		(end 81.292446 -163.748974)
		(width 0.1143)
		(layer "In2.Cu")
		(net "L3_85OHM_5INCH_DN")
	)
	(segment
		(start 88.59139 -166.011098)
		(end 88.21039 -163.85032)
		(width 0.1143)
		(layer "In2.Cu")
		(net "L3_85OHM_5INCH_DN")
	)
	(segment
		(start 79.007462 -166.076884)
		(end 78.630018 -163.936934)
		(width 0.1143)
		(layer "In2.Cu")
		(net "L3_85OHM_5INCH_DN")
	)
	(segment
		(start 93.74124 -163.4363)
		(end 94.072456 -163.668456)
		(width 0.1143)
		(layer "In2.Cu")
		(net "L3_85OHM_5INCH_DN")
	)
	(segment
		(start 95.343726 -163.452302)
		(end 95.674434 -163.68395)
		(width 0.1143)
		(layer "In2.Cu")
		(net "L3_85OHM_5INCH_DN")
	)
	(segment
		(start 70.527672 -166.182548)
		(end 70.66026 -166.275258)
		(width 0.1143)
		(layer "In2.Cu")
		(net "L3_85OHM_5INCH_DN")
	)
	(segment
		(start 78.09611 -163.757102)
		(end 78.519528 -166.16299)
		(width 0.1143)
		(layer "In2.Cu")
		(net "L3_85OHM_5INCH_DN")
	)
	(segment
		(start 95.778828 -164.277548)
		(end 95.85706 -164.585396)
		(width 0.1143)
		(layer "In2.Cu")
		(net "L3_85OHM_5INCH_DN")
	)
	(segment
		(start 93.008958 -163.856162)
		(end 93.239844 -163.524692)
		(width 0.1143)
		(layer "In2.Cu")
		(net "L3_85OHM_5INCH_DN")
	)
	(segment
		(start 88.499188 -166.143686)
		(end 88.59139 -166.011098)
		(width 0.1143)
		(layer "In2.Cu")
		(net "L3_85OHM_5INCH_DN")
	)
	(segment
		(start 87.680292 -163.692332)
		(end 88.103964 -166.097458)
		(width 0.1143)
		(layer "In2.Cu")
		(net "L3_85OHM_5INCH_DN")
	)
	(segment
		(start 73.297288 -163.752784)
		(end 73.726802 -166.186612)
		(width 0.1143)
		(layer "In2.Cu")
		(net "L3_85OHM_5INCH_DN")
	)
	(segment
		(start 95.85706 -164.585396)
		(end 95.947738 -164.7063)
		(width 0.1143)
		(layer "In2.Cu")
		(net "L3_85OHM_5INCH_DN")
	)
	(segment
		(start 85.300312 -166.139114)
		(end 85.393022 -166.006526)
		(width 0.1143)
		(layer "In2.Cu")
		(net "L3_85OHM_5INCH_DN")
	)
	(segment
		(start 88.236552 -166.190168)
		(end 88.499188 -166.143686)
		(width 0.1143)
		(layer "In2.Cu")
		(net "L3_85OHM_5INCH_DN")
	)
	(segment
		(start 93.239844 -163.524692)
		(end 93.74124 -163.4363)
		(width 0.1143)
		(layer "In2.Cu")
		(net "L3_85OHM_5INCH_DN")
	)
	(segment
		(start 73.859644 -166.280084)
		(end 74.12228 -166.233602)
		(width 0.1143)
		(layer "In2.Cu")
		(net "L3_85OHM_5INCH_DN")
	)
	(segment
		(start 70.66026 -166.275258)
		(end 70.922642 -166.229284)
		(width 0.1143)
		(layer "In2.Cu")
		(net "L3_85OHM_5INCH_DN")
	)
	(segment
		(start 78.630018 -163.936934)
		(end 78.861412 -163.605718)
		(width 0.1143)
		(layer "In2.Cu")
		(net "L3_85OHM_5INCH_DN")
	)
	(segment
		(start 91.788742 -166.00297)
		(end 91.410028 -163.855146)
		(width 0.1143)
		(layer "In2.Cu")
		(net "L3_85OHM_5INCH_DN")
	)
	(segment
		(start 83.439762 -166.193724)
		(end 83.702652 -166.147496)
		(width 0.1143)
		(layer "In2.Cu")
		(net "L3_85OHM_5INCH_DN")
	)
	(segment
		(start 85.393022 -166.006526)
		(end 85.01761 -163.879276)
		(width 0.1143)
		(layer "In2.Cu")
		(net "L3_85OHM_5INCH_DN")
	)
	(segment
		(start 72.522588 -166.233856)
		(end 72.615552 -166.101776)
		(width 0.1143)
		(layer "In2.Cu")
		(net "L3_85OHM_5INCH_DN")
	)
	(segment
		(start 81.708498 -166.101014)
		(end 81.841086 -166.193724)
		(width 0.1143)
		(layer "In2.Cu")
		(net "L3_85OHM_5INCH_DN")
	)
	(segment
		(start 75.71613 -166.205154)
		(end 75.808586 -166.072566)
		(width 0.1143)
		(layer "In2.Cu")
		(net "L3_85OHM_5INCH_DN")
	)
	(segment
		(start 80.60436 -166.064946)
		(end 80.229202 -163.936934)
		(width 0.1143)
		(layer "In2.Cu")
		(net "L3_85OHM_5INCH_DN")
	)
	(segment
		(start 72.127618 -166.187374)
		(end 72.260206 -166.27983)
		(width 0.1143)
		(layer "In2.Cu")
		(net "L3_85OHM_5INCH_DN")
	)
	(segment
		(start 94.610936 -163.871656)
		(end 94.84233 -163.54044)
		(width 0.1143)
		(layer "In2.Cu")
		(net "L3_85OHM_5INCH_DN")
	)
	(segment
		(start 89.809828 -163.849558)
		(end 90.042238 -163.519358)
		(width 0.1143)
		(layer "In2.Cu")
		(net "L3_85OHM_5INCH_DN")
	)
	(segment
		(start 92.899738 -166.089076)
		(end 93.03258 -166.181786)
		(width 0.1143)
		(layer "In2.Cu")
		(net "L3_85OHM_5INCH_DN")
	)
	(segment
		(start 71.70039 -163.761166)
		(end 72.127618 -166.187374)
		(width 0.1143)
		(layer "In2.Cu")
		(net "L3_85OHM_5INCH_DN")
	)
	(segment
		(start 66.657474 -164.901626)
		(end 66.928238 -165.107366)
		(width 0.1143)
		(layer "In2.Cu")
		(net "L3_85OHM_5INCH_DN")
	)
	(segment
		(start 77.31506 -166.205154)
		(end 77.40777 -166.072566)
		(width 0.1143)
		(layer "In2.Cu")
		(net "L3_85OHM_5INCH_DN")
	)
	(segment
		(start 89.703656 -166.097458)
		(end 89.835736 -166.189914)
		(width 0.1143)
		(layer "In2.Cu")
		(net "L3_85OHM_5INCH_DN")
	)
	(segment
		(start 86.616794 -163.87953)
		(end 86.847934 -163.54806)
		(width 0.1143)
		(layer "In2.Cu")
		(net "L3_85OHM_5INCH_DN")
	)
	(segment
		(start 74.566018 -163.52139)
		(end 74.89698 -163.75253)
		(width 0.1143)
		(layer "In2.Cu")
		(net "L3_85OHM_5INCH_DN")
	)
	(segment
		(start 89.835736 -166.189914)
		(end 90.098372 -166.143686)
		(width 0.1143)
		(layer "In2.Cu")
		(net "L3_85OHM_5INCH_DN")
	)
	(segment
		(start 76.16571 -163.526216)
		(end 76.496672 -163.757102)
		(width 0.1143)
		(layer "In2.Cu")
		(net "L3_85OHM_5INCH_DN")
	)
	(segment
		(start 86.504272 -166.092886)
		(end 86.63686 -166.185342)
		(width 0.1143)
		(layer "In2.Cu")
		(net "L3_85OHM_5INCH_DN")
	)
	(segment
		(start 95.947738 -164.7063)
		(end 96.120204 -164.848794)
		(width 0.1143)
		(layer "In2.Cu")
		(net "L3_85OHM_5INCH_DN")
	)
	(segment
		(start 90.098372 -166.143686)
		(end 90.190828 -166.011352)
		(width 0.1143)
		(layer "In2.Cu")
		(net "L3_85OHM_5INCH_DN")
	)
	(via
		(at 239.238282 -165.667436)
		(size 0.5588)
		(drill 0.3048)
		(layers "F.Cu" "B.Cu")
		(net "L3_85OHM_10INCH_DP")
	)
	(via
		(at 306.35194 -165.660324)
		(size 0.5588)
		(drill 0.3048)
		(layers "F.Cu" "B.Cu")
		(net "L3_85OHM_10INCH_DP")
	)
	(segment
		(start 238.622332 -165.051486)
		(end 239.238282 -165.667436)
		(width 0.1143)
		(layer "B.Cu")
		(net "L3_85OHM_10INCH_DP")
	)
	(segment
		(start 238.017304 -165.398704)
		(end 238.364522 -165.051486)
		(width 0.1143)
		(layer "B.Cu")
		(net "L3_85OHM_10INCH_DP")
	)
	(segment
		(start 238.364522 -165.051486)
		(end 238.622332 -165.051486)
		(width 0.1143)
		(layer "B.Cu")
		(net "L3_85OHM_10INCH_DP")
	)
	(segment
		(start 306.96789 -165.044374)
		(end 306.35194 -165.660324)
		(width 0.1143)
		(layer "B.Cu")
		(net "L3_85OHM_10INCH_DP")
	)
	(segment
		(start 307.572918 -165.412928)
		(end 307.204364 -165.044374)
		(width 0.1143)
		(layer "B.Cu")
		(net "L3_85OHM_10INCH_DP")
	)
	(segment
		(start 307.204364 -165.044374)
		(end 306.96789 -165.044374)
		(width 0.1143)
		(layer "B.Cu")
		(net "L3_85OHM_10INCH_DP")
	)
	(segment
		(start 239.854232 -165.051486)
		(end 240.308384 -165.051486)
		(width 0.1143)
		(layer "In2.Cu")
		(net "L3_85OHM_10INCH_DP")
	)
	(segment
		(start 244.92458 -166.355776)
		(end 245.155466 -166.024306)
		(width 0.1143)
		(layer "In2.Cu")
		(net "L3_85OHM_10INCH_DP")
	)
	(segment
		(start 241.394234 -164.964618)
		(end 242.18265 -165.215316)
		(width 0.1143)
		(layer "In2.Cu")
		(net "L3_85OHM_10INCH_DP")
	)
	(segment
		(start 244.423184 -166.444168)
		(end 244.92458 -166.355776)
		(width 0.1143)
		(layer "In2.Cu")
		(net "L3_85OHM_10INCH_DP")
	)
	(segment
		(start 257.573018 -163.889436)
		(end 257.672332 -163.747196)
		(width 0.1143)
		(layer "In2.Cu")
		(net "L3_85OHM_10INCH_DP")
	)
	(segment
		(start 279.58542 -166.334948)
		(end 280.086816 -166.247064)
		(width 0.1143)
		(layer "In2.Cu")
		(net "L3_85OHM_10INCH_DP")
	)
	(segment
		(start 282.453842 -166.108888)
		(end 282.784042 -166.340028)
		(width 0.1143)
		(layer "In2.Cu")
		(net "L3_85OHM_10INCH_DP")
	)
	(segment
		(start 249.722386 -166.360602)
		(end 249.954034 -166.030148)
		(width 0.1143)
		(layer "In2.Cu")
		(net "L3_85OHM_10INCH_DP")
	)
	(segment
		(start 257.704082 -166.274496)
		(end 257.935222 -165.943534)
		(width 0.1143)
		(layer "In2.Cu")
		(net "L3_85OHM_10INCH_DP")
	)
	(segment
		(start 302.722534 -165.998652)
		(end 302.345598 -163.863274)
		(width 0.1143)
		(layer "In2.Cu")
		(net "L3_85OHM_10INCH_DP")
	)
	(segment
		(start 296.300398 -163.663376)
		(end 296.43324 -163.756848)
		(width 0.1143)
		(layer "In2.Cu")
		(net "L3_85OHM_10INCH_DP")
	)
	(segment
		(start 261.132066 -165.935152)
		(end 260.769608 -163.881816)
		(width 0.1143)
		(layer "In2.Cu")
		(net "L3_85OHM_10INCH_DP")
	)
	(segment
		(start 255.620774 -166.41953)
		(end 256.105406 -166.33444)
		(width 0.1143)
		(layer "In2.Cu")
		(net "L3_85OHM_10INCH_DP")
	)
	(segment
		(start 268.89583 -166.262812)
		(end 269.12697 -165.93185)
		(width 0.1143)
		(layer "In2.Cu")
		(net "L3_85OHM_10INCH_DP")
	)
	(segment
		(start 269.12697 -165.93185)
		(end 268.765274 -163.882832)
		(width 0.1143)
		(layer "In2.Cu")
		(net "L3_85OHM_10INCH_DP")
	)
	(segment
		(start 251.54763 -166.000938)
		(end 251.172472 -163.873434)
		(width 0.1143)
		(layer "In2.Cu")
		(net "L3_85OHM_10INCH_DP")
	)
	(segment
		(start 274.457922 -166.107872)
		(end 274.788884 -166.338758)
		(width 0.1143)
		(layer "In2.Cu")
		(net "L3_85OHM_10INCH_DP")
	)
	(segment
		(start 253.25959 -163.787582)
		(end 253.682754 -166.193724)
		(width 0.1143)
		(layer "In2.Cu")
		(net "L3_85OHM_10INCH_DP")
	)
	(segment
		(start 283.157676 -163.88334)
		(end 283.250386 -163.750498)
		(width 0.1143)
		(layer "In2.Cu")
		(net "L3_85OHM_10INCH_DP")
	)
	(segment
		(start 300.390052 -166.413688)
		(end 300.891448 -166.325804)
		(width 0.1143)
		(layer "In2.Cu")
		(net "L3_85OHM_10INCH_DP")
	)
	(segment
		(start 246.522748 -166.356538)
		(end 246.754396 -166.025322)
		(width 0.1143)
		(layer "In2.Cu")
		(net "L3_85OHM_10INCH_DP")
	)
	(segment
		(start 287.259776 -166.15537)
		(end 287.589976 -166.38651)
		(width 0.1143)
		(layer "In2.Cu")
		(net "L3_85OHM_10INCH_DP")
	)
	(segment
		(start 252.864112 -163.741354)
		(end 253.127002 -163.695126)
		(width 0.1143)
		(layer "In2.Cu")
		(net "L3_85OHM_10INCH_DP")
	)
	(segment
		(start 254.014478 -166.42461)
		(end 254.515112 -166.337234)
		(width 0.1143)
		(layer "In2.Cu")
		(net "L3_85OHM_10INCH_DP")
	)
	(segment
		(start 269.120112 -163.704016)
		(end 269.253208 -163.797234)
		(width 0.1143)
		(layer "In2.Cu")
		(net "L3_85OHM_10INCH_DP")
	)
	(segment
		(start 258.060444 -163.803584)
		(end 258.470654 -166.131748)
		(width 0.1143)
		(layer "In2.Cu")
		(net "L3_85OHM_10INCH_DP")
	)
	(segment
		(start 301.122588 -165.994842)
		(end 300.74362 -163.847526)
		(width 0.1143)
		(layer "In2.Cu")
		(net "L3_85OHM_10INCH_DP")
	)
	(segment
		(start 249.22099 -166.449248)
		(end 249.722386 -166.360602)
		(width 0.1143)
		(layer "In2.Cu")
		(net "L3_85OHM_10INCH_DP")
	)
	(segment
		(start 284.38602 -166.355522)
		(end 284.887162 -166.266876)
		(width 0.1143)
		(layer "In2.Cu")
		(net "L3_85OHM_10INCH_DP")
	)
	(segment
		(start 259.658612 -163.79571)
		(end 260.068314 -166.123366)
		(width 0.1143)
		(layer "In2.Cu")
		(net "L3_85OHM_10INCH_DP")
	)
	(segment
		(start 292.063932 -166.186358)
		(end 292.394894 -166.417244)
		(width 0.1143)
		(layer "In2.Cu")
		(net "L3_85OHM_10INCH_DP")
	)
	(segment
		(start 250.06046 -163.78301)
		(end 250.484132 -166.188136)
		(width 0.1143)
		(layer "In2.Cu")
		(net "L3_85OHM_10INCH_DP")
	)
	(segment
		(start 301.2313 -163.761674)
		(end 301.65929 -166.187374)
		(width 0.1143)
		(layer "In2.Cu")
		(net "L3_85OHM_10INCH_DP")
	)
	(segment
		(start 276.388576 -166.343584)
		(end 276.889718 -166.255192)
		(width 0.1143)
		(layer "In2.Cu")
		(net "L3_85OHM_10INCH_DP")
	)
	(segment
		(start 253.127002 -163.695126)
		(end 253.25959 -163.787582)
		(width 0.1143)
		(layer "In2.Cu")
		(net "L3_85OHM_10INCH_DP")
	)
	(segment
		(start 243.26977 -163.740592)
		(end 243.532406 -163.69411)
		(width 0.1143)
		(layer "In2.Cu")
		(net "L3_85OHM_10INCH_DP")
	)
	(segment
		(start 277.120604 -165.924738)
		(end 276.756876 -163.862258)
		(width 0.1143)
		(layer "In2.Cu")
		(net "L3_85OHM_10INCH_DP")
	)
	(segment
		(start 291.24529 -163.73348)
		(end 291.507418 -163.68776)
		(width 0.1143)
		(layer "In2.Cu")
		(net "L3_85OHM_10INCH_DP")
	)
	(segment
		(start 256.871978 -166.131494)
		(end 257.20294 -166.362634)
		(width 0.1143)
		(layer "In2.Cu")
		(net "L3_85OHM_10INCH_DP")
	)
	(segment
		(start 295.945052 -163.842192)
		(end 296.037762 -163.709858)
		(width 0.1143)
		(layer "In2.Cu")
		(net "L3_85OHM_10INCH_DP")
	)
	(segment
		(start 247.291098 -166.217854)
		(end 247.62206 -166.44874)
		(width 0.1143)
		(layer "In2.Cu")
		(net "L3_85OHM_10INCH_DP")
	)
	(segment
		(start 299.14469 -163.846764)
		(end 299.2374 -163.714176)
		(width 0.1143)
		(layer "In2.Cu")
		(net "L3_85OHM_10INCH_DP")
	)
	(segment
		(start 299.2374 -163.714176)
		(end 299.499782 -163.668202)
		(width 0.1143)
		(layer "In2.Cu")
		(net "L3_85OHM_10INCH_DP")
	)
	(segment
		(start 242.48999 -166.196518)
		(end 242.820698 -166.428166)
		(width 0.1143)
		(layer "In2.Cu")
		(net "L3_85OHM_10INCH_DP")
	)
	(segment
		(start 275.5138 -163.68776)
		(end 275.646642 -163.780978)
		(width 0.1143)
		(layer "In2.Cu")
		(net "L3_85OHM_10INCH_DP")
	)
	(segment
		(start 289.654996 -163.736274)
		(end 289.900868 -163.693094)
		(width 0.1143)
		(layer "In2.Cu")
		(net "L3_85OHM_10INCH_DP")
	)
	(segment
		(start 300.058836 -166.182548)
		(end 300.390052 -166.413688)
		(width 0.1143)
		(layer "In2.Cu")
		(net "L3_85OHM_10INCH_DP")
	)
	(segment
		(start 298.032424 -163.756086)
		(end 298.459652 -166.182294)
		(width 0.1143)
		(layer "In2.Cu")
		(net "L3_85OHM_10INCH_DP")
	)
	(segment
		(start 249.665236 -163.736782)
		(end 249.927872 -163.6903)
		(width 0.1143)
		(layer "In2.Cu")
		(net "L3_85OHM_10INCH_DP")
	)
	(segment
		(start 277.245318 -163.776914)
		(end 277.657306 -166.11219)
		(width 0.1143)
		(layer "In2.Cu")
		(net "L3_85OHM_10INCH_DP")
	)
	(segment
		(start 248.122186 -166.36111)
		(end 248.354596 -166.03091)
		(width 0.1143)
		(layer "In2.Cu")
		(net "L3_85OHM_10INCH_DP")
	)
	(segment
		(start 274.04695 -163.779962)
		(end 274.457922 -166.107872)
		(width 0.1143)
		(layer "In2.Cu")
		(net "L3_85OHM_10INCH_DP")
	)
	(segment
		(start 260.900672 -166.266368)
		(end 261.132066 -165.935152)
		(width 0.1143)
		(layer "In2.Cu")
		(net "L3_85OHM_10INCH_DP")
	)
	(segment
		(start 253.682754 -166.193724)
		(end 254.014478 -166.42461)
		(width 0.1143)
		(layer "In2.Cu")
		(net "L3_85OHM_10INCH_DP")
	)
	(segment
		(start 302.980598 -164.506402)
		(end 303.229772 -164.838634)
		(width 0.1143)
		(layer "In2.Cu")
		(net "L3_85OHM_10INCH_DP")
	)
	(segment
		(start 281.91714 -165.916356)
		(end 281.555444 -163.867338)
		(width 0.1143)
		(layer "In2.Cu")
		(net "L3_85OHM_10INCH_DP")
	)
	(segment
		(start 302.833278 -163.777168)
		(end 302.918622 -164.262308)
		(width 0.1143)
		(layer "In2.Cu")
		(net "L3_85OHM_10INCH_DP")
	)
	(segment
		(start 242.18265 -165.215316)
		(end 242.340638 -165.426136)
		(width 0.1143)
		(layer "In2.Cu")
		(net "L3_85OHM_10INCH_DP")
	)
	(segment
		(start 300.836076 -163.714684)
		(end 301.098458 -163.668456)
		(width 0.1143)
		(layer "In2.Cu")
		(net "L3_85OHM_10INCH_DP")
	)
	(segment
		(start 266.464034 -166.119302)
		(end 266.79525 -166.350442)
		(width 0.1143)
		(layer "In2.Cu")
		(net "L3_85OHM_10INCH_DP")
	)
	(segment
		(start 272.858484 -166.107872)
		(end 273.189446 -166.338758)
		(width 0.1143)
		(layer "In2.Cu")
		(net "L3_85OHM_10INCH_DP")
	)
	(segment
		(start 268.857984 -163.74999)
		(end 269.120112 -163.704016)
		(width 0.1143)
		(layer "In2.Cu")
		(net "L3_85OHM_10INCH_DP")
	)
	(segment
		(start 273.189446 -166.338758)
		(end 273.690842 -166.250874)
		(width 0.1143)
		(layer "In2.Cu")
		(net "L3_85OHM_10INCH_DP")
	)
	(segment
		(start 245.690898 -166.213028)
		(end 246.02186 -166.444168)
		(width 0.1143)
		(layer "In2.Cu")
		(net "L3_85OHM_10INCH_DP")
	)
	(segment
		(start 259.263388 -163.74872)
		(end 259.525516 -163.703)
		(width 0.1143)
		(layer "In2.Cu")
		(net "L3_85OHM_10INCH_DP")
	)
	(segment
		(start 285.115508 -163.724336)
		(end 285.247842 -163.817046)
		(width 0.1143)
		(layer "In2.Cu")
		(net "L3_85OHM_10INCH_DP")
	)
	(segment
		(start 262.461248 -163.749228)
		(end 262.72363 -163.703254)
		(width 0.1143)
		(layer "In2.Cu")
		(net "L3_85OHM_10INCH_DP")
	)
	(segment
		(start 275.251418 -163.733734)
		(end 275.5138 -163.68776)
		(width 0.1143)
		(layer "In2.Cu")
		(net "L3_85OHM_10INCH_DP")
	)
	(segment
		(start 288.091118 -166.297864)
		(end 288.32302 -165.966648)
		(width 0.1143)
		(layer "In2.Cu")
		(net "L3_85OHM_10INCH_DP")
	)
	(segment
		(start 273.652488 -163.733734)
		(end 273.914616 -163.687506)
		(width 0.1143)
		(layer "In2.Cu")
		(net "L3_85OHM_10INCH_DP")
	)
	(segment
		(start 257.918204 -163.704016)
		(end 258.060444 -163.803584)
		(width 0.1143)
		(layer "In2.Cu")
		(net "L3_85OHM_10INCH_DP")
	)
	(segment
		(start 283.250386 -163.750498)
		(end 283.512768 -163.704524)
		(width 0.1143)
		(layer "In2.Cu")
		(net "L3_85OHM_10INCH_DP")
	)
	(segment
		(start 273.559778 -163.866322)
		(end 273.652488 -163.733734)
		(width 0.1143)
		(layer "In2.Cu")
		(net "L3_85OHM_10INCH_DP")
	)
	(segment
		(start 294.726614 -165.998652)
		(end 294.351456 -163.870894)
		(width 0.1143)
		(layer "In2.Cu")
		(net "L3_85OHM_10INCH_DP")
	)
	(segment
		(start 247.62206 -166.44874)
		(end 248.122186 -166.36111)
		(width 0.1143)
		(layer "In2.Cu")
		(net "L3_85OHM_10INCH_DP")
	)
	(segment
		(start 284.887162 -166.266876)
		(end 285.119064 -165.93566)
		(width 0.1143)
		(layer "In2.Cu")
		(net "L3_85OHM_10INCH_DP")
	)
	(segment
		(start 246.02186 -166.444168)
		(end 246.522748 -166.356538)
		(width 0.1143)
		(layer "In2.Cu")
		(net "L3_85OHM_10INCH_DP")
	)
	(segment
		(start 290.797234 -166.425626)
		(end 291.29863 -166.337742)
		(width 0.1143)
		(layer "In2.Cu")
		(net "L3_85OHM_10INCH_DP")
	)
	(segment
		(start 276.756876 -163.862258)
		(end 276.849586 -163.729924)
		(width 0.1143)
		(layer "In2.Cu")
		(net "L3_85OHM_10INCH_DP")
	)
	(segment
		(start 283.285184 -166.251382)
		(end 283.517086 -165.920166)
		(width 0.1143)
		(layer "In2.Cu")
		(net "L3_85OHM_10INCH_DP")
	)
	(segment
		(start 260.068314 -166.123366)
		(end 260.399276 -166.354252)
		(width 0.1143)
		(layer "In2.Cu")
		(net "L3_85OHM_10INCH_DP")
	)
	(segment
		(start 301.98949 -166.418514)
		(end 302.490632 -166.329868)
		(width 0.1143)
		(layer "In2.Cu")
		(net "L3_85OHM_10INCH_DP")
	)
	(segment
		(start 280.086816 -166.247064)
		(end 280.317956 -165.916102)
		(width 0.1143)
		(layer "In2.Cu")
		(net "L3_85OHM_10INCH_DP")
	)
	(segment
		(start 270.362934 -163.874196)
		(end 270.455644 -163.741608)
		(width 0.1143)
		(layer "In2.Cu")
		(net "L3_85OHM_10INCH_DP")
	)
	(segment
		(start 246.468138 -163.745164)
		(end 246.730774 -163.698936)
		(width 0.1143)
		(layer "In2.Cu")
		(net "L3_85OHM_10INCH_DP")
	)
	(segment
		(start 294.706294 -163.692332)
		(end 294.839136 -163.78555)
		(width 0.1143)
		(layer "In2.Cu")
		(net "L3_85OHM_10INCH_DP")
	)
	(segment
		(start 270.850614 -163.78809)
		(end 271.260824 -166.116254)
		(width 0.1143)
		(layer "In2.Cu")
		(net "L3_85OHM_10INCH_DP")
	)
	(segment
		(start 249.927872 -163.6903)
		(end 250.06046 -163.78301)
		(width 0.1143)
		(layer "In2.Cu")
		(net "L3_85OHM_10INCH_DP")
	)
	(segment
		(start 297.92549 -166.00297)
		(end 297.54449 -163.841684)
		(width 0.1143)
		(layer "In2.Cu")
		(net "L3_85OHM_10INCH_DP")
	)
	(segment
		(start 240.308384 -165.051486)
		(end 241.394234 -164.964618)
		(width 0.1143)
		(layer "In2.Cu")
		(net "L3_85OHM_10INCH_DP")
	)
	(segment
		(start 297.54449 -163.841684)
		(end 297.637454 -163.709604)
		(width 0.1143)
		(layer "In2.Cu")
		(net "L3_85OHM_10INCH_DP")
	)
	(segment
		(start 277.112222 -163.683442)
		(end 277.245318 -163.776914)
		(width 0.1143)
		(layer "In2.Cu")
		(net "L3_85OHM_10INCH_DP")
	)
	(segment
		(start 251.172472 -163.873434)
		(end 251.264928 -163.7411)
		(width 0.1143)
		(layer "In2.Cu")
		(net "L3_85OHM_10INCH_DP")
	)
	(segment
		(start 263.96315 -163.857432)
		(end 264.05586 -163.725098)
		(width 0.1143)
		(layer "In2.Cu")
		(net "L3_85OHM_10INCH_DP")
	)
	(segment
		(start 267.527786 -165.931596)
		(end 267.166344 -163.882324)
		(width 0.1143)
		(layer "In2.Cu")
		(net "L3_85OHM_10INCH_DP")
	)
	(segment
		(start 278.720042 -165.924484)
		(end 278.356314 -163.86175)
		(width 0.1143)
		(layer "In2.Cu")
		(net "L3_85OHM_10INCH_DP")
	)
	(segment
		(start 260.399276 -166.354252)
		(end 260.900672 -166.266368)
		(width 0.1143)
		(layer "In2.Cu")
		(net "L3_85OHM_10INCH_DP")
	)
	(segment
		(start 289.6997 -166.336726)
		(end 289.930332 -166.005256)
		(width 0.1143)
		(layer "In2.Cu")
		(net "L3_85OHM_10INCH_DP")
	)
	(segment
		(start 277.987506 -166.343584)
		(end 278.488902 -166.255446)
		(width 0.1143)
		(layer "In2.Cu")
		(net "L3_85OHM_10INCH_DP")
	)
	(segment
		(start 280.312368 -163.692586)
		(end 280.444956 -163.785296)
		(width 0.1143)
		(layer "In2.Cu")
		(net "L3_85OHM_10INCH_DP")
	)
	(segment
		(start 288.86658 -166.192708)
		(end 289.19805 -166.425118)
		(width 0.1143)
		(layer "In2.Cu")
		(net "L3_85OHM_10INCH_DP")
	)
	(segment
		(start 266.054078 -163.791646)
		(end 266.464034 -166.119302)
		(width 0.1143)
		(layer "In2.Cu")
		(net "L3_85OHM_10INCH_DP")
	)
	(segment
		(start 275.521166 -165.920166)
		(end 275.158962 -163.866322)
		(width 0.1143)
		(layer "In2.Cu")
		(net "L3_85OHM_10INCH_DP")
	)
	(segment
		(start 297.637454 -163.709604)
		(end 297.899836 -163.66363)
		(width 0.1143)
		(layer "In2.Cu")
		(net "L3_85OHM_10INCH_DP")
	)
	(segment
		(start 262.499856 -166.266622)
		(end 262.730996 -165.93566)
		(width 0.1143)
		(layer "In2.Cu")
		(net "L3_85OHM_10INCH_DP")
	)
	(segment
		(start 299.499782 -163.668202)
		(end 299.63237 -163.760912)
		(width 0.1143)
		(layer "In2.Cu")
		(net "L3_85OHM_10INCH_DP")
	)
	(segment
		(start 254.461772 -163.732972)
		(end 254.724662 -163.686744)
		(width 0.1143)
		(layer "In2.Cu")
		(net "L3_85OHM_10INCH_DP")
	)
	(segment
		(start 302.918622 -164.262308)
		(end 302.980598 -164.506402)
		(width 0.1143)
		(layer "In2.Cu")
		(net "L3_85OHM_10INCH_DP")
	)
	(segment
		(start 252.414786 -166.420546)
		(end 252.91542 -166.332408)
		(width 0.1143)
		(layer "In2.Cu")
		(net "L3_85OHM_10INCH_DP")
	)
	(segment
		(start 254.85725 -163.7792)
		(end 255.280414 -166.181024)
		(width 0.1143)
		(layer "In2.Cu")
		(net "L3_85OHM_10INCH_DP")
	)
	(segment
		(start 264.330434 -165.940232)
		(end 263.96315 -163.857432)
		(width 0.1143)
		(layer "In2.Cu")
		(net "L3_85OHM_10INCH_DP")
	)
	(segment
		(start 248.066052 -163.736782)
		(end 248.328688 -163.690554)
		(width 0.1143)
		(layer "In2.Cu")
		(net "L3_85OHM_10INCH_DP")
	)
	(segment
		(start 286.721042 -165.951154)
		(end 286.35706 -163.88969)
		(width 0.1143)
		(layer "In2.Cu")
		(net "L3_85OHM_10INCH_DP")
	)
	(segment
		(start 289.19805 -166.425118)
		(end 289.6997 -166.336726)
		(width 0.1143)
		(layer "In2.Cu")
		(net "L3_85OHM_10INCH_DP")
	)
	(segment
		(start 243.553488 -166.008812)
		(end 243.176552 -163.873688)
		(width 0.1143)
		(layer "In2.Cu")
		(net "L3_85OHM_10INCH_DP")
	)
	(segment
		(start 278.449278 -163.72967)
		(end 278.71166 -163.683696)
		(width 0.1143)
		(layer "In2.Cu")
		(net "L3_85OHM_10INCH_DP")
	)
	(segment
		(start 244.776498 -163.877244)
		(end 244.868954 -163.74491)
		(width 0.1143)
		(layer "In2.Cu")
		(net "L3_85OHM_10INCH_DP")
	)
	(segment
		(start 285.987998 -166.371016)
		(end 286.48914 -166.28237)
		(width 0.1143)
		(layer "In2.Cu")
		(net "L3_85OHM_10INCH_DP")
	)
	(segment
		(start 300.74362 -163.847526)
		(end 300.836076 -163.714684)
		(width 0.1143)
		(layer "In2.Cu")
		(net "L3_85OHM_10INCH_DP")
	)
	(segment
		(start 262.730996 -165.93566)
		(end 262.368792 -163.881816)
		(width 0.1143)
		(layer "In2.Cu")
		(net "L3_85OHM_10INCH_DP")
	)
	(segment
		(start 264.867136 -166.127684)
		(end 265.197336 -166.359078)
		(width 0.1143)
		(layer "In2.Cu")
		(net "L3_85OHM_10INCH_DP")
	)
	(segment
		(start 248.354596 -166.03091)
		(end 247.973596 -163.869116)
		(width 0.1143)
		(layer "In2.Cu")
		(net "L3_85OHM_10INCH_DP")
	)
	(segment
		(start 246.375682 -163.877498)
		(end 246.468138 -163.745164)
		(width 0.1143)
		(layer "In2.Cu")
		(net "L3_85OHM_10INCH_DP")
	)
	(segment
		(start 266.79525 -166.350442)
		(end 267.296646 -166.262558)
		(width 0.1143)
		(layer "In2.Cu")
		(net "L3_85OHM_10INCH_DP")
	)
	(segment
		(start 245.155466 -166.024306)
		(end 244.776498 -163.877244)
		(width 0.1143)
		(layer "In2.Cu")
		(net "L3_85OHM_10INCH_DP")
	)
	(segment
		(start 295.263062 -166.19093)
		(end 295.594024 -166.42207)
		(width 0.1143)
		(layer "In2.Cu")
		(net "L3_85OHM_10INCH_DP")
	)
	(segment
		(start 244.868954 -163.74491)
		(end 245.131844 -163.698682)
		(width 0.1143)
		(layer "In2.Cu")
		(net "L3_85OHM_10INCH_DP")
	)
	(segment
		(start 243.664232 -163.786312)
		(end 244.091968 -166.212012)
		(width 0.1143)
		(layer "In2.Cu")
		(net "L3_85OHM_10INCH_DP")
	)
	(segment
		(start 285.657798 -166.139876)
		(end 285.987998 -166.371016)
		(width 0.1143)
		(layer "In2.Cu")
		(net "L3_85OHM_10INCH_DP")
	)
	(segment
		(start 293.994332 -166.417244)
		(end 294.495474 -166.329614)
		(width 0.1143)
		(layer "In2.Cu")
		(net "L3_85OHM_10INCH_DP")
	)
	(segment
		(start 251.31649 -166.332408)
		(end 251.54763 -166.000938)
		(width 0.1143)
		(layer "In2.Cu")
		(net "L3_85OHM_10INCH_DP")
	)
	(segment
		(start 248.328688 -163.690554)
		(end 248.460768 -163.78301)
		(width 0.1143)
		(layer "In2.Cu")
		(net "L3_85OHM_10INCH_DP")
	)
	(segment
		(start 251.660152 -163.787582)
		(end 252.084078 -166.189406)
		(width 0.1143)
		(layer "In2.Cu")
		(net "L3_85OHM_10INCH_DP")
	)
	(segment
		(start 275.290026 -166.251128)
		(end 275.521166 -165.920166)
		(width 0.1143)
		(layer "In2.Cu")
		(net "L3_85OHM_10INCH_DP")
	)
	(segment
		(start 272.053558 -163.733226)
		(end 272.315686 -163.687506)
		(width 0.1143)
		(layer "In2.Cu")
		(net "L3_85OHM_10INCH_DP")
	)
	(segment
		(start 297.69435 -166.333932)
		(end 297.92549 -166.00297)
		(width 0.1143)
		(layer "In2.Cu")
		(net "L3_85OHM_10INCH_DP")
	)
	(segment
		(start 291.530024 -166.006526)
		(end 291.15258 -163.866576)
		(width 0.1143)
		(layer "In2.Cu")
		(net "L3_85OHM_10INCH_DP")
	)
	(segment
		(start 261.25678 -163.795456)
		(end 261.667752 -166.123366)
		(width 0.1143)
		(layer "In2.Cu")
		(net "L3_85OHM_10INCH_DP")
	)
	(segment
		(start 265.197336 -166.359078)
		(end 265.698732 -166.27094)
		(width 0.1143)
		(layer "In2.Cu")
		(net "L3_85OHM_10INCH_DP")
	)
	(segment
		(start 268.394434 -166.350696)
		(end 268.89583 -166.262812)
		(width 0.1143)
		(layer "In2.Cu")
		(net "L3_85OHM_10INCH_DP")
	)
	(segment
		(start 249.573034 -163.86937)
		(end 249.665236 -163.736782)
		(width 0.1143)
		(layer "In2.Cu")
		(net "L3_85OHM_10INCH_DP")
	)
	(segment
		(start 254.746506 -166.005256)
		(end 254.369062 -163.86556)
		(width 0.1143)
		(layer "In2.Cu")
		(net "L3_85OHM_10INCH_DP")
	)
	(segment
		(start 255.968246 -163.86556)
		(end 256.060702 -163.732972)
		(width 0.1143)
		(layer "In2.Cu")
		(net "L3_85OHM_10INCH_DP")
	)
	(segment
		(start 268.063218 -166.119556)
		(end 268.394434 -166.350696)
		(width 0.1143)
		(layer "In2.Cu")
		(net "L3_85OHM_10INCH_DP")
	)
	(segment
		(start 267.166344 -163.882324)
		(end 267.259054 -163.749736)
		(width 0.1143)
		(layer "In2.Cu")
		(net "L3_85OHM_10INCH_DP")
	)
	(segment
		(start 251.527564 -163.695126)
		(end 251.660152 -163.787582)
		(width 0.1143)
		(layer "In2.Cu")
		(net "L3_85OHM_10INCH_DP")
	)
	(segment
		(start 292.394894 -166.417244)
		(end 292.89629 -166.32936)
		(width 0.1143)
		(layer "In2.Cu")
		(net "L3_85OHM_10INCH_DP")
	)
	(segment
		(start 264.451338 -163.772088)
		(end 264.867136 -166.127684)
		(width 0.1143)
		(layer "In2.Cu")
		(net "L3_85OHM_10INCH_DP")
	)
	(segment
		(start 297.899836 -163.66363)
		(end 298.032424 -163.756086)
		(width 0.1143)
		(layer "In2.Cu")
		(net "L3_85OHM_10INCH_DP")
	)
	(segment
		(start 256.105406 -166.33444)
		(end 256.343404 -165.993572)
		(width 0.1143)
		(layer "In2.Cu")
		(net "L3_85OHM_10INCH_DP")
	)
	(segment
		(start 286.712406 -163.710874)
		(end 286.84474 -163.803584)
		(width 0.1143)
		(layer "In2.Cu")
		(net "L3_85OHM_10INCH_DP")
	)
	(segment
		(start 243.176552 -163.873688)
		(end 243.26977 -163.740592)
		(width 0.1143)
		(layer "In2.Cu")
		(net "L3_85OHM_10INCH_DP")
	)
	(segment
		(start 301.098458 -163.668456)
		(end 301.2313 -163.761674)
		(width 0.1143)
		(layer "In2.Cu")
		(net "L3_85OHM_10INCH_DP")
	)
	(segment
		(start 271.960848 -163.866322)
		(end 272.053558 -163.733226)
		(width 0.1143)
		(layer "In2.Cu")
		(net "L3_85OHM_10INCH_DP")
	)
	(segment
		(start 282.043378 -163.78174)
		(end 282.453842 -166.108888)
		(width 0.1143)
		(layer "In2.Cu")
		(net "L3_85OHM_10INCH_DP")
	)
	(segment
		(start 278.71166 -163.683696)
		(end 278.844248 -163.776152)
		(width 0.1143)
		(layer "In2.Cu")
		(net "L3_85OHM_10INCH_DP")
	)
	(segment
		(start 255.280414 -166.181024)
		(end 255.620774 -166.41953)
		(width 0.1143)
		(layer "In2.Cu")
		(net "L3_85OHM_10INCH_DP")
	)
	(segment
		(start 299.292264 -166.32555)
		(end 299.523404 -165.994588)
		(width 0.1143)
		(layer "In2.Cu")
		(net "L3_85OHM_10INCH_DP")
	)
	(segment
		(start 294.839136 -163.78555)
		(end 295.263062 -166.19093)
		(width 0.1143)
		(layer "In2.Cu")
		(net "L3_85OHM_10INCH_DP")
	)
	(segment
		(start 288.051748 -163.772596)
		(end 288.314384 -163.726368)
		(width 0.1143)
		(layer "In2.Cu")
		(net "L3_85OHM_10INCH_DP")
	)
	(segment
		(start 281.648154 -163.734496)
		(end 281.910282 -163.688522)
		(width 0.1143)
		(layer "In2.Cu")
		(net "L3_85OHM_10INCH_DP")
	)
	(segment
		(start 246.730774 -163.698936)
		(end 246.863616 -163.791646)
		(width 0.1143)
		(layer "In2.Cu")
		(net "L3_85OHM_10INCH_DP")
	)
	(segment
		(start 245.131844 -163.698682)
		(end 245.264686 -163.791392)
		(width 0.1143)
		(layer "In2.Cu")
		(net "L3_85OHM_10INCH_DP")
	)
	(segment
		(start 242.340638 -165.426136)
		(end 242.385596 -165.60292)
		(width 0.1143)
		(layer "In2.Cu")
		(net "L3_85OHM_10INCH_DP")
	)
	(segment
		(start 296.095166 -166.333678)
		(end 296.326052 -166.003224)
		(width 0.1143)
		(layer "In2.Cu")
		(net "L3_85OHM_10INCH_DP")
	)
	(segment
		(start 259.534406 -165.943534)
		(end 259.170678 -163.881816)
		(width 0.1143)
		(layer "In2.Cu")
		(net "L3_85OHM_10INCH_DP")
	)
	(segment
		(start 304.162206 -165.135052)
		(end 305.293776 -165.044374)
		(width 0.1143)
		(layer "In2.Cu")
		(net "L3_85OHM_10INCH_DP")
	)
	(segment
		(start 243.532406 -163.69411)
		(end 243.664232 -163.786312)
		(width 0.1143)
		(layer "In2.Cu")
		(net "L3_85OHM_10INCH_DP")
	)
	(segment
		(start 284.05582 -166.124382)
		(end 284.38602 -166.355522)
		(width 0.1143)
		(layer "In2.Cu")
		(net "L3_85OHM_10INCH_DP")
	)
	(segment
		(start 257.672332 -163.747196)
		(end 257.918204 -163.704016)
		(width 0.1143)
		(layer "In2.Cu")
		(net "L3_85OHM_10INCH_DP")
	)
	(segment
		(start 263.267444 -166.127938)
		(end 263.598406 -166.359078)
		(width 0.1143)
		(layer "In2.Cu")
		(net "L3_85OHM_10INCH_DP")
	)
	(segment
		(start 278.356314 -163.86175)
		(end 278.449278 -163.72967)
		(width 0.1143)
		(layer "In2.Cu")
		(net "L3_85OHM_10INCH_DP")
	)
	(segment
		(start 276.889718 -166.255192)
		(end 277.120604 -165.924738)
		(width 0.1143)
		(layer "In2.Cu")
		(net "L3_85OHM_10INCH_DP")
	)
	(segment
		(start 256.323338 -163.686744)
		(end 256.455926 -163.779454)
		(width 0.1143)
		(layer "In2.Cu")
		(net "L3_85OHM_10INCH_DP")
	)
	(segment
		(start 284.852872 -163.770564)
		(end 285.115508 -163.724336)
		(width 0.1143)
		(layer "In2.Cu")
		(net "L3_85OHM_10INCH_DP")
	)
	(segment
		(start 299.63237 -163.760912)
		(end 300.058836 -166.182548)
		(width 0.1143)
		(layer "In2.Cu")
		(net "L3_85OHM_10INCH_DP")
	)
	(segment
		(start 273.922236 -165.919658)
		(end 273.559778 -163.866322)
		(width 0.1143)
		(layer "In2.Cu")
		(net "L3_85OHM_10INCH_DP")
	)
	(segment
		(start 260.862318 -163.749228)
		(end 261.124446 -163.703)
		(width 0.1143)
		(layer "In2.Cu")
		(net "L3_85OHM_10INCH_DP")
	)
	(segment
		(start 258.801616 -166.362634)
		(end 259.303012 -166.27475)
		(width 0.1143)
		(layer "In2.Cu")
		(net "L3_85OHM_10INCH_DP")
	)
	(segment
		(start 275.158962 -163.866322)
		(end 275.251418 -163.733734)
		(width 0.1143)
		(layer "In2.Cu")
		(net "L3_85OHM_10INCH_DP")
	)
	(segment
		(start 244.091968 -166.212012)
		(end 244.423184 -166.444168)
		(width 0.1143)
		(layer "In2.Cu")
		(net "L3_85OHM_10INCH_DP")
	)
	(segment
		(start 261.998714 -166.354252)
		(end 262.499856 -166.266622)
		(width 0.1143)
		(layer "In2.Cu")
		(net "L3_85OHM_10INCH_DP")
	)
	(segment
		(start 293.127684 -165.998144)
		(end 292.752272 -163.870894)
		(width 0.1143)
		(layer "In2.Cu")
		(net "L3_85OHM_10INCH_DP")
	)
	(segment
		(start 261.667752 -166.123366)
		(end 261.998714 -166.354252)
		(width 0.1143)
		(layer "In2.Cu")
		(net "L3_85OHM_10INCH_DP")
	)
	(segment
		(start 289.930332 -166.005256)
		(end 289.555682 -163.878514)
		(width 0.1143)
		(layer "In2.Cu")
		(net "L3_85OHM_10INCH_DP")
	)
	(segment
		(start 270.71828 -163.69538)
		(end 270.850614 -163.78809)
		(width 0.1143)
		(layer "In2.Cu")
		(net "L3_85OHM_10INCH_DP")
	)
	(segment
		(start 279.957276 -163.871148)
		(end 280.049986 -163.73856)
		(width 0.1143)
		(layer "In2.Cu")
		(net "L3_85OHM_10INCH_DP")
	)
	(segment
		(start 258.470654 -166.131748)
		(end 258.801616 -166.362634)
		(width 0.1143)
		(layer "In2.Cu")
		(net "L3_85OHM_10INCH_DP")
	)
	(segment
		(start 302.438308 -163.730686)
		(end 302.700944 -163.684458)
		(width 0.1143)
		(layer "In2.Cu")
		(net "L3_85OHM_10INCH_DP")
	)
	(segment
		(start 245.264686 -163.791392)
		(end 245.690898 -166.213028)
		(width 0.1143)
		(layer "In2.Cu")
		(net "L3_85OHM_10INCH_DP")
	)
	(segment
		(start 252.771402 -163.873942)
		(end 252.864112 -163.741354)
		(width 0.1143)
		(layer "In2.Cu")
		(net "L3_85OHM_10INCH_DP")
	)
	(segment
		(start 248.460768 -163.78301)
		(end 248.890028 -166.216584)
		(width 0.1143)
		(layer "In2.Cu")
		(net "L3_85OHM_10INCH_DP")
	)
	(segment
		(start 285.247842 -163.817046)
		(end 285.657798 -166.139876)
		(width 0.1143)
		(layer "In2.Cu")
		(net "L3_85OHM_10INCH_DP")
	)
	(segment
		(start 252.91542 -166.332408)
		(end 253.146814 -166.001192)
		(width 0.1143)
		(layer "In2.Cu")
		(net "L3_85OHM_10INCH_DP")
	)
	(segment
		(start 302.490632 -166.329868)
		(end 302.722534 -165.998652)
		(width 0.1143)
		(layer "In2.Cu")
		(net "L3_85OHM_10INCH_DP")
	)
	(segment
		(start 286.44977 -163.757102)
		(end 286.712406 -163.710874)
		(width 0.1143)
		(layer "In2.Cu")
		(net "L3_85OHM_10INCH_DP")
	)
	(segment
		(start 293.66337 -166.186358)
		(end 293.994332 -166.417244)
		(width 0.1143)
		(layer "In2.Cu")
		(net "L3_85OHM_10INCH_DP")
	)
	(segment
		(start 273.914616 -163.687506)
		(end 274.04695 -163.779962)
		(width 0.1143)
		(layer "In2.Cu")
		(net "L3_85OHM_10INCH_DP")
	)
	(segment
		(start 265.92149 -163.69919)
		(end 266.054078 -163.791646)
		(width 0.1143)
		(layer "In2.Cu")
		(net "L3_85OHM_10INCH_DP")
	)
	(segment
		(start 292.752272 -163.870894)
		(end 292.844982 -163.738306)
		(width 0.1143)
		(layer "In2.Cu")
		(net "L3_85OHM_10INCH_DP")
	)
	(segment
		(start 248.890028 -166.216584)
		(end 249.22099 -166.449248)
		(width 0.1143)
		(layer "In2.Cu")
		(net "L3_85OHM_10INCH_DP")
	)
	(segment
		(start 282.784042 -166.340028)
		(end 283.285184 -166.251382)
		(width 0.1143)
		(layer "In2.Cu")
		(net "L3_85OHM_10INCH_DP")
	)
	(segment
		(start 268.765274 -163.882832)
		(end 268.857984 -163.74999)
		(width 0.1143)
		(layer "In2.Cu")
		(net "L3_85OHM_10INCH_DP")
	)
	(segment
		(start 265.698732 -166.27094)
		(end 265.929872 -165.939978)
		(width 0.1143)
		(layer "In2.Cu")
		(net "L3_85OHM_10INCH_DP")
	)
	(segment
		(start 284.760162 -163.903152)
		(end 284.852872 -163.770564)
		(width 0.1143)
		(layer "In2.Cu")
		(net "L3_85OHM_10INCH_DP")
	)
	(segment
		(start 293.10711 -163.692078)
		(end 293.239444 -163.784534)
		(width 0.1143)
		(layer "In2.Cu")
		(net "L3_85OHM_10INCH_DP")
	)
	(segment
		(start 276.057614 -166.112444)
		(end 276.388576 -166.343584)
		(width 0.1143)
		(layer "In2.Cu")
		(net "L3_85OHM_10INCH_DP")
	)
	(segment
		(start 291.507418 -163.68776)
		(end 291.640514 -163.78047)
		(width 0.1143)
		(layer "In2.Cu")
		(net "L3_85OHM_10INCH_DP")
	)
	(segment
		(start 263.598406 -166.359078)
		(end 264.099548 -166.270686)
		(width 0.1143)
		(layer "In2.Cu")
		(net "L3_85OHM_10INCH_DP")
	)
	(segment
		(start 249.954034 -166.030148)
		(end 249.573034 -163.86937)
		(width 0.1143)
		(layer "In2.Cu")
		(net "L3_85OHM_10INCH_DP")
	)
	(segment
		(start 296.037762 -163.709858)
		(end 296.300398 -163.663376)
		(width 0.1143)
		(layer "In2.Cu")
		(net "L3_85OHM_10INCH_DP")
	)
	(segment
		(start 259.170678 -163.881816)
		(end 259.263388 -163.74872)
		(width 0.1143)
		(layer "In2.Cu")
		(net "L3_85OHM_10INCH_DP")
	)
	(segment
		(start 291.29863 -166.337742)
		(end 291.530024 -166.006526)
		(width 0.1143)
		(layer "In2.Cu")
		(net "L3_85OHM_10INCH_DP")
	)
	(segment
		(start 259.525516 -163.703)
		(end 259.658612 -163.79571)
		(width 0.1143)
		(layer "In2.Cu")
		(net "L3_85OHM_10INCH_DP")
	)
	(segment
		(start 267.521436 -163.703762)
		(end 267.654024 -163.796472)
		(width 0.1143)
		(layer "In2.Cu")
		(net "L3_85OHM_10INCH_DP")
	)
	(segment
		(start 250.484132 -166.188136)
		(end 250.815094 -166.420292)
		(width 0.1143)
		(layer "In2.Cu")
		(net "L3_85OHM_10INCH_DP")
	)
	(segment
		(start 299.523404 -165.994588)
		(end 299.14469 -163.846764)
		(width 0.1143)
		(layer "In2.Cu")
		(net "L3_85OHM_10INCH_DP")
	)
	(segment
		(start 278.488902 -166.255446)
		(end 278.720042 -165.924484)
		(width 0.1143)
		(layer "In2.Cu")
		(net "L3_85OHM_10INCH_DP")
	)
	(segment
		(start 265.566144 -163.877244)
		(end 265.659108 -163.745164)
		(width 0.1143)
		(layer "In2.Cu")
		(net "L3_85OHM_10INCH_DP")
	)
	(segment
		(start 289.555682 -163.878514)
		(end 289.654996 -163.736274)
		(width 0.1143)
		(layer "In2.Cu")
		(net "L3_85OHM_10INCH_DP")
	)
	(segment
		(start 301.65929 -166.187374)
		(end 301.98949 -166.418514)
		(width 0.1143)
		(layer "In2.Cu")
		(net "L3_85OHM_10INCH_DP")
	)
	(segment
		(start 271.591786 -166.34714)
		(end 272.093182 -166.259256)
		(width 0.1143)
		(layer "In2.Cu")
		(net "L3_85OHM_10INCH_DP")
	)
	(segment
		(start 303.229772 -164.838634)
		(end 304.162206 -165.135052)
		(width 0.1143)
		(layer "In2.Cu")
		(net "L3_85OHM_10INCH_DP")
	)
	(segment
		(start 267.654024 -163.796472)
		(end 268.063218 -166.119556)
		(width 0.1143)
		(layer "In2.Cu")
		(net "L3_85OHM_10INCH_DP")
	)
	(segment
		(start 272.093182 -166.259256)
		(end 272.324576 -165.92804)
		(width 0.1143)
		(layer "In2.Cu")
		(net "L3_85OHM_10INCH_DP")
	)
	(segment
		(start 252.084078 -166.189406)
		(end 252.414786 -166.420546)
		(width 0.1143)
		(layer "In2.Cu")
		(net "L3_85OHM_10INCH_DP")
	)
	(segment
		(start 288.314384 -163.726368)
		(end 288.446718 -163.819078)
		(width 0.1143)
		(layer "In2.Cu")
		(net "L3_85OHM_10INCH_DP")
	)
	(segment
		(start 243.322094 -166.340028)
		(end 243.553488 -166.008812)
		(width 0.1143)
		(layer "In2.Cu")
		(net "L3_85OHM_10INCH_DP")
	)
	(segment
		(start 273.690842 -166.250874)
		(end 273.922236 -165.919658)
		(width 0.1143)
		(layer "In2.Cu")
		(net "L3_85OHM_10INCH_DP")
	)
	(segment
		(start 278.844248 -163.776152)
		(end 279.254204 -166.103808)
		(width 0.1143)
		(layer "In2.Cu")
		(net "L3_85OHM_10INCH_DP")
	)
	(segment
		(start 291.640514 -163.78047)
		(end 292.063932 -166.186358)
		(width 0.1143)
		(layer "In2.Cu")
		(net "L3_85OHM_10INCH_DP")
	)
	(segment
		(start 292.89629 -166.32936)
		(end 293.127684 -165.998144)
		(width 0.1143)
		(layer "In2.Cu")
		(net "L3_85OHM_10INCH_DP")
	)
	(segment
		(start 302.345598 -163.863274)
		(end 302.438308 -163.730686)
		(width 0.1143)
		(layer "In2.Cu")
		(net "L3_85OHM_10INCH_DP")
	)
	(segment
		(start 262.72363 -163.703254)
		(end 262.856472 -163.796472)
		(width 0.1143)
		(layer "In2.Cu")
		(net "L3_85OHM_10INCH_DP")
	)
	(segment
		(start 269.253208 -163.797234)
		(end 269.663672 -166.124382)
		(width 0.1143)
		(layer "In2.Cu")
		(net "L3_85OHM_10INCH_DP")
	)
	(segment
		(start 280.853388 -166.104062)
		(end 281.184604 -166.335202)
		(width 0.1143)
		(layer "In2.Cu")
		(net "L3_85OHM_10INCH_DP")
	)
	(segment
		(start 274.788884 -166.338758)
		(end 275.290026 -166.251128)
		(width 0.1143)
		(layer "In2.Cu")
		(net "L3_85OHM_10INCH_DP")
	)
	(segment
		(start 289.900868 -163.693094)
		(end 290.043108 -163.792662)
		(width 0.1143)
		(layer "In2.Cu")
		(net "L3_85OHM_10INCH_DP")
	)
	(segment
		(start 272.324576 -165.92804)
		(end 271.960848 -163.866322)
		(width 0.1143)
		(layer "In2.Cu")
		(net "L3_85OHM_10INCH_DP")
	)
	(segment
		(start 257.935222 -165.943534)
		(end 257.573018 -163.889436)
		(width 0.1143)
		(layer "In2.Cu")
		(net "L3_85OHM_10INCH_DP")
	)
	(segment
		(start 305.293776 -165.044374)
		(end 305.73599 -165.044374)
		(width 0.1143)
		(layer "In2.Cu")
		(net "L3_85OHM_10INCH_DP")
	)
	(segment
		(start 302.700944 -163.684458)
		(end 302.833278 -163.777168)
		(width 0.1143)
		(layer "In2.Cu")
		(net "L3_85OHM_10INCH_DP")
	)
	(segment
		(start 269.663672 -166.124382)
		(end 269.993872 -166.355522)
		(width 0.1143)
		(layer "In2.Cu")
		(net "L3_85OHM_10INCH_DP")
	)
	(segment
		(start 242.820698 -166.428166)
		(end 243.322094 -166.340028)
		(width 0.1143)
		(layer "In2.Cu")
		(net "L3_85OHM_10INCH_DP")
	)
	(segment
		(start 257.20294 -166.362634)
		(end 257.704082 -166.274496)
		(width 0.1143)
		(layer "In2.Cu")
		(net "L3_85OHM_10INCH_DP")
	)
	(segment
		(start 251.264928 -163.7411)
		(end 251.527564 -163.695126)
		(width 0.1143)
		(layer "In2.Cu")
		(net "L3_85OHM_10INCH_DP")
	)
	(segment
		(start 242.385596 -165.60292)
		(end 242.48999 -166.196518)
		(width 0.1143)
		(layer "In2.Cu")
		(net "L3_85OHM_10INCH_DP")
	)
	(segment
		(start 272.448782 -163.780216)
		(end 272.858484 -166.107872)
		(width 0.1143)
		(layer "In2.Cu")
		(net "L3_85OHM_10INCH_DP")
	)
	(segment
		(start 296.326052 -166.003224)
		(end 295.945052 -163.842192)
		(width 0.1143)
		(layer "In2.Cu")
		(net "L3_85OHM_10INCH_DP")
	)
	(segment
		(start 280.049986 -163.73856)
		(end 280.312368 -163.692586)
		(width 0.1143)
		(layer "In2.Cu")
		(net "L3_85OHM_10INCH_DP")
	)
	(segment
		(start 264.099548 -166.270686)
		(end 264.330434 -165.940232)
		(width 0.1143)
		(layer "In2.Cu")
		(net "L3_85OHM_10INCH_DP")
	)
	(segment
		(start 283.512768 -163.704524)
		(end 283.645356 -163.797234)
		(width 0.1143)
		(layer "In2.Cu")
		(net "L3_85OHM_10INCH_DP")
	)
	(segment
		(start 256.343404 -165.993572)
		(end 255.968246 -163.86556)
		(width 0.1143)
		(layer "In2.Cu")
		(net "L3_85OHM_10INCH_DP")
	)
	(segment
		(start 288.446718 -163.819078)
		(end 288.86658 -166.192708)
		(width 0.1143)
		(layer "In2.Cu")
		(net "L3_85OHM_10INCH_DP")
	)
	(segment
		(start 283.517086 -165.920166)
		(end 283.157676 -163.88334)
		(width 0.1143)
		(layer "In2.Cu")
		(net "L3_85OHM_10INCH_DP")
	)
	(segment
		(start 281.555444 -163.867338)
		(end 281.648154 -163.734496)
		(width 0.1143)
		(layer "In2.Cu")
		(net "L3_85OHM_10INCH_DP")
	)
	(segment
		(start 285.119064 -165.93566)
		(end 284.760162 -163.903152)
		(width 0.1143)
		(layer "In2.Cu")
		(net "L3_85OHM_10INCH_DP")
	)
	(segment
		(start 280.444956 -163.785296)
		(end 280.853388 -166.104062)
		(width 0.1143)
		(layer "In2.Cu")
		(net "L3_85OHM_10INCH_DP")
	)
	(segment
		(start 277.657306 -166.11219)
		(end 277.987506 -166.343584)
		(width 0.1143)
		(layer "In2.Cu")
		(net "L3_85OHM_10INCH_DP")
	)
	(segment
		(start 246.863616 -163.791646)
		(end 247.291098 -166.217854)
		(width 0.1143)
		(layer "In2.Cu")
		(net "L3_85OHM_10INCH_DP")
	)
	(segment
		(start 269.993872 -166.355522)
		(end 270.495014 -166.266876)
		(width 0.1143)
		(layer "In2.Cu")
		(net "L3_85OHM_10INCH_DP")
	)
	(segment
		(start 265.659108 -163.745164)
		(end 265.92149 -163.69919)
		(width 0.1143)
		(layer "In2.Cu")
		(net "L3_85OHM_10INCH_DP")
	)
	(segment
		(start 294.443912 -163.738306)
		(end 294.706294 -163.692332)
		(width 0.1143)
		(layer "In2.Cu")
		(net "L3_85OHM_10INCH_DP")
	)
	(segment
		(start 256.060702 -163.732972)
		(end 256.323338 -163.686744)
		(width 0.1143)
		(layer "In2.Cu")
		(net "L3_85OHM_10INCH_DP")
	)
	(segment
		(start 298.459652 -166.182294)
		(end 298.790868 -166.413434)
		(width 0.1143)
		(layer "In2.Cu")
		(net "L3_85OHM_10INCH_DP")
	)
	(segment
		(start 246.754396 -166.025322)
		(end 246.375682 -163.877498)
		(width 0.1143)
		(layer "In2.Cu")
		(net "L3_85OHM_10INCH_DP")
	)
	(segment
		(start 297.192954 -166.42207)
		(end 297.69435 -166.333932)
		(width 0.1143)
		(layer "In2.Cu")
		(net "L3_85OHM_10INCH_DP")
	)
	(segment
		(start 264.05586 -163.725098)
		(end 264.318496 -163.678616)
		(width 0.1143)
		(layer "In2.Cu")
		(net "L3_85OHM_10INCH_DP")
	)
	(segment
		(start 283.645356 -163.797234)
		(end 284.05582 -166.124382)
		(width 0.1143)
		(layer "In2.Cu")
		(net "L3_85OHM_10INCH_DP")
	)
	(segment
		(start 262.856472 -163.796472)
		(end 263.267444 -166.127938)
		(width 0.1143)
		(layer "In2.Cu")
		(net "L3_85OHM_10INCH_DP")
	)
	(segment
		(start 247.973596 -163.869116)
		(end 248.066052 -163.736782)
		(width 0.1143)
		(layer "In2.Cu")
		(net "L3_85OHM_10INCH_DP")
	)
	(segment
		(start 254.724662 -163.686744)
		(end 254.85725 -163.7792)
		(width 0.1143)
		(layer "In2.Cu")
		(net "L3_85OHM_10INCH_DP")
	)
	(segment
		(start 300.891448 -166.325804)
		(end 301.122588 -165.994842)
		(width 0.1143)
		(layer "In2.Cu")
		(net "L3_85OHM_10INCH_DP")
	)
	(segment
		(start 296.43324 -163.756848)
		(end 296.862754 -166.190676)
		(width 0.1143)
		(layer "In2.Cu")
		(net "L3_85OHM_10INCH_DP")
	)
	(segment
		(start 286.48914 -166.28237)
		(end 286.721042 -165.951154)
		(width 0.1143)
		(layer "In2.Cu")
		(net "L3_85OHM_10INCH_DP")
	)
	(segment
		(start 270.455644 -163.741608)
		(end 270.71828 -163.69538)
		(width 0.1143)
		(layer "In2.Cu")
		(net "L3_85OHM_10INCH_DP")
	)
	(segment
		(start 290.466272 -166.19474)
		(end 290.797234 -166.425626)
		(width 0.1143)
		(layer "In2.Cu")
		(net "L3_85OHM_10INCH_DP")
	)
	(segment
		(start 261.124446 -163.703)
		(end 261.25678 -163.795456)
		(width 0.1143)
		(layer "In2.Cu")
		(net "L3_85OHM_10INCH_DP")
	)
	(segment
		(start 292.844982 -163.738306)
		(end 293.10711 -163.692078)
		(width 0.1143)
		(layer "In2.Cu")
		(net "L3_85OHM_10INCH_DP")
	)
	(segment
		(start 270.495014 -166.266876)
		(end 270.726916 -165.93566)
		(width 0.1143)
		(layer "In2.Cu")
		(net "L3_85OHM_10INCH_DP")
	)
	(segment
		(start 305.73599 -165.044374)
		(end 306.35194 -165.660324)
		(width 0.1143)
		(layer "In2.Cu")
		(net "L3_85OHM_10INCH_DP")
	)
	(segment
		(start 271.260824 -166.116254)
		(end 271.591786 -166.34714)
		(width 0.1143)
		(layer "In2.Cu")
		(net "L3_85OHM_10INCH_DP")
	)
	(segment
		(start 275.646642 -163.780978)
		(end 276.057614 -166.112444)
		(width 0.1143)
		(layer "In2.Cu")
		(net "L3_85OHM_10INCH_DP")
	)
	(segment
		(start 260.769608 -163.881816)
		(end 260.862318 -163.749228)
		(width 0.1143)
		(layer "In2.Cu")
		(net "L3_85OHM_10INCH_DP")
	)
	(segment
		(start 294.495474 -166.329614)
		(end 294.726614 -165.998652)
		(width 0.1143)
		(layer "In2.Cu")
		(net "L3_85OHM_10INCH_DP")
	)
	(segment
		(start 287.589976 -166.38651)
		(end 288.091118 -166.297864)
		(width 0.1143)
		(layer "In2.Cu")
		(net "L3_85OHM_10INCH_DP")
	)
	(segment
		(start 280.317956 -165.916102)
		(end 279.957276 -163.871148)
		(width 0.1143)
		(layer "In2.Cu")
		(net "L3_85OHM_10INCH_DP")
	)
	(segment
		(start 288.32302 -165.966648)
		(end 287.959038 -163.905184)
		(width 0.1143)
		(layer "In2.Cu")
		(net "L3_85OHM_10INCH_DP")
	)
	(segment
		(start 265.929872 -165.939978)
		(end 265.566144 -163.877244)
		(width 0.1143)
		(layer "In2.Cu")
		(net "L3_85OHM_10INCH_DP")
	)
	(segment
		(start 296.862754 -166.190676)
		(end 297.192954 -166.42207)
		(width 0.1143)
		(layer "In2.Cu")
		(net "L3_85OHM_10INCH_DP")
	)
	(segment
		(start 279.254204 -166.103808)
		(end 279.58542 -166.334948)
		(width 0.1143)
		(layer "In2.Cu")
		(net "L3_85OHM_10INCH_DP")
	)
	(segment
		(start 264.318496 -163.678616)
		(end 264.451338 -163.772088)
		(width 0.1143)
		(layer "In2.Cu")
		(net "L3_85OHM_10INCH_DP")
	)
	(segment
		(start 281.910282 -163.688522)
		(end 282.043378 -163.78174)
		(width 0.1143)
		(layer "In2.Cu")
		(net "L3_85OHM_10INCH_DP")
	)
	(segment
		(start 281.184604 -166.335202)
		(end 281.686 -166.247318)
		(width 0.1143)
		(layer "In2.Cu")
		(net "L3_85OHM_10INCH_DP")
	)
	(segment
		(start 290.043108 -163.792662)
		(end 290.466272 -166.19474)
		(width 0.1143)
		(layer "In2.Cu")
		(net "L3_85OHM_10INCH_DP")
	)
	(segment
		(start 267.296646 -166.262558)
		(end 267.527786 -165.931596)
		(width 0.1143)
		(layer "In2.Cu")
		(net "L3_85OHM_10INCH_DP")
	)
	(segment
		(start 254.515112 -166.337234)
		(end 254.746506 -166.005256)
		(width 0.1143)
		(layer "In2.Cu")
		(net "L3_85OHM_10INCH_DP")
	)
	(segment
		(start 259.303012 -166.27475)
		(end 259.534406 -165.943534)
		(width 0.1143)
		(layer "In2.Cu")
		(net "L3_85OHM_10INCH_DP")
	)
	(segment
		(start 291.15258 -163.866576)
		(end 291.24529 -163.73348)
		(width 0.1143)
		(layer "In2.Cu")
		(net "L3_85OHM_10INCH_DP")
	)
	(segment
		(start 281.686 -166.247318)
		(end 281.91714 -165.916356)
		(width 0.1143)
		(layer "In2.Cu")
		(net "L3_85OHM_10INCH_DP")
	)
	(segment
		(start 287.959038 -163.905184)
		(end 288.051748 -163.772596)
		(width 0.1143)
		(layer "In2.Cu")
		(net "L3_85OHM_10INCH_DP")
	)
	(segment
		(start 262.368792 -163.881816)
		(end 262.461248 -163.749228)
		(width 0.1143)
		(layer "In2.Cu")
		(net "L3_85OHM_10INCH_DP")
	)
	(segment
		(start 293.239444 -163.784534)
		(end 293.66337 -166.186358)
		(width 0.1143)
		(layer "In2.Cu")
		(net "L3_85OHM_10INCH_DP")
	)
	(segment
		(start 239.238282 -165.667436)
		(end 239.854232 -165.051486)
		(width 0.1143)
		(layer "In2.Cu")
		(net "L3_85OHM_10INCH_DP")
	)
	(segment
		(start 256.455926 -163.779454)
		(end 256.871978 -166.131494)
		(width 0.1143)
		(layer "In2.Cu")
		(net "L3_85OHM_10INCH_DP")
	)
	(segment
		(start 294.351456 -163.870894)
		(end 294.443912 -163.738306)
		(width 0.1143)
		(layer "In2.Cu")
		(net "L3_85OHM_10INCH_DP")
	)
	(segment
		(start 276.849586 -163.729924)
		(end 277.112222 -163.683442)
		(width 0.1143)
		(layer "In2.Cu")
		(net "L3_85OHM_10INCH_DP")
	)
	(segment
		(start 270.726916 -165.93566)
		(end 270.362934 -163.874196)
		(width 0.1143)
		(layer "In2.Cu")
		(net "L3_85OHM_10INCH_DP")
	)
	(segment
		(start 272.315686 -163.687506)
		(end 272.448782 -163.780216)
		(width 0.1143)
		(layer "In2.Cu")
		(net "L3_85OHM_10INCH_DP")
	)
	(segment
		(start 254.369062 -163.86556)
		(end 254.461772 -163.732972)
		(width 0.1143)
		(layer "In2.Cu")
		(net "L3_85OHM_10INCH_DP")
	)
	(segment
		(start 267.259054 -163.749736)
		(end 267.521436 -163.703762)
		(width 0.1143)
		(layer "In2.Cu")
		(net "L3_85OHM_10INCH_DP")
	)
	(segment
		(start 286.84474 -163.803584)
		(end 287.259776 -166.15537)
		(width 0.1143)
		(layer "In2.Cu")
		(net "L3_85OHM_10INCH_DP")
	)
	(segment
		(start 253.146814 -166.001192)
		(end 252.771402 -163.873942)
		(width 0.1143)
		(layer "In2.Cu")
		(net "L3_85OHM_10INCH_DP")
	)
	(segment
		(start 298.790868 -166.413434)
		(end 299.292264 -166.32555)
		(width 0.1143)
		(layer "In2.Cu")
		(net "L3_85OHM_10INCH_DP")
	)
	(segment
		(start 295.594024 -166.42207)
		(end 296.095166 -166.333678)
		(width 0.1143)
		(layer "In2.Cu")
		(net "L3_85OHM_10INCH_DP")
	)
	(segment
		(start 286.35706 -163.88969)
		(end 286.44977 -163.757102)
		(width 0.1143)
		(layer "In2.Cu")
		(net "L3_85OHM_10INCH_DP")
	)
	(segment
		(start 250.815094 -166.420292)
		(end 251.31649 -166.332408)
		(width 0.1143)
		(layer "In2.Cu")
		(net "L3_85OHM_10INCH_DP")
	)
	(via
		(at 239.238282 -164.143436)
		(size 0.5588)
		(drill 0.3048)
		(layers "F.Cu" "B.Cu")
		(net "L3_85OHM_10INCH_DN")
	)
	(via
		(at 306.35194 -164.136324)
		(size 0.5588)
		(drill 0.3048)
		(layers "F.Cu" "B.Cu")
		(net "L3_85OHM_10INCH_DN")
	)
	(segment
		(start 307.572918 -164.412168)
		(end 307.232812 -164.752274)
		(width 0.1143)
		(layer "B.Cu")
		(net "L3_85OHM_10INCH_DN")
	)
	(segment
		(start 306.96789 -164.752274)
		(end 306.35194 -164.136324)
		(width 0.1143)
		(layer "B.Cu")
		(net "L3_85OHM_10INCH_DN")
	)
	(segment
		(start 238.622332 -164.759386)
		(end 239.238282 -164.143436)
		(width 0.1143)
		(layer "B.Cu")
		(net "L3_85OHM_10INCH_DN")
	)
	(segment
		(start 307.232812 -164.752274)
		(end 306.96789 -164.752274)
		(width 0.1143)
		(layer "B.Cu")
		(net "L3_85OHM_10INCH_DN")
	)
	(segment
		(start 238.378746 -164.759386)
		(end 238.622332 -164.759386)
		(width 0.1143)
		(layer "B.Cu")
		(net "L3_85OHM_10INCH_DN")
	)
	(segment
		(start 238.017304 -164.397944)
		(end 238.378746 -164.759386)
		(width 0.1143)
		(layer "B.Cu")
		(net "L3_85OHM_10INCH_DN")
	)
	(segment
		(start 260.730492 -165.999414)
		(end 260.467602 -166.045642)
		(width 0.1143)
		(layer "In2.Cu")
		(net "L3_85OHM_10INCH_DN")
	)
	(segment
		(start 298.299124 -163.585906)
		(end 297.968162 -163.35502)
		(width 0.1143)
		(layer "In2.Cu")
		(net "L3_85OHM_10INCH_DN")
	)
	(segment
		(start 296.017188 -165.93439)
		(end 295.924986 -166.066978)
		(width 0.1143)
		(layer "In2.Cu")
		(net "L3_85OHM_10INCH_DN")
	)
	(segment
		(start 257.271266 -166.054024)
		(end 257.138678 -165.961314)
		(width 0.1143)
		(layer "In2.Cu")
		(net "L3_85OHM_10INCH_DN")
	)
	(segment
		(start 279.88006 -163.471606)
		(end 279.648412 -163.802822)
		(width 0.1143)
		(layer "In2.Cu")
		(net "L3_85OHM_10INCH_DN")
	)
	(segment
		(start 244.491764 -166.135304)
		(end 244.358922 -166.042086)
		(width 0.1143)
		(layer "In2.Cu")
		(net "L3_85OHM_10INCH_DN")
	)
	(segment
		(start 278.04745 -163.792916)
		(end 278.411178 -165.856158)
		(width 0.1143)
		(layer "In2.Cu")
		(net "L3_85OHM_10INCH_DN")
	)
	(segment
		(start 281.120088 -165.933882)
		(end 280.71191 -163.615116)
		(width 0.1143)
		(layer "In2.Cu")
		(net "L3_85OHM_10INCH_DN")
	)
	(segment
		(start 265.133836 -165.957758)
		(end 264.718292 -163.602416)
		(width 0.1143)
		(layer "In2.Cu")
		(net "L3_85OHM_10INCH_DN")
	)
	(segment
		(start 276.324314 -165.942264)
		(end 275.913596 -163.611052)
		(width 0.1143)
		(layer "In2.Cu")
		(net "L3_85OHM_10INCH_DN")
	)
	(segment
		(start 263.885934 -163.458398)
		(end 263.654286 -163.788852)
		(width 0.1143)
		(layer "In2.Cu")
		(net "L3_85OHM_10INCH_DN")
	)
	(segment
		(start 292.330632 -166.016178)
		(end 291.907468 -163.610036)
		(width 0.1143)
		(layer "In2.Cu")
		(net "L3_85OHM_10INCH_DN")
	)
	(segment
		(start 258.861814 -163.813744)
		(end 259.225542 -165.875208)
		(width 0.1143)
		(layer "In2.Cu")
		(net "L3_85OHM_10INCH_DN")
	)
	(segment
		(start 289.969448 -163.38423)
		(end 289.484816 -163.46932)
		(width 0.1143)
		(layer "In2.Cu")
		(net "L3_85OHM_10INCH_DN")
	)
	(segment
		(start 274.31365 -163.609782)
		(end 273.982942 -163.378642)
		(width 0.1143)
		(layer "In2.Cu")
		(net "L3_85OHM_10INCH_DN")
	)
	(segment
		(start 305.281838 -164.752274)
		(end 304.195988 -164.839142)
		(width 0.1143)
		(layer "In2.Cu")
		(net "L3_85OHM_10INCH_DN")
	)
	(segment
		(start 293.175436 -163.383214)
		(end 292.674802 -163.471352)
		(width 0.1143)
		(layer "In2.Cu")
		(net "L3_85OHM_10INCH_DN")
	)
	(segment
		(start 303.204626 -164.20084)
		(end 303.100232 -163.607242)
		(width 0.1143)
		(layer "In2.Cu")
		(net "L3_85OHM_10INCH_DN")
	)
	(segment
		(start 257.264154 -163.82111)
		(end 257.626358 -165.875208)
		(width 0.1143)
		(layer "In2.Cu")
		(net "L3_85OHM_10INCH_DN")
	)
	(segment
		(start 243.244624 -165.940486)
		(end 243.151914 -166.073074)
		(width 0.1143)
		(layer "In2.Cu")
		(net "L3_85OHM_10INCH_DN")
	)
	(segment
		(start 291.575744 -163.37915)
		(end 291.07511 -163.466526)
		(width 0.1143)
		(layer "In2.Cu")
		(net "L3_85OHM_10INCH_DN")
	)
	(segment
		(start 283.581348 -163.39566)
		(end 283.079952 -163.483798)
		(width 0.1143)
		(layer "In2.Cu")
		(net "L3_85OHM_10INCH_DN")
	)
	(segment
		(start 271.883378 -163.466272)
		(end 271.651984 -163.79825)
		(width 0.1143)
		(layer "In2.Cu")
		(net "L3_85OHM_10INCH_DN")
	)
	(segment
		(start 254.792988 -163.378134)
		(end 254.291592 -163.466018)
		(width 0.1143)
		(layer "In2.Cu")
		(net "L3_85OHM_10INCH_DN")
	)
	(segment
		(start 283.079952 -163.483798)
		(end 282.848558 -163.81476)
		(width 0.1143)
		(layer "In2.Cu")
		(net "L3_85OHM_10INCH_DN")
	)
	(segment
		(start 266.85748 -163.813998)
		(end 267.218922 -165.86327)
		(width 0.1143)
		(layer "In2.Cu")
		(net "L3_85OHM_10INCH_DN")
	)
	(segment
		(start 284.716982 -166.000176)
		(end 284.454346 -166.046658)
		(width 0.1143)
		(layer "In2.Cu")
		(net "L3_85OHM_10INCH_DN")
	)
	(segment
		(start 301.92599 -166.017448)
		(end 301.498254 -163.591748)
		(width 0.1143)
		(layer "In2.Cu")
		(net "L3_85OHM_10INCH_DN")
	)
	(segment
		(start 255.935226 -166.067486)
		(end 255.689354 -166.110666)
		(width 0.1143)
		(layer "In2.Cu")
		(net "L3_85OHM_10INCH_DN")
	)
	(segment
		(start 240.296446 -164.759386)
		(end 239.854232 -164.759386)
		(width 0.1143)
		(layer "In2.Cu")
		(net "L3_85OHM_10INCH_DN")
	)
	(segment
		(start 242.36045 -164.965126)
		(end 241.428016 -164.668708)
		(width 0.1143)
		(layer "In2.Cu")
		(net "L3_85OHM_10INCH_DN")
	)
	(segment
		(start 264.02157 -165.871398)
		(end 263.929368 -166.003986)
		(width 0.1143)
		(layer "In2.Cu")
		(net "L3_85OHM_10INCH_DN")
	)
	(segment
		(start 265.48969 -163.47821)
		(end 265.25728 -163.80841)
		(width 0.1143)
		(layer "In2.Cu")
		(net "L3_85OHM_10INCH_DN")
	)
	(segment
		(start 299.568362 -163.359592)
		(end 299.067474 -163.447222)
		(width 0.1143)
		(layer "In2.Cu")
		(net "L3_85OHM_10INCH_DN")
	)
	(segment
		(start 248.397268 -163.38169)
		(end 247.895872 -163.469828)
		(width 0.1143)
		(layer "In2.Cu")
		(net "L3_85OHM_10INCH_DN")
	)
	(segment
		(start 270.418052 -165.86708)
		(end 270.324834 -166.000176)
		(width 0.1143)
		(layer "In2.Cu")
		(net "L3_85OHM_10INCH_DN")
	)
	(segment
		(start 252.693932 -163.4744)
		(end 252.462538 -163.805616)
		(width 0.1143)
		(layer "In2.Cu")
		(net "L3_85OHM_10INCH_DN")
	)
	(segment
		(start 294.062658 -166.108634)
		(end 293.93007 -166.016178)
		(width 0.1143)
		(layer "In2.Cu")
		(net "L3_85OHM_10INCH_DN")
	)
	(segment
		(start 270.78686 -163.386516)
		(end 270.285464 -163.474654)
		(width 0.1143)
		(layer "In2.Cu")
		(net "L3_85OHM_10INCH_DN")
	)
	(segment
		(start 244.754146 -166.089076)
		(end 244.491764 -166.135304)
		(width 0.1143)
		(layer "In2.Cu")
		(net "L3_85OHM_10INCH_DN")
	)
	(segment
		(start 270.062198 -166.046658)
		(end 269.930372 -165.954456)
		(width 0.1143)
		(layer "In2.Cu")
		(net "L3_85OHM_10INCH_DN")
	)
	(segment
		(start 275.081238 -163.46678)
		(end 274.850098 -163.79825)
		(width 0.1143)
		(layer "In2.Cu")
		(net "L3_85OHM_10INCH_DN")
	)
	(segment
		(start 273.482308 -163.46678)
		(end 273.250914 -163.797996)
		(width 0.1143)
		(layer "In2.Cu")
		(net "L3_85OHM_10INCH_DN")
	)
	(segment
		(start 297.52417 -166.066978)
		(end 297.261534 -166.113206)
		(width 0.1143)
		(layer "In2.Cu")
		(net "L3_85OHM_10INCH_DN")
	)
	(segment
		(start 247.664732 -163.80079)
		(end 248.045732 -165.962076)
		(width 0.1143)
		(layer "In2.Cu")
		(net "L3_85OHM_10INCH_DN")
	)
	(segment
		(start 290.843716 -163.798504)
		(end 291.22116 -165.9382)
		(width 0.1143)
		(layer "In2.Cu")
		(net "L3_85OHM_10INCH_DN")
	)
	(segment
		(start 300.434756 -163.779454)
		(end 300.813724 -165.926516)
		(width 0.1143)
		(layer "In2.Cu")
		(net "L3_85OHM_10INCH_DN")
	)
	(segment
		(start 276.456902 -166.034974)
		(end 276.324314 -165.942264)
		(width 0.1143)
		(layer "In2.Cu")
		(net "L3_85OHM_10INCH_DN")
	)
	(segment
		(start 243.151914 -166.073074)
		(end 242.889278 -166.119302)
		(width 0.1143)
		(layer "In2.Cu")
		(net "L3_85OHM_10INCH_DN")
	)
	(segment
		(start 274.850098 -163.79825)
		(end 275.212302 -165.85184)
		(width 0.1143)
		(layer "In2.Cu")
		(net "L3_85OHM_10INCH_DN")
	)
	(segment
		(start 252.83795 -165.932866)
		(end 252.74524 -166.065454)
		(width 0.1143)
		(layer "In2.Cu")
		(net "L3_85OHM_10INCH_DN")
	)
	(segment
		(start 283.912056 -163.627308)
		(end 283.581348 -163.39566)
		(width 0.1143)
		(layer "In2.Cu")
		(net "L3_85OHM_10INCH_DN")
	)
	(segment
		(start 287.111694 -163.633658)
		(end 286.780986 -163.40201)
		(width 0.1143)
		(layer "In2.Cu")
		(net "L3_85OHM_10INCH_DN")
	)
	(segment
		(start 283.115004 -165.984682)
		(end 282.852368 -166.031164)
		(width 0.1143)
		(layer "In2.Cu")
		(net "L3_85OHM_10INCH_DN")
	)
	(segment
		(start 255.689354 -166.110666)
		(end 255.547114 -166.011098)
		(width 0.1143)
		(layer "In2.Cu")
		(net "L3_85OHM_10INCH_DN")
	)
	(segment
		(start 268.818106 -165.863524)
		(end 268.72565 -165.995858)
		(width 0.1143)
		(layer "In2.Cu")
		(net "L3_85OHM_10INCH_DN")
	)
	(segment
		(start 273.520662 -165.98392)
		(end 273.257772 -166.030148)
		(width 0.1143)
		(layer "In2.Cu")
		(net "L3_85OHM_10INCH_DN")
	)
	(segment
		(start 259.225542 -165.875208)
		(end 259.132832 -166.007796)
		(width 0.1143)
		(layer "In2.Cu")
		(net "L3_85OHM_10INCH_DN")
	)
	(segment
		(start 289.484816 -163.46932)
		(end 289.246818 -163.810188)
		(width 0.1143)
		(layer "In2.Cu")
		(net "L3_85OHM_10INCH_DN")
	)
	(segment
		(start 255.12395 -163.60902)
		(end 254.792988 -163.378134)
		(width 0.1143)
		(layer "In2.Cu")
		(net "L3_85OHM_10INCH_DN")
	)
	(segment
		(start 277.924006 -165.942264)
		(end 277.512272 -163.607242)
		(width 0.1143)
		(layer "In2.Cu")
		(net "L3_85OHM_10INCH_DN")
	)
	(segment
		(start 287.658302 -166.077646)
		(end 287.526476 -165.985444)
		(width 0.1143)
		(layer "In2.Cu")
		(net "L3_85OHM_10INCH_DN")
	)
	(segment
		(start 254.437642 -165.937184)
		(end 254.344932 -166.07028)
		(width 0.1143)
		(layer "In2.Cu")
		(net "L3_85OHM_10INCH_DN")
	)
	(segment
		(start 246.09044 -166.135558)
		(end 245.957852 -166.042848)
		(width 0.1143)
		(layer "In2.Cu")
		(net "L3_85OHM_10INCH_DN")
	)
	(segment
		(start 245.20017 -163.390072)
		(end 244.698774 -163.477956)
		(width 0.1143)
		(layer "In2.Cu")
		(net "L3_85OHM_10INCH_DN")
	)
	(segment
		(start 260.460744 -163.81349)
		(end 260.823202 -165.866826)
		(width 0.1143)
		(layer "In2.Cu")
		(net "L3_85OHM_10INCH_DN")
	)
	(segment
		(start 282.310078 -163.611814)
		(end 281.978862 -163.379658)
		(width 0.1143)
		(layer "In2.Cu")
		(net "L3_85OHM_10INCH_DN")
	)
	(segment
		(start 261.192772 -163.394136)
		(end 260.692138 -163.482274)
		(width 0.1143)
		(layer "In2.Cu")
		(net "L3_85OHM_10INCH_DN")
	)
	(segment
		(start 263.654286 -163.788852)
		(end 264.02157 -165.871398)
		(width 0.1143)
		(layer "In2.Cu")
		(net "L3_85OHM_10INCH_DN")
	)
	(segment
		(start 255.890522 -163.466272)
		(end 255.659382 -163.797234)
		(width 0.1143)
		(layer "In2.Cu")
		(net "L3_85OHM_10INCH_DN")
	)
	(segment
		(start 275.582634 -163.378896)
		(end 275.081238 -163.46678)
		(width 0.1143)
		(layer "In2.Cu")
		(net "L3_85OHM_10INCH_DN")
	)
	(segment
		(start 264.718292 -163.602416)
		(end 264.38733 -163.369752)
		(width 0.1143)
		(layer "In2.Cu")
		(net "L3_85OHM_10INCH_DN")
	)
	(segment
		(start 273.250914 -163.797996)
		(end 273.613372 -165.851332)
		(width 0.1143)
		(layer "In2.Cu")
		(net "L3_85OHM_10INCH_DN")
	)
	(segment
		(start 265.25728 -163.80841)
		(end 265.621008 -165.871652)
		(width 0.1143)
		(layer "In2.Cu")
		(net "L3_85OHM_10INCH_DN")
	)
	(segment
		(start 295.529762 -166.02075)
		(end 295.10609 -163.615624)
		(width 0.1143)
		(layer "In2.Cu")
		(net "L3_85OHM_10INCH_DN")
	)
	(segment
		(start 260.823202 -165.866826)
		(end 260.730492 -165.999414)
		(width 0.1143)
		(layer "In2.Cu")
		(net "L3_85OHM_10INCH_DN")
	)
	(segment
		(start 268.45641 -163.81476)
		(end 268.818106 -165.863524)
		(width 0.1143)
		(layer "In2.Cu")
		(net "L3_85OHM_10INCH_DN")
	)
	(segment
		(start 303.407572 -164.588444)
		(end 303.249584 -164.377624)
		(width 0.1143)
		(layer "In2.Cu")
		(net "L3_85OHM_10INCH_DN")
	)
	(segment
		(start 297.129454 -166.02075)
		(end 296.700194 -163.587176)
		(width 0.1143)
		(layer "In2.Cu")
		(net "L3_85OHM_10INCH_DN")
	)
	(segment
		(start 259.093208 -163.481766)
		(end 258.861814 -163.813744)
		(width 0.1143)
		(layer "In2.Cu")
		(net "L3_85OHM_10INCH_DN")
	)
	(segment
		(start 250.883928 -166.111428)
		(end 250.751086 -166.01821)
		(width 0.1143)
		(layer "In2.Cu")
		(net "L3_85OHM_10INCH_DN")
	)
	(segment
		(start 251.14631 -166.065454)
		(end 250.883928 -166.111428)
		(width 0.1143)
		(layer "In2.Cu")
		(net "L3_85OHM_10INCH_DN")
	)
	(segment
		(start 252.462538 -163.805616)
		(end 252.83795 -165.932866)
		(width 0.1143)
		(layer "In2.Cu")
		(net "L3_85OHM_10INCH_DN")
	)
	(segment
		(start 272.015712 -165.859714)
		(end 271.923002 -165.992302)
		(width 0.1143)
		(layer "In2.Cu")
		(net "L3_85OHM_10INCH_DN")
	)
	(segment
		(start 300.325536 -166.012368)
		(end 299.899324 -163.590732)
		(width 0.1143)
		(layer "In2.Cu")
		(net "L3_85OHM_10INCH_DN")
	)
	(segment
		(start 239.854232 -164.759386)
		(end 239.238282 -164.143436)
		(width 0.1143)
		(layer "In2.Cu")
		(net "L3_85OHM_10INCH_DN")
	)
	(segment
		(start 249.64517 -165.961568)
		(end 249.55246 -166.093902)
		(width 0.1143)
		(layer "In2.Cu")
		(net "L3_85OHM_10INCH_DN")
	)
	(segment
		(start 277.181056 -163.374578)
		(end 276.67966 -163.463224)
		(width 0.1143)
		(layer "In2.Cu")
		(net "L3_85OHM_10INCH_DN")
	)
	(segment
		(start 291.07511 -163.466526)
		(end 290.843716 -163.798504)
		(width 0.1143)
		(layer "In2.Cu")
		(net "L3_85OHM_10INCH_DN")
	)
	(segment
		(start 294.273732 -163.471352)
		(end 294.042592 -163.802822)
		(width 0.1143)
		(layer "In2.Cu")
		(net "L3_85OHM_10INCH_DN")
	)
	(segment
		(start 284.682692 -163.50361)
		(end 284.451298 -163.834826)
		(width 0.1143)
		(layer "In2.Cu")
		(net "L3_85OHM_10INCH_DN")
	)
	(segment
		(start 301.498254 -163.591748)
		(end 301.167038 -163.359592)
		(width 0.1143)
		(layer "In2.Cu")
		(net "L3_85OHM_10INCH_DN")
	)
	(segment
		(start 282.848558 -163.81476)
		(end 283.208222 -165.851586)
		(width 0.1143)
		(layer "In2.Cu")
		(net "L3_85OHM_10INCH_DN")
	)
	(segment
		(start 247.895872 -163.469828)
		(end 247.664732 -163.80079)
		(width 0.1143)
		(layer "In2.Cu")
		(net "L3_85OHM_10INCH_DN")
	)
	(segment
		(start 264.38733 -163.369752)
		(end 263.885934 -163.458398)
		(width 0.1143)
		(layer "In2.Cu")
		(net "L3_85OHM_10INCH_DN")
	)
	(segment
		(start 271.527524 -165.946074)
		(end 271.117314 -163.618164)
		(width 0.1143)
		(layer "In2.Cu")
		(net "L3_85OHM_10INCH_DN")
	)
	(segment
		(start 266.320778 -163.621466)
		(end 265.989816 -163.39058)
		(width 0.1143)
		(layer "In2.Cu")
		(net "L3_85OHM_10INCH_DN")
	)
	(segment
		(start 249.26417 -163.800536)
		(end 249.64517 -165.961568)
		(width 0.1143)
		(layer "In2.Cu")
		(net "L3_85OHM_10INCH_DN")
	)
	(segment
		(start 300.665642 -163.447984)
		(end 300.434756 -163.779454)
		(width 0.1143)
		(layer "In2.Cu")
		(net "L3_85OHM_10INCH_DN")
	)
	(segment
		(start 273.125184 -165.937692)
		(end 272.715736 -163.609782)
		(width 0.1143)
		(layer "In2.Cu")
		(net "L3_85OHM_10INCH_DN")
	)
	(segment
		(start 290.86556 -166.117016)
		(end 290.732972 -166.02456)
		(width 0.1143)
		(layer "In2.Cu")
		(net "L3_85OHM_10INCH_DN")
	)
	(segment
		(start 297.468036 -163.44265)
		(end 297.235626 -163.77285)
		(width 0.1143)
		(layer "In2.Cu")
		(net "L3_85OHM_10INCH_DN")
	)
	(segment
		(start 291.907468 -163.610036)
		(end 291.575744 -163.37915)
		(width 0.1143)
		(layer "In2.Cu")
		(net "L3_85OHM_10INCH_DN")
	)
	(segment
		(start 297.968162 -163.35502)
		(end 297.468036 -163.44265)
		(width 0.1143)
		(layer "In2.Cu")
		(net "L3_85OHM_10INCH_DN")
	)
	(segment
		(start 282.852368 -166.031164)
		(end 282.720542 -165.938962)
		(width 0.1143)
		(layer "In2.Cu")
		(net "L3_85OHM_10INCH_DN")
	)
	(segment
		(start 299.122084 -166.058596)
		(end 298.859448 -166.104824)
		(width 0.1143)
		(layer "In2.Cu")
		(net "L3_85OHM_10INCH_DN")
	)
	(segment
		(start 292.443408 -163.802568)
		(end 292.81882 -165.929818)
		(width 0.1143)
		(layer "In2.Cu")
		(net "L3_85OHM_10INCH_DN")
	)
	(segment
		(start 294.325294 -166.06266)
		(end 294.062658 -166.108634)
		(width 0.1143)
		(layer "In2.Cu")
		(net "L3_85OHM_10INCH_DN")
	)
	(segment
		(start 256.722626 -163.609274)
		(end 256.391664 -163.378134)
		(width 0.1143)
		(layer "In2.Cu")
		(net "L3_85OHM_10INCH_DN")
	)
	(segment
		(start 246.799354 -163.390326)
		(end 246.297958 -163.47821)
		(width 0.1143)
		(layer "In2.Cu")
		(net "L3_85OHM_10INCH_DN")
	)
	(segment
		(start 296.700194 -163.587176)
		(end 296.369232 -163.354512)
		(width 0.1143)
		(layer "In2.Cu")
		(net "L3_85OHM_10INCH_DN")
	)
	(segment
		(start 273.257772 -166.030148)
		(end 273.125184 -165.937692)
		(width 0.1143)
		(layer "In2.Cu")
		(net "L3_85OHM_10INCH_DN")
	)
	(segment
		(start 267.218922 -165.86327)
		(end 267.126466 -165.995604)
		(width 0.1143)
		(layer "In2.Cu")
		(net "L3_85OHM_10INCH_DN")
	)
	(segment
		(start 276.81174 -165.855904)
		(end 276.719538 -165.988492)
		(width 0.1143)
		(layer "In2.Cu")
		(net "L3_85OHM_10INCH_DN")
	)
	(segment
		(start 263.929368 -166.003986)
		(end 263.666732 -166.050468)
		(width 0.1143)
		(layer "In2.Cu")
		(net "L3_85OHM_10INCH_DN")
	)
	(segment
		(start 302.036734 -163.794948)
		(end 302.41367 -165.930072)
		(width 0.1143)
		(layer "In2.Cu")
		(net "L3_85OHM_10INCH_DN")
	)
	(segment
		(start 275.913596 -163.611052)
		(end 275.582634 -163.378896)
		(width 0.1143)
		(layer "In2.Cu")
		(net "L3_85OHM_10INCH_DN")
	)
	(segment
		(start 262.422132 -165.867334)
		(end 262.329676 -165.999668)
		(width 0.1143)
		(layer "In2.Cu")
		(net "L3_85OHM_10INCH_DN")
	)
	(segment
		(start 271.923002 -165.992302)
		(end 271.660112 -166.03853)
		(width 0.1143)
		(layer "In2.Cu")
		(net "L3_85OHM_10INCH_DN")
	)
	(segment
		(start 257.533902 -166.007796)
		(end 257.271266 -166.054024)
		(width 0.1143)
		(layer "In2.Cu")
		(net "L3_85OHM_10INCH_DN")
	)
	(segment
		(start 265.265916 -166.050214)
		(end 265.133836 -165.957758)
		(width 0.1143)
		(layer "In2.Cu")
		(net "L3_85OHM_10INCH_DN")
	)
	(segment
		(start 284.32252 -165.954456)
		(end 283.912056 -163.627308)
		(width 0.1143)
		(layer "In2.Cu")
		(net "L3_85OHM_10INCH_DN")
	)
	(segment
		(start 251.094748 -163.474146)
		(end 250.863608 -163.805108)
		(width 0.1143)
		(layer "In2.Cu")
		(net "L3_85OHM_10INCH_DN")
	)
	(segment
		(start 276.719538 -165.988492)
		(end 276.456902 -166.034974)
		(width 0.1143)
		(layer "In2.Cu")
		(net "L3_85OHM_10INCH_DN")
	)
	(segment
		(start 289.621722 -165.937184)
		(end 289.529266 -166.070026)
		(width 0.1143)
		(layer "In2.Cu")
		(net "L3_85OHM_10INCH_DN")
	)
	(segment
		(start 295.867836 -163.443158)
		(end 295.636188 -163.773612)
		(width 0.1143)
		(layer "In2.Cu")
		(net "L3_85OHM_10INCH_DN")
	)
	(segment
		(start 274.724622 -165.937692)
		(end 274.31365 -163.609782)
		(width 0.1143)
		(layer "In2.Cu")
		(net "L3_85OHM_10INCH_DN")
	)
	(segment
		(start 245.531386 -163.621212)
		(end 245.20017 -163.390072)
		(width 0.1143)
		(layer "In2.Cu")
		(net "L3_85OHM_10INCH_DN")
	)
	(segment
		(start 255.547114 -166.011098)
		(end 255.12395 -163.60902)
		(width 0.1143)
		(layer "In2.Cu")
		(net "L3_85OHM_10INCH_DN")
	)
	(segment
		(start 251.926852 -163.617402)
		(end 251.59589 -163.386516)
		(width 0.1143)
		(layer "In2.Cu")
		(net "L3_85OHM_10INCH_DN")
	)
	(segment
		(start 297.261534 -166.113206)
		(end 297.129454 -166.02075)
		(width 0.1143)
		(layer "In2.Cu")
		(net "L3_85OHM_10INCH_DN")
	)
	(segment
		(start 243.09959 -163.473892)
		(end 242.867688 -163.805108)
		(width 0.1143)
		(layer "In2.Cu")
		(net "L3_85OHM_10INCH_DN")
	)
	(segment
		(start 254.291592 -163.466018)
		(end 254.060198 -163.797234)
		(width 0.1143)
		(layer "In2.Cu")
		(net "L3_85OHM_10INCH_DN")
	)
	(segment
		(start 278.27986 -163.462716)
		(end 278.04745 -163.792916)
		(width 0.1143)
		(layer "In2.Cu")
		(net "L3_85OHM_10INCH_DN")
	)
	(segment
		(start 279.916636 -165.98011)
		(end 279.654 -166.026338)
		(width 0.1143)
		(layer "In2.Cu")
		(net "L3_85OHM_10INCH_DN")
	)
	(segment
		(start 271.660112 -166.03853)
		(end 271.527524 -165.946074)
		(width 0.1143)
		(layer "In2.Cu")
		(net "L3_85OHM_10INCH_DN")
	)
	(segment
		(start 246.352822 -166.089584)
		(end 246.09044 -166.135558)
		(width 0.1143)
		(layer "In2.Cu")
		(net "L3_85OHM_10INCH_DN")
	)
	(segment
		(start 273.613372 -165.851332)
		(end 273.520662 -165.98392)
		(width 0.1143)
		(layer "In2.Cu")
		(net "L3_85OHM_10INCH_DN")
	)
	(segment
		(start 267.089128 -163.482782)
		(end 266.85748 -163.813998)
		(width 0.1143)
		(layer "In2.Cu")
		(net "L3_85OHM_10INCH_DN")
	)
	(segment
		(start 265.621008 -165.871652)
		(end 265.528552 -166.003986)
		(width 0.1143)
		(layer "In2.Cu")
		(net "L3_85OHM_10INCH_DN")
	)
	(segment
		(start 285.514796 -163.64712)
		(end 285.184088 -163.415472)
		(width 0.1143)
		(layer "In2.Cu")
		(net "L3_85OHM_10INCH_DN")
	)
	(segment
		(start 247.13057 -163.621466)
		(end 246.799354 -163.390326)
		(width 0.1143)
		(layer "In2.Cu")
		(net "L3_85OHM_10INCH_DN")
	)
	(segment
		(start 294.775128 -163.383468)
		(end 294.273732 -163.471352)
		(width 0.1143)
		(layer "In2.Cu")
		(net "L3_85OHM_10INCH_DN")
	)
	(segment
		(start 259.132832 -166.007796)
		(end 258.869942 -166.054024)
		(width 0.1143)
		(layer "In2.Cu")
		(net "L3_85OHM_10INCH_DN")
	)
	(segment
		(start 300.458378 -166.105078)
		(end 300.325536 -166.012368)
		(width 0.1143)
		(layer "In2.Cu")
		(net "L3_85OHM_10INCH_DN")
	)
	(segment
		(start 266.730988 -165.949122)
		(end 266.320778 -163.621466)
		(width 0.1143)
		(layer "In2.Cu")
		(net "L3_85OHM_10INCH_DN")
	)
	(segment
		(start 302.057816 -166.10965)
		(end 301.92599 -166.017448)
		(width 0.1143)
		(layer "In2.Cu")
		(net "L3_85OHM_10INCH_DN")
	)
	(segment
		(start 275.119846 -165.984174)
		(end 274.85721 -166.030148)
		(width 0.1143)
		(layer "In2.Cu")
		(net "L3_85OHM_10INCH_DN")
	)
	(segment
		(start 292.72611 -166.062406)
		(end 292.46322 -166.108634)
		(width 0.1143)
		(layer "In2.Cu")
		(net "L3_85OHM_10INCH_DN")
	)
	(segment
		(start 255.659382 -163.797234)
		(end 256.03454 -165.925246)
		(width 0.1143)
		(layer "In2.Cu")
		(net "L3_85OHM_10INCH_DN")
	)
	(segment
		(start 244.358922 -166.042086)
		(end 243.930932 -163.616386)
		(width 0.1143)
		(layer "In2.Cu")
		(net "L3_85OHM_10INCH_DN")
	)
	(segment
		(start 262.329676 -165.999668)
		(end 262.06704 -166.045642)
		(width 0.1143)
		(layer "In2.Cu")
		(net "L3_85OHM_10INCH_DN")
	)
	(segment
		(start 295.924986 -166.066978)
		(end 295.66235 -166.11346)
		(width 0.1143)
		(layer "In2.Cu")
		(net "L3_85OHM_10INCH_DN")
	)
	(segment
		(start 292.81882 -165.929818)
		(end 292.72611 -166.062406)
		(width 0.1143)
		(layer "In2.Cu")
		(net "L3_85OHM_10INCH_DN")
	)
	(segment
		(start 267.590016 -163.395152)
		(end 267.089128 -163.482782)
		(width 0.1143)
		(layer "In2.Cu")
		(net "L3_85OHM_10INCH_DN")
	)
	(segment
		(start 283.208222 -165.851586)
		(end 283.115004 -165.984682)
		(width 0.1143)
		(layer "In2.Cu")
		(net "L3_85OHM_10INCH_DN")
	)
	(segment
		(start 289.13328 -166.022782)
		(end 288.713418 -163.648898)
		(width 0.1143)
		(layer "In2.Cu")
		(net "L3_85OHM_10INCH_DN")
	)
	(segment
		(start 299.21454 -165.926262)
		(end 299.122084 -166.058596)
		(width 0.1143)
		(layer "In2.Cu")
		(net "L3_85OHM_10INCH_DN")
	)
	(segment
		(start 246.445532 -165.956996)
		(end 246.352822 -166.089584)
		(width 0.1143)
		(layer "In2.Cu")
		(net "L3_85OHM_10INCH_DN")
	)
	(segment
		(start 258.327144 -163.633658)
		(end 257.986784 -163.395152)
		(width 0.1143)
		(layer "In2.Cu")
		(net "L3_85OHM_10INCH_DN")
	)
	(segment
		(start 257.626358 -165.875208)
		(end 257.533902 -166.007796)
		(width 0.1143)
		(layer "In2.Cu")
		(net "L3_85OHM_10INCH_DN")
	)
	(segment
		(start 288.014156 -165.898068)
		(end 287.920938 -166.031164)
		(width 0.1143)
		(layer "In2.Cu")
		(net "L3_85OHM_10INCH_DN")
	)
	(segment
		(start 298.726606 -166.012114)
		(end 298.299124 -163.585906)
		(width 0.1143)
		(layer "In2.Cu")
		(net "L3_85OHM_10INCH_DN")
	)
	(segment
		(start 289.246818 -163.810188)
		(end 289.621722 -165.937184)
		(width 0.1143)
		(layer "In2.Cu")
		(net "L3_85OHM_10INCH_DN")
	)
	(segment
		(start 279.521158 -165.933628)
		(end 279.110948 -163.605972)
		(width 0.1143)
		(layer "In2.Cu")
		(net "L3_85OHM_10INCH_DN")
	)
	(segment
		(start 260.467602 -166.045642)
		(end 260.335014 -165.953186)
		(width 0.1143)
		(layer "In2.Cu")
		(net "L3_85OHM_10INCH_DN")
	)
	(segment
		(start 278.411178 -165.856158)
		(end 278.318722 -165.988492)
		(width 0.1143)
		(layer "In2.Cu")
		(net "L3_85OHM_10INCH_DN")
	)
	(segment
		(start 273.982942 -163.378642)
		(end 273.482308 -163.46678)
		(width 0.1143)
		(layer "In2.Cu")
		(net "L3_85OHM_10INCH_DN")
	)
	(segment
		(start 254.082804 -166.116)
		(end 253.949708 -166.02329)
		(width 0.1143)
		(layer "In2.Cu")
		(net "L3_85OHM_10INCH_DN")
	)
	(segment
		(start 295.10609 -163.615624)
		(end 294.775128 -163.383468)
		(width 0.1143)
		(layer "In2.Cu")
		(net "L3_85OHM_10INCH_DN")
	)
	(segment
		(start 244.467634 -163.808918)
		(end 244.846602 -165.956234)
		(width 0.1143)
		(layer "In2.Cu")
		(net "L3_85OHM_10INCH_DN")
	)
	(segment
		(start 242.867688 -163.805108)
		(end 243.244624 -165.940486)
		(width 0.1143)
		(layer "In2.Cu")
		(net "L3_85OHM_10INCH_DN")
	)
	(segment
		(start 265.528552 -166.003986)
		(end 265.265916 -166.050214)
		(width 0.1143)
		(layer "In2.Cu")
		(net "L3_85OHM_10INCH_DN")
	)
	(segment
		(start 257.986784 -163.395152)
		(end 257.502152 -163.480242)
		(width 0.1143)
		(layer "In2.Cu")
		(net "L3_85OHM_10INCH_DN")
	)
	(segment
		(start 269.519908 -163.627308)
		(end 269.188692 -163.395152)
		(width 0.1143)
		(layer "In2.Cu")
		(net "L3_85OHM_10INCH_DN")
	)
	(segment
		(start 252.74524 -166.065454)
		(end 252.483112 -166.111682)
		(width 0.1143)
		(layer "In2.Cu")
		(net "L3_85OHM_10INCH_DN")
	)
	(segment
		(start 286.31896 -166.01567)
		(end 286.056324 -166.062152)
		(width 0.1143)
		(layer "In2.Cu")
		(net "L3_85OHM_10INCH_DN")
	)
	(segment
		(start 242.6716 -165.541452)
		(end 242.609624 -165.297358)
		(width 0.1143)
		(layer "In2.Cu")
		(net "L3_85OHM_10INCH_DN")
	)
	(segment
		(start 261.52348 -163.625276)
		(end 261.192772 -163.394136)
		(width 0.1143)
		(layer "In2.Cu")
		(net "L3_85OHM_10INCH_DN")
	)
	(segment
		(start 268.72565 -165.995858)
		(end 268.46276 -166.042086)
		(width 0.1143)
		(layer "In2.Cu")
		(net "L3_85OHM_10INCH_DN")
	)
	(segment
		(start 254.344932 -166.07028)
		(end 254.082804 -166.116)
		(width 0.1143)
		(layer "In2.Cu")
		(net "L3_85OHM_10INCH_DN")
	)
	(segment
		(start 290.732972 -166.02456)
		(end 290.309808 -163.622736)
		(width 0.1143)
		(layer "In2.Cu")
		(net "L3_85OHM_10INCH_DN")
	)
	(segment
		(start 295.66235 -166.11346)
		(end 295.529762 -166.02075)
		(width 0.1143)
		(layer "In2.Cu")
		(net "L3_85OHM_10INCH_DN")
	)
	(segment
		(start 259.593842 -163.39439)
		(end 259.093208 -163.481766)
		(width 0.1143)
		(layer "In2.Cu")
		(net "L3_85OHM_10INCH_DN")
	)
	(segment
		(start 263.123426 -163.626546)
		(end 262.792464 -163.39439)
		(width 0.1143)
		(layer "In2.Cu")
		(net "L3_85OHM_10INCH_DN")
	)
	(segment
		(start 296.369232 -163.354512)
		(end 295.867836 -163.443158)
		(width 0.1143)
		(layer "In2.Cu")
		(net "L3_85OHM_10INCH_DN")
	)
	(segment
		(start 285.924498 -165.96995)
		(end 285.514796 -163.64712)
		(width 0.1143)
		(layer "In2.Cu")
		(net "L3_85OHM_10INCH_DN")
	)
	(segment
		(start 256.391664 -163.378134)
		(end 255.890522 -163.466272)
		(width 0.1143)
		(layer "In2.Cu")
		(net "L3_85OHM_10INCH_DN")
	)
	(segment
		(start 304.195988 -164.839142)
		(end 303.407572 -164.588444)
		(width 0.1143)
		(layer "In2.Cu")
		(net "L3_85OHM_10INCH_DN")
	)
	(segment
		(start 281.477466 -163.46805)
		(end 281.24658 -163.799266)
		(width 0.1143)
		(layer "In2.Cu")
		(net "L3_85OHM_10INCH_DN")
	)
	(segment
		(start 286.056324 -166.062152)
		(end 285.924498 -165.96995)
		(width 0.1143)
		(layer "In2.Cu")
		(net "L3_85OHM_10INCH_DN")
	)
	(segment
		(start 268.329918 -165.949376)
		(end 267.920978 -163.626292)
		(width 0.1143)
		(layer "In2.Cu")
		(net "L3_85OHM_10INCH_DN")
	)
	(segment
		(start 294.41775 -165.930326)
		(end 294.325294 -166.06266)
		(width 0.1143)
		(layer "In2.Cu")
		(net "L3_85OHM_10INCH_DN")
	)
	(segment
		(start 279.648412 -163.802822)
		(end 280.009092 -165.847776)
		(width 0.1143)
		(layer "In2.Cu")
		(net "L3_85OHM_10INCH_DN")
	)
	(segment
		(start 303.249584 -164.377624)
		(end 303.204626 -164.20084)
		(width 0.1143)
		(layer "In2.Cu")
		(net "L3_85OHM_10INCH_DN")
	)
	(segment
		(start 258.737354 -165.961568)
		(end 258.327144 -163.633658)
		(width 0.1143)
		(layer "In2.Cu")
		(net "L3_85OHM_10INCH_DN")
	)
	(segment
		(start 281.978862 -163.379658)
		(end 281.477466 -163.46805)
		(width 0.1143)
		(layer "In2.Cu")
		(net "L3_85OHM_10INCH_DN")
	)
	(segment
		(start 280.009092 -165.847776)
		(end 279.916636 -165.98011)
		(width 0.1143)
		(layer "In2.Cu")
		(net "L3_85OHM_10INCH_DN")
	)
	(segment
		(start 289.26663 -166.116254)
		(end 289.13328 -166.022782)
		(width 0.1143)
		(layer "In2.Cu")
		(net "L3_85OHM_10INCH_DN")
	)
	(segment
		(start 306.35194 -164.136324)
		(end 305.73599 -164.752274)
		(width 0.1143)
		(layer "In2.Cu")
		(net "L3_85OHM_10INCH_DN")
	)
	(segment
		(start 272.384012 -163.378896)
		(end 271.883378 -163.466272)
		(width 0.1143)
		(layer "In2.Cu")
		(net "L3_85OHM_10INCH_DN")
	)
	(segment
		(start 298.859448 -166.104824)
		(end 298.726606 -166.012114)
		(width 0.1143)
		(layer "In2.Cu")
		(net "L3_85OHM_10INCH_DN")
	)
	(segment
		(start 249.495056 -163.470082)
		(end 249.26417 -163.800536)
		(width 0.1143)
		(layer "In2.Cu")
		(net "L3_85OHM_10INCH_DN")
	)
	(segment
		(start 248.727468 -163.613084)
		(end 248.397268 -163.38169)
		(width 0.1143)
		(layer "In2.Cu")
		(net "L3_85OHM_10INCH_DN")
	)
	(segment
		(start 269.930372 -165.954456)
		(end 269.519908 -163.627308)
		(width 0.1143)
		(layer "In2.Cu")
		(net "L3_85OHM_10INCH_DN")
	)
	(segment
		(start 302.320452 -166.063168)
		(end 302.057816 -166.10965)
		(width 0.1143)
		(layer "In2.Cu")
		(net "L3_85OHM_10INCH_DN")
	)
	(segment
		(start 281.25293 -166.026592)
		(end 281.120088 -165.933882)
		(width 0.1143)
		(layer "In2.Cu")
		(net "L3_85OHM_10INCH_DN")
	)
	(segment
		(start 243.930932 -163.616386)
		(end 243.600732 -163.385246)
		(width 0.1143)
		(layer "In2.Cu")
		(net "L3_85OHM_10INCH_DN")
	)
	(segment
		(start 266.86383 -166.041832)
		(end 266.730988 -165.949122)
		(width 0.1143)
		(layer "In2.Cu")
		(net "L3_85OHM_10INCH_DN")
	)
	(segment
		(start 252.350778 -166.019226)
		(end 251.926852 -163.617402)
		(width 0.1143)
		(layer "In2.Cu")
		(net "L3_85OHM_10INCH_DN")
	)
	(segment
		(start 254.060198 -163.797234)
		(end 254.437642 -165.937184)
		(width 0.1143)
		(layer "In2.Cu")
		(net "L3_85OHM_10INCH_DN")
	)
	(segment
		(start 275.212302 -165.85184)
		(end 275.119846 -165.984174)
		(width 0.1143)
		(layer "In2.Cu")
		(net "L3_85OHM_10INCH_DN")
	)
	(segment
		(start 281.24658 -163.799266)
		(end 281.608276 -165.84803)
		(width 0.1143)
		(layer "In2.Cu")
		(net "L3_85OHM_10INCH_DN")
	)
	(segment
		(start 286.048196 -163.821364)
		(end 286.412178 -165.882574)
		(width 0.1143)
		(layer "In2.Cu")
		(net "L3_85OHM_10INCH_DN")
	)
	(segment
		(start 242.756944 -166.026592)
		(end 242.6716 -165.541452)
		(width 0.1143)
		(layer "In2.Cu")
		(net "L3_85OHM_10INCH_DN")
	)
	(segment
		(start 278.779986 -163.375086)
		(end 278.27986 -163.462716)
		(width 0.1143)
		(layer "In2.Cu")
		(net "L3_85OHM_10INCH_DN")
	)
	(segment
		(start 242.609624 -165.297358)
		(end 242.36045 -164.965126)
		(width 0.1143)
		(layer "In2.Cu")
		(net "L3_85OHM_10INCH_DN")
	)
	(segment
		(start 247.690386 -166.14013)
		(end 247.557798 -166.047674)
		(width 0.1143)
		(layer "In2.Cu")
		(net "L3_85OHM_10INCH_DN")
	)
	(segment
		(start 276.448012 -163.793678)
		(end 276.81174 -165.855904)
		(width 0.1143)
		(layer "In2.Cu")
		(net "L3_85OHM_10INCH_DN")
	)
	(segment
		(start 277.512272 -163.607242)
		(end 277.181056 -163.374578)
		(width 0.1143)
		(layer "In2.Cu")
		(net "L3_85OHM_10INCH_DN")
	)
	(segment
		(start 246.297958 -163.47821)
		(end 246.066818 -163.809172)
		(width 0.1143)
		(layer "In2.Cu")
		(net "L3_85OHM_10INCH_DN")
	)
	(segment
		(start 244.698774 -163.477956)
		(end 244.467634 -163.808918)
		(width 0.1143)
		(layer "In2.Cu")
		(net "L3_85OHM_10INCH_DN")
	)
	(segment
		(start 291.12845 -166.070788)
		(end 290.86556 -166.117016)
		(width 0.1143)
		(layer "In2.Cu")
		(net "L3_85OHM_10INCH_DN")
	)
	(segment
		(start 267.920978 -163.626292)
		(end 267.590016 -163.395152)
		(width 0.1143)
		(layer "In2.Cu")
		(net "L3_85OHM_10INCH_DN")
	)
	(segment
		(start 290.309808 -163.622736)
		(end 289.969448 -163.38423)
		(width 0.1143)
		(layer "In2.Cu")
		(net "L3_85OHM_10INCH_DN")
	)
	(segment
		(start 262.059928 -163.813744)
		(end 262.422132 -165.867334)
		(width 0.1143)
		(layer "In2.Cu")
		(net "L3_85OHM_10INCH_DN")
	)
	(segment
		(start 278.056086 -166.03472)
		(end 277.924006 -165.942264)
		(width 0.1143)
		(layer "In2.Cu")
		(net "L3_85OHM_10INCH_DN")
	)
	(segment
		(start 249.289824 -166.140384)
		(end 249.156982 -166.046912)
		(width 0.1143)
		(layer "In2.Cu")
		(net "L3_85OHM_10INCH_DN")
	)
	(segment
		(start 297.616626 -165.934644)
		(end 297.52417 -166.066978)
		(width 0.1143)
		(layer "In2.Cu")
		(net "L3_85OHM_10INCH_DN")
	)
	(segment
		(start 246.066818 -163.809172)
		(end 246.445532 -165.956996)
		(width 0.1143)
		(layer "In2.Cu")
		(net "L3_85OHM_10INCH_DN")
	)
	(segment
		(start 302.41367 -165.930072)
		(end 302.320452 -166.063168)
		(width 0.1143)
		(layer "In2.Cu")
		(net "L3_85OHM_10INCH_DN")
	)
	(segment
		(start 281.608276 -165.84803)
		(end 281.51582 -165.980364)
		(width 0.1143)
		(layer "In2.Cu")
		(net "L3_85OHM_10INCH_DN")
	)
	(segment
		(start 260.335014 -165.953186)
		(end 259.925566 -163.625276)
		(width 0.1143)
		(layer "In2.Cu")
		(net "L3_85OHM_10INCH_DN")
	)
	(segment
		(start 279.654 -166.026338)
		(end 279.521158 -165.933628)
		(width 0.1143)
		(layer "In2.Cu")
		(net "L3_85OHM_10INCH_DN")
	)
	(segment
		(start 247.557798 -166.047674)
		(end 247.13057 -163.621466)
		(width 0.1143)
		(layer "In2.Cu")
		(net "L3_85OHM_10INCH_DN")
	)
	(segment
		(start 289.529266 -166.070026)
		(end 289.26663 -166.116254)
		(width 0.1143)
		(layer "In2.Cu")
		(net "L3_85OHM_10INCH_DN")
	)
	(segment
		(start 263.534144 -165.957758)
		(end 263.123426 -163.626546)
		(width 0.1143)
		(layer "In2.Cu")
		(net "L3_85OHM_10INCH_DN")
	)
	(segment
		(start 305.73599 -164.752274)
		(end 305.281838 -164.752274)
		(width 0.1143)
		(layer "In2.Cu")
		(net "L3_85OHM_10INCH_DN")
	)
	(segment
		(start 293.93007 -166.016178)
		(end 293.506144 -163.614354)
		(width 0.1143)
		(layer "In2.Cu")
		(net "L3_85OHM_10INCH_DN")
	)
	(segment
		(start 284.451298 -163.834826)
		(end 284.8102 -165.86708)
		(width 0.1143)
		(layer "In2.Cu")
		(net "L3_85OHM_10INCH_DN")
	)
	(segment
		(start 279.110948 -163.605972)
		(end 278.779986 -163.375086)
		(width 0.1143)
		(layer "In2.Cu")
		(net "L3_85OHM_10INCH_DN")
	)
	(segment
		(start 249.996198 -163.38169)
		(end 249.495056 -163.470082)
		(width 0.1143)
		(layer "In2.Cu")
		(net "L3_85OHM_10INCH_DN")
	)
	(segment
		(start 257.138678 -165.961314)
		(end 256.722626 -163.609274)
		(width 0.1143)
		(layer "In2.Cu")
		(net "L3_85OHM_10INCH_DN")
	)
	(segment
		(start 286.780986 -163.40201)
		(end 286.27959 -163.490148)
		(width 0.1143)
		(layer "In2.Cu")
		(net "L3_85OHM_10INCH_DN")
	)
	(segment
		(start 282.720542 -165.938962)
		(end 282.310078 -163.611814)
		(width 0.1143)
		(layer "In2.Cu")
		(net "L3_85OHM_10INCH_DN")
	)
	(segment
		(start 245.957852 -166.042848)
		(end 245.531386 -163.621212)
		(width 0.1143)
		(layer "In2.Cu")
		(net "L3_85OHM_10INCH_DN")
	)
	(segment
		(start 268.687296 -163.483544)
		(end 268.45641 -163.81476)
		(width 0.1143)
		(layer "In2.Cu")
		(net "L3_85OHM_10INCH_DN")
	)
	(segment
		(start 285.184088 -163.415472)
		(end 284.682692 -163.50361)
		(width 0.1143)
		(layer "In2.Cu")
		(net "L3_85OHM_10INCH_DN")
	)
	(segment
		(start 253.195328 -163.386516)
		(end 252.693932 -163.4744)
		(width 0.1143)
		(layer "In2.Cu")
		(net "L3_85OHM_10INCH_DN")
	)
	(segment
		(start 292.674802 -163.471352)
		(end 292.443408 -163.802568)
		(width 0.1143)
		(layer "In2.Cu")
		(net "L3_85OHM_10INCH_DN")
	)
	(segment
		(start 268.46276 -166.042086)
		(end 268.329918 -165.949376)
		(width 0.1143)
		(layer "In2.Cu")
		(net "L3_85OHM_10INCH_DN")
	)
	(segment
		(start 250.751086 -166.01821)
		(end 250.32716 -163.61283)
		(width 0.1143)
		(layer "In2.Cu")
		(net "L3_85OHM_10INCH_DN")
	)
	(segment
		(start 251.238766 -165.932866)
		(end 251.14631 -166.065454)
		(width 0.1143)
		(layer "In2.Cu")
		(net "L3_85OHM_10INCH_DN")
	)
	(segment
		(start 248.045732 -165.962076)
		(end 247.952768 -166.094156)
		(width 0.1143)
		(layer "In2.Cu")
		(net "L3_85OHM_10INCH_DN")
	)
	(segment
		(start 280.380948 -163.383976)
		(end 279.88006 -163.471606)
		(width 0.1143)
		(layer "In2.Cu")
		(net "L3_85OHM_10INCH_DN")
	)
	(segment
		(start 270.05407 -163.80587)
		(end 270.418052 -165.86708)
		(width 0.1143)
		(layer "In2.Cu")
		(net "L3_85OHM_10INCH_DN")
	)
	(segment
		(start 276.67966 -163.463224)
		(end 276.448012 -163.793678)
		(width 0.1143)
		(layer "In2.Cu")
		(net "L3_85OHM_10INCH_DN")
	)
	(segment
		(start 302.268128 -163.463732)
		(end 302.036734 -163.794948)
		(width 0.1143)
		(layer "In2.Cu")
		(net "L3_85OHM_10INCH_DN")
	)
	(segment
		(start 250.32716 -163.61283)
		(end 249.996198 -163.38169)
		(width 0.1143)
		(layer "In2.Cu")
		(net "L3_85OHM_10INCH_DN")
	)
	(segment
		(start 241.428016 -164.668708)
		(end 240.296446 -164.759386)
		(width 0.1143)
		(layer "In2.Cu")
		(net "L3_85OHM_10INCH_DN")
	)
	(segment
		(start 297.235626 -163.77285)
		(end 297.616626 -165.934644)
		(width 0.1143)
		(layer "In2.Cu")
		(net "L3_85OHM_10INCH_DN")
	)
	(segment
		(start 249.156982 -166.046912)
		(end 248.727468 -163.613084)
		(width 0.1143)
		(layer "In2.Cu")
		(net "L3_85OHM_10INCH_DN")
	)
	(segment
		(start 247.952768 -166.094156)
		(end 247.690386 -166.14013)
		(width 0.1143)
		(layer "In2.Cu")
		(net "L3_85OHM_10INCH_DN")
	)
	(segment
		(start 300.721268 -166.05885)
		(end 300.458378 -166.105078)
		(width 0.1143)
		(layer "In2.Cu")
		(net "L3_85OHM_10INCH_DN")
	)
	(segment
		(start 251.59589 -163.386516)
		(end 251.094748 -163.474146)
		(width 0.1143)
		(layer "In2.Cu")
		(net "L3_85OHM_10INCH_DN")
	)
	(segment
		(start 286.27959 -163.490148)
		(end 286.048196 -163.821364)
		(width 0.1143)
		(layer "In2.Cu")
		(net "L3_85OHM_10INCH_DN")
	)
	(segment
		(start 299.899324 -163.590732)
		(end 299.568362 -163.359592)
		(width 0.1143)
		(layer "In2.Cu")
		(net "L3_85OHM_10INCH_DN")
	)
	(segment
		(start 272.715736 -163.609782)
		(end 272.384012 -163.378896)
		(width 0.1143)
		(layer "In2.Cu")
		(net "L3_85OHM_10INCH_DN")
	)
	(segment
		(start 291.22116 -165.9382)
		(end 291.12845 -166.070788)
		(width 0.1143)
		(layer "In2.Cu")
		(net "L3_85OHM_10INCH_DN")
	)
	(segment
		(start 270.285464 -163.474654)
		(end 270.05407 -163.80587)
		(width 0.1143)
		(layer "In2.Cu")
		(net "L3_85OHM_10INCH_DN")
	)
	(segment
		(start 250.863608 -163.805108)
		(end 251.238766 -165.932866)
		(width 0.1143)
		(layer "In2.Cu")
		(net "L3_85OHM_10INCH_DN")
	)
	(segment
		(start 261.934452 -165.953186)
		(end 261.52348 -163.625276)
		(width 0.1143)
		(layer "In2.Cu")
		(net "L3_85OHM_10INCH_DN")
	)
	(segment
		(start 271.117314 -163.618164)
		(end 270.78686 -163.386516)
		(width 0.1143)
		(layer "In2.Cu")
		(net "L3_85OHM_10INCH_DN")
	)
	(segment
		(start 256.03454 -165.925246)
		(end 255.935226 -166.067486)
		(width 0.1143)
		(layer "In2.Cu")
		(net "L3_85OHM_10INCH_DN")
	)
	(segment
		(start 287.526476 -165.985444)
		(end 287.111694 -163.633658)
		(width 0.1143)
		(layer "In2.Cu")
		(net "L3_85OHM_10INCH_DN")
	)
	(segment
		(start 260.692138 -163.482274)
		(end 260.460744 -163.81349)
		(width 0.1143)
		(layer "In2.Cu")
		(net "L3_85OHM_10INCH_DN")
	)
	(segment
		(start 300.813724 -165.926516)
		(end 300.721268 -166.05885)
		(width 0.1143)
		(layer "In2.Cu")
		(net "L3_85OHM_10INCH_DN")
	)
	(segment
		(start 244.846602 -165.956234)
		(end 244.754146 -166.089076)
		(width 0.1143)
		(layer "In2.Cu")
		(net "L3_85OHM_10INCH_DN")
	)
	(segment
		(start 288.382964 -163.417504)
		(end 287.881568 -163.505642)
		(width 0.1143)
		(layer "In2.Cu")
		(net "L3_85OHM_10INCH_DN")
	)
	(segment
		(start 243.600732 -163.385246)
		(end 243.09959 -163.473892)
		(width 0.1143)
		(layer "In2.Cu")
		(net "L3_85OHM_10INCH_DN")
	)
	(segment
		(start 288.713418 -163.648898)
		(end 288.382964 -163.417504)
		(width 0.1143)
		(layer "In2.Cu")
		(net "L3_85OHM_10INCH_DN")
	)
	(segment
		(start 271.651984 -163.79825)
		(end 272.015712 -165.859714)
		(width 0.1143)
		(layer "In2.Cu")
		(net "L3_85OHM_10INCH_DN")
	)
	(segment
		(start 284.8102 -165.86708)
		(end 284.716982 -166.000176)
		(width 0.1143)
		(layer "In2.Cu")
		(net "L3_85OHM_10INCH_DN")
	)
	(segment
		(start 249.55246 -166.093902)
		(end 249.289824 -166.140384)
		(width 0.1143)
		(layer "In2.Cu")
		(net "L3_85OHM_10INCH_DN")
	)
	(segment
		(start 280.71191 -163.615116)
		(end 280.380948 -163.383976)
		(width 0.1143)
		(layer "In2.Cu")
		(net "L3_85OHM_10INCH_DN")
	)
	(segment
		(start 263.666732 -166.050468)
		(end 263.534144 -165.957758)
		(width 0.1143)
		(layer "In2.Cu")
		(net "L3_85OHM_10INCH_DN")
	)
	(segment
		(start 293.506144 -163.614354)
		(end 293.175436 -163.383214)
		(width 0.1143)
		(layer "In2.Cu")
		(net "L3_85OHM_10INCH_DN")
	)
	(segment
		(start 301.167038 -163.359592)
		(end 300.665642 -163.447984)
		(width 0.1143)
		(layer "In2.Cu")
		(net "L3_85OHM_10INCH_DN")
	)
	(segment
		(start 269.188692 -163.395152)
		(end 268.687296 -163.483544)
		(width 0.1143)
		(layer "In2.Cu")
		(net "L3_85OHM_10INCH_DN")
	)
	(segment
		(start 295.636188 -163.773612)
		(end 296.017188 -165.93439)
		(width 0.1143)
		(layer "In2.Cu")
		(net "L3_85OHM_10INCH_DN")
	)
	(segment
		(start 287.650174 -163.836858)
		(end 288.014156 -165.898068)
		(width 0.1143)
		(layer "In2.Cu")
		(net "L3_85OHM_10INCH_DN")
	)
	(segment
		(start 258.869942 -166.054024)
		(end 258.737354 -165.961568)
		(width 0.1143)
		(layer "In2.Cu")
		(net "L3_85OHM_10INCH_DN")
	)
	(segment
		(start 262.792464 -163.39439)
		(end 262.291068 -163.482274)
		(width 0.1143)
		(layer "In2.Cu")
		(net "L3_85OHM_10INCH_DN")
	)
	(segment
		(start 253.52629 -163.617402)
		(end 253.195328 -163.386516)
		(width 0.1143)
		(layer "In2.Cu")
		(net "L3_85OHM_10INCH_DN")
	)
	(segment
		(start 284.454346 -166.046658)
		(end 284.32252 -165.954456)
		(width 0.1143)
		(layer "In2.Cu")
		(net "L3_85OHM_10INCH_DN")
	)
	(segment
		(start 252.483112 -166.111682)
		(end 252.350778 -166.019226)
		(width 0.1143)
		(layer "In2.Cu")
		(net "L3_85OHM_10INCH_DN")
	)
	(segment
		(start 259.925566 -163.625276)
		(end 259.593842 -163.39439)
		(width 0.1143)
		(layer "In2.Cu")
		(net "L3_85OHM_10INCH_DN")
	)
	(segment
		(start 278.318722 -165.988492)
		(end 278.056086 -166.03472)
		(width 0.1143)
		(layer "In2.Cu")
		(net "L3_85OHM_10INCH_DN")
	)
	(segment
		(start 286.412178 -165.882574)
		(end 286.31896 -166.01567)
		(width 0.1143)
		(layer "In2.Cu")
		(net "L3_85OHM_10INCH_DN")
	)
	(segment
		(start 274.85721 -166.030148)
		(end 274.724622 -165.937692)
		(width 0.1143)
		(layer "In2.Cu")
		(net "L3_85OHM_10INCH_DN")
	)
	(segment
		(start 302.769524 -163.375594)
		(end 302.268128 -163.463732)
		(width 0.1143)
		(layer "In2.Cu")
		(net "L3_85OHM_10INCH_DN")
	)
	(segment
		(start 257.502152 -163.480242)
		(end 257.264154 -163.82111)
		(width 0.1143)
		(layer "In2.Cu")
		(net "L3_85OHM_10INCH_DN")
	)
	(segment
		(start 270.324834 -166.000176)
		(end 270.062198 -166.046658)
		(width 0.1143)
		(layer "In2.Cu")
		(net "L3_85OHM_10INCH_DN")
	)
	(segment
		(start 265.989816 -163.39058)
		(end 265.48969 -163.47821)
		(width 0.1143)
		(layer "In2.Cu")
		(net "L3_85OHM_10INCH_DN")
	)
	(segment
		(start 281.51582 -165.980364)
		(end 281.25293 -166.026592)
		(width 0.1143)
		(layer "In2.Cu")
		(net "L3_85OHM_10INCH_DN")
	)
	(segment
		(start 262.291068 -163.482274)
		(end 262.059928 -163.813744)
		(width 0.1143)
		(layer "In2.Cu")
		(net "L3_85OHM_10INCH_DN")
	)
	(segment
		(start 294.042592 -163.802822)
		(end 294.41775 -165.930326)
		(width 0.1143)
		(layer "In2.Cu")
		(net "L3_85OHM_10INCH_DN")
	)
	(segment
		(start 287.920938 -166.031164)
		(end 287.658302 -166.077646)
		(width 0.1143)
		(layer "In2.Cu")
		(net "L3_85OHM_10INCH_DN")
	)
	(segment
		(start 292.46322 -166.108634)
		(end 292.330632 -166.016178)
		(width 0.1143)
		(layer "In2.Cu")
		(net "L3_85OHM_10INCH_DN")
	)
	(segment
		(start 298.835826 -163.778438)
		(end 299.21454 -165.926262)
		(width 0.1143)
		(layer "In2.Cu")
		(net "L3_85OHM_10INCH_DN")
	)
	(segment
		(start 287.881568 -163.505642)
		(end 287.650174 -163.836858)
		(width 0.1143)
		(layer "In2.Cu")
		(net "L3_85OHM_10INCH_DN")
	)
	(segment
		(start 262.06704 -166.045642)
		(end 261.934452 -165.953186)
		(width 0.1143)
		(layer "In2.Cu")
		(net "L3_85OHM_10INCH_DN")
	)
	(segment
		(start 267.126466 -165.995604)
		(end 266.86383 -166.041832)
		(width 0.1143)
		(layer "In2.Cu")
		(net "L3_85OHM_10INCH_DN")
	)
	(segment
		(start 242.889278 -166.119302)
		(end 242.756944 -166.026592)
		(width 0.1143)
		(layer "In2.Cu")
		(net "L3_85OHM_10INCH_DN")
	)
	(segment
		(start 303.100232 -163.607242)
		(end 302.769524 -163.375594)
		(width 0.1143)
		(layer "In2.Cu")
		(net "L3_85OHM_10INCH_DN")
	)
	(segment
		(start 253.949708 -166.02329)
		(end 253.52629 -163.617402)
		(width 0.1143)
		(layer "In2.Cu")
		(net "L3_85OHM_10INCH_DN")
	)
	(segment
		(start 299.067474 -163.447222)
		(end 298.835826 -163.778438)
		(width 0.1143)
		(layer "In2.Cu")
		(net "L3_85OHM_10INCH_DN")
	)
	(segment
		(start 124.895864 11.879834)
		(end 123.760484 10.744454)
		(width 0.14224)
		(layer "In2.Cu")
		(net "L3_73OHM_6INCH_DP")
	)
	(segment
		(start 145.580354 11.879834)
		(end 124.895864 11.879834)
		(width 0.14224)
		(layer "In2.Cu")
		(net "L3_73OHM_6INCH_DP")
	)
	(segment
		(start 197.503034 10.83564)
		(end 148.22424 10.83564)
		(width 0.14224)
		(layer "In2.Cu")
		(net "L3_73OHM_6INCH_DP")
	)
	(segment
		(start 146.42592 12.7254)
		(end 145.580354 11.879834)
		(width 0.14224)
		(layer "In2.Cu")
		(net "L3_73OHM_6INCH_DP")
	)
	(segment
		(start 148.22424 12.04976)
		(end 197.401434 12.04976)
		(width 0.14224)
		(layer "In2.Cu")
		(net "L3_73OHM_6INCH_DP")
	)
	(segment
		(start 197.401434 12.7254)
		(end 146.42592 12.7254)
		(width 0.14224)
		(layer "In2.Cu")
		(net "L3_73OHM_6INCH_DP")
	)
	(arc
		(start 197.401434 12.04976)
		(mid 197.739254 12.38758)
		(end 197.401434 12.7254)
		(width 0.14224)
		(layer "In2.Cu")
		(net "L3_73OHM_6INCH_DP")
	)
	(arc
		(start 148.22424 10.83564)
		(mid 147.61718 11.4427)
		(end 148.22424 12.04976)
		(width 0.14224)
		(layer "In2.Cu")
		(net "L3_73OHM_6INCH_DP")
	)
	(segment
		(start 145.468594 12.149074)
		(end 124.895864 12.149074)
		(width 0.14224)
		(layer "In2.Cu")
		(net "L3_73OHM_6INCH_DN")
	)
	(segment
		(start 124.895864 12.149074)
		(end 123.760484 13.284454)
		(width 0.14224)
		(layer "In2.Cu")
		(net "L3_73OHM_6INCH_DN")
	)
	(segment
		(start 197.503034 11.10488)
		(end 148.22424 11.10488)
		(width 0.14224)
		(layer "In2.Cu")
		(net "L3_73OHM_6INCH_DN")
	)
	(segment
		(start 197.401434 12.99464)
		(end 146.31416 12.99464)
		(width 0.14224)
		(layer "In2.Cu")
		(net "L3_73OHM_6INCH_DN")
	)
	(segment
		(start 146.31416 12.99464)
		(end 145.468594 12.149074)
		(width 0.14224)
		(layer "In2.Cu")
		(net "L3_73OHM_6INCH_DN")
	)
	(segment
		(start 148.22424 11.78052)
		(end 197.401434 11.78052)
		(width 0.14224)
		(layer "In2.Cu")
		(net "L3_73OHM_6INCH_DN")
	)
	(arc
		(start 148.22424 11.10488)
		(mid 147.88642 11.4427)
		(end 148.22424 11.78052)
		(width 0.14224)
		(layer "In2.Cu")
		(net "L3_73OHM_6INCH_DN")
	)
	(arc
		(start 197.401434 11.78052)
		(mid 198.008494 12.38758)
		(end 197.401434 12.99464)
		(width 0.14224)
		(layer "In2.Cu")
		(net "L3_73OHM_6INCH_DN")
	)
	(segment
		(start 36.83762 14.2748)
		(end 16.3703 14.2748)
		(width 0.089408)
		(layer "In2.Cu")
		(net "L3_50OHM_6INCH")
	)
	(segment
		(start 113.159286 13.677392)
		(end 37.435028 13.677392)
		(width 0.089408)
		(layer "In2.Cu")
		(net "L3_50OHM_6INCH")
	)
	(segment
		(start 37.435028 13.677392)
		(end 36.83762 14.2748)
		(width 0.089408)
		(layer "In2.Cu")
		(net "L3_50OHM_6INCH")
	)
	(segment
		(start 16.3703 14.2748)
		(end 15.367 13.2715)
		(width 0.089408)
		(layer "In2.Cu")
		(net "L3_50OHM_6INCH")
	)
	(segment
		(start 37.820854 12.825984)
		(end 113.159286 12.825984)
		(width 0.089408)
		(layer "In2.Cu")
		(net "L3_50OHM_6INCH")
	)
	(arc
		(start 113.159286 12.825984)
		(mid 113.58499 13.251688)
		(end 113.159286 13.677392)
		(width 0.089408)
		(layer "In2.Cu")
		(net "L3_50OHM_6INCH")
	)
	(segment
		(start 36.97859 11.66241)
		(end 36.6268 12.0142)
		(width 0.14224)
		(layer "In2.Cu")
		(net "L3_40OHM_6INCH")
	)
	(segment
		(start 112.559084 11.66241)
		(end 36.97859 11.66241)
		(width 0.14224)
		(layer "In2.Cu")
		(net "L3_40OHM_6INCH")
	)
	(segment
		(start 16.6497 12.0142)
		(end 15.367 10.7315)
		(width 0.14224)
		(layer "In2.Cu")
		(net "L3_40OHM_6INCH")
	)
	(segment
		(start 36.6268 12.0142)
		(end 16.6497 12.0142)
		(width 0.14224)
		(layer "In2.Cu")
		(net "L3_40OHM_6INCH")
	)
	(segment
		(start 37.159946 10.75817)
		(end 112.559084 10.75817)
		(width 0.14224)
		(layer "In2.Cu")
		(net "L3_40OHM_6INCH")
	)
	(arc
		(start 112.559084 10.75817)
		(mid 113.011204 11.21029)
		(end 112.559084 11.66241)
		(width 0.14224)
		(layer "In2.Cu")
		(net "L3_40OHM_6INCH")
	)
	(segment
		(start 281.571446 12.923774)
		(end 231.287574 12.923774)
		(width 0.1143)
		(layer "F.Cu")
		(net "L1_85OHM_6INCH_DP")
	)
	(segment
		(start 204.091286 11.831828)
		(end 202.941936 10.682478)
		(width 0.1143)
		(layer "F.Cu")
		(net "L1_85OHM_6INCH_DP")
	)
	(segment
		(start 231.287574 12.923774)
		(end 230.195628 11.831828)
		(width 0.1143)
		(layer "F.Cu")
		(net "L1_85OHM_6INCH_DP")
	)
	(segment
		(start 232.2068 11.971274)
		(end 281.571446 11.971274)
		(width 0.1143)
		(layer "F.Cu")
		(net "L1_85OHM_6INCH_DP")
	)
	(segment
		(start 230.195628 11.831828)
		(end 204.091286 11.831828)
		(width 0.1143)
		(layer "F.Cu")
		(net "L1_85OHM_6INCH_DP")
	)
	(segment
		(start 281.207972 10.536174)
		(end 232.2068 10.536174)
		(width 0.1143)
		(layer "F.Cu")
		(net "L1_85OHM_6INCH_DP")
	)
	(arc
		(start 232.2068 10.536174)
		(mid 231.48925 11.253724)
		(end 232.2068 11.971274)
		(width 0.1143)
		(layer "F.Cu")
		(net "L1_85OHM_6INCH_DP")
	)
	(arc
		(start 281.571446 11.971274)
		(mid 282.047696 12.447524)
		(end 281.571446 12.923774)
		(width 0.1143)
		(layer "F.Cu")
		(net "L1_85OHM_6INCH_DP")
	)
	(segment
		(start 230.095552 12.073128)
		(end 204.091286 12.073128)
		(width 0.1143)
		(layer "F.Cu")
		(net "L1_85OHM_6INCH_DN")
	)
	(segment
		(start 281.5717 13.165074)
		(end 231.187498 13.165074)
		(width 0.1143)
		(layer "F.Cu")
		(net "L1_85OHM_6INCH_DN")
	)
	(segment
		(start 204.091286 12.073128)
		(end 202.941936 13.222478)
		(width 0.1143)
		(layer "F.Cu")
		(net "L1_85OHM_6INCH_DN")
	)
	(segment
		(start 231.187498 13.165074)
		(end 230.095552 12.073128)
		(width 0.1143)
		(layer "F.Cu")
		(net "L1_85OHM_6INCH_DN")
	)
	(segment
		(start 232.2068 11.729974)
		(end 281.5717 11.729974)
		(width 0.1143)
		(layer "F.Cu")
		(net "L1_85OHM_6INCH_DN")
	)
	(segment
		(start 281.207972 10.777474)
		(end 232.2068 10.777474)
		(width 0.1143)
		(layer "F.Cu")
		(net "L1_85OHM_6INCH_DN")
	)
	(arc
		(start 281.5717 11.729974)
		(mid 282.28925 12.447524)
		(end 281.5717 13.165074)
		(width 0.1143)
		(layer "F.Cu")
		(net "L1_85OHM_6INCH_DN")
	)
	(arc
		(start 232.2068 10.777474)
		(mid 231.73055 11.253724)
		(end 232.2068 11.729974)
		(width 0.1143)
		(layer "F.Cu")
		(net "L1_85OHM_6INCH_DN")
	)
	(segment
		(start 26.384758 -163.510976)
		(end 25.82799 -163.608766)
		(width 0.1143)
		(layer "F.Cu")
		(net "L1_85OHM_5INCH_DP")
	)
	(segment
		(start 45.348906 -163.709604)
		(end 45.052742 -163.50234)
		(width 0.1143)
		(layer "F.Cu")
		(net "L1_85OHM_5INCH_DP")
	)
	(segment
		(start 43.65117 -163.706556)
		(end 43.35526 -163.499292)
		(width 0.1143)
		(layer "F.Cu")
		(net "L1_85OHM_5INCH_DP")
	)
	(segment
		(start 33.899602 -166.151814)
		(end 33.720786 -165.139116)
		(width 0.1143)
		(layer "F.Cu")
		(net "L1_85OHM_5INCH_DP")
	)
	(segment
		(start 29.39796 -166.07663)
		(end 29.302456 -166.21252)
		(width 0.1143)
		(layer "F.Cu")
		(net "L1_85OHM_5INCH_DP")
	)
	(segment
		(start 34.032444 -166.244778)
		(end 33.899602 -166.151814)
		(width 0.1143)
		(layer "F.Cu")
		(net "L1_85OHM_5INCH_DP")
	)
	(segment
		(start 47.885604 -163.57727)
		(end 47.67834 -163.87318)
		(width 0.1143)
		(layer "F.Cu")
		(net "L1_85OHM_5INCH_DP")
	)
	(segment
		(start 33.720786 -165.139116)
		(end 33.470596 -163.721542)
		(width 0.1143)
		(layer "F.Cu")
		(net "L1_85OHM_5INCH_DP")
	)
	(segment
		(start 38.258496 -163.483544)
		(end 37.707062 -163.580826)
		(width 0.1143)
		(layer "F.Cu")
		(net "L1_85OHM_5INCH_DP")
	)
	(segment
		(start 30.642052 -166.276274)
		(end 30.509972 -166.183818)
		(width 0.1143)
		(layer "F.Cu")
		(net "L1_85OHM_5INCH_DP")
	)
	(segment
		(start 22.991064 -163.509452)
		(end 22.43328 -163.606988)
		(width 0.1143)
		(layer "F.Cu")
		(net "L1_85OHM_5INCH_DP")
	)
	(segment
		(start 47.67834 -163.87318)
		(end 48.065944 -166.07155)
		(width 0.1143)
		(layer "F.Cu")
		(net "L1_85OHM_5INCH_DP")
	)
	(segment
		(start 24.985218 -163.721796)
		(end 24.688546 -163.514278)
		(width 0.1143)
		(layer "F.Cu")
		(net "L1_85OHM_5INCH_DP")
	)
	(segment
		(start 45.783754 -166.177722)
		(end 45.348906 -163.709604)
		(width 0.1143)
		(layer "F.Cu")
		(net "L1_85OHM_5INCH_DP")
	)
	(segment
		(start 39.193978 -163.877752)
		(end 39.576248 -166.047166)
		(width 0.1143)
		(layer "F.Cu")
		(net "L1_85OHM_5INCH_DP")
	)
	(segment
		(start 22.22627 -163.903406)
		(end 22.606508 -166.060882)
		(width 0.1143)
		(layer "F.Cu")
		(net "L1_85OHM_5INCH_DP")
	)
	(segment
		(start 20.909026 -166.059866)
		(end 20.81657 -166.1922)
		(width 0.1143)
		(layer "F.Cu")
		(net "L1_85OHM_5INCH_DP")
	)
	(segment
		(start 47.479966 -166.174166)
		(end 47.04588 -163.710112)
		(width 0.1143)
		(layer "F.Cu")
		(net "L1_85OHM_5INCH_DP")
	)
	(segment
		(start 41.954704 -163.70808)
		(end 41.65854 -163.500816)
		(width 0.1143)
		(layer "F.Cu")
		(net "L1_85OHM_5INCH_DP")
	)
	(segment
		(start 40.688514 -166.155116)
		(end 40.254428 -163.691062)
		(width 0.1143)
		(layer "F.Cu")
		(net "L1_85OHM_5INCH_DP")
	)
	(segment
		(start 22.606508 -166.060882)
		(end 22.513798 -166.192708)
		(width 0.1143)
		(layer "F.Cu")
		(net "L1_85OHM_5INCH_DP")
	)
	(segment
		(start 28.379674 -163.723574)
		(end 28.083002 -163.516056)
		(width 0.1143)
		(layer "F.Cu")
		(net "L1_85OHM_5INCH_DP")
	)
	(segment
		(start 37.879528 -166.053008)
		(end 37.786818 -166.185342)
		(width 0.1143)
		(layer "F.Cu")
		(net "L1_85OHM_5INCH_DP")
	)
	(segment
		(start 41.274238 -166.052246)
		(end 41.181528 -166.18458)
		(width 0.1143)
		(layer "F.Cu")
		(net "L1_85OHM_5INCH_DP")
	)
	(segment
		(start 19.036284 -163.589462)
		(end 18.828766 -163.885626)
		(width 0.1143)
		(layer "F.Cu")
		(net "L1_85OHM_5INCH_DP")
	)
	(segment
		(start 22.43328 -163.606988)
		(end 22.22627 -163.903406)
		(width 0.1143)
		(layer "F.Cu")
		(net "L1_85OHM_5INCH_DP")
	)
	(segment
		(start 18.631154 -166.187374)
		(end 18.545556 -165.702488)
		(width 0.1143)
		(layer "F.Cu")
		(net "L1_85OHM_5INCH_DP")
	)
	(segment
		(start 22.021292 -166.163752)
		(end 21.586444 -163.695634)
		(width 0.1143)
		(layer "F.Cu")
		(net "L1_85OHM_5INCH_DP")
	)
	(segment
		(start 27.700732 -166.079424)
		(end 27.608276 -166.211504)
		(width 0.1143)
		(layer "F.Cu")
		(net "L1_85OHM_5INCH_DP")
	)
	(segment
		(start 31.476188 -163.510976)
		(end 30.919674 -163.608512)
		(width 0.1143)
		(layer "F.Cu")
		(net "L1_85OHM_5INCH_DP")
	)
	(segment
		(start 46.74997 -163.502848)
		(end 46.192694 -163.601146)
		(width 0.1143)
		(layer "F.Cu")
		(net "L1_85OHM_5INCH_DP")
	)
	(segment
		(start 28.81249 -166.180262)
		(end 28.379674 -163.723574)
		(width 0.1143)
		(layer "F.Cu")
		(net "L1_85OHM_5INCH_DP")
	)
	(segment
		(start 47.612808 -166.26713)
		(end 47.479966 -166.174166)
		(width 0.1143)
		(layer "F.Cu")
		(net "L1_85OHM_5INCH_DP")
	)
	(segment
		(start 52.11826 -164.880544)
		(end 51.597306 -164.880544)
		(width 0.1143)
		(layer "F.Cu")
		(net "L1_85OHM_5INCH_DP")
	)
	(segment
		(start 39.123366 -166.242746)
		(end 38.990524 -166.149782)
		(width 0.1143)
		(layer "F.Cu")
		(net "L1_85OHM_5INCH_DP")
	)
	(segment
		(start 35.73018 -166.247826)
		(end 35.597084 -166.154862)
		(width 0.1143)
		(layer "F.Cu")
		(net "L1_85OHM_5INCH_DP")
	)
	(segment
		(start 41.101264 -163.598606)
		(end 40.894 -163.894516)
		(width 0.1143)
		(layer "F.Cu")
		(net "L1_85OHM_5INCH_DP")
	)
	(segment
		(start 29.302456 -166.21252)
		(end 28.947872 -166.275004)
		(width 0.1143)
		(layer "F.Cu")
		(net "L1_85OHM_5INCH_DP")
	)
	(segment
		(start 42.97045 -166.048436)
		(end 42.87774 -166.181278)
		(width 0.1143)
		(layer "F.Cu")
		(net "L1_85OHM_5INCH_DP")
	)
	(segment
		(start 30.509972 -166.183818)
		(end 30.07614 -163.717732)
		(width 0.1143)
		(layer "F.Cu")
		(net "L1_85OHM_5INCH_DP")
	)
	(segment
		(start 23.92426 -163.908994)
		(end 24.303736 -166.063676)
		(width 0.1143)
		(layer "F.Cu")
		(net "L1_85OHM_5INCH_DP")
	)
	(segment
		(start 44.495466 -163.600638)
		(end 44.288202 -163.896294)
		(width 0.1143)
		(layer "F.Cu")
		(net "L1_85OHM_5INCH_DP")
	)
	(segment
		(start 36.860226 -163.689538)
		(end 36.564316 -163.482528)
		(width 0.1143)
		(layer "F.Cu")
		(net "L1_85OHM_5INCH_DP")
	)
	(segment
		(start 23.287736 -163.716462)
		(end 22.991064 -163.509452)
		(width 0.1143)
		(layer "F.Cu")
		(net "L1_85OHM_5INCH_DP")
	)
	(segment
		(start 18.763234 -166.279576)
		(end 18.631154 -166.187374)
		(width 0.1143)
		(layer "F.Cu")
		(net "L1_85OHM_5INCH_DP")
	)
	(segment
		(start 20.525486 -163.882832)
		(end 20.909026 -166.059866)
		(width 0.1143)
		(layer "F.Cu")
		(net "L1_85OHM_5INCH_DP")
	)
	(segment
		(start 48.44288 -163.479226)
		(end 47.885604 -163.57727)
		(width 0.1143)
		(layer "F.Cu")
		(net "L1_85OHM_5INCH_DP")
	)
	(segment
		(start 39.958518 -163.484052)
		(end 39.401242 -163.581842)
		(width 0.1143)
		(layer "F.Cu")
		(net "L1_85OHM_5INCH_DP")
	)
	(segment
		(start 24.13127 -163.612068)
		(end 23.92426 -163.908994)
		(width 0.1143)
		(layer "F.Cu")
		(net "L1_85OHM_5INCH_DP")
	)
	(segment
		(start 47.973234 -166.203884)
		(end 47.612808 -166.26713)
		(width 0.1143)
		(layer "F.Cu")
		(net "L1_85OHM_5INCH_DP")
	)
	(segment
		(start 26.00071 -166.06266)
		(end 25.908254 -166.19474)
		(width 0.1143)
		(layer "F.Cu")
		(net "L1_85OHM_5INCH_DP")
	)
	(segment
		(start 48.065944 -166.07155)
		(end 47.973234 -166.203884)
		(width 0.1143)
		(layer "F.Cu")
		(net "L1_85OHM_5INCH_DP")
	)
	(segment
		(start 52.500784 -164.512244)
		(end 52.11826 -164.880544)
		(width 0.1143)
		(layer "F.Cu")
		(net "L1_85OHM_5INCH_DP")
	)
	(segment
		(start 38.557708 -163.693094)
		(end 38.258496 -163.483544)
		(width 0.1143)
		(layer "F.Cu")
		(net "L1_85OHM_5INCH_DP")
	)
	(segment
		(start 45.98543 -163.89731)
		(end 46.369224 -166.074598)
		(width 0.1143)
		(layer "F.Cu")
		(net "L1_85OHM_5INCH_DP")
	)
	(segment
		(start 36.089844 -166.184834)
		(end 35.73018 -166.247826)
		(width 0.1143)
		(layer "F.Cu")
		(net "L1_85OHM_5INCH_DP")
	)
	(segment
		(start 20.732496 -163.585906)
		(end 20.525486 -163.882832)
		(width 0.1143)
		(layer "F.Cu")
		(net "L1_85OHM_5INCH_DP")
	)
	(segment
		(start 36.564316 -163.482528)
		(end 36.006024 -163.580572)
		(width 0.1143)
		(layer "F.Cu")
		(net "L1_85OHM_5INCH_DP")
	)
	(segment
		(start 46.192694 -163.601146)
		(end 45.98543 -163.89731)
		(width 0.1143)
		(layer "F.Cu")
		(net "L1_85OHM_5INCH_DP")
	)
	(segment
		(start 30.919674 -163.608512)
		(end 30.712156 -163.904676)
		(width 0.1143)
		(layer "F.Cu")
		(net "L1_85OHM_5INCH_DP")
	)
	(segment
		(start 40.254428 -163.691062)
		(end 39.958518 -163.484052)
		(width 0.1143)
		(layer "F.Cu")
		(net "L1_85OHM_5INCH_DP")
	)
	(segment
		(start 21.586444 -163.695634)
		(end 21.289772 -163.488116)
		(width 0.1143)
		(layer "F.Cu")
		(net "L1_85OHM_5INCH_DP")
	)
	(segment
		(start 46.276514 -166.20744)
		(end 45.916596 -166.270686)
		(width 0.1143)
		(layer "F.Cu")
		(net "L1_85OHM_5INCH_DP")
	)
	(segment
		(start 29.779214 -163.510214)
		(end 29.222446 -163.608004)
		(width 0.1143)
		(layer "F.Cu")
		(net "L1_85OHM_5INCH_DP")
	)
	(segment
		(start 24.21128 -166.19601)
		(end 23.851108 -166.25951)
		(width 0.1143)
		(layer "F.Cu")
		(net "L1_85OHM_5INCH_DP")
	)
	(segment
		(start 32.409892 -163.90874)
		(end 32.7914 -166.072058)
		(width 0.1143)
		(layer "F.Cu")
		(net "L1_85OHM_5INCH_DP")
	)
	(segment
		(start 27.52598 -163.613846)
		(end 27.318462 -163.91001)
		(width 0.1143)
		(layer "F.Cu")
		(net "L1_85OHM_5INCH_DP")
	)
	(segment
		(start 48.739044 -163.685728)
		(end 48.44288 -163.479226)
		(width 0.1143)
		(layer "F.Cu")
		(net "L1_85OHM_5INCH_DP")
	)
	(segment
		(start 27.608276 -166.211504)
		(end 27.247596 -166.274496)
		(width 0.1143)
		(layer "F.Cu")
		(net "L1_85OHM_5INCH_DP")
	)
	(segment
		(start 44.215304 -166.24935)
		(end 44.082462 -166.15664)
		(width 0.1143)
		(layer "F.Cu")
		(net "L1_85OHM_5INCH_DP")
	)
	(segment
		(start 31.002986 -166.212774)
		(end 30.642052 -166.276274)
		(width 0.1143)
		(layer "F.Cu")
		(net "L1_85OHM_5INCH_DP")
	)
	(segment
		(start 25.415494 -166.165276)
		(end 24.985218 -163.721796)
		(width 0.1143)
		(layer "F.Cu")
		(net "L1_85OHM_5INCH_DP")
	)
	(segment
		(start 36.006024 -163.580572)
		(end 35.799522 -163.876736)
		(width 0.1143)
		(layer "F.Cu")
		(net "L1_85OHM_5INCH_DP")
	)
	(segment
		(start 23.719028 -166.1668)
		(end 23.287736 -163.716462)
		(width 0.1143)
		(layer "F.Cu")
		(net "L1_85OHM_5INCH_DP")
	)
	(segment
		(start 47.04588 -163.710112)
		(end 46.74997 -163.502848)
		(width 0.1143)
		(layer "F.Cu")
		(net "L1_85OHM_5INCH_DP")
	)
	(segment
		(start 31.095188 -166.080694)
		(end 31.002986 -166.212774)
		(width 0.1143)
		(layer "F.Cu")
		(net "L1_85OHM_5INCH_DP")
	)
	(segment
		(start 27.11577 -166.182294)
		(end 26.681684 -163.717986)
		(width 0.1143)
		(layer "F.Cu")
		(net "L1_85OHM_5INCH_DP")
	)
	(segment
		(start 19.59356 -163.491672)
		(end 19.036284 -163.589462)
		(width 0.1143)
		(layer "F.Cu")
		(net "L1_85OHM_5INCH_DP")
	)
	(segment
		(start 34.392108 -166.181532)
		(end 34.032444 -166.244778)
		(width 0.1143)
		(layer "F.Cu")
		(net "L1_85OHM_5INCH_DP")
	)
	(segment
		(start 35.164268 -163.69792)
		(end 34.868358 -163.49091)
		(width 0.1143)
		(layer "F.Cu")
		(net "L1_85OHM_5INCH_DP")
	)
	(segment
		(start 45.052742 -163.50234)
		(end 44.495466 -163.600638)
		(width 0.1143)
		(layer "F.Cu")
		(net "L1_85OHM_5INCH_DP")
	)
	(segment
		(start 29.222446 -163.608004)
		(end 29.015182 -163.904422)
		(width 0.1143)
		(layer "F.Cu")
		(net "L1_85OHM_5INCH_DP")
	)
	(segment
		(start 41.181528 -166.18458)
		(end 40.821356 -166.247826)
		(width 0.1143)
		(layer "F.Cu")
		(net "L1_85OHM_5INCH_DP")
	)
	(segment
		(start 31.773114 -163.718494)
		(end 31.476188 -163.510976)
		(width 0.1143)
		(layer "F.Cu")
		(net "L1_85OHM_5INCH_DP")
	)
	(segment
		(start 34.10331 -163.885118)
		(end 34.484818 -166.04869)
		(width 0.1143)
		(layer "F.Cu")
		(net "L1_85OHM_5INCH_DP")
	)
	(segment
		(start 18.545556 -165.702488)
		(end 18.001234 -165.032944)
		(width 0.1143)
		(layer "F.Cu")
		(net "L1_85OHM_5INCH_DP")
	)
	(segment
		(start 32.69869 -166.204646)
		(end 32.33801 -166.267892)
		(width 0.1143)
		(layer "F.Cu")
		(net "L1_85OHM_5INCH_DP")
	)
	(segment
		(start 44.575984 -166.186358)
		(end 44.215304 -166.24935)
		(width 0.1143)
		(layer "F.Cu")
		(net "L1_85OHM_5INCH_DP")
	)
	(segment
		(start 25.82799 -163.608766)
		(end 25.620472 -163.90493)
		(width 0.1143)
		(layer "F.Cu")
		(net "L1_85OHM_5INCH_DP")
	)
	(segment
		(start 20.456398 -166.2557)
		(end 20.324318 -166.163244)
		(width 0.1143)
		(layer "F.Cu")
		(net "L1_85OHM_5INCH_DP")
	)
	(segment
		(start 15.543022 -164.891974)
		(end 15.031466 -164.891974)
		(width 0.1143)
		(layer "F.Cu")
		(net "L1_85OHM_5INCH_DP")
	)
	(segment
		(start 25.620472 -163.90493)
		(end 26.00071 -166.06266)
		(width 0.1143)
		(layer "F.Cu")
		(net "L1_85OHM_5INCH_DP")
	)
	(segment
		(start 27.318462 -163.91001)
		(end 27.700732 -166.079424)
		(width 0.1143)
		(layer "F.Cu")
		(net "L1_85OHM_5INCH_DP")
	)
	(segment
		(start 30.07614 -163.717732)
		(end 29.779214 -163.510214)
		(width 0.1143)
		(layer "F.Cu")
		(net "L1_85OHM_5INCH_DP")
	)
	(segment
		(start 29.015182 -163.904422)
		(end 29.39796 -166.07663)
		(width 0.1143)
		(layer "F.Cu")
		(net "L1_85OHM_5INCH_DP")
	)
	(segment
		(start 24.303736 -166.063676)
		(end 24.21128 -166.19601)
		(width 0.1143)
		(layer "F.Cu")
		(net "L1_85OHM_5INCH_DP")
	)
	(segment
		(start 26.681684 -163.717986)
		(end 26.384758 -163.510976)
		(width 0.1143)
		(layer "F.Cu")
		(net "L1_85OHM_5INCH_DP")
	)
	(segment
		(start 44.66844 -166.054024)
		(end 44.575984 -166.186358)
		(width 0.1143)
		(layer "F.Cu")
		(net "L1_85OHM_5INCH_DP")
	)
	(segment
		(start 38.990524 -166.149782)
		(end 38.557708 -163.693094)
		(width 0.1143)
		(layer "F.Cu")
		(net "L1_85OHM_5INCH_DP")
	)
	(segment
		(start 37.294058 -166.155624)
		(end 36.860226 -163.689538)
		(width 0.1143)
		(layer "F.Cu")
		(net "L1_85OHM_5INCH_DP")
	)
	(segment
		(start 40.821356 -166.247826)
		(end 40.688514 -166.155116)
		(width 0.1143)
		(layer "F.Cu")
		(net "L1_85OHM_5INCH_DP")
	)
	(segment
		(start 42.517822 -166.244524)
		(end 42.38498 -166.15156)
		(width 0.1143)
		(layer "F.Cu")
		(net "L1_85OHM_5INCH_DP")
	)
	(segment
		(start 35.799522 -163.876736)
		(end 36.182554 -166.0525)
		(width 0.1143)
		(layer "F.Cu")
		(net "L1_85OHM_5INCH_DP")
	)
	(segment
		(start 32.20593 -166.175436)
		(end 31.773114 -163.718494)
		(width 0.1143)
		(layer "F.Cu")
		(net "L1_85OHM_5INCH_DP")
	)
	(segment
		(start 46.369224 -166.074598)
		(end 46.276514 -166.20744)
		(width 0.1143)
		(layer "F.Cu")
		(net "L1_85OHM_5INCH_DP")
	)
	(segment
		(start 25.908254 -166.19474)
		(end 25.547574 -166.257732)
		(width 0.1143)
		(layer "F.Cu")
		(net "L1_85OHM_5INCH_DP")
	)
	(segment
		(start 37.786818 -166.185342)
		(end 37.4269 -166.248588)
		(width 0.1143)
		(layer "F.Cu")
		(net "L1_85OHM_5INCH_DP")
	)
	(segment
		(start 32.33801 -166.267892)
		(end 32.20593 -166.175436)
		(width 0.1143)
		(layer "F.Cu")
		(net "L1_85OHM_5INCH_DP")
	)
	(segment
		(start 25.547574 -166.257732)
		(end 25.415494 -166.165276)
		(width 0.1143)
		(layer "F.Cu")
		(net "L1_85OHM_5INCH_DP")
	)
	(segment
		(start 22.153372 -166.256208)
		(end 22.021292 -166.163752)
		(width 0.1143)
		(layer "F.Cu")
		(net "L1_85OHM_5INCH_DP")
	)
	(segment
		(start 35.597084 -166.154862)
		(end 35.164268 -163.69792)
		(width 0.1143)
		(layer "F.Cu")
		(net "L1_85OHM_5INCH_DP")
	)
	(segment
		(start 19.21637 -166.083996)
		(end 19.12366 -166.216076)
		(width 0.1143)
		(layer "F.Cu")
		(net "L1_85OHM_5INCH_DP")
	)
	(segment
		(start 22.513798 -166.192708)
		(end 22.153372 -166.256208)
		(width 0.1143)
		(layer "F.Cu")
		(net "L1_85OHM_5INCH_DP")
	)
	(segment
		(start 44.288202 -163.896294)
		(end 44.66844 -166.054024)
		(width 0.1143)
		(layer "F.Cu")
		(net "L1_85OHM_5INCH_DP")
	)
	(segment
		(start 28.947872 -166.275004)
		(end 28.81249 -166.180262)
		(width 0.1143)
		(layer "F.Cu")
		(net "L1_85OHM_5INCH_DP")
	)
	(segment
		(start 33.173924 -163.514024)
		(end 32.616902 -163.611814)
		(width 0.1143)
		(layer "F.Cu")
		(net "L1_85OHM_5INCH_DP")
	)
	(segment
		(start 48.830992 -164.207698)
		(end 48.739044 -163.685728)
		(width 0.1143)
		(layer "F.Cu")
		(net "L1_85OHM_5INCH_DP")
	)
	(segment
		(start 42.797984 -163.597336)
		(end 42.59072 -163.8935)
		(width 0.1143)
		(layer "F.Cu")
		(net "L1_85OHM_5INCH_DP")
	)
	(segment
		(start 37.707062 -163.580826)
		(end 37.496496 -163.880292)
		(width 0.1143)
		(layer "F.Cu")
		(net "L1_85OHM_5INCH_DP")
	)
	(segment
		(start 32.616902 -163.611814)
		(end 32.409892 -163.90874)
		(width 0.1143)
		(layer "F.Cu")
		(net "L1_85OHM_5INCH_DP")
	)
	(segment
		(start 33.470596 -163.721542)
		(end 33.173924 -163.514024)
		(width 0.1143)
		(layer "F.Cu")
		(net "L1_85OHM_5INCH_DP")
	)
	(segment
		(start 34.868358 -163.49091)
		(end 34.310828 -163.5887)
		(width 0.1143)
		(layer "F.Cu")
		(net "L1_85OHM_5INCH_DP")
	)
	(segment
		(start 39.576248 -166.047166)
		(end 39.483538 -166.1795)
		(width 0.1143)
		(layer "F.Cu")
		(net "L1_85OHM_5INCH_DP")
	)
	(segment
		(start 18.001234 -165.032944)
		(end 16.647668 -164.806376)
		(width 0.1143)
		(layer "F.Cu")
		(net "L1_85OHM_5INCH_DP")
	)
	(segment
		(start 20.81657 -166.1922)
		(end 20.456398 -166.2557)
		(width 0.1143)
		(layer "F.Cu")
		(net "L1_85OHM_5INCH_DP")
	)
	(segment
		(start 37.496496 -163.880292)
		(end 37.879528 -166.053008)
		(width 0.1143)
		(layer "F.Cu")
		(net "L1_85OHM_5INCH_DP")
	)
	(segment
		(start 45.916596 -166.270686)
		(end 45.783754 -166.177722)
		(width 0.1143)
		(layer "F.Cu")
		(net "L1_85OHM_5INCH_DP")
	)
	(segment
		(start 50.512726 -164.964364)
		(end 49.278286 -164.757862)
		(width 0.1143)
		(layer "F.Cu")
		(net "L1_85OHM_5INCH_DP")
	)
	(segment
		(start 19.12366 -166.216076)
		(end 18.763234 -166.279576)
		(width 0.1143)
		(layer "F.Cu")
		(net "L1_85OHM_5INCH_DP")
	)
	(segment
		(start 37.4269 -166.248588)
		(end 37.294058 -166.155624)
		(width 0.1143)
		(layer "F.Cu")
		(net "L1_85OHM_5INCH_DP")
	)
	(segment
		(start 24.688546 -163.514278)
		(end 24.13127 -163.612068)
		(width 0.1143)
		(layer "F.Cu")
		(net "L1_85OHM_5INCH_DP")
	)
	(segment
		(start 34.310828 -163.5887)
		(end 34.10331 -163.885118)
		(width 0.1143)
		(layer "F.Cu")
		(net "L1_85OHM_5INCH_DP")
	)
	(segment
		(start 32.7914 -166.072058)
		(end 32.69869 -166.204646)
		(width 0.1143)
		(layer "F.Cu")
		(net "L1_85OHM_5INCH_DP")
	)
	(segment
		(start 27.247596 -166.274496)
		(end 27.11577 -166.182294)
		(width 0.1143)
		(layer "F.Cu")
		(net "L1_85OHM_5INCH_DP")
	)
	(segment
		(start 44.082462 -166.15664)
		(end 43.65117 -163.706556)
		(width 0.1143)
		(layer "F.Cu")
		(net "L1_85OHM_5INCH_DP")
	)
	(segment
		(start 42.87774 -166.181278)
		(end 42.517822 -166.244524)
		(width 0.1143)
		(layer "F.Cu")
		(net "L1_85OHM_5INCH_DP")
	)
	(segment
		(start 30.712156 -163.904676)
		(end 31.095188 -166.080694)
		(width 0.1143)
		(layer "F.Cu")
		(net "L1_85OHM_5INCH_DP")
	)
	(segment
		(start 42.38498 -166.15156)
		(end 41.954704 -163.70808)
		(width 0.1143)
		(layer "F.Cu")
		(net "L1_85OHM_5INCH_DP")
	)
	(segment
		(start 42.59072 -163.8935)
		(end 42.97045 -166.048436)
		(width 0.1143)
		(layer "F.Cu")
		(net "L1_85OHM_5INCH_DP")
	)
	(segment
		(start 23.851108 -166.25951)
		(end 23.719028 -166.1668)
		(width 0.1143)
		(layer "F.Cu")
		(net "L1_85OHM_5INCH_DP")
	)
	(segment
		(start 39.401242 -163.581842)
		(end 39.193978 -163.877752)
		(width 0.1143)
		(layer "F.Cu")
		(net "L1_85OHM_5INCH_DP")
	)
	(segment
		(start 43.35526 -163.499292)
		(end 42.797984 -163.597336)
		(width 0.1143)
		(layer "F.Cu")
		(net "L1_85OHM_5INCH_DP")
	)
	(segment
		(start 51.597306 -164.880544)
		(end 50.512726 -164.964364)
		(width 0.1143)
		(layer "F.Cu")
		(net "L1_85OHM_5INCH_DP")
	)
	(segment
		(start 28.083002 -163.516056)
		(end 27.52598 -163.613846)
		(width 0.1143)
		(layer "F.Cu")
		(net "L1_85OHM_5INCH_DP")
	)
	(segment
		(start 15.031466 -164.891974)
		(end 14.651736 -164.519356)
		(width 0.1143)
		(layer "F.Cu")
		(net "L1_85OHM_5INCH_DP")
	)
	(segment
		(start 20.324318 -166.163244)
		(end 19.890232 -163.69919)
		(width 0.1143)
		(layer "F.Cu")
		(net "L1_85OHM_5INCH_DP")
	)
	(segment
		(start 18.828766 -163.885626)
		(end 19.21637 -166.083996)
		(width 0.1143)
		(layer "F.Cu")
		(net "L1_85OHM_5INCH_DP")
	)
	(segment
		(start 36.182554 -166.0525)
		(end 36.089844 -166.184834)
		(width 0.1143)
		(layer "F.Cu")
		(net "L1_85OHM_5INCH_DP")
	)
	(segment
		(start 49.278286 -164.757862)
		(end 48.830992 -164.207698)
		(width 0.1143)
		(layer "F.Cu")
		(net "L1_85OHM_5INCH_DP")
	)
	(segment
		(start 21.289772 -163.488116)
		(end 20.732496 -163.585906)
		(width 0.1143)
		(layer "F.Cu")
		(net "L1_85OHM_5INCH_DP")
	)
	(segment
		(start 16.647668 -164.806376)
		(end 15.543022 -164.891974)
		(width 0.1143)
		(layer "F.Cu")
		(net "L1_85OHM_5INCH_DP")
	)
	(segment
		(start 39.483538 -166.1795)
		(end 39.123366 -166.242746)
		(width 0.1143)
		(layer "F.Cu")
		(net "L1_85OHM_5INCH_DP")
	)
	(segment
		(start 34.484818 -166.04869)
		(end 34.392108 -166.181532)
		(width 0.1143)
		(layer "F.Cu")
		(net "L1_85OHM_5INCH_DP")
	)
	(segment
		(start 41.65854 -163.500816)
		(end 41.101264 -163.598606)
		(width 0.1143)
		(layer "F.Cu")
		(net "L1_85OHM_5INCH_DP")
	)
	(segment
		(start 40.894 -163.894516)
		(end 41.274238 -166.052246)
		(width 0.1143)
		(layer "F.Cu")
		(net "L1_85OHM_5INCH_DP")
	)
	(segment
		(start 19.890232 -163.69919)
		(end 19.59356 -163.491672)
		(width 0.1143)
		(layer "F.Cu")
		(net "L1_85OHM_5INCH_DP")
	)
	(segment
		(start 17.87144 -165.255956)
		(end 16.637 -165.049454)
		(width 0.1143)
		(layer "F.Cu")
		(net "L1_85OHM_5INCH_DN")
	)
	(segment
		(start 18.706846 -166.534592)
		(end 18.410682 -166.32809)
		(width 0.1143)
		(layer "F.Cu")
		(net "L1_85OHM_5INCH_DN")
	)
	(segment
		(start 40.033956 -163.831524)
		(end 39.90213 -163.739322)
		(width 0.1143)
		(layer "F.Cu")
		(net "L1_85OHM_5INCH_DN")
	)
	(segment
		(start 34.943796 -163.838382)
		(end 34.811716 -163.745926)
		(width 0.1143)
		(layer "F.Cu")
		(net "L1_85OHM_5INCH_DN")
	)
	(segment
		(start 19.66976 -163.839652)
		(end 19.536918 -163.746688)
		(width 0.1143)
		(layer "F.Cu")
		(net "L1_85OHM_5INCH_DN")
	)
	(segment
		(start 23.498556 -166.307262)
		(end 23.067264 -163.857178)
		(width 0.1143)
		(layer "F.Cu")
		(net "L1_85OHM_5INCH_DN")
	)
	(segment
		(start 26.32837 -163.765992)
		(end 25.968198 -163.829238)
		(width 0.1143)
		(layer "F.Cu")
		(net "L1_85OHM_5INCH_DN")
	)
	(segment
		(start 44.923456 -166.110412)
		(end 44.716446 -166.40683)
		(width 0.1143)
		(layer "F.Cu")
		(net "L1_85OHM_5INCH_DN")
	)
	(segment
		(start 42.164508 -166.292022)
		(end 41.734232 -163.848542)
		(width 0.1143)
		(layer "F.Cu")
		(net "L1_85OHM_5INCH_DN")
	)
	(segment
		(start 47.259494 -166.314628)
		(end 46.825408 -163.850574)
		(width 0.1143)
		(layer "F.Cu")
		(net "L1_85OHM_5INCH_DN")
	)
	(segment
		(start 48.60417 -164.31133)
		(end 48.518572 -163.826444)
		(width 0.1143)
		(layer "F.Cu")
		(net "L1_85OHM_5INCH_DN")
	)
	(segment
		(start 41.241472 -163.819078)
		(end 41.149016 -163.951158)
		(width 0.1143)
		(layer "F.Cu")
		(net "L1_85OHM_5INCH_DN")
	)
	(segment
		(start 41.321736 -166.405052)
		(end 40.764968 -166.502842)
		(width 0.1143)
		(layer "F.Cu")
		(net "L1_85OHM_5INCH_DN")
	)
	(segment
		(start 51.606704 -165.121844)
		(end 50.502058 -165.207442)
		(width 0.1143)
		(layer "F.Cu")
		(net "L1_85OHM_5INCH_DN")
	)
	(segment
		(start 36.230052 -166.405306)
		(end 35.673538 -166.502842)
		(width 0.1143)
		(layer "F.Cu")
		(net "L1_85OHM_5INCH_DN")
	)
	(segment
		(start 46.2407 -163.953952)
		(end 46.62424 -166.130986)
		(width 0.1143)
		(layer "F.Cu")
		(net "L1_85OHM_5INCH_DN")
	)
	(segment
		(start 32.281368 -166.522908)
		(end 31.985458 -166.315898)
		(width 0.1143)
		(layer "F.Cu")
		(net "L1_85OHM_5INCH_DN")
	)
	(segment
		(start 31.985458 -166.315898)
		(end 31.552642 -163.858956)
		(width 0.1143)
		(layer "F.Cu")
		(net "L1_85OHM_5INCH_DN")
	)
	(segment
		(start 24.179276 -163.965382)
		(end 24.559006 -166.120318)
		(width 0.1143)
		(layer "F.Cu")
		(net "L1_85OHM_5INCH_DN")
	)
	(segment
		(start 46.333156 -163.821618)
		(end 46.2407 -163.953952)
		(width 0.1143)
		(layer "F.Cu")
		(net "L1_85OHM_5INCH_DN")
	)
	(segment
		(start 20.957032 -166.412672)
		(end 20.399756 -166.51097)
		(width 0.1143)
		(layer "F.Cu")
		(net "L1_85OHM_5INCH_DN")
	)
	(segment
		(start 45.128434 -163.850066)
		(end 44.996354 -163.75761)
		(width 0.1143)
		(layer "F.Cu")
		(net "L1_85OHM_5INCH_DN")
	)
	(segment
		(start 26.895298 -166.322756)
		(end 26.461212 -163.858702)
		(width 0.1143)
		(layer "F.Cu")
		(net "L1_85OHM_5INCH_DN")
	)
	(segment
		(start 31.419546 -163.765992)
		(end 31.059882 -163.828984)
		(width 0.1143)
		(layer "F.Cu")
		(net "L1_85OHM_5INCH_DN")
	)
	(segment
		(start 49.148492 -164.980874)
		(end 48.60417 -164.31133)
		(width 0.1143)
		(layer "F.Cu")
		(net "L1_85OHM_5INCH_DN")
	)
	(segment
		(start 42.46118 -166.49954)
		(end 42.164508 -166.292022)
		(width 0.1143)
		(layer "F.Cu")
		(net "L1_85OHM_5INCH_DN")
	)
	(segment
		(start 21.365972 -163.836096)
		(end 21.23313 -163.743132)
		(width 0.1143)
		(layer "F.Cu")
		(net "L1_85OHM_5INCH_DN")
	)
	(segment
		(start 39.831264 -166.103808)
		(end 39.623746 -166.399972)
		(width 0.1143)
		(layer "F.Cu")
		(net "L1_85OHM_5INCH_DN")
	)
	(segment
		(start 43.298618 -163.754308)
		(end 42.938446 -163.817808)
		(width 0.1143)
		(layer "F.Cu")
		(net "L1_85OHM_5INCH_DN")
	)
	(segment
		(start 28.592018 -166.320724)
		(end 28.159202 -163.864036)
		(width 0.1143)
		(layer "F.Cu")
		(net "L1_85OHM_5INCH_DN")
	)
	(segment
		(start 41.602152 -163.756086)
		(end 41.241472 -163.819078)
		(width 0.1143)
		(layer "F.Cu")
		(net "L1_85OHM_5INCH_DN")
	)
	(segment
		(start 22.65426 -166.41318)
		(end 22.096984 -166.511478)
		(width 0.1143)
		(layer "F.Cu")
		(net "L1_85OHM_5INCH_DN")
	)
	(segment
		(start 27.955748 -166.136066)
		(end 27.748484 -166.431976)
		(width 0.1143)
		(layer "F.Cu")
		(net "L1_85OHM_5INCH_DN")
	)
	(segment
		(start 21.23313 -163.743132)
		(end 20.873212 -163.806378)
		(width 0.1143)
		(layer "F.Cu")
		(net "L1_85OHM_5INCH_DN")
	)
	(segment
		(start 46.62424 -166.130986)
		(end 46.41723 -166.427912)
		(width 0.1143)
		(layer "F.Cu")
		(net "L1_85OHM_5INCH_DN")
	)
	(segment
		(start 28.02636 -163.771072)
		(end 27.666188 -163.834318)
		(width 0.1143)
		(layer "F.Cu")
		(net "L1_85OHM_5INCH_DN")
	)
	(segment
		(start 44.158662 -166.504366)
		(end 43.86199 -166.297356)
		(width 0.1143)
		(layer "F.Cu")
		(net "L1_85OHM_5INCH_DN")
	)
	(segment
		(start 33.67913 -166.292276)
		(end 33.48101 -165.170104)
		(width 0.1143)
		(layer "F.Cu")
		(net "L1_85OHM_5INCH_DN")
	)
	(segment
		(start 39.448994 -163.934394)
		(end 39.831264 -166.103808)
		(width 0.1143)
		(layer "F.Cu")
		(net "L1_85OHM_5INCH_DN")
	)
	(segment
		(start 48.518572 -163.826444)
		(end 48.386492 -163.734242)
		(width 0.1143)
		(layer "F.Cu")
		(net "L1_85OHM_5INCH_DN")
	)
	(segment
		(start 35.673538 -166.502842)
		(end 35.376612 -166.295324)
		(width 0.1143)
		(layer "F.Cu")
		(net "L1_85OHM_5INCH_DN")
	)
	(segment
		(start 33.046416 -166.1287)
		(end 32.838898 -166.425118)
		(width 0.1143)
		(layer "F.Cu")
		(net "L1_85OHM_5INCH_DN")
	)
	(segment
		(start 20.399756 -166.51097)
		(end 20.103846 -166.303706)
		(width 0.1143)
		(layer "F.Cu")
		(net "L1_85OHM_5INCH_DN")
	)
	(segment
		(start 52.500784 -165.513004)
		(end 52.11826 -165.121844)
		(width 0.1143)
		(layer "F.Cu")
		(net "L1_85OHM_5INCH_DN")
	)
	(segment
		(start 36.054538 -163.933124)
		(end 36.43757 -166.109142)
		(width 0.1143)
		(layer "F.Cu")
		(net "L1_85OHM_5INCH_DN")
	)
	(segment
		(start 48.386492 -163.734242)
		(end 48.026066 -163.797742)
		(width 0.1143)
		(layer "F.Cu")
		(net "L1_85OHM_5INCH_DN")
	)
	(segment
		(start 29.722826 -163.76523)
		(end 29.362908 -163.828476)
		(width 0.1143)
		(layer "F.Cu")
		(net "L1_85OHM_5INCH_DN")
	)
	(segment
		(start 39.54145 -163.802314)
		(end 39.448994 -163.934394)
		(width 0.1143)
		(layer "F.Cu")
		(net "L1_85OHM_5INCH_DN")
	)
	(segment
		(start 29.65323 -166.133526)
		(end 29.442664 -166.432992)
		(width 0.1143)
		(layer "F.Cu")
		(net "L1_85OHM_5INCH_DN")
	)
	(segment
		(start 22.481286 -163.959794)
		(end 22.861524 -166.117524)
		(width 0.1143)
		(layer "F.Cu")
		(net "L1_85OHM_5INCH_DN")
	)
	(segment
		(start 37.370512 -166.503604)
		(end 37.073586 -166.296086)
		(width 0.1143)
		(layer "F.Cu")
		(net "L1_85OHM_5INCH_DN")
	)
	(segment
		(start 44.635928 -163.82111)
		(end 44.543218 -163.952936)
		(width 0.1143)
		(layer "F.Cu")
		(net "L1_85OHM_5INCH_DN")
	)
	(segment
		(start 19.471386 -166.140638)
		(end 19.264122 -166.436548)
		(width 0.1143)
		(layer "F.Cu")
		(net "L1_85OHM_5INCH_DN")
	)
	(segment
		(start 22.096984 -166.511478)
		(end 21.80082 -166.304214)
		(width 0.1143)
		(layer "F.Cu")
		(net "L1_85OHM_5INCH_DN")
	)
	(segment
		(start 44.996354 -163.75761)
		(end 44.635928 -163.82111)
		(width 0.1143)
		(layer "F.Cu")
		(net "L1_85OHM_5INCH_DN")
	)
	(segment
		(start 22.573742 -163.82746)
		(end 22.481286 -163.959794)
		(width 0.1143)
		(layer "F.Cu")
		(net "L1_85OHM_5INCH_DN")
	)
	(segment
		(start 48.32096 -166.128192)
		(end 48.113442 -166.424356)
		(width 0.1143)
		(layer "F.Cu")
		(net "L1_85OHM_5INCH_DN")
	)
	(segment
		(start 31.350204 -166.137082)
		(end 31.143702 -166.433246)
		(width 0.1143)
		(layer "F.Cu")
		(net "L1_85OHM_5INCH_DN")
	)
	(segment
		(start 39.066724 -166.497762)
		(end 38.770052 -166.290244)
		(width 0.1143)
		(layer "F.Cu")
		(net "L1_85OHM_5INCH_DN")
	)
	(segment
		(start 34.358326 -163.94176)
		(end 34.739834 -166.105078)
		(width 0.1143)
		(layer "F.Cu")
		(net "L1_85OHM_5INCH_DN")
	)
	(segment
		(start 25.491186 -166.513002)
		(end 25.195022 -166.305738)
		(width 0.1143)
		(layer "F.Cu")
		(net "L1_85OHM_5INCH_DN")
	)
	(segment
		(start 34.451036 -163.809172)
		(end 34.358326 -163.94176)
		(width 0.1143)
		(layer "F.Cu")
		(net "L1_85OHM_5INCH_DN")
	)
	(segment
		(start 20.103846 -166.303706)
		(end 19.66976 -163.839652)
		(width 0.1143)
		(layer "F.Cu")
		(net "L1_85OHM_5INCH_DN")
	)
	(segment
		(start 38.134544 -166.109396)
		(end 37.92728 -166.405814)
		(width 0.1143)
		(layer "F.Cu")
		(net "L1_85OHM_5INCH_DN")
	)
	(segment
		(start 33.250124 -163.862004)
		(end 33.117282 -163.76904)
		(width 0.1143)
		(layer "F.Cu")
		(net "L1_85OHM_5INCH_DN")
	)
	(segment
		(start 46.825408 -163.850574)
		(end 46.693328 -163.758118)
		(width 0.1143)
		(layer "F.Cu")
		(net "L1_85OHM_5INCH_DN")
	)
	(segment
		(start 19.176492 -163.809934)
		(end 19.083782 -163.942268)
		(width 0.1143)
		(layer "F.Cu")
		(net "L1_85OHM_5INCH_DN")
	)
	(segment
		(start 47.933356 -163.929822)
		(end 48.32096 -166.128192)
		(width 0.1143)
		(layer "F.Cu")
		(net "L1_85OHM_5INCH_DN")
	)
	(segment
		(start 33.117282 -163.76904)
		(end 32.757618 -163.832286)
		(width 0.1143)
		(layer "F.Cu")
		(net "L1_85OHM_5INCH_DN")
	)
	(segment
		(start 36.43757 -166.109142)
		(end 36.230052 -166.405306)
		(width 0.1143)
		(layer "F.Cu")
		(net "L1_85OHM_5INCH_DN")
	)
	(segment
		(start 29.362908 -163.828476)
		(end 29.270198 -163.96081)
		(width 0.1143)
		(layer "F.Cu")
		(net "L1_85OHM_5INCH_DN")
	)
	(segment
		(start 26.255726 -166.119302)
		(end 26.048462 -166.415212)
		(width 0.1143)
		(layer "F.Cu")
		(net "L1_85OHM_5INCH_DN")
	)
	(segment
		(start 24.351742 -166.416482)
		(end 23.794466 -166.514526)
		(width 0.1143)
		(layer "F.Cu")
		(net "L1_85OHM_5INCH_DN")
	)
	(segment
		(start 25.195022 -166.305738)
		(end 24.764746 -163.862258)
		(width 0.1143)
		(layer "F.Cu")
		(net "L1_85OHM_5INCH_DN")
	)
	(segment
		(start 31.059882 -163.828984)
		(end 30.967172 -163.961318)
		(width 0.1143)
		(layer "F.Cu")
		(net "L1_85OHM_5INCH_DN")
	)
	(segment
		(start 39.90213 -163.739322)
		(end 39.54145 -163.802314)
		(width 0.1143)
		(layer "F.Cu")
		(net "L1_85OHM_5INCH_DN")
	)
	(segment
		(start 42.84599 -163.950142)
		(end 43.225466 -166.104824)
		(width 0.1143)
		(layer "F.Cu")
		(net "L1_85OHM_5INCH_DN")
	)
	(segment
		(start 28.89123 -166.530274)
		(end 28.592018 -166.320724)
		(width 0.1143)
		(layer "F.Cu")
		(net "L1_85OHM_5INCH_DN")
	)
	(segment
		(start 41.529254 -166.108888)
		(end 41.321736 -166.405052)
		(width 0.1143)
		(layer "F.Cu")
		(net "L1_85OHM_5INCH_DN")
	)
	(segment
		(start 18.410682 -166.32809)
		(end 18.318734 -165.80612)
		(width 0.1143)
		(layer "F.Cu")
		(net "L1_85OHM_5INCH_DN")
	)
	(segment
		(start 36.14674 -163.801044)
		(end 36.054538 -163.933124)
		(width 0.1143)
		(layer "F.Cu")
		(net "L1_85OHM_5INCH_DN")
	)
	(segment
		(start 48.113442 -166.424356)
		(end 47.556166 -166.522146)
		(width 0.1143)
		(layer "F.Cu")
		(net "L1_85OHM_5INCH_DN")
	)
	(segment
		(start 23.067264 -163.857178)
		(end 22.934422 -163.764468)
		(width 0.1143)
		(layer "F.Cu")
		(net "L1_85OHM_5INCH_DN")
	)
	(segment
		(start 44.543218 -163.952936)
		(end 44.923456 -166.110412)
		(width 0.1143)
		(layer "F.Cu")
		(net "L1_85OHM_5INCH_DN")
	)
	(segment
		(start 34.532824 -166.402004)
		(end 33.975802 -166.499794)
		(width 0.1143)
		(layer "F.Cu")
		(net "L1_85OHM_5INCH_DN")
	)
	(segment
		(start 31.552642 -163.858956)
		(end 31.419546 -163.765992)
		(width 0.1143)
		(layer "F.Cu")
		(net "L1_85OHM_5INCH_DN")
	)
	(segment
		(start 23.794466 -166.514526)
		(end 23.498556 -166.307262)
		(width 0.1143)
		(layer "F.Cu")
		(net "L1_85OHM_5INCH_DN")
	)
	(segment
		(start 45.859954 -166.525702)
		(end 45.563282 -166.318184)
		(width 0.1143)
		(layer "F.Cu")
		(net "L1_85OHM_5INCH_DN")
	)
	(segment
		(start 35.376612 -166.295324)
		(end 34.943796 -163.838382)
		(width 0.1143)
		(layer "F.Cu")
		(net "L1_85OHM_5INCH_DN")
	)
	(segment
		(start 37.073586 -166.296086)
		(end 36.639754 -163.83)
		(width 0.1143)
		(layer "F.Cu")
		(net "L1_85OHM_5INCH_DN")
	)
	(segment
		(start 37.84727 -163.801298)
		(end 37.751766 -163.937188)
		(width 0.1143)
		(layer "F.Cu")
		(net "L1_85OHM_5INCH_DN")
	)
	(segment
		(start 24.764746 -163.862258)
		(end 24.631904 -163.769294)
		(width 0.1143)
		(layer "F.Cu")
		(net "L1_85OHM_5INCH_DN")
	)
	(segment
		(start 38.337236 -163.833556)
		(end 38.201854 -163.738814)
		(width 0.1143)
		(layer "F.Cu")
		(net "L1_85OHM_5INCH_DN")
	)
	(segment
		(start 24.631904 -163.769294)
		(end 24.271986 -163.83254)
		(width 0.1143)
		(layer "F.Cu")
		(net "L1_85OHM_5INCH_DN")
	)
	(segment
		(start 45.563282 -166.318184)
		(end 45.128434 -163.850066)
		(width 0.1143)
		(layer "F.Cu")
		(net "L1_85OHM_5INCH_DN")
	)
	(segment
		(start 42.938446 -163.817808)
		(end 42.84599 -163.950142)
		(width 0.1143)
		(layer "F.Cu")
		(net "L1_85OHM_5INCH_DN")
	)
	(segment
		(start 25.875488 -163.961572)
		(end 26.255726 -166.119302)
		(width 0.1143)
		(layer "F.Cu")
		(net "L1_85OHM_5INCH_DN")
	)
	(segment
		(start 48.026066 -163.797742)
		(end 47.933356 -163.929822)
		(width 0.1143)
		(layer "F.Cu")
		(net "L1_85OHM_5INCH_DN")
	)
	(segment
		(start 38.201854 -163.738814)
		(end 37.84727 -163.801298)
		(width 0.1143)
		(layer "F.Cu")
		(net "L1_85OHM_5INCH_DN")
	)
	(segment
		(start 43.018456 -166.40175)
		(end 42.46118 -166.49954)
		(width 0.1143)
		(layer "F.Cu")
		(net "L1_85OHM_5INCH_DN")
	)
	(segment
		(start 46.693328 -163.758118)
		(end 46.333156 -163.821618)
		(width 0.1143)
		(layer "F.Cu")
		(net "L1_85OHM_5INCH_DN")
	)
	(segment
		(start 29.442664 -166.432992)
		(end 28.89123 -166.530274)
		(width 0.1143)
		(layer "F.Cu")
		(net "L1_85OHM_5INCH_DN")
	)
	(segment
		(start 41.149016 -163.951158)
		(end 41.529254 -166.108888)
		(width 0.1143)
		(layer "F.Cu")
		(net "L1_85OHM_5INCH_DN")
	)
	(segment
		(start 52.11826 -165.121844)
		(end 51.606704 -165.121844)
		(width 0.1143)
		(layer "F.Cu")
		(net "L1_85OHM_5INCH_DN")
	)
	(segment
		(start 29.855668 -163.858194)
		(end 29.722826 -163.76523)
		(width 0.1143)
		(layer "F.Cu")
		(net "L1_85OHM_5INCH_DN")
	)
	(segment
		(start 19.083782 -163.942268)
		(end 19.471386 -166.140638)
		(width 0.1143)
		(layer "F.Cu")
		(net "L1_85OHM_5INCH_DN")
	)
	(segment
		(start 30.2895 -166.32428)
		(end 29.855668 -163.858194)
		(width 0.1143)
		(layer "F.Cu")
		(net "L1_85OHM_5INCH_DN")
	)
	(segment
		(start 38.770052 -166.290244)
		(end 38.337236 -163.833556)
		(width 0.1143)
		(layer "F.Cu")
		(net "L1_85OHM_5INCH_DN")
	)
	(segment
		(start 20.780502 -163.93922)
		(end 21.164296 -166.116508)
		(width 0.1143)
		(layer "F.Cu")
		(net "L1_85OHM_5INCH_DN")
	)
	(segment
		(start 41.734232 -163.848542)
		(end 41.602152 -163.756086)
		(width 0.1143)
		(layer "F.Cu")
		(net "L1_85OHM_5INCH_DN")
	)
	(segment
		(start 20.873212 -163.806378)
		(end 20.780502 -163.93922)
		(width 0.1143)
		(layer "F.Cu")
		(net "L1_85OHM_5INCH_DN")
	)
	(segment
		(start 18.318734 -165.80612)
		(end 17.87144 -165.255956)
		(width 0.1143)
		(layer "F.Cu")
		(net "L1_85OHM_5INCH_DN")
	)
	(segment
		(start 26.461212 -163.858702)
		(end 26.32837 -163.765992)
		(width 0.1143)
		(layer "F.Cu")
		(net "L1_85OHM_5INCH_DN")
	)
	(segment
		(start 33.48101 -165.170104)
		(end 33.250124 -163.862004)
		(width 0.1143)
		(layer "F.Cu")
		(net "L1_85OHM_5INCH_DN")
	)
	(segment
		(start 26.048462 -166.415212)
		(end 25.491186 -166.513002)
		(width 0.1143)
		(layer "F.Cu")
		(net "L1_85OHM_5INCH_DN")
	)
	(segment
		(start 19.536918 -163.746688)
		(end 19.176492 -163.809934)
		(width 0.1143)
		(layer "F.Cu")
		(net "L1_85OHM_5INCH_DN")
	)
	(segment
		(start 27.191208 -166.529766)
		(end 26.895298 -166.322756)
		(width 0.1143)
		(layer "F.Cu")
		(net "L1_85OHM_5INCH_DN")
	)
	(segment
		(start 24.559006 -166.120318)
		(end 24.351742 -166.416482)
		(width 0.1143)
		(layer "F.Cu")
		(net "L1_85OHM_5INCH_DN")
	)
	(segment
		(start 43.225466 -166.104824)
		(end 43.018456 -166.40175)
		(width 0.1143)
		(layer "F.Cu")
		(net "L1_85OHM_5INCH_DN")
	)
	(segment
		(start 36.507674 -163.737544)
		(end 36.14674 -163.801044)
		(width 0.1143)
		(layer "F.Cu")
		(net "L1_85OHM_5INCH_DN")
	)
	(segment
		(start 44.716446 -166.40683)
		(end 44.158662 -166.504366)
		(width 0.1143)
		(layer "F.Cu")
		(net "L1_85OHM_5INCH_DN")
	)
	(segment
		(start 28.159202 -163.864036)
		(end 28.02636 -163.771072)
		(width 0.1143)
		(layer "F.Cu")
		(net "L1_85OHM_5INCH_DN")
	)
	(segment
		(start 50.502058 -165.207442)
		(end 49.148492 -164.980874)
		(width 0.1143)
		(layer "F.Cu")
		(net "L1_85OHM_5INCH_DN")
	)
	(segment
		(start 30.967172 -163.961318)
		(end 31.350204 -166.137082)
		(width 0.1143)
		(layer "F.Cu")
		(net "L1_85OHM_5INCH_DN")
	)
	(segment
		(start 27.666188 -163.834318)
		(end 27.573478 -163.966652)
		(width 0.1143)
		(layer "F.Cu")
		(net "L1_85OHM_5INCH_DN")
	)
	(segment
		(start 34.739834 -166.105078)
		(end 34.532824 -166.402004)
		(width 0.1143)
		(layer "F.Cu")
		(net "L1_85OHM_5INCH_DN")
	)
	(segment
		(start 24.271986 -163.83254)
		(end 24.179276 -163.965382)
		(width 0.1143)
		(layer "F.Cu")
		(net "L1_85OHM_5INCH_DN")
	)
	(segment
		(start 47.556166 -166.522146)
		(end 47.259494 -166.314628)
		(width 0.1143)
		(layer "F.Cu")
		(net "L1_85OHM_5INCH_DN")
	)
	(segment
		(start 29.270198 -163.96081)
		(end 29.65323 -166.133526)
		(width 0.1143)
		(layer "F.Cu")
		(net "L1_85OHM_5INCH_DN")
	)
	(segment
		(start 33.975802 -166.499794)
		(end 33.67913 -166.292276)
		(width 0.1143)
		(layer "F.Cu")
		(net "L1_85OHM_5INCH_DN")
	)
	(segment
		(start 25.968198 -163.829238)
		(end 25.875488 -163.961572)
		(width 0.1143)
		(layer "F.Cu")
		(net "L1_85OHM_5INCH_DN")
	)
	(segment
		(start 46.41723 -166.427912)
		(end 45.859954 -166.525702)
		(width 0.1143)
		(layer "F.Cu")
		(net "L1_85OHM_5INCH_DN")
	)
	(segment
		(start 21.164296 -166.116508)
		(end 20.957032 -166.412672)
		(width 0.1143)
		(layer "F.Cu")
		(net "L1_85OHM_5INCH_DN")
	)
	(segment
		(start 40.468042 -166.295832)
		(end 40.033956 -163.831524)
		(width 0.1143)
		(layer "F.Cu")
		(net "L1_85OHM_5INCH_DN")
	)
	(segment
		(start 32.838898 -166.425118)
		(end 32.281368 -166.522908)
		(width 0.1143)
		(layer "F.Cu")
		(net "L1_85OHM_5INCH_DN")
	)
	(segment
		(start 32.757618 -163.832286)
		(end 32.664908 -163.965128)
		(width 0.1143)
		(layer "F.Cu")
		(net "L1_85OHM_5INCH_DN")
	)
	(segment
		(start 19.264122 -166.436548)
		(end 18.706846 -166.534592)
		(width 0.1143)
		(layer "F.Cu")
		(net "L1_85OHM_5INCH_DN")
	)
	(segment
		(start 37.92728 -166.405814)
		(end 37.370512 -166.503604)
		(width 0.1143)
		(layer "F.Cu")
		(net "L1_85OHM_5INCH_DN")
	)
	(segment
		(start 21.80082 -166.304214)
		(end 21.365972 -163.836096)
		(width 0.1143)
		(layer "F.Cu")
		(net "L1_85OHM_5INCH_DN")
	)
	(segment
		(start 43.430698 -163.847018)
		(end 43.298618 -163.754308)
		(width 0.1143)
		(layer "F.Cu")
		(net "L1_85OHM_5INCH_DN")
	)
	(segment
		(start 34.811716 -163.745926)
		(end 34.451036 -163.809172)
		(width 0.1143)
		(layer "F.Cu")
		(net "L1_85OHM_5INCH_DN")
	)
	(segment
		(start 15.031466 -165.133274)
		(end 14.651736 -165.520116)
		(width 0.1143)
		(layer "F.Cu")
		(net "L1_85OHM_5INCH_DN")
	)
	(segment
		(start 32.664908 -163.965128)
		(end 33.046416 -166.1287)
		(width 0.1143)
		(layer "F.Cu")
		(net "L1_85OHM_5INCH_DN")
	)
	(segment
		(start 22.861524 -166.117524)
		(end 22.65426 -166.41318)
		(width 0.1143)
		(layer "F.Cu")
		(net "L1_85OHM_5INCH_DN")
	)
	(segment
		(start 27.573478 -163.966652)
		(end 27.955748 -166.136066)
		(width 0.1143)
		(layer "F.Cu")
		(net "L1_85OHM_5INCH_DN")
	)
	(segment
		(start 39.623746 -166.399972)
		(end 39.066724 -166.497762)
		(width 0.1143)
		(layer "F.Cu")
		(net "L1_85OHM_5INCH_DN")
	)
	(segment
		(start 27.748484 -166.431976)
		(end 27.191208 -166.529766)
		(width 0.1143)
		(layer "F.Cu")
		(net "L1_85OHM_5INCH_DN")
	)
	(segment
		(start 15.55242 -165.133274)
		(end 15.031466 -165.133274)
		(width 0.1143)
		(layer "F.Cu")
		(net "L1_85OHM_5INCH_DN")
	)
	(segment
		(start 36.639754 -163.83)
		(end 36.507674 -163.737544)
		(width 0.1143)
		(layer "F.Cu")
		(net "L1_85OHM_5INCH_DN")
	)
	(segment
		(start 30.58541 -166.53129)
		(end 30.2895 -166.32428)
		(width 0.1143)
		(layer "F.Cu")
		(net "L1_85OHM_5INCH_DN")
	)
	(segment
		(start 16.637 -165.049454)
		(end 15.55242 -165.133274)
		(width 0.1143)
		(layer "F.Cu")
		(net "L1_85OHM_5INCH_DN")
	)
	(segment
		(start 40.764968 -166.502842)
		(end 40.468042 -166.295832)
		(width 0.1143)
		(layer "F.Cu")
		(net "L1_85OHM_5INCH_DN")
	)
	(segment
		(start 37.751766 -163.937188)
		(end 38.134544 -166.109396)
		(width 0.1143)
		(layer "F.Cu")
		(net "L1_85OHM_5INCH_DN")
	)
	(segment
		(start 31.143702 -166.433246)
		(end 30.58541 -166.53129)
		(width 0.1143)
		(layer "F.Cu")
		(net "L1_85OHM_5INCH_DN")
	)
	(segment
		(start 22.934422 -163.764468)
		(end 22.573742 -163.82746)
		(width 0.1143)
		(layer "F.Cu")
		(net "L1_85OHM_5INCH_DN")
	)
	(segment
		(start 43.86199 -166.297356)
		(end 43.430698 -163.847018)
		(width 0.1143)
		(layer "F.Cu")
		(net "L1_85OHM_5INCH_DN")
	)
	(segment
		(start 206.530194 -165.96741)
		(end 206.437484 -166.099744)
		(width 0.1143)
		(layer "F.Cu")
		(net "L1_85OHM_10INCH_DP")
	)
	(segment
		(start 213.146386 -163.494974)
		(end 212.93582 -163.79444)
		(width 0.1143)
		(layer "F.Cu")
		(net "L1_85OHM_10INCH_DP")
	)
	(segment
		(start 187.76823 -166.090854)
		(end 187.40755 -166.153846)
		(width 0.1143)
		(layer "F.Cu")
		(net "L1_85OHM_10INCH_DP")
	)
	(segment
		(start 182.768494 -165.951662)
		(end 182.675784 -166.083996)
		(width 0.1143)
		(layer "F.Cu")
		(net "L1_85OHM_10INCH_DP")
	)
	(segment
		(start 206.908146 -163.379658)
		(end 206.35087 -163.477448)
		(width 0.1143)
		(layer "F.Cu")
		(net "L1_85OHM_10INCH_DP")
	)
	(segment
		(start 212.733382 -166.069772)
		(end 212.29955 -163.603686)
		(width 0.1143)
		(layer "F.Cu")
		(net "L1_85OHM_10INCH_DP")
	)
	(segment
		(start 187.40755 -166.153846)
		(end 187.274708 -166.061136)
		(width 0.1143)
		(layer "F.Cu")
		(net "L1_85OHM_10INCH_DP")
	)
	(segment
		(start 183.446674 -163.595558)
		(end 183.150764 -163.388548)
		(width 0.1143)
		(layer "F.Cu")
		(net "L1_85OHM_10INCH_DP")
	)
	(segment
		(start 196.252338 -166.087298)
		(end 195.892166 -166.150798)
		(width 0.1143)
		(layer "F.Cu")
		(net "L1_85OHM_10INCH_DP")
	)
	(segment
		(start 193.627502 -163.586922)
		(end 193.33083 -163.379404)
		(width 0.1143)
		(layer "F.Cu")
		(net "L1_85OHM_10INCH_DP")
	)
	(segment
		(start 214.922862 -166.093648)
		(end 214.56269 -166.156894)
		(width 0.1143)
		(layer "F.Cu")
		(net "L1_85OHM_10INCH_DP")
	)
	(segment
		(start 164.098478 -165.94836)
		(end 164.006022 -166.080694)
		(width 0.1143)
		(layer "F.Cu")
		(net "L1_85OHM_10INCH_DP")
	)
	(segment
		(start 215.015572 -165.961314)
		(end 214.922862 -166.093648)
		(width 0.1143)
		(layer "F.Cu")
		(net "L1_85OHM_10INCH_DP")
	)
	(segment
		(start 187.274708 -166.061136)
		(end 186.843416 -163.611052)
		(width 0.1143)
		(layer "F.Cu")
		(net "L1_85OHM_10INCH_DP")
	)
	(segment
		(start 173.265592 -163.606226)
		(end 172.968666 -163.398708)
		(width 0.1143)
		(layer "F.Cu")
		(net "L1_85OHM_10INCH_DP")
	)
	(segment
		(start 208.608168 -163.396422)
		(end 208.050892 -163.494212)
		(width 0.1143)
		(layer "F.Cu")
		(net "L1_85OHM_10INCH_DP")
	)
	(segment
		(start 182.593488 -163.486338)
		(end 182.386224 -163.782248)
		(width 0.1143)
		(layer "F.Cu")
		(net "L1_85OHM_10INCH_DP")
	)
	(segment
		(start 225.95205 -164.878512)
		(end 224.71761 -164.67201)
		(width 0.1143)
		(layer "F.Cu")
		(net "L1_85OHM_10INCH_DP")
	)
	(segment
		(start 211.169504 -166.161974)
		(end 211.036408 -166.06901)
		(width 0.1143)
		(layer "F.Cu")
		(net "L1_85OHM_10INCH_DP")
	)
	(segment
		(start 227.557584 -164.794692)
		(end 227.03663 -164.794692)
		(width 0.1143)
		(layer "F.Cu")
		(net "L1_85OHM_10INCH_DP")
	)
	(segment
		(start 187.480448 -163.80079)
		(end 187.860686 -165.95852)
		(width 0.1143)
		(layer "F.Cu")
		(net "L1_85OHM_10INCH_DP")
	)
	(segment
		(start 219.521786 -166.070788)
		(end 219.090494 -163.620704)
		(width 0.1143)
		(layer "F.Cu")
		(net "L1_85OHM_10INCH_DP")
	)
	(segment
		(start 192.497456 -166.146988)
		(end 192.365376 -166.054532)
		(width 0.1143)
		(layer "F.Cu")
		(net "L1_85OHM_10INCH_DP")
	)
	(segment
		(start 205.208124 -163.37915)
		(end 204.65669 -163.476432)
		(width 0.1143)
		(layer "F.Cu")
		(net "L1_85OHM_10INCH_DP")
	)
	(segment
		(start 199.355202 -163.77666)
		(end 199.74179 -165.970712)
		(width 0.1143)
		(layer "F.Cu")
		(net "L1_85OHM_10INCH_DP")
	)
	(segment
		(start 168.809924 -163.793424)
		(end 169.190162 -165.951154)
		(width 0.1143)
		(layer "F.Cu")
		(net "L1_85OHM_10INCH_DP")
	)
	(segment
		(start 195.760086 -166.058088)
		(end 195.328794 -163.60775)
		(width 0.1143)
		(layer "F.Cu")
		(net "L1_85OHM_10INCH_DP")
	)
	(segment
		(start 173.699424 -166.072312)
		(end 173.265592 -163.606226)
		(width 0.1143)
		(layer "F.Cu")
		(net "L1_85OHM_10INCH_DP")
	)
	(segment
		(start 161.735008 -165.590982)
		(end 161.190686 -164.921438)
		(width 0.1143)
		(layer "F.Cu")
		(net "L1_85OHM_10INCH_DP")
	)
	(segment
		(start 211.036408 -166.06901)
		(end 210.603592 -163.612068)
		(width 0.1143)
		(layer "F.Cu")
		(net "L1_85OHM_10INCH_DP")
	)
	(segment
		(start 203.04379 -166.105078)
		(end 202.684126 -166.16807)
		(width 0.1143)
		(layer "F.Cu")
		(net "L1_85OHM_10INCH_DP")
	)
	(segment
		(start 212.93582 -163.79444)
		(end 213.318852 -165.967156)
		(width 0.1143)
		(layer "F.Cu")
		(net "L1_85OHM_10INCH_DP")
	)
	(segment
		(start 176.660048 -163.610036)
		(end 176.363376 -163.402518)
		(width 0.1143)
		(layer "F.Cu")
		(net "L1_85OHM_10INCH_DP")
	)
	(segment
		(start 222.189294 -163.416996)
		(end 221.632018 -163.515294)
		(width 0.1143)
		(layer "F.Cu")
		(net "L1_85OHM_10INCH_DP")
	)
	(segment
		(start 210.307682 -163.405058)
		(end 209.750152 -163.502848)
		(width 0.1143)
		(layer "F.Cu")
		(net "L1_85OHM_10INCH_DP")
	)
	(segment
		(start 184.850786 -163.405312)
		(end 184.29351 -163.503102)
		(width 0.1143)
		(layer "F.Cu")
		(net "L1_85OHM_10INCH_DP")
	)
	(segment
		(start 163.51377 -166.051738)
		(end 163.079684 -163.587684)
		(width 0.1143)
		(layer "F.Cu")
		(net "L1_85OHM_10INCH_DP")
	)
	(segment
		(start 207.204056 -163.586668)
		(end 206.908146 -163.379658)
		(width 0.1143)
		(layer "F.Cu")
		(net "L1_85OHM_10INCH_DP")
	)
	(segment
		(start 208.904332 -163.603686)
		(end 208.608168 -163.396422)
		(width 0.1143)
		(layer "F.Cu")
		(net "L1_85OHM_10INCH_DP")
	)
	(segment
		(start 192.857628 -166.083488)
		(end 192.497456 -166.146988)
		(width 0.1143)
		(layer "F.Cu")
		(net "L1_85OHM_10INCH_DP")
	)
	(segment
		(start 218.409774 -165.962584)
		(end 218.317064 -166.095426)
		(width 0.1143)
		(layer "F.Cu")
		(net "L1_85OHM_10INCH_DP")
	)
	(segment
		(start 170.797728 -166.099998)
		(end 170.437048 -166.16299)
		(width 0.1143)
		(layer "F.Cu")
		(net "L1_85OHM_10INCH_DP")
	)
	(segment
		(start 197.588632 -166.14902)
		(end 197.456552 -166.056564)
		(width 0.1143)
		(layer "F.Cu")
		(net "L1_85OHM_10INCH_DP")
	)
	(segment
		(start 163.079684 -163.587684)
		(end 162.783012 -163.380166)
		(width 0.1143)
		(layer "F.Cu")
		(net "L1_85OHM_10INCH_DP")
	)
	(segment
		(start 200.416414 -163.590224)
		(end 200.119742 -163.382706)
		(width 0.1143)
		(layer "F.Cu")
		(net "L1_85OHM_10INCH_DP")
	)
	(segment
		(start 211.529168 -166.098982)
		(end 211.169504 -166.161974)
		(width 0.1143)
		(layer "F.Cu")
		(net "L1_85OHM_10INCH_DP")
	)
	(segment
		(start 196.726048 -163.385246)
		(end 196.168772 -163.483036)
		(width 0.1143)
		(layer "F.Cu")
		(net "L1_85OHM_10INCH_DP")
	)
	(segment
		(start 162.313112 -166.10457)
		(end 161.952686 -166.16807)
		(width 0.1143)
		(layer "F.Cu")
		(net "L1_85OHM_10INCH_DP")
	)
	(segment
		(start 159.83712 -164.69487)
		(end 158.732474 -164.780468)
		(width 0.1143)
		(layer "F.Cu")
		(net "L1_85OHM_10INCH_DP")
	)
	(segment
		(start 167.320722 -163.500562)
		(end 167.113712 -163.797488)
		(width 0.1143)
		(layer "F.Cu")
		(net "L1_85OHM_10INCH_DP")
	)
	(segment
		(start 212.866224 -166.162736)
		(end 212.733382 -166.069772)
		(width 0.1143)
		(layer "F.Cu")
		(net "L1_85OHM_10INCH_DP")
	)
	(segment
		(start 170.715432 -163.50234)
		(end 170.507914 -163.798504)
		(width 0.1143)
		(layer "F.Cu")
		(net "L1_85OHM_10INCH_DP")
	)
	(segment
		(start 214.840566 -163.49599)
		(end 214.633302 -163.7919)
		(width 0.1143)
		(layer "F.Cu")
		(net "L1_85OHM_10INCH_DP")
	)
	(segment
		(start 189.56147 -165.979094)
		(end 189.46876 -166.111936)
		(width 0.1143)
		(layer "F.Cu")
		(net "L1_85OHM_10INCH_DP")
	)
	(segment
		(start 161.952686 -166.16807)
		(end 161.820606 -166.075868)
		(width 0.1143)
		(layer "F.Cu")
		(net "L1_85OHM_10INCH_DP")
	)
	(segment
		(start 168.737026 -166.146226)
		(end 168.604946 -166.05377)
		(width 0.1143)
		(layer "F.Cu")
		(net "L1_85OHM_10INCH_DP")
	)
	(segment
		(start 182.675784 -166.083996)
		(end 182.315612 -166.147242)
		(width 0.1143)
		(layer "F.Cu")
		(net "L1_85OHM_10INCH_DP")
	)
	(segment
		(start 172.411898 -163.496498)
		(end 172.204634 -163.792916)
		(width 0.1143)
		(layer "F.Cu")
		(net "L1_85OHM_10INCH_DP")
	)
	(segment
		(start 211.238846 -163.790884)
		(end 211.621878 -165.966648)
		(width 0.1143)
		(layer "F.Cu")
		(net "L1_85OHM_10INCH_DP")
	)
	(segment
		(start 217.957146 -166.158672)
		(end 217.824304 -166.065708)
		(width 0.1143)
		(layer "F.Cu")
		(net "L1_85OHM_10INCH_DP")
	)
	(segment
		(start 189.177676 -163.801806)
		(end 189.56147 -165.979094)
		(width 0.1143)
		(layer "F.Cu")
		(net "L1_85OHM_10INCH_DP")
	)
	(segment
		(start 195.032122 -163.40074)
		(end 194.474338 -163.498276)
		(width 0.1143)
		(layer "F.Cu")
		(net "L1_85OHM_10INCH_DP")
	)
	(segment
		(start 224.270316 -164.121846)
		(end 224.178368 -163.599876)
		(width 0.1143)
		(layer "F.Cu")
		(net "L1_85OHM_10INCH_DP")
	)
	(segment
		(start 212.29955 -163.603686)
		(end 212.00364 -163.396676)
		(width 0.1143)
		(layer "F.Cu")
		(net "L1_85OHM_10INCH_DP")
	)
	(segment
		(start 161.190686 -164.921438)
		(end 159.83712 -164.69487)
		(width 0.1143)
		(layer "F.Cu")
		(net "L1_85OHM_10INCH_DP")
	)
	(segment
		(start 201.816716 -163.381182)
		(end 201.259948 -163.478972)
		(width 0.1143)
		(layer "F.Cu")
		(net "L1_85OHM_10INCH_DP")
	)
	(segment
		(start 224.178368 -163.599876)
		(end 223.882204 -163.393374)
		(width 0.1143)
		(layer "F.Cu")
		(net "L1_85OHM_10INCH_DP")
	)
	(segment
		(start 186.843416 -163.611052)
		(end 186.547506 -163.403788)
		(width 0.1143)
		(layer "F.Cu")
		(net "L1_85OHM_10INCH_DP")
	)
	(segment
		(start 172.968666 -163.398708)
		(end 172.411898 -163.496498)
		(width 0.1143)
		(layer "F.Cu")
		(net "L1_85OHM_10INCH_DP")
	)
	(segment
		(start 168.604946 -166.05377)
		(end 168.17467 -163.61029)
		(width 0.1143)
		(layer "F.Cu")
		(net "L1_85OHM_10INCH_DP")
	)
	(segment
		(start 190.238126 -163.614608)
		(end 189.942216 -163.407344)
		(width 0.1143)
		(layer "F.Cu")
		(net "L1_85OHM_10INCH_DP")
	)
	(segment
		(start 194.647566 -165.95217)
		(end 194.554856 -166.083996)
		(width 0.1143)
		(layer "F.Cu")
		(net "L1_85OHM_10INCH_DP")
	)
	(segment
		(start 165.342824 -166.144702)
		(end 165.210744 -166.052246)
		(width 0.1143)
		(layer "F.Cu")
		(net "L1_85OHM_10INCH_DP")
	)
	(segment
		(start 221.715838 -166.121588)
		(end 221.35592 -166.184834)
		(width 0.1143)
		(layer "F.Cu")
		(net "L1_85OHM_10INCH_DP")
	)
	(segment
		(start 212.00364 -163.396676)
		(end 211.445348 -163.49472)
		(width 0.1143)
		(layer "F.Cu")
		(net "L1_85OHM_10INCH_DP")
	)
	(segment
		(start 213.997032 -163.607242)
		(end 213.69782 -163.397692)
		(width 0.1143)
		(layer "F.Cu")
		(net "L1_85OHM_10INCH_DP")
	)
	(segment
		(start 189.46876 -166.111936)
		(end 189.108842 -166.175182)
		(width 0.1143)
		(layer "F.Cu")
		(net "L1_85OHM_10INCH_DP")
	)
	(segment
		(start 191.635126 -163.383722)
		(end 191.07785 -163.481766)
		(width 0.1143)
		(layer "F.Cu")
		(net "L1_85OHM_10INCH_DP")
	)
	(segment
		(start 178.78933 -166.059358)
		(end 178.356514 -163.602416)
		(width 0.1143)
		(layer "F.Cu")
		(net "L1_85OHM_10INCH_DP")
	)
	(segment
		(start 174.192438 -166.101268)
		(end 173.831504 -166.164768)
		(width 0.1143)
		(layer "F.Cu")
		(net "L1_85OHM_10INCH_DP")
	)
	(segment
		(start 216.26068 -166.161974)
		(end 216.127838 -166.069264)
		(width 0.1143)
		(layer "F.Cu")
		(net "L1_85OHM_10INCH_DP")
	)
	(segment
		(start 215.397842 -163.3982)
		(end 214.840566 -163.49599)
		(width 0.1143)
		(layer "F.Cu")
		(net "L1_85OHM_10INCH_DP")
	)
	(segment
		(start 223.117664 -163.787328)
		(end 223.505268 -165.985698)
		(width 0.1143)
		(layer "F.Cu")
		(net "L1_85OHM_10INCH_DP")
	)
	(segment
		(start 208.135474 -166.104824)
		(end 207.775302 -166.16807)
		(width 0.1143)
		(layer "F.Cu")
		(net "L1_85OHM_10INCH_DP")
	)
	(segment
		(start 209.750152 -163.502848)
		(end 209.542634 -163.799266)
		(width 0.1143)
		(layer "F.Cu")
		(net "L1_85OHM_10INCH_DP")
	)
	(segment
		(start 180.052472 -163.594034)
		(end 179.756562 -163.387024)
		(width 0.1143)
		(layer "F.Cu")
		(net "L1_85OHM_10INCH_DP")
	)
	(segment
		(start 220.492066 -163.416488)
		(end 219.93479 -163.514786)
		(width 0.1143)
		(layer "F.Cu")
		(net "L1_85OHM_10INCH_DP")
	)
	(segment
		(start 177.584354 -166.086028)
		(end 177.22469 -166.149274)
		(width 0.1143)
		(layer "F.Cu")
		(net "L1_85OHM_10INCH_DP")
	)
	(segment
		(start 207.843628 -163.790122)
		(end 208.228184 -165.97249)
		(width 0.1143)
		(layer "F.Cu")
		(net "L1_85OHM_10INCH_DP")
	)
	(segment
		(start 214.429848 -166.06393)
		(end 213.997032 -163.607242)
		(width 0.1143)
		(layer "F.Cu")
		(net "L1_85OHM_10INCH_DP")
	)
	(segment
		(start 184.013602 -166.152322)
		(end 183.88076 -166.059612)
		(width 0.1143)
		(layer "F.Cu")
		(net "L1_85OHM_10INCH_DP")
	)
	(segment
		(start 169.57421 -163.39947)
		(end 169.017442 -163.49726)
		(width 0.1143)
		(layer "F.Cu")
		(net "L1_85OHM_10INCH_DP")
	)
	(segment
		(start 162.405822 -165.97249)
		(end 162.313112 -166.10457)
		(width 0.1143)
		(layer "F.Cu")
		(net "L1_85OHM_10INCH_DP")
	)
	(segment
		(start 158.220918 -164.780468)
		(end 157.841188 -164.40785)
		(width 0.1143)
		(layer "F.Cu")
		(net "L1_85OHM_10INCH_DP")
	)
	(segment
		(start 175.888142 -166.09314)
		(end 175.527462 -166.156386)
		(width 0.1143)
		(layer "F.Cu")
		(net "L1_85OHM_10INCH_DP")
	)
	(segment
		(start 181.450742 -163.38804)
		(end 180.899308 -163.485322)
		(width 0.1143)
		(layer "F.Cu")
		(net "L1_85OHM_10INCH_DP")
	)
	(segment
		(start 188.244988 -163.406836)
		(end 187.687712 -163.505134)
		(width 0.1143)
		(layer "F.Cu")
		(net "L1_85OHM_10INCH_DP")
	)
	(segment
		(start 164.006022 -166.080694)
		(end 163.64585 -166.144194)
		(width 0.1143)
		(layer "F.Cu")
		(net "L1_85OHM_10INCH_DP")
	)
	(segment
		(start 197.657212 -163.77158)
		(end 198.041768 -165.953948)
		(width 0.1143)
		(layer "F.Cu")
		(net "L1_85OHM_10INCH_DP")
	)
	(segment
		(start 227.03663 -164.794692)
		(end 225.95205 -164.878512)
		(width 0.1143)
		(layer "F.Cu")
		(net "L1_85OHM_10INCH_DP")
	)
	(segment
		(start 227.937314 -164.40785)
		(end 227.557584 -164.794692)
		(width 0.1143)
		(layer "F.Cu")
		(net "L1_85OHM_10INCH_DP")
	)
	(segment
		(start 196.168772 -163.483036)
		(end 195.961762 -163.779962)
		(width 0.1143)
		(layer "F.Cu")
		(net "L1_85OHM_10INCH_DP")
	)
	(segment
		(start 194.19443 -166.147496)
		(end 194.06235 -166.05504)
		(width 0.1143)
		(layer "F.Cu")
		(net "L1_85OHM_10INCH_DP")
	)
	(segment
		(start 202.684126 -166.16807)
		(end 202.55103 -166.075106)
		(width 0.1143)
		(layer "F.Cu")
		(net "L1_85OHM_10INCH_DP")
	)
	(segment
		(start 165.79596 -165.949376)
		(end 165.70325 -166.081202)
		(width 0.1143)
		(layer "F.Cu")
		(net "L1_85OHM_10INCH_DP")
	)
	(segment
		(start 221.632018 -163.515294)
		(end 221.424754 -163.811458)
		(width 0.1143)
		(layer "F.Cu")
		(net "L1_85OHM_10INCH_DP")
	)
	(segment
		(start 202.113642 -163.5887)
		(end 201.816716 -163.381182)
		(width 0.1143)
		(layer "F.Cu")
		(net "L1_85OHM_10INCH_DP")
	)
	(segment
		(start 202.55103 -166.075106)
		(end 202.113642 -163.5887)
		(width 0.1143)
		(layer "F.Cu")
		(net "L1_85OHM_10INCH_DP")
	)
	(segment
		(start 200.119742 -163.382706)
		(end 199.56272 -163.480496)
		(width 0.1143)
		(layer "F.Cu")
		(net "L1_85OHM_10INCH_DP")
	)
	(segment
		(start 177.22469 -166.149274)
		(end 177.091848 -166.05631)
		(width 0.1143)
		(layer "F.Cu")
		(net "L1_85OHM_10INCH_DP")
	)
	(segment
		(start 215.693752 -163.60521)
		(end 215.397842 -163.3982)
		(width 0.1143)
		(layer "F.Cu")
		(net "L1_85OHM_10INCH_DP")
	)
	(segment
		(start 186.069986 -166.085774)
		(end 185.710068 -166.14902)
		(width 0.1143)
		(layer "F.Cu")
		(net "L1_85OHM_10INCH_DP")
	)
	(segment
		(start 223.882204 -163.393374)
		(end 223.324928 -163.491418)
		(width 0.1143)
		(layer "F.Cu")
		(net "L1_85OHM_10INCH_DP")
	)
	(segment
		(start 204.833474 -165.973252)
		(end 204.740764 -166.105586)
		(width 0.1143)
		(layer "F.Cu")
		(net "L1_85OHM_10INCH_DP")
	)
	(segment
		(start 221.808548 -165.988746)
		(end 221.715838 -166.121588)
		(width 0.1143)
		(layer "F.Cu")
		(net "L1_85OHM_10INCH_DP")
	)
	(segment
		(start 193.33083 -163.379404)
		(end 192.773554 -163.477194)
		(width 0.1143)
		(layer "F.Cu")
		(net "L1_85OHM_10INCH_DP")
	)
	(segment
		(start 213.318852 -165.967156)
		(end 213.226142 -166.09949)
		(width 0.1143)
		(layer "F.Cu")
		(net "L1_85OHM_10INCH_DP")
	)
	(segment
		(start 165.415722 -163.7919)
		(end 165.79596 -165.949376)
		(width 0.1143)
		(layer "F.Cu")
		(net "L1_85OHM_10INCH_DP")
	)
	(segment
		(start 170.890184 -165.967918)
		(end 170.797728 -166.099998)
		(width 0.1143)
		(layer "F.Cu")
		(net "L1_85OHM_10INCH_DP")
	)
	(segment
		(start 217.394028 -163.622228)
		(end 217.097864 -163.414964)
		(width 0.1143)
		(layer "F.Cu")
		(net "L1_85OHM_10INCH_DP")
	)
	(segment
		(start 180.688742 -163.784788)
		(end 181.071774 -165.957504)
		(width 0.1143)
		(layer "F.Cu")
		(net "L1_85OHM_10INCH_DP")
	)
	(segment
		(start 222.91929 -166.088314)
		(end 222.485204 -163.62426)
		(width 0.1143)
		(layer "F.Cu")
		(net "L1_85OHM_10INCH_DP")
	)
	(segment
		(start 168.17467 -163.61029)
		(end 167.877998 -163.402772)
		(width 0.1143)
		(layer "F.Cu")
		(net "L1_85OHM_10INCH_DP")
	)
	(segment
		(start 199.74179 -165.970712)
		(end 199.649334 -166.102792)
		(width 0.1143)
		(layer "F.Cu")
		(net "L1_85OHM_10INCH_DP")
	)
	(segment
		(start 197.02272 -163.592764)
		(end 196.726048 -163.385246)
		(width 0.1143)
		(layer "F.Cu")
		(net "L1_85OHM_10INCH_DP")
	)
	(segment
		(start 199.156828 -166.073582)
		(end 198.718424 -163.584636)
		(width 0.1143)
		(layer "F.Cu")
		(net "L1_85OHM_10INCH_DP")
	)
	(segment
		(start 169.097706 -166.083234)
		(end 168.737026 -166.146226)
		(width 0.1143)
		(layer "F.Cu")
		(net "L1_85OHM_10INCH_DP")
	)
	(segment
		(start 200.98893 -166.166292)
		(end 200.853548 -166.07155)
		(width 0.1143)
		(layer "F.Cu")
		(net "L1_85OHM_10INCH_DP")
	)
	(segment
		(start 182.315612 -166.147242)
		(end 182.18277 -166.054278)
		(width 0.1143)
		(layer "F.Cu")
		(net "L1_85OHM_10INCH_DP")
	)
	(segment
		(start 179.28209 -166.08933)
		(end 178.922426 -166.152322)
		(width 0.1143)
		(layer "F.Cu")
		(net "L1_85OHM_10INCH_DP")
	)
	(segment
		(start 198.041768 -165.953948)
		(end 197.949312 -166.086028)
		(width 0.1143)
		(layer "F.Cu")
		(net "L1_85OHM_10INCH_DP")
	)
	(segment
		(start 218.030044 -163.807648)
		(end 218.409774 -165.962584)
		(width 0.1143)
		(layer "F.Cu")
		(net "L1_85OHM_10INCH_DP")
	)
	(segment
		(start 191.16548 -166.10838)
		(end 190.805054 -166.171626)
		(width 0.1143)
		(layer "F.Cu")
		(net "L1_85OHM_10INCH_DP")
	)
	(segment
		(start 173.831504 -166.164768)
		(end 173.699424 -166.072312)
		(width 0.1143)
		(layer "F.Cu")
		(net "L1_85OHM_10INCH_DP")
	)
	(segment
		(start 187.860686 -165.95852)
		(end 187.76823 -166.090854)
		(width 0.1143)
		(layer "F.Cu")
		(net "L1_85OHM_10INCH_DP")
	)
	(segment
		(start 220.107764 -165.968172)
		(end 220.015308 -166.100506)
		(width 0.1143)
		(layer "F.Cu")
		(net "L1_85OHM_10INCH_DP")
	)
	(segment
		(start 172.137324 -166.163498)
		(end 172.001942 -166.068756)
		(width 0.1143)
		(layer "F.Cu")
		(net "L1_85OHM_10INCH_DP")
	)
	(segment
		(start 185.782966 -163.797996)
		(end 186.162696 -165.952932)
		(width 0.1143)
		(layer "F.Cu")
		(net "L1_85OHM_10INCH_DP")
	)
	(segment
		(start 190.870586 -163.777676)
		(end 191.25819 -165.976046)
		(width 0.1143)
		(layer "F.Cu")
		(net "L1_85OHM_10INCH_DP")
	)
	(segment
		(start 202.753468 -163.79698)
		(end 203.1365 -165.972744)
		(width 0.1143)
		(layer "F.Cu")
		(net "L1_85OHM_10INCH_DP")
	)
	(segment
		(start 192.950084 -165.951154)
		(end 192.857628 -166.083488)
		(width 0.1143)
		(layer "F.Cu")
		(net "L1_85OHM_10INCH_DP")
	)
	(segment
		(start 165.210744 -166.052246)
		(end 164.775896 -163.584128)
		(width 0.1143)
		(layer "F.Cu")
		(net "L1_85OHM_10INCH_DP")
	)
	(segment
		(start 181.071774 -165.957504)
		(end 180.979064 -166.089838)
		(width 0.1143)
		(layer "F.Cu")
		(net "L1_85OHM_10INCH_DP")
	)
	(segment
		(start 158.732474 -164.780468)
		(end 158.220918 -164.780468)
		(width 0.1143)
		(layer "F.Cu")
		(net "L1_85OHM_10INCH_DP")
	)
	(segment
		(start 178.356514 -163.602416)
		(end 178.060604 -163.395406)
		(width 0.1143)
		(layer "F.Cu")
		(net "L1_85OHM_10INCH_DP")
	)
	(segment
		(start 213.226142 -166.09949)
		(end 212.866224 -166.162736)
		(width 0.1143)
		(layer "F.Cu")
		(net "L1_85OHM_10INCH_DP")
	)
	(segment
		(start 179.3748 -165.956996)
		(end 179.28209 -166.08933)
		(width 0.1143)
		(layer "F.Cu")
		(net "L1_85OHM_10INCH_DP")
	)
	(segment
		(start 194.554856 -166.083996)
		(end 194.19443 -166.147496)
		(width 0.1143)
		(layer "F.Cu")
		(net "L1_85OHM_10INCH_DP")
	)
	(segment
		(start 178.991768 -163.781232)
		(end 179.3748 -165.956996)
		(width 0.1143)
		(layer "F.Cu")
		(net "L1_85OHM_10INCH_DP")
	)
	(segment
		(start 203.518262 -163.402772)
		(end 202.95997 -163.500816)
		(width 0.1143)
		(layer "F.Cu")
		(net "L1_85OHM_10INCH_DP")
	)
	(segment
		(start 171.569126 -163.612068)
		(end 171.272454 -163.40455)
		(width 0.1143)
		(layer "F.Cu")
		(net "L1_85OHM_10INCH_DP")
	)
	(segment
		(start 208.228184 -165.97249)
		(end 208.135474 -166.104824)
		(width 0.1143)
		(layer "F.Cu")
		(net "L1_85OHM_10INCH_DP")
	)
	(segment
		(start 172.204634 -163.792916)
		(end 172.587412 -165.965124)
		(width 0.1143)
		(layer "F.Cu")
		(net "L1_85OHM_10INCH_DP")
	)
	(segment
		(start 175.980852 -165.960552)
		(end 175.888142 -166.09314)
		(width 0.1143)
		(layer "F.Cu")
		(net "L1_85OHM_10INCH_DP")
	)
	(segment
		(start 169.017442 -163.49726)
		(end 168.809924 -163.793424)
		(width 0.1143)
		(layer "F.Cu")
		(net "L1_85OHM_10INCH_DP")
	)
	(segment
		(start 201.052684 -163.77539)
		(end 201.439018 -165.967918)
		(width 0.1143)
		(layer "F.Cu")
		(net "L1_85OHM_10INCH_DP")
	)
	(segment
		(start 221.223078 -166.09187)
		(end 220.78823 -163.623752)
		(width 0.1143)
		(layer "F.Cu")
		(net "L1_85OHM_10INCH_DP")
	)
	(segment
		(start 195.961762 -163.779962)
		(end 196.344794 -165.954964)
		(width 0.1143)
		(layer "F.Cu")
		(net "L1_85OHM_10INCH_DP")
	)
	(segment
		(start 185.710068 -166.14902)
		(end 185.577226 -166.056056)
		(width 0.1143)
		(layer "F.Cu")
		(net "L1_85OHM_10INCH_DP")
	)
	(segment
		(start 223.412558 -166.118032)
		(end 223.052132 -166.181278)
		(width 0.1143)
		(layer "F.Cu")
		(net "L1_85OHM_10INCH_DP")
	)
	(segment
		(start 203.814172 -163.609782)
		(end 203.518262 -163.402772)
		(width 0.1143)
		(layer "F.Cu")
		(net "L1_85OHM_10INCH_DP")
	)
	(segment
		(start 197.949312 -166.086028)
		(end 197.588632 -166.14902)
		(width 0.1143)
		(layer "F.Cu")
		(net "L1_85OHM_10INCH_DP")
	)
	(segment
		(start 162.783012 -163.380166)
		(end 162.225736 -163.477956)
		(width 0.1143)
		(layer "F.Cu")
		(net "L1_85OHM_10INCH_DP")
	)
	(segment
		(start 162.018218 -163.77412)
		(end 162.405822 -165.97249)
		(width 0.1143)
		(layer "F.Cu")
		(net "L1_85OHM_10INCH_DP")
	)
	(segment
		(start 188.541152 -163.6141)
		(end 188.244988 -163.406836)
		(width 0.1143)
		(layer "F.Cu")
		(net "L1_85OHM_10INCH_DP")
	)
	(segment
		(start 214.633302 -163.7919)
		(end 215.015572 -165.961314)
		(width 0.1143)
		(layer "F.Cu")
		(net "L1_85OHM_10INCH_DP")
	)
	(segment
		(start 221.424754 -163.811458)
		(end 221.808548 -165.988746)
		(width 0.1143)
		(layer "F.Cu")
		(net "L1_85OHM_10INCH_DP")
	)
	(segment
		(start 220.015308 -166.100506)
		(end 219.654628 -166.163498)
		(width 0.1143)
		(layer "F.Cu")
		(net "L1_85OHM_10INCH_DP")
	)
	(segment
		(start 175.806354 -163.500308)
		(end 175.599344 -163.797234)
		(width 0.1143)
		(layer "F.Cu")
		(net "L1_85OHM_10INCH_DP")
	)
	(segment
		(start 174.109126 -163.497006)
		(end 173.901608 -163.79317)
		(width 0.1143)
		(layer "F.Cu")
		(net "L1_85OHM_10INCH_DP")
	)
	(segment
		(start 197.86473 -163.475416)
		(end 197.657212 -163.77158)
		(width 0.1143)
		(layer "F.Cu")
		(net "L1_85OHM_10INCH_DP")
	)
	(segment
		(start 167.04056 -166.148004)
		(end 166.90848 -166.055294)
		(width 0.1143)
		(layer "F.Cu")
		(net "L1_85OHM_10INCH_DP")
	)
	(segment
		(start 207.64246 -166.07536)
		(end 207.204056 -163.586668)
		(width 0.1143)
		(layer "F.Cu")
		(net "L1_85OHM_10INCH_DP")
	)
	(segment
		(start 162.225736 -163.477956)
		(end 162.018218 -163.77412)
		(width 0.1143)
		(layer "F.Cu")
		(net "L1_85OHM_10INCH_DP")
	)
	(segment
		(start 217.097864 -163.414964)
		(end 216.540588 -163.512754)
		(width 0.1143)
		(layer "F.Cu")
		(net "L1_85OHM_10INCH_DP")
	)
	(segment
		(start 177.091848 -166.05631)
		(end 176.660048 -163.610036)
		(width 0.1143)
		(layer "F.Cu")
		(net "L1_85OHM_10INCH_DP")
	)
	(segment
		(start 206.437484 -166.099744)
		(end 206.077312 -166.16299)
		(width 0.1143)
		(layer "F.Cu")
		(net "L1_85OHM_10INCH_DP")
	)
	(segment
		(start 204.740764 -166.105586)
		(end 204.380846 -166.168832)
		(width 0.1143)
		(layer "F.Cu")
		(net "L1_85OHM_10INCH_DP")
	)
	(segment
		(start 163.64585 -166.144194)
		(end 163.51377 -166.051738)
		(width 0.1143)
		(layer "F.Cu")
		(net "L1_85OHM_10INCH_DP")
	)
	(segment
		(start 207.775302 -166.16807)
		(end 207.64246 -166.07536)
		(width 0.1143)
		(layer "F.Cu")
		(net "L1_85OHM_10INCH_DP")
	)
	(segment
		(start 192.365376 -166.054532)
		(end 191.93129 -163.590478)
		(width 0.1143)
		(layer "F.Cu")
		(net "L1_85OHM_10INCH_DP")
	)
	(segment
		(start 169.190162 -165.951154)
		(end 169.097706 -166.083234)
		(width 0.1143)
		(layer "F.Cu")
		(net "L1_85OHM_10INCH_DP")
	)
	(segment
		(start 203.1365 -165.972744)
		(end 203.04379 -166.105078)
		(width 0.1143)
		(layer "F.Cu")
		(net "L1_85OHM_10INCH_DP")
	)
	(segment
		(start 172.587412 -165.965124)
		(end 172.491908 -166.101014)
		(width 0.1143)
		(layer "F.Cu")
		(net "L1_85OHM_10INCH_DP")
	)
	(segment
		(start 186.547506 -163.403788)
		(end 185.99023 -163.501832)
		(width 0.1143)
		(layer "F.Cu")
		(net "L1_85OHM_10INCH_DP")
	)
	(segment
		(start 214.56269 -166.156894)
		(end 214.429848 -166.06393)
		(width 0.1143)
		(layer "F.Cu")
		(net "L1_85OHM_10INCH_DP")
	)
	(segment
		(start 188.976 -166.082218)
		(end 188.541152 -163.6141)
		(width 0.1143)
		(layer "F.Cu")
		(net "L1_85OHM_10INCH_DP")
	)
	(segment
		(start 190.805054 -166.171626)
		(end 190.672212 -166.078662)
		(width 0.1143)
		(layer "F.Cu")
		(net "L1_85OHM_10INCH_DP")
	)
	(segment
		(start 184.466484 -165.956742)
		(end 184.373774 -166.089076)
		(width 0.1143)
		(layer "F.Cu")
		(net "L1_85OHM_10INCH_DP")
	)
	(segment
		(start 184.373774 -166.089076)
		(end 184.013602 -166.152322)
		(width 0.1143)
		(layer "F.Cu")
		(net "L1_85OHM_10INCH_DP")
	)
	(segment
		(start 195.328794 -163.60775)
		(end 195.032122 -163.40074)
		(width 0.1143)
		(layer "F.Cu")
		(net "L1_85OHM_10INCH_DP")
	)
	(segment
		(start 170.507914 -163.798504)
		(end 170.890184 -165.967918)
		(width 0.1143)
		(layer "F.Cu")
		(net "L1_85OHM_10INCH_DP")
	)
	(segment
		(start 166.180516 -163.397946)
		(end 165.622732 -163.495482)
		(width 0.1143)
		(layer "F.Cu")
		(net "L1_85OHM_10INCH_DP")
	)
	(segment
		(start 201.259948 -163.478972)
		(end 201.052684 -163.77539)
		(width 0.1143)
		(layer "F.Cu")
		(net "L1_85OHM_10INCH_DP")
	)
	(segment
		(start 184.086246 -163.799012)
		(end 184.466484 -165.956742)
		(width 0.1143)
		(layer "F.Cu")
		(net "L1_85OHM_10INCH_DP")
	)
	(segment
		(start 211.621878 -165.966648)
		(end 211.529168 -166.098982)
		(width 0.1143)
		(layer "F.Cu")
		(net "L1_85OHM_10INCH_DP")
	)
	(segment
		(start 206.143606 -163.773358)
		(end 206.530194 -165.96741)
		(width 0.1143)
		(layer "F.Cu")
		(net "L1_85OHM_10INCH_DP")
	)
	(segment
		(start 185.577226 -166.056056)
		(end 185.14695 -163.612576)
		(width 0.1143)
		(layer "F.Cu")
		(net "L1_85OHM_10INCH_DP")
	)
	(segment
		(start 209.338926 -166.065962)
		(end 209.16011 -165.053264)
		(width 0.1143)
		(layer "F.Cu")
		(net "L1_85OHM_10INCH_DP")
	)
	(segment
		(start 179.756562 -163.387024)
		(end 179.19827 -163.485068)
		(width 0.1143)
		(layer "F.Cu")
		(net "L1_85OHM_10INCH_DP")
	)
	(segment
		(start 220.78823 -163.623752)
		(end 220.492066 -163.416488)
		(width 0.1143)
		(layer "F.Cu")
		(net "L1_85OHM_10INCH_DP")
	)
	(segment
		(start 183.88076 -166.059612)
		(end 183.446674 -163.595558)
		(width 0.1143)
		(layer "F.Cu")
		(net "L1_85OHM_10INCH_DP")
	)
	(segment
		(start 180.979064 -166.089838)
		(end 180.619146 -166.153084)
		(width 0.1143)
		(layer "F.Cu")
		(net "L1_85OHM_10INCH_DP")
	)
	(segment
		(start 199.649334 -166.102792)
		(end 199.288654 -166.165784)
		(width 0.1143)
		(layer "F.Cu")
		(net "L1_85OHM_10INCH_DP")
	)
	(segment
		(start 223.505268 -165.985698)
		(end 223.412558 -166.118032)
		(width 0.1143)
		(layer "F.Cu")
		(net "L1_85OHM_10INCH_DP")
	)
	(segment
		(start 223.324928 -163.491418)
		(end 223.117664 -163.787328)
		(width 0.1143)
		(layer "F.Cu")
		(net "L1_85OHM_10INCH_DP")
	)
	(segment
		(start 183.150764 -163.388548)
		(end 182.593488 -163.486338)
		(width 0.1143)
		(layer "F.Cu")
		(net "L1_85OHM_10INCH_DP")
	)
	(segment
		(start 164.775896 -163.584128)
		(end 164.479224 -163.37661)
		(width 0.1143)
		(layer "F.Cu")
		(net "L1_85OHM_10INCH_DP")
	)
	(segment
		(start 198.421498 -163.377626)
		(end 197.86473 -163.475416)
		(width 0.1143)
		(layer "F.Cu")
		(net "L1_85OHM_10INCH_DP")
	)
	(segment
		(start 180.899308 -163.485322)
		(end 180.688742 -163.784788)
		(width 0.1143)
		(layer "F.Cu")
		(net "L1_85OHM_10INCH_DP")
	)
	(segment
		(start 189.108842 -166.175182)
		(end 188.976 -166.082218)
		(width 0.1143)
		(layer "F.Cu")
		(net "L1_85OHM_10INCH_DP")
	)
	(segment
		(start 184.29351 -163.503102)
		(end 184.086246 -163.799012)
		(width 0.1143)
		(layer "F.Cu")
		(net "L1_85OHM_10INCH_DP")
	)
	(segment
		(start 205.507336 -163.5887)
		(end 205.208124 -163.37915)
		(width 0.1143)
		(layer "F.Cu")
		(net "L1_85OHM_10INCH_DP")
	)
	(segment
		(start 218.237308 -163.511484)
		(end 218.030044 -163.807648)
		(width 0.1143)
		(layer "F.Cu")
		(net "L1_85OHM_10INCH_DP")
	)
	(segment
		(start 178.060604 -163.395406)
		(end 177.503074 -163.493196)
		(width 0.1143)
		(layer "F.Cu")
		(net "L1_85OHM_10INCH_DP")
	)
	(segment
		(start 175.395382 -166.06393)
		(end 174.962566 -163.606988)
		(width 0.1143)
		(layer "F.Cu")
		(net "L1_85OHM_10INCH_DP")
	)
	(segment
		(start 180.619146 -166.153084)
		(end 180.486304 -166.06012)
		(width 0.1143)
		(layer "F.Cu")
		(net "L1_85OHM_10INCH_DP")
	)
	(segment
		(start 218.794584 -163.41344)
		(end 218.237308 -163.511484)
		(width 0.1143)
		(layer "F.Cu")
		(net "L1_85OHM_10INCH_DP")
	)
	(segment
		(start 204.65669 -163.476432)
		(end 204.446124 -163.775898)
		(width 0.1143)
		(layer "F.Cu")
		(net "L1_85OHM_10INCH_DP")
	)
	(segment
		(start 174.962566 -163.606988)
		(end 174.66564 -163.39947)
		(width 0.1143)
		(layer "F.Cu")
		(net "L1_85OHM_10INCH_DP")
	)
	(segment
		(start 219.090494 -163.620704)
		(end 218.794584 -163.41344)
		(width 0.1143)
		(layer "F.Cu")
		(net "L1_85OHM_10INCH_DP")
	)
	(segment
		(start 201.439018 -165.967918)
		(end 201.343514 -166.103808)
		(width 0.1143)
		(layer "F.Cu")
		(net "L1_85OHM_10INCH_DP")
	)
	(segment
		(start 171.272454 -163.40455)
		(end 170.715432 -163.50234)
		(width 0.1143)
		(layer "F.Cu")
		(net "L1_85OHM_10INCH_DP")
	)
	(segment
		(start 219.727526 -163.810442)
		(end 220.107764 -165.968172)
		(width 0.1143)
		(layer "F.Cu")
		(net "L1_85OHM_10INCH_DP")
	)
	(segment
		(start 213.69782 -163.397692)
		(end 213.146386 -163.494974)
		(width 0.1143)
		(layer "F.Cu")
		(net "L1_85OHM_10INCH_DP")
	)
	(segment
		(start 221.35592 -166.184834)
		(end 221.223078 -166.09187)
		(width 0.1143)
		(layer "F.Cu")
		(net "L1_85OHM_10INCH_DP")
	)
	(segment
		(start 177.503074 -163.493196)
		(end 177.295556 -163.789614)
		(width 0.1143)
		(layer "F.Cu")
		(net "L1_85OHM_10INCH_DP")
	)
	(segment
		(start 196.344794 -165.954964)
		(end 196.252338 -166.087298)
		(width 0.1143)
		(layer "F.Cu")
		(net "L1_85OHM_10INCH_DP")
	)
	(segment
		(start 209.924142 -165.962838)
		(end 209.831432 -166.09568)
		(width 0.1143)
		(layer "F.Cu")
		(net "L1_85OHM_10INCH_DP")
	)
	(segment
		(start 170.437048 -166.16299)
		(end 170.305222 -166.070788)
		(width 0.1143)
		(layer "F.Cu")
		(net "L1_85OHM_10INCH_DP")
	)
	(segment
		(start 165.70325 -166.081202)
		(end 165.342824 -166.144702)
		(width 0.1143)
		(layer "F.Cu")
		(net "L1_85OHM_10INCH_DP")
	)
	(segment
		(start 182.18277 -166.054278)
		(end 181.749954 -163.59759)
		(width 0.1143)
		(layer "F.Cu")
		(net "L1_85OHM_10INCH_DP")
	)
	(segment
		(start 189.942216 -163.407344)
		(end 189.38494 -163.505642)
		(width 0.1143)
		(layer "F.Cu")
		(net "L1_85OHM_10INCH_DP")
	)
	(segment
		(start 204.380846 -166.168832)
		(end 204.248004 -166.075868)
		(width 0.1143)
		(layer "F.Cu")
		(net "L1_85OHM_10INCH_DP")
	)
	(segment
		(start 204.446124 -163.775898)
		(end 204.833474 -165.973252)
		(width 0.1143)
		(layer "F.Cu")
		(net "L1_85OHM_10INCH_DP")
	)
	(segment
		(start 191.25819 -165.976046)
		(end 191.16548 -166.10838)
		(width 0.1143)
		(layer "F.Cu")
		(net "L1_85OHM_10INCH_DP")
	)
	(segment
		(start 170.305222 -166.070788)
		(end 169.871136 -163.60648)
		(width 0.1143)
		(layer "F.Cu")
		(net "L1_85OHM_10INCH_DP")
	)
	(segment
		(start 199.56272 -163.480496)
		(end 199.355202 -163.77666)
		(width 0.1143)
		(layer "F.Cu")
		(net "L1_85OHM_10INCH_DP")
	)
	(segment
		(start 185.14695 -163.612576)
		(end 184.850786 -163.405312)
		(width 0.1143)
		(layer "F.Cu")
		(net "L1_85OHM_10INCH_DP")
	)
	(segment
		(start 173.901608 -163.79317)
		(end 174.28464 -165.969188)
		(width 0.1143)
		(layer "F.Cu")
		(net "L1_85OHM_10INCH_DP")
	)
	(segment
		(start 216.713562 -165.966394)
		(end 216.620852 -166.098728)
		(width 0.1143)
		(layer "F.Cu")
		(net "L1_85OHM_10INCH_DP")
	)
	(segment
		(start 192.773554 -163.477194)
		(end 192.566544 -163.77412)
		(width 0.1143)
		(layer "F.Cu")
		(net "L1_85OHM_10INCH_DP")
	)
	(segment
		(start 163.714938 -163.771326)
		(end 164.098478 -165.94836)
		(width 0.1143)
		(layer "F.Cu")
		(net "L1_85OHM_10INCH_DP")
	)
	(segment
		(start 163.921948 -163.4744)
		(end 163.714938 -163.771326)
		(width 0.1143)
		(layer "F.Cu")
		(net "L1_85OHM_10INCH_DP")
	)
	(segment
		(start 192.566544 -163.77412)
		(end 192.950084 -165.951154)
		(width 0.1143)
		(layer "F.Cu")
		(net "L1_85OHM_10INCH_DP")
	)
	(segment
		(start 165.622732 -163.495482)
		(end 165.415722 -163.7919)
		(width 0.1143)
		(layer "F.Cu")
		(net "L1_85OHM_10INCH_DP")
	)
	(segment
		(start 167.400732 -166.084504)
		(end 167.04056 -166.148004)
		(width 0.1143)
		(layer "F.Cu")
		(net "L1_85OHM_10INCH_DP")
	)
	(segment
		(start 172.491908 -166.101014)
		(end 172.137324 -166.163498)
		(width 0.1143)
		(layer "F.Cu")
		(net "L1_85OHM_10INCH_DP")
	)
	(segment
		(start 222.485204 -163.62426)
		(end 222.189294 -163.416996)
		(width 0.1143)
		(layer "F.Cu")
		(net "L1_85OHM_10INCH_DP")
	)
	(segment
		(start 206.077312 -166.16299)
		(end 205.94447 -166.070026)
		(width 0.1143)
		(layer "F.Cu")
		(net "L1_85OHM_10INCH_DP")
	)
	(segment
		(start 174.66564 -163.39947)
		(end 174.109126 -163.497006)
		(width 0.1143)
		(layer "F.Cu")
		(net "L1_85OHM_10INCH_DP")
	)
	(segment
		(start 194.474338 -163.498276)
		(end 194.267328 -163.794694)
		(width 0.1143)
		(layer "F.Cu")
		(net "L1_85OHM_10INCH_DP")
	)
	(segment
		(start 217.824304 -166.065708)
		(end 217.394028 -163.622228)
		(width 0.1143)
		(layer "F.Cu")
		(net "L1_85OHM_10INCH_DP")
	)
	(segment
		(start 206.35087 -163.477448)
		(end 206.143606 -163.773358)
		(width 0.1143)
		(layer "F.Cu")
		(net "L1_85OHM_10INCH_DP")
	)
	(segment
		(start 161.820606 -166.075868)
		(end 161.735008 -165.590982)
		(width 0.1143)
		(layer "F.Cu")
		(net "L1_85OHM_10INCH_DP")
	)
	(segment
		(start 210.603592 -163.612068)
		(end 210.307682 -163.405058)
		(width 0.1143)
		(layer "F.Cu")
		(net "L1_85OHM_10INCH_DP")
	)
	(segment
		(start 223.052132 -166.181278)
		(end 222.91929 -166.088314)
		(width 0.1143)
		(layer "F.Cu")
		(net "L1_85OHM_10INCH_DP")
	)
	(segment
		(start 178.922426 -166.152322)
		(end 178.78933 -166.059358)
		(width 0.1143)
		(layer "F.Cu")
		(net "L1_85OHM_10INCH_DP")
	)
	(segment
		(start 175.527462 -166.156386)
		(end 175.395382 -166.06393)
		(width 0.1143)
		(layer "F.Cu")
		(net "L1_85OHM_10INCH_DP")
	)
	(segment
		(start 202.95997 -163.500816)
		(end 202.753468 -163.79698)
		(width 0.1143)
		(layer "F.Cu")
		(net "L1_85OHM_10INCH_DP")
	)
	(segment
		(start 185.99023 -163.501832)
		(end 185.782966 -163.797996)
		(width 0.1143)
		(layer "F.Cu")
		(net "L1_85OHM_10INCH_DP")
	)
	(segment
		(start 208.050892 -163.494212)
		(end 207.843628 -163.790122)
		(width 0.1143)
		(layer "F.Cu")
		(net "L1_85OHM_10INCH_DP")
	)
	(segment
		(start 204.248004 -166.075868)
		(end 203.814172 -163.609782)
		(width 0.1143)
		(layer "F.Cu")
		(net "L1_85OHM_10INCH_DP")
	)
	(segment
		(start 205.94447 -166.070026)
		(end 205.507336 -163.5887)
		(width 0.1143)
		(layer "F.Cu")
		(net "L1_85OHM_10INCH_DP")
	)
	(segment
		(start 224.71761 -164.67201)
		(end 224.270316 -164.121846)
		(width 0.1143)
		(layer "F.Cu")
		(net "L1_85OHM_10INCH_DP")
	)
	(segment
		(start 180.486304 -166.06012)
		(end 180.052472 -163.594034)
		(width 0.1143)
		(layer "F.Cu")
		(net "L1_85OHM_10INCH_DP")
	)
	(segment
		(start 209.16011 -165.053264)
		(end 208.904332 -163.603686)
		(width 0.1143)
		(layer "F.Cu")
		(net "L1_85OHM_10INCH_DP")
	)
	(segment
		(start 167.113712 -163.797488)
		(end 167.493188 -165.95217)
		(width 0.1143)
		(layer "F.Cu")
		(net "L1_85OHM_10INCH_DP")
	)
	(segment
		(start 219.93479 -163.514786)
		(end 219.727526 -163.810442)
		(width 0.1143)
		(layer "F.Cu")
		(net "L1_85OHM_10INCH_DP")
	)
	(segment
		(start 200.853548 -166.07155)
		(end 200.416414 -163.590224)
		(width 0.1143)
		(layer "F.Cu")
		(net "L1_85OHM_10INCH_DP")
	)
	(segment
		(start 182.386224 -163.782248)
		(end 182.768494 -165.951662)
		(width 0.1143)
		(layer "F.Cu")
		(net "L1_85OHM_10INCH_DP")
	)
	(segment
		(start 177.295556 -163.789614)
		(end 177.677064 -165.953186)
		(width 0.1143)
		(layer "F.Cu")
		(net "L1_85OHM_10INCH_DP")
	)
	(segment
		(start 187.687712 -163.505134)
		(end 187.480448 -163.80079)
		(width 0.1143)
		(layer "F.Cu")
		(net "L1_85OHM_10INCH_DP")
	)
	(segment
		(start 166.90848 -166.055294)
		(end 166.477188 -163.604956)
		(width 0.1143)
		(layer "F.Cu")
		(net "L1_85OHM_10INCH_DP")
	)
	(segment
		(start 177.677064 -165.953186)
		(end 177.584354 -166.086028)
		(width 0.1143)
		(layer "F.Cu")
		(net "L1_85OHM_10INCH_DP")
	)
	(segment
		(start 172.001942 -166.068756)
		(end 171.569126 -163.612068)
		(width 0.1143)
		(layer "F.Cu")
		(net "L1_85OHM_10INCH_DP")
	)
	(segment
		(start 194.06235 -166.05504)
		(end 193.627502 -163.586922)
		(width 0.1143)
		(layer "F.Cu")
		(net "L1_85OHM_10INCH_DP")
	)
	(segment
		(start 209.471768 -166.158926)
		(end 209.338926 -166.065962)
		(width 0.1143)
		(layer "F.Cu")
		(net "L1_85OHM_10INCH_DP")
	)
	(segment
		(start 194.267328 -163.794694)
		(end 194.647566 -165.95217)
		(width 0.1143)
		(layer "F.Cu")
		(net "L1_85OHM_10INCH_DP")
	)
	(segment
		(start 211.445348 -163.49472)
		(end 211.238846 -163.790884)
		(width 0.1143)
		(layer "F.Cu")
		(net "L1_85OHM_10INCH_DP")
	)
	(segment
		(start 195.892166 -166.150798)
		(end 195.760086 -166.058088)
		(width 0.1143)
		(layer "F.Cu")
		(net "L1_85OHM_10INCH_DP")
	)
	(segment
		(start 181.749954 -163.59759)
		(end 181.450742 -163.38804)
		(width 0.1143)
		(layer "F.Cu")
		(net "L1_85OHM_10INCH_DP")
	)
	(segment
		(start 198.718424 -163.584636)
		(end 198.421498 -163.377626)
		(width 0.1143)
		(layer "F.Cu")
		(net "L1_85OHM_10INCH_DP")
	)
	(segment
		(start 167.493188 -165.95217)
		(end 167.400732 -166.084504)
		(width 0.1143)
		(layer "F.Cu")
		(net "L1_85OHM_10INCH_DP")
	)
	(segment
		(start 189.38494 -163.505642)
		(end 189.177676 -163.801806)
		(width 0.1143)
		(layer "F.Cu")
		(net "L1_85OHM_10INCH_DP")
	)
	(segment
		(start 179.19827 -163.485068)
		(end 178.991768 -163.781232)
		(width 0.1143)
		(layer "F.Cu")
		(net "L1_85OHM_10INCH_DP")
	)
	(segment
		(start 186.162696 -165.952932)
		(end 186.069986 -166.085774)
		(width 0.1143)
		(layer "F.Cu")
		(net "L1_85OHM_10INCH_DP")
	)
	(segment
		(start 218.317064 -166.095426)
		(end 217.957146 -166.158672)
		(width 0.1143)
		(layer "F.Cu")
		(net "L1_85OHM_10INCH_DP")
	)
	(segment
		(start 175.599344 -163.797234)
		(end 175.980852 -165.960552)
		(width 0.1143)
		(layer "F.Cu")
		(net "L1_85OHM_10INCH_DP")
	)
	(segment
		(start 216.333324 -163.808664)
		(end 216.713562 -165.966394)
		(width 0.1143)
		(layer "F.Cu")
		(net "L1_85OHM_10INCH_DP")
	)
	(segment
		(start 197.456552 -166.056564)
		(end 197.02272 -163.592764)
		(width 0.1143)
		(layer "F.Cu")
		(net "L1_85OHM_10INCH_DP")
	)
	(segment
		(start 216.540588 -163.512754)
		(end 216.333324 -163.808664)
		(width 0.1143)
		(layer "F.Cu")
		(net "L1_85OHM_10INCH_DP")
	)
	(segment
		(start 190.672212 -166.078662)
		(end 190.238126 -163.614608)
		(width 0.1143)
		(layer "F.Cu")
		(net "L1_85OHM_10INCH_DP")
	)
	(segment
		(start 167.877998 -163.402772)
		(end 167.320722 -163.500562)
		(width 0.1143)
		(layer "F.Cu")
		(net "L1_85OHM_10INCH_DP")
	)
	(segment
		(start 209.542634 -163.799266)
		(end 209.924142 -165.962838)
		(width 0.1143)
		(layer "F.Cu")
		(net "L1_85OHM_10INCH_DP")
	)
	(segment
		(start 169.871136 -163.60648)
		(end 169.57421 -163.39947)
		(width 0.1143)
		(layer "F.Cu")
		(net "L1_85OHM_10INCH_DP")
	)
	(segment
		(start 191.93129 -163.590478)
		(end 191.635126 -163.383722)
		(width 0.1143)
		(layer "F.Cu")
		(net "L1_85OHM_10INCH_DP")
	)
	(segment
		(start 216.620852 -166.098728)
		(end 216.26068 -166.161974)
		(width 0.1143)
		(layer "F.Cu")
		(net "L1_85OHM_10INCH_DP")
	)
	(segment
		(start 176.363376 -163.402518)
		(end 175.806354 -163.500308)
		(width 0.1143)
		(layer "F.Cu")
		(net "L1_85OHM_10INCH_DP")
	)
	(segment
		(start 201.343514 -166.103808)
		(end 200.98893 -166.166292)
		(width 0.1143)
		(layer "F.Cu")
		(net "L1_85OHM_10INCH_DP")
	)
	(segment
		(start 191.07785 -163.481766)
		(end 190.870586 -163.777676)
		(width 0.1143)
		(layer "F.Cu")
		(net "L1_85OHM_10INCH_DP")
	)
	(segment
		(start 209.831432 -166.09568)
		(end 209.471768 -166.158926)
		(width 0.1143)
		(layer "F.Cu")
		(net "L1_85OHM_10INCH_DP")
	)
	(segment
		(start 216.127838 -166.069264)
		(end 215.693752 -163.60521)
		(width 0.1143)
		(layer "F.Cu")
		(net "L1_85OHM_10INCH_DP")
	)
	(segment
		(start 199.288654 -166.165784)
		(end 199.156828 -166.073582)
		(width 0.1143)
		(layer "F.Cu")
		(net "L1_85OHM_10INCH_DP")
	)
	(segment
		(start 164.479224 -163.37661)
		(end 163.921948 -163.4744)
		(width 0.1143)
		(layer "F.Cu")
		(net "L1_85OHM_10INCH_DP")
	)
	(segment
		(start 219.654628 -166.163498)
		(end 219.521786 -166.070788)
		(width 0.1143)
		(layer "F.Cu")
		(net "L1_85OHM_10INCH_DP")
	)
	(segment
		(start 174.28464 -165.969188)
		(end 174.192438 -166.101268)
		(width 0.1143)
		(layer "F.Cu")
		(net "L1_85OHM_10INCH_DP")
	)
	(segment
		(start 166.477188 -163.604956)
		(end 166.180516 -163.397946)
		(width 0.1143)
		(layer "F.Cu")
		(net "L1_85OHM_10INCH_DP")
	)
	(segment
		(start 172.912278 -163.653724)
		(end 172.55236 -163.71697)
		(width 0.1143)
		(layer "F.Cu")
		(net "L1_85OHM_10INCH_DN")
	)
	(segment
		(start 185.356754 -166.196518)
		(end 184.926478 -163.753038)
		(width 0.1143)
		(layer "F.Cu")
		(net "L1_85OHM_10INCH_DN")
	)
	(segment
		(start 222.698818 -166.228776)
		(end 222.264732 -163.764722)
		(width 0.1143)
		(layer "F.Cu")
		(net "L1_85OHM_10INCH_DN")
	)
	(segment
		(start 221.002606 -166.232332)
		(end 220.567758 -163.764214)
		(width 0.1143)
		(layer "F.Cu")
		(net "L1_85OHM_10INCH_DN")
	)
	(segment
		(start 186.210702 -166.306246)
		(end 185.653426 -166.404036)
		(width 0.1143)
		(layer "F.Cu")
		(net "L1_85OHM_10INCH_DN")
	)
	(segment
		(start 184.794398 -163.660582)
		(end 184.433718 -163.723574)
		(width 0.1143)
		(layer "F.Cu")
		(net "L1_85OHM_10INCH_DN")
	)
	(segment
		(start 227.937314 -165.40861)
		(end 227.557584 -165.035992)
		(width 0.1143)
		(layer "F.Cu")
		(net "L1_85OHM_10INCH_DN")
	)
	(segment
		(start 167.368728 -163.853876)
		(end 167.748458 -166.008812)
		(width 0.1143)
		(layer "F.Cu")
		(net "L1_85OHM_10INCH_DN")
	)
	(segment
		(start 227.046028 -165.035992)
		(end 225.941382 -165.12159)
		(width 0.1143)
		(layer "F.Cu")
		(net "L1_85OHM_10INCH_DN")
	)
	(segment
		(start 198.36511 -163.632642)
		(end 198.004938 -163.695888)
		(width 0.1143)
		(layer "F.Cu")
		(net "L1_85OHM_10INCH_DN")
	)
	(segment
		(start 214.980774 -163.716462)
		(end 214.888318 -163.848542)
		(width 0.1143)
		(layer "F.Cu")
		(net "L1_85OHM_10INCH_DN")
	)
	(segment
		(start 178.568858 -166.19982)
		(end 178.136042 -163.742878)
		(width 0.1143)
		(layer "F.Cu")
		(net "L1_85OHM_10INCH_DN")
	)
	(segment
		(start 222.99549 -166.436294)
		(end 222.698818 -166.228776)
		(width 0.1143)
		(layer "F.Cu")
		(net "L1_85OHM_10INCH_DN")
	)
	(segment
		(start 164.422582 -163.631626)
		(end 164.062664 -163.694872)
		(width 0.1143)
		(layer "F.Cu")
		(net "L1_85OHM_10INCH_DN")
	)
	(segment
		(start 199.996806 -166.027354)
		(end 199.789542 -166.323264)
		(width 0.1143)
		(layer "F.Cu")
		(net "L1_85OHM_10INCH_DN")
	)
	(segment
		(start 189.885574 -163.662614)
		(end 189.525402 -163.726114)
		(width 0.1143)
		(layer "F.Cu")
		(net "L1_85OHM_10INCH_DN")
	)
	(segment
		(start 183.094376 -163.643818)
		(end 182.733696 -163.70681)
		(width 0.1143)
		(layer "F.Cu")
		(net "L1_85OHM_10INCH_DN")
	)
	(segment
		(start 221.299278 -166.43985)
		(end 221.002606 -166.232332)
		(width 0.1143)
		(layer "F.Cu")
		(net "L1_85OHM_10INCH_DN")
	)
	(segment
		(start 188.1886 -163.662106)
		(end 187.828174 -163.725606)
		(width 0.1143)
		(layer "F.Cu")
		(net "L1_85OHM_10INCH_DN")
	)
	(segment
		(start 220.567758 -163.764214)
		(end 220.435678 -163.671758)
		(width 0.1143)
		(layer "F.Cu")
		(net "L1_85OHM_10INCH_DN")
	)
	(segment
		(start 216.680796 -163.733226)
		(end 216.58834 -163.865306)
		(width 0.1143)
		(layer "F.Cu")
		(net "L1_85OHM_10INCH_DN")
	)
	(segment
		(start 222.132652 -163.672266)
		(end 221.77248 -163.735766)
		(width 0.1143)
		(layer "F.Cu")
		(net "L1_85OHM_10INCH_DN")
	)
	(segment
		(start 181.3941 -163.64331)
		(end 181.039516 -163.705794)
		(width 0.1143)
		(layer "F.Cu")
		(net "L1_85OHM_10INCH_DN")
	)
	(segment
		(start 167.821356 -163.657788)
		(end 167.461438 -163.721034)
		(width 0.1143)
		(layer "F.Cu")
		(net "L1_85OHM_10INCH_DN")
	)
	(segment
		(start 170.85564 -163.722812)
		(end 170.76293 -163.855146)
		(width 0.1143)
		(layer "F.Cu")
		(net "L1_85OHM_10INCH_DN")
	)
	(segment
		(start 176.439576 -163.750498)
		(end 176.306734 -163.657534)
		(width 0.1143)
		(layer "F.Cu")
		(net "L1_85OHM_10INCH_DN")
	)
	(segment
		(start 169.445178 -166.007796)
		(end 169.237914 -166.303706)
		(width 0.1143)
		(layer "F.Cu")
		(net "L1_85OHM_10INCH_DN")
	)
	(segment
		(start 191.578738 -163.638738)
		(end 191.218312 -163.702238)
		(width 0.1143)
		(layer "F.Cu")
		(net "L1_85OHM_10INCH_DN")
	)
	(segment
		(start 169.517822 -163.654486)
		(end 169.15765 -163.717732)
		(width 0.1143)
		(layer "F.Cu")
		(net "L1_85OHM_10INCH_DN")
	)
	(segment
		(start 211.946998 -163.651692)
		(end 211.586064 -163.715192)
		(width 0.1143)
		(layer "F.Cu")
		(net "L1_85OHM_10INCH_DN")
	)
	(segment
		(start 174.608998 -163.654486)
		(end 174.249334 -163.717478)
		(width 0.1143)
		(layer "F.Cu")
		(net "L1_85OHM_10INCH_DN")
	)
	(segment
		(start 176.673256 -165.0746)
		(end 176.439576 -163.750498)
		(width 0.1143)
		(layer "F.Cu")
		(net "L1_85OHM_10INCH_DN")
	)
	(segment
		(start 217.900504 -166.413688)
		(end 217.603832 -166.20617)
		(width 0.1143)
		(layer "F.Cu")
		(net "L1_85OHM_10INCH_DN")
	)
	(segment
		(start 215.907366 -166.20998)
		(end 215.47328 -163.745672)
		(width 0.1143)
		(layer "F.Cu")
		(net "L1_85OHM_10INCH_DN")
	)
	(segment
		(start 218.37777 -163.731956)
		(end 218.285314 -163.86429)
		(width 0.1143)
		(layer "F.Cu")
		(net "L1_85OHM_10INCH_DN")
	)
	(segment
		(start 218.45778 -166.315898)
		(end 217.900504 -166.413688)
		(width 0.1143)
		(layer "F.Cu")
		(net "L1_85OHM_10INCH_DN")
	)
	(segment
		(start 194.6148 -163.718748)
		(end 194.522344 -163.851082)
		(width 0.1143)
		(layer "F.Cu")
		(net "L1_85OHM_10INCH_DN")
	)
	(segment
		(start 208.55178 -163.651692)
		(end 208.1911 -163.714684)
		(width 0.1143)
		(layer "F.Cu")
		(net "L1_85OHM_10INCH_DN")
	)
	(segment
		(start 204.027532 -166.21633)
		(end 203.5937 -163.750244)
		(width 0.1143)
		(layer "F.Cu")
		(net "L1_85OHM_10INCH_DN")
	)
	(segment
		(start 167.954198 -163.750752)
		(end 167.821356 -163.657788)
		(width 0.1143)
		(layer "F.Cu")
		(net "L1_85OHM_10INCH_DN")
	)
	(segment
		(start 223.957896 -163.740592)
		(end 223.825816 -163.64839)
		(width 0.1143)
		(layer "F.Cu")
		(net "L1_85OHM_10INCH_DN")
	)
	(segment
		(start 164.146484 -166.301166)
		(end 163.589208 -166.399464)
		(width 0.1143)
		(layer "F.Cu")
		(net "L1_85OHM_10INCH_DN")
	)
	(segment
		(start 178.136042 -163.742878)
		(end 178.003962 -163.650422)
		(width 0.1143)
		(layer "F.Cu")
		(net "L1_85OHM_10INCH_DN")
	)
	(segment
		(start 196.802248 -163.733226)
		(end 196.669406 -163.640262)
		(width 0.1143)
		(layer "F.Cu")
		(net "L1_85OHM_10INCH_DN")
	)
	(segment
		(start 214.209376 -166.204392)
		(end 213.77656 -163.747704)
		(width 0.1143)
		(layer "F.Cu")
		(net "L1_85OHM_10INCH_DN")
	)
	(segment
		(start 169.650664 -163.747196)
		(end 169.517822 -163.654486)
		(width 0.1143)
		(layer "F.Cu")
		(net "L1_85OHM_10INCH_DN")
	)
	(segment
		(start 221.680024 -163.8681)
		(end 222.063564 -166.045134)
		(width 0.1143)
		(layer "F.Cu")
		(net "L1_85OHM_10INCH_DN")
	)
	(segment
		(start 212.809836 -166.417752)
		(end 212.51291 -166.210234)
		(width 0.1143)
		(layer "F.Cu")
		(net "L1_85OHM_10INCH_DN")
	)
	(segment
		(start 184.433718 -163.723574)
		(end 184.341262 -163.855654)
		(width 0.1143)
		(layer "F.Cu")
		(net "L1_85OHM_10INCH_DN")
	)
	(segment
		(start 190.748412 -166.426642)
		(end 190.45174 -166.219124)
		(width 0.1143)
		(layer "F.Cu")
		(net "L1_85OHM_10INCH_DN")
	)
	(segment
		(start 186.622944 -163.751514)
		(end 186.490864 -163.658804)
		(width 0.1143)
		(layer "F.Cu")
		(net "L1_85OHM_10INCH_DN")
	)
	(segment
		(start 225.941382 -165.12159)
		(end 224.587816 -164.895022)
		(width 0.1143)
		(layer "F.Cu")
		(net "L1_85OHM_10INCH_DN")
	)
	(segment
		(start 171.348654 -163.75253)
		(end 171.215812 -163.659566)
		(width 0.1143)
		(layer "F.Cu")
		(net "L1_85OHM_10INCH_DN")
	)
	(segment
		(start 208.866994 -164.781484)
		(end 208.68386 -163.744148)
		(width 0.1143)
		(layer "F.Cu")
		(net "L1_85OHM_10INCH_DN")
	)
	(segment
		(start 186.490864 -163.658804)
		(end 186.130692 -163.722304)
		(width 0.1143)
		(layer "F.Cu")
		(net "L1_85OHM_10INCH_DN")
	)
	(segment
		(start 189.0522 -166.430198)
		(end 188.755528 -166.22268)
		(width 0.1143)
		(layer "F.Cu")
		(net "L1_85OHM_10INCH_DN")
	)
	(segment
		(start 218.870022 -163.761166)
		(end 218.737942 -163.668456)
		(width 0.1143)
		(layer "F.Cu")
		(net "L1_85OHM_10INCH_DN")
	)
	(segment
		(start 214.506048 -166.41191)
		(end 214.209376 -166.204392)
		(width 0.1143)
		(layer "F.Cu")
		(net "L1_85OHM_10INCH_DN")
	)
	(segment
		(start 168.680638 -166.401496)
		(end 168.384474 -166.194232)
		(width 0.1143)
		(layer "F.Cu")
		(net "L1_85OHM_10INCH_DN")
	)
	(segment
		(start 165.286436 -166.399972)
		(end 164.990272 -166.192708)
		(width 0.1143)
		(layer "F.Cu")
		(net "L1_85OHM_10INCH_DN")
	)
	(segment
		(start 161.896298 -166.423086)
		(end 161.600134 -166.216584)
		(width 0.1143)
		(layer "F.Cu")
		(net "L1_85OHM_10INCH_DN")
	)
	(segment
		(start 207.718914 -166.423086)
		(end 207.421988 -166.216076)
		(width 0.1143)
		(layer "F.Cu")
		(net "L1_85OHM_10INCH_DN")
	)
	(segment
		(start 176.235868 -166.017194)
		(end 176.02835 -166.313612)
		(width 0.1143)
		(layer "F.Cu")
		(net "L1_85OHM_10INCH_DN")
	)
	(segment
		(start 174.742094 -163.74745)
		(end 174.608998 -163.654486)
		(width 0.1143)
		(layer "F.Cu")
		(net "L1_85OHM_10INCH_DN")
	)
	(segment
		(start 158.741872 -165.021768)
		(end 158.220918 -165.021768)
		(width 0.1143)
		(layer "F.Cu")
		(net "L1_85OHM_10INCH_DN")
	)
	(segment
		(start 162.273234 -163.830762)
		(end 162.660838 -166.029132)
		(width 0.1143)
		(layer "F.Cu")
		(net "L1_85OHM_10INCH_DN")
	)
	(segment
		(start 208.4832 -166.029132)
		(end 208.275682 -166.325296)
		(width 0.1143)
		(layer "F.Cu")
		(net "L1_85OHM_10INCH_DN")
	)
	(segment
		(start 172.55236 -163.71697)
		(end 172.45965 -163.849304)
		(width 0.1143)
		(layer "F.Cu")
		(net "L1_85OHM_10INCH_DN")
	)
	(segment
		(start 174.539656 -166.025576)
		(end 174.333154 -166.32174)
		(width 0.1143)
		(layer "F.Cu")
		(net "L1_85OHM_10INCH_DN")
	)
	(segment
		(start 163.969954 -163.827714)
		(end 164.353748 -166.005002)
		(width 0.1143)
		(layer "F.Cu")
		(net "L1_85OHM_10INCH_DN")
	)
	(segment
		(start 218.737942 -163.668456)
		(end 218.37777 -163.731956)
		(width 0.1143)
		(layer "F.Cu")
		(net "L1_85OHM_10INCH_DN")
	)
	(segment
		(start 211.112862 -166.41699)
		(end 210.815936 -166.209472)
		(width 0.1143)
		(layer "F.Cu")
		(net "L1_85OHM_10INCH_DN")
	)
	(segment
		(start 189.609476 -166.332408)
		(end 189.0522 -166.430198)
		(width 0.1143)
		(layer "F.Cu")
		(net "L1_85OHM_10INCH_DN")
	)
	(segment
		(start 197.912228 -163.828222)
		(end 198.296784 -166.01059)
		(width 0.1143)
		(layer "F.Cu")
		(net "L1_85OHM_10INCH_DN")
	)
	(segment
		(start 205.286864 -163.729162)
		(end 205.151482 -163.63442)
		(width 0.1143)
		(layer "F.Cu")
		(net "L1_85OHM_10INCH_DN")
	)
	(segment
		(start 191.710818 -163.73094)
		(end 191.578738 -163.638738)
		(width 0.1143)
		(layer "F.Cu")
		(net "L1_85OHM_10INCH_DN")
	)
	(segment
		(start 209.89036 -163.72332)
		(end 209.79765 -163.855908)
		(width 0.1143)
		(layer "F.Cu")
		(net "L1_85OHM_10INCH_DN")
	)
	(segment
		(start 194.902582 -166.008812)
		(end 194.695318 -166.304468)
		(width 0.1143)
		(layer "F.Cu")
		(net "L1_85OHM_10INCH_DN")
	)
	(segment
		(start 164.062664 -163.694872)
		(end 163.969954 -163.827714)
		(width 0.1143)
		(layer "F.Cu")
		(net "L1_85OHM_10INCH_DN")
	)
	(segment
		(start 166.688008 -166.195756)
		(end 166.256716 -163.745672)
		(width 0.1143)
		(layer "F.Cu")
		(net "L1_85OHM_10INCH_DN")
	)
	(segment
		(start 187.350908 -166.408862)
		(end 187.054236 -166.201852)
		(width 0.1143)
		(layer "F.Cu")
		(net "L1_85OHM_10INCH_DN")
	)
	(segment
		(start 191.218312 -163.702238)
		(end 191.125602 -163.834318)
		(width 0.1143)
		(layer "F.Cu")
		(net "L1_85OHM_10INCH_DN")
	)
	(segment
		(start 184.513982 -166.309548)
		(end 183.957214 -166.407338)
		(width 0.1143)
		(layer "F.Cu")
		(net "L1_85OHM_10INCH_DN")
	)
	(segment
		(start 162.660838 -166.029132)
		(end 162.453574 -166.325042)
		(width 0.1143)
		(layer "F.Cu")
		(net "L1_85OHM_10INCH_DN")
	)
	(segment
		(start 162.72637 -163.635182)
		(end 162.365944 -163.698428)
		(width 0.1143)
		(layer "F.Cu")
		(net "L1_85OHM_10INCH_DN")
	)
	(segment
		(start 210.815936 -166.209472)
		(end 210.38312 -163.75253)
		(width 0.1143)
		(layer "F.Cu")
		(net "L1_85OHM_10INCH_DN")
	)
	(segment
		(start 179.69992 -163.64204)
		(end 179.338986 -163.70554)
		(width 0.1143)
		(layer "F.Cu")
		(net "L1_85OHM_10INCH_DN")
	)
	(segment
		(start 187.054236 -166.201852)
		(end 186.622944 -163.751514)
		(width 0.1143)
		(layer "F.Cu")
		(net "L1_85OHM_10INCH_DN")
	)
	(segment
		(start 179.422298 -166.309802)
		(end 178.865784 -166.407338)
		(width 0.1143)
		(layer "F.Cu")
		(net "L1_85OHM_10INCH_DN")
	)
	(segment
		(start 201.694288 -166.024814)
		(end 201.483722 -166.32428)
		(width 0.1143)
		(layer "F.Cu")
		(net "L1_85OHM_10INCH_DN")
	)
	(segment
		(start 167.541194 -166.304976)
		(end 166.983918 -166.40302)
		(width 0.1143)
		(layer "F.Cu")
		(net "L1_85OHM_10INCH_DN")
	)
	(segment
		(start 162.453574 -166.325042)
		(end 161.896298 -166.423086)
		(width 0.1143)
		(layer "F.Cu")
		(net "L1_85OHM_10INCH_DN")
	)
	(segment
		(start 212.079078 -163.744148)
		(end 211.946998 -163.651692)
		(width 0.1143)
		(layer "F.Cu")
		(net "L1_85OHM_10INCH_DN")
	)
	(segment
		(start 212.51291 -166.210234)
		(end 212.079078 -163.744148)
		(width 0.1143)
		(layer "F.Cu")
		(net "L1_85OHM_10INCH_DN")
	)
	(segment
		(start 204.796898 -163.696904)
		(end 204.701394 -163.832794)
		(width 0.1143)
		(layer "F.Cu")
		(net "L1_85OHM_10INCH_DN")
	)
	(segment
		(start 211.876894 -166.02329)
		(end 211.669376 -166.319454)
		(width 0.1143)
		(layer "F.Cu")
		(net "L1_85OHM_10INCH_DN")
	)
	(segment
		(start 177.168048 -166.40429)
		(end 176.871376 -166.196772)
		(width 0.1143)
		(layer "F.Cu")
		(net "L1_85OHM_10INCH_DN")
	)
	(segment
		(start 223.825816 -163.64839)
		(end 223.46539 -163.71189)
		(width 0.1143)
		(layer "F.Cu")
		(net "L1_85OHM_10INCH_DN")
	)
	(segment
		(start 192.99809 -166.30396)
		(end 192.440814 -166.402258)
		(width 0.1143)
		(layer "F.Cu")
		(net "L1_85OHM_10INCH_DN")
	)
	(segment
		(start 201.3077 -163.831778)
		(end 201.694288 -166.024814)
		(width 0.1143)
		(layer "F.Cu")
		(net "L1_85OHM_10INCH_DN")
	)
	(segment
		(start 218.285314 -163.86429)
		(end 218.66479 -166.018972)
		(width 0.1143)
		(layer "F.Cu")
		(net "L1_85OHM_10INCH_DN")
	)
	(segment
		(start 177.93208 -166.009574)
		(end 177.72507 -166.3065)
		(width 0.1143)
		(layer "F.Cu")
		(net "L1_85OHM_10INCH_DN")
	)
	(segment
		(start 200.932288 -166.421562)
		(end 200.633076 -166.212012)
		(width 0.1143)
		(layer "F.Cu")
		(net "L1_85OHM_10INCH_DN")
	)
	(segment
		(start 205.723998 -166.210488)
		(end 205.286864 -163.729162)
		(width 0.1143)
		(layer "F.Cu")
		(net "L1_85OHM_10INCH_DN")
	)
	(segment
		(start 199.702928 -163.700968)
		(end 199.610218 -163.833302)
		(width 0.1143)
		(layer "F.Cu")
		(net "L1_85OHM_10INCH_DN")
	)
	(segment
		(start 182.25897 -166.402258)
		(end 181.962298 -166.19474)
		(width 0.1143)
		(layer "F.Cu")
		(net "L1_85OHM_10INCH_DN")
	)
	(segment
		(start 170.38066 -166.41826)
		(end 170.08475 -166.21125)
		(width 0.1143)
		(layer "F.Cu")
		(net "L1_85OHM_10INCH_DN")
	)
	(segment
		(start 217.041476 -163.670234)
		(end 216.680796 -163.733226)
		(width 0.1143)
		(layer "F.Cu")
		(net "L1_85OHM_10INCH_DN")
	)
	(segment
		(start 214.888318 -163.848542)
		(end 215.270588 -166.017956)
		(width 0.1143)
		(layer "F.Cu")
		(net "L1_85OHM_10INCH_DN")
	)
	(segment
		(start 200.195942 -163.730686)
		(end 200.0631 -163.637722)
		(width 0.1143)
		(layer "F.Cu")
		(net "L1_85OHM_10INCH_DN")
	)
	(segment
		(start 216.968578 -166.023036)
		(end 216.76106 -166.3192)
		(width 0.1143)
		(layer "F.Cu")
		(net "L1_85OHM_10INCH_DN")
	)
	(segment
		(start 181.039516 -163.705794)
		(end 180.944012 -163.841684)
		(width 0.1143)
		(layer "F.Cu")
		(net "L1_85OHM_10INCH_DN")
	)
	(segment
		(start 213.286594 -163.715446)
		(end 213.19109 -163.851336)
		(width 0.1143)
		(layer "F.Cu")
		(net "L1_85OHM_10INCH_DN")
	)
	(segment
		(start 219.982542 -163.867084)
		(end 220.36278 -166.02456)
		(width 0.1143)
		(layer "F.Cu")
		(net "L1_85OHM_10INCH_DN")
	)
	(segment
		(start 192.91427 -163.697666)
		(end 192.82156 -163.830508)
		(width 0.1143)
		(layer "F.Cu")
		(net "L1_85OHM_10INCH_DN")
	)
	(segment
		(start 213.77656 -163.747704)
		(end 213.641178 -163.652962)
		(width 0.1143)
		(layer "F.Cu")
		(net "L1_85OHM_10INCH_DN")
	)
	(segment
		(start 179.246784 -163.83762)
		(end 179.629816 -166.013638)
		(width 0.1143)
		(layer "F.Cu")
		(net "L1_85OHM_10INCH_DN")
	)
	(segment
		(start 210.179158 -166.019226)
		(end 209.972148 -166.316152)
		(width 0.1143)
		(layer "F.Cu")
		(net "L1_85OHM_10INCH_DN")
	)
	(segment
		(start 158.220918 -165.021768)
		(end 157.841188 -165.40861)
		(width 0.1143)
		(layer "F.Cu")
		(net "L1_85OHM_10INCH_DN")
	)
	(segment
		(start 203.100686 -163.721288)
		(end 203.008484 -163.853368)
		(width 0.1143)
		(layer "F.Cu")
		(net "L1_85OHM_10INCH_DN")
	)
	(segment
		(start 187.828174 -163.725606)
		(end 187.735464 -163.857432)
		(width 0.1143)
		(layer "F.Cu")
		(net "L1_85OHM_10INCH_DN")
	)
	(segment
		(start 203.183998 -166.32555)
		(end 202.627484 -166.423086)
		(width 0.1143)
		(layer "F.Cu")
		(net "L1_85OHM_10INCH_DN")
	)
	(segment
		(start 172.632116 -166.321486)
		(end 172.080682 -166.418768)
		(width 0.1143)
		(layer "F.Cu")
		(net "L1_85OHM_10INCH_DN")
	)
	(segment
		(start 191.305688 -166.328852)
		(end 190.748412 -166.426642)
		(width 0.1143)
		(layer "F.Cu")
		(net "L1_85OHM_10INCH_DN")
	)
	(segment
		(start 193.274188 -163.63442)
		(end 192.91427 -163.697666)
		(width 0.1143)
		(layer "F.Cu")
		(net "L1_85OHM_10INCH_DN")
	)
	(segment
		(start 196.216778 -163.83635)
		(end 196.600064 -166.011606)
		(width 0.1143)
		(layer "F.Cu")
		(net "L1_85OHM_10INCH_DN")
	)
	(segment
		(start 171.215812 -163.659566)
		(end 170.85564 -163.722812)
		(width 0.1143)
		(layer "F.Cu")
		(net "L1_85OHM_10INCH_DN")
	)
	(segment
		(start 215.341454 -163.65347)
		(end 214.980774 -163.716462)
		(width 0.1143)
		(layer "F.Cu")
		(net "L1_85OHM_10INCH_DN")
	)
	(segment
		(start 184.926478 -163.753038)
		(end 184.794398 -163.660582)
		(width 0.1143)
		(layer "F.Cu")
		(net "L1_85OHM_10INCH_DN")
	)
	(segment
		(start 202.330558 -166.215568)
		(end 201.89317 -163.729162)
		(width 0.1143)
		(layer "F.Cu")
		(net "L1_85OHM_10INCH_DN")
	)
	(segment
		(start 198.936356 -166.214044)
		(end 198.497952 -163.725352)
		(width 0.1143)
		(layer "F.Cu")
		(net "L1_85OHM_10INCH_DN")
	)
	(segment
		(start 179.629816 -166.013638)
		(end 179.422298 -166.309802)
		(width 0.1143)
		(layer "F.Cu")
		(net "L1_85OHM_10INCH_DN")
	)
	(segment
		(start 183.226202 -163.73602)
		(end 183.094376 -163.643818)
		(width 0.1143)
		(layer "F.Cu")
		(net "L1_85OHM_10INCH_DN")
	)
	(segment
		(start 205.151482 -163.63442)
		(end 204.796898 -163.696904)
		(width 0.1143)
		(layer "F.Cu")
		(net "L1_85OHM_10INCH_DN")
	)
	(segment
		(start 159.826452 -164.937948)
		(end 158.741872 -165.021768)
		(width 0.1143)
		(layer "F.Cu")
		(net "L1_85OHM_10INCH_DN")
	)
	(segment
		(start 223.37268 -163.84397)
		(end 223.760284 -166.04234)
		(width 0.1143)
		(layer "F.Cu")
		(net "L1_85OHM_10INCH_DN")
	)
	(segment
		(start 190.45174 -166.219124)
		(end 190.017654 -163.75507)
		(width 0.1143)
		(layer "F.Cu")
		(net "L1_85OHM_10INCH_DN")
	)
	(segment
		(start 199.789542 -166.323264)
		(end 199.232266 -166.421054)
		(width 0.1143)
		(layer "F.Cu")
		(net "L1_85OHM_10INCH_DN")
	)
	(segment
		(start 220.36278 -166.02456)
		(end 220.15577 -166.320978)
		(width 0.1143)
		(layer "F.Cu")
		(net "L1_85OHM_10INCH_DN")
	)
	(segment
		(start 170.76293 -163.855146)
		(end 171.1452 -166.02456)
		(width 0.1143)
		(layer "F.Cu")
		(net "L1_85OHM_10INCH_DN")
	)
	(segment
		(start 227.557584 -165.035992)
		(end 227.046028 -165.035992)
		(width 0.1143)
		(layer "F.Cu")
		(net "L1_85OHM_10INCH_DN")
	)
	(segment
		(start 223.46539 -163.71189)
		(end 223.37268 -163.84397)
		(width 0.1143)
		(layer "F.Cu")
		(net "L1_85OHM_10INCH_DN")
	)
	(segment
		(start 209.415126 -166.413942)
		(end 209.118454 -166.206424)
		(width 0.1143)
		(layer "F.Cu")
		(net "L1_85OHM_10INCH_DN")
	)
	(segment
		(start 224.587816 -164.895022)
		(end 224.043494 -164.225478)
		(width 0.1143)
		(layer "F.Cu")
		(net "L1_85OHM_10INCH_DN")
	)
	(segment
		(start 216.204292 -166.41699)
		(end 215.907366 -166.20998)
		(width 0.1143)
		(layer "F.Cu")
		(net "L1_85OHM_10INCH_DN")
	)
	(segment
		(start 187.735464 -163.857432)
		(end 188.115702 -166.014908)
		(width 0.1143)
		(layer "F.Cu")
		(net "L1_85OHM_10INCH_DN")
	)
	(segment
		(start 204.324458 -166.423848)
		(end 204.027532 -166.21633)
		(width 0.1143)
		(layer "F.Cu")
		(net "L1_85OHM_10INCH_DN")
	)
	(segment
		(start 173.478952 -166.212774)
		(end 173.04512 -163.746688)
		(width 0.1143)
		(layer "F.Cu")
		(net "L1_85OHM_10INCH_DN")
	)
	(segment
		(start 186.417712 -166.00932)
		(end 186.210702 -166.306246)
		(width 0.1143)
		(layer "F.Cu")
		(net "L1_85OHM_10INCH_DN")
	)
	(segment
		(start 174.156624 -163.849812)
		(end 174.539656 -166.025576)
		(width 0.1143)
		(layer "F.Cu")
		(net "L1_85OHM_10INCH_DN")
	)
	(segment
		(start 224.043494 -164.225478)
		(end 223.957896 -163.740592)
		(width 0.1143)
		(layer "F.Cu")
		(net "L1_85OHM_10INCH_DN")
	)
	(segment
		(start 216.76106 -166.3192)
		(end 216.204292 -166.41699)
		(width 0.1143)
		(layer "F.Cu")
		(net "L1_85OHM_10INCH_DN")
	)
	(segment
		(start 177.550572 -163.846256)
		(end 177.93208 -166.009574)
		(width 0.1143)
		(layer "F.Cu")
		(net "L1_85OHM_10INCH_DN")
	)
	(segment
		(start 163.589208 -166.399464)
		(end 163.293298 -166.1922)
		(width 0.1143)
		(layer "F.Cu")
		(net "L1_85OHM_10INCH_DN")
	)
	(segment
		(start 196.600064 -166.011606)
		(end 196.3928 -166.30777)
		(width 0.1143)
		(layer "F.Cu")
		(net "L1_85OHM_10INCH_DN")
	)
	(segment
		(start 217.173556 -163.76269)
		(end 217.041476 -163.670234)
		(width 0.1143)
		(layer "F.Cu")
		(net "L1_85OHM_10INCH_DN")
	)
	(segment
		(start 175.17491 -166.204392)
		(end 174.742094 -163.74745)
		(width 0.1143)
		(layer "F.Cu")
		(net "L1_85OHM_10INCH_DN")
	)
	(segment
		(start 187.908692 -166.311326)
		(end 187.350908 -166.408862)
		(width 0.1143)
		(layer "F.Cu")
		(net "L1_85OHM_10INCH_DN")
	)
	(segment
		(start 172.45965 -163.849304)
		(end 172.842682 -166.02202)
		(width 0.1143)
		(layer "F.Cu")
		(net "L1_85OHM_10INCH_DN")
	)
	(segment
		(start 220.15577 -166.320978)
		(end 219.597986 -166.418514)
		(width 0.1143)
		(layer "F.Cu")
		(net "L1_85OHM_10INCH_DN")
	)
	(segment
		(start 207.421988 -166.216076)
		(end 206.983584 -163.72713)
		(width 0.1143)
		(layer "F.Cu")
		(net "L1_85OHM_10INCH_DN")
	)
	(segment
		(start 183.957214 -166.407338)
		(end 183.660288 -166.200328)
		(width 0.1143)
		(layer "F.Cu")
		(net "L1_85OHM_10INCH_DN")
	)
	(segment
		(start 172.080682 -166.418768)
		(end 171.78147 -166.209218)
		(width 0.1143)
		(layer "F.Cu")
		(net "L1_85OHM_10INCH_DN")
	)
	(segment
		(start 206.78521 -166.024052)
		(end 206.577692 -166.320216)
		(width 0.1143)
		(layer "F.Cu")
		(net "L1_85OHM_10INCH_DN")
	)
	(segment
		(start 182.733696 -163.70681)
		(end 182.64124 -163.83889)
		(width 0.1143)
		(layer "F.Cu")
		(net "L1_85OHM_10INCH_DN")
	)
	(segment
		(start 200.0631 -163.637722)
		(end 199.702928 -163.700968)
		(width 0.1143)
		(layer "F.Cu")
		(net "L1_85OHM_10INCH_DN")
	)
	(segment
		(start 180.562758 -166.4081)
		(end 180.265832 -166.200582)
		(width 0.1143)
		(layer "F.Cu")
		(net "L1_85OHM_10INCH_DN")
	)
	(segment
		(start 162.365944 -163.698428)
		(end 162.273234 -163.830762)
		(width 0.1143)
		(layer "F.Cu")
		(net "L1_85OHM_10INCH_DN")
	)
	(segment
		(start 179.832 -163.734496)
		(end 179.69992 -163.64204)
		(width 0.1143)
		(layer "F.Cu")
		(net "L1_85OHM_10INCH_DN")
	)
	(segment
		(start 167.748458 -166.008812)
		(end 167.541194 -166.304976)
		(width 0.1143)
		(layer "F.Cu")
		(net "L1_85OHM_10INCH_DN")
	)
	(segment
		(start 211.669376 -166.319454)
		(end 211.112862 -166.41699)
		(width 0.1143)
		(layer "F.Cu")
		(net "L1_85OHM_10INCH_DN")
	)
	(segment
		(start 215.06307 -166.31412)
		(end 214.506048 -166.41191)
		(width 0.1143)
		(layer "F.Cu")
		(net "L1_85OHM_10INCH_DN")
	)
	(segment
		(start 215.47328 -163.745672)
		(end 215.341454 -163.65347)
		(width 0.1143)
		(layer "F.Cu")
		(net "L1_85OHM_10INCH_DN")
	)
	(segment
		(start 200.633076 -166.212012)
		(end 200.195942 -163.730686)
		(width 0.1143)
		(layer "F.Cu")
		(net "L1_85OHM_10INCH_DN")
	)
	(segment
		(start 196.309488 -163.703508)
		(end 196.216778 -163.83635)
		(width 0.1143)
		(layer "F.Cu")
		(net "L1_85OHM_10INCH_DN")
	)
	(segment
		(start 165.763194 -163.715954)
		(end 165.670738 -163.848288)
		(width 0.1143)
		(layer "F.Cu")
		(net "L1_85OHM_10INCH_DN")
	)
	(segment
		(start 198.08952 -166.3065)
		(end 197.532244 -166.40429)
		(width 0.1143)
		(layer "F.Cu")
		(net "L1_85OHM_10INCH_DN")
	)
	(segment
		(start 197.23608 -166.197026)
		(end 196.802248 -163.733226)
		(width 0.1143)
		(layer "F.Cu")
		(net "L1_85OHM_10INCH_DN")
	)
	(segment
		(start 195.835524 -166.405814)
		(end 195.539614 -166.19855)
		(width 0.1143)
		(layer "F.Cu")
		(net "L1_85OHM_10INCH_DN")
	)
	(segment
		(start 191.125602 -163.834318)
		(end 191.513206 -166.032688)
		(width 0.1143)
		(layer "F.Cu")
		(net "L1_85OHM_10INCH_DN")
	)
	(segment
		(start 194.97548 -163.655756)
		(end 194.6148 -163.718748)
		(width 0.1143)
		(layer "F.Cu")
		(net "L1_85OHM_10INCH_DN")
	)
	(segment
		(start 188.755528 -166.22268)
		(end 188.32068 -163.754562)
		(width 0.1143)
		(layer "F.Cu")
		(net "L1_85OHM_10INCH_DN")
	)
	(segment
		(start 182.815992 -166.304468)
		(end 182.25897 -166.402258)
		(width 0.1143)
		(layer "F.Cu")
		(net "L1_85OHM_10INCH_DN")
	)
	(segment
		(start 219.597986 -166.418514)
		(end 219.301314 -166.211504)
		(width 0.1143)
		(layer "F.Cu")
		(net "L1_85OHM_10INCH_DN")
	)
	(segment
		(start 193.40703 -163.727384)
		(end 193.274188 -163.63442)
		(width 0.1143)
		(layer "F.Cu")
		(net "L1_85OHM_10INCH_DN")
	)
	(segment
		(start 186.130692 -163.722304)
		(end 186.038236 -163.854638)
		(width 0.1143)
		(layer "F.Cu")
		(net "L1_85OHM_10INCH_DN")
	)
	(segment
		(start 171.78147 -166.209218)
		(end 171.348654 -163.75253)
		(width 0.1143)
		(layer "F.Cu")
		(net "L1_85OHM_10INCH_DN")
	)
	(segment
		(start 169.15765 -163.717732)
		(end 169.06494 -163.850066)
		(width 0.1143)
		(layer "F.Cu")
		(net "L1_85OHM_10INCH_DN")
	)
	(segment
		(start 169.237914 -166.303706)
		(end 168.680638 -166.401496)
		(width 0.1143)
		(layer "F.Cu")
		(net "L1_85OHM_10INCH_DN")
	)
	(segment
		(start 174.249334 -163.717478)
		(end 174.156624 -163.849812)
		(width 0.1143)
		(layer "F.Cu")
		(net "L1_85OHM_10INCH_DN")
	)
	(segment
		(start 192.144904 -166.194994)
		(end 191.710818 -163.73094)
		(width 0.1143)
		(layer "F.Cu")
		(net "L1_85OHM_10INCH_DN")
	)
	(segment
		(start 172.842682 -166.02202)
		(end 172.632116 -166.321486)
		(width 0.1143)
		(layer "F.Cu")
		(net "L1_85OHM_10INCH_DN")
	)
	(segment
		(start 202.627484 -166.423086)
		(end 202.330558 -166.215568)
		(width 0.1143)
		(layer "F.Cu")
		(net "L1_85OHM_10INCH_DN")
	)
	(segment
		(start 164.990272 -166.192708)
		(end 164.555424 -163.72459)
		(width 0.1143)
		(layer "F.Cu")
		(net "L1_85OHM_10INCH_DN")
	)
	(segment
		(start 193.841878 -166.195502)
		(end 193.40703 -163.727384)
		(width 0.1143)
		(layer "F.Cu")
		(net "L1_85OHM_10INCH_DN")
	)
	(segment
		(start 181.32679 -166.013892)
		(end 181.119526 -166.31031)
		(width 0.1143)
		(layer "F.Cu")
		(net "L1_85OHM_10INCH_DN")
	)
	(segment
		(start 208.098644 -163.846764)
		(end 208.4832 -166.029132)
		(width 0.1143)
		(layer "F.Cu")
		(net "L1_85OHM_10INCH_DN")
	)
	(segment
		(start 209.118454 -166.206424)
		(end 208.866994 -164.781484)
		(width 0.1143)
		(layer "F.Cu")
		(net "L1_85OHM_10INCH_DN")
	)
	(segment
		(start 223.760284 -166.04234)
		(end 223.552766 -166.338504)
		(width 0.1143)
		(layer "F.Cu")
		(net "L1_85OHM_10INCH_DN")
	)
	(segment
		(start 196.669406 -163.640262)
		(end 196.309488 -163.703508)
		(width 0.1143)
		(layer "F.Cu")
		(net "L1_85OHM_10INCH_DN")
	)
	(segment
		(start 198.296784 -166.01059)
		(end 198.08952 -166.3065)
		(width 0.1143)
		(layer "F.Cu")
		(net "L1_85OHM_10INCH_DN")
	)
	(segment
		(start 166.123874 -163.652962)
		(end 165.763194 -163.715954)
		(width 0.1143)
		(layer "F.Cu")
		(net "L1_85OHM_10INCH_DN")
	)
	(segment
		(start 208.1911 -163.714684)
		(end 208.098644 -163.846764)
		(width 0.1143)
		(layer "F.Cu")
		(net "L1_85OHM_10INCH_DN")
	)
	(segment
		(start 211.586064 -163.715192)
		(end 211.493862 -163.847272)
		(width 0.1143)
		(layer "F.Cu")
		(net "L1_85OHM_10INCH_DN")
	)
	(segment
		(start 185.653426 -166.404036)
		(end 185.356754 -166.196518)
		(width 0.1143)
		(layer "F.Cu")
		(net "L1_85OHM_10INCH_DN")
	)
	(segment
		(start 176.871376 -166.196772)
		(end 176.673256 -165.0746)
		(width 0.1143)
		(layer "F.Cu")
		(net "L1_85OHM_10INCH_DN")
	)
	(segment
		(start 168.384474 -166.194232)
		(end 167.954198 -163.750752)
		(width 0.1143)
		(layer "F.Cu")
		(net "L1_85OHM_10INCH_DN")
	)
	(segment
		(start 216.58834 -163.865306)
		(end 216.968578 -166.023036)
		(width 0.1143)
		(layer "F.Cu")
		(net "L1_85OHM_10INCH_DN")
	)
	(segment
		(start 166.256716 -163.745672)
		(end 166.123874 -163.652962)
		(width 0.1143)
		(layer "F.Cu")
		(net "L1_85OHM_10INCH_DN")
	)
	(segment
		(start 209.972148 -166.316152)
		(end 209.415126 -166.413942)
		(width 0.1143)
		(layer "F.Cu")
		(net "L1_85OHM_10INCH_DN")
	)
	(segment
		(start 165.670738 -163.848288)
		(end 166.050976 -166.006018)
		(width 0.1143)
		(layer "F.Cu")
		(net "L1_85OHM_10INCH_DN")
	)
	(segment
		(start 210.38312 -163.75253)
		(end 210.25104 -163.660074)
		(width 0.1143)
		(layer "F.Cu")
		(net "L1_85OHM_10INCH_DN")
	)
	(segment
		(start 206.398622 -163.83)
		(end 206.78521 -166.024052)
		(width 0.1143)
		(layer "F.Cu")
		(net "L1_85OHM_10INCH_DN")
	)
	(segment
		(start 208.68386 -163.744148)
		(end 208.55178 -163.651692)
		(width 0.1143)
		(layer "F.Cu")
		(net "L1_85OHM_10INCH_DN")
	)
	(segment
		(start 213.19109 -163.851336)
		(end 213.573868 -166.023544)
		(width 0.1143)
		(layer "F.Cu")
		(net "L1_85OHM_10INCH_DN")
	)
	(segment
		(start 206.983584 -163.72713)
		(end 206.851758 -163.634928)
		(width 0.1143)
		(layer "F.Cu")
		(net "L1_85OHM_10INCH_DN")
	)
	(segment
		(start 165.843712 -166.301674)
		(end 165.286436 -166.399972)
		(width 0.1143)
		(layer "F.Cu")
		(net "L1_85OHM_10INCH_DN")
	)
	(segment
		(start 188.32068 -163.754562)
		(end 188.1886 -163.662106)
		(width 0.1143)
		(layer "F.Cu")
		(net "L1_85OHM_10INCH_DN")
	)
	(segment
		(start 178.003962 -163.650422)
		(end 177.643282 -163.713668)
		(width 0.1143)
		(layer "F.Cu")
		(net "L1_85OHM_10INCH_DN")
	)
	(segment
		(start 191.513206 -166.032688)
		(end 191.305688 -166.328852)
		(width 0.1143)
		(layer "F.Cu")
		(net "L1_85OHM_10INCH_DN")
	)
	(segment
		(start 206.851758 -163.634928)
		(end 206.491078 -163.69792)
		(width 0.1143)
		(layer "F.Cu")
		(net "L1_85OHM_10INCH_DN")
	)
	(segment
		(start 203.008484 -163.853368)
		(end 203.391516 -166.029386)
		(width 0.1143)
		(layer "F.Cu")
		(net "L1_85OHM_10INCH_DN")
	)
	(segment
		(start 203.5937 -163.750244)
		(end 203.46162 -163.657788)
		(width 0.1143)
		(layer "F.Cu")
		(net "L1_85OHM_10INCH_DN")
	)
	(segment
		(start 173.04512 -163.746688)
		(end 172.912278 -163.653724)
		(width 0.1143)
		(layer "F.Cu")
		(net "L1_85OHM_10INCH_DN")
	)
	(segment
		(start 183.02351 -166.008304)
		(end 182.815992 -166.304468)
		(width 0.1143)
		(layer "F.Cu")
		(net "L1_85OHM_10INCH_DN")
	)
	(segment
		(start 181.529482 -163.738052)
		(end 181.3941 -163.64331)
		(width 0.1143)
		(layer "F.Cu")
		(net "L1_85OHM_10INCH_DN")
	)
	(segment
		(start 170.937936 -166.32047)
		(end 170.38066 -166.41826)
		(width 0.1143)
		(layer "F.Cu")
		(net "L1_85OHM_10INCH_DN")
	)
	(segment
		(start 201.760328 -163.636198)
		(end 201.40041 -163.699444)
		(width 0.1143)
		(layer "F.Cu")
		(net "L1_85OHM_10INCH_DN")
	)
	(segment
		(start 194.522344 -163.851082)
		(end 194.902582 -166.008812)
		(width 0.1143)
		(layer "F.Cu")
		(net "L1_85OHM_10INCH_DN")
	)
	(segment
		(start 189.432946 -163.858448)
		(end 189.816486 -166.035482)
		(width 0.1143)
		(layer "F.Cu")
		(net "L1_85OHM_10INCH_DN")
	)
	(segment
		(start 192.440814 -166.402258)
		(end 192.144904 -166.194994)
		(width 0.1143)
		(layer "F.Cu")
		(net "L1_85OHM_10INCH_DN")
	)
	(segment
		(start 164.353748 -166.005002)
		(end 164.146484 -166.301166)
		(width 0.1143)
		(layer "F.Cu")
		(net "L1_85OHM_10INCH_DN")
	)
	(segment
		(start 161.060892 -165.14445)
		(end 159.826452 -164.937948)
		(width 0.1143)
		(layer "F.Cu")
		(net "L1_85OHM_10INCH_DN")
	)
	(segment
		(start 170.08475 -166.21125)
		(end 169.650664 -163.747196)
		(width 0.1143)
		(layer "F.Cu")
		(net "L1_85OHM_10INCH_DN")
	)
	(segment
		(start 201.483722 -166.32428)
		(end 200.932288 -166.421562)
		(width 0.1143)
		(layer "F.Cu")
		(net "L1_85OHM_10INCH_DN")
	)
	(segment
		(start 189.525402 -163.726114)
		(end 189.432946 -163.858448)
		(width 0.1143)
		(layer "F.Cu")
		(net "L1_85OHM_10INCH_DN")
	)
	(segment
		(start 210.25104 -163.660074)
		(end 209.89036 -163.72332)
		(width 0.1143)
		(layer "F.Cu")
		(net "L1_85OHM_10INCH_DN")
	)
	(segment
		(start 171.1452 -166.02456)
		(end 170.937936 -166.32047)
		(width 0.1143)
		(layer "F.Cu")
		(net "L1_85OHM_10INCH_DN")
	)
	(segment
		(start 181.119526 -166.31031)
		(end 180.562758 -166.4081)
		(width 0.1143)
		(layer "F.Cu")
		(net "L1_85OHM_10INCH_DN")
	)
	(segment
		(start 213.366604 -166.319962)
		(end 212.809836 -166.417752)
		(width 0.1143)
		(layer "F.Cu")
		(net "L1_85OHM_10INCH_DN")
	)
	(segment
		(start 177.72507 -166.3065)
		(end 177.168048 -166.40429)
		(width 0.1143)
		(layer "F.Cu")
		(net "L1_85OHM_10INCH_DN")
	)
	(segment
		(start 175.94707 -163.72078)
		(end 175.85436 -163.853622)
		(width 0.1143)
		(layer "F.Cu")
		(net "L1_85OHM_10INCH_DN")
	)
	(segment
		(start 173.774862 -166.419784)
		(end 173.478952 -166.212774)
		(width 0.1143)
		(layer "F.Cu")
		(net "L1_85OHM_10INCH_DN")
	)
	(segment
		(start 163.293298 -166.1922)
		(end 162.859212 -163.728146)
		(width 0.1143)
		(layer "F.Cu")
		(net "L1_85OHM_10INCH_DN")
	)
	(segment
		(start 180.944012 -163.841684)
		(end 181.32679 -166.013892)
		(width 0.1143)
		(layer "F.Cu")
		(net "L1_85OHM_10INCH_DN")
	)
	(segment
		(start 186.038236 -163.854638)
		(end 186.417712 -166.00932)
		(width 0.1143)
		(layer "F.Cu")
		(net "L1_85OHM_10INCH_DN")
	)
	(segment
		(start 184.7215 -166.013384)
		(end 184.513982 -166.309548)
		(width 0.1143)
		(layer "F.Cu")
		(net "L1_85OHM_10INCH_DN")
	)
	(segment
		(start 201.40041 -163.699444)
		(end 201.3077 -163.831778)
		(width 0.1143)
		(layer "F.Cu")
		(net "L1_85OHM_10INCH_DN")
	)
	(segment
		(start 209.79765 -163.855908)
		(end 210.179158 -166.019226)
		(width 0.1143)
		(layer "F.Cu")
		(net "L1_85OHM_10INCH_DN")
	)
	(segment
		(start 166.983918 -166.40302)
		(end 166.688008 -166.195756)
		(width 0.1143)
		(layer "F.Cu")
		(net "L1_85OHM_10INCH_DN")
	)
	(segment
		(start 218.66479 -166.018972)
		(end 218.45778 -166.315898)
		(width 0.1143)
		(layer "F.Cu")
		(net "L1_85OHM_10INCH_DN")
	)
	(segment
		(start 206.491078 -163.69792)
		(end 206.398622 -163.83)
		(width 0.1143)
		(layer "F.Cu")
		(net "L1_85OHM_10INCH_DN")
	)
	(segment
		(start 204.881226 -166.326058)
		(end 204.324458 -166.423848)
		(width 0.1143)
		(layer "F.Cu")
		(net "L1_85OHM_10INCH_DN")
	)
	(segment
		(start 169.06494 -163.850066)
		(end 169.445178 -166.007796)
		(width 0.1143)
		(layer "F.Cu")
		(net "L1_85OHM_10INCH_DN")
	)
	(segment
		(start 197.532244 -166.40429)
		(end 197.23608 -166.197026)
		(width 0.1143)
		(layer "F.Cu")
		(net "L1_85OHM_10INCH_DN")
	)
	(segment
		(start 201.89317 -163.729162)
		(end 201.760328 -163.636198)
		(width 0.1143)
		(layer "F.Cu")
		(net "L1_85OHM_10INCH_DN")
	)
	(segment
		(start 178.865784 -166.407338)
		(end 178.568858 -166.19982)
		(width 0.1143)
		(layer "F.Cu")
		(net "L1_85OHM_10INCH_DN")
	)
	(segment
		(start 174.333154 -166.32174)
		(end 173.774862 -166.419784)
		(width 0.1143)
		(layer "F.Cu")
		(net "L1_85OHM_10INCH_DN")
	)
	(segment
		(start 206.577692 -166.320216)
		(end 206.02067 -166.418006)
		(width 0.1143)
		(layer "F.Cu")
		(net "L1_85OHM_10INCH_DN")
	)
	(segment
		(start 188.115702 -166.014908)
		(end 187.908692 -166.311326)
		(width 0.1143)
		(layer "F.Cu")
		(net "L1_85OHM_10INCH_DN")
	)
	(segment
		(start 195.539614 -166.19855)
		(end 195.108322 -163.748466)
		(width 0.1143)
		(layer "F.Cu")
		(net "L1_85OHM_10INCH_DN")
	)
	(segment
		(start 196.3928 -166.30777)
		(end 195.835524 -166.405814)
		(width 0.1143)
		(layer "F.Cu")
		(net "L1_85OHM_10INCH_DN")
	)
	(segment
		(start 217.603832 -166.20617)
		(end 217.173556 -163.76269)
		(width 0.1143)
		(layer "F.Cu")
		(net "L1_85OHM_10INCH_DN")
	)
	(segment
		(start 199.232266 -166.421054)
		(end 198.936356 -166.214044)
		(width 0.1143)
		(layer "F.Cu")
		(net "L1_85OHM_10INCH_DN")
	)
	(segment
		(start 205.08849 -166.02964)
		(end 204.881226 -166.326058)
		(width 0.1143)
		(layer "F.Cu")
		(net "L1_85OHM_10INCH_DN")
	)
	(segment
		(start 193.205354 -166.007796)
		(end 192.99809 -166.30396)
		(width 0.1143)
		(layer "F.Cu")
		(net "L1_85OHM_10INCH_DN")
	)
	(segment
		(start 190.017654 -163.75507)
		(end 189.885574 -163.662614)
		(width 0.1143)
		(layer "F.Cu")
		(net "L1_85OHM_10INCH_DN")
	)
	(segment
		(start 208.275682 -166.325296)
		(end 207.718914 -166.423086)
		(width 0.1143)
		(layer "F.Cu")
		(net "L1_85OHM_10INCH_DN")
	)
	(segment
		(start 195.108322 -163.748466)
		(end 194.97548 -163.655756)
		(width 0.1143)
		(layer "F.Cu")
		(net "L1_85OHM_10INCH_DN")
	)
	(segment
		(start 211.493862 -163.847272)
		(end 211.876894 -166.02329)
		(width 0.1143)
		(layer "F.Cu")
		(net "L1_85OHM_10INCH_DN")
	)
	(segment
		(start 213.641178 -163.652962)
		(end 213.286594 -163.715446)
		(width 0.1143)
		(layer "F.Cu")
		(net "L1_85OHM_10INCH_DN")
	)
	(segment
		(start 199.610218 -163.833302)
		(end 199.996806 -166.027354)
		(width 0.1143)
		(layer "F.Cu")
		(net "L1_85OHM_10INCH_DN")
	)
	(segment
		(start 164.555424 -163.72459)
		(end 164.422582 -163.631626)
		(width 0.1143)
		(layer "F.Cu")
		(net "L1_85OHM_10INCH_DN")
	)
	(segment
		(start 180.265832 -166.200582)
		(end 179.832 -163.734496)
		(width 0.1143)
		(layer "F.Cu")
		(net "L1_85OHM_10INCH_DN")
	)
	(segment
		(start 161.508186 -165.694614)
		(end 161.060892 -165.14445)
		(width 0.1143)
		(layer "F.Cu")
		(net "L1_85OHM_10INCH_DN")
	)
	(segment
		(start 219.301314 -166.211504)
		(end 218.870022 -163.761166)
		(width 0.1143)
		(layer "F.Cu")
		(net "L1_85OHM_10INCH_DN")
	)
	(segment
		(start 184.341262 -163.855654)
		(end 184.7215 -166.013384)
		(width 0.1143)
		(layer "F.Cu")
		(net "L1_85OHM_10INCH_DN")
	)
	(segment
		(start 161.600134 -166.216584)
		(end 161.508186 -165.694614)
		(width 0.1143)
		(layer "F.Cu")
		(net "L1_85OHM_10INCH_DN")
	)
	(segment
		(start 182.64124 -163.83889)
		(end 183.02351 -166.008304)
		(width 0.1143)
		(layer "F.Cu")
		(net "L1_85OHM_10INCH_DN")
	)
	(segment
		(start 167.461438 -163.721034)
		(end 167.368728 -163.853876)
		(width 0.1143)
		(layer "F.Cu")
		(net "L1_85OHM_10INCH_DN")
	)
	(segment
		(start 194.138042 -166.402766)
		(end 193.841878 -166.195502)
		(width 0.1143)
		(layer "F.Cu")
		(net "L1_85OHM_10INCH_DN")
	)
	(segment
		(start 221.77248 -163.735766)
		(end 221.680024 -163.8681)
		(width 0.1143)
		(layer "F.Cu")
		(net "L1_85OHM_10INCH_DN")
	)
	(segment
		(start 213.573868 -166.023544)
		(end 213.366604 -166.319962)
		(width 0.1143)
		(layer "F.Cu")
		(net "L1_85OHM_10INCH_DN")
	)
	(segment
		(start 204.701394 -163.832794)
		(end 205.08849 -166.02964)
		(width 0.1143)
		(layer "F.Cu")
		(net "L1_85OHM_10INCH_DN")
	)
	(segment
		(start 175.85436 -163.853622)
		(end 176.235868 -166.017194)
		(width 0.1143)
		(layer "F.Cu")
		(net "L1_85OHM_10INCH_DN")
	)
	(segment
		(start 189.816486 -166.035482)
		(end 189.609476 -166.332408)
		(width 0.1143)
		(layer "F.Cu")
		(net "L1_85OHM_10INCH_DN")
	)
	(segment
		(start 176.02835 -166.313612)
		(end 175.47082 -166.411402)
		(width 0.1143)
		(layer "F.Cu")
		(net "L1_85OHM_10INCH_DN")
	)
	(segment
		(start 175.47082 -166.411402)
		(end 175.17491 -166.204392)
		(width 0.1143)
		(layer "F.Cu")
		(net "L1_85OHM_10INCH_DN")
	)
	(segment
		(start 192.82156 -163.830508)
		(end 193.205354 -166.007796)
		(width 0.1143)
		(layer "F.Cu")
		(net "L1_85OHM_10INCH_DN")
	)
	(segment
		(start 183.660288 -166.200328)
		(end 183.226202 -163.73602)
		(width 0.1143)
		(layer "F.Cu")
		(net "L1_85OHM_10INCH_DN")
	)
	(segment
		(start 222.063564 -166.045134)
		(end 221.856554 -166.34206)
		(width 0.1143)
		(layer "F.Cu")
		(net "L1_85OHM_10INCH_DN")
	)
	(segment
		(start 203.46162 -163.657788)
		(end 203.100686 -163.721288)
		(width 0.1143)
		(layer "F.Cu")
		(net "L1_85OHM_10INCH_DN")
	)
	(segment
		(start 221.856554 -166.34206)
		(end 221.299278 -166.43985)
		(width 0.1143)
		(layer "F.Cu")
		(net "L1_85OHM_10INCH_DN")
	)
	(segment
		(start 222.264732 -163.764722)
		(end 222.132652 -163.672266)
		(width 0.1143)
		(layer "F.Cu")
		(net "L1_85OHM_10INCH_DN")
	)
	(segment
		(start 206.02067 -166.418006)
		(end 205.723998 -166.210488)
		(width 0.1143)
		(layer "F.Cu")
		(net "L1_85OHM_10INCH_DN")
	)
	(segment
		(start 220.075252 -163.735258)
		(end 219.982542 -163.867084)
		(width 0.1143)
		(layer "F.Cu")
		(net "L1_85OHM_10INCH_DN")
	)
	(segment
		(start 181.962298 -166.19474)
		(end 181.529482 -163.738052)
		(width 0.1143)
		(layer "F.Cu")
		(net "L1_85OHM_10INCH_DN")
	)
	(segment
		(start 176.306734 -163.657534)
		(end 175.94707 -163.72078)
		(width 0.1143)
		(layer "F.Cu")
		(net "L1_85OHM_10INCH_DN")
	)
	(segment
		(start 223.552766 -166.338504)
		(end 222.99549 -166.436294)
		(width 0.1143)
		(layer "F.Cu")
		(net "L1_85OHM_10INCH_DN")
	)
	(segment
		(start 220.435678 -163.671758)
		(end 220.075252 -163.735258)
		(width 0.1143)
		(layer "F.Cu")
		(net "L1_85OHM_10INCH_DN")
	)
	(segment
		(start 194.695318 -166.304468)
		(end 194.138042 -166.402766)
		(width 0.1143)
		(layer "F.Cu")
		(net "L1_85OHM_10INCH_DN")
	)
	(segment
		(start 162.859212 -163.728146)
		(end 162.72637 -163.635182)
		(width 0.1143)
		(layer "F.Cu")
		(net "L1_85OHM_10INCH_DN")
	)
	(segment
		(start 166.050976 -166.006018)
		(end 165.843712 -166.301674)
		(width 0.1143)
		(layer "F.Cu")
		(net "L1_85OHM_10INCH_DN")
	)
	(segment
		(start 179.338986 -163.70554)
		(end 179.246784 -163.83762)
		(width 0.1143)
		(layer "F.Cu")
		(net "L1_85OHM_10INCH_DN")
	)
	(segment
		(start 177.643282 -163.713668)
		(end 177.550572 -163.846256)
		(width 0.1143)
		(layer "F.Cu")
		(net "L1_85OHM_10INCH_DN")
	)
	(segment
		(start 198.004938 -163.695888)
		(end 197.912228 -163.828222)
		(width 0.1143)
		(layer "F.Cu")
		(net "L1_85OHM_10INCH_DN")
	)
	(segment
		(start 215.270588 -166.017956)
		(end 215.06307 -166.31412)
		(width 0.1143)
		(layer "F.Cu")
		(net "L1_85OHM_10INCH_DN")
	)
	(segment
		(start 198.497952 -163.725352)
		(end 198.36511 -163.632642)
		(width 0.1143)
		(layer "F.Cu")
		(net "L1_85OHM_10INCH_DN")
	)
	(segment
		(start 203.391516 -166.029386)
		(end 203.183998 -166.32555)
		(width 0.1143)
		(layer "F.Cu")
		(net "L1_85OHM_10INCH_DN")
	)
	(segment
		(start 148.255228 11.93165)
		(end 197.31101 11.93165)
		(width 0.1651)
		(layer "F.Cu")
		(net "L1_73OHM_6INCH_DP")
	)
	(segment
		(start 145.558002 11.868404)
		(end 119.804434 11.868404)
		(width 0.1651)
		(layer "F.Cu")
		(net "L1_73OHM_6INCH_DP")
	)
	(segment
		(start 196.843396 10.34415)
		(end 148.255228 10.34415)
		(width 0.1651)
		(layer "F.Cu")
		(net "L1_73OHM_6INCH_DP")
	)
	(segment
		(start 146.624548 12.93495)
		(end 145.558002 11.868404)
		(width 0.1651)
		(layer "F.Cu")
		(net "L1_73OHM_6INCH_DP")
	)
	(segment
		(start 119.804434 11.868404)
		(end 118.680484 10.744454)
		(width 0.1651)
		(layer "F.Cu")
		(net "L1_73OHM_6INCH_DP")
	)
	(segment
		(start 197.31101 12.93495)
		(end 146.624548 12.93495)
		(width 0.1651)
		(layer "F.Cu")
		(net "L1_73OHM_6INCH_DP")
	)
	(arc
		(start 148.255228 10.34415)
		(mid 147.461478 11.1379)
		(end 148.255228 11.93165)
		(width 0.1651)
		(layer "F.Cu")
		(net "L1_73OHM_6INCH_DP")
	)
	(arc
		(start 197.31101 11.93165)
		(mid 197.81266 12.4333)
		(end 197.31101 12.93495)
		(width 0.1651)
		(layer "F.Cu")
		(net "L1_73OHM_6INCH_DP")
	)
	(segment
		(start 196.843396 10.63625)
		(end 148.255228 10.63625)
		(width 0.1651)
		(layer "F.Cu")
		(net "L1_73OHM_6INCH_DN")
	)
	(segment
		(start 197.31101 13.22705)
		(end 146.50339 13.22705)
		(width 0.1651)
		(layer "F.Cu")
		(net "L1_73OHM_6INCH_DN")
	)
	(segment
		(start 145.436844 12.160504)
		(end 119.804434 12.160504)
		(width 0.1651)
		(layer "F.Cu")
		(net "L1_73OHM_6INCH_DN")
	)
	(segment
		(start 119.804434 12.160504)
		(end 118.680484 13.284454)
		(width 0.1651)
		(layer "F.Cu")
		(net "L1_73OHM_6INCH_DN")
	)
	(segment
		(start 148.255228 11.63955)
		(end 197.31101 11.63955)
		(width 0.1651)
		(layer "F.Cu")
		(net "L1_73OHM_6INCH_DN")
	)
	(segment
		(start 146.50339 13.22705)
		(end 145.436844 12.160504)
		(width 0.1651)
		(layer "F.Cu")
		(net "L1_73OHM_6INCH_DN")
	)
	(arc
		(start 197.31101 11.63955)
		(mid 198.10476 12.4333)
		(end 197.31101 13.22705)
		(width 0.1651)
		(layer "F.Cu")
		(net "L1_73OHM_6INCH_DN")
	)
	(arc
		(start 148.255228 10.63625)
		(mid 147.753578 11.1379)
		(end 148.255228 11.63955)
		(width 0.1651)
		(layer "F.Cu")
		(net "L1_73OHM_6INCH_DN")
	)
	(segment
		(start 37.820854 12.807442)
		(end 113.14938 12.807442)
		(width 0.10795)
		(layer "F.Cu")
		(net "L1_50OHM_6INCH")
	)
	(segment
		(start 113.14938 13.677392)
		(end 37.435028 13.677392)
		(width 0.10795)
		(layer "F.Cu")
		(net "L1_50OHM_6INCH")
	)
	(segment
		(start 11.303 14.2875)
		(end 10.287 13.2715)
		(width 0.10795)
		(layer "F.Cu")
		(net "L1_50OHM_6INCH")
	)
	(segment
		(start 36.82492 14.2875)
		(end 11.303 14.2875)
		(width 0.10795)
		(layer "F.Cu")
		(net "L1_50OHM_6INCH")
	)
	(segment
		(start 37.435028 13.677392)
		(end 36.82492 14.2875)
		(width 0.10795)
		(layer "F.Cu")
		(net "L1_50OHM_6INCH")
	)
	(arc
		(start 113.14938 12.807442)
		(mid 113.584482 13.242544)
		(end 113.14938 13.677392)
		(width 0.10795)
		(layer "F.Cu")
		(net "L1_50OHM_6INCH")
	)
	(segment
		(start 112.540034 11.66241)
		(end 36.97859 11.66241)
		(width 0.1651)
		(layer "F.Cu")
		(net "L1_40OHM_6INCH")
	)
	(segment
		(start 36.97859 11.66241)
		(end 36.6395 12.0015)
		(width 0.1651)
		(layer "F.Cu")
		(net "L1_40OHM_6INCH")
	)
	(segment
		(start 37.15766 10.73531)
		(end 112.540034 10.73531)
		(width 0.1651)
		(layer "F.Cu")
		(net "L1_40OHM_6INCH")
	)
	(segment
		(start 11.557 12.0015)
		(end 10.287 10.7315)
		(width 0.1651)
		(layer "F.Cu")
		(net "L1_40OHM_6INCH")
	)
	(segment
		(start 36.6395 12.0015)
		(end 11.557 12.0015)
		(width 0.1651)
		(layer "F.Cu")
		(net "L1_40OHM_6INCH")
	)
	(arc
		(start 112.540034 10.73531)
		(mid 113.003584 11.19886)
		(end 112.540034 11.66241)
		(width 0.1651)
		(layer "F.Cu")
		(net "L1_40OHM_6INCH")
	)
	(segment
		(start 422.570148 10.060432)
		(end 373.585486 10.060432)
		(width 0.101854)
		(layer "F.Cu")
		(net "L1_100OHM_6INCH_DP")
	)
	(segment
		(start 373.585994 11.914886)
		(end 422.273222 11.914886)
		(width 0.101854)
		(layer "F.Cu")
		(net "L1_100OHM_6INCH_DP")
	)
	(segment
		(start 370.854478 11.774678)
		(end 354.674932 11.774678)
		(width 0.101854)
		(layer "F.Cu")
		(net "L1_100OHM_6INCH_DP")
	)
	(segment
		(start 371.93474 12.85494)
		(end 370.854478 11.774678)
		(width 0.101854)
		(layer "F.Cu")
		(net "L1_100OHM_6INCH_DP")
	)
	(segment
		(start 354.674932 11.774678)
		(end 353.633532 10.733278)
		(width 0.101854)
		(layer "F.Cu")
		(net "L1_100OHM_6INCH_DP")
	)
	(segment
		(start 422.273222 12.85494)
		(end 371.93474 12.85494)
		(width 0.101854)
		(layer "F.Cu")
		(net "L1_100OHM_6INCH_DP")
	)
	(arc
		(start 373.585486 10.060432)
		(mid 372.65864 10.987786)
		(end 373.585994 11.914886)
		(width 0.101854)
		(layer "F.Cu")
		(net "L1_100OHM_6INCH_DP")
	)
	(arc
		(start 422.273222 11.914886)
		(mid 422.743376 12.38504)
		(end 422.273222 12.85494)
		(width 0.101854)
		(layer "F.Cu")
		(net "L1_100OHM_6INCH_DP")
	)
	(segment
		(start 422.273222 13.31214)
		(end 371.745256 13.31214)
		(width 0.101854)
		(layer "F.Cu")
		(net "L1_100OHM_6INCH_DN")
	)
	(segment
		(start 373.58574 11.457686)
		(end 422.273222 11.457686)
		(width 0.101854)
		(layer "F.Cu")
		(net "L1_100OHM_6INCH_DN")
	)
	(segment
		(start 354.674932 12.231878)
		(end 353.633532 13.273278)
		(width 0.101854)
		(layer "F.Cu")
		(net "L1_100OHM_6INCH_DN")
	)
	(segment
		(start 371.745256 13.31214)
		(end 370.664994 12.231878)
		(width 0.101854)
		(layer "F.Cu")
		(net "L1_100OHM_6INCH_DN")
	)
	(segment
		(start 370.664994 12.231878)
		(end 354.674932 12.231878)
		(width 0.101854)
		(layer "F.Cu")
		(net "L1_100OHM_6INCH_DN")
	)
	(segment
		(start 422.570148 10.517632)
		(end 373.58574 10.517632)
		(width 0.101854)
		(layer "F.Cu")
		(net "L1_100OHM_6INCH_DN")
	)
	(arc
		(start 373.58574 10.517632)
		(mid 373.115586 10.987786)
		(end 373.58574 11.457686)
		(width 0.101854)
		(layer "F.Cu")
		(net "L1_100OHM_6INCH_DN")
	)
	(arc
		(start 422.273222 11.457686)
		(mid 423.200576 12.38504)
		(end 422.273222 13.31214)
		(width 0.101854)
		(layer "F.Cu")
		(net "L1_100OHM_6INCH_DN")
	)
	(segment
		(start 229.491286 11.831828)
		(end 228.341936 10.682478)
		(width 0.1143)
		(layer "B.Cu")
		(net "L14_85OHM_6INCH_DP")
	)
	(segment
		(start 279.908 10.536174)
		(end 232.2068 10.536174)
		(width 0.1143)
		(layer "B.Cu")
		(net "L14_85OHM_6INCH_DP")
	)
	(segment
		(start 230.195628 11.831828)
		(end 229.491286 11.831828)
		(width 0.1143)
		(layer "B.Cu")
		(net "L14_85OHM_6INCH_DP")
	)
	(segment
		(start 232.2068 11.971274)
		(end 280.288746 11.971274)
		(width 0.1143)
		(layer "B.Cu")
		(net "L14_85OHM_6INCH_DP")
	)
	(segment
		(start 280.288746 12.923774)
		(end 231.287574 12.923774)
		(width 0.1143)
		(layer "B.Cu")
		(net "L14_85OHM_6INCH_DP")
	)
	(segment
		(start 231.287574 12.923774)
		(end 230.195628 11.831828)
		(width 0.1143)
		(layer "B.Cu")
		(net "L14_85OHM_6INCH_DP")
	)
	(arc
		(start 232.2068 10.536174)
		(mid 231.48925 11.253724)
		(end 232.2068 11.971274)
		(width 0.1143)
		(layer "B.Cu")
		(net "L14_85OHM_6INCH_DP")
	)
	(arc
		(start 280.288746 11.971274)
		(mid 280.764996 12.447524)
		(end 280.288746 12.923774)
		(width 0.1143)
		(layer "B.Cu")
		(net "L14_85OHM_6INCH_DP")
	)
	(segment
		(start 280.289 13.165074)
		(end 231.187498 13.165074)
		(width 0.1143)
		(layer "B.Cu")
		(net "L14_85OHM_6INCH_DN")
	)
	(segment
		(start 279.908 10.777474)
		(end 232.2068 10.777474)
		(width 0.1143)
		(layer "B.Cu")
		(net "L14_85OHM_6INCH_DN")
	)
	(segment
		(start 230.095552 12.073128)
		(end 229.491286 12.073128)
		(width 0.1143)
		(layer "B.Cu")
		(net "L14_85OHM_6INCH_DN")
	)
	(segment
		(start 231.187498 13.165074)
		(end 230.095552 12.073128)
		(width 0.1143)
		(layer "B.Cu")
		(net "L14_85OHM_6INCH_DN")
	)
	(segment
		(start 229.491286 12.073128)
		(end 228.341936 13.222478)
		(width 0.1143)
		(layer "B.Cu")
		(net "L14_85OHM_6INCH_DN")
	)
	(segment
		(start 232.2068 11.729974)
		(end 280.289 11.729974)
		(width 0.1143)
		(layer "B.Cu")
		(net "L14_85OHM_6INCH_DN")
	)
	(arc
		(start 232.2068 10.777474)
		(mid 231.73055 11.253724)
		(end 232.2068 11.729974)
		(width 0.1143)
		(layer "B.Cu")
		(net "L14_85OHM_6INCH_DN")
	)
	(arc
		(start 280.289 11.729974)
		(mid 281.00655 12.447524)
		(end 280.289 13.165074)
		(width 0.1143)
		(layer "B.Cu")
		(net "L14_85OHM_6INCH_DN")
	)
	(segment
		(start 24.13127 -163.612068)
		(end 23.92426 -163.908994)
		(width 0.1143)
		(layer "B.Cu")
		(net "L14_85OHM_5INCH_DP")
	)
	(segment
		(start 27.247596 -166.274496)
		(end 27.11577 -166.182294)
		(width 0.1143)
		(layer "B.Cu")
		(net "L14_85OHM_5INCH_DP")
	)
	(segment
		(start 40.254428 -163.691062)
		(end 39.958518 -163.484052)
		(width 0.1143)
		(layer "B.Cu")
		(net "L14_85OHM_5INCH_DP")
	)
	(segment
		(start 28.083002 -163.516056)
		(end 27.52598 -163.613846)
		(width 0.1143)
		(layer "B.Cu")
		(net "L14_85OHM_5INCH_DP")
	)
	(segment
		(start 40.688514 -166.155116)
		(end 40.254428 -163.691062)
		(width 0.1143)
		(layer "B.Cu")
		(net "L14_85OHM_5INCH_DP")
	)
	(segment
		(start 52.500784 -164.519356)
		(end 52.11826 -164.880544)
		(width 0.1143)
		(layer "B.Cu")
		(net "L14_85OHM_5INCH_DP")
	)
	(segment
		(start 38.258496 -163.483544)
		(end 37.707062 -163.580826)
		(width 0.1143)
		(layer "B.Cu")
		(net "L14_85OHM_5INCH_DP")
	)
	(segment
		(start 41.954704 -163.70808)
		(end 41.65854 -163.500816)
		(width 0.1143)
		(layer "B.Cu")
		(net "L14_85OHM_5INCH_DP")
	)
	(segment
		(start 19.12366 -166.216076)
		(end 18.763234 -166.279576)
		(width 0.1143)
		(layer "B.Cu")
		(net "L14_85OHM_5INCH_DP")
	)
	(segment
		(start 36.006024 -163.580572)
		(end 35.799522 -163.876736)
		(width 0.1143)
		(layer "B.Cu")
		(net "L14_85OHM_5INCH_DP")
	)
	(segment
		(start 20.324318 -166.163244)
		(end 19.890232 -163.69919)
		(width 0.1143)
		(layer "B.Cu")
		(net "L14_85OHM_5INCH_DP")
	)
	(segment
		(start 39.193978 -163.877752)
		(end 39.576248 -166.047166)
		(width 0.1143)
		(layer "B.Cu")
		(net "L14_85OHM_5INCH_DP")
	)
	(segment
		(start 32.616902 -163.611814)
		(end 32.409892 -163.90874)
		(width 0.1143)
		(layer "B.Cu")
		(net "L14_85OHM_5INCH_DP")
	)
	(segment
		(start 26.681684 -163.717986)
		(end 26.384758 -163.510976)
		(width 0.1143)
		(layer "B.Cu")
		(net "L14_85OHM_5INCH_DP")
	)
	(segment
		(start 35.597084 -166.154862)
		(end 35.164268 -163.69792)
		(width 0.1143)
		(layer "B.Cu")
		(net "L14_85OHM_5INCH_DP")
	)
	(segment
		(start 42.517822 -166.244524)
		(end 42.38498 -166.15156)
		(width 0.1143)
		(layer "B.Cu")
		(net "L14_85OHM_5INCH_DP")
	)
	(segment
		(start 51.597306 -164.880544)
		(end 50.512726 -164.964364)
		(width 0.1143)
		(layer "B.Cu")
		(net "L14_85OHM_5INCH_DP")
	)
	(segment
		(start 42.97045 -166.048436)
		(end 42.87774 -166.181278)
		(width 0.1143)
		(layer "B.Cu")
		(net "L14_85OHM_5INCH_DP")
	)
	(segment
		(start 22.22627 -163.903406)
		(end 22.606508 -166.060882)
		(width 0.1143)
		(layer "B.Cu")
		(net "L14_85OHM_5INCH_DP")
	)
	(segment
		(start 36.089844 -166.184834)
		(end 35.73018 -166.247826)
		(width 0.1143)
		(layer "B.Cu")
		(net "L14_85OHM_5INCH_DP")
	)
	(segment
		(start 29.302456 -166.21252)
		(end 28.947872 -166.275004)
		(width 0.1143)
		(layer "B.Cu")
		(net "L14_85OHM_5INCH_DP")
	)
	(segment
		(start 22.606508 -166.060882)
		(end 22.513798 -166.192708)
		(width 0.1143)
		(layer "B.Cu")
		(net "L14_85OHM_5INCH_DP")
	)
	(segment
		(start 47.973234 -166.203884)
		(end 47.612808 -166.26713)
		(width 0.1143)
		(layer "B.Cu")
		(net "L14_85OHM_5INCH_DP")
	)
	(segment
		(start 31.002986 -166.212774)
		(end 30.642052 -166.276274)
		(width 0.1143)
		(layer "B.Cu")
		(net "L14_85OHM_5INCH_DP")
	)
	(segment
		(start 27.11577 -166.182294)
		(end 26.681684 -163.717986)
		(width 0.1143)
		(layer "B.Cu")
		(net "L14_85OHM_5INCH_DP")
	)
	(segment
		(start 30.07614 -163.717732)
		(end 29.779214 -163.510214)
		(width 0.1143)
		(layer "B.Cu")
		(net "L14_85OHM_5INCH_DP")
	)
	(segment
		(start 28.947872 -166.275004)
		(end 28.81249 -166.180262)
		(width 0.1143)
		(layer "B.Cu")
		(net "L14_85OHM_5INCH_DP")
	)
	(segment
		(start 48.44288 -163.479226)
		(end 47.885604 -163.57727)
		(width 0.1143)
		(layer "B.Cu")
		(net "L14_85OHM_5INCH_DP")
	)
	(segment
		(start 44.082462 -166.15664)
		(end 43.65117 -163.706556)
		(width 0.1143)
		(layer "B.Cu")
		(net "L14_85OHM_5INCH_DP")
	)
	(segment
		(start 29.015182 -163.904422)
		(end 29.39796 -166.07663)
		(width 0.1143)
		(layer "B.Cu")
		(net "L14_85OHM_5INCH_DP")
	)
	(segment
		(start 30.642052 -166.276274)
		(end 30.509972 -166.183818)
		(width 0.1143)
		(layer "B.Cu")
		(net "L14_85OHM_5INCH_DP")
	)
	(segment
		(start 50.512726 -164.964364)
		(end 49.278286 -164.757862)
		(width 0.1143)
		(layer "B.Cu")
		(net "L14_85OHM_5INCH_DP")
	)
	(segment
		(start 20.456398 -166.2557)
		(end 20.324318 -166.163244)
		(width 0.1143)
		(layer "B.Cu")
		(net "L14_85OHM_5INCH_DP")
	)
	(segment
		(start 23.287736 -163.716462)
		(end 22.991064 -163.509452)
		(width 0.1143)
		(layer "B.Cu")
		(net "L14_85OHM_5INCH_DP")
	)
	(segment
		(start 32.33801 -166.267892)
		(end 32.20593 -166.175436)
		(width 0.1143)
		(layer "B.Cu")
		(net "L14_85OHM_5INCH_DP")
	)
	(segment
		(start 41.101264 -163.598606)
		(end 40.894 -163.894516)
		(width 0.1143)
		(layer "B.Cu")
		(net "L14_85OHM_5INCH_DP")
	)
	(segment
		(start 35.799522 -163.876736)
		(end 36.182554 -166.0525)
		(width 0.1143)
		(layer "B.Cu")
		(net "L14_85OHM_5INCH_DP")
	)
	(segment
		(start 40.894 -163.894516)
		(end 41.274238 -166.052246)
		(width 0.1143)
		(layer "B.Cu")
		(net "L14_85OHM_5INCH_DP")
	)
	(segment
		(start 49.278286 -164.757862)
		(end 48.830992 -164.207698)
		(width 0.1143)
		(layer "B.Cu")
		(net "L14_85OHM_5INCH_DP")
	)
	(segment
		(start 46.369224 -166.074598)
		(end 46.276514 -166.20744)
		(width 0.1143)
		(layer "B.Cu")
		(net "L14_85OHM_5INCH_DP")
	)
	(segment
		(start 46.276514 -166.20744)
		(end 45.916596 -166.270686)
		(width 0.1143)
		(layer "B.Cu")
		(net "L14_85OHM_5INCH_DP")
	)
	(segment
		(start 31.773114 -163.718494)
		(end 31.476188 -163.510976)
		(width 0.1143)
		(layer "B.Cu")
		(net "L14_85OHM_5INCH_DP")
	)
	(segment
		(start 18.001234 -165.032944)
		(end 16.647668 -164.806376)
		(width 0.1143)
		(layer "B.Cu")
		(net "L14_85OHM_5INCH_DP")
	)
	(segment
		(start 27.608276 -166.211504)
		(end 27.247596 -166.274496)
		(width 0.1143)
		(layer "B.Cu")
		(net "L14_85OHM_5INCH_DP")
	)
	(segment
		(start 35.73018 -166.247826)
		(end 35.597084 -166.154862)
		(width 0.1143)
		(layer "B.Cu")
		(net "L14_85OHM_5INCH_DP")
	)
	(segment
		(start 26.00071 -166.06266)
		(end 25.908254 -166.19474)
		(width 0.1143)
		(layer "B.Cu")
		(net "L14_85OHM_5INCH_DP")
	)
	(segment
		(start 43.65117 -163.706556)
		(end 43.35526 -163.499292)
		(width 0.1143)
		(layer "B.Cu")
		(net "L14_85OHM_5INCH_DP")
	)
	(segment
		(start 42.797984 -163.597336)
		(end 42.59072 -163.8935)
		(width 0.1143)
		(layer "B.Cu")
		(net "L14_85OHM_5INCH_DP")
	)
	(segment
		(start 43.35526 -163.499292)
		(end 42.797984 -163.597336)
		(width 0.1143)
		(layer "B.Cu")
		(net "L14_85OHM_5INCH_DP")
	)
	(segment
		(start 44.495466 -163.600638)
		(end 44.288202 -163.896294)
		(width 0.1143)
		(layer "B.Cu")
		(net "L14_85OHM_5INCH_DP")
	)
	(segment
		(start 24.985218 -163.721796)
		(end 24.688546 -163.514278)
		(width 0.1143)
		(layer "B.Cu")
		(net "L14_85OHM_5INCH_DP")
	)
	(segment
		(start 35.164268 -163.69792)
		(end 34.868358 -163.49091)
		(width 0.1143)
		(layer "B.Cu")
		(net "L14_85OHM_5INCH_DP")
	)
	(segment
		(start 15.031466 -164.891974)
		(end 14.651736 -164.512244)
		(width 0.1143)
		(layer "B.Cu")
		(net "L14_85OHM_5INCH_DP")
	)
	(segment
		(start 29.779214 -163.510214)
		(end 29.222446 -163.608004)
		(width 0.1143)
		(layer "B.Cu")
		(net "L14_85OHM_5INCH_DP")
	)
	(segment
		(start 36.860226 -163.689538)
		(end 36.564316 -163.482528)
		(width 0.1143)
		(layer "B.Cu")
		(net "L14_85OHM_5INCH_DP")
	)
	(segment
		(start 30.712156 -163.904676)
		(end 31.095188 -166.080694)
		(width 0.1143)
		(layer "B.Cu")
		(net "L14_85OHM_5INCH_DP")
	)
	(segment
		(start 45.052742 -163.50234)
		(end 44.495466 -163.600638)
		(width 0.1143)
		(layer "B.Cu")
		(net "L14_85OHM_5INCH_DP")
	)
	(segment
		(start 23.851108 -166.25951)
		(end 23.719028 -166.1668)
		(width 0.1143)
		(layer "B.Cu")
		(net "L14_85OHM_5INCH_DP")
	)
	(segment
		(start 33.899602 -166.151814)
		(end 33.470596 -163.721542)
		(width 0.1143)
		(layer "B.Cu")
		(net "L14_85OHM_5INCH_DP")
	)
	(segment
		(start 31.476188 -163.510976)
		(end 30.919674 -163.608512)
		(width 0.1143)
		(layer "B.Cu")
		(net "L14_85OHM_5INCH_DP")
	)
	(segment
		(start 47.04588 -163.710112)
		(end 46.74997 -163.502848)
		(width 0.1143)
		(layer "B.Cu")
		(net "L14_85OHM_5INCH_DP")
	)
	(segment
		(start 37.4269 -166.248588)
		(end 37.294058 -166.155624)
		(width 0.1143)
		(layer "B.Cu")
		(net "L14_85OHM_5INCH_DP")
	)
	(segment
		(start 42.38498 -166.15156)
		(end 41.954704 -163.70808)
		(width 0.1143)
		(layer "B.Cu")
		(net "L14_85OHM_5INCH_DP")
	)
	(segment
		(start 19.036284 -163.589462)
		(end 18.828766 -163.885626)
		(width 0.1143)
		(layer "B.Cu")
		(net "L14_85OHM_5INCH_DP")
	)
	(segment
		(start 37.294058 -166.155624)
		(end 36.860226 -163.689538)
		(width 0.1143)
		(layer "B.Cu")
		(net "L14_85OHM_5INCH_DP")
	)
	(segment
		(start 48.065944 -166.07155)
		(end 47.973234 -166.203884)
		(width 0.1143)
		(layer "B.Cu")
		(net "L14_85OHM_5INCH_DP")
	)
	(segment
		(start 39.576248 -166.047166)
		(end 39.483538 -166.1795)
		(width 0.1143)
		(layer "B.Cu")
		(net "L14_85OHM_5INCH_DP")
	)
	(segment
		(start 26.384758 -163.510976)
		(end 25.82799 -163.608766)
		(width 0.1143)
		(layer "B.Cu")
		(net "L14_85OHM_5INCH_DP")
	)
	(segment
		(start 33.470596 -163.721542)
		(end 33.173924 -163.514024)
		(width 0.1143)
		(layer "B.Cu")
		(net "L14_85OHM_5INCH_DP")
	)
	(segment
		(start 39.123366 -166.242746)
		(end 38.990524 -166.149782)
		(width 0.1143)
		(layer "B.Cu")
		(net "L14_85OHM_5INCH_DP")
	)
	(segment
		(start 48.830992 -164.207698)
		(end 48.739044 -163.685728)
		(width 0.1143)
		(layer "B.Cu")
		(net "L14_85OHM_5INCH_DP")
	)
	(segment
		(start 20.732496 -163.585906)
		(end 20.525486 -163.882832)
		(width 0.1143)
		(layer "B.Cu")
		(net "L14_85OHM_5INCH_DP")
	)
	(segment
		(start 27.700732 -166.079424)
		(end 27.608276 -166.211504)
		(width 0.1143)
		(layer "B.Cu")
		(net "L14_85OHM_5INCH_DP")
	)
	(segment
		(start 29.39796 -166.07663)
		(end 29.302456 -166.21252)
		(width 0.1143)
		(layer "B.Cu")
		(net "L14_85OHM_5INCH_DP")
	)
	(segment
		(start 34.484818 -166.04869)
		(end 34.392108 -166.181532)
		(width 0.1143)
		(layer "B.Cu")
		(net "L14_85OHM_5INCH_DP")
	)
	(segment
		(start 40.821356 -166.247826)
		(end 40.688514 -166.155116)
		(width 0.1143)
		(layer "B.Cu")
		(net "L14_85OHM_5INCH_DP")
	)
	(segment
		(start 37.786818 -166.185342)
		(end 37.4269 -166.248588)
		(width 0.1143)
		(layer "B.Cu")
		(net "L14_85OHM_5INCH_DP")
	)
	(segment
		(start 32.7914 -166.072058)
		(end 32.69869 -166.204646)
		(width 0.1143)
		(layer "B.Cu")
		(net "L14_85OHM_5INCH_DP")
	)
	(segment
		(start 33.173924 -163.514024)
		(end 32.616902 -163.611814)
		(width 0.1143)
		(layer "B.Cu")
		(net "L14_85OHM_5INCH_DP")
	)
	(segment
		(start 45.783754 -166.177722)
		(end 45.348906 -163.709604)
		(width 0.1143)
		(layer "B.Cu")
		(net "L14_85OHM_5INCH_DP")
	)
	(segment
		(start 25.415494 -166.165276)
		(end 24.985218 -163.721796)
		(width 0.1143)
		(layer "B.Cu")
		(net "L14_85OHM_5INCH_DP")
	)
	(segment
		(start 28.379674 -163.723574)
		(end 28.083002 -163.516056)
		(width 0.1143)
		(layer "B.Cu")
		(net "L14_85OHM_5INCH_DP")
	)
	(segment
		(start 36.564316 -163.482528)
		(end 36.006024 -163.580572)
		(width 0.1143)
		(layer "B.Cu")
		(net "L14_85OHM_5INCH_DP")
	)
	(segment
		(start 23.92426 -163.908994)
		(end 24.303736 -166.063676)
		(width 0.1143)
		(layer "B.Cu")
		(net "L14_85OHM_5INCH_DP")
	)
	(segment
		(start 20.909026 -166.059866)
		(end 20.81657 -166.1922)
		(width 0.1143)
		(layer "B.Cu")
		(net "L14_85OHM_5INCH_DP")
	)
	(segment
		(start 19.890232 -163.69919)
		(end 19.59356 -163.491672)
		(width 0.1143)
		(layer "B.Cu")
		(net "L14_85OHM_5INCH_DP")
	)
	(segment
		(start 18.545556 -165.702488)
		(end 18.001234 -165.032944)
		(width 0.1143)
		(layer "B.Cu")
		(net "L14_85OHM_5INCH_DP")
	)
	(segment
		(start 37.879528 -166.053008)
		(end 37.786818 -166.185342)
		(width 0.1143)
		(layer "B.Cu")
		(net "L14_85OHM_5INCH_DP")
	)
	(segment
		(start 20.525486 -163.882832)
		(end 20.909026 -166.059866)
		(width 0.1143)
		(layer "B.Cu")
		(net "L14_85OHM_5INCH_DP")
	)
	(segment
		(start 25.620472 -163.90493)
		(end 26.00071 -166.06266)
		(width 0.1143)
		(layer "B.Cu")
		(net "L14_85OHM_5INCH_DP")
	)
	(segment
		(start 32.69869 -166.204646)
		(end 32.33801 -166.267892)
		(width 0.1143)
		(layer "B.Cu")
		(net "L14_85OHM_5INCH_DP")
	)
	(segment
		(start 34.310828 -163.5887)
		(end 34.10331 -163.885118)
		(width 0.1143)
		(layer "B.Cu")
		(net "L14_85OHM_5INCH_DP")
	)
	(segment
		(start 38.557708 -163.693094)
		(end 38.258496 -163.483544)
		(width 0.1143)
		(layer "B.Cu")
		(net "L14_85OHM_5INCH_DP")
	)
	(segment
		(start 27.318462 -163.91001)
		(end 27.700732 -166.079424)
		(width 0.1143)
		(layer "B.Cu")
		(net "L14_85OHM_5INCH_DP")
	)
	(segment
		(start 39.958518 -163.484052)
		(end 39.401242 -163.581842)
		(width 0.1143)
		(layer "B.Cu")
		(net "L14_85OHM_5INCH_DP")
	)
	(segment
		(start 24.21128 -166.19601)
		(end 23.851108 -166.25951)
		(width 0.1143)
		(layer "B.Cu")
		(net "L14_85OHM_5INCH_DP")
	)
	(segment
		(start 34.392108 -166.181532)
		(end 34.032444 -166.244778)
		(width 0.1143)
		(layer "B.Cu")
		(net "L14_85OHM_5INCH_DP")
	)
	(segment
		(start 18.631154 -166.187374)
		(end 18.545556 -165.702488)
		(width 0.1143)
		(layer "B.Cu")
		(net "L14_85OHM_5INCH_DP")
	)
	(segment
		(start 45.916596 -166.270686)
		(end 45.783754 -166.177722)
		(width 0.1143)
		(layer "B.Cu")
		(net "L14_85OHM_5INCH_DP")
	)
	(segment
		(start 22.43328 -163.606988)
		(end 22.22627 -163.903406)
		(width 0.1143)
		(layer "B.Cu")
		(net "L14_85OHM_5INCH_DP")
	)
	(segment
		(start 37.707062 -163.580826)
		(end 37.496496 -163.880292)
		(width 0.1143)
		(layer "B.Cu")
		(net "L14_85OHM_5INCH_DP")
	)
	(segment
		(start 22.021292 -166.163752)
		(end 21.586444 -163.695634)
		(width 0.1143)
		(layer "B.Cu")
		(net "L14_85OHM_5INCH_DP")
	)
	(segment
		(start 32.20593 -166.175436)
		(end 31.773114 -163.718494)
		(width 0.1143)
		(layer "B.Cu")
		(net "L14_85OHM_5INCH_DP")
	)
	(segment
		(start 30.919674 -163.608512)
		(end 30.712156 -163.904676)
		(width 0.1143)
		(layer "B.Cu")
		(net "L14_85OHM_5INCH_DP")
	)
	(segment
		(start 31.095188 -166.080694)
		(end 31.002986 -166.212774)
		(width 0.1143)
		(layer "B.Cu")
		(net "L14_85OHM_5INCH_DP")
	)
	(segment
		(start 47.479966 -166.174166)
		(end 47.04588 -163.710112)
		(width 0.1143)
		(layer "B.Cu")
		(net "L14_85OHM_5INCH_DP")
	)
	(segment
		(start 42.87774 -166.181278)
		(end 42.517822 -166.244524)
		(width 0.1143)
		(layer "B.Cu")
		(net "L14_85OHM_5INCH_DP")
	)
	(segment
		(start 32.409892 -163.90874)
		(end 32.7914 -166.072058)
		(width 0.1143)
		(layer "B.Cu")
		(net "L14_85OHM_5INCH_DP")
	)
	(segment
		(start 46.74997 -163.502848)
		(end 46.192694 -163.601146)
		(width 0.1143)
		(layer "B.Cu")
		(net "L14_85OHM_5INCH_DP")
	)
	(segment
		(start 15.543022 -164.891974)
		(end 15.031466 -164.891974)
		(width 0.1143)
		(layer "B.Cu")
		(net "L14_85OHM_5INCH_DP")
	)
	(segment
		(start 24.303736 -166.063676)
		(end 24.21128 -166.19601)
		(width 0.1143)
		(layer "B.Cu")
		(net "L14_85OHM_5INCH_DP")
	)
	(segment
		(start 21.289772 -163.488116)
		(end 20.732496 -163.585906)
		(width 0.1143)
		(layer "B.Cu")
		(net "L14_85OHM_5INCH_DP")
	)
	(segment
		(start 42.59072 -163.8935)
		(end 42.97045 -166.048436)
		(width 0.1143)
		(layer "B.Cu")
		(net "L14_85OHM_5INCH_DP")
	)
	(segment
		(start 24.688546 -163.514278)
		(end 24.13127 -163.612068)
		(width 0.1143)
		(layer "B.Cu")
		(net "L14_85OHM_5INCH_DP")
	)
	(segment
		(start 38.990524 -166.149782)
		(end 38.557708 -163.693094)
		(width 0.1143)
		(layer "B.Cu")
		(net "L14_85OHM_5INCH_DP")
	)
	(segment
		(start 21.586444 -163.695634)
		(end 21.289772 -163.488116)
		(width 0.1143)
		(layer "B.Cu")
		(net "L14_85OHM_5INCH_DP")
	)
	(segment
		(start 18.763234 -166.279576)
		(end 18.631154 -166.187374)
		(width 0.1143)
		(layer "B.Cu")
		(net "L14_85OHM_5INCH_DP")
	)
	(segment
		(start 16.647668 -164.806376)
		(end 15.543022 -164.891974)
		(width 0.1143)
		(layer "B.Cu")
		(net "L14_85OHM_5INCH_DP")
	)
	(segment
		(start 22.153372 -166.256208)
		(end 22.021292 -166.163752)
		(width 0.1143)
		(layer "B.Cu")
		(net "L14_85OHM_5INCH_DP")
	)
	(segment
		(start 25.82799 -163.608766)
		(end 25.620472 -163.90493)
		(width 0.1143)
		(layer "B.Cu")
		(net "L14_85OHM_5INCH_DP")
	)
	(segment
		(start 34.868358 -163.49091)
		(end 34.310828 -163.5887)
		(width 0.1143)
		(layer "B.Cu")
		(net "L14_85OHM_5INCH_DP")
	)
	(segment
		(start 23.719028 -166.1668)
		(end 23.287736 -163.716462)
		(width 0.1143)
		(layer "B.Cu")
		(net "L14_85OHM_5INCH_DP")
	)
	(segment
		(start 52.11826 -164.880544)
		(end 51.597306 -164.880544)
		(width 0.1143)
		(layer "B.Cu")
		(net "L14_85OHM_5INCH_DP")
	)
	(segment
		(start 44.66844 -166.054024)
		(end 44.575984 -166.186358)
		(width 0.1143)
		(layer "B.Cu")
		(net "L14_85OHM_5INCH_DP")
	)
	(segment
		(start 47.885604 -163.57727)
		(end 47.67834 -163.87318)
		(width 0.1143)
		(layer "B.Cu")
		(net "L14_85OHM_5INCH_DP")
	)
	(segment
		(start 39.483538 -166.1795)
		(end 39.123366 -166.242746)
		(width 0.1143)
		(layer "B.Cu")
		(net "L14_85OHM_5INCH_DP")
	)
	(segment
		(start 36.182554 -166.0525)
		(end 36.089844 -166.184834)
		(width 0.1143)
		(layer "B.Cu")
		(net "L14_85OHM_5INCH_DP")
	)
	(segment
		(start 34.032444 -166.244778)
		(end 33.899602 -166.151814)
		(width 0.1143)
		(layer "B.Cu")
		(net "L14_85OHM_5INCH_DP")
	)
	(segment
		(start 27.52598 -163.613846)
		(end 27.318462 -163.91001)
		(width 0.1143)
		(layer "B.Cu")
		(net "L14_85OHM_5INCH_DP")
	)
	(segment
		(start 45.98543 -163.89731)
		(end 46.369224 -166.074598)
		(width 0.1143)
		(layer "B.Cu")
		(net "L14_85OHM_5INCH_DP")
	)
	(segment
		(start 22.513798 -166.192708)
		(end 22.153372 -166.256208)
		(width 0.1143)
		(layer "B.Cu")
		(net "L14_85OHM_5INCH_DP")
	)
	(segment
		(start 46.192694 -163.601146)
		(end 45.98543 -163.89731)
		(width 0.1143)
		(layer "B.Cu")
		(net "L14_85OHM_5INCH_DP")
	)
	(segment
		(start 44.215304 -166.24935)
		(end 44.082462 -166.15664)
		(width 0.1143)
		(layer "B.Cu")
		(net "L14_85OHM_5INCH_DP")
	)
	(segment
		(start 25.547574 -166.257732)
		(end 25.415494 -166.165276)
		(width 0.1143)
		(layer "B.Cu")
		(net "L14_85OHM_5INCH_DP")
	)
	(segment
		(start 29.222446 -163.608004)
		(end 29.015182 -163.904422)
		(width 0.1143)
		(layer "B.Cu")
		(net "L14_85OHM_5INCH_DP")
	)
	(segment
		(start 44.575984 -166.186358)
		(end 44.215304 -166.24935)
		(width 0.1143)
		(layer "B.Cu")
		(net "L14_85OHM_5INCH_DP")
	)
	(segment
		(start 19.21637 -166.083996)
		(end 19.12366 -166.216076)
		(width 0.1143)
		(layer "B.Cu")
		(net "L14_85OHM_5INCH_DP")
	)
	(segment
		(start 28.81249 -166.180262)
		(end 28.379674 -163.723574)
		(width 0.1143)
		(layer "B.Cu")
		(net "L14_85OHM_5INCH_DP")
	)
	(segment
		(start 34.10331 -163.885118)
		(end 34.484818 -166.04869)
		(width 0.1143)
		(layer "B.Cu")
		(net "L14_85OHM_5INCH_DP")
	)
	(segment
		(start 22.991064 -163.509452)
		(end 22.43328 -163.606988)
		(width 0.1143)
		(layer "B.Cu")
		(net "L14_85OHM_5INCH_DP")
	)
	(segment
		(start 25.908254 -166.19474)
		(end 25.547574 -166.257732)
		(width 0.1143)
		(layer "B.Cu")
		(net "L14_85OHM_5INCH_DP")
	)
	(segment
		(start 19.59356 -163.491672)
		(end 19.036284 -163.589462)
		(width 0.1143)
		(layer "B.Cu")
		(net "L14_85OHM_5INCH_DP")
	)
	(segment
		(start 48.739044 -163.685728)
		(end 48.44288 -163.479226)
		(width 0.1143)
		(layer "B.Cu")
		(net "L14_85OHM_5INCH_DP")
	)
	(segment
		(start 47.612808 -166.26713)
		(end 47.479966 -166.174166)
		(width 0.1143)
		(layer "B.Cu")
		(net "L14_85OHM_5INCH_DP")
	)
	(segment
		(start 41.274238 -166.052246)
		(end 41.181528 -166.18458)
		(width 0.1143)
		(layer "B.Cu")
		(net "L14_85OHM_5INCH_DP")
	)
	(segment
		(start 30.509972 -166.183818)
		(end 30.07614 -163.717732)
		(width 0.1143)
		(layer "B.Cu")
		(net "L14_85OHM_5INCH_DP")
	)
	(segment
		(start 41.181528 -166.18458)
		(end 40.821356 -166.247826)
		(width 0.1143)
		(layer "B.Cu")
		(net "L14_85OHM_5INCH_DP")
	)
	(segment
		(start 47.67834 -163.87318)
		(end 48.065944 -166.07155)
		(width 0.1143)
		(layer "B.Cu")
		(net "L14_85OHM_5INCH_DP")
	)
	(segment
		(start 45.348906 -163.709604)
		(end 45.052742 -163.50234)
		(width 0.1143)
		(layer "B.Cu")
		(net "L14_85OHM_5INCH_DP")
	)
	(segment
		(start 44.288202 -163.896294)
		(end 44.66844 -166.054024)
		(width 0.1143)
		(layer "B.Cu")
		(net "L14_85OHM_5INCH_DP")
	)
	(segment
		(start 18.828766 -163.885626)
		(end 19.21637 -166.083996)
		(width 0.1143)
		(layer "B.Cu")
		(net "L14_85OHM_5INCH_DP")
	)
	(segment
		(start 20.81657 -166.1922)
		(end 20.456398 -166.2557)
		(width 0.1143)
		(layer "B.Cu")
		(net "L14_85OHM_5INCH_DP")
	)
	(segment
		(start 37.496496 -163.880292)
		(end 37.879528 -166.053008)
		(width 0.1143)
		(layer "B.Cu")
		(net "L14_85OHM_5INCH_DP")
	)
	(segment
		(start 39.401242 -163.581842)
		(end 39.193978 -163.877752)
		(width 0.1143)
		(layer "B.Cu")
		(net "L14_85OHM_5INCH_DP")
	)
	(segment
		(start 41.65854 -163.500816)
		(end 41.101264 -163.598606)
		(width 0.1143)
		(layer "B.Cu")
		(net "L14_85OHM_5INCH_DP")
	)
	(segment
		(start 41.602152 -163.756086)
		(end 41.241472 -163.819078)
		(width 0.1143)
		(layer "B.Cu")
		(net "L14_85OHM_5INCH_DN")
	)
	(segment
		(start 46.2407 -163.953952)
		(end 46.62424 -166.130986)
		(width 0.1143)
		(layer "B.Cu")
		(net "L14_85OHM_5INCH_DN")
	)
	(segment
		(start 47.933356 -163.929822)
		(end 48.32096 -166.128192)
		(width 0.1143)
		(layer "B.Cu")
		(net "L14_85OHM_5INCH_DN")
	)
	(segment
		(start 28.592018 -166.320724)
		(end 28.159202 -163.864036)
		(width 0.1143)
		(layer "B.Cu")
		(net "L14_85OHM_5INCH_DN")
	)
	(segment
		(start 29.442664 -166.432992)
		(end 28.89123 -166.530274)
		(width 0.1143)
		(layer "B.Cu")
		(net "L14_85OHM_5INCH_DN")
	)
	(segment
		(start 29.270198 -163.96081)
		(end 29.65323 -166.133526)
		(width 0.1143)
		(layer "B.Cu")
		(net "L14_85OHM_5INCH_DN")
	)
	(segment
		(start 42.164508 -166.292022)
		(end 41.734232 -163.848542)
		(width 0.1143)
		(layer "B.Cu")
		(net "L14_85OHM_5INCH_DN")
	)
	(segment
		(start 24.351742 -166.416482)
		(end 23.794466 -166.514526)
		(width 0.1143)
		(layer "B.Cu")
		(net "L14_85OHM_5INCH_DN")
	)
	(segment
		(start 36.507674 -163.737544)
		(end 36.14674 -163.801044)
		(width 0.1143)
		(layer "B.Cu")
		(net "L14_85OHM_5INCH_DN")
	)
	(segment
		(start 30.2895 -166.32428)
		(end 29.855668 -163.858194)
		(width 0.1143)
		(layer "B.Cu")
		(net "L14_85OHM_5INCH_DN")
	)
	(segment
		(start 15.031466 -165.133274)
		(end 14.651736 -165.513004)
		(width 0.1143)
		(layer "B.Cu")
		(net "L14_85OHM_5INCH_DN")
	)
	(segment
		(start 38.770052 -166.290244)
		(end 38.337236 -163.833556)
		(width 0.1143)
		(layer "B.Cu")
		(net "L14_85OHM_5INCH_DN")
	)
	(segment
		(start 27.955748 -166.136066)
		(end 27.748484 -166.431976)
		(width 0.1143)
		(layer "B.Cu")
		(net "L14_85OHM_5INCH_DN")
	)
	(segment
		(start 19.083782 -163.942268)
		(end 19.471386 -166.140638)
		(width 0.1143)
		(layer "B.Cu")
		(net "L14_85OHM_5INCH_DN")
	)
	(segment
		(start 48.026066 -163.797742)
		(end 47.933356 -163.929822)
		(width 0.1143)
		(layer "B.Cu")
		(net "L14_85OHM_5INCH_DN")
	)
	(segment
		(start 34.358326 -163.94176)
		(end 34.739834 -166.105078)
		(width 0.1143)
		(layer "B.Cu")
		(net "L14_85OHM_5INCH_DN")
	)
	(segment
		(start 52.11826 -165.121844)
		(end 51.606704 -165.121844)
		(width 0.1143)
		(layer "B.Cu")
		(net "L14_85OHM_5INCH_DN")
	)
	(segment
		(start 26.461212 -163.858702)
		(end 26.32837 -163.765992)
		(width 0.1143)
		(layer "B.Cu")
		(net "L14_85OHM_5INCH_DN")
	)
	(segment
		(start 22.096984 -166.511478)
		(end 21.80082 -166.304214)
		(width 0.1143)
		(layer "B.Cu")
		(net "L14_85OHM_5INCH_DN")
	)
	(segment
		(start 29.722826 -163.76523)
		(end 29.362908 -163.828476)
		(width 0.1143)
		(layer "B.Cu")
		(net "L14_85OHM_5INCH_DN")
	)
	(segment
		(start 44.923456 -166.110412)
		(end 44.716446 -166.40683)
		(width 0.1143)
		(layer "B.Cu")
		(net "L14_85OHM_5INCH_DN")
	)
	(segment
		(start 31.419546 -163.765992)
		(end 31.059882 -163.828984)
		(width 0.1143)
		(layer "B.Cu")
		(net "L14_85OHM_5INCH_DN")
	)
	(segment
		(start 21.164296 -166.116508)
		(end 20.957032 -166.412672)
		(width 0.1143)
		(layer "B.Cu")
		(net "L14_85OHM_5INCH_DN")
	)
	(segment
		(start 19.471386 -166.140638)
		(end 19.264122 -166.436548)
		(width 0.1143)
		(layer "B.Cu")
		(net "L14_85OHM_5INCH_DN")
	)
	(segment
		(start 25.195022 -166.305738)
		(end 24.764746 -163.862258)
		(width 0.1143)
		(layer "B.Cu")
		(net "L14_85OHM_5INCH_DN")
	)
	(segment
		(start 33.250124 -163.862004)
		(end 33.117282 -163.76904)
		(width 0.1143)
		(layer "B.Cu")
		(net "L14_85OHM_5INCH_DN")
	)
	(segment
		(start 39.448994 -163.934394)
		(end 39.831264 -166.103808)
		(width 0.1143)
		(layer "B.Cu")
		(net "L14_85OHM_5INCH_DN")
	)
	(segment
		(start 29.362908 -163.828476)
		(end 29.270198 -163.96081)
		(width 0.1143)
		(layer "B.Cu")
		(net "L14_85OHM_5INCH_DN")
	)
	(segment
		(start 48.32096 -166.128192)
		(end 48.113442 -166.424356)
		(width 0.1143)
		(layer "B.Cu")
		(net "L14_85OHM_5INCH_DN")
	)
	(segment
		(start 25.491186 -166.513002)
		(end 25.195022 -166.305738)
		(width 0.1143)
		(layer "B.Cu")
		(net "L14_85OHM_5INCH_DN")
	)
	(segment
		(start 51.606704 -165.121844)
		(end 50.502058 -165.207442)
		(width 0.1143)
		(layer "B.Cu")
		(net "L14_85OHM_5INCH_DN")
	)
	(segment
		(start 22.861524 -166.117524)
		(end 22.65426 -166.41318)
		(width 0.1143)
		(layer "B.Cu")
		(net "L14_85OHM_5INCH_DN")
	)
	(segment
		(start 31.059882 -163.828984)
		(end 30.967172 -163.961318)
		(width 0.1143)
		(layer "B.Cu")
		(net "L14_85OHM_5INCH_DN")
	)
	(segment
		(start 37.370512 -166.503604)
		(end 37.073586 -166.296086)
		(width 0.1143)
		(layer "B.Cu")
		(net "L14_85OHM_5INCH_DN")
	)
	(segment
		(start 34.811716 -163.745926)
		(end 34.451036 -163.809172)
		(width 0.1143)
		(layer "B.Cu")
		(net "L14_85OHM_5INCH_DN")
	)
	(segment
		(start 20.873212 -163.806378)
		(end 20.780502 -163.93922)
		(width 0.1143)
		(layer "B.Cu")
		(net "L14_85OHM_5INCH_DN")
	)
	(segment
		(start 50.502058 -165.207442)
		(end 49.148492 -164.980874)
		(width 0.1143)
		(layer "B.Cu")
		(net "L14_85OHM_5INCH_DN")
	)
	(segment
		(start 32.757618 -163.832286)
		(end 32.664908 -163.965128)
		(width 0.1143)
		(layer "B.Cu")
		(net "L14_85OHM_5INCH_DN")
	)
	(segment
		(start 35.673538 -166.502842)
		(end 35.376612 -166.295324)
		(width 0.1143)
		(layer "B.Cu")
		(net "L14_85OHM_5INCH_DN")
	)
	(segment
		(start 41.241472 -163.819078)
		(end 41.149016 -163.951158)
		(width 0.1143)
		(layer "B.Cu")
		(net "L14_85OHM_5INCH_DN")
	)
	(segment
		(start 23.498556 -166.307262)
		(end 23.067264 -163.857178)
		(width 0.1143)
		(layer "B.Cu")
		(net "L14_85OHM_5INCH_DN")
	)
	(segment
		(start 43.225466 -166.104824)
		(end 43.018456 -166.40175)
		(width 0.1143)
		(layer "B.Cu")
		(net "L14_85OHM_5INCH_DN")
	)
	(segment
		(start 39.54145 -163.802314)
		(end 39.448994 -163.934394)
		(width 0.1143)
		(layer "B.Cu")
		(net "L14_85OHM_5INCH_DN")
	)
	(segment
		(start 45.128434 -163.850066)
		(end 44.996354 -163.75761)
		(width 0.1143)
		(layer "B.Cu")
		(net "L14_85OHM_5INCH_DN")
	)
	(segment
		(start 21.365972 -163.836096)
		(end 21.23313 -163.743132)
		(width 0.1143)
		(layer "B.Cu")
		(net "L14_85OHM_5INCH_DN")
	)
	(segment
		(start 25.875488 -163.961572)
		(end 26.255726 -166.119302)
		(width 0.1143)
		(layer "B.Cu")
		(net "L14_85OHM_5INCH_DN")
	)
	(segment
		(start 44.158662 -166.504366)
		(end 43.86199 -166.297356)
		(width 0.1143)
		(layer "B.Cu")
		(net "L14_85OHM_5INCH_DN")
	)
	(segment
		(start 27.191208 -166.529766)
		(end 26.895298 -166.322756)
		(width 0.1143)
		(layer "B.Cu")
		(net "L14_85OHM_5INCH_DN")
	)
	(segment
		(start 48.386492 -163.734242)
		(end 48.026066 -163.797742)
		(width 0.1143)
		(layer "B.Cu")
		(net "L14_85OHM_5INCH_DN")
	)
	(segment
		(start 29.65323 -166.133526)
		(end 29.442664 -166.432992)
		(width 0.1143)
		(layer "B.Cu")
		(net "L14_85OHM_5INCH_DN")
	)
	(segment
		(start 43.430698 -163.847018)
		(end 43.298618 -163.754308)
		(width 0.1143)
		(layer "B.Cu")
		(net "L14_85OHM_5INCH_DN")
	)
	(segment
		(start 19.176492 -163.809934)
		(end 19.083782 -163.942268)
		(width 0.1143)
		(layer "B.Cu")
		(net "L14_85OHM_5INCH_DN")
	)
	(segment
		(start 31.985458 -166.315898)
		(end 31.552642 -163.858956)
		(width 0.1143)
		(layer "B.Cu")
		(net "L14_85OHM_5INCH_DN")
	)
	(segment
		(start 44.716446 -166.40683)
		(end 44.158662 -166.504366)
		(width 0.1143)
		(layer "B.Cu")
		(net "L14_85OHM_5INCH_DN")
	)
	(segment
		(start 42.46118 -166.49954)
		(end 42.164508 -166.292022)
		(width 0.1143)
		(layer "B.Cu")
		(net "L14_85OHM_5INCH_DN")
	)
	(segment
		(start 18.410682 -166.32809)
		(end 18.318734 -165.80612)
		(width 0.1143)
		(layer "B.Cu")
		(net "L14_85OHM_5INCH_DN")
	)
	(segment
		(start 30.58541 -166.53129)
		(end 30.2895 -166.32428)
		(width 0.1143)
		(layer "B.Cu")
		(net "L14_85OHM_5INCH_DN")
	)
	(segment
		(start 46.825408 -163.850574)
		(end 46.693328 -163.758118)
		(width 0.1143)
		(layer "B.Cu")
		(net "L14_85OHM_5INCH_DN")
	)
	(segment
		(start 33.117282 -163.76904)
		(end 32.757618 -163.832286)
		(width 0.1143)
		(layer "B.Cu")
		(net "L14_85OHM_5INCH_DN")
	)
	(segment
		(start 44.996354 -163.75761)
		(end 44.635928 -163.82111)
		(width 0.1143)
		(layer "B.Cu")
		(net "L14_85OHM_5INCH_DN")
	)
	(segment
		(start 35.376612 -166.295324)
		(end 34.943796 -163.838382)
		(width 0.1143)
		(layer "B.Cu")
		(net "L14_85OHM_5INCH_DN")
	)
	(segment
		(start 47.556166 -166.522146)
		(end 47.259494 -166.314628)
		(width 0.1143)
		(layer "B.Cu")
		(net "L14_85OHM_5INCH_DN")
	)
	(segment
		(start 24.631904 -163.769294)
		(end 24.271986 -163.83254)
		(width 0.1143)
		(layer "B.Cu")
		(net "L14_85OHM_5INCH_DN")
	)
	(segment
		(start 20.957032 -166.412672)
		(end 20.399756 -166.51097)
		(width 0.1143)
		(layer "B.Cu")
		(net "L14_85OHM_5INCH_DN")
	)
	(segment
		(start 46.333156 -163.821618)
		(end 46.2407 -163.953952)
		(width 0.1143)
		(layer "B.Cu")
		(net "L14_85OHM_5INCH_DN")
	)
	(segment
		(start 52.500784 -165.520116)
		(end 52.11826 -165.121844)
		(width 0.1143)
		(layer "B.Cu")
		(net "L14_85OHM_5INCH_DN")
	)
	(segment
		(start 19.264122 -166.436548)
		(end 18.706846 -166.534592)
		(width 0.1143)
		(layer "B.Cu")
		(net "L14_85OHM_5INCH_DN")
	)
	(segment
		(start 34.532824 -166.402004)
		(end 33.975802 -166.499794)
		(width 0.1143)
		(layer "B.Cu")
		(net "L14_85OHM_5INCH_DN")
	)
	(segment
		(start 28.02636 -163.771072)
		(end 27.666188 -163.834318)
		(width 0.1143)
		(layer "B.Cu")
		(net "L14_85OHM_5INCH_DN")
	)
	(segment
		(start 23.067264 -163.857178)
		(end 22.934422 -163.764468)
		(width 0.1143)
		(layer "B.Cu")
		(net "L14_85OHM_5INCH_DN")
	)
	(segment
		(start 43.018456 -166.40175)
		(end 42.46118 -166.49954)
		(width 0.1143)
		(layer "B.Cu")
		(net "L14_85OHM_5INCH_DN")
	)
	(segment
		(start 40.033956 -163.831524)
		(end 39.90213 -163.739322)
		(width 0.1143)
		(layer "B.Cu")
		(net "L14_85OHM_5INCH_DN")
	)
	(segment
		(start 39.90213 -163.739322)
		(end 39.54145 -163.802314)
		(width 0.1143)
		(layer "B.Cu")
		(net "L14_85OHM_5INCH_DN")
	)
	(segment
		(start 22.934422 -163.764468)
		(end 22.573742 -163.82746)
		(width 0.1143)
		(layer "B.Cu")
		(net "L14_85OHM_5INCH_DN")
	)
	(segment
		(start 36.639754 -163.83)
		(end 36.507674 -163.737544)
		(width 0.1143)
		(layer "B.Cu")
		(net "L14_85OHM_5INCH_DN")
	)
	(segment
		(start 28.89123 -166.530274)
		(end 28.592018 -166.320724)
		(width 0.1143)
		(layer "B.Cu")
		(net "L14_85OHM_5INCH_DN")
	)
	(segment
		(start 27.666188 -163.834318)
		(end 27.573478 -163.966652)
		(width 0.1143)
		(layer "B.Cu")
		(net "L14_85OHM_5INCH_DN")
	)
	(segment
		(start 18.318734 -165.80612)
		(end 17.87144 -165.255956)
		(width 0.1143)
		(layer "B.Cu")
		(net "L14_85OHM_5INCH_DN")
	)
	(segment
		(start 45.563282 -166.318184)
		(end 45.128434 -163.850066)
		(width 0.1143)
		(layer "B.Cu")
		(net "L14_85OHM_5INCH_DN")
	)
	(segment
		(start 29.855668 -163.858194)
		(end 29.722826 -163.76523)
		(width 0.1143)
		(layer "B.Cu")
		(net "L14_85OHM_5INCH_DN")
	)
	(segment
		(start 26.32837 -163.765992)
		(end 25.968198 -163.829238)
		(width 0.1143)
		(layer "B.Cu")
		(net "L14_85OHM_5INCH_DN")
	)
	(segment
		(start 26.255726 -166.119302)
		(end 26.048462 -166.415212)
		(width 0.1143)
		(layer "B.Cu")
		(net "L14_85OHM_5INCH_DN")
	)
	(segment
		(start 31.350204 -166.137082)
		(end 31.143702 -166.433246)
		(width 0.1143)
		(layer "B.Cu")
		(net "L14_85OHM_5INCH_DN")
	)
	(segment
		(start 28.159202 -163.864036)
		(end 28.02636 -163.771072)
		(width 0.1143)
		(layer "B.Cu")
		(net "L14_85OHM_5INCH_DN")
	)
	(segment
		(start 48.113442 -166.424356)
		(end 47.556166 -166.522146)
		(width 0.1143)
		(layer "B.Cu")
		(net "L14_85OHM_5INCH_DN")
	)
	(segment
		(start 38.201854 -163.738814)
		(end 37.84727 -163.801298)
		(width 0.1143)
		(layer "B.Cu")
		(net "L14_85OHM_5INCH_DN")
	)
	(segment
		(start 34.451036 -163.809172)
		(end 34.358326 -163.94176)
		(width 0.1143)
		(layer "B.Cu")
		(net "L14_85OHM_5INCH_DN")
	)
	(segment
		(start 36.054538 -163.933124)
		(end 36.43757 -166.109142)
		(width 0.1143)
		(layer "B.Cu")
		(net "L14_85OHM_5INCH_DN")
	)
	(segment
		(start 24.559006 -166.120318)
		(end 24.351742 -166.416482)
		(width 0.1143)
		(layer "B.Cu")
		(net "L14_85OHM_5INCH_DN")
	)
	(segment
		(start 41.734232 -163.848542)
		(end 41.602152 -163.756086)
		(width 0.1143)
		(layer "B.Cu")
		(net "L14_85OHM_5INCH_DN")
	)
	(segment
		(start 22.573742 -163.82746)
		(end 22.481286 -163.959794)
		(width 0.1143)
		(layer "B.Cu")
		(net "L14_85OHM_5INCH_DN")
	)
	(segment
		(start 41.149016 -163.951158)
		(end 41.529254 -166.108888)
		(width 0.1143)
		(layer "B.Cu")
		(net "L14_85OHM_5INCH_DN")
	)
	(segment
		(start 21.23313 -163.743132)
		(end 20.873212 -163.806378)
		(width 0.1143)
		(layer "B.Cu")
		(net "L14_85OHM_5INCH_DN")
	)
	(segment
		(start 15.55242 -165.133274)
		(end 15.031466 -165.133274)
		(width 0.1143)
		(layer "B.Cu")
		(net "L14_85OHM_5INCH_DN")
	)
	(segment
		(start 41.321736 -166.405052)
		(end 40.764968 -166.502842)
		(width 0.1143)
		(layer "B.Cu")
		(net "L14_85OHM_5INCH_DN")
	)
	(segment
		(start 48.60417 -164.31133)
		(end 48.518572 -163.826444)
		(width 0.1143)
		(layer "B.Cu")
		(net "L14_85OHM_5INCH_DN")
	)
	(segment
		(start 49.148492 -164.980874)
		(end 48.60417 -164.31133)
		(width 0.1143)
		(layer "B.Cu")
		(net "L14_85OHM_5INCH_DN")
	)
	(segment
		(start 36.43757 -166.109142)
		(end 36.230052 -166.405306)
		(width 0.1143)
		(layer "B.Cu")
		(net "L14_85OHM_5INCH_DN")
	)
	(segment
		(start 38.134544 -166.109396)
		(end 37.92728 -166.405814)
		(width 0.1143)
		(layer "B.Cu")
		(net "L14_85OHM_5INCH_DN")
	)
	(segment
		(start 32.664908 -163.965128)
		(end 33.046416 -166.1287)
		(width 0.1143)
		(layer "B.Cu")
		(net "L14_85OHM_5INCH_DN")
	)
	(segment
		(start 38.337236 -163.833556)
		(end 38.201854 -163.738814)
		(width 0.1143)
		(layer "B.Cu")
		(net "L14_85OHM_5INCH_DN")
	)
	(segment
		(start 37.84727 -163.801298)
		(end 37.751766 -163.937188)
		(width 0.1143)
		(layer "B.Cu")
		(net "L14_85OHM_5INCH_DN")
	)
	(segment
		(start 31.143702 -166.433246)
		(end 30.58541 -166.53129)
		(width 0.1143)
		(layer "B.Cu")
		(net "L14_85OHM_5INCH_DN")
	)
	(segment
		(start 21.80082 -166.304214)
		(end 21.365972 -163.836096)
		(width 0.1143)
		(layer "B.Cu")
		(net "L14_85OHM_5INCH_DN")
	)
	(segment
		(start 39.623746 -166.399972)
		(end 39.066724 -166.497762)
		(width 0.1143)
		(layer "B.Cu")
		(net "L14_85OHM_5INCH_DN")
	)
	(segment
		(start 26.895298 -166.322756)
		(end 26.461212 -163.858702)
		(width 0.1143)
		(layer "B.Cu")
		(net "L14_85OHM_5INCH_DN")
	)
	(segment
		(start 24.271986 -163.83254)
		(end 24.179276 -163.965382)
		(width 0.1143)
		(layer "B.Cu")
		(net "L14_85OHM_5INCH_DN")
	)
	(segment
		(start 22.65426 -166.41318)
		(end 22.096984 -166.511478)
		(width 0.1143)
		(layer "B.Cu")
		(net "L14_85OHM_5INCH_DN")
	)
	(segment
		(start 19.66976 -163.839652)
		(end 19.536918 -163.746688)
		(width 0.1143)
		(layer "B.Cu")
		(net "L14_85OHM_5INCH_DN")
	)
	(segment
		(start 32.281368 -166.522908)
		(end 31.985458 -166.315898)
		(width 0.1143)
		(layer "B.Cu")
		(net "L14_85OHM_5INCH_DN")
	)
	(segment
		(start 36.14674 -163.801044)
		(end 36.054538 -163.933124)
		(width 0.1143)
		(layer "B.Cu")
		(net "L14_85OHM_5INCH_DN")
	)
	(segment
		(start 37.751766 -163.937188)
		(end 38.134544 -166.109396)
		(width 0.1143)
		(layer "B.Cu")
		(net "L14_85OHM_5INCH_DN")
	)
	(segment
		(start 48.518572 -163.826444)
		(end 48.386492 -163.734242)
		(width 0.1143)
		(layer "B.Cu")
		(net "L14_85OHM_5INCH_DN")
	)
	(segment
		(start 23.794466 -166.514526)
		(end 23.498556 -166.307262)
		(width 0.1143)
		(layer "B.Cu")
		(net "L14_85OHM_5INCH_DN")
	)
	(segment
		(start 44.635928 -163.82111)
		(end 44.543218 -163.952936)
		(width 0.1143)
		(layer "B.Cu")
		(net "L14_85OHM_5INCH_DN")
	)
	(segment
		(start 40.764968 -166.502842)
		(end 40.468042 -166.295832)
		(width 0.1143)
		(layer "B.Cu")
		(net "L14_85OHM_5INCH_DN")
	)
	(segment
		(start 22.481286 -163.959794)
		(end 22.861524 -166.117524)
		(width 0.1143)
		(layer "B.Cu")
		(net "L14_85OHM_5INCH_DN")
	)
	(segment
		(start 24.764746 -163.862258)
		(end 24.631904 -163.769294)
		(width 0.1143)
		(layer "B.Cu")
		(net "L14_85OHM_5INCH_DN")
	)
	(segment
		(start 45.859954 -166.525702)
		(end 45.563282 -166.318184)
		(width 0.1143)
		(layer "B.Cu")
		(net "L14_85OHM_5INCH_DN")
	)
	(segment
		(start 27.573478 -163.966652)
		(end 27.955748 -166.136066)
		(width 0.1143)
		(layer "B.Cu")
		(net "L14_85OHM_5INCH_DN")
	)
	(segment
		(start 30.967172 -163.961318)
		(end 31.350204 -166.137082)
		(width 0.1143)
		(layer "B.Cu")
		(net "L14_85OHM_5INCH_DN")
	)
	(segment
		(start 20.399756 -166.51097)
		(end 20.103846 -166.303706)
		(width 0.1143)
		(layer "B.Cu")
		(net "L14_85OHM_5INCH_DN")
	)
	(segment
		(start 19.536918 -163.746688)
		(end 19.176492 -163.809934)
		(width 0.1143)
		(layer "B.Cu")
		(net "L14_85OHM_5INCH_DN")
	)
	(segment
		(start 43.86199 -166.297356)
		(end 43.430698 -163.847018)
		(width 0.1143)
		(layer "B.Cu")
		(net "L14_85OHM_5INCH_DN")
	)
	(segment
		(start 27.748484 -166.431976)
		(end 27.191208 -166.529766)
		(width 0.1143)
		(layer "B.Cu")
		(net "L14_85OHM_5INCH_DN")
	)
	(segment
		(start 36.230052 -166.405306)
		(end 35.673538 -166.502842)
		(width 0.1143)
		(layer "B.Cu")
		(net "L14_85OHM_5INCH_DN")
	)
	(segment
		(start 24.179276 -163.965382)
		(end 24.559006 -166.120318)
		(width 0.1143)
		(layer "B.Cu")
		(net "L14_85OHM_5INCH_DN")
	)
	(segment
		(start 43.298618 -163.754308)
		(end 42.938446 -163.817808)
		(width 0.1143)
		(layer "B.Cu")
		(net "L14_85OHM_5INCH_DN")
	)
	(segment
		(start 46.41723 -166.427912)
		(end 45.859954 -166.525702)
		(width 0.1143)
		(layer "B.Cu")
		(net "L14_85OHM_5INCH_DN")
	)
	(segment
		(start 47.259494 -166.314628)
		(end 46.825408 -163.850574)
		(width 0.1143)
		(layer "B.Cu")
		(net "L14_85OHM_5INCH_DN")
	)
	(segment
		(start 41.529254 -166.108888)
		(end 41.321736 -166.405052)
		(width 0.1143)
		(layer "B.Cu")
		(net "L14_85OHM_5INCH_DN")
	)
	(segment
		(start 34.943796 -163.838382)
		(end 34.811716 -163.745926)
		(width 0.1143)
		(layer "B.Cu")
		(net "L14_85OHM_5INCH_DN")
	)
	(segment
		(start 32.838898 -166.425118)
		(end 32.281368 -166.522908)
		(width 0.1143)
		(layer "B.Cu")
		(net "L14_85OHM_5INCH_DN")
	)
	(segment
		(start 46.693328 -163.758118)
		(end 46.333156 -163.821618)
		(width 0.1143)
		(layer "B.Cu")
		(net "L14_85OHM_5INCH_DN")
	)
	(segment
		(start 20.103846 -166.303706)
		(end 19.66976 -163.839652)
		(width 0.1143)
		(layer "B.Cu")
		(net "L14_85OHM_5INCH_DN")
	)
	(segment
		(start 39.066724 -166.497762)
		(end 38.770052 -166.290244)
		(width 0.1143)
		(layer "B.Cu")
		(net "L14_85OHM_5INCH_DN")
	)
	(segment
		(start 40.468042 -166.295832)
		(end 40.033956 -163.831524)
		(width 0.1143)
		(layer "B.Cu")
		(net "L14_85OHM_5INCH_DN")
	)
	(segment
		(start 46.62424 -166.130986)
		(end 46.41723 -166.427912)
		(width 0.1143)
		(layer "B.Cu")
		(net "L14_85OHM_5INCH_DN")
	)
	(segment
		(start 42.938446 -163.817808)
		(end 42.84599 -163.950142)
		(width 0.1143)
		(layer "B.Cu")
		(net "L14_85OHM_5INCH_DN")
	)
	(segment
		(start 17.87144 -165.255956)
		(end 16.637 -165.049454)
		(width 0.1143)
		(layer "B.Cu")
		(net "L14_85OHM_5INCH_DN")
	)
	(segment
		(start 16.637 -165.049454)
		(end 15.55242 -165.133274)
		(width 0.1143)
		(layer "B.Cu")
		(net "L14_85OHM_5INCH_DN")
	)
	(segment
		(start 39.831264 -166.103808)
		(end 39.623746 -166.399972)
		(width 0.1143)
		(layer "B.Cu")
		(net "L14_85OHM_5INCH_DN")
	)
	(segment
		(start 37.92728 -166.405814)
		(end 37.370512 -166.503604)
		(width 0.1143)
		(layer "B.Cu")
		(net "L14_85OHM_5INCH_DN")
	)
	(segment
		(start 26.048462 -166.415212)
		(end 25.491186 -166.513002)
		(width 0.1143)
		(layer "B.Cu")
		(net "L14_85OHM_5INCH_DN")
	)
	(segment
		(start 25.968198 -163.829238)
		(end 25.875488 -163.961572)
		(width 0.1143)
		(layer "B.Cu")
		(net "L14_85OHM_5INCH_DN")
	)
	(segment
		(start 31.552642 -163.858956)
		(end 31.419546 -163.765992)
		(width 0.1143)
		(layer "B.Cu")
		(net "L14_85OHM_5INCH_DN")
	)
	(segment
		(start 42.84599 -163.950142)
		(end 43.225466 -166.104824)
		(width 0.1143)
		(layer "B.Cu")
		(net "L14_85OHM_5INCH_DN")
	)
	(segment
		(start 33.046416 -166.1287)
		(end 32.838898 -166.425118)
		(width 0.1143)
		(layer "B.Cu")
		(net "L14_85OHM_5INCH_DN")
	)
	(segment
		(start 34.739834 -166.105078)
		(end 34.532824 -166.402004)
		(width 0.1143)
		(layer "B.Cu")
		(net "L14_85OHM_5INCH_DN")
	)
	(segment
		(start 44.543218 -163.952936)
		(end 44.923456 -166.110412)
		(width 0.1143)
		(layer "B.Cu")
		(net "L14_85OHM_5INCH_DN")
	)
	(segment
		(start 18.706846 -166.534592)
		(end 18.410682 -166.32809)
		(width 0.1143)
		(layer "B.Cu")
		(net "L14_85OHM_5INCH_DN")
	)
	(segment
		(start 37.073586 -166.296086)
		(end 36.639754 -163.83)
		(width 0.1143)
		(layer "B.Cu")
		(net "L14_85OHM_5INCH_DN")
	)
	(segment
		(start 20.780502 -163.93922)
		(end 21.164296 -166.116508)
		(width 0.1143)
		(layer "B.Cu")
		(net "L14_85OHM_5INCH_DN")
	)
	(segment
		(start 33.67913 -166.292276)
		(end 33.250124 -163.862004)
		(width 0.1143)
		(layer "B.Cu")
		(net "L14_85OHM_5INCH_DN")
	)
	(segment
		(start 33.975802 -166.499794)
		(end 33.67913 -166.292276)
		(width 0.1143)
		(layer "B.Cu")
		(net "L14_85OHM_5INCH_DN")
	)
	(segment
		(start 166.256716 -163.745672)
		(end 166.688008 -166.195756)
		(width 0.1143)
		(layer "B.Cu")
		(net "L14_85OHM_10INCH_DP")
	)
	(segment
		(start 213.286594 -163.715446)
		(end 213.641178 -163.652962)
		(width 0.1143)
		(layer "B.Cu")
		(net "L14_85OHM_10INCH_DP")
	)
	(segment
		(start 187.735464 -163.857432)
		(end 187.828174 -163.725606)
		(width 0.1143)
		(layer "B.Cu")
		(net "L14_85OHM_10INCH_DP")
	)
	(segment
		(start 177.550572 -163.846256)
		(end 177.643282 -163.713668)
		(width 0.1143)
		(layer "B.Cu")
		(net "L14_85OHM_10INCH_DP")
	)
	(segment
		(start 179.832 -163.734496)
		(end 180.265832 -166.200582)
		(width 0.1143)
		(layer "B.Cu")
		(net "L14_85OHM_10INCH_DP")
	)
	(segment
		(start 196.669406 -163.640262)
		(end 196.802248 -163.733226)
		(width 0.1143)
		(layer "B.Cu")
		(net "L14_85OHM_10INCH_DP")
	)
	(segment
		(start 195.539614 -166.19855)
		(end 195.835524 -166.405814)
		(width 0.1143)
		(layer "B.Cu")
		(net "L14_85OHM_10INCH_DP")
	)
	(segment
		(start 199.232266 -166.421054)
		(end 199.789542 -166.323264)
		(width 0.1143)
		(layer "B.Cu")
		(net "L14_85OHM_10INCH_DP")
	)
	(segment
		(start 191.125602 -163.834318)
		(end 191.218312 -163.702238)
		(width 0.1143)
		(layer "B.Cu")
		(net "L14_85OHM_10INCH_DP")
	)
	(segment
		(start 204.324458 -166.423848)
		(end 204.881226 -166.326058)
		(width 0.1143)
		(layer "B.Cu")
		(net "L14_85OHM_10INCH_DP")
	)
	(segment
		(start 191.578738 -163.638738)
		(end 191.710818 -163.73094)
		(width 0.1143)
		(layer "B.Cu")
		(net "L14_85OHM_10INCH_DP")
	)
	(segment
		(start 213.366604 -166.319962)
		(end 213.573868 -166.023544)
		(width 0.1143)
		(layer "B.Cu")
		(net "L14_85OHM_10INCH_DP")
	)
	(segment
		(start 191.218312 -163.702238)
		(end 191.578738 -163.638738)
		(width 0.1143)
		(layer "B.Cu")
		(net "L14_85OHM_10INCH_DP")
	)
	(segment
		(start 161.508186 -165.694614)
		(end 161.600134 -166.216584)
		(width 0.1143)
		(layer "B.Cu")
		(net "L14_85OHM_10INCH_DP")
	)
	(segment
		(start 223.46539 -163.71189)
		(end 223.825816 -163.64839)
		(width 0.1143)
		(layer "B.Cu")
		(net "L14_85OHM_10INCH_DP")
	)
	(segment
		(start 220.075252 -163.735258)
		(end 220.435678 -163.671758)
		(width 0.1143)
		(layer "B.Cu")
		(net "L14_85OHM_10INCH_DP")
	)
	(segment
		(start 171.215812 -163.659566)
		(end 171.348654 -163.75253)
		(width 0.1143)
		(layer "B.Cu")
		(net "L14_85OHM_10INCH_DP")
	)
	(segment
		(start 201.694288 -166.024814)
		(end 201.3077 -163.831778)
		(width 0.1143)
		(layer "B.Cu")
		(net "L14_85OHM_10INCH_DP")
	)
	(segment
		(start 198.36511 -163.632642)
		(end 198.497952 -163.725352)
		(width 0.1143)
		(layer "B.Cu")
		(net "L14_85OHM_10INCH_DP")
	)
	(segment
		(start 203.183998 -166.32555)
		(end 203.391516 -166.029386)
		(width 0.1143)
		(layer "B.Cu")
		(net "L14_85OHM_10INCH_DP")
	)
	(segment
		(start 171.78147 -166.209218)
		(end 172.080682 -166.418768)
		(width 0.1143)
		(layer "B.Cu")
		(net "L14_85OHM_10INCH_DP")
	)
	(segment
		(start 189.816486 -166.035482)
		(end 189.432946 -163.858448)
		(width 0.1143)
		(layer "B.Cu")
		(net "L14_85OHM_10INCH_DP")
	)
	(segment
		(start 180.944012 -163.841684)
		(end 181.039516 -163.705794)
		(width 0.1143)
		(layer "B.Cu")
		(net "L14_85OHM_10INCH_DP")
	)
	(segment
		(start 163.589208 -166.399464)
		(end 164.146484 -166.301166)
		(width 0.1143)
		(layer "B.Cu")
		(net "L14_85OHM_10INCH_DP")
	)
	(segment
		(start 199.702928 -163.700968)
		(end 200.0631 -163.637722)
		(width 0.1143)
		(layer "B.Cu")
		(net "L14_85OHM_10INCH_DP")
	)
	(segment
		(start 209.972148 -166.316152)
		(end 210.179158 -166.019226)
		(width 0.1143)
		(layer "B.Cu")
		(net "L14_85OHM_10INCH_DP")
	)
	(segment
		(start 222.698818 -166.228776)
		(end 222.99549 -166.436294)
		(width 0.1143)
		(layer "B.Cu")
		(net "L14_85OHM_10INCH_DP")
	)
	(segment
		(start 217.173556 -163.76269)
		(end 217.603832 -166.20617)
		(width 0.1143)
		(layer "B.Cu")
		(net "L14_85OHM_10INCH_DP")
	)
	(segment
		(start 200.0631 -163.637722)
		(end 200.195942 -163.730686)
		(width 0.1143)
		(layer "B.Cu")
		(net "L14_85OHM_10INCH_DP")
	)
	(segment
		(start 169.650664 -163.747196)
		(end 170.08475 -166.21125)
		(width 0.1143)
		(layer "B.Cu")
		(net "L14_85OHM_10INCH_DP")
	)
	(segment
		(start 204.701394 -163.832794)
		(end 204.796898 -163.696904)
		(width 0.1143)
		(layer "B.Cu")
		(net "L14_85OHM_10INCH_DP")
	)
	(segment
		(start 198.004938 -163.695888)
		(end 198.36511 -163.632642)
		(width 0.1143)
		(layer "B.Cu")
		(net "L14_85OHM_10INCH_DP")
	)
	(segment
		(start 206.851758 -163.634928)
		(end 206.983584 -163.72713)
		(width 0.1143)
		(layer "B.Cu")
		(net "L14_85OHM_10INCH_DP")
	)
	(segment
		(start 179.246784 -163.83762)
		(end 179.338986 -163.70554)
		(width 0.1143)
		(layer "B.Cu")
		(net "L14_85OHM_10INCH_DP")
	)
	(segment
		(start 169.445178 -166.007796)
		(end 169.06494 -163.850066)
		(width 0.1143)
		(layer "B.Cu")
		(net "L14_85OHM_10INCH_DP")
	)
	(segment
		(start 186.210702 -166.306246)
		(end 186.417712 -166.00932)
		(width 0.1143)
		(layer "B.Cu")
		(net "L14_85OHM_10INCH_DP")
	)
	(segment
		(start 189.432946 -163.858448)
		(end 189.525402 -163.726114)
		(width 0.1143)
		(layer "B.Cu")
		(net "L14_85OHM_10INCH_DP")
	)
	(segment
		(start 176.02835 -166.313612)
		(end 176.235868 -166.017194)
		(width 0.1143)
		(layer "B.Cu")
		(net "L14_85OHM_10INCH_DP")
	)
	(segment
		(start 211.876894 -166.02329)
		(end 211.493862 -163.847272)
		(width 0.1143)
		(layer "B.Cu")
		(net "L14_85OHM_10INCH_DP")
	)
	(segment
		(start 214.209376 -166.204392)
		(end 214.506048 -166.41191)
		(width 0.1143)
		(layer "B.Cu")
		(net "L14_85OHM_10INCH_DP")
	)
	(segment
		(start 205.723998 -166.210488)
		(end 206.02067 -166.418006)
		(width 0.1143)
		(layer "B.Cu")
		(net "L14_85OHM_10INCH_DP")
	)
	(segment
		(start 194.6148 -163.718748)
		(end 194.97548 -163.655756)
		(width 0.1143)
		(layer "B.Cu")
		(net "L14_85OHM_10INCH_DP")
	)
	(segment
		(start 196.600064 -166.011606)
		(end 196.216778 -163.83635)
		(width 0.1143)
		(layer "B.Cu")
		(net "L14_85OHM_10INCH_DP")
	)
	(segment
		(start 158.741872 -165.021768)
		(end 159.826452 -164.937948)
		(width 0.1143)
		(layer "B.Cu")
		(net "L14_85OHM_10INCH_DP")
	)
	(segment
		(start 164.146484 -166.301166)
		(end 164.353748 -166.005002)
		(width 0.1143)
		(layer "B.Cu")
		(net "L14_85OHM_10INCH_DP")
	)
	(segment
		(start 180.265832 -166.200582)
		(end 180.562758 -166.4081)
		(width 0.1143)
		(layer "B.Cu")
		(net "L14_85OHM_10INCH_DP")
	)
	(segment
		(start 203.100686 -163.721288)
		(end 203.46162 -163.657788)
		(width 0.1143)
		(layer "B.Cu")
		(net "L14_85OHM_10INCH_DP")
	)
	(segment
		(start 163.969954 -163.827714)
		(end 164.062664 -163.694872)
		(width 0.1143)
		(layer "B.Cu")
		(net "L14_85OHM_10INCH_DP")
	)
	(segment
		(start 185.653426 -166.404036)
		(end 186.210702 -166.306246)
		(width 0.1143)
		(layer "B.Cu")
		(net "L14_85OHM_10INCH_DP")
	)
	(segment
		(start 170.38066 -166.41826)
		(end 170.937936 -166.32047)
		(width 0.1143)
		(layer "B.Cu")
		(net "L14_85OHM_10INCH_DP")
	)
	(segment
		(start 186.490864 -163.658804)
		(end 186.622944 -163.751514)
		(width 0.1143)
		(layer "B.Cu")
		(net "L14_85OHM_10INCH_DP")
	)
	(segment
		(start 177.643282 -163.713668)
		(end 178.003962 -163.650422)
		(width 0.1143)
		(layer "B.Cu")
		(net "L14_85OHM_10INCH_DP")
	)
	(segment
		(start 170.76293 -163.855146)
		(end 170.85564 -163.722812)
		(width 0.1143)
		(layer "B.Cu")
		(net "L14_85OHM_10INCH_DP")
	)
	(segment
		(start 191.513206 -166.032688)
		(end 191.125602 -163.834318)
		(width 0.1143)
		(layer "B.Cu")
		(net "L14_85OHM_10INCH_DP")
	)
	(segment
		(start 165.286436 -166.399972)
		(end 165.843712 -166.301674)
		(width 0.1143)
		(layer "B.Cu")
		(net "L14_85OHM_10INCH_DP")
	)
	(segment
		(start 175.94707 -163.72078)
		(end 176.306734 -163.657534)
		(width 0.1143)
		(layer "B.Cu")
		(net "L14_85OHM_10INCH_DP")
	)
	(segment
		(start 157.841188 -165.401498)
		(end 158.220918 -165.021768)
		(width 0.1143)
		(layer "B.Cu")
		(net "L14_85OHM_10INCH_DP")
	)
	(segment
		(start 167.541194 -166.304976)
		(end 167.748458 -166.008812)
		(width 0.1143)
		(layer "B.Cu")
		(net "L14_85OHM_10INCH_DP")
	)
	(segment
		(start 163.293298 -166.1922)
		(end 163.589208 -166.399464)
		(width 0.1143)
		(layer "B.Cu")
		(net "L14_85OHM_10INCH_DP")
	)
	(segment
		(start 208.68386 -163.744148)
		(end 209.118454 -166.206424)
		(width 0.1143)
		(layer "B.Cu")
		(net "L14_85OHM_10INCH_DP")
	)
	(segment
		(start 181.3941 -163.64331)
		(end 181.529482 -163.738052)
		(width 0.1143)
		(layer "B.Cu")
		(net "L14_85OHM_10INCH_DP")
	)
	(segment
		(start 178.136042 -163.742878)
		(end 178.568858 -166.19982)
		(width 0.1143)
		(layer "B.Cu")
		(net "L14_85OHM_10INCH_DP")
	)
	(segment
		(start 197.912228 -163.828222)
		(end 198.004938 -163.695888)
		(width 0.1143)
		(layer "B.Cu")
		(net "L14_85OHM_10INCH_DP")
	)
	(segment
		(start 223.37268 -163.84397)
		(end 223.46539 -163.71189)
		(width 0.1143)
		(layer "B.Cu")
		(net "L14_85OHM_10INCH_DP")
	)
	(segment
		(start 182.733696 -163.70681)
		(end 183.094376 -163.643818)
		(width 0.1143)
		(layer "B.Cu")
		(net "L14_85OHM_10INCH_DP")
	)
	(segment
		(start 217.041476 -163.670234)
		(end 217.173556 -163.76269)
		(width 0.1143)
		(layer "B.Cu")
		(net "L14_85OHM_10INCH_DP")
	)
	(segment
		(start 184.7215 -166.013384)
		(end 184.341262 -163.855654)
		(width 0.1143)
		(layer "B.Cu")
		(net "L14_85OHM_10INCH_DP")
	)
	(segment
		(start 174.608998 -163.654486)
		(end 174.742094 -163.74745)
		(width 0.1143)
		(layer "B.Cu")
		(net "L14_85OHM_10INCH_DP")
	)
	(segment
		(start 195.108322 -163.748466)
		(end 195.539614 -166.19855)
		(width 0.1143)
		(layer "B.Cu")
		(net "L14_85OHM_10INCH_DP")
	)
	(segment
		(start 194.522344 -163.851082)
		(end 194.6148 -163.718748)
		(width 0.1143)
		(layer "B.Cu")
		(net "L14_85OHM_10INCH_DP")
	)
	(segment
		(start 199.789542 -166.323264)
		(end 199.996806 -166.027354)
		(width 0.1143)
		(layer "B.Cu")
		(net "L14_85OHM_10INCH_DP")
	)
	(segment
		(start 193.841878 -166.195502)
		(end 194.138042 -166.402766)
		(width 0.1143)
		(layer "B.Cu")
		(net "L14_85OHM_10INCH_DP")
	)
	(segment
		(start 162.859212 -163.728146)
		(end 163.293298 -166.1922)
		(width 0.1143)
		(layer "B.Cu")
		(net "L14_85OHM_10INCH_DP")
	)
	(segment
		(start 186.417712 -166.00932)
		(end 186.038236 -163.854638)
		(width 0.1143)
		(layer "B.Cu")
		(net "L14_85OHM_10INCH_DP")
	)
	(segment
		(start 182.815992 -166.304468)
		(end 183.02351 -166.008304)
		(width 0.1143)
		(layer "B.Cu")
		(net "L14_85OHM_10INCH_DP")
	)
	(segment
		(start 209.79765 -163.855908)
		(end 209.89036 -163.72332)
		(width 0.1143)
		(layer "B.Cu")
		(net "L14_85OHM_10INCH_DP")
	)
	(segment
		(start 212.809836 -166.417752)
		(end 213.366604 -166.319962)
		(width 0.1143)
		(layer "B.Cu")
		(net "L14_85OHM_10INCH_DP")
	)
	(segment
		(start 204.881226 -166.326058)
		(end 205.08849 -166.02964)
		(width 0.1143)
		(layer "B.Cu")
		(net "L14_85OHM_10INCH_DP")
	)
	(segment
		(start 208.55178 -163.651692)
		(end 208.68386 -163.744148)
		(width 0.1143)
		(layer "B.Cu")
		(net "L14_85OHM_10INCH_DP")
	)
	(segment
		(start 201.89317 -163.729162)
		(end 202.330558 -166.215568)
		(width 0.1143)
		(layer "B.Cu")
		(net "L14_85OHM_10INCH_DP")
	)
	(segment
		(start 183.660288 -166.200328)
		(end 183.957214 -166.407338)
		(width 0.1143)
		(layer "B.Cu")
		(net "L14_85OHM_10INCH_DP")
	)
	(segment
		(start 158.220918 -165.021768)
		(end 158.741872 -165.021768)
		(width 0.1143)
		(layer "B.Cu")
		(net "L14_85OHM_10INCH_DP")
	)
	(segment
		(start 206.02067 -166.418006)
		(end 206.577692 -166.320216)
		(width 0.1143)
		(layer "B.Cu")
		(net "L14_85OHM_10INCH_DP")
	)
	(segment
		(start 194.138042 -166.402766)
		(end 194.695318 -166.304468)
		(width 0.1143)
		(layer "B.Cu")
		(net "L14_85OHM_10INCH_DP")
	)
	(segment
		(start 181.962298 -166.19474)
		(end 182.25897 -166.402258)
		(width 0.1143)
		(layer "B.Cu")
		(net "L14_85OHM_10INCH_DP")
	)
	(segment
		(start 181.529482 -163.738052)
		(end 181.962298 -166.19474)
		(width 0.1143)
		(layer "B.Cu")
		(net "L14_85OHM_10INCH_DP")
	)
	(segment
		(start 176.439576 -163.750498)
		(end 176.871376 -166.196772)
		(width 0.1143)
		(layer "B.Cu")
		(net "L14_85OHM_10INCH_DP")
	)
	(segment
		(start 211.112862 -166.41699)
		(end 211.669376 -166.319454)
		(width 0.1143)
		(layer "B.Cu")
		(net "L14_85OHM_10INCH_DP")
	)
	(segment
		(start 173.774862 -166.419784)
		(end 174.333154 -166.32174)
		(width 0.1143)
		(layer "B.Cu")
		(net "L14_85OHM_10INCH_DP")
	)
	(segment
		(start 170.08475 -166.21125)
		(end 170.38066 -166.41826)
		(width 0.1143)
		(layer "B.Cu")
		(net "L14_85OHM_10INCH_DP")
	)
	(segment
		(start 218.45778 -166.315898)
		(end 218.66479 -166.018972)
		(width 0.1143)
		(layer "B.Cu")
		(net "L14_85OHM_10INCH_DP")
	)
	(segment
		(start 191.710818 -163.73094)
		(end 192.144904 -166.194994)
		(width 0.1143)
		(layer "B.Cu")
		(net "L14_85OHM_10INCH_DP")
	)
	(segment
		(start 219.982542 -163.867084)
		(end 220.075252 -163.735258)
		(width 0.1143)
		(layer "B.Cu")
		(net "L14_85OHM_10INCH_DP")
	)
	(segment
		(start 205.08849 -166.02964)
		(end 204.701394 -163.832794)
		(width 0.1143)
		(layer "B.Cu")
		(net "L14_85OHM_10INCH_DP")
	)
	(segment
		(start 173.04512 -163.746688)
		(end 173.478952 -166.212774)
		(width 0.1143)
		(layer "B.Cu")
		(net "L14_85OHM_10INCH_DP")
	)
	(segment
		(start 177.93208 -166.009574)
		(end 177.550572 -163.846256)
		(width 0.1143)
		(layer "B.Cu")
		(net "L14_85OHM_10INCH_DP")
	)
	(segment
		(start 215.270588 -166.017956)
		(end 214.888318 -163.848542)
		(width 0.1143)
		(layer "B.Cu")
		(net "L14_85OHM_10INCH_DP")
	)
	(segment
		(start 171.1452 -166.02456)
		(end 170.76293 -163.855146)
		(width 0.1143)
		(layer "B.Cu")
		(net "L14_85OHM_10INCH_DP")
	)
	(segment
		(start 196.3928 -166.30777)
		(end 196.600064 -166.011606)
		(width 0.1143)
		(layer "B.Cu")
		(net "L14_85OHM_10INCH_DP")
	)
	(segment
		(start 205.151482 -163.63442)
		(end 205.286864 -163.729162)
		(width 0.1143)
		(layer "B.Cu")
		(net "L14_85OHM_10INCH_DP")
	)
	(segment
		(start 220.36278 -166.02456)
		(end 219.982542 -163.867084)
		(width 0.1143)
		(layer "B.Cu")
		(net "L14_85OHM_10INCH_DP")
	)
	(segment
		(start 172.912278 -163.653724)
		(end 173.04512 -163.746688)
		(width 0.1143)
		(layer "B.Cu")
		(net "L14_85OHM_10INCH_DP")
	)
	(segment
		(start 172.080682 -166.418768)
		(end 172.632116 -166.321486)
		(width 0.1143)
		(layer "B.Cu")
		(net "L14_85OHM_10INCH_DP")
	)
	(segment
		(start 167.368728 -163.853876)
		(end 167.461438 -163.721034)
		(width 0.1143)
		(layer "B.Cu")
		(net "L14_85OHM_10INCH_DP")
	)
	(segment
		(start 220.567758 -163.764214)
		(end 221.002606 -166.232332)
		(width 0.1143)
		(layer "B.Cu")
		(net "L14_85OHM_10INCH_DP")
	)
	(segment
		(start 162.72637 -163.635182)
		(end 162.859212 -163.728146)
		(width 0.1143)
		(layer "B.Cu")
		(net "L14_85OHM_10INCH_DP")
	)
	(segment
		(start 204.796898 -163.696904)
		(end 205.151482 -163.63442)
		(width 0.1143)
		(layer "B.Cu")
		(net "L14_85OHM_10INCH_DP")
	)
	(segment
		(start 215.47328 -163.745672)
		(end 215.907366 -166.20998)
		(width 0.1143)
		(layer "B.Cu")
		(net "L14_85OHM_10INCH_DP")
	)
	(segment
		(start 217.900504 -166.413688)
		(end 218.45778 -166.315898)
		(width 0.1143)
		(layer "B.Cu")
		(net "L14_85OHM_10INCH_DP")
	)
	(segment
		(start 164.990272 -166.192708)
		(end 165.286436 -166.399972)
		(width 0.1143)
		(layer "B.Cu")
		(net "L14_85OHM_10INCH_DP")
	)
	(segment
		(start 204.027532 -166.21633)
		(end 204.324458 -166.423848)
		(width 0.1143)
		(layer "B.Cu")
		(net "L14_85OHM_10INCH_DP")
	)
	(segment
		(start 187.828174 -163.725606)
		(end 188.1886 -163.662106)
		(width 0.1143)
		(layer "B.Cu")
		(net "L14_85OHM_10INCH_DP")
	)
	(segment
		(start 215.907366 -166.20998)
		(end 216.204292 -166.41699)
		(width 0.1143)
		(layer "B.Cu")
		(net "L14_85OHM_10INCH_DP")
	)
	(segment
		(start 207.718914 -166.423086)
		(end 208.275682 -166.325296)
		(width 0.1143)
		(layer "B.Cu")
		(net "L14_85OHM_10INCH_DP")
	)
	(segment
		(start 198.497952 -163.725352)
		(end 198.936356 -166.214044)
		(width 0.1143)
		(layer "B.Cu")
		(net "L14_85OHM_10INCH_DP")
	)
	(segment
		(start 174.156624 -163.849812)
		(end 174.249334 -163.717478)
		(width 0.1143)
		(layer "B.Cu")
		(net "L14_85OHM_10INCH_DP")
	)
	(segment
		(start 201.40041 -163.699444)
		(end 201.760328 -163.636198)
		(width 0.1143)
		(layer "B.Cu")
		(net "L14_85OHM_10INCH_DP")
	)
	(segment
		(start 206.78521 -166.024052)
		(end 206.398622 -163.83)
		(width 0.1143)
		(layer "B.Cu")
		(net "L14_85OHM_10INCH_DP")
	)
	(segment
		(start 184.433718 -163.723574)
		(end 184.794398 -163.660582)
		(width 0.1143)
		(layer "B.Cu")
		(net "L14_85OHM_10INCH_DP")
	)
	(segment
		(start 166.050976 -166.006018)
		(end 165.670738 -163.848288)
		(width 0.1143)
		(layer "B.Cu")
		(net "L14_85OHM_10INCH_DP")
	)
	(segment
		(start 179.338986 -163.70554)
		(end 179.69992 -163.64204)
		(width 0.1143)
		(layer "B.Cu")
		(net "L14_85OHM_10INCH_DP")
	)
	(segment
		(start 186.038236 -163.854638)
		(end 186.130692 -163.722304)
		(width 0.1143)
		(layer "B.Cu")
		(net "L14_85OHM_10INCH_DP")
	)
	(segment
		(start 208.1911 -163.714684)
		(end 208.55178 -163.651692)
		(width 0.1143)
		(layer "B.Cu")
		(net "L14_85OHM_10INCH_DP")
	)
	(segment
		(start 167.461438 -163.721034)
		(end 167.821356 -163.657788)
		(width 0.1143)
		(layer "B.Cu")
		(net "L14_85OHM_10INCH_DP")
	)
	(segment
		(start 178.568858 -166.19982)
		(end 178.865784 -166.407338)
		(width 0.1143)
		(layer "B.Cu")
		(net "L14_85OHM_10INCH_DP")
	)
	(segment
		(start 198.08952 -166.3065)
		(end 198.296784 -166.01059)
		(width 0.1143)
		(layer "B.Cu")
		(net "L14_85OHM_10INCH_DP")
	)
	(segment
		(start 210.815936 -166.209472)
		(end 211.112862 -166.41699)
		(width 0.1143)
		(layer "B.Cu")
		(net "L14_85OHM_10INCH_DP")
	)
	(segment
		(start 216.76106 -166.3192)
		(end 216.968578 -166.023036)
		(width 0.1143)
		(layer "B.Cu")
		(net "L14_85OHM_10INCH_DP")
	)
	(segment
		(start 188.755528 -166.22268)
		(end 189.0522 -166.430198)
		(width 0.1143)
		(layer "B.Cu")
		(net "L14_85OHM_10INCH_DP")
	)
	(segment
		(start 211.669376 -166.319454)
		(end 211.876894 -166.02329)
		(width 0.1143)
		(layer "B.Cu")
		(net "L14_85OHM_10INCH_DP")
	)
	(segment
		(start 213.77656 -163.747704)
		(end 214.209376 -166.204392)
		(width 0.1143)
		(layer "B.Cu")
		(net "L14_85OHM_10INCH_DP")
	)
	(segment
		(start 219.597986 -166.418514)
		(end 220.15577 -166.320978)
		(width 0.1143)
		(layer "B.Cu")
		(net "L14_85OHM_10INCH_DP")
	)
	(segment
		(start 177.72507 -166.3065)
		(end 177.93208 -166.009574)
		(width 0.1143)
		(layer "B.Cu")
		(net "L14_85OHM_10INCH_DP")
	)
	(segment
		(start 212.51291 -166.210234)
		(end 212.809836 -166.417752)
		(width 0.1143)
		(layer "B.Cu")
		(net "L14_85OHM_10INCH_DP")
	)
	(segment
		(start 170.85564 -163.722812)
		(end 171.215812 -163.659566)
		(width 0.1143)
		(layer "B.Cu")
		(net "L14_85OHM_10INCH_DP")
	)
	(segment
		(start 172.55236 -163.71697)
		(end 172.912278 -163.653724)
		(width 0.1143)
		(layer "B.Cu")
		(net "L14_85OHM_10INCH_DP")
	)
	(segment
		(start 180.562758 -166.4081)
		(end 181.119526 -166.31031)
		(width 0.1143)
		(layer "B.Cu")
		(net "L14_85OHM_10INCH_DP")
	)
	(segment
		(start 203.391516 -166.029386)
		(end 203.008484 -163.853368)
		(width 0.1143)
		(layer "B.Cu")
		(net "L14_85OHM_10INCH_DP")
	)
	(segment
		(start 216.968578 -166.023036)
		(end 216.58834 -163.865306)
		(width 0.1143)
		(layer "B.Cu")
		(net "L14_85OHM_10INCH_DP")
	)
	(segment
		(start 164.555424 -163.72459)
		(end 164.990272 -166.192708)
		(width 0.1143)
		(layer "B.Cu")
		(net "L14_85OHM_10INCH_DP")
	)
	(segment
		(start 161.060892 -165.14445)
		(end 161.508186 -165.694614)
		(width 0.1143)
		(layer "B.Cu")
		(net "L14_85OHM_10INCH_DP")
	)
	(segment
		(start 192.91427 -163.697666)
		(end 193.274188 -163.63442)
		(width 0.1143)
		(layer "B.Cu")
		(net "L14_85OHM_10INCH_DP")
	)
	(segment
		(start 175.17491 -166.204392)
		(end 175.47082 -166.411402)
		(width 0.1143)
		(layer "B.Cu")
		(net "L14_85OHM_10INCH_DP")
	)
	(segment
		(start 184.926478 -163.753038)
		(end 185.356754 -166.196518)
		(width 0.1143)
		(layer "B.Cu")
		(net "L14_85OHM_10INCH_DP")
	)
	(segment
		(start 193.205354 -166.007796)
		(end 192.82156 -163.830508)
		(width 0.1143)
		(layer "B.Cu")
		(net "L14_85OHM_10INCH_DP")
	)
	(segment
		(start 194.695318 -166.304468)
		(end 194.902582 -166.008812)
		(width 0.1143)
		(layer "B.Cu")
		(net "L14_85OHM_10INCH_DP")
	)
	(segment
		(start 191.305688 -166.328852)
		(end 191.513206 -166.032688)
		(width 0.1143)
		(layer "B.Cu")
		(net "L14_85OHM_10INCH_DP")
	)
	(segment
		(start 176.306734 -163.657534)
		(end 176.439576 -163.750498)
		(width 0.1143)
		(layer "B.Cu")
		(net "L14_85OHM_10INCH_DP")
	)
	(segment
		(start 169.15765 -163.717732)
		(end 169.517822 -163.654486)
		(width 0.1143)
		(layer "B.Cu")
		(net "L14_85OHM_10INCH_DP")
	)
	(segment
		(start 206.983584 -163.72713)
		(end 207.421988 -166.216076)
		(width 0.1143)
		(layer "B.Cu")
		(net "L14_85OHM_10INCH_DP")
	)
	(segment
		(start 209.415126 -166.413942)
		(end 209.972148 -166.316152)
		(width 0.1143)
		(layer "B.Cu")
		(net "L14_85OHM_10INCH_DP")
	)
	(segment
		(start 200.195942 -163.730686)
		(end 200.633076 -166.212012)
		(width 0.1143)
		(layer "B.Cu")
		(net "L14_85OHM_10INCH_DP")
	)
	(segment
		(start 202.627484 -166.423086)
		(end 203.183998 -166.32555)
		(width 0.1143)
		(layer "B.Cu")
		(net "L14_85OHM_10INCH_DP")
	)
	(segment
		(start 176.235868 -166.017194)
		(end 175.85436 -163.853622)
		(width 0.1143)
		(layer "B.Cu")
		(net "L14_85OHM_10INCH_DP")
	)
	(segment
		(start 189.525402 -163.726114)
		(end 189.885574 -163.662614)
		(width 0.1143)
		(layer "B.Cu")
		(net "L14_85OHM_10INCH_DP")
	)
	(segment
		(start 222.264732 -163.764722)
		(end 222.698818 -166.228776)
		(width 0.1143)
		(layer "B.Cu")
		(net "L14_85OHM_10INCH_DP")
	)
	(segment
		(start 189.885574 -163.662614)
		(end 190.017654 -163.75507)
		(width 0.1143)
		(layer "B.Cu")
		(net "L14_85OHM_10INCH_DP")
	)
	(segment
		(start 200.932288 -166.421562)
		(end 201.483722 -166.32428)
		(width 0.1143)
		(layer "B.Cu")
		(net "L14_85OHM_10INCH_DP")
	)
	(segment
		(start 206.491078 -163.69792)
		(end 206.851758 -163.634928)
		(width 0.1143)
		(layer "B.Cu")
		(net "L14_85OHM_10INCH_DP")
	)
	(segment
		(start 225.941382 -165.12159)
		(end 227.046028 -165.035992)
		(width 0.1143)
		(layer "B.Cu")
		(net "L14_85OHM_10INCH_DP")
	)
	(segment
		(start 184.794398 -163.660582)
		(end 184.926478 -163.753038)
		(width 0.1143)
		(layer "B.Cu")
		(net "L14_85OHM_10INCH_DP")
	)
	(segment
		(start 161.896298 -166.423086)
		(end 162.453574 -166.325042)
		(width 0.1143)
		(layer "B.Cu")
		(net "L14_85OHM_10INCH_DP")
	)
	(segment
		(start 203.46162 -163.657788)
		(end 203.5937 -163.750244)
		(width 0.1143)
		(layer "B.Cu")
		(net "L14_85OHM_10INCH_DP")
	)
	(segment
		(start 165.843712 -166.301674)
		(end 166.050976 -166.006018)
		(width 0.1143)
		(layer "B.Cu")
		(net "L14_85OHM_10INCH_DP")
	)
	(segment
		(start 188.32068 -163.754562)
		(end 188.755528 -166.22268)
		(width 0.1143)
		(layer "B.Cu")
		(net "L14_85OHM_10INCH_DP")
	)
	(segment
		(start 162.453574 -166.325042)
		(end 162.660838 -166.029132)
		(width 0.1143)
		(layer "B.Cu")
		(net "L14_85OHM_10INCH_DP")
	)
	(segment
		(start 214.506048 -166.41191)
		(end 215.06307 -166.31412)
		(width 0.1143)
		(layer "B.Cu")
		(net "L14_85OHM_10INCH_DP")
	)
	(segment
		(start 193.40703 -163.727384)
		(end 193.841878 -166.195502)
		(width 0.1143)
		(layer "B.Cu")
		(net "L14_85OHM_10INCH_DP")
	)
	(segment
		(start 192.99809 -166.30396)
		(end 193.205354 -166.007796)
		(width 0.1143)
		(layer "B.Cu")
		(net "L14_85OHM_10INCH_DP")
	)
	(segment
		(start 179.629816 -166.013638)
		(end 179.246784 -163.83762)
		(width 0.1143)
		(layer "B.Cu")
		(net "L14_85OHM_10INCH_DP")
	)
	(segment
		(start 224.587816 -164.895022)
		(end 225.941382 -165.12159)
		(width 0.1143)
		(layer "B.Cu")
		(net "L14_85OHM_10INCH_DP")
	)
	(segment
		(start 171.348654 -163.75253)
		(end 171.78147 -166.209218)
		(width 0.1143)
		(layer "B.Cu")
		(net "L14_85OHM_10INCH_DP")
	)
	(segment
		(start 205.286864 -163.729162)
		(end 205.723998 -166.210488)
		(width 0.1143)
		(layer "B.Cu")
		(net "L14_85OHM_10INCH_DP")
	)
	(segment
		(start 208.275682 -166.325296)
		(end 208.4832 -166.029132)
		(width 0.1143)
		(layer "B.Cu")
		(net "L14_85OHM_10INCH_DP")
	)
	(segment
		(start 186.622944 -163.751514)
		(end 187.054236 -166.201852)
		(width 0.1143)
		(layer "B.Cu")
		(net "L14_85OHM_10INCH_DP")
	)
	(segment
		(start 200.633076 -166.212012)
		(end 200.932288 -166.421562)
		(width 0.1143)
		(layer "B.Cu")
		(net "L14_85OHM_10INCH_DP")
	)
	(segment
		(start 223.760284 -166.04234)
		(end 223.37268 -163.84397)
		(width 0.1143)
		(layer "B.Cu")
		(net "L14_85OHM_10INCH_DP")
	)
	(segment
		(start 182.25897 -166.402258)
		(end 182.815992 -166.304468)
		(width 0.1143)
		(layer "B.Cu")
		(net "L14_85OHM_10INCH_DP")
	)
	(segment
		(start 182.64124 -163.83889)
		(end 182.733696 -163.70681)
		(width 0.1143)
		(layer "B.Cu")
		(net "L14_85OHM_10INCH_DP")
	)
	(segment
		(start 199.610218 -163.833302)
		(end 199.702928 -163.700968)
		(width 0.1143)
		(layer "B.Cu")
		(net "L14_85OHM_10INCH_DP")
	)
	(segment
		(start 212.079078 -163.744148)
		(end 212.51291 -166.210234)
		(width 0.1143)
		(layer "B.Cu")
		(net "L14_85OHM_10INCH_DP")
	)
	(segment
		(start 172.632116 -166.321486)
		(end 172.842682 -166.02202)
		(width 0.1143)
		(layer "B.Cu")
		(net "L14_85OHM_10INCH_DP")
	)
	(segment
		(start 209.118454 -166.206424)
		(end 209.415126 -166.413942)
		(width 0.1143)
		(layer "B.Cu")
		(net "L14_85OHM_10INCH_DP")
	)
	(segment
		(start 185.356754 -166.196518)
		(end 185.653426 -166.404036)
		(width 0.1143)
		(layer "B.Cu")
		(net "L14_85OHM_10INCH_DP")
	)
	(segment
		(start 203.5937 -163.750244)
		(end 204.027532 -166.21633)
		(width 0.1143)
		(layer "B.Cu")
		(net "L14_85OHM_10INCH_DP")
	)
	(segment
		(start 187.908692 -166.311326)
		(end 188.115702 -166.014908)
		(width 0.1143)
		(layer "B.Cu")
		(net "L14_85OHM_10INCH_DP")
	)
	(segment
		(start 211.493862 -163.847272)
		(end 211.586064 -163.715192)
		(width 0.1143)
		(layer "B.Cu")
		(net "L14_85OHM_10INCH_DP")
	)
	(segment
		(start 162.365944 -163.698428)
		(end 162.72637 -163.635182)
		(width 0.1143)
		(layer "B.Cu")
		(net "L14_85OHM_10INCH_DP")
	)
	(segment
		(start 192.82156 -163.830508)
		(end 192.91427 -163.697666)
		(width 0.1143)
		(layer "B.Cu")
		(net "L14_85OHM_10INCH_DP")
	)
	(segment
		(start 169.237914 -166.303706)
		(end 169.445178 -166.007796)
		(width 0.1143)
		(layer "B.Cu")
		(net "L14_85OHM_10INCH_DP")
	)
	(segment
		(start 174.742094 -163.74745)
		(end 175.17491 -166.204392)
		(width 0.1143)
		(layer "B.Cu")
		(net "L14_85OHM_10INCH_DP")
	)
	(segment
		(start 188.115702 -166.014908)
		(end 187.735464 -163.857432)
		(width 0.1143)
		(layer "B.Cu")
		(net "L14_85OHM_10INCH_DP")
	)
	(segment
		(start 223.957896 -163.740592)
		(end 224.043494 -164.225478)
		(width 0.1143)
		(layer "B.Cu")
		(net "L14_85OHM_10INCH_DP")
	)
	(segment
		(start 190.017654 -163.75507)
		(end 190.45174 -166.219124)
		(width 0.1143)
		(layer "B.Cu")
		(net "L14_85OHM_10INCH_DP")
	)
	(segment
		(start 201.3077 -163.831778)
		(end 201.40041 -163.699444)
		(width 0.1143)
		(layer "B.Cu")
		(net "L14_85OHM_10INCH_DP")
	)
	(segment
		(start 210.25104 -163.660074)
		(end 210.38312 -163.75253)
		(width 0.1143)
		(layer "B.Cu")
		(net "L14_85OHM_10INCH_DP")
	)
	(segment
		(start 218.285314 -163.86429)
		(end 218.37777 -163.731956)
		(width 0.1143)
		(layer "B.Cu")
		(net "L14_85OHM_10INCH_DP")
	)
	(segment
		(start 221.856554 -166.34206)
		(end 222.063564 -166.045134)
		(width 0.1143)
		(layer "B.Cu")
		(net "L14_85OHM_10INCH_DP")
	)
	(segment
		(start 178.003962 -163.650422)
		(end 178.136042 -163.742878)
		(width 0.1143)
		(layer "B.Cu")
		(net "L14_85OHM_10INCH_DP")
	)
	(segment
		(start 164.353748 -166.005002)
		(end 163.969954 -163.827714)
		(width 0.1143)
		(layer "B.Cu")
		(net "L14_85OHM_10INCH_DP")
	)
	(segment
		(start 199.996806 -166.027354)
		(end 199.610218 -163.833302)
		(width 0.1143)
		(layer "B.Cu")
		(net "L14_85OHM_10INCH_DP")
	)
	(segment
		(start 219.301314 -166.211504)
		(end 219.597986 -166.418514)
		(width 0.1143)
		(layer "B.Cu")
		(net "L14_85OHM_10INCH_DP")
	)
	(segment
		(start 221.680024 -163.8681)
		(end 221.77248 -163.735766)
		(width 0.1143)
		(layer "B.Cu")
		(net "L14_85OHM_10INCH_DP")
	)
	(segment
		(start 167.821356 -163.657788)
		(end 167.954198 -163.750752)
		(width 0.1143)
		(layer "B.Cu")
		(net "L14_85OHM_10INCH_DP")
	)
	(segment
		(start 166.688008 -166.195756)
		(end 166.983918 -166.40302)
		(width 0.1143)
		(layer "B.Cu")
		(net "L14_85OHM_10INCH_DP")
	)
	(segment
		(start 209.89036 -163.72332)
		(end 210.25104 -163.660074)
		(width 0.1143)
		(layer "B.Cu")
		(net "L14_85OHM_10INCH_DP")
	)
	(segment
		(start 192.440814 -166.402258)
		(end 192.99809 -166.30396)
		(width 0.1143)
		(layer "B.Cu")
		(net "L14_85OHM_10INCH_DP")
	)
	(segment
		(start 183.226202 -163.73602)
		(end 183.660288 -166.200328)
		(width 0.1143)
		(layer "B.Cu")
		(net "L14_85OHM_10INCH_DP")
	)
	(segment
		(start 224.043494 -164.225478)
		(end 224.587816 -164.895022)
		(width 0.1143)
		(layer "B.Cu")
		(net "L14_85OHM_10INCH_DP")
	)
	(segment
		(start 164.422582 -163.631626)
		(end 164.555424 -163.72459)
		(width 0.1143)
		(layer "B.Cu")
		(net "L14_85OHM_10INCH_DP")
	)
	(segment
		(start 211.586064 -163.715192)
		(end 211.946998 -163.651692)
		(width 0.1143)
		(layer "B.Cu")
		(net "L14_85OHM_10INCH_DP")
	)
	(segment
		(start 216.58834 -163.865306)
		(end 216.680796 -163.733226)
		(width 0.1143)
		(layer "B.Cu")
		(net "L14_85OHM_10INCH_DP")
	)
	(segment
		(start 162.273234 -163.830762)
		(end 162.365944 -163.698428)
		(width 0.1143)
		(layer "B.Cu")
		(net "L14_85OHM_10INCH_DP")
	)
	(segment
		(start 193.274188 -163.63442)
		(end 193.40703 -163.727384)
		(width 0.1143)
		(layer "B.Cu")
		(net "L14_85OHM_10INCH_DP")
	)
	(segment
		(start 179.69992 -163.64204)
		(end 179.832 -163.734496)
		(width 0.1143)
		(layer "B.Cu")
		(net "L14_85OHM_10INCH_DP")
	)
	(segment
		(start 198.936356 -166.214044)
		(end 199.232266 -166.421054)
		(width 0.1143)
		(layer "B.Cu")
		(net "L14_85OHM_10INCH_DP")
	)
	(segment
		(start 210.179158 -166.019226)
		(end 209.79765 -163.855908)
		(width 0.1143)
		(layer "B.Cu")
		(net "L14_85OHM_10INCH_DP")
	)
	(segment
		(start 215.06307 -166.31412)
		(end 215.270588 -166.017956)
		(width 0.1143)
		(layer "B.Cu")
		(net "L14_85OHM_10INCH_DP")
	)
	(segment
		(start 197.532244 -166.40429)
		(end 198.08952 -166.3065)
		(width 0.1143)
		(layer "B.Cu")
		(net "L14_85OHM_10INCH_DP")
	)
	(segment
		(start 218.66479 -166.018972)
		(end 218.285314 -163.86429)
		(width 0.1143)
		(layer "B.Cu")
		(net "L14_85OHM_10INCH_DP")
	)
	(segment
		(start 227.046028 -165.035992)
		(end 227.557584 -165.035992)
		(width 0.1143)
		(layer "B.Cu")
		(net "L14_85OHM_10INCH_DP")
	)
	(segment
		(start 220.15577 -166.320978)
		(end 220.36278 -166.02456)
		(width 0.1143)
		(layer "B.Cu")
		(net "L14_85OHM_10INCH_DP")
	)
	(segment
		(start 208.098644 -163.846764)
		(end 208.1911 -163.714684)
		(width 0.1143)
		(layer "B.Cu")
		(net "L14_85OHM_10INCH_DP")
	)
	(segment
		(start 186.130692 -163.722304)
		(end 186.490864 -163.658804)
		(width 0.1143)
		(layer "B.Cu")
		(net "L14_85OHM_10INCH_DP")
	)
	(segment
		(start 222.99549 -166.436294)
		(end 223.552766 -166.338504)
		(width 0.1143)
		(layer "B.Cu")
		(net "L14_85OHM_10INCH_DP")
	)
	(segment
		(start 217.603832 -166.20617)
		(end 217.900504 -166.413688)
		(width 0.1143)
		(layer "B.Cu")
		(net "L14_85OHM_10INCH_DP")
	)
	(segment
		(start 213.641178 -163.652962)
		(end 213.77656 -163.747704)
		(width 0.1143)
		(layer "B.Cu")
		(net "L14_85OHM_10INCH_DP")
	)
	(segment
		(start 166.983918 -166.40302)
		(end 167.541194 -166.304976)
		(width 0.1143)
		(layer "B.Cu")
		(net "L14_85OHM_10INCH_DP")
	)
	(segment
		(start 173.478952 -166.212774)
		(end 173.774862 -166.419784)
		(width 0.1143)
		(layer "B.Cu")
		(net "L14_85OHM_10INCH_DP")
	)
	(segment
		(start 221.299278 -166.43985)
		(end 221.856554 -166.34206)
		(width 0.1143)
		(layer "B.Cu")
		(net "L14_85OHM_10INCH_DP")
	)
	(segment
		(start 188.1886 -163.662106)
		(end 188.32068 -163.754562)
		(width 0.1143)
		(layer "B.Cu")
		(net "L14_85OHM_10INCH_DP")
	)
	(segment
		(start 189.0522 -166.430198)
		(end 189.609476 -166.332408)
		(width 0.1143)
		(layer "B.Cu")
		(net "L14_85OHM_10INCH_DP")
	)
	(segment
		(start 169.517822 -163.654486)
		(end 169.650664 -163.747196)
		(width 0.1143)
		(layer "B.Cu")
		(net "L14_85OHM_10INCH_DP")
	)
	(segment
		(start 183.094376 -163.643818)
		(end 183.226202 -163.73602)
		(width 0.1143)
		(layer "B.Cu")
		(net "L14_85OHM_10INCH_DP")
	)
	(segment
		(start 206.398622 -163.83)
		(end 206.491078 -163.69792)
		(width 0.1143)
		(layer "B.Cu")
		(net "L14_85OHM_10INCH_DP")
	)
	(segment
		(start 187.054236 -166.201852)
		(end 187.350908 -166.408862)
		(width 0.1143)
		(layer "B.Cu")
		(net "L14_85OHM_10INCH_DP")
	)
	(segment
		(start 174.249334 -163.717478)
		(end 174.608998 -163.654486)
		(width 0.1143)
		(layer "B.Cu")
		(net "L14_85OHM_10INCH_DP")
	)
	(segment
		(start 203.008484 -163.853368)
		(end 203.100686 -163.721288)
		(width 0.1143)
		(layer "B.Cu")
		(net "L14_85OHM_10INCH_DP")
	)
	(segment
		(start 181.32679 -166.013892)
		(end 180.944012 -163.841684)
		(width 0.1143)
		(layer "B.Cu")
		(net "L14_85OHM_10INCH_DP")
	)
	(segment
		(start 221.002606 -166.232332)
		(end 221.299278 -166.43985)
		(width 0.1143)
		(layer "B.Cu")
		(net "L14_85OHM_10INCH_DP")
	)
	(segment
		(start 167.954198 -163.750752)
		(end 168.384474 -166.194232)
		(width 0.1143)
		(layer "B.Cu")
		(net "L14_85OHM_10INCH_DP")
	)
	(segment
		(start 187.350908 -166.408862)
		(end 187.908692 -166.311326)
		(width 0.1143)
		(layer "B.Cu")
		(net "L14_85OHM_10INCH_DP")
	)
	(segment
		(start 197.23608 -166.197026)
		(end 197.532244 -166.40429)
		(width 0.1143)
		(layer "B.Cu")
		(net "L14_85OHM_10INCH_DP")
	)
	(segment
		(start 222.063564 -166.045134)
		(end 221.680024 -163.8681)
		(width 0.1143)
		(layer "B.Cu")
		(net "L14_85OHM_10INCH_DP")
	)
	(segment
		(start 178.865784 -166.407338)
		(end 179.422298 -166.309802)
		(width 0.1143)
		(layer "B.Cu")
		(net "L14_85OHM_10INCH_DP")
	)
	(segment
		(start 183.957214 -166.407338)
		(end 184.513982 -166.309548)
		(width 0.1143)
		(layer "B.Cu")
		(net "L14_85OHM_10INCH_DP")
	)
	(segment
		(start 165.763194 -163.715954)
		(end 166.123874 -163.652962)
		(width 0.1143)
		(layer "B.Cu")
		(net "L14_85OHM_10INCH_DP")
	)
	(segment
		(start 184.341262 -163.855654)
		(end 184.433718 -163.723574)
		(width 0.1143)
		(layer "B.Cu")
		(net "L14_85OHM_10INCH_DP")
	)
	(segment
		(start 167.748458 -166.008812)
		(end 167.368728 -163.853876)
		(width 0.1143)
		(layer "B.Cu")
		(net "L14_85OHM_10INCH_DP")
	)
	(segment
		(start 194.97548 -163.655756)
		(end 195.108322 -163.748466)
		(width 0.1143)
		(layer "B.Cu")
		(net "L14_85OHM_10INCH_DP")
	)
	(segment
		(start 195.835524 -166.405814)
		(end 196.3928 -166.30777)
		(width 0.1143)
		(layer "B.Cu")
		(net "L14_85OHM_10INCH_DP")
	)
	(segment
		(start 211.946998 -163.651692)
		(end 212.079078 -163.744148)
		(width 0.1143)
		(layer "B.Cu")
		(net "L14_85OHM_10INCH_DP")
	)
	(segment
		(start 166.123874 -163.652962)
		(end 166.256716 -163.745672)
		(width 0.1143)
		(layer "B.Cu")
		(net "L14_85OHM_10INCH_DP")
	)
	(segment
		(start 190.45174 -166.219124)
		(end 190.748412 -166.426642)
		(width 0.1143)
		(layer "B.Cu")
		(net "L14_85OHM_10INCH_DP")
	)
	(segment
		(start 175.85436 -163.853622)
		(end 175.94707 -163.72078)
		(width 0.1143)
		(layer "B.Cu")
		(net "L14_85OHM_10INCH_DP")
	)
	(segment
		(start 201.760328 -163.636198)
		(end 201.89317 -163.729162)
		(width 0.1143)
		(layer "B.Cu")
		(net "L14_85OHM_10INCH_DP")
	)
	(segment
		(start 181.039516 -163.705794)
		(end 181.3941 -163.64331)
		(width 0.1143)
		(layer "B.Cu")
		(net "L14_85OHM_10INCH_DP")
	)
	(segment
		(start 223.825816 -163.64839)
		(end 223.957896 -163.740592)
		(width 0.1143)
		(layer "B.Cu")
		(net "L14_85OHM_10INCH_DP")
	)
	(segment
		(start 213.19109 -163.851336)
		(end 213.286594 -163.715446)
		(width 0.1143)
		(layer "B.Cu")
		(net "L14_85OHM_10INCH_DP")
	)
	(segment
		(start 181.119526 -166.31031)
		(end 181.32679 -166.013892)
		(width 0.1143)
		(layer "B.Cu")
		(net "L14_85OHM_10INCH_DP")
	)
	(segment
		(start 220.435678 -163.671758)
		(end 220.567758 -163.764214)
		(width 0.1143)
		(layer "B.Cu")
		(net "L14_85OHM_10INCH_DP")
	)
	(segment
		(start 214.888318 -163.848542)
		(end 214.980774 -163.716462)
		(width 0.1143)
		(layer "B.Cu")
		(net "L14_85OHM_10INCH_DP")
	)
	(segment
		(start 227.557584 -165.035992)
		(end 227.937314 -165.415722)
		(width 0.1143)
		(layer "B.Cu")
		(net "L14_85OHM_10INCH_DP")
	)
	(segment
		(start 172.45965 -163.849304)
		(end 172.55236 -163.71697)
		(width 0.1143)
		(layer "B.Cu")
		(net "L14_85OHM_10INCH_DP")
	)
	(segment
		(start 162.660838 -166.029132)
		(end 162.273234 -163.830762)
		(width 0.1143)
		(layer "B.Cu")
		(net "L14_85OHM_10INCH_DP")
	)
	(segment
		(start 222.132652 -163.672266)
		(end 222.264732 -163.764722)
		(width 0.1143)
		(layer "B.Cu")
		(net "L14_85OHM_10INCH_DP")
	)
	(segment
		(start 196.802248 -163.733226)
		(end 197.23608 -166.197026)
		(width 0.1143)
		(layer "B.Cu")
		(net "L14_85OHM_10INCH_DP")
	)
	(segment
		(start 201.483722 -166.32428)
		(end 201.694288 -166.024814)
		(width 0.1143)
		(layer "B.Cu")
		(net "L14_85OHM_10INCH_DP")
	)
	(segment
		(start 223.552766 -166.338504)
		(end 223.760284 -166.04234)
		(width 0.1143)
		(layer "B.Cu")
		(net "L14_85OHM_10INCH_DP")
	)
	(segment
		(start 214.980774 -163.716462)
		(end 215.341454 -163.65347)
		(width 0.1143)
		(layer "B.Cu")
		(net "L14_85OHM_10INCH_DP")
	)
	(segment
		(start 179.422298 -166.309802)
		(end 179.629816 -166.013638)
		(width 0.1143)
		(layer "B.Cu")
		(net "L14_85OHM_10INCH_DP")
	)
	(segment
		(start 206.577692 -166.320216)
		(end 206.78521 -166.024052)
		(width 0.1143)
		(layer "B.Cu")
		(net "L14_85OHM_10INCH_DP")
	)
	(segment
		(start 165.670738 -163.848288)
		(end 165.763194 -163.715954)
		(width 0.1143)
		(layer "B.Cu")
		(net "L14_85OHM_10INCH_DP")
	)
	(segment
		(start 216.204292 -166.41699)
		(end 216.76106 -166.3192)
		(width 0.1143)
		(layer "B.Cu")
		(net "L14_85OHM_10INCH_DP")
	)
	(segment
		(start 218.870022 -163.761166)
		(end 219.301314 -166.211504)
		(width 0.1143)
		(layer "B.Cu")
		(net "L14_85OHM_10INCH_DP")
	)
	(segment
		(start 207.421988 -166.216076)
		(end 207.718914 -166.423086)
		(width 0.1143)
		(layer "B.Cu")
		(net "L14_85OHM_10INCH_DP")
	)
	(segment
		(start 189.609476 -166.332408)
		(end 189.816486 -166.035482)
		(width 0.1143)
		(layer "B.Cu")
		(net "L14_85OHM_10INCH_DP")
	)
	(segment
		(start 168.384474 -166.194232)
		(end 168.680638 -166.401496)
		(width 0.1143)
		(layer "B.Cu")
		(net "L14_85OHM_10INCH_DP")
	)
	(segment
		(start 221.77248 -163.735766)
		(end 222.132652 -163.672266)
		(width 0.1143)
		(layer "B.Cu")
		(net "L14_85OHM_10INCH_DP")
	)
	(segment
		(start 208.4832 -166.029132)
		(end 208.098644 -163.846764)
		(width 0.1143)
		(layer "B.Cu")
		(net "L14_85OHM_10INCH_DP")
	)
	(segment
		(start 215.341454 -163.65347)
		(end 215.47328 -163.745672)
		(width 0.1143)
		(layer "B.Cu")
		(net "L14_85OHM_10INCH_DP")
	)
	(segment
		(start 164.062664 -163.694872)
		(end 164.422582 -163.631626)
		(width 0.1143)
		(layer "B.Cu")
		(net "L14_85OHM_10INCH_DP")
	)
	(segment
		(start 216.680796 -163.733226)
		(end 217.041476 -163.670234)
		(width 0.1143)
		(layer "B.Cu")
		(net "L14_85OHM_10INCH_DP")
	)
	(segment
		(start 169.06494 -163.850066)
		(end 169.15765 -163.717732)
		(width 0.1143)
		(layer "B.Cu")
		(net "L14_85OHM_10INCH_DP")
	)
	(segment
		(start 177.168048 -166.40429)
		(end 177.72507 -166.3065)
		(width 0.1143)
		(layer "B.Cu")
		(net "L14_85OHM_10INCH_DP")
	)
	(segment
		(start 170.937936 -166.32047)
		(end 171.1452 -166.02456)
		(width 0.1143)
		(layer "B.Cu")
		(net "L14_85OHM_10INCH_DP")
	)
	(segment
		(start 174.539656 -166.025576)
		(end 174.156624 -163.849812)
		(width 0.1143)
		(layer "B.Cu")
		(net "L14_85OHM_10INCH_DP")
	)
	(segment
		(start 213.573868 -166.023544)
		(end 213.19109 -163.851336)
		(width 0.1143)
		(layer "B.Cu")
		(net "L14_85OHM_10INCH_DP")
	)
	(segment
		(start 168.680638 -166.401496)
		(end 169.237914 -166.303706)
		(width 0.1143)
		(layer "B.Cu")
		(net "L14_85OHM_10INCH_DP")
	)
	(segment
		(start 183.02351 -166.008304)
		(end 182.64124 -163.83889)
		(width 0.1143)
		(layer "B.Cu")
		(net "L14_85OHM_10INCH_DP")
	)
	(segment
		(start 172.842682 -166.02202)
		(end 172.45965 -163.849304)
		(width 0.1143)
		(layer "B.Cu")
		(net "L14_85OHM_10INCH_DP")
	)
	(segment
		(start 218.37777 -163.731956)
		(end 218.737942 -163.668456)
		(width 0.1143)
		(layer "B.Cu")
		(net "L14_85OHM_10INCH_DP")
	)
	(segment
		(start 196.309488 -163.703508)
		(end 196.669406 -163.640262)
		(width 0.1143)
		(layer "B.Cu")
		(net "L14_85OHM_10INCH_DP")
	)
	(segment
		(start 174.333154 -166.32174)
		(end 174.539656 -166.025576)
		(width 0.1143)
		(layer "B.Cu")
		(net "L14_85OHM_10INCH_DP")
	)
	(segment
		(start 218.737942 -163.668456)
		(end 218.870022 -163.761166)
		(width 0.1143)
		(layer "B.Cu")
		(net "L14_85OHM_10INCH_DP")
	)
	(segment
		(start 198.296784 -166.01059)
		(end 197.912228 -163.828222)
		(width 0.1143)
		(layer "B.Cu")
		(net "L14_85OHM_10INCH_DP")
	)
	(segment
		(start 159.826452 -164.937948)
		(end 161.060892 -165.14445)
		(width 0.1143)
		(layer "B.Cu")
		(net "L14_85OHM_10INCH_DP")
	)
	(segment
		(start 176.871376 -166.196772)
		(end 177.168048 -166.40429)
		(width 0.1143)
		(layer "B.Cu")
		(net "L14_85OHM_10INCH_DP")
	)
	(segment
		(start 184.513982 -166.309548)
		(end 184.7215 -166.013384)
		(width 0.1143)
		(layer "B.Cu")
		(net "L14_85OHM_10INCH_DP")
	)
	(segment
		(start 210.38312 -163.75253)
		(end 210.815936 -166.209472)
		(width 0.1143)
		(layer "B.Cu")
		(net "L14_85OHM_10INCH_DP")
	)
	(segment
		(start 194.902582 -166.008812)
		(end 194.522344 -163.851082)
		(width 0.1143)
		(layer "B.Cu")
		(net "L14_85OHM_10INCH_DP")
	)
	(segment
		(start 175.47082 -166.411402)
		(end 176.02835 -166.313612)
		(width 0.1143)
		(layer "B.Cu")
		(net "L14_85OHM_10INCH_DP")
	)
	(segment
		(start 161.600134 -166.216584)
		(end 161.896298 -166.423086)
		(width 0.1143)
		(layer "B.Cu")
		(net "L14_85OHM_10INCH_DP")
	)
	(segment
		(start 190.748412 -166.426642)
		(end 191.305688 -166.328852)
		(width 0.1143)
		(layer "B.Cu")
		(net "L14_85OHM_10INCH_DP")
	)
	(segment
		(start 196.216778 -163.83635)
		(end 196.309488 -163.703508)
		(width 0.1143)
		(layer "B.Cu")
		(net "L14_85OHM_10INCH_DP")
	)
	(segment
		(start 192.144904 -166.194994)
		(end 192.440814 -166.402258)
		(width 0.1143)
		(layer "B.Cu")
		(net "L14_85OHM_10INCH_DP")
	)
	(segment
		(start 202.330558 -166.215568)
		(end 202.627484 -166.423086)
		(width 0.1143)
		(layer "B.Cu")
		(net "L14_85OHM_10INCH_DP")
	)
	(segment
		(start 185.577226 -166.056056)
		(end 185.710068 -166.14902)
		(width 0.1143)
		(layer "B.Cu")
		(net "L14_85OHM_10INCH_DN")
	)
	(segment
		(start 199.56272 -163.480496)
		(end 200.119742 -163.382706)
		(width 0.1143)
		(layer "B.Cu")
		(net "L14_85OHM_10INCH_DN")
	)
	(segment
		(start 173.831504 -166.164768)
		(end 174.192438 -166.101268)
		(width 0.1143)
		(layer "B.Cu")
		(net "L14_85OHM_10INCH_DN")
	)
	(segment
		(start 210.603592 -163.612068)
		(end 211.036408 -166.06901)
		(width 0.1143)
		(layer "B.Cu")
		(net "L14_85OHM_10INCH_DN")
	)
	(segment
		(start 214.633302 -163.7919)
		(end 214.840566 -163.49599)
		(width 0.1143)
		(layer "B.Cu")
		(net "L14_85OHM_10INCH_DN")
	)
	(segment
		(start 202.684126 -166.16807)
		(end 203.04379 -166.105078)
		(width 0.1143)
		(layer "B.Cu")
		(net "L14_85OHM_10INCH_DN")
	)
	(segment
		(start 204.248004 -166.075868)
		(end 204.380846 -166.168832)
		(width 0.1143)
		(layer "B.Cu")
		(net "L14_85OHM_10INCH_DN")
	)
	(segment
		(start 165.622732 -163.495482)
		(end 166.180516 -163.397946)
		(width 0.1143)
		(layer "B.Cu")
		(net "L14_85OHM_10INCH_DN")
	)
	(segment
		(start 174.109126 -163.497006)
		(end 174.66564 -163.39947)
		(width 0.1143)
		(layer "B.Cu")
		(net "L14_85OHM_10INCH_DN")
	)
	(segment
		(start 184.466484 -165.956742)
		(end 184.086246 -163.799012)
		(width 0.1143)
		(layer "B.Cu")
		(net "L14_85OHM_10INCH_DN")
	)
	(segment
		(start 167.400732 -166.084504)
		(end 167.493188 -165.95217)
		(width 0.1143)
		(layer "B.Cu")
		(net "L14_85OHM_10INCH_DN")
	)
	(segment
		(start 209.924142 -165.962838)
		(end 209.542634 -163.799266)
		(width 0.1143)
		(layer "B.Cu")
		(net "L14_85OHM_10INCH_DN")
	)
	(segment
		(start 172.587412 -165.965124)
		(end 172.204634 -163.792916)
		(width 0.1143)
		(layer "B.Cu")
		(net "L14_85OHM_10INCH_DN")
	)
	(segment
		(start 175.395382 -166.06393)
		(end 175.527462 -166.156386)
		(width 0.1143)
		(layer "B.Cu")
		(net "L14_85OHM_10INCH_DN")
	)
	(segment
		(start 201.816716 -163.381182)
		(end 202.113642 -163.5887)
		(width 0.1143)
		(layer "B.Cu")
		(net "L14_85OHM_10INCH_DN")
	)
	(segment
		(start 206.143606 -163.773358)
		(end 206.35087 -163.477448)
		(width 0.1143)
		(layer "B.Cu")
		(net "L14_85OHM_10INCH_DN")
	)
	(segment
		(start 180.619146 -166.153084)
		(end 180.979064 -166.089838)
		(width 0.1143)
		(layer "B.Cu")
		(net "L14_85OHM_10INCH_DN")
	)
	(segment
		(start 177.091848 -166.05631)
		(end 177.22469 -166.149274)
		(width 0.1143)
		(layer "B.Cu")
		(net "L14_85OHM_10INCH_DN")
	)
	(segment
		(start 162.405822 -165.97249)
		(end 162.018218 -163.77412)
		(width 0.1143)
		(layer "B.Cu")
		(net "L14_85OHM_10INCH_DN")
	)
	(segment
		(start 190.870586 -163.777676)
		(end 191.07785 -163.481766)
		(width 0.1143)
		(layer "B.Cu")
		(net "L14_85OHM_10INCH_DN")
	)
	(segment
		(start 178.991768 -163.781232)
		(end 179.19827 -163.485068)
		(width 0.1143)
		(layer "B.Cu")
		(net "L14_85OHM_10INCH_DN")
	)
	(segment
		(start 201.052684 -163.77539)
		(end 201.259948 -163.478972)
		(width 0.1143)
		(layer "B.Cu")
		(net "L14_85OHM_10INCH_DN")
	)
	(segment
		(start 174.66564 -163.39947)
		(end 174.962566 -163.606988)
		(width 0.1143)
		(layer "B.Cu")
		(net "L14_85OHM_10INCH_DN")
	)
	(segment
		(start 185.782966 -163.797996)
		(end 185.99023 -163.501832)
		(width 0.1143)
		(layer "B.Cu")
		(net "L14_85OHM_10INCH_DN")
	)
	(segment
		(start 166.180516 -163.397946)
		(end 166.477188 -163.604956)
		(width 0.1143)
		(layer "B.Cu")
		(net "L14_85OHM_10INCH_DN")
	)
	(segment
		(start 211.169504 -166.161974)
		(end 211.529168 -166.098982)
		(width 0.1143)
		(layer "B.Cu")
		(net "L14_85OHM_10INCH_DN")
	)
	(segment
		(start 224.270316 -164.121846)
		(end 224.71761 -164.67201)
		(width 0.1143)
		(layer "B.Cu")
		(net "L14_85OHM_10INCH_DN")
	)
	(segment
		(start 220.492066 -163.416488)
		(end 220.78823 -163.623752)
		(width 0.1143)
		(layer "B.Cu")
		(net "L14_85OHM_10INCH_DN")
	)
	(segment
		(start 167.04056 -166.148004)
		(end 167.400732 -166.084504)
		(width 0.1143)
		(layer "B.Cu")
		(net "L14_85OHM_10INCH_DN")
	)
	(segment
		(start 203.518262 -163.402772)
		(end 203.814172 -163.609782)
		(width 0.1143)
		(layer "B.Cu")
		(net "L14_85OHM_10INCH_DN")
	)
	(segment
		(start 161.190686 -164.921438)
		(end 161.735008 -165.590982)
		(width 0.1143)
		(layer "B.Cu")
		(net "L14_85OHM_10INCH_DN")
	)
	(segment
		(start 217.957146 -166.158672)
		(end 218.317064 -166.095426)
		(width 0.1143)
		(layer "B.Cu")
		(net "L14_85OHM_10INCH_DN")
	)
	(segment
		(start 187.40755 -166.153846)
		(end 187.76823 -166.090854)
		(width 0.1143)
		(layer "B.Cu")
		(net "L14_85OHM_10INCH_DN")
	)
	(segment
		(start 175.527462 -166.156386)
		(end 175.888142 -166.09314)
		(width 0.1143)
		(layer "B.Cu")
		(net "L14_85OHM_10INCH_DN")
	)
	(segment
		(start 165.415722 -163.7919)
		(end 165.622732 -163.495482)
		(width 0.1143)
		(layer "B.Cu")
		(net "L14_85OHM_10INCH_DN")
	)
	(segment
		(start 181.450742 -163.38804)
		(end 181.749954 -163.59759)
		(width 0.1143)
		(layer "B.Cu")
		(net "L14_85OHM_10INCH_DN")
	)
	(segment
		(start 219.090494 -163.620704)
		(end 219.521786 -166.070788)
		(width 0.1143)
		(layer "B.Cu")
		(net "L14_85OHM_10INCH_DN")
	)
	(segment
		(start 187.76823 -166.090854)
		(end 187.860686 -165.95852)
		(width 0.1143)
		(layer "B.Cu")
		(net "L14_85OHM_10INCH_DN")
	)
	(segment
		(start 199.355202 -163.77666)
		(end 199.56272 -163.480496)
		(width 0.1143)
		(layer "B.Cu")
		(net "L14_85OHM_10INCH_DN")
	)
	(segment
		(start 192.566544 -163.77412)
		(end 192.773554 -163.477194)
		(width 0.1143)
		(layer "B.Cu")
		(net "L14_85OHM_10INCH_DN")
	)
	(segment
		(start 175.806354 -163.500308)
		(end 176.363376 -163.402518)
		(width 0.1143)
		(layer "B.Cu")
		(net "L14_85OHM_10INCH_DN")
	)
	(segment
		(start 203.814172 -163.609782)
		(end 204.248004 -166.075868)
		(width 0.1143)
		(layer "B.Cu")
		(net "L14_85OHM_10INCH_DN")
	)
	(segment
		(start 178.922426 -166.152322)
		(end 179.28209 -166.08933)
		(width 0.1143)
		(layer "B.Cu")
		(net "L14_85OHM_10INCH_DN")
	)
	(segment
		(start 206.908146 -163.379658)
		(end 207.204056 -163.586668)
		(width 0.1143)
		(layer "B.Cu")
		(net "L14_85OHM_10INCH_DN")
	)
	(segment
		(start 190.805054 -166.171626)
		(end 191.16548 -166.10838)
		(width 0.1143)
		(layer "B.Cu")
		(net "L14_85OHM_10INCH_DN")
	)
	(segment
		(start 211.036408 -166.06901)
		(end 211.169504 -166.161974)
		(width 0.1143)
		(layer "B.Cu")
		(net "L14_85OHM_10INCH_DN")
	)
	(segment
		(start 172.204634 -163.792916)
		(end 172.411898 -163.496498)
		(width 0.1143)
		(layer "B.Cu")
		(net "L14_85OHM_10INCH_DN")
	)
	(segment
		(start 192.857628 -166.083488)
		(end 192.950084 -165.951154)
		(width 0.1143)
		(layer "B.Cu")
		(net "L14_85OHM_10INCH_DN")
	)
	(segment
		(start 194.554856 -166.083996)
		(end 194.647566 -165.95217)
		(width 0.1143)
		(layer "B.Cu")
		(net "L14_85OHM_10INCH_DN")
	)
	(segment
		(start 196.726048 -163.385246)
		(end 197.02272 -163.592764)
		(width 0.1143)
		(layer "B.Cu")
		(net "L14_85OHM_10INCH_DN")
	)
	(segment
		(start 194.647566 -165.95217)
		(end 194.267328 -163.794694)
		(width 0.1143)
		(layer "B.Cu")
		(net "L14_85OHM_10INCH_DN")
	)
	(segment
		(start 227.557584 -164.794692)
		(end 227.937314 -164.414962)
		(width 0.1143)
		(layer "B.Cu")
		(net "L14_85OHM_10INCH_DN")
	)
	(segment
		(start 177.677064 -165.953186)
		(end 177.295556 -163.789614)
		(width 0.1143)
		(layer "B.Cu")
		(net "L14_85OHM_10INCH_DN")
	)
	(segment
		(start 208.050892 -163.494212)
		(end 208.608168 -163.396422)
		(width 0.1143)
		(layer "B.Cu")
		(net "L14_85OHM_10INCH_DN")
	)
	(segment
		(start 173.265592 -163.606226)
		(end 173.699424 -166.072312)
		(width 0.1143)
		(layer "B.Cu")
		(net "L14_85OHM_10INCH_DN")
	)
	(segment
		(start 183.88076 -166.059612)
		(end 184.013602 -166.152322)
		(width 0.1143)
		(layer "B.Cu")
		(net "L14_85OHM_10INCH_DN")
	)
	(segment
		(start 192.365376 -166.054532)
		(end 192.497456 -166.146988)
		(width 0.1143)
		(layer "B.Cu")
		(net "L14_85OHM_10INCH_DN")
	)
	(segment
		(start 196.168772 -163.483036)
		(end 196.726048 -163.385246)
		(width 0.1143)
		(layer "B.Cu")
		(net "L14_85OHM_10INCH_DN")
	)
	(segment
		(start 202.55103 -166.075106)
		(end 202.684126 -166.16807)
		(width 0.1143)
		(layer "B.Cu")
		(net "L14_85OHM_10INCH_DN")
	)
	(segment
		(start 212.00364 -163.396676)
		(end 212.29955 -163.603686)
		(width 0.1143)
		(layer "B.Cu")
		(net "L14_85OHM_10INCH_DN")
	)
	(segment
		(start 184.373774 -166.089076)
		(end 184.466484 -165.956742)
		(width 0.1143)
		(layer "B.Cu")
		(net "L14_85OHM_10INCH_DN")
	)
	(segment
		(start 209.471768 -166.158926)
		(end 209.831432 -166.09568)
		(width 0.1143)
		(layer "B.Cu")
		(net "L14_85OHM_10INCH_DN")
	)
	(segment
		(start 167.113712 -163.797488)
		(end 167.320722 -163.500562)
		(width 0.1143)
		(layer "B.Cu")
		(net "L14_85OHM_10INCH_DN")
	)
	(segment
		(start 223.117664 -163.787328)
		(end 223.324928 -163.491418)
		(width 0.1143)
		(layer "B.Cu")
		(net "L14_85OHM_10INCH_DN")
	)
	(segment
		(start 186.843416 -163.611052)
		(end 187.274708 -166.061136)
		(width 0.1143)
		(layer "B.Cu")
		(net "L14_85OHM_10INCH_DN")
	)
	(segment
		(start 163.921948 -163.4744)
		(end 164.479224 -163.37661)
		(width 0.1143)
		(layer "B.Cu")
		(net "L14_85OHM_10INCH_DN")
	)
	(segment
		(start 222.91929 -166.088314)
		(end 223.052132 -166.181278)
		(width 0.1143)
		(layer "B.Cu")
		(net "L14_85OHM_10INCH_DN")
	)
	(segment
		(start 163.64585 -166.144194)
		(end 164.006022 -166.080694)
		(width 0.1143)
		(layer "B.Cu")
		(net "L14_85OHM_10INCH_DN")
	)
	(segment
		(start 187.274708 -166.061136)
		(end 187.40755 -166.153846)
		(width 0.1143)
		(layer "B.Cu")
		(net "L14_85OHM_10INCH_DN")
	)
	(segment
		(start 223.412558 -166.118032)
		(end 223.505268 -165.985698)
		(width 0.1143)
		(layer "B.Cu")
		(net "L14_85OHM_10INCH_DN")
	)
	(segment
		(start 166.477188 -163.604956)
		(end 166.90848 -166.055294)
		(width 0.1143)
		(layer "B.Cu")
		(net "L14_85OHM_10INCH_DN")
	)
	(segment
		(start 221.715838 -166.121588)
		(end 221.808548 -165.988746)
		(width 0.1143)
		(layer "B.Cu")
		(net "L14_85OHM_10INCH_DN")
	)
	(segment
		(start 190.672212 -166.078662)
		(end 190.805054 -166.171626)
		(width 0.1143)
		(layer "B.Cu")
		(net "L14_85OHM_10INCH_DN")
	)
	(segment
		(start 180.052472 -163.594034)
		(end 180.486304 -166.06012)
		(width 0.1143)
		(layer "B.Cu")
		(net "L14_85OHM_10INCH_DN")
	)
	(segment
		(start 200.119742 -163.382706)
		(end 200.416414 -163.590224)
		(width 0.1143)
		(layer "B.Cu")
		(net "L14_85OHM_10INCH_DN")
	)
	(segment
		(start 204.380846 -166.168832)
		(end 204.740764 -166.105586)
		(width 0.1143)
		(layer "B.Cu")
		(net "L14_85OHM_10INCH_DN")
	)
	(segment
		(start 212.866224 -166.162736)
		(end 213.226142 -166.09949)
		(width 0.1143)
		(layer "B.Cu")
		(net "L14_85OHM_10INCH_DN")
	)
	(segment
		(start 182.315612 -166.147242)
		(end 182.675784 -166.083996)
		(width 0.1143)
		(layer "B.Cu")
		(net "L14_85OHM_10INCH_DN")
	)
	(segment
		(start 217.097864 -163.414964)
		(end 217.394028 -163.622228)
		(width 0.1143)
		(layer "B.Cu")
		(net "L14_85OHM_10INCH_DN")
	)
	(segment
		(start 215.397842 -163.3982)
		(end 215.693752 -163.60521)
		(width 0.1143)
		(layer "B.Cu")
		(net "L14_85OHM_10INCH_DN")
	)
	(segment
		(start 199.288654 -166.165784)
		(end 199.649334 -166.102792)
		(width 0.1143)
		(layer "B.Cu")
		(net "L14_85OHM_10INCH_DN")
	)
	(segment
		(start 179.28209 -166.08933)
		(end 179.3748 -165.956996)
		(width 0.1143)
		(layer "B.Cu")
		(net "L14_85OHM_10INCH_DN")
	)
	(segment
		(start 220.78823 -163.623752)
		(end 221.223078 -166.09187)
		(width 0.1143)
		(layer "B.Cu")
		(net "L14_85OHM_10INCH_DN")
	)
	(segment
		(start 172.491908 -166.101014)
		(end 172.587412 -165.965124)
		(width 0.1143)
		(layer "B.Cu")
		(net "L14_85OHM_10INCH_DN")
	)
	(segment
		(start 167.320722 -163.500562)
		(end 167.877998 -163.402772)
		(width 0.1143)
		(layer "B.Cu")
		(net "L14_85OHM_10INCH_DN")
	)
	(segment
		(start 216.620852 -166.098728)
		(end 216.713562 -165.966394)
		(width 0.1143)
		(layer "B.Cu")
		(net "L14_85OHM_10INCH_DN")
	)
	(segment
		(start 184.086246 -163.799012)
		(end 184.29351 -163.503102)
		(width 0.1143)
		(layer "B.Cu")
		(net "L14_85OHM_10INCH_DN")
	)
	(segment
		(start 202.753468 -163.79698)
		(end 202.95997 -163.500816)
		(width 0.1143)
		(layer "B.Cu")
		(net "L14_85OHM_10INCH_DN")
	)
	(segment
		(start 169.871136 -163.60648)
		(end 170.305222 -166.070788)
		(width 0.1143)
		(layer "B.Cu")
		(net "L14_85OHM_10INCH_DN")
	)
	(segment
		(start 173.901608 -163.79317)
		(end 174.109126 -163.497006)
		(width 0.1143)
		(layer "B.Cu")
		(net "L14_85OHM_10INCH_DN")
	)
	(segment
		(start 166.90848 -166.055294)
		(end 167.04056 -166.148004)
		(width 0.1143)
		(layer "B.Cu")
		(net "L14_85OHM_10INCH_DN")
	)
	(segment
		(start 214.840566 -163.49599)
		(end 215.397842 -163.3982)
		(width 0.1143)
		(layer "B.Cu")
		(net "L14_85OHM_10INCH_DN")
	)
	(segment
		(start 172.001942 -166.068756)
		(end 172.137324 -166.163498)
		(width 0.1143)
		(layer "B.Cu")
		(net "L14_85OHM_10INCH_DN")
	)
	(segment
		(start 202.113642 -163.5887)
		(end 202.55103 -166.075106)
		(width 0.1143)
		(layer "B.Cu")
		(net "L14_85OHM_10INCH_DN")
	)
	(segment
		(start 199.74179 -165.970712)
		(end 199.355202 -163.77666)
		(width 0.1143)
		(layer "B.Cu")
		(net "L14_85OHM_10INCH_DN")
	)
	(segment
		(start 180.486304 -166.06012)
		(end 180.619146 -166.153084)
		(width 0.1143)
		(layer "B.Cu")
		(net "L14_85OHM_10INCH_DN")
	)
	(segment
		(start 189.108842 -166.175182)
		(end 189.46876 -166.111936)
		(width 0.1143)
		(layer "B.Cu")
		(net "L14_85OHM_10INCH_DN")
	)
	(segment
		(start 204.740764 -166.105586)
		(end 204.833474 -165.973252)
		(width 0.1143)
		(layer "B.Cu")
		(net "L14_85OHM_10INCH_DN")
	)
	(segment
		(start 203.04379 -166.105078)
		(end 203.1365 -165.972744)
		(width 0.1143)
		(layer "B.Cu")
		(net "L14_85OHM_10INCH_DN")
	)
	(segment
		(start 213.146386 -163.494974)
		(end 213.69782 -163.397692)
		(width 0.1143)
		(layer "B.Cu")
		(net "L14_85OHM_10INCH_DN")
	)
	(segment
		(start 161.735008 -165.590982)
		(end 161.820606 -166.075868)
		(width 0.1143)
		(layer "B.Cu")
		(net "L14_85OHM_10INCH_DN")
	)
	(segment
		(start 168.604946 -166.05377)
		(end 168.737026 -166.146226)
		(width 0.1143)
		(layer "B.Cu")
		(net "L14_85OHM_10INCH_DN")
	)
	(segment
		(start 197.456552 -166.056564)
		(end 197.588632 -166.14902)
		(width 0.1143)
		(layer "B.Cu")
		(net "L14_85OHM_10INCH_DN")
	)
	(segment
		(start 223.505268 -165.985698)
		(end 223.117664 -163.787328)
		(width 0.1143)
		(layer "B.Cu")
		(net "L14_85OHM_10INCH_DN")
	)
	(segment
		(start 199.649334 -166.102792)
		(end 199.74179 -165.970712)
		(width 0.1143)
		(layer "B.Cu")
		(net "L14_85OHM_10INCH_DN")
	)
	(segment
		(start 168.809924 -163.793424)
		(end 169.017442 -163.49726)
		(width 0.1143)
		(layer "B.Cu")
		(net "L14_85OHM_10INCH_DN")
	)
	(segment
		(start 183.446674 -163.595558)
		(end 183.88076 -166.059612)
		(width 0.1143)
		(layer "B.Cu")
		(net "L14_85OHM_10INCH_DN")
	)
	(segment
		(start 195.760086 -166.058088)
		(end 195.892166 -166.150798)
		(width 0.1143)
		(layer "B.Cu")
		(net "L14_85OHM_10INCH_DN")
	)
	(segment
		(start 208.608168 -163.396422)
		(end 208.904332 -163.603686)
		(width 0.1143)
		(layer "B.Cu")
		(net "L14_85OHM_10INCH_DN")
	)
	(segment
		(start 171.569126 -163.612068)
		(end 172.001942 -166.068756)
		(width 0.1143)
		(layer "B.Cu")
		(net "L14_85OHM_10INCH_DN")
	)
	(segment
		(start 169.190162 -165.951154)
		(end 168.809924 -163.793424)
		(width 0.1143)
		(layer "B.Cu")
		(net "L14_85OHM_10INCH_DN")
	)
	(segment
		(start 162.018218 -163.77412)
		(end 162.225736 -163.477956)
		(width 0.1143)
		(layer "B.Cu")
		(net "L14_85OHM_10INCH_DN")
	)
	(segment
		(start 216.127838 -166.069264)
		(end 216.26068 -166.161974)
		(width 0.1143)
		(layer "B.Cu")
		(net "L14_85OHM_10INCH_DN")
	)
	(segment
		(start 211.621878 -165.966648)
		(end 211.238846 -163.790884)
		(width 0.1143)
		(layer "B.Cu")
		(net "L14_85OHM_10INCH_DN")
	)
	(segment
		(start 170.715432 -163.50234)
		(end 171.272454 -163.40455)
		(width 0.1143)
		(layer "B.Cu")
		(net "L14_85OHM_10INCH_DN")
	)
	(segment
		(start 170.437048 -166.16299)
		(end 170.797728 -166.099998)
		(width 0.1143)
		(layer "B.Cu")
		(net "L14_85OHM_10INCH_DN")
	)
	(segment
		(start 221.35592 -166.184834)
		(end 221.715838 -166.121588)
		(width 0.1143)
		(layer "B.Cu")
		(net "L14_85OHM_10INCH_DN")
	)
	(segment
		(start 194.267328 -163.794694)
		(end 194.474338 -163.498276)
		(width 0.1143)
		(layer "B.Cu")
		(net "L14_85OHM_10INCH_DN")
	)
	(segment
		(start 182.18277 -166.054278)
		(end 182.315612 -166.147242)
		(width 0.1143)
		(layer "B.Cu")
		(net "L14_85OHM_10INCH_DN")
	)
	(segment
		(start 200.98893 -166.166292)
		(end 201.343514 -166.103808)
		(width 0.1143)
		(layer "B.Cu")
		(net "L14_85OHM_10INCH_DN")
	)
	(segment
		(start 179.756562 -163.387024)
		(end 180.052472 -163.594034)
		(width 0.1143)
		(layer "B.Cu")
		(net "L14_85OHM_10INCH_DN")
	)
	(segment
		(start 178.060604 -163.395406)
		(end 178.356514 -163.602416)
		(width 0.1143)
		(layer "B.Cu")
		(net "L14_85OHM_10INCH_DN")
	)
	(segment
		(start 211.238846 -163.790884)
		(end 211.445348 -163.49472)
		(width 0.1143)
		(layer "B.Cu")
		(net "L14_85OHM_10INCH_DN")
	)
	(segment
		(start 208.904332 -163.603686)
		(end 209.338926 -166.065962)
		(width 0.1143)
		(layer "B.Cu")
		(net "L14_85OHM_10INCH_DN")
	)
	(segment
		(start 207.843628 -163.790122)
		(end 208.050892 -163.494212)
		(width 0.1143)
		(layer "B.Cu")
		(net "L14_85OHM_10INCH_DN")
	)
	(segment
		(start 176.363376 -163.402518)
		(end 176.660048 -163.610036)
		(width 0.1143)
		(layer "B.Cu")
		(net "L14_85OHM_10INCH_DN")
	)
	(segment
		(start 206.35087 -163.477448)
		(end 206.908146 -163.379658)
		(width 0.1143)
		(layer "B.Cu")
		(net "L14_85OHM_10INCH_DN")
	)
	(segment
		(start 177.22469 -166.149274)
		(end 177.584354 -166.086028)
		(width 0.1143)
		(layer "B.Cu")
		(net "L14_85OHM_10INCH_DN")
	)
	(segment
		(start 207.775302 -166.16807)
		(end 208.135474 -166.104824)
		(width 0.1143)
		(layer "B.Cu")
		(net "L14_85OHM_10INCH_DN")
	)
	(segment
		(start 207.204056 -163.586668)
		(end 207.64246 -166.07536)
		(width 0.1143)
		(layer "B.Cu")
		(net "L14_85OHM_10INCH_DN")
	)
	(segment
		(start 169.017442 -163.49726)
		(end 169.57421 -163.39947)
		(width 0.1143)
		(layer "B.Cu")
		(net "L14_85OHM_10INCH_DN")
	)
	(segment
		(start 216.26068 -166.161974)
		(end 216.620852 -166.098728)
		(width 0.1143)
		(layer "B.Cu")
		(net "L14_85OHM_10INCH_DN")
	)
	(segment
		(start 200.853548 -166.07155)
		(end 200.98893 -166.166292)
		(width 0.1143)
		(layer "B.Cu")
		(net "L14_85OHM_10INCH_DN")
	)
	(segment
		(start 221.632018 -163.515294)
		(end 222.189294 -163.416996)
		(width 0.1143)
		(layer "B.Cu")
		(net "L14_85OHM_10INCH_DN")
	)
	(segment
		(start 157.841188 -164.400738)
		(end 158.220918 -164.780468)
		(width 0.1143)
		(layer "B.Cu")
		(net "L14_85OHM_10INCH_DN")
	)
	(segment
		(start 159.83712 -164.69487)
		(end 161.190686 -164.921438)
		(width 0.1143)
		(layer "B.Cu")
		(net "L14_85OHM_10INCH_DN")
	)
	(segment
		(start 172.411898 -163.496498)
		(end 172.968666 -163.398708)
		(width 0.1143)
		(layer "B.Cu")
		(net "L14_85OHM_10INCH_DN")
	)
	(segment
		(start 202.95997 -163.500816)
		(end 203.518262 -163.402772)
		(width 0.1143)
		(layer "B.Cu")
		(net "L14_85OHM_10INCH_DN")
	)
	(segment
		(start 164.098478 -165.94836)
		(end 163.714938 -163.771326)
		(width 0.1143)
		(layer "B.Cu")
		(net "L14_85OHM_10INCH_DN")
	)
	(segment
		(start 193.627502 -163.586922)
		(end 194.06235 -166.05504)
		(width 0.1143)
		(layer "B.Cu")
		(net "L14_85OHM_10INCH_DN")
	)
	(segment
		(start 169.097706 -166.083234)
		(end 169.190162 -165.951154)
		(width 0.1143)
		(layer "B.Cu")
		(net "L14_85OHM_10INCH_DN")
	)
	(segment
		(start 182.386224 -163.782248)
		(end 182.593488 -163.486338)
		(width 0.1143)
		(layer "B.Cu")
		(net "L14_85OHM_10INCH_DN")
	)
	(segment
		(start 188.244988 -163.406836)
		(end 188.541152 -163.6141)
		(width 0.1143)
		(layer "B.Cu")
		(net "L14_85OHM_10INCH_DN")
	)
	(segment
		(start 179.19827 -163.485068)
		(end 179.756562 -163.387024)
		(width 0.1143)
		(layer "B.Cu")
		(net "L14_85OHM_10INCH_DN")
	)
	(segment
		(start 213.318852 -165.967156)
		(end 212.93582 -163.79444)
		(width 0.1143)
		(layer "B.Cu")
		(net "L14_85OHM_10INCH_DN")
	)
	(segment
		(start 173.699424 -166.072312)
		(end 173.831504 -166.164768)
		(width 0.1143)
		(layer "B.Cu")
		(net "L14_85OHM_10INCH_DN")
	)
	(segment
		(start 204.446124 -163.775898)
		(end 204.65669 -163.476432)
		(width 0.1143)
		(layer "B.Cu")
		(net "L14_85OHM_10INCH_DN")
	)
	(segment
		(start 188.541152 -163.6141)
		(end 188.976 -166.082218)
		(width 0.1143)
		(layer "B.Cu")
		(net "L14_85OHM_10INCH_DN")
	)
	(segment
		(start 172.968666 -163.398708)
		(end 173.265592 -163.606226)
		(width 0.1143)
		(layer "B.Cu")
		(net "L14_85OHM_10INCH_DN")
	)
	(segment
		(start 220.015308 -166.100506)
		(end 220.107764 -165.968172)
		(width 0.1143)
		(layer "B.Cu")
		(net "L14_85OHM_10INCH_DN")
	)
	(segment
		(start 211.529168 -166.098982)
		(end 211.621878 -165.966648)
		(width 0.1143)
		(layer "B.Cu")
		(net "L14_85OHM_10INCH_DN")
	)
	(segment
		(start 184.013602 -166.152322)
		(end 184.373774 -166.089076)
		(width 0.1143)
		(layer "B.Cu")
		(net "L14_85OHM_10INCH_DN")
	)
	(segment
		(start 161.820606 -166.075868)
		(end 161.952686 -166.16807)
		(width 0.1143)
		(layer "B.Cu")
		(net "L14_85OHM_10INCH_DN")
	)
	(segment
		(start 184.850786 -163.405312)
		(end 185.14695 -163.612576)
		(width 0.1143)
		(layer "B.Cu")
		(net "L14_85OHM_10INCH_DN")
	)
	(segment
		(start 195.032122 -163.40074)
		(end 195.328794 -163.60775)
		(width 0.1143)
		(layer "B.Cu")
		(net "L14_85OHM_10INCH_DN")
	)
	(segment
		(start 186.547506 -163.403788)
		(end 186.843416 -163.611052)
		(width 0.1143)
		(layer "B.Cu")
		(net "L14_85OHM_10INCH_DN")
	)
	(segment
		(start 194.06235 -166.05504)
		(end 194.19443 -166.147496)
		(width 0.1143)
		(layer "B.Cu")
		(net "L14_85OHM_10INCH_DN")
	)
	(segment
		(start 219.93479 -163.514786)
		(end 220.492066 -163.416488)
		(width 0.1143)
		(layer "B.Cu")
		(net "L14_85OHM_10INCH_DN")
	)
	(segment
		(start 219.727526 -163.810442)
		(end 219.93479 -163.514786)
		(width 0.1143)
		(layer "B.Cu")
		(net "L14_85OHM_10INCH_DN")
	)
	(segment
		(start 221.223078 -166.09187)
		(end 221.35592 -166.184834)
		(width 0.1143)
		(layer "B.Cu")
		(net "L14_85OHM_10INCH_DN")
	)
	(segment
		(start 191.635126 -163.383722)
		(end 191.93129 -163.590478)
		(width 0.1143)
		(layer "B.Cu")
		(net "L14_85OHM_10INCH_DN")
	)
	(segment
		(start 191.25819 -165.976046)
		(end 190.870586 -163.777676)
		(width 0.1143)
		(layer "B.Cu")
		(net "L14_85OHM_10INCH_DN")
	)
	(segment
		(start 223.882204 -163.393374)
		(end 224.178368 -163.599876)
		(width 0.1143)
		(layer "B.Cu")
		(net "L14_85OHM_10INCH_DN")
	)
	(segment
		(start 219.654628 -166.163498)
		(end 220.015308 -166.100506)
		(width 0.1143)
		(layer "B.Cu")
		(net "L14_85OHM_10INCH_DN")
	)
	(segment
		(start 215.015572 -165.961314)
		(end 214.633302 -163.7919)
		(width 0.1143)
		(layer "B.Cu")
		(net "L14_85OHM_10INCH_DN")
	)
	(segment
		(start 170.890184 -165.967918)
		(end 170.507914 -163.798504)
		(width 0.1143)
		(layer "B.Cu")
		(net "L14_85OHM_10INCH_DN")
	)
	(segment
		(start 184.29351 -163.503102)
		(end 184.850786 -163.405312)
		(width 0.1143)
		(layer "B.Cu")
		(net "L14_85OHM_10INCH_DN")
	)
	(segment
		(start 174.962566 -163.606988)
		(end 175.395382 -166.06393)
		(width 0.1143)
		(layer "B.Cu")
		(net "L14_85OHM_10INCH_DN")
	)
	(segment
		(start 218.794584 -163.41344)
		(end 219.090494 -163.620704)
		(width 0.1143)
		(layer "B.Cu")
		(net "L14_85OHM_10INCH_DN")
	)
	(segment
		(start 158.220918 -164.780468)
		(end 158.732474 -164.780468)
		(width 0.1143)
		(layer "B.Cu")
		(net "L14_85OHM_10INCH_DN")
	)
	(segment
		(start 188.976 -166.082218)
		(end 189.108842 -166.175182)
		(width 0.1143)
		(layer "B.Cu")
		(net "L14_85OHM_10INCH_DN")
	)
	(segment
		(start 196.252338 -166.087298)
		(end 196.344794 -165.954964)
		(width 0.1143)
		(layer "B.Cu")
		(net "L14_85OHM_10INCH_DN")
	)
	(segment
		(start 178.356514 -163.602416)
		(end 178.78933 -166.059358)
		(width 0.1143)
		(layer "B.Cu")
		(net "L14_85OHM_10INCH_DN")
	)
	(segment
		(start 216.333324 -163.808664)
		(end 216.540588 -163.512754)
		(width 0.1143)
		(layer "B.Cu")
		(net "L14_85OHM_10INCH_DN")
	)
	(segment
		(start 162.783012 -163.380166)
		(end 163.079684 -163.587684)
		(width 0.1143)
		(layer "B.Cu")
		(net "L14_85OHM_10INCH_DN")
	)
	(segment
		(start 181.749954 -163.59759)
		(end 182.18277 -166.054278)
		(width 0.1143)
		(layer "B.Cu")
		(net "L14_85OHM_10INCH_DN")
	)
	(segment
		(start 182.768494 -165.951662)
		(end 182.386224 -163.782248)
		(width 0.1143)
		(layer "B.Cu")
		(net "L14_85OHM_10INCH_DN")
	)
	(segment
		(start 227.03663 -164.794692)
		(end 227.557584 -164.794692)
		(width 0.1143)
		(layer "B.Cu")
		(net "L14_85OHM_10INCH_DN")
	)
	(segment
		(start 165.70325 -166.081202)
		(end 165.79596 -165.949376)
		(width 0.1143)
		(layer "B.Cu")
		(net "L14_85OHM_10INCH_DN")
	)
	(segment
		(start 224.178368 -163.599876)
		(end 224.270316 -164.121846)
		(width 0.1143)
		(layer "B.Cu")
		(net "L14_85OHM_10INCH_DN")
	)
	(segment
		(start 210.307682 -163.405058)
		(end 210.603592 -163.612068)
		(width 0.1143)
		(layer "B.Cu")
		(net "L14_85OHM_10INCH_DN")
	)
	(segment
		(start 177.584354 -166.086028)
		(end 177.677064 -165.953186)
		(width 0.1143)
		(layer "B.Cu")
		(net "L14_85OHM_10INCH_DN")
	)
	(segment
		(start 177.503074 -163.493196)
		(end 178.060604 -163.395406)
		(width 0.1143)
		(layer "B.Cu")
		(net "L14_85OHM_10INCH_DN")
	)
	(segment
		(start 171.272454 -163.40455)
		(end 171.569126 -163.612068)
		(width 0.1143)
		(layer "B.Cu")
		(net "L14_85OHM_10INCH_DN")
	)
	(segment
		(start 220.107764 -165.968172)
		(end 219.727526 -163.810442)
		(width 0.1143)
		(layer "B.Cu")
		(net "L14_85OHM_10INCH_DN")
	)
	(segment
		(start 185.710068 -166.14902)
		(end 186.069986 -166.085774)
		(width 0.1143)
		(layer "B.Cu")
		(net "L14_85OHM_10INCH_DN")
	)
	(segment
		(start 180.899308 -163.485322)
		(end 181.450742 -163.38804)
		(width 0.1143)
		(layer "B.Cu")
		(net "L14_85OHM_10INCH_DN")
	)
	(segment
		(start 176.660048 -163.610036)
		(end 177.091848 -166.05631)
		(width 0.1143)
		(layer "B.Cu")
		(net "L14_85OHM_10INCH_DN")
	)
	(segment
		(start 209.338926 -166.065962)
		(end 209.471768 -166.158926)
		(width 0.1143)
		(layer "B.Cu")
		(net "L14_85OHM_10INCH_DN")
	)
	(segment
		(start 200.416414 -163.590224)
		(end 200.853548 -166.07155)
		(width 0.1143)
		(layer "B.Cu")
		(net "L14_85OHM_10INCH_DN")
	)
	(segment
		(start 192.950084 -165.951154)
		(end 192.566544 -163.77412)
		(width 0.1143)
		(layer "B.Cu")
		(net "L14_85OHM_10INCH_DN")
	)
	(segment
		(start 205.208124 -163.37915)
		(end 205.507336 -163.5887)
		(width 0.1143)
		(layer "B.Cu")
		(net "L14_85OHM_10INCH_DN")
	)
	(segment
		(start 204.65669 -163.476432)
		(end 205.208124 -163.37915)
		(width 0.1143)
		(layer "B.Cu")
		(net "L14_85OHM_10INCH_DN")
	)
	(segment
		(start 199.156828 -166.073582)
		(end 199.288654 -166.165784)
		(width 0.1143)
		(layer "B.Cu")
		(net "L14_85OHM_10INCH_DN")
	)
	(segment
		(start 163.079684 -163.587684)
		(end 163.51377 -166.051738)
		(width 0.1143)
		(layer "B.Cu")
		(net "L14_85OHM_10INCH_DN")
	)
	(segment
		(start 207.64246 -166.07536)
		(end 207.775302 -166.16807)
		(width 0.1143)
		(layer "B.Cu")
		(net "L14_85OHM_10INCH_DN")
	)
	(segment
		(start 196.344794 -165.954964)
		(end 195.961762 -163.779962)
		(width 0.1143)
		(layer "B.Cu")
		(net "L14_85OHM_10INCH_DN")
	)
	(segment
		(start 203.1365 -165.972744)
		(end 202.753468 -163.79698)
		(width 0.1143)
		(layer "B.Cu")
		(net "L14_85OHM_10INCH_DN")
	)
	(segment
		(start 178.78933 -166.059358)
		(end 178.922426 -166.152322)
		(width 0.1143)
		(layer "B.Cu")
		(net "L14_85OHM_10INCH_DN")
	)
	(segment
		(start 175.599344 -163.797234)
		(end 175.806354 -163.500308)
		(width 0.1143)
		(layer "B.Cu")
		(net "L14_85OHM_10INCH_DN")
	)
	(segment
		(start 209.831432 -166.09568)
		(end 209.924142 -165.962838)
		(width 0.1143)
		(layer "B.Cu")
		(net "L14_85OHM_10INCH_DN")
	)
	(segment
		(start 218.030044 -163.807648)
		(end 218.237308 -163.511484)
		(width 0.1143)
		(layer "B.Cu")
		(net "L14_85OHM_10INCH_DN")
	)
	(segment
		(start 218.237308 -163.511484)
		(end 218.794584 -163.41344)
		(width 0.1143)
		(layer "B.Cu")
		(net "L14_85OHM_10INCH_DN")
	)
	(segment
		(start 221.808548 -165.988746)
		(end 221.424754 -163.811458)
		(width 0.1143)
		(layer "B.Cu")
		(net "L14_85OHM_10INCH_DN")
	)
	(segment
		(start 164.775896 -163.584128)
		(end 165.210744 -166.052246)
		(width 0.1143)
		(layer "B.Cu")
		(net "L14_85OHM_10INCH_DN")
	)
	(segment
		(start 187.860686 -165.95852)
		(end 187.480448 -163.80079)
		(width 0.1143)
		(layer "B.Cu")
		(net "L14_85OHM_10INCH_DN")
	)
	(segment
		(start 204.833474 -165.973252)
		(end 204.446124 -163.775898)
		(width 0.1143)
		(layer "B.Cu")
		(net "L14_85OHM_10INCH_DN")
	)
	(segment
		(start 212.29955 -163.603686)
		(end 212.733382 -166.069772)
		(width 0.1143)
		(layer "B.Cu")
		(net "L14_85OHM_10INCH_DN")
	)
	(segment
		(start 218.409774 -165.962584)
		(end 218.030044 -163.807648)
		(width 0.1143)
		(layer "B.Cu")
		(net "L14_85OHM_10INCH_DN")
	)
	(segment
		(start 174.192438 -166.101268)
		(end 174.28464 -165.969188)
		(width 0.1143)
		(layer "B.Cu")
		(net "L14_85OHM_10INCH_DN")
	)
	(segment
		(start 197.588632 -166.14902)
		(end 197.949312 -166.086028)
		(width 0.1143)
		(layer "B.Cu")
		(net "L14_85OHM_10INCH_DN")
	)
	(segment
		(start 163.51377 -166.051738)
		(end 163.64585 -166.144194)
		(width 0.1143)
		(layer "B.Cu")
		(net "L14_85OHM_10INCH_DN")
	)
	(segment
		(start 214.429848 -166.06393)
		(end 214.56269 -166.156894)
		(width 0.1143)
		(layer "B.Cu")
		(net "L14_85OHM_10INCH_DN")
	)
	(segment
		(start 195.328794 -163.60775)
		(end 195.760086 -166.058088)
		(width 0.1143)
		(layer "B.Cu")
		(net "L14_85OHM_10INCH_DN")
	)
	(segment
		(start 195.961762 -163.779962)
		(end 196.168772 -163.483036)
		(width 0.1143)
		(layer "B.Cu")
		(net "L14_85OHM_10INCH_DN")
	)
	(segment
		(start 197.86473 -163.475416)
		(end 198.421498 -163.377626)
		(width 0.1143)
		(layer "B.Cu")
		(net "L14_85OHM_10INCH_DN")
	)
	(segment
		(start 185.14695 -163.612576)
		(end 185.577226 -166.056056)
		(width 0.1143)
		(layer "B.Cu")
		(net "L14_85OHM_10INCH_DN")
	)
	(segment
		(start 213.69782 -163.397692)
		(end 213.997032 -163.607242)
		(width 0.1143)
		(layer "B.Cu")
		(net "L14_85OHM_10INCH_DN")
	)
	(segment
		(start 189.942216 -163.407344)
		(end 190.238126 -163.614608)
		(width 0.1143)
		(layer "B.Cu")
		(net "L14_85OHM_10INCH_DN")
	)
	(segment
		(start 223.052132 -166.181278)
		(end 223.412558 -166.118032)
		(width 0.1143)
		(layer "B.Cu")
		(net "L14_85OHM_10INCH_DN")
	)
	(segment
		(start 174.28464 -165.969188)
		(end 173.901608 -163.79317)
		(width 0.1143)
		(layer "B.Cu")
		(net "L14_85OHM_10INCH_DN")
	)
	(segment
		(start 162.225736 -163.477956)
		(end 162.783012 -163.380166)
		(width 0.1143)
		(layer "B.Cu")
		(net "L14_85OHM_10INCH_DN")
	)
	(segment
		(start 219.521786 -166.070788)
		(end 219.654628 -166.163498)
		(width 0.1143)
		(layer "B.Cu")
		(net "L14_85OHM_10INCH_DN")
	)
	(segment
		(start 183.150764 -163.388548)
		(end 183.446674 -163.595558)
		(width 0.1143)
		(layer "B.Cu")
		(net "L14_85OHM_10INCH_DN")
	)
	(segment
		(start 189.38494 -163.505642)
		(end 189.942216 -163.407344)
		(width 0.1143)
		(layer "B.Cu")
		(net "L14_85OHM_10INCH_DN")
	)
	(segment
		(start 167.877998 -163.402772)
		(end 168.17467 -163.61029)
		(width 0.1143)
		(layer "B.Cu")
		(net "L14_85OHM_10INCH_DN")
	)
	(segment
		(start 211.445348 -163.49472)
		(end 212.00364 -163.396676)
		(width 0.1143)
		(layer "B.Cu")
		(net "L14_85OHM_10INCH_DN")
	)
	(segment
		(start 225.95205 -164.878512)
		(end 227.03663 -164.794692)
		(width 0.1143)
		(layer "B.Cu")
		(net "L14_85OHM_10INCH_DN")
	)
	(segment
		(start 216.540588 -163.512754)
		(end 217.097864 -163.414964)
		(width 0.1143)
		(layer "B.Cu")
		(net "L14_85OHM_10INCH_DN")
	)
	(segment
		(start 179.3748 -165.956996)
		(end 178.991768 -163.781232)
		(width 0.1143)
		(layer "B.Cu")
		(net "L14_85OHM_10INCH_DN")
	)
	(segment
		(start 162.313112 -166.10457)
		(end 162.405822 -165.97249)
		(width 0.1143)
		(layer "B.Cu")
		(net "L14_85OHM_10INCH_DN")
	)
	(segment
		(start 201.259948 -163.478972)
		(end 201.816716 -163.381182)
		(width 0.1143)
		(layer "B.Cu")
		(net "L14_85OHM_10INCH_DN")
	)
	(segment
		(start 158.732474 -164.780468)
		(end 159.83712 -164.69487)
		(width 0.1143)
		(layer "B.Cu")
		(net "L14_85OHM_10INCH_DN")
	)
	(segment
		(start 189.56147 -165.979094)
		(end 189.177676 -163.801806)
		(width 0.1143)
		(layer "B.Cu")
		(net "L14_85OHM_10INCH_DN")
	)
	(segment
		(start 212.93582 -163.79444)
		(end 213.146386 -163.494974)
		(width 0.1143)
		(layer "B.Cu")
		(net "L14_85OHM_10INCH_DN")
	)
	(segment
		(start 185.99023 -163.501832)
		(end 186.547506 -163.403788)
		(width 0.1143)
		(layer "B.Cu")
		(net "L14_85OHM_10INCH_DN")
	)
	(segment
		(start 224.71761 -164.67201)
		(end 225.95205 -164.878512)
		(width 0.1143)
		(layer "B.Cu")
		(net "L14_85OHM_10INCH_DN")
	)
	(segment
		(start 193.33083 -163.379404)
		(end 193.627502 -163.586922)
		(width 0.1143)
		(layer "B.Cu")
		(net "L14_85OHM_10INCH_DN")
	)
	(segment
		(start 194.19443 -166.147496)
		(end 194.554856 -166.083996)
		(width 0.1143)
		(layer "B.Cu")
		(net "L14_85OHM_10INCH_DN")
	)
	(segment
		(start 201.439018 -165.967918)
		(end 201.052684 -163.77539)
		(width 0.1143)
		(layer "B.Cu")
		(net "L14_85OHM_10INCH_DN")
	)
	(segment
		(start 161.952686 -166.16807)
		(end 162.313112 -166.10457)
		(width 0.1143)
		(layer "B.Cu")
		(net "L14_85OHM_10INCH_DN")
	)
	(segment
		(start 190.238126 -163.614608)
		(end 190.672212 -166.078662)
		(width 0.1143)
		(layer "B.Cu")
		(net "L14_85OHM_10INCH_DN")
	)
	(segment
		(start 177.295556 -163.789614)
		(end 177.503074 -163.493196)
		(width 0.1143)
		(layer "B.Cu")
		(net "L14_85OHM_10INCH_DN")
	)
	(segment
		(start 163.714938 -163.771326)
		(end 163.921948 -163.4744)
		(width 0.1143)
		(layer "B.Cu")
		(net "L14_85OHM_10INCH_DN")
	)
	(segment
		(start 195.892166 -166.150798)
		(end 196.252338 -166.087298)
		(width 0.1143)
		(layer "B.Cu")
		(net "L14_85OHM_10INCH_DN")
	)
	(segment
		(start 186.162696 -165.952932)
		(end 185.782966 -163.797996)
		(width 0.1143)
		(layer "B.Cu")
		(net "L14_85OHM_10INCH_DN")
	)
	(segment
		(start 206.530194 -165.96741)
		(end 206.143606 -163.773358)
		(width 0.1143)
		(layer "B.Cu")
		(net "L14_85OHM_10INCH_DN")
	)
	(segment
		(start 165.342824 -166.144702)
		(end 165.70325 -166.081202)
		(width 0.1143)
		(layer "B.Cu")
		(net "L14_85OHM_10INCH_DN")
	)
	(segment
		(start 209.542634 -163.799266)
		(end 209.750152 -163.502848)
		(width 0.1143)
		(layer "B.Cu")
		(net "L14_85OHM_10INCH_DN")
	)
	(segment
		(start 172.137324 -166.163498)
		(end 172.491908 -166.101014)
		(width 0.1143)
		(layer "B.Cu")
		(net "L14_85OHM_10INCH_DN")
	)
	(segment
		(start 191.07785 -163.481766)
		(end 191.635126 -163.383722)
		(width 0.1143)
		(layer "B.Cu")
		(net "L14_85OHM_10INCH_DN")
	)
	(segment
		(start 164.479224 -163.37661)
		(end 164.775896 -163.584128)
		(width 0.1143)
		(layer "B.Cu")
		(net "L14_85OHM_10INCH_DN")
	)
	(segment
		(start 189.46876 -166.111936)
		(end 189.56147 -165.979094)
		(width 0.1143)
		(layer "B.Cu")
		(net "L14_85OHM_10INCH_DN")
	)
	(segment
		(start 209.750152 -163.502848)
		(end 210.307682 -163.405058)
		(width 0.1143)
		(layer "B.Cu")
		(net "L14_85OHM_10INCH_DN")
	)
	(segment
		(start 169.57421 -163.39947)
		(end 169.871136 -163.60648)
		(width 0.1143)
		(layer "B.Cu")
		(net "L14_85OHM_10INCH_DN")
	)
	(segment
		(start 216.713562 -165.966394)
		(end 216.333324 -163.808664)
		(width 0.1143)
		(layer "B.Cu")
		(net "L14_85OHM_10INCH_DN")
	)
	(segment
		(start 205.94447 -166.070026)
		(end 206.077312 -166.16299)
		(width 0.1143)
		(layer "B.Cu")
		(net "L14_85OHM_10INCH_DN")
	)
	(segment
		(start 175.888142 -166.09314)
		(end 175.980852 -165.960552)
		(width 0.1143)
		(layer "B.Cu")
		(net "L14_85OHM_10INCH_DN")
	)
	(segment
		(start 208.228184 -165.97249)
		(end 207.843628 -163.790122)
		(width 0.1143)
		(layer "B.Cu")
		(net "L14_85OHM_10INCH_DN")
	)
	(segment
		(start 197.949312 -166.086028)
		(end 198.041768 -165.953948)
		(width 0.1143)
		(layer "B.Cu")
		(net "L14_85OHM_10INCH_DN")
	)
	(segment
		(start 170.305222 -166.070788)
		(end 170.437048 -166.16299)
		(width 0.1143)
		(layer "B.Cu")
		(net "L14_85OHM_10INCH_DN")
	)
	(segment
		(start 168.737026 -166.146226)
		(end 169.097706 -166.083234)
		(width 0.1143)
		(layer "B.Cu")
		(net "L14_85OHM_10INCH_DN")
	)
	(segment
		(start 217.394028 -163.622228)
		(end 217.824304 -166.065708)
		(width 0.1143)
		(layer "B.Cu")
		(net "L14_85OHM_10INCH_DN")
	)
	(segment
		(start 222.189294 -163.416996)
		(end 222.485204 -163.62426)
		(width 0.1143)
		(layer "B.Cu")
		(net "L14_85OHM_10INCH_DN")
	)
	(segment
		(start 175.980852 -165.960552)
		(end 175.599344 -163.797234)
		(width 0.1143)
		(layer "B.Cu")
		(net "L14_85OHM_10INCH_DN")
	)
	(segment
		(start 198.718424 -163.584636)
		(end 199.156828 -166.073582)
		(width 0.1143)
		(layer "B.Cu")
		(net "L14_85OHM_10INCH_DN")
	)
	(segment
		(start 223.324928 -163.491418)
		(end 223.882204 -163.393374)
		(width 0.1143)
		(layer "B.Cu")
		(net "L14_85OHM_10INCH_DN")
	)
	(segment
		(start 201.343514 -166.103808)
		(end 201.439018 -165.967918)
		(width 0.1143)
		(layer "B.Cu")
		(net "L14_85OHM_10INCH_DN")
	)
	(segment
		(start 217.824304 -166.065708)
		(end 217.957146 -166.158672)
		(width 0.1143)
		(layer "B.Cu")
		(net "L14_85OHM_10INCH_DN")
	)
	(segment
		(start 165.210744 -166.052246)
		(end 165.342824 -166.144702)
		(width 0.1143)
		(layer "B.Cu")
		(net "L14_85OHM_10INCH_DN")
	)
	(segment
		(start 167.493188 -165.95217)
		(end 167.113712 -163.797488)
		(width 0.1143)
		(layer "B.Cu")
		(net "L14_85OHM_10INCH_DN")
	)
	(segment
		(start 182.675784 -166.083996)
		(end 182.768494 -165.951662)
		(width 0.1143)
		(layer "B.Cu")
		(net "L14_85OHM_10INCH_DN")
	)
	(segment
		(start 218.317064 -166.095426)
		(end 218.409774 -165.962584)
		(width 0.1143)
		(layer "B.Cu")
		(net "L14_85OHM_10INCH_DN")
	)
	(segment
		(start 180.688742 -163.784788)
		(end 180.899308 -163.485322)
		(width 0.1143)
		(layer "B.Cu")
		(net "L14_85OHM_10INCH_DN")
	)
	(segment
		(start 187.480448 -163.80079)
		(end 187.687712 -163.505134)
		(width 0.1143)
		(layer "B.Cu")
		(net "L14_85OHM_10INCH_DN")
	)
	(segment
		(start 170.797728 -166.099998)
		(end 170.890184 -165.967918)
		(width 0.1143)
		(layer "B.Cu")
		(net "L14_85OHM_10INCH_DN")
	)
	(segment
		(start 192.497456 -166.146988)
		(end 192.857628 -166.083488)
		(width 0.1143)
		(layer "B.Cu")
		(net "L14_85OHM_10INCH_DN")
	)
	(segment
		(start 222.485204 -163.62426)
		(end 222.91929 -166.088314)
		(width 0.1143)
		(layer "B.Cu")
		(net "L14_85OHM_10INCH_DN")
	)
	(segment
		(start 213.226142 -166.09949)
		(end 213.318852 -165.967156)
		(width 0.1143)
		(layer "B.Cu")
		(net "L14_85OHM_10INCH_DN")
	)
	(segment
		(start 194.474338 -163.498276)
		(end 195.032122 -163.40074)
		(width 0.1143)
		(layer "B.Cu")
		(net "L14_85OHM_10INCH_DN")
	)
	(segment
		(start 213.997032 -163.607242)
		(end 214.429848 -166.06393)
		(width 0.1143)
		(layer "B.Cu")
		(net "L14_85OHM_10INCH_DN")
	)
	(segment
		(start 191.16548 -166.10838)
		(end 191.25819 -165.976046)
		(width 0.1143)
		(layer "B.Cu")
		(net "L14_85OHM_10INCH_DN")
	)
	(segment
		(start 170.507914 -163.798504)
		(end 170.715432 -163.50234)
		(width 0.1143)
		(layer "B.Cu")
		(net "L14_85OHM_10INCH_DN")
	)
	(segment
		(start 206.437484 -166.099744)
		(end 206.530194 -165.96741)
		(width 0.1143)
		(layer "B.Cu")
		(net "L14_85OHM_10INCH_DN")
	)
	(segment
		(start 182.593488 -163.486338)
		(end 183.150764 -163.388548)
		(width 0.1143)
		(layer "B.Cu")
		(net "L14_85OHM_10INCH_DN")
	)
	(segment
		(start 189.177676 -163.801806)
		(end 189.38494 -163.505642)
		(width 0.1143)
		(layer "B.Cu")
		(net "L14_85OHM_10INCH_DN")
	)
	(segment
		(start 215.693752 -163.60521)
		(end 216.127838 -166.069264)
		(width 0.1143)
		(layer "B.Cu")
		(net "L14_85OHM_10INCH_DN")
	)
	(segment
		(start 186.069986 -166.085774)
		(end 186.162696 -165.952932)
		(width 0.1143)
		(layer "B.Cu")
		(net "L14_85OHM_10INCH_DN")
	)
	(segment
		(start 205.507336 -163.5887)
		(end 205.94447 -166.070026)
		(width 0.1143)
		(layer "B.Cu")
		(net "L14_85OHM_10INCH_DN")
	)
	(segment
		(start 197.657212 -163.77158)
		(end 197.86473 -163.475416)
		(width 0.1143)
		(layer "B.Cu")
		(net "L14_85OHM_10INCH_DN")
	)
	(segment
		(start 180.979064 -166.089838)
		(end 181.071774 -165.957504)
		(width 0.1143)
		(layer "B.Cu")
		(net "L14_85OHM_10INCH_DN")
	)
	(segment
		(start 212.733382 -166.069772)
		(end 212.866224 -166.162736)
		(width 0.1143)
		(layer "B.Cu")
		(net "L14_85OHM_10INCH_DN")
	)
	(segment
		(start 208.135474 -166.104824)
		(end 208.228184 -165.97249)
		(width 0.1143)
		(layer "B.Cu")
		(net "L14_85OHM_10INCH_DN")
	)
	(segment
		(start 181.071774 -165.957504)
		(end 180.688742 -163.784788)
		(width 0.1143)
		(layer "B.Cu")
		(net "L14_85OHM_10INCH_DN")
	)
	(segment
		(start 165.79596 -165.949376)
		(end 165.415722 -163.7919)
		(width 0.1143)
		(layer "B.Cu")
		(net "L14_85OHM_10INCH_DN")
	)
	(segment
		(start 214.922862 -166.093648)
		(end 215.015572 -165.961314)
		(width 0.1143)
		(layer "B.Cu")
		(net "L14_85OHM_10INCH_DN")
	)
	(segment
		(start 191.93129 -163.590478)
		(end 192.365376 -166.054532)
		(width 0.1143)
		(layer "B.Cu")
		(net "L14_85OHM_10INCH_DN")
	)
	(segment
		(start 197.02272 -163.592764)
		(end 197.456552 -166.056564)
		(width 0.1143)
		(layer "B.Cu")
		(net "L14_85OHM_10INCH_DN")
	)
	(segment
		(start 221.424754 -163.811458)
		(end 221.632018 -163.515294)
		(width 0.1143)
		(layer "B.Cu")
		(net "L14_85OHM_10INCH_DN")
	)
	(segment
		(start 168.17467 -163.61029)
		(end 168.604946 -166.05377)
		(width 0.1143)
		(layer "B.Cu")
		(net "L14_85OHM_10INCH_DN")
	)
	(segment
		(start 198.041768 -165.953948)
		(end 197.657212 -163.77158)
		(width 0.1143)
		(layer "B.Cu")
		(net "L14_85OHM_10INCH_DN")
	)
	(segment
		(start 198.421498 -163.377626)
		(end 198.718424 -163.584636)
		(width 0.1143)
		(layer "B.Cu")
		(net "L14_85OHM_10INCH_DN")
	)
	(segment
		(start 192.773554 -163.477194)
		(end 193.33083 -163.379404)
		(width 0.1143)
		(layer "B.Cu")
		(net "L14_85OHM_10INCH_DN")
	)
	(segment
		(start 187.687712 -163.505134)
		(end 188.244988 -163.406836)
		(width 0.1143)
		(layer "B.Cu")
		(net "L14_85OHM_10INCH_DN")
	)
	(segment
		(start 214.56269 -166.156894)
		(end 214.922862 -166.093648)
		(width 0.1143)
		(layer "B.Cu")
		(net "L14_85OHM_10INCH_DN")
	)
	(segment
		(start 206.077312 -166.16299)
		(end 206.437484 -166.099744)
		(width 0.1143)
		(layer "B.Cu")
		(net "L14_85OHM_10INCH_DN")
	)
	(segment
		(start 164.006022 -166.080694)
		(end 164.098478 -165.94836)
		(width 0.1143)
		(layer "B.Cu")
		(net "L14_85OHM_10INCH_DN")
	)
	(segment
		(start 195.726558 12.93495)
		(end 146.940016 12.93495)
		(width 0.1651)
		(layer "B.Cu")
		(net "L14_73OHM_6INCH_DP")
	)
	(segment
		(start 195.697348 10.34415)
		(end 147.823428 10.34415)
		(width 0.1651)
		(layer "B.Cu")
		(net "L14_73OHM_6INCH_DP")
	)
	(segment
		(start 145.87347 11.868404)
		(end 145.204434 11.868404)
		(width 0.1651)
		(layer "B.Cu")
		(net "L14_73OHM_6INCH_DP")
	)
	(segment
		(start 146.940016 12.93495)
		(end 145.87347 11.868404)
		(width 0.1651)
		(layer "B.Cu")
		(net "L14_73OHM_6INCH_DP")
	)
	(segment
		(start 147.823428 11.93165)
		(end 195.726558 11.93165)
		(width 0.1651)
		(layer "B.Cu")
		(net "L14_73OHM_6INCH_DP")
	)
	(segment
		(start 145.204434 11.868404)
		(end 144.080484 10.744454)
		(width 0.1651)
		(layer "B.Cu")
		(net "L14_73OHM_6INCH_DP")
	)
	(arc
		(start 147.823428 10.34415)
		(mid 147.029678 11.1379)
		(end 147.823428 11.93165)
		(width 0.1651)
		(layer "B.Cu")
		(net "L14_73OHM_6INCH_DP")
	)
	(arc
		(start 195.726558 11.93165)
		(mid 196.228208 12.4333)
		(end 195.726558 12.93495)
		(width 0.1651)
		(layer "B.Cu")
		(net "L14_73OHM_6INCH_DP")
	)
	(segment
		(start 145.752312 12.160504)
		(end 145.204434 12.160504)
		(width 0.1651)
		(layer "B.Cu")
		(net "L14_73OHM_6INCH_DN")
	)
	(segment
		(start 195.726558 13.22705)
		(end 146.818858 13.22705)
		(width 0.1651)
		(layer "B.Cu")
		(net "L14_73OHM_6INCH_DN")
	)
	(segment
		(start 195.697348 10.63625)
		(end 147.823428 10.63625)
		(width 0.1651)
		(layer "B.Cu")
		(net "L14_73OHM_6INCH_DN")
	)
	(segment
		(start 147.823428 11.63955)
		(end 195.726558 11.63955)
		(width 0.1651)
		(layer "B.Cu")
		(net "L14_73OHM_6INCH_DN")
	)
	(segment
		(start 145.204434 12.160504)
		(end 144.080484 13.284454)
		(width 0.1651)
		(layer "B.Cu")
		(net "L14_73OHM_6INCH_DN")
	)
	(segment
		(start 146.818858 13.22705)
		(end 145.752312 12.160504)
		(width 0.1651)
		(layer "B.Cu")
		(net "L14_73OHM_6INCH_DN")
	)
	(arc
		(start 147.823428 10.63625)
		(mid 147.321778 11.1379)
		(end 147.823428 11.63955)
		(width 0.1651)
		(layer "B.Cu")
		(net "L14_73OHM_6INCH_DN")
	)
	(arc
		(start 195.726558 11.63955)
		(mid 196.520308 12.4333)
		(end 195.726558 13.22705)
		(width 0.1651)
		(layer "B.Cu")
		(net "L14_73OHM_6INCH_DN")
	)
	(segment
		(start 37.820854 12.807442)
		(end 112.18672 12.807442)
		(width 0.10795)
		(layer "B.Cu")
		(net "L14_50OHM_6INCH")
	)
	(segment
		(start 36.092892 13.677392)
		(end 35.687 13.2715)
		(width 0.10795)
		(layer "B.Cu")
		(net "L14_50OHM_6INCH")
	)
	(segment
		(start 112.18672 13.677392)
		(end 36.092892 13.677392)
		(width 0.10795)
		(layer "B.Cu")
		(net "L14_50OHM_6INCH")
	)
	(arc
		(start 112.18672 12.807442)
		(mid 112.621822 13.242544)
		(end 112.18672 13.677392)
		(width 0.10795)
		(layer "B.Cu")
		(net "L14_50OHM_6INCH")
	)
	(segment
		(start 111.714788 11.66241)
		(end 36.61791 11.66241)
		(width 0.1651)
		(layer "B.Cu")
		(net "L14_40OHM_6INCH")
	)
	(segment
		(start 36.61791 11.66241)
		(end 35.687 10.7315)
		(width 0.1651)
		(layer "B.Cu")
		(net "L14_40OHM_6INCH")
	)
	(segment
		(start 37.184076 10.73531)
		(end 111.714788 10.73531)
		(width 0.1651)
		(layer "B.Cu")
		(net "L14_40OHM_6INCH")
	)
	(arc
		(start 111.714788 10.73531)
		(mid 112.178338 11.19886)
		(end 111.714788 11.66241)
		(width 0.1651)
		(layer "B.Cu")
		(net "L14_40OHM_6INCH")
	)
	(segment
		(start 370.854478 11.774678)
		(end 369.914932 11.774678)
		(width 0.101854)
		(layer "B.Cu")
		(net "L14_100OHM_6INCH_DP")
	)
	(segment
		(start 420.9669 12.85494)
		(end 371.93474 12.85494)
		(width 0.101854)
		(layer "B.Cu")
		(net "L14_100OHM_6INCH_DP")
	)
	(segment
		(start 371.93474 12.85494)
		(end 370.854478 11.774678)
		(width 0.101854)
		(layer "B.Cu")
		(net "L14_100OHM_6INCH_DP")
	)
	(segment
		(start 369.914932 11.774678)
		(end 368.873532 10.733278)
		(width 0.101854)
		(layer "B.Cu")
		(net "L14_100OHM_6INCH_DP")
	)
	(segment
		(start 421.27932 10.060432)
		(end 373.585486 10.060432)
		(width 0.101854)
		(layer "B.Cu")
		(net "L14_100OHM_6INCH_DP")
	)
	(segment
		(start 373.585994 11.914886)
		(end 420.9669 11.914886)
		(width 0.101854)
		(layer "B.Cu")
		(net "L14_100OHM_6INCH_DP")
	)
	(arc
		(start 420.9669 11.914886)
		(mid 421.437054 12.38504)
		(end 420.9669 12.85494)
		(width 0.101854)
		(layer "B.Cu")
		(net "L14_100OHM_6INCH_DP")
	)
	(arc
		(start 373.585486 10.060432)
		(mid 372.65864 10.987786)
		(end 373.585994 11.914886)
		(width 0.101854)
		(layer "B.Cu")
		(net "L14_100OHM_6INCH_DP")
	)
	(segment
		(start 371.745256 13.31214)
		(end 370.664994 12.231878)
		(width 0.101854)
		(layer "B.Cu")
		(net "L14_100OHM_6INCH_DN")
	)
	(segment
		(start 421.27932 10.517632)
		(end 373.58574 10.517632)
		(width 0.101854)
		(layer "B.Cu")
		(net "L14_100OHM_6INCH_DN")
	)
	(segment
		(start 420.9669 13.31214)
		(end 371.745256 13.31214)
		(width 0.101854)
		(layer "B.Cu")
		(net "L14_100OHM_6INCH_DN")
	)
	(segment
		(start 373.58574 11.457686)
		(end 420.9669 11.457686)
		(width 0.101854)
		(layer "B.Cu")
		(net "L14_100OHM_6INCH_DN")
	)
	(segment
		(start 369.914932 12.231878)
		(end 368.873532 13.273278)
		(width 0.101854)
		(layer "B.Cu")
		(net "L14_100OHM_6INCH_DN")
	)
	(segment
		(start 370.664994 12.231878)
		(end 369.914932 12.231878)
		(width 0.101854)
		(layer "B.Cu")
		(net "L14_100OHM_6INCH_DN")
	)
	(arc
		(start 373.58574 10.517632)
		(mid 373.115586 10.987786)
		(end 373.58574 11.457686)
		(width 0.101854)
		(layer "B.Cu")
		(net "L14_100OHM_6INCH_DN")
	)
	(arc
		(start 420.9669 11.457686)
		(mid 421.894254 12.38504)
		(end 420.9669 13.31214)
		(width 0.101854)
		(layer "B.Cu")
		(net "L14_100OHM_6INCH_DN")
	)
	(segment
		(start 296.02176 12.6492)
		(end 346.329 12.6492)
		(width 0.102108)
		(layer "In11.Cu")
		(net "L12_95OHM_6INCH_DP")
	)
	(segment
		(start 294.584882 11.80719)
		(end 295.17975 11.80719)
		(width 0.102108)
		(layer "In11.Cu")
		(net "L12_95OHM_6INCH_DP")
	)
	(segment
		(start 296.9768 10.565384)
		(end 346.738702 10.565384)
		(width 0.102108)
		(layer "In11.Cu")
		(net "L12_95OHM_6INCH_DP")
	)
	(segment
		(start 293.518082 10.74039)
		(end 294.584882 11.80719)
		(width 0.102108)
		(layer "In11.Cu")
		(net "L12_95OHM_6INCH_DP")
	)
	(segment
		(start 295.17975 11.80719)
		(end 296.02176 12.6492)
		(width 0.102108)
		(layer "In11.Cu")
		(net "L12_95OHM_6INCH_DP")
	)
	(segment
		(start 346.329 12.013692)
		(end 296.9768 12.013692)
		(width 0.102108)
		(layer "In11.Cu")
		(net "L12_95OHM_6INCH_DP")
	)
	(arc
		(start 296.9768 12.013692)
		(mid 296.252646 11.289538)
		(end 296.9768 10.565384)
		(width 0.102108)
		(layer "In11.Cu")
		(net "L12_95OHM_6INCH_DP")
	)
	(arc
		(start 346.329 12.6492)
		(mid 346.646754 12.331446)
		(end 346.329 12.013692)
		(width 0.102108)
		(layer "In11.Cu")
		(net "L12_95OHM_6INCH_DP")
	)
	(segment
		(start 232.283 12.0396)
		(end 281.69489 12.0396)
		(width 0.1143)
		(layer "In11.Cu")
		(net "L12_85OHM_6INCH_DP")
	)
	(segment
		(start 281.69489 12.6873)
		(end 231.1019 12.6873)
		(width 0.1143)
		(layer "In11.Cu")
		(net "L12_85OHM_6INCH_DP")
	)
	(segment
		(start 230.221028 11.806428)
		(end 224.385886 11.806428)
		(width 0.1143)
		(layer "In11.Cu")
		(net "L12_85OHM_6INCH_DP")
	)
	(segment
		(start 281.725624 10.8077)
		(end 232.283 10.8077)
		(width 0.1143)
		(layer "In11.Cu")
		(net "L12_85OHM_6INCH_DP")
	)
	(segment
		(start 231.1019 12.6873)
		(end 230.221028 11.806428)
		(width 0.1143)
		(layer "In11.Cu")
		(net "L12_85OHM_6INCH_DP")
	)
	(segment
		(start 224.385886 11.806428)
		(end 223.261936 10.682478)
		(width 0.1143)
		(layer "In11.Cu")
		(net "L12_85OHM_6INCH_DP")
	)
	(arc
		(start 281.69489 12.0396)
		(mid 282.01874 12.36345)
		(end 281.69489 12.6873)
		(width 0.1143)
		(layer "In11.Cu")
		(net "L12_85OHM_6INCH_DP")
	)
	(arc
		(start 232.283 10.8077)
		(mid 231.66705 11.42365)
		(end 232.283 12.0396)
		(width 0.1143)
		(layer "In11.Cu")
		(net "L12_85OHM_6INCH_DP")
	)
	(segment
		(start 281.69489 12.9794)
		(end 230.980742 12.9794)
		(width 0.1143)
		(layer "In11.Cu")
		(net "L12_85OHM_6INCH_DN")
	)
	(segment
		(start 232.283 11.7475)
		(end 281.69489 11.7475)
		(width 0.1143)
		(layer "In11.Cu")
		(net "L12_85OHM_6INCH_DN")
	)
	(segment
		(start 230.980742 12.9794)
		(end 230.09987 12.098528)
		(width 0.1143)
		(layer "In11.Cu")
		(net "L12_85OHM_6INCH_DN")
	)
	(segment
		(start 281.725624 11.0998)
		(end 232.283 11.0998)
		(width 0.1143)
		(layer "In11.Cu")
		(net "L12_85OHM_6INCH_DN")
	)
	(segment
		(start 230.09987 12.098528)
		(end 224.385886 12.098528)
		(width 0.1143)
		(layer "In11.Cu")
		(net "L12_85OHM_6INCH_DN")
	)
	(segment
		(start 224.385886 12.098528)
		(end 223.261936 13.222478)
		(width 0.1143)
		(layer "In11.Cu")
		(net "L12_85OHM_6INCH_DN")
	)
	(arc
		(start 281.69489 11.7475)
		(mid 282.31084 12.36345)
		(end 281.69489 12.9794)
		(width 0.1143)
		(layer "In11.Cu")
		(net "L12_85OHM_6INCH_DN")
	)
	(arc
		(start 232.283 11.0998)
		(mid 231.95915 11.42365)
		(end 232.283 11.7475)
		(width 0.1143)
		(layer "In11.Cu")
		(net "L12_85OHM_6INCH_DN")
	)
	(segment
		(start 99.542092 -165.121082)
		(end 98.926142 -165.737032)
		(width 0.1143)
		(layer "F.Cu")
		(net "L12_85OHM_5INCH_DP")
	)
	(segment
		(start 100.14712 -165.482524)
		(end 99.785678 -165.121082)
		(width 0.1143)
		(layer "F.Cu")
		(net "L12_85OHM_5INCH_DP")
	)
	(segment
		(start 63.192152 -165.191186)
		(end 63.808102 -165.807136)
		(width 0.1143)
		(layer "F.Cu")
		(net "L12_85OHM_5INCH_DP")
	)
	(segment
		(start 62.587124 -165.545516)
		(end 62.941454 -165.191186)
		(width 0.1143)
		(layer "F.Cu")
		(net "L12_85OHM_5INCH_DP")
	)
	(segment
		(start 99.785678 -165.121082)
		(end 99.542092 -165.121082)
		(width 0.1143)
		(layer "F.Cu")
		(net "L12_85OHM_5INCH_DP")
	)
	(segment
		(start 62.941454 -165.191186)
		(end 63.192152 -165.191186)
		(width 0.1143)
		(layer "F.Cu")
		(net "L12_85OHM_5INCH_DP")
	)
	(via
		(at 63.808102 -165.807136)
		(size 0.5588)
		(drill 0.3048)
		(layers "F.Cu" "B.Cu")
		(net "L12_85OHM_5INCH_DP")
	)
	(via
		(at 98.926142 -165.737032)
		(size 0.5588)
		(drill 0.3048)
		(layers "F.Cu" "B.Cu")
		(net "L12_85OHM_5INCH_DP")
	)
	(segment
		(start 68.123308 -166.148512)
		(end 67.746372 -164.013388)
		(width 0.1143)
		(layer "In11.Cu")
		(net "L12_85OHM_5INCH_DP")
	)
	(segment
		(start 86.925658 -163.947602)
		(end 87.018114 -163.815014)
		(width 0.1143)
		(layer "In11.Cu")
		(net "L12_85OHM_5INCH_DP")
	)
	(segment
		(start 77.716634 -166.140892)
		(end 77.341222 -164.013642)
		(width 0.1143)
		(layer "In11.Cu")
		(net "L12_85OHM_5INCH_DP")
	)
	(segment
		(start 73.79081 -166.588948)
		(end 74.292206 -166.500302)
		(width 0.1143)
		(layer "In11.Cu")
		(net "L12_85OHM_5INCH_DP")
	)
	(segment
		(start 87.413338 -163.862258)
		(end 87.837264 -166.267638)
		(width 0.1143)
		(layer "In11.Cu")
		(net "L12_85OHM_5INCH_DP")
	)
	(segment
		(start 87.837264 -166.267638)
		(end 88.168226 -166.498778)
		(width 0.1143)
		(layer "In11.Cu")
		(net "L12_85OHM_5INCH_DP")
	)
	(segment
		(start 77.433932 -163.881054)
		(end 77.696822 -163.834826)
		(width 0.1143)
		(layer "In11.Cu")
		(net "L12_85OHM_5INCH_DP")
	)
	(segment
		(start 85.419184 -163.815014)
		(end 85.681312 -163.768786)
		(width 0.1143)
		(layer "In11.Cu")
		(net "L12_85OHM_5INCH_DP")
	)
	(segment
		(start 95.803974 -164.915342)
		(end 96.736408 -165.21176)
		(width 0.1143)
		(layer "In11.Cu")
		(net "L12_85OHM_5INCH_DP")
	)
	(segment
		(start 67.891914 -166.479728)
		(end 68.123308 -166.148512)
		(width 0.1143)
		(layer "In11.Cu")
		(net "L12_85OHM_5INCH_DP")
	)
	(segment
		(start 95.40748 -163.853876)
		(end 95.492824 -164.339016)
		(width 0.1143)
		(layer "In11.Cu")
		(net "L12_85OHM_5INCH_DP")
	)
	(segment
		(start 75.88631 -166.472108)
		(end 76.11745 -166.140638)
		(width 0.1143)
		(layer "In11.Cu")
		(net "L12_85OHM_5INCH_DP")
	)
	(segment
		(start 69.438774 -163.88461)
		(end 69.701664 -163.838382)
		(width 0.1143)
		(layer "In11.Cu")
		(net "L12_85OHM_5INCH_DP")
	)
	(segment
		(start 90.474038 -163.740338)
		(end 90.606626 -163.832794)
		(width 0.1143)
		(layer "In11.Cu")
		(net "L12_85OHM_5INCH_DP")
	)
	(segment
		(start 95.296736 -166.07536)
		(end 94.9198 -163.939982)
		(width 0.1143)
		(layer "In11.Cu")
		(net "L12_85OHM_5INCH_DP")
	)
	(segment
		(start 83.726782 -163.943284)
		(end 83.819492 -163.810188)
		(width 0.1143)
		(layer "In11.Cu")
		(net "L12_85OHM_5INCH_DP")
	)
	(segment
		(start 80.630522 -163.872672)
		(end 80.893158 -163.826444)
		(width 0.1143)
		(layer "In11.Cu")
		(net "L12_85OHM_5INCH_DP")
	)
	(segment
		(start 98.310192 -165.121082)
		(end 98.926142 -165.737032)
		(width 0.1143)
		(layer "In11.Cu")
		(net "L12_85OHM_5INCH_DP")
	)
	(segment
		(start 71.860918 -166.357554)
		(end 72.19188 -166.58844)
		(width 0.1143)
		(layer "In11.Cu")
		(net "L12_85OHM_5INCH_DP")
	)
	(segment
		(start 84.969096 -166.493952)
		(end 85.470492 -166.406068)
		(width 0.1143)
		(layer "In11.Cu")
		(net "L12_85OHM_5INCH_DP")
	)
	(segment
		(start 92.073984 -163.74491)
		(end 92.206572 -163.83762)
		(width 0.1143)
		(layer "In11.Cu")
		(net "L12_85OHM_5INCH_DP")
	)
	(segment
		(start 82.47507 -163.769802)
		(end 82.61731 -163.86937)
		(width 0.1143)
		(layer "In11.Cu")
		(net "L12_85OHM_5INCH_DP")
	)
	(segment
		(start 76.984606 -166.560246)
		(end 77.48524 -166.472108)
		(width 0.1143)
		(layer "In11.Cu")
		(net "L12_85OHM_5INCH_DP")
	)
	(segment
		(start 82.505042 -166.083234)
		(end 82.129884 -163.955222)
		(width 0.1143)
		(layer "In11.Cu")
		(net "L12_85OHM_5INCH_DP")
	)
	(segment
		(start 81.025746 -163.919154)
		(end 81.218786 -165.014402)
		(width 0.1143)
		(layer "In11.Cu")
		(net "L12_85OHM_5INCH_DP")
	)
	(segment
		(start 79.42707 -163.9189)
		(end 79.850234 -166.320724)
		(width 0.1143)
		(layer "In11.Cu")
		(net "L12_85OHM_5INCH_DP")
	)
	(segment
		(start 75.053952 -166.327836)
		(end 75.384914 -166.559992)
		(width 0.1143)
		(layer "In11.Cu")
		(net "L12_85OHM_5INCH_DP")
	)
	(segment
		(start 69.834506 -163.931092)
		(end 70.260718 -166.352728)
		(width 0.1143)
		(layer "In11.Cu")
		(net "L12_85OHM_5INCH_DP")
	)
	(segment
		(start 68.234052 -163.926012)
		(end 68.661788 -166.351712)
		(width 0.1143)
		(layer "In11.Cu")
		(net "L12_85OHM_5INCH_DP")
	)
	(segment
		(start 67.390518 -166.567866)
		(end 67.891914 -166.479728)
		(width 0.1143)
		(layer "In11.Cu")
		(net "L12_85OHM_5INCH_DP")
	)
	(segment
		(start 78.938882 -164.00526)
		(end 79.031592 -163.872672)
		(width 0.1143)
		(layer "In11.Cu")
		(net "L12_85OHM_5INCH_DP")
	)
	(segment
		(start 77.341222 -164.013642)
		(end 77.433932 -163.881054)
		(width 0.1143)
		(layer "In11.Cu")
		(net "L12_85OHM_5INCH_DP")
	)
	(segment
		(start 72.692006 -166.50081)
		(end 72.924416 -166.17061)
		(width 0.1143)
		(layer "In11.Cu")
		(net "L12_85OHM_5INCH_DP")
	)
	(segment
		(start 82.61731 -163.86937)
		(end 83.040474 -166.271448)
		(width 0.1143)
		(layer "In11.Cu")
		(net "L12_85OHM_5INCH_DP")
	)
	(segment
		(start 88.669368 -166.410386)
		(end 88.900254 -166.079932)
		(width 0.1143)
		(layer "In11.Cu")
		(net "L12_85OHM_5INCH_DP")
	)
	(segment
		(start 79.316326 -166.144956)
		(end 78.938882 -164.00526)
		(width 0.1143)
		(layer "In11.Cu")
		(net "L12_85OHM_5INCH_DP")
	)
	(segment
		(start 88.519254 -163.9189)
		(end 88.611964 -163.786566)
		(width 0.1143)
		(layer "In11.Cu")
		(net "L12_85OHM_5INCH_DP")
	)
	(segment
		(start 84.104226 -166.083234)
		(end 83.726782 -163.943284)
		(width 0.1143)
		(layer "In11.Cu")
		(net "L12_85OHM_5INCH_DP")
	)
	(segment
		(start 80.538066 -164.00526)
		(end 80.630522 -163.872672)
		(width 0.1143)
		(layer "In11.Cu")
		(net "L12_85OHM_5INCH_DP")
	)
	(segment
		(start 75.742292 -164.013134)
		(end 75.834748 -163.8808)
		(width 0.1143)
		(layer "In11.Cu")
		(net "L12_85OHM_5INCH_DP")
	)
	(segment
		(start 74.142854 -164.00907)
		(end 74.235056 -163.876482)
		(width 0.1143)
		(layer "In11.Cu")
		(net "L12_85OHM_5INCH_DP")
	)
	(segment
		(start 69.725286 -166.164006)
		(end 69.346318 -164.016944)
		(width 0.1143)
		(layer "In11.Cu")
		(net "L12_85OHM_5INCH_DP")
	)
	(segment
		(start 74.523854 -166.169848)
		(end 74.142854 -164.00907)
		(width 0.1143)
		(layer "In11.Cu")
		(net "L12_85OHM_5INCH_DP")
	)
	(segment
		(start 83.819492 -163.810188)
		(end 84.08162 -163.764468)
		(width 0.1143)
		(layer "In11.Cu")
		(net "L12_85OHM_5INCH_DP")
	)
	(segment
		(start 70.260718 -166.352728)
		(end 70.59168 -166.583868)
		(width 0.1143)
		(layer "In11.Cu")
		(net "L12_85OHM_5INCH_DP")
	)
	(segment
		(start 93.69679 -166.07155)
		(end 93.317822 -163.924234)
		(width 0.1143)
		(layer "In11.Cu")
		(net "L12_85OHM_5INCH_DP")
	)
	(segment
		(start 79.294482 -163.826444)
		(end 79.42707 -163.9189)
		(width 0.1143)
		(layer "In11.Cu")
		(net "L12_85OHM_5INCH_DP")
	)
	(segment
		(start 87.018114 -163.815014)
		(end 87.280496 -163.76904)
		(width 0.1143)
		(layer "In11.Cu")
		(net "L12_85OHM_5INCH_DP")
	)
	(segment
		(start 79.084932 -166.476934)
		(end 79.316326 -166.144956)
		(width 0.1143)
		(layer "In11.Cu")
		(net "L12_85OHM_5INCH_DP")
	)
	(segment
		(start 81.77276 -166.502334)
		(end 82.273902 -166.414196)
		(width 0.1143)
		(layer "In11.Cu")
		(net "L12_85OHM_5INCH_DP")
	)
	(segment
		(start 67.746372 -164.013388)
		(end 67.83959 -163.880292)
		(width 0.1143)
		(layer "In11.Cu")
		(net "L12_85OHM_5INCH_DP")
	)
	(segment
		(start 68.102226 -163.83381)
		(end 68.234052 -163.926012)
		(width 0.1143)
		(layer "In11.Cu")
		(net "L12_85OHM_5INCH_DP")
	)
	(segment
		(start 66.910458 -165.565836)
		(end 66.955416 -165.74262)
		(width 0.1143)
		(layer "In11.Cu")
		(net "L12_85OHM_5INCH_DP")
	)
	(segment
		(start 77.82941 -163.927282)
		(end 78.252574 -166.333424)
		(width 0.1143)
		(layer "In11.Cu")
		(net "L12_85OHM_5INCH_DP")
	)
	(segment
		(start 74.63028 -163.92271)
		(end 75.053952 -166.327836)
		(width 0.1143)
		(layer "In11.Cu")
		(net "L12_85OHM_5INCH_DP")
	)
	(segment
		(start 79.850234 -166.320724)
		(end 80.190594 -166.55923)
		(width 0.1143)
		(layer "In11.Cu")
		(net "L12_85OHM_5INCH_DP")
	)
	(segment
		(start 75.384914 -166.559992)
		(end 75.88631 -166.472108)
		(width 0.1143)
		(layer "In11.Cu")
		(net "L12_85OHM_5INCH_DP")
	)
	(segment
		(start 93.317822 -163.924234)
		(end 93.410278 -163.791392)
		(width 0.1143)
		(layer "In11.Cu")
		(net "L12_85OHM_5INCH_DP")
	)
	(segment
		(start 72.19188 -166.58844)
		(end 72.692006 -166.50081)
		(width 0.1143)
		(layer "In11.Cu")
		(net "L12_85OHM_5INCH_DP")
	)
	(segment
		(start 68.993004 -166.583868)
		(end 69.4944 -166.495476)
		(width 0.1143)
		(layer "In11.Cu")
		(net "L12_85OHM_5INCH_DP")
	)
	(segment
		(start 87.300816 -166.07536)
		(end 86.925658 -163.947602)
		(width 0.1143)
		(layer "In11.Cu")
		(net "L12_85OHM_5INCH_DP")
	)
	(segment
		(start 83.872832 -166.41445)
		(end 84.104226 -166.083234)
		(width 0.1143)
		(layer "In11.Cu")
		(net "L12_85OHM_5INCH_DP")
	)
	(segment
		(start 85.681312 -163.768786)
		(end 85.813646 -163.861242)
		(width 0.1143)
		(layer "In11.Cu")
		(net "L12_85OHM_5INCH_DP")
	)
	(segment
		(start 88.900254 -166.079932)
		(end 88.519254 -163.9189)
		(width 0.1143)
		(layer "In11.Cu")
		(net "L12_85OHM_5INCH_DP")
	)
	(segment
		(start 88.8746 -163.740084)
		(end 89.007442 -163.833556)
		(width 0.1143)
		(layer "In11.Cu")
		(net "L12_85OHM_5INCH_DP")
	)
	(segment
		(start 85.813646 -163.861242)
		(end 86.237572 -166.263066)
		(width 0.1143)
		(layer "In11.Cu")
		(net "L12_85OHM_5INCH_DP")
	)
	(segment
		(start 74.497692 -163.83)
		(end 74.63028 -163.92271)
		(width 0.1143)
		(layer "In11.Cu")
		(net "L12_85OHM_5INCH_DP")
	)
	(segment
		(start 67.05981 -166.336218)
		(end 67.390518 -166.567866)
		(width 0.1143)
		(layer "In11.Cu")
		(net "L12_85OHM_5INCH_DP")
	)
	(segment
		(start 92.097606 -166.071296)
		(end 91.718892 -163.923472)
		(width 0.1143)
		(layer "In11.Cu")
		(net "L12_85OHM_5INCH_DP")
	)
	(segment
		(start 64.878204 -165.191186)
		(end 65.964054 -165.104318)
		(width 0.1143)
		(layer "In11.Cu")
		(net "L12_85OHM_5INCH_DP")
	)
	(segment
		(start 93.410278 -163.791392)
		(end 93.67266 -163.745164)
		(width 0.1143)
		(layer "In11.Cu")
		(net "L12_85OHM_5INCH_DP")
	)
	(segment
		(start 91.36507 -166.490142)
		(end 91.866466 -166.402258)
		(width 0.1143)
		(layer "In11.Cu")
		(net "L12_85OHM_5INCH_DP")
	)
	(segment
		(start 79.031592 -163.872672)
		(end 79.294482 -163.826444)
		(width 0.1143)
		(layer "In11.Cu")
		(net "L12_85OHM_5INCH_DP")
	)
	(segment
		(start 83.040474 -166.271448)
		(end 83.371436 -166.502334)
		(width 0.1143)
		(layer "In11.Cu")
		(net "L12_85OHM_5INCH_DP")
	)
	(segment
		(start 71.324216 -166.165022)
		(end 70.945502 -164.017198)
		(width 0.1143)
		(layer "In11.Cu")
		(net "L12_85OHM_5INCH_DP")
	)
	(segment
		(start 75.834748 -163.8808)
		(end 76.097384 -163.834826)
		(width 0.1143)
		(layer "In11.Cu")
		(net "L12_85OHM_5INCH_DP")
	)
	(segment
		(start 73.030588 -163.92271)
		(end 73.459848 -166.356284)
		(width 0.1143)
		(layer "In11.Cu")
		(net "L12_85OHM_5INCH_DP")
	)
	(segment
		(start 86.237572 -166.263066)
		(end 86.568534 -166.493952)
		(width 0.1143)
		(layer "In11.Cu")
		(net "L12_85OHM_5INCH_DP")
	)
	(segment
		(start 92.206572 -163.83762)
		(end 92.633038 -166.259256)
		(width 0.1143)
		(layer "In11.Cu")
		(net "L12_85OHM_5INCH_DP")
	)
	(segment
		(start 94.233492 -166.264082)
		(end 94.563692 -166.495222)
		(width 0.1143)
		(layer "In11.Cu")
		(net "L12_85OHM_5INCH_DP")
	)
	(segment
		(start 72.924416 -166.17061)
		(end 72.543416 -164.008816)
		(width 0.1143)
		(layer "In11.Cu")
		(net "L12_85OHM_5INCH_DP")
	)
	(segment
		(start 95.492824 -164.339016)
		(end 95.5548 -164.58311)
		(width 0.1143)
		(layer "In11.Cu")
		(net "L12_85OHM_5INCH_DP")
	)
	(segment
		(start 78.252574 -166.333424)
		(end 78.584298 -166.56431)
		(width 0.1143)
		(layer "In11.Cu")
		(net "L12_85OHM_5INCH_DP")
	)
	(segment
		(start 92.633038 -166.259256)
		(end 92.964254 -166.490396)
		(width 0.1143)
		(layer "In11.Cu")
		(net "L12_85OHM_5INCH_DP")
	)
	(segment
		(start 85.326474 -163.947602)
		(end 85.419184 -163.815014)
		(width 0.1143)
		(layer "In11.Cu")
		(net "L12_85OHM_5INCH_DP")
	)
	(segment
		(start 92.964254 -166.490396)
		(end 93.46565 -166.402512)
		(width 0.1143)
		(layer "In11.Cu")
		(net "L12_85OHM_5INCH_DP")
	)
	(segment
		(start 76.653898 -166.329106)
		(end 76.984606 -166.560246)
		(width 0.1143)
		(layer "In11.Cu")
		(net "L12_85OHM_5INCH_DP")
	)
	(segment
		(start 84.638134 -166.263066)
		(end 84.969096 -166.493952)
		(width 0.1143)
		(layer "In11.Cu")
		(net "L12_85OHM_5INCH_DP")
	)
	(segment
		(start 84.08162 -163.764468)
		(end 84.214716 -163.857178)
		(width 0.1143)
		(layer "In11.Cu")
		(net "L12_85OHM_5INCH_DP")
	)
	(segment
		(start 65.964054 -165.104318)
		(end 66.75247 -165.355016)
		(width 0.1143)
		(layer "In11.Cu")
		(net "L12_85OHM_5INCH_DP")
	)
	(segment
		(start 93.805502 -163.838382)
		(end 94.233492 -166.264082)
		(width 0.1143)
		(layer "In11.Cu")
		(net "L12_85OHM_5INCH_DP")
	)
	(segment
		(start 85.470492 -166.406068)
		(end 85.701886 -166.074852)
		(width 0.1143)
		(layer "In11.Cu")
		(net "L12_85OHM_5INCH_DP")
	)
	(segment
		(start 93.67266 -163.745164)
		(end 93.805502 -163.838382)
		(width 0.1143)
		(layer "In11.Cu")
		(net "L12_85OHM_5INCH_DP")
	)
	(segment
		(start 72.898508 -163.830254)
		(end 73.030588 -163.92271)
		(width 0.1143)
		(layer "In11.Cu")
		(net "L12_85OHM_5INCH_DP")
	)
	(segment
		(start 69.346318 -164.016944)
		(end 69.438774 -163.88461)
		(width 0.1143)
		(layer "In11.Cu")
		(net "L12_85OHM_5INCH_DP")
	)
	(segment
		(start 67.83959 -163.880292)
		(end 68.102226 -163.83381)
		(width 0.1143)
		(layer "In11.Cu")
		(net "L12_85OHM_5INCH_DP")
	)
	(segment
		(start 84.214716 -163.857178)
		(end 84.638134 -166.263066)
		(width 0.1143)
		(layer "In11.Cu")
		(net "L12_85OHM_5INCH_DP")
	)
	(segment
		(start 94.563692 -166.495222)
		(end 95.064834 -166.406576)
		(width 0.1143)
		(layer "In11.Cu")
		(net "L12_85OHM_5INCH_DP")
	)
	(segment
		(start 91.033854 -166.259002)
		(end 91.36507 -166.490142)
		(width 0.1143)
		(layer "In11.Cu")
		(net "L12_85OHM_5INCH_DP")
	)
	(segment
		(start 87.280496 -163.76904)
		(end 87.413338 -163.862258)
		(width 0.1143)
		(layer "In11.Cu")
		(net "L12_85OHM_5INCH_DP")
	)
	(segment
		(start 82.229198 -163.812982)
		(end 82.47507 -163.769802)
		(width 0.1143)
		(layer "In11.Cu")
		(net "L12_85OHM_5INCH_DP")
	)
	(segment
		(start 73.459848 -166.356284)
		(end 73.79081 -166.588948)
		(width 0.1143)
		(layer "In11.Cu")
		(net "L12_85OHM_5INCH_DP")
	)
	(segment
		(start 76.097384 -163.834826)
		(end 76.229972 -163.927282)
		(width 0.1143)
		(layer "In11.Cu")
		(net "L12_85OHM_5INCH_DP")
	)
	(segment
		(start 90.499692 -166.079678)
		(end 90.118692 -163.918392)
		(width 0.1143)
		(layer "In11.Cu")
		(net "L12_85OHM_5INCH_DP")
	)
	(segment
		(start 88.611964 -163.786566)
		(end 88.8746 -163.740084)
		(width 0.1143)
		(layer "In11.Cu")
		(net "L12_85OHM_5INCH_DP")
	)
	(segment
		(start 74.292206 -166.500302)
		(end 74.523854 -166.169848)
		(width 0.1143)
		(layer "In11.Cu")
		(net "L12_85OHM_5INCH_DP")
	)
	(segment
		(start 91.718892 -163.923472)
		(end 91.811602 -163.790884)
		(width 0.1143)
		(layer "In11.Cu")
		(net "L12_85OHM_5INCH_DP")
	)
	(segment
		(start 95.275146 -163.761166)
		(end 95.40748 -163.853876)
		(width 0.1143)
		(layer "In11.Cu")
		(net "L12_85OHM_5INCH_DP")
	)
	(segment
		(start 94.9198 -163.939982)
		(end 95.01251 -163.807394)
		(width 0.1143)
		(layer "In11.Cu")
		(net "L12_85OHM_5INCH_DP")
	)
	(segment
		(start 76.11745 -166.140638)
		(end 75.742292 -164.013134)
		(width 0.1143)
		(layer "In11.Cu")
		(net "L12_85OHM_5INCH_DP")
	)
	(segment
		(start 71.037958 -163.884864)
		(end 71.300594 -163.838636)
		(width 0.1143)
		(layer "In11.Cu")
		(net "L12_85OHM_5INCH_DP")
	)
	(segment
		(start 82.273902 -166.414196)
		(end 82.505042 -166.083234)
		(width 0.1143)
		(layer "In11.Cu")
		(net "L12_85OHM_5INCH_DP")
	)
	(segment
		(start 97.867978 -165.121082)
		(end 98.310192 -165.121082)
		(width 0.1143)
		(layer "In11.Cu")
		(net "L12_85OHM_5INCH_DP")
	)
	(segment
		(start 70.59168 -166.583868)
		(end 71.092568 -166.496238)
		(width 0.1143)
		(layer "In11.Cu")
		(net "L12_85OHM_5INCH_DP")
	)
	(segment
		(start 95.01251 -163.807394)
		(end 95.275146 -163.761166)
		(width 0.1143)
		(layer "In11.Cu")
		(net "L12_85OHM_5INCH_DP")
	)
	(segment
		(start 91.811602 -163.790884)
		(end 92.073984 -163.74491)
		(width 0.1143)
		(layer "In11.Cu")
		(net "L12_85OHM_5INCH_DP")
	)
	(segment
		(start 69.701664 -163.838382)
		(end 69.834506 -163.931092)
		(width 0.1143)
		(layer "In11.Cu")
		(net "L12_85OHM_5INCH_DP")
	)
	(segment
		(start 88.168226 -166.498778)
		(end 88.669368 -166.410386)
		(width 0.1143)
		(layer "In11.Cu")
		(net "L12_85OHM_5INCH_DP")
	)
	(segment
		(start 90.211656 -163.786312)
		(end 90.474038 -163.740338)
		(width 0.1143)
		(layer "In11.Cu")
		(net "L12_85OHM_5INCH_DP")
	)
	(segment
		(start 82.129884 -163.955222)
		(end 82.229198 -163.812982)
		(width 0.1143)
		(layer "In11.Cu")
		(net "L12_85OHM_5INCH_DP")
	)
	(segment
		(start 71.433436 -163.931346)
		(end 71.860918 -166.357554)
		(width 0.1143)
		(layer "In11.Cu")
		(net "L12_85OHM_5INCH_DP")
	)
	(segment
		(start 89.007442 -163.833556)
		(end 89.436956 -166.267384)
		(width 0.1143)
		(layer "In11.Cu")
		(net "L12_85OHM_5INCH_DP")
	)
	(segment
		(start 80.675226 -166.47414)
		(end 80.913224 -166.133272)
		(width 0.1143)
		(layer "In11.Cu")
		(net "L12_85OHM_5INCH_DP")
	)
	(segment
		(start 63.808102 -165.807136)
		(end 64.424052 -165.191186)
		(width 0.1143)
		(layer "In11.Cu")
		(net "L12_85OHM_5INCH_DP")
	)
	(segment
		(start 70.945502 -164.017198)
		(end 71.037958 -163.884864)
		(width 0.1143)
		(layer "In11.Cu")
		(net "L12_85OHM_5INCH_DP")
	)
	(segment
		(start 81.218786 -165.014402)
		(end 81.441798 -166.271194)
		(width 0.1143)
		(layer "In11.Cu")
		(net "L12_85OHM_5INCH_DP")
	)
	(segment
		(start 66.75247 -165.355016)
		(end 66.910458 -165.565836)
		(width 0.1143)
		(layer "In11.Cu")
		(net "L12_85OHM_5INCH_DP")
	)
	(segment
		(start 71.300594 -163.838636)
		(end 71.433436 -163.931346)
		(width 0.1143)
		(layer "In11.Cu")
		(net "L12_85OHM_5INCH_DP")
	)
	(segment
		(start 89.436956 -166.267384)
		(end 89.767156 -166.498778)
		(width 0.1143)
		(layer "In11.Cu")
		(net "L12_85OHM_5INCH_DP")
	)
	(segment
		(start 85.701886 -166.074852)
		(end 85.326474 -163.947602)
		(width 0.1143)
		(layer "In11.Cu")
		(net "L12_85OHM_5INCH_DP")
	)
	(segment
		(start 89.767156 -166.498778)
		(end 90.268552 -166.41064)
		(width 0.1143)
		(layer "In11.Cu")
		(net "L12_85OHM_5INCH_DP")
	)
	(segment
		(start 96.736408 -165.21176)
		(end 97.867978 -165.121082)
		(width 0.1143)
		(layer "In11.Cu")
		(net "L12_85OHM_5INCH_DP")
	)
	(segment
		(start 90.118692 -163.918392)
		(end 90.211656 -163.786312)
		(width 0.1143)
		(layer "In11.Cu")
		(net "L12_85OHM_5INCH_DP")
	)
	(segment
		(start 87.069676 -166.406322)
		(end 87.300816 -166.07536)
		(width 0.1143)
		(layer "In11.Cu")
		(net "L12_85OHM_5INCH_DP")
	)
	(segment
		(start 64.424052 -165.191186)
		(end 64.878204 -165.191186)
		(width 0.1143)
		(layer "In11.Cu")
		(net "L12_85OHM_5INCH_DP")
	)
	(segment
		(start 90.606626 -163.832794)
		(end 91.033854 -166.259002)
		(width 0.1143)
		(layer "In11.Cu")
		(net "L12_85OHM_5INCH_DP")
	)
	(segment
		(start 83.371436 -166.502334)
		(end 83.872832 -166.41445)
		(width 0.1143)
		(layer "In11.Cu")
		(net "L12_85OHM_5INCH_DP")
	)
	(segment
		(start 86.568534 -166.493952)
		(end 87.069676 -166.406322)
		(width 0.1143)
		(layer "In11.Cu")
		(net "L12_85OHM_5INCH_DP")
	)
	(segment
		(start 95.064834 -166.406576)
		(end 95.296736 -166.07536)
		(width 0.1143)
		(layer "In11.Cu")
		(net "L12_85OHM_5INCH_DP")
	)
	(segment
		(start 72.543416 -164.008816)
		(end 72.635872 -163.876482)
		(width 0.1143)
		(layer "In11.Cu")
		(net "L12_85OHM_5INCH_DP")
	)
	(segment
		(start 66.955416 -165.74262)
		(end 67.05981 -166.336218)
		(width 0.1143)
		(layer "In11.Cu")
		(net "L12_85OHM_5INCH_DP")
	)
	(segment
		(start 93.46565 -166.402512)
		(end 93.69679 -166.07155)
		(width 0.1143)
		(layer "In11.Cu")
		(net "L12_85OHM_5INCH_DP")
	)
	(segment
		(start 80.190594 -166.55923)
		(end 80.675226 -166.47414)
		(width 0.1143)
		(layer "In11.Cu")
		(net "L12_85OHM_5INCH_DP")
	)
	(segment
		(start 68.661788 -166.351712)
		(end 68.993004 -166.583868)
		(width 0.1143)
		(layer "In11.Cu")
		(net "L12_85OHM_5INCH_DP")
	)
	(segment
		(start 78.584298 -166.56431)
		(end 79.084932 -166.476934)
		(width 0.1143)
		(layer "In11.Cu")
		(net "L12_85OHM_5INCH_DP")
	)
	(segment
		(start 76.229972 -163.927282)
		(end 76.653898 -166.329106)
		(width 0.1143)
		(layer "In11.Cu")
		(net "L12_85OHM_5INCH_DP")
	)
	(segment
		(start 77.696822 -163.834826)
		(end 77.82941 -163.927282)
		(width 0.1143)
		(layer "In11.Cu")
		(net "L12_85OHM_5INCH_DP")
	)
	(segment
		(start 80.893158 -163.826444)
		(end 81.025746 -163.919154)
		(width 0.1143)
		(layer "In11.Cu")
		(net "L12_85OHM_5INCH_DP")
	)
	(segment
		(start 77.48524 -166.472108)
		(end 77.716634 -166.140892)
		(width 0.1143)
		(layer "In11.Cu")
		(net "L12_85OHM_5INCH_DP")
	)
	(segment
		(start 95.5548 -164.58311)
		(end 95.803974 -164.915342)
		(width 0.1143)
		(layer "In11.Cu")
		(net "L12_85OHM_5INCH_DP")
	)
	(segment
		(start 81.441798 -166.271194)
		(end 81.77276 -166.502334)
		(width 0.1143)
		(layer "In11.Cu")
		(net "L12_85OHM_5INCH_DP")
	)
	(segment
		(start 72.635872 -163.876482)
		(end 72.898508 -163.830254)
		(width 0.1143)
		(layer "In11.Cu")
		(net "L12_85OHM_5INCH_DP")
	)
	(segment
		(start 80.913224 -166.133272)
		(end 80.538066 -164.00526)
		(width 0.1143)
		(layer "In11.Cu")
		(net "L12_85OHM_5INCH_DP")
	)
	(segment
		(start 74.235056 -163.876482)
		(end 74.497692 -163.83)
		(width 0.1143)
		(layer "In11.Cu")
		(net "L12_85OHM_5INCH_DP")
	)
	(segment
		(start 91.866466 -166.402258)
		(end 92.097606 -166.071296)
		(width 0.1143)
		(layer "In11.Cu")
		(net "L12_85OHM_5INCH_DP")
	)
	(segment
		(start 71.092568 -166.496238)
		(end 71.324216 -166.165022)
		(width 0.1143)
		(layer "In11.Cu")
		(net "L12_85OHM_5INCH_DP")
	)
	(segment
		(start 90.268552 -166.41064)
		(end 90.499692 -166.079678)
		(width 0.1143)
		(layer "In11.Cu")
		(net "L12_85OHM_5INCH_DP")
	)
	(segment
		(start 69.4944 -166.495476)
		(end 69.725286 -166.164006)
		(width 0.1143)
		(layer "In11.Cu")
		(net "L12_85OHM_5INCH_DP")
	)
	(segment
		(start 100.14712 -164.481764)
		(end 99.799902 -164.828982)
		(width 0.1143)
		(layer "F.Cu")
		(net "L12_85OHM_5INCH_DN")
	)
	(segment
		(start 62.941454 -164.899086)
		(end 63.192152 -164.899086)
		(width 0.1143)
		(layer "F.Cu")
		(net "L12_85OHM_5INCH_DN")
	)
	(segment
		(start 62.587124 -164.544756)
		(end 62.941454 -164.899086)
		(width 0.1143)
		(layer "F.Cu")
		(net "L12_85OHM_5INCH_DN")
	)
	(segment
		(start 63.192152 -164.899086)
		(end 63.808102 -164.283136)
		(width 0.1143)
		(layer "F.Cu")
		(net "L12_85OHM_5INCH_DN")
	)
	(segment
		(start 99.799902 -164.828982)
		(end 99.542092 -164.828982)
		(width 0.1143)
		(layer "F.Cu")
		(net "L12_85OHM_5INCH_DN")
	)
	(segment
		(start 99.542092 -164.828982)
		(end 98.926142 -164.213032)
		(width 0.1143)
		(layer "F.Cu")
		(net "L12_85OHM_5INCH_DN")
	)
	(via
		(at 63.808102 -164.283136)
		(size 0.5588)
		(drill 0.3048)
		(layers "F.Cu" "B.Cu")
		(net "L12_85OHM_5INCH_DN")
	)
	(via
		(at 98.926142 -164.213032)
		(size 0.5588)
		(drill 0.3048)
		(layers "F.Cu" "B.Cu")
		(net "L12_85OHM_5INCH_DN")
	)
	(segment
		(start 86.080346 -163.691062)
		(end 86.504272 -166.092886)
		(width 0.1143)
		(layer "In11.Cu")
		(net "L12_85OHM_5INCH_DN")
	)
	(segment
		(start 85.249004 -163.54806)
		(end 85.749638 -163.459922)
		(width 0.1143)
		(layer "In11.Cu")
		(net "L12_85OHM_5INCH_DN")
	)
	(segment
		(start 89.809828 -163.849558)
		(end 90.042238 -163.519358)
		(width 0.1143)
		(layer "In11.Cu")
		(net "L12_85OHM_5INCH_DN")
	)
	(segment
		(start 86.504272 -166.092886)
		(end 86.63686 -166.185342)
		(width 0.1143)
		(layer "In11.Cu")
		(net "L12_85OHM_5INCH_DN")
	)
	(segment
		(start 72.234552 -163.94049)
		(end 72.465692 -163.609528)
		(width 0.1143)
		(layer "In11.Cu")
		(net "L12_85OHM_5INCH_DN")
	)
	(segment
		(start 69.76999 -163.529772)
		(end 70.101206 -163.760912)
		(width 0.1143)
		(layer "In11.Cu")
		(net "L12_85OHM_5INCH_DN")
	)
	(segment
		(start 65.997836 -164.808408)
		(end 66.93027 -165.104826)
		(width 0.1143)
		(layer "In11.Cu")
		(net "L12_85OHM_5INCH_DN")
	)
	(segment
		(start 96.77019 -164.91585)
		(end 97.85604 -164.828982)
		(width 0.1143)
		(layer "In11.Cu")
		(net "L12_85OHM_5INCH_DN")
	)
	(segment
		(start 75.71613 -166.205154)
		(end 75.808586 -166.072566)
		(width 0.1143)
		(layer "In11.Cu")
		(net "L12_85OHM_5INCH_DN")
	)
	(segment
		(start 69.323966 -166.228776)
		(end 69.416422 -166.095934)
		(width 0.1143)
		(layer "In11.Cu")
		(net "L12_85OHM_5INCH_DN")
	)
	(segment
		(start 93.387926 -166.003224)
		(end 93.008958 -163.856162)
		(width 0.1143)
		(layer "In11.Cu")
		(net "L12_85OHM_5INCH_DN")
	)
	(segment
		(start 92.899738 -166.089076)
		(end 93.03258 -166.181786)
		(width 0.1143)
		(layer "In11.Cu")
		(net "L12_85OHM_5INCH_DN")
	)
	(segment
		(start 86.899496 -166.139368)
		(end 86.991952 -166.007034)
		(width 0.1143)
		(layer "In11.Cu")
		(net "L12_85OHM_5INCH_DN")
	)
	(segment
		(start 67.721734 -166.212774)
		(end 67.814444 -166.080186)
		(width 0.1143)
		(layer "In11.Cu")
		(net "L12_85OHM_5INCH_DN")
	)
	(segment
		(start 98.310192 -164.828982)
		(end 98.926142 -164.213032)
		(width 0.1143)
		(layer "In11.Cu")
		(net "L12_85OHM_5INCH_DN")
	)
	(segment
		(start 97.85604 -164.828982)
		(end 98.310192 -164.828982)
		(width 0.1143)
		(layer "In11.Cu")
		(net "L12_85OHM_5INCH_DN")
	)
	(segment
		(start 83.795362 -166.014908)
		(end 83.417918 -163.875212)
		(width 0.1143)
		(layer "In11.Cu")
		(net "L12_85OHM_5INCH_DN")
	)
	(segment
		(start 63.808102 -164.283136)
		(end 64.424052 -164.899086)
		(width 0.1143)
		(layer "In11.Cu")
		(net "L12_85OHM_5INCH_DN")
	)
	(segment
		(start 93.29547 -166.135558)
		(end 93.387926 -166.003224)
		(width 0.1143)
		(layer "In11.Cu")
		(net "L12_85OHM_5INCH_DN")
	)
	(segment
		(start 88.442038 -163.519866)
		(end 88.943434 -163.43122)
		(width 0.1143)
		(layer "In11.Cu")
		(net "L12_85OHM_5INCH_DN")
	)
	(segment
		(start 74.89698 -163.75253)
		(end 75.320906 -166.15791)
		(width 0.1143)
		(layer "In11.Cu")
		(net "L12_85OHM_5INCH_DN")
	)
	(segment
		(start 84.149946 -163.455858)
		(end 84.48167 -163.686744)
		(width 0.1143)
		(layer "In11.Cu")
		(net "L12_85OHM_5INCH_DN")
	)
	(segment
		(start 89.703656 -166.097458)
		(end 89.835736 -166.189914)
		(width 0.1143)
		(layer "In11.Cu")
		(net "L12_85OHM_5INCH_DN")
	)
	(segment
		(start 67.66941 -163.613592)
		(end 68.170552 -163.524946)
		(width 0.1143)
		(layer "In11.Cu")
		(net "L12_85OHM_5INCH_DN")
	)
	(segment
		(start 82.059018 -163.546028)
		(end 82.54365 -163.460938)
		(width 0.1143)
		(layer "In11.Cu")
		(net "L12_85OHM_5INCH_DN")
	)
	(segment
		(start 75.320906 -166.15791)
		(end 75.453748 -166.251128)
		(width 0.1143)
		(layer "In11.Cu")
		(net "L12_85OHM_5INCH_DN")
	)
	(segment
		(start 66.93027 -165.104826)
		(end 67.179444 -165.437058)
		(width 0.1143)
		(layer "In11.Cu")
		(net "L12_85OHM_5INCH_DN")
	)
	(segment
		(start 70.636638 -163.948872)
		(end 70.867778 -163.61791)
		(width 0.1143)
		(layer "In11.Cu")
		(net "L12_85OHM_5INCH_DN")
	)
	(segment
		(start 74.064876 -163.609782)
		(end 74.566018 -163.52139)
		(width 0.1143)
		(layer "In11.Cu")
		(net "L12_85OHM_5INCH_DN")
	)
	(segment
		(start 67.437508 -163.944808)
		(end 67.66941 -163.613592)
		(width 0.1143)
		(layer "In11.Cu")
		(net "L12_85OHM_5INCH_DN")
	)
	(segment
		(start 69.061584 -166.275004)
		(end 69.323966 -166.228776)
		(width 0.1143)
		(layer "In11.Cu")
		(net "L12_85OHM_5INCH_DN")
	)
	(segment
		(start 94.987872 -166.00678)
		(end 94.610936 -163.871656)
		(width 0.1143)
		(layer "In11.Cu")
		(net "L12_85OHM_5INCH_DN")
	)
	(segment
		(start 81.841086 -166.193724)
		(end 82.103722 -166.147496)
		(width 0.1143)
		(layer "In11.Cu")
		(net "L12_85OHM_5INCH_DN")
	)
	(segment
		(start 82.103722 -166.147496)
		(end 82.196178 -166.014908)
		(width 0.1143)
		(layer "In11.Cu")
		(net "L12_85OHM_5INCH_DN")
	)
	(segment
		(start 90.098372 -166.143686)
		(end 90.190828 -166.011352)
		(width 0.1143)
		(layer "In11.Cu")
		(net "L12_85OHM_5INCH_DN")
	)
	(segment
		(start 76.920598 -166.158926)
		(end 77.052932 -166.251382)
		(width 0.1143)
		(layer "In11.Cu")
		(net "L12_85OHM_5INCH_DN")
	)
	(segment
		(start 68.500752 -163.756086)
		(end 68.928742 -166.181786)
		(width 0.1143)
		(layer "In11.Cu")
		(net "L12_85OHM_5INCH_DN")
	)
	(segment
		(start 83.417918 -163.875212)
		(end 83.649312 -163.543234)
		(width 0.1143)
		(layer "In11.Cu")
		(net "L12_85OHM_5INCH_DN")
	)
	(segment
		(start 75.433428 -163.944808)
		(end 75.664568 -163.613846)
		(width 0.1143)
		(layer "In11.Cu")
		(net "L12_85OHM_5INCH_DN")
	)
	(segment
		(start 81.82102 -163.886896)
		(end 82.059018 -163.546028)
		(width 0.1143)
		(layer "In11.Cu")
		(net "L12_85OHM_5INCH_DN")
	)
	(segment
		(start 70.922642 -166.229284)
		(end 71.015352 -166.096696)
		(width 0.1143)
		(layer "In11.Cu")
		(net "L12_85OHM_5INCH_DN")
	)
	(segment
		(start 86.63686 -166.185342)
		(end 86.899496 -166.139368)
		(width 0.1143)
		(layer "In11.Cu")
		(net "L12_85OHM_5INCH_DN")
	)
	(segment
		(start 72.615552 -166.101776)
		(end 72.234552 -163.94049)
		(width 0.1143)
		(layer "In11.Cu")
		(net "L12_85OHM_5INCH_DN")
	)
	(segment
		(start 77.765148 -163.526216)
		(end 78.09611 -163.757102)
		(width 0.1143)
		(layer "In11.Cu")
		(net "L12_85OHM_5INCH_DN")
	)
	(segment
		(start 69.416422 -166.095934)
		(end 69.037454 -163.948618)
		(width 0.1143)
		(layer "In11.Cu")
		(net "L12_85OHM_5INCH_DN")
	)
	(segment
		(start 87.680292 -163.692332)
		(end 88.103964 -166.097458)
		(width 0.1143)
		(layer "In11.Cu")
		(net "L12_85OHM_5INCH_DN")
	)
	(segment
		(start 90.873326 -163.662614)
		(end 91.300808 -166.088822)
		(width 0.1143)
		(layer "In11.Cu")
		(net "L12_85OHM_5INCH_DN")
	)
	(segment
		(start 79.69377 -163.74872)
		(end 80.116934 -166.150798)
		(width 0.1143)
		(layer "In11.Cu")
		(net "L12_85OHM_5INCH_DN")
	)
	(segment
		(start 70.867778 -163.61791)
		(end 71.369174 -163.530026)
		(width 0.1143)
		(layer "In11.Cu")
		(net "L12_85OHM_5INCH_DN")
	)
	(segment
		(start 87.34933 -163.460176)
		(end 87.680292 -163.692332)
		(width 0.1143)
		(layer "In11.Cu")
		(net "L12_85OHM_5INCH_DN")
	)
	(segment
		(start 88.21039 -163.85032)
		(end 88.442038 -163.519866)
		(width 0.1143)
		(layer "In11.Cu")
		(net "L12_85OHM_5INCH_DN")
	)
	(segment
		(start 81.292446 -163.748974)
		(end 81.510632 -164.986462)
		(width 0.1143)
		(layer "In11.Cu")
		(net "L12_85OHM_5INCH_DN")
	)
	(segment
		(start 73.83399 -163.940236)
		(end 74.064876 -163.609782)
		(width 0.1143)
		(layer "In11.Cu")
		(net "L12_85OHM_5INCH_DN")
	)
	(segment
		(start 94.072456 -163.668456)
		(end 94.500192 -166.094156)
		(width 0.1143)
		(layer "In11.Cu")
		(net "L12_85OHM_5INCH_DN")
	)
	(segment
		(start 95.823786 -164.454332)
		(end 95.981774 -164.665152)
		(width 0.1143)
		(layer "In11.Cu")
		(net "L12_85OHM_5INCH_DN")
	)
	(segment
		(start 80.961484 -163.517834)
		(end 81.292446 -163.748974)
		(width 0.1143)
		(layer "In11.Cu")
		(net "L12_85OHM_5INCH_DN")
	)
	(segment
		(start 81.510632 -164.986462)
		(end 81.708498 -166.101014)
		(width 0.1143)
		(layer "In11.Cu")
		(net "L12_85OHM_5INCH_DN")
	)
	(segment
		(start 85.393022 -166.006526)
		(end 85.01761 -163.879276)
		(width 0.1143)
		(layer "In11.Cu")
		(net "L12_85OHM_5INCH_DN")
	)
	(segment
		(start 69.037454 -163.948618)
		(end 69.268594 -163.617656)
		(width 0.1143)
		(layer "In11.Cu")
		(net "L12_85OHM_5INCH_DN")
	)
	(segment
		(start 85.749638 -163.459922)
		(end 86.080346 -163.691062)
		(width 0.1143)
		(layer "In11.Cu")
		(net "L12_85OHM_5INCH_DN")
	)
	(segment
		(start 72.522588 -166.233856)
		(end 72.615552 -166.101776)
		(width 0.1143)
		(layer "In11.Cu")
		(net "L12_85OHM_5INCH_DN")
	)
	(segment
		(start 85.037422 -166.185342)
		(end 85.300312 -166.139114)
		(width 0.1143)
		(layer "In11.Cu")
		(net "L12_85OHM_5INCH_DN")
	)
	(segment
		(start 77.31506 -166.205154)
		(end 77.40777 -166.072566)
		(width 0.1143)
		(layer "In11.Cu")
		(net "L12_85OHM_5INCH_DN")
	)
	(segment
		(start 93.239844 -163.524692)
		(end 93.74124 -163.4363)
		(width 0.1143)
		(layer "In11.Cu")
		(net "L12_85OHM_5INCH_DN")
	)
	(segment
		(start 83.439762 -166.193724)
		(end 83.702652 -166.147496)
		(width 0.1143)
		(layer "In11.Cu")
		(net "L12_85OHM_5INCH_DN")
	)
	(segment
		(start 95.674434 -163.68395)
		(end 95.778828 -164.277548)
		(width 0.1143)
		(layer "In11.Cu")
		(net "L12_85OHM_5INCH_DN")
	)
	(segment
		(start 92.142564 -163.4363)
		(end 92.473526 -163.66744)
		(width 0.1143)
		(layer "In11.Cu")
		(net "L12_85OHM_5INCH_DN")
	)
	(segment
		(start 88.103964 -166.097458)
		(end 88.236552 -166.190168)
		(width 0.1143)
		(layer "In11.Cu")
		(net "L12_85OHM_5INCH_DN")
	)
	(segment
		(start 70.101206 -163.760912)
		(end 70.527672 -166.182548)
		(width 0.1143)
		(layer "In11.Cu")
		(net "L12_85OHM_5INCH_DN")
	)
	(segment
		(start 64.866266 -164.899086)
		(end 65.997836 -164.808408)
		(width 0.1143)
		(layer "In11.Cu")
		(net "L12_85OHM_5INCH_DN")
	)
	(segment
		(start 72.465692 -163.609528)
		(end 72.967088 -163.52139)
		(width 0.1143)
		(layer "In11.Cu")
		(net "L12_85OHM_5INCH_DN")
	)
	(segment
		(start 91.696286 -166.135304)
		(end 91.788742 -166.00297)
		(width 0.1143)
		(layer "In11.Cu")
		(net "L12_85OHM_5INCH_DN")
	)
	(segment
		(start 93.008958 -163.856162)
		(end 93.239844 -163.524692)
		(width 0.1143)
		(layer "In11.Cu")
		(net "L12_85OHM_5INCH_DN")
	)
	(segment
		(start 88.236552 -166.190168)
		(end 88.499188 -166.143686)
		(width 0.1143)
		(layer "In11.Cu")
		(net "L12_85OHM_5INCH_DN")
	)
	(segment
		(start 78.09611 -163.757102)
		(end 78.519528 -166.16299)
		(width 0.1143)
		(layer "In11.Cu")
		(net "L12_85OHM_5INCH_DN")
	)
	(segment
		(start 80.460342 -163.605972)
		(end 80.961484 -163.517834)
		(width 0.1143)
		(layer "In11.Cu")
		(net "L12_85OHM_5INCH_DN")
	)
	(segment
		(start 77.263752 -163.6141)
		(end 77.765148 -163.526216)
		(width 0.1143)
		(layer "In11.Cu")
		(net "L12_85OHM_5INCH_DN")
	)
	(segment
		(start 71.70039 -163.761166)
		(end 72.127618 -166.187374)
		(width 0.1143)
		(layer "In11.Cu")
		(net "L12_85OHM_5INCH_DN")
	)
	(segment
		(start 91.788742 -166.00297)
		(end 91.410028 -163.855146)
		(width 0.1143)
		(layer "In11.Cu")
		(net "L12_85OHM_5INCH_DN")
	)
	(segment
		(start 68.170552 -163.524946)
		(end 68.500752 -163.756086)
		(width 0.1143)
		(layer "In11.Cu")
		(net "L12_85OHM_5INCH_DN")
	)
	(segment
		(start 83.649312 -163.543234)
		(end 84.149946 -163.455858)
		(width 0.1143)
		(layer "In11.Cu")
		(net "L12_85OHM_5INCH_DN")
	)
	(segment
		(start 71.015352 -166.096696)
		(end 70.636638 -163.948872)
		(width 0.1143)
		(layer "In11.Cu")
		(net "L12_85OHM_5INCH_DN")
	)
	(segment
		(start 95.778828 -164.277548)
		(end 95.823786 -164.454332)
		(width 0.1143)
		(layer "In11.Cu")
		(net "L12_85OHM_5INCH_DN")
	)
	(segment
		(start 67.24142 -165.681152)
		(end 67.326764 -166.166292)
		(width 0.1143)
		(layer "In11.Cu")
		(net "L12_85OHM_5INCH_DN")
	)
	(segment
		(start 73.859644 -166.280084)
		(end 74.12228 -166.233602)
		(width 0.1143)
		(layer "In11.Cu")
		(net "L12_85OHM_5INCH_DN")
	)
	(segment
		(start 70.66026 -166.275258)
		(end 70.922642 -166.229284)
		(width 0.1143)
		(layer "In11.Cu")
		(net "L12_85OHM_5INCH_DN")
	)
	(segment
		(start 86.616794 -163.87953)
		(end 86.847934 -163.54806)
		(width 0.1143)
		(layer "In11.Cu")
		(net "L12_85OHM_5INCH_DN")
	)
	(segment
		(start 67.326764 -166.166292)
		(end 67.459098 -166.259002)
		(width 0.1143)
		(layer "In11.Cu")
		(net "L12_85OHM_5INCH_DN")
	)
	(segment
		(start 94.632018 -166.186358)
		(end 94.894654 -166.139876)
		(width 0.1143)
		(layer "In11.Cu")
		(net "L12_85OHM_5INCH_DN")
	)
	(segment
		(start 94.500192 -166.094156)
		(end 94.632018 -166.186358)
		(width 0.1143)
		(layer "In11.Cu")
		(net "L12_85OHM_5INCH_DN")
	)
	(segment
		(start 94.610936 -163.871656)
		(end 94.84233 -163.54044)
		(width 0.1143)
		(layer "In11.Cu")
		(net "L12_85OHM_5INCH_DN")
	)
	(segment
		(start 67.814444 -166.080186)
		(end 67.437508 -163.944808)
		(width 0.1143)
		(layer "In11.Cu")
		(net "L12_85OHM_5INCH_DN")
	)
	(segment
		(start 78.861412 -163.605718)
		(end 79.362808 -163.517834)
		(width 0.1143)
		(layer "In11.Cu")
		(net "L12_85OHM_5INCH_DN")
	)
	(segment
		(start 89.835736 -166.189914)
		(end 90.098372 -166.143686)
		(width 0.1143)
		(layer "In11.Cu")
		(net "L12_85OHM_5INCH_DN")
	)
	(segment
		(start 73.297288 -163.752784)
		(end 73.726802 -166.186612)
		(width 0.1143)
		(layer "In11.Cu")
		(net "L12_85OHM_5INCH_DN")
	)
	(segment
		(start 72.967088 -163.52139)
		(end 73.297288 -163.752784)
		(width 0.1143)
		(layer "In11.Cu")
		(net "L12_85OHM_5INCH_DN")
	)
	(segment
		(start 90.190828 -166.011352)
		(end 89.809828 -163.849558)
		(width 0.1143)
		(layer "In11.Cu")
		(net "L12_85OHM_5INCH_DN")
	)
	(segment
		(start 93.74124 -163.4363)
		(end 94.072456 -163.668456)
		(width 0.1143)
		(layer "In11.Cu")
		(net "L12_85OHM_5INCH_DN")
	)
	(segment
		(start 80.116934 -166.150798)
		(end 80.259174 -166.250366)
		(width 0.1143)
		(layer "In11.Cu")
		(net "L12_85OHM_5INCH_DN")
	)
	(segment
		(start 85.300312 -166.139114)
		(end 85.393022 -166.006526)
		(width 0.1143)
		(layer "In11.Cu")
		(net "L12_85OHM_5INCH_DN")
	)
	(segment
		(start 69.268594 -163.617656)
		(end 69.76999 -163.529772)
		(width 0.1143)
		(layer "In11.Cu")
		(net "L12_85OHM_5INCH_DN")
	)
	(segment
		(start 78.519528 -166.16299)
		(end 78.652624 -166.2557)
		(width 0.1143)
		(layer "In11.Cu")
		(net "L12_85OHM_5INCH_DN")
	)
	(segment
		(start 70.527672 -166.182548)
		(end 70.66026 -166.275258)
		(width 0.1143)
		(layer "In11.Cu")
		(net "L12_85OHM_5INCH_DN")
	)
	(segment
		(start 92.473526 -163.66744)
		(end 92.899738 -166.089076)
		(width 0.1143)
		(layer "In11.Cu")
		(net "L12_85OHM_5INCH_DN")
	)
	(segment
		(start 75.664568 -163.613846)
		(end 76.16571 -163.526216)
		(width 0.1143)
		(layer "In11.Cu")
		(net "L12_85OHM_5INCH_DN")
	)
	(segment
		(start 94.894654 -166.139876)
		(end 94.987872 -166.00678)
		(width 0.1143)
		(layer "In11.Cu")
		(net "L12_85OHM_5INCH_DN")
	)
	(segment
		(start 79.362808 -163.517834)
		(end 79.69377 -163.74872)
		(width 0.1143)
		(layer "In11.Cu")
		(net "L12_85OHM_5INCH_DN")
	)
	(segment
		(start 73.726802 -166.186612)
		(end 73.859644 -166.280084)
		(width 0.1143)
		(layer "In11.Cu")
		(net "L12_85OHM_5INCH_DN")
	)
	(segment
		(start 91.641676 -163.52393)
		(end 92.142564 -163.4363)
		(width 0.1143)
		(layer "In11.Cu")
		(net "L12_85OHM_5INCH_DN")
	)
	(segment
		(start 90.042238 -163.519358)
		(end 90.542364 -163.431728)
		(width 0.1143)
		(layer "In11.Cu")
		(net "L12_85OHM_5INCH_DN")
	)
	(segment
		(start 78.630018 -163.936934)
		(end 78.861412 -163.605718)
		(width 0.1143)
		(layer "In11.Cu")
		(net "L12_85OHM_5INCH_DN")
	)
	(segment
		(start 88.943434 -163.43122)
		(end 89.274396 -163.663884)
		(width 0.1143)
		(layer "In11.Cu")
		(net "L12_85OHM_5INCH_DN")
	)
	(segment
		(start 95.343726 -163.452302)
		(end 95.674434 -163.68395)
		(width 0.1143)
		(layer "In11.Cu")
		(net "L12_85OHM_5INCH_DN")
	)
	(segment
		(start 76.496672 -163.757102)
		(end 76.920598 -166.158926)
		(width 0.1143)
		(layer "In11.Cu")
		(net "L12_85OHM_5INCH_DN")
	)
	(segment
		(start 80.259174 -166.250366)
		(end 80.505046 -166.207186)
		(width 0.1143)
		(layer "In11.Cu")
		(net "L12_85OHM_5INCH_DN")
	)
	(segment
		(start 75.808586 -166.072566)
		(end 75.433428 -163.944808)
		(width 0.1143)
		(layer "In11.Cu")
		(net "L12_85OHM_5INCH_DN")
	)
	(segment
		(start 90.542364 -163.431728)
		(end 90.873326 -163.662614)
		(width 0.1143)
		(layer "In11.Cu")
		(net "L12_85OHM_5INCH_DN")
	)
	(segment
		(start 82.88401 -163.699444)
		(end 83.307174 -166.101268)
		(width 0.1143)
		(layer "In11.Cu")
		(net "L12_85OHM_5INCH_DN")
	)
	(segment
		(start 91.43365 -166.181532)
		(end 91.696286 -166.135304)
		(width 0.1143)
		(layer "In11.Cu")
		(net "L12_85OHM_5INCH_DN")
	)
	(segment
		(start 95.981774 -164.665152)
		(end 96.77019 -164.91585)
		(width 0.1143)
		(layer "In11.Cu")
		(net "L12_85OHM_5INCH_DN")
	)
	(segment
		(start 75.453748 -166.251128)
		(end 75.71613 -166.205154)
		(width 0.1143)
		(layer "In11.Cu")
		(net "L12_85OHM_5INCH_DN")
	)
	(segment
		(start 72.260206 -166.27983)
		(end 72.522588 -166.233856)
		(width 0.1143)
		(layer "In11.Cu")
		(net "L12_85OHM_5INCH_DN")
	)
	(segment
		(start 94.84233 -163.54044)
		(end 95.343726 -163.452302)
		(width 0.1143)
		(layer "In11.Cu")
		(net "L12_85OHM_5INCH_DN")
	)
	(segment
		(start 74.12228 -166.233602)
		(end 74.21499 -166.101268)
		(width 0.1143)
		(layer "In11.Cu")
		(net "L12_85OHM_5INCH_DN")
	)
	(segment
		(start 88.499188 -166.143686)
		(end 88.59139 -166.011098)
		(width 0.1143)
		(layer "In11.Cu")
		(net "L12_85OHM_5INCH_DN")
	)
	(segment
		(start 76.16571 -163.526216)
		(end 76.496672 -163.757102)
		(width 0.1143)
		(layer "In11.Cu")
		(net "L12_85OHM_5INCH_DN")
	)
	(segment
		(start 93.03258 -166.181786)
		(end 93.29547 -166.135558)
		(width 0.1143)
		(layer "In11.Cu")
		(net "L12_85OHM_5INCH_DN")
	)
	(segment
		(start 79.007462 -166.076884)
		(end 78.630018 -163.936934)
		(width 0.1143)
		(layer "In11.Cu")
		(net "L12_85OHM_5INCH_DN")
	)
	(segment
		(start 77.052932 -166.251382)
		(end 77.31506 -166.205154)
		(width 0.1143)
		(layer "In11.Cu")
		(net "L12_85OHM_5INCH_DN")
	)
	(segment
		(start 78.914752 -166.20998)
		(end 79.007462 -166.076884)
		(width 0.1143)
		(layer "In11.Cu")
		(net "L12_85OHM_5INCH_DN")
	)
	(segment
		(start 89.274396 -163.663884)
		(end 89.703656 -166.097458)
		(width 0.1143)
		(layer "In11.Cu")
		(net "L12_85OHM_5INCH_DN")
	)
	(segment
		(start 86.847934 -163.54806)
		(end 87.34933 -163.460176)
		(width 0.1143)
		(layer "In11.Cu")
		(net "L12_85OHM_5INCH_DN")
	)
	(segment
		(start 80.505046 -166.207186)
		(end 80.60436 -166.064946)
		(width 0.1143)
		(layer "In11.Cu")
		(net "L12_85OHM_5INCH_DN")
	)
	(segment
		(start 78.652624 -166.2557)
		(end 78.914752 -166.20998)
		(width 0.1143)
		(layer "In11.Cu")
		(net "L12_85OHM_5INCH_DN")
	)
	(segment
		(start 68.928742 -166.181786)
		(end 69.061584 -166.275004)
		(width 0.1143)
		(layer "In11.Cu")
		(net "L12_85OHM_5INCH_DN")
	)
	(segment
		(start 83.307174 -166.101268)
		(end 83.439762 -166.193724)
		(width 0.1143)
		(layer "In11.Cu")
		(net "L12_85OHM_5INCH_DN")
	)
	(segment
		(start 82.54365 -163.460938)
		(end 82.88401 -163.699444)
		(width 0.1143)
		(layer "In11.Cu")
		(net "L12_85OHM_5INCH_DN")
	)
	(segment
		(start 84.904834 -166.092886)
		(end 85.037422 -166.185342)
		(width 0.1143)
		(layer "In11.Cu")
		(net "L12_85OHM_5INCH_DN")
	)
	(segment
		(start 67.459098 -166.259002)
		(end 67.721734 -166.212774)
		(width 0.1143)
		(layer "In11.Cu")
		(net "L12_85OHM_5INCH_DN")
	)
	(segment
		(start 71.369174 -163.530026)
		(end 71.70039 -163.761166)
		(width 0.1143)
		(layer "In11.Cu")
		(net "L12_85OHM_5INCH_DN")
	)
	(segment
		(start 84.48167 -163.686744)
		(end 84.904834 -166.092886)
		(width 0.1143)
		(layer "In11.Cu")
		(net "L12_85OHM_5INCH_DN")
	)
	(segment
		(start 77.40777 -166.072566)
		(end 77.032358 -163.945316)
		(width 0.1143)
		(layer "In11.Cu")
		(net "L12_85OHM_5INCH_DN")
	)
	(segment
		(start 81.708498 -166.101014)
		(end 81.841086 -166.193724)
		(width 0.1143)
		(layer "In11.Cu")
		(net "L12_85OHM_5INCH_DN")
	)
	(segment
		(start 85.01761 -163.879276)
		(end 85.249004 -163.54806)
		(width 0.1143)
		(layer "In11.Cu")
		(net "L12_85OHM_5INCH_DN")
	)
	(segment
		(start 74.566018 -163.52139)
		(end 74.89698 -163.75253)
		(width 0.1143)
		(layer "In11.Cu")
		(net "L12_85OHM_5INCH_DN")
	)
	(segment
		(start 91.410028 -163.855146)
		(end 91.641676 -163.52393)
		(width 0.1143)
		(layer "In11.Cu")
		(net "L12_85OHM_5INCH_DN")
	)
	(segment
		(start 67.179444 -165.437058)
		(end 67.24142 -165.681152)
		(width 0.1143)
		(layer "In11.Cu")
		(net "L12_85OHM_5INCH_DN")
	)
	(segment
		(start 91.300808 -166.088822)
		(end 91.43365 -166.181532)
		(width 0.1143)
		(layer "In11.Cu")
		(net "L12_85OHM_5INCH_DN")
	)
	(segment
		(start 83.702652 -166.147496)
		(end 83.795362 -166.014908)
		(width 0.1143)
		(layer "In11.Cu")
		(net "L12_85OHM_5INCH_DN")
	)
	(segment
		(start 77.032358 -163.945316)
		(end 77.263752 -163.6141)
		(width 0.1143)
		(layer "In11.Cu")
		(net "L12_85OHM_5INCH_DN")
	)
	(segment
		(start 80.229202 -163.936934)
		(end 80.460342 -163.605972)
		(width 0.1143)
		(layer "In11.Cu")
		(net "L12_85OHM_5INCH_DN")
	)
	(segment
		(start 72.127618 -166.187374)
		(end 72.260206 -166.27983)
		(width 0.1143)
		(layer "In11.Cu")
		(net "L12_85OHM_5INCH_DN")
	)
	(segment
		(start 64.424052 -164.899086)
		(end 64.866266 -164.899086)
		(width 0.1143)
		(layer "In11.Cu")
		(net "L12_85OHM_5INCH_DN")
	)
	(segment
		(start 74.21499 -166.101268)
		(end 73.83399 -163.940236)
		(width 0.1143)
		(layer "In11.Cu")
		(net "L12_85OHM_5INCH_DN")
	)
	(segment
		(start 88.59139 -166.011098)
		(end 88.21039 -163.85032)
		(width 0.1143)
		(layer "In11.Cu")
		(net "L12_85OHM_5INCH_DN")
	)
	(segment
		(start 80.60436 -166.064946)
		(end 80.229202 -163.936934)
		(width 0.1143)
		(layer "In11.Cu")
		(net "L12_85OHM_5INCH_DN")
	)
	(segment
		(start 82.196178 -166.014908)
		(end 81.82102 -163.886896)
		(width 0.1143)
		(layer "In11.Cu")
		(net "L12_85OHM_5INCH_DN")
	)
	(segment
		(start 86.991952 -166.007034)
		(end 86.616794 -163.87953)
		(width 0.1143)
		(layer "In11.Cu")
		(net "L12_85OHM_5INCH_DN")
	)
	(segment
		(start 307.2257 -164.752274)
		(end 304.450242 -164.752274)
		(width 0.1143)
		(layer "F.Cu")
		(net "L12_85OHM_10INCH_DP")
	)
	(segment
		(start 238.371634 -164.759386)
		(end 241.13998 -164.759386)
		(width 0.1143)
		(layer "F.Cu")
		(net "L12_85OHM_10INCH_DP")
	)
	(segment
		(start 241.13998 -164.759386)
		(end 241.75593 -164.143436)
		(width 0.1143)
		(layer "F.Cu")
		(net "L12_85OHM_10INCH_DP")
	)
	(segment
		(start 238.017304 -164.405056)
		(end 238.371634 -164.759386)
		(width 0.1143)
		(layer "F.Cu")
		(net "L12_85OHM_10INCH_DP")
	)
	(segment
		(start 304.450242 -164.752274)
		(end 303.834292 -164.136324)
		(width 0.1143)
		(layer "F.Cu")
		(net "L12_85OHM_10INCH_DP")
	)
	(segment
		(start 307.572918 -164.405056)
		(end 307.2257 -164.752274)
		(width 0.1143)
		(layer "F.Cu")
		(net "L12_85OHM_10INCH_DP")
	)
	(via
		(at 241.75593 -164.143436)
		(size 0.5588)
		(drill 0.3048)
		(layers "F.Cu" "B.Cu")
		(net "L12_85OHM_10INCH_DP")
	)
	(via
		(at 303.834292 -164.136324)
		(size 0.5588)
		(drill 0.3048)
		(layers "F.Cu" "B.Cu")
		(net "L12_85OHM_10INCH_DP")
	)
	(segment
		(start 254.291592 -163.466018)
		(end 254.060198 -163.797234)
		(width 0.1143)
		(layer "In11.Cu")
		(net "L12_85OHM_10INCH_DP")
	)
	(segment
		(start 248.397268 -163.38169)
		(end 247.895872 -163.469828)
		(width 0.1143)
		(layer "In11.Cu")
		(net "L12_85OHM_10INCH_DP")
	)
	(segment
		(start 275.913596 -163.611052)
		(end 275.582634 -163.378896)
		(width 0.1143)
		(layer "In11.Cu")
		(net "L12_85OHM_10INCH_DP")
	)
	(segment
		(start 291.12845 -166.070788)
		(end 290.86556 -166.117016)
		(width 0.1143)
		(layer "In11.Cu")
		(net "L12_85OHM_10INCH_DP")
	)
	(segment
		(start 268.46276 -166.042086)
		(end 268.329918 -165.949376)
		(width 0.1143)
		(layer "In11.Cu")
		(net "L12_85OHM_10INCH_DP")
	)
	(segment
		(start 242.756944 -166.026592)
		(end 242.6716 -165.541452)
		(width 0.1143)
		(layer "In11.Cu")
		(net "L12_85OHM_10INCH_DP")
	)
	(segment
		(start 273.257772 -166.030148)
		(end 273.125184 -165.937692)
		(width 0.1143)
		(layer "In11.Cu")
		(net "L12_85OHM_10INCH_DP")
	)
	(segment
		(start 260.692138 -163.482274)
		(end 260.460744 -163.81349)
		(width 0.1143)
		(layer "In11.Cu")
		(net "L12_85OHM_10INCH_DP")
	)
	(segment
		(start 289.621722 -165.937184)
		(end 289.529266 -166.069772)
		(width 0.1143)
		(layer "In11.Cu")
		(net "L12_85OHM_10INCH_DP")
	)
	(segment
		(start 270.324834 -166.000176)
		(end 270.062198 -166.046658)
		(width 0.1143)
		(layer "In11.Cu")
		(net "L12_85OHM_10INCH_DP")
	)
	(segment
		(start 266.730988 -165.949122)
		(end 266.320778 -163.621466)
		(width 0.1143)
		(layer "In11.Cu")
		(net "L12_85OHM_10INCH_DP")
	)
	(segment
		(start 250.751086 -166.01821)
		(end 250.32716 -163.61283)
		(width 0.1143)
		(layer "In11.Cu")
		(net "L12_85OHM_10INCH_DP")
	)
	(segment
		(start 299.067474 -163.447222)
		(end 298.835826 -163.778438)
		(width 0.1143)
		(layer "In11.Cu")
		(net "L12_85OHM_10INCH_DP")
	)
	(segment
		(start 279.654 -166.026338)
		(end 279.521158 -165.933628)
		(width 0.1143)
		(layer "In11.Cu")
		(net "L12_85OHM_10INCH_DP")
	)
	(segment
		(start 286.27959 -163.490148)
		(end 286.048196 -163.821364)
		(width 0.1143)
		(layer "In11.Cu")
		(net "L12_85OHM_10INCH_DP")
	)
	(segment
		(start 295.10609 -163.615624)
		(end 294.775128 -163.383468)
		(width 0.1143)
		(layer "In11.Cu")
		(net "L12_85OHM_10INCH_DP")
	)
	(segment
		(start 289.246818 -163.810188)
		(end 289.621722 -165.937184)
		(width 0.1143)
		(layer "In11.Cu")
		(net "L12_85OHM_10INCH_DP")
	)
	(segment
		(start 256.391664 -163.378134)
		(end 255.890522 -163.466272)
		(width 0.1143)
		(layer "In11.Cu")
		(net "L12_85OHM_10INCH_DP")
	)
	(segment
		(start 298.835826 -163.778438)
		(end 299.21454 -165.926262)
		(width 0.1143)
		(layer "In11.Cu")
		(net "L12_85OHM_10INCH_DP")
	)
	(segment
		(start 276.448012 -163.793678)
		(end 276.81174 -165.855904)
		(width 0.1143)
		(layer "In11.Cu")
		(net "L12_85OHM_10INCH_DP")
	)
	(segment
		(start 302.057816 -166.10965)
		(end 301.92599 -166.017448)
		(width 0.1143)
		(layer "In11.Cu")
		(net "L12_85OHM_10INCH_DP")
	)
	(segment
		(start 303.282858 -164.508688)
		(end 303.204626 -164.20084)
		(width 0.1143)
		(layer "In11.Cu")
		(net "L12_85OHM_10INCH_DP")
	)
	(segment
		(start 270.062198 -166.046658)
		(end 269.930372 -165.954456)
		(width 0.1143)
		(layer "In11.Cu")
		(net "L12_85OHM_10INCH_DP")
	)
	(segment
		(start 257.626358 -165.874954)
		(end 257.533902 -166.007542)
		(width 0.1143)
		(layer "In11.Cu")
		(net "L12_85OHM_10INCH_DP")
	)
	(segment
		(start 262.291068 -163.482274)
		(end 262.059928 -163.813744)
		(width 0.1143)
		(layer "In11.Cu")
		(net "L12_85OHM_10INCH_DP")
	)
	(segment
		(start 257.138678 -165.96106)
		(end 256.722626 -163.609274)
		(width 0.1143)
		(layer "In11.Cu")
		(net "L12_85OHM_10INCH_DP")
	)
	(segment
		(start 251.094748 -163.474146)
		(end 250.863608 -163.805108)
		(width 0.1143)
		(layer "In11.Cu")
		(net "L12_85OHM_10INCH_DP")
	)
	(segment
		(start 290.309808 -163.622736)
		(end 289.969448 -163.38423)
		(width 0.1143)
		(layer "In11.Cu")
		(net "L12_85OHM_10INCH_DP")
	)
	(segment
		(start 284.32252 -165.954456)
		(end 283.912056 -163.627308)
		(width 0.1143)
		(layer "In11.Cu")
		(net "L12_85OHM_10INCH_DP")
	)
	(segment
		(start 291.575744 -163.37915)
		(end 291.07511 -163.466526)
		(width 0.1143)
		(layer "In11.Cu")
		(net "L12_85OHM_10INCH_DP")
	)
	(segment
		(start 289.26663 -166.116)
		(end 289.13328 -166.022782)
		(width 0.1143)
		(layer "In11.Cu")
		(net "L12_85OHM_10INCH_DP")
	)
	(segment
		(start 263.534144 -165.957758)
		(end 263.123426 -163.626546)
		(width 0.1143)
		(layer "In11.Cu")
		(net "L12_85OHM_10INCH_DP")
	)
	(segment
		(start 265.989816 -163.39058)
		(end 265.48969 -163.47821)
		(width 0.1143)
		(layer "In11.Cu")
		(net "L12_85OHM_10INCH_DP")
	)
	(segment
		(start 247.557798 -166.047674)
		(end 247.13057 -163.621466)
		(width 0.1143)
		(layer "In11.Cu")
		(net "L12_85OHM_10INCH_DP")
	)
	(segment
		(start 276.67966 -163.463224)
		(end 276.448012 -163.793678)
		(width 0.1143)
		(layer "In11.Cu")
		(net "L12_85OHM_10INCH_DP")
	)
	(segment
		(start 268.329918 -165.949376)
		(end 267.920978 -163.626292)
		(width 0.1143)
		(layer "In11.Cu")
		(net "L12_85OHM_10INCH_DP")
	)
	(segment
		(start 302.268128 -163.463732)
		(end 302.036734 -163.794948)
		(width 0.1143)
		(layer "In11.Cu")
		(net "L12_85OHM_10INCH_DP")
	)
	(segment
		(start 299.122084 -166.058596)
		(end 298.859448 -166.104824)
		(width 0.1143)
		(layer "In11.Cu")
		(net "L12_85OHM_10INCH_DP")
	)
	(segment
		(start 246.352822 -166.089584)
		(end 246.09044 -166.135558)
		(width 0.1143)
		(layer "In11.Cu")
		(net "L12_85OHM_10INCH_DP")
	)
	(segment
		(start 268.45641 -163.81476)
		(end 268.818106 -165.863524)
		(width 0.1143)
		(layer "In11.Cu")
		(net "L12_85OHM_10INCH_DP")
	)
	(segment
		(start 262.792464 -163.39439)
		(end 262.291068 -163.482274)
		(width 0.1143)
		(layer "In11.Cu")
		(net "L12_85OHM_10INCH_DP")
	)
	(segment
		(start 283.115004 -165.984682)
		(end 282.852368 -166.031164)
		(width 0.1143)
		(layer "In11.Cu")
		(net "L12_85OHM_10INCH_DP")
	)
	(segment
		(start 290.86556 -166.117016)
		(end 290.732972 -166.02456)
		(width 0.1143)
		(layer "In11.Cu")
		(net "L12_85OHM_10INCH_DP")
	)
	(segment
		(start 301.498254 -163.591748)
		(end 301.167038 -163.359592)
		(width 0.1143)
		(layer "In11.Cu")
		(net "L12_85OHM_10INCH_DP")
	)
	(segment
		(start 277.924006 -165.942264)
		(end 277.512272 -163.607242)
		(width 0.1143)
		(layer "In11.Cu")
		(net "L12_85OHM_10INCH_DP")
	)
	(segment
		(start 296.369232 -163.354512)
		(end 295.867836 -163.443158)
		(width 0.1143)
		(layer "In11.Cu")
		(net "L12_85OHM_10INCH_DP")
	)
	(segment
		(start 261.192772 -163.394136)
		(end 260.692138 -163.482274)
		(width 0.1143)
		(layer "In11.Cu")
		(net "L12_85OHM_10INCH_DP")
	)
	(segment
		(start 284.454346 -166.046658)
		(end 284.32252 -165.954456)
		(width 0.1143)
		(layer "In11.Cu")
		(net "L12_85OHM_10INCH_DP")
	)
	(segment
		(start 281.24658 -163.799266)
		(end 281.608276 -165.84803)
		(width 0.1143)
		(layer "In11.Cu")
		(net "L12_85OHM_10INCH_DP")
	)
	(segment
		(start 299.568362 -163.359592)
		(end 299.067474 -163.447222)
		(width 0.1143)
		(layer "In11.Cu")
		(net "L12_85OHM_10INCH_DP")
	)
	(segment
		(start 272.384012 -163.378896)
		(end 271.883378 -163.466272)
		(width 0.1143)
		(layer "In11.Cu")
		(net "L12_85OHM_10INCH_DP")
	)
	(segment
		(start 274.724622 -165.937692)
		(end 274.31365 -163.609782)
		(width 0.1143)
		(layer "In11.Cu")
		(net "L12_85OHM_10INCH_DP")
	)
	(segment
		(start 245.531386 -163.621212)
		(end 245.20017 -163.390072)
		(width 0.1143)
		(layer "In11.Cu")
		(net "L12_85OHM_10INCH_DP")
	)
	(segment
		(start 259.593842 -163.39439)
		(end 259.093208 -163.481766)
		(width 0.1143)
		(layer "In11.Cu")
		(net "L12_85OHM_10INCH_DP")
	)
	(segment
		(start 264.38733 -163.369752)
		(end 263.885934 -163.458398)
		(width 0.1143)
		(layer "In11.Cu")
		(net "L12_85OHM_10INCH_DP")
	)
	(segment
		(start 297.52417 -166.066978)
		(end 297.261534 -166.113206)
		(width 0.1143)
		(layer "In11.Cu")
		(net "L12_85OHM_10INCH_DP")
	)
	(segment
		(start 249.156982 -166.046912)
		(end 248.727468 -163.613084)
		(width 0.1143)
		(layer "In11.Cu")
		(net "L12_85OHM_10INCH_DP")
	)
	(segment
		(start 247.690386 -166.14013)
		(end 247.557798 -166.047674)
		(width 0.1143)
		(layer "In11.Cu")
		(net "L12_85OHM_10INCH_DP")
	)
	(segment
		(start 278.411178 -165.856158)
		(end 278.318722 -165.988492)
		(width 0.1143)
		(layer "In11.Cu")
		(net "L12_85OHM_10INCH_DP")
	)
	(segment
		(start 286.048196 -163.821364)
		(end 286.412178 -165.882574)
		(width 0.1143)
		(layer "In11.Cu")
		(net "L12_85OHM_10INCH_DP")
	)
	(segment
		(start 267.218922 -165.86327)
		(end 267.126466 -165.995604)
		(width 0.1143)
		(layer "In11.Cu")
		(net "L12_85OHM_10INCH_DP")
	)
	(segment
		(start 242.611656 -165.305232)
		(end 242.358418 -164.967666)
		(width 0.1143)
		(layer "In11.Cu")
		(net "L12_85OHM_10INCH_DP")
	)
	(segment
		(start 252.693932 -163.4744)
		(end 252.462538 -163.805616)
		(width 0.1143)
		(layer "In11.Cu")
		(net "L12_85OHM_10INCH_DP")
	)
	(segment
		(start 241.75593 -164.645086)
		(end 241.75593 -164.143436)
		(width 0.1143)
		(layer "In11.Cu")
		(net "L12_85OHM_10INCH_DP")
	)
	(segment
		(start 259.925566 -163.625276)
		(end 259.593842 -163.39439)
		(width 0.1143)
		(layer "In11.Cu")
		(net "L12_85OHM_10INCH_DP")
	)
	(segment
		(start 287.920938 -166.031164)
		(end 287.658302 -166.077646)
		(width 0.1143)
		(layer "In11.Cu")
		(net "L12_85OHM_10INCH_DP")
	)
	(segment
		(start 300.721268 -166.05885)
		(end 300.458378 -166.105078)
		(width 0.1143)
		(layer "In11.Cu")
		(net "L12_85OHM_10INCH_DP")
	)
	(segment
		(start 303.546002 -164.772086)
		(end 303.373536 -164.629592)
		(width 0.1143)
		(layer "In11.Cu")
		(net "L12_85OHM_10INCH_DP")
	)
	(segment
		(start 244.846602 -165.956234)
		(end 244.754146 -166.089076)
		(width 0.1143)
		(layer "In11.Cu")
		(net "L12_85OHM_10INCH_DP")
	)
	(segment
		(start 243.930932 -163.616386)
		(end 243.600732 -163.385246)
		(width 0.1143)
		(layer "In11.Cu")
		(net "L12_85OHM_10INCH_DP")
	)
	(segment
		(start 283.079952 -163.483798)
		(end 282.848558 -163.81476)
		(width 0.1143)
		(layer "In11.Cu")
		(net "L12_85OHM_10INCH_DP")
	)
	(segment
		(start 274.850098 -163.79825)
		(end 275.212302 -165.85184)
		(width 0.1143)
		(layer "In11.Cu")
		(net "L12_85OHM_10INCH_DP")
	)
	(segment
		(start 262.059928 -163.813744)
		(end 262.422132 -165.867334)
		(width 0.1143)
		(layer "In11.Cu")
		(net "L12_85OHM_10INCH_DP")
	)
	(segment
		(start 284.451298 -163.834826)
		(end 284.8102 -165.86708)
		(width 0.1143)
		(layer "In11.Cu")
		(net "L12_85OHM_10INCH_DP")
	)
	(segment
		(start 251.14631 -166.065454)
		(end 250.883928 -166.111428)
		(width 0.1143)
		(layer "In11.Cu")
		(net "L12_85OHM_10INCH_DP")
	)
	(segment
		(start 263.885934 -163.458398)
		(end 263.654286 -163.788852)
		(width 0.1143)
		(layer "In11.Cu")
		(net "L12_85OHM_10INCH_DP")
	)
	(segment
		(start 249.495056 -163.470082)
		(end 249.26417 -163.800536)
		(width 0.1143)
		(layer "In11.Cu")
		(net "L12_85OHM_10INCH_DP")
	)
	(segment
		(start 269.519908 -163.627308)
		(end 269.188692 -163.395152)
		(width 0.1143)
		(layer "In11.Cu")
		(net "L12_85OHM_10INCH_DP")
	)
	(segment
		(start 297.468036 -163.44265)
		(end 297.235626 -163.77285)
		(width 0.1143)
		(layer "In11.Cu")
		(net "L12_85OHM_10INCH_DP")
	)
	(segment
		(start 278.04745 -163.792916)
		(end 278.411178 -165.856158)
		(width 0.1143)
		(layer "In11.Cu")
		(net "L12_85OHM_10INCH_DP")
	)
	(segment
		(start 242.889278 -166.119302)
		(end 242.756944 -166.026592)
		(width 0.1143)
		(layer "In11.Cu")
		(net "L12_85OHM_10INCH_DP")
	)
	(segment
		(start 262.06704 -166.045642)
		(end 261.934452 -165.953186)
		(width 0.1143)
		(layer "In11.Cu")
		(net "L12_85OHM_10INCH_DP")
	)
	(segment
		(start 284.8102 -165.86708)
		(end 284.716982 -166.000176)
		(width 0.1143)
		(layer "In11.Cu")
		(net "L12_85OHM_10INCH_DP")
	)
	(segment
		(start 300.434756 -163.779454)
		(end 300.813724 -165.926516)
		(width 0.1143)
		(layer "In11.Cu")
		(net "L12_85OHM_10INCH_DP")
	)
	(segment
		(start 247.664732 -163.80079)
		(end 248.045732 -165.962076)
		(width 0.1143)
		(layer "In11.Cu")
		(net "L12_85OHM_10INCH_DP")
	)
	(segment
		(start 279.110948 -163.605972)
		(end 278.779986 -163.375086)
		(width 0.1143)
		(layer "In11.Cu")
		(net "L12_85OHM_10INCH_DP")
	)
	(segment
		(start 255.12395 -163.60902)
		(end 254.792988 -163.378134)
		(width 0.1143)
		(layer "In11.Cu")
		(net "L12_85OHM_10INCH_DP")
	)
	(segment
		(start 278.779986 -163.375086)
		(end 278.27986 -163.462716)
		(width 0.1143)
		(layer "In11.Cu")
		(net "L12_85OHM_10INCH_DP")
	)
	(segment
		(start 255.890522 -163.466272)
		(end 255.659382 -163.797234)
		(width 0.1143)
		(layer "In11.Cu")
		(net "L12_85OHM_10INCH_DP")
	)
	(segment
		(start 267.920978 -163.626292)
		(end 267.590016 -163.395152)
		(width 0.1143)
		(layer "In11.Cu")
		(net "L12_85OHM_10INCH_DP")
	)
	(segment
		(start 241.87277 -164.761926)
		(end 241.75593 -164.645086)
		(width 0.1143)
		(layer "In11.Cu")
		(net "L12_85OHM_10INCH_DP")
	)
	(segment
		(start 249.996198 -163.38169)
		(end 249.495056 -163.470082)
		(width 0.1143)
		(layer "In11.Cu")
		(net "L12_85OHM_10INCH_DP")
	)
	(segment
		(start 244.698774 -163.477956)
		(end 244.467634 -163.808918)
		(width 0.1143)
		(layer "In11.Cu")
		(net "L12_85OHM_10INCH_DP")
	)
	(segment
		(start 282.310078 -163.611814)
		(end 281.978862 -163.379658)
		(width 0.1143)
		(layer "In11.Cu")
		(net "L12_85OHM_10INCH_DP")
	)
	(segment
		(start 280.009092 -165.847776)
		(end 279.916636 -165.98011)
		(width 0.1143)
		(layer "In11.Cu")
		(net "L12_85OHM_10INCH_DP")
	)
	(segment
		(start 265.621008 -165.871652)
		(end 265.528552 -166.003986)
		(width 0.1143)
		(layer "In11.Cu")
		(net "L12_85OHM_10INCH_DP")
	)
	(segment
		(start 242.867688 -163.805108)
		(end 243.244624 -165.940486)
		(width 0.1143)
		(layer "In11.Cu")
		(net "L12_85OHM_10INCH_DP")
	)
	(segment
		(start 302.036734 -163.794948)
		(end 302.41367 -165.930072)
		(width 0.1143)
		(layer "In11.Cu")
		(net "L12_85OHM_10INCH_DP")
	)
	(segment
		(start 279.88006 -163.471606)
		(end 279.648412 -163.802822)
		(width 0.1143)
		(layer "In11.Cu")
		(net "L12_85OHM_10INCH_DP")
	)
	(segment
		(start 283.912056 -163.627308)
		(end 283.581348 -163.39566)
		(width 0.1143)
		(layer "In11.Cu")
		(net "L12_85OHM_10INCH_DP")
	)
	(segment
		(start 292.81882 -165.929818)
		(end 292.72611 -166.062406)
		(width 0.1143)
		(layer "In11.Cu")
		(net "L12_85OHM_10INCH_DP")
	)
	(segment
		(start 245.957852 -166.042848)
		(end 245.531386 -163.621212)
		(width 0.1143)
		(layer "In11.Cu")
		(net "L12_85OHM_10INCH_DP")
	)
	(segment
		(start 297.129454 -166.02075)
		(end 296.700194 -163.587176)
		(width 0.1143)
		(layer "In11.Cu")
		(net "L12_85OHM_10INCH_DP")
	)
	(segment
		(start 261.934452 -165.953186)
		(end 261.52348 -163.625276)
		(width 0.1143)
		(layer "In11.Cu")
		(net "L12_85OHM_10INCH_DP")
	)
	(segment
		(start 257.986784 -163.395152)
		(end 257.502152 -163.480242)
		(width 0.1143)
		(layer "In11.Cu")
		(net "L12_85OHM_10INCH_DP")
	)
	(segment
		(start 288.014156 -165.898068)
		(end 287.920938 -166.031164)
		(width 0.1143)
		(layer "In11.Cu")
		(net "L12_85OHM_10INCH_DP")
	)
	(segment
		(start 258.737354 -165.961568)
		(end 258.327144 -163.633658)
		(width 0.1143)
		(layer "In11.Cu")
		(net "L12_85OHM_10INCH_DP")
	)
	(segment
		(start 262.329676 -165.999668)
		(end 262.06704 -166.045642)
		(width 0.1143)
		(layer "In11.Cu")
		(net "L12_85OHM_10INCH_DP")
	)
	(segment
		(start 292.72611 -166.062406)
		(end 292.46322 -166.108634)
		(width 0.1143)
		(layer "In11.Cu")
		(net "L12_85OHM_10INCH_DP")
	)
	(segment
		(start 249.26417 -163.800536)
		(end 249.64517 -165.961568)
		(width 0.1143)
		(layer "In11.Cu")
		(net "L12_85OHM_10INCH_DP")
	)
	(segment
		(start 266.320778 -163.621466)
		(end 265.989816 -163.39058)
		(width 0.1143)
		(layer "In11.Cu")
		(net "L12_85OHM_10INCH_DP")
	)
	(segment
		(start 254.792988 -163.378134)
		(end 254.291592 -163.466018)
		(width 0.1143)
		(layer "In11.Cu")
		(net "L12_85OHM_10INCH_DP")
	)
	(segment
		(start 281.25293 -166.026592)
		(end 281.120088 -165.933882)
		(width 0.1143)
		(layer "In11.Cu")
		(net "L12_85OHM_10INCH_DP")
	)
	(segment
		(start 291.907468 -163.610036)
		(end 291.575744 -163.37915)
		(width 0.1143)
		(layer "In11.Cu")
		(net "L12_85OHM_10INCH_DP")
	)
	(segment
		(start 255.659382 -163.797234)
		(end 256.03454 -165.925246)
		(width 0.1143)
		(layer "In11.Cu")
		(net "L12_85OHM_10INCH_DP")
	)
	(segment
		(start 291.07511 -163.466526)
		(end 290.843716 -163.798504)
		(width 0.1143)
		(layer "In11.Cu")
		(net "L12_85OHM_10INCH_DP")
	)
	(segment
		(start 250.863608 -163.805108)
		(end 251.238766 -165.932866)
		(width 0.1143)
		(layer "In11.Cu")
		(net "L12_85OHM_10INCH_DP")
	)
	(segment
		(start 290.732972 -166.02456)
		(end 290.309808 -163.622736)
		(width 0.1143)
		(layer "In11.Cu")
		(net "L12_85OHM_10INCH_DP")
	)
	(segment
		(start 296.700194 -163.587176)
		(end 296.369232 -163.354512)
		(width 0.1143)
		(layer "In11.Cu")
		(net "L12_85OHM_10INCH_DP")
	)
	(segment
		(start 292.330632 -166.016178)
		(end 291.907468 -163.610036)
		(width 0.1143)
		(layer "In11.Cu")
		(net "L12_85OHM_10INCH_DP")
	)
	(segment
		(start 295.924986 -166.066978)
		(end 295.66235 -166.11346)
		(width 0.1143)
		(layer "In11.Cu")
		(net "L12_85OHM_10INCH_DP")
	)
	(segment
		(start 280.380948 -163.383976)
		(end 279.88006 -163.471606)
		(width 0.1143)
		(layer "In11.Cu")
		(net "L12_85OHM_10INCH_DP")
	)
	(segment
		(start 262.422132 -165.867334)
		(end 262.329676 -165.999668)
		(width 0.1143)
		(layer "In11.Cu")
		(net "L12_85OHM_10INCH_DP")
	)
	(segment
		(start 296.017188 -165.93439)
		(end 295.924986 -166.066978)
		(width 0.1143)
		(layer "In11.Cu")
		(net "L12_85OHM_10INCH_DP")
	)
	(segment
		(start 275.081238 -163.46678)
		(end 274.850098 -163.79825)
		(width 0.1143)
		(layer "In11.Cu")
		(net "L12_85OHM_10INCH_DP")
	)
	(segment
		(start 247.895872 -163.469828)
		(end 247.664732 -163.80079)
		(width 0.1143)
		(layer "In11.Cu")
		(net "L12_85OHM_10INCH_DP")
	)
	(segment
		(start 243.09959 -163.473892)
		(end 242.867688 -163.805108)
		(width 0.1143)
		(layer "In11.Cu")
		(net "L12_85OHM_10INCH_DP")
	)
	(segment
		(start 251.238766 -165.932866)
		(end 251.14631 -166.065454)
		(width 0.1143)
		(layer "In11.Cu")
		(net "L12_85OHM_10INCH_DP")
	)
	(segment
		(start 260.730492 -165.999414)
		(end 260.467602 -166.045642)
		(width 0.1143)
		(layer "In11.Cu")
		(net "L12_85OHM_10INCH_DP")
	)
	(segment
		(start 243.600732 -163.385246)
		(end 243.09959 -163.473892)
		(width 0.1143)
		(layer "In11.Cu")
		(net "L12_85OHM_10INCH_DP")
	)
	(segment
		(start 247.13057 -163.621466)
		(end 246.799354 -163.390326)
		(width 0.1143)
		(layer "In11.Cu")
		(net "L12_85OHM_10INCH_DP")
	)
	(segment
		(start 297.235626 -163.77285)
		(end 297.616626 -165.934644)
		(width 0.1143)
		(layer "In11.Cu")
		(net "L12_85OHM_10INCH_DP")
	)
	(segment
		(start 295.867836 -163.443158)
		(end 295.636188 -163.773612)
		(width 0.1143)
		(layer "In11.Cu")
		(net "L12_85OHM_10INCH_DP")
	)
	(segment
		(start 302.320452 -166.063168)
		(end 302.057816 -166.10965)
		(width 0.1143)
		(layer "In11.Cu")
		(net "L12_85OHM_10INCH_DP")
	)
	(segment
		(start 246.09044 -166.135558)
		(end 245.957852 -166.042848)
		(width 0.1143)
		(layer "In11.Cu")
		(net "L12_85OHM_10INCH_DP")
	)
	(segment
		(start 259.093208 -163.481766)
		(end 258.861814 -163.813744)
		(width 0.1143)
		(layer "In11.Cu")
		(net "L12_85OHM_10INCH_DP")
	)
	(segment
		(start 277.181056 -163.374578)
		(end 276.67966 -163.463224)
		(width 0.1143)
		(layer "In11.Cu")
		(net "L12_85OHM_10INCH_DP")
	)
	(segment
		(start 273.125184 -165.937692)
		(end 272.715736 -163.609782)
		(width 0.1143)
		(layer "In11.Cu")
		(net "L12_85OHM_10INCH_DP")
	)
	(segment
		(start 273.613372 -165.851332)
		(end 273.520662 -165.98392)
		(width 0.1143)
		(layer "In11.Cu")
		(net "L12_85OHM_10INCH_DP")
	)
	(segment
		(start 252.483112 -166.111682)
		(end 252.350778 -166.019226)
		(width 0.1143)
		(layer "In11.Cu")
		(net "L12_85OHM_10INCH_DP")
	)
	(segment
		(start 252.83795 -165.932866)
		(end 252.74524 -166.065454)
		(width 0.1143)
		(layer "In11.Cu")
		(net "L12_85OHM_10INCH_DP")
	)
	(segment
		(start 300.665642 -163.447984)
		(end 300.434756 -163.779454)
		(width 0.1143)
		(layer "In11.Cu")
		(net "L12_85OHM_10INCH_DP")
	)
	(segment
		(start 298.299124 -163.585906)
		(end 297.968162 -163.35502)
		(width 0.1143)
		(layer "In11.Cu")
		(net "L12_85OHM_10INCH_DP")
	)
	(segment
		(start 293.506144 -163.614354)
		(end 293.175436 -163.383214)
		(width 0.1143)
		(layer "In11.Cu")
		(net "L12_85OHM_10INCH_DP")
	)
	(segment
		(start 270.78686 -163.386516)
		(end 270.285464 -163.474654)
		(width 0.1143)
		(layer "In11.Cu")
		(net "L12_85OHM_10INCH_DP")
	)
	(segment
		(start 285.514796 -163.64712)
		(end 285.184088 -163.415472)
		(width 0.1143)
		(layer "In11.Cu")
		(net "L12_85OHM_10INCH_DP")
	)
	(segment
		(start 247.952768 -166.094156)
		(end 247.690386 -166.14013)
		(width 0.1143)
		(layer "In11.Cu")
		(net "L12_85OHM_10INCH_DP")
	)
	(segment
		(start 281.51582 -165.980364)
		(end 281.25293 -166.026592)
		(width 0.1143)
		(layer "In11.Cu")
		(net "L12_85OHM_10INCH_DP")
	)
	(segment
		(start 256.03454 -165.925246)
		(end 255.935226 -166.067486)
		(width 0.1143)
		(layer "In11.Cu")
		(net "L12_85OHM_10INCH_DP")
	)
	(segment
		(start 273.982942 -163.378642)
		(end 273.482308 -163.46678)
		(width 0.1143)
		(layer "In11.Cu")
		(net "L12_85OHM_10INCH_DP")
	)
	(segment
		(start 288.382964 -163.417504)
		(end 287.881568 -163.505642)
		(width 0.1143)
		(layer "In11.Cu")
		(net "L12_85OHM_10INCH_DP")
	)
	(segment
		(start 290.843716 -163.798504)
		(end 291.22116 -165.9382)
		(width 0.1143)
		(layer "In11.Cu")
		(net "L12_85OHM_10INCH_DP")
	)
	(segment
		(start 294.41775 -165.930326)
		(end 294.325294 -166.06266)
		(width 0.1143)
		(layer "In11.Cu")
		(net "L12_85OHM_10INCH_DP")
	)
	(segment
		(start 252.74524 -166.065454)
		(end 252.483112 -166.111682)
		(width 0.1143)
		(layer "In11.Cu")
		(net "L12_85OHM_10INCH_DP")
	)
	(segment
		(start 255.935226 -166.067486)
		(end 255.689354 -166.110666)
		(width 0.1143)
		(layer "In11.Cu")
		(net "L12_85OHM_10INCH_DP")
	)
	(segment
		(start 255.689354 -166.110666)
		(end 255.547114 -166.011098)
		(width 0.1143)
		(layer "In11.Cu")
		(net "L12_85OHM_10INCH_DP")
	)
	(segment
		(start 244.754146 -166.089076)
		(end 244.491764 -166.135304)
		(width 0.1143)
		(layer "In11.Cu")
		(net "L12_85OHM_10INCH_DP")
	)
	(segment
		(start 287.111694 -163.633658)
		(end 286.780986 -163.40201)
		(width 0.1143)
		(layer "In11.Cu")
		(net "L12_85OHM_10INCH_DP")
	)
	(segment
		(start 283.581348 -163.39566)
		(end 283.079952 -163.483798)
		(width 0.1143)
		(layer "In11.Cu")
		(net "L12_85OHM_10INCH_DP")
	)
	(segment
		(start 263.666732 -166.050468)
		(end 263.534144 -165.957758)
		(width 0.1143)
		(layer "In11.Cu")
		(net "L12_85OHM_10INCH_DP")
	)
	(segment
		(start 252.462538 -163.805616)
		(end 252.83795 -165.932866)
		(width 0.1143)
		(layer "In11.Cu")
		(net "L12_85OHM_10INCH_DP")
	)
	(segment
		(start 278.056086 -166.03472)
		(end 277.924006 -165.942264)
		(width 0.1143)
		(layer "In11.Cu")
		(net "L12_85OHM_10INCH_DP")
	)
	(segment
		(start 267.089128 -163.482782)
		(end 266.85748 -163.813998)
		(width 0.1143)
		(layer "In11.Cu")
		(net "L12_85OHM_10INCH_DP")
	)
	(segment
		(start 245.20017 -163.390072)
		(end 244.698774 -163.477956)
		(width 0.1143)
		(layer "In11.Cu")
		(net "L12_85OHM_10INCH_DP")
	)
	(segment
		(start 260.335014 -165.953186)
		(end 259.925566 -163.625276)
		(width 0.1143)
		(layer "In11.Cu")
		(net "L12_85OHM_10INCH_DP")
	)
	(segment
		(start 295.636188 -163.773612)
		(end 296.017188 -165.93439)
		(width 0.1143)
		(layer "In11.Cu")
		(net "L12_85OHM_10INCH_DP")
	)
	(segment
		(start 273.250914 -163.797996)
		(end 273.613372 -165.851332)
		(width 0.1143)
		(layer "In11.Cu")
		(net "L12_85OHM_10INCH_DP")
	)
	(segment
		(start 278.318722 -165.988492)
		(end 278.056086 -166.03472)
		(width 0.1143)
		(layer "In11.Cu")
		(net "L12_85OHM_10INCH_DP")
	)
	(segment
		(start 260.823202 -165.866826)
		(end 260.730492 -165.999414)
		(width 0.1143)
		(layer "In11.Cu")
		(net "L12_85OHM_10INCH_DP")
	)
	(segment
		(start 254.437642 -165.937184)
		(end 254.344932 -166.07028)
		(width 0.1143)
		(layer "In11.Cu")
		(net "L12_85OHM_10INCH_DP")
	)
	(segment
		(start 253.949708 -166.02329)
		(end 253.52629 -163.617402)
		(width 0.1143)
		(layer "In11.Cu")
		(net "L12_85OHM_10INCH_DP")
	)
	(segment
		(start 292.46322 -166.108634)
		(end 292.330632 -166.016178)
		(width 0.1143)
		(layer "In11.Cu")
		(net "L12_85OHM_10INCH_DP")
	)
	(segment
		(start 297.968162 -163.35502)
		(end 297.468036 -163.44265)
		(width 0.1143)
		(layer "In11.Cu")
		(net "L12_85OHM_10INCH_DP")
	)
	(segment
		(start 270.418052 -165.86708)
		(end 270.324834 -166.000176)
		(width 0.1143)
		(layer "In11.Cu")
		(net "L12_85OHM_10INCH_DP")
	)
	(segment
		(start 303.100232 -163.607242)
		(end 302.769524 -163.375594)
		(width 0.1143)
		(layer "In11.Cu")
		(net "L12_85OHM_10INCH_DP")
	)
	(segment
		(start 271.117314 -163.618164)
		(end 270.78686 -163.386516)
		(width 0.1143)
		(layer "In11.Cu")
		(net "L12_85OHM_10INCH_DP")
	)
	(segment
		(start 269.188692 -163.395152)
		(end 268.687296 -163.483544)
		(width 0.1143)
		(layer "In11.Cu")
		(net "L12_85OHM_10INCH_DP")
	)
	(segment
		(start 267.126466 -165.995604)
		(end 266.86383 -166.041832)
		(width 0.1143)
		(layer "In11.Cu")
		(net "L12_85OHM_10INCH_DP")
	)
	(segment
		(start 251.926852 -163.617402)
		(end 251.59589 -163.386516)
		(width 0.1143)
		(layer "In11.Cu")
		(net "L12_85OHM_10INCH_DP")
	)
	(segment
		(start 300.813724 -165.926516)
		(end 300.721268 -166.05885)
		(width 0.1143)
		(layer "In11.Cu")
		(net "L12_85OHM_10INCH_DP")
	)
	(segment
		(start 252.350778 -166.019226)
		(end 251.926852 -163.617402)
		(width 0.1143)
		(layer "In11.Cu")
		(net "L12_85OHM_10INCH_DP")
	)
	(segment
		(start 257.533902 -166.007542)
		(end 257.271266 -166.05377)
		(width 0.1143)
		(layer "In11.Cu")
		(net "L12_85OHM_10INCH_DP")
	)
	(segment
		(start 289.529266 -166.069772)
		(end 289.26663 -166.116)
		(width 0.1143)
		(layer "In11.Cu")
		(net "L12_85OHM_10INCH_DP")
	)
	(segment
		(start 274.85721 -166.030148)
		(end 274.724622 -165.937692)
		(width 0.1143)
		(layer "In11.Cu")
		(net "L12_85OHM_10INCH_DP")
	)
	(segment
		(start 280.71191 -163.615116)
		(end 280.380948 -163.383976)
		(width 0.1143)
		(layer "In11.Cu")
		(net "L12_85OHM_10INCH_DP")
	)
	(segment
		(start 276.719538 -165.988492)
		(end 276.456902 -166.034974)
		(width 0.1143)
		(layer "In11.Cu")
		(net "L12_85OHM_10INCH_DP")
	)
	(segment
		(start 265.48969 -163.47821)
		(end 265.25728 -163.80841)
		(width 0.1143)
		(layer "In11.Cu")
		(net "L12_85OHM_10INCH_DP")
	)
	(segment
		(start 244.467634 -163.808918)
		(end 244.846602 -165.956234)
		(width 0.1143)
		(layer "In11.Cu")
		(net "L12_85OHM_10INCH_DP")
	)
	(segment
		(start 295.66235 -166.11346)
		(end 295.529762 -166.02075)
		(width 0.1143)
		(layer "In11.Cu")
		(net "L12_85OHM_10INCH_DP")
	)
	(segment
		(start 265.528552 -166.003986)
		(end 265.265916 -166.050214)
		(width 0.1143)
		(layer "In11.Cu")
		(net "L12_85OHM_10INCH_DP")
	)
	(segment
		(start 298.859448 -166.104824)
		(end 298.726606 -166.012114)
		(width 0.1143)
		(layer "In11.Cu")
		(net "L12_85OHM_10INCH_DP")
	)
	(segment
		(start 246.297958 -163.47821)
		(end 246.066818 -163.809172)
		(width 0.1143)
		(layer "In11.Cu")
		(net "L12_85OHM_10INCH_DP")
	)
	(segment
		(start 285.924498 -165.96995)
		(end 285.514796 -163.64712)
		(width 0.1143)
		(layer "In11.Cu")
		(net "L12_85OHM_10INCH_DP")
	)
	(segment
		(start 253.52629 -163.617402)
		(end 253.195328 -163.386516)
		(width 0.1143)
		(layer "In11.Cu")
		(net "L12_85OHM_10INCH_DP")
	)
	(segment
		(start 303.7078 -164.764466)
		(end 303.546002 -164.772086)
		(width 0.1143)
		(layer "In11.Cu")
		(net "L12_85OHM_10INCH_DP")
	)
	(segment
		(start 249.289824 -166.140384)
		(end 249.156982 -166.046912)
		(width 0.1143)
		(layer "In11.Cu")
		(net "L12_85OHM_10INCH_DP")
	)
	(segment
		(start 281.120088 -165.933882)
		(end 280.71191 -163.615116)
		(width 0.1143)
		(layer "In11.Cu")
		(net "L12_85OHM_10INCH_DP")
	)
	(segment
		(start 284.716982 -166.000176)
		(end 284.454346 -166.046658)
		(width 0.1143)
		(layer "In11.Cu")
		(net "L12_85OHM_10INCH_DP")
	)
	(segment
		(start 248.045732 -165.962076)
		(end 247.952768 -166.094156)
		(width 0.1143)
		(layer "In11.Cu")
		(net "L12_85OHM_10INCH_DP")
	)
	(segment
		(start 289.484816 -163.46932)
		(end 289.246818 -163.810188)
		(width 0.1143)
		(layer "In11.Cu")
		(net "L12_85OHM_10INCH_DP")
	)
	(segment
		(start 244.491764 -166.135304)
		(end 244.358922 -166.042086)
		(width 0.1143)
		(layer "In11.Cu")
		(net "L12_85OHM_10INCH_DP")
	)
	(segment
		(start 270.05407 -163.80587)
		(end 270.418052 -165.86708)
		(width 0.1143)
		(layer "In11.Cu")
		(net "L12_85OHM_10INCH_DP")
	)
	(segment
		(start 277.512272 -163.607242)
		(end 277.181056 -163.374578)
		(width 0.1143)
		(layer "In11.Cu")
		(net "L12_85OHM_10INCH_DP")
	)
	(segment
		(start 294.042592 -163.802822)
		(end 294.41775 -165.930326)
		(width 0.1143)
		(layer "In11.Cu")
		(net "L12_85OHM_10INCH_DP")
	)
	(segment
		(start 265.265916 -166.050214)
		(end 265.133836 -165.957758)
		(width 0.1143)
		(layer "In11.Cu")
		(net "L12_85OHM_10INCH_DP")
	)
	(segment
		(start 274.31365 -163.609782)
		(end 273.982942 -163.378642)
		(width 0.1143)
		(layer "In11.Cu")
		(net "L12_85OHM_10INCH_DP")
	)
	(segment
		(start 257.502152 -163.480242)
		(end 257.264154 -163.82111)
		(width 0.1143)
		(layer "In11.Cu")
		(net "L12_85OHM_10INCH_DP")
	)
	(segment
		(start 242.6716 -165.541452)
		(end 242.611656 -165.305232)
		(width 0.1143)
		(layer "In11.Cu")
		(net "L12_85OHM_10INCH_DP")
	)
	(segment
		(start 301.167038 -163.359592)
		(end 300.665642 -163.447984)
		(width 0.1143)
		(layer "In11.Cu")
		(net "L12_85OHM_10INCH_DP")
	)
	(segment
		(start 266.86383 -166.041832)
		(end 266.730988 -165.949122)
		(width 0.1143)
		(layer "In11.Cu")
		(net "L12_85OHM_10INCH_DP")
	)
	(segment
		(start 265.25728 -163.80841)
		(end 265.621008 -165.871652)
		(width 0.1143)
		(layer "In11.Cu")
		(net "L12_85OHM_10INCH_DP")
	)
	(segment
		(start 302.41367 -165.930072)
		(end 302.320452 -166.063168)
		(width 0.1143)
		(layer "In11.Cu")
		(net "L12_85OHM_10INCH_DP")
	)
	(segment
		(start 256.722626 -163.609274)
		(end 256.391664 -163.378134)
		(width 0.1143)
		(layer "In11.Cu")
		(net "L12_85OHM_10INCH_DP")
	)
	(segment
		(start 243.151914 -166.073074)
		(end 242.889278 -166.119302)
		(width 0.1143)
		(layer "In11.Cu")
		(net "L12_85OHM_10INCH_DP")
	)
	(segment
		(start 271.923002 -165.992302)
		(end 271.660112 -166.03853)
		(width 0.1143)
		(layer "In11.Cu")
		(net "L12_85OHM_10INCH_DP")
	)
	(segment
		(start 246.799354 -163.390326)
		(end 246.297958 -163.47821)
		(width 0.1143)
		(layer "In11.Cu")
		(net "L12_85OHM_10INCH_DP")
	)
	(segment
		(start 283.208222 -165.851586)
		(end 283.115004 -165.984682)
		(width 0.1143)
		(layer "In11.Cu")
		(net "L12_85OHM_10INCH_DP")
	)
	(segment
		(start 263.654286 -163.788852)
		(end 264.02157 -165.871398)
		(width 0.1143)
		(layer "In11.Cu")
		(net "L12_85OHM_10INCH_DP")
	)
	(segment
		(start 293.175436 -163.383214)
		(end 292.674802 -163.471352)
		(width 0.1143)
		(layer "In11.Cu")
		(net "L12_85OHM_10INCH_DP")
	)
	(segment
		(start 258.861814 -163.813744)
		(end 259.225542 -165.875208)
		(width 0.1143)
		(layer "In11.Cu")
		(net "L12_85OHM_10INCH_DP")
	)
	(segment
		(start 293.93007 -166.016178)
		(end 293.506144 -163.614354)
		(width 0.1143)
		(layer "In11.Cu")
		(net "L12_85OHM_10INCH_DP")
	)
	(segment
		(start 246.066818 -163.809172)
		(end 246.445532 -165.956996)
		(width 0.1143)
		(layer "In11.Cu")
		(net "L12_85OHM_10INCH_DP")
	)
	(segment
		(start 261.52348 -163.625276)
		(end 261.192772 -163.394136)
		(width 0.1143)
		(layer "In11.Cu")
		(net "L12_85OHM_10INCH_DP")
	)
	(segment
		(start 257.264154 -163.82111)
		(end 257.626358 -165.874954)
		(width 0.1143)
		(layer "In11.Cu")
		(net "L12_85OHM_10INCH_DP")
	)
	(segment
		(start 259.132832 -166.007796)
		(end 258.869942 -166.054024)
		(width 0.1143)
		(layer "In11.Cu")
		(net "L12_85OHM_10INCH_DP")
	)
	(segment
		(start 244.358922 -166.042086)
		(end 243.930932 -163.616386)
		(width 0.1143)
		(layer "In11.Cu")
		(net "L12_85OHM_10INCH_DP")
	)
	(segment
		(start 275.119846 -165.984174)
		(end 274.85721 -166.030148)
		(width 0.1143)
		(layer "In11.Cu")
		(net "L12_85OHM_10INCH_DP")
	)
	(segment
		(start 300.325536 -166.012368)
		(end 299.899324 -163.590732)
		(width 0.1143)
		(layer "In11.Cu")
		(net "L12_85OHM_10INCH_DP")
	)
	(segment
		(start 248.727468 -163.613084)
		(end 248.397268 -163.38169)
		(width 0.1143)
		(layer "In11.Cu")
		(net "L12_85OHM_10INCH_DP")
	)
	(segment
		(start 251.59589 -163.386516)
		(end 251.094748 -163.474146)
		(width 0.1143)
		(layer "In11.Cu")
		(net "L12_85OHM_10INCH_DP")
	)
	(segment
		(start 286.31896 -166.01567)
		(end 286.056324 -166.062152)
		(width 0.1143)
		(layer "In11.Cu")
		(net "L12_85OHM_10INCH_DP")
	)
	(segment
		(start 295.529762 -166.02075)
		(end 295.10609 -163.615624)
		(width 0.1143)
		(layer "In11.Cu")
		(net "L12_85OHM_10INCH_DP")
	)
	(segment
		(start 246.445532 -165.956996)
		(end 246.352822 -166.089584)
		(width 0.1143)
		(layer "In11.Cu")
		(net "L12_85OHM_10INCH_DP")
	)
	(segment
		(start 287.526476 -165.985444)
		(end 287.111694 -163.633658)
		(width 0.1143)
		(layer "In11.Cu")
		(net "L12_85OHM_10INCH_DP")
	)
	(segment
		(start 297.261534 -166.113206)
		(end 297.129454 -166.02075)
		(width 0.1143)
		(layer "In11.Cu")
		(net "L12_85OHM_10INCH_DP")
	)
	(segment
		(start 275.212302 -165.85184)
		(end 275.119846 -165.984174)
		(width 0.1143)
		(layer "In11.Cu")
		(net "L12_85OHM_10INCH_DP")
	)
	(segment
		(start 264.718292 -163.602416)
		(end 264.38733 -163.369752)
		(width 0.1143)
		(layer "In11.Cu")
		(net "L12_85OHM_10INCH_DP")
	)
	(segment
		(start 273.482308 -163.46678)
		(end 273.250914 -163.797996)
		(width 0.1143)
		(layer "In11.Cu")
		(net "L12_85OHM_10INCH_DP")
	)
	(segment
		(start 271.651984 -163.79825)
		(end 272.015712 -165.859714)
		(width 0.1143)
		(layer "In11.Cu")
		(net "L12_85OHM_10INCH_DP")
	)
	(segment
		(start 275.582634 -163.378896)
		(end 275.081238 -163.46678)
		(width 0.1143)
		(layer "In11.Cu")
		(net "L12_85OHM_10INCH_DP")
	)
	(segment
		(start 282.720542 -165.938962)
		(end 282.310078 -163.611814)
		(width 0.1143)
		(layer "In11.Cu")
		(net "L12_85OHM_10INCH_DP")
	)
	(segment
		(start 276.81174 -165.855904)
		(end 276.719538 -165.988492)
		(width 0.1143)
		(layer "In11.Cu")
		(net "L12_85OHM_10INCH_DP")
	)
	(segment
		(start 282.848558 -163.81476)
		(end 283.208222 -165.851586)
		(width 0.1143)
		(layer "In11.Cu")
		(net "L12_85OHM_10INCH_DP")
	)
	(segment
		(start 263.123426 -163.626546)
		(end 262.792464 -163.39439)
		(width 0.1143)
		(layer "In11.Cu")
		(net "L12_85OHM_10INCH_DP")
	)
	(segment
		(start 281.608276 -165.84803)
		(end 281.51582 -165.980364)
		(width 0.1143)
		(layer "In11.Cu")
		(net "L12_85OHM_10INCH_DP")
	)
	(segment
		(start 266.85748 -163.813998)
		(end 267.218922 -165.86327)
		(width 0.1143)
		(layer "In11.Cu")
		(net "L12_85OHM_10INCH_DP")
	)
	(segment
		(start 299.21454 -165.926262)
		(end 299.122084 -166.058596)
		(width 0.1143)
		(layer "In11.Cu")
		(net "L12_85OHM_10INCH_DP")
	)
	(segment
		(start 301.92599 -166.017448)
		(end 301.498254 -163.591748)
		(width 0.1143)
		(layer "In11.Cu")
		(net "L12_85OHM_10INCH_DP")
	)
	(segment
		(start 272.715736 -163.609782)
		(end 272.384012 -163.378896)
		(width 0.1143)
		(layer "In11.Cu")
		(net "L12_85OHM_10INCH_DP")
	)
	(segment
		(start 291.22116 -165.9382)
		(end 291.12845 -166.070788)
		(width 0.1143)
		(layer "In11.Cu")
		(net "L12_85OHM_10INCH_DP")
	)
	(segment
		(start 249.64517 -165.961568)
		(end 249.55246 -166.093902)
		(width 0.1143)
		(layer "In11.Cu")
		(net "L12_85OHM_10INCH_DP")
	)
	(segment
		(start 267.590016 -163.395152)
		(end 267.089128 -163.482782)
		(width 0.1143)
		(layer "In11.Cu")
		(net "L12_85OHM_10INCH_DP")
	)
	(segment
		(start 279.916636 -165.98011)
		(end 279.654 -166.026338)
		(width 0.1143)
		(layer "In11.Cu")
		(net "L12_85OHM_10INCH_DP")
	)
	(segment
		(start 284.682692 -163.50361)
		(end 284.451298 -163.834826)
		(width 0.1143)
		(layer "In11.Cu")
		(net "L12_85OHM_10INCH_DP")
	)
	(segment
		(start 282.852368 -166.031164)
		(end 282.720542 -165.938962)
		(width 0.1143)
		(layer "In11.Cu")
		(net "L12_85OHM_10INCH_DP")
	)
	(segment
		(start 271.527524 -165.946074)
		(end 271.117314 -163.618164)
		(width 0.1143)
		(layer "In11.Cu")
		(net "L12_85OHM_10INCH_DP")
	)
	(segment
		(start 281.477466 -163.46805)
		(end 281.24658 -163.799266)
		(width 0.1143)
		(layer "In11.Cu")
		(net "L12_85OHM_10INCH_DP")
	)
	(segment
		(start 242.358418 -164.967666)
		(end 242.087654 -164.761926)
		(width 0.1143)
		(layer "In11.Cu")
		(net "L12_85OHM_10INCH_DP")
	)
	(segment
		(start 271.883378 -163.466272)
		(end 271.651984 -163.79825)
		(width 0.1143)
		(layer "In11.Cu")
		(net "L12_85OHM_10INCH_DP")
	)
	(segment
		(start 278.27986 -163.462716)
		(end 278.04745 -163.792916)
		(width 0.1143)
		(layer "In11.Cu")
		(net "L12_85OHM_10INCH_DP")
	)
	(segment
		(start 253.195328 -163.386516)
		(end 252.693932 -163.4744)
		(width 0.1143)
		(layer "In11.Cu")
		(net "L12_85OHM_10INCH_DP")
	)
	(segment
		(start 264.02157 -165.871398)
		(end 263.929368 -166.003986)
		(width 0.1143)
		(layer "In11.Cu")
		(net "L12_85OHM_10INCH_DP")
	)
	(segment
		(start 257.271266 -166.05377)
		(end 257.138678 -165.96106)
		(width 0.1143)
		(layer "In11.Cu")
		(net "L12_85OHM_10INCH_DP")
	)
	(segment
		(start 298.726606 -166.012114)
		(end 298.299124 -163.585906)
		(width 0.1143)
		(layer "In11.Cu")
		(net "L12_85OHM_10INCH_DP")
	)
	(segment
		(start 259.225542 -165.875208)
		(end 259.132832 -166.007796)
		(width 0.1143)
		(layer "In11.Cu")
		(net "L12_85OHM_10INCH_DP")
	)
	(segment
		(start 271.660112 -166.03853)
		(end 271.527524 -165.946074)
		(width 0.1143)
		(layer "In11.Cu")
		(net "L12_85OHM_10INCH_DP")
	)
	(segment
		(start 276.324314 -165.942264)
		(end 275.913596 -163.611052)
		(width 0.1143)
		(layer "In11.Cu")
		(net "L12_85OHM_10INCH_DP")
	)
	(segment
		(start 242.087654 -164.761926)
		(end 241.87277 -164.761926)
		(width 0.1143)
		(layer "In11.Cu")
		(net "L12_85OHM_10INCH_DP")
	)
	(segment
		(start 263.929368 -166.003986)
		(end 263.666732 -166.050468)
		(width 0.1143)
		(layer "In11.Cu")
		(net "L12_85OHM_10INCH_DP")
	)
	(segment
		(start 268.72565 -165.995858)
		(end 268.46276 -166.042086)
		(width 0.1143)
		(layer "In11.Cu")
		(net "L12_85OHM_10INCH_DP")
	)
	(segment
		(start 258.327144 -163.633658)
		(end 257.986784 -163.395152)
		(width 0.1143)
		(layer "In11.Cu")
		(net "L12_85OHM_10INCH_DP")
	)
	(segment
		(start 294.062658 -166.108634)
		(end 293.93007 -166.016178)
		(width 0.1143)
		(layer "In11.Cu")
		(net "L12_85OHM_10INCH_DP")
	)
	(segment
		(start 268.818106 -165.863524)
		(end 268.72565 -165.995858)
		(width 0.1143)
		(layer "In11.Cu")
		(net "L12_85OHM_10INCH_DP")
	)
	(segment
		(start 297.616626 -165.934644)
		(end 297.52417 -166.066978)
		(width 0.1143)
		(layer "In11.Cu")
		(net "L12_85OHM_10INCH_DP")
	)
	(segment
		(start 254.082804 -166.116)
		(end 253.949708 -166.02329)
		(width 0.1143)
		(layer "In11.Cu")
		(net "L12_85OHM_10INCH_DP")
	)
	(segment
		(start 294.775128 -163.383468)
		(end 294.273732 -163.471352)
		(width 0.1143)
		(layer "In11.Cu")
		(net "L12_85OHM_10INCH_DP")
	)
	(segment
		(start 300.458378 -166.105078)
		(end 300.325536 -166.012368)
		(width 0.1143)
		(layer "In11.Cu")
		(net "L12_85OHM_10INCH_DP")
	)
	(segment
		(start 276.456902 -166.034974)
		(end 276.324314 -165.942264)
		(width 0.1143)
		(layer "In11.Cu")
		(net "L12_85OHM_10INCH_DP")
	)
	(segment
		(start 303.834292 -164.637974)
		(end 303.7078 -164.764466)
		(width 0.1143)
		(layer "In11.Cu")
		(net "L12_85OHM_10INCH_DP")
	)
	(segment
		(start 294.325294 -166.06266)
		(end 294.062658 -166.108634)
		(width 0.1143)
		(layer "In11.Cu")
		(net "L12_85OHM_10INCH_DP")
	)
	(segment
		(start 288.713418 -163.648898)
		(end 288.382964 -163.417504)
		(width 0.1143)
		(layer "In11.Cu")
		(net "L12_85OHM_10INCH_DP")
	)
	(segment
		(start 265.133836 -165.957758)
		(end 264.718292 -163.602416)
		(width 0.1143)
		(layer "In11.Cu")
		(net "L12_85OHM_10INCH_DP")
	)
	(segment
		(start 250.883928 -166.111428)
		(end 250.751086 -166.01821)
		(width 0.1143)
		(layer "In11.Cu")
		(net "L12_85OHM_10INCH_DP")
	)
	(segment
		(start 272.015712 -165.859714)
		(end 271.923002 -165.992302)
		(width 0.1143)
		(layer "In11.Cu")
		(net "L12_85OHM_10INCH_DP")
	)
	(segment
		(start 286.056324 -166.062152)
		(end 285.924498 -165.96995)
		(width 0.1143)
		(layer "In11.Cu")
		(net "L12_85OHM_10INCH_DP")
	)
	(segment
		(start 302.769524 -163.375594)
		(end 302.268128 -163.463732)
		(width 0.1143)
		(layer "In11.Cu")
		(net "L12_85OHM_10INCH_DP")
	)
	(segment
		(start 273.520662 -165.98392)
		(end 273.257772 -166.030148)
		(width 0.1143)
		(layer "In11.Cu")
		(net "L12_85OHM_10INCH_DP")
	)
	(segment
		(start 254.060198 -163.797234)
		(end 254.437642 -165.937184)
		(width 0.1143)
		(layer "In11.Cu")
		(net "L12_85OHM_10INCH_DP")
	)
	(segment
		(start 286.412178 -165.882574)
		(end 286.31896 -166.01567)
		(width 0.1143)
		(layer "In11.Cu")
		(net "L12_85OHM_10INCH_DP")
	)
	(segment
		(start 260.467602 -166.045642)
		(end 260.335014 -165.953186)
		(width 0.1143)
		(layer "In11.Cu")
		(net "L12_85OHM_10INCH_DP")
	)
	(segment
		(start 268.687296 -163.483544)
		(end 268.45641 -163.81476)
		(width 0.1143)
		(layer "In11.Cu")
		(net "L12_85OHM_10INCH_DP")
	)
	(segment
		(start 294.273732 -163.471352)
		(end 294.042592 -163.802822)
		(width 0.1143)
		(layer "In11.Cu")
		(net "L12_85OHM_10INCH_DP")
	)
	(segment
		(start 254.344932 -166.07028)
		(end 254.082804 -166.116)
		(width 0.1143)
		(layer "In11.Cu")
		(net "L12_85OHM_10INCH_DP")
	)
	(segment
		(start 281.978862 -163.379658)
		(end 281.477466 -163.46805)
		(width 0.1143)
		(layer "In11.Cu")
		(net "L12_85OHM_10INCH_DP")
	)
	(segment
		(start 260.460744 -163.81349)
		(end 260.823202 -165.866826)
		(width 0.1143)
		(layer "In11.Cu")
		(net "L12_85OHM_10INCH_DP")
	)
	(segment
		(start 303.373536 -164.629592)
		(end 303.282858 -164.508688)
		(width 0.1143)
		(layer "In11.Cu")
		(net "L12_85OHM_10INCH_DP")
	)
	(segment
		(start 269.930372 -165.954456)
		(end 269.519908 -163.627308)
		(width 0.1143)
		(layer "In11.Cu")
		(net "L12_85OHM_10INCH_DP")
	)
	(segment
		(start 292.443408 -163.802568)
		(end 292.81882 -165.929818)
		(width 0.1143)
		(layer "In11.Cu")
		(net "L12_85OHM_10INCH_DP")
	)
	(segment
		(start 250.32716 -163.61283)
		(end 249.996198 -163.38169)
		(width 0.1143)
		(layer "In11.Cu")
		(net "L12_85OHM_10INCH_DP")
	)
	(segment
		(start 299.899324 -163.590732)
		(end 299.568362 -163.359592)
		(width 0.1143)
		(layer "In11.Cu")
		(net "L12_85OHM_10INCH_DP")
	)
	(segment
		(start 303.204626 -164.20084)
		(end 303.100232 -163.607242)
		(width 0.1143)
		(layer "In11.Cu")
		(net "L12_85OHM_10INCH_DP")
	)
	(segment
		(start 287.881568 -163.505642)
		(end 287.650174 -163.836858)
		(width 0.1143)
		(layer "In11.Cu")
		(net "L12_85OHM_10INCH_DP")
	)
	(segment
		(start 292.674802 -163.471352)
		(end 292.443408 -163.802568)
		(width 0.1143)
		(layer "In11.Cu")
		(net "L12_85OHM_10INCH_DP")
	)
	(segment
		(start 286.780986 -163.40201)
		(end 286.27959 -163.490148)
		(width 0.1143)
		(layer "In11.Cu")
		(net "L12_85OHM_10INCH_DP")
	)
	(segment
		(start 279.648412 -163.802822)
		(end 280.009092 -165.847776)
		(width 0.1143)
		(layer "In11.Cu")
		(net "L12_85OHM_10INCH_DP")
	)
	(segment
		(start 249.55246 -166.093902)
		(end 249.289824 -166.140384)
		(width 0.1143)
		(layer "In11.Cu")
		(net "L12_85OHM_10INCH_DP")
	)
	(segment
		(start 279.521158 -165.933628)
		(end 279.110948 -163.605972)
		(width 0.1143)
		(layer "In11.Cu")
		(net "L12_85OHM_10INCH_DP")
	)
	(segment
		(start 258.869942 -166.054024)
		(end 258.737354 -165.961568)
		(width 0.1143)
		(layer "In11.Cu")
		(net "L12_85OHM_10INCH_DP")
	)
	(segment
		(start 289.969448 -163.38423)
		(end 289.484816 -163.46932)
		(width 0.1143)
		(layer "In11.Cu")
		(net "L12_85OHM_10INCH_DP")
	)
	(segment
		(start 289.13328 -166.022782)
		(end 288.713418 -163.648898)
		(width 0.1143)
		(layer "In11.Cu")
		(net "L12_85OHM_10INCH_DP")
	)
	(segment
		(start 303.834292 -164.136324)
		(end 303.834292 -164.637974)
		(width 0.1143)
		(layer "In11.Cu")
		(net "L12_85OHM_10INCH_DP")
	)
	(segment
		(start 285.184088 -163.415472)
		(end 284.682692 -163.50361)
		(width 0.1143)
		(layer "In11.Cu")
		(net "L12_85OHM_10INCH_DP")
	)
	(segment
		(start 243.244624 -165.940486)
		(end 243.151914 -166.073074)
		(width 0.1143)
		(layer "In11.Cu")
		(net "L12_85OHM_10INCH_DP")
	)
	(segment
		(start 270.285464 -163.474654)
		(end 270.05407 -163.80587)
		(width 0.1143)
		(layer "In11.Cu")
		(net "L12_85OHM_10INCH_DP")
	)
	(segment
		(start 255.547114 -166.011098)
		(end 255.12395 -163.60902)
		(width 0.1143)
		(layer "In11.Cu")
		(net "L12_85OHM_10INCH_DP")
	)
	(segment
		(start 287.650174 -163.836858)
		(end 288.014156 -165.898068)
		(width 0.1143)
		(layer "In11.Cu")
		(net "L12_85OHM_10INCH_DP")
	)
	(segment
		(start 287.658302 -166.077646)
		(end 287.526476 -165.985444)
		(width 0.1143)
		(layer "In11.Cu")
		(net "L12_85OHM_10INCH_DP")
	)
	(segment
		(start 241.13998 -165.051486)
		(end 241.75593 -165.667436)
		(width 0.1143)
		(layer "F.Cu")
		(net "L12_85OHM_10INCH_DN")
	)
	(segment
		(start 307.572918 -165.405816)
		(end 307.211476 -165.044374)
		(width 0.1143)
		(layer "F.Cu")
		(net "L12_85OHM_10INCH_DN")
	)
	(segment
		(start 238.371634 -165.051486)
		(end 241.13998 -165.051486)
		(width 0.1143)
		(layer "F.Cu")
		(net "L12_85OHM_10INCH_DN")
	)
	(segment
		(start 238.017304 -165.405816)
		(end 238.371634 -165.051486)
		(width 0.1143)
		(layer "F.Cu")
		(net "L12_85OHM_10INCH_DN")
	)
	(segment
		(start 307.211476 -165.044374)
		(end 304.450242 -165.044374)
		(width 0.1143)
		(layer "F.Cu")
		(net "L12_85OHM_10INCH_DN")
	)
	(segment
		(start 304.450242 -165.044374)
		(end 303.834292 -165.660324)
		(width 0.1143)
		(layer "F.Cu")
		(net "L12_85OHM_10INCH_DN")
	)
	(via
		(at 241.75593 -165.667436)
		(size 0.5588)
		(drill 0.3048)
		(layers "F.Cu" "B.Cu")
		(net "L12_85OHM_10INCH_DN")
	)
	(via
		(at 303.834292 -165.660324)
		(size 0.5588)
		(drill 0.3048)
		(layers "F.Cu" "B.Cu")
		(net "L12_85OHM_10INCH_DN")
	)
	(segment
		(start 265.929872 -165.939978)
		(end 265.566144 -163.877244)
		(width 0.1143)
		(layer "In11.Cu")
		(net "L12_85OHM_10INCH_DN")
	)
	(segment
		(start 253.25959 -163.787582)
		(end 253.682754 -166.193724)
		(width 0.1143)
		(layer "In11.Cu")
		(net "L12_85OHM_10INCH_DN")
	)
	(segment
		(start 241.86769 -165.054026)
		(end 241.989102 -165.054026)
		(width 0.1143)
		(layer "In11.Cu")
		(net "L12_85OHM_10INCH_DN")
	)
	(segment
		(start 286.84474 -163.803584)
		(end 287.259776 -166.15537)
		(width 0.1143)
		(layer "In11.Cu")
		(net "L12_85OHM_10INCH_DN")
	)
	(segment
		(start 278.356314 -163.86175)
		(end 278.449278 -163.72967)
		(width 0.1143)
		(layer "In11.Cu")
		(net "L12_85OHM_10INCH_DN")
	)
	(segment
		(start 244.868954 -163.74491)
		(end 245.131844 -163.698682)
		(width 0.1143)
		(layer "In11.Cu")
		(net "L12_85OHM_10INCH_DN")
	)
	(segment
		(start 260.769608 -163.881816)
		(end 260.862318 -163.749228)
		(width 0.1143)
		(layer "In11.Cu")
		(net "L12_85OHM_10INCH_DN")
	)
	(segment
		(start 282.784042 -166.340028)
		(end 283.285184 -166.251382)
		(width 0.1143)
		(layer "In11.Cu")
		(net "L12_85OHM_10INCH_DN")
	)
	(segment
		(start 302.700944 -163.684458)
		(end 302.833532 -163.777168)
		(width 0.1143)
		(layer "In11.Cu")
		(net "L12_85OHM_10INCH_DN")
	)
	(segment
		(start 242.34267 -165.433756)
		(end 242.385596 -165.60292)
		(width 0.1143)
		(layer "In11.Cu")
		(net "L12_85OHM_10INCH_DN")
	)
	(segment
		(start 297.92549 -166.00297)
		(end 297.54449 -163.841684)
		(width 0.1143)
		(layer "In11.Cu")
		(net "L12_85OHM_10INCH_DN")
	)
	(segment
		(start 261.132066 -165.935152)
		(end 260.769608 -163.881816)
		(width 0.1143)
		(layer "In11.Cu")
		(net "L12_85OHM_10INCH_DN")
	)
	(segment
		(start 291.640514 -163.78047)
		(end 292.063932 -166.186358)
		(width 0.1143)
		(layer "In11.Cu")
		(net "L12_85OHM_10INCH_DN")
	)
	(segment
		(start 289.699446 -166.336472)
		(end 289.930586 -166.005256)
		(width 0.1143)
		(layer "In11.Cu")
		(net "L12_85OHM_10INCH_DN")
	)
	(segment
		(start 277.112222 -163.683442)
		(end 277.245318 -163.776914)
		(width 0.1143)
		(layer "In11.Cu")
		(net "L12_85OHM_10INCH_DN")
	)
	(segment
		(start 302.918622 -164.262308)
		(end 303.013872 -164.637466)
		(width 0.1143)
		(layer "In11.Cu")
		(net "L12_85OHM_10INCH_DN")
	)
	(segment
		(start 266.464034 -166.119302)
		(end 266.79525 -166.350442)
		(width 0.1143)
		(layer "In11.Cu")
		(net "L12_85OHM_10INCH_DN")
	)
	(segment
		(start 271.960848 -163.866322)
		(end 272.053558 -163.733226)
		(width 0.1143)
		(layer "In11.Cu")
		(net "L12_85OHM_10INCH_DN")
	)
	(segment
		(start 287.259776 -166.15537)
		(end 287.589976 -166.38651)
		(width 0.1143)
		(layer "In11.Cu")
		(net "L12_85OHM_10INCH_DN")
	)
	(segment
		(start 249.954034 -166.030148)
		(end 249.573034 -163.86937)
		(width 0.1143)
		(layer "In11.Cu")
		(net "L12_85OHM_10INCH_DN")
	)
	(segment
		(start 291.24529 -163.73348)
		(end 291.507418 -163.68776)
		(width 0.1143)
		(layer "In11.Cu")
		(net "L12_85OHM_10INCH_DN")
	)
	(segment
		(start 241.75593 -165.165786)
		(end 241.86769 -165.054026)
		(width 0.1143)
		(layer "In11.Cu")
		(net "L12_85OHM_10INCH_DN")
	)
	(segment
		(start 253.682754 -166.193724)
		(end 254.014478 -166.42461)
		(width 0.1143)
		(layer "In11.Cu")
		(net "L12_85OHM_10INCH_DN")
	)
	(segment
		(start 290.797234 -166.425626)
		(end 291.29863 -166.337742)
		(width 0.1143)
		(layer "In11.Cu")
		(net "L12_85OHM_10INCH_DN")
	)
	(segment
		(start 297.899836 -163.66363)
		(end 298.032424 -163.756086)
		(width 0.1143)
		(layer "In11.Cu")
		(net "L12_85OHM_10INCH_DN")
	)
	(segment
		(start 289.930586 -166.005256)
		(end 289.555682 -163.878514)
		(width 0.1143)
		(layer "In11.Cu")
		(net "L12_85OHM_10INCH_DN")
	)
	(segment
		(start 281.91714 -165.916356)
		(end 281.555444 -163.867338)
		(width 0.1143)
		(layer "In11.Cu")
		(net "L12_85OHM_10INCH_DN")
	)
	(segment
		(start 249.722386 -166.360602)
		(end 249.954034 -166.030148)
		(width 0.1143)
		(layer "In11.Cu")
		(net "L12_85OHM_10INCH_DN")
	)
	(segment
		(start 298.459652 -166.182294)
		(end 298.790868 -166.413434)
		(width 0.1143)
		(layer "In11.Cu")
		(net "L12_85OHM_10INCH_DN")
	)
	(segment
		(start 279.58542 -166.334948)
		(end 280.086816 -166.247064)
		(width 0.1143)
		(layer "In11.Cu")
		(net "L12_85OHM_10INCH_DN")
	)
	(segment
		(start 251.660152 -163.787582)
		(end 252.084078 -166.189406)
		(width 0.1143)
		(layer "In11.Cu")
		(net "L12_85OHM_10INCH_DN")
	)
	(segment
		(start 272.858484 -166.107872)
		(end 273.189446 -166.338758)
		(width 0.1143)
		(layer "In11.Cu")
		(net "L12_85OHM_10INCH_DN")
	)
	(segment
		(start 254.724662 -163.686744)
		(end 254.85725 -163.7792)
		(width 0.1143)
		(layer "In11.Cu")
		(net "L12_85OHM_10INCH_DN")
	)
	(segment
		(start 283.512768 -163.704524)
		(end 283.645356 -163.797234)
		(width 0.1143)
		(layer "In11.Cu")
		(net "L12_85OHM_10INCH_DN")
	)
	(segment
		(start 300.058836 -166.182548)
		(end 300.390052 -166.413688)
		(width 0.1143)
		(layer "In11.Cu")
		(net "L12_85OHM_10INCH_DN")
	)
	(segment
		(start 274.04695 -163.779962)
		(end 274.457922 -166.107872)
		(width 0.1143)
		(layer "In11.Cu")
		(net "L12_85OHM_10INCH_DN")
	)
	(segment
		(start 268.063218 -166.119556)
		(end 268.394434 -166.350696)
		(width 0.1143)
		(layer "In11.Cu")
		(net "L12_85OHM_10INCH_DN")
	)
	(segment
		(start 300.74362 -163.847526)
		(end 300.836076 -163.714684)
		(width 0.1143)
		(layer "In11.Cu")
		(net "L12_85OHM_10INCH_DN")
	)
	(segment
		(start 290.043108 -163.792662)
		(end 290.466272 -166.19474)
		(width 0.1143)
		(layer "In11.Cu")
		(net "L12_85OHM_10INCH_DN")
	)
	(segment
		(start 292.752272 -163.870894)
		(end 292.844982 -163.738306)
		(width 0.1143)
		(layer "In11.Cu")
		(net "L12_85OHM_10INCH_DN")
	)
	(segment
		(start 249.927872 -163.6903)
		(end 250.06046 -163.78301)
		(width 0.1143)
		(layer "In11.Cu")
		(net "L12_85OHM_10INCH_DN")
	)
	(segment
		(start 267.296646 -166.262558)
		(end 267.527786 -165.931596)
		(width 0.1143)
		(layer "In11.Cu")
		(net "L12_85OHM_10INCH_DN")
	)
	(segment
		(start 277.987506 -166.343584)
		(end 278.488902 -166.255446)
		(width 0.1143)
		(layer "In11.Cu")
		(net "L12_85OHM_10INCH_DN")
	)
	(segment
		(start 292.063932 -166.186358)
		(end 292.394894 -166.417244)
		(width 0.1143)
		(layer "In11.Cu")
		(net "L12_85OHM_10INCH_DN")
	)
	(segment
		(start 251.31649 -166.332408)
		(end 251.54763 -166.000938)
		(width 0.1143)
		(layer "In11.Cu")
		(net "L12_85OHM_10INCH_DN")
	)
	(segment
		(start 251.172472 -163.873434)
		(end 251.264928 -163.7411)
		(width 0.1143)
		(layer "In11.Cu")
		(net "L12_85OHM_10INCH_DN")
	)
	(segment
		(start 242.385596 -165.60292)
		(end 242.490244 -166.196518)
		(width 0.1143)
		(layer "In11.Cu")
		(net "L12_85OHM_10INCH_DN")
	)
	(segment
		(start 249.22099 -166.449248)
		(end 249.722386 -166.360602)
		(width 0.1143)
		(layer "In11.Cu")
		(net "L12_85OHM_10INCH_DN")
	)
	(segment
		(start 274.788884 -166.338758)
		(end 275.290026 -166.251128)
		(width 0.1143)
		(layer "In11.Cu")
		(net "L12_85OHM_10INCH_DN")
	)
	(segment
		(start 294.443912 -163.738306)
		(end 294.706294 -163.692332)
		(width 0.1143)
		(layer "In11.Cu")
		(net "L12_85OHM_10INCH_DN")
	)
	(segment
		(start 267.654024 -163.796472)
		(end 268.063218 -166.119556)
		(width 0.1143)
		(layer "In11.Cu")
		(net "L12_85OHM_10INCH_DN")
	)
	(segment
		(start 303.834292 -165.158674)
		(end 303.834292 -165.660324)
		(width 0.1143)
		(layer "In11.Cu")
		(net "L12_85OHM_10INCH_DN")
	)
	(segment
		(start 255.968246 -163.86556)
		(end 256.060702 -163.732972)
		(width 0.1143)
		(layer "In11.Cu")
		(net "L12_85OHM_10INCH_DN")
	)
	(segment
		(start 269.993872 -166.355522)
		(end 270.495014 -166.266876)
		(width 0.1143)
		(layer "In11.Cu")
		(net "L12_85OHM_10INCH_DN")
	)
	(segment
		(start 256.323338 -163.686744)
		(end 256.455926 -163.779454)
		(width 0.1143)
		(layer "In11.Cu")
		(net "L12_85OHM_10INCH_DN")
	)
	(segment
		(start 289.654996 -163.736274)
		(end 289.900868 -163.693094)
		(width 0.1143)
		(layer "In11.Cu")
		(net "L12_85OHM_10INCH_DN")
	)
	(segment
		(start 292.844982 -163.738306)
		(end 293.10711 -163.692078)
		(width 0.1143)
		(layer "In11.Cu")
		(net "L12_85OHM_10INCH_DN")
	)
	(segment
		(start 294.839136 -163.78555)
		(end 295.263062 -166.19093)
		(width 0.1143)
		(layer "In11.Cu")
		(net "L12_85OHM_10INCH_DN")
	)
	(segment
		(start 273.922236 -165.919658)
		(end 273.559778 -163.866322)
		(width 0.1143)
		(layer "In11.Cu")
		(net "L12_85OHM_10INCH_DN")
	)
	(segment
		(start 257.573018 -163.889436)
		(end 257.672078 -163.747196)
		(width 0.1143)
		(layer "In11.Cu")
		(net "L12_85OHM_10INCH_DN")
	)
	(segment
		(start 247.973596 -163.869116)
		(end 248.066052 -163.736782)
		(width 0.1143)
		(layer "In11.Cu")
		(net "L12_85OHM_10INCH_DN")
	)
	(segment
		(start 273.189446 -166.338758)
		(end 273.690842 -166.250874)
		(width 0.1143)
		(layer "In11.Cu")
		(net "L12_85OHM_10INCH_DN")
	)
	(segment
		(start 273.690842 -166.250874)
		(end 273.922236 -165.919658)
		(width 0.1143)
		(layer "In11.Cu")
		(net "L12_85OHM_10INCH_DN")
	)
	(segment
		(start 254.746506 -166.005256)
		(end 254.369062 -163.86556)
		(width 0.1143)
		(layer "In11.Cu")
		(net "L12_85OHM_10INCH_DN")
	)
	(segment
		(start 292.394894 -166.417244)
		(end 292.89629 -166.32936)
		(width 0.1143)
		(layer "In11.Cu")
		(net "L12_85OHM_10INCH_DN")
	)
	(segment
		(start 249.573034 -163.86937)
		(end 249.665236 -163.736782)
		(width 0.1143)
		(layer "In11.Cu")
		(net "L12_85OHM_10INCH_DN")
	)
	(segment
		(start 264.451338 -163.772088)
		(end 264.867136 -166.127684)
		(width 0.1143)
		(layer "In11.Cu")
		(net "L12_85OHM_10INCH_DN")
	)
	(segment
		(start 257.704082 -166.274242)
		(end 257.935222 -165.943026)
		(width 0.1143)
		(layer "In11.Cu")
		(net "L12_85OHM_10INCH_DN")
	)
	(segment
		(start 283.250386 -163.750498)
		(end 283.512768 -163.704524)
		(width 0.1143)
		(layer "In11.Cu")
		(net "L12_85OHM_10INCH_DN")
	)
	(segment
		(start 250.484132 -166.188136)
		(end 250.815094 -166.420292)
		(width 0.1143)
		(layer "In11.Cu")
		(net "L12_85OHM_10INCH_DN")
	)
	(segment
		(start 295.594024 -166.42207)
		(end 296.095166 -166.333678)
		(width 0.1143)
		(layer "In11.Cu")
		(net "L12_85OHM_10INCH_DN")
	)
	(segment
		(start 266.79525 -166.350442)
		(end 267.296646 -166.262558)
		(width 0.1143)
		(layer "In11.Cu")
		(net "L12_85OHM_10INCH_DN")
	)
	(segment
		(start 284.852872 -163.770564)
		(end 285.115508 -163.724336)
		(width 0.1143)
		(layer "In11.Cu")
		(net "L12_85OHM_10INCH_DN")
	)
	(segment
		(start 252.084078 -166.189406)
		(end 252.414786 -166.420546)
		(width 0.1143)
		(layer "In11.Cu")
		(net "L12_85OHM_10INCH_DN")
	)
	(segment
		(start 283.517086 -165.920166)
		(end 283.157676 -163.88334)
		(width 0.1143)
		(layer "In11.Cu")
		(net "L12_85OHM_10INCH_DN")
	)
	(segment
		(start 292.89629 -166.32936)
		(end 293.127684 -165.998144)
		(width 0.1143)
		(layer "In11.Cu")
		(net "L12_85OHM_10INCH_DN")
	)
	(segment
		(start 248.890028 -166.216584)
		(end 249.22099 -166.449248)
		(width 0.1143)
		(layer "In11.Cu")
		(net "L12_85OHM_10INCH_DN")
	)
	(segment
		(start 262.72363 -163.703254)
		(end 262.856472 -163.796472)
		(width 0.1143)
		(layer "In11.Cu")
		(net "L12_85OHM_10INCH_DN")
	)
	(segment
		(start 280.853388 -166.104062)
		(end 281.184604 -166.335202)
		(width 0.1143)
		(layer "In11.Cu")
		(net "L12_85OHM_10INCH_DN")
	)
	(segment
		(start 303.16043 -164.832792)
		(end 303.446942 -165.069266)
		(width 0.1143)
		(layer "In11.Cu")
		(net "L12_85OHM_10INCH_DN")
	)
	(segment
		(start 245.155466 -166.024306)
		(end 244.776498 -163.877244)
		(width 0.1143)
		(layer "In11.Cu")
		(net "L12_85OHM_10INCH_DN")
	)
	(segment
		(start 255.280414 -166.181024)
		(end 255.620774 -166.41953)
		(width 0.1143)
		(layer "In11.Cu")
		(net "L12_85OHM_10INCH_DN")
	)
	(segment
		(start 278.844248 -163.776152)
		(end 279.254204 -166.103808)
		(width 0.1143)
		(layer "In11.Cu")
		(net "L12_85OHM_10INCH_DN")
	)
	(segment
		(start 299.523404 -165.994588)
		(end 299.14469 -163.846764)
		(width 0.1143)
		(layer "In11.Cu")
		(net "L12_85OHM_10INCH_DN")
	)
	(segment
		(start 246.522748 -166.356538)
		(end 246.754396 -166.025322)
		(width 0.1143)
		(layer "In11.Cu")
		(net "L12_85OHM_10INCH_DN")
	)
	(segment
		(start 270.362934 -163.874196)
		(end 270.455644 -163.741608)
		(width 0.1143)
		(layer "In11.Cu")
		(net "L12_85OHM_10INCH_DN")
	)
	(segment
		(start 303.013872 -164.637466)
		(end 303.16043 -164.832792)
		(width 0.1143)
		(layer "In11.Cu")
		(net "L12_85OHM_10INCH_DN")
	)
	(segment
		(start 270.455644 -163.741608)
		(end 270.71828 -163.69538)
		(width 0.1143)
		(layer "In11.Cu")
		(net "L12_85OHM_10INCH_DN")
	)
	(segment
		(start 275.521166 -165.920166)
		(end 275.158962 -163.866322)
		(width 0.1143)
		(layer "In11.Cu")
		(net "L12_85OHM_10INCH_DN")
	)
	(segment
		(start 251.54763 -166.000938)
		(end 251.172472 -163.873434)
		(width 0.1143)
		(layer "In11.Cu")
		(net "L12_85OHM_10INCH_DN")
	)
	(segment
		(start 300.390052 -166.413688)
		(end 300.891448 -166.325804)
		(width 0.1143)
		(layer "In11.Cu")
		(net "L12_85OHM_10INCH_DN")
	)
	(segment
		(start 283.645356 -163.797234)
		(end 284.05582 -166.124382)
		(width 0.1143)
		(layer "In11.Cu")
		(net "L12_85OHM_10INCH_DN")
	)
	(segment
		(start 267.521436 -163.703762)
		(end 267.654024 -163.796472)
		(width 0.1143)
		(layer "In11.Cu")
		(net "L12_85OHM_10INCH_DN")
	)
	(segment
		(start 243.664232 -163.786312)
		(end 244.091968 -166.212012)
		(width 0.1143)
		(layer "In11.Cu")
		(net "L12_85OHM_10INCH_DN")
	)
	(segment
		(start 284.760162 -163.903152)
		(end 284.852872 -163.770564)
		(width 0.1143)
		(layer "In11.Cu")
		(net "L12_85OHM_10INCH_DN")
	)
	(segment
		(start 289.555682 -163.878514)
		(end 289.654996 -163.736274)
		(width 0.1143)
		(layer "In11.Cu")
		(net "L12_85OHM_10INCH_DN")
	)
	(segment
		(start 242.149122 -165.175692)
		(end 242.34267 -165.433756)
		(width 0.1143)
		(layer "In11.Cu")
		(net "L12_85OHM_10INCH_DN")
	)
	(segment
		(start 242.490244 -166.196518)
		(end 242.820698 -166.428166)
		(width 0.1143)
		(layer "In11.Cu")
		(net "L12_85OHM_10INCH_DN")
	)
	(segment
		(start 254.369062 -163.86556)
		(end 254.461772 -163.732972)
		(width 0.1143)
		(layer "In11.Cu")
		(net "L12_85OHM_10INCH_DN")
	)
	(segment
		(start 272.053558 -163.733226)
		(end 272.315686 -163.687506)
		(width 0.1143)
		(layer "In11.Cu")
		(net "L12_85OHM_10INCH_DN")
	)
	(segment
		(start 287.589976 -166.38651)
		(end 288.091118 -166.297864)
		(width 0.1143)
		(layer "In11.Cu")
		(net "L12_85OHM_10INCH_DN")
	)
	(segment
		(start 286.712406 -163.710874)
		(end 286.84474 -163.803584)
		(width 0.1143)
		(layer "In11.Cu")
		(net "L12_85OHM_10INCH_DN")
	)
	(segment
		(start 241.989102 -165.054026)
		(end 242.149122 -165.175692)
		(width 0.1143)
		(layer "In11.Cu")
		(net "L12_85OHM_10INCH_DN")
	)
	(segment
		(start 275.158962 -163.866322)
		(end 275.251418 -163.733734)
		(width 0.1143)
		(layer "In11.Cu")
		(net "L12_85OHM_10INCH_DN")
	)
	(segment
		(start 261.124446 -163.703)
		(end 261.25678 -163.795456)
		(width 0.1143)
		(layer "In11.Cu")
		(net "L12_85OHM_10INCH_DN")
	)
	(segment
		(start 286.48914 -166.28237)
		(end 286.721042 -165.951154)
		(width 0.1143)
		(layer "In11.Cu")
		(net "L12_85OHM_10INCH_DN")
	)
	(segment
		(start 285.247842 -163.817046)
		(end 285.657798 -166.139876)
		(width 0.1143)
		(layer "In11.Cu")
		(net "L12_85OHM_10INCH_DN")
	)
	(segment
		(start 276.889718 -166.255192)
		(end 277.120604 -165.924738)
		(width 0.1143)
		(layer "In11.Cu")
		(net "L12_85OHM_10INCH_DN")
	)
	(segment
		(start 252.864112 -163.741354)
		(end 253.127002 -163.695126)
		(width 0.1143)
		(layer "In11.Cu")
		(net "L12_85OHM_10INCH_DN")
	)
	(segment
		(start 285.657798 -166.139876)
		(end 285.987998 -166.371016)
		(width 0.1143)
		(layer "In11.Cu")
		(net "L12_85OHM_10INCH_DN")
	)
	(segment
		(start 301.98949 -166.418514)
		(end 302.490632 -166.329868)
		(width 0.1143)
		(layer "In11.Cu")
		(net "L12_85OHM_10INCH_DN")
	)
	(segment
		(start 296.095166 -166.333678)
		(end 296.326052 -166.003224)
		(width 0.1143)
		(layer "In11.Cu")
		(net "L12_85OHM_10INCH_DN")
	)
	(segment
		(start 300.891448 -166.325804)
		(end 301.122588 -165.994842)
		(width 0.1143)
		(layer "In11.Cu")
		(net "L12_85OHM_10INCH_DN")
	)
	(segment
		(start 280.049986 -163.73856)
		(end 280.312368 -163.692586)
		(width 0.1143)
		(layer "In11.Cu")
		(net "L12_85OHM_10INCH_DN")
	)
	(segment
		(start 280.317956 -165.916102)
		(end 279.957276 -163.871148)
		(width 0.1143)
		(layer "In11.Cu")
		(net "L12_85OHM_10INCH_DN")
	)
	(segment
		(start 288.446718 -163.819078)
		(end 288.86658 -166.192962)
		(width 0.1143)
		(layer "In11.Cu")
		(net "L12_85OHM_10INCH_DN")
	)
	(segment
		(start 246.754396 -166.025322)
		(end 246.375682 -163.877498)
		(width 0.1143)
		(layer "In11.Cu")
		(net "L12_85OHM_10INCH_DN")
	)
	(segment
		(start 263.267444 -166.127938)
		(end 263.598406 -166.359078)
		(width 0.1143)
		(layer "In11.Cu")
		(net "L12_85OHM_10INCH_DN")
	)
	(segment
		(start 264.05586 -163.725098)
		(end 264.318496 -163.678616)
		(width 0.1143)
		(layer "In11.Cu")
		(net "L12_85OHM_10INCH_DN")
	)
	(segment
		(start 244.423184 -166.444168)
		(end 244.92458 -166.355776)
		(width 0.1143)
		(layer "In11.Cu")
		(net "L12_85OHM_10INCH_DN")
	)
	(segment
		(start 252.771402 -163.873942)
		(end 252.864112 -163.741354)
		(width 0.1143)
		(layer "In11.Cu")
		(net "L12_85OHM_10INCH_DN")
	)
	(segment
		(start 303.731422 -165.056058)
		(end 303.834292 -165.158674)
		(width 0.1143)
		(layer "In11.Cu")
		(net "L12_85OHM_10INCH_DN")
	)
	(segment
		(start 260.399276 -166.354252)
		(end 260.900672 -166.266368)
		(width 0.1143)
		(layer "In11.Cu")
		(net "L12_85OHM_10INCH_DN")
	)
	(segment
		(start 288.32302 -165.966648)
		(end 287.959038 -163.905184)
		(width 0.1143)
		(layer "In11.Cu")
		(net "L12_85OHM_10INCH_DN")
	)
	(segment
		(start 276.388576 -166.343584)
		(end 276.889718 -166.255192)
		(width 0.1143)
		(layer "In11.Cu")
		(net "L12_85OHM_10INCH_DN")
	)
	(segment
		(start 269.120112 -163.704016)
		(end 269.253208 -163.797234)
		(width 0.1143)
		(layer "In11.Cu")
		(net "L12_85OHM_10INCH_DN")
	)
	(segment
		(start 256.343404 -165.993572)
		(end 255.968246 -163.86556)
		(width 0.1143)
		(layer "In11.Cu")
		(net "L12_85OHM_10INCH_DN")
	)
	(segment
		(start 263.96315 -163.857432)
		(end 264.05586 -163.725098)
		(width 0.1143)
		(layer "In11.Cu")
		(net "L12_85OHM_10INCH_DN")
	)
	(segment
		(start 295.945052 -163.842192)
		(end 296.037762 -163.709858)
		(width 0.1143)
		(layer "In11.Cu")
		(net "L12_85OHM_10INCH_DN")
	)
	(segment
		(start 298.790868 -166.413434)
		(end 299.292264 -166.32555)
		(width 0.1143)
		(layer "In11.Cu")
		(net "L12_85OHM_10INCH_DN")
	)
	(segment
		(start 291.15258 -163.866576)
		(end 291.24529 -163.73348)
		(width 0.1143)
		(layer "In11.Cu")
		(net "L12_85OHM_10INCH_DN")
	)
	(segment
		(start 288.091118 -166.297864)
		(end 288.32302 -165.966648)
		(width 0.1143)
		(layer "In11.Cu")
		(net "L12_85OHM_10INCH_DN")
	)
	(segment
		(start 260.900672 -166.266368)
		(end 261.132066 -165.935152)
		(width 0.1143)
		(layer "In11.Cu")
		(net "L12_85OHM_10INCH_DN")
	)
	(segment
		(start 288.051748 -163.772596)
		(end 288.314384 -163.726368)
		(width 0.1143)
		(layer "In11.Cu")
		(net "L12_85OHM_10INCH_DN")
	)
	(segment
		(start 262.368792 -163.881816)
		(end 262.461248 -163.749228)
		(width 0.1143)
		(layer "In11.Cu")
		(net "L12_85OHM_10INCH_DN")
	)
	(segment
		(start 303.446942 -165.069266)
		(end 303.731422 -165.056058)
		(width 0.1143)
		(layer "In11.Cu")
		(net "L12_85OHM_10INCH_DN")
	)
	(segment
		(start 299.499782 -163.668202)
		(end 299.63237 -163.760912)
		(width 0.1143)
		(layer "In11.Cu")
		(net "L12_85OHM_10INCH_DN")
	)
	(segment
		(start 252.91542 -166.332408)
		(end 253.146814 -166.001192)
		(width 0.1143)
		(layer "In11.Cu")
		(net "L12_85OHM_10INCH_DN")
	)
	(segment
		(start 269.663672 -166.124382)
		(end 269.993872 -166.355522)
		(width 0.1143)
		(layer "In11.Cu")
		(net "L12_85OHM_10INCH_DN")
	)
	(segment
		(start 297.192954 -166.42207)
		(end 297.69435 -166.333932)
		(width 0.1143)
		(layer "In11.Cu")
		(net "L12_85OHM_10INCH_DN")
	)
	(segment
		(start 302.833532 -163.777168)
		(end 302.918622 -164.262308)
		(width 0.1143)
		(layer "In11.Cu")
		(net "L12_85OHM_10INCH_DN")
	)
	(segment
		(start 286.721042 -165.951154)
		(end 286.35706 -163.88969)
		(width 0.1143)
		(layer "In11.Cu")
		(net "L12_85OHM_10INCH_DN")
	)
	(segment
		(start 260.068314 -166.123366)
		(end 260.399276 -166.354252)
		(width 0.1143)
		(layer "In11.Cu")
		(net "L12_85OHM_10INCH_DN")
	)
	(segment
		(start 280.086816 -166.247064)
		(end 280.317956 -165.916102)
		(width 0.1143)
		(layer "In11.Cu")
		(net "L12_85OHM_10INCH_DN")
	)
	(segment
		(start 254.461772 -163.732972)
		(end 254.724662 -163.686744)
		(width 0.1143)
		(layer "In11.Cu")
		(net "L12_85OHM_10INCH_DN")
	)
	(segment
		(start 244.776498 -163.877244)
		(end 244.868954 -163.74491)
		(width 0.1143)
		(layer "In11.Cu")
		(net "L12_85OHM_10INCH_DN")
	)
	(segment
		(start 288.314384 -163.726368)
		(end 288.446718 -163.819078)
		(width 0.1143)
		(layer "In11.Cu")
		(net "L12_85OHM_10INCH_DN")
	)
	(segment
		(start 248.460768 -163.78301)
		(end 248.890028 -166.216584)
		(width 0.1143)
		(layer "In11.Cu")
		(net "L12_85OHM_10INCH_DN")
	)
	(segment
		(start 249.665236 -163.736782)
		(end 249.927872 -163.6903)
		(width 0.1143)
		(layer "In11.Cu")
		(net "L12_85OHM_10INCH_DN")
	)
	(segment
		(start 285.115508 -163.724336)
		(end 285.247842 -163.817046)
		(width 0.1143)
		(layer "In11.Cu")
		(net "L12_85OHM_10INCH_DN")
	)
	(segment
		(start 266.054078 -163.791646)
		(end 266.464034 -166.119302)
		(width 0.1143)
		(layer "In11.Cu")
		(net "L12_85OHM_10INCH_DN")
	)
	(segment
		(start 278.449278 -163.72967)
		(end 278.71166 -163.683696)
		(width 0.1143)
		(layer "In11.Cu")
		(net "L12_85OHM_10INCH_DN")
	)
	(segment
		(start 243.26977 -163.740592)
		(end 243.532406 -163.69411)
		(width 0.1143)
		(layer "In11.Cu")
		(net "L12_85OHM_10INCH_DN")
	)
	(segment
		(start 282.453842 -166.108888)
		(end 282.784042 -166.340028)
		(width 0.1143)
		(layer "In11.Cu")
		(net "L12_85OHM_10INCH_DN")
	)
	(segment
		(start 274.457922 -166.107872)
		(end 274.788884 -166.338758)
		(width 0.1143)
		(layer "In11.Cu")
		(net "L12_85OHM_10INCH_DN")
	)
	(segment
		(start 297.637454 -163.709604)
		(end 297.899836 -163.66363)
		(width 0.1143)
		(layer "In11.Cu")
		(net "L12_85OHM_10INCH_DN")
	)
	(segment
		(start 291.530024 -166.006526)
		(end 291.15258 -163.866576)
		(width 0.1143)
		(layer "In11.Cu")
		(net "L12_85OHM_10INCH_DN")
	)
	(segment
		(start 269.12697 -165.93185)
		(end 268.765274 -163.882832)
		(width 0.1143)
		(layer "In11.Cu")
		(net "L12_85OHM_10INCH_DN")
	)
	(segment
		(start 253.146814 -166.001192)
		(end 252.771402 -163.873942)
		(width 0.1143)
		(layer "In11.Cu")
		(net "L12_85OHM_10INCH_DN")
	)
	(segment
		(start 259.658612 -163.79571)
		(end 260.068314 -166.123366)
		(width 0.1143)
		(layer "In11.Cu")
		(net "L12_85OHM_10INCH_DN")
	)
	(segment
		(start 270.850614 -163.78809)
		(end 271.260824 -166.116254)
		(width 0.1143)
		(layer "In11.Cu")
		(net "L12_85OHM_10INCH_DN")
	)
	(segment
		(start 295.263062 -166.19093)
		(end 295.594024 -166.42207)
		(width 0.1143)
		(layer "In11.Cu")
		(net "L12_85OHM_10INCH_DN")
	)
	(segment
		(start 262.461248 -163.749228)
		(end 262.72363 -163.703254)
		(width 0.1143)
		(layer "In11.Cu")
		(net "L12_85OHM_10INCH_DN")
	)
	(segment
		(start 293.239444 -163.784534)
		(end 293.66337 -166.186358)
		(width 0.1143)
		(layer "In11.Cu")
		(net "L12_85OHM_10INCH_DN")
	)
	(segment
		(start 259.303012 -166.27475)
		(end 259.534406 -165.943534)
		(width 0.1143)
		(layer "In11.Cu")
		(net "L12_85OHM_10INCH_DN")
	)
	(segment
		(start 273.914616 -163.687506)
		(end 274.04695 -163.779962)
		(width 0.1143)
		(layer "In11.Cu")
		(net "L12_85OHM_10INCH_DN")
	)
	(segment
		(start 243.322094 -166.340028)
		(end 243.553488 -166.008812)
		(width 0.1143)
		(layer "In11.Cu")
		(net "L12_85OHM_10INCH_DN")
	)
	(segment
		(start 262.499856 -166.266622)
		(end 262.730996 -165.93566)
		(width 0.1143)
		(layer "In11.Cu")
		(net "L12_85OHM_10INCH_DN")
	)
	(segment
		(start 271.260824 -166.116254)
		(end 271.591786 -166.34714)
		(width 0.1143)
		(layer "In11.Cu")
		(net "L12_85OHM_10INCH_DN")
	)
	(segment
		(start 277.120604 -165.924738)
		(end 276.756876 -163.862258)
		(width 0.1143)
		(layer "In11.Cu")
		(net "L12_85OHM_10INCH_DN")
	)
	(segment
		(start 261.25678 -163.795456)
		(end 261.667752 -166.123366)
		(width 0.1143)
		(layer "In11.Cu")
		(net "L12_85OHM_10INCH_DN")
	)
	(segment
		(start 278.488902 -166.255446)
		(end 278.720042 -165.924484)
		(width 0.1143)
		(layer "In11.Cu")
		(net "L12_85OHM_10INCH_DN")
	)
	(segment
		(start 294.726614 -165.998652)
		(end 294.351456 -163.870894)
		(width 0.1143)
		(layer "In11.Cu")
		(net "L12_85OHM_10INCH_DN")
	)
	(segment
		(start 246.468138 -163.745164)
		(end 246.730774 -163.698936)
		(width 0.1143)
		(layer "In11.Cu")
		(net "L12_85OHM_10INCH_DN")
	)
	(segment
		(start 261.998714 -166.354252)
		(end 262.499856 -166.266622)
		(width 0.1143)
		(layer "In11.Cu")
		(net "L12_85OHM_10INCH_DN")
	)
	(segment
		(start 270.495014 -166.266876)
		(end 270.726916 -165.93566)
		(width 0.1143)
		(layer "In11.Cu")
		(net "L12_85OHM_10INCH_DN")
	)
	(segment
		(start 278.720042 -165.924484)
		(end 278.356314 -163.86175)
		(width 0.1143)
		(layer "In11.Cu")
		(net "L12_85OHM_10INCH_DN")
	)
	(segment
		(start 265.92149 -163.69919)
		(end 266.054078 -163.791646)
		(width 0.1143)
		(layer "In11.Cu")
		(net "L12_85OHM_10INCH_DN")
	)
	(segment
		(start 247.291098 -166.217854)
		(end 247.62206 -166.44874)
		(width 0.1143)
		(layer "In11.Cu")
		(net "L12_85OHM_10INCH_DN")
	)
	(segment
		(start 242.820698 -166.428166)
		(end 243.322094 -166.340028)
		(width 0.1143)
		(layer "In11.Cu")
		(net "L12_85OHM_10INCH_DN")
	)
	(segment
		(start 296.43324 -163.756848)
		(end 296.862754 -166.190676)
		(width 0.1143)
		(layer "In11.Cu")
		(net "L12_85OHM_10INCH_DN")
	)
	(segment
		(start 256.871978 -166.13124)
		(end 257.20294 -166.362634)
		(width 0.1143)
		(layer "In11.Cu")
		(net "L12_85OHM_10INCH_DN")
	)
	(segment
		(start 281.555444 -163.867338)
		(end 281.648154 -163.734496)
		(width 0.1143)
		(layer "In11.Cu")
		(net "L12_85OHM_10INCH_DN")
	)
	(segment
		(start 299.63237 -163.760912)
		(end 300.058836 -166.182548)
		(width 0.1143)
		(layer "In11.Cu")
		(net "L12_85OHM_10INCH_DN")
	)
	(segment
		(start 268.857984 -163.74999)
		(end 269.120112 -163.704016)
		(width 0.1143)
		(layer "In11.Cu")
		(net "L12_85OHM_10INCH_DN")
	)
	(segment
		(start 296.862754 -166.190676)
		(end 297.192954 -166.42207)
		(width 0.1143)
		(layer "In11.Cu")
		(net "L12_85OHM_10INCH_DN")
	)
	(segment
		(start 253.127002 -163.695126)
		(end 253.25959 -163.787582)
		(width 0.1143)
		(layer "In11.Cu")
		(net "L12_85OHM_10INCH_DN")
	)
	(segment
		(start 254.85725 -163.7792)
		(end 255.280414 -166.181024)
		(width 0.1143)
		(layer "In11.Cu")
		(net "L12_85OHM_10INCH_DN")
	)
	(segment
		(start 256.105406 -166.33444)
		(end 256.343404 -165.993572)
		(width 0.1143)
		(layer "In11.Cu")
		(net "L12_85OHM_10INCH_DN")
	)
	(segment
		(start 256.455926 -163.779454)
		(end 256.871978 -166.13124)
		(width 0.1143)
		(layer "In11.Cu")
		(net "L12_85OHM_10INCH_DN")
	)
	(segment
		(start 246.730774 -163.698936)
		(end 246.863616 -163.791646)
		(width 0.1143)
		(layer "In11.Cu")
		(net "L12_85OHM_10INCH_DN")
	)
	(segment
		(start 272.448782 -163.780216)
		(end 272.858484 -166.107872)
		(width 0.1143)
		(layer "In11.Cu")
		(net "L12_85OHM_10INCH_DN")
	)
	(segment
		(start 271.591786 -166.34714)
		(end 272.093182 -166.259256)
		(width 0.1143)
		(layer "In11.Cu")
		(net "L12_85OHM_10INCH_DN")
	)
	(segment
		(start 301.122588 -165.994842)
		(end 300.74362 -163.847526)
		(width 0.1143)
		(layer "In11.Cu")
		(net "L12_85OHM_10INCH_DN")
	)
	(segment
		(start 277.245318 -163.776914)
		(end 277.657306 -166.11219)
		(width 0.1143)
		(layer "In11.Cu")
		(net "L12_85OHM_10INCH_DN")
	)
	(segment
		(start 243.176552 -163.873688)
		(end 243.26977 -163.740592)
		(width 0.1143)
		(layer "In11.Cu")
		(net "L12_85OHM_10INCH_DN")
	)
	(segment
		(start 293.66337 -166.186358)
		(end 293.994332 -166.417244)
		(width 0.1143)
		(layer "In11.Cu")
		(net "L12_85OHM_10INCH_DN")
	)
	(segment
		(start 243.532406 -163.69411)
		(end 243.664232 -163.786312)
		(width 0.1143)
		(layer "In11.Cu")
		(net "L12_85OHM_10INCH_DN")
	)
	(segment
		(start 285.987998 -166.371016)
		(end 286.48914 -166.28237)
		(width 0.1143)
		(layer "In11.Cu")
		(net "L12_85OHM_10INCH_DN")
	)
	(segment
		(start 299.14469 -163.846764)
		(end 299.2374 -163.714176)
		(width 0.1143)
		(layer "In11.Cu")
		(net "L12_85OHM_10INCH_DN")
	)
	(segment
		(start 257.20294 -166.362634)
		(end 257.704082 -166.274242)
		(width 0.1143)
		(layer "In11.Cu")
		(net "L12_85OHM_10INCH_DN")
	)
	(segment
		(start 272.315686 -163.687506)
		(end 272.448782 -163.780216)
		(width 0.1143)
		(layer "In11.Cu")
		(net "L12_85OHM_10INCH_DN")
	)
	(segment
		(start 293.994332 -166.417244)
		(end 294.495474 -166.329614)
		(width 0.1143)
		(layer "In11.Cu")
		(net "L12_85OHM_10INCH_DN")
	)
	(segment
		(start 297.69435 -166.333932)
		(end 297.92549 -166.00297)
		(width 0.1143)
		(layer "In11.Cu")
		(net "L12_85OHM_10INCH_DN")
	)
	(segment
		(start 291.507418 -163.68776)
		(end 291.640514 -163.78047)
		(width 0.1143)
		(layer "In11.Cu")
		(net "L12_85OHM_10INCH_DN")
	)
	(segment
		(start 294.495474 -166.329614)
		(end 294.726614 -165.998652)
		(width 0.1143)
		(layer "In11.Cu")
		(net "L12_85OHM_10INCH_DN")
	)
	(segment
		(start 250.06046 -163.78301)
		(end 250.484132 -166.188136)
		(width 0.1143)
		(layer "In11.Cu")
		(net "L12_85OHM_10INCH_DN")
	)
	(segment
		(start 296.326052 -166.003224)
		(end 295.945052 -163.842192)
		(width 0.1143)
		(layer "In11.Cu")
		(net "L12_85OHM_10INCH_DN")
	)
	(segment
		(start 259.525516 -163.703)
		(end 259.658612 -163.79571)
		(width 0.1143)
		(layer "In11.Cu")
		(net "L12_85OHM_10INCH_DN")
	)
	(segment
		(start 245.264686 -163.791392)
		(end 245.690898 -166.213028)
		(width 0.1143)
		(layer "In11.Cu")
		(net "L12_85OHM_10INCH_DN")
	)
	(segment
		(start 275.5138 -163.68776)
		(end 275.646642 -163.780978)
		(width 0.1143)
		(layer "In11.Cu")
		(net "L12_85OHM_10INCH_DN")
	)
	(segment
		(start 291.29863 -166.337742)
		(end 291.530024 -166.006526)
		(width 0.1143)
		(layer "In11.Cu")
		(net "L12_85OHM_10INCH_DN")
	)
	(segment
		(start 258.801616 -166.362634)
		(end 259.303012 -166.27475)
		(width 0.1143)
		(layer "In11.Cu")
		(net "L12_85OHM_10INCH_DN")
	)
	(segment
		(start 281.184604 -166.335202)
		(end 281.686 -166.247318)
		(width 0.1143)
		(layer "In11.Cu")
		(net "L12_85OHM_10INCH_DN")
	)
	(segment
		(start 276.756876 -163.862258)
		(end 276.849586 -163.729924)
		(width 0.1143)
		(layer "In11.Cu")
		(net "L12_85OHM_10INCH_DN")
	)
	(segment
		(start 246.375682 -163.877498)
		(end 246.468138 -163.745164)
		(width 0.1143)
		(layer "In11.Cu")
		(net "L12_85OHM_10INCH_DN")
	)
	(segment
		(start 248.066052 -163.736782)
		(end 248.328688 -163.690554)
		(width 0.1143)
		(layer "In11.Cu")
		(net "L12_85OHM_10INCH_DN")
	)
	(segment
		(start 301.098458 -163.668456)
		(end 301.2313 -163.761674)
		(width 0.1143)
		(layer "In11.Cu")
		(net "L12_85OHM_10INCH_DN")
	)
	(segment
		(start 285.119064 -165.93566)
		(end 284.760162 -163.903152)
		(width 0.1143)
		(layer "In11.Cu")
		(net "L12_85OHM_10INCH_DN")
	)
	(segment
		(start 280.312368 -163.692586)
		(end 280.444956 -163.785296)
		(width 0.1143)
		(layer "In11.Cu")
		(net "L12_85OHM_10INCH_DN")
	)
	(segment
		(start 259.263388 -163.74872)
		(end 259.525516 -163.703)
		(width 0.1143)
		(layer "In11.Cu")
		(net "L12_85OHM_10INCH_DN")
	)
	(segment
		(start 259.170678 -163.881816)
		(end 259.263388 -163.74872)
		(width 0.1143)
		(layer "In11.Cu")
		(net "L12_85OHM_10INCH_DN")
	)
	(segment
		(start 280.444956 -163.785296)
		(end 280.853388 -166.104062)
		(width 0.1143)
		(layer "In11.Cu")
		(net "L12_85OHM_10INCH_DN")
	)
	(segment
		(start 289.900868 -163.693094)
		(end 290.043108 -163.792662)
		(width 0.1143)
		(layer "In11.Cu")
		(net "L12_85OHM_10INCH_DN")
	)
	(segment
		(start 283.157676 -163.88334)
		(end 283.250386 -163.750498)
		(width 0.1143)
		(layer "In11.Cu")
		(net "L12_85OHM_10INCH_DN")
	)
	(segment
		(start 257.672078 -163.747196)
		(end 257.918204 -163.704016)
		(width 0.1143)
		(layer "In11.Cu")
		(net "L12_85OHM_10INCH_DN")
	)
	(segment
		(start 273.559778 -163.866322)
		(end 273.652488 -163.733734)
		(width 0.1143)
		(layer "In11.Cu")
		(net "L12_85OHM_10INCH_DN")
	)
	(segment
		(start 298.032424 -163.756086)
		(end 298.459652 -166.182294)
		(width 0.1143)
		(layer "In11.Cu")
		(net "L12_85OHM_10INCH_DN")
	)
	(segment
		(start 277.657306 -166.11219)
		(end 277.987506 -166.343584)
		(width 0.1143)
		(layer "In11.Cu")
		(net "L12_85OHM_10INCH_DN")
	)
	(segment
		(start 263.598406 -166.359078)
		(end 264.099548 -166.270686)
		(width 0.1143)
		(layer "In11.Cu")
		(net "L12_85OHM_10INCH_DN")
	)
	(segment
		(start 258.470654 -166.131748)
		(end 258.801616 -166.362634)
		(width 0.1143)
		(layer "In11.Cu")
		(net "L12_85OHM_10INCH_DN")
	)
	(segment
		(start 282.043378 -163.78174)
		(end 282.453842 -166.108888)
		(width 0.1143)
		(layer "In11.Cu")
		(net "L12_85OHM_10INCH_DN")
	)
	(segment
		(start 270.726916 -165.93566)
		(end 270.362934 -163.874196)
		(width 0.1143)
		(layer "In11.Cu")
		(net "L12_85OHM_10INCH_DN")
	)
	(segment
		(start 264.099548 -166.270686)
		(end 264.330434 -165.940232)
		(width 0.1143)
		(layer "In11.Cu")
		(net "L12_85OHM_10INCH_DN")
	)
	(segment
		(start 284.05582 -166.124382)
		(end 284.38602 -166.355522)
		(width 0.1143)
		(layer "In11.Cu")
		(net "L12_85OHM_10INCH_DN")
	)
	(segment
		(start 244.92458 -166.355776)
		(end 245.155466 -166.024306)
		(width 0.1143)
		(layer "In11.Cu")
		(net "L12_85OHM_10INCH_DN")
	)
	(segment
		(start 252.414786 -166.420546)
		(end 252.91542 -166.332408)
		(width 0.1143)
		(layer "In11.Cu")
		(net "L12_85OHM_10INCH_DN")
	)
	(segment
		(start 272.324576 -165.92804)
		(end 271.960848 -163.866322)
		(width 0.1143)
		(layer "In11.Cu")
		(net "L12_85OHM_10INCH_DN")
	)
	(segment
		(start 302.490632 -166.329868)
		(end 302.722534 -165.998652)
		(width 0.1143)
		(layer "In11.Cu")
		(net "L12_85OHM_10INCH_DN")
	)
	(segment
		(start 275.251418 -163.733734)
		(end 275.5138 -163.68776)
		(width 0.1143)
		(layer "In11.Cu")
		(net "L12_85OHM_10INCH_DN")
	)
	(segment
		(start 265.566144 -163.877244)
		(end 265.659108 -163.745164)
		(width 0.1143)
		(layer "In11.Cu")
		(net "L12_85OHM_10INCH_DN")
	)
	(segment
		(start 261.667752 -166.123366)
		(end 261.998714 -166.354252)
		(width 0.1143)
		(layer "In11.Cu")
		(net "L12_85OHM_10INCH_DN")
	)
	(segment
		(start 302.345598 -163.863274)
		(end 302.438308 -163.730686)
		(width 0.1143)
		(layer "In11.Cu")
		(net "L12_85OHM_10INCH_DN")
	)
	(segment
		(start 260.862318 -163.749228)
		(end 261.124446 -163.703)
		(width 0.1143)
		(layer "In11.Cu")
		(net "L12_85OHM_10INCH_DN")
	)
	(segment
		(start 256.060702 -163.732972)
		(end 256.323338 -163.686744)
		(width 0.1143)
		(layer "In11.Cu")
		(net "L12_85OHM_10INCH_DN")
	)
	(segment
		(start 262.856472 -163.796472)
		(end 263.267444 -166.127938)
		(width 0.1143)
		(layer "In11.Cu")
		(net "L12_85OHM_10INCH_DN")
	)
	(segment
		(start 286.35706 -163.88969)
		(end 286.44977 -163.757102)
		(width 0.1143)
		(layer "In11.Cu")
		(net "L12_85OHM_10INCH_DN")
	)
	(segment
		(start 288.86658 -166.192962)
		(end 289.198304 -166.424864)
		(width 0.1143)
		(layer "In11.Cu")
		(net "L12_85OHM_10INCH_DN")
	)
	(segment
		(start 276.849586 -163.729924)
		(end 277.112222 -163.683442)
		(width 0.1143)
		(layer "In11.Cu")
		(net "L12_85OHM_10INCH_DN")
	)
	(segment
		(start 284.887162 -166.266876)
		(end 285.119064 -165.93566)
		(width 0.1143)
		(layer "In11.Cu")
		(net "L12_85OHM_10INCH_DN")
	)
	(segment
		(start 257.918204 -163.704016)
		(end 258.060444 -163.803584)
		(width 0.1143)
		(layer "In11.Cu")
		(net "L12_85OHM_10INCH_DN")
	)
	(segment
		(start 248.354596 -166.03091)
		(end 247.973596 -163.869116)
		(width 0.1143)
		(layer "In11.Cu")
		(net "L12_85OHM_10INCH_DN")
	)
	(segment
		(start 276.057614 -166.112444)
		(end 276.388576 -166.343584)
		(width 0.1143)
		(layer "In11.Cu")
		(net "L12_85OHM_10INCH_DN")
	)
	(segment
		(start 272.093182 -166.259256)
		(end 272.324576 -165.92804)
		(width 0.1143)
		(layer "In11.Cu")
		(net "L12_85OHM_10INCH_DN")
	)
	(segment
		(start 267.166344 -163.882324)
		(end 267.259054 -163.749736)
		(width 0.1143)
		(layer "In11.Cu")
		(net "L12_85OHM_10INCH_DN")
	)
	(segment
		(start 281.686 -166.247318)
		(end 281.91714 -165.916356)
		(width 0.1143)
		(layer "In11.Cu")
		(net "L12_85OHM_10INCH_DN")
	)
	(segment
		(start 294.351456 -163.870894)
		(end 294.443912 -163.738306)
		(width 0.1143)
		(layer "In11.Cu")
		(net "L12_85OHM_10INCH_DN")
	)
	(segment
		(start 296.037762 -163.709858)
		(end 296.300398 -163.663376)
		(width 0.1143)
		(layer "In11.Cu")
		(net "L12_85OHM_10INCH_DN")
	)
	(segment
		(start 268.765274 -163.882832)
		(end 268.857984 -163.74999)
		(width 0.1143)
		(layer "In11.Cu")
		(net "L12_85OHM_10INCH_DN")
	)
	(segment
		(start 299.292264 -166.32555)
		(end 299.523404 -165.994588)
		(width 0.1143)
		(layer "In11.Cu")
		(net "L12_85OHM_10INCH_DN")
	)
	(segment
		(start 281.910282 -163.688522)
		(end 282.043378 -163.78174)
		(width 0.1143)
		(layer "In11.Cu")
		(net "L12_85OHM_10INCH_DN")
	)
	(segment
		(start 279.254204 -166.103808)
		(end 279.58542 -166.334948)
		(width 0.1143)
		(layer "In11.Cu")
		(net "L12_85OHM_10INCH_DN")
	)
	(segment
		(start 283.285184 -166.251382)
		(end 283.517086 -165.920166)
		(width 0.1143)
		(layer "In11.Cu")
		(net "L12_85OHM_10INCH_DN")
	)
	(segment
		(start 265.659108 -163.745164)
		(end 265.92149 -163.69919)
		(width 0.1143)
		(layer "In11.Cu")
		(net "L12_85OHM_10INCH_DN")
	)
	(segment
		(start 262.730996 -165.93566)
		(end 262.368792 -163.881816)
		(width 0.1143)
		(layer "In11.Cu")
		(net "L12_85OHM_10INCH_DN")
	)
	(segment
		(start 244.091968 -166.212012)
		(end 244.423184 -166.444168)
		(width 0.1143)
		(layer "In11.Cu")
		(net "L12_85OHM_10INCH_DN")
	)
	(segment
		(start 293.127684 -165.998144)
		(end 292.752272 -163.870894)
		(width 0.1143)
		(layer "In11.Cu")
		(net "L12_85OHM_10INCH_DN")
	)
	(segment
		(start 300.836076 -163.714684)
		(end 301.098458 -163.668456)
		(width 0.1143)
		(layer "In11.Cu")
		(net "L12_85OHM_10INCH_DN")
	)
	(segment
		(start 264.330434 -165.940232)
		(end 263.96315 -163.857432)
		(width 0.1143)
		(layer "In11.Cu")
		(net "L12_85OHM_10INCH_DN")
	)
	(segment
		(start 254.515112 -166.337234)
		(end 254.746506 -166.005256)
		(width 0.1143)
		(layer "In11.Cu")
		(net "L12_85OHM_10INCH_DN")
	)
	(segment
		(start 268.89583 -166.262812)
		(end 269.12697 -165.93185)
		(width 0.1143)
		(layer "In11.Cu")
		(net "L12_85OHM_10INCH_DN")
	)
	(segment
		(start 257.935222 -165.943026)
		(end 257.573018 -163.889436)
		(width 0.1143)
		(layer "In11.Cu")
		(net "L12_85OHM_10INCH_DN")
	)
	(segment
		(start 279.957276 -163.871148)
		(end 280.049986 -163.73856)
		(width 0.1143)
		(layer "In11.Cu")
		(net "L12_85OHM_10INCH_DN")
	)
	(segment
		(start 281.648154 -163.734496)
		(end 281.910282 -163.688522)
		(width 0.1143)
		(layer "In11.Cu")
		(net "L12_85OHM_10INCH_DN")
	)
	(segment
		(start 301.2313 -163.761674)
		(end 301.65929 -166.187374)
		(width 0.1143)
		(layer "In11.Cu")
		(net "L12_85OHM_10INCH_DN")
	)
	(segment
		(start 259.534406 -165.943534)
		(end 259.170678 -163.881816)
		(width 0.1143)
		(layer "In11.Cu")
		(net "L12_85OHM_10INCH_DN")
	)
	(segment
		(start 247.62206 -166.44874)
		(end 248.122186 -166.36111)
		(width 0.1143)
		(layer "In11.Cu")
		(net "L12_85OHM_10INCH_DN")
	)
	(segment
		(start 251.264928 -163.7411)
		(end 251.527564 -163.695126)
		(width 0.1143)
		(layer "In11.Cu")
		(net "L12_85OHM_10INCH_DN")
	)
	(segment
		(start 267.259054 -163.749736)
		(end 267.521436 -163.703762)
		(width 0.1143)
		(layer "In11.Cu")
		(net "L12_85OHM_10INCH_DN")
	)
	(segment
		(start 287.959038 -163.905184)
		(end 288.051748 -163.772596)
		(width 0.1143)
		(layer "In11.Cu")
		(net "L12_85OHM_10INCH_DN")
	)
	(segment
		(start 275.290026 -166.251128)
		(end 275.521166 -165.920166)
		(width 0.1143)
		(layer "In11.Cu")
		(net "L12_85OHM_10INCH_DN")
	)
	(segment
		(start 273.652488 -163.733734)
		(end 273.914616 -163.687506)
		(width 0.1143)
		(layer "In11.Cu")
		(net "L12_85OHM_10INCH_DN")
	)
	(segment
		(start 289.198304 -166.424864)
		(end 289.699446 -166.336472)
		(width 0.1143)
		(layer "In11.Cu")
		(net "L12_85OHM_10INCH_DN")
	)
	(segment
		(start 297.54449 -163.841684)
		(end 297.637454 -163.709604)
		(width 0.1143)
		(layer "In11.Cu")
		(net "L12_85OHM_10INCH_DN")
	)
	(segment
		(start 264.318496 -163.678616)
		(end 264.451338 -163.772088)
		(width 0.1143)
		(layer "In11.Cu")
		(net "L12_85OHM_10INCH_DN")
	)
	(segment
		(start 265.698732 -166.27094)
		(end 265.929872 -165.939978)
		(width 0.1143)
		(layer "In11.Cu")
		(net "L12_85OHM_10INCH_DN")
	)
	(segment
		(start 245.131844 -163.698682)
		(end 245.264686 -163.791392)
		(width 0.1143)
		(layer "In11.Cu")
		(net "L12_85OHM_10INCH_DN")
	)
	(segment
		(start 245.690898 -166.213028)
		(end 246.02186 -166.444168)
		(width 0.1143)
		(layer "In11.Cu")
		(net "L12_85OHM_10INCH_DN")
	)
	(segment
		(start 294.706294 -163.692332)
		(end 294.839136 -163.78555)
		(width 0.1143)
		(layer "In11.Cu")
		(net "L12_85OHM_10INCH_DN")
	)
	(segment
		(start 251.527564 -163.695126)
		(end 251.660152 -163.787582)
		(width 0.1143)
		(layer "In11.Cu")
		(net "L12_85OHM_10INCH_DN")
	)
	(segment
		(start 301.65929 -166.187374)
		(end 301.98949 -166.418514)
		(width 0.1143)
		(layer "In11.Cu")
		(net "L12_85OHM_10INCH_DN")
	)
	(segment
		(start 264.867136 -166.127684)
		(end 265.197336 -166.359078)
		(width 0.1143)
		(layer "In11.Cu")
		(net "L12_85OHM_10INCH_DN")
	)
	(segment
		(start 243.553488 -166.008812)
		(end 243.176552 -163.873688)
		(width 0.1143)
		(layer "In11.Cu")
		(net "L12_85OHM_10INCH_DN")
	)
	(segment
		(start 246.02186 -166.444168)
		(end 246.522748 -166.356538)
		(width 0.1143)
		(layer "In11.Cu")
		(net "L12_85OHM_10INCH_DN")
	)
	(segment
		(start 258.060444 -163.803584)
		(end 258.470654 -166.131748)
		(width 0.1143)
		(layer "In11.Cu")
		(net "L12_85OHM_10INCH_DN")
	)
	(segment
		(start 278.71166 -163.683696)
		(end 278.844248 -163.776152)
		(width 0.1143)
		(layer "In11.Cu")
		(net "L12_85OHM_10INCH_DN")
	)
	(segment
		(start 286.44977 -163.757102)
		(end 286.712406 -163.710874)
		(width 0.1143)
		(layer "In11.Cu")
		(net "L12_85OHM_10INCH_DN")
	)
	(segment
		(start 267.527786 -165.931596)
		(end 267.166344 -163.882324)
		(width 0.1143)
		(layer "In11.Cu")
		(net "L12_85OHM_10INCH_DN")
	)
	(segment
		(start 241.75593 -165.667436)
		(end 241.75593 -165.165786)
		(width 0.1143)
		(layer "In11.Cu")
		(net "L12_85OHM_10INCH_DN")
	)
	(segment
		(start 275.646642 -163.780978)
		(end 276.057614 -166.112444)
		(width 0.1143)
		(layer "In11.Cu")
		(net "L12_85OHM_10INCH_DN")
	)
	(segment
		(start 269.253208 -163.797234)
		(end 269.663672 -166.124382)
		(width 0.1143)
		(layer "In11.Cu")
		(net "L12_85OHM_10INCH_DN")
	)
	(segment
		(start 250.815094 -166.420292)
		(end 251.31649 -166.332408)
		(width 0.1143)
		(layer "In11.Cu")
		(net "L12_85OHM_10INCH_DN")
	)
	(segment
		(start 254.014478 -166.42461)
		(end 254.515112 -166.337234)
		(width 0.1143)
		(layer "In11.Cu")
		(net "L12_85OHM_10INCH_DN")
	)
	(segment
		(start 299.2374 -163.714176)
		(end 299.499782 -163.668202)
		(width 0.1143)
		(layer "In11.Cu")
		(net "L12_85OHM_10INCH_DN")
	)
	(segment
		(start 270.71828 -163.69538)
		(end 270.850614 -163.78809)
		(width 0.1143)
		(layer "In11.Cu")
		(net "L12_85OHM_10INCH_DN")
	)
	(segment
		(start 302.722534 -165.998652)
		(end 302.345598 -163.863274)
		(width 0.1143)
		(layer "In11.Cu")
		(net "L12_85OHM_10INCH_DN")
	)
	(segment
		(start 248.122186 -166.36111)
		(end 248.354596 -166.03091)
		(width 0.1143)
		(layer "In11.Cu")
		(net "L12_85OHM_10INCH_DN")
	)
	(segment
		(start 255.620774 -166.41953)
		(end 256.105406 -166.33444)
		(width 0.1143)
		(layer "In11.Cu")
		(net "L12_85OHM_10INCH_DN")
	)
	(segment
		(start 293.10711 -163.692078)
		(end 293.239444 -163.784534)
		(width 0.1143)
		(layer "In11.Cu")
		(net "L12_85OHM_10INCH_DN")
	)
	(segment
		(start 246.863616 -163.791646)
		(end 247.291098 -166.217854)
		(width 0.1143)
		(layer "In11.Cu")
		(net "L12_85OHM_10INCH_DN")
	)
	(segment
		(start 296.300398 -163.663376)
		(end 296.43324 -163.756848)
		(width 0.1143)
		(layer "In11.Cu")
		(net "L12_85OHM_10INCH_DN")
	)
	(segment
		(start 302.438308 -163.730686)
		(end 302.700944 -163.684458)
		(width 0.1143)
		(layer "In11.Cu")
		(net "L12_85OHM_10INCH_DN")
	)
	(segment
		(start 290.466272 -166.19474)
		(end 290.797234 -166.425626)
		(width 0.1143)
		(layer "In11.Cu")
		(net "L12_85OHM_10INCH_DN")
	)
	(segment
		(start 284.38602 -166.355522)
		(end 284.887162 -166.266876)
		(width 0.1143)
		(layer "In11.Cu")
		(net "L12_85OHM_10INCH_DN")
	)
	(segment
		(start 265.197336 -166.359078)
		(end 265.698732 -166.27094)
		(width 0.1143)
		(layer "In11.Cu")
		(net "L12_85OHM_10INCH_DN")
	)
	(segment
		(start 268.394434 -166.350696)
		(end 268.89583 -166.262812)
		(width 0.1143)
		(layer "In11.Cu")
		(net "L12_85OHM_10INCH_DN")
	)
	(segment
		(start 248.328688 -163.690554)
		(end 248.460768 -163.78301)
		(width 0.1143)
		(layer "In11.Cu")
		(net "L12_85OHM_10INCH_DN")
	)
	(segment
		(start 140.135864 11.879834)
		(end 139.000484 10.744454)
		(width 0.14224)
		(layer "In11.Cu")
		(net "L12_73OHM_6INCH_DP")
	)
	(segment
		(start 145.580354 11.879834)
		(end 140.135864 11.879834)
		(width 0.14224)
		(layer "In11.Cu")
		(net "L12_73OHM_6INCH_DP")
	)
	(segment
		(start 146.42592 12.7254)
		(end 145.580354 11.879834)
		(width 0.14224)
		(layer "In11.Cu")
		(net "L12_73OHM_6INCH_DP")
	)
	(segment
		(start 148.22424 12.04976)
		(end 197.397624 12.04976)
		(width 0.14224)
		(layer "In11.Cu")
		(net "L12_73OHM_6INCH_DP")
	)
	(segment
		(start 197.397624 12.7254)
		(end 146.42592 12.7254)
		(width 0.14224)
		(layer "In11.Cu")
		(net "L12_73OHM_6INCH_DP")
	)
	(segment
		(start 197.510654 10.83564)
		(end 148.22424 10.83564)
		(width 0.14224)
		(layer "In11.Cu")
		(net "L12_73OHM_6INCH_DP")
	)
	(arc
		(start 197.397624 12.04976)
		(mid 197.735444 12.38758)
		(end 197.397624 12.7254)
		(width 0.14224)
		(layer "In11.Cu")
		(net "L12_73OHM_6INCH_DP")
	)
	(arc
		(start 148.22424 10.83564)
		(mid 147.61718 11.4427)
		(end 148.22424 12.04976)
		(width 0.14224)
		(layer "In11.Cu")
		(net "L12_73OHM_6INCH_DP")
	)
	(segment
		(start 197.510654 11.10488)
		(end 148.22424 11.10488)
		(width 0.14224)
		(layer "In11.Cu")
		(net "L12_73OHM_6INCH_DN")
	)
	(segment
		(start 140.135864 12.149074)
		(end 139.000484 13.284454)
		(width 0.14224)
		(layer "In11.Cu")
		(net "L12_73OHM_6INCH_DN")
	)
	(segment
		(start 197.397624 12.99464)
		(end 146.31416 12.99464)
		(width 0.14224)
		(layer "In11.Cu")
		(net "L12_73OHM_6INCH_DN")
	)
	(segment
		(start 148.22424 11.78052)
		(end 197.397624 11.78052)
		(width 0.14224)
		(layer "In11.Cu")
		(net "L12_73OHM_6INCH_DN")
	)
	(segment
		(start 145.468594 12.149074)
		(end 140.135864 12.149074)
		(width 0.14224)
		(layer "In11.Cu")
		(net "L12_73OHM_6INCH_DN")
	)
	(segment
		(start 146.31416 12.99464)
		(end 145.468594 12.149074)
		(width 0.14224)
		(layer "In11.Cu")
		(net "L12_73OHM_6INCH_DN")
	)
	(arc
		(start 148.22424 11.10488)
		(mid 147.88642 11.4427)
		(end 148.22424 11.78052)
		(width 0.14224)
		(layer "In11.Cu")
		(net "L12_73OHM_6INCH_DN")
	)
	(arc
		(start 197.397624 11.78052)
		(mid 198.004684 12.38758)
		(end 197.397624 12.99464)
		(width 0.14224)
		(layer "In11.Cu")
		(net "L12_73OHM_6INCH_DN")
	)
	(segment
		(start 31.6103 14.2748)
		(end 30.607 13.2715)
		(width 0.089408)
		(layer "In11.Cu")
		(net "L12_50OHM_6INCH")
	)
	(segment
		(start 36.83762 14.2748)
		(end 31.6103 14.2748)
		(width 0.089408)
		(layer "In11.Cu")
		(net "L12_50OHM_6INCH")
	)
	(segment
		(start 113.15954 13.677392)
		(end 37.435028 13.677392)
		(width 0.089408)
		(layer "In11.Cu")
		(net "L12_50OHM_6INCH")
	)
	(segment
		(start 37.820854 12.825984)
		(end 113.15954 12.825984)
		(width 0.089408)
		(layer "In11.Cu")
		(net "L12_50OHM_6INCH")
	)
	(segment
		(start 37.435028 13.677392)
		(end 36.83762 14.2748)
		(width 0.089408)
		(layer "In11.Cu")
		(net "L12_50OHM_6INCH")
	)
	(arc
		(start 113.15954 12.825984)
		(mid 113.585244 13.251688)
		(end 113.15954 13.677392)
		(width 0.089408)
		(layer "In11.Cu")
		(net "L12_50OHM_6INCH")
	)
	(segment
		(start 37.159946 10.75817)
		(end 112.559338 10.75817)
		(width 0.14224)
		(layer "In11.Cu")
		(net "L12_40OHM_6INCH")
	)
	(segment
		(start 112.559338 11.66241)
		(end 36.97859 11.66241)
		(width 0.14224)
		(layer "In11.Cu")
		(net "L12_40OHM_6INCH")
	)
	(segment
		(start 36.97859 11.66241)
		(end 36.6268 12.0142)
		(width 0.14224)
		(layer "In11.Cu")
		(net "L12_40OHM_6INCH")
	)
	(segment
		(start 31.8897 12.0142)
		(end 30.607 10.7315)
		(width 0.14224)
		(layer "In11.Cu")
		(net "L12_40OHM_6INCH")
	)
	(segment
		(start 36.6268 12.0142)
		(end 31.8897 12.0142)
		(width 0.14224)
		(layer "In11.Cu")
		(net "L12_40OHM_6INCH")
	)
	(arc
		(start 112.559338 10.75817)
		(mid 113.011458 11.21029)
		(end 112.559338 11.66241)
		(width 0.14224)
		(layer "In11.Cu")
		(net "L12_40OHM_6INCH")
	)
	(segment
		(start 422.720262 10.583164)
		(end 373.5324 10.583164)
		(width 0.089154)
		(layer "In11.Cu")
		(net "L12_100OHM_6INCH_DP")
	)
	(segment
		(start 370.848128 11.793728)
		(end 364.853982 11.793728)
		(width 0.089154)
		(layer "In11.Cu")
		(net "L12_100OHM_6INCH_DP")
	)
	(segment
		(start 371.72138 12.66698)
		(end 370.848128 11.793728)
		(width 0.089154)
		(layer "In11.Cu")
		(net "L12_100OHM_6INCH_DP")
	)
	(segment
		(start 373.5324 12.044426)
		(end 422.59631 12.044426)
		(width 0.089154)
		(layer "In11.Cu")
		(net "L12_100OHM_6INCH_DP")
	)
	(segment
		(start 364.853982 11.793728)
		(end 363.793532 10.733278)
		(width 0.089154)
		(layer "In11.Cu")
		(net "L12_100OHM_6INCH_DP")
	)
	(segment
		(start 422.59631 12.66698)
		(end 371.72138 12.66698)
		(width 0.089154)
		(layer "In11.Cu")
		(net "L12_100OHM_6INCH_DP")
	)
	(arc
		(start 373.5324 10.583164)
		(mid 372.801642 11.313922)
		(end 373.5324 12.044426)
		(width 0.089154)
		(layer "In11.Cu")
		(net "L12_100OHM_6INCH_DP")
	)
	(arc
		(start 422.59631 12.044426)
		(mid 422.907714 12.35583)
		(end 422.59631 12.66698)
		(width 0.089154)
		(layer "In11.Cu")
		(net "L12_100OHM_6INCH_DP")
	)
	(segment
		(start 370.674392 12.213082)
		(end 364.853728 12.213082)
		(width 0.089154)
		(layer "In11.Cu")
		(net "L12_100OHM_6INCH_DN")
	)
	(segment
		(start 373.5324 11.625072)
		(end 422.59631 11.625072)
		(width 0.089154)
		(layer "In11.Cu")
		(net "L12_100OHM_6INCH_DN")
	)
	(segment
		(start 364.853728 12.213082)
		(end 363.793532 13.273278)
		(width 0.089154)
		(layer "In11.Cu")
		(net "L12_100OHM_6INCH_DN")
	)
	(segment
		(start 422.59631 13.086334)
		(end 371.547644 13.086334)
		(width 0.089154)
		(layer "In11.Cu")
		(net "L12_100OHM_6INCH_DN")
	)
	(segment
		(start 422.720262 11.002518)
		(end 373.5324 11.002518)
		(width 0.089154)
		(layer "In11.Cu")
		(net "L12_100OHM_6INCH_DN")
	)
	(segment
		(start 371.547644 13.086334)
		(end 370.674392 12.213082)
		(width 0.089154)
		(layer "In11.Cu")
		(net "L12_100OHM_6INCH_DN")
	)
	(arc
		(start 373.5324 11.002518)
		(mid 373.220996 11.313922)
		(end 373.5324 11.625072)
		(width 0.089154)
		(layer "In11.Cu")
		(net "L12_100OHM_6INCH_DN")
	)
	(arc
		(start 422.59631 11.625072)
		(mid 423.327068 12.35583)
		(end 422.59631 13.086334)
		(width 0.089154)
		(layer "In11.Cu")
		(net "L12_100OHM_6INCH_DN")
	)
	(segment
		(start 219.305886 11.806428)
		(end 218.181936 10.682478)
		(width 0.1143)
		(layer "In9.Cu")
		(net "L10_85OHM_6INCH_DP")
	)
	(segment
		(start 232.283 12.0396)
		(end 281.69743 12.0396)
		(width 0.1143)
		(layer "In9.Cu")
		(net "L10_85OHM_6INCH_DP")
	)
	(segment
		(start 281.69743 12.6873)
		(end 231.1019 12.6873)
		(width 0.1143)
		(layer "In9.Cu")
		(net "L10_85OHM_6INCH_DP")
	)
	(segment
		(start 231.1019 12.6873)
		(end 230.221028 11.806428)
		(width 0.1143)
		(layer "In9.Cu")
		(net "L10_85OHM_6INCH_DP")
	)
	(segment
		(start 281.720544 10.8077)
		(end 232.283 10.8077)
		(width 0.1143)
		(layer "In9.Cu")
		(net "L10_85OHM_6INCH_DP")
	)
	(segment
		(start 230.221028 11.806428)
		(end 219.305886 11.806428)
		(width 0.1143)
		(layer "In9.Cu")
		(net "L10_85OHM_6INCH_DP")
	)
	(arc
		(start 232.283 10.8077)
		(mid 231.66705 11.42365)
		(end 232.283 12.0396)
		(width 0.1143)
		(layer "In9.Cu")
		(net "L10_85OHM_6INCH_DP")
	)
	(arc
		(start 281.69743 12.0396)
		(mid 282.02128 12.36345)
		(end 281.69743 12.6873)
		(width 0.1143)
		(layer "In9.Cu")
		(net "L10_85OHM_6INCH_DP")
	)
	(segment
		(start 230.980742 12.9794)
		(end 230.09987 12.098528)
		(width 0.1143)
		(layer "In9.Cu")
		(net "L10_85OHM_6INCH_DN")
	)
	(segment
		(start 230.09987 12.098528)
		(end 219.305886 12.098528)
		(width 0.1143)
		(layer "In9.Cu")
		(net "L10_85OHM_6INCH_DN")
	)
	(segment
		(start 219.305886 12.098528)
		(end 218.181936 13.222478)
		(width 0.1143)
		(layer "In9.Cu")
		(net "L10_85OHM_6INCH_DN")
	)
	(segment
		(start 281.69743 12.9794)
		(end 230.980742 12.9794)
		(width 0.1143)
		(layer "In9.Cu")
		(net "L10_85OHM_6INCH_DN")
	)
	(segment
		(start 232.283 11.7475)
		(end 281.69743 11.7475)
		(width 0.1143)
		(layer "In9.Cu")
		(net "L10_85OHM_6INCH_DN")
	)
	(segment
		(start 281.720544 11.0998)
		(end 232.283 11.0998)
		(width 0.1143)
		(layer "In9.Cu")
		(net "L10_85OHM_6INCH_DN")
	)
	(arc
		(start 232.283 11.0998)
		(mid 231.95915 11.42365)
		(end 232.283 11.7475)
		(width 0.1143)
		(layer "In9.Cu")
		(net "L10_85OHM_6INCH_DN")
	)
	(arc
		(start 281.69743 11.7475)
		(mid 282.31338 12.36345)
		(end 281.69743 12.9794)
		(width 0.1143)
		(layer "In9.Cu")
		(net "L10_85OHM_6INCH_DN")
	)
	(segment
		(start 147.416774 -164.760402)
		(end 144.641316 -164.760402)
		(width 0.1143)
		(layer "F.Cu")
		(net "L10_85OHM_5INCH_DP")
	)
	(segment
		(start 113.326672 -164.830506)
		(end 113.942622 -164.214556)
		(width 0.1143)
		(layer "F.Cu")
		(net "L10_85OHM_5INCH_DP")
	)
	(segment
		(start 144.641316 -164.760402)
		(end 144.025366 -164.144452)
		(width 0.1143)
		(layer "F.Cu")
		(net "L10_85OHM_5INCH_DP")
	)
	(segment
		(start 110.203996 -164.476176)
		(end 110.558326 -164.830506)
		(width 0.1143)
		(layer "F.Cu")
		(net "L10_85OHM_5INCH_DP")
	)
	(segment
		(start 147.763992 -164.413184)
		(end 147.416774 -164.760402)
		(width 0.1143)
		(layer "F.Cu")
		(net "L10_85OHM_5INCH_DP")
	)
	(segment
		(start 110.558326 -164.830506)
		(end 113.326672 -164.830506)
		(width 0.1143)
		(layer "F.Cu")
		(net "L10_85OHM_5INCH_DP")
	)
	(via
		(at 113.942622 -164.214556)
		(size 0.5588)
		(drill 0.3048)
		(layers "F.Cu" "B.Cu")
		(net "L10_85OHM_5INCH_DP")
	)
	(via
		(at 144.025366 -164.144452)
		(size 0.5588)
		(drill 0.3048)
		(layers "F.Cu" "B.Cu")
		(net "L10_85OHM_5INCH_DP")
	)
	(segment
		(start 143.56461 -164.63772)
		(end 143.473932 -164.516816)
		(width 0.1143)
		(layer "In9.Cu")
		(net "L10_85OHM_5INCH_DP")
	)
	(segment
		(start 124.880624 -163.54552)
		(end 124.64923 -163.876736)
		(width 0.1143)
		(layer "In9.Cu")
		(net "L10_85OHM_5INCH_DP")
	)
	(segment
		(start 141.358112 -163.36772)
		(end 140.856716 -163.456112)
		(width 0.1143)
		(layer "In9.Cu")
		(net "L10_85OHM_5INCH_DP")
	)
	(segment
		(start 121.476516 -166.211504)
		(end 121.343674 -166.118032)
		(width 0.1143)
		(layer "In9.Cu")
		(net "L10_85OHM_5INCH_DP")
	)
	(segment
		(start 143.291306 -163.61537)
		(end 142.960598 -163.383722)
		(width 0.1143)
		(layer "In9.Cu")
		(net "L10_85OHM_5INCH_DP")
	)
	(segment
		(start 114.943636 -166.097712)
		(end 114.858292 -165.612572)
		(width 0.1143)
		(layer "In9.Cu")
		(net "L10_85OHM_5INCH_DP")
	)
	(segment
		(start 116.545614 -166.113206)
		(end 116.117624 -163.687506)
		(width 0.1143)
		(layer "In9.Cu")
		(net "L10_85OHM_5INCH_DP")
	)
	(segment
		(start 137.452608 -166.121334)
		(end 137.320528 -166.028878)
		(width 0.1143)
		(layer "In9.Cu")
		(net "L10_85OHM_5INCH_DP")
	)
	(segment
		(start 121.343674 -166.118032)
		(end 120.91416 -163.684204)
		(width 0.1143)
		(layer "In9.Cu")
		(net "L10_85OHM_5INCH_DP")
	)
	(segment
		(start 121.681748 -163.541202)
		(end 121.450862 -163.871656)
		(width 0.1143)
		(layer "In9.Cu")
		(net "L10_85OHM_5INCH_DP")
	)
	(segment
		(start 123.425458 -166.003986)
		(end 123.333002 -166.136574)
		(width 0.1143)
		(layer "In9.Cu")
		(net "L10_85OHM_5INCH_DP")
	)
	(segment
		(start 133.009894 -165.937946)
		(end 132.917184 -166.070534)
		(width 0.1143)
		(layer "In9.Cu")
		(net "L10_85OHM_5INCH_DP")
	)
	(segment
		(start 128.221232 -165.996366)
		(end 128.121918 -166.138606)
		(width 0.1143)
		(layer "In9.Cu")
		(net "L10_85OHM_5INCH_DP")
	)
	(segment
		(start 122.937778 -166.08933)
		(end 122.513852 -163.68395)
		(width 0.1143)
		(layer "In9.Cu")
		(net "L10_85OHM_5INCH_DP")
	)
	(segment
		(start 136.11606 -166.075106)
		(end 135.853424 -166.121588)
		(width 0.1143)
		(layer "In9.Cu")
		(net "L10_85OHM_5INCH_DP")
	)
	(segment
		(start 126.624334 -166.008304)
		(end 126.531624 -166.1414)
		(width 0.1143)
		(layer "In9.Cu")
		(net "L10_85OHM_5INCH_DP")
	)
	(segment
		(start 140.912342 -166.066978)
		(end 140.649452 -166.113206)
		(width 0.1143)
		(layer "In9.Cu")
		(net "L10_85OHM_5INCH_DP")
	)
	(segment
		(start 144.025366 -164.646102)
		(end 143.898874 -164.772594)
		(width 0.1143)
		(layer "In9.Cu")
		(net "L10_85OHM_5INCH_DP")
	)
	(segment
		(start 137.715244 -166.075106)
		(end 137.452608 -166.121334)
		(width 0.1143)
		(layer "In9.Cu")
		(net "L10_85OHM_5INCH_DP")
	)
	(segment
		(start 132.098542 -163.618164)
		(end 131.766818 -163.387278)
		(width 0.1143)
		(layer "In9.Cu")
		(net "L10_85OHM_5INCH_DP")
	)
	(segment
		(start 115.431316 -166.011606)
		(end 115.338606 -166.144194)
		(width 0.1143)
		(layer "In9.Cu")
		(net "L10_85OHM_5INCH_DP")
	)
	(segment
		(start 143.3957 -164.208968)
		(end 143.291306 -163.61537)
		(width 0.1143)
		(layer "In9.Cu")
		(net "L10_85OHM_5INCH_DP")
	)
	(segment
		(start 121.831862 -166.032688)
		(end 121.739152 -166.165022)
		(width 0.1143)
		(layer "In9.Cu")
		(net "L10_85OHM_5INCH_DP")
	)
	(segment
		(start 120.13946 -166.165276)
		(end 119.877078 -166.21125)
		(width 0.1143)
		(layer "In9.Cu")
		(net "L10_85OHM_5INCH_DP")
	)
	(segment
		(start 120.232424 -166.033196)
		(end 120.13946 -166.165276)
		(width 0.1143)
		(layer "In9.Cu")
		(net "L10_85OHM_5INCH_DP")
	)
	(segment
		(start 136.05891 -163.451286)
		(end 135.827262 -163.78174)
		(width 0.1143)
		(layer "In9.Cu")
		(net "L10_85OHM_5INCH_DP")
	)
	(segment
		(start 137.65911 -163.450778)
		(end 137.4267 -163.780978)
		(width 0.1143)
		(layer "In9.Cu")
		(net "L10_85OHM_5INCH_DP")
	)
	(segment
		(start 131.766818 -163.387278)
		(end 131.266184 -163.474654)
		(width 0.1143)
		(layer "In9.Cu")
		(net "L10_85OHM_5INCH_DP")
	)
	(segment
		(start 137.4267 -163.780978)
		(end 137.8077 -165.942772)
		(width 0.1143)
		(layer "In9.Cu")
		(net "L10_85OHM_5INCH_DP")
	)
	(segment
		(start 132.521706 -166.024306)
		(end 132.098542 -163.618164)
		(width 0.1143)
		(layer "In9.Cu")
		(net "L10_85OHM_5INCH_DP")
	)
	(segment
		(start 134.233666 -163.81095)
		(end 134.608824 -165.938454)
		(width 0.1143)
		(layer "In9.Cu")
		(net "L10_85OHM_5INCH_DP")
	)
	(segment
		(start 134.966202 -163.391596)
		(end 134.464806 -163.47948)
		(width 0.1143)
		(layer "In9.Cu")
		(net "L10_85OHM_5INCH_DP")
	)
	(segment
		(start 127.876046 -166.181786)
		(end 127.733806 -166.082218)
		(width 0.1143)
		(layer "In9.Cu")
		(net "L10_85OHM_5INCH_DP")
	)
	(segment
		(start 136.208262 -165.942518)
		(end 136.11606 -166.075106)
		(width 0.1143)
		(layer "In9.Cu")
		(net "L10_85OHM_5INCH_DP")
	)
	(segment
		(start 119.74449 -166.118794)
		(end 119.317262 -163.692586)
		(width 0.1143)
		(layer "In9.Cu")
		(net "L10_85OHM_5INCH_DP")
	)
	(segment
		(start 137.8077 -165.942772)
		(end 137.715244 -166.075106)
		(width 0.1143)
		(layer "In9.Cu")
		(net "L10_85OHM_5INCH_DP")
	)
	(segment
		(start 122.18289 -163.45281)
		(end 121.681748 -163.541202)
		(width 0.1143)
		(layer "In9.Cu")
		(net "L10_85OHM_5INCH_DP")
	)
	(segment
		(start 142.459202 -163.47186)
		(end 142.227808 -163.803076)
		(width 0.1143)
		(layer "In9.Cu")
		(net "L10_85OHM_5INCH_DP")
	)
	(segment
		(start 114.798348 -165.376352)
		(end 114.54511 -165.038786)
		(width 0.1143)
		(layer "In9.Cu")
		(net "L10_85OHM_5INCH_DP")
	)
	(segment
		(start 113.942622 -164.716206)
		(end 113.942622 -164.214556)
		(width 0.1143)
		(layer "In9.Cu")
		(net "L10_85OHM_5INCH_DP")
	)
	(segment
		(start 132.654294 -166.116762)
		(end 132.521706 -166.024306)
		(width 0.1143)
		(layer "In9.Cu")
		(net "L10_85OHM_5INCH_DP")
	)
	(segment
		(start 121.450862 -163.871656)
		(end 121.831862 -166.032688)
		(width 0.1143)
		(layer "In9.Cu")
		(net "L10_85OHM_5INCH_DP")
	)
	(segment
		(start 135.827262 -163.78174)
		(end 136.208262 -165.942518)
		(width 0.1143)
		(layer "In9.Cu")
		(net "L10_85OHM_5INCH_DP")
	)
	(segment
		(start 118.632224 -166.028116)
		(end 118.539514 -166.160704)
		(width 0.1143)
		(layer "In9.Cu")
		(net "L10_85OHM_5INCH_DP")
	)
	(segment
		(start 131.03479 -163.806632)
		(end 131.412234 -165.946328)
		(width 0.1143)
		(layer "In9.Cu")
		(net "L10_85OHM_5INCH_DP")
	)
	(segment
		(start 134.253732 -166.116762)
		(end 134.121144 -166.024306)
		(width 0.1143)
		(layer "In9.Cu")
		(net "L10_85OHM_5INCH_DP")
	)
	(segment
		(start 123.782582 -163.457636)
		(end 123.28144 -163.545266)
		(width 0.1143)
		(layer "In9.Cu")
		(net "L10_85OHM_5INCH_DP")
	)
	(segment
		(start 120.082564 -163.540948)
		(end 119.851424 -163.87191)
		(width 0.1143)
		(layer "In9.Cu")
		(net "L10_85OHM_5INCH_DP")
	)
	(segment
		(start 141.004798 -165.934644)
		(end 140.912342 -166.066978)
		(width 0.1143)
		(layer "In9.Cu")
		(net "L10_85OHM_5INCH_DP")
	)
	(segment
		(start 131.412234 -165.946328)
		(end 131.319524 -166.078916)
		(width 0.1143)
		(layer "In9.Cu")
		(net "L10_85OHM_5INCH_DP")
	)
	(segment
		(start 132.634482 -163.810696)
		(end 133.009894 -165.937946)
		(width 0.1143)
		(layer "In9.Cu")
		(net "L10_85OHM_5INCH_DP")
	)
	(segment
		(start 139.0269 -163.786566)
		(end 139.405614 -165.93439)
		(width 0.1143)
		(layer "In9.Cu")
		(net "L10_85OHM_5INCH_DP")
	)
	(segment
		(start 142.604744 -165.9382)
		(end 142.511526 -166.071296)
		(width 0.1143)
		(layer "In9.Cu")
		(net "L10_85OHM_5INCH_DP")
	)
	(segment
		(start 131.319524 -166.078916)
		(end 131.056634 -166.125144)
		(width 0.1143)
		(layer "In9.Cu")
		(net "L10_85OHM_5INCH_DP")
	)
	(segment
		(start 126.269496 -166.18712)
		(end 126.1364 -166.09441)
		(width 0.1143)
		(layer "In9.Cu")
		(net "L10_85OHM_5INCH_DP")
	)
	(segment
		(start 124.64923 -163.876736)
		(end 125.024642 -166.003986)
		(width 0.1143)
		(layer "In9.Cu")
		(net "L10_85OHM_5INCH_DP")
	)
	(segment
		(start 119.317262 -163.692586)
		(end 118.986046 -163.461446)
		(width 0.1143)
		(layer "In9.Cu")
		(net "L10_85OHM_5INCH_DP")
	)
	(segment
		(start 118.144544 -166.113968)
		(end 117.718078 -163.692332)
		(width 0.1143)
		(layer "In9.Cu")
		(net "L10_85OHM_5INCH_DP")
	)
	(segment
		(start 137.320528 -166.028878)
		(end 136.891268 -163.595304)
		(width 0.1143)
		(layer "In9.Cu")
		(net "L10_85OHM_5INCH_DP")
	)
	(segment
		(start 118.25351 -163.880292)
		(end 118.632224 -166.028116)
		(width 0.1143)
		(layer "In9.Cu")
		(net "L10_85OHM_5INCH_DP")
	)
	(segment
		(start 124.113544 -163.688522)
		(end 123.782582 -163.457636)
		(width 0.1143)
		(layer "In9.Cu")
		(net "L10_85OHM_5INCH_DP")
	)
	(segment
		(start 139.759436 -163.36772)
		(end 139.258548 -163.45535)
		(width 0.1143)
		(layer "In9.Cu")
		(net "L10_85OHM_5INCH_DP")
	)
	(segment
		(start 136.560306 -163.36264)
		(end 136.05891 -163.451286)
		(width 0.1143)
		(layer "In9.Cu")
		(net "L10_85OHM_5INCH_DP")
	)
	(segment
		(start 139.405614 -165.93439)
		(end 139.313158 -166.066724)
		(width 0.1143)
		(layer "In9.Cu")
		(net "L10_85OHM_5INCH_DP")
	)
	(segment
		(start 129.457958 -166.125144)
		(end 129.32537 -166.032434)
		(width 0.1143)
		(layer "In9.Cu")
		(net "L10_85OHM_5INCH_DP")
	)
	(segment
		(start 130.160522 -163.392358)
		(end 129.67589 -163.477448)
		(width 0.1143)
		(layer "In9.Cu")
		(net "L10_85OHM_5INCH_DP")
	)
	(segment
		(start 141.689328 -163.599876)
		(end 141.358112 -163.36772)
		(width 0.1143)
		(layer "In9.Cu")
		(net "L10_85OHM_5INCH_DP")
	)
	(segment
		(start 116.885466 -163.549076)
		(end 116.654326 -163.880038)
		(width 0.1143)
		(layer "In9.Cu")
		(net "L10_85OHM_5INCH_DP")
	)
	(segment
		(start 126.1364 -166.09441)
		(end 125.712982 -163.688522)
		(width 0.1143)
		(layer "In9.Cu")
		(net "L10_85OHM_5INCH_DP")
	)
	(segment
		(start 118.48465 -163.54933)
		(end 118.25351 -163.880292)
		(width 0.1143)
		(layer "In9.Cu")
		(net "L10_85OHM_5INCH_DP")
	)
	(segment
		(start 114.059462 -164.833046)
		(end 113.942622 -164.716206)
		(width 0.1143)
		(layer "In9.Cu")
		(net "L10_85OHM_5INCH_DP")
	)
	(segment
		(start 130.924046 -166.032688)
		(end 130.500882 -163.630864)
		(width 0.1143)
		(layer "In9.Cu")
		(net "L10_85OHM_5INCH_DP")
	)
	(segment
		(start 116.940838 -166.160196)
		(end 116.678456 -166.206424)
		(width 0.1143)
		(layer "In9.Cu")
		(net "L10_85OHM_5INCH_DP")
	)
	(segment
		(start 142.24889 -166.117778)
		(end 142.117064 -166.025576)
		(width 0.1143)
		(layer "In9.Cu")
		(net "L10_85OHM_5INCH_DP")
	)
	(segment
		(start 143.898874 -164.772594)
		(end 143.737076 -164.780214)
		(width 0.1143)
		(layer "In9.Cu")
		(net "L10_85OHM_5INCH_DP")
	)
	(segment
		(start 117.033294 -166.027354)
		(end 116.940838 -166.160196)
		(width 0.1143)
		(layer "In9.Cu")
		(net "L10_85OHM_5INCH_DP")
	)
	(segment
		(start 120.58396 -163.45281)
		(end 120.082564 -163.540948)
		(width 0.1143)
		(layer "In9.Cu")
		(net "L10_85OHM_5INCH_DP")
	)
	(segment
		(start 138.91768 -166.020242)
		(end 138.490198 -163.594034)
		(width 0.1143)
		(layer "In9.Cu")
		(net "L10_85OHM_5INCH_DP")
	)
	(segment
		(start 129.32537 -166.032434)
		(end 128.909318 -163.680394)
		(width 0.1143)
		(layer "In9.Cu")
		(net "L10_85OHM_5INCH_DP")
	)
	(segment
		(start 116.678456 -166.206424)
		(end 116.545614 -166.113206)
		(width 0.1143)
		(layer "In9.Cu")
		(net "L10_85OHM_5INCH_DP")
	)
	(segment
		(start 129.81305 -165.946328)
		(end 129.720594 -166.078916)
		(width 0.1143)
		(layer "In9.Cu")
		(net "L10_85OHM_5INCH_DP")
	)
	(segment
		(start 123.28144 -163.545266)
		(end 123.0503 -163.876228)
		(width 0.1143)
		(layer "In9.Cu")
		(net "L10_85OHM_5INCH_DP")
	)
	(segment
		(start 144.025366 -164.144452)
		(end 144.025366 -164.646102)
		(width 0.1143)
		(layer "In9.Cu")
		(net "L10_85OHM_5INCH_DP")
	)
	(segment
		(start 115.05438 -163.876228)
		(end 115.431316 -166.011606)
		(width 0.1143)
		(layer "In9.Cu")
		(net "L10_85OHM_5INCH_DP")
	)
	(segment
		(start 140.090398 -163.59886)
		(end 139.759436 -163.36772)
		(width 0.1143)
		(layer "In9.Cu")
		(net "L10_85OHM_5INCH_DP")
	)
	(segment
		(start 128.909318 -163.680394)
		(end 128.578356 -163.449254)
		(width 0.1143)
		(layer "In9.Cu")
		(net "L10_85OHM_5INCH_DP")
	)
	(segment
		(start 129.67589 -163.477448)
		(end 129.437892 -163.818316)
		(width 0.1143)
		(layer "In9.Cu")
		(net "L10_85OHM_5INCH_DP")
	)
	(segment
		(start 139.313158 -166.066724)
		(end 139.050522 -166.112952)
		(width 0.1143)
		(layer "In9.Cu")
		(net "L10_85OHM_5INCH_DP")
	)
	(segment
		(start 123.333002 -166.136574)
		(end 123.07062 -166.182548)
		(width 0.1143)
		(layer "In9.Cu")
		(net "L10_85OHM_5INCH_DP")
	)
	(segment
		(start 126.531624 -166.1414)
		(end 126.269496 -166.18712)
		(width 0.1143)
		(layer "In9.Cu")
		(net "L10_85OHM_5INCH_DP")
	)
	(segment
		(start 132.917184 -166.070534)
		(end 132.654294 -166.116762)
		(width 0.1143)
		(layer "In9.Cu")
		(net "L10_85OHM_5INCH_DP")
	)
	(segment
		(start 118.277132 -166.206678)
		(end 118.144544 -166.113968)
		(width 0.1143)
		(layer "In9.Cu")
		(net "L10_85OHM_5INCH_DP")
	)
	(segment
		(start 116.654326 -163.880038)
		(end 117.033294 -166.027354)
		(width 0.1143)
		(layer "In9.Cu")
		(net "L10_85OHM_5INCH_DP")
	)
	(segment
		(start 142.960598 -163.383722)
		(end 142.459202 -163.47186)
		(width 0.1143)
		(layer "In9.Cu")
		(net "L10_85OHM_5INCH_DP")
	)
	(segment
		(start 123.0503 -163.876228)
		(end 123.425458 -166.003986)
		(width 0.1143)
		(layer "In9.Cu")
		(net "L10_85OHM_5INCH_DP")
	)
	(segment
		(start 139.258548 -163.45535)
		(end 139.0269 -163.786566)
		(width 0.1143)
		(layer "In9.Cu")
		(net "L10_85OHM_5INCH_DP")
	)
	(segment
		(start 130.500882 -163.630864)
		(end 130.160522 -163.392358)
		(width 0.1143)
		(layer "In9.Cu")
		(net "L10_85OHM_5INCH_DP")
	)
	(segment
		(start 120.91416 -163.684204)
		(end 120.58396 -163.45281)
		(width 0.1143)
		(layer "In9.Cu")
		(net "L10_85OHM_5INCH_DP")
	)
	(segment
		(start 132.865876 -163.47948)
		(end 132.634482 -163.810696)
		(width 0.1143)
		(layer "In9.Cu")
		(net "L10_85OHM_5INCH_DP")
	)
	(segment
		(start 131.056634 -166.125144)
		(end 130.924046 -166.032688)
		(width 0.1143)
		(layer "In9.Cu")
		(net "L10_85OHM_5INCH_DP")
	)
	(segment
		(start 127.846074 -163.868354)
		(end 128.221232 -165.996366)
		(width 0.1143)
		(layer "In9.Cu")
		(net "L10_85OHM_5INCH_DP")
	)
	(segment
		(start 140.856716 -163.456112)
		(end 140.62583 -163.787582)
		(width 0.1143)
		(layer "In9.Cu")
		(net "L10_85OHM_5INCH_DP")
	)
	(segment
		(start 128.077214 -163.537392)
		(end 127.846074 -163.868354)
		(width 0.1143)
		(layer "In9.Cu")
		(net "L10_85OHM_5INCH_DP")
	)
	(segment
		(start 136.891268 -163.595304)
		(end 136.560306 -163.36264)
		(width 0.1143)
		(layer "In9.Cu")
		(net "L10_85OHM_5INCH_DP")
	)
	(segment
		(start 128.578356 -163.449254)
		(end 128.077214 -163.537392)
		(width 0.1143)
		(layer "In9.Cu")
		(net "L10_85OHM_5INCH_DP")
	)
	(segment
		(start 115.338606 -166.144194)
		(end 115.07597 -166.190422)
		(width 0.1143)
		(layer "In9.Cu")
		(net "L10_85OHM_5INCH_DP")
	)
	(segment
		(start 142.227808 -163.803076)
		(end 142.604744 -165.9382)
		(width 0.1143)
		(layer "In9.Cu")
		(net "L10_85OHM_5INCH_DP")
	)
	(segment
		(start 126.97968 -163.449254)
		(end 126.478284 -163.537138)
		(width 0.1143)
		(layer "In9.Cu")
		(net "L10_85OHM_5INCH_DP")
	)
	(segment
		(start 143.473932 -164.516816)
		(end 143.3957 -164.208968)
		(width 0.1143)
		(layer "In9.Cu")
		(net "L10_85OHM_5INCH_DP")
	)
	(segment
		(start 142.117064 -166.025576)
		(end 141.689328 -163.599876)
		(width 0.1143)
		(layer "In9.Cu")
		(net "L10_85OHM_5INCH_DP")
	)
	(segment
		(start 115.286282 -163.545012)
		(end 115.05438 -163.876228)
		(width 0.1143)
		(layer "In9.Cu")
		(net "L10_85OHM_5INCH_DP")
	)
	(segment
		(start 124.53747 -166.090346)
		(end 124.113544 -163.688522)
		(width 0.1143)
		(layer "In9.Cu")
		(net "L10_85OHM_5INCH_DP")
	)
	(segment
		(start 119.877078 -166.21125)
		(end 119.74449 -166.118794)
		(width 0.1143)
		(layer "In9.Cu")
		(net "L10_85OHM_5INCH_DP")
	)
	(segment
		(start 138.490198 -163.594034)
		(end 138.159236 -163.363148)
		(width 0.1143)
		(layer "In9.Cu")
		(net "L10_85OHM_5INCH_DP")
	)
	(segment
		(start 134.516368 -166.070788)
		(end 134.253732 -166.116762)
		(width 0.1143)
		(layer "In9.Cu")
		(net "L10_85OHM_5INCH_DP")
	)
	(segment
		(start 131.266184 -163.474654)
		(end 131.03479 -163.806632)
		(width 0.1143)
		(layer "In9.Cu")
		(net "L10_85OHM_5INCH_DP")
	)
	(segment
		(start 133.36651 -163.391342)
		(end 132.865876 -163.47948)
		(width 0.1143)
		(layer "In9.Cu")
		(net "L10_85OHM_5INCH_DP")
	)
	(segment
		(start 121.739152 -166.165022)
		(end 121.476516 -166.211504)
		(width 0.1143)
		(layer "In9.Cu")
		(net "L10_85OHM_5INCH_DP")
	)
	(segment
		(start 118.539514 -166.160704)
		(end 118.277132 -166.206678)
		(width 0.1143)
		(layer "In9.Cu")
		(net "L10_85OHM_5INCH_DP")
	)
	(segment
		(start 114.54511 -165.038786)
		(end 114.274346 -164.833046)
		(width 0.1143)
		(layer "In9.Cu")
		(net "L10_85OHM_5INCH_DP")
	)
	(segment
		(start 143.737076 -164.780214)
		(end 143.56461 -164.63772)
		(width 0.1143)
		(layer "In9.Cu")
		(net "L10_85OHM_5INCH_DP")
	)
	(segment
		(start 134.608824 -165.938454)
		(end 134.516368 -166.070788)
		(width 0.1143)
		(layer "In9.Cu")
		(net "L10_85OHM_5INCH_DP")
	)
	(segment
		(start 142.511526 -166.071296)
		(end 142.24889 -166.117778)
		(width 0.1143)
		(layer "In9.Cu")
		(net "L10_85OHM_5INCH_DP")
	)
	(segment
		(start 139.050522 -166.112952)
		(end 138.91768 -166.020242)
		(width 0.1143)
		(layer "In9.Cu")
		(net "L10_85OHM_5INCH_DP")
	)
	(segment
		(start 117.386862 -163.461192)
		(end 116.885466 -163.549076)
		(width 0.1143)
		(layer "In9.Cu")
		(net "L10_85OHM_5INCH_DP")
	)
	(segment
		(start 125.38202 -163.457636)
		(end 124.880624 -163.54552)
		(width 0.1143)
		(layer "In9.Cu")
		(net "L10_85OHM_5INCH_DP")
	)
	(segment
		(start 124.669804 -166.182802)
		(end 124.53747 -166.090346)
		(width 0.1143)
		(layer "In9.Cu")
		(net "L10_85OHM_5INCH_DP")
	)
	(segment
		(start 129.437892 -163.818316)
		(end 129.81305 -165.946328)
		(width 0.1143)
		(layer "In9.Cu")
		(net "L10_85OHM_5INCH_DP")
	)
	(segment
		(start 126.478284 -163.537138)
		(end 126.24689 -163.868354)
		(width 0.1143)
		(layer "In9.Cu")
		(net "L10_85OHM_5INCH_DP")
	)
	(segment
		(start 128.121918 -166.138606)
		(end 127.876046 -166.181786)
		(width 0.1143)
		(layer "In9.Cu")
		(net "L10_85OHM_5INCH_DP")
	)
	(segment
		(start 126.24689 -163.868354)
		(end 126.624334 -166.008304)
		(width 0.1143)
		(layer "In9.Cu")
		(net "L10_85OHM_5INCH_DP")
	)
	(segment
		(start 134.464806 -163.47948)
		(end 134.233666 -163.81095)
		(width 0.1143)
		(layer "In9.Cu")
		(net "L10_85OHM_5INCH_DP")
	)
	(segment
		(start 135.297164 -163.623752)
		(end 134.966202 -163.391596)
		(width 0.1143)
		(layer "In9.Cu")
		(net "L10_85OHM_5INCH_DP")
	)
	(segment
		(start 127.310642 -163.68014)
		(end 126.97968 -163.449254)
		(width 0.1143)
		(layer "In9.Cu")
		(net "L10_85OHM_5INCH_DP")
	)
	(segment
		(start 123.07062 -166.182548)
		(end 122.937778 -166.08933)
		(width 0.1143)
		(layer "In9.Cu")
		(net "L10_85OHM_5INCH_DP")
	)
	(segment
		(start 114.274346 -164.833046)
		(end 114.059462 -164.833046)
		(width 0.1143)
		(layer "In9.Cu")
		(net "L10_85OHM_5INCH_DP")
	)
	(segment
		(start 129.720594 -166.078916)
		(end 129.457958 -166.125144)
		(width 0.1143)
		(layer "In9.Cu")
		(net "L10_85OHM_5INCH_DP")
	)
	(segment
		(start 118.986046 -163.461446)
		(end 118.48465 -163.54933)
		(width 0.1143)
		(layer "In9.Cu")
		(net "L10_85OHM_5INCH_DP")
	)
	(segment
		(start 124.931932 -166.136574)
		(end 124.669804 -166.182802)
		(width 0.1143)
		(layer "In9.Cu")
		(net "L10_85OHM_5INCH_DP")
	)
	(segment
		(start 116.117624 -163.687506)
		(end 115.787424 -163.456366)
		(width 0.1143)
		(layer "In9.Cu")
		(net "L10_85OHM_5INCH_DP")
	)
	(segment
		(start 127.733806 -166.082218)
		(end 127.310642 -163.68014)
		(width 0.1143)
		(layer "In9.Cu")
		(net "L10_85OHM_5INCH_DP")
	)
	(segment
		(start 125.712982 -163.688522)
		(end 125.38202 -163.457636)
		(width 0.1143)
		(layer "In9.Cu")
		(net "L10_85OHM_5INCH_DP")
	)
	(segment
		(start 115.07597 -166.190422)
		(end 114.943636 -166.097712)
		(width 0.1143)
		(layer "In9.Cu")
		(net "L10_85OHM_5INCH_DP")
	)
	(segment
		(start 140.62583 -163.787582)
		(end 141.004798 -165.934644)
		(width 0.1143)
		(layer "In9.Cu")
		(net "L10_85OHM_5INCH_DP")
	)
	(segment
		(start 134.121144 -166.024306)
		(end 133.697218 -163.622482)
		(width 0.1143)
		(layer "In9.Cu")
		(net "L10_85OHM_5INCH_DP")
	)
	(segment
		(start 119.851424 -163.87191)
		(end 120.232424 -166.033196)
		(width 0.1143)
		(layer "In9.Cu")
		(net "L10_85OHM_5INCH_DP")
	)
	(segment
		(start 117.718078 -163.692332)
		(end 117.386862 -163.461192)
		(width 0.1143)
		(layer "In9.Cu")
		(net "L10_85OHM_5INCH_DP")
	)
	(segment
		(start 133.697218 -163.622482)
		(end 133.36651 -163.391342)
		(width 0.1143)
		(layer "In9.Cu")
		(net "L10_85OHM_5INCH_DP")
	)
	(segment
		(start 135.720836 -166.028878)
		(end 135.297164 -163.623752)
		(width 0.1143)
		(layer "In9.Cu")
		(net "L10_85OHM_5INCH_DP")
	)
	(segment
		(start 140.51661 -166.020496)
		(end 140.090398 -163.59886)
		(width 0.1143)
		(layer "In9.Cu")
		(net "L10_85OHM_5INCH_DP")
	)
	(segment
		(start 125.024642 -166.003986)
		(end 124.931932 -166.136574)
		(width 0.1143)
		(layer "In9.Cu")
		(net "L10_85OHM_5INCH_DP")
	)
	(segment
		(start 115.787424 -163.456366)
		(end 115.286282 -163.545012)
		(width 0.1143)
		(layer "In9.Cu")
		(net "L10_85OHM_5INCH_DP")
	)
	(segment
		(start 122.513852 -163.68395)
		(end 122.18289 -163.45281)
		(width 0.1143)
		(layer "In9.Cu")
		(net "L10_85OHM_5INCH_DP")
	)
	(segment
		(start 138.159236 -163.363148)
		(end 137.65911 -163.450778)
		(width 0.1143)
		(layer "In9.Cu")
		(net "L10_85OHM_5INCH_DP")
	)
	(segment
		(start 114.858292 -165.612572)
		(end 114.798348 -165.376352)
		(width 0.1143)
		(layer "In9.Cu")
		(net "L10_85OHM_5INCH_DP")
	)
	(segment
		(start 140.649452 -166.113206)
		(end 140.51661 -166.020496)
		(width 0.1143)
		(layer "In9.Cu")
		(net "L10_85OHM_5INCH_DP")
	)
	(segment
		(start 135.853424 -166.121588)
		(end 135.720836 -166.028878)
		(width 0.1143)
		(layer "In9.Cu")
		(net "L10_85OHM_5INCH_DP")
	)
	(segment
		(start 110.558326 -165.122606)
		(end 113.326672 -165.122606)
		(width 0.1143)
		(layer "F.Cu")
		(net "L10_85OHM_5INCH_DN")
	)
	(segment
		(start 110.203996 -165.476936)
		(end 110.558326 -165.122606)
		(width 0.1143)
		(layer "F.Cu")
		(net "L10_85OHM_5INCH_DN")
	)
	(segment
		(start 147.40255 -165.052502)
		(end 144.641316 -165.052502)
		(width 0.1143)
		(layer "F.Cu")
		(net "L10_85OHM_5INCH_DN")
	)
	(segment
		(start 113.326672 -165.122606)
		(end 113.942622 -165.738556)
		(width 0.1143)
		(layer "F.Cu")
		(net "L10_85OHM_5INCH_DN")
	)
	(segment
		(start 147.763992 -165.413944)
		(end 147.40255 -165.052502)
		(width 0.1143)
		(layer "F.Cu")
		(net "L10_85OHM_5INCH_DN")
	)
	(segment
		(start 144.641316 -165.052502)
		(end 144.025366 -165.668452)
		(width 0.1143)
		(layer "F.Cu")
		(net "L10_85OHM_5INCH_DN")
	)
	(via
		(at 144.025366 -165.668452)
		(size 0.5588)
		(drill 0.3048)
		(layers "F.Cu" "B.Cu")
		(net "L10_85OHM_5INCH_DN")
	)
	(via
		(at 113.942622 -165.738556)
		(size 0.5588)
		(drill 0.3048)
		(layers "F.Cu" "B.Cu")
		(net "L10_85OHM_5INCH_DN")
	)
	(segment
		(start 133.430518 -163.792662)
		(end 133.298184 -163.700206)
		(width 0.1143)
		(layer "In9.Cu")
		(net "L10_85OHM_5INCH_DN")
	)
	(segment
		(start 114.572288 -165.67404)
		(end 114.529362 -165.504876)
		(width 0.1143)
		(layer "In9.Cu")
		(net "L10_85OHM_5INCH_DN")
	)
	(segment
		(start 142.629382 -163.738814)
		(end 142.536672 -163.871402)
		(width 0.1143)
		(layer "In9.Cu")
		(net "L10_85OHM_5INCH_DN")
	)
	(segment
		(start 114.676936 -166.267638)
		(end 114.572288 -165.67404)
		(width 0.1143)
		(layer "In9.Cu")
		(net "L10_85OHM_5INCH_DN")
	)
	(segment
		(start 116.96319 -163.948364)
		(end 117.342158 -166.095426)
		(width 0.1143)
		(layer "In9.Cu")
		(net "L10_85OHM_5INCH_DN")
	)
	(segment
		(start 131.489704 -166.34587)
		(end 130.988308 -166.433754)
		(width 0.1143)
		(layer "In9.Cu")
		(net "L10_85OHM_5INCH_DN")
	)
	(segment
		(start 123.359164 -163.944554)
		(end 123.734322 -166.072058)
		(width 0.1143)
		(layer "In9.Cu")
		(net "L10_85OHM_5INCH_DN")
	)
	(segment
		(start 123.714256 -163.766246)
		(end 123.45162 -163.81222)
		(width 0.1143)
		(layer "In9.Cu")
		(net "L10_85OHM_5INCH_DN")
	)
	(segment
		(start 136.228836 -163.717986)
		(end 136.136126 -163.85032)
		(width 0.1143)
		(layer "In9.Cu")
		(net "L10_85OHM_5INCH_DN")
	)
	(segment
		(start 115.456462 -163.811712)
		(end 115.363244 -163.944808)
		(width 0.1143)
		(layer "In9.Cu")
		(net "L10_85OHM_5INCH_DN")
	)
	(segment
		(start 142.180564 -166.426642)
		(end 141.850364 -166.195502)
		(width 0.1143)
		(layer "In9.Cu")
		(net "L10_85OHM_5INCH_DN")
	)
	(segment
		(start 132.943346 -163.879022)
		(end 133.318758 -166.006272)
		(width 0.1143)
		(layer "In9.Cu")
		(net "L10_85OHM_5INCH_DN")
	)
	(segment
		(start 137.053828 -166.198804)
		(end 136.624314 -163.764976)
		(width 0.1143)
		(layer "In9.Cu")
		(net "L10_85OHM_5INCH_DN")
	)
	(segment
		(start 114.054382 -165.125146)
		(end 113.942622 -165.236906)
		(width 0.1143)
		(layer "In9.Cu")
		(net "L10_85OHM_5INCH_DN")
	)
	(segment
		(start 129.890774 -166.345616)
		(end 129.389632 -166.433754)
		(width 0.1143)
		(layer "In9.Cu")
		(net "L10_85OHM_5INCH_DN")
	)
	(segment
		(start 115.74018 -166.079932)
		(end 115.508786 -166.411148)
		(width 0.1143)
		(layer "In9.Cu")
		(net "L10_85OHM_5INCH_DN")
	)
	(segment
		(start 126.648464 -163.804092)
		(end 126.555754 -163.93668)
		(width 0.1143)
		(layer "In9.Cu")
		(net "L10_85OHM_5INCH_DN")
	)
	(segment
		(start 130.091942 -163.701222)
		(end 129.84607 -163.744402)
		(width 0.1143)
		(layer "In9.Cu")
		(net "L10_85OHM_5INCH_DN")
	)
	(segment
		(start 134.54253 -163.879022)
		(end 134.917688 -166.00678)
		(width 0.1143)
		(layer "In9.Cu")
		(net "L10_85OHM_5INCH_DN")
	)
	(segment
		(start 126.555754 -163.93668)
		(end 126.933198 -166.076376)
		(width 0.1143)
		(layer "In9.Cu")
		(net "L10_85OHM_5INCH_DN")
	)
	(segment
		(start 141.02715 -163.722812)
		(end 140.934694 -163.855654)
		(width 0.1143)
		(layer "In9.Cu")
		(net "L10_85OHM_5INCH_DN")
	)
	(segment
		(start 141.313662 -166.00297)
		(end 141.082522 -166.333932)
		(width 0.1143)
		(layer "In9.Cu")
		(net "L10_85OHM_5INCH_DN")
	)
	(segment
		(start 122.670824 -166.259256)
		(end 122.247152 -163.85413)
		(width 0.1143)
		(layer "In9.Cu")
		(net "L10_85OHM_5INCH_DN")
	)
	(segment
		(start 119.47779 -166.288974)
		(end 119.050308 -163.862766)
		(width 0.1143)
		(layer "In9.Cu")
		(net "L10_85OHM_5INCH_DN")
	)
	(segment
		(start 125.869446 -166.264844)
		(end 125.446282 -163.858702)
		(width 0.1143)
		(layer "In9.Cu")
		(net "L10_85OHM_5INCH_DN")
	)
	(segment
		(start 131.343654 -163.874704)
		(end 131.721098 -166.014654)
		(width 0.1143)
		(layer "In9.Cu")
		(net "L10_85OHM_5INCH_DN")
	)
	(segment
		(start 143.204946 -164.645594)
		(end 143.109696 -164.270436)
		(width 0.1143)
		(layer "In9.Cu")
		(net "L10_85OHM_5INCH_DN")
	)
	(segment
		(start 125.446282 -163.858702)
		(end 125.313694 -163.766246)
		(width 0.1143)
		(layer "In9.Cu")
		(net "L10_85OHM_5INCH_DN")
	)
	(segment
		(start 128.642618 -163.850574)
		(end 128.51003 -163.757864)
		(width 0.1143)
		(layer "In9.Cu")
		(net "L10_85OHM_5INCH_DN")
	)
	(segment
		(start 125.102112 -166.403528)
		(end 124.601478 -166.491666)
		(width 0.1143)
		(layer "In9.Cu")
		(net "L10_85OHM_5INCH_DN")
	)
	(segment
		(start 133.298184 -163.700206)
		(end 133.036056 -163.746434)
		(width 0.1143)
		(layer "In9.Cu")
		(net "L10_85OHM_5INCH_DN")
	)
	(segment
		(start 121.07672 -166.287704)
		(end 120.64746 -163.85413)
		(width 0.1143)
		(layer "In9.Cu")
		(net "L10_85OHM_5INCH_DN")
	)
	(segment
		(start 127.043942 -163.85032)
		(end 126.911354 -163.757864)
		(width 0.1143)
		(layer "In9.Cu")
		(net "L10_85OHM_5INCH_DN")
	)
	(segment
		(start 129.746756 -163.886642)
		(end 130.121914 -166.014654)
		(width 0.1143)
		(layer "In9.Cu")
		(net "L10_85OHM_5INCH_DN")
	)
	(segment
		(start 122.247152 -163.85413)
		(end 122.114564 -163.76142)
		(width 0.1143)
		(layer "In9.Cu")
		(net "L10_85OHM_5INCH_DN")
	)
	(segment
		(start 127.807466 -166.49065)
		(end 127.467106 -166.252144)
		(width 0.1143)
		(layer "In9.Cu")
		(net "L10_85OHM_5INCH_DN")
	)
	(segment
		(start 141.082522 -166.333932)
		(end 140.581126 -166.421816)
		(width 0.1143)
		(layer "In9.Cu")
		(net "L10_85OHM_5INCH_DN")
	)
	(segment
		(start 118.562374 -163.948618)
		(end 118.941088 -166.096442)
		(width 0.1143)
		(layer "In9.Cu")
		(net "L10_85OHM_5INCH_DN")
	)
	(segment
		(start 120.64746 -163.85413)
		(end 120.51538 -163.761674)
		(width 0.1143)
		(layer "In9.Cu")
		(net "L10_85OHM_5INCH_DN")
	)
	(segment
		(start 143.351504 -164.84092)
		(end 143.204946 -164.645594)
		(width 0.1143)
		(layer "In9.Cu")
		(net "L10_85OHM_5INCH_DN")
	)
	(segment
		(start 118.941088 -166.096442)
		(end 118.70944 -166.427658)
		(width 0.1143)
		(layer "In9.Cu")
		(net "L10_85OHM_5INCH_DN")
	)
	(segment
		(start 138.09091 -163.671758)
		(end 137.828528 -163.717732)
		(width 0.1143)
		(layer "In9.Cu")
		(net "L10_85OHM_5INCH_DN")
	)
	(segment
		(start 115.719098 -163.76523)
		(end 115.456462 -163.811712)
		(width 0.1143)
		(layer "In9.Cu")
		(net "L10_85OHM_5INCH_DN")
	)
	(segment
		(start 144.025366 -165.166802)
		(end 143.922496 -165.064186)
		(width 0.1143)
		(layer "In9.Cu")
		(net "L10_85OHM_5INCH_DN")
	)
	(segment
		(start 124.27077 -166.260526)
		(end 123.846844 -163.858702)
		(width 0.1143)
		(layer "In9.Cu")
		(net "L10_85OHM_5INCH_DN")
	)
	(segment
		(start 131.831588 -163.788598)
		(end 131.698492 -163.695888)
		(width 0.1143)
		(layer "In9.Cu")
		(net "L10_85OHM_5INCH_DN")
	)
	(segment
		(start 120.160288 -163.940236)
		(end 120.541288 -166.10203)
		(width 0.1143)
		(layer "In9.Cu")
		(net "L10_85OHM_5INCH_DN")
	)
	(segment
		(start 123.001786 -166.491412)
		(end 122.670824 -166.259256)
		(width 0.1143)
		(layer "In9.Cu")
		(net "L10_85OHM_5INCH_DN")
	)
	(segment
		(start 118.917466 -163.770056)
		(end 118.65483 -163.816284)
		(width 0.1143)
		(layer "In9.Cu")
		(net "L10_85OHM_5INCH_DN")
	)
	(segment
		(start 123.503182 -166.403528)
		(end 123.001786 -166.491412)
		(width 0.1143)
		(layer "In9.Cu")
		(net "L10_85OHM_5INCH_DN")
	)
	(segment
		(start 120.308878 -166.43223)
		(end 119.808752 -166.51986)
		(width 0.1143)
		(layer "In9.Cu")
		(net "L10_85OHM_5INCH_DN")
	)
	(segment
		(start 122.114564 -163.76142)
		(end 121.851928 -163.807902)
		(width 0.1143)
		(layer "In9.Cu")
		(net "L10_85OHM_5INCH_DN")
	)
	(segment
		(start 138.981942 -166.421562)
		(end 138.650726 -166.190422)
		(width 0.1143)
		(layer "In9.Cu")
		(net "L10_85OHM_5INCH_DN")
	)
	(segment
		(start 123.45162 -163.81222)
		(end 123.359164 -163.944554)
		(width 0.1143)
		(layer "In9.Cu")
		(net "L10_85OHM_5INCH_DN")
	)
	(segment
		(start 116.609876 -166.515288)
		(end 116.27866 -166.283132)
		(width 0.1143)
		(layer "In9.Cu")
		(net "L10_85OHM_5INCH_DN")
	)
	(segment
		(start 124.958094 -163.945062)
		(end 125.333506 -166.072312)
		(width 0.1143)
		(layer "In9.Cu")
		(net "L10_85OHM_5INCH_DN")
	)
	(segment
		(start 125.333506 -166.072312)
		(end 125.102112 -166.403528)
		(width 0.1143)
		(layer "In9.Cu")
		(net "L10_85OHM_5INCH_DN")
	)
	(segment
		(start 137.735564 -163.849812)
		(end 138.116564 -166.011098)
		(width 0.1143)
		(layer "In9.Cu")
		(net "L10_85OHM_5INCH_DN")
	)
	(segment
		(start 127.467106 -166.252144)
		(end 127.043942 -163.85032)
		(width 0.1143)
		(layer "In9.Cu")
		(net "L10_85OHM_5INCH_DN")
	)
	(segment
		(start 121.851928 -163.807902)
		(end 121.759726 -163.94049)
		(width 0.1143)
		(layer "In9.Cu")
		(net "L10_85OHM_5INCH_DN")
	)
	(segment
		(start 115.508786 -166.411148)
		(end 115.00739 -166.499286)
		(width 0.1143)
		(layer "In9.Cu")
		(net "L10_85OHM_5INCH_DN")
	)
	(segment
		(start 131.436364 -163.741608)
		(end 131.343654 -163.874704)
		(width 0.1143)
		(layer "In9.Cu")
		(net "L10_85OHM_5INCH_DN")
	)
	(segment
		(start 136.624314 -163.764976)
		(end 136.491472 -163.671504)
		(width 0.1143)
		(layer "In9.Cu")
		(net "L10_85OHM_5INCH_DN")
	)
	(segment
		(start 142.913608 -166.00678)
		(end 142.681706 -166.337996)
		(width 0.1143)
		(layer "In9.Cu")
		(net "L10_85OHM_5INCH_DN")
	)
	(segment
		(start 132.255006 -166.194486)
		(end 131.831588 -163.788598)
		(width 0.1143)
		(layer "In9.Cu")
		(net "L10_85OHM_5INCH_DN")
	)
	(segment
		(start 124.601478 -166.491666)
		(end 124.27077 -166.260526)
		(width 0.1143)
		(layer "In9.Cu")
		(net "L10_85OHM_5INCH_DN")
	)
	(segment
		(start 134.634986 -163.746434)
		(end 134.54253 -163.879022)
		(width 0.1143)
		(layer "In9.Cu")
		(net "L10_85OHM_5INCH_DN")
	)
	(segment
		(start 113.942622 -165.236906)
		(end 113.942622 -165.738556)
		(width 0.1143)
		(layer "In9.Cu")
		(net "L10_85OHM_5INCH_DN")
	)
	(segment
		(start 130.234182 -163.80079)
		(end 130.091942 -163.701222)
		(width 0.1143)
		(layer "In9.Cu")
		(net "L10_85OHM_5INCH_DN")
	)
	(segment
		(start 117.111272 -166.426896)
		(end 116.609876 -166.515288)
		(width 0.1143)
		(layer "In9.Cu")
		(net "L10_85OHM_5INCH_DN")
	)
	(segment
		(start 120.51538 -163.761674)
		(end 120.252744 -163.807902)
		(width 0.1143)
		(layer "In9.Cu")
		(net "L10_85OHM_5INCH_DN")
	)
	(segment
		(start 126.20117 -166.49573)
		(end 125.869446 -166.264844)
		(width 0.1143)
		(layer "In9.Cu")
		(net "L10_85OHM_5INCH_DN")
	)
	(segment
		(start 138.116564 -166.011098)
		(end 137.885424 -166.34206)
		(width 0.1143)
		(layer "In9.Cu")
		(net "L10_85OHM_5INCH_DN")
	)
	(segment
		(start 128.51003 -163.757864)
		(end 128.247394 -163.804092)
		(width 0.1143)
		(layer "In9.Cu")
		(net "L10_85OHM_5INCH_DN")
	)
	(segment
		(start 143.922496 -165.064186)
		(end 143.638016 -165.077394)
		(width 0.1143)
		(layer "In9.Cu")
		(net "L10_85OHM_5INCH_DN")
	)
	(segment
		(start 138.650726 -166.190422)
		(end 138.223498 -163.764214)
		(width 0.1143)
		(layer "In9.Cu")
		(net "L10_85OHM_5INCH_DN")
	)
	(segment
		(start 130.121914 -166.014654)
		(end 129.890774 -166.345616)
		(width 0.1143)
		(layer "In9.Cu")
		(net "L10_85OHM_5INCH_DN")
	)
	(segment
		(start 123.846844 -163.858702)
		(end 123.714256 -163.766246)
		(width 0.1143)
		(layer "In9.Cu")
		(net "L10_85OHM_5INCH_DN")
	)
	(segment
		(start 128.530096 -166.064692)
		(end 128.292098 -166.40556)
		(width 0.1143)
		(layer "In9.Cu")
		(net "L10_85OHM_5INCH_DN")
	)
	(segment
		(start 128.247394 -163.804092)
		(end 128.154938 -163.93668)
		(width 0.1143)
		(layer "In9.Cu")
		(net "L10_85OHM_5INCH_DN")
	)
	(segment
		(start 131.721098 -166.014654)
		(end 131.489704 -166.34587)
		(width 0.1143)
		(layer "In9.Cu")
		(net "L10_85OHM_5INCH_DN")
	)
	(segment
		(start 136.28624 -166.341806)
		(end 135.785098 -166.430198)
		(width 0.1143)
		(layer "In9.Cu")
		(net "L10_85OHM_5INCH_DN")
	)
	(segment
		(start 118.65483 -163.816284)
		(end 118.562374 -163.948618)
		(width 0.1143)
		(layer "In9.Cu")
		(net "L10_85OHM_5INCH_DN")
	)
	(segment
		(start 139.714478 -166.002716)
		(end 139.483338 -166.333678)
		(width 0.1143)
		(layer "In9.Cu")
		(net "L10_85OHM_5INCH_DN")
	)
	(segment
		(start 136.491472 -163.671504)
		(end 136.228836 -163.717986)
		(width 0.1143)
		(layer "In9.Cu")
		(net "L10_85OHM_5INCH_DN")
	)
	(segment
		(start 130.657346 -166.202868)
		(end 130.234182 -163.80079)
		(width 0.1143)
		(layer "In9.Cu")
		(net "L10_85OHM_5INCH_DN")
	)
	(segment
		(start 129.05867 -166.202614)
		(end 128.642618 -163.850574)
		(width 0.1143)
		(layer "In9.Cu")
		(net "L10_85OHM_5INCH_DN")
	)
	(segment
		(start 134.185406 -166.425372)
		(end 133.854444 -166.194486)
		(width 0.1143)
		(layer "In9.Cu")
		(net "L10_85OHM_5INCH_DN")
	)
	(segment
		(start 141.422374 -163.769802)
		(end 141.289532 -163.676584)
		(width 0.1143)
		(layer "In9.Cu")
		(net "L10_85OHM_5INCH_DN")
	)
	(segment
		(start 141.850364 -166.195502)
		(end 141.422374 -163.769802)
		(width 0.1143)
		(layer "In9.Cu")
		(net "L10_85OHM_5INCH_DN")
	)
	(segment
		(start 133.087364 -166.337488)
		(end 132.585968 -166.425372)
		(width 0.1143)
		(layer "In9.Cu")
		(net "L10_85OHM_5INCH_DN")
	)
	(segment
		(start 136.517126 -166.011352)
		(end 136.28624 -166.341806)
		(width 0.1143)
		(layer "In9.Cu")
		(net "L10_85OHM_5INCH_DN")
	)
	(segment
		(start 133.854444 -166.194486)
		(end 133.430518 -163.792662)
		(width 0.1143)
		(layer "In9.Cu")
		(net "L10_85OHM_5INCH_DN")
	)
	(segment
		(start 135.785098 -166.430198)
		(end 135.454136 -166.199058)
		(width 0.1143)
		(layer "In9.Cu")
		(net "L10_85OHM_5INCH_DN")
	)
	(segment
		(start 140.581126 -166.421816)
		(end 140.24991 -166.190676)
		(width 0.1143)
		(layer "In9.Cu")
		(net "L10_85OHM_5INCH_DN")
	)
	(segment
		(start 118.70944 -166.427658)
		(end 118.208552 -166.515288)
		(width 0.1143)
		(layer "In9.Cu")
		(net "L10_85OHM_5INCH_DN")
	)
	(segment
		(start 116.27866 -166.283132)
		(end 115.850924 -163.857432)
		(width 0.1143)
		(layer "In9.Cu")
		(net "L10_85OHM_5INCH_DN")
	)
	(segment
		(start 117.318536 -163.769802)
		(end 117.055646 -163.81603)
		(width 0.1143)
		(layer "In9.Cu")
		(net "L10_85OHM_5INCH_DN")
	)
	(segment
		(start 125.313694 -163.766246)
		(end 125.050804 -163.812474)
		(width 0.1143)
		(layer "In9.Cu")
		(net "L10_85OHM_5INCH_DN")
	)
	(segment
		(start 134.897368 -163.70046)
		(end 134.634986 -163.746434)
		(width 0.1143)
		(layer "In9.Cu")
		(net "L10_85OHM_5INCH_DN")
	)
	(segment
		(start 144.025366 -165.668452)
		(end 144.025366 -165.166802)
		(width 0.1143)
		(layer "In9.Cu")
		(net "L10_85OHM_5INCH_DN")
	)
	(segment
		(start 131.698492 -163.695888)
		(end 131.436364 -163.741608)
		(width 0.1143)
		(layer "In9.Cu")
		(net "L10_85OHM_5INCH_DN")
	)
	(segment
		(start 138.223498 -163.764214)
		(end 138.09091 -163.671758)
		(width 0.1143)
		(layer "In9.Cu")
		(net "L10_85OHM_5INCH_DN")
	)
	(segment
		(start 133.318758 -166.006272)
		(end 133.087364 -166.337488)
		(width 0.1143)
		(layer "In9.Cu")
		(net "L10_85OHM_5INCH_DN")
	)
	(segment
		(start 126.911354 -163.757864)
		(end 126.648464 -163.804092)
		(width 0.1143)
		(layer "In9.Cu")
		(net "L10_85OHM_5INCH_DN")
	)
	(segment
		(start 115.850924 -163.857432)
		(end 115.719098 -163.76523)
		(width 0.1143)
		(layer "In9.Cu")
		(net "L10_85OHM_5INCH_DN")
	)
	(segment
		(start 137.384028 -166.430198)
		(end 137.053828 -166.198804)
		(width 0.1143)
		(layer "In9.Cu")
		(net "L10_85OHM_5INCH_DN")
	)
	(segment
		(start 114.175794 -165.125146)
		(end 114.054382 -165.125146)
		(width 0.1143)
		(layer "In9.Cu")
		(net "L10_85OHM_5INCH_DN")
	)
	(segment
		(start 129.389632 -166.433754)
		(end 129.05867 -166.202614)
		(width 0.1143)
		(layer "In9.Cu")
		(net "L10_85OHM_5INCH_DN")
	)
	(segment
		(start 137.885424 -166.34206)
		(end 137.384028 -166.430198)
		(width 0.1143)
		(layer "In9.Cu")
		(net "L10_85OHM_5INCH_DN")
	)
	(segment
		(start 128.154938 -163.93668)
		(end 128.530096 -166.064692)
		(width 0.1143)
		(layer "In9.Cu")
		(net "L10_85OHM_5INCH_DN")
	)
	(segment
		(start 139.335764 -163.854892)
		(end 139.714478 -166.002716)
		(width 0.1143)
		(layer "In9.Cu")
		(net "L10_85OHM_5INCH_DN")
	)
	(segment
		(start 134.686548 -166.337742)
		(end 134.185406 -166.425372)
		(width 0.1143)
		(layer "In9.Cu")
		(net "L10_85OHM_5INCH_DN")
	)
	(segment
		(start 137.828528 -163.717732)
		(end 137.735564 -163.849812)
		(width 0.1143)
		(layer "In9.Cu")
		(net "L10_85OHM_5INCH_DN")
	)
	(segment
		(start 128.292098 -166.40556)
		(end 127.807466 -166.49065)
		(width 0.1143)
		(layer "In9.Cu")
		(net "L10_85OHM_5INCH_DN")
	)
	(segment
		(start 125.050804 -163.812474)
		(end 124.958094 -163.945062)
		(width 0.1143)
		(layer "In9.Cu")
		(net "L10_85OHM_5INCH_DN")
	)
	(segment
		(start 121.909078 -166.431722)
		(end 121.407682 -166.520368)
		(width 0.1143)
		(layer "In9.Cu")
		(net "L10_85OHM_5INCH_DN")
	)
	(segment
		(start 143.024606 -163.785296)
		(end 142.892018 -163.692586)
		(width 0.1143)
		(layer "In9.Cu")
		(net "L10_85OHM_5INCH_DN")
	)
	(segment
		(start 139.823444 -163.76904)
		(end 139.690856 -163.67633)
		(width 0.1143)
		(layer "In9.Cu")
		(net "L10_85OHM_5INCH_DN")
	)
	(segment
		(start 115.363244 -163.944808)
		(end 115.74018 -166.079932)
		(width 0.1143)
		(layer "In9.Cu")
		(net "L10_85OHM_5INCH_DN")
	)
	(segment
		(start 115.00739 -166.499286)
		(end 114.676936 -166.267638)
		(width 0.1143)
		(layer "In9.Cu")
		(net "L10_85OHM_5INCH_DN")
	)
	(segment
		(start 121.407682 -166.520368)
		(end 121.07672 -166.287704)
		(width 0.1143)
		(layer "In9.Cu")
		(net "L10_85OHM_5INCH_DN")
	)
	(segment
		(start 139.428474 -163.722304)
		(end 139.335764 -163.854892)
		(width 0.1143)
		(layer "In9.Cu")
		(net "L10_85OHM_5INCH_DN")
	)
	(segment
		(start 143.638016 -165.077394)
		(end 143.351504 -164.84092)
		(width 0.1143)
		(layer "In9.Cu")
		(net "L10_85OHM_5INCH_DN")
	)
	(segment
		(start 133.036056 -163.746434)
		(end 132.943346 -163.879022)
		(width 0.1143)
		(layer "In9.Cu")
		(net "L10_85OHM_5INCH_DN")
	)
	(segment
		(start 117.342158 -166.095426)
		(end 117.111272 -166.426896)
		(width 0.1143)
		(layer "In9.Cu")
		(net "L10_85OHM_5INCH_DN")
	)
	(segment
		(start 139.690856 -163.67633)
		(end 139.428474 -163.722304)
		(width 0.1143)
		(layer "In9.Cu")
		(net "L10_85OHM_5INCH_DN")
	)
	(segment
		(start 118.208552 -166.515288)
		(end 117.87759 -166.284148)
		(width 0.1143)
		(layer "In9.Cu")
		(net "L10_85OHM_5INCH_DN")
	)
	(segment
		(start 120.252744 -163.807902)
		(end 120.160288 -163.940236)
		(width 0.1143)
		(layer "In9.Cu")
		(net "L10_85OHM_5INCH_DN")
	)
	(segment
		(start 135.454136 -166.199058)
		(end 135.03021 -163.793678)
		(width 0.1143)
		(layer "In9.Cu")
		(net "L10_85OHM_5INCH_DN")
	)
	(segment
		(start 119.050308 -163.862766)
		(end 118.917466 -163.770056)
		(width 0.1143)
		(layer "In9.Cu")
		(net "L10_85OHM_5INCH_DN")
	)
	(segment
		(start 114.529362 -165.504876)
		(end 114.335814 -165.246812)
		(width 0.1143)
		(layer "In9.Cu")
		(net "L10_85OHM_5INCH_DN")
	)
	(segment
		(start 135.03021 -163.793678)
		(end 134.897368 -163.70046)
		(width 0.1143)
		(layer "In9.Cu")
		(net "L10_85OHM_5INCH_DN")
	)
	(segment
		(start 139.483338 -166.333678)
		(end 138.981942 -166.421562)
		(width 0.1143)
		(layer "In9.Cu")
		(net "L10_85OHM_5INCH_DN")
	)
	(segment
		(start 117.055646 -163.81603)
		(end 116.96319 -163.948364)
		(width 0.1143)
		(layer "In9.Cu")
		(net "L10_85OHM_5INCH_DN")
	)
	(segment
		(start 142.892018 -163.692586)
		(end 142.629382 -163.738814)
		(width 0.1143)
		(layer "In9.Cu")
		(net "L10_85OHM_5INCH_DN")
	)
	(segment
		(start 119.808752 -166.51986)
		(end 119.47779 -166.288974)
		(width 0.1143)
		(layer "In9.Cu")
		(net "L10_85OHM_5INCH_DN")
	)
	(segment
		(start 117.451378 -163.862512)
		(end 117.318536 -163.769802)
		(width 0.1143)
		(layer "In9.Cu")
		(net "L10_85OHM_5INCH_DN")
	)
	(segment
		(start 134.917688 -166.00678)
		(end 134.686548 -166.337742)
		(width 0.1143)
		(layer "In9.Cu")
		(net "L10_85OHM_5INCH_DN")
	)
	(segment
		(start 121.759726 -163.94049)
		(end 122.140726 -166.101268)
		(width 0.1143)
		(layer "In9.Cu")
		(net "L10_85OHM_5INCH_DN")
	)
	(segment
		(start 142.681706 -166.337996)
		(end 142.180564 -166.426642)
		(width 0.1143)
		(layer "In9.Cu")
		(net "L10_85OHM_5INCH_DN")
	)
	(segment
		(start 130.988308 -166.433754)
		(end 130.657346 -166.202868)
		(width 0.1143)
		(layer "In9.Cu")
		(net "L10_85OHM_5INCH_DN")
	)
	(segment
		(start 120.541288 -166.10203)
		(end 120.308878 -166.43223)
		(width 0.1143)
		(layer "In9.Cu")
		(net "L10_85OHM_5INCH_DN")
	)
	(segment
		(start 140.934694 -163.855654)
		(end 141.313662 -166.00297)
		(width 0.1143)
		(layer "In9.Cu")
		(net "L10_85OHM_5INCH_DN")
	)
	(segment
		(start 123.734322 -166.072058)
		(end 123.503182 -166.403528)
		(width 0.1143)
		(layer "In9.Cu")
		(net "L10_85OHM_5INCH_DN")
	)
	(segment
		(start 142.536672 -163.871402)
		(end 142.913608 -166.00678)
		(width 0.1143)
		(layer "In9.Cu")
		(net "L10_85OHM_5INCH_DN")
	)
	(segment
		(start 129.84607 -163.744402)
		(end 129.746756 -163.886642)
		(width 0.1143)
		(layer "In9.Cu")
		(net "L10_85OHM_5INCH_DN")
	)
	(segment
		(start 141.289532 -163.676584)
		(end 141.02715 -163.722812)
		(width 0.1143)
		(layer "In9.Cu")
		(net "L10_85OHM_5INCH_DN")
	)
	(segment
		(start 140.24991 -166.190676)
		(end 139.823444 -163.76904)
		(width 0.1143)
		(layer "In9.Cu")
		(net "L10_85OHM_5INCH_DN")
	)
	(segment
		(start 143.109696 -164.270436)
		(end 143.024606 -163.785296)
		(width 0.1143)
		(layer "In9.Cu")
		(net "L10_85OHM_5INCH_DN")
	)
	(segment
		(start 126.701804 -166.408354)
		(end 126.20117 -166.49573)
		(width 0.1143)
		(layer "In9.Cu")
		(net "L10_85OHM_5INCH_DN")
	)
	(segment
		(start 117.87759 -166.284148)
		(end 117.451378 -163.862512)
		(width 0.1143)
		(layer "In9.Cu")
		(net "L10_85OHM_5INCH_DN")
	)
	(segment
		(start 132.585968 -166.425372)
		(end 132.255006 -166.194486)
		(width 0.1143)
		(layer "In9.Cu")
		(net "L10_85OHM_5INCH_DN")
	)
	(segment
		(start 136.136126 -163.85032)
		(end 136.517126 -166.011352)
		(width 0.1143)
		(layer "In9.Cu")
		(net "L10_85OHM_5INCH_DN")
	)
	(segment
		(start 126.933198 -166.076376)
		(end 126.701804 -166.408354)
		(width 0.1143)
		(layer "In9.Cu")
		(net "L10_85OHM_5INCH_DN")
	)
	(segment
		(start 122.140726 -166.101268)
		(end 121.909078 -166.431722)
		(width 0.1143)
		(layer "In9.Cu")
		(net "L10_85OHM_5INCH_DN")
	)
	(segment
		(start 114.335814 -165.246812)
		(end 114.175794 -165.125146)
		(width 0.1143)
		(layer "In9.Cu")
		(net "L10_85OHM_5INCH_DN")
	)
	(segment
		(start 387.20141 -164.412676)
		(end 386.854192 -164.759894)
		(width 0.1143)
		(layer "F.Cu")
		(net "L10_85OHM_10INCH_DP")
	)
	(segment
		(start 320.768472 -164.767006)
		(end 321.384422 -164.151056)
		(width 0.1143)
		(layer "F.Cu")
		(net "L10_85OHM_10INCH_DP")
	)
	(segment
		(start 318.000126 -164.767006)
		(end 320.768472 -164.767006)
		(width 0.1143)
		(layer "F.Cu")
		(net "L10_85OHM_10INCH_DP")
	)
	(segment
		(start 317.645796 -164.412676)
		(end 318.000126 -164.767006)
		(width 0.1143)
		(layer "F.Cu")
		(net "L10_85OHM_10INCH_DP")
	)
	(segment
		(start 384.078734 -164.759894)
		(end 383.462784 -164.143944)
		(width 0.1143)
		(layer "F.Cu")
		(net "L10_85OHM_10INCH_DP")
	)
	(segment
		(start 386.854192 -164.759894)
		(end 384.078734 -164.759894)
		(width 0.1143)
		(layer "F.Cu")
		(net "L10_85OHM_10INCH_DP")
	)
	(via
		(at 321.384422 -164.151056)
		(size 0.5588)
		(drill 0.3048)
		(layers "F.Cu" "B.Cu")
		(net "L10_85OHM_10INCH_DP")
	)
	(via
		(at 383.462784 -164.143944)
		(size 0.5588)
		(drill 0.3048)
		(layers "F.Cu" "B.Cu")
		(net "L10_85OHM_10INCH_DP")
	)
	(segment
		(start 327.293224 -163.80841)
		(end 327.674224 -165.969696)
		(width 0.1143)
		(layer "In9.Cu")
		(net "L10_85OHM_10INCH_DP")
	)
	(segment
		(start 341.151972 -163.632896)
		(end 340.821264 -163.401756)
		(width 0.1143)
		(layer "In9.Cu")
		(net "L10_85OHM_10INCH_DP")
	)
	(segment
		(start 333.711296 -166.12362)
		(end 333.5782 -166.03091)
		(width 0.1143)
		(layer "In9.Cu")
		(net "L10_85OHM_10INCH_DP")
	)
	(segment
		(start 357.947214 -165.996112)
		(end 357.684578 -166.04234)
		(width 0.1143)
		(layer "In9.Cu")
		(net "L10_85OHM_10INCH_DP")
	)
	(segment
		(start 368.87531 -163.817808)
		(end 369.250214 -165.944804)
		(width 0.1143)
		(layer "In9.Cu")
		(net "L10_85OHM_10INCH_DP")
	)
	(segment
		(start 325.69531 -163.816792)
		(end 326.074024 -165.964616)
		(width 0.1143)
		(layer "In9.Cu")
		(net "L10_85OHM_10INCH_DP")
	)
	(segment
		(start 334.066134 -165.944804)
		(end 333.973424 -166.0779)
		(width 0.1143)
		(layer "In9.Cu")
		(net "L10_85OHM_10INCH_DP")
	)
	(segment
		(start 354.485702 -166.037768)
		(end 354.353114 -165.945312)
		(width 0.1143)
		(layer "In9.Cu")
		(net "L10_85OHM_10INCH_DP")
	)
	(segment
		(start 370.494052 -166.124636)
		(end 370.361464 -166.03218)
		(width 0.1143)
		(layer "In9.Cu")
		(net "L10_85OHM_10INCH_DP")
	)
	(segment
		(start 324.096126 -163.816538)
		(end 324.475094 -165.963854)
		(width 0.1143)
		(layer "In9.Cu")
		(net "L10_85OHM_10INCH_DP")
	)
	(segment
		(start 353.149154 -165.99154)
		(end 352.886264 -166.037768)
		(width 0.1143)
		(layer "In9.Cu")
		(net "L10_85OHM_10INCH_DP")
	)
	(segment
		(start 331.224382 -163.394136)
		(end 330.72324 -163.481766)
		(width 0.1143)
		(layer "In9.Cu")
		(net "L10_85OHM_10INCH_DP")
	)
	(segment
		(start 326.074024 -165.964616)
		(end 325.981314 -166.097204)
		(width 0.1143)
		(layer "In9.Cu")
		(net "L10_85OHM_10INCH_DP")
	)
	(segment
		(start 368.761772 -166.030402)
		(end 368.34191 -163.656518)
		(width 0.1143)
		(layer "In9.Cu")
		(net "L10_85OHM_10INCH_DP")
	)
	(segment
		(start 329.62469 -163.38931)
		(end 329.123548 -163.477702)
		(width 0.1143)
		(layer "In9.Cu")
		(net "L10_85OHM_10INCH_DP")
	)
	(segment
		(start 359.637584 -165.855396)
		(end 359.545128 -165.98773)
		(width 0.1143)
		(layer "In9.Cu")
		(net "L10_85OHM_10INCH_DP")
	)
	(segment
		(start 325.92645 -163.48583)
		(end 325.69531 -163.816792)
		(width 0.1143)
		(layer "In9.Cu")
		(net "L10_85OHM_10INCH_DP")
	)
	(segment
		(start 344.346784 -163.610036)
		(end 344.015822 -163.377372)
		(width 0.1143)
		(layer "In9.Cu")
		(net "L10_85OHM_10INCH_DP")
	)
	(segment
		(start 351.288604 -166.04615)
		(end 351.156016 -165.953694)
		(width 0.1143)
		(layer "In9.Cu")
		(net "L10_85OHM_10INCH_DP")
	)
	(segment
		(start 333.68869 -163.804854)
		(end 334.066134 -165.944804)
		(width 0.1143)
		(layer "In9.Cu")
		(net "L10_85OHM_10INCH_DP")
	)
	(segment
		(start 328.918316 -166.148004)
		(end 328.785474 -166.054532)
		(width 0.1143)
		(layer "In9.Cu")
		(net "L10_85OHM_10INCH_DP")
	)
	(segment
		(start 381.554482 -166.025068)
		(end 381.126746 -163.599368)
		(width 0.1143)
		(layer "In9.Cu")
		(net "L10_85OHM_10INCH_DP")
	)
	(segment
		(start 354.353114 -165.945312)
		(end 353.942142 -163.617402)
		(width 0.1143)
		(layer "In9.Cu")
		(net "L10_85OHM_10INCH_DP")
	)
	(segment
		(start 322.780406 -166.080694)
		(end 322.51777 -166.126922)
		(width 0.1143)
		(layer "In9.Cu")
		(net "L10_85OHM_10INCH_DP")
	)
	(segment
		(start 375.553478 -166.074598)
		(end 375.290842 -166.12108)
		(width 0.1143)
		(layer "In9.Cu")
		(net "L10_85OHM_10INCH_DP")
	)
	(segment
		(start 327.524364 -163.477448)
		(end 327.293224 -163.80841)
		(width 0.1143)
		(layer "In9.Cu")
		(net "L10_85OHM_10INCH_DP")
	)
	(segment
		(start 341.91956 -163.489894)
		(end 341.68842 -163.821364)
		(width 0.1143)
		(layer "In9.Cu")
		(net "L10_85OHM_10INCH_DP")
	)
	(segment
		(start 324.382638 -166.096696)
		(end 324.120256 -166.142924)
		(width 0.1143)
		(layer "In9.Cu")
		(net "L10_85OHM_10INCH_DP")
	)
	(segment
		(start 375.997724 -163.362132)
		(end 375.496328 -163.450778)
		(width 0.1143)
		(layer "In9.Cu")
		(net "L10_85OHM_10INCH_DP")
	)
	(segment
		(start 344.885772 -163.81603)
		(end 345.2495 -165.879272)
		(width 0.1143)
		(layer "In9.Cu")
		(net "L10_85OHM_10INCH_DP")
	)
	(segment
		(start 350.745806 -163.625784)
		(end 350.415352 -163.394136)
		(width 0.1143)
		(layer "In9.Cu")
		(net "L10_85OHM_10INCH_DP")
	)
	(segment
		(start 343.650062 -165.879018)
		(end 343.55786 -166.011606)
		(width 0.1143)
		(layer "In9.Cu")
		(net "L10_85OHM_10INCH_DP")
	)
	(segment
		(start 338.365846 -165.969188)
		(end 337.955636 -163.641278)
		(width 0.1143)
		(layer "In9.Cu")
		(net "L10_85OHM_10INCH_DP")
	)
	(segment
		(start 359.508552 -163.479226)
		(end 359.276904 -163.810442)
		(width 0.1143)
		(layer "In9.Cu")
		(net "L10_85OHM_10INCH_DP")
	)
	(segment
		(start 348.817184 -163.402772)
		(end 348.315788 -163.491164)
		(width 0.1143)
		(layer "In9.Cu")
		(net "L10_85OHM_10INCH_DP")
	)
	(segment
		(start 356.809548 -163.382198)
		(end 356.308152 -163.470844)
		(width 0.1143)
		(layer "In9.Cu")
		(net "L10_85OHM_10INCH_DP")
	)
	(segment
		(start 332.466442 -165.940486)
		(end 332.373732 -166.073074)
		(width 0.1143)
		(layer "In9.Cu")
		(net "L10_85OHM_10INCH_DP")
	)
	(segment
		(start 353.611434 -163.386262)
		(end 353.1108 -163.4744)
		(width 0.1143)
		(layer "In9.Cu")
		(net "L10_85OHM_10INCH_DP")
	)
	(segment
		(start 364.345474 -166.007796)
		(end 364.082838 -166.054278)
		(width 0.1143)
		(layer "In9.Cu")
		(net "L10_85OHM_10INCH_DP")
	)
	(segment
		(start 341.562944 -165.960806)
		(end 341.151972 -163.632896)
		(width 0.1143)
		(layer "In9.Cu")
		(net "L10_85OHM_10INCH_DP")
	)
	(segment
		(start 364.07979 -163.842446)
		(end 364.438692 -165.8747)
		(width 0.1143)
		(layer "In9.Cu")
		(net "L10_85OHM_10INCH_DP")
	)
	(segment
		(start 356.085394 -166.042594)
		(end 355.952806 -165.949884)
		(width 0.1143)
		(layer "In9.Cu")
		(net "L10_85OHM_10INCH_DP")
	)
	(segment
		(start 344.015822 -163.377372)
		(end 343.514426 -163.466018)
		(width 0.1143)
		(layer "In9.Cu")
		(net "L10_85OHM_10INCH_DP")
	)
	(segment
		(start 381.948944 -166.070788)
		(end 381.686308 -166.11727)
		(width 0.1143)
		(layer "In9.Cu")
		(net "L10_85OHM_10INCH_DP")
	)
	(segment
		(start 339.963506 -165.960806)
		(end 339.554058 -163.632896)
		(width 0.1143)
		(layer "In9.Cu")
		(net "L10_85OHM_10INCH_DP")
	)
	(segment
		(start 337.25485 -165.882574)
		(end 337.162394 -166.015162)
		(width 0.1143)
		(layer "In9.Cu")
		(net "L10_85OHM_10INCH_DP")
	)
	(segment
		(start 335.519014 -163.473892)
		(end 335.287874 -163.804854)
		(width 0.1143)
		(layer "In9.Cu")
		(net "L10_85OHM_10INCH_DP")
	)
	(segment
		(start 335.287874 -163.804854)
		(end 335.663032 -165.932866)
		(width 0.1143)
		(layer "In9.Cu")
		(net "L10_85OHM_10INCH_DP")
	)
	(segment
		(start 371.959124 -166.023798)
		(end 371.53596 -163.617656)
		(width 0.1143)
		(layer "In9.Cu")
		(net "L10_85OHM_10INCH_DP")
	)
	(segment
		(start 343.55786 -166.011606)
		(end 343.295224 -166.058088)
		(width 0.1143)
		(layer "In9.Cu")
		(net "L10_85OHM_10INCH_DP")
	)
	(segment
		(start 382.398016 -163.383214)
		(end 381.89662 -163.471352)
		(width 0.1143)
		(layer "In9.Cu")
		(net "L10_85OHM_10INCH_DP")
	)
	(segment
		(start 379.196854 -163.367212)
		(end 378.695966 -163.454842)
		(width 0.1143)
		(layer "In9.Cu")
		(net "L10_85OHM_10INCH_DP")
	)
	(segment
		(start 323.229224 -163.392866)
		(end 322.728082 -163.481512)
		(width 0.1143)
		(layer "In9.Cu")
		(net "L10_85OHM_10INCH_DP")
	)
	(segment
		(start 352.344228 -163.617402)
		(end 352.012504 -163.386516)
		(width 0.1143)
		(layer "In9.Cu")
		(net "L10_85OHM_10INCH_DP")
	)
	(segment
		(start 373.134636 -163.621974)
		(end 372.803928 -163.390834)
		(width 0.1143)
		(layer "In9.Cu")
		(net "L10_85OHM_10INCH_DP")
	)
	(segment
		(start 330.4921 -163.812728)
		(end 330.867258 -165.940486)
		(width 0.1143)
		(layer "In9.Cu")
		(net "L10_85OHM_10INCH_DP")
	)
	(segment
		(start 348.084902 -163.82238)
		(end 348.446598 -165.871144)
		(width 0.1143)
		(layer "In9.Cu")
		(net "L10_85OHM_10INCH_DP")
	)
	(segment
		(start 341.68842 -163.821364)
		(end 342.050624 -165.874954)
		(width 0.1143)
		(layer "In9.Cu")
		(net "L10_85OHM_10INCH_DP")
	)
	(segment
		(start 367.54943 -166.038784)
		(end 367.286794 -166.085266)
		(width 0.1143)
		(layer "In9.Cu")
		(net "L10_85OHM_10INCH_DP")
	)
	(segment
		(start 378.695966 -163.454842)
		(end 378.464318 -163.786058)
		(width 0.1143)
		(layer "In9.Cu")
		(net "L10_85OHM_10INCH_DP")
	)
	(segment
		(start 360.00944 -163.391596)
		(end 359.508552 -163.479226)
		(width 0.1143)
		(layer "In9.Cu")
		(net "L10_85OHM_10INCH_DP")
	)
	(segment
		(start 357.675942 -163.800536)
		(end 358.03967 -165.863778)
		(width 0.1143)
		(layer "In9.Cu")
		(net "L10_85OHM_10INCH_DP")
	)
	(segment
		(start 351.551494 -165.999922)
		(end 351.288604 -166.04615)
		(width 0.1143)
		(layer "In9.Cu")
		(net "L10_85OHM_10INCH_DP")
	)
	(segment
		(start 340.358984 -166.007034)
		(end 340.096094 -166.053262)
		(width 0.1143)
		(layer "In9.Cu")
		(net "L10_85OHM_10INCH_DP")
	)
	(segment
		(start 371.204236 -163.38677)
		(end 370.703602 -163.474146)
		(width 0.1143)
		(layer "In9.Cu")
		(net "L10_85OHM_10INCH_DP")
	)
	(segment
		(start 335.317846 -166.118286)
		(end 335.175606 -166.018718)
		(width 0.1143)
		(layer "In9.Cu")
		(net "L10_85OHM_10INCH_DP")
	)
	(segment
		(start 343.282778 -163.796472)
		(end 343.650062 -165.879018)
		(width 0.1143)
		(layer "In9.Cu")
		(net "L10_85OHM_10INCH_DP")
	)
	(segment
		(start 367.51006 -163.513262)
		(end 367.278666 -163.844478)
		(width 0.1143)
		(layer "In9.Cu")
		(net "L10_85OHM_10INCH_DP")
	)
	(segment
		(start 365.676688 -163.828984)
		(end 366.04067 -165.890194)
		(width 0.1143)
		(layer "In9.Cu")
		(net "L10_85OHM_10INCH_DP")
	)
	(segment
		(start 354.748338 -165.991794)
		(end 354.485702 -166.037768)
		(width 0.1143)
		(layer "In9.Cu")
		(net "L10_85OHM_10INCH_DP")
	)
	(segment
		(start 349.913956 -163.482274)
		(end 349.682562 -163.81349)
		(width 0.1143)
		(layer "In9.Cu")
		(net "L10_85OHM_10INCH_DP")
	)
	(segment
		(start 345.2495 -165.879272)
		(end 345.157044 -166.011606)
		(width 0.1143)
		(layer "In9.Cu")
		(net "L10_85OHM_10INCH_DP")
	)
	(segment
		(start 372.354602 -166.070026)
		(end 372.091712 -166.116254)
		(width 0.1143)
		(layer "In9.Cu")
		(net "L10_85OHM_10INCH_DP")
	)
	(segment
		(start 356.34803 -165.996112)
		(end 356.085394 -166.042594)
		(width 0.1143)
		(layer "In9.Cu")
		(net "L10_85OHM_10INCH_DP")
	)
	(segment
		(start 364.082838 -166.054278)
		(end 363.951012 -165.962076)
		(width 0.1143)
		(layer "In9.Cu")
		(net "L10_85OHM_10INCH_DP")
	)
	(segment
		(start 345.94927 -163.629086)
		(end 345.618308 -163.3982)
		(width 0.1143)
		(layer "In9.Cu")
		(net "L10_85OHM_10INCH_DP")
	)
	(segment
		(start 375.290842 -166.12108)
		(end 375.158254 -166.02837)
		(width 0.1143)
		(layer "In9.Cu")
		(net "L10_85OHM_10INCH_DP")
	)
	(segment
		(start 357.140764 -163.614862)
		(end 356.809548 -163.382198)
		(width 0.1143)
		(layer "In9.Cu")
		(net "L10_85OHM_10INCH_DP")
	)
	(segment
		(start 368.895122 -166.12362)
		(end 368.761772 -166.030402)
		(width 0.1143)
		(layer "In9.Cu")
		(net "L10_85OHM_10INCH_DP")
	)
	(segment
		(start 321.501262 -164.769546)
		(end 321.384422 -164.652706)
		(width 0.1143)
		(layer "In9.Cu")
		(net "L10_85OHM_10INCH_DP")
	)
	(segment
		(start 376.328686 -163.594796)
		(end 375.997724 -163.362132)
		(width 0.1143)
		(layer "In9.Cu")
		(net "L10_85OHM_10INCH_DP")
	)
	(segment
		(start 365.947452 -166.02329)
		(end 365.684816 -166.069772)
		(width 0.1143)
		(layer "In9.Cu")
		(net "L10_85OHM_10INCH_DP")
	)
	(segment
		(start 342.751918 -163.634166)
		(end 342.420956 -163.40201)
		(width 0.1143)
		(layer "In9.Cu")
		(net "L10_85OHM_10INCH_DP")
	)
	(segment
		(start 380.79553 -163.367212)
		(end 380.294134 -163.455604)
		(width 0.1143)
		(layer "In9.Cu")
		(net "L10_85OHM_10INCH_DP")
	)
	(segment
		(start 361.144312 -165.987984)
		(end 360.881422 -166.034212)
		(width 0.1143)
		(layer "In9.Cu")
		(net "L10_85OHM_10INCH_DP")
	)
	(segment
		(start 338.7217 -163.489386)
		(end 338.490306 -163.821364)
		(width 0.1143)
		(layer "In9.Cu")
		(net "L10_85OHM_10INCH_DP")
	)
	(segment
		(start 354.840794 -165.85946)
		(end 354.748338 -165.991794)
		(width 0.1143)
		(layer "In9.Cu")
		(net "L10_85OHM_10INCH_DP")
	)
	(segment
		(start 330.379578 -166.02583)
		(end 329.955652 -163.62045)
		(width 0.1143)
		(layer "In9.Cu")
		(net "L10_85OHM_10INCH_DP")
	)
	(segment
		(start 343.514426 -163.466018)
		(end 343.282778 -163.796472)
		(width 0.1143)
		(layer "In9.Cu")
		(net "L10_85OHM_10INCH_DP")
	)
	(segment
		(start 374.734582 -163.623244)
		(end 374.40362 -163.391088)
		(width 0.1143)
		(layer "In9.Cu")
		(net "L10_85OHM_10INCH_DP")
	)
	(segment
		(start 369.113308 -163.47694)
		(end 368.87531 -163.817808)
		(width 0.1143)
		(layer "In9.Cu")
		(net "L10_85OHM_10INCH_DP")
	)
	(segment
		(start 382.042162 -165.937692)
		(end 381.948944 -166.070788)
		(width 0.1143)
		(layer "In9.Cu")
		(net "L10_85OHM_10INCH_DP")
	)
	(segment
		(start 372.447312 -165.937438)
		(end 372.354602 -166.070026)
		(width 0.1143)
		(layer "In9.Cu")
		(net "L10_85OHM_10INCH_DP")
	)
	(segment
		(start 351.156016 -165.953694)
		(end 350.745806 -163.625784)
		(width 0.1143)
		(layer "In9.Cu")
		(net "L10_85OHM_10INCH_DP")
	)
	(segment
		(start 381.126746 -163.599368)
		(end 380.79553 -163.367212)
		(width 0.1143)
		(layer "In9.Cu")
		(net "L10_85OHM_10INCH_DP")
	)
	(segment
		(start 370.361464 -166.03218)
		(end 369.9383 -163.630356)
		(width 0.1143)
		(layer "In9.Cu")
		(net "L10_85OHM_10INCH_DP")
	)
	(segment
		(start 337.955636 -163.641278)
		(end 337.615276 -163.402772)
		(width 0.1143)
		(layer "In9.Cu")
		(net "L10_85OHM_10INCH_DP")
	)
	(segment
		(start 336.899758 -166.06139)
		(end 336.76717 -165.96868)
		(width 0.1143)
		(layer "In9.Cu")
		(net "L10_85OHM_10INCH_DP")
	)
	(segment
		(start 366.409478 -163.40963)
		(end 365.908082 -163.497768)
		(width 0.1143)
		(layer "In9.Cu")
		(net "L10_85OHM_10INCH_DP")
	)
	(segment
		(start 360.74858 -165.941502)
		(end 360.340402 -163.622736)
		(width 0.1143)
		(layer "In9.Cu")
		(net "L10_85OHM_10INCH_DP")
	)
	(segment
		(start 336.76717 -165.96868)
		(end 336.351118 -163.616894)
		(width 0.1143)
		(layer "In9.Cu")
		(net "L10_85OHM_10INCH_DP")
	)
	(segment
		(start 337.615276 -163.402772)
		(end 337.130644 -163.487862)
		(width 0.1143)
		(layer "In9.Cu")
		(net "L10_85OHM_10INCH_DP")
	)
	(segment
		(start 364.438692 -165.8747)
		(end 364.345474 -166.007796)
		(width 0.1143)
		(layer "In9.Cu")
		(net "L10_85OHM_10INCH_DP")
	)
	(segment
		(start 328.785474 -166.054532)
		(end 328.35596 -163.620704)
		(width 0.1143)
		(layer "In9.Cu")
		(net "L10_85OHM_10INCH_DP")
	)
	(segment
		(start 378.48794 -166.112444)
		(end 378.355098 -166.019734)
		(width 0.1143)
		(layer "In9.Cu")
		(net "L10_85OHM_10INCH_DP")
	)
	(segment
		(start 370.703602 -163.474146)
		(end 370.472208 -163.806124)
		(width 0.1143)
		(layer "In9.Cu")
		(net "L10_85OHM_10INCH_DP")
	)
	(segment
		(start 376.890026 -166.120826)
		(end 376.757946 -166.02837)
		(width 0.1143)
		(layer "In9.Cu")
		(net "L10_85OHM_10INCH_DP")
	)
	(segment
		(start 329.180952 -166.101522)
		(end 328.918316 -166.148004)
		(width 0.1143)
		(layer "In9.Cu")
		(net "L10_85OHM_10INCH_DP")
	)
	(segment
		(start 357.684578 -166.04234)
		(end 357.552498 -165.949884)
		(width 0.1143)
		(layer "In9.Cu")
		(net "L10_85OHM_10INCH_DP")
	)
	(segment
		(start 346.71762 -163.490402)
		(end 346.485972 -163.821618)
		(width 0.1143)
		(layer "In9.Cu")
		(net "L10_85OHM_10INCH_DP")
	)
	(segment
		(start 380.34976 -166.06647)
		(end 380.08687 -166.112698)
		(width 0.1143)
		(layer "In9.Cu")
		(net "L10_85OHM_10INCH_DP")
	)
	(segment
		(start 377.152662 -166.074598)
		(end 376.890026 -166.120826)
		(width 0.1143)
		(layer "In9.Cu")
		(net "L10_85OHM_10INCH_DP")
	)
	(segment
		(start 382.833118 -164.20846)
		(end 382.728724 -163.614862)
		(width 0.1143)
		(layer "In9.Cu")
		(net "L10_85OHM_10INCH_DP")
	)
	(segment
		(start 322.873116 -165.948106)
		(end 322.780406 -166.080694)
		(width 0.1143)
		(layer "In9.Cu")
		(net "L10_85OHM_10INCH_DP")
	)
	(segment
		(start 351.280476 -163.80587)
		(end 351.644204 -165.867334)
		(width 0.1143)
		(layer "In9.Cu")
		(net "L10_85OHM_10INCH_DP")
	)
	(segment
		(start 335.563718 -166.075106)
		(end 335.317846 -166.118286)
		(width 0.1143)
		(layer "In9.Cu")
		(net "L10_85OHM_10INCH_DP")
	)
	(segment
		(start 359.276904 -163.810442)
		(end 359.637584 -165.855396)
		(width 0.1143)
		(layer "In9.Cu")
		(net "L10_85OHM_10INCH_DP")
	)
	(segment
		(start 369.59794 -163.39185)
		(end 369.113308 -163.47694)
		(width 0.1143)
		(layer "In9.Cu")
		(net "L10_85OHM_10INCH_DP")
	)
	(segment
		(start 355.211126 -163.386516)
		(end 354.70973 -163.4744)
		(width 0.1143)
		(layer "In9.Cu")
		(net "L10_85OHM_10INCH_DP")
	)
	(segment
		(start 373.69115 -166.116254)
		(end 373.558562 -166.023798)
		(width 0.1143)
		(layer "In9.Cu")
		(net "L10_85OHM_10INCH_DP")
	)
	(segment
		(start 363.951012 -165.962076)
		(end 363.540548 -163.634928)
		(width 0.1143)
		(layer "In9.Cu")
		(net "L10_85OHM_10INCH_DP")
	)
	(segment
		(start 338.854034 -165.882828)
		(end 338.761324 -166.015416)
		(width 0.1143)
		(layer "In9.Cu")
		(net "L10_85OHM_10INCH_DP")
	)
	(segment
		(start 330.51242 -166.119048)
		(end 330.379578 -166.02583)
		(width 0.1143)
		(layer "In9.Cu")
		(net "L10_85OHM_10INCH_DP")
	)
	(segment
		(start 371.53596 -163.617656)
		(end 371.204236 -163.38677)
		(width 0.1143)
		(layer "In9.Cu")
		(net "L10_85OHM_10INCH_DP")
	)
	(segment
		(start 326.759062 -163.629086)
		(end 326.427846 -163.397946)
		(width 0.1143)
		(layer "In9.Cu")
		(net "L10_85OHM_10INCH_DP")
	)
	(segment
		(start 343.162636 -165.965378)
		(end 342.751918 -163.634166)
		(width 0.1143)
		(layer "In9.Cu")
		(net "L10_85OHM_10INCH_DP")
	)
	(segment
		(start 340.096094 -166.053262)
		(end 339.963506 -165.960806)
		(width 0.1143)
		(layer "In9.Cu")
		(net "L10_85OHM_10INCH_DP")
	)
	(segment
		(start 372.0719 -163.810188)
		(end 372.447312 -165.937438)
		(width 0.1143)
		(layer "In9.Cu")
		(net "L10_85OHM_10INCH_DP")
	)
	(segment
		(start 360.340402 -163.622736)
		(end 360.00944 -163.391596)
		(width 0.1143)
		(layer "In9.Cu")
		(net "L10_85OHM_10INCH_DP")
	)
	(segment
		(start 335.663032 -165.932866)
		(end 335.563718 -166.075106)
		(width 0.1143)
		(layer "In9.Cu")
		(net "L10_85OHM_10INCH_DP")
	)
	(segment
		(start 346.847414 -165.87089)
		(end 346.754958 -166.003224)
		(width 0.1143)
		(layer "In9.Cu")
		(net "L10_85OHM_10INCH_DP")
	)
	(segment
		(start 360.875072 -163.806886)
		(end 361.236768 -165.85565)
		(width 0.1143)
		(layer "In9.Cu")
		(net "L10_85OHM_10INCH_DP")
	)
	(segment
		(start 327.18629 -166.055294)
		(end 326.759062 -163.629086)
		(width 0.1143)
		(layer "In9.Cu")
		(net "L10_85OHM_10INCH_DP")
	)
	(segment
		(start 330.867258 -165.940486)
		(end 330.774802 -166.073074)
		(width 0.1143)
		(layer "In9.Cu")
		(net "L10_85OHM_10INCH_DP")
	)
	(segment
		(start 380.063248 -163.787074)
		(end 380.442216 -165.934136)
		(width 0.1143)
		(layer "In9.Cu")
		(net "L10_85OHM_10INCH_DP")
	)
	(segment
		(start 331.97927 -166.026846)
		(end 331.555344 -163.625022)
		(width 0.1143)
		(layer "In9.Cu")
		(net "L10_85OHM_10INCH_DP")
	)
	(segment
		(start 378.464318 -163.786058)
		(end 378.843032 -165.933882)
		(width 0.1143)
		(layer "In9.Cu")
		(net "L10_85OHM_10INCH_DP")
	)
	(segment
		(start 327.58126 -166.101776)
		(end 327.318878 -166.14775)
		(width 0.1143)
		(layer "In9.Cu")
		(net "L10_85OHM_10INCH_DP")
	)
	(segment
		(start 361.236768 -165.85565)
		(end 361.144312 -165.987984)
		(width 0.1143)
		(layer "In9.Cu")
		(net "L10_85OHM_10INCH_DP")
	)
	(segment
		(start 325.586344 -166.050468)
		(end 325.159878 -163.628832)
		(width 0.1143)
		(layer "In9.Cu")
		(net "L10_85OHM_10INCH_DP")
	)
	(segment
		(start 323.559424 -163.624006)
		(end 323.229224 -163.392866)
		(width 0.1143)
		(layer "In9.Cu")
		(net "L10_85OHM_10INCH_DP")
	)
	(segment
		(start 348.354142 -166.003478)
		(end 348.091252 -166.049706)
		(width 0.1143)
		(layer "In9.Cu")
		(net "L10_85OHM_10INCH_DP")
	)
	(segment
		(start 329.273662 -165.969188)
		(end 329.180952 -166.101522)
		(width 0.1143)
		(layer "In9.Cu")
		(net "L10_85OHM_10INCH_DP")
	)
	(segment
		(start 329.123548 -163.477702)
		(end 328.892662 -163.808156)
		(width 0.1143)
		(layer "In9.Cu")
		(net "L10_85OHM_10INCH_DP")
	)
	(segment
		(start 355.542088 -163.618672)
		(end 355.211126 -163.386516)
		(width 0.1143)
		(layer "In9.Cu")
		(net "L10_85OHM_10INCH_DP")
	)
	(segment
		(start 377.927616 -163.593526)
		(end 377.596654 -163.36264)
		(width 0.1143)
		(layer "In9.Cu")
		(net "L10_85OHM_10INCH_DP")
	)
	(segment
		(start 362.349034 -165.946582)
		(end 361.93857 -163.619434)
		(width 0.1143)
		(layer "In9.Cu")
		(net "L10_85OHM_10INCH_DP")
	)
	(segment
		(start 357.552498 -165.949884)
		(end 357.140764 -163.614862)
		(width 0.1143)
		(layer "In9.Cu")
		(net "L10_85OHM_10INCH_DP")
	)
	(segment
		(start 372.091712 -166.116254)
		(end 371.959124 -166.023798)
		(width 0.1143)
		(layer "In9.Cu")
		(net "L10_85OHM_10INCH_DP")
	)
	(segment
		(start 347.218508 -163.402772)
		(end 346.71762 -163.490402)
		(width 0.1143)
		(layer "In9.Cu")
		(net "L10_85OHM_10INCH_DP")
	)
	(segment
		(start 375.496328 -163.450778)
		(end 375.26468 -163.781232)
		(width 0.1143)
		(layer "In9.Cu")
		(net "L10_85OHM_10INCH_DP")
	)
	(segment
		(start 380.08687 -166.112698)
		(end 379.954028 -166.019988)
		(width 0.1143)
		(layer "In9.Cu")
		(net "L10_85OHM_10INCH_DP")
	)
	(segment
		(start 358.408478 -163.382706)
		(end 357.908352 -163.470336)
		(width 0.1143)
		(layer "In9.Cu")
		(net "L10_85OHM_10INCH_DP")
	)
	(segment
		(start 378.750576 -166.066216)
		(end 378.48794 -166.112444)
		(width 0.1143)
		(layer "In9.Cu")
		(net "L10_85OHM_10INCH_DP")
	)
	(segment
		(start 383.462784 -164.645594)
		(end 383.336292 -164.772086)
		(width 0.1143)
		(layer "In9.Cu")
		(net "L10_85OHM_10INCH_DP")
	)
	(segment
		(start 321.716146 -164.769546)
		(end 321.501262 -164.769546)
		(width 0.1143)
		(layer "In9.Cu")
		(net "L10_85OHM_10INCH_DP")
	)
	(segment
		(start 379.527816 -163.598352)
		(end 379.196854 -163.367212)
		(width 0.1143)
		(layer "In9.Cu")
		(net "L10_85OHM_10INCH_DP")
	)
	(segment
		(start 334.752442 -163.61664)
		(end 334.42148 -163.385754)
		(width 0.1143)
		(layer "In9.Cu")
		(net "L10_85OHM_10INCH_DP")
	)
	(segment
		(start 376.864118 -163.78047)
		(end 377.245118 -165.942264)
		(width 0.1143)
		(layer "In9.Cu")
		(net "L10_85OHM_10INCH_DP")
	)
	(segment
		(start 349.1484 -163.634928)
		(end 348.817184 -163.402772)
		(width 0.1143)
		(layer "In9.Cu")
		(net "L10_85OHM_10INCH_DP")
	)
	(segment
		(start 352.012504 -163.386516)
		(end 351.51187 -163.473892)
		(width 0.1143)
		(layer "In9.Cu")
		(net "L10_85OHM_10INCH_DP")
	)
	(segment
		(start 328.892662 -163.808156)
		(end 329.273662 -165.969188)
		(width 0.1143)
		(layer "In9.Cu")
		(net "L10_85OHM_10INCH_DP")
	)
	(segment
		(start 362.743496 -165.992302)
		(end 362.48086 -166.038784)
		(width 0.1143)
		(layer "In9.Cu")
		(net "L10_85OHM_10INCH_DP")
	)
	(segment
		(start 362.48086 -166.038784)
		(end 362.349034 -165.946582)
		(width 0.1143)
		(layer "In9.Cu")
		(net "L10_85OHM_10INCH_DP")
	)
	(segment
		(start 326.427846 -163.397946)
		(end 325.92645 -163.48583)
		(width 0.1143)
		(layer "In9.Cu")
		(net "L10_85OHM_10INCH_DP")
	)
	(segment
		(start 323.987414 -166.049706)
		(end 323.559424 -163.624006)
		(width 0.1143)
		(layer "In9.Cu")
		(net "L10_85OHM_10INCH_DP")
	)
	(segment
		(start 342.420956 -163.40201)
		(end 341.91956 -163.489894)
		(width 0.1143)
		(layer "In9.Cu")
		(net "L10_85OHM_10INCH_DP")
	)
	(segment
		(start 325.981314 -166.097204)
		(end 325.718932 -166.143178)
		(width 0.1143)
		(layer "In9.Cu")
		(net "L10_85OHM_10INCH_DP")
	)
	(segment
		(start 372.803928 -163.390834)
		(end 372.303294 -163.478972)
		(width 0.1143)
		(layer "In9.Cu")
		(net "L10_85OHM_10INCH_DP")
	)
	(segment
		(start 381.665226 -163.802568)
		(end 382.042162 -165.937692)
		(width 0.1143)
		(layer "In9.Cu")
		(net "L10_85OHM_10INCH_DP")
	)
	(segment
		(start 347.54947 -163.633912)
		(end 347.218508 -163.402772)
		(width 0.1143)
		(layer "In9.Cu")
		(net "L10_85OHM_10INCH_DP")
	)
	(segment
		(start 322.240148 -165.312852)
		(end 321.98691 -164.975286)
		(width 0.1143)
		(layer "In9.Cu")
		(net "L10_85OHM_10INCH_DP")
	)
	(segment
		(start 349.682562 -163.81349)
		(end 350.046544 -165.8747)
		(width 0.1143)
		(layer "In9.Cu")
		(net "L10_85OHM_10INCH_DP")
	)
	(segment
		(start 332.82382 -163.394136)
		(end 332.322424 -163.48202)
		(width 0.1143)
		(layer "In9.Cu")
		(net "L10_85OHM_10INCH_DP")
	)
	(segment
		(start 332.111604 -166.119302)
		(end 331.97927 -166.026846)
		(width 0.1143)
		(layer "In9.Cu")
		(net "L10_85OHM_10INCH_DP")
	)
	(segment
		(start 361.607354 -163.387278)
		(end 361.105958 -163.47567)
		(width 0.1143)
		(layer "In9.Cu")
		(net "L10_85OHM_10INCH_DP")
	)
	(segment
		(start 338.498434 -166.061644)
		(end 338.365846 -165.969188)
		(width 0.1143)
		(layer "In9.Cu")
		(net "L10_85OHM_10INCH_DP")
	)
	(segment
		(start 358.03967 -165.863778)
		(end 357.947214 -165.996112)
		(width 0.1143)
		(layer "In9.Cu")
		(net "L10_85OHM_10INCH_DP")
	)
	(segment
		(start 354.47859 -163.80587)
		(end 354.840794 -165.85946)
		(width 0.1143)
		(layer "In9.Cu")
		(net "L10_85OHM_10INCH_DP")
	)
	(segment
		(start 321.98691 -164.975286)
		(end 321.716146 -164.769546)
		(width 0.1143)
		(layer "In9.Cu")
		(net "L10_85OHM_10INCH_DP")
	)
	(segment
		(start 359.282492 -166.033958)
		(end 359.14965 -165.941248)
		(width 0.1143)
		(layer "In9.Cu")
		(net "L10_85OHM_10INCH_DP")
	)
	(segment
		(start 363.540548 -163.634928)
		(end 363.20984 -163.40328)
		(width 0.1143)
		(layer "In9.Cu")
		(net "L10_85OHM_10INCH_DP")
	)
	(segment
		(start 336.892646 -163.82873)
		(end 337.25485 -165.882574)
		(width 0.1143)
		(layer "In9.Cu")
		(net "L10_85OHM_10INCH_DP")
	)
	(segment
		(start 338.761324 -166.015416)
		(end 338.498434 -166.061644)
		(width 0.1143)
		(layer "In9.Cu")
		(net "L10_85OHM_10INCH_DP")
	)
	(segment
		(start 363.20984 -163.40328)
		(end 362.708444 -163.491418)
		(width 0.1143)
		(layer "In9.Cu")
		(net "L10_85OHM_10INCH_DP")
	)
	(segment
		(start 352.879406 -163.805616)
		(end 353.241864 -165.858952)
		(width 0.1143)
		(layer "In9.Cu")
		(net "L10_85OHM_10INCH_DP")
	)
	(segment
		(start 322.49618 -163.812728)
		(end 322.873116 -165.948106)
		(width 0.1143)
		(layer "In9.Cu")
		(net "L10_85OHM_10INCH_DP")
	)
	(segment
		(start 334.42148 -163.385754)
		(end 333.920084 -163.473638)
		(width 0.1143)
		(layer "In9.Cu")
		(net "L10_85OHM_10INCH_DP")
	)
	(segment
		(start 322.300092 -165.549072)
		(end 322.240148 -165.312852)
		(width 0.1143)
		(layer "In9.Cu")
		(net "L10_85OHM_10INCH_DP")
	)
	(segment
		(start 365.143288 -163.65474)
		(end 364.81258 -163.423092)
		(width 0.1143)
		(layer "In9.Cu")
		(net "L10_85OHM_10INCH_DP")
	)
	(segment
		(start 339.222334 -163.40201)
		(end 338.7217 -163.489386)
		(width 0.1143)
		(layer "In9.Cu")
		(net "L10_85OHM_10INCH_DP")
	)
	(segment
		(start 345.618308 -163.3982)
		(end 345.118182 -163.48583)
		(width 0.1143)
		(layer "In9.Cu")
		(net "L10_85OHM_10INCH_DP")
	)
	(segment
		(start 375.26468 -163.781232)
		(end 375.64568 -165.94201)
		(width 0.1143)
		(layer "In9.Cu")
		(net "L10_85OHM_10INCH_DP")
	)
	(segment
		(start 324.828662 -163.397692)
		(end 324.327266 -163.485576)
		(width 0.1143)
		(layer "In9.Cu")
		(net "L10_85OHM_10INCH_DP")
	)
	(segment
		(start 373.953786 -166.07028)
		(end 373.69115 -166.116254)
		(width 0.1143)
		(layer "In9.Cu")
		(net "L10_85OHM_10INCH_DP")
	)
	(segment
		(start 365.684816 -166.069772)
		(end 365.55299 -165.97757)
		(width 0.1143)
		(layer "In9.Cu")
		(net "L10_85OHM_10INCH_DP")
	)
	(segment
		(start 340.32063 -163.489894)
		(end 340.089236 -163.82111)
		(width 0.1143)
		(layer "In9.Cu")
		(net "L10_85OHM_10INCH_DP")
	)
	(segment
		(start 333.920084 -163.473638)
		(end 333.68869 -163.804854)
		(width 0.1143)
		(layer "In9.Cu")
		(net "L10_85OHM_10INCH_DP")
	)
	(segment
		(start 333.5782 -166.03091)
		(end 333.154782 -163.625022)
		(width 0.1143)
		(layer "In9.Cu")
		(net "L10_85OHM_10INCH_DP")
	)
	(segment
		(start 337.130644 -163.487862)
		(end 336.892646 -163.82873)
		(width 0.1143)
		(layer "In9.Cu")
		(net "L10_85OHM_10INCH_DP")
	)
	(segment
		(start 383.174494 -164.779706)
		(end 383.002028 -164.637212)
		(width 0.1143)
		(layer "In9.Cu")
		(net "L10_85OHM_10INCH_DP")
	)
	(segment
		(start 333.973424 -166.0779)
		(end 333.711296 -166.12362)
		(width 0.1143)
		(layer "In9.Cu")
		(net "L10_85OHM_10INCH_DP")
	)
	(segment
		(start 356.440232 -165.863524)
		(end 356.34803 -165.996112)
		(width 0.1143)
		(layer "In9.Cu")
		(net "L10_85OHM_10INCH_DP")
	)
	(segment
		(start 383.462784 -164.143944)
		(end 383.462784 -164.645594)
		(width 0.1143)
		(layer "In9.Cu")
		(net "L10_85OHM_10INCH_DP")
	)
	(segment
		(start 380.294134 -163.455604)
		(end 380.063248 -163.787074)
		(width 0.1143)
		(layer "In9.Cu")
		(net "L10_85OHM_10INCH_DP")
	)
	(segment
		(start 360.881422 -166.034212)
		(end 360.74858 -165.941502)
		(width 0.1143)
		(layer "In9.Cu")
		(net "L10_85OHM_10INCH_DP")
	)
	(segment
		(start 324.475094 -165.963854)
		(end 324.382638 -166.096696)
		(width 0.1143)
		(layer "In9.Cu")
		(net "L10_85OHM_10INCH_DP")
	)
	(segment
		(start 345.118182 -163.48583)
		(end 344.885772 -163.81603)
		(width 0.1143)
		(layer "In9.Cu")
		(net "L10_85OHM_10INCH_DP")
	)
	(segment
		(start 358.73944 -163.613592)
		(end 358.408478 -163.382706)
		(width 0.1143)
		(layer "In9.Cu")
		(net "L10_85OHM_10INCH_DP")
	)
	(segment
		(start 375.64568 -165.94201)
		(end 375.553478 -166.074598)
		(width 0.1143)
		(layer "In9.Cu")
		(net "L10_85OHM_10INCH_DP")
	)
	(segment
		(start 378.355098 -166.019734)
		(end 377.927616 -163.593526)
		(width 0.1143)
		(layer "In9.Cu")
		(net "L10_85OHM_10INCH_DP")
	)
	(segment
		(start 359.545128 -165.98773)
		(end 359.282492 -166.033958)
		(width 0.1143)
		(layer "In9.Cu")
		(net "L10_85OHM_10INCH_DP")
	)
	(segment
		(start 382.91135 -164.516308)
		(end 382.833118 -164.20846)
		(width 0.1143)
		(layer "In9.Cu")
		(net "L10_85OHM_10INCH_DP")
	)
	(segment
		(start 373.671084 -163.810442)
		(end 374.046242 -165.937946)
		(width 0.1143)
		(layer "In9.Cu")
		(net "L10_85OHM_10INCH_DP")
	)
	(segment
		(start 376.757946 -166.02837)
		(end 376.328686 -163.594796)
		(width 0.1143)
		(layer "In9.Cu")
		(net "L10_85OHM_10INCH_DP")
	)
	(segment
		(start 362.47705 -163.82238)
		(end 362.836714 -165.859206)
		(width 0.1143)
		(layer "In9.Cu")
		(net "L10_85OHM_10INCH_DP")
	)
	(segment
		(start 343.295224 -166.058088)
		(end 343.162636 -165.965378)
		(width 0.1143)
		(layer "In9.Cu")
		(net "L10_85OHM_10INCH_DP")
	)
	(segment
		(start 346.35948 -165.956742)
		(end 345.94927 -163.629086)
		(width 0.1143)
		(layer "In9.Cu")
		(net "L10_85OHM_10INCH_DP")
	)
	(segment
		(start 344.762328 -165.965378)
		(end 344.346784 -163.610036)
		(width 0.1143)
		(layer "In9.Cu")
		(net "L10_85OHM_10INCH_DP")
	)
	(segment
		(start 353.241864 -165.858952)
		(end 353.149154 -165.99154)
		(width 0.1143)
		(layer "In9.Cu")
		(net "L10_85OHM_10INCH_DP")
	)
	(segment
		(start 330.774802 -166.073074)
		(end 330.51242 -166.119048)
		(width 0.1143)
		(layer "In9.Cu")
		(net "L10_85OHM_10INCH_DP")
	)
	(segment
		(start 378.843032 -165.933882)
		(end 378.750576 -166.066216)
		(width 0.1143)
		(layer "In9.Cu")
		(net "L10_85OHM_10INCH_DP")
	)
	(segment
		(start 325.718932 -166.143178)
		(end 325.586344 -166.050468)
		(width 0.1143)
		(layer "In9.Cu")
		(net "L10_85OHM_10INCH_DP")
	)
	(segment
		(start 350.415352 -163.394136)
		(end 349.913956 -163.482274)
		(width 0.1143)
		(layer "In9.Cu")
		(net "L10_85OHM_10INCH_DP")
	)
	(segment
		(start 341.695532 -166.053262)
		(end 341.562944 -165.960806)
		(width 0.1143)
		(layer "In9.Cu")
		(net "L10_85OHM_10INCH_DP")
	)
	(segment
		(start 348.091252 -166.049706)
		(end 347.95841 -165.956996)
		(width 0.1143)
		(layer "In9.Cu")
		(net "L10_85OHM_10INCH_DP")
	)
	(segment
		(start 381.686308 -166.11727)
		(end 381.554482 -166.025068)
		(width 0.1143)
		(layer "In9.Cu")
		(net "L10_85OHM_10INCH_DP")
	)
	(segment
		(start 351.51187 -163.473892)
		(end 351.280476 -163.80587)
		(width 0.1143)
		(layer "In9.Cu")
		(net "L10_85OHM_10INCH_DP")
	)
	(segment
		(start 383.002028 -164.637212)
		(end 382.91135 -164.516308)
		(width 0.1143)
		(layer "In9.Cu")
		(net "L10_85OHM_10INCH_DP")
	)
	(segment
		(start 367.278666 -163.844478)
		(end 367.642648 -165.905688)
		(width 0.1143)
		(layer "In9.Cu")
		(net "L10_85OHM_10INCH_DP")
	)
	(segment
		(start 362.836714 -165.859206)
		(end 362.743496 -165.992302)
		(width 0.1143)
		(layer "In9.Cu")
		(net "L10_85OHM_10INCH_DP")
	)
	(segment
		(start 335.175606 -166.018718)
		(end 334.752442 -163.61664)
		(width 0.1143)
		(layer "In9.Cu")
		(net "L10_85OHM_10INCH_DP")
	)
	(segment
		(start 375.158254 -166.02837)
		(end 374.734582 -163.623244)
		(width 0.1143)
		(layer "In9.Cu")
		(net "L10_85OHM_10INCH_DP")
	)
	(segment
		(start 322.385436 -166.034212)
		(end 322.300092 -165.549072)
		(width 0.1143)
		(layer "In9.Cu")
		(net "L10_85OHM_10INCH_DP")
	)
	(segment
		(start 374.046242 -165.937946)
		(end 373.953786 -166.07028)
		(width 0.1143)
		(layer "In9.Cu")
		(net "L10_85OHM_10INCH_DP")
	)
	(segment
		(start 364.311184 -163.51123)
		(end 364.07979 -163.842446)
		(width 0.1143)
		(layer "In9.Cu")
		(net "L10_85OHM_10INCH_DP")
	)
	(segment
		(start 353.1108 -163.4744)
		(end 352.879406 -163.805616)
		(width 0.1143)
		(layer "In9.Cu")
		(net "L10_85OHM_10INCH_DP")
	)
	(segment
		(start 321.384422 -164.652706)
		(end 321.384422 -164.151056)
		(width 0.1143)
		(layer "In9.Cu")
		(net "L10_85OHM_10INCH_DP")
	)
	(segment
		(start 322.51777 -166.126922)
		(end 322.385436 -166.034212)
		(width 0.1143)
		(layer "In9.Cu")
		(net "L10_85OHM_10INCH_DP")
	)
	(segment
		(start 344.894408 -166.057834)
		(end 344.762328 -165.965378)
		(width 0.1143)
		(layer "In9.Cu")
		(net "L10_85OHM_10INCH_DP")
	)
	(segment
		(start 359.14965 -165.941248)
		(end 358.73944 -163.613592)
		(width 0.1143)
		(layer "In9.Cu")
		(net "L10_85OHM_10INCH_DP")
	)
	(segment
		(start 339.554058 -163.632896)
		(end 339.222334 -163.40201)
		(width 0.1143)
		(layer "In9.Cu")
		(net "L10_85OHM_10INCH_DP")
	)
	(segment
		(start 370.756942 -166.078408)
		(end 370.494052 -166.124636)
		(width 0.1143)
		(layer "In9.Cu")
		(net "L10_85OHM_10INCH_DP")
	)
	(segment
		(start 351.644204 -165.867334)
		(end 351.551494 -165.999922)
		(width 0.1143)
		(layer "In9.Cu")
		(net "L10_85OHM_10INCH_DP")
	)
	(segment
		(start 361.105958 -163.47567)
		(end 360.875072 -163.806886)
		(width 0.1143)
		(layer "In9.Cu")
		(net "L10_85OHM_10INCH_DP")
	)
	(segment
		(start 372.303294 -163.478972)
		(end 372.0719 -163.810188)
		(width 0.1143)
		(layer "In9.Cu")
		(net "L10_85OHM_10INCH_DP")
	)
	(segment
		(start 352.753676 -165.945312)
		(end 352.344228 -163.617402)
		(width 0.1143)
		(layer "In9.Cu")
		(net "L10_85OHM_10INCH_DP")
	)
	(segment
		(start 346.754958 -166.003224)
		(end 346.492322 -166.049452)
		(width 0.1143)
		(layer "In9.Cu")
		(net "L10_85OHM_10INCH_DP")
	)
	(segment
		(start 370.849652 -165.94582)
		(end 370.756942 -166.078408)
		(width 0.1143)
		(layer "In9.Cu")
		(net "L10_85OHM_10INCH_DP")
	)
	(segment
		(start 368.011456 -163.425124)
		(end 367.51006 -163.513262)
		(width 0.1143)
		(layer "In9.Cu")
		(net "L10_85OHM_10INCH_DP")
	)
	(segment
		(start 341.958168 -166.007288)
		(end 341.695532 -166.053262)
		(width 0.1143)
		(layer "In9.Cu")
		(net "L10_85OHM_10INCH_DP")
	)
	(segment
		(start 355.952806 -165.949884)
		(end 355.542088 -163.618672)
		(width 0.1143)
		(layer "In9.Cu")
		(net "L10_85OHM_10INCH_DP")
	)
	(segment
		(start 328.35596 -163.620704)
		(end 328.02576 -163.38931)
		(width 0.1143)
		(layer "In9.Cu")
		(net "L10_85OHM_10INCH_DP")
	)
	(segment
		(start 366.740186 -163.641278)
		(end 366.409478 -163.40963)
		(width 0.1143)
		(layer "In9.Cu")
		(net "L10_85OHM_10INCH_DP")
	)
	(segment
		(start 365.908082 -163.497768)
		(end 365.676688 -163.828984)
		(width 0.1143)
		(layer "In9.Cu")
		(net "L10_85OHM_10INCH_DP")
	)
	(segment
		(start 322.728082 -163.481512)
		(end 322.49618 -163.812728)
		(width 0.1143)
		(layer "In9.Cu")
		(net "L10_85OHM_10INCH_DP")
	)
	(segment
		(start 348.315788 -163.491164)
		(end 348.084902 -163.82238)
		(width 0.1143)
		(layer "In9.Cu")
		(net "L10_85OHM_10INCH_DP")
	)
	(segment
		(start 356.076504 -163.801298)
		(end 356.440232 -165.863524)
		(width 0.1143)
		(layer "In9.Cu")
		(net "L10_85OHM_10INCH_DP")
	)
	(segment
		(start 368.34191 -163.656518)
		(end 368.011456 -163.425124)
		(width 0.1143)
		(layer "In9.Cu")
		(net "L10_85OHM_10INCH_DP")
	)
	(segment
		(start 369.250214 -165.944804)
		(end 369.157758 -166.077392)
		(width 0.1143)
		(layer "In9.Cu")
		(net "L10_85OHM_10INCH_DP")
	)
	(segment
		(start 336.020156 -163.385754)
		(end 335.519014 -163.473892)
		(width 0.1143)
		(layer "In9.Cu")
		(net "L10_85OHM_10INCH_DP")
	)
	(segment
		(start 354.70973 -163.4744)
		(end 354.47859 -163.80587)
		(width 0.1143)
		(layer "In9.Cu")
		(net "L10_85OHM_10INCH_DP")
	)
	(segment
		(start 349.558864 -165.962076)
		(end 349.1484 -163.634928)
		(width 0.1143)
		(layer "In9.Cu")
		(net "L10_85OHM_10INCH_DP")
	)
	(segment
		(start 373.902224 -163.478972)
		(end 373.671084 -163.810442)
		(width 0.1143)
		(layer "In9.Cu")
		(net "L10_85OHM_10INCH_DP")
	)
	(segment
		(start 340.451694 -165.874446)
		(end 340.358984 -166.007034)
		(width 0.1143)
		(layer "In9.Cu")
		(net "L10_85OHM_10INCH_DP")
	)
	(segment
		(start 333.154782 -163.625022)
		(end 332.82382 -163.394136)
		(width 0.1143)
		(layer "In9.Cu")
		(net "L10_85OHM_10INCH_DP")
	)
	(segment
		(start 369.9383 -163.630356)
		(end 369.59794 -163.39185)
		(width 0.1143)
		(layer "In9.Cu")
		(net "L10_85OHM_10INCH_DP")
	)
	(segment
		(start 336.351118 -163.616894)
		(end 336.020156 -163.385754)
		(width 0.1143)
		(layer "In9.Cu")
		(net "L10_85OHM_10INCH_DP")
	)
	(segment
		(start 356.308152 -163.470844)
		(end 356.076504 -163.801298)
		(width 0.1143)
		(layer "In9.Cu")
		(net "L10_85OHM_10INCH_DP")
	)
	(segment
		(start 379.954028 -166.019988)
		(end 379.527816 -163.598352)
		(width 0.1143)
		(layer "In9.Cu")
		(net "L10_85OHM_10INCH_DP")
	)
	(segment
		(start 346.485972 -163.821618)
		(end 346.847414 -165.87089)
		(width 0.1143)
		(layer "In9.Cu")
		(net "L10_85OHM_10INCH_DP")
	)
	(segment
		(start 345.157044 -166.011606)
		(end 344.894408 -166.057834)
		(width 0.1143)
		(layer "In9.Cu")
		(net "L10_85OHM_10INCH_DP")
	)
	(segment
		(start 329.955652 -163.62045)
		(end 329.62469 -163.38931)
		(width 0.1143)
		(layer "In9.Cu")
		(net "L10_85OHM_10INCH_DP")
	)
	(segment
		(start 353.942142 -163.617402)
		(end 353.611434 -163.386262)
		(width 0.1143)
		(layer "In9.Cu")
		(net "L10_85OHM_10INCH_DP")
	)
	(segment
		(start 367.286794 -166.085266)
		(end 367.154968 -165.993064)
		(width 0.1143)
		(layer "In9.Cu")
		(net "L10_85OHM_10INCH_DP")
	)
	(segment
		(start 377.245118 -165.942264)
		(end 377.152662 -166.074598)
		(width 0.1143)
		(layer "In9.Cu")
		(net "L10_85OHM_10INCH_DP")
	)
	(segment
		(start 357.908352 -163.470336)
		(end 357.675942 -163.800536)
		(width 0.1143)
		(layer "In9.Cu")
		(net "L10_85OHM_10INCH_DP")
	)
	(segment
		(start 330.72324 -163.481766)
		(end 330.4921 -163.812728)
		(width 0.1143)
		(layer "In9.Cu")
		(net "L10_85OHM_10INCH_DP")
	)
	(segment
		(start 327.674224 -165.969696)
		(end 327.58126 -166.101776)
		(width 0.1143)
		(layer "In9.Cu")
		(net "L10_85OHM_10INCH_DP")
	)
	(segment
		(start 374.40362 -163.391088)
		(end 373.902224 -163.478972)
		(width 0.1143)
		(layer "In9.Cu")
		(net "L10_85OHM_10INCH_DP")
	)
	(segment
		(start 328.02576 -163.38931)
		(end 327.524364 -163.477448)
		(width 0.1143)
		(layer "In9.Cu")
		(net "L10_85OHM_10INCH_DP")
	)
	(segment
		(start 340.821264 -163.401756)
		(end 340.32063 -163.489894)
		(width 0.1143)
		(layer "In9.Cu")
		(net "L10_85OHM_10INCH_DP")
	)
	(segment
		(start 352.886264 -166.037768)
		(end 352.753676 -165.945312)
		(width 0.1143)
		(layer "In9.Cu")
		(net "L10_85OHM_10INCH_DP")
	)
	(segment
		(start 346.492322 -166.049452)
		(end 346.35948 -165.956742)
		(width 0.1143)
		(layer "In9.Cu")
		(net "L10_85OHM_10INCH_DP")
	)
	(segment
		(start 367.642648 -165.905688)
		(end 367.54943 -166.038784)
		(width 0.1143)
		(layer "In9.Cu")
		(net "L10_85OHM_10INCH_DP")
	)
	(segment
		(start 350.046544 -165.8747)
		(end 349.953326 -166.007796)
		(width 0.1143)
		(layer "In9.Cu")
		(net "L10_85OHM_10INCH_DP")
	)
	(segment
		(start 337.162394 -166.015162)
		(end 336.899758 -166.06139)
		(width 0.1143)
		(layer "In9.Cu")
		(net "L10_85OHM_10INCH_DP")
	)
	(segment
		(start 325.159878 -163.628832)
		(end 324.828662 -163.397692)
		(width 0.1143)
		(layer "In9.Cu")
		(net "L10_85OHM_10INCH_DP")
	)
	(segment
		(start 331.555344 -163.625022)
		(end 331.224382 -163.394136)
		(width 0.1143)
		(layer "In9.Cu")
		(net "L10_85OHM_10INCH_DP")
	)
	(segment
		(start 361.93857 -163.619434)
		(end 361.607354 -163.387278)
		(width 0.1143)
		(layer "In9.Cu")
		(net "L10_85OHM_10INCH_DP")
	)
	(segment
		(start 382.728724 -163.614862)
		(end 382.398016 -163.383214)
		(width 0.1143)
		(layer "In9.Cu")
		(net "L10_85OHM_10INCH_DP")
	)
	(segment
		(start 332.373732 -166.073074)
		(end 332.111604 -166.119302)
		(width 0.1143)
		(layer "In9.Cu")
		(net "L10_85OHM_10INCH_DP")
	)
	(segment
		(start 332.09103 -163.813236)
		(end 332.466442 -165.940486)
		(width 0.1143)
		(layer "In9.Cu")
		(net "L10_85OHM_10INCH_DP")
	)
	(segment
		(start 370.472208 -163.806124)
		(end 370.849652 -165.94582)
		(width 0.1143)
		(layer "In9.Cu")
		(net "L10_85OHM_10INCH_DP")
	)
	(segment
		(start 349.953326 -166.007796)
		(end 349.69069 -166.054278)
		(width 0.1143)
		(layer "In9.Cu")
		(net "L10_85OHM_10INCH_DP")
	)
	(segment
		(start 349.69069 -166.054278)
		(end 349.558864 -165.962076)
		(width 0.1143)
		(layer "In9.Cu")
		(net "L10_85OHM_10INCH_DP")
	)
	(segment
		(start 324.327266 -163.485576)
		(end 324.096126 -163.816538)
		(width 0.1143)
		(layer "In9.Cu")
		(net "L10_85OHM_10INCH_DP")
	)
	(segment
		(start 348.446598 -165.871144)
		(end 348.354142 -166.003478)
		(width 0.1143)
		(layer "In9.Cu")
		(net "L10_85OHM_10INCH_DP")
	)
	(segment
		(start 362.708444 -163.491418)
		(end 362.47705 -163.82238)
		(width 0.1143)
		(layer "In9.Cu")
		(net "L10_85OHM_10INCH_DP")
	)
	(segment
		(start 366.04067 -165.890194)
		(end 365.947452 -166.02329)
		(width 0.1143)
		(layer "In9.Cu")
		(net "L10_85OHM_10INCH_DP")
	)
	(segment
		(start 365.55299 -165.97757)
		(end 365.143288 -163.65474)
		(width 0.1143)
		(layer "In9.Cu")
		(net "L10_85OHM_10INCH_DP")
	)
	(segment
		(start 347.95841 -165.956996)
		(end 347.54947 -163.633912)
		(width 0.1143)
		(layer "In9.Cu")
		(net "L10_85OHM_10INCH_DP")
	)
	(segment
		(start 377.096528 -163.45027)
		(end 376.864118 -163.78047)
		(width 0.1143)
		(layer "In9.Cu")
		(net "L10_85OHM_10INCH_DP")
	)
	(segment
		(start 380.442216 -165.934136)
		(end 380.34976 -166.06647)
		(width 0.1143)
		(layer "In9.Cu")
		(net "L10_85OHM_10INCH_DP")
	)
	(segment
		(start 364.81258 -163.423092)
		(end 364.311184 -163.51123)
		(width 0.1143)
		(layer "In9.Cu")
		(net "L10_85OHM_10INCH_DP")
	)
	(segment
		(start 381.89662 -163.471352)
		(end 381.665226 -163.802568)
		(width 0.1143)
		(layer "In9.Cu")
		(net "L10_85OHM_10INCH_DP")
	)
	(segment
		(start 338.490306 -163.821364)
		(end 338.854034 -165.882828)
		(width 0.1143)
		(layer "In9.Cu")
		(net "L10_85OHM_10INCH_DP")
	)
	(segment
		(start 332.322424 -163.48202)
		(end 332.09103 -163.813236)
		(width 0.1143)
		(layer "In9.Cu")
		(net "L10_85OHM_10INCH_DP")
	)
	(segment
		(start 373.558562 -166.023798)
		(end 373.134636 -163.621974)
		(width 0.1143)
		(layer "In9.Cu")
		(net "L10_85OHM_10INCH_DP")
	)
	(segment
		(start 342.050624 -165.874954)
		(end 341.958168 -166.007288)
		(width 0.1143)
		(layer "In9.Cu")
		(net "L10_85OHM_10INCH_DP")
	)
	(segment
		(start 383.336292 -164.772086)
		(end 383.174494 -164.779706)
		(width 0.1143)
		(layer "In9.Cu")
		(net "L10_85OHM_10INCH_DP")
	)
	(segment
		(start 340.089236 -163.82111)
		(end 340.451694 -165.874446)
		(width 0.1143)
		(layer "In9.Cu")
		(net "L10_85OHM_10INCH_DP")
	)
	(segment
		(start 377.596654 -163.36264)
		(end 377.096528 -163.45027)
		(width 0.1143)
		(layer "In9.Cu")
		(net "L10_85OHM_10INCH_DP")
	)
	(segment
		(start 327.318878 -166.14775)
		(end 327.18629 -166.055294)
		(width 0.1143)
		(layer "In9.Cu")
		(net "L10_85OHM_10INCH_DP")
	)
	(segment
		(start 324.120256 -166.142924)
		(end 323.987414 -166.049706)
		(width 0.1143)
		(layer "In9.Cu")
		(net "L10_85OHM_10INCH_DP")
	)
	(segment
		(start 367.154968 -165.993064)
		(end 366.740186 -163.641278)
		(width 0.1143)
		(layer "In9.Cu")
		(net "L10_85OHM_10INCH_DP")
	)
	(segment
		(start 369.157758 -166.077392)
		(end 368.895122 -166.12362)
		(width 0.1143)
		(layer "In9.Cu")
		(net "L10_85OHM_10INCH_DP")
	)
	(segment
		(start 318.000126 -165.059106)
		(end 320.768472 -165.059106)
		(width 0.1143)
		(layer "F.Cu")
		(net "L10_85OHM_10INCH_DN")
	)
	(segment
		(start 320.768472 -165.059106)
		(end 321.384422 -165.675056)
		(width 0.1143)
		(layer "F.Cu")
		(net "L10_85OHM_10INCH_DN")
	)
	(segment
		(start 386.839968 -165.051994)
		(end 384.078734 -165.051994)
		(width 0.1143)
		(layer "F.Cu")
		(net "L10_85OHM_10INCH_DN")
	)
	(segment
		(start 387.20141 -165.413436)
		(end 386.839968 -165.051994)
		(width 0.1143)
		(layer "F.Cu")
		(net "L10_85OHM_10INCH_DN")
	)
	(segment
		(start 317.645796 -165.413436)
		(end 318.000126 -165.059106)
		(width 0.1143)
		(layer "F.Cu")
		(net "L10_85OHM_10INCH_DN")
	)
	(segment
		(start 384.078734 -165.051994)
		(end 383.462784 -165.667944)
		(width 0.1143)
		(layer "F.Cu")
		(net "L10_85OHM_10INCH_DN")
	)
	(via
		(at 321.384422 -165.675056)
		(size 0.5588)
		(drill 0.3048)
		(layers "F.Cu" "B.Cu")
		(net "L10_85OHM_10INCH_DN")
	)
	(via
		(at 383.462784 -165.667944)
		(size 0.5588)
		(drill 0.3048)
		(layers "F.Cu" "B.Cu")
		(net "L10_85OHM_10INCH_DN")
	)
	(segment
		(start 345.68257 -163.799266)
		(end 346.092526 -166.126922)
		(width 0.1143)
		(layer "In9.Cu")
		(net "L10_85OHM_10INCH_DN")
	)
	(segment
		(start 323.18198 -166.016432)
		(end 322.805044 -163.881308)
		(width 0.1143)
		(layer "In9.Cu")
		(net "L10_85OHM_10INCH_DN")
	)
	(segment
		(start 351.721674 -166.266876)
		(end 351.953068 -165.93566)
		(width 0.1143)
		(layer "In9.Cu")
		(net "L10_85OHM_10INCH_DN")
	)
	(segment
		(start 374.123966 -166.337234)
		(end 374.355106 -166.006272)
		(width 0.1143)
		(layer "In9.Cu")
		(net "L10_85OHM_10INCH_DN")
	)
	(segment
		(start 378.088144 -166.189914)
		(end 378.41936 -166.421054)
		(width 0.1143)
		(layer "In9.Cu")
		(net "L10_85OHM_10INCH_DN")
	)
	(segment
		(start 379.687328 -166.190168)
		(end 380.018544 -166.421308)
		(width 0.1143)
		(layer "In9.Cu")
		(net "L10_85OHM_10INCH_DN")
	)
	(segment
		(start 335.596738 -163.87318)
		(end 335.689194 -163.740592)
		(width 0.1143)
		(layer "In9.Cu")
		(net "L10_85OHM_10INCH_DN")
	)
	(segment
		(start 345.194636 -163.884864)
		(end 345.2876 -163.752784)
		(width 0.1143)
		(layer "In9.Cu")
		(net "L10_85OHM_10INCH_DN")
	)
	(segment
		(start 357.285798 -166.11981)
		(end 357.615998 -166.351204)
		(width 0.1143)
		(layer "In9.Cu")
		(net "L10_85OHM_10INCH_DN")
	)
	(segment
		(start 381.617982 -166.426134)
		(end 382.119124 -166.337488)
		(width 0.1143)
		(layer "In9.Cu")
		(net "L10_85OHM_10INCH_DN")
	)
	(segment
		(start 358.348534 -165.932104)
		(end 357.984806 -163.86937)
		(width 0.1143)
		(layer "In9.Cu")
		(net "L10_85OHM_10INCH_DN")
	)
	(segment
		(start 340.885272 -163.803076)
		(end 341.296244 -166.130986)
		(width 0.1143)
		(layer "In9.Cu")
		(net "L10_85OHM_10INCH_DN")
	)
	(segment
		(start 337.20151 -163.897056)
		(end 337.30057 -163.754816)
		(width 0.1143)
		(layer "In9.Cu")
		(net "L10_85OHM_10INCH_DN")
	)
	(segment
		(start 379.128274 -163.675822)
		(end 379.260862 -163.768532)
		(width 0.1143)
		(layer "In9.Cu")
		(net "L10_85OHM_10INCH_DN")
	)
	(segment
		(start 366.349534 -165.958774)
		(end 365.985552 -163.89731)
		(width 0.1143)
		(layer "In9.Cu")
		(net "L10_85OHM_10INCH_DN")
	)
	(segment
		(start 350.346772 -163.703)
		(end 350.479106 -163.79571)
		(width 0.1143)
		(layer "In9.Cu")
		(net "L10_85OHM_10INCH_DN")
	)
	(segment
		(start 348.8817 -163.804854)
		(end 349.292164 -166.132002)
		(width 0.1143)
		(layer "In9.Cu")
		(net "L10_85OHM_10INCH_DN")
	)
	(segment
		(start 344.825828 -166.366698)
		(end 345.327224 -166.27856)
		(width 0.1143)
		(layer "In9.Cu")
		(net "L10_85OHM_10INCH_DN")
	)
	(segment
		(start 324.893178 -163.799012)
		(end 325.31939 -166.220648)
		(width 0.1143)
		(layer "In9.Cu")
		(net "L10_85OHM_10INCH_DN")
	)
	(segment
		(start 379.260862 -163.768532)
		(end 379.687328 -166.190168)
		(width 0.1143)
		(layer "In9.Cu")
		(net "L10_85OHM_10INCH_DN")
	)
	(segment
		(start 350.355408 -165.94328)
		(end 349.991426 -163.881816)
		(width 0.1143)
		(layer "In9.Cu")
		(net "L10_85OHM_10INCH_DN")
	)
	(segment
		(start 328.849482 -166.456868)
		(end 329.350878 -166.368222)
		(width 0.1143)
		(layer "In9.Cu")
		(net "L10_85OHM_10INCH_DN")
	)
	(segment
		(start 369.283488 -163.743894)
		(end 369.52936 -163.700714)
		(width 0.1143)
		(layer "In9.Cu")
		(net "L10_85OHM_10INCH_DN")
	)
	(segment
		(start 355.686106 -166.120064)
		(end 356.017068 -166.351204)
		(width 0.1143)
		(layer "In9.Cu")
		(net "L10_85OHM_10INCH_DN")
	)
	(segment
		(start 328.08926 -163.79063)
		(end 328.51852 -166.224204)
		(width 0.1143)
		(layer "In9.Cu")
		(net "L10_85OHM_10INCH_DN")
	)
	(segment
		(start 342.359488 -165.94328)
		(end 341.997284 -163.889436)
		(width 0.1143)
		(layer "In9.Cu")
		(net "L10_85OHM_10INCH_DN")
	)
	(segment
		(start 333.997554 -163.87318)
		(end 334.090264 -163.740592)
		(width 0.1143)
		(layer "In9.Cu")
		(net "L10_85OHM_10INCH_DN")
	)
	(segment
		(start 343.72804 -166.278306)
		(end 343.958926 -165.947852)
		(width 0.1143)
		(layer "In9.Cu")
		(net "L10_85OHM_10INCH_DN")
	)
	(segment
		(start 332.492604 -163.748974)
		(end 332.755494 -163.702746)
		(width 0.1143)
		(layer "In9.Cu")
		(net "L10_85OHM_10INCH_DN")
	)
	(segment
		(start 374.072404 -163.745926)
		(end 374.334786 -163.699952)
		(width 0.1143)
		(layer "In9.Cu")
		(net "L10_85OHM_10INCH_DN")
	)
	(segment
		(start 370.873782 -163.7411)
		(end 371.13591 -163.69538)
		(width 0.1143)
		(layer "In9.Cu")
		(net "L10_85OHM_10INCH_DN")
	)
	(segment
		(start 360.813096 -166.342822)
		(end 361.314492 -166.254938)
		(width 0.1143)
		(layer "In9.Cu")
		(net "L10_85OHM_10INCH_DN")
	)
	(segment
		(start 354.87991 -163.741354)
		(end 355.142292 -163.69538)
		(width 0.1143)
		(layer "In9.Cu")
		(net "L10_85OHM_10INCH_DN")
	)
	(segment
		(start 359.946448 -165.923722)
		(end 359.585768 -163.878768)
		(width 0.1143)
		(layer "In9.Cu")
		(net "L10_85OHM_10INCH_DN")
	)
	(segment
		(start 349.991426 -163.881816)
		(end 350.084136 -163.749228)
		(width 0.1143)
		(layer "In9.Cu")
		(net "L10_85OHM_10INCH_DN")
	)
	(segment
		(start 334.908906 -166.188644)
		(end 335.249266 -166.42715)
		(width 0.1143)
		(layer "In9.Cu")
		(net "L10_85OHM_10INCH_DN")
	)
	(segment
		(start 329.688952 -163.79063)
		(end 330.112624 -166.195756)
		(width 0.1143)
		(layer "In9.Cu")
		(net "L10_85OHM_10INCH_DN")
	)
	(segment
		(start 382.788922 -164.840412)
		(end 383.075434 -165.076886)
		(width 0.1143)
		(layer "In9.Cu")
		(net "L10_85OHM_10INCH_DN")
	)
	(segment
		(start 330.443586 -166.427912)
		(end 330.944982 -166.340028)
		(width 0.1143)
		(layer "In9.Cu")
		(net "L10_85OHM_10INCH_DN")
	)
	(segment
		(start 329.556364 -163.69792)
		(end 329.688952 -163.79063)
		(width 0.1143)
		(layer "In9.Cu")
		(net "L10_85OHM_10INCH_DN")
	)
	(segment
		(start 358.882696 -166.111428)
		(end 359.213912 -166.342568)
		(width 0.1143)
		(layer "In9.Cu")
		(net "L10_85OHM_10INCH_DN")
	)
	(segment
		(start 340.752938 -163.71062)
		(end 340.885272 -163.803076)
		(width 0.1143)
		(layer "In9.Cu")
		(net "L10_85OHM_10INCH_DN")
	)
	(segment
		(start 340.027768 -166.361872)
		(end 340.529164 -166.273988)
		(width 0.1143)
		(layer "In9.Cu")
		(net "L10_85OHM_10INCH_DN")
	)
	(segment
		(start 381.97409 -163.870894)
		(end 382.0668 -163.738306)
		(width 0.1143)
		(layer "In9.Cu")
		(net "L10_85OHM_10INCH_DN")
	)
	(segment
		(start 335.95183 -163.694364)
		(end 336.084418 -163.787074)
		(width 0.1143)
		(layer "In9.Cu")
		(net "L10_85OHM_10INCH_DN")
	)
	(segment
		(start 373.979948 -163.878514)
		(end 374.072404 -163.745926)
		(width 0.1143)
		(layer "In9.Cu")
		(net "L10_85OHM_10INCH_DN")
	)
	(segment
		(start 380.72695 -163.676076)
		(end 380.859792 -163.769294)
		(width 0.1143)
		(layer "In9.Cu")
		(net "L10_85OHM_10INCH_DN")
	)
	(segment
		(start 382.547114 -164.269928)
		(end 382.642364 -164.645086)
		(width 0.1143)
		(layer "In9.Cu")
		(net "L10_85OHM_10INCH_DN")
	)
	(segment
		(start 372.867936 -163.792154)
		(end 373.291862 -166.193978)
		(width 0.1143)
		(layer "In9.Cu")
		(net "L10_85OHM_10INCH_DN")
	)
	(segment
		(start 321.384422 -165.675056)
		(end 321.384422 -165.173406)
		(width 0.1143)
		(layer "In9.Cu")
		(net "L10_85OHM_10INCH_DN")
	)
	(segment
		(start 370.094764 -166.20236)
		(end 370.425726 -166.433246)
		(width 0.1143)
		(layer "In9.Cu")
		(net "L10_85OHM_10INCH_DN")
	)
	(segment
		(start 370.927122 -166.345362)
		(end 371.158516 -166.014146)
		(width 0.1143)
		(layer "In9.Cu")
		(net "L10_85OHM_10INCH_DN")
	)
	(segment
		(start 367.218468 -166.39413)
		(end 367.71961 -166.305484)
		(width 0.1143)
		(layer "In9.Cu")
		(net "L10_85OHM_10INCH_DN")
	)
	(segment
		(start 343.591642 -163.865052)
		(end 343.684352 -163.732718)
		(width 0.1143)
		(layer "In9.Cu")
		(net "L10_85OHM_10INCH_DN")
	)
	(segment
		(start 350.889316 -166.123874)
		(end 351.220278 -166.35476)
		(width 0.1143)
		(layer "In9.Cu")
		(net "L10_85OHM_10INCH_DN")
	)
	(segment
		(start 330.89342 -163.74872)
		(end 331.156056 -163.702746)
		(width 0.1143)
		(layer "In9.Cu")
		(net "L10_85OHM_10INCH_DN")
	)
	(segment
		(start 334.090264 -163.740592)
		(end 334.353154 -163.694364)
		(width 0.1143)
		(layer "In9.Cu")
		(net "L10_85OHM_10INCH_DN")
	)
	(segment
		(start 377.322842 -166.341552)
		(end 377.553982 -166.01059)
		(width 0.1143)
		(layer "In9.Cu")
		(net "L10_85OHM_10INCH_DN")
	)
	(segment
		(start 336.50047 -166.13886)
		(end 336.831432 -166.370254)
		(width 0.1143)
		(layer "In9.Cu")
		(net "L10_85OHM_10INCH_DN")
	)
	(segment
		(start 340.49081 -163.756848)
		(end 340.752938 -163.71062)
		(width 0.1143)
		(layer "In9.Cu")
		(net "L10_85OHM_10INCH_DN")
	)
	(segment
		(start 351.953068 -165.93566)
		(end 351.58934 -163.873942)
		(width 0.1143)
		(layer "In9.Cu")
		(net "L10_85OHM_10INCH_DN")
	)
	(segment
		(start 371.158516 -166.014146)
		(end 370.781072 -163.874196)
		(width 0.1143)
		(layer "In9.Cu")
		(net "L10_85OHM_10INCH_DN")
	)
	(segment
		(start 375.666254 -163.717478)
		(end 375.92889 -163.670996)
		(width 0.1143)
		(layer "In9.Cu")
		(net "L10_85OHM_10INCH_DN")
	)
	(segment
		(start 367.951512 -165.974268)
		(end 367.58753 -163.912804)
		(width 0.1143)
		(layer "In9.Cu")
		(net "L10_85OHM_10INCH_DN")
	)
	(segment
		(start 336.831432 -166.370254)
		(end 337.332574 -166.281862)
		(width 0.1143)
		(layer "In9.Cu")
		(net "L10_85OHM_10INCH_DN")
	)
	(segment
		(start 375.723658 -166.341298)
		(end 375.954544 -166.010844)
		(width 0.1143)
		(layer "In9.Cu")
		(net "L10_85OHM_10INCH_DN")
	)
	(segment
		(start 334.374998 -166.012876)
		(end 333.997554 -163.87318)
		(width 0.1143)
		(layer "In9.Cu")
		(net "L10_85OHM_10INCH_DN")
	)
	(segment
		(start 351.68205 -163.740846)
		(end 351.944178 -163.695126)
		(width 0.1143)
		(layer "In9.Cu")
		(net "L10_85OHM_10INCH_DN")
	)
	(segment
		(start 372.735602 -163.699698)
		(end 372.867936 -163.792154)
		(width 0.1143)
		(layer "In9.Cu")
		(net "L10_85OHM_10INCH_DN")
	)
	(segment
		(start 341.997284 -163.889436)
		(end 342.08974 -163.756848)
		(width 0.1143)
		(layer "In9.Cu")
		(net "L10_85OHM_10INCH_DN")
	)
	(segment
		(start 371.692424 -166.193978)
		(end 372.023386 -166.424864)
		(width 0.1143)
		(layer "In9.Cu")
		(net "L10_85OHM_10INCH_DN")
	)
	(segment
		(start 379.151896 -166.002208)
		(end 378.773182 -163.854384)
		(width 0.1143)
		(layer "In9.Cu")
		(net "L10_85OHM_10INCH_DN")
	)
	(segment
		(start 382.462024 -163.784788)
		(end 382.547114 -164.269928)
		(width 0.1143)
		(layer "In9.Cu")
		(net "L10_85OHM_10INCH_DN")
	)
	(segment
		(start 335.971896 -166.001192)
		(end 335.596738 -163.87318)
		(width 0.1143)
		(layer "In9.Cu")
		(net "L10_85OHM_10INCH_DN")
	)
	(segment
		(start 363.145578 -165.927786)
		(end 362.786168 -163.89096)
		(width 0.1143)
		(layer "In9.Cu")
		(net "L10_85OHM_10INCH_DN")
	)
	(segment
		(start 322.014088 -165.61054)
		(end 322.118736 -166.204138)
		(width 0.1143)
		(layer "In9.Cu")
		(net "L10_85OHM_10INCH_DN")
	)
	(segment
		(start 353.675442 -163.787582)
		(end 354.086414 -166.115492)
		(width 0.1143)
		(layer "In9.Cu")
		(net "L10_85OHM_10INCH_DN")
	)
	(segment
		(start 356.87381 -163.784534)
		(end 357.285798 -166.11981)
		(width 0.1143)
		(layer "In9.Cu")
		(net "L10_85OHM_10INCH_DN")
	)
	(segment
		(start 334.353154 -163.694364)
		(end 334.485742 -163.78682)
		(width 0.1143)
		(layer "In9.Cu")
		(net "L10_85OHM_10INCH_DN")
	)
	(segment
		(start 375.222516 -166.42969)
		(end 375.723658 -166.341298)
		(width 0.1143)
		(layer "In9.Cu")
		(net "L10_85OHM_10INCH_DN")
	)
	(segment
		(start 338.430108 -166.370254)
		(end 338.931504 -166.28237)
		(width 0.1143)
		(layer "In9.Cu")
		(net "L10_85OHM_10INCH_DN")
	)
	(segment
		(start 356.478078 -163.737544)
		(end 356.740714 -163.691062)
		(width 0.1143)
		(layer "In9.Cu")
		(net "L10_85OHM_10INCH_DN")
	)
	(segment
		(start 350.479106 -163.79571)
		(end 350.889316 -166.123874)
		(width 0.1143)
		(layer "In9.Cu")
		(net "L10_85OHM_10INCH_DN")
	)
	(segment
		(start 326.91959 -166.225474)
		(end 327.250552 -166.45636)
		(width 0.1143)
		(layer "In9.Cu")
		(net "L10_85OHM_10INCH_DN")
	)
	(segment
		(start 362.878878 -163.758118)
		(end 363.14126 -163.712144)
		(width 0.1143)
		(layer "In9.Cu")
		(net "L10_85OHM_10INCH_DN")
	)
	(segment
		(start 356.017068 -166.351204)
		(end 356.51821 -166.262812)
		(width 0.1143)
		(layer "In9.Cu")
		(net "L10_85OHM_10INCH_DN")
	)
	(segment
		(start 337.30057 -163.754816)
		(end 337.546696 -163.711636)
		(width 0.1143)
		(layer "In9.Cu")
		(net "L10_85OHM_10INCH_DN")
	)
	(segment
		(start 327.983088 -166.03853)
		(end 327.602088 -163.876736)
		(width 0.1143)
		(layer "In9.Cu")
		(net "L10_85OHM_10INCH_DN")
	)
	(segment
		(start 330.800964 -163.881054)
		(end 330.89342 -163.74872)
		(width 0.1143)
		(layer "In9.Cu")
		(net "L10_85OHM_10INCH_DN")
	)
	(segment
		(start 377.553982 -166.01059)
		(end 377.172982 -163.849304)
		(width 0.1143)
		(layer "In9.Cu")
		(net "L10_85OHM_10INCH_DN")
	)
	(segment
		(start 367.68024 -163.780216)
		(end 367.942876 -163.733988)
		(width 0.1143)
		(layer "In9.Cu")
		(net "L10_85OHM_10INCH_DN")
	)
	(segment
		(start 347.282516 -163.804092)
		(end 347.69171 -166.127176)
		(width 0.1143)
		(layer "In9.Cu")
		(net "L10_85OHM_10INCH_DN")
	)
	(segment
		(start 359.94086 -163.700206)
		(end 360.073448 -163.792916)
		(width 0.1143)
		(layer "In9.Cu")
		(net "L10_85OHM_10INCH_DN")
	)
	(segment
		(start 342.895936 -166.135558)
		(end 343.226898 -166.366698)
		(width 0.1143)
		(layer "In9.Cu")
		(net "L10_85OHM_10INCH_DN")
	)
	(segment
		(start 343.958926 -165.947852)
		(end 343.591642 -163.865052)
		(width 0.1143)
		(layer "In9.Cu")
		(net "L10_85OHM_10INCH_DN")
	)
	(segment
		(start 369.52936 -163.700714)
		(end 369.6716 -163.800282)
		(width 0.1143)
		(layer "In9.Cu")
		(net "L10_85OHM_10INCH_DN")
	)
	(segment
		(start 351.220278 -166.35476)
		(end 351.721674 -166.266876)
		(width 0.1143)
		(layer "In9.Cu")
		(net "L10_85OHM_10INCH_DN")
	)
	(segment
		(start 323.292724 -163.793932)
		(end 323.72046 -166.219632)
		(width 0.1143)
		(layer "In9.Cu")
		(net "L10_85OHM_10INCH_DN")
	)
	(segment
		(start 366.473232 -163.811204)
		(end 366.888268 -166.16299)
		(width 0.1143)
		(layer "In9.Cu")
		(net "L10_85OHM_10INCH_DN")
	)
	(segment
		(start 321.496182 -165.061646)
		(end 321.617594 -165.061646)
		(width 0.1143)
		(layer "In9.Cu")
		(net "L10_85OHM_10INCH_DN")
	)
	(segment
		(start 361.314492 -166.254938)
		(end 361.545632 -165.923976)
		(width 0.1143)
		(layer "In9.Cu")
		(net "L10_85OHM_10INCH_DN")
	)
	(segment
		(start 326.359266 -163.706556)
		(end 326.492108 -163.799266)
		(width 0.1143)
		(layer "In9.Cu")
		(net "L10_85OHM_10INCH_DN")
	)
	(segment
		(start 381.287782 -166.194994)
		(end 381.617982 -166.426134)
		(width 0.1143)
		(layer "In9.Cu")
		(net "L10_85OHM_10INCH_DN")
	)
	(segment
		(start 376.491246 -166.198296)
		(end 376.821446 -166.42969)
		(width 0.1143)
		(layer "In9.Cu")
		(net "L10_85OHM_10INCH_DN")
	)
	(segment
		(start 353.550728 -165.927278)
		(end 353.18827 -163.873942)
		(width 0.1143)
		(layer "In9.Cu")
		(net "L10_85OHM_10INCH_DN")
	)
	(segment
		(start 347.156278 -165.939216)
		(end 346.794836 -163.889944)
		(width 0.1143)
		(layer "In9.Cu")
		(net "L10_85OHM_10INCH_DN")
	)
	(segment
		(start 349.292164 -166.132002)
		(end 349.622364 -166.363142)
		(width 0.1143)
		(layer "In9.Cu")
		(net "L10_85OHM_10INCH_DN")
	)
	(segment
		(start 367.71961 -166.305484)
		(end 367.951512 -165.974268)
		(width 0.1143)
		(layer "In9.Cu")
		(net "L10_85OHM_10INCH_DN")
	)
	(segment
		(start 335.733898 -166.34206)
		(end 335.971896 -166.001192)
		(width 0.1143)
		(layer "In9.Cu")
		(net "L10_85OHM_10INCH_DN")
	)
	(segment
		(start 335.689194 -163.740592)
		(end 335.95183 -163.694364)
		(width 0.1143)
		(layer "In9.Cu")
		(net "L10_85OHM_10INCH_DN")
	)
	(segment
		(start 332.888082 -163.795202)
		(end 333.311246 -166.201344)
		(width 0.1143)
		(layer "In9.Cu")
		(net "L10_85OHM_10INCH_DN")
	)
	(segment
		(start 347.149928 -163.711382)
		(end 347.282516 -163.804092)
		(width 0.1143)
		(layer "In9.Cu")
		(net "L10_85OHM_10INCH_DN")
	)
	(segment
		(start 378.920756 -166.33317)
		(end 379.151896 -166.002208)
		(width 0.1143)
		(layer "In9.Cu")
		(net "L10_85OHM_10INCH_DN")
	)
	(segment
		(start 337.563714 -165.950646)
		(end 337.20151 -163.897056)
		(width 0.1143)
		(layer "In9.Cu")
		(net "L10_85OHM_10INCH_DN")
	)
	(segment
		(start 324.783958 -166.031926)
		(end 324.40499 -163.884864)
		(width 0.1143)
		(layer "In9.Cu")
		(net "L10_85OHM_10INCH_DN")
	)
	(segment
		(start 373.622824 -166.424864)
		(end 374.123966 -166.337234)
		(width 0.1143)
		(layer "In9.Cu")
		(net "L10_85OHM_10INCH_DN")
	)
	(segment
		(start 331.288644 -163.795202)
		(end 331.71257 -166.197026)
		(width 0.1143)
		(layer "In9.Cu")
		(net "L10_85OHM_10INCH_DN")
	)
	(segment
		(start 380.464568 -163.722304)
		(end 380.72695 -163.676076)
		(width 0.1143)
		(layer "In9.Cu")
		(net "L10_85OHM_10INCH_DN")
	)
	(segment
		(start 348.486476 -163.75761)
		(end 348.748604 -163.711636)
		(width 0.1143)
		(layer "In9.Cu")
		(net "L10_85OHM_10INCH_DN")
	)
	(segment
		(start 345.327224 -166.27856)
		(end 345.558364 -165.947598)
		(width 0.1143)
		(layer "In9.Cu")
		(net "L10_85OHM_10INCH_DN")
	)
	(segment
		(start 326.382888 -166.032942)
		(end 326.004174 -163.885118)
		(width 0.1143)
		(layer "In9.Cu")
		(net "L10_85OHM_10INCH_DN")
	)
	(segment
		(start 335.249266 -166.42715)
		(end 335.733898 -166.34206)
		(width 0.1143)
		(layer "In9.Cu")
		(net "L10_85OHM_10INCH_DN")
	)
	(segment
		(start 367.58753 -163.912804)
		(end 367.68024 -163.780216)
		(width 0.1143)
		(layer "In9.Cu")
		(net "L10_85OHM_10INCH_DN")
	)
	(segment
		(start 367.942876 -163.733988)
		(end 368.07521 -163.826698)
		(width 0.1143)
		(layer "In9.Cu")
		(net "L10_85OHM_10INCH_DN")
	)
	(segment
		(start 353.319334 -166.258494)
		(end 353.550728 -165.927278)
		(width 0.1143)
		(layer "In9.Cu")
		(net "L10_85OHM_10INCH_DN")
	)
	(segment
		(start 351.944178 -163.695126)
		(end 352.077274 -163.787836)
		(width 0.1143)
		(layer "In9.Cu")
		(net "L10_85OHM_10INCH_DN")
	)
	(segment
		(start 378.41936 -166.421054)
		(end 378.920756 -166.33317)
		(width 0.1143)
		(layer "In9.Cu")
		(net "L10_85OHM_10INCH_DN")
	)
	(segment
		(start 343.226898 -166.366698)
		(end 343.72804 -166.278306)
		(width 0.1143)
		(layer "In9.Cu")
		(net "L10_85OHM_10INCH_DN")
	)
	(segment
		(start 331.156056 -163.702746)
		(end 331.288644 -163.795202)
		(width 0.1143)
		(layer "In9.Cu")
		(net "L10_85OHM_10INCH_DN")
	)
	(segment
		(start 322.805044 -163.881308)
		(end 322.898262 -163.748212)
		(width 0.1143)
		(layer "In9.Cu")
		(net "L10_85OHM_10INCH_DN")
	)
	(segment
		(start 361.545632 -165.923976)
		(end 361.183936 -163.874958)
		(width 0.1143)
		(layer "In9.Cu")
		(net "L10_85OHM_10INCH_DN")
	)
	(segment
		(start 321.617594 -165.061646)
		(end 321.777614 -165.183312)
		(width 0.1143)
		(layer "In9.Cu")
		(net "L10_85OHM_10INCH_DN")
	)
	(segment
		(start 375.92889 -163.670996)
		(end 376.061732 -163.764468)
		(width 0.1143)
		(layer "In9.Cu")
		(net "L10_85OHM_10INCH_DN")
	)
	(segment
		(start 332.755494 -163.702746)
		(end 332.888082 -163.795202)
		(width 0.1143)
		(layer "In9.Cu")
		(net "L10_85OHM_10INCH_DN")
	)
	(segment
		(start 329.350878 -166.368222)
		(end 329.582526 -166.037768)
		(width 0.1143)
		(layer "In9.Cu")
		(net "L10_85OHM_10INCH_DN")
	)
	(segment
		(start 364.744 -163.731956)
		(end 364.876334 -163.824666)
		(width 0.1143)
		(layer "In9.Cu")
		(net "L10_85OHM_10INCH_DN")
	)
	(segment
		(start 361.538774 -163.696142)
		(end 361.67187 -163.78936)
		(width 0.1143)
		(layer "In9.Cu")
		(net "L10_85OHM_10INCH_DN")
	)
	(segment
		(start 358.340152 -163.691316)
		(end 358.47274 -163.783772)
		(width 0.1143)
		(layer "In9.Cu")
		(net "L10_85OHM_10INCH_DN")
	)
	(segment
		(start 359.585768 -163.878768)
		(end 359.678478 -163.74618)
		(width 0.1143)
		(layer "In9.Cu")
		(net "L10_85OHM_10INCH_DN")
	)
	(segment
		(start 376.821446 -166.42969)
		(end 377.322842 -166.341552)
		(width 0.1143)
		(layer "In9.Cu")
		(net "L10_85OHM_10INCH_DN")
	)
	(segment
		(start 331.176122 -166.008558)
		(end 330.800964 -163.881054)
		(width 0.1143)
		(layer "In9.Cu")
		(net "L10_85OHM_10INCH_DN")
	)
	(segment
		(start 374.891554 -166.19855)
		(end 375.222516 -166.42969)
		(width 0.1143)
		(layer "In9.Cu")
		(net "L10_85OHM_10INCH_DN")
	)
	(segment
		(start 366.117632 -166.28999)
		(end 366.349534 -165.958774)
		(width 0.1143)
		(layer "In9.Cu")
		(net "L10_85OHM_10INCH_DN")
	)
	(segment
		(start 321.777614 -165.183312)
		(end 321.971162 -165.441376)
		(width 0.1143)
		(layer "In9.Cu")
		(net "L10_85OHM_10INCH_DN")
	)
	(segment
		(start 341.627206 -166.361872)
		(end 342.128348 -166.274242)
		(width 0.1143)
		(layer "In9.Cu")
		(net "L10_85OHM_10INCH_DN")
	)
	(segment
		(start 339.287104 -163.80333)
		(end 339.696806 -166.130986)
		(width 0.1143)
		(layer "In9.Cu")
		(net "L10_85OHM_10INCH_DN")
	)
	(segment
		(start 327.694544 -163.744402)
		(end 327.95718 -163.698174)
		(width 0.1143)
		(layer "In9.Cu")
		(net "L10_85OHM_10INCH_DN")
	)
	(segment
		(start 329.201526 -163.87699)
		(end 329.293728 -163.744402)
		(width 0.1143)
		(layer "In9.Cu")
		(net "L10_85OHM_10INCH_DN")
	)
	(segment
		(start 339.696806 -166.130986)
		(end 340.027768 -166.361872)
		(width 0.1143)
		(layer "In9.Cu")
		(net "L10_85OHM_10INCH_DN")
	)
	(segment
		(start 363.684312 -166.132002)
		(end 364.014512 -166.363142)
		(width 0.1143)
		(layer "In9.Cu")
		(net "L10_85OHM_10INCH_DN")
	)
	(segment
		(start 368.826796 -166.432484)
		(end 369.327938 -166.344092)
		(width 0.1143)
		(layer "In9.Cu")
		(net "L10_85OHM_10INCH_DN")
	)
	(segment
		(start 330.112624 -166.195756)
		(end 330.443586 -166.427912)
		(width 0.1143)
		(layer "In9.Cu")
		(net "L10_85OHM_10INCH_DN")
	)
	(segment
		(start 365.28629 -166.147496)
		(end 365.61649 -166.378636)
		(width 0.1143)
		(layer "In9.Cu")
		(net "L10_85OHM_10INCH_DN")
	)
	(segment
		(start 334.485742 -163.78682)
		(end 334.908906 -166.188644)
		(width 0.1143)
		(layer "In9.Cu")
		(net "L10_85OHM_10INCH_DN")
	)
	(segment
		(start 327.95718 -163.698174)
		(end 328.08926 -163.79063)
		(width 0.1143)
		(layer "In9.Cu")
		(net "L10_85OHM_10INCH_DN")
	)
	(segment
		(start 353.18827 -163.873942)
		(end 353.28098 -163.741354)
		(width 0.1143)
		(layer "In9.Cu")
		(net "L10_85OHM_10INCH_DN")
	)
	(segment
		(start 352.817938 -166.346378)
		(end 353.319334 -166.258494)
		(width 0.1143)
		(layer "In9.Cu")
		(net "L10_85OHM_10INCH_DN")
	)
	(segment
		(start 380.018544 -166.421308)
		(end 380.51994 -166.333424)
		(width 0.1143)
		(layer "In9.Cu")
		(net "L10_85OHM_10INCH_DN")
	)
	(segment
		(start 352.486976 -166.115492)
		(end 352.817938 -166.346378)
		(width 0.1143)
		(layer "In9.Cu")
		(net "L10_85OHM_10INCH_DN")
	)
	(segment
		(start 326.09663 -163.752784)
		(end 326.359266 -163.706556)
		(width 0.1143)
		(layer "In9.Cu")
		(net "L10_85OHM_10INCH_DN")
	)
	(segment
		(start 325.650352 -166.451788)
		(end 326.15124 -166.364158)
		(width 0.1143)
		(layer "In9.Cu")
		(net "L10_85OHM_10INCH_DN")
	)
	(segment
		(start 370.781072 -163.874196)
		(end 370.873782 -163.7411)
		(width 0.1143)
		(layer "In9.Cu")
		(net "L10_85OHM_10INCH_DN")
	)
	(segment
		(start 340.3981 -163.889436)
		(end 340.49081 -163.756848)
		(width 0.1143)
		(layer "In9.Cu")
		(net "L10_85OHM_10INCH_DN")
	)
	(segment
		(start 353.543108 -163.695126)
		(end 353.675442 -163.787582)
		(width 0.1143)
		(layer "In9.Cu")
		(net "L10_85OHM_10INCH_DN")
	)
	(segment
		(start 382.119124 -166.337488)
		(end 382.351026 -166.006272)
		(width 0.1143)
		(layer "In9.Cu")
		(net "L10_85OHM_10INCH_DN")
	)
	(segment
		(start 363.14126 -163.712144)
		(end 363.273848 -163.804854)
		(width 0.1143)
		(layer "In9.Cu")
		(net "L10_85OHM_10INCH_DN")
	)
	(segment
		(start 354.787454 -163.873942)
		(end 354.87991 -163.741354)
		(width 0.1143)
		(layer "In9.Cu")
		(net "L10_85OHM_10INCH_DN")
	)
	(segment
		(start 358.47274 -163.783772)
		(end 358.882696 -166.111428)
		(width 0.1143)
		(layer "In9.Cu")
		(net "L10_85OHM_10INCH_DN")
	)
	(segment
		(start 324.553072 -166.363396)
		(end 324.783958 -166.031926)
		(width 0.1143)
		(layer "In9.Cu")
		(net "L10_85OHM_10INCH_DN")
	)
	(segment
		(start 382.642364 -164.645086)
		(end 382.788922 -164.840412)
		(width 0.1143)
		(layer "In9.Cu")
		(net "L10_85OHM_10INCH_DN")
	)
	(segment
		(start 344.495628 -166.135304)
		(end 344.825828 -166.366698)
		(width 0.1143)
		(layer "In9.Cu")
		(net "L10_85OHM_10INCH_DN")
	)
	(segment
		(start 377.528328 -163.67125)
		(end 377.660916 -163.763706)
		(width 0.1143)
		(layer "In9.Cu")
		(net "L10_85OHM_10INCH_DN")
	)
	(segment
		(start 378.773182 -163.854384)
		(end 378.865892 -163.721796)
		(width 0.1143)
		(layer "In9.Cu")
		(net "L10_85OHM_10INCH_DN")
	)
	(segment
		(start 368.07521 -163.826698)
		(end 368.495072 -166.200582)
		(width 0.1143)
		(layer "In9.Cu")
		(net "L10_85OHM_10INCH_DN")
	)
	(segment
		(start 378.865892 -163.721796)
		(end 379.128274 -163.675822)
		(width 0.1143)
		(layer "In9.Cu")
		(net "L10_85OHM_10INCH_DN")
	)
	(segment
		(start 346.925138 -166.270178)
		(end 347.156278 -165.939216)
		(width 0.1143)
		(layer "In9.Cu")
		(net "L10_85OHM_10INCH_DN")
	)
	(segment
		(start 383.075434 -165.076886)
		(end 383.359914 -165.063678)
		(width 0.1143)
		(layer "In9.Cu")
		(net "L10_85OHM_10INCH_DN")
	)
	(segment
		(start 355.275134 -163.788598)
		(end 355.686106 -166.120064)
		(width 0.1143)
		(layer "In9.Cu")
		(net "L10_85OHM_10INCH_DN")
	)
	(segment
		(start 348.393766 -163.890452)
		(end 348.486476 -163.75761)
		(width 0.1143)
		(layer "In9.Cu")
		(net "L10_85OHM_10INCH_DN")
	)
	(segment
		(start 329.582526 -166.037768)
		(end 329.201526 -163.87699)
		(width 0.1143)
		(layer "In9.Cu")
		(net "L10_85OHM_10INCH_DN")
	)
	(segment
		(start 348.022926 -166.358316)
		(end 348.524322 -166.270432)
		(width 0.1143)
		(layer "In9.Cu")
		(net "L10_85OHM_10INCH_DN")
	)
	(segment
		(start 377.265946 -163.717224)
		(end 377.528328 -163.67125)
		(width 0.1143)
		(layer "In9.Cu")
		(net "L10_85OHM_10INCH_DN")
	)
	(segment
		(start 369.559078 -166.012876)
		(end 369.184174 -163.886134)
		(width 0.1143)
		(layer "In9.Cu")
		(net "L10_85OHM_10INCH_DN")
	)
	(segment
		(start 355.142292 -163.69538)
		(end 355.275134 -163.788598)
		(width 0.1143)
		(layer "In9.Cu")
		(net "L10_85OHM_10INCH_DN")
	)
	(segment
		(start 383.462784 -165.166294)
		(end 383.462784 -165.667944)
		(width 0.1143)
		(layer "In9.Cu")
		(net "L10_85OHM_10INCH_DN")
	)
	(segment
		(start 365.61649 -166.378636)
		(end 366.117632 -166.28999)
		(width 0.1143)
		(layer "In9.Cu")
		(net "L10_85OHM_10INCH_DN")
	)
	(segment
		(start 353.28098 -163.741354)
		(end 353.543108 -163.695126)
		(width 0.1143)
		(layer "In9.Cu")
		(net "L10_85OHM_10INCH_DN")
	)
	(segment
		(start 346.092526 -166.126922)
		(end 346.423742 -166.358062)
		(width 0.1143)
		(layer "In9.Cu")
		(net "L10_85OHM_10INCH_DN")
	)
	(segment
		(start 363.273848 -163.804854)
		(end 363.684312 -166.132002)
		(width 0.1143)
		(layer "In9.Cu")
		(net "L10_85OHM_10INCH_DN")
	)
	(segment
		(start 358.117394 -166.263066)
		(end 358.348534 -165.932104)
		(width 0.1143)
		(layer "In9.Cu")
		(net "L10_85OHM_10INCH_DN")
	)
	(segment
		(start 343.684352 -163.732718)
		(end 343.946988 -163.686236)
		(width 0.1143)
		(layer "In9.Cu")
		(net "L10_85OHM_10INCH_DN")
	)
	(segment
		(start 382.329436 -163.692078)
		(end 382.462024 -163.784788)
		(width 0.1143)
		(layer "In9.Cu")
		(net "L10_85OHM_10INCH_DN")
	)
	(segment
		(start 342.128348 -166.274242)
		(end 342.359488 -165.94328)
		(width 0.1143)
		(layer "In9.Cu")
		(net "L10_85OHM_10INCH_DN")
	)
	(segment
		(start 364.481364 -163.778184)
		(end 364.744 -163.731956)
		(width 0.1143)
		(layer "In9.Cu")
		(net "L10_85OHM_10INCH_DN")
	)
	(segment
		(start 369.327938 -166.344092)
		(end 369.559078 -166.012876)
		(width 0.1143)
		(layer "In9.Cu")
		(net "L10_85OHM_10INCH_DN")
	)
	(segment
		(start 327.250552 -166.45636)
		(end 327.750678 -166.36873)
		(width 0.1143)
		(layer "In9.Cu")
		(net "L10_85OHM_10INCH_DN")
	)
	(segment
		(start 360.48188 -166.111682)
		(end 360.813096 -166.342822)
		(width 0.1143)
		(layer "In9.Cu")
		(net "L10_85OHM_10INCH_DN")
	)
	(segment
		(start 368.495072 -166.200582)
		(end 368.826796 -166.432484)
		(width 0.1143)
		(layer "In9.Cu")
		(net "L10_85OHM_10INCH_DN")
	)
	(segment
		(start 323.160898 -163.70173)
		(end 323.292724 -163.793932)
		(width 0.1143)
		(layer "In9.Cu")
		(net "L10_85OHM_10INCH_DN")
	)
	(segment
		(start 369.184174 -163.886134)
		(end 369.283488 -163.743894)
		(width 0.1143)
		(layer "In9.Cu")
		(net "L10_85OHM_10INCH_DN")
	)
	(segment
		(start 339.162898 -165.951154)
		(end 338.79917 -163.889436)
		(width 0.1143)
		(layer "In9.Cu")
		(net "L10_85OHM_10INCH_DN")
	)
	(segment
		(start 359.213912 -166.342568)
		(end 359.715308 -166.254684)
		(width 0.1143)
		(layer "In9.Cu")
		(net "L10_85OHM_10INCH_DN")
	)
	(segment
		(start 360.073448 -163.792916)
		(end 360.48188 -166.111682)
		(width 0.1143)
		(layer "In9.Cu")
		(net "L10_85OHM_10INCH_DN")
	)
	(segment
		(start 382.0668 -163.738306)
		(end 382.329436 -163.692078)
		(width 0.1143)
		(layer "In9.Cu")
		(net "L10_85OHM_10INCH_DN")
	)
	(segment
		(start 331.71257 -166.197026)
		(end 332.043278 -166.428166)
		(width 0.1143)
		(layer "In9.Cu")
		(net "L10_85OHM_10INCH_DN")
	)
	(segment
		(start 323.72046 -166.219632)
		(end 324.051676 -166.451788)
		(width 0.1143)
		(layer "In9.Cu")
		(net "L10_85OHM_10INCH_DN")
	)
	(segment
		(start 372.756176 -166.005764)
		(end 372.380764 -163.878514)
		(width 0.1143)
		(layer "In9.Cu")
		(net "L10_85OHM_10INCH_DN")
	)
	(segment
		(start 328.51852 -166.224204)
		(end 328.849482 -166.456868)
		(width 0.1143)
		(layer "In9.Cu")
		(net "L10_85OHM_10INCH_DN")
	)
	(segment
		(start 366.340898 -163.718494)
		(end 366.473232 -163.811204)
		(width 0.1143)
		(layer "In9.Cu")
		(net "L10_85OHM_10INCH_DN")
	)
	(segment
		(start 334.143604 -166.344854)
		(end 334.374998 -166.012876)
		(width 0.1143)
		(layer "In9.Cu")
		(net "L10_85OHM_10INCH_DN")
	)
	(segment
		(start 324.051676 -166.451788)
		(end 324.553072 -166.363396)
		(width 0.1143)
		(layer "In9.Cu")
		(net "L10_85OHM_10INCH_DN")
	)
	(segment
		(start 352.077274 -163.787836)
		(end 352.486976 -166.115492)
		(width 0.1143)
		(layer "In9.Cu")
		(net "L10_85OHM_10INCH_DN")
	)
	(segment
		(start 362.412534 -166.347648)
		(end 362.913676 -166.259002)
		(width 0.1143)
		(layer "In9.Cu")
		(net "L10_85OHM_10INCH_DN")
	)
	(segment
		(start 337.332574 -166.281862)
		(end 337.563714 -165.950646)
		(width 0.1143)
		(layer "In9.Cu")
		(net "L10_85OHM_10INCH_DN")
	)
	(segment
		(start 359.678478 -163.74618)
		(end 359.94086 -163.700206)
		(width 0.1143)
		(layer "In9.Cu")
		(net "L10_85OHM_10INCH_DN")
	)
	(segment
		(start 356.740714 -163.691062)
		(end 356.87381 -163.784534)
		(width 0.1143)
		(layer "In9.Cu")
		(net "L10_85OHM_10INCH_DN")
	)
	(segment
		(start 362.913676 -166.259002)
		(end 363.145578 -165.927786)
		(width 0.1143)
		(layer "In9.Cu")
		(net "L10_85OHM_10INCH_DN")
	)
	(segment
		(start 336.084418 -163.787074)
		(end 336.50047 -166.13886)
		(width 0.1143)
		(layer "In9.Cu")
		(net "L10_85OHM_10INCH_DN")
	)
	(segment
		(start 354.086414 -166.115492)
		(end 354.417376 -166.346378)
		(width 0.1143)
		(layer "In9.Cu")
		(net "L10_85OHM_10INCH_DN")
	)
	(segment
		(start 371.269006 -163.78809)
		(end 371.692424 -166.193978)
		(width 0.1143)
		(layer "In9.Cu")
		(net "L10_85OHM_10INCH_DN")
	)
	(segment
		(start 366.078262 -163.764722)
		(end 366.340898 -163.718494)
		(width 0.1143)
		(layer "In9.Cu")
		(net "L10_85OHM_10INCH_DN")
	)
	(segment
		(start 346.423742 -166.358062)
		(end 346.925138 -166.270178)
		(width 0.1143)
		(layer "In9.Cu")
		(net "L10_85OHM_10INCH_DN")
	)
	(segment
		(start 364.014512 -166.363142)
		(end 364.515654 -166.274496)
		(width 0.1143)
		(layer "In9.Cu")
		(net "L10_85OHM_10INCH_DN")
	)
	(segment
		(start 344.07983 -163.779708)
		(end 344.495628 -166.135304)
		(width 0.1143)
		(layer "In9.Cu")
		(net "L10_85OHM_10INCH_DN")
	)
	(segment
		(start 337.546696 -163.711636)
		(end 337.688936 -163.811204)
		(width 0.1143)
		(layer "In9.Cu")
		(net "L10_85OHM_10INCH_DN")
	)
	(segment
		(start 375.573544 -163.849812)
		(end 375.666254 -163.717478)
		(width 0.1143)
		(layer "In9.Cu")
		(net "L10_85OHM_10INCH_DN")
	)
	(segment
		(start 322.118736 -166.204138)
		(end 322.44919 -166.435786)
		(width 0.1143)
		(layer "In9.Cu")
		(net "L10_85OHM_10INCH_DN")
	)
	(segment
		(start 321.384422 -165.173406)
		(end 321.496182 -165.061646)
		(width 0.1143)
		(layer "In9.Cu")
		(net "L10_85OHM_10INCH_DN")
	)
	(segment
		(start 326.492108 -163.799266)
		(end 326.91959 -166.225474)
		(width 0.1143)
		(layer "In9.Cu")
		(net "L10_85OHM_10INCH_DN")
	)
	(segment
		(start 338.89188 -163.75634)
		(end 339.154008 -163.71062)
		(width 0.1143)
		(layer "In9.Cu")
		(net "L10_85OHM_10INCH_DN")
	)
	(segment
		(start 357.984806 -163.86937)
		(end 358.07777 -163.73729)
		(width 0.1143)
		(layer "In9.Cu")
		(net "L10_85OHM_10INCH_DN")
	)
	(segment
		(start 362.082334 -166.116508)
		(end 362.412534 -166.347648)
		(width 0.1143)
		(layer "In9.Cu")
		(net "L10_85OHM_10INCH_DN")
	)
	(segment
		(start 345.2876 -163.752784)
		(end 345.549982 -163.70681)
		(width 0.1143)
		(layer "In9.Cu")
		(net "L10_85OHM_10INCH_DN")
	)
	(segment
		(start 330.944982 -166.340028)
		(end 331.176122 -166.008558)
		(width 0.1143)
		(layer "In9.Cu")
		(net "L10_85OHM_10INCH_DN")
	)
	(segment
		(start 343.946988 -163.686236)
		(end 344.07983 -163.779708)
		(width 0.1143)
		(layer "In9.Cu")
		(net "L10_85OHM_10INCH_DN")
	)
	(segment
		(start 322.898262 -163.748212)
		(end 323.160898 -163.70173)
		(width 0.1143)
		(layer "In9.Cu")
		(net "L10_85OHM_10INCH_DN")
	)
	(segment
		(start 364.388654 -163.910772)
		(end 364.481364 -163.778184)
		(width 0.1143)
		(layer "In9.Cu")
		(net "L10_85OHM_10INCH_DN")
	)
	(segment
		(start 341.296244 -166.130986)
		(end 341.627206 -166.361872)
		(width 0.1143)
		(layer "In9.Cu")
		(net "L10_85OHM_10INCH_DN")
	)
	(segment
		(start 345.549982 -163.70681)
		(end 345.68257 -163.799266)
		(width 0.1143)
		(layer "In9.Cu")
		(net "L10_85OHM_10INCH_DN")
	)
	(segment
		(start 372.023386 -166.424864)
		(end 372.524782 -166.33698)
		(width 0.1143)
		(layer "In9.Cu")
		(net "L10_85OHM_10INCH_DN")
	)
	(segment
		(start 361.183936 -163.874958)
		(end 361.276646 -163.742116)
		(width 0.1143)
		(layer "In9.Cu")
		(net "L10_85OHM_10INCH_DN")
	)
	(segment
		(start 383.359914 -165.063678)
		(end 383.462784 -165.166294)
		(width 0.1143)
		(layer "In9.Cu")
		(net "L10_85OHM_10INCH_DN")
	)
	(segment
		(start 356.385368 -163.869878)
		(end 356.478078 -163.737544)
		(width 0.1143)
		(layer "In9.Cu")
		(net "L10_85OHM_10INCH_DN")
	)
	(segment
		(start 342.08974 -163.756848)
		(end 342.352122 -163.710874)
		(width 0.1143)
		(layer "In9.Cu")
		(net "L10_85OHM_10INCH_DN")
	)
	(segment
		(start 322.950586 -166.347648)
		(end 323.18198 -166.016432)
		(width 0.1143)
		(layer "In9.Cu")
		(net "L10_85OHM_10INCH_DN")
	)
	(segment
		(start 332.043278 -166.428166)
		(end 332.543912 -166.340028)
		(width 0.1143)
		(layer "In9.Cu")
		(net "L10_85OHM_10INCH_DN")
	)
	(segment
		(start 346.887546 -163.757356)
		(end 347.149928 -163.711382)
		(width 0.1143)
		(layer "In9.Cu")
		(net "L10_85OHM_10INCH_DN")
	)
	(segment
		(start 364.515654 -166.274496)
		(end 364.747556 -165.94328)
		(width 0.1143)
		(layer "In9.Cu")
		(net "L10_85OHM_10INCH_DN")
	)
	(segment
		(start 374.334786 -163.699952)
		(end 374.467628 -163.79317)
		(width 0.1143)
		(layer "In9.Cu")
		(net "L10_85OHM_10INCH_DN")
	)
	(segment
		(start 380.51994 -166.333424)
		(end 380.75108 -166.002462)
		(width 0.1143)
		(layer "In9.Cu")
		(net "L10_85OHM_10INCH_DN")
	)
	(segment
		(start 325.31939 -166.220648)
		(end 325.650352 -166.451788)
		(width 0.1143)
		(layer "In9.Cu")
		(net "L10_85OHM_10INCH_DN")
	)
	(segment
		(start 329.293728 -163.744402)
		(end 329.556364 -163.69792)
		(width 0.1143)
		(layer "In9.Cu")
		(net "L10_85OHM_10INCH_DN")
	)
	(segment
		(start 332.543912 -166.340028)
		(end 332.775306 -166.008812)
		(width 0.1143)
		(layer "In9.Cu")
		(net "L10_85OHM_10INCH_DN")
	)
	(segment
		(start 354.417376 -166.346378)
		(end 354.918518 -166.258748)
		(width 0.1143)
		(layer "In9.Cu")
		(net "L10_85OHM_10INCH_DN")
	)
	(segment
		(start 327.750678 -166.36873)
		(end 327.983088 -166.03853)
		(width 0.1143)
		(layer "In9.Cu")
		(net "L10_85OHM_10INCH_DN")
	)
	(segment
		(start 377.660916 -163.763706)
		(end 378.088144 -166.189914)
		(width 0.1143)
		(layer "In9.Cu")
		(net "L10_85OHM_10INCH_DN")
	)
	(segment
		(start 340.529164 -166.273988)
		(end 340.760558 -165.942772)
		(width 0.1143)
		(layer "In9.Cu")
		(net "L10_85OHM_10INCH_DN")
	)
	(segment
		(start 364.876334 -163.824666)
		(end 365.28629 -166.147496)
		(width 0.1143)
		(layer "In9.Cu")
		(net "L10_85OHM_10INCH_DN")
	)
	(segment
		(start 342.352122 -163.710874)
		(end 342.484964 -163.804092)
		(width 0.1143)
		(layer "In9.Cu")
		(net "L10_85OHM_10INCH_DN")
	)
	(segment
		(start 357.615998 -166.351204)
		(end 358.117394 -166.263066)
		(width 0.1143)
		(layer "In9.Cu")
		(net "L10_85OHM_10INCH_DN")
	)
	(segment
		(start 339.154008 -163.71062)
		(end 339.287104 -163.80333)
		(width 0.1143)
		(layer "In9.Cu")
		(net "L10_85OHM_10INCH_DN")
	)
	(segment
		(start 351.58934 -163.873942)
		(end 351.68205 -163.740846)
		(width 0.1143)
		(layer "In9.Cu")
		(net "L10_85OHM_10INCH_DN")
	)
	(segment
		(start 350.123506 -166.274496)
		(end 350.355408 -165.94328)
		(width 0.1143)
		(layer "In9.Cu")
		(net "L10_85OHM_10INCH_DN")
	)
	(segment
		(start 347.69171 -166.127176)
		(end 348.022926 -166.358316)
		(width 0.1143)
		(layer "In9.Cu")
		(net "L10_85OHM_10INCH_DN")
	)
	(segment
		(start 361.276646 -163.742116)
		(end 361.538774 -163.696142)
		(width 0.1143)
		(layer "In9.Cu")
		(net "L10_85OHM_10INCH_DN")
	)
	(segment
		(start 370.425726 -166.433246)
		(end 370.927122 -166.345362)
		(width 0.1143)
		(layer "In9.Cu")
		(net "L10_85OHM_10INCH_DN")
	)
	(segment
		(start 355.149658 -165.927786)
		(end 354.787454 -163.873942)
		(width 0.1143)
		(layer "In9.Cu")
		(net "L10_85OHM_10INCH_DN")
	)
	(segment
		(start 372.524782 -166.33698)
		(end 372.756176 -166.005764)
		(width 0.1143)
		(layer "In9.Cu")
		(net "L10_85OHM_10INCH_DN")
	)
	(segment
		(start 375.954544 -166.010844)
		(end 375.573544 -163.849812)
		(width 0.1143)
		(layer "In9.Cu")
		(net "L10_85OHM_10INCH_DN")
	)
	(segment
		(start 361.67187 -163.78936)
		(end 362.082334 -166.116508)
		(width 0.1143)
		(layer "In9.Cu")
		(net "L10_85OHM_10INCH_DN")
	)
	(segment
		(start 324.760336 -163.706302)
		(end 324.893178 -163.799012)
		(width 0.1143)
		(layer "In9.Cu")
		(net "L10_85OHM_10INCH_DN")
	)
	(segment
		(start 346.794836 -163.889944)
		(end 346.887546 -163.757356)
		(width 0.1143)
		(layer "In9.Cu")
		(net "L10_85OHM_10INCH_DN")
	)
	(segment
		(start 358.07777 -163.73729)
		(end 358.340152 -163.691316)
		(width 0.1143)
		(layer "In9.Cu")
		(net "L10_85OHM_10INCH_DN")
	)
	(segment
		(start 327.602088 -163.876736)
		(end 327.694544 -163.744402)
		(width 0.1143)
		(layer "In9.Cu")
		(net "L10_85OHM_10INCH_DN")
	)
	(segment
		(start 348.748604 -163.711636)
		(end 348.8817 -163.804854)
		(width 0.1143)
		(layer "In9.Cu")
		(net "L10_85OHM_10INCH_DN")
	)
	(segment
		(start 348.524322 -166.270432)
		(end 348.755462 -165.93947)
		(width 0.1143)
		(layer "In9.Cu")
		(net "L10_85OHM_10INCH_DN")
	)
	(segment
		(start 356.749096 -165.932358)
		(end 356.385368 -163.869878)
		(width 0.1143)
		(layer "In9.Cu")
		(net "L10_85OHM_10INCH_DN")
	)
	(segment
		(start 350.084136 -163.749228)
		(end 350.346772 -163.703)
		(width 0.1143)
		(layer "In9.Cu")
		(net "L10_85OHM_10INCH_DN")
	)
	(segment
		(start 324.40499 -163.884864)
		(end 324.497446 -163.75253)
		(width 0.1143)
		(layer "In9.Cu")
		(net "L10_85OHM_10INCH_DN")
	)
	(segment
		(start 337.688936 -163.811204)
		(end 338.099146 -166.139368)
		(width 0.1143)
		(layer "In9.Cu")
		(net "L10_85OHM_10INCH_DN")
	)
	(segment
		(start 374.467628 -163.79317)
		(end 374.891554 -166.19855)
		(width 0.1143)
		(layer "In9.Cu")
		(net "L10_85OHM_10INCH_DN")
	)
	(segment
		(start 354.918518 -166.258748)
		(end 355.149658 -165.927786)
		(width 0.1143)
		(layer "In9.Cu")
		(net "L10_85OHM_10INCH_DN")
	)
	(segment
		(start 372.380764 -163.878514)
		(end 372.473474 -163.745926)
		(width 0.1143)
		(layer "In9.Cu")
		(net "L10_85OHM_10INCH_DN")
	)
	(segment
		(start 338.79917 -163.889436)
		(end 338.89188 -163.75634)
		(width 0.1143)
		(layer "In9.Cu")
		(net "L10_85OHM_10INCH_DN")
	)
	(segment
		(start 333.64297 -166.43223)
		(end 334.143604 -166.344854)
		(width 0.1143)
		(layer "In9.Cu")
		(net "L10_85OHM_10INCH_DN")
	)
	(segment
		(start 349.622364 -166.363142)
		(end 350.123506 -166.274496)
		(width 0.1143)
		(layer "In9.Cu")
		(net "L10_85OHM_10INCH_DN")
	)
	(segment
		(start 359.715308 -166.254684)
		(end 359.946448 -165.923722)
		(width 0.1143)
		(layer "In9.Cu")
		(net "L10_85OHM_10INCH_DN")
	)
	(segment
		(start 364.747556 -165.94328)
		(end 364.388654 -163.910772)
		(width 0.1143)
		(layer "In9.Cu")
		(net "L10_85OHM_10INCH_DN")
	)
	(segment
		(start 340.760558 -165.942772)
		(end 340.3981 -163.889436)
		(width 0.1143)
		(layer "In9.Cu")
		(net "L10_85OHM_10INCH_DN")
	)
	(segment
		(start 362.786168 -163.89096)
		(end 362.878878 -163.758118)
		(width 0.1143)
		(layer "In9.Cu")
		(net "L10_85OHM_10INCH_DN")
	)
	(segment
		(start 382.351026 -166.006272)
		(end 381.97409 -163.870894)
		(width 0.1143)
		(layer "In9.Cu")
		(net "L10_85OHM_10INCH_DN")
	)
	(segment
		(start 338.099146 -166.139368)
		(end 338.430108 -166.370254)
		(width 0.1143)
		(layer "In9.Cu")
		(net "L10_85OHM_10INCH_DN")
	)
	(segment
		(start 322.44919 -166.435786)
		(end 322.950586 -166.347648)
		(width 0.1143)
		(layer "In9.Cu")
		(net "L10_85OHM_10INCH_DN")
	)
	(segment
		(start 372.473474 -163.745926)
		(end 372.735602 -163.699698)
		(width 0.1143)
		(layer "In9.Cu")
		(net "L10_85OHM_10INCH_DN")
	)
	(segment
		(start 377.172982 -163.849304)
		(end 377.265946 -163.717224)
		(width 0.1143)
		(layer "In9.Cu")
		(net "L10_85OHM_10INCH_DN")
	)
	(segment
		(start 366.888268 -166.16299)
		(end 367.218468 -166.39413)
		(width 0.1143)
		(layer "In9.Cu")
		(net "L10_85OHM_10INCH_DN")
	)
	(segment
		(start 332.399894 -163.881562)
		(end 332.492604 -163.748974)
		(width 0.1143)
		(layer "In9.Cu")
		(net "L10_85OHM_10INCH_DN")
	)
	(segment
		(start 338.931504 -166.28237)
		(end 339.162898 -165.951154)
		(width 0.1143)
		(layer "In9.Cu")
		(net "L10_85OHM_10INCH_DN")
	)
	(segment
		(start 332.775306 -166.008812)
		(end 332.399894 -163.881562)
		(width 0.1143)
		(layer "In9.Cu")
		(net "L10_85OHM_10INCH_DN")
	)
	(segment
		(start 342.484964 -163.804092)
		(end 342.895936 -166.135558)
		(width 0.1143)
		(layer "In9.Cu")
		(net "L10_85OHM_10INCH_DN")
	)
	(segment
		(start 380.75108 -166.002462)
		(end 380.372112 -163.855146)
		(width 0.1143)
		(layer "In9.Cu")
		(net "L10_85OHM_10INCH_DN")
	)
	(segment
		(start 321.971162 -165.441376)
		(end 322.014088 -165.61054)
		(width 0.1143)
		(layer "In9.Cu")
		(net "L10_85OHM_10INCH_DN")
	)
	(segment
		(start 365.985552 -163.89731)
		(end 366.078262 -163.764722)
		(width 0.1143)
		(layer "In9.Cu")
		(net "L10_85OHM_10INCH_DN")
	)
	(segment
		(start 356.51821 -166.262812)
		(end 356.749096 -165.932358)
		(width 0.1143)
		(layer "In9.Cu")
		(net "L10_85OHM_10INCH_DN")
	)
	(segment
		(start 380.859792 -163.769294)
		(end 381.287782 -166.194994)
		(width 0.1143)
		(layer "In9.Cu")
		(net "L10_85OHM_10INCH_DN")
	)
	(segment
		(start 348.755462 -165.93947)
		(end 348.393766 -163.890452)
		(width 0.1143)
		(layer "In9.Cu")
		(net "L10_85OHM_10INCH_DN")
	)
	(segment
		(start 324.497446 -163.75253)
		(end 324.760336 -163.706302)
		(width 0.1143)
		(layer "In9.Cu")
		(net "L10_85OHM_10INCH_DN")
	)
	(segment
		(start 376.061732 -163.764468)
		(end 376.491246 -166.198296)
		(width 0.1143)
		(layer "In9.Cu")
		(net "L10_85OHM_10INCH_DN")
	)
	(segment
		(start 373.291862 -166.193978)
		(end 373.622824 -166.424864)
		(width 0.1143)
		(layer "In9.Cu")
		(net "L10_85OHM_10INCH_DN")
	)
	(segment
		(start 369.6716 -163.800282)
		(end 370.094764 -166.20236)
		(width 0.1143)
		(layer "In9.Cu")
		(net "L10_85OHM_10INCH_DN")
	)
	(segment
		(start 380.372112 -163.855146)
		(end 380.464568 -163.722304)
		(width 0.1143)
		(layer "In9.Cu")
		(net "L10_85OHM_10INCH_DN")
	)
	(segment
		(start 374.355106 -166.006272)
		(end 373.979948 -163.878514)
		(width 0.1143)
		(layer "In9.Cu")
		(net "L10_85OHM_10INCH_DN")
	)
	(segment
		(start 326.15124 -166.364158)
		(end 326.382888 -166.032942)
		(width 0.1143)
		(layer "In9.Cu")
		(net "L10_85OHM_10INCH_DN")
	)
	(segment
		(start 333.311246 -166.201344)
		(end 333.64297 -166.43223)
		(width 0.1143)
		(layer "In9.Cu")
		(net "L10_85OHM_10INCH_DN")
	)
	(segment
		(start 345.558364 -165.947598)
		(end 345.194636 -163.884864)
		(width 0.1143)
		(layer "In9.Cu")
		(net "L10_85OHM_10INCH_DN")
	)
	(segment
		(start 371.13591 -163.69538)
		(end 371.269006 -163.78809)
		(width 0.1143)
		(layer "In9.Cu")
		(net "L10_85OHM_10INCH_DN")
	)
	(segment
		(start 326.004174 -163.885118)
		(end 326.09663 -163.752784)
		(width 0.1143)
		(layer "In9.Cu")
		(net "L10_85OHM_10INCH_DN")
	)
	(segment
		(start 145.580354 11.879834)
		(end 135.055864 11.879834)
		(width 0.14224)
		(layer "In9.Cu")
		(net "L10_73OHM_6INCH_DP")
	)
	(segment
		(start 197.510654 10.83564)
		(end 148.22424 10.83564)
		(width 0.14224)
		(layer "In9.Cu")
		(net "L10_73OHM_6INCH_DP")
	)
	(segment
		(start 135.055864 11.879834)
		(end 133.920484 10.744454)
		(width 0.14224)
		(layer "In9.Cu")
		(net "L10_73OHM_6INCH_DP")
	)
	(segment
		(start 146.42592 12.7254)
		(end 145.580354 11.879834)
		(width 0.14224)
		(layer "In9.Cu")
		(net "L10_73OHM_6INCH_DP")
	)
	(segment
		(start 197.397624 12.7254)
		(end 146.42592 12.7254)
		(width 0.14224)
		(layer "In9.Cu")
		(net "L10_73OHM_6INCH_DP")
	)
	(segment
		(start 148.22424 12.04976)
		(end 197.397624 12.04976)
		(width 0.14224)
		(layer "In9.Cu")
		(net "L10_73OHM_6INCH_DP")
	)
	(arc
		(start 197.397624 12.04976)
		(mid 197.735444 12.38758)
		(end 197.397624 12.7254)
		(width 0.14224)
		(layer "In9.Cu")
		(net "L10_73OHM_6INCH_DP")
	)
	(arc
		(start 148.22424 10.83564)
		(mid 147.61718 11.4427)
		(end 148.22424 12.04976)
		(width 0.14224)
		(layer "In9.Cu")
		(net "L10_73OHM_6INCH_DP")
	)
	(segment
		(start 146.31416 12.99464)
		(end 145.468594 12.149074)
		(width 0.14224)
		(layer "In9.Cu")
		(net "L10_73OHM_6INCH_DN")
	)
	(segment
		(start 197.397624 12.99464)
		(end 146.31416 12.99464)
		(width 0.14224)
		(layer "In9.Cu")
		(net "L10_73OHM_6INCH_DN")
	)
	(segment
		(start 135.055864 12.149074)
		(end 133.920484 13.284454)
		(width 0.14224)
		(layer "In9.Cu")
		(net "L10_73OHM_6INCH_DN")
	)
	(segment
		(start 197.510654 11.10488)
		(end 148.22424 11.10488)
		(width 0.14224)
		(layer "In9.Cu")
		(net "L10_73OHM_6INCH_DN")
	)
	(segment
		(start 145.468594 12.149074)
		(end 135.055864 12.149074)
		(width 0.14224)
		(layer "In9.Cu")
		(net "L10_73OHM_6INCH_DN")
	)
	(segment
		(start 148.22424 11.78052)
		(end 197.397624 11.78052)
		(width 0.14224)
		(layer "In9.Cu")
		(net "L10_73OHM_6INCH_DN")
	)
	(arc
		(start 148.22424 11.10488)
		(mid 147.88642 11.4427)
		(end 148.22424 11.78052)
		(width 0.14224)
		(layer "In9.Cu")
		(net "L10_73OHM_6INCH_DN")
	)
	(arc
		(start 197.397624 11.78052)
		(mid 198.004684 12.38758)
		(end 197.397624 12.99464)
		(width 0.14224)
		(layer "In9.Cu")
		(net "L10_73OHM_6INCH_DN")
	)
	(segment
		(start 26.5303 14.2748)
		(end 25.527 13.2715)
		(width 0.089408)
		(layer "In9.Cu")
		(net "L10_50OHM_6INCH")
	)
	(segment
		(start 37.820854 12.825984)
		(end 113.159286 12.825984)
		(width 0.089408)
		(layer "In9.Cu")
		(net "L10_50OHM_6INCH")
	)
	(segment
		(start 36.83762 14.2748)
		(end 26.5303 14.2748)
		(width 0.089408)
		(layer "In9.Cu")
		(net "L10_50OHM_6INCH")
	)
	(segment
		(start 113.159286 13.677392)
		(end 37.435028 13.677392)
		(width 0.089408)
		(layer "In9.Cu")
		(net "L10_50OHM_6INCH")
	)
	(segment
		(start 37.435028 13.677392)
		(end 36.83762 14.2748)
		(width 0.089408)
		(layer "In9.Cu")
		(net "L10_50OHM_6INCH")
	)
	(arc
		(start 113.159286 12.825984)
		(mid 113.58499 13.251688)
		(end 113.159286 13.677392)
		(width 0.089408)
		(layer "In9.Cu")
		(net "L10_50OHM_6INCH")
	)
	(segment
		(start 36.6268 12.0142)
		(end 26.8097 12.0142)
		(width 0.14224)
		(layer "In9.Cu")
		(net "L10_40OHM_6INCH")
	)
	(segment
		(start 26.8097 12.0142)
		(end 25.527 10.7315)
		(width 0.14224)
		(layer "In9.Cu")
		(net "L10_40OHM_6INCH")
	)
	(segment
		(start 112.559084 11.66241)
		(end 36.97859 11.66241)
		(width 0.14224)
		(layer "In9.Cu")
		(net "L10_40OHM_6INCH")
	)
	(segment
		(start 37.159946 10.75817)
		(end 112.559084 10.75817)
		(width 0.14224)
		(layer "In9.Cu")
		(net "L10_40OHM_6INCH")
	)
	(segment
		(start 36.97859 11.66241)
		(end 36.6268 12.0142)
		(width 0.14224)
		(layer "In9.Cu")
		(net "L10_40OHM_6INCH")
	)
	(arc
		(start 112.559084 10.75817)
		(mid 113.011204 11.21029)
		(end 112.559084 11.66241)
		(width 0.14224)
		(layer "In9.Cu")
		(net "L10_40OHM_6INCH")
	)
	(segment
		(start 371.72138 12.66698)
		(end 370.848128 11.793728)
		(width 0.089154)
		(layer "In9.Cu")
		(net "L10_100OHM_6INCH_DP")
	)
	(segment
		(start 359.773982 11.793728)
		(end 358.713532 10.733278)
		(width 0.089154)
		(layer "In9.Cu")
		(net "L10_100OHM_6INCH_DP")
	)
	(segment
		(start 422.721278 10.583164)
		(end 373.5324 10.583164)
		(width 0.089154)
		(layer "In9.Cu")
		(net "L10_100OHM_6INCH_DP")
	)
	(segment
		(start 370.848128 11.793728)
		(end 359.773982 11.793728)
		(width 0.089154)
		(layer "In9.Cu")
		(net "L10_100OHM_6INCH_DP")
	)
	(segment
		(start 422.595802 12.66698)
		(end 371.72138 12.66698)
		(width 0.089154)
		(layer "In9.Cu")
		(net "L10_100OHM_6INCH_DP")
	)
	(segment
		(start 373.5324 12.044426)
		(end 422.595802 12.044426)
		(width 0.089154)
		(layer "In9.Cu")
		(net "L10_100OHM_6INCH_DP")
	)
	(arc
		(start 422.595802 12.044426)
		(mid 422.907206 12.35583)
		(end 422.595802 12.66698)
		(width 0.089154)
		(layer "In9.Cu")
		(net "L10_100OHM_6INCH_DP")
	)
	(arc
		(start 373.5324 10.583164)
		(mid 372.801642 11.313922)
		(end 373.5324 12.044426)
		(width 0.089154)
		(layer "In9.Cu")
		(net "L10_100OHM_6INCH_DP")
	)
	(segment
		(start 373.5324 11.625072)
		(end 422.595802 11.625072)
		(width 0.089154)
		(layer "In9.Cu")
		(net "L10_100OHM_6INCH_DN")
	)
	(segment
		(start 371.547644 13.086334)
		(end 370.674392 12.213082)
		(width 0.089154)
		(layer "In9.Cu")
		(net "L10_100OHM_6INCH_DN")
	)
	(segment
		(start 370.674392 12.213082)
		(end 359.773728 12.213082)
		(width 0.089154)
		(layer "In9.Cu")
		(net "L10_100OHM_6INCH_DN")
	)
	(segment
		(start 422.595802 13.086334)
		(end 371.547644 13.086334)
		(width 0.089154)
		(layer "In9.Cu")
		(net "L10_100OHM_6INCH_DN")
	)
	(segment
		(start 359.773728 12.213082)
		(end 358.713532 13.273278)
		(width 0.089154)
		(layer "In9.Cu")
		(net "L10_100OHM_6INCH_DN")
	)
	(segment
		(start 422.721278 11.002518)
		(end 373.5324 11.002518)
		(width 0.089154)
		(layer "In9.Cu")
		(net "L10_100OHM_6INCH_DN")
	)
	(arc
		(start 422.595802 11.625072)
		(mid 423.32656 12.35583)
		(end 422.595802 13.086334)
		(width 0.089154)
		(layer "In9.Cu")
		(net "L10_100OHM_6INCH_DN")
	)
	(arc
		(start 373.5324 11.002518)
		(mid 373.220996 11.313922)
		(end 373.5324 11.625072)
		(width 0.089154)
		(layer "In9.Cu")
		(net "L10_100OHM_6INCH_DN")
	)
	(segment
		(start 375.369582 -98.71964)
		(end 375.00052 -98.71964)
		(width 0.10795)
		(layer "F.Cu")
		(net "TP_PCH_GDP8_SUSCLK")
	)
	(segment
		(start 372.03888 -97.1296)
		(end 371.9576 -97.21088)
		(width 0.10795)
		(layer "F.Cu")
		(net "TP_PCH_GDP8_SUSCLK")
	)
	(segment
		(start 374.4087 -97.1296)
		(end 372.03888 -97.1296)
		(width 0.10795)
		(layer "F.Cu")
		(net "TP_PCH_GDP8_SUSCLK")
	)
	(segment
		(start 375.00052 -98.71964)
		(end 374.75414 -98.47326)
		(width 0.10795)
		(layer "F.Cu")
		(net "TP_PCH_GDP8_SUSCLK")
	)
	(segment
		(start 375.504964 -98.855022)
		(end 375.369582 -98.71964)
		(width 0.10795)
		(layer "F.Cu")
		(net "TP_PCH_GDP8_SUSCLK")
	)
	(segment
		(start 375.008394 -97.977452)
		(end 375.008394 -97.729294)
		(width 0.10795)
		(layer "F.Cu")
		(net "TP_PCH_GDP8_SUSCLK")
	)
	(segment
		(start 374.75414 -98.47326)
		(end 374.75414 -98.231706)
		(width 0.10795)
		(layer "F.Cu")
		(net "TP_PCH_GDP8_SUSCLK")
	)
	(segment
		(start 375.008394 -97.729294)
		(end 374.4087 -97.1296)
		(width 0.10795)
		(layer "F.Cu")
		(net "TP_PCH_GDP8_SUSCLK")
	)
	(segment
		(start 374.75414 -98.231706)
		(end 375.008394 -97.977452)
		(width 0.10795)
		(layer "F.Cu")
		(net "TP_PCH_GDP8_SUSCLK")
	)
	(via
		(at 371.9576 -97.21088)
		(size 0.508)
		(drill 0.254)
		(layers "F.Cu" "B.Cu")
		(net "TP_PCH_GDP8_SUSCLK")
	)
	(via
		(at 372.92026 -97.50298)
		(size 0.6604)
		(drill 0.3302)
		(layers "F.Cu" "B.Cu")
		(net "TP_PCH_GDP8_SUSCLK")
	)
	(segment
		(start 371.9576 -97.21088)
		(end 372.2497 -97.50298)
		(width 0.10795)
		(layer "B.Cu")
		(net "TP_PCH_GDP8_SUSCLK")
	)
	(segment
		(start 372.2497 -97.50298)
		(end 372.92026 -97.50298)
		(width 0.10795)
		(layer "B.Cu")
		(net "TP_PCH_GDP8_SUSCLK")
	)
	(segment
		(start 482.501194 -48.3362)
		(end 482.524054 -48.35906)
		(width 0.10795)
		(layer "F.Cu")
		(net "PU_DEV_OFF_N")
	)
	(segment
		(start 482.2952 -49.617376)
		(end 482.2952 -49.938686)
		(width 0.10795)
		(layer "F.Cu")
		(net "PU_DEV_OFF_N")
	)
	(segment
		(start 482.2952 -49.224946)
		(end 482.2952 -49.617376)
		(width 0.10795)
		(layer "F.Cu")
		(net "PU_DEV_OFF_N")
	)
	(segment
		(start 482.524054 -48.996092)
		(end 482.2952 -49.224946)
		(width 0.10795)
		(layer "F.Cu")
		(net "PU_DEV_OFF_N")
	)
	(segment
		(start 482.2952 -49.938686)
		(end 482.03104 -50.202846)
		(width 0.10795)
		(layer "F.Cu")
		(net "PU_DEV_OFF_N")
	)
	(segment
		(start 482.524054 -48.35906)
		(end 482.524054 -48.996092)
		(width 0.10795)
		(layer "F.Cu")
		(net "PU_DEV_OFF_N")
	)
	(segment
		(start 482.03104 -50.202846)
		(end 482.03104 -50.47234)
		(width 0.10795)
		(layer "F.Cu")
		(net "PU_DEV_OFF_N")
	)
	(via
		(at 482.2952 -49.617376)
		(size 0.508)
		(drill 0.254)
		(layers "F.Cu" "B.Cu")
		(net "PU_DEV_OFF_N")
	)
	(segment
		(start 490.1184 -149.8854)
		(end 490.82706 -149.8854)
		(width 0.254)
		(layer "F.Cu")
		(net "SPA_5V_SIN_SW_D")
	)
	(segment
		(start 490.1184 -149.498812)
		(end 489.803948 -149.18436)
		(width 0.254)
		(layer "F.Cu")
		(net "SPA_5V_SIN_SW_D")
	)
	(segment
		(start 491.62716 -151.39416)
		(end 492.0234 -150.99792)
		(width 0.254)
		(layer "F.Cu")
		(net "SPA_5V_SIN_SW_D")
	)
	(segment
		(start 490.1184 -150.11146)
		(end 490.1184 -149.8854)
		(width 0.254)
		(layer "F.Cu")
		(net "SPA_5V_SIN_SW_D")
	)
	(segment
		(start 489.803948 -149.18436)
		(end 489.803948 -148.717)
		(width 0.254)
		(layer "F.Cu")
		(net "SPA_5V_SIN_SW_D")
	)
	(segment
		(start 492.0234 -150.99792)
		(end 492.21898 -150.99792)
		(width 0.254)
		(layer "F.Cu")
		(net "SPA_5V_SIN_SW_D")
	)
	(segment
		(start 490.1184 -149.8854)
		(end 490.1184 -149.498812)
		(width 0.254)
		(layer "F.Cu")
		(net "SPA_5V_SIN_SW_D")
	)
	(segment
		(start 489.3056 -150.92426)
		(end 490.1184 -150.11146)
		(width 0.254)
		(layer "F.Cu")
		(net "SPA_5V_SIN_SW_D")
	)
	(segment
		(start 489.3056 -151.0538)
		(end 489.3056 -150.92426)
		(width 0.254)
		(layer "F.Cu")
		(net "SPA_5V_SIN_SW_D")
	)
	(segment
		(start 491.423706 -151.39416)
		(end 491.62716 -151.39416)
		(width 0.254)
		(layer "F.Cu")
		(net "SPA_5V_SIN_SW_D")
	)
	(via
		(at 492.21898 -150.99792)
		(size 0.508)
		(drill 0.254)
		(layers "F.Cu" "B.Cu")
		(net "SPA_5V_SIN_SW_D")
	)
	(via
		(at 488.8992 -148.9456)
		(size 0.6604)
		(drill 0.3302)
		(layers "F.Cu" "B.Cu")
		(net "SPA_5V_SIN_SW_D")
	)
	(via
		(at 490.82706 -149.8854)
		(size 0.508)
		(drill 0.254)
		(layers "F.Cu" "B.Cu")
		(net "SPA_5V_SIN_SW_D")
	)
	(segment
		(start 489.1786 -149.225)
		(end 490.16666 -149.225)
		(width 0.10795)
		(layer "B.Cu")
		(net "SPA_5V_SIN_SW_D")
	)
	(segment
		(start 488.8992 -148.9456)
		(end 489.1786 -149.225)
		(width 0.10795)
		(layer "B.Cu")
		(net "SPA_5V_SIN_SW_D")
	)
	(segment
		(start 490.16666 -149.225)
		(end 490.82706 -149.8854)
		(width 0.10795)
		(layer "B.Cu")
		(net "SPA_5V_SIN_SW_D")
	)
	(segment
		(start 491.10646 -149.8854)
		(end 492.21898 -150.99792)
		(width 0.254)
		(layer "In2.Cu")
		(net "SPA_5V_SIN_SW_D")
	)
	(segment
		(start 490.82706 -149.8854)
		(end 491.10646 -149.8854)
		(width 0.254)
		(layer "In2.Cu")
		(net "SPA_5V_SIN_SW_D")
	)
	(segment
		(start 446.151 -142.29461)
		(end 445.83604 -142.60957)
		(width 0.10795)
		(layer "F.Cu")
		(net "BMC_PWR_DEBUG_BUF_N")
	)
	(segment
		(start 445.83604 -142.60957)
		(end 444.492634 -142.60957)
		(width 0.10795)
		(layer "F.Cu")
		(net "BMC_PWR_DEBUG_BUF_N")
	)
	(segment
		(start 446.151 -140.843)
		(end 446.151 -142.29461)
		(width 0.10795)
		(layer "F.Cu")
		(net "BMC_PWR_DEBUG_BUF_N")
	)
	(segment
		(start 442.412882 -141.703552)
		(end 443.3189 -142.60957)
		(width 0.10795)
		(layer "F.Cu")
		(net "BMC_PWR_DEBUG_BUF_N")
	)
	(segment
		(start 443.3189 -142.60957)
		(end 444.492634 -142.60957)
		(width 0.10795)
		(layer "F.Cu")
		(net "BMC_PWR_DEBUG_BUF_N")
	)
	(segment
		(start 441.629038 -141.703552)
		(end 442.412882 -141.703552)
		(width 0.10795)
		(layer "F.Cu")
		(net "BMC_PWR_DEBUG_BUF_N")
	)
	(via
		(at 441.6044 -143.5354)
		(size 0.6604)
		(drill 0.3302)
		(layers "F.Cu" "B.Cu")
		(net "BMC_PWR_DEBUG_BUF_N")
	)
	(via
		(at 446.151 -140.843)
		(size 0.508)
		(drill 0.254)
		(layers "F.Cu" "B.Cu")
		(net "BMC_PWR_DEBUG_BUF_N")
	)
	(via
		(at 441.629038 -141.703552)
		(size 0.508)
		(drill 0.254)
		(layers "F.Cu" "B.Cu")
		(net "BMC_PWR_DEBUG_BUF_N")
	)
	(segment
		(start 446.129918 -140.864082)
		(end 446.151 -140.843)
		(width 0.10795)
		(layer "B.Cu")
		(net "BMC_PWR_DEBUG_BUF_N")
	)
	(segment
		(start 442.2648 -142.4178)
		(end 442.2648 -142.0368)
		(width 0.10795)
		(layer "B.Cu")
		(net "BMC_PWR_DEBUG_BUF_N")
	)
	(segment
		(start 446.129918 -141.665452)
		(end 446.129918 -140.864082)
		(width 0.10795)
		(layer "B.Cu")
		(net "BMC_PWR_DEBUG_BUF_N")
	)
	(segment
		(start 441.962286 -142.0368)
		(end 441.629038 -141.703552)
		(width 0.10795)
		(layer "B.Cu")
		(net "BMC_PWR_DEBUG_BUF_N")
	)
	(segment
		(start 441.6044 -143.5354)
		(end 441.6044 -143.0782)
		(width 0.10795)
		(layer "B.Cu")
		(net "BMC_PWR_DEBUG_BUF_N")
	)
	(segment
		(start 441.6044 -143.0782)
		(end 442.2648 -142.4178)
		(width 0.10795)
		(layer "B.Cu")
		(net "BMC_PWR_DEBUG_BUF_N")
	)
	(segment
		(start 442.2648 -142.0368)
		(end 441.962286 -142.0368)
		(width 0.10795)
		(layer "B.Cu")
		(net "BMC_PWR_DEBUG_BUF_N")
	)
	(segment
		(start 441.513722 -140.716)
		(end 441.578492 -140.78077)
		(width 0.10795)
		(layer "F.Cu")
		(net "BMC_PREQ_BUF_N")
	)
	(segment
		(start 441.578492 -140.78077)
		(end 442.029088 -140.78077)
		(width 0.10795)
		(layer "F.Cu")
		(net "BMC_PREQ_BUF_N")
	)
	(segment
		(start 443.207648 -141.95933)
		(end 444.492634 -141.95933)
		(width 0.10795)
		(layer "F.Cu")
		(net "BMC_PREQ_BUF_N")
	)
	(segment
		(start 440.944 -140.716)
		(end 441.513722 -140.716)
		(width 0.10795)
		(layer "F.Cu")
		(net "BMC_PREQ_BUF_N")
	)
	(segment
		(start 442.029088 -140.78077)
		(end 443.207648 -141.95933)
		(width 0.10795)
		(layer "F.Cu")
		(net "BMC_PREQ_BUF_N")
	)
	(segment
		(start 441.751466 -150.38578)
		(end 441.572904 -150.564342)
		(width 0.10795)
		(layer "F.Cu")
		(net "BMC_PREQ_BUF_N")
	)
	(segment
		(start 441.572904 -150.564342)
		(end 441.00623 -150.564342)
		(width 0.10795)
		(layer "F.Cu")
		(net "BMC_PREQ_BUF_N")
	)
	(via
		(at 441.751466 -150.38578)
		(size 0.508)
		(drill 0.254)
		(layers "F.Cu" "B.Cu")
		(net "BMC_PREQ_BUF_N")
	)
	(via
		(at 443.1538 -150.7998)
		(size 0.6604)
		(drill 0.3302)
		(layers "F.Cu" "B.Cu")
		(net "BMC_PREQ_BUF_N")
	)
	(via
		(at 441.578492 -140.78077)
		(size 0.508)
		(drill 0.254)
		(layers "F.Cu" "B.Cu")
		(net "BMC_PREQ_BUF_N")
	)
	(segment
		(start 441.751466 -150.38578)
		(end 442.05398 -150.38578)
		(width 0.10795)
		(layer "B.Cu")
		(net "BMC_PREQ_BUF_N")
	)
	(segment
		(start 442.05398 -150.38578)
		(end 442.468 -150.7998)
		(width 0.10795)
		(layer "B.Cu")
		(net "BMC_PREQ_BUF_N")
	)
	(segment
		(start 442.468 -150.7998)
		(end 443.1538 -150.7998)
		(width 0.10795)
		(layer "B.Cu")
		(net "BMC_PREQ_BUF_N")
	)
	(segment
		(start 441.30595 -150.38578)
		(end 440.442604 -149.522434)
		(width 0.089408)
		(layer "In11.Cu")
		(net "BMC_PREQ_BUF_N")
	)
	(segment
		(start 440.442604 -149.522434)
		(end 440.442604 -148.553678)
		(width 0.089408)
		(layer "In11.Cu")
		(net "BMC_PREQ_BUF_N")
	)
	(segment
		(start 442.179456 -143.691102)
		(end 442.179456 -141.272006)
		(width 0.089408)
		(layer "In11.Cu")
		(net "BMC_PREQ_BUF_N")
	)
	(segment
		(start 440.442604 -148.553678)
		(end 441.070492 -147.92579)
		(width 0.089408)
		(layer "In11.Cu")
		(net "BMC_PREQ_BUF_N")
	)
	(segment
		(start 441.751466 -150.38578)
		(end 441.30595 -150.38578)
		(width 0.089408)
		(layer "In11.Cu")
		(net "BMC_PREQ_BUF_N")
	)
	(segment
		(start 441.68822 -140.78077)
		(end 441.578492 -140.78077)
		(width 0.089408)
		(layer "In11.Cu")
		(net "BMC_PREQ_BUF_N")
	)
	(segment
		(start 442.179456 -141.272006)
		(end 441.68822 -140.78077)
		(width 0.089408)
		(layer "In11.Cu")
		(net "BMC_PREQ_BUF_N")
	)
	(segment
		(start 441.070492 -144.800066)
		(end 442.179456 -143.691102)
		(width 0.089408)
		(layer "In11.Cu")
		(net "BMC_PREQ_BUF_N")
	)
	(segment
		(start 441.070492 -147.92579)
		(end 441.070492 -144.800066)
		(width 0.089408)
		(layer "In11.Cu")
		(net "BMC_PREQ_BUF_N")
	)
	(segment
		(start 435.727094 -150.070058)
		(end 435.727094 -150.043642)
		(width 0.10795)
		(layer "F.Cu")
		(net "JTAG_BMC_TRST_BUF_N")
	)
	(segment
		(start 438.998614 -156.172154)
		(end 438.998614 -156.961586)
		(width 0.10795)
		(layer "F.Cu")
		(net "JTAG_BMC_TRST_BUF_N")
	)
	(segment
		(start 435.727094 -150.043642)
		(end 435.944518 -150.043642)
		(width 0.10795)
		(layer "F.Cu")
		(net "JTAG_BMC_TRST_BUF_N")
	)
	(segment
		(start 436.532274 -149.893274)
		(end 436.70347 -150.06447)
		(width 0.10795)
		(layer "F.Cu")
		(net "JTAG_BMC_TRST_BUF_N")
	)
	(segment
		(start 435.240684 -150.556468)
		(end 435.727094 -150.070058)
		(width 0.10795)
		(layer "F.Cu")
		(net "JTAG_BMC_TRST_BUF_N")
	)
	(segment
		(start 435.944518 -150.043642)
		(end 436.094886 -149.893274)
		(width 0.10795)
		(layer "F.Cu")
		(net "JTAG_BMC_TRST_BUF_N")
	)
	(segment
		(start 436.094886 -149.893274)
		(end 436.532274 -149.893274)
		(width 0.10795)
		(layer "F.Cu")
		(net "JTAG_BMC_TRST_BUF_N")
	)
	(segment
		(start 435.791356 -153.810462)
		(end 435.240684 -153.25979)
		(width 0.10795)
		(layer "F.Cu")
		(net "JTAG_BMC_TRST_BUF_N")
	)
	(segment
		(start 435.240684 -153.25979)
		(end 435.240684 -150.556468)
		(width 0.10795)
		(layer "F.Cu")
		(net "JTAG_BMC_TRST_BUF_N")
	)
	(segment
		(start 438.998614 -156.172154)
		(end 436.636922 -153.810462)
		(width 0.10795)
		(layer "F.Cu")
		(net "JTAG_BMC_TRST_BUF_N")
	)
	(segment
		(start 436.70347 -150.06447)
		(end 437.906414 -150.06447)
		(width 0.10795)
		(layer "F.Cu")
		(net "JTAG_BMC_TRST_BUF_N")
	)
	(segment
		(start 436.636922 -153.810462)
		(end 435.791356 -153.810462)
		(width 0.10795)
		(layer "F.Cu")
		(net "JTAG_BMC_TRST_BUF_N")
	)
	(via
		(at 438.998614 -156.172154)
		(size 0.508)
		(drill 0.254)
		(layers "F.Cu" "B.Cu")
		(net "JTAG_BMC_TRST_BUF_N")
	)
	(via
		(at 438.998614 -156.961586)
		(size 0.762)
		(drill 0.381)
		(layers "F.Cu" "B.Cu")
		(net "JTAG_BMC_TRST_BUF_N")
	)
	(segment
		(start 439.32094 -155.849828)
		(end 440.69 -155.849828)
		(width 0.10795)
		(layer "B.Cu")
		(net "JTAG_BMC_TRST_BUF_N")
	)
	(segment
		(start 438.998614 -156.172154)
		(end 439.32094 -155.849828)
		(width 0.10795)
		(layer "B.Cu")
		(net "JTAG_BMC_TRST_BUF_N")
	)
	(segment
		(start 438.967372 -146.477228)
		(end 439.626756 -146.477228)
		(width 0.10795)
		(layer "F.Cu")
		(net "BMC_JTAG_SEL_BUF")
	)
	(segment
		(start 440.206384 -148.715984)
		(end 439.705496 -148.215096)
		(width 0.10795)
		(layer "F.Cu")
		(net "BMC_JTAG_SEL_BUF")
	)
	(segment
		(start 440.844178 -149.51456)
		(end 440.944762 -149.413976)
		(width 0.10795)
		(layer "F.Cu")
		(net "BMC_JTAG_SEL_BUF")
	)
	(segment
		(start 440.206384 -149.51456)
		(end 440.844178 -149.51456)
		(width 0.10795)
		(layer "F.Cu")
		(net "BMC_JTAG_SEL_BUF")
	)
	(segment
		(start 440.206384 -149.51456)
		(end 440.206384 -148.715984)
		(width 0.10795)
		(layer "F.Cu")
		(net "BMC_JTAG_SEL_BUF")
	)
	(segment
		(start 438.7596 -146.685)
		(end 438.967372 -146.477228)
		(width 0.10795)
		(layer "F.Cu")
		(net "BMC_JTAG_SEL_BUF")
	)
	(segment
		(start 438.7596 -147.2692)
		(end 438.7596 -146.685)
		(width 0.10795)
		(layer "F.Cu")
		(net "BMC_JTAG_SEL_BUF")
	)
	(segment
		(start 439.705496 -148.215096)
		(end 438.7596 -147.2692)
		(width 0.10795)
		(layer "F.Cu")
		(net "BMC_JTAG_SEL_BUF")
	)
	(via
		(at 448.287648 -157.154372)
		(size 0.508)
		(drill 0.254)
		(layers "F.Cu" "B.Cu")
		(net "BMC_JTAG_SEL_BUF")
	)
	(via
		(at 450.234812 -146.302222)
		(size 0.508)
		(drill 0.254)
		(layers "F.Cu" "B.Cu")
		(net "BMC_JTAG_SEL_BUF")
	)
	(via
		(at 446.913 -140.843)
		(size 0.508)
		(drill 0.254)
		(layers "F.Cu" "B.Cu")
		(net "BMC_JTAG_SEL_BUF")
	)
	(via
		(at 442.849 -143.383)
		(size 0.508)
		(drill 0.254)
		(layers "F.Cu" "B.Cu")
		(net "BMC_JTAG_SEL_BUF")
	)
	(via
		(at 439.705496 -148.215096)
		(size 0.6604)
		(drill 0.3302)
		(layers "F.Cu" "B.Cu")
		(net "BMC_JTAG_SEL_BUF")
	)
	(via
		(at 440.944762 -149.413976)
		(size 0.508)
		(drill 0.254)
		(layers "F.Cu" "B.Cu")
		(net "BMC_JTAG_SEL_BUF")
	)
	(segment
		(start 445.12992 -141.092428)
		(end 445.041782 -141.00429)
		(width 0.10795)
		(layer "B.Cu")
		(net "BMC_JTAG_SEL_BUF")
	)
	(segment
		(start 445.041782 -141.00429)
		(end 445.041782 -140.277088)
		(width 0.10795)
		(layer "B.Cu")
		(net "BMC_JTAG_SEL_BUF")
	)
	(segment
		(start 445.041782 -140.277088)
		(end 445.23787 -140.081)
		(width 0.10795)
		(layer "B.Cu")
		(net "BMC_JTAG_SEL_BUF")
	)
	(segment
		(start 442.44895 -145.465546)
		(end 443.179454 -145.465546)
		(width 0.10795)
		(layer "B.Cu")
		(net "BMC_JTAG_SEL_BUF")
	)
	(segment
		(start 446.517776 -140.081)
		(end 446.913 -140.476224)
		(width 0.10795)
		(layer "B.Cu")
		(net "BMC_JTAG_SEL_BUF")
	)
	(segment
		(start 444.119 -145.034)
		(end 444.754 -145.669)
		(width 0.10795)
		(layer "B.Cu")
		(net "BMC_JTAG_SEL_BUF")
	)
	(segment
		(start 445.791336 -145.64741)
		(end 446.129918 -145.308828)
		(width 0.10795)
		(layer "B.Cu")
		(net "BMC_JTAG_SEL_BUF")
	)
	(segment
		(start 446.630044 -141.665452)
		(end 446.630044 -141.125956)
		(width 0.10795)
		(layer "B.Cu")
		(net "BMC_JTAG_SEL_BUF")
	)
	(segment
		(start 442.468 -156.499814)
		(end 443.202314 -156.499814)
		(width 0.10795)
		(layer "B.Cu")
		(net "BMC_JTAG_SEL_BUF")
	)
	(segment
		(start 445.516 -145.669)
		(end 445.53759 -145.64741)
		(width 0.10795)
		(layer "B.Cu")
		(net "BMC_JTAG_SEL_BUF")
	)
	(segment
		(start 443.179454 -145.465546)
		(end 443.611 -145.034)
		(width 0.10795)
		(layer "B.Cu")
		(net "BMC_JTAG_SEL_BUF")
	)
	(segment
		(start 447.223388 -157.154372)
		(end 447.3702 -157.154372)
		(width 0.10795)
		(layer "B.Cu")
		(net "BMC_JTAG_SEL_BUF")
	)
	(segment
		(start 447.3702 -157.154372)
		(end 448.287648 -157.154372)
		(width 0.10795)
		(layer "B.Cu")
		(net "BMC_JTAG_SEL_BUF")
	)
	(segment
		(start 442.350398 -143.919194)
		(end 442.350398 -144.211802)
		(width 0.10795)
		(layer "B.Cu")
		(net "BMC_JTAG_SEL_BUF")
	)
	(segment
		(start 442.350398 -144.211802)
		(end 442.248798 -144.313402)
		(width 0.10795)
		(layer "B.Cu")
		(net "BMC_JTAG_SEL_BUF")
	)
	(segment
		(start 445.12992 -141.665452)
		(end 445.12992 -141.092428)
		(width 0.10795)
		(layer "B.Cu")
		(net "BMC_JTAG_SEL_BUF")
	)
	(segment
		(start 444.754 -145.669)
		(end 445.516 -145.669)
		(width 0.10795)
		(layer "B.Cu")
		(net "BMC_JTAG_SEL_BUF")
	)
	(segment
		(start 446.51676 -157.861)
		(end 447.223388 -157.154372)
		(width 0.10795)
		(layer "B.Cu")
		(net "BMC_JTAG_SEL_BUF")
	)
	(segment
		(start 442.849 -143.383)
		(end 443.431422 -143.965422)
		(width 0.10795)
		(layer "B.Cu")
		(net "BMC_JTAG_SEL_BUF")
	)
	(segment
		(start 443.611 -145.034)
		(end 444.119 -145.034)
		(width 0.10795)
		(layer "B.Cu")
		(net "BMC_JTAG_SEL_BUF")
	)
	(segment
		(start 444.5635 -157.861)
		(end 446.51676 -157.861)
		(width 0.10795)
		(layer "B.Cu")
		(net "BMC_JTAG_SEL_BUF")
	)
	(segment
		(start 446.913 -140.476224)
		(end 446.913 -140.843)
		(width 0.10795)
		(layer "B.Cu")
		(net "BMC_JTAG_SEL_BUF")
	)
	(segment
		(start 443.431422 -143.965422)
		(end 444.58001 -143.965422)
		(width 0.10795)
		(layer "B.Cu")
		(net "BMC_JTAG_SEL_BUF")
	)
	(segment
		(start 445.53759 -145.64741)
		(end 445.791336 -145.64741)
		(width 0.10795)
		(layer "B.Cu")
		(net "BMC_JTAG_SEL_BUF")
	)
	(segment
		(start 446.129918 -145.308828)
		(end 446.129918 -144.765268)
		(width 0.10795)
		(layer "B.Cu")
		(net "BMC_JTAG_SEL_BUF")
	)
	(segment
		(start 445.23787 -140.081)
		(end 446.517776 -140.081)
		(width 0.10795)
		(layer "B.Cu")
		(net "BMC_JTAG_SEL_BUF")
	)
	(segment
		(start 442.849 -143.383)
		(end 442.626496 -143.605504)
		(width 0.10795)
		(layer "B.Cu")
		(net "BMC_JTAG_SEL_BUF")
	)
	(segment
		(start 442.626496 -143.643096)
		(end 442.350398 -143.919194)
		(width 0.10795)
		(layer "B.Cu")
		(net "BMC_JTAG_SEL_BUF")
	)
	(segment
		(start 446.630044 -141.125956)
		(end 446.913 -140.843)
		(width 0.10795)
		(layer "B.Cu")
		(net "BMC_JTAG_SEL_BUF")
	)
	(segment
		(start 443.202314 -156.499814)
		(end 444.5635 -157.861)
		(width 0.10795)
		(layer "B.Cu")
		(net "BMC_JTAG_SEL_BUF")
	)
	(segment
		(start 442.248798 -145.265394)
		(end 442.44895 -145.465546)
		(width 0.10795)
		(layer "B.Cu")
		(net "BMC_JTAG_SEL_BUF")
	)
	(segment
		(start 442.248798 -144.313402)
		(end 442.248798 -145.265394)
		(width 0.10795)
		(layer "B.Cu")
		(net "BMC_JTAG_SEL_BUF")
	)
	(segment
		(start 442.626496 -143.605504)
		(end 442.626496 -143.643096)
		(width 0.10795)
		(layer "B.Cu")
		(net "BMC_JTAG_SEL_BUF")
	)
	(segment
		(start 444.373 -143.383)
		(end 446.913 -140.843)
		(width 0.089408)
		(layer "In2.Cu")
		(net "BMC_JTAG_SEL_BUF")
	)
	(segment
		(start 442.849 -143.383)
		(end 444.373 -143.383)
		(width 0.089408)
		(layer "In2.Cu")
		(net "BMC_JTAG_SEL_BUF")
	)
	(segment
		(start 449.648834 -146.8882)
		(end 450.234812 -146.302222)
		(width 0.089408)
		(layer "In4.Cu")
		(net "BMC_JTAG_SEL_BUF")
	)
	(segment
		(start 446.607946 -146.8882)
		(end 449.648834 -146.8882)
		(width 0.089408)
		(layer "In4.Cu")
		(net "BMC_JTAG_SEL_BUF")
	)
	(segment
		(start 442.849 -143.383)
		(end 443.102746 -143.383)
		(width 0.089408)
		(layer "In4.Cu")
		(net "BMC_JTAG_SEL_BUF")
	)
	(segment
		(start 443.102746 -143.383)
		(end 446.607946 -146.8882)
		(width 0.089408)
		(layer "In4.Cu")
		(net "BMC_JTAG_SEL_BUF")
	)
	(segment
		(start 450.234812 -146.302222)
		(end 450.234812 -152.939242)
		(width 0.089408)
		(layer "In9.Cu")
		(net "BMC_JTAG_SEL_BUF")
	)
	(segment
		(start 449.166996 -156.275024)
		(end 448.287648 -157.154372)
		(width 0.089408)
		(layer "In9.Cu")
		(net "BMC_JTAG_SEL_BUF")
	)
	(segment
		(start 450.234812 -152.939242)
		(end 449.166996 -154.007058)
		(width 0.089408)
		(layer "In9.Cu")
		(net "BMC_JTAG_SEL_BUF")
	)
	(segment
		(start 449.166996 -154.007058)
		(end 449.166996 -156.275024)
		(width 0.089408)
		(layer "In9.Cu")
		(net "BMC_JTAG_SEL_BUF")
	)
	(segment
		(start 441.26912 -148.099018)
		(end 441.26912 -144.96288)
		(width 0.089408)
		(layer "In11.Cu")
		(net "BMC_JTAG_SEL_BUF")
	)
	(segment
		(start 440.944762 -148.423376)
		(end 441.26912 -148.099018)
		(width 0.089408)
		(layer "In11.Cu")
		(net "BMC_JTAG_SEL_BUF")
	)
	(segment
		(start 441.26912 -144.96288)
		(end 442.849 -143.383)
		(width 0.089408)
		(layer "In11.Cu")
		(net "BMC_JTAG_SEL_BUF")
	)
	(segment
		(start 440.944762 -149.413976)
		(end 440.944762 -148.423376)
		(width 0.089408)
		(layer "In11.Cu")
		(net "BMC_JTAG_SEL_BUF")
	)
	(segment
		(start 443.576456 -144.56029)
		(end 444.492634 -144.56029)
		(width 0.10795)
		(layer "F.Cu")
		(net "JTAG_BMC_BUF_TMS")
	)
	(segment
		(start 445.93129 -144.56029)
		(end 444.492634 -144.56029)
		(width 0.10795)
		(layer "F.Cu")
		(net "JTAG_BMC_BUF_TMS")
	)
	(segment
		(start 442.924946 -145.2118)
		(end 443.576456 -144.56029)
		(width 0.10795)
		(layer "F.Cu")
		(net "JTAG_BMC_BUF_TMS")
	)
	(segment
		(start 448.3862 -145.9738)
		(end 448.2846 -145.8722)
		(width 0.10795)
		(layer "F.Cu")
		(net "JTAG_BMC_BUF_TMS")
	)
	(segment
		(start 447.2432 -145.8722)
		(end 445.93129 -144.56029)
		(width 0.10795)
		(layer "F.Cu")
		(net "JTAG_BMC_BUF_TMS")
	)
	(segment
		(start 441.706 -144.398746)
		(end 442.519054 -145.2118)
		(width 0.10795)
		(layer "F.Cu")
		(net "JTAG_BMC_BUF_TMS")
	)
	(segment
		(start 441.706 -143.764)
		(end 441.706 -144.398746)
		(width 0.10795)
		(layer "F.Cu")
		(net "JTAG_BMC_BUF_TMS")
	)
	(segment
		(start 442.519054 -145.2118)
		(end 442.924946 -145.2118)
		(width 0.10795)
		(layer "F.Cu")
		(net "JTAG_BMC_BUF_TMS")
	)
	(segment
		(start 448.2846 -145.8722)
		(end 447.2432 -145.8722)
		(width 0.10795)
		(layer "F.Cu")
		(net "JTAG_BMC_BUF_TMS")
	)
	(via
		(at 448.3862 -145.9738)
		(size 0.508)
		(drill 0.254)
		(layers "F.Cu" "B.Cu")
		(net "JTAG_BMC_BUF_TMS")
	)
	(segment
		(start 448.3862 -145.9738)
		(end 448.2846 -145.8722)
		(width 0.10795)
		(layer "B.Cu")
		(net "JTAG_BMC_BUF_TMS")
	)
	(segment
		(start 447.3702 -145.8722)
		(end 447.129916 -145.631916)
		(width 0.10795)
		(layer "B.Cu")
		(net "JTAG_BMC_BUF_TMS")
	)
	(segment
		(start 447.129916 -145.631916)
		(end 447.129916 -144.765268)
		(width 0.10795)
		(layer "B.Cu")
		(net "JTAG_BMC_BUF_TMS")
	)
	(segment
		(start 448.2846 -145.8722)
		(end 447.3702 -145.8722)
		(width 0.10795)
		(layer "B.Cu")
		(net "JTAG_BMC_BUF_TMS")
	)
	(segment
		(start 448.6148 -145.4912)
		(end 447.78295 -145.4912)
		(width 0.10795)
		(layer "F.Cu")
		(net "JTAG_BMC_BUF_TDO")
	)
	(segment
		(start 448.8688 -146.3294)
		(end 448.8688 -145.7452)
		(width 0.10795)
		(layer "F.Cu")
		(net "JTAG_BMC_BUF_TDO")
	)
	(segment
		(start 447.675 -143.4592)
		(end 448.945 -142.1892)
		(width 0.10795)
		(layer "F.Cu")
		(net "JTAG_BMC_BUF_TDO")
	)
	(segment
		(start 448.8688 -145.7452)
		(end 448.6148 -145.4912)
		(width 0.10795)
		(layer "F.Cu")
		(net "JTAG_BMC_BUF_TDO")
	)
	(segment
		(start 448.437 -150.495)
		(end 448.437 -146.7612)
		(width 0.10795)
		(layer "F.Cu")
		(net "JTAG_BMC_BUF_TDO")
	)
	(segment
		(start 447.46672 -151.46528)
		(end 448.437 -150.495)
		(width 0.10795)
		(layer "F.Cu")
		(net "JTAG_BMC_BUF_TDO")
	)
	(segment
		(start 447.46672 -153.54046)
		(end 447.46672 -151.46528)
		(width 0.10795)
		(layer "F.Cu")
		(net "JTAG_BMC_BUF_TDO")
	)
	(segment
		(start 447.675 -145.38325)
		(end 447.675 -143.4592)
		(width 0.10795)
		(layer "F.Cu")
		(net "JTAG_BMC_BUF_TDO")
	)
	(segment
		(start 447.78295 -145.4912)
		(end 447.675 -145.38325)
		(width 0.10795)
		(layer "F.Cu")
		(net "JTAG_BMC_BUF_TDO")
	)
	(segment
		(start 448.437 -146.7612)
		(end 448.8688 -146.3294)
		(width 0.10795)
		(layer "F.Cu")
		(net "JTAG_BMC_BUF_TDO")
	)
	(via
		(at 448.945 -142.1892)
		(size 0.508)
		(drill 0.254)
		(layers "F.Cu" "B.Cu")
		(net "JTAG_BMC_BUF_TDO")
	)
	(segment
		(start 448.642486 -142.1892)
		(end 448.3862 -142.445486)
		(width 0.10795)
		(layer "B.Cu")
		(net "JTAG_BMC_BUF_TDO")
	)
	(segment
		(start 448.945 -142.1892)
		(end 448.642486 -142.1892)
		(width 0.10795)
		(layer "B.Cu")
		(net "JTAG_BMC_BUF_TDO")
	)
	(segment
		(start 448.3862 -142.445486)
		(end 447.679826 -142.445486)
		(width 0.10795)
		(layer "B.Cu")
		(net "JTAG_BMC_BUF_TDO")
	)
	(segment
		(start 443.23 -144.018)
		(end 443.33795 -143.91005)
		(width 0.10795)
		(layer "F.Cu")
		(net "JTAG_BMC_BUF_TDI")
	)
	(segment
		(start 442.3156 -143.21155)
		(end 442.10605 -143.002)
		(width 0.10795)
		(layer "F.Cu")
		(net "JTAG_BMC_BUF_TDI")
	)
	(segment
		(start 443.23 -144.272)
		(end 443.23 -144.018)
		(width 0.10795)
		(layer "F.Cu")
		(net "JTAG_BMC_BUF_TDI")
	)
	(segment
		(start 443.33795 -143.91005)
		(end 444.492634 -143.91005)
		(width 0.10795)
		(layer "F.Cu")
		(net "JTAG_BMC_BUF_TDI")
	)
	(segment
		(start 442.722 -144.78)
		(end 443.23 -144.272)
		(width 0.10795)
		(layer "F.Cu")
		(net "JTAG_BMC_BUF_TDI")
	)
	(segment
		(start 442.722 -144.78)
		(end 442.3156 -144.3736)
		(width 0.10795)
		(layer "F.Cu")
		(net "JTAG_BMC_BUF_TDI")
	)
	(segment
		(start 442.3156 -144.3736)
		(end 442.3156 -143.21155)
		(width 0.10795)
		(layer "F.Cu")
		(net "JTAG_BMC_BUF_TDI")
	)
	(segment
		(start 442.10605 -143.002)
		(end 441.706 -143.002)
		(width 0.10795)
		(layer "F.Cu")
		(net "JTAG_BMC_BUF_TDI")
	)
	(via
		(at 442.722 -144.78)
		(size 0.508)
		(drill 0.254)
		(layers "F.Cu" "B.Cu")
		(net "JTAG_BMC_BUF_TDI")
	)
	(segment
		(start 444.881 -145.415)
		(end 445.389 -145.415)
		(width 0.10795)
		(layer "B.Cu")
		(net "JTAG_BMC_BUF_TDI")
	)
	(segment
		(start 445.629792 -145.174208)
		(end 445.629792 -144.765268)
		(width 0.10795)
		(layer "B.Cu")
		(net "JTAG_BMC_BUF_TDI")
	)
	(segment
		(start 445.389 -145.415)
		(end 445.629792 -145.174208)
		(width 0.10795)
		(layer "B.Cu")
		(net "JTAG_BMC_BUF_TDI")
	)
	(segment
		(start 444.246 -144.78)
		(end 444.881 -145.415)
		(width 0.10795)
		(layer "B.Cu")
		(net "JTAG_BMC_BUF_TDI")
	)
	(segment
		(start 442.722 -144.78)
		(end 444.246 -144.78)
		(width 0.10795)
		(layer "B.Cu")
		(net "JTAG_BMC_BUF_TDI")
	)
	(segment
		(start 496.47348 -132.166106)
		(end 498.449854 -134.14248)
		(width 0.10795)
		(layer "F.Cu")
		(net "BMC_JTAG_SEL")
	)
	(segment
		(start 496.873784 -125.710696)
		(end 496.09502 -126.48946)
		(width 0.10795)
		(layer "F.Cu")
		(net "BMC_JTAG_SEL")
	)
	(segment
		(start 498.449854 -135.242554)
		(end 499.08206 -135.87476)
		(width 0.10795)
		(layer "F.Cu")
		(net "BMC_JTAG_SEL")
	)
	(segment
		(start 496.09502 -128.04394)
		(end 496.47348 -128.4224)
		(width 0.10795)
		(layer "F.Cu")
		(net "BMC_JTAG_SEL")
	)
	(segment
		(start 452.312024 -145.66646)
		(end 449.883022 -145.66646)
		(width 0.10795)
		(layer "F.Cu")
		(net "BMC_JTAG_SEL")
	)
	(segment
		(start 449.883022 -145.66646)
		(end 449.762626 -145.786856)
		(width 0.10795)
		(layer "F.Cu")
		(net "BMC_JTAG_SEL")
	)
	(segment
		(start 496.09502 -126.48946)
		(end 496.09502 -128.04394)
		(width 0.10795)
		(layer "F.Cu")
		(net "BMC_JTAG_SEL")
	)
	(segment
		(start 498.449854 -125.710696)
		(end 496.873784 -125.710696)
		(width 0.10795)
		(layer "F.Cu")
		(net "BMC_JTAG_SEL")
	)
	(segment
		(start 496.47348 -128.4224)
		(end 496.47348 -132.166106)
		(width 0.10795)
		(layer "F.Cu")
		(net "BMC_JTAG_SEL")
	)
	(segment
		(start 498.449854 -134.14248)
		(end 498.449854 -135.242554)
		(width 0.10795)
		(layer "F.Cu")
		(net "BMC_JTAG_SEL")
	)
	(via
		(at 499.08206 -135.87476)
		(size 0.508)
		(drill 0.254)
		(layers "F.Cu" "B.Cu")
		(net "BMC_JTAG_SEL")
	)
	(via
		(at 449.7324 -152.6032)
		(size 0.508)
		(drill 0.254)
		(layers "F.Cu" "B.Cu")
		(net "BMC_JTAG_SEL")
	)
	(via
		(at 449.762626 -145.786856)
		(size 0.508)
		(drill 0.254)
		(layers "F.Cu" "B.Cu")
		(net "BMC_JTAG_SEL")
	)
	(via
		(at 444.0174 -154.178)
		(size 0.6604)
		(drill 0.3302)
		(layers "F.Cu" "B.Cu")
		(net "BMC_JTAG_SEL")
	)
	(segment
		(start 448.8434 -154.3558)
		(end 447.7258 -154.3558)
		(width 0.10795)
		(layer "B.Cu")
		(net "BMC_JTAG_SEL")
	)
	(segment
		(start 449.5546 -152.781)
		(end 449.5546 -153.6446)
		(width 0.10795)
		(layer "B.Cu")
		(net "BMC_JTAG_SEL")
	)
	(segment
		(start 444.0174 -155.956)
		(end 444.565786 -156.504386)
		(width 0.10795)
		(layer "B.Cu")
		(net "BMC_JTAG_SEL")
	)
	(segment
		(start 444.565786 -156.504386)
		(end 445.5922 -156.504386)
		(width 0.10795)
		(layer "B.Cu")
		(net "BMC_JTAG_SEL")
	)
	(segment
		(start 449.7324 -152.6032)
		(end 449.9991 -152.3365)
		(width 0.10795)
		(layer "B.Cu")
		(net "BMC_JTAG_SEL")
	)
	(segment
		(start 446.085214 -156.504386)
		(end 445.5922 -156.504386)
		(width 0.10795)
		(layer "B.Cu")
		(net "BMC_JTAG_SEL")
	)
	(segment
		(start 444.0174 -154.178)
		(end 444.0174 -155.956)
		(width 0.10795)
		(layer "B.Cu")
		(net "BMC_JTAG_SEL")
	)
	(segment
		(start 449.9991 -152.3365)
		(end 450.8246 -152.3365)
		(width 0.10795)
		(layer "B.Cu")
		(net "BMC_JTAG_SEL")
	)
	(segment
		(start 446.5066 -155.575)
		(end 446.5066 -156.083)
		(width 0.10795)
		(layer "B.Cu")
		(net "BMC_JTAG_SEL")
	)
	(segment
		(start 446.5066 -156.083)
		(end 446.085214 -156.504386)
		(width 0.10795)
		(layer "B.Cu")
		(net "BMC_JTAG_SEL")
	)
	(segment
		(start 447.7258 -154.3558)
		(end 446.5066 -155.575)
		(width 0.10795)
		(layer "B.Cu")
		(net "BMC_JTAG_SEL")
	)
	(segment
		(start 449.5546 -153.6446)
		(end 448.8434 -154.3558)
		(width 0.10795)
		(layer "B.Cu")
		(net "BMC_JTAG_SEL")
	)
	(segment
		(start 449.7324 -152.6032)
		(end 449.5546 -152.781)
		(width 0.10795)
		(layer "B.Cu")
		(net "BMC_JTAG_SEL")
	)
	(segment
		(start 454.67524 -155.8671)
		(end 455.5998 -154.94254)
		(width 0.089408)
		(layer "In2.Cu")
		(net "BMC_JTAG_SEL")
	)
	(segment
		(start 498.24132 -152.05964)
		(end 497.43868 -151.257)
		(width 0.089408)
		(layer "In2.Cu")
		(net "BMC_JTAG_SEL")
	)
	(segment
		(start 496.48872 -155.66136)
		(end 498.24132 -153.90876)
		(width 0.089408)
		(layer "In2.Cu")
		(net "BMC_JTAG_SEL")
	)
	(segment
		(start 467.41588 -149.01672)
		(end 468.95004 -147.48256)
		(width 0.089408)
		(layer "In2.Cu")
		(net "BMC_JTAG_SEL")
	)
	(segment
		(start 463.34172 -154.94254)
		(end 467.41588 -150.86838)
		(width 0.089408)
		(layer "In2.Cu")
		(net "BMC_JTAG_SEL")
	)
	(segment
		(start 477.74098 -149.39264)
		(end 481.50526 -149.39264)
		(width 0.089408)
		(layer "In2.Cu")
		(net "BMC_JTAG_SEL")
	)
	(segment
		(start 455.5998 -154.94254)
		(end 463.34172 -154.94254)
		(width 0.089408)
		(layer "In2.Cu")
		(net "BMC_JTAG_SEL")
	)
	(segment
		(start 449.7324 -152.6032)
		(end 449.7324 -153.7843)
		(width 0.089408)
		(layer "In2.Cu")
		(net "BMC_JTAG_SEL")
	)
	(segment
		(start 468.95004 -147.48256)
		(end 475.8309 -147.48256)
		(width 0.089408)
		(layer "In2.Cu")
		(net "BMC_JTAG_SEL")
	)
	(segment
		(start 498.24132 -153.90876)
		(end 498.24132 -152.05964)
		(width 0.089408)
		(layer "In2.Cu")
		(net "BMC_JTAG_SEL")
	)
	(segment
		(start 467.41588 -150.86838)
		(end 467.41588 -149.01672)
		(width 0.089408)
		(layer "In2.Cu")
		(net "BMC_JTAG_SEL")
	)
	(segment
		(start 449.7324 -153.7843)
		(end 451.8152 -155.8671)
		(width 0.089408)
		(layer "In2.Cu")
		(net "BMC_JTAG_SEL")
	)
	(segment
		(start 497.43868 -145.75536)
		(end 499.08206 -144.11198)
		(width 0.089408)
		(layer "In2.Cu")
		(net "BMC_JTAG_SEL")
	)
	(segment
		(start 475.8309 -147.48256)
		(end 477.74098 -149.39264)
		(width 0.089408)
		(layer "In2.Cu")
		(net "BMC_JTAG_SEL")
	)
	(segment
		(start 451.8152 -155.8671)
		(end 454.67524 -155.8671)
		(width 0.089408)
		(layer "In2.Cu")
		(net "BMC_JTAG_SEL")
	)
	(segment
		(start 497.43868 -151.257)
		(end 497.43868 -145.75536)
		(width 0.089408)
		(layer "In2.Cu")
		(net "BMC_JTAG_SEL")
	)
	(segment
		(start 491.34014 -155.66136)
		(end 496.48872 -155.66136)
		(width 0.089408)
		(layer "In2.Cu")
		(net "BMC_JTAG_SEL")
	)
	(segment
		(start 481.50526 -149.39264)
		(end 486.3211 -154.20848)
		(width 0.089408)
		(layer "In2.Cu")
		(net "BMC_JTAG_SEL")
	)
	(segment
		(start 499.08206 -144.11198)
		(end 499.08206 -135.87476)
		(width 0.089408)
		(layer "In2.Cu")
		(net "BMC_JTAG_SEL")
	)
	(segment
		(start 486.3211 -154.20848)
		(end 489.88726 -154.20848)
		(width 0.089408)
		(layer "In2.Cu")
		(net "BMC_JTAG_SEL")
	)
	(segment
		(start 489.88726 -154.20848)
		(end 491.34014 -155.66136)
		(width 0.089408)
		(layer "In2.Cu")
		(net "BMC_JTAG_SEL")
	)
	(segment
		(start 449.7324 -145.817082)
		(end 449.762626 -145.786856)
		(width 0.089408)
		(layer "In9.Cu")
		(net "BMC_JTAG_SEL")
	)
	(segment
		(start 449.7324 -152.6032)
		(end 449.7324 -145.817082)
		(width 0.089408)
		(layer "In9.Cu")
		(net "BMC_JTAG_SEL")
	)
	(segment
		(start 420.69004 -40.93464)
		(end 421.09009 -40.53459)
		(width 0.089408)
		(layer "F.Cu")
		(net "RST_BMC_PLTRST_BUF_N")
	)
	(via
		(at 421.09009 -40.53459)
		(size 0.4572)
		(drill 0.2032)
		(layers "F.Cu" "B.Cu")
		(net "RST_BMC_PLTRST_BUF_N")
	)
	(via
		(at 424.487086 -44.706794)
		(size 0.6604)
		(drill 0.3302)
		(layers "F.Cu" "B.Cu")
		(net "RST_BMC_PLTRST_BUF_N")
	)
	(segment
		(start 422.5417 -43.024044)
		(end 422.5417 -44.263564)
		(width 0.089408)
		(layer "B.Cu")
		(net "RST_BMC_PLTRST_BUF_N")
	)
	(segment
		(start 421.51554 -42.290238)
		(end 421.734742 -42.50944)
		(width 0.089408)
		(layer "B.Cu")
		(net "RST_BMC_PLTRST_BUF_N")
	)
	(segment
		(start 422.027096 -42.50944)
		(end 422.5417 -43.024044)
		(width 0.089408)
		(layer "B.Cu")
		(net "RST_BMC_PLTRST_BUF_N")
	)
	(segment
		(start 421.51554 -40.96004)
		(end 421.51554 -42.290238)
		(width 0.089408)
		(layer "B.Cu")
		(net "RST_BMC_PLTRST_BUF_N")
	)
	(segment
		(start 423.342054 -44.706794)
		(end 424.487086 -44.706794)
		(width 0.089408)
		(layer "B.Cu")
		(net "RST_BMC_PLTRST_BUF_N")
	)
	(segment
		(start 422.5417 -44.263564)
		(end 422.98493 -44.706794)
		(width 0.089408)
		(layer "B.Cu")
		(net "RST_BMC_PLTRST_BUF_N")
	)
	(segment
		(start 421.734742 -42.50944)
		(end 422.027096 -42.50944)
		(width 0.089408)
		(layer "B.Cu")
		(net "RST_BMC_PLTRST_BUF_N")
	)
	(segment
		(start 421.09009 -40.53459)
		(end 421.51554 -40.96004)
		(width 0.089408)
		(layer "B.Cu")
		(net "RST_BMC_PLTRST_BUF_N")
	)
	(segment
		(start 422.98493 -44.706794)
		(end 423.342054 -44.706794)
		(width 0.089408)
		(layer "B.Cu")
		(net "RST_BMC_PLTRST_BUF_N")
	)
	(segment
		(start 405.282908 1.701292)
		(end 405.282908 1.152398)
		(width 0.10795)
		(layer "F.Cu")
		(net "JTAG_PLD_TMS_MUX")
	)
	(segment
		(start 407.797 2.794)
		(end 407.3906 3.2004)
		(width 0.10795)
		(layer "F.Cu")
		(net "JTAG_PLD_TMS_MUX")
	)
	(segment
		(start 404.495 2.4892)
		(end 405.282908 1.701292)
		(width 0.10795)
		(layer "F.Cu")
		(net "JTAG_PLD_TMS_MUX")
	)
	(segment
		(start 407.797 0.9144)
		(end 407.797 2.794)
		(width 0.10795)
		(layer "F.Cu")
		(net "JTAG_PLD_TMS_MUX")
	)
	(segment
		(start 404.495 3.2004)
		(end 404.495 2.4892)
		(width 0.10795)
		(layer "F.Cu")
		(net "JTAG_PLD_TMS_MUX")
	)
	(segment
		(start 407.3906 3.2004)
		(end 404.495 3.2004)
		(width 0.10795)
		(layer "F.Cu")
		(net "JTAG_PLD_TMS_MUX")
	)
	(via
		(at 407.797 0.9144)
		(size 0.508)
		(drill 0.254)
		(layers "F.Cu" "B.Cu")
		(net "JTAG_PLD_TMS_MUX")
	)
	(via
		(at 359.5116 -6.02742)
		(size 0.6604)
		(drill 0.3302)
		(layers "F.Cu" "B.Cu")
		(net "JTAG_PLD_TMS_MUX")
	)
	(via
		(at 356.2604 -2.54)
		(size 0.508)
		(drill 0.254)
		(layers "F.Cu" "B.Cu")
		(net "JTAG_PLD_TMS_MUX")
	)
	(segment
		(start 356.48265 -2.76225)
		(end 356.2604 -2.54)
		(width 0.10795)
		(layer "B.Cu")
		(net "JTAG_PLD_TMS_MUX")
	)
	(segment
		(start 358.141778 -6.02742)
		(end 356.48265 -4.368292)
		(width 0.10795)
		(layer "B.Cu")
		(net "JTAG_PLD_TMS_MUX")
	)
	(segment
		(start 359.5116 -6.02742)
		(end 359.8672 -5.67182)
		(width 0.10795)
		(layer "B.Cu")
		(net "JTAG_PLD_TMS_MUX")
	)
	(segment
		(start 359.8672 -5.67182)
		(end 359.8672 -5.1308)
		(width 0.10795)
		(layer "B.Cu")
		(net "JTAG_PLD_TMS_MUX")
	)
	(segment
		(start 356.48265 -4.368292)
		(end 356.48265 -2.76225)
		(width 0.10795)
		(layer "B.Cu")
		(net "JTAG_PLD_TMS_MUX")
	)
	(segment
		(start 359.5116 -6.02742)
		(end 358.141778 -6.02742)
		(width 0.10795)
		(layer "B.Cu")
		(net "JTAG_PLD_TMS_MUX")
	)
	(segment
		(start 357.03256 -4.305808)
		(end 363.451648 -4.305808)
		(width 0.089408)
		(layer "In11.Cu")
		(net "JTAG_PLD_TMS_MUX")
	)
	(segment
		(start 363.451648 -4.305808)
		(end 365.610648 -2.146808)
		(width 0.089408)
		(layer "In11.Cu")
		(net "JTAG_PLD_TMS_MUX")
	)
	(segment
		(start 377.974352 -2.553208)
		(end 379.80747 -2.553208)
		(width 0.089408)
		(layer "In11.Cu")
		(net "JTAG_PLD_TMS_MUX")
	)
	(segment
		(start 356.704392 -2.983992)
		(end 356.704392 -3.97764)
		(width 0.089408)
		(layer "In11.Cu")
		(net "JTAG_PLD_TMS_MUX")
	)
	(segment
		(start 356.704392 -3.97764)
		(end 357.03256 -4.305808)
		(width 0.089408)
		(layer "In11.Cu")
		(net "JTAG_PLD_TMS_MUX")
	)
	(segment
		(start 382.24587 -0.114808)
		(end 399.753328 -0.114808)
		(width 0.089408)
		(layer "In11.Cu")
		(net "JTAG_PLD_TMS_MUX")
	)
	(segment
		(start 356.2604 -2.54)
		(end 356.704392 -2.983992)
		(width 0.089408)
		(layer "In11.Cu")
		(net "JTAG_PLD_TMS_MUX")
	)
	(segment
		(start 365.610648 -2.146808)
		(end 377.567952 -2.146808)
		(width 0.089408)
		(layer "In11.Cu")
		(net "JTAG_PLD_TMS_MUX")
	)
	(segment
		(start 400.782536 0.9144)
		(end 407.797 0.9144)
		(width 0.089408)
		(layer "In11.Cu")
		(net "JTAG_PLD_TMS_MUX")
	)
	(segment
		(start 399.753328 -0.114808)
		(end 400.782536 0.9144)
		(width 0.089408)
		(layer "In11.Cu")
		(net "JTAG_PLD_TMS_MUX")
	)
	(segment
		(start 379.80747 -2.553208)
		(end 382.24587 -0.114808)
		(width 0.089408)
		(layer "In11.Cu")
		(net "JTAG_PLD_TMS_MUX")
	)
	(segment
		(start 377.567952 -2.146808)
		(end 377.974352 -2.553208)
		(width 0.089408)
		(layer "In11.Cu")
		(net "JTAG_PLD_TMS_MUX")
	)
	(segment
		(start 401.285456 -0.847598)
		(end 402.183092 -0.847598)
		(width 0.10795)
		(layer "F.Cu")
		(net "JTAG_PLD_TDO_MUX")
	)
	(segment
		(start 400.659092 -0.998474)
		(end 401.13458 -0.998474)
		(width 0.10795)
		(layer "F.Cu")
		(net "JTAG_PLD_TDO_MUX")
	)
	(segment
		(start 401.13458 -0.998474)
		(end 401.285456 -0.847598)
		(width 0.10795)
		(layer "F.Cu")
		(net "JTAG_PLD_TDO_MUX")
	)
	(segment
		(start 405.78278 -0.347726)
		(end 405.282908 -0.347726)
		(width 0.10795)
		(layer "F.Cu")
		(net "JTAG_PLD_TDI_MUX")
	)
	(segment
		(start 404.495 4.0894)
		(end 404.814532 4.0894)
		(width 0.10795)
		(layer "F.Cu")
		(net "JTAG_PLD_TDI_MUX")
	)
	(segment
		(start 406.044908 -0.872998)
		(end 406.044908 -0.609854)
		(width 0.10795)
		(layer "F.Cu")
		(net "JTAG_PLD_TDI_MUX")
	)
	(segment
		(start 406.044908 -0.609854)
		(end 405.78278 -0.347726)
		(width 0.10795)
		(layer "F.Cu")
		(net "JTAG_PLD_TDI_MUX")
	)
	(segment
		(start 404.814532 4.0894)
		(end 405.131016 4.405884)
		(width 0.10795)
		(layer "F.Cu")
		(net "JTAG_PLD_TDI_MUX")
	)
	(via
		(at 405.131016 4.405884)
		(size 0.508)
		(drill 0.254)
		(layers "F.Cu" "B.Cu")
		(net "JTAG_PLD_TDI_MUX")
	)
	(via
		(at 406.044908 -0.872998)
		(size 0.508)
		(drill 0.254)
		(layers "F.Cu" "B.Cu")
		(net "JTAG_PLD_TDI_MUX")
	)
	(via
		(at 406.781508 -0.872998)
		(size 0.6604)
		(drill 0.3302)
		(layers "F.Cu" "B.Cu")
		(net "JTAG_PLD_TDI_MUX")
	)
	(segment
		(start 405.7396 3.857498)
		(end 405.605996 3.991102)
		(width 0.10795)
		(layer "B.Cu")
		(net "JTAG_PLD_TDI_MUX")
	)
	(segment
		(start 405.5618 -0.38989)
		(end 405.5618 1.7272)
		(width 0.10795)
		(layer "B.Cu")
		(net "JTAG_PLD_TDI_MUX")
	)
	(segment
		(start 406.044908 -0.872998)
		(end 405.5618 -0.38989)
		(width 0.10795)
		(layer "B.Cu")
		(net "JTAG_PLD_TDI_MUX")
	)
	(segment
		(start 405.5618 1.7272)
		(end 405.7396 1.905)
		(width 0.10795)
		(layer "B.Cu")
		(net "JTAG_PLD_TDI_MUX")
	)
	(segment
		(start 405.7396 1.905)
		(end 405.7396 3.857498)
		(width 0.10795)
		(layer "B.Cu")
		(net "JTAG_PLD_TDI_MUX")
	)
	(segment
		(start 405.605996 3.991102)
		(end 405.279098 3.991102)
		(width 0.10795)
		(layer "B.Cu")
		(net "JTAG_PLD_TDI_MUX")
	)
	(segment
		(start 405.279098 3.991102)
		(end 405.131016 4.139184)
		(width 0.10795)
		(layer "B.Cu")
		(net "JTAG_PLD_TDI_MUX")
	)
	(segment
		(start 406.781508 -0.872998)
		(end 406.044908 -0.872998)
		(width 0.10795)
		(layer "B.Cu")
		(net "JTAG_PLD_TDI_MUX")
	)
	(segment
		(start 405.131016 4.139184)
		(end 405.131016 4.405884)
		(width 0.10795)
		(layer "B.Cu")
		(net "JTAG_PLD_TDI_MUX")
	)
	(segment
		(start 401.2946 0.652526)
		(end 402.183092 0.652526)
		(width 0.10795)
		(layer "F.Cu")
		(net "JTAG_PLD_TCK_MUX")
	)
	(segment
		(start 400.659092 0.779526)
		(end 401.1676 0.779526)
		(width 0.10795)
		(layer "F.Cu")
		(net "JTAG_PLD_TCK_MUX")
	)
	(segment
		(start 399.161 0.357124)
		(end 400.550888 0.357124)
		(width 0.10795)
		(layer "F.Cu")
		(net "JTAG_PLD_TCK_MUX")
	)
	(segment
		(start 400.659092 0.465328)
		(end 400.659092 0.779526)
		(width 0.10795)
		(layer "F.Cu")
		(net "JTAG_PLD_TCK_MUX")
	)
	(segment
		(start 400.550888 0.357124)
		(end 400.659092 0.465328)
		(width 0.10795)
		(layer "F.Cu")
		(net "JTAG_PLD_TCK_MUX")
	)
	(segment
		(start 401.1676 0.779526)
		(end 401.2946 0.652526)
		(width 0.10795)
		(layer "F.Cu")
		(net "JTAG_PLD_TCK_MUX")
	)
	(via
		(at 399.161 0.357124)
		(size 0.508)
		(drill 0.254)
		(layers "F.Cu" "B.Cu")
		(net "JTAG_PLD_TCK_MUX")
	)
	(via
		(at 356.8954 -2.54)
		(size 0.508)
		(drill 0.254)
		(layers "F.Cu" "B.Cu")
		(net "JTAG_PLD_TCK_MUX")
	)
	(segment
		(start 359.1052 -5.65785)
		(end 358.99725 -5.7658)
		(width 0.10795)
		(layer "B.Cu")
		(net "JTAG_PLD_TCK_MUX")
	)
	(segment
		(start 356.6922 -4.281424)
		(end 356.6922 -2.7432)
		(width 0.10795)
		(layer "B.Cu")
		(net "JTAG_PLD_TCK_MUX")
	)
	(segment
		(start 358.99725 -5.7658)
		(end 358.176576 -5.7658)
		(width 0.10795)
		(layer "B.Cu")
		(net "JTAG_PLD_TCK_MUX")
	)
	(segment
		(start 356.6922 -2.7432)
		(end 356.8954 -2.54)
		(width 0.10795)
		(layer "B.Cu")
		(net "JTAG_PLD_TCK_MUX")
	)
	(segment
		(start 358.176576 -5.7658)
		(end 356.6922 -4.281424)
		(width 0.10795)
		(layer "B.Cu")
		(net "JTAG_PLD_TCK_MUX")
	)
	(segment
		(start 359.1052 -5.1308)
		(end 359.1052 -5.65785)
		(width 0.10795)
		(layer "B.Cu")
		(net "JTAG_PLD_TCK_MUX")
	)
	(segment
		(start 357.111808 -4.1148)
		(end 363.3724 -4.1148)
		(width 0.089408)
		(layer "In11.Cu")
		(net "JTAG_PLD_TCK_MUX")
	)
	(segment
		(start 356.8954 -3.898392)
		(end 357.111808 -4.1148)
		(width 0.089408)
		(layer "In11.Cu")
		(net "JTAG_PLD_TCK_MUX")
	)
	(segment
		(start 382.166622 0.0762)
		(end 398.880076 0.0762)
		(width 0.089408)
		(layer "In11.Cu")
		(net "JTAG_PLD_TCK_MUX")
	)
	(segment
		(start 356.8954 -2.54)
		(end 356.8954 -3.898392)
		(width 0.089408)
		(layer "In11.Cu")
		(net "JTAG_PLD_TCK_MUX")
	)
	(segment
		(start 377.6472 -1.9558)
		(end 378.0536 -2.3622)
		(width 0.089408)
		(layer "In11.Cu")
		(net "JTAG_PLD_TCK_MUX")
	)
	(segment
		(start 365.5314 -1.9558)
		(end 377.6472 -1.9558)
		(width 0.089408)
		(layer "In11.Cu")
		(net "JTAG_PLD_TCK_MUX")
	)
	(segment
		(start 363.3724 -4.1148)
		(end 365.5314 -1.9558)
		(width 0.089408)
		(layer "In11.Cu")
		(net "JTAG_PLD_TCK_MUX")
	)
	(segment
		(start 378.0536 -2.3622)
		(end 379.728222 -2.3622)
		(width 0.089408)
		(layer "In11.Cu")
		(net "JTAG_PLD_TCK_MUX")
	)
	(segment
		(start 379.728222 -2.3622)
		(end 382.166622 0.0762)
		(width 0.089408)
		(layer "In11.Cu")
		(net "JTAG_PLD_TCK_MUX")
	)
	(segment
		(start 398.880076 0.0762)
		(end 399.161 0.357124)
		(width 0.089408)
		(layer "In11.Cu")
		(net "JTAG_PLD_TCK_MUX")
	)
	(segment
		(start 406.679908 0.1524)
		(end 406.9334 -0.101092)
		(width 0.10795)
		(layer "F.Cu")
		(net "BMC_JTAG_SEL_N_MUX")
	)
	(segment
		(start 406.179782 0.652526)
		(end 406.679908 0.1524)
		(width 0.10795)
		(layer "F.Cu")
		(net "BMC_JTAG_SEL_N_MUX")
	)
	(segment
		(start 401.421092 0.1524)
		(end 402.183092 0.1524)
		(width 0.10795)
		(layer "F.Cu")
		(net "BMC_JTAG_SEL_N_MUX")
	)
	(segment
		(start 405.282908 0.652526)
		(end 406.179782 0.652526)
		(width 0.10795)
		(layer "F.Cu")
		(net "BMC_JTAG_SEL_N_MUX")
	)
	(segment
		(start 401.159218 -0.109474)
		(end 400.659092 -0.109474)
		(width 0.10795)
		(layer "F.Cu")
		(net "BMC_JTAG_SEL_N_MUX")
	)
	(segment
		(start 406.9334 -0.101092)
		(end 406.9334 -1.3716)
		(width 0.10795)
		(layer "F.Cu")
		(net "BMC_JTAG_SEL_N_MUX")
	)
	(segment
		(start 402.982938 -1.397508)
		(end 401.447 -1.397508)
		(width 0.10795)
		(layer "F.Cu")
		(net "BMC_JTAG_SEL_N_MUX")
	)
	(segment
		(start 406.9334 -1.3716)
		(end 406.7556 -1.5494)
		(width 0.10795)
		(layer "F.Cu")
		(net "BMC_JTAG_SEL_N_MUX")
	)
	(segment
		(start 406.7556 -1.5494)
		(end 405.384 -1.5494)
		(width 0.10795)
		(layer "F.Cu")
		(net "BMC_JTAG_SEL_N_MUX")
	)
	(segment
		(start 401.447 -1.397508)
		(end 401.421092 -1.3716)
		(width 0.10795)
		(layer "F.Cu")
		(net "BMC_JTAG_SEL_N_MUX")
	)
	(segment
		(start 401.421092 0.1524)
		(end 401.159218 -0.109474)
		(width 0.10795)
		(layer "F.Cu")
		(net "BMC_JTAG_SEL_N_MUX")
	)
	(segment
		(start 405.282908 -1.448308)
		(end 405.282908 -0.847598)
		(width 0.10795)
		(layer "F.Cu")
		(net "BMC_JTAG_SEL_N_MUX")
	)
	(segment
		(start 405.384 -1.5494)
		(end 405.282908 -1.448308)
		(width 0.10795)
		(layer "F.Cu")
		(net "BMC_JTAG_SEL_N_MUX")
	)
	(via
		(at 401.421092 0.1524)
		(size 0.508)
		(drill 0.254)
		(layers "F.Cu" "B.Cu")
		(net "BMC_JTAG_SEL_N_MUX")
	)
	(via
		(at 401.421092 -0.5842)
		(size 0.6604)
		(drill 0.3302)
		(layers "F.Cu" "B.Cu")
		(net "BMC_JTAG_SEL_N_MUX")
	)
	(via
		(at 406.679908 0.1524)
		(size 0.508)
		(drill 0.254)
		(layers "F.Cu" "B.Cu")
		(net "BMC_JTAG_SEL_N_MUX")
	)
	(via
		(at 401.421092 -1.3716)
		(size 0.508)
		(drill 0.254)
		(layers "F.Cu" "B.Cu")
		(net "BMC_JTAG_SEL_N_MUX")
	)
	(segment
		(start 401.421092 -1.3716)
		(end 401.421092 -0.5842)
		(width 0.10795)
		(layer "B.Cu")
		(net "BMC_JTAG_SEL_N_MUX")
	)
	(segment
		(start 401.421092 -0.5842)
		(end 401.421092 0.1524)
		(width 0.10795)
		(layer "B.Cu")
		(net "BMC_JTAG_SEL_N_MUX")
	)
	(segment
		(start 406.279604 -0.247904)
		(end 406.679908 0.1524)
		(width 0.089408)
		(layer "In2.Cu")
		(net "BMC_JTAG_SEL_N_MUX")
	)
	(segment
		(start 401.421092 -1.3716)
		(end 402.544788 -0.247904)
		(width 0.089408)
		(layer "In2.Cu")
		(net "BMC_JTAG_SEL_N_MUX")
	)
	(segment
		(start 402.544788 -0.247904)
		(end 406.279604 -0.247904)
		(width 0.089408)
		(layer "In2.Cu")
		(net "BMC_JTAG_SEL_N_MUX")
	)
	(segment
		(start 425.7167 -13.84808)
		(end 426.545756 -13.019024)
		(width 0.10795)
		(layer "F.Cu")
		(net "PCA9554_INT_N")
	)
	(segment
		(start 429.575976 -13.019024)
		(end 429.8696 -12.7254)
		(width 0.10795)
		(layer "F.Cu")
		(net "PCA9554_INT_N")
	)
	(segment
		(start 423.8879 -15.33398)
		(end 424.8023 -15.33398)
		(width 0.10795)
		(layer "F.Cu")
		(net "PCA9554_INT_N")
	)
	(segment
		(start 429.8696 -12.7254)
		(end 429.8696 -11.7856)
		(width 0.10795)
		(layer "F.Cu")
		(net "PCA9554_INT_N")
	)
	(segment
		(start 423.650664 -15.096744)
		(end 423.8879 -15.33398)
		(width 0.10795)
		(layer "F.Cu")
		(net "PCA9554_INT_N")
	)
	(segment
		(start 425.0436 -15.09268)
		(end 425.7167 -14.41958)
		(width 0.10795)
		(layer "F.Cu")
		(net "PCA9554_INT_N")
	)
	(segment
		(start 423.650664 -14.761464)
		(end 423.650664 -15.096744)
		(width 0.10795)
		(layer "F.Cu")
		(net "PCA9554_INT_N")
	)
	(segment
		(start 426.545756 -13.019024)
		(end 429.575976 -13.019024)
		(width 0.10795)
		(layer "F.Cu")
		(net "PCA9554_INT_N")
	)
	(segment
		(start 424.8023 -15.33398)
		(end 425.0436 -15.09268)
		(width 0.10795)
		(layer "F.Cu")
		(net "PCA9554_INT_N")
	)
	(segment
		(start 425.7167 -14.41958)
		(end 425.7167 -13.84808)
		(width 0.10795)
		(layer "F.Cu")
		(net "PCA9554_INT_N")
	)
	(via
		(at 425.0436 -15.09268)
		(size 0.762)
		(drill 0.381)
		(layers "F.Cu" "B.Cu")
		(net "PCA9554_INT_N")
	)
	(segment
		(start 431.82032 -16.565626)
		(end 431.82032 -17.4244)
		(width 0.10795)
		(layer "F.Cu")
		(net "PCA9554_A0")
	)
	(segment
		(start 432.333146 -16.0528)
		(end 431.82032 -16.565626)
		(width 0.10795)
		(layer "F.Cu")
		(net "PCA9554_A0")
	)
	(segment
		(start 433.0446 -16.0528)
		(end 433.0446 -16.832072)
		(width 0.10795)
		(layer "F.Cu")
		(net "PCA9554_A0")
	)
	(segment
		(start 433.0446 -16.0528)
		(end 432.333146 -16.0528)
		(width 0.10795)
		(layer "F.Cu")
		(net "PCA9554_A0")
	)
	(segment
		(start 420.69004 -30.53461)
		(end 421.09009 -30.13456)
		(width 0.10795)
		(layer "F.Cu")
		(net "BMC_RSMRST_B_N")
	)
	(via
		(at 394.551662 -31.549086)
		(size 0.508)
		(drill 0.254)
		(layers "F.Cu" "B.Cu")
		(net "BMC_RSMRST_B_N")
	)
	(via
		(at 421.09009 -30.13456)
		(size 0.4572)
		(drill 0.2032)
		(layers "F.Cu" "B.Cu")
		(net "BMC_RSMRST_B_N")
	)
	(via
		(at 420.33825 -29.280612)
		(size 0.6604)
		(drill 0.3302)
		(layers "F.Cu" "B.Cu")
		(net "BMC_RSMRST_B_N")
	)
	(segment
		(start 394.251434 -32.250634)
		(end 394.251434 -31.849314)
		(width 0.10795)
		(layer "B.Cu")
		(net "BMC_RSMRST_B_N")
	)
	(segment
		(start 421.09009 -30.032452)
		(end 420.33825 -29.280612)
		(width 0.10795)
		(layer "B.Cu")
		(net "BMC_RSMRST_B_N")
	)
	(segment
		(start 394.251434 -31.849314)
		(end 394.551662 -31.549086)
		(width 0.10795)
		(layer "B.Cu")
		(net "BMC_RSMRST_B_N")
	)
	(segment
		(start 421.09009 -30.13456)
		(end 421.09009 -30.032452)
		(width 0.10795)
		(layer "B.Cu")
		(net "BMC_RSMRST_B_N")
	)
	(segment
		(start 396.251684 -30.460696)
		(end 395.428724 -30.460696)
		(width 0.089408)
		(layer "In4.Cu")
		(net "BMC_RSMRST_B_N")
	)
	(segment
		(start 406.325832 -32.159448)
		(end 405.307038 -33.178242)
		(width 0.089408)
		(layer "In4.Cu")
		(net "BMC_RSMRST_B_N")
	)
	(segment
		(start 408.664664 -31.8897)
		(end 408.394916 -32.159448)
		(width 0.089408)
		(layer "In4.Cu")
		(net "BMC_RSMRST_B_N")
	)
	(segment
		(start 413.951928 -31.30931)
		(end 408.985466 -31.30931)
		(width 0.089408)
		(layer "In4.Cu")
		(net "BMC_RSMRST_B_N")
	)
	(segment
		(start 408.985466 -31.30931)
		(end 408.664664 -31.630112)
		(width 0.089408)
		(layer "In4.Cu")
		(net "BMC_RSMRST_B_N")
	)
	(segment
		(start 402.730208 -33.178242)
		(end 401.610576 -32.05861)
		(width 0.089408)
		(layer "In4.Cu")
		(net "BMC_RSMRST_B_N")
	)
	(segment
		(start 414.535874 -30.725364)
		(end 413.951928 -31.30931)
		(width 0.089408)
		(layer "In4.Cu")
		(net "BMC_RSMRST_B_N")
	)
	(segment
		(start 419.884098 -30.004258)
		(end 419.323266 -30.004258)
		(width 0.089408)
		(layer "In4.Cu")
		(net "BMC_RSMRST_B_N")
	)
	(segment
		(start 418.60216 -30.725364)
		(end 414.535874 -30.725364)
		(width 0.089408)
		(layer "In4.Cu")
		(net "BMC_RSMRST_B_N")
	)
	(segment
		(start 395.428724 -30.460696)
		(end 394.551662 -31.337758)
		(width 0.089408)
		(layer "In4.Cu")
		(net "BMC_RSMRST_B_N")
	)
	(segment
		(start 419.323266 -30.004258)
		(end 418.60216 -30.725364)
		(width 0.089408)
		(layer "In4.Cu")
		(net "BMC_RSMRST_B_N")
	)
	(segment
		(start 405.307038 -33.178242)
		(end 402.730208 -33.178242)
		(width 0.089408)
		(layer "In4.Cu")
		(net "BMC_RSMRST_B_N")
	)
	(segment
		(start 408.394916 -32.159448)
		(end 406.325832 -32.159448)
		(width 0.089408)
		(layer "In4.Cu")
		(net "BMC_RSMRST_B_N")
	)
	(segment
		(start 420.712392 -29.756862)
		(end 420.131494 -29.756862)
		(width 0.089408)
		(layer "In4.Cu")
		(net "BMC_RSMRST_B_N")
	)
	(segment
		(start 398.940528 -31.403544)
		(end 397.194532 -31.403544)
		(width 0.089408)
		(layer "In4.Cu")
		(net "BMC_RSMRST_B_N")
	)
	(segment
		(start 420.131494 -29.756862)
		(end 419.884098 -30.004258)
		(width 0.089408)
		(layer "In4.Cu")
		(net "BMC_RSMRST_B_N")
	)
	(segment
		(start 397.194532 -31.403544)
		(end 396.251684 -30.460696)
		(width 0.089408)
		(layer "In4.Cu")
		(net "BMC_RSMRST_B_N")
	)
	(segment
		(start 401.610576 -32.05861)
		(end 399.595594 -32.05861)
		(width 0.089408)
		(layer "In4.Cu")
		(net "BMC_RSMRST_B_N")
	)
	(segment
		(start 394.551662 -31.337758)
		(end 394.551662 -31.549086)
		(width 0.089408)
		(layer "In4.Cu")
		(net "BMC_RSMRST_B_N")
	)
	(segment
		(start 399.595594 -32.05861)
		(end 398.940528 -31.403544)
		(width 0.089408)
		(layer "In4.Cu")
		(net "BMC_RSMRST_B_N")
	)
	(segment
		(start 421.09009 -30.13456)
		(end 420.712392 -29.756862)
		(width 0.089408)
		(layer "In4.Cu")
		(net "BMC_RSMRST_B_N")
	)
	(segment
		(start 408.664664 -31.630112)
		(end 408.664664 -31.8897)
		(width 0.089408)
		(layer "In4.Cu")
		(net "BMC_RSMRST_B_N")
	)
	(segment
		(start 399.280126 -0.109474)
		(end 398.526 -0.8636)
		(width 0.10795)
		(layer "F.Cu")
		(net "BMC_JTAG_SEL_N")
	)
	(segment
		(start 399.770092 -0.109474)
		(end 399.280126 -0.109474)
		(width 0.10795)
		(layer "F.Cu")
		(net "BMC_JTAG_SEL_N")
	)
	(segment
		(start 417.490148 -43.334686)
		(end 417.490148 -43.842686)
		(width 0.089408)
		(layer "F.Cu")
		(net "BMC_JTAG_SEL_N")
	)
	(via
		(at 438.326276 -145.240756)
		(size 0.508)
		(drill 0.254)
		(layers "F.Cu" "B.Cu")
		(net "BMC_JTAG_SEL_N")
	)
	(via
		(at 422.849548 -111.94669)
		(size 0.508)
		(drill 0.254)
		(layers "F.Cu" "B.Cu")
		(net "BMC_JTAG_SEL_N")
	)
	(via
		(at 466.2424 -0.9906)
		(size 0.508)
		(drill 0.254)
		(layers "F.Cu" "B.Cu")
		(net "BMC_JTAG_SEL_N")
	)
	(via
		(at 427.63821 -63.625222)
		(size 0.508)
		(drill 0.254)
		(layers "F.Cu" "B.Cu")
		(net "BMC_JTAG_SEL_N")
	)
	(via
		(at 398.526 -0.8636)
		(size 0.508)
		(drill 0.254)
		(layers "F.Cu" "B.Cu")
		(net "BMC_JTAG_SEL_N")
	)
	(via
		(at 448.6656 -152.2476)
		(size 0.508)
		(drill 0.254)
		(layers "F.Cu" "B.Cu")
		(net "BMC_JTAG_SEL_N")
	)
	(via
		(at 471.1446 -44.6786)
		(size 0.508)
		(drill 0.254)
		(layers "F.Cu" "B.Cu")
		(net "BMC_JTAG_SEL_N")
	)
	(via
		(at 417.490148 -43.842686)
		(size 0.4572)
		(drill 0.2032)
		(layers "F.Cu" "B.Cu")
		(net "BMC_JTAG_SEL_N")
	)
	(segment
		(start 438.976516 -144.590516)
		(end 438.976516 -143.589756)
		(width 0.10795)
		(layer "B.Cu")
		(net "BMC_JTAG_SEL_N")
	)
	(segment
		(start 438.6199 -141.986)
		(end 438.6199 -142.5829)
		(width 0.10795)
		(layer "B.Cu")
		(net "BMC_JTAG_SEL_N")
	)
	(segment
		(start 438.6199 -141.986)
		(end 437.642 -141.986)
		(width 0.10795)
		(layer "B.Cu")
		(net "BMC_JTAG_SEL_N")
	)
	(segment
		(start 438.976516 -142.939516)
		(end 438.976516 -143.589756)
		(width 0.10795)
		(layer "B.Cu")
		(net "BMC_JTAG_SEL_N")
	)
	(segment
		(start 438.6199 -142.5829)
		(end 438.976516 -142.939516)
		(width 0.10795)
		(layer "B.Cu")
		(net "BMC_JTAG_SEL_N")
	)
	(segment
		(start 438.326276 -145.240756)
		(end 438.976516 -144.590516)
		(width 0.10795)
		(layer "B.Cu")
		(net "BMC_JTAG_SEL_N")
	)
	(segment
		(start 448.6656 -151.384)
		(end 448.6656 -152.2476)
		(width 0.10795)
		(layer "B.Cu")
		(net "BMC_JTAG_SEL_N")
	)
	(segment
		(start 448.6656 -152.2476)
		(end 448.6656 -150.1394)
		(width 0.089408)
		(layer "In2.Cu")
		(net "BMC_JTAG_SEL_N")
	)
	(segment
		(start 425.027598 -46.83125)
		(end 425.027598 -46.084998)
		(width 0.089408)
		(layer "In2.Cu")
		(net "BMC_JTAG_SEL_N")
	)
	(segment
		(start 438.52592 -145.4404)
		(end 438.326276 -145.240756)
		(width 0.089408)
		(layer "In2.Cu")
		(net "BMC_JTAG_SEL_N")
	)
	(segment
		(start 422.651428 -76.13015)
		(end 422.651428 -67.547744)
		(width 0.089408)
		(layer "In2.Cu")
		(net "BMC_JTAG_SEL_N")
	)
	(segment
		(start 422.097962 -95.598996)
		(end 424.008042 -93.688916)
		(width 0.089408)
		(layer "In2.Cu")
		(net "BMC_JTAG_SEL_N")
	)
	(segment
		(start 433.4764 -47.0154)
		(end 432.938682 -47.553118)
		(width 0.089408)
		(layer "In2.Cu")
		(net "BMC_JTAG_SEL_N")
	)
	(segment
		(start 429.18126 -48.38446)
		(end 428.54626 -47.74946)
		(width 0.089408)
		(layer "In2.Cu")
		(net "BMC_JTAG_SEL_N")
	)
	(segment
		(start 470.84869 -44.6786)
		(end 468.022178 -47.505112)
		(width 0.089408)
		(layer "In2.Cu")
		(net "BMC_JTAG_SEL_N")
	)
	(segment
		(start 422.523158 -111.94669)
		(end 421.98544 -111.408972)
		(width 0.089408)
		(layer "In2.Cu")
		(net "BMC_JTAG_SEL_N")
	)
	(segment
		(start 448.6656 -150.1394)
		(end 447.158618 -148.632418)
		(width 0.089408)
		(layer "In2.Cu")
		(net "BMC_JTAG_SEL_N")
	)
	(segment
		(start 423.441368 -43.0276)
		(end 421.8686 -43.0276)
		(width 0.089408)
		(layer "In2.Cu")
		(net "BMC_JTAG_SEL_N")
	)
	(segment
		(start 439.337704 -47.441104)
		(end 434.765704 -47.441104)
		(width 0.089408)
		(layer "In2.Cu")
		(net "BMC_JTAG_SEL_N")
	)
	(segment
		(start 428.54626 -47.74946)
		(end 427.509686 -47.74946)
		(width 0.089408)
		(layer "In2.Cu")
		(net "BMC_JTAG_SEL_N")
	)
	(segment
		(start 468.022178 -47.505112)
		(end 439.401712 -47.505112)
		(width 0.089408)
		(layer "In2.Cu")
		(net "BMC_JTAG_SEL_N")
	)
	(segment
		(start 423.39006 -78.987396)
		(end 423.39006 -76.868782)
		(width 0.089408)
		(layer "In2.Cu")
		(net "BMC_JTAG_SEL_N")
	)
	(segment
		(start 425.027598 -46.084998)
		(end 424.100752 -45.158152)
		(width 0.089408)
		(layer "In2.Cu")
		(net "BMC_JTAG_SEL_N")
	)
	(segment
		(start 447.158618 -148.632418)
		(end 444.644018 -148.632418)
		(width 0.089408)
		(layer "In2.Cu")
		(net "BMC_JTAG_SEL_N")
	)
	(segment
		(start 423.232834 -103.633016)
		(end 423.232834 -97.602294)
		(width 0.089408)
		(layer "In2.Cu")
		(net "BMC_JTAG_SEL_N")
	)
	(segment
		(start 432.238658 -49.873408)
		(end 429.349408 -49.873408)
		(width 0.089408)
		(layer "In2.Cu")
		(net "BMC_JTAG_SEL_N")
	)
	(segment
		(start 429.349408 -49.873408)
		(end 429.18126 -49.70526)
		(width 0.089408)
		(layer "In2.Cu")
		(net "BMC_JTAG_SEL_N")
	)
	(segment
		(start 427.271942 -63.99149)
		(end 427.63821 -63.625222)
		(width 0.089408)
		(layer "In2.Cu")
		(net "BMC_JTAG_SEL_N")
	)
	(segment
		(start 422.849548 -111.94669)
		(end 422.523158 -111.94669)
		(width 0.089408)
		(layer "In2.Cu")
		(net "BMC_JTAG_SEL_N")
	)
	(segment
		(start 424.100752 -43.686984)
		(end 423.441368 -43.0276)
		(width 0.089408)
		(layer "In2.Cu")
		(net "BMC_JTAG_SEL_N")
	)
	(segment
		(start 426.207682 -63.99149)
		(end 427.271942 -63.99149)
		(width 0.089408)
		(layer "In2.Cu")
		(net "BMC_JTAG_SEL_N")
	)
	(segment
		(start 423.232834 -97.602294)
		(end 422.097962 -96.467422)
		(width 0.089408)
		(layer "In2.Cu")
		(net "BMC_JTAG_SEL_N")
	)
	(segment
		(start 434.34 -47.0154)
		(end 433.4764 -47.0154)
		(width 0.089408)
		(layer "In2.Cu")
		(net "BMC_JTAG_SEL_N")
	)
	(segment
		(start 429.18126 -49.70526)
		(end 429.18126 -48.38446)
		(width 0.089408)
		(layer "In2.Cu")
		(net "BMC_JTAG_SEL_N")
	)
	(segment
		(start 424.008042 -79.605378)
		(end 423.39006 -78.987396)
		(width 0.089408)
		(layer "In2.Cu")
		(net "BMC_JTAG_SEL_N")
	)
	(segment
		(start 423.39006 -76.868782)
		(end 422.651428 -76.13015)
		(width 0.089408)
		(layer "In2.Cu")
		(net "BMC_JTAG_SEL_N")
	)
	(segment
		(start 442.1886 -146.177)
		(end 441.6806 -146.177)
		(width 0.089408)
		(layer "In2.Cu")
		(net "BMC_JTAG_SEL_N")
	)
	(segment
		(start 440.944 -145.4404)
		(end 438.52592 -145.4404)
		(width 0.089408)
		(layer "In2.Cu")
		(net "BMC_JTAG_SEL_N")
	)
	(segment
		(start 421.98544 -111.408972)
		(end 421.98544 -104.88041)
		(width 0.089408)
		(layer "In2.Cu")
		(net "BMC_JTAG_SEL_N")
	)
	(segment
		(start 421.98544 -104.88041)
		(end 423.232834 -103.633016)
		(width 0.089408)
		(layer "In2.Cu")
		(net "BMC_JTAG_SEL_N")
	)
	(segment
		(start 441.6806 -146.177)
		(end 440.944 -145.4404)
		(width 0.089408)
		(layer "In2.Cu")
		(net "BMC_JTAG_SEL_N")
	)
	(segment
		(start 421.8686 -43.0276)
		(end 421.51173 -43.38447)
		(width 0.089408)
		(layer "In2.Cu")
		(net "BMC_JTAG_SEL_N")
	)
	(segment
		(start 439.401712 -47.505112)
		(end 439.337704 -47.441104)
		(width 0.089408)
		(layer "In2.Cu")
		(net "BMC_JTAG_SEL_N")
	)
	(segment
		(start 427.509686 -47.74946)
		(end 427.346618 -47.912528)
		(width 0.089408)
		(layer "In2.Cu")
		(net "BMC_JTAG_SEL_N")
	)
	(segment
		(start 422.097962 -96.467422)
		(end 422.097962 -95.598996)
		(width 0.089408)
		(layer "In2.Cu")
		(net "BMC_JTAG_SEL_N")
	)
	(segment
		(start 424.008042 -93.688916)
		(end 424.008042 -79.605378)
		(width 0.089408)
		(layer "In2.Cu")
		(net "BMC_JTAG_SEL_N")
	)
	(segment
		(start 427.346618 -47.912528)
		(end 426.10913 -47.912528)
		(width 0.089408)
		(layer "In2.Cu")
		(net "BMC_JTAG_SEL_N")
	)
	(segment
		(start 444.644018 -148.632418)
		(end 442.1886 -146.177)
		(width 0.089408)
		(layer "In2.Cu")
		(net "BMC_JTAG_SEL_N")
	)
	(segment
		(start 417.891214 -43.842686)
		(end 417.490148 -43.842686)
		(width 0.089408)
		(layer "In2.Cu")
		(net "BMC_JTAG_SEL_N")
	)
	(segment
		(start 421.51173 -43.38447)
		(end 418.34943 -43.38447)
		(width 0.089408)
		(layer "In2.Cu")
		(net "BMC_JTAG_SEL_N")
	)
	(segment
		(start 471.1446 -44.6786)
		(end 470.84869 -44.6786)
		(width 0.089408)
		(layer "In2.Cu")
		(net "BMC_JTAG_SEL_N")
	)
	(segment
		(start 432.938682 -49.173384)
		(end 432.238658 -49.873408)
		(width 0.089408)
		(layer "In2.Cu")
		(net "BMC_JTAG_SEL_N")
	)
	(segment
		(start 425.469558 -47.27321)
		(end 425.027598 -46.83125)
		(width 0.089408)
		(layer "In2.Cu")
		(net "BMC_JTAG_SEL_N")
	)
	(segment
		(start 434.765704 -47.441104)
		(end 434.34 -47.0154)
		(width 0.089408)
		(layer "In2.Cu")
		(net "BMC_JTAG_SEL_N")
	)
	(segment
		(start 432.938682 -47.553118)
		(end 432.938682 -49.173384)
		(width 0.089408)
		(layer "In2.Cu")
		(net "BMC_JTAG_SEL_N")
	)
	(segment
		(start 426.10913 -47.912528)
		(end 425.469812 -47.27321)
		(width 0.089408)
		(layer "In2.Cu")
		(net "BMC_JTAG_SEL_N")
	)
	(segment
		(start 425.469812 -47.27321)
		(end 425.469558 -47.27321)
		(width 0.089408)
		(layer "In2.Cu")
		(net "BMC_JTAG_SEL_N")
	)
	(segment
		(start 418.34943 -43.38447)
		(end 417.891214 -43.842686)
		(width 0.089408)
		(layer "In2.Cu")
		(net "BMC_JTAG_SEL_N")
	)
	(segment
		(start 424.100752 -45.158152)
		(end 424.100752 -43.686984)
		(width 0.089408)
		(layer "In2.Cu")
		(net "BMC_JTAG_SEL_N")
	)
	(segment
		(start 422.651428 -67.547744)
		(end 426.207682 -63.99149)
		(width 0.089408)
		(layer "In2.Cu")
		(net "BMC_JTAG_SEL_N")
	)
	(segment
		(start 471.6272 -42.164)
		(end 471.2462 -41.783)
		(width 0.089408)
		(layer "In9.Cu")
		(net "BMC_JTAG_SEL_N")
	)
	(segment
		(start 471.500454 -40.969946)
		(end 471.500454 -39.297102)
		(width 0.089408)
		(layer "In9.Cu")
		(net "BMC_JTAG_SEL_N")
	)
	(segment
		(start 462.7118 -5.8166)
		(end 462.7118 -4.9276)
		(width 0.089408)
		(layer "In9.Cu")
		(net "BMC_JTAG_SEL_N")
	)
	(segment
		(start 422.43375 -112.362488)
		(end 422.849548 -111.94669)
		(width 0.089408)
		(layer "In9.Cu")
		(net "BMC_JTAG_SEL_N")
	)
	(segment
		(start 471.6272 -43.2308)
		(end 471.6272 -42.164)
		(width 0.089408)
		(layer "In9.Cu")
		(net "BMC_JTAG_SEL_N")
	)
	(segment
		(start 438.785 -144.782032)
		(end 438.785 -142.368016)
		(width 0.089408)
		(layer "In9.Cu")
		(net "BMC_JTAG_SEL_N")
	)
	(segment
		(start 438.326276 -145.240756)
		(end 438.785 -144.782032)
		(width 0.089408)
		(layer "In9.Cu")
		(net "BMC_JTAG_SEL_N")
	)
	(segment
		(start 468.8332 -13.716)
		(end 467.8172 -12.7)
		(width 0.089408)
		(layer "In9.Cu")
		(net "BMC_JTAG_SEL_N")
	)
	(segment
		(start 417.670488 -123.30684)
		(end 417.670488 -121.502678)
		(width 0.089408)
		(layer "In9.Cu")
		(net "BMC_JTAG_SEL_N")
	)
	(segment
		(start 471.500454 -39.297102)
		(end 470.374472 -38.17112)
		(width 0.089408)
		(layer "In9.Cu")
		(net "BMC_JTAG_SEL_N")
	)
	(segment
		(start 471.2462 -41.783)
		(end 471.2462 -41.2242)
		(width 0.089408)
		(layer "In9.Cu")
		(net "BMC_JTAG_SEL_N")
	)
	(segment
		(start 471.2462 -41.2242)
		(end 471.500454 -40.969946)
		(width 0.089408)
		(layer "In9.Cu")
		(net "BMC_JTAG_SEL_N")
	)
	(segment
		(start 462.7118 -4.9276)
		(end 463.7278 -3.9116)
		(width 0.089408)
		(layer "In9.Cu")
		(net "BMC_JTAG_SEL_N")
	)
	(segment
		(start 436.9943 -134.347712)
		(end 429.937672 -134.347712)
		(width 0.089408)
		(layer "In9.Cu")
		(net "BMC_JTAG_SEL_N")
	)
	(segment
		(start 470.374472 -38.17112)
		(end 470.374472 -35.56)
		(width 0.089408)
		(layer "In9.Cu")
		(net "BMC_JTAG_SEL_N")
	)
	(segment
		(start 471.1446 -43.7134)
		(end 471.6272 -43.2308)
		(width 0.089408)
		(layer "In9.Cu")
		(net "BMC_JTAG_SEL_N")
	)
	(segment
		(start 470.662 -13.716)
		(end 468.8332 -13.716)
		(width 0.089408)
		(layer "In9.Cu")
		(net "BMC_JTAG_SEL_N")
	)
	(segment
		(start 464.568032 -7.368032)
		(end 464.263232 -7.368032)
		(width 0.089408)
		(layer "In9.Cu")
		(net "BMC_JTAG_SEL_N")
	)
	(segment
		(start 418.82441 -125.242574)
		(end 418.342064 -124.760228)
		(width 0.089408)
		(layer "In9.Cu")
		(net "BMC_JTAG_SEL_N")
	)
	(segment
		(start 424.43273 -131.755134)
		(end 418.82441 -126.146814)
		(width 0.089408)
		(layer "In9.Cu")
		(net "BMC_JTAG_SEL_N")
	)
	(segment
		(start 467.8172 -12.7)
		(end 467.8172 -9.8806)
		(width 0.089408)
		(layer "In9.Cu")
		(net "BMC_JTAG_SEL_N")
	)
	(segment
		(start 475.163642 -25.013158)
		(end 475.163642 -18.217642)
		(width 0.089408)
		(layer "In9.Cu")
		(net "BMC_JTAG_SEL_N")
	)
	(segment
		(start 463.7278 -2.6162)
		(end 464.439 -1.905)
		(width 0.089408)
		(layer "In9.Cu")
		(net "BMC_JTAG_SEL_N")
	)
	(segment
		(start 417.670488 -121.502678)
		(end 422.43375 -116.739416)
		(width 0.089408)
		(layer "In9.Cu")
		(net "BMC_JTAG_SEL_N")
	)
	(segment
		(start 470.374472 -35.56)
		(end 470.219532 -35.40506)
		(width 0.089408)
		(layer "In9.Cu")
		(net "BMC_JTAG_SEL_N")
	)
	(segment
		(start 438.523888 -135.8773)
		(end 436.9943 -134.347712)
		(width 0.089408)
		(layer "In9.Cu")
		(net "BMC_JTAG_SEL_N")
	)
	(segment
		(start 427.345094 -131.755134)
		(end 424.43273 -131.755134)
		(width 0.089408)
		(layer "In9.Cu")
		(net "BMC_JTAG_SEL_N")
	)
	(segment
		(start 464.263232 -7.368032)
		(end 462.7118 -5.8166)
		(width 0.089408)
		(layer "In9.Cu")
		(net "BMC_JTAG_SEL_N")
	)
	(segment
		(start 418.342064 -123.978416)
		(end 417.670488 -123.30684)
		(width 0.089408)
		(layer "In9.Cu")
		(net "BMC_JTAG_SEL_N")
	)
	(segment
		(start 466.489034 -9.4742)
		(end 466.324696 -9.309862)
		(width 0.089408)
		(layer "In9.Cu")
		(net "BMC_JTAG_SEL_N")
	)
	(segment
		(start 422.43375 -116.739416)
		(end 422.43375 -112.362488)
		(width 0.089408)
		(layer "In9.Cu")
		(net "BMC_JTAG_SEL_N")
	)
	(segment
		(start 467.4108 -9.4742)
		(end 466.489034 -9.4742)
		(width 0.089408)
		(layer "In9.Cu")
		(net "BMC_JTAG_SEL_N")
	)
	(segment
		(start 465.328 -1.905)
		(end 466.2424 -0.9906)
		(width 0.089408)
		(layer "In9.Cu")
		(net "BMC_JTAG_SEL_N")
	)
	(segment
		(start 438.785 -142.368016)
		(end 438.523888 -142.106904)
		(width 0.089408)
		(layer "In9.Cu")
		(net "BMC_JTAG_SEL_N")
	)
	(segment
		(start 472.5162 -29.5402)
		(end 472.5162 -27.6606)
		(width 0.089408)
		(layer "In9.Cu")
		(net "BMC_JTAG_SEL_N")
	)
	(segment
		(start 472.5162 -27.6606)
		(end 475.163642 -25.013158)
		(width 0.089408)
		(layer "In9.Cu")
		(net "BMC_JTAG_SEL_N")
	)
	(segment
		(start 466.324696 -9.309862)
		(end 466.324696 -9.124696)
		(width 0.089408)
		(layer "In9.Cu")
		(net "BMC_JTAG_SEL_N")
	)
	(segment
		(start 464.439 -1.905)
		(end 465.328 -1.905)
		(width 0.089408)
		(layer "In9.Cu")
		(net "BMC_JTAG_SEL_N")
	)
	(segment
		(start 438.523888 -142.106904)
		(end 438.523888 -135.8773)
		(width 0.089408)
		(layer "In9.Cu")
		(net "BMC_JTAG_SEL_N")
	)
	(segment
		(start 466.324696 -9.124696)
		(end 464.568032 -7.368032)
		(width 0.089408)
		(layer "In9.Cu")
		(net "BMC_JTAG_SEL_N")
	)
	(segment
		(start 467.8172 -9.8806)
		(end 467.4108 -9.4742)
		(width 0.089408)
		(layer "In9.Cu")
		(net "BMC_JTAG_SEL_N")
	)
	(segment
		(start 463.7278 -3.9116)
		(end 463.7278 -2.6162)
		(width 0.089408)
		(layer "In9.Cu")
		(net "BMC_JTAG_SEL_N")
	)
	(segment
		(start 475.163642 -18.217642)
		(end 470.662 -13.716)
		(width 0.089408)
		(layer "In9.Cu")
		(net "BMC_JTAG_SEL_N")
	)
	(segment
		(start 418.82441 -126.146814)
		(end 418.82441 -125.242574)
		(width 0.089408)
		(layer "In9.Cu")
		(net "BMC_JTAG_SEL_N")
	)
	(segment
		(start 470.219532 -35.40506)
		(end 470.219532 -31.836868)
		(width 0.089408)
		(layer "In9.Cu")
		(net "BMC_JTAG_SEL_N")
	)
	(segment
		(start 470.219532 -31.836868)
		(end 472.5162 -29.5402)
		(width 0.089408)
		(layer "In9.Cu")
		(net "BMC_JTAG_SEL_N")
	)
	(segment
		(start 429.937672 -134.347712)
		(end 427.345094 -131.755134)
		(width 0.089408)
		(layer "In9.Cu")
		(net "BMC_JTAG_SEL_N")
	)
	(segment
		(start 418.342064 -124.760228)
		(end 418.342064 -123.978416)
		(width 0.089408)
		(layer "In9.Cu")
		(net "BMC_JTAG_SEL_N")
	)
	(segment
		(start 471.1446 -44.6786)
		(end 471.1446 -43.7134)
		(width 0.089408)
		(layer "In9.Cu")
		(net "BMC_JTAG_SEL_N")
	)
	(segment
		(start 465.149692 1.270508)
		(end 463.70748 2.71272)
		(width 0.089408)
		(layer "In11.Cu")
		(net "BMC_JTAG_SEL_N")
	)
	(segment
		(start 463.167476 2.712974)
		(end 463.167222 2.71272)
		(width 0.089408)
		(layer "In11.Cu")
		(net "BMC_JTAG_SEL_N")
	)
	(segment
		(start 419.202616 -43.48861)
		(end 421.44315 -45.729144)
		(width 0.089408)
		(layer "In11.Cu")
		(net "BMC_JTAG_SEL_N")
	)
	(segment
		(start 426.328332 -1.030732)
		(end 426.328332 -0.802132)
		(width 0.089408)
		(layer "In11.Cu")
		(net "BMC_JTAG_SEL_N")
	)
	(segment
		(start 421.44315 -46.70679)
		(end 421.90797 -47.17161)
		(width 0.089408)
		(layer "In11.Cu")
		(net "BMC_JTAG_SEL_N")
	)
	(segment
		(start 423.670984 1.855216)
		(end 417.322 1.855216)
		(width 0.089408)
		(layer "In11.Cu")
		(net "BMC_JTAG_SEL_N")
	)
	(segment
		(start 423.723308 -49.183544)
		(end 423.723308 -49.42586)
		(width 0.089408)
		(layer "In11.Cu")
		(net "BMC_JTAG_SEL_N")
	)
	(segment
		(start 426.514768 -60.364116)
		(end 426.514768 -62.361572)
		(width 0.089408)
		(layer "In11.Cu")
		(net "BMC_JTAG_SEL_N")
	)
	(segment
		(start 466.2424 -0.9906)
		(end 466.2424 -0.473456)
		(width 0.089408)
		(layer "In11.Cu")
		(net "BMC_JTAG_SEL_N")
	)
	(segment
		(start 445.551052 -1.336548)
		(end 426.634148 -1.336548)
		(width 0.089408)
		(layer "In11.Cu")
		(net "BMC_JTAG_SEL_N")
	)
	(segment
		(start 400.849592 0.7112)
		(end 399.274792 -0.8636)
		(width 0.089408)
		(layer "In11.Cu")
		(net "BMC_JTAG_SEL_N")
	)
	(segment
		(start 447.966592 1.078992)
		(end 445.551052 -1.336548)
		(width 0.089408)
		(layer "In11.Cu")
		(net "BMC_JTAG_SEL_N")
	)
	(segment
		(start 463.70748 2.71272)
		(end 463.568542 2.71272)
		(width 0.089408)
		(layer "In11.Cu")
		(net "BMC_JTAG_SEL_N")
	)
	(segment
		(start 426.634148 -1.336548)
		(end 426.328332 -1.030732)
		(width 0.089408)
		(layer "In11.Cu")
		(net "BMC_JTAG_SEL_N")
	)
	(segment
		(start 426.32884 -54.182264)
		(end 426.32884 -60.178188)
		(width 0.089408)
		(layer "In11.Cu")
		(net "BMC_JTAG_SEL_N")
	)
	(segment
		(start 424.46575 -51.234594)
		(end 424.83278 -51.601624)
		(width 0.089408)
		(layer "In11.Cu")
		(net "BMC_JTAG_SEL_N")
	)
	(segment
		(start 447.966592 1.7653)
		(end 447.966592 1.078992)
		(width 0.089408)
		(layer "In11.Cu")
		(net "BMC_JTAG_SEL_N")
	)
	(segment
		(start 423.723054 -49.92624)
		(end 424.176444 -50.37963)
		(width 0.089408)
		(layer "In11.Cu")
		(net "BMC_JTAG_SEL_N")
	)
	(segment
		(start 463.167222 2.71272)
		(end 448.914012 2.71272)
		(width 0.089408)
		(layer "In11.Cu")
		(net "BMC_JTAG_SEL_N")
	)
	(segment
		(start 417.844224 -43.48861)
		(end 419.202616 -43.48861)
		(width 0.089408)
		(layer "In11.Cu")
		(net "BMC_JTAG_SEL_N")
	)
	(segment
		(start 407.543 0.1778)
		(end 407.0096 0.7112)
		(width 0.089408)
		(layer "In11.Cu")
		(net "BMC_JTAG_SEL_N")
	)
	(segment
		(start 423.723054 -48.842676)
		(end 423.723054 -49.18329)
		(width 0.089408)
		(layer "In11.Cu")
		(net "BMC_JTAG_SEL_N")
	)
	(segment
		(start 465.149692 0.619252)
		(end 465.149692 1.270508)
		(width 0.089408)
		(layer "In11.Cu")
		(net "BMC_JTAG_SEL_N")
	)
	(segment
		(start 424.176444 -50.37963)
		(end 424.176444 -50.382678)
		(width 0.089408)
		(layer "In11.Cu")
		(net "BMC_JTAG_SEL_N")
	)
	(segment
		(start 422.051988 -47.17161)
		(end 423.723054 -48.842676)
		(width 0.089408)
		(layer "In11.Cu")
		(net "BMC_JTAG_SEL_N")
	)
	(segment
		(start 399.274792 -0.8636)
		(end 398.526 -0.8636)
		(width 0.089408)
		(layer "In11.Cu")
		(net "BMC_JTAG_SEL_N")
	)
	(segment
		(start 421.90797 -47.17161)
		(end 422.051988 -47.17161)
		(width 0.089408)
		(layer "In11.Cu")
		(net "BMC_JTAG_SEL_N")
	)
	(segment
		(start 424.176444 -50.382678)
		(end 424.46575 -50.671984)
		(width 0.089408)
		(layer "In11.Cu")
		(net "BMC_JTAG_SEL_N")
	)
	(segment
		(start 463.568288 2.712974)
		(end 463.167476 2.712974)
		(width 0.089408)
		(layer "In11.Cu")
		(net "BMC_JTAG_SEL_N")
	)
	(segment
		(start 427.63821 -63.485014)
		(end 427.63821 -63.625222)
		(width 0.089408)
		(layer "In11.Cu")
		(net "BMC_JTAG_SEL_N")
	)
	(segment
		(start 421.44315 -45.729144)
		(end 421.44315 -46.70679)
		(width 0.089408)
		(layer "In11.Cu")
		(net "BMC_JTAG_SEL_N")
	)
	(segment
		(start 423.723054 -49.18329)
		(end 423.723308 -49.183544)
		(width 0.089408)
		(layer "In11.Cu")
		(net "BMC_JTAG_SEL_N")
	)
	(segment
		(start 448.914012 2.71272)
		(end 447.966592 1.7653)
		(width 0.089408)
		(layer "In11.Cu")
		(net "BMC_JTAG_SEL_N")
	)
	(segment
		(start 463.568542 2.71272)
		(end 463.568288 2.712974)
		(width 0.089408)
		(layer "In11.Cu")
		(net "BMC_JTAG_SEL_N")
	)
	(segment
		(start 426.514768 -62.361572)
		(end 427.63821 -63.485014)
		(width 0.089408)
		(layer "In11.Cu")
		(net "BMC_JTAG_SEL_N")
	)
	(segment
		(start 417.322 1.855216)
		(end 415.644584 0.1778)
		(width 0.089408)
		(layer "In11.Cu")
		(net "BMC_JTAG_SEL_N")
	)
	(segment
		(start 424.83278 -51.601624)
		(end 426.104812 -51.601624)
		(width 0.089408)
		(layer "In11.Cu")
		(net "BMC_JTAG_SEL_N")
	)
	(segment
		(start 424.46575 -50.671984)
		(end 424.46575 -51.234594)
		(width 0.089408)
		(layer "In11.Cu")
		(net "BMC_JTAG_SEL_N")
	)
	(segment
		(start 426.104812 -51.601624)
		(end 426.600112 -52.096924)
		(width 0.089408)
		(layer "In11.Cu")
		(net "BMC_JTAG_SEL_N")
	)
	(segment
		(start 423.723054 -49.426114)
		(end 423.723054 -49.92624)
		(width 0.089408)
		(layer "In11.Cu")
		(net "BMC_JTAG_SEL_N")
	)
	(segment
		(start 426.600112 -53.910992)
		(end 426.32884 -54.182264)
		(width 0.089408)
		(layer "In11.Cu")
		(net "BMC_JTAG_SEL_N")
	)
	(segment
		(start 415.644584 0.1778)
		(end 407.543 0.1778)
		(width 0.089408)
		(layer "In11.Cu")
		(net "BMC_JTAG_SEL_N")
	)
	(segment
		(start 426.32884 -60.178188)
		(end 426.514768 -60.364116)
		(width 0.089408)
		(layer "In11.Cu")
		(net "BMC_JTAG_SEL_N")
	)
	(segment
		(start 426.600112 -52.096924)
		(end 426.600112 -53.910992)
		(width 0.089408)
		(layer "In11.Cu")
		(net "BMC_JTAG_SEL_N")
	)
	(segment
		(start 466.2424 -0.473456)
		(end 465.149692 0.619252)
		(width 0.089408)
		(layer "In11.Cu")
		(net "BMC_JTAG_SEL_N")
	)
	(segment
		(start 417.490148 -43.842686)
		(end 417.844224 -43.48861)
		(width 0.089408)
		(layer "In11.Cu")
		(net "BMC_JTAG_SEL_N")
	)
	(segment
		(start 423.723308 -49.42586)
		(end 423.723054 -49.426114)
		(width 0.089408)
		(layer "In11.Cu")
		(net "BMC_JTAG_SEL_N")
	)
	(segment
		(start 407.0096 0.7112)
		(end 400.849592 0.7112)
		(width 0.089408)
		(layer "In11.Cu")
		(net "BMC_JTAG_SEL_N")
	)
	(segment
		(start 426.328332 -0.802132)
		(end 423.670984 1.855216)
		(width 0.089408)
		(layer "In11.Cu")
		(net "BMC_JTAG_SEL_N")
	)
	(segment
		(start 392.69035 -122.7328)
		(end 393.18565 -122.962924)
		(width 0.1143)
		(layer "F.Cu")
		(net "Net_134")
	)
	(via
		(at 393.18565 -122.962924)
		(size 0.508)
		(drill 0.254)
		(layers "F.Cu" "B.Cu")
		(net "Net_134")
	)
	(segment
		(start 391.69975 -122.7328)
		(end 392.19505 -122.962924)
		(width 0.1143)
		(layer "F.Cu")
		(net "Net_135")
	)
	(via
		(at 392.19505 -122.962924)
		(size 0.508)
		(drill 0.254)
		(layers "F.Cu" "B.Cu")
		(net "Net_135")
	)
	(segment
		(start 391.630916 -122.0724)
		(end 391.69975 -122.104404)
		(width 0.1143)
		(layer "F.Cu")
		(net "Net_136")
	)
	(segment
		(start 391.20445 -121.87428)
		(end 391.630916 -122.0724)
		(width 0.1143)
		(layer "F.Cu")
		(net "Net_136")
	)
	(via
		(at 391.69975 -122.104404)
		(size 0.508)
		(drill 0.254)
		(layers "F.Cu" "B.Cu")
		(net "Net_136")
	)
	(segment
		(start 390.21385 -123.59132)
		(end 390.70915 -123.821444)
		(width 0.1143)
		(layer "F.Cu")
		(net "Net_137")
	)
	(via
		(at 390.70915 -123.821444)
		(size 0.508)
		(drill 0.254)
		(layers "F.Cu" "B.Cu")
		(net "Net_137")
	)
	(segment
		(start 393.68095 -122.7328)
		(end 394.17625 -122.962924)
		(width 0.1143)
		(layer "F.Cu")
		(net "Net_138")
	)
	(via
		(at 394.17625 -122.962924)
		(size 0.508)
		(drill 0.254)
		(layers "F.Cu" "B.Cu")
		(net "Net_138")
	)
	(segment
		(start 392.19505 -123.59132)
		(end 392.69035 -123.821444)
		(width 0.1143)
		(layer "F.Cu")
		(net "Net_139")
	)
	(via
		(at 392.69035 -123.821444)
		(size 0.508)
		(drill 0.254)
		(layers "F.Cu" "B.Cu")
		(net "Net_139")
	)
	(segment
		(start 390.70915 -122.7328)
		(end 391.20445 -122.962924)
		(width 0.1143)
		(layer "F.Cu")
		(net "Net_140")
	)
	(via
		(at 391.20445 -122.962924)
		(size 0.508)
		(drill 0.254)
		(layers "F.Cu" "B.Cu")
		(net "Net_140")
	)
	(segment
		(start 391.20445 -123.59132)
		(end 391.69975 -123.821444)
		(width 0.1143)
		(layer "F.Cu")
		(net "Net_141")
	)
	(via
		(at 391.69975 -123.821444)
		(size 0.508)
		(drill 0.254)
		(layers "F.Cu" "B.Cu")
		(net "Net_141")
	)
	(segment
		(start 431.964846 -15.113)
		(end 430.51984 -16.558006)
		(width 0.10795)
		(layer "F.Cu")
		(net "PCA9554_A2")
	)
	(segment
		(start 433.07 -15.113)
		(end 433.832 -15.113)
		(width 0.10795)
		(layer "F.Cu")
		(net "PCA9554_A2")
	)
	(segment
		(start 430.51984 -16.558006)
		(end 430.51984 -17.4244)
		(width 0.10795)
		(layer "F.Cu")
		(net "PCA9554_A2")
	)
	(segment
		(start 433.07 -15.113)
		(end 431.964846 -15.113)
		(width 0.10795)
		(layer "F.Cu")
		(net "PCA9554_A2")
	)
	(segment
		(start 431.17008 -16.42872)
		(end 431.17008 -17.4244)
		(width 0.10795)
		(layer "F.Cu")
		(net "PCA9554_A1")
	)
	(segment
		(start 434.7718 -15.748)
		(end 434.6194 -15.5956)
		(width 0.10795)
		(layer "F.Cu")
		(net "PCA9554_A1")
	)
	(segment
		(start 432.0032 -15.5956)
		(end 431.17008 -16.42872)
		(width 0.10795)
		(layer "F.Cu")
		(net "PCA9554_A1")
	)
	(segment
		(start 434.6194 -15.5956)
		(end 432.0032 -15.5956)
		(width 0.10795)
		(layer "F.Cu")
		(net "PCA9554_A1")
	)
	(segment
		(start 434.7718 -15.748)
		(end 435.5338 -15.748)
		(width 0.10795)
		(layer "F.Cu")
		(net "PCA9554_A1")
	)
	(segment
		(start 403.48662 -109.476032)
		(end 403.869398 -109.85881)
		(width 0.0889)
		(layer "F.Cu")
		(net "FM_PMBUS_ALERT_BUF_EN_R_N")
	)
	(segment
		(start 401.55241 -109.373416)
		(end 401.718018 -109.539024)
		(width 0.0889)
		(layer "F.Cu")
		(net "FM_PMBUS_ALERT_BUF_EN_R_N")
	)
	(segment
		(start 400.880072 -109.354874)
		(end 400.898614 -109.373416)
		(width 0.0889)
		(layer "F.Cu")
		(net "FM_PMBUS_ALERT_BUF_EN_R_N")
	)
	(segment
		(start 402.948648 -109.539024)
		(end 403.01164 -109.476032)
		(width 0.0889)
		(layer "F.Cu")
		(net "FM_PMBUS_ALERT_BUF_EN_R_N")
	)
	(segment
		(start 400.898614 -109.373416)
		(end 401.55241 -109.373416)
		(width 0.0889)
		(layer "F.Cu")
		(net "FM_PMBUS_ALERT_BUF_EN_R_N")
	)
	(segment
		(start 403.01164 -109.476032)
		(end 403.48662 -109.476032)
		(width 0.0889)
		(layer "F.Cu")
		(net "FM_PMBUS_ALERT_BUF_EN_R_N")
	)
	(segment
		(start 401.718018 -109.539024)
		(end 402.948648 -109.539024)
		(width 0.0889)
		(layer "F.Cu")
		(net "FM_PMBUS_ALERT_BUF_EN_R_N")
	)
	(via
		(at 392.056112 -89.521284)
		(size 0.508)
		(drill 0.254)
		(layers "F.Cu" "B.Cu")
		(net "FM_PMBUS_ALERT_BUF_EN_R_N")
	)
	(via
		(at 403.869398 -109.85881)
		(size 0.508)
		(drill 0.254)
		(layers "F.Cu" "B.Cu")
		(net "FM_PMBUS_ALERT_BUF_EN_R_N")
	)
	(segment
		(start 392.269726 -89.30767)
		(end 392.269726 -89.299288)
		(width 0.10795)
		(layer "B.Cu")
		(net "FM_PMBUS_ALERT_BUF_EN_R_N")
	)
	(segment
		(start 392.368532 -89.200482)
		(end 392.376914 -89.200482)
		(width 0.10795)
		(layer "B.Cu")
		(net "FM_PMBUS_ALERT_BUF_EN_R_N")
	)
	(segment
		(start 392.056112 -89.521284)
		(end 392.269726 -89.30767)
		(width 0.10795)
		(layer "B.Cu")
		(net "FM_PMBUS_ALERT_BUF_EN_R_N")
	)
	(segment
		(start 392.692128 -88.885268)
		(end 392.692128 -88.314784)
		(width 0.10795)
		(layer "B.Cu")
		(net "FM_PMBUS_ALERT_BUF_EN_R_N")
	)
	(segment
		(start 392.376914 -89.200482)
		(end 392.692128 -88.885268)
		(width 0.10795)
		(layer "B.Cu")
		(net "FM_PMBUS_ALERT_BUF_EN_R_N")
	)
	(segment
		(start 392.269726 -89.299288)
		(end 392.368532 -89.200482)
		(width 0.10795)
		(layer "B.Cu")
		(net "FM_PMBUS_ALERT_BUF_EN_R_N")
	)
	(segment
		(start 396.2527 -104.484932)
		(end 396.2527 -104.452166)
		(width 0.0889)
		(layer "In2.Cu")
		(net "FM_PMBUS_ALERT_BUF_EN_R_N")
	)
	(segment
		(start 396.650972 -94.283276)
		(end 396.650972 -90.97264)
		(width 0.089408)
		(layer "In2.Cu")
		(net "FM_PMBUS_ALERT_BUF_EN_R_N")
	)
	(segment
		(start 397.547846 -96.441768)
		(end 397.24457 -96.138492)
		(width 0.089408)
		(layer "In2.Cu")
		(net "FM_PMBUS_ALERT_BUF_EN_R_N")
	)
	(segment
		(start 397.547846 -100.20173)
		(end 397.547846 -100.168964)
		(width 0.089408)
		(layer "In2.Cu")
		(net "FM_PMBUS_ALERT_BUF_EN_R_N")
	)
	(segment
		(start 396.420086 -103.206042)
		(end 397.54683 -102.079298)
		(width 0.0889)
		(layer "In2.Cu")
		(net "FM_PMBUS_ALERT_BUF_EN_R_N")
	)
	(segment
		(start 396.30731 -103.206042)
		(end 396.420086 -103.206042)
		(width 0.0889)
		(layer "In2.Cu")
		(net "FM_PMBUS_ALERT_BUF_EN_R_N")
	)
	(segment
		(start 397.24457 -94.876874)
		(end 396.650972 -94.283276)
		(width 0.089408)
		(layer "In2.Cu")
		(net "FM_PMBUS_ALERT_BUF_EN_R_N")
	)
	(segment
		(start 396.748 -108.777532)
		(end 396.748 -108.376212)
		(width 0.0889)
		(layer "In2.Cu")
		(net "FM_PMBUS_ALERT_BUF_EN_R_N")
	)
	(segment
		(start 396.273782 -90.59545)
		(end 395.021054 -90.59545)
		(width 0.089408)
		(layer "In2.Cu")
		(net "FM_PMBUS_ALERT_BUF_EN_R_N")
	)
	(segment
		(start 397.09471 -106.323892)
		(end 397.09471 -106.019854)
		(width 0.0889)
		(layer "In2.Cu")
		(net "FM_PMBUS_ALERT_BUF_EN_R_N")
	)
	(segment
		(start 396.555976 -105.48112)
		(end 396.555976 -104.92359)
		(width 0.0889)
		(layer "In2.Cu")
		(net "FM_PMBUS_ALERT_BUF_EN_R_N")
	)
	(segment
		(start 403.869398 -109.85881)
		(end 403.377908 -110.3503)
		(width 0.089408)
		(layer "In2.Cu")
		(net "FM_PMBUS_ALERT_BUF_EN_R_N")
	)
	(segment
		(start 397.546576 -106.775758)
		(end 397.09471 -106.323892)
		(width 0.0889)
		(layer "In2.Cu")
		(net "FM_PMBUS_ALERT_BUF_EN_R_N")
	)
	(segment
		(start 396.555976 -104.92359)
		(end 396.452852 -104.820466)
		(width 0.0889)
		(layer "In2.Cu")
		(net "FM_PMBUS_ALERT_BUF_EN_R_N")
	)
	(segment
		(start 397.509492 -110.3503)
		(end 397.2433 -110.084108)
		(width 0.089408)
		(layer "In2.Cu")
		(net "FM_PMBUS_ALERT_BUF_EN_R_N")
	)
	(segment
		(start 397.54683 -101.81717)
		(end 398.089882 -101.274118)
		(width 0.089408)
		(layer "In2.Cu")
		(net "FM_PMBUS_ALERT_BUF_EN_R_N")
	)
	(segment
		(start 397.95577 -100.758244)
		(end 397.843248 -100.69322)
		(width 0.089408)
		(layer "In2.Cu")
		(net "FM_PMBUS_ALERT_BUF_EN_R_N")
	)
	(segment
		(start 397.09471 -106.019854)
		(end 396.555976 -105.48112)
		(width 0.0889)
		(layer "In2.Cu")
		(net "FM_PMBUS_ALERT_BUF_EN_R_N")
	)
	(segment
		(start 397.222218 -107.901994)
		(end 397.222218 -107.538774)
		(width 0.0889)
		(layer "In2.Cu")
		(net "FM_PMBUS_ALERT_BUF_EN_R_N")
	)
	(segment
		(start 397.546576 -107.214416)
		(end 397.546576 -106.775758)
		(width 0.0889)
		(layer "In2.Cu")
		(net "FM_PMBUS_ALERT_BUF_EN_R_N")
	)
	(segment
		(start 396.650972 -90.97264)
		(end 396.273782 -90.59545)
		(width 0.089408)
		(layer "In2.Cu")
		(net "FM_PMBUS_ALERT_BUF_EN_R_N")
	)
	(segment
		(start 397.54683 -102.079298)
		(end 397.54683 -101.81717)
		(width 0.089408)
		(layer "In2.Cu")
		(net "FM_PMBUS_ALERT_BUF_EN_R_N")
	)
	(segment
		(start 403.377908 -110.3503)
		(end 397.509492 -110.3503)
		(width 0.089408)
		(layer "In2.Cu")
		(net "FM_PMBUS_ALERT_BUF_EN_R_N")
	)
	(segment
		(start 397.24457 -96.138492)
		(end 397.24457 -94.876874)
		(width 0.089408)
		(layer "In2.Cu")
		(net "FM_PMBUS_ALERT_BUF_EN_R_N")
	)
	(segment
		(start 393.946888 -89.521284)
		(end 392.056112 -89.521284)
		(width 0.089408)
		(layer "In2.Cu")
		(net "FM_PMBUS_ALERT_BUF_EN_R_N")
	)
	(segment
		(start 395.021054 -90.59545)
		(end 393.946888 -89.521284)
		(width 0.089408)
		(layer "In2.Cu")
		(net "FM_PMBUS_ALERT_BUF_EN_R_N")
	)
	(segment
		(start 396.748 -108.376212)
		(end 397.222218 -107.901994)
		(width 0.0889)
		(layer "In2.Cu")
		(net "FM_PMBUS_ALERT_BUF_EN_R_N")
	)
	(segment
		(start 397.2433 -110.084108)
		(end 397.2433 -109.603286)
		(width 0.0889)
		(layer "In2.Cu")
		(net "FM_PMBUS_ALERT_BUF_EN_R_N")
	)
	(segment
		(start 398.133316 -101.169216)
		(end 398.133316 -101.06533)
		(width 0.089408)
		(layer "In2.Cu")
		(net "FM_PMBUS_ALERT_BUF_EN_R_N")
	)
	(segment
		(start 397.222218 -107.538774)
		(end 397.546576 -107.214416)
		(width 0.0889)
		(layer "In2.Cu")
		(net "FM_PMBUS_ALERT_BUF_EN_R_N")
	)
	(segment
		(start 397.547846 -96.747076)
		(end 397.547846 -96.441768)
		(width 0.089408)
		(layer "In2.Cu")
		(net "FM_PMBUS_ALERT_BUF_EN_R_N")
	)
	(arc
		(start 395.957552 -103.961946)
		(mid 395.757241 -103.615236)
		(end 395.957552 -103.268526)
		(width 0.0889)
		(layer "In2.Cu")
		(net "FM_PMBUS_ALERT_BUF_EN_R_N")
	)
	(arc
		(start 397.2433 -109.603286)
		(mid 397.159019 -109.320069)
		(end 396.948152 -109.113066)
		(width 0.0889)
		(layer "In2.Cu")
		(net "FM_PMBUS_ALERT_BUF_EN_R_N")
	)
	(arc
		(start 397.5481 -98.477832)
		(mid 397.547131 -98.432543)
		(end 397.540988 -98.387662)
		(width 0.089408)
		(layer "In2.Cu")
		(net "FM_PMBUS_ALERT_BUF_EN_R_N")
	)
	(arc
		(start 396.2527 -104.452166)
		(mid 396.168419 -104.168949)
		(end 395.957552 -103.961946)
		(width 0.0889)
		(layer "In2.Cu")
		(net "FM_PMBUS_ALERT_BUF_EN_R_N")
	)
	(arc
		(start 397.347948 -97.093786)
		(mid 397.408403 -97.050972)
		(end 397.459962 -96.997774)
		(width 0.089408)
		(layer "In2.Cu")
		(net "FM_PMBUS_ALERT_BUF_EN_R_N")
	)
	(arc
		(start 398.089882 -101.274118)
		(mid 398.122041 -101.225989)
		(end 398.133316 -101.169216)
		(width 0.089408)
		(layer "In2.Cu")
		(net "FM_PMBUS_ALERT_BUF_EN_R_N")
	)
	(arc
		(start 397.547846 -100.168964)
		(mid 397.491327 -99.975861)
		(end 397.347948 -99.8347)
		(width 0.089408)
		(layer "In2.Cu")
		(net "FM_PMBUS_ALERT_BUF_EN_R_N")
	)
	(arc
		(start 397.843248 -100.69322)
		(mid 397.631964 -100.485691)
		(end 397.547846 -100.20173)
		(width 0.089408)
		(layer "In2.Cu")
		(net "FM_PMBUS_ALERT_BUF_EN_R_N")
	)
	(arc
		(start 396.452852 -104.820466)
		(mid 396.309048 -104.678783)
		(end 396.2527 -104.484932)
		(width 0.0889)
		(layer "In2.Cu")
		(net "FM_PMBUS_ALERT_BUF_EN_R_N")
	)
	(arc
		(start 395.957552 -103.268526)
		(mid 396.126969 -103.206757)
		(end 396.30731 -103.206042)
		(width 0.0889)
		(layer "In2.Cu")
		(net "FM_PMBUS_ALERT_BUF_EN_R_N")
	)
	(arc
		(start 398.133316 -101.06533)
		(mid 398.085734 -100.887973)
		(end 397.95577 -100.758244)
		(width 0.089408)
		(layer "In2.Cu")
		(net "FM_PMBUS_ALERT_BUF_EN_R_N")
	)
	(arc
		(start 396.948152 -109.113066)
		(mid 396.804348 -108.971383)
		(end 396.748 -108.777532)
		(width 0.0889)
		(layer "In2.Cu")
		(net "FM_PMBUS_ALERT_BUF_EN_R_N")
	)
	(arc
		(start 397.347948 -98.810826)
		(mid 397.4911 -98.670232)
		(end 397.5481 -98.477832)
		(width 0.089408)
		(layer "In2.Cu")
		(net "FM_PMBUS_ALERT_BUF_EN_R_N")
	)
	(arc
		(start 397.347948 -99.8347)
		(mid 397.052409 -99.322827)
		(end 397.347948 -98.810826)
		(width 0.089408)
		(layer "In2.Cu")
		(net "FM_PMBUS_ALERT_BUF_EN_R_N")
	)
	(arc
		(start 397.459962 -96.997774)
		(mid 397.525229 -96.879902)
		(end 397.547846 -96.747076)
		(width 0.089408)
		(layer "In2.Cu")
		(net "FM_PMBUS_ALERT_BUF_EN_R_N")
	)
	(arc
		(start 397.348202 -98.117406)
		(mid 397.052535 -97.605706)
		(end 397.347948 -97.093786)
		(width 0.089408)
		(layer "In2.Cu")
		(net "FM_PMBUS_ALERT_BUF_EN_R_N")
	)
	(arc
		(start 397.540988 -98.387662)
		(mid 397.473962 -98.231582)
		(end 397.348202 -98.117406)
		(width 0.089408)
		(layer "In2.Cu")
		(net "FM_PMBUS_ALERT_BUF_EN_R_N")
	)
	(segment
		(start 417.490148 -28.134564)
		(end 417.890198 -27.734514)
		(width 0.10795)
		(layer "F.Cu")
		(net "FM_PMBUS_ALERT_BUF_EN_R3_N")
	)
	(via
		(at 417.890198 -27.734514)
		(size 0.4572)
		(drill 0.2032)
		(layers "F.Cu" "B.Cu")
		(net "FM_PMBUS_ALERT_BUF_EN_R3_N")
	)
	(via
		(at 425.3992 -26.1874)
		(size 0.508)
		(drill 0.254)
		(layers "F.Cu" "B.Cu")
		(net "FM_PMBUS_ALERT_BUF_EN_R3_N")
	)
	(via
		(at 423.5704 -26.982928)
		(size 0.6604)
		(drill 0.3302)
		(layers "F.Cu" "B.Cu")
		(net "FM_PMBUS_ALERT_BUF_EN_R3_N")
	)
	(segment
		(start 423.5704 -26.708862)
		(end 423.746422 -26.53284)
		(width 0.089408)
		(layer "B.Cu")
		(net "FM_PMBUS_ALERT_BUF_EN_R3_N")
	)
	(segment
		(start 423.724832 -27.209496)
		(end 423.5704 -27.055064)
		(width 0.089408)
		(layer "B.Cu")
		(net "FM_PMBUS_ALERT_BUF_EN_R3_N")
	)
	(segment
		(start 423.5704 -27.055064)
		(end 423.5704 -26.982928)
		(width 0.089408)
		(layer "B.Cu")
		(net "FM_PMBUS_ALERT_BUF_EN_R3_N")
	)
	(segment
		(start 424.815 -27.0002)
		(end 424.605704 -27.209496)
		(width 0.089408)
		(layer "B.Cu")
		(net "FM_PMBUS_ALERT_BUF_EN_R3_N")
	)
	(segment
		(start 423.5704 -26.982928)
		(end 423.5704 -26.708862)
		(width 0.089408)
		(layer "B.Cu")
		(net "FM_PMBUS_ALERT_BUF_EN_R3_N")
	)
	(segment
		(start 425.04995 -26.53665)
		(end 425.3992 -26.1874)
		(width 0.089408)
		(layer "B.Cu")
		(net "FM_PMBUS_ALERT_BUF_EN_R3_N")
	)
	(segment
		(start 423.746422 -26.53284)
		(end 424.274742 -26.53284)
		(width 0.089408)
		(layer "B.Cu")
		(net "FM_PMBUS_ALERT_BUF_EN_R3_N")
	)
	(segment
		(start 424.274742 -26.53284)
		(end 424.278552 -26.53665)
		(width 0.089408)
		(layer "B.Cu")
		(net "FM_PMBUS_ALERT_BUF_EN_R3_N")
	)
	(segment
		(start 424.278552 -26.53665)
		(end 425.04995 -26.53665)
		(width 0.089408)
		(layer "B.Cu")
		(net "FM_PMBUS_ALERT_BUF_EN_R3_N")
	)
	(segment
		(start 424.605704 -27.209496)
		(end 423.724832 -27.209496)
		(width 0.089408)
		(layer "B.Cu")
		(net "FM_PMBUS_ALERT_BUF_EN_R3_N")
	)
	(segment
		(start 424.912028 -25.700228)
		(end 425.3992 -26.1874)
		(width 0.089408)
		(layer "In11.Cu")
		(net "FM_PMBUS_ALERT_BUF_EN_R3_N")
	)
	(segment
		(start 423.459656 -25.700228)
		(end 424.912028 -25.700228)
		(width 0.089408)
		(layer "In11.Cu")
		(net "FM_PMBUS_ALERT_BUF_EN_R3_N")
	)
	(segment
		(start 422.784016 -26.375868)
		(end 423.459656 -25.700228)
		(width 0.089408)
		(layer "In11.Cu")
		(net "FM_PMBUS_ALERT_BUF_EN_R3_N")
	)
	(segment
		(start 417.890198 -27.346402)
		(end 418.860732 -26.375868)
		(width 0.089408)
		(layer "In11.Cu")
		(net "FM_PMBUS_ALERT_BUF_EN_R3_N")
	)
	(segment
		(start 417.890198 -27.734514)
		(end 417.890198 -27.346402)
		(width 0.089408)
		(layer "In11.Cu")
		(net "FM_PMBUS_ALERT_BUF_EN_R3_N")
	)
	(segment
		(start 418.860732 -26.375868)
		(end 422.784016 -26.375868)
		(width 0.089408)
		(layer "In11.Cu")
		(net "FM_PMBUS_ALERT_BUF_EN_R3_N")
	)
	(segment
		(start 397.14805 -96.747076)
		(end 396.917926 -96.9772)
		(width 0.10795)
		(layer "F.Cu")
		(net "FM_PMBUS_ALERT_BUF_EN_R2_N")
	)
	(segment
		(start 396.917926 -96.9772)
		(end 396.65275 -96.9772)
		(width 0.10795)
		(layer "F.Cu")
		(net "FM_PMBUS_ALERT_BUF_EN_R2_N")
	)
	(via
		(at 392.730228 -90.283284)
		(size 0.508)
		(drill 0.254)
		(layers "F.Cu" "B.Cu")
		(net "FM_PMBUS_ALERT_BUF_EN_R2_N")
	)
	(via
		(at 397.14805 -96.747076)
		(size 0.508)
		(drill 0.254)
		(layers "F.Cu" "B.Cu")
		(net "FM_PMBUS_ALERT_BUF_EN_R2_N")
	)
	(segment
		(start 392.730228 -90.089228)
		(end 392.692128 -90.051128)
		(width 0.10795)
		(layer "B.Cu")
		(net "FM_PMBUS_ALERT_BUF_EN_R2_N")
	)
	(segment
		(start 392.730228 -90.283284)
		(end 392.730228 -90.089228)
		(width 0.10795)
		(layer "B.Cu")
		(net "FM_PMBUS_ALERT_BUF_EN_R2_N")
	)
	(segment
		(start 392.692128 -90.051128)
		(end 392.692128 -89.622884)
		(width 0.10795)
		(layer "B.Cu")
		(net "FM_PMBUS_ALERT_BUF_EN_R2_N")
	)
	(segment
		(start 396.459964 -91.174062)
		(end 396.459964 -92.332048)
		(width 0.089408)
		(layer "In2.Cu")
		(net "FM_PMBUS_ALERT_BUF_EN_R2_N")
	)
	(segment
		(start 396.460218 -94.362524)
		(end 397.013176 -94.915482)
		(width 0.089408)
		(layer "In2.Cu")
		(net "FM_PMBUS_ALERT_BUF_EN_R2_N")
	)
	(segment
		(start 396.136622 -90.85072)
		(end 396.459964 -91.174062)
		(width 0.089408)
		(layer "In2.Cu")
		(net "FM_PMBUS_ALERT_BUF_EN_R2_N")
	)
	(segment
		(start 397.013176 -94.915482)
		(end 397.013176 -95.684848)
		(width 0.089408)
		(layer "In2.Cu")
		(net "FM_PMBUS_ALERT_BUF_EN_R2_N")
	)
	(segment
		(start 397.14805 -96.412558)
		(end 397.14805 -96.747076)
		(width 0.089408)
		(layer "In2.Cu")
		(net "FM_PMBUS_ALERT_BUF_EN_R2_N")
	)
	(segment
		(start 397.013176 -95.684848)
		(end 397.05153 -95.723202)
		(width 0.089408)
		(layer "In2.Cu")
		(net "FM_PMBUS_ALERT_BUF_EN_R2_N")
	)
	(segment
		(start 392.730228 -90.283284)
		(end 394.184124 -90.283284)
		(width 0.089408)
		(layer "In2.Cu")
		(net "FM_PMBUS_ALERT_BUF_EN_R2_N")
	)
	(segment
		(start 396.460218 -92.332302)
		(end 396.460218 -94.362524)
		(width 0.089408)
		(layer "In2.Cu")
		(net "FM_PMBUS_ALERT_BUF_EN_R2_N")
	)
	(segment
		(start 396.459964 -92.332048)
		(end 396.460218 -92.332302)
		(width 0.089408)
		(layer "In2.Cu")
		(net "FM_PMBUS_ALERT_BUF_EN_R2_N")
	)
	(segment
		(start 397.05153 -95.723202)
		(end 397.05153 -96.316038)
		(width 0.089408)
		(layer "In2.Cu")
		(net "FM_PMBUS_ALERT_BUF_EN_R2_N")
	)
	(segment
		(start 394.184124 -90.283284)
		(end 394.75156 -90.85072)
		(width 0.089408)
		(layer "In2.Cu")
		(net "FM_PMBUS_ALERT_BUF_EN_R2_N")
	)
	(segment
		(start 397.05153 -96.316038)
		(end 397.14805 -96.412558)
		(width 0.089408)
		(layer "In2.Cu")
		(net "FM_PMBUS_ALERT_BUF_EN_R2_N")
	)
	(segment
		(start 394.75156 -90.85072)
		(end 396.136622 -90.85072)
		(width 0.089408)
		(layer "In2.Cu")
		(net "FM_PMBUS_ALERT_BUF_EN_R2_N")
	)
	(segment
		(start 419.08984 -39.334694)
		(end 418.690044 -39.73449)
		(width 0.089408)
		(layer "F.Cu")
		(net "BMC_TCK_MUX_SEL")
	)
	(segment
		(start 472.162378 -47.092362)
		(end 472.162378 -50.025554)
		(width 0.10795)
		(layer "F.Cu")
		(net "BMC_TCK_MUX_SEL")
	)
	(segment
		(start 476.67164 -54.29758)
		(end 476.67164 -54.655974)
		(width 0.10795)
		(layer "F.Cu")
		(net "BMC_TCK_MUX_SEL")
	)
	(segment
		(start 473.5068 -44.577)
		(end 472.4908 -44.577)
		(width 0.10795)
		(layer "F.Cu")
		(net "BMC_TCK_MUX_SEL")
	)
	(segment
		(start 476.889318 -54.873652)
		(end 476.889318 -55.368952)
		(width 0.10795)
		(layer "F.Cu")
		(net "BMC_TCK_MUX_SEL")
	)
	(segment
		(start 476.052896 -53.678836)
		(end 476.67164 -54.29758)
		(width 0.10795)
		(layer "F.Cu")
		(net "BMC_TCK_MUX_SEL")
	)
	(segment
		(start 419.090094 -39.334694)
		(end 419.08984 -39.334694)
		(width 0.089408)
		(layer "F.Cu")
		(net "BMC_TCK_MUX_SEL")
	)
	(segment
		(start 471.636598 -51.000406)
		(end 474.315028 -53.678836)
		(width 0.10795)
		(layer "F.Cu")
		(net "BMC_TCK_MUX_SEL")
	)
	(segment
		(start 476.67164 -54.655974)
		(end 476.889318 -54.873652)
		(width 0.10795)
		(layer "F.Cu")
		(net "BMC_TCK_MUX_SEL")
	)
	(segment
		(start 471.628724 -46.558708)
		(end 472.162378 -47.092362)
		(width 0.10795)
		(layer "F.Cu")
		(net "BMC_TCK_MUX_SEL")
	)
	(segment
		(start 473.7354 -44.3484)
		(end 473.5068 -44.577)
		(width 0.10795)
		(layer "F.Cu")
		(net "BMC_TCK_MUX_SEL")
	)
	(segment
		(start 472.162378 -50.025554)
		(end 471.636598 -50.551334)
		(width 0.10795)
		(layer "F.Cu")
		(net "BMC_TCK_MUX_SEL")
	)
	(segment
		(start 471.628724 -45.439076)
		(end 471.628724 -46.558708)
		(width 0.10795)
		(layer "F.Cu")
		(net "BMC_TCK_MUX_SEL")
	)
	(segment
		(start 474.315028 -53.678836)
		(end 476.052896 -53.678836)
		(width 0.10795)
		(layer "F.Cu")
		(net "BMC_TCK_MUX_SEL")
	)
	(segment
		(start 471.636598 -50.551334)
		(end 471.636598 -51.000406)
		(width 0.10795)
		(layer "F.Cu")
		(net "BMC_TCK_MUX_SEL")
	)
	(segment
		(start 472.4908 -44.577)
		(end 471.628724 -45.439076)
		(width 0.10795)
		(layer "F.Cu")
		(net "BMC_TCK_MUX_SEL")
	)
	(via
		(at 476.889318 -55.368952)
		(size 0.508)
		(drill 0.254)
		(layers "F.Cu" "B.Cu")
		(net "BMC_TCK_MUX_SEL")
	)
	(via
		(at 422.849548 -112.70869)
		(size 0.508)
		(drill 0.254)
		(layers "F.Cu" "B.Cu")
		(net "BMC_TCK_MUX_SEL")
	)
	(via
		(at 473.7354 -44.3484)
		(size 0.508)
		(drill 0.254)
		(layers "F.Cu" "B.Cu")
		(net "BMC_TCK_MUX_SEL")
	)
	(via
		(at 418.690044 -39.73449)
		(size 0.4572)
		(drill 0.2032)
		(layers "F.Cu" "B.Cu")
		(net "BMC_TCK_MUX_SEL")
	)
	(via
		(at 439.616596 -147.30984)
		(size 0.508)
		(drill 0.254)
		(layers "F.Cu" "B.Cu")
		(net "BMC_TCK_MUX_SEL")
	)
	(segment
		(start 439.626756 -146.282156)
		(end 439.626756 -147.29968)
		(width 0.10795)
		(layer "B.Cu")
		(net "BMC_TCK_MUX_SEL")
	)
	(segment
		(start 439.626756 -147.29968)
		(end 439.616596 -147.30984)
		(width 0.10795)
		(layer "B.Cu")
		(net "BMC_TCK_MUX_SEL")
	)
	(segment
		(start 439.6613 -147.955)
		(end 439.6613 -147.354544)
		(width 0.10795)
		(layer "B.Cu")
		(net "BMC_TCK_MUX_SEL")
	)
	(segment
		(start 439.6613 -147.354544)
		(end 439.616596 -147.30984)
		(width 0.10795)
		(layer "B.Cu")
		(net "BMC_TCK_MUX_SEL")
	)
	(segment
		(start 423.650918 -93.658182)
		(end 423.650918 -79.623666)
		(width 0.089408)
		(layer "In2.Cu")
		(net "BMC_TCK_MUX_SEL")
	)
	(segment
		(start 433.95519 -63.132462)
		(end 436.13578 -63.132462)
		(width 0.089408)
		(layer "In2.Cu")
		(net "BMC_TCK_MUX_SEL")
	)
	(segment
		(start 432.9938 -46.313598)
		(end 435.979062 -46.313598)
		(width 0.089408)
		(layer "In2.Cu")
		(net "BMC_TCK_MUX_SEL")
	)
	(segment
		(start 472.337384 -43.843448)
		(end 472.669616 -44.17568)
		(width 0.089408)
		(layer "In2.Cu")
		(net "BMC_TCK_MUX_SEL")
	)
	(segment
		(start 421.88384 -96.730058)
		(end 421.88384 -95.42526)
		(width 0.089408)
		(layer "In2.Cu")
		(net "BMC_TCK_MUX_SEL")
	)
	(segment
		(start 433.2224 -63.865252)
		(end 433.95519 -63.132462)
		(width 0.089408)
		(layer "In2.Cu")
		(net "BMC_TCK_MUX_SEL")
	)
	(segment
		(start 435.979062 -46.313598)
		(end 436.545228 -46.879764)
		(width 0.089408)
		(layer "In2.Cu")
		(net "BMC_TCK_MUX_SEL")
	)
	(segment
		(start 423.599864 -42.646092)
		(end 424.482514 -43.528742)
		(width 0.089408)
		(layer "In2.Cu")
		(net "BMC_TCK_MUX_SEL")
	)
	(segment
		(start 465.4804 -60.044838)
		(end 465.4804 -59.0804)
		(width 0.089408)
		(layer "In2.Cu")
		(net "BMC_TCK_MUX_SEL")
	)
	(segment
		(start 473.56268 -44.17568)
		(end 473.7354 -44.3484)
		(width 0.089408)
		(layer "In2.Cu")
		(net "BMC_TCK_MUX_SEL")
	)
	(segment
		(start 418.690044 -39.73449)
		(end 418.690044 -39.967662)
		(width 0.089408)
		(layer "In2.Cu")
		(net "BMC_TCK_MUX_SEL")
	)
	(segment
		(start 429.30826 -63.02756)
		(end 430.145952 -63.865252)
		(width 0.089408)
		(layer "In2.Cu")
		(net "BMC_TCK_MUX_SEL")
	)
	(segment
		(start 422.849548 -112.70869)
		(end 421.794432 -111.653574)
		(width 0.089408)
		(layer "In2.Cu")
		(net "BMC_TCK_MUX_SEL")
	)
	(segment
		(start 472.669616 -44.17568)
		(end 473.56268 -44.17568)
		(width 0.089408)
		(layer "In2.Cu")
		(net "BMC_TCK_MUX_SEL")
	)
	(segment
		(start 421.51554 -41.490138)
		(end 421.785542 -41.76014)
		(width 0.089408)
		(layer "In2.Cu")
		(net "BMC_TCK_MUX_SEL")
	)
	(segment
		(start 422.50233 -41.76014)
		(end 423.388282 -42.646092)
		(width 0.089408)
		(layer "In2.Cu")
		(net "BMC_TCK_MUX_SEL")
	)
	(segment
		(start 436.545228 -46.879764)
		(end 449.690236 -46.879764)
		(width 0.089408)
		(layer "In2.Cu")
		(net "BMC_TCK_MUX_SEL")
	)
	(segment
		(start 421.51554 -41.230042)
		(end 421.51554 -41.490138)
		(width 0.089408)
		(layer "In2.Cu")
		(net "BMC_TCK_MUX_SEL")
	)
	(segment
		(start 449.690236 -46.879764)
		(end 450.723 -45.847)
		(width 0.089408)
		(layer "In2.Cu")
		(net "BMC_TCK_MUX_SEL")
	)
	(segment
		(start 436.575454 -62.225936)
		(end 436.734712 -62.066678)
		(width 0.089408)
		(layer "In2.Cu")
		(net "BMC_TCK_MUX_SEL")
	)
	(segment
		(start 421.794432 -111.653574)
		(end 421.794432 -104.602026)
		(width 0.089408)
		(layer "In2.Cu")
		(net "BMC_TCK_MUX_SEL")
	)
	(segment
		(start 466.301074 -44.538392)
		(end 470.06256 -44.538392)
		(width 0.089408)
		(layer "In2.Cu")
		(net "BMC_TCK_MUX_SEL")
	)
	(segment
		(start 450.723 -45.847)
		(end 450.723 -44.45)
		(width 0.089408)
		(layer "In2.Cu")
		(net "BMC_TCK_MUX_SEL")
	)
	(segment
		(start 476.5929 -55.66537)
		(end 476.889318 -55.368952)
		(width 0.089408)
		(layer "In2.Cu")
		(net "BMC_TCK_MUX_SEL")
	)
	(segment
		(start 470.757504 -43.843448)
		(end 472.337384 -43.843448)
		(width 0.089408)
		(layer "In2.Cu")
		(net "BMC_TCK_MUX_SEL")
	)
	(segment
		(start 421.794432 -104.602026)
		(end 422.996868 -103.39959)
		(width 0.089408)
		(layer "In2.Cu")
		(net "BMC_TCK_MUX_SEL")
	)
	(segment
		(start 424.482514 -43.528742)
		(end 424.482514 -43.68673)
		(width 0.089408)
		(layer "In2.Cu")
		(net "BMC_TCK_MUX_SEL")
	)
	(segment
		(start 455.061828 -43.942)
		(end 455.442828 -44.323)
		(width 0.089408)
		(layer "In2.Cu")
		(net "BMC_TCK_MUX_SEL")
	)
	(segment
		(start 436.734712 -62.066678)
		(end 463.45856 -62.066678)
		(width 0.089408)
		(layer "In2.Cu")
		(net "BMC_TCK_MUX_SEL")
	)
	(segment
		(start 425.349162 -63.164466)
		(end 428.563786 -63.164466)
		(width 0.089408)
		(layer "In2.Cu")
		(net "BMC_TCK_MUX_SEL")
	)
	(segment
		(start 423.171366 -76.964032)
		(end 422.46042 -76.253086)
		(width 0.089408)
		(layer "In2.Cu")
		(net "BMC_TCK_MUX_SEL")
	)
	(segment
		(start 457.263246 -44.014136)
		(end 465.776818 -44.014136)
		(width 0.089408)
		(layer "In2.Cu")
		(net "BMC_TCK_MUX_SEL")
	)
	(segment
		(start 422.996868 -103.39959)
		(end 422.996868 -97.843086)
		(width 0.089408)
		(layer "In2.Cu")
		(net "BMC_TCK_MUX_SEL")
	)
	(segment
		(start 422.46042 -76.253086)
		(end 422.46042 -66.053208)
		(width 0.089408)
		(layer "In2.Cu")
		(net "BMC_TCK_MUX_SEL")
	)
	(segment
		(start 419.1 -40.377618)
		(end 419.1 -40.767)
		(width 0.089408)
		(layer "In2.Cu")
		(net "BMC_TCK_MUX_SEL")
	)
	(segment
		(start 470.06256 -44.538392)
		(end 470.757504 -43.843448)
		(width 0.089408)
		(layer "In2.Cu")
		(net "BMC_TCK_MUX_SEL")
	)
	(segment
		(start 419.26764 -40.93464)
		(end 421.220138 -40.93464)
		(width 0.089408)
		(layer "In2.Cu")
		(net "BMC_TCK_MUX_SEL")
	)
	(segment
		(start 430.145952 -63.865252)
		(end 433.2224 -63.865252)
		(width 0.089408)
		(layer "In2.Cu")
		(net "BMC_TCK_MUX_SEL")
	)
	(segment
		(start 451.231 -43.942)
		(end 455.061828 -43.942)
		(width 0.089408)
		(layer "In2.Cu")
		(net "BMC_TCK_MUX_SEL")
	)
	(segment
		(start 425.75988 -45.8851)
		(end 428.5488 -45.8851)
		(width 0.089408)
		(layer "In2.Cu")
		(net "BMC_TCK_MUX_SEL")
	)
	(segment
		(start 424.48226 -43.686984)
		(end 424.48226 -44.60748)
		(width 0.089408)
		(layer "In2.Cu")
		(net "BMC_TCK_MUX_SEL")
	)
	(segment
		(start 418.690044 -39.967662)
		(end 419.1 -40.377618)
		(width 0.089408)
		(layer "In2.Cu")
		(net "BMC_TCK_MUX_SEL")
	)
	(segment
		(start 423.650918 -79.623666)
		(end 423.171366 -79.144114)
		(width 0.089408)
		(layer "In2.Cu")
		(net "BMC_TCK_MUX_SEL")
	)
	(segment
		(start 428.563786 -63.164466)
		(end 428.700692 -63.02756)
		(width 0.089408)
		(layer "In2.Cu")
		(net "BMC_TCK_MUX_SEL")
	)
	(segment
		(start 428.700692 -63.02756)
		(end 429.30826 -63.02756)
		(width 0.089408)
		(layer "In2.Cu")
		(net "BMC_TCK_MUX_SEL")
	)
	(segment
		(start 469.51138 -58.5216)
		(end 472.36761 -55.66537)
		(width 0.089408)
		(layer "In2.Cu")
		(net "BMC_TCK_MUX_SEL")
	)
	(segment
		(start 436.13578 -63.132462)
		(end 436.575454 -62.692788)
		(width 0.089408)
		(layer "In2.Cu")
		(net "BMC_TCK_MUX_SEL")
	)
	(segment
		(start 421.785542 -41.76014)
		(end 422.50233 -41.76014)
		(width 0.089408)
		(layer "In2.Cu")
		(net "BMC_TCK_MUX_SEL")
	)
	(segment
		(start 455.442828 -44.323)
		(end 456.954382 -44.323)
		(width 0.089408)
		(layer "In2.Cu")
		(net "BMC_TCK_MUX_SEL")
	)
	(segment
		(start 463.45856 -62.066678)
		(end 465.4804 -60.044838)
		(width 0.089408)
		(layer "In2.Cu")
		(net "BMC_TCK_MUX_SEL")
	)
	(segment
		(start 422.996868 -97.843086)
		(end 421.88384 -96.730058)
		(width 0.089408)
		(layer "In2.Cu")
		(net "BMC_TCK_MUX_SEL")
	)
	(segment
		(start 428.5488 -45.8851)
		(end 428.79518 -45.63872)
		(width 0.089408)
		(layer "In2.Cu")
		(net "BMC_TCK_MUX_SEL")
	)
	(segment
		(start 423.171366 -79.144114)
		(end 423.171366 -76.964032)
		(width 0.089408)
		(layer "In2.Cu")
		(net "BMC_TCK_MUX_SEL")
	)
	(segment
		(start 472.36761 -55.66537)
		(end 476.5929 -55.66537)
		(width 0.089408)
		(layer "In2.Cu")
		(net "BMC_TCK_MUX_SEL")
	)
	(segment
		(start 436.575454 -62.692788)
		(end 436.575454 -62.225936)
		(width 0.089408)
		(layer "In2.Cu")
		(net "BMC_TCK_MUX_SEL")
	)
	(segment
		(start 428.79518 -45.63872)
		(end 432.318922 -45.63872)
		(width 0.089408)
		(layer "In2.Cu")
		(net "BMC_TCK_MUX_SEL")
	)
	(segment
		(start 419.1 -40.767)
		(end 419.26764 -40.93464)
		(width 0.089408)
		(layer "In2.Cu")
		(net "BMC_TCK_MUX_SEL")
	)
	(segment
		(start 421.220138 -40.93464)
		(end 421.51554 -41.230042)
		(width 0.089408)
		(layer "In2.Cu")
		(net "BMC_TCK_MUX_SEL")
	)
	(segment
		(start 465.4804 -59.0804)
		(end 466.0392 -58.5216)
		(width 0.089408)
		(layer "In2.Cu")
		(net "BMC_TCK_MUX_SEL")
	)
	(segment
		(start 424.48226 -44.60748)
		(end 425.75988 -45.8851)
		(width 0.089408)
		(layer "In2.Cu")
		(net "BMC_TCK_MUX_SEL")
	)
	(segment
		(start 421.88384 -95.42526)
		(end 423.650918 -93.658182)
		(width 0.089408)
		(layer "In2.Cu")
		(net "BMC_TCK_MUX_SEL")
	)
	(segment
		(start 456.954382 -44.323)
		(end 457.263246 -44.014136)
		(width 0.089408)
		(layer "In2.Cu")
		(net "BMC_TCK_MUX_SEL")
	)
	(segment
		(start 466.0392 -58.5216)
		(end 469.51138 -58.5216)
		(width 0.089408)
		(layer "In2.Cu")
		(net "BMC_TCK_MUX_SEL")
	)
	(segment
		(start 423.388282 -42.646092)
		(end 423.599864 -42.646092)
		(width 0.089408)
		(layer "In2.Cu")
		(net "BMC_TCK_MUX_SEL")
	)
	(segment
		(start 450.723 -44.45)
		(end 451.231 -43.942)
		(width 0.089408)
		(layer "In2.Cu")
		(net "BMC_TCK_MUX_SEL")
	)
	(segment
		(start 465.776818 -44.014136)
		(end 466.301074 -44.538392)
		(width 0.089408)
		(layer "In2.Cu")
		(net "BMC_TCK_MUX_SEL")
	)
	(segment
		(start 424.482514 -43.68673)
		(end 424.48226 -43.686984)
		(width 0.089408)
		(layer "In2.Cu")
		(net "BMC_TCK_MUX_SEL")
	)
	(segment
		(start 422.46042 -66.053208)
		(end 425.349162 -63.164466)
		(width 0.089408)
		(layer "In2.Cu")
		(net "BMC_TCK_MUX_SEL")
	)
	(segment
		(start 432.318922 -45.63872)
		(end 432.9938 -46.313598)
		(width 0.089408)
		(layer "In2.Cu")
		(net "BMC_TCK_MUX_SEL")
	)
	(segment
		(start 417.861496 -123.227592)
		(end 417.861496 -121.581926)
		(width 0.089408)
		(layer "In9.Cu")
		(net "BMC_TCK_MUX_SEL")
	)
	(segment
		(start 439.616596 -147.30984)
		(end 439.0136 -146.706844)
		(width 0.089408)
		(layer "In9.Cu")
		(net "BMC_TCK_MUX_SEL")
	)
	(segment
		(start 438.714896 -135.798052)
		(end 437.073548 -134.156704)
		(width 0.089408)
		(layer "In9.Cu")
		(net "BMC_TCK_MUX_SEL")
	)
	(segment
		(start 418.533072 -123.899168)
		(end 417.861496 -123.227592)
		(width 0.089408)
		(layer "In9.Cu")
		(net "BMC_TCK_MUX_SEL")
	)
	(segment
		(start 422.696894 -112.861344)
		(end 422.849548 -112.70869)
		(width 0.089408)
		(layer "In9.Cu")
		(net "BMC_TCK_MUX_SEL")
	)
	(segment
		(start 430.01692 -134.156704)
		(end 427.424342 -131.564126)
		(width 0.089408)
		(layer "In9.Cu")
		(net "BMC_TCK_MUX_SEL")
	)
	(segment
		(start 424.511978 -131.564126)
		(end 419.015418 -126.067566)
		(width 0.089408)
		(layer "In9.Cu")
		(net "BMC_TCK_MUX_SEL")
	)
	(segment
		(start 437.073548 -134.156704)
		(end 430.01692 -134.156704)
		(width 0.089408)
		(layer "In9.Cu")
		(net "BMC_TCK_MUX_SEL")
	)
	(segment
		(start 439.0136 -146.706844)
		(end 439.0136 -142.32636)
		(width 0.089408)
		(layer "In9.Cu")
		(net "BMC_TCK_MUX_SEL")
	)
	(segment
		(start 422.696894 -116.746528)
		(end 422.696894 -112.861344)
		(width 0.089408)
		(layer "In9.Cu")
		(net "BMC_TCK_MUX_SEL")
	)
	(segment
		(start 419.015418 -126.067566)
		(end 419.015418 -125.163326)
		(width 0.089408)
		(layer "In9.Cu")
		(net "BMC_TCK_MUX_SEL")
	)
	(segment
		(start 427.424342 -131.564126)
		(end 424.511978 -131.564126)
		(width 0.089408)
		(layer "In9.Cu")
		(net "BMC_TCK_MUX_SEL")
	)
	(segment
		(start 439.0136 -142.32636)
		(end 438.714896 -142.027656)
		(width 0.089408)
		(layer "In9.Cu")
		(net "BMC_TCK_MUX_SEL")
	)
	(segment
		(start 417.861496 -121.581926)
		(end 422.696894 -116.746528)
		(width 0.089408)
		(layer "In9.Cu")
		(net "BMC_TCK_MUX_SEL")
	)
	(segment
		(start 418.533072 -124.68098)
		(end 418.533072 -123.899168)
		(width 0.089408)
		(layer "In9.Cu")
		(net "BMC_TCK_MUX_SEL")
	)
	(segment
		(start 419.015418 -125.163326)
		(end 418.533072 -124.68098)
		(width 0.089408)
		(layer "In9.Cu")
		(net "BMC_TCK_MUX_SEL")
	)
	(segment
		(start 438.714896 -142.027656)
		(end 438.714896 -135.798052)
		(width 0.089408)
		(layer "In9.Cu")
		(net "BMC_TCK_MUX_SEL")
	)
	(segment
		(start 424.133264 -113.399062)
		(end 423.379138 -113.399062)
		(width 0.10795)
		(layer "F.Cu")
		(net "BMC_PWR_DEBUG_N")
	)
	(segment
		(start 423.379138 -113.399062)
		(end 423.2148 -113.5634)
		(width 0.10795)
		(layer "F.Cu")
		(net "BMC_PWR_DEBUG_N")
	)
	(segment
		(start 421.49014 -30.53461)
		(end 421.89019 -30.13456)
		(width 0.10795)
		(layer "F.Cu")
		(net "BMC_PWR_DEBUG_N")
	)
	(via
		(at 423.2148 -113.5634)
		(size 0.762)
		(drill 0.381)
		(layers "F.Cu" "B.Cu")
		(net "BMC_PWR_DEBUG_N")
	)
	(via
		(at 445.516 -140.589)
		(size 0.508)
		(drill 0.254)
		(layers "F.Cu" "B.Cu")
		(net "BMC_PWR_DEBUG_N")
	)
	(via
		(at 470.083642 -55.6895)
		(size 0.508)
		(drill 0.254)
		(layers "F.Cu" "B.Cu")
		(net "BMC_PWR_DEBUG_N")
	)
	(via
		(at 421.89019 -30.13456)
		(size 0.4572)
		(drill 0.2032)
		(layers "F.Cu" "B.Cu")
		(net "BMC_PWR_DEBUG_N")
	)
	(via
		(at 469.4174 -34.2265)
		(size 0.508)
		(drill 0.254)
		(layers "F.Cu" "B.Cu")
		(net "BMC_PWR_DEBUG_N")
	)
	(via
		(at 441.441332 -142.367)
		(size 0.508)
		(drill 0.254)
		(layers "F.Cu" "B.Cu")
		(net "BMC_PWR_DEBUG_N")
	)
	(via
		(at 424.133264 -113.399062)
		(size 0.508)
		(drill 0.254)
		(layers "F.Cu" "B.Cu")
		(net "BMC_PWR_DEBUG_N")
	)
	(segment
		(start 445.629792 -141.665452)
		(end 445.629792 -140.702792)
		(width 0.10795)
		(layer "B.Cu")
		(net "BMC_PWR_DEBUG_N")
	)
	(segment
		(start 445.629792 -140.702792)
		(end 445.516 -140.589)
		(width 0.10795)
		(layer "B.Cu")
		(net "BMC_PWR_DEBUG_N")
	)
	(segment
		(start 436.384192 -62.530736)
		(end 436.384446 -62.53099)
		(width 0.089408)
		(layer "In2.Cu")
		(net "BMC_PWR_DEBUG_N")
	)
	(segment
		(start 421.603424 -104.48544)
		(end 421.603424 -112.028732)
		(width 0.089408)
		(layer "In2.Cu")
		(net "BMC_PWR_DEBUG_N")
	)
	(segment
		(start 433.143152 -63.674244)
		(end 430.227486 -63.674244)
		(width 0.089408)
		(layer "In2.Cu")
		(net "BMC_PWR_DEBUG_N")
	)
	(segment
		(start 436.384446 -62.53607)
		(end 435.979062 -62.941454)
		(width 0.089408)
		(layer "In2.Cu")
		(net "BMC_PWR_DEBUG_N")
	)
	(segment
		(start 436.384192 -62.372748)
		(end 436.384192 -62.530736)
		(width 0.089408)
		(layer "In2.Cu")
		(net "BMC_PWR_DEBUG_N")
	)
	(segment
		(start 469.692228 -56.080914)
		(end 469.692228 -57.415684)
		(width 0.089408)
		(layer "In2.Cu")
		(net "BMC_PWR_DEBUG_N")
	)
	(segment
		(start 443.85992 -142.24508)
		(end 441.563252 -142.24508)
		(width 0.089408)
		(layer "In2.Cu")
		(net "BMC_PWR_DEBUG_N")
	)
	(segment
		(start 428.42053 -62.645544)
		(end 428.092616 -62.973458)
		(width 0.089408)
		(layer "In2.Cu")
		(net "BMC_PWR_DEBUG_N")
	)
	(segment
		(start 423.45991 -80.005682)
		(end 423.45991 -93.578934)
		(width 0.089408)
		(layer "In2.Cu")
		(net "BMC_PWR_DEBUG_N")
	)
	(segment
		(start 436.384446 -62.146688)
		(end 436.384446 -62.372494)
		(width 0.089408)
		(layer "In2.Cu")
		(net "BMC_PWR_DEBUG_N")
	)
	(segment
		(start 422.80586 -103.283004)
		(end 421.603424 -104.48544)
		(width 0.089408)
		(layer "In2.Cu")
		(net "BMC_PWR_DEBUG_N")
	)
	(segment
		(start 421.603424 -112.028732)
		(end 422.973754 -113.399062)
		(width 0.089408)
		(layer "In2.Cu")
		(net "BMC_PWR_DEBUG_N")
	)
	(segment
		(start 433.875942 -62.941454)
		(end 433.143152 -63.674244)
		(width 0.089408)
		(layer "In2.Cu")
		(net "BMC_PWR_DEBUG_N")
	)
	(segment
		(start 430.227486 -63.674244)
		(end 429.198786 -62.645544)
		(width 0.089408)
		(layer "In2.Cu")
		(net "BMC_PWR_DEBUG_N")
	)
	(segment
		(start 441.563252 -142.24508)
		(end 441.441332 -142.367)
		(width 0.089408)
		(layer "In2.Cu")
		(net "BMC_PWR_DEBUG_N")
	)
	(segment
		(start 422.80586 -97.922334)
		(end 422.80586 -103.283004)
		(width 0.089408)
		(layer "In2.Cu")
		(net "BMC_PWR_DEBUG_N")
	)
	(segment
		(start 468.840312 -58.2676)
		(end 466.022944 -58.2676)
		(width 0.089408)
		(layer "In2.Cu")
		(net "BMC_PWR_DEBUG_N")
	)
	(segment
		(start 435.979062 -62.941454)
		(end 433.875942 -62.941454)
		(width 0.089408)
		(layer "In2.Cu")
		(net "BMC_PWR_DEBUG_N")
	)
	(segment
		(start 466.022944 -58.2676)
		(end 465.289392 -59.001152)
		(width 0.089408)
		(layer "In2.Cu")
		(net "BMC_PWR_DEBUG_N")
	)
	(segment
		(start 421.692832 -95.346012)
		(end 421.692832 -96.809306)
		(width 0.089408)
		(layer "In2.Cu")
		(net "BMC_PWR_DEBUG_N")
	)
	(segment
		(start 422.269412 -78.815184)
		(end 423.45991 -80.005682)
		(width 0.089408)
		(layer "In2.Cu")
		(net "BMC_PWR_DEBUG_N")
	)
	(segment
		(start 470.083642 -55.6895)
		(end 469.692228 -56.080914)
		(width 0.089408)
		(layer "In2.Cu")
		(net "BMC_PWR_DEBUG_N")
	)
	(segment
		(start 436.384446 -62.53099)
		(end 436.384446 -62.53607)
		(width 0.089408)
		(layer "In2.Cu")
		(net "BMC_PWR_DEBUG_N")
	)
	(segment
		(start 428.092616 -62.973458)
		(end 425.234354 -62.973458)
		(width 0.089408)
		(layer "In2.Cu")
		(net "BMC_PWR_DEBUG_N")
	)
	(segment
		(start 425.234354 -62.973458)
		(end 422.269412 -65.9384)
		(width 0.089408)
		(layer "In2.Cu")
		(net "BMC_PWR_DEBUG_N")
	)
	(segment
		(start 421.692832 -96.809306)
		(end 422.80586 -97.922334)
		(width 0.089408)
		(layer "In2.Cu")
		(net "BMC_PWR_DEBUG_N")
	)
	(segment
		(start 463.53603 -61.718952)
		(end 436.812182 -61.718952)
		(width 0.089408)
		(layer "In2.Cu")
		(net "BMC_PWR_DEBUG_N")
	)
	(segment
		(start 445.516 -140.589)
		(end 443.85992 -142.24508)
		(width 0.089408)
		(layer "In2.Cu")
		(net "BMC_PWR_DEBUG_N")
	)
	(segment
		(start 465.289392 -59.001152)
		(end 465.289392 -59.96559)
		(width 0.089408)
		(layer "In2.Cu")
		(net "BMC_PWR_DEBUG_N")
	)
	(segment
		(start 436.812182 -61.718952)
		(end 436.384446 -62.146688)
		(width 0.089408)
		(layer "In2.Cu")
		(net "BMC_PWR_DEBUG_N")
	)
	(segment
		(start 429.198786 -62.645544)
		(end 428.42053 -62.645544)
		(width 0.089408)
		(layer "In2.Cu")
		(net "BMC_PWR_DEBUG_N")
	)
	(segment
		(start 422.973754 -113.399062)
		(end 424.133264 -113.399062)
		(width 0.089408)
		(layer "In2.Cu")
		(net "BMC_PWR_DEBUG_N")
	)
	(segment
		(start 469.692228 -57.415684)
		(end 468.840312 -58.2676)
		(width 0.089408)
		(layer "In2.Cu")
		(net "BMC_PWR_DEBUG_N")
	)
	(segment
		(start 423.45991 -93.578934)
		(end 421.692832 -95.346012)
		(width 0.089408)
		(layer "In2.Cu")
		(net "BMC_PWR_DEBUG_N")
	)
	(segment
		(start 422.269412 -65.9384)
		(end 422.269412 -78.815184)
		(width 0.089408)
		(layer "In2.Cu")
		(net "BMC_PWR_DEBUG_N")
	)
	(segment
		(start 436.384446 -62.372494)
		(end 436.384192 -62.372748)
		(width 0.089408)
		(layer "In2.Cu")
		(net "BMC_PWR_DEBUG_N")
	)
	(segment
		(start 465.289392 -59.96559)
		(end 463.53603 -61.718952)
		(width 0.089408)
		(layer "In2.Cu")
		(net "BMC_PWR_DEBUG_N")
	)
	(segment
		(start 437.712358 -132.783072)
		(end 430.586642 -132.783072)
		(width 0.089408)
		(layer "In9.Cu")
		(net "BMC_PWR_DEBUG_N")
	)
	(segment
		(start 469.854788 -44.905168)
		(end 469.854788 -47.915068)
		(width 0.089408)
		(layer "In9.Cu")
		(net "BMC_PWR_DEBUG_N")
	)
	(segment
		(start 423.73296 -116.93906)
		(end 423.73296 -113.799366)
		(width 0.089408)
		(layer "In9.Cu")
		(net "BMC_PWR_DEBUG_N")
	)
	(segment
		(start 469.670384 -48.099472)
		(end 469.670384 -52.930806)
		(width 0.089408)
		(layer "In9.Cu")
		(net "BMC_PWR_DEBUG_N")
	)
	(segment
		(start 441.860432 -142.367)
		(end 443.122304 -141.105128)
		(width 0.089408)
		(layer "In9.Cu")
		(net "BMC_PWR_DEBUG_N")
	)
	(segment
		(start 468.20074 -36.44392)
		(end 468.20074 -37.262562)
		(width 0.089408)
		(layer "In9.Cu")
		(net "BMC_PWR_DEBUG_N")
	)
	(segment
		(start 470.522808 -54.350158)
		(end 470.393268 -54.479698)
		(width 0.089408)
		(layer "In9.Cu")
		(net "BMC_PWR_DEBUG_N")
	)
	(segment
		(start 422.521634 -127.432562)
		(end 422.521634 -118.150386)
		(width 0.089408)
		(layer "In9.Cu")
		(net "BMC_PWR_DEBUG_N")
	)
	(segment
		(start 470.393268 -55.394606)
		(end 470.098374 -55.6895)
		(width 0.089408)
		(layer "In9.Cu")
		(net "BMC_PWR_DEBUG_N")
	)
	(segment
		(start 469.4174 -35.22726)
		(end 468.20074 -36.44392)
		(width 0.089408)
		(layer "In9.Cu")
		(net "BMC_PWR_DEBUG_N")
	)
	(segment
		(start 470.522808 -53.78323)
		(end 470.522808 -54.350158)
		(width 0.089408)
		(layer "In9.Cu")
		(net "BMC_PWR_DEBUG_N")
	)
	(segment
		(start 422.521634 -118.150386)
		(end 423.73296 -116.93906)
		(width 0.089408)
		(layer "In9.Cu")
		(net "BMC_PWR_DEBUG_N")
	)
	(segment
		(start 440.574684 -135.645398)
		(end 437.712358 -132.783072)
		(width 0.089408)
		(layer "In9.Cu")
		(net "BMC_PWR_DEBUG_N")
	)
	(segment
		(start 423.73296 -113.799366)
		(end 424.133264 -113.399062)
		(width 0.089408)
		(layer "In9.Cu")
		(net "BMC_PWR_DEBUG_N")
	)
	(segment
		(start 468.425022 -43.475402)
		(end 469.854788 -44.905168)
		(width 0.089408)
		(layer "In9.Cu")
		(net "BMC_PWR_DEBUG_N")
	)
	(segment
		(start 443.122304 -141.105128)
		(end 443.122304 -139.953238)
		(width 0.089408)
		(layer "In9.Cu")
		(net "BMC_PWR_DEBUG_N")
	)
	(segment
		(start 443.122304 -139.953238)
		(end 440.574684 -137.405618)
		(width 0.089408)
		(layer "In9.Cu")
		(net "BMC_PWR_DEBUG_N")
	)
	(segment
		(start 441.441332 -142.367)
		(end 441.860432 -142.367)
		(width 0.089408)
		(layer "In9.Cu")
		(net "BMC_PWR_DEBUG_N")
	)
	(segment
		(start 440.574684 -137.405618)
		(end 440.574684 -135.645398)
		(width 0.089408)
		(layer "In9.Cu")
		(net "BMC_PWR_DEBUG_N")
	)
	(segment
		(start 468.425022 -38.236144)
		(end 468.425022 -43.475402)
		(width 0.089408)
		(layer "In9.Cu")
		(net "BMC_PWR_DEBUG_N")
	)
	(segment
		(start 468.285068 -37.34689)
		(end 468.285068 -38.09619)
		(width 0.089408)
		(layer "In9.Cu")
		(net "BMC_PWR_DEBUG_N")
	)
	(segment
		(start 425.279566 -130.190494)
		(end 422.521634 -127.432562)
		(width 0.089408)
		(layer "In9.Cu")
		(net "BMC_PWR_DEBUG_N")
	)
	(segment
		(start 470.098374 -55.6895)
		(end 470.083642 -55.6895)
		(width 0.089408)
		(layer "In9.Cu")
		(net "BMC_PWR_DEBUG_N")
	)
	(segment
		(start 469.854788 -47.915068)
		(end 469.670384 -48.099472)
		(width 0.089408)
		(layer "In9.Cu")
		(net "BMC_PWR_DEBUG_N")
	)
	(segment
		(start 468.285068 -38.09619)
		(end 468.425022 -38.236144)
		(width 0.089408)
		(layer "In9.Cu")
		(net "BMC_PWR_DEBUG_N")
	)
	(segment
		(start 469.4174 -34.2265)
		(end 469.4174 -35.22726)
		(width 0.089408)
		(layer "In9.Cu")
		(net "BMC_PWR_DEBUG_N")
	)
	(segment
		(start 468.20074 -37.262562)
		(end 468.285068 -37.34689)
		(width 0.089408)
		(layer "In9.Cu")
		(net "BMC_PWR_DEBUG_N")
	)
	(segment
		(start 470.393268 -54.479698)
		(end 470.393268 -55.394606)
		(width 0.089408)
		(layer "In9.Cu")
		(net "BMC_PWR_DEBUG_N")
	)
	(segment
		(start 430.586642 -132.783072)
		(end 427.994064 -130.190494)
		(width 0.089408)
		(layer "In9.Cu")
		(net "BMC_PWR_DEBUG_N")
	)
	(segment
		(start 427.994064 -130.190494)
		(end 425.279566 -130.190494)
		(width 0.089408)
		(layer "In9.Cu")
		(net "BMC_PWR_DEBUG_N")
	)
	(segment
		(start 469.670384 -52.930806)
		(end 470.522808 -53.78323)
		(width 0.089408)
		(layer "In9.Cu")
		(net "BMC_PWR_DEBUG_N")
	)
	(segment
		(start 466.444584 -34.50082)
		(end 463.291682 -34.50082)
		(width 0.089408)
		(layer "In11.Cu")
		(net "BMC_PWR_DEBUG_N")
	)
	(segment
		(start 433.749196 -37.428424)
		(end 433.749196 -35.795204)
		(width 0.089408)
		(layer "In11.Cu")
		(net "BMC_PWR_DEBUG_N")
	)
	(segment
		(start 422.26484 -31.06801)
		(end 422.26484 -30.749494)
		(width 0.089408)
		(layer "In11.Cu")
		(net "BMC_PWR_DEBUG_N")
	)
	(segment
		(start 469.4174 -34.668206)
		(end 469.11895 -34.966656)
		(width 0.089408)
		(layer "In11.Cu")
		(net "BMC_PWR_DEBUG_N")
	)
	(segment
		(start 469.4174 -34.2265)
		(end 469.4174 -34.668206)
		(width 0.089408)
		(layer "In11.Cu")
		(net "BMC_PWR_DEBUG_N")
	)
	(segment
		(start 422.558718 -31.361888)
		(end 422.26484 -31.06801)
		(width 0.089408)
		(layer "In11.Cu")
		(net "BMC_PWR_DEBUG_N")
	)
	(segment
		(start 462.709514 -35.082988)
		(end 449.102988 -35.082988)
		(width 0.089408)
		(layer "In11.Cu")
		(net "BMC_PWR_DEBUG_N")
	)
	(segment
		(start 446.594484 -37.591492)
		(end 445.949832 -37.591492)
		(width 0.089408)
		(layer "In11.Cu")
		(net "BMC_PWR_DEBUG_N")
	)
	(segment
		(start 442.789056 -38.336982)
		(end 442.377322 -38.748716)
		(width 0.089408)
		(layer "In11.Cu")
		(net "BMC_PWR_DEBUG_N")
	)
	(segment
		(start 445.204342 -38.336982)
		(end 442.789056 -38.336982)
		(width 0.089408)
		(layer "In11.Cu")
		(net "BMC_PWR_DEBUG_N")
	)
	(segment
		(start 463.291682 -34.50082)
		(end 462.709514 -35.082988)
		(width 0.089408)
		(layer "In11.Cu")
		(net "BMC_PWR_DEBUG_N")
	)
	(segment
		(start 429.944022 -32.691324)
		(end 429.220376 -31.967678)
		(width 0.089408)
		(layer "In11.Cu")
		(net "BMC_PWR_DEBUG_N")
	)
	(segment
		(start 445.949832 -37.591492)
		(end 445.204342 -38.336982)
		(width 0.089408)
		(layer "In11.Cu")
		(net "BMC_PWR_DEBUG_N")
	)
	(segment
		(start 430.645316 -32.691324)
		(end 429.944022 -32.691324)
		(width 0.089408)
		(layer "In11.Cu")
		(net "BMC_PWR_DEBUG_N")
	)
	(segment
		(start 424.306238 -31.361888)
		(end 422.558718 -31.361888)
		(width 0.089408)
		(layer "In11.Cu")
		(net "BMC_PWR_DEBUG_N")
	)
	(segment
		(start 433.749196 -35.795204)
		(end 430.645316 -32.691324)
		(width 0.089408)
		(layer "In11.Cu")
		(net "BMC_PWR_DEBUG_N")
	)
	(segment
		(start 429.220376 -31.967678)
		(end 424.912028 -31.967678)
		(width 0.089408)
		(layer "In11.Cu")
		(net "BMC_PWR_DEBUG_N")
	)
	(segment
		(start 466.91042 -34.966656)
		(end 466.444584 -34.50082)
		(width 0.089408)
		(layer "In11.Cu")
		(net "BMC_PWR_DEBUG_N")
	)
	(segment
		(start 424.912028 -31.967678)
		(end 424.306238 -31.361888)
		(width 0.089408)
		(layer "In11.Cu")
		(net "BMC_PWR_DEBUG_N")
	)
	(segment
		(start 435.069488 -38.748716)
		(end 433.749196 -37.428424)
		(width 0.089408)
		(layer "In11.Cu")
		(net "BMC_PWR_DEBUG_N")
	)
	(segment
		(start 469.11895 -34.966656)
		(end 466.91042 -34.966656)
		(width 0.089408)
		(layer "In11.Cu")
		(net "BMC_PWR_DEBUG_N")
	)
	(segment
		(start 449.102988 -35.082988)
		(end 446.594484 -37.591492)
		(width 0.089408)
		(layer "In11.Cu")
		(net "BMC_PWR_DEBUG_N")
	)
	(segment
		(start 442.377322 -38.748716)
		(end 435.069488 -38.748716)
		(width 0.089408)
		(layer "In11.Cu")
		(net "BMC_PWR_DEBUG_N")
	)
	(segment
		(start 422.26484 -30.749494)
		(end 421.89019 -30.374844)
		(width 0.089408)
		(layer "In11.Cu")
		(net "BMC_PWR_DEBUG_N")
	)
	(segment
		(start 421.89019 -30.374844)
		(end 421.89019 -30.13456)
		(width 0.089408)
		(layer "In11.Cu")
		(net "BMC_PWR_DEBUG_N")
	)
	(segment
		(start 441.562236 -149.956266)
		(end 441.562236 -149.602444)
		(width 0.10795)
		(layer "F.Cu")
		(net "BMC_PREQ_N")
	)
	(segment
		(start 441.00623 -150.06447)
		(end 441.454032 -150.06447)
		(width 0.10795)
		(layer "F.Cu")
		(net "BMC_PREQ_N")
	)
	(segment
		(start 422.29024 -29.734764)
		(end 422.69029 -29.334714)
		(width 0.10795)
		(layer "F.Cu")
		(net "BMC_PREQ_N")
	)
	(segment
		(start 441.454032 -150.06447)
		(end 441.562236 -149.956266)
		(width 0.10795)
		(layer "F.Cu")
		(net "BMC_PREQ_N")
	)
	(via
		(at 471.160348 -33.937702)
		(size 0.508)
		(drill 0.254)
		(layers "F.Cu" "B.Cu")
		(net "BMC_PREQ_N")
	)
	(via
		(at 480.637596 -59.71032)
		(size 0.508)
		(drill 0.254)
		(layers "F.Cu" "B.Cu")
		(net "BMC_PREQ_N")
	)
	(via
		(at 441.562236 -149.602444)
		(size 0.508)
		(drill 0.254)
		(layers "F.Cu" "B.Cu")
		(net "BMC_PREQ_N")
	)
	(via
		(at 490.152944 -32.597598)
		(size 0.508)
		(drill 0.254)
		(layers "F.Cu" "B.Cu")
		(net "BMC_PREQ_N")
	)
	(via
		(at 422.69029 -29.334714)
		(size 0.4572)
		(drill 0.2032)
		(layers "F.Cu" "B.Cu")
		(net "BMC_PREQ_N")
	)
	(via
		(at 424.133264 -112.764062)
		(size 0.508)
		(drill 0.254)
		(layers "F.Cu" "B.Cu")
		(net "BMC_PREQ_N")
	)
	(segment
		(start 471.160348 -33.937702)
		(end 471.18016 -33.937702)
		(width 0.089408)
		(layer "In2.Cu")
		(net "BMC_PREQ_N")
	)
	(segment
		(start 467.40953 -63.945008)
		(end 468.75573 -63.945008)
		(width 0.089408)
		(layer "In2.Cu")
		(net "BMC_PREQ_N")
	)
	(segment
		(start 424.782488 -76.395834)
		(end 424.091354 -75.7047)
		(width 0.089408)
		(layer "In2.Cu")
		(net "BMC_PREQ_N")
	)
	(segment
		(start 472.191588 -33.110678)
		(end 472.191588 -31.51378)
		(width 0.089408)
		(layer "In2.Cu")
		(net "BMC_PREQ_N")
	)
	(segment
		(start 424.299126 -112.346994)
		(end 424.33621 -112.346994)
		(width 0.089408)
		(layer "In2.Cu")
		(net "BMC_PREQ_N")
	)
	(segment
		(start 424.628056 -112.018064)
		(end 424.628056 -111.28502)
		(width 0.089408)
		(layer "In2.Cu")
		(net "BMC_PREQ_N")
	)
	(segment
		(start 425.40301 -78.929738)
		(end 424.782488 -78.309216)
		(width 0.089408)
		(layer "In2.Cu")
		(net "BMC_PREQ_N")
	)
	(segment
		(start 482.80828 -31.994856)
		(end 482.80828 -31.113476)
		(width 0.089408)
		(layer "In2.Cu")
		(net "BMC_PREQ_N")
	)
	(segment
		(start 471.422984 -33.879282)
		(end 472.191588 -33.110678)
		(width 0.089408)
		(layer "In2.Cu")
		(net "BMC_PREQ_N")
	)
	(segment
		(start 481.86594 -32.937196)
		(end 482.80828 -31.994856)
		(width 0.089408)
		(layer "In2.Cu")
		(net "BMC_PREQ_N")
	)
	(segment
		(start 424.782488 -78.309216)
		(end 424.782488 -76.395834)
		(width 0.089408)
		(layer "In2.Cu")
		(net "BMC_PREQ_N")
	)
	(segment
		(start 471.18016 -33.937702)
		(end 471.18016 -33.94964)
		(width 0.089408)
		(layer "In2.Cu")
		(net "BMC_PREQ_N")
	)
	(segment
		(start 427.729904 -65.38341)
		(end 427.730158 -65.383664)
		(width 0.089408)
		(layer "In2.Cu")
		(net "BMC_PREQ_N")
	)
	(segment
		(start 424.628056 -111.28502)
		(end 425.40301 -110.510066)
		(width 0.089408)
		(layer "In2.Cu")
		(net "BMC_PREQ_N")
	)
	(segment
		(start 472.191588 -31.51378)
		(end 472.482672 -31.222696)
		(width 0.089408)
		(layer "In2.Cu")
		(net "BMC_PREQ_N")
	)
	(segment
		(start 425.40301 -80.302608)
		(end 425.403264 -80.302354)
		(width 0.089408)
		(layer "In2.Cu")
		(net "BMC_PREQ_N")
	)
	(segment
		(start 475.285816 -63.665608)
		(end 478.991676 -59.959748)
		(width 0.089408)
		(layer "In2.Cu")
		(net "BMC_PREQ_N")
	)
	(segment
		(start 425.403264 -79.542386)
		(end 425.40301 -79.542132)
		(width 0.089408)
		(layer "In2.Cu")
		(net "BMC_PREQ_N")
	)
	(segment
		(start 490.153198 -32.597598)
		(end 490.152944 -32.597598)
		(width 0.089408)
		(layer "In2.Cu")
		(net "BMC_PREQ_N")
	)
	(segment
		(start 427.730158 -65.383664)
		(end 465.970874 -65.383664)
		(width 0.089408)
		(layer "In2.Cu")
		(net "BMC_PREQ_N")
	)
	(segment
		(start 425.40301 -79.542132)
		(end 425.40301 -78.929738)
		(width 0.089408)
		(layer "In2.Cu")
		(net "BMC_PREQ_N")
	)
	(segment
		(start 473.371164 -31.222696)
		(end 473.46616 -31.1277)
		(width 0.089408)
		(layer "In2.Cu")
		(net "BMC_PREQ_N")
	)
	(segment
		(start 424.570652 -112.112552)
		(end 424.570652 -112.075468)
		(width 0.089408)
		(layer "In2.Cu")
		(net "BMC_PREQ_N")
	)
	(segment
		(start 487.663998 -30.616144)
		(end 489.650024 -32.60217)
		(width 0.089408)
		(layer "In2.Cu")
		(net "BMC_PREQ_N")
	)
	(segment
		(start 490.153198 -32.60217)
		(end 490.153198 -32.597598)
		(width 0.089408)
		(layer "In2.Cu")
		(net "BMC_PREQ_N")
	)
	(segment
		(start 472.61907 -63.665608)
		(end 475.285816 -63.665608)
		(width 0.089408)
		(layer "In2.Cu")
		(net "BMC_PREQ_N")
	)
	(segment
		(start 474.256862 -31.444438)
		(end 474.256862 -32.21736)
		(width 0.089408)
		(layer "In2.Cu")
		(net "BMC_PREQ_N")
	)
	(segment
		(start 471.73007 -62.776608)
		(end 472.61907 -63.665608)
		(width 0.089408)
		(layer "In2.Cu")
		(net "BMC_PREQ_N")
	)
	(segment
		(start 474.256862 -32.21736)
		(end 474.976698 -32.937196)
		(width 0.089408)
		(layer "In2.Cu")
		(net "BMC_PREQ_N")
	)
	(segment
		(start 424.570652 -112.075468)
		(end 424.628056 -112.018064)
		(width 0.089408)
		(layer "In2.Cu")
		(net "BMC_PREQ_N")
	)
	(segment
		(start 489.650024 -32.60217)
		(end 490.153198 -32.60217)
		(width 0.089408)
		(layer "In2.Cu")
		(net "BMC_PREQ_N")
	)
	(segment
		(start 472.482672 -31.222696)
		(end 473.371164 -31.222696)
		(width 0.089408)
		(layer "In2.Cu")
		(net "BMC_PREQ_N")
	)
	(segment
		(start 471.18016 -33.94964)
		(end 471.250518 -33.879282)
		(width 0.089408)
		(layer "In2.Cu")
		(net "BMC_PREQ_N")
	)
	(segment
		(start 424.133264 -112.764062)
		(end 424.133264 -112.512856)
		(width 0.089408)
		(layer "In2.Cu")
		(net "BMC_PREQ_N")
	)
	(segment
		(start 424.33621 -112.346994)
		(end 424.570652 -112.112552)
		(width 0.089408)
		(layer "In2.Cu")
		(net "BMC_PREQ_N")
	)
	(segment
		(start 473.46616 -31.1277)
		(end 473.940124 -31.1277)
		(width 0.089408)
		(layer "In2.Cu")
		(net "BMC_PREQ_N")
	)
	(segment
		(start 426.652944 -65.38341)
		(end 427.729904 -65.38341)
		(width 0.089408)
		(layer "In2.Cu")
		(net "BMC_PREQ_N")
	)
	(segment
		(start 469.92413 -62.776608)
		(end 471.73007 -62.776608)
		(width 0.089408)
		(layer "In2.Cu")
		(net "BMC_PREQ_N")
	)
	(segment
		(start 473.940124 -31.1277)
		(end 474.256862 -31.444438)
		(width 0.089408)
		(layer "In2.Cu")
		(net "BMC_PREQ_N")
	)
	(segment
		(start 480.388168 -59.959748)
		(end 480.637596 -59.71032)
		(width 0.089408)
		(layer "In2.Cu")
		(net "BMC_PREQ_N")
	)
	(segment
		(start 465.970874 -65.383664)
		(end 467.40953 -63.945008)
		(width 0.089408)
		(layer "In2.Cu")
		(net "BMC_PREQ_N")
	)
	(segment
		(start 474.976698 -32.937196)
		(end 481.86594 -32.937196)
		(width 0.089408)
		(layer "In2.Cu")
		(net "BMC_PREQ_N")
	)
	(segment
		(start 424.091354 -75.7047)
		(end 424.091354 -67.945)
		(width 0.089408)
		(layer "In2.Cu")
		(net "BMC_PREQ_N")
	)
	(segment
		(start 424.133264 -112.512856)
		(end 424.299126 -112.346994)
		(width 0.089408)
		(layer "In2.Cu")
		(net "BMC_PREQ_N")
	)
	(segment
		(start 471.250518 -33.879282)
		(end 471.422984 -33.879282)
		(width 0.089408)
		(layer "In2.Cu")
		(net "BMC_PREQ_N")
	)
	(segment
		(start 424.091354 -67.945)
		(end 426.652944 -65.38341)
		(width 0.089408)
		(layer "In2.Cu")
		(net "BMC_PREQ_N")
	)
	(segment
		(start 478.991676 -59.959748)
		(end 480.388168 -59.959748)
		(width 0.089408)
		(layer "In2.Cu")
		(net "BMC_PREQ_N")
	)
	(segment
		(start 482.80828 -31.113476)
		(end 483.305612 -30.616144)
		(width 0.089408)
		(layer "In2.Cu")
		(net "BMC_PREQ_N")
	)
	(segment
		(start 425.40301 -110.510066)
		(end 425.40301 -80.302608)
		(width 0.089408)
		(layer "In2.Cu")
		(net "BMC_PREQ_N")
	)
	(segment
		(start 483.305612 -30.616144)
		(end 487.663998 -30.616144)
		(width 0.089408)
		(layer "In2.Cu")
		(net "BMC_PREQ_N")
	)
	(segment
		(start 468.75573 -63.945008)
		(end 469.92413 -62.776608)
		(width 0.089408)
		(layer "In2.Cu")
		(net "BMC_PREQ_N")
	)
	(segment
		(start 425.403264 -80.302354)
		(end 425.403264 -79.542386)
		(width 0.089408)
		(layer "In2.Cu")
		(net "BMC_PREQ_N")
	)
	(segment
		(start 490.43336 -32.60217)
		(end 490.720634 -32.889444)
		(width 0.089408)
		(layer "In9.Cu")
		(net "BMC_PREQ_N")
	)
	(segment
		(start 437.63311 -132.97408)
		(end 430.507394 -132.97408)
		(width 0.089408)
		(layer "In9.Cu")
		(net "BMC_PREQ_N")
	)
	(segment
		(start 442.032644 -139.133834)
		(end 440.383676 -137.484866)
		(width 0.089408)
		(layer "In9.Cu")
		(net "BMC_PREQ_N")
	)
	(segment
		(start 422.330626 -127.51181)
		(end 422.330626 -118.071138)
		(width 0.089408)
		(layer "In9.Cu")
		(net "BMC_PREQ_N")
	)
	(segment
		(start 490.06887 -50.473356)
		(end 490.06887 -51.107848)
		(width 0.089408)
		(layer "In9.Cu")
		(net "BMC_PREQ_N")
	)
	(segment
		(start 442.032644 -140.892784)
		(end 442.032644 -139.133834)
		(width 0.089408)
		(layer "In9.Cu")
		(net "BMC_PREQ_N")
	)
	(segment
		(start 491.358428 -49.85512)
		(end 490.687106 -49.85512)
		(width 0.089408)
		(layer "In9.Cu")
		(net "BMC_PREQ_N")
	)
	(segment
		(start 490.720634 -32.889444)
		(end 490.720634 -36.0553)
		(width 0.089408)
		(layer "In9.Cu")
		(net "BMC_PREQ_N")
	)
	(segment
		(start 488.322874 -52.853844)
		(end 488.322874 -55.563516)
		(width 0.089408)
		(layer "In9.Cu")
		(net "BMC_PREQ_N")
	)
	(segment
		(start 489.064554 -42.423334)
		(end 488.945682 -42.542206)
		(width 0.089408)
		(layer "In9.Cu")
		(net "BMC_PREQ_N")
	)
	(segment
		(start 440.383676 -137.484866)
		(end 440.383676 -135.724646)
		(width 0.089408)
		(layer "In9.Cu")
		(net "BMC_PREQ_N")
	)
	(segment
		(start 442.411866 -150.733506)
		(end 442.784484 -150.733506)
		(width 0.089408)
		(layer "In9.Cu")
		(net "BMC_PREQ_N")
	)
	(segment
		(start 490.449616 -36.326318)
		(end 490.449616 -38.584124)
		(width 0.089408)
		(layer "In9.Cu")
		(net "BMC_PREQ_N")
	)
	(segment
		(start 490.153198 -32.60217)
		(end 490.43336 -32.60217)
		(width 0.089408)
		(layer "In9.Cu")
		(net "BMC_PREQ_N")
	)
	(segment
		(start 443.976252 -145.180304)
		(end 442.420502 -145.180304)
		(width 0.089408)
		(layer "In9.Cu")
		(net "BMC_PREQ_N")
	)
	(segment
		(start 491.699804 -49.513744)
		(end 491.358428 -49.85512)
		(width 0.089408)
		(layer "In9.Cu")
		(net "BMC_PREQ_N")
	)
	(segment
		(start 441.018676 -141.456918)
		(end 441.29452 -141.181074)
		(width 0.089408)
		(layer "In9.Cu")
		(net "BMC_PREQ_N")
	)
	(segment
		(start 490.720634 -36.0553)
		(end 490.449616 -36.326318)
		(width 0.089408)
		(layer "In9.Cu")
		(net "BMC_PREQ_N")
	)
	(segment
		(start 488.945682 -42.542206)
		(end 488.945682 -46.187868)
		(width 0.089408)
		(layer "In9.Cu")
		(net "BMC_PREQ_N")
	)
	(segment
		(start 423.541952 -113.384584)
		(end 424.133264 -112.793272)
		(width 0.089408)
		(layer "In9.Cu")
		(net "BMC_PREQ_N")
	)
	(segment
		(start 485.239822 -60.426092)
		(end 481.353368 -60.426092)
		(width 0.089408)
		(layer "In9.Cu")
		(net "BMC_PREQ_N")
	)
	(segment
		(start 442.420502 -145.180304)
		(end 441.018676 -143.778478)
		(width 0.089408)
		(layer "In9.Cu")
		(net "BMC_PREQ_N")
	)
	(segment
		(start 444.260732 -145.464784)
		(end 443.976252 -145.180304)
		(width 0.089408)
		(layer "In9.Cu")
		(net "BMC_PREQ_N")
	)
	(segment
		(start 490.921802 -41.956736)
		(end 490.455204 -42.423334)
		(width 0.089408)
		(layer "In9.Cu")
		(net "BMC_PREQ_N")
	)
	(segment
		(start 444.260732 -149.257258)
		(end 444.260732 -145.464784)
		(width 0.089408)
		(layer "In9.Cu")
		(net "BMC_PREQ_N")
	)
	(segment
		(start 481.353368 -60.426092)
		(end 480.637596 -59.71032)
		(width 0.089408)
		(layer "In9.Cu")
		(net "BMC_PREQ_N")
	)
	(segment
		(start 490.455204 -42.423334)
		(end 489.064554 -42.423334)
		(width 0.089408)
		(layer "In9.Cu")
		(net "BMC_PREQ_N")
	)
	(segment
		(start 490.152944 -32.597598)
		(end 490.153198 -32.597598)
		(width 0.089408)
		(layer "In9.Cu")
		(net "BMC_PREQ_N")
	)
	(segment
		(start 487.320336 -56.566054)
		(end 487.320336 -58.345578)
		(width 0.089408)
		(layer "In9.Cu")
		(net "BMC_PREQ_N")
	)
	(segment
		(start 490.687106 -49.85512)
		(end 490.06887 -50.473356)
		(width 0.089408)
		(layer "In9.Cu")
		(net "BMC_PREQ_N")
	)
	(segment
		(start 490.921802 -39.05631)
		(end 490.921802 -41.956736)
		(width 0.089408)
		(layer "In9.Cu")
		(net "BMC_PREQ_N")
	)
	(segment
		(start 425.200318 -130.381502)
		(end 422.330626 -127.51181)
		(width 0.089408)
		(layer "In9.Cu")
		(net "BMC_PREQ_N")
	)
	(segment
		(start 441.960508 -149.602444)
		(end 442.15177 -149.793706)
		(width 0.089408)
		(layer "In9.Cu")
		(net "BMC_PREQ_N")
	)
	(segment
		(start 442.15177 -149.793706)
		(end 442.15177 -150.47341)
		(width 0.089408)
		(layer "In9.Cu")
		(net "BMC_PREQ_N")
	)
	(segment
		(start 490.153198 -32.597598)
		(end 490.153198 -32.60217)
		(width 0.089408)
		(layer "In9.Cu")
		(net "BMC_PREQ_N")
	)
	(segment
		(start 424.133264 -112.793272)
		(end 424.133264 -112.764062)
		(width 0.089408)
		(layer "In9.Cu")
		(net "BMC_PREQ_N")
	)
	(segment
		(start 491.699804 -48.94199)
		(end 491.699804 -49.513744)
		(width 0.089408)
		(layer "In9.Cu")
		(net "BMC_PREQ_N")
	)
	(segment
		(start 441.29452 -141.181074)
		(end 441.744354 -141.181074)
		(width 0.089408)
		(layer "In9.Cu")
		(net "BMC_PREQ_N")
	)
	(segment
		(start 442.784484 -150.733506)
		(end 444.260732 -149.257258)
		(width 0.089408)
		(layer "In9.Cu")
		(net "BMC_PREQ_N")
	)
	(segment
		(start 441.562236 -149.602444)
		(end 441.960508 -149.602444)
		(width 0.089408)
		(layer "In9.Cu")
		(net "BMC_PREQ_N")
	)
	(segment
		(start 442.15177 -150.47341)
		(end 442.411866 -150.733506)
		(width 0.089408)
		(layer "In9.Cu")
		(net "BMC_PREQ_N")
	)
	(segment
		(start 488.322874 -55.563516)
		(end 487.320336 -56.566054)
		(width 0.089408)
		(layer "In9.Cu")
		(net "BMC_PREQ_N")
	)
	(segment
		(start 427.914816 -130.381502)
		(end 425.200318 -130.381502)
		(width 0.089408)
		(layer "In9.Cu")
		(net "BMC_PREQ_N")
	)
	(segment
		(start 490.449616 -38.584124)
		(end 490.921802 -39.05631)
		(width 0.089408)
		(layer "In9.Cu")
		(net "BMC_PREQ_N")
	)
	(segment
		(start 422.330626 -118.071138)
		(end 423.541952 -116.859812)
		(width 0.089408)
		(layer "In9.Cu")
		(net "BMC_PREQ_N")
	)
	(segment
		(start 423.541952 -116.859812)
		(end 423.541952 -113.384584)
		(width 0.089408)
		(layer "In9.Cu")
		(net "BMC_PREQ_N")
	)
	(segment
		(start 488.945682 -46.187868)
		(end 491.699804 -48.94199)
		(width 0.089408)
		(layer "In9.Cu")
		(net "BMC_PREQ_N")
	)
	(segment
		(start 440.383676 -135.724646)
		(end 437.63311 -132.97408)
		(width 0.089408)
		(layer "In9.Cu")
		(net "BMC_PREQ_N")
	)
	(segment
		(start 441.744354 -141.181074)
		(end 442.032644 -140.892784)
		(width 0.089408)
		(layer "In9.Cu")
		(net "BMC_PREQ_N")
	)
	(segment
		(start 490.06887 -51.107848)
		(end 488.322874 -52.853844)
		(width 0.089408)
		(layer "In9.Cu")
		(net "BMC_PREQ_N")
	)
	(segment
		(start 430.507394 -132.97408)
		(end 427.914816 -130.381502)
		(width 0.089408)
		(layer "In9.Cu")
		(net "BMC_PREQ_N")
	)
	(segment
		(start 487.320336 -58.345578)
		(end 485.239822 -60.426092)
		(width 0.089408)
		(layer "In9.Cu")
		(net "BMC_PREQ_N")
	)
	(segment
		(start 441.018676 -143.778478)
		(end 441.018676 -141.456918)
		(width 0.089408)
		(layer "In9.Cu")
		(net "BMC_PREQ_N")
	)
	(segment
		(start 462.204562 -34.562796)
		(end 463.027776 -33.739582)
		(width 0.089408)
		(layer "In11.Cu")
		(net "BMC_PREQ_N")
	)
	(segment
		(start 445.930782 -37.319712)
		(end 446.275968 -37.319712)
		(width 0.089408)
		(layer "In11.Cu")
		(net "BMC_PREQ_N")
	)
	(segment
		(start 435.164992 -38.541452)
		(end 442.304678 -38.541452)
		(width 0.089408)
		(layer "In11.Cu")
		(net "BMC_PREQ_N")
	)
	(segment
		(start 442.304678 -38.541452)
		(end 442.722254 -38.123876)
		(width 0.089408)
		(layer "In11.Cu")
		(net "BMC_PREQ_N")
	)
	(segment
		(start 433.95646 -35.709352)
		(end 433.95646 -37.33292)
		(width 0.089408)
		(layer "In11.Cu")
		(net "BMC_PREQ_N")
	)
	(segment
		(start 423.288968 -29.754576)
		(end 425.393612 -29.754576)
		(width 0.089408)
		(layer "In11.Cu")
		(net "BMC_PREQ_N")
	)
	(segment
		(start 425.393612 -29.754576)
		(end 425.89069 -29.257498)
		(width 0.089408)
		(layer "In11.Cu")
		(net "BMC_PREQ_N")
	)
	(segment
		(start 471.109802 -33.879282)
		(end 471.168222 -33.937702)
		(width 0.089408)
		(layer "In11.Cu")
		(net "BMC_PREQ_N")
	)
	(segment
		(start 471.168222 -33.937702)
		(end 471.160348 -33.937702)
		(width 0.089408)
		(layer "In11.Cu")
		(net "BMC_PREQ_N")
	)
	(segment
		(start 460.40294 -34.127948)
		(end 460.837788 -34.562796)
		(width 0.089408)
		(layer "In11.Cu")
		(net "BMC_PREQ_N")
	)
	(segment
		(start 460.837788 -34.562796)
		(end 462.204562 -34.562796)
		(width 0.089408)
		(layer "In11.Cu")
		(net "BMC_PREQ_N")
	)
	(segment
		(start 463.027776 -33.739582)
		(end 470.756996 -33.739582)
		(width 0.089408)
		(layer "In11.Cu")
		(net "BMC_PREQ_N")
	)
	(segment
		(start 433.95646 -37.33292)
		(end 435.164992 -38.541452)
		(width 0.089408)
		(layer "In11.Cu")
		(net "BMC_PREQ_N")
	)
	(segment
		(start 446.275968 -37.319712)
		(end 449.115942 -34.479738)
		(width 0.089408)
		(layer "In11.Cu")
		(net "BMC_PREQ_N")
	)
	(segment
		(start 458.6478 -34.127948)
		(end 460.40294 -34.127948)
		(width 0.089408)
		(layer "In11.Cu")
		(net "BMC_PREQ_N")
	)
	(segment
		(start 449.115942 -34.479738)
		(end 458.29601 -34.479738)
		(width 0.089408)
		(layer "In11.Cu")
		(net "BMC_PREQ_N")
	)
	(segment
		(start 470.756996 -33.739582)
		(end 470.896696 -33.879282)
		(width 0.089408)
		(layer "In11.Cu")
		(net "BMC_PREQ_N")
	)
	(segment
		(start 426.908214 -29.257498)
		(end 430.134776 -32.48406)
		(width 0.089408)
		(layer "In11.Cu")
		(net "BMC_PREQ_N")
	)
	(segment
		(start 442.722254 -38.123876)
		(end 445.126618 -38.123876)
		(width 0.089408)
		(layer "In11.Cu")
		(net "BMC_PREQ_N")
	)
	(segment
		(start 470.896696 -33.879282)
		(end 471.109802 -33.879282)
		(width 0.089408)
		(layer "In11.Cu")
		(net "BMC_PREQ_N")
	)
	(segment
		(start 430.731168 -32.48406)
		(end 433.95646 -35.709352)
		(width 0.089408)
		(layer "In11.Cu")
		(net "BMC_PREQ_N")
	)
	(segment
		(start 458.29601 -34.479738)
		(end 458.6478 -34.127948)
		(width 0.089408)
		(layer "In11.Cu")
		(net "BMC_PREQ_N")
	)
	(segment
		(start 430.134776 -32.48406)
		(end 430.731168 -32.48406)
		(width 0.089408)
		(layer "In11.Cu")
		(net "BMC_PREQ_N")
	)
	(segment
		(start 445.126618 -38.123876)
		(end 445.930782 -37.319712)
		(width 0.089408)
		(layer "In11.Cu")
		(net "BMC_PREQ_N")
	)
	(segment
		(start 422.69029 -29.334714)
		(end 422.869106 -29.334714)
		(width 0.089408)
		(layer "In11.Cu")
		(net "BMC_PREQ_N")
	)
	(segment
		(start 425.89069 -29.257498)
		(end 426.908214 -29.257498)
		(width 0.089408)
		(layer "In11.Cu")
		(net "BMC_PREQ_N")
	)
	(segment
		(start 422.869106 -29.334714)
		(end 423.288968 -29.754576)
		(width 0.089408)
		(layer "In11.Cu")
		(net "BMC_PREQ_N")
	)
	(segment
		(start 422.29024 -40.93464)
		(end 421.89019 -41.33469)
		(width 0.089408)
		(layer "F.Cu")
		(net "BMC_PRDY_N")
	)
	(segment
		(start 442.564774 -149.48662)
		(end 442.986414 -149.06498)
		(width 0.10795)
		(layer "F.Cu")
		(net "BMC_PRDY_N")
	)
	(segment
		(start 442.986414 -149.06498)
		(end 444.1952 -149.06498)
		(width 0.10795)
		(layer "F.Cu")
		(net "BMC_PRDY_N")
	)
	(via
		(at 423.535348 -111.94669)
		(size 0.508)
		(drill 0.254)
		(layers "F.Cu" "B.Cu")
		(net "BMC_PRDY_N")
	)
	(via
		(at 421.89019 -41.33469)
		(size 0.4572)
		(drill 0.2032)
		(layers "F.Cu" "B.Cu")
		(net "BMC_PRDY_N")
	)
	(via
		(at 437.941974 -62.524386)
		(size 0.508)
		(drill 0.254)
		(layers "F.Cu" "B.Cu")
		(net "BMC_PRDY_N")
	)
	(via
		(at 442.564774 -149.48662)
		(size 0.508)
		(drill 0.254)
		(layers "F.Cu" "B.Cu")
		(net "BMC_PRDY_N")
	)
	(segment
		(start 423.423842 -103.712264)
		(end 423.423842 -97.523046)
		(width 0.089408)
		(layer "In2.Cu")
		(net "BMC_PRDY_N")
	)
	(segment
		(start 426.28693 -64.182498)
		(end 436.283862 -64.182498)
		(width 0.089408)
		(layer "In2.Cu")
		(net "BMC_PRDY_N")
	)
	(segment
		(start 424.19905 -93.768164)
		(end 424.19905 -79.52613)
		(width 0.089408)
		(layer "In2.Cu")
		(net "BMC_PRDY_N")
	)
	(segment
		(start 436.283862 -64.182498)
		(end 437.941974 -62.524386)
		(width 0.089408)
		(layer "In2.Cu")
		(net "BMC_PRDY_N")
	)
	(segment
		(start 422.842436 -76.050902)
		(end 422.842436 -67.626992)
		(width 0.089408)
		(layer "In2.Cu")
		(net "BMC_PRDY_N")
	)
	(segment
		(start 423.498264 -111.314992)
		(end 422.176448 -109.993176)
		(width 0.089408)
		(layer "In2.Cu")
		(net "BMC_PRDY_N")
	)
	(segment
		(start 422.28897 -96.388174)
		(end 422.28897 -95.678244)
		(width 0.089408)
		(layer "In2.Cu")
		(net "BMC_PRDY_N")
	)
	(segment
		(start 423.498264 -111.94669)
		(end 423.498264 -111.314992)
		(width 0.089408)
		(layer "In2.Cu")
		(net "BMC_PRDY_N")
	)
	(segment
		(start 422.28897 -95.678244)
		(end 424.19905 -93.768164)
		(width 0.089408)
		(layer "In2.Cu")
		(net "BMC_PRDY_N")
	)
	(segment
		(start 423.581068 -78.908148)
		(end 423.581068 -76.789534)
		(width 0.089408)
		(layer "In2.Cu")
		(net "BMC_PRDY_N")
	)
	(segment
		(start 423.423842 -97.523046)
		(end 422.28897 -96.388174)
		(width 0.089408)
		(layer "In2.Cu")
		(net "BMC_PRDY_N")
	)
	(segment
		(start 422.176448 -104.959658)
		(end 423.423842 -103.712264)
		(width 0.089408)
		(layer "In2.Cu")
		(net "BMC_PRDY_N")
	)
	(segment
		(start 422.842436 -67.626992)
		(end 426.28693 -64.182498)
		(width 0.089408)
		(layer "In2.Cu")
		(net "BMC_PRDY_N")
	)
	(segment
		(start 423.581068 -76.789534)
		(end 422.842436 -76.050902)
		(width 0.089408)
		(layer "In2.Cu")
		(net "BMC_PRDY_N")
	)
	(segment
		(start 422.176448 -109.993176)
		(end 422.176448 -104.959658)
		(width 0.089408)
		(layer "In2.Cu")
		(net "BMC_PRDY_N")
	)
	(segment
		(start 424.19905 -79.52613)
		(end 423.581068 -78.908148)
		(width 0.089408)
		(layer "In2.Cu")
		(net "BMC_PRDY_N")
	)
	(segment
		(start 423.535348 -111.94669)
		(end 423.498264 -111.94669)
		(width 0.089408)
		(layer "In2.Cu")
		(net "BMC_PRDY_N")
	)
	(segment
		(start 423.058336 -113.183924)
		(end 423.327322 -112.914938)
		(width 0.089408)
		(layer "In9.Cu")
		(net "BMC_PRDY_N")
	)
	(segment
		(start 437.152796 -133.965696)
		(end 430.096168 -133.965696)
		(width 0.089408)
		(layer "In9.Cu")
		(net "BMC_PRDY_N")
	)
	(segment
		(start 424.591226 -131.373118)
		(end 419.206426 -125.988318)
		(width 0.089408)
		(layer "In9.Cu")
		(net "BMC_PRDY_N")
	)
	(segment
		(start 438.93867 -135.75157)
		(end 437.152796 -133.965696)
		(width 0.089408)
		(layer "In9.Cu")
		(net "BMC_PRDY_N")
	)
	(segment
		(start 423.058336 -116.655342)
		(end 423.058336 -113.183924)
		(width 0.089408)
		(layer "In9.Cu")
		(net "BMC_PRDY_N")
	)
	(segment
		(start 430.096168 -133.965696)
		(end 427.50359 -131.373118)
		(width 0.089408)
		(layer "In9.Cu")
		(net "BMC_PRDY_N")
	)
	(segment
		(start 423.327322 -112.914938)
		(end 423.327322 -112.154716)
		(width 0.089408)
		(layer "In9.Cu")
		(net "BMC_PRDY_N")
	)
	(segment
		(start 419.206426 -125.988318)
		(end 419.206426 -125.084078)
		(width 0.089408)
		(layer "In9.Cu")
		(net "BMC_PRDY_N")
	)
	(segment
		(start 442.341254 -145.371312)
		(end 440.59729 -143.627348)
		(width 0.089408)
		(layer "In9.Cu")
		(net "BMC_PRDY_N")
	)
	(segment
		(start 419.206426 -125.084078)
		(end 418.903404 -124.781056)
		(width 0.089408)
		(layer "In9.Cu")
		(net "BMC_PRDY_N")
	)
	(segment
		(start 440.59729 -139.560554)
		(end 439.38952 -138.352784)
		(width 0.089408)
		(layer "In9.Cu")
		(net "BMC_PRDY_N")
	)
	(segment
		(start 423.327322 -112.154716)
		(end 423.535348 -111.94669)
		(width 0.089408)
		(layer "In9.Cu")
		(net "BMC_PRDY_N")
	)
	(segment
		(start 438.93867 -137.889234)
		(end 438.93867 -135.75157)
		(width 0.089408)
		(layer "In9.Cu")
		(net "BMC_PRDY_N")
	)
	(segment
		(start 427.50359 -131.373118)
		(end 424.591226 -131.373118)
		(width 0.089408)
		(layer "In9.Cu")
		(net "BMC_PRDY_N")
	)
	(segment
		(start 442.564774 -149.48662)
		(end 444.069724 -147.98167)
		(width 0.089408)
		(layer "In9.Cu")
		(net "BMC_PRDY_N")
	)
	(segment
		(start 443.897004 -145.371312)
		(end 442.341254 -145.371312)
		(width 0.089408)
		(layer "In9.Cu")
		(net "BMC_PRDY_N")
	)
	(segment
		(start 418.903404 -120.810274)
		(end 423.058336 -116.655342)
		(width 0.089408)
		(layer "In9.Cu")
		(net "BMC_PRDY_N")
	)
	(segment
		(start 418.903404 -124.781056)
		(end 418.903404 -120.810274)
		(width 0.089408)
		(layer "In9.Cu")
		(net "BMC_PRDY_N")
	)
	(segment
		(start 439.38952 -138.340084)
		(end 438.93867 -137.889234)
		(width 0.089408)
		(layer "In9.Cu")
		(net "BMC_PRDY_N")
	)
	(segment
		(start 440.59729 -143.627348)
		(end 440.59729 -139.560554)
		(width 0.089408)
		(layer "In9.Cu")
		(net "BMC_PRDY_N")
	)
	(segment
		(start 439.38952 -138.352784)
		(end 439.38952 -138.340084)
		(width 0.089408)
		(layer "In9.Cu")
		(net "BMC_PRDY_N")
	)
	(segment
		(start 444.069724 -147.98167)
		(end 444.069724 -145.544032)
		(width 0.089408)
		(layer "In9.Cu")
		(net "BMC_PRDY_N")
	)
	(segment
		(start 444.069724 -145.544032)
		(end 443.897004 -145.371312)
		(width 0.089408)
		(layer "In9.Cu")
		(net "BMC_PRDY_N")
	)
	(segment
		(start 428.64278 -50.523902)
		(end 435.6608 -57.541922)
		(width 0.089408)
		(layer "In11.Cu")
		(net "BMC_PRDY_N")
	)
	(segment
		(start 426.20946 -46.315884)
		(end 426.209206 -46.316138)
		(width 0.089408)
		(layer "In11.Cu")
		(net "BMC_PRDY_N")
	)
	(segment
		(start 428.64278 -50.097944)
		(end 428.64278 -50.523902)
		(width 0.089408)
		(layer "In11.Cu")
		(net "BMC_PRDY_N")
	)
	(segment
		(start 426.209206 -47.989236)
		(end 426.875448 -48.655478)
		(width 0.089408)
		(layer "In11.Cu")
		(net "BMC_PRDY_N")
	)
	(segment
		(start 426.875448 -48.655478)
		(end 427.200314 -48.655478)
		(width 0.089408)
		(layer "In11.Cu")
		(net "BMC_PRDY_N")
	)
	(segment
		(start 435.6608 -60.058554)
		(end 437.500776 -61.89853)
		(width 0.089408)
		(layer "In11.Cu")
		(net "BMC_PRDY_N")
	)
	(segment
		(start 421.89019 -41.33469)
		(end 424.58767 -44.03217)
		(width 0.089408)
		(layer "In11.Cu")
		(net "BMC_PRDY_N")
	)
	(segment
		(start 435.6608 -57.541922)
		(end 435.6608 -60.058554)
		(width 0.089408)
		(layer "In11.Cu")
		(net "BMC_PRDY_N")
	)
	(segment
		(start 425.187618 -45.136054)
		(end 426.20946 -46.157896)
		(width 0.089408)
		(layer "In11.Cu")
		(net "BMC_PRDY_N")
	)
	(segment
		(start 424.58767 -44.956222)
		(end 424.767502 -45.136054)
		(width 0.089408)
		(layer "In11.Cu")
		(net "BMC_PRDY_N")
	)
	(segment
		(start 424.58767 -44.03217)
		(end 424.58767 -44.956222)
		(width 0.089408)
		(layer "In11.Cu")
		(net "BMC_PRDY_N")
	)
	(segment
		(start 426.209206 -46.316138)
		(end 426.209206 -47.989236)
		(width 0.089408)
		(layer "In11.Cu")
		(net "BMC_PRDY_N")
	)
	(segment
		(start 426.20946 -46.157896)
		(end 426.20946 -46.315884)
		(width 0.089408)
		(layer "In11.Cu")
		(net "BMC_PRDY_N")
	)
	(segment
		(start 424.767502 -45.136054)
		(end 425.187618 -45.136054)
		(width 0.089408)
		(layer "In11.Cu")
		(net "BMC_PRDY_N")
	)
	(segment
		(start 437.500776 -61.89853)
		(end 437.500776 -62.083188)
		(width 0.089408)
		(layer "In11.Cu")
		(net "BMC_PRDY_N")
	)
	(segment
		(start 427.200314 -48.655478)
		(end 428.64278 -50.097944)
		(width 0.089408)
		(layer "In11.Cu")
		(net "BMC_PRDY_N")
	)
	(segment
		(start 437.500776 -62.083188)
		(end 437.941974 -62.524386)
		(width 0.089408)
		(layer "In11.Cu")
		(net "BMC_PRDY_N")
	)
	(segment
		(start 415.090102 -40.93464)
		(end 415.490152 -41.33469)
		(width 0.10795)
		(layer "F.Cu")
		(net "BMC_DEBUG_EN_N")
	)
	(via
		(at 457.30668 -37.65296)
		(size 0.508)
		(drill 0.254)
		(layers "F.Cu" "B.Cu")
		(net "BMC_DEBUG_EN_N")
	)
	(via
		(at 470.94521 -33.304734)
		(size 0.508)
		(drill 0.254)
		(layers "F.Cu" "B.Cu")
		(net "BMC_DEBUG_EN_N")
	)
	(via
		(at 445.743838 -147.0025)
		(size 0.508)
		(drill 0.254)
		(layers "F.Cu" "B.Cu")
		(net "BMC_DEBUG_EN_N")
	)
	(via
		(at 415.490152 -41.33469)
		(size 0.4572)
		(drill 0.2032)
		(layers "F.Cu" "B.Cu")
		(net "BMC_DEBUG_EN_N")
	)
	(via
		(at 481.718366 -59.71032)
		(size 0.508)
		(drill 0.254)
		(layers "F.Cu" "B.Cu")
		(net "BMC_DEBUG_EN_N")
	)
	(via
		(at 489.691172 -32.043624)
		(size 0.508)
		(drill 0.254)
		(layers "F.Cu" "B.Cu")
		(net "BMC_DEBUG_EN_N")
	)
	(via
		(at 424.959272 -113.924588)
		(size 0.508)
		(drill 0.254)
		(layers "F.Cu" "B.Cu")
		(net "BMC_DEBUG_EN_N")
	)
	(via
		(at 456.59548 -37.65296)
		(size 0.6604)
		(drill 0.3302)
		(layers "F.Cu" "B.Cu")
		(net "BMC_DEBUG_EN_N")
	)
	(segment
		(start 457.30668 -37.65296)
		(end 456.59548 -37.65296)
		(width 0.10795)
		(layer "B.Cu")
		(net "BMC_DEBUG_EN_N")
	)
	(segment
		(start 444.701168 -147.043648)
		(end 445.70269 -147.043648)
		(width 0.10795)
		(layer "B.Cu")
		(net "BMC_DEBUG_EN_N")
	)
	(segment
		(start 444.134494 -147.043648)
		(end 443.9666 -146.875754)
		(width 0.10795)
		(layer "B.Cu")
		(net "BMC_DEBUG_EN_N")
	)
	(segment
		(start 443.9666 -146.875754)
		(end 443.558168 -146.875754)
		(width 0.10795)
		(layer "B.Cu")
		(net "BMC_DEBUG_EN_N")
	)
	(segment
		(start 444.701168 -147.043648)
		(end 444.134494 -147.043648)
		(width 0.10795)
		(layer "B.Cu")
		(net "BMC_DEBUG_EN_N")
	)
	(segment
		(start 445.70269 -147.043648)
		(end 445.743838 -147.0025)
		(width 0.10795)
		(layer "B.Cu")
		(net "BMC_DEBUG_EN_N")
	)
	(segment
		(start 481.781866 -32.734504)
		(end 475.082616 -32.734504)
		(width 0.089408)
		(layer "In2.Cu")
		(net "BMC_DEBUG_EN_N")
	)
	(segment
		(start 424.819064 -111.364268)
		(end 424.819064 -111.938816)
		(width 0.089408)
		(layer "In2.Cu")
		(net "BMC_DEBUG_EN_N")
	)
	(segment
		(start 424.819064 -111.938816)
		(end 424.819318 -111.93907)
		(width 0.089408)
		(layer "In2.Cu")
		(net "BMC_DEBUG_EN_N")
	)
	(segment
		(start 424.76166 -112.154716)
		(end 424.76166 -112.1918)
		(width 0.089408)
		(layer "In2.Cu")
		(net "BMC_DEBUG_EN_N")
	)
	(segment
		(start 482.617018 -31.034482)
		(end 482.617018 -31.239206)
		(width 0.089408)
		(layer "In2.Cu")
		(net "BMC_DEBUG_EN_N")
	)
	(segment
		(start 474.05671 -30.91942)
		(end 473.316046 -30.91942)
		(width 0.089408)
		(layer "In2.Cu")
		(net "BMC_DEBUG_EN_N")
	)
	(segment
		(start 479.07067 -60.15101)
		(end 473.647008 -65.574672)
		(width 0.089408)
		(layer "In2.Cu")
		(net "BMC_DEBUG_EN_N")
	)
	(segment
		(start 424.973496 -76.316586)
		(end 424.973496 -78.229968)
		(width 0.089408)
		(layer "In2.Cu")
		(net "BMC_DEBUG_EN_N")
	)
	(segment
		(start 471.872818 -31.031688)
		(end 470.685368 -32.219138)
		(width 0.089408)
		(layer "In2.Cu")
		(net "BMC_DEBUG_EN_N")
	)
	(segment
		(start 489.691172 -32.043624)
		(end 489.523278 -32.043624)
		(width 0.089408)
		(layer "In2.Cu")
		(net "BMC_DEBUG_EN_N")
	)
	(segment
		(start 424.557952 -112.395508)
		(end 424.557952 -113.523268)
		(width 0.089408)
		(layer "In2.Cu")
		(net "BMC_DEBUG_EN_N")
	)
	(segment
		(start 424.819318 -112.097058)
		(end 424.76166 -112.154716)
		(width 0.089408)
		(layer "In2.Cu")
		(net "BMC_DEBUG_EN_N")
	)
	(segment
		(start 425.594272 -79.463138)
		(end 425.594272 -80.381602)
		(width 0.089408)
		(layer "In2.Cu")
		(net "BMC_DEBUG_EN_N")
	)
	(segment
		(start 426.732192 -65.574418)
		(end 424.282362 -68.024248)
		(width 0.089408)
		(layer "In2.Cu")
		(net "BMC_DEBUG_EN_N")
	)
	(segment
		(start 425.594018 -110.589314)
		(end 424.819064 -111.364268)
		(width 0.089408)
		(layer "In2.Cu")
		(net "BMC_DEBUG_EN_N")
	)
	(segment
		(start 424.557952 -113.523268)
		(end 424.959272 -113.924588)
		(width 0.089408)
		(layer "In2.Cu")
		(net "BMC_DEBUG_EN_N")
	)
	(segment
		(start 487.852974 -30.37332)
		(end 483.27818 -30.37332)
		(width 0.089408)
		(layer "In2.Cu")
		(net "BMC_DEBUG_EN_N")
	)
	(segment
		(start 425.594018 -80.381856)
		(end 425.594018 -110.589314)
		(width 0.089408)
		(layer "In2.Cu")
		(net "BMC_DEBUG_EN_N")
	)
	(segment
		(start 427.650656 -65.574418)
		(end 426.732192 -65.574418)
		(width 0.089408)
		(layer "In2.Cu")
		(net "BMC_DEBUG_EN_N")
	)
	(segment
		(start 424.282362 -68.024248)
		(end 424.282362 -75.625452)
		(width 0.089408)
		(layer "In2.Cu")
		(net "BMC_DEBUG_EN_N")
	)
	(segment
		(start 489.523278 -32.043624)
		(end 487.852974 -30.37332)
		(width 0.089408)
		(layer "In2.Cu")
		(net "BMC_DEBUG_EN_N")
	)
	(segment
		(start 474.513148 -31.375858)
		(end 474.05671 -30.91942)
		(width 0.089408)
		(layer "In2.Cu")
		(net "BMC_DEBUG_EN_N")
	)
	(segment
		(start 424.76166 -112.1918)
		(end 424.557952 -112.395508)
		(width 0.089408)
		(layer "In2.Cu")
		(net "BMC_DEBUG_EN_N")
	)
	(segment
		(start 473.203778 -31.031688)
		(end 471.872818 -31.031688)
		(width 0.089408)
		(layer "In2.Cu")
		(net "BMC_DEBUG_EN_N")
	)
	(segment
		(start 425.594272 -80.381602)
		(end 425.594018 -80.381856)
		(width 0.089408)
		(layer "In2.Cu")
		(net "BMC_DEBUG_EN_N")
	)
	(segment
		(start 425.594018 -79.462884)
		(end 425.594272 -79.463138)
		(width 0.089408)
		(layer "In2.Cu")
		(net "BMC_DEBUG_EN_N")
	)
	(segment
		(start 481.277676 -60.15101)
		(end 479.07067 -60.15101)
		(width 0.089408)
		(layer "In2.Cu")
		(net "BMC_DEBUG_EN_N")
	)
	(segment
		(start 424.819318 -111.93907)
		(end 424.819318 -112.097058)
		(width 0.089408)
		(layer "In2.Cu")
		(net "BMC_DEBUG_EN_N")
	)
	(segment
		(start 474.513148 -32.165036)
		(end 474.513148 -31.375858)
		(width 0.089408)
		(layer "In2.Cu")
		(net "BMC_DEBUG_EN_N")
	)
	(segment
		(start 424.282362 -75.625452)
		(end 424.973496 -76.316586)
		(width 0.089408)
		(layer "In2.Cu")
		(net "BMC_DEBUG_EN_N")
	)
	(segment
		(start 482.617272 -31.23946)
		(end 482.617272 -31.899098)
		(width 0.089408)
		(layer "In2.Cu")
		(net "BMC_DEBUG_EN_N")
	)
	(segment
		(start 483.27818 -30.37332)
		(end 482.617018 -31.034482)
		(width 0.089408)
		(layer "In2.Cu")
		(net "BMC_DEBUG_EN_N")
	)
	(segment
		(start 425.594018 -78.85049)
		(end 425.594018 -79.462884)
		(width 0.089408)
		(layer "In2.Cu")
		(net "BMC_DEBUG_EN_N")
	)
	(segment
		(start 482.617018 -31.239206)
		(end 482.617272 -31.23946)
		(width 0.089408)
		(layer "In2.Cu")
		(net "BMC_DEBUG_EN_N")
	)
	(segment
		(start 482.617272 -31.899098)
		(end 481.781866 -32.734504)
		(width 0.089408)
		(layer "In2.Cu")
		(net "BMC_DEBUG_EN_N")
	)
	(segment
		(start 470.685368 -33.044892)
		(end 470.94521 -33.304734)
		(width 0.089408)
		(layer "In2.Cu")
		(net "BMC_DEBUG_EN_N")
	)
	(segment
		(start 481.718366 -59.71032)
		(end 481.277676 -60.15101)
		(width 0.089408)
		(layer "In2.Cu")
		(net "BMC_DEBUG_EN_N")
	)
	(segment
		(start 475.082616 -32.734504)
		(end 474.513148 -32.165036)
		(width 0.089408)
		(layer "In2.Cu")
		(net "BMC_DEBUG_EN_N")
	)
	(segment
		(start 473.316046 -30.91942)
		(end 473.203778 -31.031688)
		(width 0.089408)
		(layer "In2.Cu")
		(net "BMC_DEBUG_EN_N")
	)
	(segment
		(start 427.65091 -65.574672)
		(end 427.650656 -65.574418)
		(width 0.089408)
		(layer "In2.Cu")
		(net "BMC_DEBUG_EN_N")
	)
	(segment
		(start 470.685368 -32.219138)
		(end 470.685368 -33.044892)
		(width 0.089408)
		(layer "In2.Cu")
		(net "BMC_DEBUG_EN_N")
	)
	(segment
		(start 424.973496 -78.229968)
		(end 425.594018 -78.85049)
		(width 0.089408)
		(layer "In2.Cu")
		(net "BMC_DEBUG_EN_N")
	)
	(segment
		(start 473.647008 -65.574672)
		(end 427.65091 -65.574672)
		(width 0.089408)
		(layer "In2.Cu")
		(net "BMC_DEBUG_EN_N")
	)
	(segment
		(start 446.742566 -39.812214)
		(end 448.90182 -37.65296)
		(width 0.089408)
		(layer "In4.Cu")
		(net "BMC_DEBUG_EN_N")
	)
	(segment
		(start 430.190148 -38.90137)
		(end 430.734978 -39.4462)
		(width 0.089408)
		(layer "In4.Cu")
		(net "BMC_DEBUG_EN_N")
	)
	(segment
		(start 448.90182 -37.65296)
		(end 457.30668 -37.65296)
		(width 0.089408)
		(layer "In4.Cu")
		(net "BMC_DEBUG_EN_N")
	)
	(segment
		(start 416.224974 -42.895774)
		(end 419.083236 -42.895774)
		(width 0.089408)
		(layer "In4.Cu")
		(net "BMC_DEBUG_EN_N")
	)
	(segment
		(start 427.754796 -38.90137)
		(end 430.190148 -38.90137)
		(width 0.089408)
		(layer "In4.Cu")
		(net "BMC_DEBUG_EN_N")
	)
	(segment
		(start 415.8742 -41.718738)
		(end 415.8742 -42.545)
		(width 0.089408)
		(layer "In4.Cu")
		(net "BMC_DEBUG_EN_N")
	)
	(segment
		(start 419.241986 -43.054524)
		(end 421.770556 -43.054524)
		(width 0.089408)
		(layer "In4.Cu")
		(net "BMC_DEBUG_EN_N")
	)
	(segment
		(start 425.668694 -40.987472)
		(end 427.754796 -38.90137)
		(width 0.089408)
		(layer "In4.Cu")
		(net "BMC_DEBUG_EN_N")
	)
	(segment
		(start 430.734978 -39.4462)
		(end 433.21732 -39.4462)
		(width 0.089408)
		(layer "In4.Cu")
		(net "BMC_DEBUG_EN_N")
	)
	(segment
		(start 415.8742 -42.545)
		(end 416.224974 -42.895774)
		(width 0.089408)
		(layer "In4.Cu")
		(net "BMC_DEBUG_EN_N")
	)
	(segment
		(start 433.21732 -39.4462)
		(end 433.583334 -39.812214)
		(width 0.089408)
		(layer "In4.Cu")
		(net "BMC_DEBUG_EN_N")
	)
	(segment
		(start 421.770556 -43.054524)
		(end 423.837608 -40.987472)
		(width 0.089408)
		(layer "In4.Cu")
		(net "BMC_DEBUG_EN_N")
	)
	(segment
		(start 419.083236 -42.895774)
		(end 419.241986 -43.054524)
		(width 0.089408)
		(layer "In4.Cu")
		(net "BMC_DEBUG_EN_N")
	)
	(segment
		(start 433.583334 -39.812214)
		(end 446.742566 -39.812214)
		(width 0.089408)
		(layer "In4.Cu")
		(net "BMC_DEBUG_EN_N")
	)
	(segment
		(start 415.490152 -41.33469)
		(end 415.8742 -41.718738)
		(width 0.089408)
		(layer "In4.Cu")
		(net "BMC_DEBUG_EN_N")
	)
	(segment
		(start 423.837608 -40.987472)
		(end 425.668694 -40.987472)
		(width 0.089408)
		(layer "In4.Cu")
		(net "BMC_DEBUG_EN_N")
	)
	(segment
		(start 490.258608 -38.735254)
		(end 490.679994 -39.15664)
		(width 0.089408)
		(layer "In9.Cu")
		(net "BMC_DEBUG_EN_N")
	)
	(segment
		(start 424.314112 -124.242322)
		(end 424.468544 -124.242322)
		(width 0.089408)
		(layer "In9.Cu")
		(net "BMC_DEBUG_EN_N")
	)
	(segment
		(start 441.325 -133.025896)
		(end 439.227976 -130.928872)
		(width 0.089408)
		(layer "In9.Cu")
		(net "BMC_DEBUG_EN_N")
	)
	(segment
		(start 488.059984 -55.55615)
		(end 487.053636 -56.562498)
		(width 0.089408)
		(layer "In9.Cu")
		(net "BMC_DEBUG_EN_N")
	)
	(segment
		(start 439.227976 -130.928872)
		(end 433.97805 -130.928872)
		(width 0.089408)
		(layer "In9.Cu")
		(net "BMC_DEBUG_EN_N")
	)
	(segment
		(start 490.478826 -34.500058)
		(end 490.478826 -35.95497)
		(width 0.089408)
		(layer "In9.Cu")
		(net "BMC_DEBUG_EN_N")
	)
	(segment
		(start 424.468544 -124.242322)
		(end 425.088812 -123.622054)
		(width 0.089408)
		(layer "In9.Cu")
		(net "BMC_DEBUG_EN_N")
	)
	(segment
		(start 424.560492 -117.12194)
		(end 424.560492 -114.848132)
		(width 0.089408)
		(layer "In9.Cu")
		(net "BMC_DEBUG_EN_N")
	)
	(segment
		(start 487.053636 -58.234834)
		(end 485.089708 -60.198762)
		(width 0.089408)
		(layer "In9.Cu")
		(net "BMC_DEBUG_EN_N")
	)
	(segment
		(start 431.659284 -127.669798)
		(end 430.546002 -126.556516)
		(width 0.089408)
		(layer "In9.Cu")
		(net "BMC_DEBUG_EN_N")
	)
	(segment
		(start 444.671958 -145.93062)
		(end 444.671958 -139.739624)
		(width 0.089408)
		(layer "In9.Cu")
		(net "BMC_DEBUG_EN_N")
	)
	(segment
		(start 488.703874 -46.728126)
		(end 490.738922 -48.763174)
		(width 0.089408)
		(layer "In9.Cu")
		(net "BMC_DEBUG_EN_N")
	)
	(segment
		(start 489.80598 -50.36439)
		(end 489.80598 -50.998882)
		(width 0.089408)
		(layer "In9.Cu")
		(net "BMC_DEBUG_EN_N")
	)
	(segment
		(start 424.355006 -120.080024)
		(end 424.770042 -119.664988)
		(width 0.089408)
		(layer "In9.Cu")
		(net "BMC_DEBUG_EN_N")
	)
	(segment
		(start 490.258608 -36.175188)
		(end 490.258608 -38.735254)
		(width 0.089408)
		(layer "In9.Cu")
		(net "BMC_DEBUG_EN_N")
	)
	(segment
		(start 490.354874 -42.181526)
		(end 488.964224 -42.181526)
		(width 0.089408)
		(layer "In9.Cu")
		(net "BMC_DEBUG_EN_N")
	)
	(segment
		(start 424.355006 -120.518682)
		(end 424.355006 -120.080024)
		(width 0.089408)
		(layer "In9.Cu")
		(net "BMC_DEBUG_EN_N")
	)
	(segment
		(start 490.679994 -39.15664)
		(end 490.679994 -41.856406)
		(width 0.089408)
		(layer "In9.Cu")
		(net "BMC_DEBUG_EN_N")
	)
	(segment
		(start 431.659284 -128.610106)
		(end 431.659284 -127.669798)
		(width 0.089408)
		(layer "In9.Cu")
		(net "BMC_DEBUG_EN_N")
	)
	(segment
		(start 423.781474 -126.90983)
		(end 423.781474 -124.77496)
		(width 0.089408)
		(layer "In9.Cu")
		(net "BMC_DEBUG_EN_N")
	)
	(segment
		(start 426.10913 -127.743712)
		(end 424.615356 -127.743712)
		(width 0.089408)
		(layer "In9.Cu")
		(net "BMC_DEBUG_EN_N")
	)
	(segment
		(start 433.97805 -130.928872)
		(end 431.659284 -128.610106)
		(width 0.089408)
		(layer "In9.Cu")
		(net "BMC_DEBUG_EN_N")
	)
	(segment
		(start 490.738922 -49.431448)
		(end 489.80598 -50.36439)
		(width 0.089408)
		(layer "In9.Cu")
		(net "BMC_DEBUG_EN_N")
	)
	(segment
		(start 490.738922 -48.763174)
		(end 490.738922 -49.431448)
		(width 0.089408)
		(layer "In9.Cu")
		(net "BMC_DEBUG_EN_N")
	)
	(segment
		(start 424.959272 -114.449352)
		(end 424.959272 -113.924588)
		(width 0.089408)
		(layer "In9.Cu")
		(net "BMC_DEBUG_EN_N")
	)
	(segment
		(start 444.290958 -139.358624)
		(end 443.86119 -139.358624)
		(width 0.089408)
		(layer "In9.Cu")
		(net "BMC_DEBUG_EN_N")
	)
	(segment
		(start 423.781474 -124.77496)
		(end 424.314112 -124.242322)
		(width 0.089408)
		(layer "In9.Cu")
		(net "BMC_DEBUG_EN_N")
	)
	(segment
		(start 489.691172 -32.043624)
		(end 489.634022 -32.100774)
		(width 0.089408)
		(layer "In9.Cu")
		(net "BMC_DEBUG_EN_N")
	)
	(segment
		(start 445.743838 -147.0025)
		(end 444.671958 -145.93062)
		(width 0.089408)
		(layer "In9.Cu")
		(net "BMC_DEBUG_EN_N")
	)
	(segment
		(start 424.770042 -117.33149)
		(end 424.560492 -117.12194)
		(width 0.089408)
		(layer "In9.Cu")
		(net "BMC_DEBUG_EN_N")
	)
	(segment
		(start 489.634022 -32.100774)
		(end 489.634022 -33.655254)
		(width 0.089408)
		(layer "In9.Cu")
		(net "BMC_DEBUG_EN_N")
	)
	(segment
		(start 487.053636 -56.562498)
		(end 487.053636 -58.234834)
		(width 0.089408)
		(layer "In9.Cu")
		(net "BMC_DEBUG_EN_N")
	)
	(segment
		(start 485.089708 -60.198762)
		(end 482.206808 -60.198762)
		(width 0.089408)
		(layer "In9.Cu")
		(net "BMC_DEBUG_EN_N")
	)
	(segment
		(start 489.634022 -33.655254)
		(end 490.478826 -34.500058)
		(width 0.089408)
		(layer "In9.Cu")
		(net "BMC_DEBUG_EN_N")
	)
	(segment
		(start 444.671958 -139.739624)
		(end 444.290958 -139.358624)
		(width 0.089408)
		(layer "In9.Cu")
		(net "BMC_DEBUG_EN_N")
	)
	(segment
		(start 430.546002 -126.556516)
		(end 427.296326 -126.556516)
		(width 0.089408)
		(layer "In9.Cu")
		(net "BMC_DEBUG_EN_N")
	)
	(segment
		(start 482.206808 -60.198762)
		(end 481.718366 -59.71032)
		(width 0.089408)
		(layer "In9.Cu")
		(net "BMC_DEBUG_EN_N")
	)
	(segment
		(start 425.088812 -123.622054)
		(end 425.088812 -121.252488)
		(width 0.089408)
		(layer "In9.Cu")
		(net "BMC_DEBUG_EN_N")
	)
	(segment
		(start 424.615356 -127.743712)
		(end 423.781474 -126.90983)
		(width 0.089408)
		(layer "In9.Cu")
		(net "BMC_DEBUG_EN_N")
	)
	(segment
		(start 488.703874 -42.441876)
		(end 488.703874 -46.728126)
		(width 0.089408)
		(layer "In9.Cu")
		(net "BMC_DEBUG_EN_N")
	)
	(segment
		(start 488.964224 -42.181526)
		(end 488.703874 -42.441876)
		(width 0.089408)
		(layer "In9.Cu")
		(net "BMC_DEBUG_EN_N")
	)
	(segment
		(start 488.059984 -52.744878)
		(end 488.059984 -55.55615)
		(width 0.089408)
		(layer "In9.Cu")
		(net "BMC_DEBUG_EN_N")
	)
	(segment
		(start 490.478826 -35.95497)
		(end 490.258608 -36.175188)
		(width 0.089408)
		(layer "In9.Cu")
		(net "BMC_DEBUG_EN_N")
	)
	(segment
		(start 441.325 -136.822434)
		(end 441.325 -133.025896)
		(width 0.089408)
		(layer "In9.Cu")
		(net "BMC_DEBUG_EN_N")
	)
	(segment
		(start 424.770042 -119.664988)
		(end 424.770042 -117.33149)
		(width 0.089408)
		(layer "In9.Cu")
		(net "BMC_DEBUG_EN_N")
	)
	(segment
		(start 424.560492 -114.848132)
		(end 424.959272 -114.449352)
		(width 0.089408)
		(layer "In9.Cu")
		(net "BMC_DEBUG_EN_N")
	)
	(segment
		(start 425.088812 -121.252488)
		(end 424.355006 -120.518682)
		(width 0.089408)
		(layer "In9.Cu")
		(net "BMC_DEBUG_EN_N")
	)
	(segment
		(start 490.679994 -41.856406)
		(end 490.354874 -42.181526)
		(width 0.089408)
		(layer "In9.Cu")
		(net "BMC_DEBUG_EN_N")
	)
	(segment
		(start 489.80598 -50.998882)
		(end 488.059984 -52.744878)
		(width 0.089408)
		(layer "In9.Cu")
		(net "BMC_DEBUG_EN_N")
	)
	(segment
		(start 443.86119 -139.358624)
		(end 441.325 -136.822434)
		(width 0.089408)
		(layer "In9.Cu")
		(net "BMC_DEBUG_EN_N")
	)
	(segment
		(start 427.296326 -126.556516)
		(end 426.10913 -127.743712)
		(width 0.089408)
		(layer "In9.Cu")
		(net "BMC_DEBUG_EN_N")
	)
	(segment
		(start 467.68004 -39.06012)
		(end 467.087458 -39.06012)
		(width 0.089408)
		(layer "In11.Cu")
		(net "BMC_DEBUG_EN_N")
	)
	(segment
		(start 465.723986 -37.726112)
		(end 464.600798 -37.726112)
		(width 0.089408)
		(layer "In11.Cu")
		(net "BMC_DEBUG_EN_N")
	)
	(segment
		(start 466.454998 -38.457124)
		(end 465.723986 -37.726112)
		(width 0.089408)
		(layer "In11.Cu")
		(net "BMC_DEBUG_EN_N")
	)
	(segment
		(start 470.41308 -34.94278)
		(end 470.41308 -37.81298)
		(width 0.089408)
		(layer "In11.Cu")
		(net "BMC_DEBUG_EN_N")
	)
	(segment
		(start 471.27922 -34.4043)
		(end 470.95156 -34.4043)
		(width 0.089408)
		(layer "In11.Cu")
		(net "BMC_DEBUG_EN_N")
	)
	(segment
		(start 470.41308 -37.81298)
		(end 469.91778 -38.30828)
		(width 0.089408)
		(layer "In11.Cu")
		(net "BMC_DEBUG_EN_N")
	)
	(segment
		(start 468.43188 -38.30828)
		(end 467.68004 -39.06012)
		(width 0.089408)
		(layer "In11.Cu")
		(net "BMC_DEBUG_EN_N")
	)
	(segment
		(start 471.560652 -34.122868)
		(end 471.27922 -34.4043)
		(width 0.089408)
		(layer "In11.Cu")
		(net "BMC_DEBUG_EN_N")
	)
	(segment
		(start 471.560652 -33.63722)
		(end 471.560652 -34.122868)
		(width 0.089408)
		(layer "In11.Cu")
		(net "BMC_DEBUG_EN_N")
	)
	(segment
		(start 469.91778 -38.30828)
		(end 468.43188 -38.30828)
		(width 0.089408)
		(layer "In11.Cu")
		(net "BMC_DEBUG_EN_N")
	)
	(segment
		(start 464.600798 -37.726112)
		(end 464.321906 -37.44722)
		(width 0.089408)
		(layer "In11.Cu")
		(net "BMC_DEBUG_EN_N")
	)
	(segment
		(start 470.94521 -33.304734)
		(end 471.228166 -33.304734)
		(width 0.089408)
		(layer "In11.Cu")
		(net "BMC_DEBUG_EN_N")
	)
	(segment
		(start 470.95156 -34.4043)
		(end 470.41308 -34.94278)
		(width 0.089408)
		(layer "In11.Cu")
		(net "BMC_DEBUG_EN_N")
	)
	(segment
		(start 459.83144 -37.93236)
		(end 457.58608 -37.93236)
		(width 0.089408)
		(layer "In11.Cu")
		(net "BMC_DEBUG_EN_N")
	)
	(segment
		(start 457.58608 -37.93236)
		(end 457.30668 -37.65296)
		(width 0.089408)
		(layer "In11.Cu")
		(net "BMC_DEBUG_EN_N")
	)
	(segment
		(start 464.321906 -37.44722)
		(end 460.31658 -37.44722)
		(width 0.089408)
		(layer "In11.Cu")
		(net "BMC_DEBUG_EN_N")
	)
	(segment
		(start 471.228166 -33.304734)
		(end 471.560652 -33.63722)
		(width 0.089408)
		(layer "In11.Cu")
		(net "BMC_DEBUG_EN_N")
	)
	(segment
		(start 460.31658 -37.44722)
		(end 459.83144 -37.93236)
		(width 0.089408)
		(layer "In11.Cu")
		(net "BMC_DEBUG_EN_N")
	)
	(segment
		(start 466.484462 -38.457124)
		(end 466.454998 -38.457124)
		(width 0.089408)
		(layer "In11.Cu")
		(net "BMC_DEBUG_EN_N")
	)
	(segment
		(start 467.087458 -39.06012)
		(end 466.484462 -38.457124)
		(width 0.089408)
		(layer "In11.Cu")
		(net "BMC_DEBUG_EN_N")
	)
	(segment
		(start 450.1642 -150.36546)
		(end 451.71487 -150.36546)
		(width 0.10795)
		(layer "F.Cu")
		(net "PD_GTL2014_6_B2")
	)
	(segment
		(start 451.71487 -150.36546)
		(end 451.774306 -150.424896)
		(width 0.10795)
		(layer "F.Cu")
		(net "PD_GTL2014_6_B2")
	)
	(segment
		(start 451.774306 -150.424896)
		(end 451.78345 -150.424896)
		(width 0.10795)
		(layer "F.Cu")
		(net "PD_GTL2014_6_B2")
	)
	(via
		(at 452.5264 -150.5204)
		(size 0.6604)
		(drill 0.3302)
		(layers "F.Cu" "B.Cu")
		(net "PD_GTL2014_6_B2")
	)
	(via
		(at 451.78345 -150.424896)
		(size 0.508)
		(drill 0.254)
		(layers "F.Cu" "B.Cu")
		(net "PD_GTL2014_6_B2")
	)
	(segment
		(start 450.215 -150.1394)
		(end 451.497954 -150.1394)
		(width 0.10795)
		(layer "B.Cu")
		(net "PD_GTL2014_6_B2")
	)
	(segment
		(start 451.497954 -150.1394)
		(end 451.78345 -150.424896)
		(width 0.10795)
		(layer "B.Cu")
		(net "PD_GTL2014_6_B2")
	)
	(segment
		(start 452.5264 -150.5204)
		(end 452.4502 -150.5204)
		(width 0.10795)
		(layer "B.Cu")
		(net "PD_GTL2014_6_B2")
	)
	(segment
		(start 452.4502 -150.5204)
		(end 452.354696 -150.424896)
		(width 0.10795)
		(layer "B.Cu")
		(net "PD_GTL2014_6_B2")
	)
	(segment
		(start 452.354696 -150.424896)
		(end 451.78345 -150.424896)
		(width 0.10795)
		(layer "B.Cu")
		(net "PD_GTL2014_6_B2")
	)
	(segment
		(start 451.9676 -147.955)
		(end 451.9168 -147.955)
		(width 0.10795)
		(layer "F.Cu")
		(net "PD_GTL2014_6_B0")
	)
	(segment
		(start 451.45706 -148.41474)
		(end 450.1642 -148.41474)
		(width 0.10795)
		(layer "F.Cu")
		(net "PD_GTL2014_6_B0")
	)
	(segment
		(start 451.9168 -147.955)
		(end 451.45706 -148.41474)
		(width 0.10795)
		(layer "F.Cu")
		(net "PD_GTL2014_6_B0")
	)
	(via
		(at 451.2056 -148.3106)
		(size 0.6604)
		(drill 0.3302)
		(layers "F.Cu" "B.Cu")
		(net "PD_GTL2014_6_B0")
	)
	(via
		(at 451.9676 -147.955)
		(size 0.508)
		(drill 0.254)
		(layers "F.Cu" "B.Cu")
		(net "PD_GTL2014_6_B0")
	)
	(segment
		(start 451.612 -148.3106)
		(end 451.9676 -147.955)
		(width 0.10795)
		(layer "B.Cu")
		(net "PD_GTL2014_6_B0")
	)
	(segment
		(start 451.2056 -148.3106)
		(end 451.2056 -148.209)
		(width 0.10795)
		(layer "B.Cu")
		(net "PD_GTL2014_6_B0")
	)
	(segment
		(start 450.7992 -147.8026)
		(end 450.215 -147.8026)
		(width 0.10795)
		(layer "B.Cu")
		(net "PD_GTL2014_6_B0")
	)
	(segment
		(start 451.2056 -148.209)
		(end 450.7992 -147.8026)
		(width 0.10795)
		(layer "B.Cu")
		(net "PD_GTL2014_6_B0")
	)
	(segment
		(start 451.2056 -148.3106)
		(end 451.612 -148.3106)
		(width 0.10795)
		(layer "B.Cu")
		(net "PD_GTL2014_6_B0")
	)
	(segment
		(start 453.1868 -150.621746)
		(end 453.567546 -150.241)
		(width 0.10795)
		(layer "F.Cu")
		(net "CPU_XDP_PRESENT_N")
	)
	(segment
		(start 125.080268 -69.772784)
		(end 125.651768 -69.772784)
		(width 0.1016)
		(layer "F.Cu")
		(net "CPU_XDP_PRESENT_N")
	)
	(segment
		(start 453.1868 -150.856696)
		(end 453.1868 -150.621746)
		(width 0.10795)
		(layer "F.Cu")
		(net "CPU_XDP_PRESENT_N")
	)
	(segment
		(start 453.567546 -150.241)
		(end 454.025 -150.241)
		(width 0.10795)
		(layer "F.Cu")
		(net "CPU_XDP_PRESENT_N")
	)
	(segment
		(start 290.0807 -69.772784)
		(end 290.6522 -69.772784)
		(width 0.10795)
		(layer "F.Cu")
		(net "CPU_XDP_PRESENT_N")
	)
	(via
		(at 125.651768 -69.772784)
		(size 0.508)
		(drill 0.254)
		(layers "F.Cu" "B.Cu")
		(net "CPU_XDP_PRESENT_N")
	)
	(via
		(at 306.963826 -58.381138)
		(size 0.508)
		(drill 0.254)
		(layers "F.Cu" "B.Cu")
		(net "CPU_XDP_PRESENT_N")
	)
	(via
		(at 290.6522 -69.772784)
		(size 0.508)
		(drill 0.254)
		(layers "F.Cu" "B.Cu")
		(net "CPU_XDP_PRESENT_N")
	)
	(via
		(at 452.9328 -151.7396)
		(size 0.6604)
		(drill 0.3302)
		(layers "F.Cu" "B.Cu")
		(net "CPU_XDP_PRESENT_N")
	)
	(via
		(at 157.1752 -25.4254)
		(size 0.508)
		(drill 0.254)
		(layers "F.Cu" "B.Cu")
		(net "CPU_XDP_PRESENT_N")
	)
	(via
		(at 354.891594 -57.414414)
		(size 0.508)
		(drill 0.254)
		(layers "F.Cu" "B.Cu")
		(net "CPU_XDP_PRESENT_N")
	)
	(via
		(at 453.1868 -150.856696)
		(size 0.508)
		(drill 0.254)
		(layers "F.Cu" "B.Cu")
		(net "CPU_XDP_PRESENT_N")
	)
	(via
		(at 336.807556 -88.323928)
		(size 0.508)
		(drill 0.254)
		(layers "F.Cu" "B.Cu")
		(net "CPU_XDP_PRESENT_N")
	)
	(via
		(at 191.77 -4.38277)
		(size 0.508)
		(drill 0.254)
		(layers "F.Cu" "B.Cu")
		(net "CPU_XDP_PRESENT_N")
	)
	(segment
		(start 448.945 -150.7744)
		(end 448.314064 -150.143464)
		(width 0.10795)
		(layer "B.Cu")
		(net "CPU_XDP_PRESENT_N")
	)
	(segment
		(start 446.479168 -147.981162)
		(end 446.803018 -148.305012)
		(width 0.10795)
		(layer "B.Cu")
		(net "CPU_XDP_PRESENT_N")
	)
	(segment
		(start 453.1868 -150.856696)
		(end 453.1868 -151.4856)
		(width 0.10795)
		(layer "B.Cu")
		(net "CPU_XDP_PRESENT_N")
	)
	(segment
		(start 453.1868 -151.4856)
		(end 452.9328 -151.7396)
		(width 0.10795)
		(layer "B.Cu")
		(net "CPU_XDP_PRESENT_N")
	)
	(segment
		(start 446.479168 -147.693634)
		(end 446.479168 -147.981162)
		(width 0.10795)
		(layer "B.Cu")
		(net "CPU_XDP_PRESENT_N")
	)
	(segment
		(start 452.9328 -151.7396)
		(end 452.4248 -151.7396)
		(width 0.10795)
		(layer "B.Cu")
		(net "CPU_XDP_PRESENT_N")
	)
	(segment
		(start 448.314064 -149.4917)
		(end 447.855086 -149.032722)
		(width 0.10795)
		(layer "B.Cu")
		(net "CPU_XDP_PRESENT_N")
	)
	(segment
		(start 451.4596 -150.7744)
		(end 448.945 -150.7744)
		(width 0.10795)
		(layer "B.Cu")
		(net "CPU_XDP_PRESENT_N")
	)
	(segment
		(start 446.803018 -148.305012)
		(end 446.803018 -149.032722)
		(width 0.10795)
		(layer "B.Cu")
		(net "CPU_XDP_PRESENT_N")
	)
	(segment
		(start 452.4248 -151.7396)
		(end 451.4596 -150.7744)
		(width 0.10795)
		(layer "B.Cu")
		(net "CPU_XDP_PRESENT_N")
	)
	(segment
		(start 448.314064 -150.143464)
		(end 448.314064 -149.4917)
		(width 0.10795)
		(layer "B.Cu")
		(net "CPU_XDP_PRESENT_N")
	)
	(segment
		(start 447.855086 -149.032722)
		(end 446.803018 -149.032722)
		(width 0.10795)
		(layer "B.Cu")
		(net "CPU_XDP_PRESENT_N")
	)
	(segment
		(start 161.3916 -5.8928)
		(end 163.195 -5.8928)
		(width 0.089408)
		(layer "In2.Cu")
		(net "CPU_XDP_PRESENT_N")
	)
	(segment
		(start 157.1752 -25.4254)
		(end 158.44012 -24.16048)
		(width 0.089408)
		(layer "In2.Cu")
		(net "CPU_XDP_PRESENT_N")
	)
	(segment
		(start 174.164752 -5.8674)
		(end 174.487332 -6.18998)
		(width 0.089408)
		(layer "In2.Cu")
		(net "CPU_XDP_PRESENT_N")
	)
	(segment
		(start 186.8932 -4.0386)
		(end 188.1124 -5.2578)
		(width 0.089408)
		(layer "In2.Cu")
		(net "CPU_XDP_PRESENT_N")
	)
	(segment
		(start 174.487332 -6.18998)
		(end 178.82362 -6.18998)
		(width 0.089408)
		(layer "In2.Cu")
		(net "CPU_XDP_PRESENT_N")
	)
	(segment
		(start 173.023022 -5.8674)
		(end 174.164752 -5.8674)
		(width 0.089408)
		(layer "In2.Cu")
		(net "CPU_XDP_PRESENT_N")
	)
	(segment
		(start 170.672506 -8.217916)
		(end 173.023022 -5.8674)
		(width 0.089408)
		(layer "In2.Cu")
		(net "CPU_XDP_PRESENT_N")
	)
	(segment
		(start 164.383466 -7.081266)
		(end 167.839644 -7.081266)
		(width 0.089408)
		(layer "In2.Cu")
		(net "CPU_XDP_PRESENT_N")
	)
	(segment
		(start 167.839644 -7.081266)
		(end 168.976294 -8.217916)
		(width 0.089408)
		(layer "In2.Cu")
		(net "CPU_XDP_PRESENT_N")
	)
	(segment
		(start 190.905892 -4.38277)
		(end 191.77 -4.38277)
		(width 0.089408)
		(layer "In2.Cu")
		(net "CPU_XDP_PRESENT_N")
	)
	(segment
		(start 168.976294 -8.217916)
		(end 170.672506 -8.217916)
		(width 0.089408)
		(layer "In2.Cu")
		(net "CPU_XDP_PRESENT_N")
	)
	(segment
		(start 163.195 -5.8928)
		(end 164.383466 -7.081266)
		(width 0.089408)
		(layer "In2.Cu")
		(net "CPU_XDP_PRESENT_N")
	)
	(segment
		(start 158.44012 -24.16048)
		(end 158.44012 -8.84428)
		(width 0.089408)
		(layer "In2.Cu")
		(net "CPU_XDP_PRESENT_N")
	)
	(segment
		(start 158.44012 -8.84428)
		(end 161.3916 -5.8928)
		(width 0.089408)
		(layer "In2.Cu")
		(net "CPU_XDP_PRESENT_N")
	)
	(segment
		(start 190.030862 -5.2578)
		(end 190.905892 -4.38277)
		(width 0.089408)
		(layer "In2.Cu")
		(net "CPU_XDP_PRESENT_N")
	)
	(segment
		(start 178.82362 -6.18998)
		(end 180.975 -4.0386)
		(width 0.089408)
		(layer "In2.Cu")
		(net "CPU_XDP_PRESENT_N")
	)
	(segment
		(start 180.975 -4.0386)
		(end 186.8932 -4.0386)
		(width 0.089408)
		(layer "In2.Cu")
		(net "CPU_XDP_PRESENT_N")
	)
	(segment
		(start 188.1124 -5.2578)
		(end 190.030862 -5.2578)
		(width 0.089408)
		(layer "In2.Cu")
		(net "CPU_XDP_PRESENT_N")
	)
	(segment
		(start 406.483566 -155.880054)
		(end 405.893016 -155.289504)
		(width 0.089408)
		(layer "In4.Cu")
		(net "CPU_XDP_PRESENT_N")
	)
	(segment
		(start 396.410942 -147.009612)
		(end 392.82116 -147.009612)
		(width 0.089408)
		(layer "In4.Cu")
		(net "CPU_XDP_PRESENT_N")
	)
	(segment
		(start 336.491072 -88.323928)
		(end 336.807556 -88.323928)
		(width 0.089408)
		(layer "In4.Cu")
		(net "CPU_XDP_PRESENT_N")
	)
	(segment
		(start 371.982238 -143.746728)
		(end 371.728492 -144.000474)
		(width 0.089408)
		(layer "In4.Cu")
		(net "CPU_XDP_PRESENT_N")
	)
	(segment
		(start 195.026026 -1.925574)
		(end 193.0654 -3.8862)
		(width 0.089408)
		(layer "In4.Cu")
		(net "CPU_XDP_PRESENT_N")
	)
	(segment
		(start 408.906472 -154.10434)
		(end 407.639012 -155.3718)
		(width 0.089408)
		(layer "In4.Cu")
		(net "CPU_XDP_PRESENT_N")
	)
	(segment
		(start 266.723368 -1.881632)
		(end 266.518644 -2.086356)
		(width 0.089408)
		(layer "In4.Cu")
		(net "CPU_XDP_PRESENT_N")
	)
	(segment
		(start 266.518644 -4.710176)
		(end 266.286234 -4.942586)
		(width 0.089408)
		(layer "In4.Cu")
		(net "CPU_XDP_PRESENT_N")
	)
	(segment
		(start 298.577 -51.943)
		(end 313.299602 -37.220398)
		(width 0.089408)
		(layer "In4.Cu")
		(net "CPU_XDP_PRESENT_N")
	)
	(segment
		(start 446.848484 -152.766776)
		(end 446.510664 -153.104596)
		(width 0.089408)
		(layer "In4.Cu")
		(net "CPU_XDP_PRESENT_N")
	)
	(segment
		(start 430.94021 -156.139642)
		(end 429.626776 -157.453076)
		(width 0.089408)
		(layer "In4.Cu")
		(net "CPU_XDP_PRESENT_N")
	)
	(segment
		(start 405.68626 -149.604476)
		(end 403.870414 -147.78863)
		(width 0.089408)
		(layer "In4.Cu")
		(net "CPU_XDP_PRESENT_N")
	)
	(segment
		(start 361.769406 -142.345918)
		(end 360.354372 -142.345918)
		(width 0.089408)
		(layer "In4.Cu")
		(net "CPU_XDP_PRESENT_N")
	)
	(segment
		(start 320.548 -24.384)
		(end 320.0908 -23.9268)
		(width 0.089408)
		(layer "In4.Cu")
		(net "CPU_XDP_PRESENT_N")
	)
	(segment
		(start 297.942 -51.943)
		(end 298.577 -51.943)
		(width 0.089408)
		(layer "In4.Cu")
		(net "CPU_XDP_PRESENT_N")
	)
	(segment
		(start 294.724074 -54.906926)
		(end 295.105074 -54.906926)
		(width 0.089408)
		(layer "In4.Cu")
		(net "CPU_XDP_PRESENT_N")
	)
	(segment
		(start 396.458186 -147.03171)
		(end 396.43304 -147.03171)
		(width 0.089408)
		(layer "In4.Cu")
		(net "CPU_XDP_PRESENT_N")
	)
	(segment
		(start 352.09607 -140.105384)
		(end 348.54515 -140.105384)
		(width 0.089408)
		(layer "In4.Cu")
		(net "CPU_XDP_PRESENT_N")
	)
	(segment
		(start 323.069204 -24.746458)
		(end 322.706746 -24.384)
		(width 0.089408)
		(layer "In4.Cu")
		(net "CPU_XDP_PRESENT_N")
	)
	(segment
		(start 319.112646 -30.111446)
		(end 318.9478 -29.9466)
		(width 0.089408)
		(layer "In4.Cu")
		(net "CPU_XDP_PRESENT_N")
	)
	(segment
		(start 318.9478 -29.9466)
		(end 318.9478 -27.94)
		(width 0.089408)
		(layer "In4.Cu")
		(net "CPU_XDP_PRESENT_N")
	)
	(segment
		(start 296.926 -52.959)
		(end 297.942 -51.943)
		(width 0.089408)
		(layer "In4.Cu")
		(net "CPU_XDP_PRESENT_N")
	)
	(segment
		(start 396.43304 -147.03171)
		(end 396.410942 -147.009612)
		(width 0.089408)
		(layer "In4.Cu")
		(net "CPU_XDP_PRESENT_N")
	)
	(segment
		(start 452.329296 -151.7142)
		(end 449.9356 -151.7142)
		(width 0.089408)
		(layer "In4.Cu")
		(net "CPU_XDP_PRESENT_N")
	)
	(segment
		(start 363.519974 -144.000474)
		(end 362.52277 -143.00327)
		(width 0.089408)
		(layer "In4.Cu")
		(net "CPU_XDP_PRESENT_N")
	)
	(segment
		(start 338.697062 -136.144254)
		(end 337.28406 -134.731252)
		(width 0.089408)
		(layer "In4.Cu")
		(net "CPU_XDP_PRESENT_N")
	)
	(segment
		(start 409.727146 -154.10434)
		(end 408.906472 -154.10434)
		(width 0.089408)
		(layer "In4.Cu")
		(net "CPU_XDP_PRESENT_N")
	)
	(segment
		(start 296.037 -53.467)
		(end 296.545 -52.959)
		(width 0.089408)
		(layer "In4.Cu")
		(net "CPU_XDP_PRESENT_N")
	)
	(segment
		(start 449.9356 -151.7142)
		(end 448.883024 -152.766776)
		(width 0.089408)
		(layer "In4.Cu")
		(net "CPU_XDP_PRESENT_N")
	)
	(segment
		(start 411.345126 -155.72232)
		(end 409.727146 -154.10434)
		(width 0.089408)
		(layer "In4.Cu")
		(net "CPU_XDP_PRESENT_N")
	)
	(segment
		(start 295.105074 -54.906926)
		(end 295.402 -54.61)
		(width 0.089408)
		(layer "In4.Cu")
		(net "CPU_XDP_PRESENT_N")
	)
	(segment
		(start 290.6522 -69.772784)
		(end 291.0586 -69.366384)
		(width 0.089408)
		(layer "In4.Cu")
		(net "CPU_XDP_PRESENT_N")
	)
	(segment
		(start 295.402 -53.721)
		(end 295.656 -53.467)
		(width 0.089408)
		(layer "In4.Cu")
		(net "CPU_XDP_PRESENT_N")
	)
	(segment
		(start 332.057502 -110.616746)
		(end 332.047342 -110.606586)
		(width 0.089408)
		(layer "In4.Cu")
		(net "CPU_XDP_PRESENT_N")
	)
	(segment
		(start 319.9638 -33.1216)
		(end 319.9638 -30.5308)
		(width 0.089408)
		(layer "In4.Cu")
		(net "CPU_XDP_PRESENT_N")
	)
	(segment
		(start 332.259178 -112.687608)
		(end 332.259178 -111.033052)
		(width 0.089408)
		(layer "In4.Cu")
		(net "CPU_XDP_PRESENT_N")
	)
	(segment
		(start 291.0586 -57.278524)
		(end 291.489384 -56.84774)
		(width 0.089408)
		(layer "In4.Cu")
		(net "CPU_XDP_PRESENT_N")
	)
	(segment
		(start 316.899798 -35.4076)
		(end 317.6778 -35.4076)
		(width 0.089408)
		(layer "In4.Cu")
		(net "CPU_XDP_PRESENT_N")
	)
	(segment
		(start 348.54515 -140.105384)
		(end 348.325694 -140.32484)
		(width 0.089408)
		(layer "In4.Cu")
		(net "CPU_XDP_PRESENT_N")
	)
	(segment
		(start 431.844704 -154.140662)
		(end 431.133758 -154.851608)
		(width 0.089408)
		(layer "In4.Cu")
		(net "CPU_XDP_PRESENT_N")
	)
	(segment
		(start 407.169112 -155.880054)
		(end 406.483566 -155.880054)
		(width 0.089408)
		(layer "In4.Cu")
		(net "CPU_XDP_PRESENT_N")
	)
	(segment
		(start 361.837224 -142.413736)
		(end 361.769406 -142.345918)
		(width 0.089408)
		(layer "In4.Cu")
		(net "CPU_XDP_PRESENT_N")
	)
	(segment
		(start 319.2018 -3.0988)
		(end 319.2018 -2.0574)
		(width 0.089408)
		(layer "In4.Cu")
		(net "CPU_XDP_PRESENT_N")
	)
	(segment
		(start 265.231118 -4.942586)
		(end 264.814304 -5.3594)
		(width 0.089408)
		(layer "In4.Cu")
		(net "CPU_XDP_PRESENT_N")
	)
	(segment
		(start 332.047342 -110.606586)
		(end 332.047342 -108.126276)
		(width 0.089408)
		(layer "In4.Cu")
		(net "CPU_XDP_PRESENT_N")
	)
	(segment
		(start 430.94021 -155.052776)
		(end 430.94021 -156.139642)
		(width 0.089408)
		(layer "In4.Cu")
		(net "CPU_XDP_PRESENT_N")
	)
	(segment
		(start 262.6868 -5.3594)
		(end 259.1816 -1.8542)
		(width 0.089408)
		(layer "In4.Cu")
		(net "CPU_XDP_PRESENT_N")
	)
	(segment
		(start 293.37 -55.88)
		(end 293.878 -55.372)
		(width 0.089408)
		(layer "In4.Cu")
		(net "CPU_XDP_PRESENT_N")
	)
	(segment
		(start 337.28406 -125.703584)
		(end 333.463646 -121.88317)
		(width 0.089408)
		(layer "In4.Cu")
		(net "CPU_XDP_PRESENT_N")
	)
	(segment
		(start 293.878 -55.372)
		(end 294.259 -55.372)
		(width 0.089408)
		(layer "In4.Cu")
		(net "CPU_XDP_PRESENT_N")
	)
	(segment
		(start 192.26657 -3.8862)
		(end 191.77 -4.38277)
		(width 0.089408)
		(layer "In4.Cu")
		(net "CPU_XDP_PRESENT_N")
	)
	(segment
		(start 397.215106 -147.78863)
		(end 396.458186 -147.03171)
		(width 0.089408)
		(layer "In4.Cu")
		(net "CPU_XDP_PRESENT_N")
	)
	(segment
		(start 320.0908 -23.9268)
		(end 320.0908 -3.9878)
		(width 0.089408)
		(layer "In4.Cu")
		(net "CPU_XDP_PRESENT_N")
	)
	(segment
		(start 291.489384 -56.84774)
		(end 291.627052 -56.84774)
		(width 0.089408)
		(layer "In4.Cu")
		(net "CPU_XDP_PRESENT_N")
	)
	(segment
		(start 332.259178 -111.033052)
		(end 332.057502 -110.831376)
		(width 0.089408)
		(layer "In4.Cu")
		(net "CPU_XDP_PRESENT_N")
	)
	(segment
		(start 362.52277 -143.00327)
		(end 362.52277 -142.758922)
		(width 0.089408)
		(layer "In4.Cu")
		(net "CPU_XDP_PRESENT_N")
	)
	(segment
		(start 431.133758 -154.859228)
		(end 430.94021 -155.052776)
		(width 0.089408)
		(layer "In4.Cu")
		(net "CPU_XDP_PRESENT_N")
	)
	(segment
		(start 446.271396 -153.343864)
		(end 445.06896 -154.5463)
		(width 0.089408)
		(layer "In4.Cu")
		(net "CPU_XDP_PRESENT_N")
	)
	(segment
		(start 323.118226 -27.0002)
		(end 323.361304 -26.757122)
		(width 0.089408)
		(layer "In4.Cu")
		(net "CPU_XDP_PRESENT_N")
	)
	(segment
		(start 333.463646 -113.892076)
		(end 332.259178 -112.687608)
		(width 0.089408)
		(layer "In4.Cu")
		(net "CPU_XDP_PRESENT_N")
	)
	(segment
		(start 292.957758 -55.88)
		(end 293.37 -55.88)
		(width 0.089408)
		(layer "In4.Cu")
		(net "CPU_XDP_PRESENT_N")
	)
	(segment
		(start 193.0654 -3.8862)
		(end 192.26657 -3.8862)
		(width 0.089408)
		(layer "In4.Cu")
		(net "CPU_XDP_PRESENT_N")
	)
	(segment
		(start 337.28406 -134.731252)
		(end 337.28406 -125.703584)
		(width 0.089408)
		(layer "In4.Cu")
		(net "CPU_XDP_PRESENT_N")
	)
	(segment
		(start 338.697062 -136.883648)
		(end 338.697062 -136.144254)
		(width 0.089408)
		(layer "In4.Cu")
		(net "CPU_XDP_PRESENT_N")
	)
	(segment
		(start 319.6844 -27.2034)
		(end 320.6242 -27.2034)
		(width 0.089408)
		(layer "In4.Cu")
		(net "CPU_XDP_PRESENT_N")
	)
	(segment
		(start 330.907898 -97.286064)
		(end 330.907644 -97.28581)
		(width 0.089408)
		(layer "In4.Cu")
		(net "CPU_XDP_PRESENT_N")
	)
	(segment
		(start 264.814304 -5.3594)
		(end 262.6868 -5.3594)
		(width 0.089408)
		(layer "In4.Cu")
		(net "CPU_XDP_PRESENT_N")
	)
	(segment
		(start 317.6778 -35.4076)
		(end 319.9638 -33.1216)
		(width 0.089408)
		(layer "In4.Cu")
		(net "CPU_XDP_PRESENT_N")
	)
	(segment
		(start 266.286234 -4.942586)
		(end 265.231118 -4.942586)
		(width 0.089408)
		(layer "In4.Cu")
		(net "CPU_XDP_PRESENT_N")
	)
	(segment
		(start 332.047342 -108.126276)
		(end 330.907898 -106.986832)
		(width 0.089408)
		(layer "In4.Cu")
		(net "CPU_XDP_PRESENT_N")
	)
	(segment
		(start 429.626776 -157.453076)
		(end 412.689548 -157.453076)
		(width 0.089408)
		(layer "In4.Cu")
		(net "CPU_XDP_PRESENT_N")
	)
	(segment
		(start 323.361304 -26.757122)
		(end 323.361304 -25.724104)
		(width 0.089408)
		(layer "In4.Cu")
		(net "CPU_XDP_PRESENT_N")
	)
	(segment
		(start 333.463646 -121.88317)
		(end 333.463646 -113.892076)
		(width 0.089408)
		(layer "In4.Cu")
		(net "CPU_XDP_PRESENT_N")
	)
	(segment
		(start 319.9638 -30.5308)
		(end 319.544446 -30.111446)
		(width 0.089408)
		(layer "In4.Cu")
		(net "CPU_XDP_PRESENT_N")
	)
	(segment
		(start 373.46636 -143.746728)
		(end 371.982238 -143.746728)
		(width 0.089408)
		(layer "In4.Cu")
		(net "CPU_XDP_PRESENT_N")
	)
	(segment
		(start 315.087 -37.220398)
		(end 316.899798 -35.4076)
		(width 0.089408)
		(layer "In4.Cu")
		(net "CPU_XDP_PRESENT_N")
	)
	(segment
		(start 330.907898 -93.907102)
		(end 336.491072 -88.323928)
		(width 0.089408)
		(layer "In4.Cu")
		(net "CPU_XDP_PRESENT_N")
	)
	(segment
		(start 332.057502 -110.831376)
		(end 332.057502 -110.616746)
		(width 0.089408)
		(layer "In4.Cu")
		(net "CPU_XDP_PRESENT_N")
	)
	(segment
		(start 389.815578 -144.00403)
		(end 373.723662 -144.00403)
		(width 0.089408)
		(layer "In4.Cu")
		(net "CPU_XDP_PRESENT_N")
	)
	(segment
		(start 405.893016 -155.289504)
		(end 405.893016 -152.347676)
		(width 0.089408)
		(layer "In4.Cu")
		(net "CPU_XDP_PRESENT_N")
	)
	(segment
		(start 195.707 -1.8542)
		(end 195.635626 -1.925574)
		(width 0.089408)
		(layer "In4.Cu")
		(net "CPU_XDP_PRESENT_N")
	)
	(segment
		(start 322.706746 -24.384)
		(end 320.548 -24.384)
		(width 0.089408)
		(layer "In4.Cu")
		(net "CPU_XDP_PRESENT_N")
	)
	(segment
		(start 453.1868 -150.856696)
		(end 452.329296 -151.7142)
		(width 0.089408)
		(layer "In4.Cu")
		(net "CPU_XDP_PRESENT_N")
	)
	(segment
		(start 319.2018 -2.0574)
		(end 319.026032 -1.881632)
		(width 0.089408)
		(layer "In4.Cu")
		(net "CPU_XDP_PRESENT_N")
	)
	(segment
		(start 442.510926 -154.5463)
		(end 442.105288 -154.140662)
		(width 0.089408)
		(layer "In4.Cu")
		(net "CPU_XDP_PRESENT_N")
	)
	(segment
		(start 448.883024 -152.766776)
		(end 446.848484 -152.766776)
		(width 0.089408)
		(layer "In4.Cu")
		(net "CPU_XDP_PRESENT_N")
	)
	(segment
		(start 371.728492 -144.000474)
		(end 363.519974 -144.000474)
		(width 0.089408)
		(layer "In4.Cu")
		(net "CPU_XDP_PRESENT_N")
	)
	(segment
		(start 291.0586 -69.366384)
		(end 291.0586 -57.278524)
		(width 0.089408)
		(layer "In4.Cu")
		(net "CPU_XDP_PRESENT_N")
	)
	(segment
		(start 266.518644 -2.086356)
		(end 266.518644 -4.710176)
		(width 0.089408)
		(layer "In4.Cu")
		(net "CPU_XDP_PRESENT_N")
	)
	(segment
		(start 446.271396 -153.339038)
		(end 446.271396 -153.343864)
		(width 0.089408)
		(layer "In4.Cu")
		(net "CPU_XDP_PRESENT_N")
	)
	(segment
		(start 319.026032 -1.881632)
		(end 266.723368 -1.881632)
		(width 0.089408)
		(layer "In4.Cu")
		(net "CPU_XDP_PRESENT_N")
	)
	(segment
		(start 442.105288 -154.140662)
		(end 431.844704 -154.140662)
		(width 0.089408)
		(layer "In4.Cu")
		(net "CPU_XDP_PRESENT_N")
	)
	(segment
		(start 339.894418 -138.081004)
		(end 338.697062 -136.883648)
		(width 0.089408)
		(layer "In4.Cu")
		(net "CPU_XDP_PRESENT_N")
	)
	(segment
		(start 330.907898 -94.943168)
		(end 330.907898 -93.907102)
		(width 0.089408)
		(layer "In4.Cu")
		(net "CPU_XDP_PRESENT_N")
	)
	(segment
		(start 319.544446 -30.111446)
		(end 319.112646 -30.111446)
		(width 0.089408)
		(layer "In4.Cu")
		(net "CPU_XDP_PRESENT_N")
	)
	(segment
		(start 195.635626 -1.925574)
		(end 195.026026 -1.925574)
		(width 0.089408)
		(layer "In4.Cu")
		(net "CPU_XDP_PRESENT_N")
	)
	(segment
		(start 360.354372 -142.345918)
		(end 358.769412 -140.760958)
		(width 0.089408)
		(layer "In4.Cu")
		(net "CPU_XDP_PRESENT_N")
	)
	(segment
		(start 446.505838 -153.104596)
		(end 446.271396 -153.339038)
		(width 0.089408)
		(layer "In4.Cu")
		(net "CPU_XDP_PRESENT_N")
	)
	(segment
		(start 313.299602 -37.220398)
		(end 315.087 -37.220398)
		(width 0.089408)
		(layer "In4.Cu")
		(net "CPU_XDP_PRESENT_N")
	)
	(segment
		(start 411.345126 -156.108654)
		(end 411.345126 -155.72232)
		(width 0.089408)
		(layer "In4.Cu")
		(net "CPU_XDP_PRESENT_N")
	)
	(segment
		(start 292.449758 -56.388)
		(end 292.957758 -55.88)
		(width 0.089408)
		(layer "In4.Cu")
		(net "CPU_XDP_PRESENT_N")
	)
	(segment
		(start 352.751644 -140.760958)
		(end 352.09607 -140.105384)
		(width 0.089408)
		(layer "In4.Cu")
		(net "CPU_XDP_PRESENT_N")
	)
	(segment
		(start 291.627052 -56.84774)
		(end 292.086792 -56.388)
		(width 0.089408)
		(layer "In4.Cu")
		(net "CPU_XDP_PRESENT_N")
	)
	(segment
		(start 405.893016 -152.347676)
		(end 405.68626 -152.14092)
		(width 0.089408)
		(layer "In4.Cu")
		(net "CPU_XDP_PRESENT_N")
	)
	(segment
		(start 373.723662 -144.00403)
		(end 373.46636 -143.746728)
		(width 0.089408)
		(layer "In4.Cu")
		(net "CPU_XDP_PRESENT_N")
	)
	(segment
		(start 320.0908 -3.9878)
		(end 319.2018 -3.0988)
		(width 0.089408)
		(layer "In4.Cu")
		(net "CPU_XDP_PRESENT_N")
	)
	(segment
		(start 412.689548 -157.453076)
		(end 411.345126 -156.108654)
		(width 0.089408)
		(layer "In4.Cu")
		(net "CPU_XDP_PRESENT_N")
	)
	(segment
		(start 323.069204 -25.432004)
		(end 323.069204 -24.746458)
		(width 0.089408)
		(layer "In4.Cu")
		(net "CPU_XDP_PRESENT_N")
	)
	(segment
		(start 431.133758 -154.851608)
		(end 431.133758 -154.859228)
		(width 0.089408)
		(layer "In4.Cu")
		(net "CPU_XDP_PRESENT_N")
	)
	(segment
		(start 296.545 -52.959)
		(end 296.926 -52.959)
		(width 0.089408)
		(layer "In4.Cu")
		(net "CPU_XDP_PRESENT_N")
	)
	(segment
		(start 295.656 -53.467)
		(end 296.037 -53.467)
		(width 0.089408)
		(layer "In4.Cu")
		(net "CPU_XDP_PRESENT_N")
	)
	(segment
		(start 295.402 -54.61)
		(end 295.402 -53.721)
		(width 0.089408)
		(layer "In4.Cu")
		(net "CPU_XDP_PRESENT_N")
	)
	(segment
		(start 344.656664 -140.32484)
		(end 342.412828 -138.081004)
		(width 0.089408)
		(layer "In4.Cu")
		(net "CPU_XDP_PRESENT_N")
	)
	(segment
		(start 320.6242 -27.2034)
		(end 320.8274 -27.0002)
		(width 0.089408)
		(layer "In4.Cu")
		(net "CPU_XDP_PRESENT_N")
	)
	(segment
		(start 358.769412 -140.760958)
		(end 352.751644 -140.760958)
		(width 0.089408)
		(layer "In4.Cu")
		(net "CPU_XDP_PRESENT_N")
	)
	(segment
		(start 330.907644 -97.28581)
		(end 330.907644 -94.943422)
		(width 0.089408)
		(layer "In4.Cu")
		(net "CPU_XDP_PRESENT_N")
	)
	(segment
		(start 342.412828 -138.081004)
		(end 339.894418 -138.081004)
		(width 0.089408)
		(layer "In4.Cu")
		(net "CPU_XDP_PRESENT_N")
	)
	(segment
		(start 318.9478 -27.94)
		(end 319.6844 -27.2034)
		(width 0.089408)
		(layer "In4.Cu")
		(net "CPU_XDP_PRESENT_N")
	)
	(segment
		(start 407.639012 -155.3718)
		(end 407.639012 -155.410154)
		(width 0.089408)
		(layer "In4.Cu")
		(net "CPU_XDP_PRESENT_N")
	)
	(segment
		(start 407.639012 -155.410154)
		(end 407.169112 -155.880054)
		(width 0.089408)
		(layer "In4.Cu")
		(net "CPU_XDP_PRESENT_N")
	)
	(segment
		(start 362.52277 -142.758922)
		(end 362.177584 -142.413736)
		(width 0.089408)
		(layer "In4.Cu")
		(net "CPU_XDP_PRESENT_N")
	)
	(segment
		(start 403.870414 -147.78863)
		(end 397.215106 -147.78863)
		(width 0.089408)
		(layer "In4.Cu")
		(net "CPU_XDP_PRESENT_N")
	)
	(segment
		(start 259.1816 -1.8542)
		(end 195.707 -1.8542)
		(width 0.089408)
		(layer "In4.Cu")
		(net "CPU_XDP_PRESENT_N")
	)
	(segment
		(start 362.177584 -142.413736)
		(end 361.837224 -142.413736)
		(width 0.089408)
		(layer "In4.Cu")
		(net "CPU_XDP_PRESENT_N")
	)
	(segment
		(start 323.361304 -25.724104)
		(end 323.069204 -25.432004)
		(width 0.089408)
		(layer "In4.Cu")
		(net "CPU_XDP_PRESENT_N")
	)
	(segment
		(start 330.907644 -94.943422)
		(end 330.907898 -94.943168)
		(width 0.089408)
		(layer "In4.Cu")
		(net "CPU_XDP_PRESENT_N")
	)
	(segment
		(start 445.06896 -154.5463)
		(end 442.510926 -154.5463)
		(width 0.089408)
		(layer "In4.Cu")
		(net "CPU_XDP_PRESENT_N")
	)
	(segment
		(start 320.8274 -27.0002)
		(end 323.118226 -27.0002)
		(width 0.089408)
		(layer "In4.Cu")
		(net "CPU_XDP_PRESENT_N")
	)
	(segment
		(start 348.325694 -140.32484)
		(end 344.656664 -140.32484)
		(width 0.089408)
		(layer "In4.Cu")
		(net "CPU_XDP_PRESENT_N")
	)
	(segment
		(start 446.510664 -153.104596)
		(end 446.505838 -153.104596)
		(width 0.089408)
		(layer "In4.Cu")
		(net "CPU_XDP_PRESENT_N")
	)
	(segment
		(start 292.086792 -56.388)
		(end 292.449758 -56.388)
		(width 0.089408)
		(layer "In4.Cu")
		(net "CPU_XDP_PRESENT_N")
	)
	(segment
		(start 294.259 -55.372)
		(end 294.724074 -54.906926)
		(width 0.089408)
		(layer "In4.Cu")
		(net "CPU_XDP_PRESENT_N")
	)
	(segment
		(start 405.68626 -152.14092)
		(end 405.68626 -149.604476)
		(width 0.089408)
		(layer "In4.Cu")
		(net "CPU_XDP_PRESENT_N")
	)
	(segment
		(start 330.907898 -106.986832)
		(end 330.907898 -97.286064)
		(width 0.089408)
		(layer "In4.Cu")
		(net "CPU_XDP_PRESENT_N")
	)
	(segment
		(start 392.82116 -147.009612)
		(end 389.815578 -144.00403)
		(width 0.089408)
		(layer "In4.Cu")
		(net "CPU_XDP_PRESENT_N")
	)
	(segment
		(start 349.927926 -68.3387)
		(end 351.284286 -68.3387)
		(width 0.089408)
		(layer "In9.Cu")
		(net "CPU_XDP_PRESENT_N")
	)
	(segment
		(start 339.920834 -73.25106)
		(end 341.152734 -72.01916)
		(width 0.089408)
		(layer "In9.Cu")
		(net "CPU_XDP_PRESENT_N")
	)
	(segment
		(start 125.2474 -69.368416)
		(end 125.651768 -69.772784)
		(width 0.089408)
		(layer "In9.Cu")
		(net "CPU_XDP_PRESENT_N")
	)
	(segment
		(start 297.7134 -62.3062)
		(end 297.434 -62.3062)
		(width 0.089408)
		(layer "In9.Cu")
		(net "CPU_XDP_PRESENT_N")
	)
	(segment
		(start 305.257962 -59.771534)
		(end 305.108356 -59.771534)
		(width 0.0889)
		(layer "In9.Cu")
		(net "CPU_XDP_PRESENT_N")
	)
	(segment
		(start 354.519738 -58.11774)
		(end 354.891594 -57.745884)
		(width 0.089408)
		(layer "In9.Cu")
		(net "CPU_XDP_PRESENT_N")
	)
	(segment
		(start 122.368564 -39.42842)
		(end 122.368564 -49.90592)
		(width 0.089408)
		(layer "In9.Cu")
		(net "CPU_XDP_PRESENT_N")
	)
	(segment
		(start 154.912568 -27.438096)
		(end 152.597104 -27.438096)
		(width 0.089408)
		(layer "In9.Cu")
		(net "CPU_XDP_PRESENT_N")
	)
	(segment
		(start 346.898468 -73.350374)
		(end 348.05366 -72.195182)
		(width 0.089408)
		(layer "In9.Cu")
		(net "CPU_XDP_PRESENT_N")
	)
	(segment
		(start 298.1706 -61.849)
		(end 297.7134 -62.3062)
		(width 0.089408)
		(layer "In9.Cu")
		(net "CPU_XDP_PRESENT_N")
	)
	(segment
		(start 120.368568 -61.798708)
		(end 120.88876 -62.3189)
		(width 0.089408)
		(layer "In9.Cu")
		(net "CPU_XDP_PRESENT_N")
	)
	(segment
		(start 118.958868 -53.315616)
		(end 118.958868 -61.022484)
		(width 0.089408)
		(layer "In9.Cu")
		(net "CPU_XDP_PRESENT_N")
	)
	(segment
		(start 293.9542 -68.2498)
		(end 293.4462 -68.7578)
		(width 0.089408)
		(layer "In9.Cu")
		(net "CPU_XDP_PRESENT_N")
	)
	(segment
		(start 351.379536 -65.446656)
		(end 351.379536 -58.828432)
		(width 0.089408)
		(layer "In9.Cu")
		(net "CPU_XDP_PRESENT_N")
	)
	(segment
		(start 292.1254 -69.2658)
		(end 291.618416 -69.772784)
		(width 0.089408)
		(layer "In9.Cu")
		(net "CPU_XDP_PRESENT_N")
	)
	(segment
		(start 300.228 -61.7982)
		(end 299.8216 -61.7982)
		(width 0.089408)
		(layer "In9.Cu")
		(net "CPU_XDP_PRESENT_N")
	)
	(segment
		(start 119.554752 -61.371226)
		(end 119.982234 -61.798708)
		(width 0.089408)
		(layer "In9.Cu")
		(net "CPU_XDP_PRESENT_N")
	)
	(segment
		(start 304.2412 -60.3758)
		(end 303.7586 -60.8584)
		(width 0.089408)
		(layer "In9.Cu")
		(net "CPU_XDP_PRESENT_N")
	)
	(segment
		(start 119.982234 -61.798708)
		(end 120.368568 -61.798708)
		(width 0.089408)
		(layer "In9.Cu")
		(net "CPU_XDP_PRESENT_N")
	)
	(segment
		(start 121.753884 -62.813184)
		(end 122.01652 -62.813184)
		(width 0.089408)
		(layer "In9.Cu")
		(net "CPU_XDP_PRESENT_N")
	)
	(segment
		(start 342.092534 -72.01916)
		(end 342.468454 -72.39508)
		(width 0.089408)
		(layer "In9.Cu")
		(net "CPU_XDP_PRESENT_N")
	)
	(segment
		(start 119.30761 -61.371226)
		(end 119.554752 -61.371226)
		(width 0.089408)
		(layer "In9.Cu")
		(net "CPU_XDP_PRESENT_N")
	)
	(segment
		(start 305.688746 -58.79338)
		(end 305.688746 -59.447176)
		(width 0.0889)
		(layer "In9.Cu")
		(net "CPU_XDP_PRESENT_N")
	)
	(segment
		(start 302.8696 -61.3156)
		(end 302.4632 -61.3156)
		(width 0.089408)
		(layer "In9.Cu")
		(net "CPU_XDP_PRESENT_N")
	)
	(segment
		(start 351.284286 -68.3387)
		(end 351.948496 -67.67449)
		(width 0.089408)
		(layer "In9.Cu")
		(net "CPU_XDP_PRESENT_N")
	)
	(segment
		(start 293.4462 -68.7578)
		(end 293.0906 -68.7578)
		(width 0.089408)
		(layer "In9.Cu")
		(net "CPU_XDP_PRESENT_N")
	)
	(segment
		(start 298.9834 -61.3664)
		(end 298.5008 -61.849)
		(width 0.089408)
		(layer "In9.Cu")
		(net "CPU_XDP_PRESENT_N")
	)
	(segment
		(start 351.948496 -67.67449)
		(end 351.948496 -66.015616)
		(width 0.089408)
		(layer "In9.Cu")
		(net "CPU_XDP_PRESENT_N")
	)
	(segment
		(start 354.891594 -57.745884)
		(end 354.891594 -57.414414)
		(width 0.089408)
		(layer "In9.Cu")
		(net "CPU_XDP_PRESENT_N")
	)
	(segment
		(start 156.925264 -25.4254)
		(end 154.912568 -27.438096)
		(width 0.089408)
		(layer "In9.Cu")
		(net "CPU_XDP_PRESENT_N")
	)
	(segment
		(start 157.1752 -25.4254)
		(end 156.925264 -25.4254)
		(width 0.089408)
		(layer "In9.Cu")
		(net "CPU_XDP_PRESENT_N")
	)
	(segment
		(start 336.469736 -87.56396)
		(end 336.469736 -82.539332)
		(width 0.089408)
		(layer "In9.Cu")
		(net "CPU_XDP_PRESENT_N")
	)
	(segment
		(start 120.88876 -62.3189)
		(end 121.2596 -62.3189)
		(width 0.089408)
		(layer "In9.Cu")
		(net "CPU_XDP_PRESENT_N")
	)
	(segment
		(start 336.677 -82.332068)
		(end 336.677 -75.705208)
		(width 0.089408)
		(layer "In9.Cu")
		(net "CPU_XDP_PRESENT_N")
	)
	(segment
		(start 305.758596 -58.67654)
		(end 305.688746 -58.79338)
		(width 0.0889)
		(layer "In9.Cu")
		(net "CPU_XDP_PRESENT_N")
	)
	(segment
		(start 299.3898 -61.3664)
		(end 298.9834 -61.3664)
		(width 0.089408)
		(layer "In9.Cu")
		(net "CPU_XDP_PRESENT_N")
	)
	(segment
		(start 348.05366 -70.212966)
		(end 349.927926 -68.3387)
		(width 0.089408)
		(layer "In9.Cu")
		(net "CPU_XDP_PRESENT_N")
	)
	(segment
		(start 123.40717 -63.79718)
		(end 123.686824 -63.79718)
		(width 0.089408)
		(layer "In9.Cu")
		(net "CPU_XDP_PRESENT_N")
	)
	(segment
		(start 352.272092 -57.935876)
		(end 353.7331 -57.935876)
		(width 0.089408)
		(layer "In9.Cu")
		(net "CPU_XDP_PRESENT_N")
	)
	(segment
		(start 291.618416 -69.772784)
		(end 290.6522 -69.772784)
		(width 0.089408)
		(layer "In9.Cu")
		(net "CPU_XDP_PRESENT_N")
	)
	(segment
		(start 296.7736 -67.818)
		(end 296.0624 -67.818)
		(width 0.089408)
		(layer "In9.Cu")
		(net "CPU_XDP_PRESENT_N")
	)
	(segment
		(start 151.975566 -29.169106)
		(end 147.748752 -33.39592)
		(width 0.089408)
		(layer "In9.Cu")
		(net "CPU_XDP_PRESENT_N")
	)
	(segment
		(start 292.5826 -69.2658)
		(end 292.1254 -69.2658)
		(width 0.089408)
		(layer "In9.Cu")
		(net "CPU_XDP_PRESENT_N")
	)
	(segment
		(start 353.914964 -58.11774)
		(end 354.519738 -58.11774)
		(width 0.089408)
		(layer "In9.Cu")
		(net "CPU_XDP_PRESENT_N")
	)
	(segment
		(start 122.01652 -62.813184)
		(end 122.48007 -63.276734)
		(width 0.089408)
		(layer "In9.Cu")
		(net "CPU_XDP_PRESENT_N")
	)
	(segment
		(start 122.48007 -63.276734)
		(end 122.886724 -63.276734)
		(width 0.089408)
		(layer "In9.Cu")
		(net "CPU_XDP_PRESENT_N")
	)
	(segment
		(start 294.1828 -68.2498)
		(end 293.9542 -68.2498)
		(width 0.089408)
		(layer "In9.Cu")
		(net "CPU_XDP_PRESENT_N")
	)
	(segment
		(start 293.0906 -68.7578)
		(end 292.5826 -69.2658)
		(width 0.089408)
		(layer "In9.Cu")
		(net "CPU_XDP_PRESENT_N")
	)
	(segment
		(start 343.029032 -73.350374)
		(end 346.898468 -73.350374)
		(width 0.089408)
		(layer "In9.Cu")
		(net "CPU_XDP_PRESENT_N")
	)
	(segment
		(start 299.8216 -61.7982)
		(end 299.3898 -61.3664)
		(width 0.089408)
		(layer "In9.Cu")
		(net "CPU_XDP_PRESENT_N")
	)
	(segment
		(start 303.7586 -60.8584)
		(end 303.3268 -60.8584)
		(width 0.089408)
		(layer "In9.Cu")
		(net "CPU_XDP_PRESENT_N")
	)
	(segment
		(start 301.5488 -61.7982)
		(end 301.0916 -61.341)
		(width 0.089408)
		(layer "In9.Cu")
		(net "CPU_XDP_PRESENT_N")
	)
	(segment
		(start 306.297076 -58.476388)
		(end 306.09413 -58.476388)
		(width 0.0889)
		(layer "In9.Cu")
		(net "CPU_XDP_PRESENT_N")
	)
	(segment
		(start 118.958868 -61.022484)
		(end 119.30761 -61.371226)
		(width 0.089408)
		(layer "In9.Cu")
		(net "CPU_XDP_PRESENT_N")
	)
	(segment
		(start 302.4632 -61.3156)
		(end 301.9806 -61.7982)
		(width 0.089408)
		(layer "In9.Cu")
		(net "CPU_XDP_PRESENT_N")
	)
	(segment
		(start 123.686824 -63.79718)
		(end 124.375672 -64.486028)
		(width 0.089408)
		(layer "In9.Cu")
		(net "CPU_XDP_PRESENT_N")
	)
	(segment
		(start 128.401064 -33.39592)
		(end 122.368564 -39.42842)
		(width 0.089408)
		(layer "In9.Cu")
		(net "CPU_XDP_PRESENT_N")
	)
	(segment
		(start 121.2596 -62.3189)
		(end 121.753884 -62.813184)
		(width 0.089408)
		(layer "In9.Cu")
		(net "CPU_XDP_PRESENT_N")
	)
	(segment
		(start 351.948496 -66.015616)
		(end 351.379536 -65.446656)
		(width 0.089408)
		(layer "In9.Cu")
		(net "CPU_XDP_PRESENT_N")
	)
	(segment
		(start 147.748752 -33.39592)
		(end 128.401064 -33.39592)
		(width 0.089408)
		(layer "In9.Cu")
		(net "CPU_XDP_PRESENT_N")
	)
	(segment
		(start 125.2474 -67.027806)
		(end 125.2474 -69.368416)
		(width 0.089408)
		(layer "In9.Cu")
		(net "CPU_XDP_PRESENT_N")
	)
	(segment
		(start 336.807556 -88.323928)
		(end 336.807556 -87.90178)
		(width 0.089408)
		(layer "In9.Cu")
		(net "CPU_XDP_PRESENT_N")
	)
	(segment
		(start 341.152734 -72.01916)
		(end 342.092534 -72.01916)
		(width 0.089408)
		(layer "In9.Cu")
		(net "CPU_XDP_PRESENT_N")
	)
	(segment
		(start 301.9806 -61.7982)
		(end 301.5488 -61.7982)
		(width 0.089408)
		(layer "In9.Cu")
		(net "CPU_XDP_PRESENT_N")
	)
	(segment
		(start 304.50409 -60.3758)
		(end 304.2412 -60.3758)
		(width 0.089408)
		(layer "In9.Cu")
		(net "CPU_XDP_PRESENT_N")
	)
	(segment
		(start 336.469736 -82.539332)
		(end 336.677 -82.332068)
		(width 0.089408)
		(layer "In9.Cu")
		(net "CPU_XDP_PRESENT_N")
	)
	(segment
		(start 348.05366 -72.195182)
		(end 348.05366 -70.212966)
		(width 0.089408)
		(layer "In9.Cu")
		(net "CPU_XDP_PRESENT_N")
	)
	(segment
		(start 303.3268 -60.8584)
		(end 302.8696 -61.3156)
		(width 0.089408)
		(layer "In9.Cu")
		(net "CPU_XDP_PRESENT_N")
	)
	(segment
		(start 336.677 -75.705208)
		(end 339.131148 -73.25106)
		(width 0.089408)
		(layer "In9.Cu")
		(net "CPU_XDP_PRESENT_N")
	)
	(segment
		(start 305.108356 -59.771534)
		(end 304.50409 -60.3758)
		(width 0.0889)
		(layer "In9.Cu")
		(net "CPU_XDP_PRESENT_N")
	)
	(segment
		(start 339.131148 -73.25106)
		(end 339.920834 -73.25106)
		(width 0.089408)
		(layer "In9.Cu")
		(net "CPU_XDP_PRESENT_N")
	)
	(segment
		(start 296.0624 -67.818)
		(end 295.0972 -68.7832)
		(width 0.089408)
		(layer "In9.Cu")
		(net "CPU_XDP_PRESENT_N")
	)
	(segment
		(start 124.375672 -66.156078)
		(end 125.2474 -67.027806)
		(width 0.089408)
		(layer "In9.Cu")
		(net "CPU_XDP_PRESENT_N")
	)
	(segment
		(start 342.468454 -72.39508)
		(end 342.468454 -72.789796)
		(width 0.089408)
		(layer "In9.Cu")
		(net "CPU_XDP_PRESENT_N")
	)
	(segment
		(start 306.963826 -58.381138)
		(end 306.297076 -58.476388)
		(width 0.0889)
		(layer "In9.Cu")
		(net "CPU_XDP_PRESENT_N")
	)
	(segment
		(start 342.468454 -72.789796)
		(end 343.029032 -73.350374)
		(width 0.089408)
		(layer "In9.Cu")
		(net "CPU_XDP_PRESENT_N")
	)
	(segment
		(start 124.375672 -64.486028)
		(end 124.375672 -66.156078)
		(width 0.089408)
		(layer "In9.Cu")
		(net "CPU_XDP_PRESENT_N")
	)
	(segment
		(start 295.0972 -68.7832)
		(end 294.7162 -68.7832)
		(width 0.089408)
		(layer "In9.Cu")
		(net "CPU_XDP_PRESENT_N")
	)
	(segment
		(start 297.0784 -67.5132)
		(end 296.7736 -67.818)
		(width 0.089408)
		(layer "In9.Cu")
		(net "CPU_XDP_PRESENT_N")
	)
	(segment
		(start 353.7331 -57.935876)
		(end 353.914964 -58.11774)
		(width 0.089408)
		(layer "In9.Cu")
		(net "CPU_XDP_PRESENT_N")
	)
	(segment
		(start 152.597104 -27.438096)
		(end 151.975566 -28.059634)
		(width 0.089408)
		(layer "In9.Cu")
		(net "CPU_XDP_PRESENT_N")
	)
	(segment
		(start 300.6852 -61.341)
		(end 300.228 -61.7982)
		(width 0.089408)
		(layer "In9.Cu")
		(net "CPU_XDP_PRESENT_N")
	)
	(segment
		(start 122.368564 -49.90592)
		(end 118.958868 -53.315616)
		(width 0.089408)
		(layer "In9.Cu")
		(net "CPU_XDP_PRESENT_N")
	)
	(segment
		(start 294.7162 -68.7832)
		(end 294.1828 -68.2498)
		(width 0.089408)
		(layer "In9.Cu")
		(net "CPU_XDP_PRESENT_N")
	)
	(segment
		(start 297.0784 -62.6618)
		(end 297.0784 -67.5132)
		(width 0.089408)
		(layer "In9.Cu")
		(net "CPU_XDP_PRESENT_N")
	)
	(segment
		(start 298.5008 -61.849)
		(end 298.1706 -61.849)
		(width 0.089408)
		(layer "In9.Cu")
		(net "CPU_XDP_PRESENT_N")
	)
	(segment
		(start 151.975566 -28.059634)
		(end 151.975566 -29.169106)
		(width 0.089408)
		(layer "In9.Cu")
		(net "CPU_XDP_PRESENT_N")
	)
	(segment
		(start 301.0916 -61.341)
		(end 300.6852 -61.341)
		(width 0.089408)
		(layer "In9.Cu")
		(net "CPU_XDP_PRESENT_N")
	)
	(segment
		(start 297.434 -62.3062)
		(end 297.0784 -62.6618)
		(width 0.089408)
		(layer "In9.Cu")
		(net "CPU_XDP_PRESENT_N")
	)
	(segment
		(start 336.807556 -87.90178)
		(end 336.469736 -87.56396)
		(width 0.089408)
		(layer "In9.Cu")
		(net "CPU_XDP_PRESENT_N")
	)
	(segment
		(start 351.379536 -58.828432)
		(end 352.272092 -57.935876)
		(width 0.089408)
		(layer "In9.Cu")
		(net "CPU_XDP_PRESENT_N")
	)
	(segment
		(start 122.886724 -63.276734)
		(end 123.40717 -63.79718)
		(width 0.089408)
		(layer "In9.Cu")
		(net "CPU_XDP_PRESENT_N")
	)
	(arc
		(start 305.688746 -59.447176)
		(mid 305.637035 -59.506147)
		(end 305.593496 -59.571382)
		(width 0.0889)
		(layer "In9.Cu")
		(net "CPU_XDP_PRESENT_N")
	)
	(arc
		(start 306.09413 -58.476388)
		(mid 305.90028 -58.532738)
		(end 305.758596 -58.67654)
		(width 0.0889)
		(layer "In9.Cu")
		(net "CPU_XDP_PRESENT_N")
	)
	(arc
		(start 305.593496 -59.571382)
		(mid 305.451813 -59.715186)
		(end 305.257962 -59.771534)
		(width 0.0889)
		(layer "In9.Cu")
		(net "CPU_XDP_PRESENT_N")
	)
	(segment
		(start 354.734622 -57.414414)
		(end 354.891594 -57.414414)
		(width 0.089408)
		(layer "In11.Cu")
		(net "CPU_XDP_PRESENT_N")
	)
	(segment
		(start 328.198226 -57.581292)
		(end 328.427334 -57.8104)
		(width 0.089408)
		(layer "In11.Cu")
		(net "CPU_XDP_PRESENT_N")
	)
	(segment
		(start 328.427334 -57.8104)
		(end 329.610466 -57.8104)
		(width 0.089408)
		(layer "In11.Cu")
		(net "CPU_XDP_PRESENT_N")
	)
	(segment
		(start 319.212468 -61.031882)
		(end 319.21323 -61.031882)
		(width 0.089408)
		(layer "In11.Cu")
		(net "CPU_XDP_PRESENT_N")
	)
	(segment
		(start 329.610466 -57.8104)
		(end 330.331064 -57.089802)
		(width 0.089408)
		(layer "In11.Cu")
		(net "CPU_XDP_PRESENT_N")
	)
	(segment
		(start 325.455026 -57.3151)
		(end 325.721218 -57.581292)
		(width 0.089408)
		(layer "In11.Cu")
		(net "CPU_XDP_PRESENT_N")
	)
	(segment
		(start 354.41001 -57.089802)
		(end 354.734622 -57.414414)
		(width 0.089408)
		(layer "In11.Cu")
		(net "CPU_XDP_PRESENT_N")
	)
	(segment
		(start 325.721218 -57.581292)
		(end 328.198226 -57.581292)
		(width 0.089408)
		(layer "In11.Cu")
		(net "CPU_XDP_PRESENT_N")
	)
	(segment
		(start 330.331064 -57.089802)
		(end 354.41001 -57.089802)
		(width 0.089408)
		(layer "In11.Cu")
		(net "CPU_XDP_PRESENT_N")
	)
	(segment
		(start 314.734702 -61.077094)
		(end 318.175132 -61.077094)
		(width 0.089408)
		(layer "In11.Cu")
		(net "CPU_XDP_PRESENT_N")
	)
	(segment
		(start 312.038746 -58.381138)
		(end 314.734702 -61.077094)
		(width 0.089408)
		(layer "In11.Cu")
		(net "CPU_XDP_PRESENT_N")
	)
	(segment
		(start 319.21323 -61.031882)
		(end 322.930012 -57.3151)
		(width 0.089408)
		(layer "In11.Cu")
		(net "CPU_XDP_PRESENT_N")
	)
	(segment
		(start 306.963826 -58.381138)
		(end 312.038746 -58.381138)
		(width 0.089408)
		(layer "In11.Cu")
		(net "CPU_XDP_PRESENT_N")
	)
	(segment
		(start 318.175386 -61.077348)
		(end 319.167002 -61.077348)
		(width 0.089408)
		(layer "In11.Cu")
		(net "CPU_XDP_PRESENT_N")
	)
	(segment
		(start 322.930012 -57.3151)
		(end 325.455026 -57.3151)
		(width 0.089408)
		(layer "In11.Cu")
		(net "CPU_XDP_PRESENT_N")
	)
	(segment
		(start 318.175132 -61.077094)
		(end 318.175386 -61.077348)
		(width 0.089408)
		(layer "In11.Cu")
		(net "CPU_XDP_PRESENT_N")
	)
	(segment
		(start 319.167002 -61.077348)
		(end 319.212468 -61.031882)
		(width 0.089408)
		(layer "In11.Cu")
		(net "CPU_XDP_PRESENT_N")
	)
	(segment
		(start 437.906414 -151.064468)
		(end 437.891682 -151.049736)
		(width 0.10795)
		(layer "F.Cu")
		(net "XDP_TRST_R_N")
	)
	(segment
		(start 437.891682 -151.049736)
		(end 436.381398 -151.049736)
		(width 0.10795)
		(layer "F.Cu")
		(net "XDP_TRST_R_N")
	)
	(via
		(at 436.381398 -151.049736)
		(size 0.508)
		(drill 0.254)
		(layers "F.Cu" "B.Cu")
		(net "XDP_TRST_R_N")
	)
	(via
		(at 435.975252 -152.5016)
		(size 0.6604)
		(drill 0.3302)
		(layers "F.Cu" "B.Cu")
		(net "XDP_TRST_R_N")
	)
	(segment
		(start 436.071518 -151.049736)
		(end 435.8386 -151.282654)
		(width 0.10795)
		(layer "B.Cu")
		(net "XDP_TRST_R_N")
	)
	(segment
		(start 435.8386 -152.364948)
		(end 435.975252 -152.5016)
		(width 0.10795)
		(layer "B.Cu")
		(net "XDP_TRST_R_N")
	)
	(segment
		(start 437.339232 -151.88057)
		(end 436.718202 -152.5016)
		(width 0.10795)
		(layer "B.Cu")
		(net "XDP_TRST_R_N")
	)
	(segment
		(start 436.381398 -151.049736)
		(end 436.071518 -151.049736)
		(width 0.10795)
		(layer "B.Cu")
		(net "XDP_TRST_R_N")
	)
	(segment
		(start 435.8386 -151.282654)
		(end 435.8386 -152.364948)
		(width 0.10795)
		(layer "B.Cu")
		(net "XDP_TRST_R_N")
	)
	(segment
		(start 436.718202 -152.5016)
		(end 435.975252 -152.5016)
		(width 0.10795)
		(layer "B.Cu")
		(net "XDP_TRST_R_N")
	)
	(segment
		(start 451.844918 -144.56029)
		(end 452.247 -144.962372)
		(width 0.10795)
		(layer "F.Cu")
		(net "XDP_TMS_R")
	)
	(segment
		(start 450.461634 -144.56029)
		(end 451.844918 -144.56029)
		(width 0.10795)
		(layer "F.Cu")
		(net "XDP_TMS_R")
	)
	(via
		(at 452.1073 -146.1262)
		(size 0.6604)
		(drill 0.3302)
		(layers "F.Cu" "B.Cu")
		(net "XDP_TMS_R")
	)
	(via
		(at 452.247 -144.962372)
		(size 0.508)
		(drill 0.254)
		(layers "F.Cu" "B.Cu")
		(net "XDP_TMS_R")
	)
	(segment
		(start 451.3072 -145.21053)
		(end 451.3072 -145.6944)
		(width 0.10795)
		(layer "B.Cu")
		(net "XDP_TMS_R")
	)
	(segment
		(start 451.3072 -145.6944)
		(end 451.739 -146.1262)
		(width 0.10795)
		(layer "B.Cu")
		(net "XDP_TMS_R")
	)
	(segment
		(start 452.247 -144.962372)
		(end 452.247 -145.9865)
		(width 0.10795)
		(layer "B.Cu")
		(net "XDP_TMS_R")
	)
	(segment
		(start 451.739 -146.1262)
		(end 452.1073 -146.1262)
		(width 0.10795)
		(layer "B.Cu")
		(net "XDP_TMS_R")
	)
	(segment
		(start 452.247 -145.9865)
		(end 452.1073 -146.1262)
		(width 0.10795)
		(layer "B.Cu")
		(net "XDP_TMS_R")
	)
	(segment
		(start 451.88505 -143.91005)
		(end 452.247 -144.272)
		(width 0.10795)
		(layer "F.Cu")
		(net "XDP_TDI_R")
	)
	(segment
		(start 450.461634 -143.91005)
		(end 451.88505 -143.91005)
		(width 0.10795)
		(layer "F.Cu")
		(net "XDP_TDI_R")
	)
	(via
		(at 452.9836 -145.0086)
		(size 0.6604)
		(drill 0.3302)
		(layers "F.Cu" "B.Cu")
		(net "XDP_TDI_R")
	)
	(via
		(at 452.247 -144.272)
		(size 0.508)
		(drill 0.254)
		(layers "F.Cu" "B.Cu")
		(net "XDP_TDI_R")
	)
	(segment
		(start 451.3072 -144.1831)
		(end 452.1581 -144.1831)
		(width 0.10795)
		(layer "B.Cu")
		(net "XDP_TDI_R")
	)
	(segment
		(start 452.9836 -145.0086)
		(end 452.247 -144.272)
		(width 0.10795)
		(layer "B.Cu")
		(net "XDP_TDI_R")
	)
	(segment
		(start 452.1581 -144.1831)
		(end 452.247 -144.272)
		(width 0.10795)
		(layer "B.Cu")
		(net "XDP_TDI_R")
	)
	(segment
		(start 438.715912 -153.191464)
		(end 438.715912 -153.572718)
		(width 0.10795)
		(layer "F.Cu")
		(net "XDP_PCH_TCK1_R")
	)
	(segment
		(start 438.686448 -153.162)
		(end 438.715912 -153.191464)
		(width 0.10795)
		(layer "F.Cu")
		(net "XDP_PCH_TCK1_R")
	)
	(segment
		(start 438.715912 -154.591766)
		(end 438.827164 -154.703018)
		(width 0.10795)
		(layer "F.Cu")
		(net "XDP_PCH_TCK1_R")
	)
	(segment
		(start 438.686448 -152.614376)
		(end 438.686448 -153.162)
		(width 0.10795)
		(layer "F.Cu")
		(net "XDP_PCH_TCK1_R")
	)
	(segment
		(start 438.715912 -153.572718)
		(end 438.715912 -154.591766)
		(width 0.10795)
		(layer "F.Cu")
		(net "XDP_PCH_TCK1_R")
	)
	(via
		(at 438.827164 -154.703018)
		(size 0.762)
		(drill 0.381)
		(layers "F.Cu" "B.Cu")
		(net "XDP_PCH_TCK1_R")
	)
	(segment
		(start 442.845444 -153.225246)
		(end 441.684664 -152.064466)
		(width 0.10795)
		(layer "F.Cu")
		(net "XDP_CPU_TCK0_R")
	)
	(segment
		(start 441.684664 -152.064466)
		(end 441.00623 -152.064466)
		(width 0.10795)
		(layer "F.Cu")
		(net "XDP_CPU_TCK0_R")
	)
	(segment
		(start 442.845444 -154.200352)
		(end 442.845444 -153.225246)
		(width 0.10795)
		(layer "F.Cu")
		(net "XDP_CPU_TCK0_R")
	)
	(via
		(at 442.845444 -154.200352)
		(size 0.762)
		(drill 0.381)
		(layers "F.Cu" "B.Cu")
		(net "XDP_CPU_TCK0_R")
	)
	(segment
		(start 452.59371 -141.30909)
		(end 452.7042 -141.1986)
		(width 0.10795)
		(layer "F.Cu")
		(net "PU_GTL2014_3_DIR")
	)
	(segment
		(start 450.461634 -141.30909)
		(end 452.59371 -141.30909)
		(width 0.10795)
		(layer "F.Cu")
		(net "PU_GTL2014_3_DIR")
	)
	(via
		(at 452.7042 -141.1986)
		(size 0.508)
		(drill 0.254)
		(layers "F.Cu" "B.Cu")
		(net "PU_GTL2014_3_DIR")
	)
	(segment
		(start 452.6026 -141.097)
		(end 450.596 -141.097)
		(width 0.10795)
		(layer "B.Cu")
		(net "PU_GTL2014_3_DIR")
	)
	(segment
		(start 452.7042 -141.1986)
		(end 452.6026 -141.097)
		(width 0.10795)
		(layer "B.Cu")
		(net "PU_GTL2014_3_DIR")
	)
	(segment
		(start 450.1642 -147.7645)
		(end 451.4215 -147.7645)
		(width 0.10795)
		(layer "F.Cu")
		(net "PD_GTL2014_DIR_6")
	)
	(segment
		(start 451.4215 -147.7645)
		(end 451.993 -147.193)
		(width 0.10795)
		(layer "F.Cu")
		(net "PD_GTL2014_DIR_6")
	)
	(via
		(at 451.1548 -146.9771)
		(size 0.6604)
		(drill 0.3302)
		(layers "F.Cu" "B.Cu")
		(net "PD_GTL2014_DIR_6")
	)
	(via
		(at 451.993 -147.193)
		(size 0.508)
		(drill 0.254)
		(layers "F.Cu" "B.Cu")
		(net "PD_GTL2014_DIR_6")
	)
	(segment
		(start 451.993 -147.193)
		(end 451.7771 -146.9771)
		(width 0.10795)
		(layer "B.Cu")
		(net "PD_GTL2014_DIR_6")
	)
	(segment
		(start 451.1548 -146.9771)
		(end 450.2785 -146.9771)
		(width 0.10795)
		(layer "B.Cu")
		(net "PD_GTL2014_DIR_6")
	)
	(segment
		(start 450.2785 -146.9771)
		(end 450.215 -147.0406)
		(width 0.10795)
		(layer "B.Cu")
		(net "PD_GTL2014_DIR_6")
	)
	(segment
		(start 451.7771 -146.9771)
		(end 451.1548 -146.9771)
		(width 0.10795)
		(layer "B.Cu")
		(net "PD_GTL2014_DIR_6")
	)
	(segment
		(start 450.461634 -143.25981)
		(end 452.12381 -143.25981)
		(width 0.10795)
		(layer "F.Cu")
		(net "PD_GTL2014_3_VREF")
	)
	(segment
		(start 452.12381 -143.25981)
		(end 452.374 -143.51)
		(width 0.10795)
		(layer "F.Cu")
		(net "PD_GTL2014_3_VREF")
	)
	(via
		(at 452.374 -143.51)
		(size 0.508)
		(drill 0.254)
		(layers "F.Cu" "B.Cu")
		(net "PD_GTL2014_3_VREF")
	)
	(via
		(at 453.3011 -143.764)
		(size 0.6604)
		(drill 0.3302)
		(layers "F.Cu" "B.Cu")
		(net "PD_GTL2014_3_VREF")
	)
	(segment
		(start 453.3011 -143.764)
		(end 452.628 -143.764)
		(width 0.10795)
		(layer "B.Cu")
		(net "PD_GTL2014_3_VREF")
	)
	(segment
		(start 452.628 -143.764)
		(end 452.374 -143.51)
		(width 0.10795)
		(layer "B.Cu")
		(net "PD_GTL2014_3_VREF")
	)
	(segment
		(start 451.7263 -142.8623)
		(end 452.374 -143.51)
		(width 0.10795)
		(layer "B.Cu")
		(net "PD_GTL2014_3_VREF")
	)
	(segment
		(start 450.5706 -142.8623)
		(end 451.7263 -142.8623)
		(width 0.10795)
		(layer "B.Cu")
		(net "PD_GTL2014_3_VREF")
	)
	(segment
		(start 451.62978 -149.71522)
		(end 451.866 -149.479)
		(width 0.10795)
		(layer "F.Cu")
		(net "P0V7_GTL2014_VREF_6")
	)
	(segment
		(start 450.1642 -149.71522)
		(end 451.62978 -149.71522)
		(width 0.10795)
		(layer "F.Cu")
		(net "P0V7_GTL2014_VREF_6")
	)
	(segment
		(start 451.866 -149.479)
		(end 452.628 -149.479)
		(width 0.10795)
		(layer "F.Cu")
		(net "P0V7_GTL2014_VREF_6")
	)
	(via
		(at 451.0786 -149.4536)
		(size 0.508)
		(drill 0.254)
		(layers "F.Cu" "B.Cu")
		(net "P0V7_GTL2014_VREF_6")
	)
	(via
		(at 451.866 -149.479)
		(size 0.508)
		(drill 0.254)
		(layers "F.Cu" "B.Cu")
		(net "P0V7_GTL2014_VREF_6")
	)
	(segment
		(start 451.866 -149.479)
		(end 451.8406 -149.4536)
		(width 0.10795)
		(layer "B.Cu")
		(net "P0V7_GTL2014_VREF_6")
	)
	(segment
		(start 451.8406 -149.4536)
		(end 451.0786 -149.4536)
		(width 0.10795)
		(layer "B.Cu")
		(net "P0V7_GTL2014_VREF_6")
	)
	(segment
		(start 451.0786 -149.4536)
		(end 450.3039 -149.4536)
		(width 0.10795)
		(layer "B.Cu")
		(net "P0V7_GTL2014_VREF_6")
	)
	(segment
		(start 450.3039 -149.4536)
		(end 450.2277 -149.3774)
		(width 0.10795)
		(layer "B.Cu")
		(net "P0V7_GTL2014_VREF_6")
	)
	(segment
		(start 452.5772 -149.479)
		(end 451.866 -149.479)
		(width 0.10795)
		(layer "B.Cu")
		(net "P0V7_GTL2014_VREF_6")
	)
	(segment
		(start 450.2277 -149.3774)
		(end 450.2277 -148.59)
		(width 0.10795)
		(layer "B.Cu")
		(net "P0V7_GTL2014_VREF_6")
	)
	(segment
		(start 437.891682 -151.549862)
		(end 436.516272 -151.549862)
		(width 0.10795)
		(layer "F.Cu")
		(net "JTAG_BMC_TCK1")
	)
	(segment
		(start 436.516272 -151.549862)
		(end 436.381398 -151.684736)
		(width 0.10795)
		(layer "F.Cu")
		(net "JTAG_BMC_TCK1")
	)
	(segment
		(start 437.906414 -151.564594)
		(end 437.891682 -151.549862)
		(width 0.10795)
		(layer "F.Cu")
		(net "JTAG_BMC_TCK1")
	)
	(via
		(at 440.275472 -147.286472)
		(size 0.508)
		(drill 0.254)
		(layers "F.Cu" "B.Cu")
		(net "JTAG_BMC_TCK1")
	)
	(via
		(at 436.381398 -151.684736)
		(size 0.508)
		(drill 0.254)
		(layers "F.Cu" "B.Cu")
		(net "JTAG_BMC_TCK1")
	)
	(via
		(at 441.579 -147.7518)
		(size 0.6604)
		(drill 0.3302)
		(layers "F.Cu" "B.Cu")
		(net "JTAG_BMC_TCK1")
	)
	(segment
		(start 441.480956 -146.282156)
		(end 441.723526 -146.524726)
		(width 0.10795)
		(layer "B.Cu")
		(net "JTAG_BMC_TCK1")
	)
	(segment
		(start 440.925712 -147.286472)
		(end 441.39104 -147.7518)
		(width 0.10795)
		(layer "B.Cu")
		(net "JTAG_BMC_TCK1")
	)
	(segment
		(start 440.275472 -147.451572)
		(end 440.4233 -147.5994)
		(width 0.10795)
		(layer "B.Cu")
		(net "JTAG_BMC_TCK1")
	)
	(segment
		(start 441.39104 -147.7518)
		(end 441.579 -147.7518)
		(width 0.10795)
		(layer "B.Cu")
		(net "JTAG_BMC_TCK1")
	)
	(segment
		(start 440.4233 -147.5994)
		(end 440.4233 -147.956016)
		(width 0.10795)
		(layer "B.Cu")
		(net "JTAG_BMC_TCK1")
	)
	(segment
		(start 441.723526 -147.607274)
		(end 441.579 -147.7518)
		(width 0.10795)
		(layer "B.Cu")
		(net "JTAG_BMC_TCK1")
	)
	(segment
		(start 441.723526 -146.524726)
		(end 441.723526 -147.607274)
		(width 0.10795)
		(layer "B.Cu")
		(net "JTAG_BMC_TCK1")
	)
	(segment
		(start 440.275472 -147.286472)
		(end 440.275472 -147.451572)
		(width 0.10795)
		(layer "B.Cu")
		(net "JTAG_BMC_TCK1")
	)
	(segment
		(start 440.275472 -147.286472)
		(end 440.925712 -147.286472)
		(width 0.10795)
		(layer "B.Cu")
		(net "JTAG_BMC_TCK1")
	)
	(segment
		(start 440.275726 -146.282156)
		(end 441.480956 -146.282156)
		(width 0.10795)
		(layer "B.Cu")
		(net "JTAG_BMC_TCK1")
	)
	(segment
		(start 436.381398 -151.684736)
		(end 437.018176 -151.047958)
		(width 0.089408)
		(layer "In2.Cu")
		(net "JTAG_BMC_TCK1")
	)
	(segment
		(start 437.018176 -149.003512)
		(end 437.896 -148.125688)
		(width 0.089408)
		(layer "In2.Cu")
		(net "JTAG_BMC_TCK1")
	)
	(segment
		(start 439.436256 -148.125688)
		(end 440.275472 -147.286472)
		(width 0.089408)
		(layer "In2.Cu")
		(net "JTAG_BMC_TCK1")
	)
	(segment
		(start 437.018176 -151.047958)
		(end 437.018176 -149.003512)
		(width 0.089408)
		(layer "In2.Cu")
		(net "JTAG_BMC_TCK1")
	)
	(segment
		(start 437.896 -148.125688)
		(end 439.436256 -148.125688)
		(width 0.089408)
		(layer "In2.Cu")
		(net "JTAG_BMC_TCK1")
	)
	(segment
		(start 441.00623 -151.064468)
		(end 441.946538 -151.064468)
		(width 0.10795)
		(layer "F.Cu")
		(net "JTAG_BMC_TCK0")
	)
	(segment
		(start 441.946538 -151.064468)
		(end 442.02858 -150.982426)
		(width 0.10795)
		(layer "F.Cu")
		(net "JTAG_BMC_TCK0")
	)
	(via
		(at 442.02858 -150.982426)
		(size 0.508)
		(drill 0.254)
		(layers "F.Cu" "B.Cu")
		(net "JTAG_BMC_TCK0")
	)
	(via
		(at 439.048398 -149.692868)
		(size 0.6604)
		(drill 0.3302)
		(layers "F.Cu" "B.Cu")
		(net "JTAG_BMC_TCK0")
	)
	(segment
		(start 438.895998 -149.692868)
		(end 438.17413 -148.971)
		(width 0.10795)
		(layer "B.Cu")
		(net "JTAG_BMC_TCK0")
	)
	(segment
		(start 439.048398 -149.692868)
		(end 438.895998 -149.692868)
		(width 0.10795)
		(layer "B.Cu")
		(net "JTAG_BMC_TCK0")
	)
	(segment
		(start 442.02858 -150.982426)
		(end 441.750704 -150.982426)
		(width 0.10795)
		(layer "B.Cu")
		(net "JTAG_BMC_TCK0")
	)
	(segment
		(start 438.17413 -148.971)
		(end 437.971946 -148.971)
		(width 0.10795)
		(layer "B.Cu")
		(net "JTAG_BMC_TCK0")
	)
	(segment
		(start 440.467496 -149.692868)
		(end 439.048398 -149.692868)
		(width 0.10795)
		(layer "B.Cu")
		(net "JTAG_BMC_TCK0")
	)
	(segment
		(start 437.689244 -148.688298)
		(end 437.689244 -148.168868)
		(width 0.10795)
		(layer "B.Cu")
		(net "JTAG_BMC_TCK0")
	)
	(segment
		(start 440.968638 -150.713186)
		(end 440.968638 -150.19401)
		(width 0.10795)
		(layer "B.Cu")
		(net "JTAG_BMC_TCK0")
	)
	(segment
		(start 438.326276 -147.531836)
		(end 438.326276 -146.282156)
		(width 0.10795)
		(layer "B.Cu")
		(net "JTAG_BMC_TCK0")
	)
	(segment
		(start 440.968638 -150.19401)
		(end 440.467496 -149.692868)
		(width 0.10795)
		(layer "B.Cu")
		(net "JTAG_BMC_TCK0")
	)
	(segment
		(start 441.481464 -150.713186)
		(end 440.968638 -150.713186)
		(width 0.10795)
		(layer "B.Cu")
		(net "JTAG_BMC_TCK0")
	)
	(segment
		(start 441.750704 -150.982426)
		(end 441.481464 -150.713186)
		(width 0.10795)
		(layer "B.Cu")
		(net "JTAG_BMC_TCK0")
	)
	(segment
		(start 437.689244 -148.168868)
		(end 438.326276 -147.531836)
		(width 0.10795)
		(layer "B.Cu")
		(net "JTAG_BMC_TCK0")
	)
	(segment
		(start 437.971946 -148.971)
		(end 437.689244 -148.688298)
		(width 0.10795)
		(layer "B.Cu")
		(net "JTAG_BMC_TCK0")
	)
	(segment
		(start 418.5666 -64.553592)
		(end 418.223192 -64.897)
		(width 0.10795)
		(layer "F.Cu")
		(net "BMC_SELF_HW_D_RST")
	)
	(segment
		(start 418.223192 -64.897)
		(end 417.8935 -64.897)
		(width 0.10795)
		(layer "F.Cu")
		(net "BMC_SELF_HW_D_RST")
	)
	(segment
		(start 419.015164 -61.324236)
		(end 418.5666 -61.7728)
		(width 0.10795)
		(layer "F.Cu")
		(net "BMC_SELF_HW_D_RST")
	)
	(segment
		(start 418.5666 -61.7728)
		(end 418.5666 -64.553592)
		(width 0.10795)
		(layer "F.Cu")
		(net "BMC_SELF_HW_D_RST")
	)
	(segment
		(start 425.8945 -54.4449)
		(end 419.015164 -61.324236)
		(width 0.10795)
		(layer "F.Cu")
		(net "BMC_SELF_HW_D_RST")
	)
	(segment
		(start 425.8945 -52.3367)
		(end 425.8945 -54.4449)
		(width 0.10795)
		(layer "F.Cu")
		(net "BMC_SELF_HW_D_RST")
	)
	(via
		(at 425.8945 -52.3367)
		(size 0.508)
		(drill 0.254)
		(layers "F.Cu" "B.Cu")
		(net "BMC_SELF_HW_D_RST")
	)
	(via
		(at 459.020164 -37.439854)
		(size 0.508)
		(drill 0.254)
		(layers "F.Cu" "B.Cu")
		(net "BMC_SELF_HW_D_RST")
	)
	(via
		(at 419.015164 -61.324236)
		(size 0.762)
		(drill 0.381)
		(layers "F.Cu" "B.Cu")
		(net "BMC_SELF_HW_D_RST")
	)
	(segment
		(start 457.622402 -34.787332)
		(end 457.622148 -34.787586)
		(width 0.10795)
		(layer "B.Cu")
		(net "BMC_SELF_HW_D_RST")
	)
	(segment
		(start 454.570084 -27.394916)
		(end 457.41717 -30.242002)
		(width 0.10795)
		(layer "B.Cu")
		(net "BMC_SELF_HW_D_RST")
	)
	(segment
		(start 457.622402 -35.192462)
		(end 458.399134 -35.969194)
		(width 0.10795)
		(layer "B.Cu")
		(net "BMC_SELF_HW_D_RST")
	)
	(segment
		(start 457.622402 -32.319214)
		(end 457.622402 -34.787332)
		(width 0.10795)
		(layer "B.Cu")
		(net "BMC_SELF_HW_D_RST")
	)
	(segment
		(start 450.6976 -16.4719)
		(end 451.030594 -16.804894)
		(width 0.10795)
		(layer "B.Cu")
		(net "BMC_SELF_HW_D_RST")
	)
	(segment
		(start 453.619362 -18.535904)
		(end 455.264012 -20.180554)
		(width 0.10795)
		(layer "B.Cu")
		(net "BMC_SELF_HW_D_RST")
	)
	(segment
		(start 451.6882 -16.6116)
		(end 452.0946 -16.6116)
		(width 0.10795)
		(layer "B.Cu")
		(net "BMC_SELF_HW_D_RST")
	)
	(segment
		(start 450.9135 -15.8496)
		(end 450.6976 -16.0655)
		(width 0.10795)
		(layer "B.Cu")
		(net "BMC_SELF_HW_D_RST")
	)
	(segment
		(start 453.619362 -17.749266)
		(end 453.619362 -18.535904)
		(width 0.10795)
		(layer "B.Cu")
		(net "BMC_SELF_HW_D_RST")
	)
	(segment
		(start 454.570084 -26.218896)
		(end 454.570084 -27.394916)
		(width 0.10795)
		(layer "B.Cu")
		(net "BMC_SELF_HW_D_RST")
	)
	(segment
		(start 457.622148 -34.787586)
		(end 457.622148 -35.145218)
		(width 0.10795)
		(layer "B.Cu")
		(net "BMC_SELF_HW_D_RST")
	)
	(segment
		(start 458.399134 -36.818824)
		(end 459.020164 -37.439854)
		(width 0.10795)
		(layer "B.Cu")
		(net "BMC_SELF_HW_D_RST")
	)
	(segment
		(start 451.517512 -15.84833)
		(end 451.517512 -16.440912)
		(width 0.10795)
		(layer "B.Cu")
		(net "BMC_SELF_HW_D_RST")
	)
	(segment
		(start 451.517512 -16.440912)
		(end 451.6882 -16.6116)
		(width 0.10795)
		(layer "B.Cu")
		(net "BMC_SELF_HW_D_RST")
	)
	(segment
		(start 458.29347 -30.780228)
		(end 458.29347 -31.648146)
		(width 0.10795)
		(layer "B.Cu")
		(net "BMC_SELF_HW_D_RST")
	)
	(segment
		(start 458.399134 -35.969194)
		(end 458.399134 -36.818824)
		(width 0.10795)
		(layer "B.Cu")
		(net "BMC_SELF_HW_D_RST")
	)
	(segment
		(start 458.29347 -31.648146)
		(end 457.622402 -32.319214)
		(width 0.10795)
		(layer "B.Cu")
		(net "BMC_SELF_HW_D_RST")
	)
	(segment
		(start 457.622148 -35.145218)
		(end 457.622402 -35.145472)
		(width 0.10795)
		(layer "B.Cu")
		(net "BMC_SELF_HW_D_RST")
	)
	(segment
		(start 457.622402 -35.145472)
		(end 457.622402 -35.192462)
		(width 0.10795)
		(layer "B.Cu")
		(net "BMC_SELF_HW_D_RST")
	)
	(segment
		(start 451.517512 -15.84833)
		(end 451.516242 -15.8496)
		(width 0.10795)
		(layer "B.Cu")
		(net "BMC_SELF_HW_D_RST")
	)
	(segment
		(start 450.6976 -16.0655)
		(end 450.6976 -16.4719)
		(width 0.10795)
		(layer "B.Cu")
		(net "BMC_SELF_HW_D_RST")
	)
	(segment
		(start 457.755244 -30.242002)
		(end 458.29347 -30.780228)
		(width 0.10795)
		(layer "B.Cu")
		(net "BMC_SELF_HW_D_RST")
	)
	(segment
		(start 451.516242 -15.8496)
		(end 450.9135 -15.8496)
		(width 0.10795)
		(layer "B.Cu")
		(net "BMC_SELF_HW_D_RST")
	)
	(segment
		(start 457.41717 -30.242002)
		(end 457.755244 -30.242002)
		(width 0.10795)
		(layer "B.Cu")
		(net "BMC_SELF_HW_D_RST")
	)
	(segment
		(start 452.0946 -16.6116)
		(end 453.232266 -17.749266)
		(width 0.10795)
		(layer "B.Cu")
		(net "BMC_SELF_HW_D_RST")
	)
	(segment
		(start 455.264012 -25.524968)
		(end 454.570084 -26.218896)
		(width 0.10795)
		(layer "B.Cu")
		(net "BMC_SELF_HW_D_RST")
	)
	(segment
		(start 455.264012 -20.180554)
		(end 455.264012 -25.524968)
		(width 0.10795)
		(layer "B.Cu")
		(net "BMC_SELF_HW_D_RST")
	)
	(segment
		(start 451.030594 -16.804894)
		(end 451.030594 -17.1831)
		(width 0.10795)
		(layer "B.Cu")
		(net "BMC_SELF_HW_D_RST")
	)
	(segment
		(start 453.232266 -17.749266)
		(end 453.619362 -17.749266)
		(width 0.10795)
		(layer "B.Cu")
		(net "BMC_SELF_HW_D_RST")
	)
	(segment
		(start 436.481474 -50.45075)
		(end 435.545738 -51.386486)
		(width 0.089408)
		(layer "In9.Cu")
		(net "BMC_SELF_HW_D_RST")
	)
	(segment
		(start 456.945238 -44.982384)
		(end 456.945238 -46.340014)
		(width 0.089408)
		(layer "In9.Cu")
		(net "BMC_SELF_HW_D_RST")
	)
	(segment
		(start 459.020164 -39.579804)
		(end 457.701904 -40.898064)
		(width 0.089408)
		(layer "In9.Cu")
		(net "BMC_SELF_HW_D_RST")
	)
	(segment
		(start 439.218832 -47.635414)
		(end 436.481474 -50.372772)
		(width 0.089408)
		(layer "In9.Cu")
		(net "BMC_SELF_HW_D_RST")
	)
	(segment
		(start 459.020164 -37.439854)
		(end 459.020164 -39.579804)
		(width 0.089408)
		(layer "In9.Cu")
		(net "BMC_SELF_HW_D_RST")
	)
	(segment
		(start 455.649838 -47.635414)
		(end 439.218832 -47.635414)
		(width 0.089408)
		(layer "In9.Cu")
		(net "BMC_SELF_HW_D_RST")
	)
	(segment
		(start 457.283312 -44.64431)
		(end 456.945238 -44.982384)
		(width 0.089408)
		(layer "In9.Cu")
		(net "BMC_SELF_HW_D_RST")
	)
	(segment
		(start 457.283312 -43.253152)
		(end 457.283312 -44.64431)
		(width 0.089408)
		(layer "In9.Cu")
		(net "BMC_SELF_HW_D_RST")
	)
	(segment
		(start 457.701904 -42.83456)
		(end 457.283312 -43.253152)
		(width 0.089408)
		(layer "In9.Cu")
		(net "BMC_SELF_HW_D_RST")
	)
	(segment
		(start 436.481474 -50.372772)
		(end 436.481474 -50.45075)
		(width 0.089408)
		(layer "In9.Cu")
		(net "BMC_SELF_HW_D_RST")
	)
	(segment
		(start 456.945238 -46.340014)
		(end 455.649838 -47.635414)
		(width 0.089408)
		(layer "In9.Cu")
		(net "BMC_SELF_HW_D_RST")
	)
	(segment
		(start 457.701904 -40.898064)
		(end 457.701904 -42.83456)
		(width 0.089408)
		(layer "In9.Cu")
		(net "BMC_SELF_HW_D_RST")
	)
	(segment
		(start 426.091858 -52.3367)
		(end 425.8945 -52.3367)
		(width 0.089408)
		(layer "In9.Cu")
		(net "BMC_SELF_HW_D_RST")
	)
	(segment
		(start 435.545738 -51.386486)
		(end 427.042072 -51.386486)
		(width 0.089408)
		(layer "In9.Cu")
		(net "BMC_SELF_HW_D_RST")
	)
	(segment
		(start 427.042072 -51.386486)
		(end 426.091858 -52.3367)
		(width 0.089408)
		(layer "In9.Cu")
		(net "BMC_SELF_HW_D_RST")
	)
	(via
		(at 461.712818 -25.6794)
		(size 0.6604)
		(drill 0.3302)
		(layers "F.Cu" "B.Cu")
		(net "PU_ID_EEPROM_A0")
	)
	(segment
		(start 461.712818 -25.6794)
		(end 461.712818 -26.678382)
		(width 0.10795)
		(layer "B.Cu")
		(net "PU_ID_EEPROM_A0")
	)
	(segment
		(start 462.5975 -24.003)
		(end 462.082134 -24.003)
		(width 0.1016)
		(layer "B.Cu")
		(net "PU_ID_EEPROM_A0")
	)
	(segment
		(start 461.079342 -27.311858)
		(end 458.037438 -27.311858)
		(width 0.10795)
		(layer "B.Cu")
		(net "PU_ID_EEPROM_A0")
	)
	(segment
		(start 461.712818 -24.372316)
		(end 461.712818 -25.6794)
		(width 0.1016)
		(layer "B.Cu")
		(net "PU_ID_EEPROM_A0")
	)
	(segment
		(start 462.082134 -24.003)
		(end 461.712818 -24.372316)
		(width 0.1016)
		(layer "B.Cu")
		(net "PU_ID_EEPROM_A0")
	)
	(segment
		(start 457.7842 -27.05862)
		(end 457.7842 -26.543)
		(width 0.10795)
		(layer "B.Cu")
		(net "PU_ID_EEPROM_A0")
	)
	(segment
		(start 461.712818 -26.678382)
		(end 461.079342 -27.311858)
		(width 0.10795)
		(layer "B.Cu")
		(net "PU_ID_EEPROM_A0")
	)
	(segment
		(start 458.037438 -27.311858)
		(end 457.7842 -27.05862)
		(width 0.10795)
		(layer "B.Cu")
		(net "PU_ID_EEPROM_A0")
	)
	(segment
		(start 394.2969 -20.6248)
		(end 394.2969 -21.081238)
		(width 0.10795)
		(layer "B.Cu")
		(net "VREF_LMV431_1V42")
	)
	(segment
		(start 394.2334 -21.144738)
		(end 394.2334 -21.844)
		(width 0.10795)
		(layer "B.Cu")
		(net "VREF_LMV431_1V42")
	)
	(segment
		(start 394.2969 -21.081238)
		(end 394.2334 -21.144738)
		(width 0.10795)
		(layer "B.Cu")
		(net "VREF_LMV431_1V42")
	)
	(segment
		(start 394.2969 -20.6248)
		(end 395.0843 -20.6248)
		(width 0.10795)
		(layer "B.Cu")
		(net "VREF_LMV431_1V42")
	)
	(via
		(at 391.9728 -10.744962)
		(size 0.6604)
		(drill 0.3302)
		(layers "F.Cu" "B.Cu")
		(net "SMB_M2_SDA_R")
	)
	(segment
		(start 392.680698 -12.582144)
		(end 392.680698 -11.432032)
		(width 0.10795)
		(layer "B.Cu")
		(net "SMB_M2_SDA_R")
	)
	(segment
		(start 391.9728 -10.744962)
		(end 392.135868 -10.90803)
		(width 0.10795)
		(layer "B.Cu")
		(net "SMB_M2_SDA_R")
	)
	(segment
		(start 392.135868 -10.90803)
		(end 393.2047 -10.90803)
		(width 0.10795)
		(layer "B.Cu")
		(net "SMB_M2_SDA_R")
	)
	(segment
		(start 392.680698 -11.432032)
		(end 393.2047 -10.90803)
		(width 0.10795)
		(layer "B.Cu")
		(net "SMB_M2_SDA_R")
	)
	(segment
		(start 391.8966 -30.9118)
		(end 391.287508 -31.520892)
		(width 0.10795)
		(layer "F.Cu")
		(net "SMB_M2_SDA")
	)
	(segment
		(start 391.287508 -31.520892)
		(end 390.347454 -31.520892)
		(width 0.10795)
		(layer "F.Cu")
		(net "SMB_M2_SDA")
	)
	(via
		(at 396.89405 -19.362674)
		(size 0.508)
		(drill 0.254)
		(layers "F.Cu" "B.Cu")
		(net "SMB_M2_SDA")
	)
	(via
		(at 391.8966 -30.9118)
		(size 0.508)
		(drill 0.254)
		(layers "F.Cu" "B.Cu")
		(net "SMB_M2_SDA")
	)
	(via
		(at 397.671798 -13.341096)
		(size 0.6604)
		(drill 0.3302)
		(layers "F.Cu" "B.Cu")
		(net "SMB_M2_SDA")
	)
	(segment
		(start 397.401288 -18.865088)
		(end 396.903702 -19.362674)
		(width 0.10795)
		(layer "B.Cu")
		(net "SMB_M2_SDA")
	)
	(segment
		(start 397.671798 -14.62278)
		(end 397.834104 -14.785086)
		(width 0.10795)
		(layer "B.Cu")
		(net "SMB_M2_SDA")
	)
	(segment
		(start 395.666976 -8.670036)
		(end 394.20165 -8.670036)
		(width 0.10795)
		(layer "B.Cu")
		(net "SMB_M2_SDA")
	)
	(segment
		(start 394.20165 -8.670036)
		(end 393.447016 -9.42467)
		(width 0.10795)
		(layer "B.Cu")
		(net "SMB_M2_SDA")
	)
	(segment
		(start 397.671798 -13.341096)
		(end 397.671798 -14.62278)
		(width 0.10795)
		(layer "B.Cu")
		(net "SMB_M2_SDA")
	)
	(segment
		(start 397.401288 -17.533112)
		(end 397.401288 -18.865088)
		(width 0.10795)
		(layer "B.Cu")
		(net "SMB_M2_SDA")
	)
	(segment
		(start 396.539466 -18.338292)
		(end 396.216886 -18.015712)
		(width 0.10795)
		(layer "B.Cu")
		(net "SMB_M2_SDA")
	)
	(segment
		(start 397.671798 -10.674858)
		(end 395.666976 -8.670036)
		(width 0.10795)
		(layer "B.Cu")
		(net "SMB_M2_SDA")
	)
	(segment
		(start 393.447016 -9.42467)
		(end 393.447016 -9.776714)
		(width 0.10795)
		(layer "B.Cu")
		(net "SMB_M2_SDA")
	)
	(segment
		(start 397.834104 -17.100296)
		(end 397.401288 -17.533112)
		(width 0.10795)
		(layer "B.Cu")
		(net "SMB_M2_SDA")
	)
	(segment
		(start 396.216886 -18.015712)
		(end 396.216886 -17.327372)
		(width 0.10795)
		(layer "B.Cu")
		(net "SMB_M2_SDA")
	)
	(segment
		(start 396.89405 -19.362674)
		(end 396.539466 -19.00809)
		(width 0.10795)
		(layer "B.Cu")
		(net "SMB_M2_SDA")
	)
	(segment
		(start 397.834104 -14.785086)
		(end 397.834104 -17.100296)
		(width 0.10795)
		(layer "B.Cu")
		(net "SMB_M2_SDA")
	)
	(segment
		(start 396.539466 -19.00809)
		(end 396.539466 -18.338292)
		(width 0.10795)
		(layer "B.Cu")
		(net "SMB_M2_SDA")
	)
	(segment
		(start 396.903702 -19.362674)
		(end 396.89405 -19.362674)
		(width 0.10795)
		(layer "B.Cu")
		(net "SMB_M2_SDA")
	)
	(segment
		(start 397.671798 -13.341096)
		(end 397.671798 -10.674858)
		(width 0.10795)
		(layer "B.Cu")
		(net "SMB_M2_SDA")
	)
	(segment
		(start 393.447016 -9.776714)
		(end 393.2047 -10.01903)
		(width 0.10795)
		(layer "B.Cu")
		(net "SMB_M2_SDA")
	)
	(segment
		(start 392.363198 -21.533358)
		(end 392.363198 -20.958048)
		(width 0.089408)
		(layer "In9.Cu")
		(net "SMB_M2_SDA")
	)
	(segment
		(start 392.44905 -24.529542)
		(end 392.932412 -24.04618)
		(width 0.089408)
		(layer "In9.Cu")
		(net "SMB_M2_SDA")
	)
	(segment
		(start 392.932412 -24.04618)
		(end 392.93546 -24.04618)
		(width 0.089408)
		(layer "In9.Cu")
		(net "SMB_M2_SDA")
	)
	(segment
		(start 392.26744 -27.932634)
		(end 392.494262 -27.705812)
		(width 0.089408)
		(layer "In9.Cu")
		(net "SMB_M2_SDA")
	)
	(segment
		(start 396.383002 -19.362674)
		(end 396.89405 -19.362674)
		(width 0.089408)
		(layer "In9.Cu")
		(net "SMB_M2_SDA")
	)
	(segment
		(start 393.08786 -22.1996)
		(end 392.73734 -21.84908)
		(width 0.089408)
		(layer "In9.Cu")
		(net "SMB_M2_SDA")
	)
	(segment
		(start 391.8966 -30.9118)
		(end 391.8966 -30.727904)
		(width 0.089408)
		(layer "In9.Cu")
		(net "SMB_M2_SDA")
	)
	(segment
		(start 391.8966 -30.727904)
		(end 392.26744 -30.357064)
		(width 0.089408)
		(layer "In9.Cu")
		(net "SMB_M2_SDA")
	)
	(segment
		(start 392.26744 -30.357064)
		(end 392.26744 -27.932634)
		(width 0.089408)
		(layer "In9.Cu")
		(net "SMB_M2_SDA")
	)
	(segment
		(start 392.363198 -20.958048)
		(end 392.818112 -20.503134)
		(width 0.089408)
		(layer "In9.Cu")
		(net "SMB_M2_SDA")
	)
	(segment
		(start 392.67892 -21.84908)
		(end 392.363198 -21.533358)
		(width 0.089408)
		(layer "In9.Cu")
		(net "SMB_M2_SDA")
	)
	(segment
		(start 392.93546 -24.04618)
		(end 393.04722 -23.93442)
		(width 0.089408)
		(layer "In9.Cu")
		(net "SMB_M2_SDA")
	)
	(segment
		(start 395.242542 -20.503134)
		(end 396.383002 -19.362674)
		(width 0.089408)
		(layer "In9.Cu")
		(net "SMB_M2_SDA")
	)
	(segment
		(start 393.04722 -23.93442)
		(end 393.04722 -22.72792)
		(width 0.089408)
		(layer "In9.Cu")
		(net "SMB_M2_SDA")
	)
	(segment
		(start 392.494262 -26.708862)
		(end 392.44905 -26.66365)
		(width 0.089408)
		(layer "In9.Cu")
		(net "SMB_M2_SDA")
	)
	(segment
		(start 393.08786 -22.68728)
		(end 393.08786 -22.1996)
		(width 0.089408)
		(layer "In9.Cu")
		(net "SMB_M2_SDA")
	)
	(segment
		(start 392.73734 -21.84908)
		(end 392.67892 -21.84908)
		(width 0.089408)
		(layer "In9.Cu")
		(net "SMB_M2_SDA")
	)
	(segment
		(start 392.494262 -27.705812)
		(end 392.494262 -26.708862)
		(width 0.089408)
		(layer "In9.Cu")
		(net "SMB_M2_SDA")
	)
	(segment
		(start 392.44905 -26.66365)
		(end 392.44905 -24.529542)
		(width 0.089408)
		(layer "In9.Cu")
		(net "SMB_M2_SDA")
	)
	(segment
		(start 393.04722 -22.72792)
		(end 393.08786 -22.68728)
		(width 0.089408)
		(layer "In9.Cu")
		(net "SMB_M2_SDA")
	)
	(segment
		(start 392.818112 -20.503134)
		(end 395.242542 -20.503134)
		(width 0.089408)
		(layer "In9.Cu")
		(net "SMB_M2_SDA")
	)
	(via
		(at 395.128242 -10.554462)
		(size 0.6604)
		(drill 0.3302)
		(layers "F.Cu" "B.Cu")
		(net "SMB_M2_SCL_R")
	)
	(segment
		(start 393.9667 -10.90803)
		(end 394.774674 -10.90803)
		(width 0.10795)
		(layer "B.Cu")
		(net "SMB_M2_SCL_R")
	)
	(segment
		(start 393.330938 -12.582144)
		(end 393.330938 -11.543792)
		(width 0.10795)
		(layer "B.Cu")
		(net "SMB_M2_SCL_R")
	)
	(segment
		(start 394.774674 -10.90803)
		(end 395.128242 -10.554462)
		(width 0.10795)
		(layer "B.Cu")
		(net "SMB_M2_SCL_R")
	)
	(segment
		(start 393.330938 -11.543792)
		(end 393.9667 -10.90803)
		(width 0.10795)
		(layer "B.Cu")
		(net "SMB_M2_SCL_R")
	)
	(segment
		(start 391.6934 -30.2768)
		(end 391.431272 -30.538928)
		(width 0.10795)
		(layer "F.Cu")
		(net "SMB_M2_SCL")
	)
	(segment
		(start 391.247884 -31.02102)
		(end 390.347454 -31.02102)
		(width 0.10795)
		(layer "F.Cu")
		(net "SMB_M2_SCL")
	)
	(segment
		(start 391.431272 -30.538928)
		(end 391.431272 -30.837632)
		(width 0.10795)
		(layer "F.Cu")
		(net "SMB_M2_SCL")
	)
	(segment
		(start 391.431272 -30.837632)
		(end 391.247884 -31.02102)
		(width 0.10795)
		(layer "F.Cu")
		(net "SMB_M2_SCL")
	)
	(via
		(at 391.6934 -30.2768)
		(size 0.508)
		(drill 0.254)
		(layers "F.Cu" "B.Cu")
		(net "SMB_M2_SCL")
	)
	(via
		(at 397.2814 -15.053564)
		(size 0.6604)
		(drill 0.3302)
		(layers "F.Cu" "B.Cu")
		(net "SMB_M2_SCL")
	)
	(via
		(at 396.9639 -18.705068)
		(size 0.508)
		(drill 0.254)
		(layers "F.Cu" "B.Cu")
		(net "SMB_M2_SCL")
	)
	(segment
		(start 397.57858 -15.350744)
		(end 397.2814 -15.053564)
		(width 0.10795)
		(layer "B.Cu")
		(net "SMB_M2_SCL")
	)
	(segment
		(start 397.264128 -17.327372)
		(end 397.57858 -17.01292)
		(width 0.10795)
		(layer "B.Cu")
		(net "SMB_M2_SCL")
	)
	(segment
		(start 394.233908 -9.000236)
		(end 393.70762 -9.526524)
		(width 0.10795)
		(layer "B.Cu")
		(net "SMB_M2_SCL")
	)
	(segment
		(start 397.173196 -14.94536)
		(end 397.173196 -13.134594)
		(width 0.10795)
		(layer "B.Cu")
		(net "SMB_M2_SCL")
	)
	(segment
		(start 395.605254 -9.000236)
		(end 394.233908 -9.000236)
		(width 0.10795)
		(layer "B.Cu")
		(net "SMB_M2_SCL")
	)
	(segment
		(start 393.70762 -9.526524)
		(end 393.70762 -9.75995)
		(width 0.10795)
		(layer "B.Cu")
		(net "SMB_M2_SCL")
	)
	(segment
		(start 397.43634 -10.831322)
		(end 395.605254 -9.000236)
		(width 0.10795)
		(layer "B.Cu")
		(net "SMB_M2_SCL")
	)
	(segment
		(start 397.2814 -15.053564)
		(end 397.173196 -14.94536)
		(width 0.10795)
		(layer "B.Cu")
		(net "SMB_M2_SCL")
	)
	(segment
		(start 397.43634 -12.87145)
		(end 397.43634 -10.831322)
		(width 0.10795)
		(layer "B.Cu")
		(net "SMB_M2_SCL")
	)
	(segment
		(start 397.173196 -13.134594)
		(end 397.43634 -12.87145)
		(width 0.10795)
		(layer "B.Cu")
		(net "SMB_M2_SCL")
	)
	(segment
		(start 396.978886 -18.690082)
		(end 396.9639 -18.705068)
		(width 0.10795)
		(layer "B.Cu")
		(net "SMB_M2_SCL")
	)
	(segment
		(start 396.978886 -17.327372)
		(end 396.978886 -18.690082)
		(width 0.10795)
		(layer "B.Cu")
		(net "SMB_M2_SCL")
	)
	(segment
		(start 393.70762 -9.75995)
		(end 393.9667 -10.01903)
		(width 0.10795)
		(layer "B.Cu")
		(net "SMB_M2_SCL")
	)
	(segment
		(start 397.57858 -17.01292)
		(end 397.57858 -15.350744)
		(width 0.10795)
		(layer "B.Cu")
		(net "SMB_M2_SCL")
	)
	(segment
		(start 396.978886 -17.327372)
		(end 397.264128 -17.327372)
		(width 0.10795)
		(layer "B.Cu")
		(net "SMB_M2_SCL")
	)
	(segment
		(start 392.7729 -20.27809)
		(end 392.17219 -20.8788)
		(width 0.089408)
		(layer "In9.Cu")
		(net "SMB_M2_SCL")
	)
	(segment
		(start 392.17219 -20.8788)
		(end 392.17219 -21.614638)
		(width 0.089408)
		(layer "In9.Cu")
		(net "SMB_M2_SCL")
	)
	(segment
		(start 392.258042 -26.742898)
		(end 392.303254 -26.78811)
		(width 0.089408)
		(layer "In9.Cu")
		(net "SMB_M2_SCL")
	)
	(segment
		(start 392.303254 -26.78811)
		(end 392.303254 -27.52852)
		(width 0.089408)
		(layer "In9.Cu")
		(net "SMB_M2_SCL")
	)
	(segment
		(start 392.89482 -22.60854)
		(end 392.855196 -22.648164)
		(width 0.089408)
		(layer "In9.Cu")
		(net "SMB_M2_SCL")
	)
	(segment
		(start 392.020044 -27.81173)
		(end 392.020044 -29.950156)
		(width 0.089408)
		(layer "In9.Cu")
		(net "SMB_M2_SCL")
	)
	(segment
		(start 392.599672 -22.04212)
		(end 392.6586 -22.04212)
		(width 0.089408)
		(layer "In9.Cu")
		(net "SMB_M2_SCL")
	)
	(segment
		(start 392.303254 -27.52852)
		(end 392.020044 -27.81173)
		(width 0.089408)
		(layer "In9.Cu")
		(net "SMB_M2_SCL")
	)
	(segment
		(start 396.9639 -18.705068)
		(end 396.719044 -18.705068)
		(width 0.089408)
		(layer "In9.Cu")
		(net "SMB_M2_SCL")
	)
	(segment
		(start 396.719044 -18.705068)
		(end 395.146022 -20.27809)
		(width 0.089408)
		(layer "In9.Cu")
		(net "SMB_M2_SCL")
	)
	(segment
		(start 392.89482 -22.27834)
		(end 392.89482 -22.60854)
		(width 0.089408)
		(layer "In9.Cu")
		(net "SMB_M2_SCL")
	)
	(segment
		(start 392.020044 -29.950156)
		(end 391.6934 -30.2768)
		(width 0.089408)
		(layer "In9.Cu")
		(net "SMB_M2_SCL")
	)
	(segment
		(start 392.258042 -24.450294)
		(end 392.258042 -26.742898)
		(width 0.089408)
		(layer "In9.Cu")
		(net "SMB_M2_SCL")
	)
	(segment
		(start 392.855196 -23.85314)
		(end 392.258042 -24.450294)
		(width 0.089408)
		(layer "In9.Cu")
		(net "SMB_M2_SCL")
	)
	(segment
		(start 392.6586 -22.04212)
		(end 392.89482 -22.27834)
		(width 0.089408)
		(layer "In9.Cu")
		(net "SMB_M2_SCL")
	)
	(segment
		(start 392.855196 -22.648164)
		(end 392.855196 -23.85314)
		(width 0.089408)
		(layer "In9.Cu")
		(net "SMB_M2_SCL")
	)
	(segment
		(start 395.146022 -20.27809)
		(end 392.7729 -20.27809)
		(width 0.089408)
		(layer "In9.Cu")
		(net "SMB_M2_SCL")
	)
	(segment
		(start 392.17219 -21.614638)
		(end 392.599672 -22.04212)
		(width 0.089408)
		(layer "In9.Cu")
		(net "SMB_M2_SCL")
	)
	(via
		(at 386.305298 -11.183112)
		(size 0.6604)
		(drill 0.3302)
		(layers "F.Cu" "B.Cu")
		(net "SMB_M2_ALT_R_N")
	)
	(segment
		(start 389.117586 -11.523218)
		(end 389.217662 -11.423142)
		(width 0.10795)
		(layer "B.Cu")
		(net "SMB_M2_ALT_R_N")
	)
	(segment
		(start 387.401816 -11.523218)
		(end 389.117586 -11.523218)
		(width 0.10795)
		(layer "B.Cu")
		(net "SMB_M2_ALT_R_N")
	)
	(segment
		(start 389.217662 -11.423142)
		(end 389.217662 -10.418572)
		(width 0.10795)
		(layer "B.Cu")
		(net "SMB_M2_ALT_R_N")
	)
	(segment
		(start 386.305298 -11.183112)
		(end 386.309616 -11.18743)
		(width 0.10795)
		(layer "B.Cu")
		(net "SMB_M2_ALT_R_N")
	)
	(segment
		(start 386.305298 -11.183112)
		(end 387.06171 -11.183112)
		(width 0.10795)
		(layer "B.Cu")
		(net "SMB_M2_ALT_R_N")
	)
	(segment
		(start 386.309616 -11.18743)
		(end 386.309616 -12.15517)
		(width 0.10795)
		(layer "B.Cu")
		(net "SMB_M2_ALT_R_N")
	)
	(segment
		(start 387.06171 -11.183112)
		(end 387.401816 -11.523218)
		(width 0.10795)
		(layer "B.Cu")
		(net "SMB_M2_ALT_R_N")
	)
	(segment
		(start 390.347454 -32.021018)
		(end 391.622534 -32.021018)
		(width 0.10795)
		(layer "F.Cu")
		(net "SMB_M2_ALT_N")
	)
	(segment
		(start 391.622534 -32.021018)
		(end 391.668 -32.066484)
		(width 0.10795)
		(layer "F.Cu")
		(net "SMB_M2_ALT_N")
	)
	(via
		(at 390.461246 -30.010862)
		(size 0.6604)
		(drill 0.3302)
		(layers "F.Cu" "B.Cu")
		(net "SMB_M2_ALT_N")
	)
	(via
		(at 391.668 -32.066484)
		(size 0.508)
		(drill 0.254)
		(layers "F.Cu" "B.Cu")
		(net "SMB_M2_ALT_N")
	)
	(segment
		(start 389.24992 -20.75434)
		(end 391.760456 -20.75434)
		(width 0.10795)
		(layer "B.Cu")
		(net "SMB_M2_ALT_N")
	)
	(segment
		(start 391.760456 -20.75434)
		(end 391.952226 -20.56257)
		(width 0.10795)
		(layer "B.Cu")
		(net "SMB_M2_ALT_N")
	)
	(segment
		(start 392.143488 -27.19832)
		(end 392.143488 -26.19121)
		(width 0.10795)
		(layer "B.Cu")
		(net "SMB_M2_ALT_N")
	)
	(segment
		(start 392.355578 -21.601938)
		(end 392.355578 -20.93087)
		(width 0.10795)
		(layer "B.Cu")
		(net "SMB_M2_ALT_N")
	)
	(segment
		(start 390.461246 -30.010862)
		(end 390.461246 -30.51937)
		(width 0.10795)
		(layer "B.Cu")
		(net "SMB_M2_ALT_N")
	)
	(segment
		(start 393.150852 -25.183846)
		(end 393.150852 -22.882352)
		(width 0.10795)
		(layer "B.Cu")
		(net "SMB_M2_ALT_N")
	)
	(segment
		(start 391.668 -31.726124)
		(end 391.668 -32.066484)
		(width 0.10795)
		(layer "B.Cu")
		(net "SMB_M2_ALT_N")
	)
	(segment
		(start 392.143488 -26.19121)
		(end 393.150852 -25.183846)
		(width 0.10795)
		(layer "B.Cu")
		(net "SMB_M2_ALT_N")
	)
	(segment
		(start 392.94562 -22.67712)
		(end 392.94562 -22.19198)
		(width 0.10795)
		(layer "B.Cu")
		(net "SMB_M2_ALT_N")
	)
	(segment
		(start 387.056376 -16.225774)
		(end 387.056376 -21.009356)
		(width 0.10795)
		(layer "B.Cu")
		(net "SMB_M2_ALT_N")
	)
	(segment
		(start 390.461246 -30.010862)
		(end 390.461246 -28.880562)
		(width 0.10795)
		(layer "B.Cu")
		(net "SMB_M2_ALT_N")
	)
	(segment
		(start 390.461246 -30.51937)
		(end 391.668 -31.726124)
		(width 0.10795)
		(layer "B.Cu")
		(net "SMB_M2_ALT_N")
	)
	(segment
		(start 388.50824 -21.49602)
		(end 389.24992 -20.75434)
		(width 0.10795)
		(layer "B.Cu")
		(net "SMB_M2_ALT_N")
	)
	(segment
		(start 390.461246 -28.880562)
		(end 392.143488 -27.19832)
		(width 0.10795)
		(layer "B.Cu")
		(net "SMB_M2_ALT_N")
	)
	(segment
		(start 387.056376 -21.009356)
		(end 387.54304 -21.49602)
		(width 0.10795)
		(layer "B.Cu")
		(net "SMB_M2_ALT_N")
	)
	(segment
		(start 386.309616 -15.479014)
		(end 387.056376 -16.225774)
		(width 0.10795)
		(layer "B.Cu")
		(net "SMB_M2_ALT_N")
	)
	(segment
		(start 393.150852 -22.882352)
		(end 392.94562 -22.67712)
		(width 0.10795)
		(layer "B.Cu")
		(net "SMB_M2_ALT_N")
	)
	(segment
		(start 392.382756 -20.903692)
		(end 392.382756 -20.57019)
		(width 0.10795)
		(layer "B.Cu")
		(net "SMB_M2_ALT_N")
	)
	(segment
		(start 392.94562 -22.19198)
		(end 392.355578 -21.601938)
		(width 0.10795)
		(layer "B.Cu")
		(net "SMB_M2_ALT_N")
	)
	(segment
		(start 391.952226 -20.56257)
		(end 392.375136 -20.56257)
		(width 0.10795)
		(layer "B.Cu")
		(net "SMB_M2_ALT_N")
	)
	(segment
		(start 392.355578 -20.93087)
		(end 392.382756 -20.903692)
		(width 0.10795)
		(layer "B.Cu")
		(net "SMB_M2_ALT_N")
	)
	(segment
		(start 387.54304 -21.49602)
		(end 388.50824 -21.49602)
		(width 0.10795)
		(layer "B.Cu")
		(net "SMB_M2_ALT_N")
	)
	(segment
		(start 392.375136 -20.56257)
		(end 392.382756 -20.57019)
		(width 0.10795)
		(layer "B.Cu")
		(net "SMB_M2_ALT_N")
	)
	(segment
		(start 386.309616 -13.04417)
		(end 386.309616 -15.479014)
		(width 0.10795)
		(layer "B.Cu")
		(net "SMB_M2_ALT_N")
	)
	(segment
		(start 434.483002 -21.83511)
		(end 434.232812 -22.0853)
		(width 0.10795)
		(layer "F.Cu")
		(net "PUMP_TACH1")
	)
	(segment
		(start 1.5113 -115.951)
		(end 1.5113 -114.554)
		(width 0.10795)
		(layer "F.Cu")
		(net "PUMP_TACH1")
	)
	(segment
		(start 0.376682 -120.400318)
		(end -0.277622 -119.746014)
		(width 0.10795)
		(layer "F.Cu")
		(net "PUMP_TACH1")
	)
	(segment
		(start 0.5969 -120.1801)
		(end 0.5969 -119.2911)
		(width 0.10795)
		(layer "F.Cu")
		(net "PUMP_TACH1")
	)
	(segment
		(start -0.277622 -119.746014)
		(end -0.277622 -118.636034)
		(width 0.10795)
		(layer "F.Cu")
		(net "PUMP_TACH1")
	)
	(segment
		(start -0.277622 -118.286022)
		(end -0.324612 -118.239032)
		(width 0.10795)
		(layer "F.Cu")
		(net "PUMP_TACH1")
	)
	(segment
		(start 433.166774 -22.872446)
		(end 433.025296 -22.872446)
		(width 0.10795)
		(layer "F.Cu")
		(net "PUMP_TACH1")
	)
	(segment
		(start 0.376682 -120.400318)
		(end 0.5969 -120.1801)
		(width 0.10795)
		(layer "F.Cu")
		(net "PUMP_TACH1")
	)
	(segment
		(start -0.277622 -118.636034)
		(end -0.277622 -118.286022)
		(width 0.10795)
		(layer "F.Cu")
		(net "PUMP_TACH1")
	)
	(segment
		(start 0.6223 -116.84)
		(end 1.5113 -115.951)
		(width 0.10795)
		(layer "F.Cu")
		(net "PUMP_TACH1")
	)
	(segment
		(start 433.95392 -22.0853)
		(end 433.166774 -22.872446)
		(width 0.10795)
		(layer "F.Cu")
		(net "PUMP_TACH1")
	)
	(segment
		(start 434.814726 -20.74926)
		(end 435.5719 -19.992086)
		(width 0.1016)
		(layer "F.Cu")
		(net "PUMP_TACH1")
	)
	(segment
		(start -0.324612 -118.239032)
		(end -0.324612 -117.874034)
		(width 0.10795)
		(layer "F.Cu")
		(net "PUMP_TACH1")
	)
	(segment
		(start 435.5719 -19.992086)
		(end 435.5719 -19.755612)
		(width 0.1016)
		(layer "F.Cu")
		(net "PUMP_TACH1")
	)
	(segment
		(start 434.814726 -20.74926)
		(end 434.483002 -21.080984)
		(width 0.10795)
		(layer "F.Cu")
		(net "PUMP_TACH1")
	)
	(segment
		(start 434.232812 -22.0853)
		(end 433.95392 -22.0853)
		(width 0.10795)
		(layer "F.Cu")
		(net "PUMP_TACH1")
	)
	(segment
		(start 434.483002 -21.080984)
		(end 434.483002 -21.83511)
		(width 0.10795)
		(layer "F.Cu")
		(net "PUMP_TACH1")
	)
	(segment
		(start 422.29024 -28.934664)
		(end 422.69029 -28.534614)
		(width 0.10795)
		(layer "F.Cu")
		(net "PUMP_TACH1")
	)
	(via
		(at 331.158596 4.785868)
		(size 0.508)
		(drill 0.254)
		(layers "F.Cu" "B.Cu")
		(net "PUMP_TACH1")
	)
	(via
		(at 434.814726 -20.74926)
		(size 0.762)
		(drill 0.381)
		(layers "F.Cu" "B.Cu")
		(net "PUMP_TACH1")
	)
	(via
		(at 422.69029 -28.534614)
		(size 0.4572)
		(drill 0.2032)
		(layers "F.Cu" "B.Cu")
		(net "PUMP_TACH1")
	)
	(via
		(at 433.025296 -22.872446)
		(size 0.508)
		(drill 0.254)
		(layers "F.Cu" "B.Cu")
		(net "PUMP_TACH1")
	)
	(via
		(at 426.728636 -0.727202)
		(size 0.508)
		(drill 0.254)
		(layers "F.Cu" "B.Cu")
		(net "PUMP_TACH1")
	)
	(via
		(at 0.376682 -120.400318)
		(size 0.762)
		(drill 0.381)
		(layers "F.Cu" "B.Cu")
		(net "PUMP_TACH1")
	)
	(via
		(at 0.6223 -116.84)
		(size 0.508)
		(drill 0.254)
		(layers "F.Cu" "B.Cu")
		(net "PUMP_TACH1")
	)
	(via
		(at 182.61965 1.130554)
		(size 0.508)
		(drill 0.254)
		(layers "F.Cu" "B.Cu")
		(net "PUMP_TACH1")
	)
	(via
		(at 0.5969 -119.2911)
		(size 0.508)
		(drill 0.254)
		(layers "F.Cu" "B.Cu")
		(net "PUMP_TACH1")
	)
	(via
		(at 358.2924 -2.3114)
		(size 0.508)
		(drill 0.254)
		(layers "F.Cu" "B.Cu")
		(net "PUMP_TACH1")
	)
	(segment
		(start 436.62346 -17.08658)
		(end 437.44388 -17.08658)
		(width 0.10795)
		(layer "B.Cu")
		(net "PUMP_TACH1")
	)
	(segment
		(start 436.1307 -18.16354)
		(end 436.1307 -17.57934)
		(width 0.10795)
		(layer "B.Cu")
		(net "PUMP_TACH1")
	)
	(segment
		(start 439.704226 -17.663668)
		(end 444.527432 -17.663668)
		(width 0.10795)
		(layer "B.Cu")
		(net "PUMP_TACH1")
	)
	(segment
		(start 445.4398 -11.934444)
		(end 446.445386 -10.928858)
		(width 0.10795)
		(layer "B.Cu")
		(net "PUMP_TACH1")
	)
	(segment
		(start 0.6223 -119.2657)
		(end 0.5969 -119.2911)
		(width 0.10795)
		(layer "B.Cu")
		(net "PUMP_TACH1")
	)
	(segment
		(start 439.296048 -2.219452)
		(end 430.387506 -2.219452)
		(width 0.10795)
		(layer "B.Cu")
		(net "PUMP_TACH1")
	)
	(segment
		(start 434.95468 -19.341592)
		(end 434.95468 -19.33956)
		(width 0.10795)
		(layer "B.Cu")
		(net "PUMP_TACH1")
	)
	(segment
		(start 445.4398 -16.7513)
		(end 445.4398 -11.934444)
		(width 0.10795)
		(layer "B.Cu")
		(net "PUMP_TACH1")
	)
	(segment
		(start 444.527432 -17.663668)
		(end 445.4398 -16.7513)
		(width 0.10795)
		(layer "B.Cu")
		(net "PUMP_TACH1")
	)
	(segment
		(start 440.084718 -3.008122)
		(end 439.296048 -2.219452)
		(width 0.10795)
		(layer "B.Cu")
		(net "PUMP_TACH1")
	)
	(segment
		(start 439.185558 -17.145)
		(end 439.704226 -17.663668)
		(width 0.10795)
		(layer "B.Cu")
		(net "PUMP_TACH1")
	)
	(segment
		(start 0.6223 -116.84)
		(end 0.6223 -119.2657)
		(width 0.10795)
		(layer "B.Cu")
		(net "PUMP_TACH1")
	)
	(segment
		(start 427.480222 -1.478788)
		(end 426.728636 -0.727202)
		(width 0.10795)
		(layer "B.Cu")
		(net "PUMP_TACH1")
	)
	(segment
		(start 446.396364 -7.013194)
		(end 440.0169 -7.013194)
		(width 0.10795)
		(layer "B.Cu")
		(net "PUMP_TACH1")
	)
	(segment
		(start 438.724548 -5.720842)
		(end 438.724548 -4.983226)
		(width 0.10795)
		(layer "B.Cu")
		(net "PUMP_TACH1")
	)
	(segment
		(start 430.387506 -2.219452)
		(end 429.646842 -1.478788)
		(width 0.10795)
		(layer "B.Cu")
		(net "PUMP_TACH1")
	)
	(segment
		(start 446.445386 -10.928858)
		(end 446.449704 -10.928858)
		(width 0.10795)
		(layer "B.Cu")
		(net "PUMP_TACH1")
	)
	(segment
		(start 438.724548 -4.983226)
		(end 440.084718 -3.623056)
		(width 0.10795)
		(layer "B.Cu")
		(net "PUMP_TACH1")
	)
	(segment
		(start 447.049652 -10.32891)
		(end 447.049652 -7.666482)
		(width 0.10795)
		(layer "B.Cu")
		(net "PUMP_TACH1")
	)
	(segment
		(start 433.025296 -22.872446)
		(end 433.025296 -21.270976)
		(width 0.10795)
		(layer "B.Cu")
		(net "PUMP_TACH1")
	)
	(segment
		(start 429.646842 -1.478788)
		(end 427.480222 -1.478788)
		(width 0.10795)
		(layer "B.Cu")
		(net "PUMP_TACH1")
	)
	(segment
		(start 440.084718 -3.623056)
		(end 440.084718 -3.008122)
		(width 0.10795)
		(layer "B.Cu")
		(net "PUMP_TACH1")
	)
	(segment
		(start 434.95468 -19.33956)
		(end 436.1307 -18.16354)
		(width 0.10795)
		(layer "B.Cu")
		(net "PUMP_TACH1")
	)
	(segment
		(start 447.049652 -7.666482)
		(end 446.396364 -7.013194)
		(width 0.10795)
		(layer "B.Cu")
		(net "PUMP_TACH1")
	)
	(segment
		(start 433.025296 -21.270976)
		(end 434.95468 -19.341592)
		(width 0.10795)
		(layer "B.Cu")
		(net "PUMP_TACH1")
	)
	(segment
		(start 436.1307 -17.57934)
		(end 436.62346 -17.08658)
		(width 0.10795)
		(layer "B.Cu")
		(net "PUMP_TACH1")
	)
	(segment
		(start 440.0169 -7.013194)
		(end 438.724548 -5.720842)
		(width 0.10795)
		(layer "B.Cu")
		(net "PUMP_TACH1")
	)
	(segment
		(start 437.5023 -17.145)
		(end 439.185558 -17.145)
		(width 0.10795)
		(layer "B.Cu")
		(net "PUMP_TACH1")
	)
	(segment
		(start 446.449704 -10.928858)
		(end 447.049652 -10.32891)
		(width 0.10795)
		(layer "B.Cu")
		(net "PUMP_TACH1")
	)
	(segment
		(start 437.44388 -17.08658)
		(end 437.5023 -17.145)
		(width 0.10795)
		(layer "B.Cu")
		(net "PUMP_TACH1")
	)
	(segment
		(start 358.2924 -2.3114)
		(end 357.8606 -1.8796)
		(width 0.089408)
		(layer "In2.Cu")
		(net "PUMP_TACH1")
	)
	(segment
		(start 331.158596 4.918964)
		(end 331.158596 4.785868)
		(width 0.089408)
		(layer "In2.Cu")
		(net "PUMP_TACH1")
	)
	(segment
		(start 353.368356 -0.282448)
		(end 353.368356 3.978148)
		(width 0.089408)
		(layer "In2.Cu")
		(net "PUMP_TACH1")
	)
	(segment
		(start 357.8606 -1.8796)
		(end 354.965508 -1.8796)
		(width 0.089408)
		(layer "In2.Cu")
		(net "PUMP_TACH1")
	)
	(segment
		(start 331.733906 5.494274)
		(end 331.158596 4.918964)
		(width 0.089408)
		(layer "In2.Cu")
		(net "PUMP_TACH1")
	)
	(segment
		(start 351.85223 5.494274)
		(end 331.733906 5.494274)
		(width 0.089408)
		(layer "In2.Cu")
		(net "PUMP_TACH1")
	)
	(segment
		(start 353.368356 3.978148)
		(end 351.85223 5.494274)
		(width 0.089408)
		(layer "In2.Cu")
		(net "PUMP_TACH1")
	)
	(segment
		(start 354.965508 -1.8796)
		(end 353.368356 -0.282448)
		(width 0.089408)
		(layer "In2.Cu")
		(net "PUMP_TACH1")
	)
	(segment
		(start 328.23912 2.884678)
		(end 327.88733 3.236468)
		(width 0.089408)
		(layer "In9.Cu")
		(net "PUMP_TACH1")
	)
	(segment
		(start 423.658792 -26.094944)
		(end 423.658792 -25.715468)
		(width 0.089408)
		(layer "In9.Cu")
		(net "PUMP_TACH1")
	)
	(segment
		(start 182.61965 3.038856)
		(end 182.61965 1.130554)
		(width 0.089408)
		(layer "In9.Cu")
		(net "PUMP_TACH1")
	)
	(segment
		(start 183.825896 4.941316)
		(end 183.014366 4.129786)
		(width 0.089408)
		(layer "In9.Cu")
		(net "PUMP_TACH1")
	)
	(segment
		(start 331.158596 4.17068)
		(end 329.872594 2.884678)
		(width 0.089408)
		(layer "In9.Cu")
		(net "PUMP_TACH1")
	)
	(segment
		(start 323.549772 3.096768)
		(end 321.705224 4.941316)
		(width 0.089408)
		(layer "In9.Cu")
		(net "PUMP_TACH1")
	)
	(segment
		(start 183.014366 4.129786)
		(end 183.014366 3.433572)
		(width 0.089408)
		(layer "In9.Cu")
		(net "PUMP_TACH1")
	)
	(segment
		(start 427.100492 -22.809708)
		(end 432.133756 -22.809708)
		(width 0.089408)
		(layer "In9.Cu")
		(net "PUMP_TACH1")
	)
	(segment
		(start 327.88733 3.236468)
		(end 325.85152 3.236468)
		(width 0.089408)
		(layer "In9.Cu")
		(net "PUMP_TACH1")
	)
	(segment
		(start 329.872594 2.884678)
		(end 328.23912 2.884678)
		(width 0.089408)
		(layer "In9.Cu")
		(net "PUMP_TACH1")
	)
	(segment
		(start 324.739 2.123948)
		(end 323.962776 2.123948)
		(width 0.089408)
		(layer "In9.Cu")
		(net "PUMP_TACH1")
	)
	(segment
		(start 432.948334 -22.795484)
		(end 433.025296 -22.872446)
		(width 0.089408)
		(layer "In9.Cu")
		(net "PUMP_TACH1")
	)
	(segment
		(start 423.658792 -25.715468)
		(end 425.148248 -24.226012)
		(width 0.089408)
		(layer "In9.Cu")
		(net "PUMP_TACH1")
	)
	(segment
		(start 325.85152 3.236468)
		(end 324.739 2.123948)
		(width 0.089408)
		(layer "In9.Cu")
		(net "PUMP_TACH1")
	)
	(segment
		(start 425.684188 -24.226012)
		(end 427.100492 -22.809708)
		(width 0.089408)
		(layer "In9.Cu")
		(net "PUMP_TACH1")
	)
	(segment
		(start 422.69029 -27.063446)
		(end 423.658792 -26.094944)
		(width 0.089408)
		(layer "In9.Cu")
		(net "PUMP_TACH1")
	)
	(segment
		(start 323.962776 2.123948)
		(end 323.549772 2.536952)
		(width 0.089408)
		(layer "In9.Cu")
		(net "PUMP_TACH1")
	)
)
